(kicad_pcb
	(version 20260206)
	(generator "pcbnew")
	(generator_version "10.0")
	(general
		(thickness 1.6)
		(legacy_teardrops no)
	)
	(paper "A4")
	(layers
		(0 "F.Cu" signal "TOP")
		(4 "In1.Cu" signal "GND")
		(6 "In2.Cu" signal "IN1")
		(8 "In3.Cu" signal "GND1")
		(10 "In4.Cu" signal "IN2")
		(12 "In5.Cu" signal "GND2")
		(14 "In6.Cu" signal "IN3")
		(16 "In7.Cu" signal "GND3")
		(18 "In8.Cu" signal "VCC")
		(20 "In9.Cu" signal "VCC1")
		(22 "In10.Cu" signal "GND4")
		(24 "In11.Cu" signal "IN4")
		(26 "In12.Cu" signal "GND5")
		(28 "In13.Cu" signal "IN5")
		(30 "In14.Cu" signal "GND6")
		(32 "In15.Cu" signal "IN6")
		(34 "In16.Cu" signal "GND7")
		(2 "B.Cu" signal "BOTTOM")
		(9 "F.Adhes" user "F.Adhesive")
		(11 "B.Adhes" user "B.Adhesive")
		(13 "F.Paste" user "Package Geometry/Pastemask Top")
		(15 "B.Paste" user "Package Geometry/Pastemask Bottom")
		(5 "F.SilkS" user "Ref Des/Silkscreen Top")
		(7 "B.SilkS" user "Ref Des/Silkscreen Bottom")
		(1 "F.Mask" user "Board Geometry/Soldermask Top")
		(3 "B.Mask" user "Board Geometry/Soldermask Bottom")
		(17 "Dwgs.User" user "User.Drawings")
		(19 "Cmts.User" user "User.Comments")
		(21 "Eco1.User" user "User.Eco1")
		(23 "Eco2.User" user "User.Eco2")
		(25 "Edge.Cuts" user "Board Geometry/Outline")
		(27 "Margin" user)
		(31 "F.CrtYd" user "Package Geometry/Place Bound Top")
		(29 "B.CrtYd" user "Package Geometry/Place Bound Bottom")
		(35 "F.Fab" user "Ref Des/Assembly Top")
		(33 "B.Fab" user "Ref Des/Assembly Bottom")
	)
	(setup
		(pad_to_mask_clearance 0)
		(allow_soldermask_bridges_in_footprints no)
		(tenting
			(front yes)
			(back yes)
		)
		(covering
			(front no)
			(back no)
		)
		(plugging
			(front no)
			(back no)
		)
		(capping no)
		(filling no)
		(pcbplotparams
			(layerselection 0x00000000_00000000_55555555_5755f5ff)
			(plot_on_all_layers_selection 0x00000000_00000000_00000000_00000000)
			(disableapertmacros no)
			(usegerberextensions no)
			(usegerberattributes yes)
			(usegerberadvancedattributes yes)
			(creategerberjobfile yes)
			(dashed_line_dash_ratio 12)
			(dashed_line_gap_ratio 3)
			(svgprecision 4)
			(plotframeref no)
			(mode 1)
			(useauxorigin no)
			(pdf_front_fp_property_popups yes)
			(pdf_back_fp_property_popups yes)
			(pdf_metadata yes)
			(pdf_single_document no)
			(dxfpolygonmode yes)
			(dxfimperialunits yes)
			(dxfusepcbnewfont yes)
			(psnegative no)
			(psa4output no)
			(plot_black_and_white yes)
			(sketchpadsonfab no)
			(plotpadnumbers no)
			(hidednponfab no)
			(sketchdnponfab yes)
			(crossoutdnponfab yes)
			(subtractmaskfromsilk no)
			(outputformat 1)
			(mirror no)
			(drillshape 1)
			(scaleselection 1)
			(outputdirectory "")
		)
	)
	(gr_poly
		(pts
			(xy 171.612814 -440.69508) (xy 171.622883 -440.694654) (xy 171.641482 -440.686934) (xy 171.648882 -440.680094)
			(xy 172.915326 -439.41365) (xy 172.922724 -439.406802) (xy 172.941322 -439.39907) (xy 172.951394 -439.398664)
			(xy 175.851566 -439.398664) (xy 175.861466 -439.398189) (xy 175.879791 -439.390689) (xy 175.893928 -439.376825)
			(xy 175.898302 -439.36793) (xy 175.941228 -439.268108) (xy 175.935894 -439.23839) (xy 175.92548 -439.227214)
			(xy 175.85342 -439.150471) (xy 175.714756 -438.99204) (xy 175.582531 -438.828199) (xy 175.456953 -438.659208)
			(xy 175.338225 -438.485336) (xy 175.226535 -438.306862) (xy 175.122062 -438.12407) (xy 175.024973 -437.937251)
			(xy 174.935421 -437.746704) (xy 174.853551 -437.552732) (xy 174.779492 -437.355646) (xy 174.713364 -437.155759)
			(xy 174.65527 -436.953391) (xy 174.605305 -436.748864) (xy 174.563548 -436.542505) (xy 174.530065 -436.334643)
			(xy 174.50491 -436.12561) (xy 174.488124 -435.915739) (xy 174.479732 -435.705365) (xy 174.479204 -435.600094)
			(xy 174.4797 -435.497873) (xy 174.487627 -435.293583) (xy 174.50347 -435.089755) (xy 174.527204 -434.886695)
			(xy 174.558794 -434.684707) (xy 174.598193 -434.484096) (xy 174.645341 -434.285164) (xy 174.700167 -434.08821)
			(xy 174.762589 -433.893529) (xy 174.832512 -433.701416) (xy 174.909833 -433.512158) (xy 174.994433 -433.326041)
			(xy 175.086187 -433.143344) (xy 175.184956 -432.964342) (xy 175.290592 -432.789305) (xy 175.402935 -432.618495)
			(xy 175.521817 -432.45217) (xy 175.647059 -432.29058) (xy 175.778472 -432.133968) (xy 175.915859 -431.982569)
			(xy 176.059014 -431.836611) (xy 176.20772 -431.696314) (xy 176.361755 -431.561888) (xy 176.520886 -431.433536)
			(xy 176.684875 -431.311451) (xy 176.853473 -431.195817) (xy 177.026429 -431.086807) (xy 177.203482 -430.984586)
			(xy 177.384366 -430.889306) (xy 177.568807 -430.801113) (xy 177.75653 -430.720137) (xy 177.947252 -430.646501)
			(xy 178.140685 -430.580316) (xy 178.336539 -430.521681) (xy 178.53452 -430.470685) (xy 178.734329 -430.427403)
			(xy 178.935666 -430.391902) (xy 179.138228 -430.364235) (xy 179.34171 -430.344442) (xy 179.545807 -430.332555)
			(xy 179.750212 -430.328591) (xy 179.954617 -430.332555) (xy 180.158714 -430.344442) (xy 180.362196 -430.364235)
			(xy 180.564758 -430.391902) (xy 180.766095 -430.427403) (xy 180.965904 -430.470685) (xy 181.163885 -430.521681)
			(xy 181.359739 -430.580316) (xy 181.553172 -430.646501) (xy 181.712717 -430.7081) (xy 185.635322 -430.7081)
			(xy 185.639337 -430.644295) (xy 185.651316 -430.581496) (xy 185.671072 -430.520694) (xy 185.698293 -430.462848)
			(xy 185.73255 -430.408869) (xy 185.773301 -430.35961) (xy 185.819905 -430.315846) (xy 185.871627 -430.278269)
			(xy 185.927651 -430.24747) (xy 185.987092 -430.223937) (xy 186.049015 -430.208038) (xy 186.112442 -430.200027)
			(xy 186.144408 -430.199546) (xy 186.175812 -430.199996) (xy 186.238143 -430.207729) (xy 186.299048 -430.223075)
			(xy 186.3576 -430.245801) (xy 186.41291 -430.275562) (xy 186.464136 -430.311906) (xy 186.510498 -430.354278)
			(xy 186.53125 -430.377854) (xy 186.538108 -430.385982) (xy 186.556904 -430.395126) (xy 186.6519 -430.399698)
			(xy 186.671458 -430.392332) (xy 186.679078 -430.384966) (xy 186.700548 -430.364971) (xy 186.748481 -430.331144)
			(xy 186.801026 -430.30505) (xy 186.856945 -430.287302) (xy 186.91492 -430.278319) (xy 186.944254 -430.277778)
			(xy 186.972399 -430.278264) (xy 187.028077 -430.286543) (xy 187.081935 -430.302912) (xy 187.132803 -430.327017)
			(xy 187.179578 -430.358334) (xy 187.221243 -430.396184) (xy 187.256896 -430.439744) (xy 187.285761 -430.48807)
			(xy 187.307212 -430.540113) (xy 187.320784 -430.594743) (xy 187.323984 -430.62271) (xy 187.325254 -430.636426)
			(xy 187.341764 -430.659032) (xy 187.449968 -430.704752) (xy 187.477654 -430.700942) (xy 187.488576 -430.692306)
			(xy 187.522337 -430.666) (xy 187.594058 -430.619286) (xy 187.669934 -430.579674) (xy 187.749263 -430.547531)
			(xy 187.831311 -430.523153) (xy 187.91532 -430.506765) (xy 188.000516 -430.498519) (xy 188.043312 -430.497996)
			(xy 188.085237 -430.498488) (xy 188.168714 -430.50638) (xy 188.251077 -430.522093) (xy 188.331597 -430.545487)
			(xy 188.409558 -430.576355) (xy 188.484267 -430.614423) (xy 188.555063 -430.659352) (xy 188.621316 -430.710745)
			(xy 188.682439 -430.768144) (xy 188.737889 -430.831041) (xy 188.787174 -430.898877) (xy 188.829856 -430.97105)
			(xy 188.865556 -431.046919) (xy 188.893959 -431.125811) (xy 188.91481 -431.207026) (xy 188.927927 -431.289843)
			(xy 188.933191 -431.373527) (xy 188.930556 -431.457335) (xy 188.920047 -431.540523) (xy 188.901755 -431.622353)
			(xy 188.875844 -431.702098) (xy 188.842543 -431.779051) (xy 188.802148 -431.852528) (xy 188.755017 -431.921878)
			(xy 188.701569 -431.986485) (xy 188.642279 -432.045775) (xy 188.577671 -432.099222) (xy 188.508321 -432.146352)
			(xy 188.434843 -432.186746) (xy 188.35789 -432.220047) (xy 188.278145 -432.245957) (xy 188.196315 -432.264248)
			(xy 188.113127 -432.274757) (xy 188.029319 -432.277391) (xy 187.945635 -432.272126) (xy 187.862819 -432.259009)
			(xy 187.781604 -432.238156) (xy 187.702712 -432.209753) (xy 187.626843 -432.174052) (xy 187.55467 -432.131369)
			(xy 187.486834 -432.082084) (xy 187.423938 -432.026634) (xy 187.366539 -431.96551) (xy 187.315147 -431.899257)
			(xy 187.270219 -431.82846) (xy 187.232152 -431.75375) (xy 187.201284 -431.675789) (xy 187.177891 -431.59527)
			(xy 187.162179 -431.512906) (xy 187.154288 -431.429429) (xy 187.153804 -431.387504) (xy 187.154281 -431.347032)
			(xy 187.161671 -431.266426) (xy 187.176346 -431.186823) (xy 187.186824 -431.147728) (xy 187.190634 -431.134266)
			(xy 187.183268 -431.107088) (xy 187.09894 -431.025554) (xy 187.071762 -431.019204) (xy 187.058554 -431.023268)
			(xy 187.030692 -431.03146) (xy 186.97329 -431.040254) (xy 186.944254 -431.040794) (xy 186.9134 -431.040188)
			(xy 186.852495 -431.030269) (xy 186.793978 -431.010682) (xy 186.739375 -430.981936) (xy 186.714384 -430.963832)
			(xy 186.706002 -430.957482) (xy 186.685682 -430.952402) (xy 186.591702 -430.968404) (xy 186.574176 -430.979834)
			(xy 186.568334 -430.988724) (xy 186.550664 -431.014619) (xy 186.509903 -431.062249) (xy 186.463593 -431.104506)
			(xy 186.412439 -431.140748) (xy 186.357217 -431.170425) (xy 186.298765 -431.193086) (xy 186.237969 -431.208388)
			(xy 186.175754 -431.216098) (xy 186.144408 -431.216562) (xy 186.112442 -431.216173) (xy 186.049015 -431.208162)
			(xy 185.987092 -431.192263) (xy 185.927651 -431.16873) (xy 185.871627 -431.137931) (xy 185.819905 -431.100354)
			(xy 185.773301 -431.05659) (xy 185.73255 -431.007331) (xy 185.698293 -430.953352) (xy 185.671072 -430.895506)
			(xy 185.651316 -430.834704) (xy 185.639337 -430.771905) (xy 185.635322 -430.7081) (xy 181.712717 -430.7081)
			(xy 181.743894 -430.720137) (xy 181.931617 -430.801113) (xy 182.116058 -430.889306) (xy 182.296942 -430.984586)
			(xy 182.473995 -431.086807) (xy 182.646951 -431.195817) (xy 182.815549 -431.311451) (xy 182.979538 -431.433536)
			(xy 183.138669 -431.561888) (xy 183.292704 -431.696314) (xy 183.44141 -431.836611) (xy 183.584565 -431.982569)
			(xy 183.721952 -432.133968) (xy 183.853365 -432.29058) (xy 183.978607 -432.45217) (xy 184.015716 -432.504088)
			(xy 191.422032 -432.504088) (xy 191.425998 -432.419557) (xy 191.437863 -432.33577) (xy 191.457521 -432.253461)
			(xy 191.484801 -432.173355) (xy 191.519462 -432.096156) (xy 191.5612 -432.022541) (xy 191.609647 -431.953158)
			(xy 191.664379 -431.888617) (xy 191.724915 -431.829485) (xy 191.790721 -431.776281) (xy 191.861221 -431.729473)
			(xy 191.935793 -431.689472) (xy 192.013784 -431.65663) (xy 192.094508 -431.631236) (xy 192.177255 -431.613513)
			(xy 192.261297 -431.603615) (xy 192.345898 -431.601632) (xy 192.430312 -431.607579) (xy 192.513799 -431.621404)
			(xy 192.595624 -431.642987) (xy 192.675068 -431.672137) (xy 192.751434 -431.708598) (xy 192.82405 -431.75205)
			(xy 192.892278 -431.802111) (xy 192.955518 -431.858341) (xy 193.013215 -431.920246) (xy 193.064862 -431.987282)
			(xy 193.110004 -432.058859) (xy 193.148246 -432.134349) (xy 193.17925 -432.213088) (xy 193.202745 -432.294385)
			(xy 193.218524 -432.377524) (xy 193.226448 -432.461776) (xy 193.226944 -432.504088) (xy 193.226448 -432.5464)
			(xy 193.218524 -432.630652) (xy 193.202745 -432.713791) (xy 193.17925 -432.795088) (xy 193.148246 -432.873827)
			(xy 193.110004 -432.949317) (xy 193.064862 -433.020894) (xy 193.013215 -433.08793) (xy 192.955518 -433.149835)
			(xy 192.892278 -433.206065) (xy 192.82405 -433.256126) (xy 192.751434 -433.299578) (xy 192.675068 -433.336039)
			(xy 192.595624 -433.365189) (xy 192.513799 -433.386772) (xy 192.430312 -433.400597) (xy 192.345898 -433.406544)
			(xy 192.261297 -433.404561) (xy 192.177255 -433.394663) (xy 192.094508 -433.37694) (xy 192.013784 -433.351546)
			(xy 191.935793 -433.318704) (xy 191.861221 -433.278703) (xy 191.790721 -433.231895) (xy 191.724915 -433.178691)
			(xy 191.664379 -433.119559) (xy 191.609647 -433.055018) (xy 191.5612 -432.985635) (xy 191.519462 -432.91202)
			(xy 191.484801 -432.834821) (xy 191.457521 -432.754715) (xy 191.437863 -432.672406) (xy 191.425998 -432.588619)
			(xy 191.422032 -432.504088) (xy 184.015716 -432.504088) (xy 184.097489 -432.618495) (xy 184.209832 -432.789305)
			(xy 184.315468 -432.964342) (xy 184.414237 -433.143344) (xy 184.505991 -433.326041) (xy 184.590591 -433.512158)
			(xy 184.667912 -433.701416) (xy 184.737835 -433.893529) (xy 184.800257 -434.08821) (xy 184.855083 -434.285164)
			(xy 184.902231 -434.484096) (xy 184.94163 -434.684707) (xy 184.97322 -434.886695) (xy 184.991616 -435.044088)
			(xy 191.295024 -435.044088) (xy 191.299053 -434.953082) (xy 191.31111 -434.862788) (xy 191.3311 -434.773913)
			(xy 191.358866 -434.687153) (xy 191.394192 -434.603186) (xy 191.4368 -434.52267) (xy 191.486358 -434.446234)
			(xy 191.542477 -434.374478) (xy 191.604718 -434.307962) (xy 191.672595 -434.247207) (xy 191.745575 -434.192689)
			(xy 191.823088 -434.144835) (xy 191.904527 -434.104018) (xy 191.989255 -434.070559) (xy 192.076609 -434.044718)
			(xy 192.165904 -434.0267) (xy 192.256442 -434.016643) (xy 192.347515 -434.014628) (xy 192.43841 -434.02067)
			(xy 192.528415 -434.034721) (xy 192.616826 -434.056672) (xy 192.702951 -434.086351) (xy 192.786116 -434.123525)
			(xy 192.86567 -434.167904) (xy 192.94099 -434.219141) (xy 193.011488 -434.276834) (xy 193.07661 -434.340531)
			(xy 193.135848 -434.409735) (xy 193.188738 -434.483904) (xy 193.234867 -434.562456) (xy 193.273872 -434.644779)
			(xy 193.305449 -434.730226) (xy 193.32935 -434.81813) (xy 193.345389 -434.907802) (xy 193.35344 -434.99854)
			(xy 193.353944 -435.044088) (xy 193.35344 -435.089636) (xy 193.345389 -435.180374) (xy 193.32935 -435.270046)
			(xy 193.305449 -435.35795) (xy 193.273872 -435.443397) (xy 193.234867 -435.52572) (xy 193.188738 -435.604272)
			(xy 193.135848 -435.678441) (xy 193.07661 -435.747645) (xy 193.011488 -435.811342) (xy 192.94099 -435.869035)
			(xy 192.86567 -435.920272) (xy 192.786116 -435.964651) (xy 192.702951 -436.001825) (xy 192.616826 -436.031504)
			(xy 192.528415 -436.053455) (xy 192.43841 -436.067506) (xy 192.347515 -436.073548) (xy 192.256442 -436.071533)
			(xy 192.165904 -436.061476) (xy 192.076609 -436.043458) (xy 191.989255 -436.017617) (xy 191.904527 -435.984158)
			(xy 191.823088 -435.943341) (xy 191.745575 -435.895487) (xy 191.672595 -435.840969) (xy 191.604718 -435.780214)
			(xy 191.542477 -435.713698) (xy 191.486358 -435.641942) (xy 191.4368 -435.565506) (xy 191.394192 -435.48499)
			(xy 191.358866 -435.401023) (xy 191.3311 -435.314263) (xy 191.31111 -435.225388) (xy 191.299053 -435.135094)
			(xy 191.295024 -435.044088) (xy 184.991616 -435.044088) (xy 184.996954 -435.089755) (xy 185.012797 -435.293583)
			(xy 185.020724 -435.497873) (xy 185.02122 -435.600094) (xy 185.020695 -435.705364) (xy 185.012285 -435.915735)
			(xy 184.995483 -436.125604) (xy 184.970315 -436.334633) (xy 184.936822 -436.542492) (xy 184.895056 -436.748847)
			(xy 184.845085 -436.953371) (xy 184.786988 -437.155736) (xy 184.720858 -437.35562) (xy 184.6468 -437.552705)
			(xy 184.633554 -437.584088) (xy 191.295024 -437.584088) (xy 191.299053 -437.493082) (xy 191.31111 -437.402788)
			(xy 191.3311 -437.313913) (xy 191.358866 -437.227153) (xy 191.394192 -437.143186) (xy 191.4368 -437.06267)
			(xy 191.486358 -436.986234) (xy 191.542477 -436.914478) (xy 191.604718 -436.847962) (xy 191.672595 -436.787207)
			(xy 191.745575 -436.732689) (xy 191.823088 -436.684835) (xy 191.904527 -436.644018) (xy 191.989255 -436.610559)
			(xy 192.076609 -436.584718) (xy 192.165904 -436.5667) (xy 192.256442 -436.556643) (xy 192.347515 -436.554628)
			(xy 192.43841 -436.56067) (xy 192.528415 -436.574721) (xy 192.616826 -436.596672) (xy 192.702951 -436.626351)
			(xy 192.786116 -436.663525) (xy 192.86567 -436.707904) (xy 192.94099 -436.759141) (xy 193.011488 -436.816834)
			(xy 193.07661 -436.880531) (xy 193.135848 -436.949735) (xy 193.188738 -437.023904) (xy 193.234867 -437.102456)
			(xy 193.273872 -437.184779) (xy 193.305449 -437.270226) (xy 193.32935 -437.35813) (xy 193.345389 -437.447802)
			(xy 193.35344 -437.53854) (xy 193.353944 -437.584088) (xy 193.353867 -437.591063) (xy 276.104713 -437.591063)
			(xy 276.109924 -437.528198) (xy 276.122871 -437.46646) (xy 276.143356 -437.406798) (xy 276.171062 -437.350128)
			(xy 276.205566 -437.297321) (xy 276.246337 -437.249187) (xy 276.292748 -437.206465) (xy 276.344088 -437.169812)
			(xy 276.399566 -437.139792) (xy 276.458333 -437.116864) (xy 276.519483 -437.101381) (xy 276.58208 -437.09358)
			(xy 276.61362 -437.093106) (xy 276.643941 -437.093541) (xy 276.704153 -437.100737) (xy 276.763084 -437.115037)
			(xy 276.819899 -437.136237) (xy 276.847046 -437.149748) (xy 276.860035 -437.155953) (xy 276.88826 -437.161548)
			(xy 276.916925 -437.159045) (xy 276.943753 -437.148643) (xy 276.966614 -437.131169) (xy 276.983691 -437.108011)
			(xy 276.993629 -437.081007) (xy 276.995128 -437.06669) (xy 276.997674 -437.038169) (xy 277.010192 -436.982296)
			(xy 277.030921 -436.928921) (xy 277.059397 -436.879245) (xy 277.094978 -436.834384) (xy 277.136866 -436.795346)
			(xy 277.184119 -436.763009) (xy 277.235675 -436.738098) (xy 277.290375 -436.721174) (xy 277.346991 -436.712618)
			(xy 277.37562 -436.712106) (xy 277.402871 -436.712565) (xy 277.456819 -436.720324) (xy 277.509113 -436.735682)
			(xy 277.55869 -436.758325) (xy 277.604539 -436.787793) (xy 277.645729 -436.823486) (xy 277.681419 -436.864677)
			(xy 277.710885 -436.910528) (xy 277.733525 -436.960106) (xy 277.74888 -437.012401) (xy 277.756636 -437.066349)
			(xy 277.756636 -437.120851) (xy 277.74888 -437.174799) (xy 277.733525 -437.227094) (xy 277.710885 -437.276672)
			(xy 277.681419 -437.322523) (xy 277.645729 -437.363714) (xy 277.604539 -437.399407) (xy 277.55869 -437.428875)
			(xy 277.509113 -437.451518) (xy 277.456819 -437.466876) (xy 277.402871 -437.474635) (xy 277.37562 -437.475122)
			(xy 277.344647 -437.474558) (xy 277.283508 -437.464598) (xy 277.253954 -437.45531) (xy 277.240167 -437.451197)
			(xy 277.211436 -437.449973) (xy 277.183505 -437.456814) (xy 277.158592 -437.471178) (xy 277.138677 -437.491923)
			(xy 277.125342 -437.517401) (xy 277.119646 -437.545588) (xy 277.12035 -437.559958) (xy 277.122128 -437.601614)
			(xy 277.121617 -437.633154) (xy 277.113813 -437.69575) (xy 277.098326 -437.7569) (xy 277.075394 -437.815664)
			(xy 277.04537 -437.871141) (xy 277.008713 -437.922478) (xy 277.007601 -437.923686) (xy 281.436316 -437.923686)
			(xy 281.440387 -437.868064) (xy 281.452513 -437.813627) (xy 281.472436 -437.761536) (xy 281.499732 -437.712901)
			(xy 281.533818 -437.668758) (xy 281.573967 -437.630049) (xy 281.619325 -437.597598) (xy 281.668925 -437.572097)
			(xy 281.721709 -437.55409) (xy 281.776552 -437.54396) (xy 281.832286 -437.541923) (xy 281.887723 -437.548023)
			(xy 281.94168 -437.562129) (xy 281.993009 -437.583941) (xy 282.040615 -437.612995) (xy 282.083483 -437.64867)
			(xy 282.1207 -437.690207) (xy 282.151473 -437.73672) (xy 282.175145 -437.787217) (xy 282.191213 -437.840624)
			(xy 282.199333 -437.8958) (xy 282.199842 -437.923686) (xy 282.199333 -437.951572) (xy 282.191213 -438.006748)
			(xy 282.175145 -438.060155) (xy 282.151473 -438.110652) (xy 282.1207 -438.157165) (xy 282.083483 -438.198702)
			(xy 282.040615 -438.234377) (xy 281.993009 -438.263431) (xy 281.94168 -438.285243) (xy 281.887723 -438.299349)
			(xy 281.832286 -438.305449) (xy 281.776552 -438.303412) (xy 281.721709 -438.293282) (xy 281.668925 -438.275275)
			(xy 281.619325 -438.249774) (xy 281.573967 -438.217323) (xy 281.533818 -438.178614) (xy 281.499732 -438.134471)
			(xy 281.472436 -438.085836) (xy 281.452513 -438.033745) (xy 281.440387 -437.979308) (xy 281.436316 -437.923686)
			(xy 277.007601 -437.923686) (xy 276.965989 -437.968887) (xy 276.917852 -438.009654) (xy 276.865042 -438.044154)
			(xy 276.80837 -438.071857) (xy 276.748707 -438.092338) (xy 276.686969 -438.105281) (xy 276.624103 -438.110488)
			(xy 276.561077 -438.107879) (xy 276.498857 -438.097495) (xy 276.4384 -438.079494) (xy 276.380633 -438.054153)
			(xy 276.326444 -438.021861) (xy 276.276666 -437.983114) (xy 276.232063 -437.938508) (xy 276.19332 -437.888727)
			(xy 276.161032 -437.834537) (xy 276.135695 -437.776769) (xy 276.117698 -437.71631) (xy 276.107317 -437.654089)
			(xy 276.104713 -437.591063) (xy 193.353867 -437.591063) (xy 193.35344 -437.629636) (xy 193.345389 -437.720374)
			(xy 193.32935 -437.810046) (xy 193.305449 -437.89795) (xy 193.273872 -437.983397) (xy 193.234867 -438.06572)
			(xy 193.188738 -438.144272) (xy 193.135848 -438.218441) (xy 193.07661 -438.287645) (xy 193.011488 -438.351342)
			(xy 192.949936 -438.401714) (xy 276.993602 -438.401714) (xy 276.997673 -438.346092) (xy 277.009799 -438.291655)
			(xy 277.029722 -438.239564) (xy 277.057018 -438.190929) (xy 277.091104 -438.146786) (xy 277.131253 -438.108077)
			(xy 277.176611 -438.075626) (xy 277.226211 -438.050125) (xy 277.278995 -438.032118) (xy 277.333838 -438.021988)
			(xy 277.389572 -438.019951) (xy 277.445009 -438.026051) (xy 277.498966 -438.040157) (xy 277.550295 -438.061969)
			(xy 277.597901 -438.091023) (xy 277.640769 -438.126698) (xy 277.677986 -438.168235) (xy 277.708759 -438.214748)
			(xy 277.732431 -438.265245) (xy 277.748499 -438.318652) (xy 277.756619 -438.373828) (xy 277.757128 -438.401714)
			(xy 277.756619 -438.4296) (xy 277.748499 -438.484776) (xy 277.732431 -438.538183) (xy 277.708759 -438.58868)
			(xy 277.677986 -438.635193) (xy 277.640769 -438.67673) (xy 277.597901 -438.712405) (xy 277.550295 -438.741459)
			(xy 277.498966 -438.763271) (xy 277.445009 -438.777377) (xy 277.389572 -438.783477) (xy 277.333838 -438.78144)
			(xy 277.278995 -438.77131) (xy 277.226211 -438.753303) (xy 277.176611 -438.727802) (xy 277.131253 -438.695351)
			(xy 277.091104 -438.656642) (xy 277.057018 -438.612499) (xy 277.029722 -438.563864) (xy 277.009799 -438.511773)
			(xy 276.997673 -438.457336) (xy 276.993602 -438.401714) (xy 192.949936 -438.401714) (xy 192.94099 -438.409035)
			(xy 192.86567 -438.460272) (xy 192.786116 -438.504651) (xy 192.702951 -438.541825) (xy 192.616826 -438.571504)
			(xy 192.528415 -438.593455) (xy 192.43841 -438.607506) (xy 192.347515 -438.613548) (xy 192.256442 -438.611533)
			(xy 192.165904 -438.601476) (xy 192.076609 -438.583458) (xy 191.989255 -438.557617) (xy 191.904527 -438.524158)
			(xy 191.823088 -438.483341) (xy 191.745575 -438.435487) (xy 191.672595 -438.380969) (xy 191.604718 -438.320214)
			(xy 191.542477 -438.253698) (xy 191.486358 -438.181942) (xy 191.4368 -438.105506) (xy 191.394192 -438.02499)
			(xy 191.358866 -437.941023) (xy 191.3311 -437.854263) (xy 191.31111 -437.765388) (xy 191.299053 -437.675094)
			(xy 191.295024 -437.584088) (xy 184.633554 -437.584088) (xy 184.564932 -437.746675) (xy 184.475385 -437.937223)
			(xy 184.378302 -438.124043) (xy 184.273837 -438.306838) (xy 184.162158 -438.485317) (xy 184.043441 -438.659194)
			(xy 183.917877 -438.828193) (xy 183.785666 -438.992044) (xy 183.647019 -439.150486) (xy 183.574944 -439.227214)
			(xy 183.56453 -439.23839) (xy 183.559196 -439.268108) (xy 183.602122 -439.36793) (xy 183.606455 -439.376855)
			(xy 183.620592 -439.390746) (xy 183.638947 -439.398221) (xy 183.648858 -439.398664) (xy 277.021036 -439.398664)
			(xy 277.031102 -439.399095) (xy 277.049691 -439.406826) (xy 277.057104 -439.41365) (xy 277.48992 -439.846466)
			(xy 277.491952 -439.848498) (xy 277.540974 -439.89371) (xy 277.548325 -439.900191) (xy 277.566489 -439.907501)
			(xy 277.57628 -439.907934) (xy 278.088598 -439.907934) (xy 278.098667 -439.90751) (xy 278.117266 -439.899788)
			(xy 278.124666 -439.892948) (xy 278.16556 -439.852054) (xy 278.172959 -439.845211) (xy 278.191558 -439.83749)
			(xy 278.201628 -439.837068) (xy 278.909272 -439.837068) (xy 278.927814 -439.844942) (xy 278.934926 -439.852054)
			(xy 285.241238 -439.852054) (xy 285.249874 -439.851292) (xy 285.257389 -439.849685) (xy 285.271069 -439.8427)
			(xy 285.276798 -439.837576) (xy 286.546036 -438.568338) (xy 286.55288 -438.560939) (xy 286.560602 -438.54234)
			(xy 286.561022 -438.53227) (xy 286.561022 -431.237136) (xy 286.561457 -431.227071) (xy 286.569191 -431.208486)
			(xy 286.576008 -431.201068) (xy 290.286694 -427.490382) (xy 290.294088 -427.483526) (xy 290.312687 -427.475776)
			(xy 290.322762 -427.475396) (xy 292.053518 -427.475396) (xy 292.067521 -427.474911) (xy 292.094454 -427.467225)
			(xy 292.11829 -427.452517) (xy 292.137239 -427.431892) (xy 292.149878 -427.406898) (xy 292.15526 -427.379412)
			(xy 292.15461 -427.365414) (xy 292.152832 -427.322996) (xy 292.152832 -427.322742) (xy 292.153334 -427.290765)
			(xy 292.161349 -427.227315) (xy 292.177254 -427.16537) (xy 292.200797 -427.105908) (xy 292.231607 -427.049864)
			(xy 292.269199 -426.998124) (xy 292.312978 -426.951504) (xy 292.362256 -426.910738) (xy 292.416254 -426.87647)
			(xy 292.474121 -426.849239) (xy 292.534945 -426.829476) (xy 292.597766 -426.817493) (xy 292.661594 -426.813477)
			(xy 292.725422 -426.817493) (xy 292.788243 -426.829476) (xy 292.849067 -426.849239) (xy 292.906934 -426.87647)
			(xy 292.960932 -426.910738) (xy 293.01021 -426.951504) (xy 293.053989 -426.998124) (xy 293.091581 -427.049864)
			(xy 293.122391 -427.105908) (xy 293.145934 -427.16537) (xy 293.161839 -427.227315) (xy 293.169854 -427.290765)
			(xy 293.170356 -427.322742) (xy 293.170356 -427.322996) (xy 293.168578 -427.365414) (xy 293.167864 -427.379414)
			(xy 293.173231 -427.406919) (xy 293.185874 -427.431928) (xy 293.20484 -427.452558) (xy 293.228701 -427.467253)
			(xy 293.255659 -427.474907) (xy 293.26967 -427.475396) (xy 293.902892 -427.475396) (xy 293.916474 -427.474968)
			(xy 293.942679 -427.467812) (xy 293.966072 -427.454004) (xy 293.985 -427.43452) (xy 293.998125 -427.410736)
			(xy 294.004519 -427.384335) (xy 294.004492 -427.370748) (xy 294.004238 -427.355) (xy 294.004238 -427.354746)
			(xy 294.004652 -427.325106) (xy 294.011542 -427.266228) (xy 294.025233 -427.20855) (xy 294.045539 -427.152856)
			(xy 294.072186 -427.099903) (xy 294.10481 -427.050407) (xy 294.14297 -427.005043) (xy 294.164258 -426.984414)
			(xy 294.174005 -426.974604) (xy 294.188308 -426.950949) (xy 294.195733 -426.924322) (xy 294.195733 -426.896678)
			(xy 294.188308 -426.870051) (xy 294.174005 -426.846396) (xy 294.164258 -426.836586) (xy 294.139486 -426.812451)
			(xy 294.09603 -426.758648) (xy 294.060258 -426.699458) (xy 294.032827 -426.63597) (xy 294.014242 -426.569353)
			(xy 294.004846 -426.500834) (xy 294.004238 -426.466254) (xy 294.004238 -426.466) (xy 294.00474 -426.434023)
			(xy 294.012755 -426.370573) (xy 294.02866 -426.308628) (xy 294.052203 -426.249166) (xy 294.083013 -426.193122)
			(xy 294.120605 -426.141382) (xy 294.164384 -426.094762) (xy 294.213662 -426.053996) (xy 294.26766 -426.019728)
			(xy 294.325527 -425.992497) (xy 294.386351 -425.972734) (xy 294.449172 -425.960751) (xy 294.513 -425.956735)
			(xy 294.576828 -425.960751) (xy 294.639649 -425.972734) (xy 294.700473 -425.992497) (xy 294.75834 -426.019728)
			(xy 294.812338 -426.053996) (xy 294.861616 -426.094762) (xy 294.905395 -426.141382) (xy 294.942987 -426.193122)
			(xy 294.973797 -426.249166) (xy 294.99734 -426.308628) (xy 295.013245 -426.370573) (xy 295.02126 -426.434023)
			(xy 295.021762 -426.466) (xy 295.021762 -426.466254) (xy 295.021348 -426.495894) (xy 295.014458 -426.554772)
			(xy 295.000767 -426.61245) (xy 294.980461 -426.668144) (xy 294.953814 -426.721097) (xy 294.92119 -426.770593)
			(xy 294.88303 -426.815957) (xy 294.874586 -426.82414) (xy 302.54143 -426.82414) (xy 302.545501 -426.768518)
			(xy 302.557627 -426.714081) (xy 302.57755 -426.66199) (xy 302.604846 -426.613355) (xy 302.638932 -426.569212)
			(xy 302.679081 -426.530503) (xy 302.724439 -426.498052) (xy 302.774039 -426.472551) (xy 302.826823 -426.454544)
			(xy 302.881666 -426.444414) (xy 302.9374 -426.442377) (xy 302.992837 -426.448477) (xy 303.046794 -426.462583)
			(xy 303.098123 -426.484395) (xy 303.145729 -426.513449) (xy 303.188597 -426.549124) (xy 303.225814 -426.590661)
			(xy 303.256587 -426.637174) (xy 303.280259 -426.687671) (xy 303.296327 -426.741078) (xy 303.304447 -426.796254)
			(xy 303.304956 -426.82414) (xy 303.304447 -426.852026) (xy 303.296327 -426.907202) (xy 303.282802 -426.952156)
			(xy 303.718976 -426.952156) (xy 303.719478 -426.920195) (xy 303.727489 -426.856777) (xy 303.743386 -426.794863)
			(xy 303.766918 -426.73543) (xy 303.797712 -426.679415) (xy 303.835285 -426.6277) (xy 303.879042 -426.581103)
			(xy 303.928295 -426.540358) (xy 303.982266 -426.506107) (xy 304.040105 -426.47889) (xy 304.100898 -426.459137)
			(xy 304.163688 -426.447159) (xy 304.227484 -426.443146) (xy 304.29128 -426.447159) (xy 304.35407 -426.459137)
			(xy 304.414863 -426.47889) (xy 304.472702 -426.506107) (xy 304.526673 -426.540358) (xy 304.575926 -426.581103)
			(xy 304.619683 -426.6277) (xy 304.657256 -426.679415) (xy 304.68805 -426.73543) (xy 304.711582 -426.794863)
			(xy 304.727479 -426.856777) (xy 304.73549 -426.920195) (xy 304.735992 -426.952156) (xy 304.735992 -426.955712)
			(xy 304.736351 -426.966522) (xy 304.745063 -426.986302) (xy 304.761148 -427.000738) (xy 304.771298 -427.00448)
			(xy 304.801619 -427.014753) (xy 304.859597 -427.041904) (xy 304.913707 -427.07612) (xy 304.963094 -427.116858)
			(xy 305.006975 -427.163474) (xy 305.044656 -427.215231) (xy 305.075541 -427.271309) (xy 305.099142 -427.330821)
			(xy 305.115084 -427.392825) (xy 305.123115 -427.45634) (xy 305.123596 -427.48835) (xy 305.123094 -427.520311)
			(xy 305.115083 -427.583729) (xy 305.099186 -427.645643) (xy 305.075654 -427.705076) (xy 305.04486 -427.761091)
			(xy 305.007287 -427.812806) (xy 304.96353 -427.859403) (xy 304.914277 -427.900148) (xy 304.860306 -427.934399)
			(xy 304.802467 -427.961616) (xy 304.741674 -427.981369) (xy 304.678884 -427.993347) (xy 304.615088 -427.997361)
			(xy 304.551292 -427.993347) (xy 304.488502 -427.981369) (xy 304.427709 -427.961616) (xy 304.36987 -427.934399)
			(xy 304.315899 -427.900148) (xy 304.266646 -427.859403) (xy 304.222889 -427.812806) (xy 304.185316 -427.761091)
			(xy 304.154522 -427.705076) (xy 304.13099 -427.645643) (xy 304.115093 -427.583729) (xy 304.107082 -427.520311)
			(xy 304.10658 -427.48835) (xy 304.10658 -427.484794) (xy 304.106235 -427.473981) (xy 304.09752 -427.454199)
			(xy 304.081428 -427.439764) (xy 304.071274 -427.436026) (xy 304.040949 -427.425765) (xy 303.982972 -427.398611)
			(xy 303.928863 -427.364393) (xy 303.879477 -427.323653) (xy 303.835597 -427.277035) (xy 303.797916 -427.225277)
			(xy 303.767031 -427.169199) (xy 303.743431 -427.109686) (xy 303.727489 -427.047682) (xy 303.719457 -426.984167)
			(xy 303.718976 -426.952156) (xy 303.282802 -426.952156) (xy 303.280259 -426.960609) (xy 303.256587 -427.011106)
			(xy 303.225814 -427.057619) (xy 303.188597 -427.099156) (xy 303.145729 -427.134831) (xy 303.098123 -427.163885)
			(xy 303.046794 -427.185697) (xy 302.992837 -427.199803) (xy 302.9374 -427.205903) (xy 302.881666 -427.203866)
			(xy 302.826823 -427.193736) (xy 302.774039 -427.175729) (xy 302.724439 -427.150228) (xy 302.679081 -427.117777)
			(xy 302.638932 -427.079068) (xy 302.604846 -427.034925) (xy 302.57755 -426.98629) (xy 302.557627 -426.934199)
			(xy 302.545501 -426.879762) (xy 302.54143 -426.82414) (xy 294.874586 -426.82414) (xy 294.861742 -426.836586)
			(xy 294.851995 -426.846396) (xy 294.837692 -426.870051) (xy 294.830267 -426.896678) (xy 294.830267 -426.924322)
			(xy 294.837692 -426.950949) (xy 294.851995 -426.974604) (xy 294.861742 -426.984414) (xy 294.886514 -427.008549)
			(xy 294.92997 -427.062352) (xy 294.965742 -427.121542) (xy 294.993173 -427.18503) (xy 295.011758 -427.251647)
			(xy 295.021154 -427.320166) (xy 295.021762 -427.354746) (xy 295.021762 -427.355) (xy 295.021508 -427.370748)
			(xy 295.02153 -427.384333) (xy 295.025293 -427.399915) (xy 301.564796 -427.399915) (xy 301.564796 -427.335993)
			(xy 301.572807 -427.272575) (xy 301.588704 -427.210661) (xy 301.612236 -427.151228) (xy 301.64303 -427.095213)
			(xy 301.680603 -427.043498) (xy 301.72436 -426.996901) (xy 301.773613 -426.956156) (xy 301.827584 -426.921905)
			(xy 301.885423 -426.894688) (xy 301.946216 -426.874935) (xy 302.009006 -426.862957) (xy 302.072802 -426.858944)
			(xy 302.136598 -426.862957) (xy 302.199388 -426.874935) (xy 302.260181 -426.894688) (xy 302.31802 -426.921905)
			(xy 302.371991 -426.956156) (xy 302.421244 -426.996901) (xy 302.465001 -427.043498) (xy 302.502574 -427.095213)
			(xy 302.533368 -427.151228) (xy 302.5569 -427.210661) (xy 302.572797 -427.272575) (xy 302.580808 -427.335993)
			(xy 302.58131 -427.367954) (xy 302.580808 -427.399915) (xy 302.572797 -427.463333) (xy 302.5569 -427.525247)
			(xy 302.533368 -427.58468) (xy 302.502574 -427.640695) (xy 302.465001 -427.69241) (xy 302.421244 -427.739007)
			(xy 302.371991 -427.779752) (xy 302.31802 -427.814003) (xy 302.260181 -427.84122) (xy 302.199388 -427.860973)
			(xy 302.136598 -427.872951) (xy 302.072802 -427.876965) (xy 302.009006 -427.872951) (xy 301.946216 -427.860973)
			(xy 301.885423 -427.84122) (xy 301.827584 -427.814003) (xy 301.773613 -427.779752) (xy 301.72436 -427.739007)
			(xy 301.680603 -427.69241) (xy 301.64303 -427.640695) (xy 301.612236 -427.58468) (xy 301.588704 -427.525247)
			(xy 301.572807 -427.463333) (xy 301.564796 -427.399915) (xy 295.025293 -427.399915) (xy 295.027904 -427.41073)
			(xy 295.041016 -427.434511) (xy 295.059938 -427.453989) (xy 295.083328 -427.467786) (xy 295.10953 -427.474922)
			(xy 295.123108 -427.475396) (xy 297.44035 -427.475396) (xy 297.450416 -427.475828) (xy 297.469008 -427.483555)
			(xy 297.476418 -427.490382) (xy 298.407328 -428.421292) (xy 299.06671 -428.421292) (xy 299.070781 -428.36567)
			(xy 299.082907 -428.311233) (xy 299.10283 -428.259142) (xy 299.130126 -428.210507) (xy 299.164212 -428.166364)
			(xy 299.204361 -428.127655) (xy 299.249719 -428.095204) (xy 299.299319 -428.069703) (xy 299.352103 -428.051696)
			(xy 299.406946 -428.041566) (xy 299.46268 -428.039529) (xy 299.518117 -428.045629) (xy 299.572074 -428.059735)
			(xy 299.623403 -428.081547) (xy 299.639875 -428.0916) (xy 305.714908 -428.0916) (xy 305.715387 -428.060689)
			(xy 305.722888 -427.999325) (xy 305.737765 -427.939321) (xy 305.759801 -427.88156) (xy 305.788671 -427.826894)
			(xy 305.82395 -427.776127) (xy 305.844194 -427.752764) (xy 305.850544 -427.745906) (xy 305.857148 -427.728634)
			(xy 305.857148 -427.641766) (xy 305.850544 -427.624494) (xy 305.844194 -427.617636) (xy 305.823947 -427.594275)
			(xy 305.788665 -427.54351) (xy 305.759794 -427.488844) (xy 305.737761 -427.431082) (xy 305.722889 -427.371077)
			(xy 305.715398 -427.309711) (xy 305.715398 -427.247889) (xy 305.722889 -427.186523) (xy 305.737761 -427.126518)
			(xy 305.759794 -427.068756) (xy 305.788665 -427.01409) (xy 305.823947 -426.963325) (xy 305.844194 -426.939964)
			(xy 305.850544 -426.933106) (xy 305.857148 -426.915834) (xy 305.857148 -426.828966) (xy 305.850544 -426.811694)
			(xy 305.844194 -426.804836) (xy 305.823947 -426.781475) (xy 305.788665 -426.73071) (xy 305.759794 -426.676044)
			(xy 305.737761 -426.618282) (xy 305.722889 -426.558277) (xy 305.715398 -426.496911) (xy 305.715398 -426.435089)
			(xy 305.722889 -426.373723) (xy 305.737761 -426.313718) (xy 305.759794 -426.255956) (xy 305.788665 -426.20129)
			(xy 305.823947 -426.150525) (xy 305.844194 -426.127164) (xy 305.850544 -426.120306) (xy 305.857148 -426.103034)
			(xy 305.857148 -426.016166) (xy 305.850544 -425.998894) (xy 305.844194 -425.992036) (xy 305.823953 -425.968668)
			(xy 305.788659 -425.917909) (xy 305.759778 -425.863246) (xy 305.737736 -425.805486) (xy 305.722859 -425.745479)
			(xy 305.715364 -425.684112) (xy 305.714908 -425.6532) (xy 305.71541 -425.621239) (xy 305.723421 -425.557821)
			(xy 305.739318 -425.495907) (xy 305.76285 -425.436474) (xy 305.793644 -425.380459) (xy 305.831217 -425.328744)
			(xy 305.874974 -425.282147) (xy 305.924227 -425.241402) (xy 305.978198 -425.207151) (xy 306.036037 -425.179934)
			(xy 306.09683 -425.160181) (xy 306.15962 -425.148203) (xy 306.223416 -425.14419) (xy 306.287212 -425.148203)
			(xy 306.350002 -425.160181) (xy 306.410795 -425.179934) (xy 306.468634 -425.207151) (xy 306.522605 -425.241402)
			(xy 306.571858 -425.282147) (xy 306.615615 -425.328744) (xy 306.653188 -425.380459) (xy 306.683982 -425.436474)
			(xy 306.707514 -425.495907) (xy 306.723411 -425.557821) (xy 306.731422 -425.621239) (xy 306.731924 -425.6532)
			(xy 306.731462 -425.684111) (xy 306.723961 -425.745477) (xy 306.709081 -425.805482) (xy 306.687042 -425.863243)
			(xy 306.658168 -425.917909) (xy 306.622885 -425.968674) (xy 306.602638 -425.992036) (xy 306.596288 -425.998894)
			(xy 306.589684 -426.016166) (xy 306.589684 -426.103034) (xy 306.596288 -426.120306) (xy 306.602638 -426.127164)
			(xy 306.621556 -426.148922) (xy 306.654886 -426.195973) (xy 306.682672 -426.246495) (xy 306.704558 -426.299839)
			(xy 306.720262 -426.355319) (xy 306.72532 -426.383704) (xy 306.727218 -426.392803) (xy 306.736611 -426.408826)
			(xy 306.743608 -426.414946) (xy 306.767738 -426.43425) (xy 306.77518 -426.43976) (xy 306.792769 -426.445493)
			(xy 306.802028 -426.445426) (xy 306.820316 -426.444918) (xy 306.84757 -426.44534) (xy 306.901524 -426.4531)
			(xy 306.953825 -426.468459) (xy 307.003407 -426.491106) (xy 307.049261 -426.520578) (xy 307.090454 -426.556276)
			(xy 307.126148 -426.597473) (xy 307.155615 -426.64333) (xy 307.178255 -426.692915) (xy 307.193609 -426.745217)
			(xy 307.201363 -426.799171) (xy 307.201824 -426.826426) (xy 307.201402 -426.853229) (xy 307.193874 -426.906303)
			(xy 307.178997 -426.957803) (xy 307.157064 -427.006716) (xy 307.128506 -427.052081) (xy 307.093884 -427.093006)
			(xy 307.053879 -427.128687) (xy 307.009277 -427.158423) (xy 306.960955 -427.181629) (xy 306.909862 -427.197849)
			(xy 306.857003 -427.206764) (xy 306.830222 -427.207934) (xy 306.820316 -427.207934) (xy 306.803044 -427.2153)
			(xy 306.739544 -427.277276) (xy 306.73167 -427.294548) (xy 306.731162 -427.3042) (xy 306.728878 -427.33868)
			(xy 306.716147 -427.406598) (xy 306.699595 -427.456346) (xy 307.73827 -427.456346) (xy 307.742341 -427.400724)
			(xy 307.754467 -427.346287) (xy 307.77439 -427.294196) (xy 307.801686 -427.245561) (xy 307.835772 -427.201418)
			(xy 307.875921 -427.162709) (xy 307.921279 -427.130258) (xy 307.970879 -427.104757) (xy 308.023663 -427.08675)
			(xy 308.078506 -427.07662) (xy 308.13424 -427.074583) (xy 308.189677 -427.080683) (xy 308.243634 -427.094789)
			(xy 308.294963 -427.116601) (xy 308.342569 -427.145655) (xy 308.385437 -427.18133) (xy 308.422654 -427.222867)
			(xy 308.453427 -427.26938) (xy 308.477099 -427.319877) (xy 308.493167 -427.373284) (xy 308.501287 -427.42846)
			(xy 308.501796 -427.456346) (xy 308.501287 -427.484232) (xy 308.493167 -427.539408) (xy 308.477099 -427.592815)
			(xy 308.453427 -427.643312) (xy 308.422654 -427.689825) (xy 308.385437 -427.731362) (xy 308.342569 -427.767037)
			(xy 308.294963 -427.796091) (xy 308.243634 -427.817903) (xy 308.189677 -427.832009) (xy 308.13424 -427.838109)
			(xy 308.078506 -427.836072) (xy 308.023663 -427.825942) (xy 307.970879 -427.807935) (xy 307.921279 -427.782434)
			(xy 307.875921 -427.749983) (xy 307.835772 -427.711274) (xy 307.801686 -427.667131) (xy 307.77439 -427.618496)
			(xy 307.754467 -427.566405) (xy 307.742341 -427.511968) (xy 307.73827 -427.456346) (xy 306.699595 -427.456346)
			(xy 306.694331 -427.472166) (xy 306.663834 -427.534173) (xy 306.625217 -427.591478) (xy 306.602638 -427.617636)
			(xy 306.596288 -427.624494) (xy 306.589684 -427.641766) (xy 306.589684 -427.728634) (xy 306.596288 -427.745906)
			(xy 306.602638 -427.752764) (xy 306.622867 -427.776142) (xy 306.658165 -427.826897) (xy 306.687049 -427.881558)
			(xy 306.709093 -427.939317) (xy 306.723973 -427.999322) (xy 306.731468 -428.060689) (xy 306.731924 -428.0916)
			(xy 306.731422 -428.123561) (xy 306.723411 -428.186979) (xy 306.707514 -428.248893) (xy 306.683982 -428.308326)
			(xy 306.653188 -428.364341) (xy 306.615615 -428.416056) (xy 306.571858 -428.462653) (xy 306.522605 -428.503398)
			(xy 306.468634 -428.537649) (xy 306.410795 -428.564866) (xy 306.350002 -428.584619) (xy 306.287212 -428.596597)
			(xy 306.223416 -428.600611) (xy 306.15962 -428.596597) (xy 306.09683 -428.584619) (xy 306.036037 -428.564866)
			(xy 305.978198 -428.537649) (xy 305.924227 -428.503398) (xy 305.874974 -428.462653) (xy 305.831217 -428.416056)
			(xy 305.793644 -428.364341) (xy 305.76285 -428.308326) (xy 305.739318 -428.248893) (xy 305.723421 -428.186979)
			(xy 305.71541 -428.123561) (xy 305.714908 -428.0916) (xy 299.639875 -428.0916) (xy 299.671009 -428.110601)
			(xy 299.713877 -428.146276) (xy 299.751094 -428.187813) (xy 299.781867 -428.234326) (xy 299.805539 -428.284823)
			(xy 299.821607 -428.33823) (xy 299.829727 -428.393406) (xy 299.830236 -428.421292) (xy 299.829727 -428.449178)
			(xy 299.821607 -428.504354) (xy 299.805539 -428.557761) (xy 299.781867 -428.608258) (xy 299.751094 -428.654771)
			(xy 299.713877 -428.696308) (xy 299.671009 -428.731983) (xy 299.623403 -428.761037) (xy 299.572074 -428.782849)
			(xy 299.518117 -428.796955) (xy 299.46268 -428.803055) (xy 299.406946 -428.801018) (xy 299.352103 -428.790888)
			(xy 299.299319 -428.772881) (xy 299.249719 -428.74738) (xy 299.204361 -428.714929) (xy 299.164212 -428.67622)
			(xy 299.130126 -428.632077) (xy 299.10283 -428.583442) (xy 299.082907 -428.531351) (xy 299.070781 -428.476914)
			(xy 299.06671 -428.421292) (xy 298.407328 -428.421292) (xy 298.806616 -428.82058) (xy 303.904902 -428.82058)
			(xy 303.908973 -428.764958) (xy 303.921099 -428.710521) (xy 303.941022 -428.65843) (xy 303.968318 -428.609795)
			(xy 304.002404 -428.565652) (xy 304.042553 -428.526943) (xy 304.087911 -428.494492) (xy 304.137511 -428.468991)
			(xy 304.190295 -428.450984) (xy 304.245138 -428.440854) (xy 304.300872 -428.438817) (xy 304.356309 -428.444917)
			(xy 304.410266 -428.459023) (xy 304.461595 -428.480835) (xy 304.509201 -428.509889) (xy 304.552069 -428.545564)
			(xy 304.589286 -428.587101) (xy 304.620059 -428.633614) (xy 304.643731 -428.684111) (xy 304.659799 -428.737518)
			(xy 304.667919 -428.792694) (xy 304.668428 -428.82058) (xy 304.667919 -428.848466) (xy 304.659799 -428.903642)
			(xy 304.643731 -428.957049) (xy 304.620059 -429.007546) (xy 304.589286 -429.054059) (xy 304.552069 -429.095596)
			(xy 304.509201 -429.131271) (xy 304.461595 -429.160325) (xy 304.410266 -429.182137) (xy 304.356309 -429.196243)
			(xy 304.300872 -429.202343) (xy 304.245138 -429.200306) (xy 304.190295 -429.190176) (xy 304.137511 -429.172169)
			(xy 304.087911 -429.146668) (xy 304.042553 -429.114217) (xy 304.002404 -429.075508) (xy 303.968318 -429.031365)
			(xy 303.941022 -428.98273) (xy 303.921099 -428.930639) (xy 303.908973 -428.876202) (xy 303.904902 -428.82058)
			(xy 298.806616 -428.82058) (xy 299.535342 -429.549306) (xy 299.542194 -429.556702) (xy 299.549935 -429.575301)
			(xy 299.550328 -429.585374) (xy 299.550328 -429.606964) (xy 301.74133 -429.606964) (xy 301.745401 -429.551342)
			(xy 301.757527 -429.496905) (xy 301.77745 -429.444814) (xy 301.804746 -429.396179) (xy 301.838832 -429.352036)
			(xy 301.878981 -429.313327) (xy 301.924339 -429.280876) (xy 301.973939 -429.255375) (xy 302.026723 -429.237368)
			(xy 302.081566 -429.227238) (xy 302.1373 -429.225201) (xy 302.192737 -429.231301) (xy 302.246694 -429.245407)
			(xy 302.298023 -429.267219) (xy 302.345629 -429.296273) (xy 302.388497 -429.331948) (xy 302.425714 -429.373485)
			(xy 302.456487 -429.419998) (xy 302.480159 -429.470495) (xy 302.496227 -429.523902) (xy 302.504347 -429.579078)
			(xy 302.504856 -429.606964) (xy 302.504814 -429.60925) (xy 305.638198 -429.60925) (xy 305.642269 -429.553628)
			(xy 305.654395 -429.499191) (xy 305.674318 -429.4471) (xy 305.701614 -429.398465) (xy 305.7357 -429.354322)
			(xy 305.775849 -429.315613) (xy 305.821207 -429.283162) (xy 305.870807 -429.257661) (xy 305.923591 -429.239654)
			(xy 305.978434 -429.229524) (xy 306.034168 -429.227487) (xy 306.089605 -429.233587) (xy 306.143562 -429.247693)
			(xy 306.194891 -429.269505) (xy 306.242497 -429.298559) (xy 306.285365 -429.334234) (xy 306.322582 -429.375771)
			(xy 306.353355 -429.422284) (xy 306.377027 -429.472781) (xy 306.393095 -429.526188) (xy 306.401215 -429.581364)
			(xy 306.401724 -429.60925) (xy 306.401215 -429.637136) (xy 306.393095 -429.692312) (xy 306.377027 -429.745719)
			(xy 306.353355 -429.796216) (xy 306.322582 -429.842729) (xy 306.285365 -429.884266) (xy 306.242497 -429.919941)
			(xy 306.194891 -429.948995) (xy 306.143562 -429.970807) (xy 306.089605 -429.984913) (xy 306.034168 -429.991013)
			(xy 305.978434 -429.988976) (xy 305.923591 -429.978846) (xy 305.870807 -429.960839) (xy 305.821207 -429.935338)
			(xy 305.775849 -429.902887) (xy 305.7357 -429.864178) (xy 305.701614 -429.820035) (xy 305.674318 -429.7714)
			(xy 305.654395 -429.719309) (xy 305.642269 -429.664872) (xy 305.638198 -429.60925) (xy 302.504814 -429.60925)
			(xy 302.504347 -429.63485) (xy 302.496227 -429.690026) (xy 302.480159 -429.743433) (xy 302.456487 -429.79393)
			(xy 302.425714 -429.840443) (xy 302.388497 -429.88198) (xy 302.345629 -429.917655) (xy 302.298023 -429.946709)
			(xy 302.246694 -429.968521) (xy 302.192737 -429.982627) (xy 302.1373 -429.988727) (xy 302.081566 -429.98669)
			(xy 302.026723 -429.97656) (xy 301.973939 -429.958553) (xy 301.924339 -429.933052) (xy 301.878981 -429.900601)
			(xy 301.838832 -429.861892) (xy 301.804746 -429.817749) (xy 301.77745 -429.769114) (xy 301.757527 -429.717023)
			(xy 301.745401 -429.662586) (xy 301.74133 -429.606964) (xy 299.550328 -429.606964) (xy 299.550328 -431.101246)
			(xy 300.779686 -431.101246) (xy 300.783757 -431.045624) (xy 300.795883 -430.991187) (xy 300.815806 -430.939096)
			(xy 300.843102 -430.890461) (xy 300.877188 -430.846318) (xy 300.917337 -430.807609) (xy 300.962695 -430.775158)
			(xy 301.012295 -430.749657) (xy 301.065079 -430.73165) (xy 301.119922 -430.72152) (xy 301.175656 -430.719483)
			(xy 301.231093 -430.725583) (xy 301.28505 -430.739689) (xy 301.336379 -430.761501) (xy 301.383985 -430.790555)
			(xy 301.426853 -430.82623) (xy 301.46407 -430.867767) (xy 301.494843 -430.91428) (xy 301.518515 -430.964777)
			(xy 301.534583 -431.018184) (xy 301.542703 -431.07336) (xy 301.543212 -431.101246) (xy 301.542703 -431.129132)
			(xy 301.534583 -431.184308) (xy 301.518515 -431.237715) (xy 301.494843 -431.288212) (xy 301.46407 -431.334725)
			(xy 301.426853 -431.376262) (xy 301.383985 -431.411937) (xy 301.336379 -431.440991) (xy 301.28505 -431.462803)
			(xy 301.231093 -431.476909) (xy 301.175656 -431.483009) (xy 301.119922 -431.480972) (xy 301.065079 -431.470842)
			(xy 301.012295 -431.452835) (xy 300.962695 -431.427334) (xy 300.917337 -431.394883) (xy 300.877188 -431.356174)
			(xy 300.843102 -431.312031) (xy 300.815806 -431.263396) (xy 300.795883 -431.211305) (xy 300.783757 -431.156868)
			(xy 300.779686 -431.101246) (xy 299.550328 -431.101246) (xy 299.550328 -432.678797) (xy 302.415442 -432.678797)
			(xy 302.415442 -432.614875) (xy 302.423453 -432.551457) (xy 302.43935 -432.489543) (xy 302.462882 -432.43011)
			(xy 302.493676 -432.374095) (xy 302.531249 -432.32238) (xy 302.575006 -432.275783) (xy 302.624259 -432.235038)
			(xy 302.67823 -432.200787) (xy 302.736069 -432.17357) (xy 302.796862 -432.153817) (xy 302.859652 -432.141839)
			(xy 302.923448 -432.137826) (xy 302.987244 -432.141839) (xy 303.050034 -432.153817) (xy 303.110827 -432.17357)
			(xy 303.168666 -432.200787) (xy 303.222637 -432.235038) (xy 303.27189 -432.275783) (xy 303.315647 -432.32238)
			(xy 303.35322 -432.374095) (xy 303.384014 -432.43011) (xy 303.407546 -432.489543) (xy 303.423443 -432.551457)
			(xy 303.431454 -432.614875) (xy 303.43179 -432.636237) (xy 303.684535 -432.636237) (xy 303.68975 -432.573375)
			(xy 303.702699 -432.511641) (xy 303.723186 -432.451982) (xy 303.750895 -432.395316) (xy 303.7854 -432.342512)
			(xy 303.826171 -432.294382) (xy 303.872583 -432.251665) (xy 303.923922 -432.215017) (xy 303.979401 -432.185)
			(xy 304.038166 -432.162076) (xy 304.099315 -432.146597) (xy 304.161909 -432.138801) (xy 304.193448 -432.138328)
			(xy 304.235104 -432.140106) (xy 304.249462 -432.140721) (xy 304.277604 -432.134979) (xy 304.303037 -432.121633)
			(xy 304.323752 -432.101738) (xy 304.338114 -432.076865) (xy 304.344989 -432.048978) (xy 304.343834 -432.020279)
			(xy 304.339752 -432.006502) (xy 304.330484 -431.976944) (xy 304.320526 -431.915807) (xy 304.31994 -431.884836)
			(xy 304.320426 -431.857585) (xy 304.328182 -431.803637) (xy 304.343537 -431.751342) (xy 304.366179 -431.701765)
			(xy 304.395645 -431.655915) (xy 304.431336 -431.614724) (xy 304.472527 -431.579033) (xy 304.518377 -431.549567)
			(xy 304.567954 -431.526925) (xy 304.620249 -431.51157) (xy 304.674197 -431.503814) (xy 304.728699 -431.503814)
			(xy 304.782647 -431.51157) (xy 304.834942 -431.526925) (xy 304.884519 -431.549567) (xy 304.930369 -431.579033)
			(xy 304.97156 -431.614724) (xy 305.007251 -431.655915) (xy 305.036717 -431.701765) (xy 305.059359 -431.751342)
			(xy 305.074714 -431.803637) (xy 305.08247 -431.857585) (xy 305.082956 -431.884836) (xy 305.08246 -431.913464)
			(xy 305.073885 -431.970075) (xy 305.056949 -432.024769) (xy 305.03203 -432.076318) (xy 304.99969 -432.123566)
			(xy 304.960653 -432.165452) (xy 304.915797 -432.201035) (xy 304.866127 -432.229517) (xy 304.81276 -432.250259)
			(xy 304.756892 -432.262793) (xy 304.728372 -432.265328) (xy 304.714067 -432.266889) (xy 304.687081 -432.276826)
			(xy 304.663937 -432.293896) (xy 304.646472 -432.316743) (xy 304.636072 -432.343554) (xy 304.633562 -432.372203)
			(xy 304.639141 -432.400414) (xy 304.645314 -432.41341) (xy 304.658848 -432.440547) (xy 304.680059 -432.497361)
			(xy 304.694356 -432.556296) (xy 304.701536 -432.616514) (xy 304.701841 -432.638563) (xy 306.311421 -432.638563)
			(xy 306.316632 -432.575699) (xy 306.329579 -432.513963) (xy 306.350063 -432.454302) (xy 306.377769 -432.397634)
			(xy 306.412272 -432.344827) (xy 306.453041 -432.296694) (xy 306.499452 -432.253973) (xy 306.55079 -432.217321)
			(xy 306.606267 -432.1873) (xy 306.665032 -432.164372) (xy 306.726181 -432.148889) (xy 306.788776 -432.141089)
			(xy 306.820316 -432.140614) (xy 306.8447 -432.141122) (xy 306.858749 -432.141367) (xy 306.886121 -432.135072)
			(xy 306.910737 -432.121547) (xy 306.930729 -432.101819) (xy 306.94458 -432.077386) (xy 306.951239 -432.0501)
			(xy 306.9502 -432.022032) (xy 306.9463 -432.008534) (xy 306.937674 -431.979965) (xy 306.928358 -431.921023)
			(xy 306.927758 -431.891186) (xy 306.928244 -431.863935) (xy 306.936 -431.809987) (xy 306.951355 -431.757692)
			(xy 306.973997 -431.708115) (xy 307.003463 -431.662265) (xy 307.039154 -431.621074) (xy 307.080345 -431.585383)
			(xy 307.126195 -431.555917) (xy 307.175772 -431.533275) (xy 307.228067 -431.51792) (xy 307.282015 -431.510164)
			(xy 307.336517 -431.510164) (xy 307.390465 -431.51792) (xy 307.44276 -431.533275) (xy 307.492337 -431.555917)
			(xy 307.538187 -431.585383) (xy 307.579378 -431.621074) (xy 307.615069 -431.662265) (xy 307.644535 -431.708115)
			(xy 307.667177 -431.757692) (xy 307.682532 -431.809987) (xy 307.690288 -431.863935) (xy 307.690774 -431.891186)
			(xy 307.690297 -431.919032) (xy 307.682228 -431.974137) (xy 307.66623 -432.027481) (xy 307.642644 -432.077932)
			(xy 307.611971 -432.124416) (xy 307.574864 -432.165945) (xy 307.532111 -432.201635) (xy 307.484622 -432.230728)
			(xy 307.433406 -432.252604) (xy 307.379554 -432.266799) (xy 307.351938 -432.270408) (xy 307.338031 -432.27234)
			(xy 307.31205 -432.282967) (xy 307.289946 -432.300271) (xy 307.273395 -432.322943) (xy 307.263647 -432.349267)
			(xy 307.261442 -432.377251) (xy 307.266945 -432.404777) (xy 307.272944 -432.417474) (xy 307.286278 -432.444436)
			(xy 307.307191 -432.500836) (xy 307.321293 -432.559313) (xy 307.328387 -432.619046) (xy 307.328671 -432.638563)
			(xy 307.581421 -432.638563) (xy 307.586632 -432.575699) (xy 307.599579 -432.513963) (xy 307.620063 -432.454302)
			(xy 307.647769 -432.397634) (xy 307.682272 -432.344827) (xy 307.723041 -432.296694) (xy 307.769452 -432.253973)
			(xy 307.82079 -432.217321) (xy 307.876267 -432.1873) (xy 307.935032 -432.164372) (xy 307.996181 -432.148889)
			(xy 308.058776 -432.141089) (xy 308.090316 -432.140614) (xy 308.131972 -432.142392) (xy 308.146328 -432.143086)
			(xy 308.174475 -432.137327) (xy 308.19991 -432.123965) (xy 308.220625 -432.104057) (xy 308.234985 -432.079173)
			(xy 308.241859 -432.051277) (xy 308.240702 -432.02257) (xy 308.23662 -432.008788) (xy 308.227351 -431.97923)
			(xy 308.217393 -431.918093) (xy 308.216808 -431.887122) (xy 308.217294 -431.859871) (xy 308.22505 -431.805923)
			(xy 308.240405 -431.753628) (xy 308.263047 -431.704051) (xy 308.292513 -431.658201) (xy 308.328204 -431.61701)
			(xy 308.369395 -431.581319) (xy 308.415245 -431.551853) (xy 308.464822 -431.529211) (xy 308.517117 -431.513856)
			(xy 308.571065 -431.5061) (xy 308.625567 -431.5061) (xy 308.679515 -431.513856) (xy 308.73181 -431.529211)
			(xy 308.781387 -431.551853) (xy 308.827237 -431.581319) (xy 308.868428 -431.61701) (xy 308.904119 -431.658201)
			(xy 308.933585 -431.704051) (xy 308.956227 -431.753628) (xy 308.971582 -431.805923) (xy 308.979338 -431.859871)
			(xy 308.979824 -431.887122) (xy 308.979345 -431.915751) (xy 308.970771 -431.972364) (xy 308.953834 -432.02706)
			(xy 308.928915 -432.078612) (xy 308.896573 -432.125861) (xy 308.857534 -432.167747) (xy 308.812675 -432.20333)
			(xy 308.763002 -432.231811) (xy 308.709632 -432.25255) (xy 308.653762 -432.265081) (xy 308.62524 -432.267614)
			(xy 308.610936 -432.269172) (xy 308.583954 -432.279115) (xy 308.560814 -432.296187) (xy 308.543352 -432.319034)
			(xy 308.532952 -432.345843) (xy 308.530439 -432.374489) (xy 308.536012 -432.4027) (xy 308.542182 -432.415696)
			(xy 308.555709 -432.442837) (xy 308.576922 -432.499649) (xy 308.591221 -432.558583) (xy 308.598403 -432.6188)
			(xy 308.598824 -432.649122) (xy 308.598309 -432.680662) (xy 308.590504 -432.743256) (xy 308.575016 -432.804404)
			(xy 308.552084 -432.863167) (xy 308.522059 -432.918643) (xy 308.485403 -432.969978) (xy 308.442679 -433.016385)
			(xy 308.394543 -433.057151) (xy 308.341733 -433.09165) (xy 308.285063 -433.119352) (xy 308.2254 -433.139831)
			(xy 308.163663 -433.152774) (xy 308.100799 -433.15798) (xy 308.037774 -433.155371) (xy 307.975556 -433.144986)
			(xy 307.915099 -433.126985) (xy 307.857334 -433.101644) (xy 307.803147 -433.069353) (xy 307.75337 -433.030607)
			(xy 307.708768 -432.986001) (xy 307.670026 -432.936222) (xy 307.637738 -432.882032) (xy 307.612402 -432.824265)
			(xy 307.594405 -432.763807) (xy 307.584025 -432.701588) (xy 307.581421 -432.638563) (xy 307.328671 -432.638563)
			(xy 307.328824 -432.649122) (xy 307.328309 -432.680662) (xy 307.320504 -432.743256) (xy 307.305016 -432.804404)
			(xy 307.282084 -432.863167) (xy 307.252059 -432.918643) (xy 307.215403 -432.969978) (xy 307.172679 -433.016385)
			(xy 307.124543 -433.057151) (xy 307.071733 -433.09165) (xy 307.015063 -433.119352) (xy 306.9554 -433.139831)
			(xy 306.893663 -433.152774) (xy 306.830799 -433.15798) (xy 306.767774 -433.155371) (xy 306.705556 -433.144986)
			(xy 306.645099 -433.126985) (xy 306.587334 -433.101644) (xy 306.533147 -433.069353) (xy 306.48337 -433.030607)
			(xy 306.438768 -432.986001) (xy 306.400026 -432.936222) (xy 306.367738 -432.882032) (xy 306.342402 -432.824265)
			(xy 306.324405 -432.763807) (xy 306.314025 -432.701588) (xy 306.311421 -432.638563) (xy 304.701841 -432.638563)
			(xy 304.701956 -432.646836) (xy 304.701394 -432.678375) (xy 304.693587 -432.740968) (xy 304.678098 -432.802115)
			(xy 304.655165 -432.860876) (xy 304.625139 -432.916349) (xy 304.588482 -432.967682) (xy 304.545757 -433.014087)
			(xy 304.49762 -433.05485) (xy 304.444811 -433.089347) (xy 304.38814 -433.117046) (xy 304.328478 -433.137523)
			(xy 304.266742 -433.150463) (xy 304.203879 -433.155667) (xy 304.140855 -433.153055) (xy 304.078638 -433.142668)
			(xy 304.018184 -433.124664) (xy 303.960421 -433.099322) (xy 303.906236 -433.067029) (xy 303.856462 -433.028281)
			(xy 303.811863 -432.983675) (xy 303.773124 -432.933894) (xy 303.74084 -432.879704) (xy 303.715507 -432.821937)
			(xy 303.697513 -432.76148) (xy 303.687136 -432.699261) (xy 303.684535 -432.636237) (xy 303.43179 -432.636237)
			(xy 303.431956 -432.646836) (xy 303.431454 -432.678797) (xy 303.423443 -432.742215) (xy 303.407546 -432.804129)
			(xy 303.384014 -432.863562) (xy 303.35322 -432.919577) (xy 303.315647 -432.971292) (xy 303.27189 -433.017889)
			(xy 303.222637 -433.058634) (xy 303.168666 -433.092885) (xy 303.110827 -433.120102) (xy 303.050034 -433.139855)
			(xy 302.987244 -433.151833) (xy 302.923448 -433.155847) (xy 302.859652 -433.151833) (xy 302.796862 -433.139855)
			(xy 302.736069 -433.120102) (xy 302.67823 -433.092885) (xy 302.624259 -433.058634) (xy 302.575006 -433.017889)
			(xy 302.531249 -432.971292) (xy 302.493676 -432.919577) (xy 302.462882 -432.863562) (xy 302.43935 -432.804129)
			(xy 302.423453 -432.742215) (xy 302.415442 -432.678797) (xy 299.550328 -432.678797) (xy 299.550328 -433.614322)
			(xy 305.54752 -433.614322) (xy 305.551591 -433.5587) (xy 305.563717 -433.504263) (xy 305.58364 -433.452172)
			(xy 305.610936 -433.403537) (xy 305.645022 -433.359394) (xy 305.685171 -433.320685) (xy 305.730529 -433.288234)
			(xy 305.780129 -433.262733) (xy 305.832913 -433.244726) (xy 305.887756 -433.234596) (xy 305.94349 -433.232559)
			(xy 305.998927 -433.238659) (xy 306.052884 -433.252765) (xy 306.104213 -433.274577) (xy 306.112778 -433.279804)
			(xy 308.704232 -433.279804) (xy 308.708303 -433.224182) (xy 308.720429 -433.169745) (xy 308.740352 -433.117654)
			(xy 308.767648 -433.069019) (xy 308.801734 -433.024876) (xy 308.841883 -432.986167) (xy 308.887241 -432.953716)
			(xy 308.936841 -432.928215) (xy 308.989625 -432.910208) (xy 309.044468 -432.900078) (xy 309.100202 -432.898041)
			(xy 309.155639 -432.904141) (xy 309.209596 -432.918247) (xy 309.260925 -432.940059) (xy 309.308531 -432.969113)
			(xy 309.351399 -433.004788) (xy 309.388616 -433.046325) (xy 309.419389 -433.092838) (xy 309.443061 -433.143335)
			(xy 309.459129 -433.196742) (xy 309.467249 -433.251918) (xy 309.467758 -433.279804) (xy 309.467249 -433.30769)
			(xy 309.459129 -433.362866) (xy 309.443061 -433.416273) (xy 309.419389 -433.46677) (xy 309.388616 -433.513283)
			(xy 309.351399 -433.55482) (xy 309.308531 -433.590495) (xy 309.260925 -433.619549) (xy 309.209596 -433.641361)
			(xy 309.155639 -433.655467) (xy 309.100202 -433.661567) (xy 309.044468 -433.65953) (xy 308.989625 -433.6494)
			(xy 308.936841 -433.631393) (xy 308.887241 -433.605892) (xy 308.841883 -433.573441) (xy 308.801734 -433.534732)
			(xy 308.767648 -433.490589) (xy 308.740352 -433.441954) (xy 308.720429 -433.389863) (xy 308.708303 -433.335426)
			(xy 308.704232 -433.279804) (xy 306.112778 -433.279804) (xy 306.151819 -433.303631) (xy 306.194687 -433.339306)
			(xy 306.231904 -433.380843) (xy 306.262677 -433.427356) (xy 306.286349 -433.477853) (xy 306.302417 -433.53126)
			(xy 306.310537 -433.586436) (xy 306.311046 -433.614322) (xy 306.310537 -433.642208) (xy 306.302417 -433.697384)
			(xy 306.286349 -433.750791) (xy 306.262677 -433.801288) (xy 306.231904 -433.847801) (xy 306.194687 -433.889338)
			(xy 306.151819 -433.925013) (xy 306.104213 -433.954067) (xy 306.052884 -433.975879) (xy 305.998927 -433.989985)
			(xy 305.94349 -433.996085) (xy 305.887756 -433.994048) (xy 305.832913 -433.983918) (xy 305.780129 -433.965911)
			(xy 305.730529 -433.94041) (xy 305.685171 -433.907959) (xy 305.645022 -433.86925) (xy 305.610936 -433.825107)
			(xy 305.58364 -433.776472) (xy 305.563717 -433.724381) (xy 305.551591 -433.669944) (xy 305.54752 -433.614322)
			(xy 299.550328 -433.614322) (xy 299.550328 -434.082655) (xy 309.305446 -434.082655) (xy 309.305446 -434.018733)
			(xy 309.313457 -433.955315) (xy 309.329354 -433.893401) (xy 309.352886 -433.833968) (xy 309.38368 -433.777953)
			(xy 309.421253 -433.726238) (xy 309.46501 -433.679641) (xy 309.514263 -433.638896) (xy 309.568234 -433.604645)
			(xy 309.626073 -433.577428) (xy 309.686866 -433.557675) (xy 309.749656 -433.545697) (xy 309.813452 -433.541684)
			(xy 309.877248 -433.545697) (xy 309.940038 -433.557675) (xy 310.000831 -433.577428) (xy 310.05867 -433.604645)
			(xy 310.112641 -433.638896) (xy 310.161894 -433.679641) (xy 310.205651 -433.726238) (xy 310.243224 -433.777953)
			(xy 310.274018 -433.833968) (xy 310.29755 -433.893401) (xy 310.313447 -433.955315) (xy 310.321458 -434.018733)
			(xy 310.32196 -434.050694) (xy 310.321458 -434.082655) (xy 310.313447 -434.146073) (xy 310.29755 -434.207987)
			(xy 310.274018 -434.26742) (xy 310.243224 -434.323435) (xy 310.205651 -434.37515) (xy 310.161894 -434.421747)
			(xy 310.112641 -434.462492) (xy 310.05867 -434.496743) (xy 310.000831 -434.52396) (xy 309.940038 -434.543713)
			(xy 309.877248 -434.555691) (xy 309.813452 -434.559705) (xy 309.749656 -434.555691) (xy 309.686866 -434.543713)
			(xy 309.626073 -434.52396) (xy 309.568234 -434.496743) (xy 309.514263 -434.462492) (xy 309.46501 -434.421747)
			(xy 309.421253 -434.37515) (xy 309.38368 -434.323435) (xy 309.352886 -434.26742) (xy 309.329354 -434.207987)
			(xy 309.313457 -434.146073) (xy 309.305446 -434.082655) (xy 299.550328 -434.082655) (xy 299.550328 -434.914294)
			(xy 303.5968 -434.914294) (xy 303.600871 -434.858672) (xy 303.612997 -434.804235) (xy 303.63292 -434.752144)
			(xy 303.660216 -434.703509) (xy 303.694302 -434.659366) (xy 303.734451 -434.620657) (xy 303.779809 -434.588206)
			(xy 303.829409 -434.562705) (xy 303.882193 -434.544698) (xy 303.937036 -434.534568) (xy 303.99277 -434.532531)
			(xy 304.048207 -434.538631) (xy 304.102164 -434.552737) (xy 304.153493 -434.574549) (xy 304.201099 -434.603603)
			(xy 304.243967 -434.639278) (xy 304.281184 -434.680815) (xy 304.311957 -434.727328) (xy 304.335629 -434.777825)
			(xy 304.351697 -434.831232) (xy 304.359817 -434.886408) (xy 304.360326 -434.914294) (xy 304.359817 -434.94218)
			(xy 304.351697 -434.997356) (xy 304.335629 -435.050763) (xy 304.311957 -435.10126) (xy 304.281184 -435.147773)
			(xy 304.243967 -435.18931) (xy 304.201099 -435.224985) (xy 304.153493 -435.254039) (xy 304.102164 -435.275851)
			(xy 304.048207 -435.289957) (xy 303.99277 -435.296057) (xy 303.937036 -435.29402) (xy 303.882193 -435.28389)
			(xy 303.829409 -435.265883) (xy 303.779809 -435.240382) (xy 303.734451 -435.207931) (xy 303.694302 -435.169222)
			(xy 303.660216 -435.125079) (xy 303.63292 -435.076444) (xy 303.612997 -435.024353) (xy 303.600871 -434.969916)
			(xy 303.5968 -434.914294) (xy 299.550328 -434.914294) (xy 299.550328 -435.320694) (xy 309.304944 -435.320694)
			(xy 309.305446 -435.288733) (xy 309.313457 -435.225315) (xy 309.329354 -435.163401) (xy 309.352886 -435.103968)
			(xy 309.38368 -435.047953) (xy 309.421253 -434.996238) (xy 309.46501 -434.949641) (xy 309.514263 -434.908896)
			(xy 309.568234 -434.874645) (xy 309.626073 -434.847428) (xy 309.686866 -434.827675) (xy 309.749656 -434.815697)
			(xy 309.813452 -434.811684) (xy 309.877248 -434.815697) (xy 309.940038 -434.827675) (xy 310.000831 -434.847428)
			(xy 310.05867 -434.874645) (xy 310.112641 -434.908896) (xy 310.161894 -434.949641) (xy 310.205651 -434.996238)
			(xy 310.243224 -435.047953) (xy 310.274018 -435.103968) (xy 310.29755 -435.163401) (xy 310.313447 -435.225315)
			(xy 310.321458 -435.288733) (xy 310.32196 -435.320694) (xy 310.321457 -435.354253) (xy 310.312605 -435.420785)
			(xy 310.295081 -435.485575) (xy 310.269189 -435.547498) (xy 310.235378 -435.605478) (xy 310.194237 -435.658509)
			(xy 310.146478 -435.705668) (xy 310.12003 -435.726332) (xy 310.111394 -435.732936) (xy 310.101234 -435.750716)
			(xy 310.09082 -435.845712) (xy 310.096916 -435.86527) (xy 310.103774 -435.873398) (xy 310.120893 -435.894198)
			(xy 310.149738 -435.939692) (xy 310.171891 -435.988795) (xy 310.18691 -436.040528) (xy 310.194495 -436.09386)
			(xy 310.19496 -436.120794) (xy 310.194474 -436.148045) (xy 310.186718 -436.201993) (xy 310.171363 -436.254288)
			(xy 310.148721 -436.303865) (xy 310.119255 -436.349715) (xy 310.083564 -436.390906) (xy 310.042373 -436.426597)
			(xy 309.996523 -436.456063) (xy 309.946946 -436.478705) (xy 309.894651 -436.49406) (xy 309.840703 -436.501816)
			(xy 309.786201 -436.501816) (xy 309.732253 -436.49406) (xy 309.679958 -436.478705) (xy 309.630381 -436.456063)
			(xy 309.584531 -436.426597) (xy 309.54334 -436.390906) (xy 309.507649 -436.349715) (xy 309.478183 -436.303865)
			(xy 309.455541 -436.254288) (xy 309.440186 -436.201993) (xy 309.43243 -436.148045) (xy 309.431944 -436.120794)
			(xy 309.432443 -436.093861) (xy 309.440024 -436.040531) (xy 309.455035 -435.988799) (xy 309.477177 -435.939694)
			(xy 309.506009 -435.894194) (xy 309.52313 -435.873398) (xy 309.529988 -435.86527) (xy 309.536084 -435.845712)
			(xy 309.52567 -435.750716) (xy 309.51551 -435.732936) (xy 309.506874 -435.726332) (xy 309.480448 -435.70564)
			(xy 309.432678 -435.658496) (xy 309.391529 -435.605474) (xy 309.357716 -435.547498) (xy 309.331828 -435.485575)
			(xy 309.314315 -435.420784) (xy 309.305482 -435.354252) (xy 309.304944 -435.320694) (xy 299.550328 -435.320694)
			(xy 299.550328 -436.120794) (xy 306.391562 -436.120794) (xy 306.395633 -436.065172) (xy 306.407759 -436.010735)
			(xy 306.427682 -435.958644) (xy 306.454978 -435.910009) (xy 306.489064 -435.865866) (xy 306.529213 -435.827157)
			(xy 306.574571 -435.794706) (xy 306.624171 -435.769205) (xy 306.676955 -435.751198) (xy 306.731798 -435.741068)
			(xy 306.787532 -435.739031) (xy 306.842969 -435.745131) (xy 306.896926 -435.759237) (xy 306.948255 -435.781049)
			(xy 306.995861 -435.810103) (xy 307.038729 -435.845778) (xy 307.075946 -435.887315) (xy 307.106719 -435.933828)
			(xy 307.130391 -435.984325) (xy 307.146459 -436.037732) (xy 307.154579 -436.092908) (xy 307.155088 -436.120794)
			(xy 307.154579 -436.14868) (xy 307.146459 -436.203856) (xy 307.130391 -436.257263) (xy 307.106719 -436.30776)
			(xy 307.075946 -436.354273) (xy 307.038729 -436.39581) (xy 306.995861 -436.431485) (xy 306.948255 -436.460539)
			(xy 306.896926 -436.482351) (xy 306.842969 -436.496457) (xy 306.787532 -436.502557) (xy 306.731798 -436.50052)
			(xy 306.676955 -436.49039) (xy 306.624171 -436.472383) (xy 306.574571 -436.446882) (xy 306.529213 -436.414431)
			(xy 306.489064 -436.375722) (xy 306.454978 -436.331579) (xy 306.427682 -436.282944) (xy 306.407759 -436.230853)
			(xy 306.395633 -436.176416) (xy 306.391562 -436.120794) (xy 299.550328 -436.120794) (xy 299.550328 -437.170322)
			(xy 304.238658 -437.170322) (xy 304.242729 -437.1147) (xy 304.254855 -437.060263) (xy 304.274778 -437.008172)
			(xy 304.302074 -436.959537) (xy 304.33616 -436.915394) (xy 304.376309 -436.876685) (xy 304.421667 -436.844234)
			(xy 304.471267 -436.818733) (xy 304.524051 -436.800726) (xy 304.578894 -436.790596) (xy 304.634628 -436.788559)
			(xy 304.690065 -436.794659) (xy 304.744022 -436.808765) (xy 304.795351 -436.830577) (xy 304.842957 -436.859631)
			(xy 304.885825 -436.895306) (xy 304.923042 -436.936843) (xy 304.953815 -436.983356) (xy 304.977487 -437.033853)
			(xy 304.993555 -437.08726) (xy 304.999249 -437.125949) (xy 308.670472 -437.125949) (xy 308.670472 -437.071451)
			(xy 308.678227 -437.017506) (xy 308.69358 -436.965214) (xy 308.716218 -436.91564) (xy 308.74568 -436.869791)
			(xy 308.781367 -436.828601) (xy 308.822552 -436.792909) (xy 308.868397 -436.763441) (xy 308.917969 -436.740797)
			(xy 308.970259 -436.725437) (xy 309.024203 -436.717675) (xy 309.051452 -436.717186) (xy 309.080082 -436.717628)
			(xy 309.136697 -436.726207) (xy 309.191395 -436.743148) (xy 309.242947 -436.768071) (xy 309.290196 -436.800418)
			(xy 309.332083 -436.839461) (xy 309.367665 -436.884324) (xy 309.396145 -436.934) (xy 309.416882 -436.987374)
			(xy 309.429412 -437.043247) (xy 309.431944 -437.07177) (xy 309.433453 -437.086081) (xy 309.443402 -437.113069)
			(xy 309.460482 -437.136213) (xy 309.483338 -437.153677) (xy 309.510156 -437.164075) (xy 309.53881 -437.166583)
			(xy 309.567027 -437.161002) (xy 309.580026 -437.154828) (xy 309.607162 -437.141291) (xy 309.663976 -437.12008)
			(xy 309.722911 -437.105784) (xy 309.783129 -437.098605) (xy 309.813452 -437.098186) (xy 309.844997 -437.098616)
			(xy 309.907603 -437.106414) (xy 309.968763 -437.121896) (xy 310.027538 -437.144825) (xy 310.083027 -437.174848)
			(xy 310.134375 -437.211503) (xy 310.180795 -437.254229) (xy 310.221573 -437.302369) (xy 310.256083 -437.355183)
			(xy 310.283796 -437.41186) (xy 310.304285 -437.471529) (xy 310.317236 -437.533275) (xy 310.32245 -437.596149)
			(xy 310.319846 -437.659185) (xy 310.309465 -437.721414) (xy 310.291467 -437.781882) (xy 310.266127 -437.839659)
			(xy 310.233835 -437.893858) (xy 310.195087 -437.943646) (xy 310.150478 -437.988259) (xy 310.100693 -438.027011)
			(xy 310.046496 -438.059308) (xy 309.988722 -438.084652) (xy 309.928255 -438.102656) (xy 309.866027 -438.113042)
			(xy 309.802991 -438.115651) (xy 309.740117 -438.110442) (xy 309.67837 -438.097496) (xy 309.618698 -438.077012)
			(xy 309.562019 -438.049304) (xy 309.509202 -438.014798) (xy 309.461059 -437.974024) (xy 309.41833 -437.927607)
			(xy 309.38167 -437.876262) (xy 309.351643 -437.820777) (xy 309.328709 -437.762003) (xy 309.313222 -437.700844)
			(xy 309.305419 -437.638239) (xy 309.304944 -437.606694) (xy 309.306722 -437.565038) (xy 309.307368 -437.550682)
			(xy 309.301612 -437.522542) (xy 309.288258 -437.497113) (xy 309.268359 -437.476401) (xy 309.243484 -437.462039)
			(xy 309.215597 -437.455162) (xy 309.186897 -437.456312) (xy 309.173118 -437.46039) (xy 309.143558 -437.469652)
			(xy 309.082423 -437.479615) (xy 309.051452 -437.480202) (xy 309.024203 -437.479725) (xy 308.970259 -437.471963)
			(xy 308.917969 -437.456603) (xy 308.868397 -437.433959) (xy 308.822552 -437.404491) (xy 308.781367 -437.368799)
			(xy 308.74568 -437.327609) (xy 308.716218 -437.28176) (xy 308.69358 -437.232186) (xy 308.678227 -437.179894)
			(xy 308.670472 -437.125949) (xy 304.999249 -437.125949) (xy 305.001675 -437.142436) (xy 305.002184 -437.170322)
			(xy 305.001675 -437.198208) (xy 304.993555 -437.253384) (xy 304.977487 -437.306791) (xy 304.953815 -437.357288)
			(xy 304.923042 -437.403801) (xy 304.885825 -437.445338) (xy 304.842957 -437.481013) (xy 304.795351 -437.510067)
			(xy 304.744022 -437.531879) (xy 304.690065 -437.545985) (xy 304.634628 -437.552085) (xy 304.578894 -437.550048)
			(xy 304.524051 -437.539918) (xy 304.471267 -437.521911) (xy 304.421667 -437.49641) (xy 304.376309 -437.463959)
			(xy 304.33616 -437.42525) (xy 304.302074 -437.381107) (xy 304.274778 -437.332472) (xy 304.254855 -437.280381)
			(xy 304.242729 -437.225944) (xy 304.238658 -437.170322) (xy 299.550328 -437.170322) (xy 299.550328 -438.470294)
			(xy 303.608738 -438.470294) (xy 303.612809 -438.414672) (xy 303.624935 -438.360235) (xy 303.644858 -438.308144)
			(xy 303.672154 -438.259509) (xy 303.70624 -438.215366) (xy 303.746389 -438.176657) (xy 303.791747 -438.144206)
			(xy 303.841347 -438.118705) (xy 303.894131 -438.100698) (xy 303.948974 -438.090568) (xy 304.004708 -438.088531)
			(xy 304.060145 -438.094631) (xy 304.114102 -438.108737) (xy 304.165431 -438.130549) (xy 304.213037 -438.159603)
			(xy 304.255905 -438.195278) (xy 304.293122 -438.236815) (xy 304.323895 -438.283328) (xy 304.347567 -438.333825)
			(xy 304.363635 -438.387232) (xy 304.371755 -438.442408) (xy 304.372264 -438.470294) (xy 304.371755 -438.49818)
			(xy 304.363635 -438.553356) (xy 304.347567 -438.606763) (xy 304.323895 -438.65726) (xy 304.293122 -438.703773)
			(xy 304.255905 -438.74531) (xy 304.213037 -438.780985) (xy 304.165431 -438.810039) (xy 304.114102 -438.831851)
			(xy 304.060145 -438.845957) (xy 304.004708 -438.852057) (xy 303.948974 -438.85002) (xy 303.894131 -438.83989)
			(xy 303.841347 -438.821883) (xy 303.791747 -438.796382) (xy 303.746389 -438.763931) (xy 303.70624 -438.725222)
			(xy 303.672154 -438.681079) (xy 303.644858 -438.632444) (xy 303.624935 -438.580353) (xy 303.612809 -438.525916)
			(xy 303.608738 -438.470294) (xy 299.550328 -438.470294) (xy 299.550328 -438.876694) (xy 309.304944 -438.876694)
			(xy 309.305446 -438.844733) (xy 309.313457 -438.781315) (xy 309.329354 -438.719401) (xy 309.352886 -438.659968)
			(xy 309.38368 -438.603953) (xy 309.421253 -438.552238) (xy 309.46501 -438.505641) (xy 309.514263 -438.464896)
			(xy 309.568234 -438.430645) (xy 309.626073 -438.403428) (xy 309.686866 -438.383675) (xy 309.749656 -438.371697)
			(xy 309.813452 -438.367684) (xy 309.877248 -438.371697) (xy 309.940038 -438.383675) (xy 310.000831 -438.403428)
			(xy 310.05867 -438.430645) (xy 310.112641 -438.464896) (xy 310.161894 -438.505641) (xy 310.205651 -438.552238)
			(xy 310.243224 -438.603953) (xy 310.274018 -438.659968) (xy 310.29755 -438.719401) (xy 310.313447 -438.781315)
			(xy 310.321458 -438.844733) (xy 310.32196 -438.876694) (xy 310.321457 -438.910253) (xy 310.312605 -438.976785)
			(xy 310.295081 -439.041575) (xy 310.269189 -439.103498) (xy 310.235378 -439.161478) (xy 310.194237 -439.214509)
			(xy 310.146478 -439.261668) (xy 310.12003 -439.282332) (xy 310.111394 -439.288936) (xy 310.101234 -439.306716)
			(xy 310.09082 -439.401712) (xy 310.096916 -439.42127) (xy 310.103774 -439.429398) (xy 310.120893 -439.450198)
			(xy 310.149738 -439.495692) (xy 310.171891 -439.544795) (xy 310.18691 -439.596528) (xy 310.194495 -439.64986)
			(xy 310.19496 -439.676794) (xy 310.194474 -439.704045) (xy 310.186718 -439.757993) (xy 310.171363 -439.810288)
			(xy 310.148721 -439.859865) (xy 310.119255 -439.905715) (xy 310.083564 -439.946906) (xy 310.042373 -439.982597)
			(xy 309.996523 -440.012063) (xy 309.946946 -440.034705) (xy 309.894651 -440.05006) (xy 309.840703 -440.057816)
			(xy 309.786201 -440.057816) (xy 309.732253 -440.05006) (xy 309.679958 -440.034705) (xy 309.630381 -440.012063)
			(xy 309.584531 -439.982597) (xy 309.54334 -439.946906) (xy 309.507649 -439.905715) (xy 309.478183 -439.859865)
			(xy 309.455541 -439.810288) (xy 309.440186 -439.757993) (xy 309.43243 -439.704045) (xy 309.431944 -439.676794)
			(xy 309.432443 -439.649861) (xy 309.440024 -439.596531) (xy 309.455035 -439.544799) (xy 309.477177 -439.495694)
			(xy 309.506009 -439.450194) (xy 309.52313 -439.429398) (xy 309.529988 -439.42127) (xy 309.536084 -439.401712)
			(xy 309.52567 -439.306716) (xy 309.51551 -439.288936) (xy 309.506874 -439.282332) (xy 309.480448 -439.26164)
			(xy 309.432678 -439.214496) (xy 309.391529 -439.161474) (xy 309.357716 -439.103498) (xy 309.331828 -439.041575)
			(xy 309.314315 -438.976784) (xy 309.305482 -438.910252) (xy 309.304944 -438.876694) (xy 299.550328 -438.876694)
			(xy 299.550328 -439.676794) (xy 306.391562 -439.676794) (xy 306.395633 -439.621172) (xy 306.407759 -439.566735)
			(xy 306.427682 -439.514644) (xy 306.454978 -439.466009) (xy 306.489064 -439.421866) (xy 306.529213 -439.383157)
			(xy 306.574571 -439.350706) (xy 306.624171 -439.325205) (xy 306.676955 -439.307198) (xy 306.731798 -439.297068)
			(xy 306.787532 -439.295031) (xy 306.842969 -439.301131) (xy 306.896926 -439.315237) (xy 306.948255 -439.337049)
			(xy 306.995861 -439.366103) (xy 307.038729 -439.401778) (xy 307.075946 -439.443315) (xy 307.106719 -439.489828)
			(xy 307.130391 -439.540325) (xy 307.146459 -439.593732) (xy 307.154579 -439.648908) (xy 307.155088 -439.676794)
			(xy 307.154579 -439.70468) (xy 307.146459 -439.759856) (xy 307.130391 -439.813263) (xy 307.106719 -439.86376)
			(xy 307.075946 -439.910273) (xy 307.038729 -439.95181) (xy 306.995861 -439.987485) (xy 306.948255 -440.016539)
			(xy 306.896926 -440.038351) (xy 306.842969 -440.052457) (xy 306.787532 -440.058557) (xy 306.731798 -440.05652)
			(xy 306.676955 -440.04639) (xy 306.624171 -440.028383) (xy 306.574571 -440.002882) (xy 306.529213 -439.970431)
			(xy 306.489064 -439.931722) (xy 306.454978 -439.887579) (xy 306.427682 -439.838944) (xy 306.407759 -439.786853)
			(xy 306.395633 -439.732416) (xy 306.391562 -439.676794) (xy 299.550328 -439.676794) (xy 299.550328 -440.006486)
			(xy 299.550767 -440.016549) (xy 299.558507 -440.035128) (xy 299.565314 -440.042554) (xy 300.121574 -440.598814)
			(xy 300.128972 -440.605658) (xy 300.147572 -440.613379) (xy 300.157642 -440.6138) (xy 310.654446 -440.6138)
			(xy 310.664512 -440.613368) (xy 310.683105 -440.605642) (xy 310.690514 -440.598814) (xy 311.043828 -440.2455)
			(xy 311.050682 -440.238105) (xy 311.058428 -440.219506) (xy 311.058814 -440.209432) (xy 311.058814 -424.940222)
			(xy 311.058358 -424.930383) (xy 311.050932 -424.91216) (xy 311.03717 -424.898094) (xy 311.028334 -424.89374)
			(xy 307.669184 -423.426636) (xy 307.663596 -423.424604) (xy 307.408326 -423.347134) (xy 307.394664 -423.342957)
			(xy 307.367727 -423.333429) (xy 307.354478 -423.328084) (xy 305.86807 -422.71188) (xy 305.841927 -422.70063)
			(xy 305.791766 -422.673733) (xy 305.744477 -422.642055) (xy 305.722274 -422.62425) (xy 305.603402 -422.526714)
			(xy 305.591718 -422.519348) (xy 303.964086 -421.808656) (xy 303.953719 -421.804719) (xy 303.931574 -421.805231)
			(xy 303.921414 -421.809672) (xy 303.907444 -421.81653) (xy 303.90268 -421.819033) (xy 303.894224 -421.825688)
			(xy 303.89068 -421.829738) (xy 303.890426 -421.829992) (xy 303.872777 -421.850661) (xy 303.832637 -421.887303)
			(xy 303.787728 -421.917914) (xy 303.73895 -421.941884) (xy 303.687277 -421.958731) (xy 303.633745 -421.96812)
			(xy 303.579423 -421.969862) (xy 303.525399 -421.963922) (xy 303.472754 -421.950419) (xy 303.42254 -421.929624)
			(xy 303.375762 -421.901953) (xy 303.354232 -421.885364) (xy 303.294542 -421.825674) (xy 303.286414 -421.81907)
			(xy 303.251616 -421.802052) (xy 303.183798 -421.802052) (xy 303.173729 -421.801627) (xy 303.15513 -421.793907)
			(xy 303.14773 -421.787066) (xy 301.833788 -420.473124) (xy 301.826944 -420.465726) (xy 301.819223 -420.447126)
			(xy 301.818802 -420.437056) (xy 301.818802 -414.54197) (xy 301.818802 -414.541716) (xy 301.81834 -414.528084)
			(xy 301.811076 -414.501805) (xy 301.797114 -414.478386) (xy 301.77745 -414.459498) (xy 301.753489 -414.446488)
			(xy 301.726939 -414.440286) (xy 301.699693 -414.441333) (xy 301.673697 -414.449554) (xy 301.650805 -414.464364)
			(xy 301.632649 -414.484705) (xy 301.62627 -414.496758) (xy 301.623476 -414.503616) (xy 301.594268 -414.591167)
			(xy 301.529265 -414.763929) (xy 301.456854 -414.933719) (xy 301.37717 -415.100219) (xy 301.290361 -415.263119)
			(xy 301.19659 -415.422113) (xy 301.096033 -415.576904) (xy 300.988878 -415.727203) (xy 300.875324 -415.872729)
			(xy 300.755585 -416.013208) (xy 300.629884 -416.14838) (xy 300.498457 -416.27799) (xy 300.361548 -416.401797)
			(xy 300.219415 -416.519568) (xy 300.072323 -416.631085) (xy 299.920546 -416.736137) (xy 299.76437 -416.834529)
			(xy 299.604086 -416.926077) (xy 299.439993 -417.010609) (xy 299.272399 -417.087967) (xy 299.101617 -417.158007)
			(xy 298.927967 -417.220598) (xy 298.751773 -417.275622) (xy 298.573365 -417.322977) (xy 298.393076 -417.362575)
			(xy 298.211243 -417.39434) (xy 298.028208 -417.418214) (xy 297.844311 -417.434152) (xy 297.659897 -417.442124)
			(xy 297.567604 -417.44265) (xy 297.475764 -417.442163) (xy 297.292253 -417.434261) (xy 297.109252 -417.418471)
			(xy 296.927099 -417.394822) (xy 296.746133 -417.363359) (xy 296.566688 -417.32414) (xy 296.389097 -417.277236)
			(xy 296.213688 -417.222736) (xy 296.040785 -417.16074) (xy 295.870711 -417.091362) (xy 295.703778 -417.014732)
			(xy 295.540297 -416.93099) (xy 295.38057 -416.840293) (xy 295.224893 -416.742808) (xy 295.073554 -416.638716)
			(xy 294.926833 -416.528209) (xy 294.785003 -416.411493) (xy 294.648325 -416.288782) (xy 294.517053 -416.160305)
			(xy 294.39143 -416.026299) (xy 294.271689 -415.887013) (xy 294.15805 -415.742704) (xy 294.050726 -415.59364)
			(xy 293.949914 -415.440096) (xy 293.855801 -415.282358) (xy 293.768561 -415.120716) (xy 293.688357 -414.955471)
			(xy 293.615336 -414.786929) (xy 293.549633 -414.615401) (xy 293.491371 -414.441205) (xy 293.440658 -414.264664)
			(xy 293.397586 -414.086104) (xy 293.362236 -413.905857) (xy 293.334674 -413.724256) (xy 293.31495 -413.541637)
			(xy 293.303101 -413.358338) (xy 293.299149 -413.1747) (xy 293.303101 -412.991062) (xy 293.31495 -412.807763)
			(xy 293.334674 -412.625144) (xy 293.362236 -412.443543) (xy 293.397586 -412.263296) (xy 293.440658 -412.084736)
			(xy 293.491371 -411.908195) (xy 293.549633 -411.733999) (xy 293.615336 -411.562471) (xy 293.688357 -411.393929)
			(xy 293.768561 -411.228684) (xy 293.855801 -411.067042) (xy 293.949914 -410.909304) (xy 294.050726 -410.75576)
			(xy 294.15805 -410.606696) (xy 294.271689 -410.462387) (xy 294.39143 -410.323101) (xy 294.517053 -410.189095)
			(xy 294.648325 -410.060618) (xy 294.785003 -409.937907) (xy 294.926833 -409.821191) (xy 295.073554 -409.710684)
			(xy 295.224893 -409.606592) (xy 295.38057 -409.509107) (xy 295.540297 -409.41841) (xy 295.703778 -409.334668)
			(xy 295.870711 -409.258038) (xy 296.040785 -409.18866) (xy 296.213688 -409.126664) (xy 296.389097 -409.072164)
			(xy 296.566688 -409.02526) (xy 296.746133 -408.986041) (xy 296.927099 -408.954578) (xy 297.109252 -408.930929)
			(xy 297.292253 -408.915139) (xy 297.475764 -408.907237) (xy 297.567604 -408.906726) (xy 297.634451 -408.906991)
			(xy 297.76808 -408.911183) (xy 297.834812 -408.915108) (xy 297.841162 -408.915108) (xy 297.85572 -408.913758)
			(xy 297.883203 -408.903816) (xy 297.906741 -408.886493) (xy 297.924405 -408.86321) (xy 297.934746 -408.835875)
			(xy 297.936917 -408.80673) (xy 297.930739 -408.778165) (xy 297.916719 -408.752522) (xy 297.906694 -408.74188)
			(xy 296.501312 -407.336498) (xy 296.494465 -407.3291) (xy 296.486729 -407.310502) (xy 296.486326 -407.30043)
			(xy 296.486326 -404.06193) (xy 296.486109 -404.054889) (xy 296.482254 -404.041345) (xy 296.478706 -404.03526)
			(xy 296.461688 -404.007828) (xy 296.451782 -403.998684) (xy 296.445432 -403.995382) (xy 296.418061 -403.980814)
			(xy 296.36675 -403.946001) (xy 296.320052 -403.90521) (xy 296.278659 -403.859043) (xy 296.243185 -403.808187)
			(xy 296.214157 -403.753396) (xy 296.192006 -403.695482) (xy 296.177059 -403.635305) (xy 296.169538 -403.573757)
			(xy 296.16908 -403.542754) (xy 296.169517 -403.512802) (xy 296.176556 -403.453313) (xy 296.190533 -403.395062)
			(xy 296.211252 -403.338856) (xy 296.238428 -403.285471) (xy 296.254678 -403.260306) (xy 296.258996 -403.253956)
			(xy 296.263314 -403.239732) (xy 296.265168 -403.232611) (xy 296.265155 -403.217902) (xy 296.263314 -403.210776)
			(xy 296.258996 -403.196552) (xy 296.254678 -403.190202) (xy 296.238412 -403.165048) (xy 296.211239 -403.11166)
			(xy 296.190524 -403.055451) (xy 296.176555 -402.997197) (xy 296.169524 -402.937706) (xy 296.16908 -402.907754)
			(xy 296.169543 -402.876753) (xy 296.177082 -402.815211) (xy 296.19204 -402.755041) (xy 296.214199 -402.697134)
			(xy 296.243228 -402.642348) (xy 296.278698 -402.591494) (xy 296.320083 -402.545326) (xy 296.366771 -402.504528)
			(xy 296.418069 -402.469704) (xy 296.445432 -402.455126) (xy 296.451782 -402.451824) (xy 296.461688 -402.44268)
			(xy 296.478706 -402.415248) (xy 296.482214 -402.409144) (xy 296.486089 -402.395614) (xy 296.486326 -402.388578)
			(xy 296.486326 -397.213836) (xy 296.485899 -397.200534) (xy 296.479033 -397.174832) (xy 296.465757 -397.151777)
			(xy 296.446975 -397.132936) (xy 296.423962 -397.119589) (xy 296.398281 -397.112643) (xy 296.38498 -397.112236)
			(xy 296.353034 -397.111691) (xy 296.289655 -397.1036) (xy 296.227788 -397.087637) (xy 296.168407 -397.064052)
			(xy 296.112446 -397.033218) (xy 296.060788 -396.995618) (xy 296.014244 -396.951846) (xy 295.973547 -396.90259)
			(xy 295.939339 -396.848626) (xy 295.912157 -396.790803) (xy 295.892431 -396.730031) (xy 295.880469 -396.667267)
			(xy 295.87646 -396.6035) (xy 295.880469 -396.539733) (xy 295.892431 -396.476969) (xy 295.912157 -396.416197)
			(xy 295.939339 -396.358374) (xy 295.973547 -396.30441) (xy 296.014244 -396.255154) (xy 296.060788 -396.211382)
			(xy 296.112447 -396.173782) (xy 296.168407 -396.142947) (xy 296.227788 -396.119363) (xy 296.289655 -396.1034)
			(xy 296.353034 -396.095309) (xy 296.38498 -396.094712) (xy 296.398275 -396.094244) (xy 296.423945 -396.087303)
			(xy 296.446951 -396.073966) (xy 296.465729 -396.055137) (xy 296.479006 -396.032097) (xy 296.485879 -396.006408)
			(xy 296.486326 -395.993112) (xy 296.486326 -392.369802) (xy 296.485056 -392.35888) (xy 296.4815 -392.342878)
			(xy 296.479214 -392.338052) (xy 296.464529 -392.304555) (xy 296.443828 -392.234408) (xy 296.433366 -392.162023)
			(xy 296.432732 -392.125454) (xy 296.432732 -392.124946) (xy 296.433345 -392.088375) (xy 296.44379 -392.015984)
			(xy 296.464513 -391.94584) (xy 296.479214 -391.912348) (xy 296.4815 -391.907522) (xy 296.485056 -391.89152)
			(xy 296.486326 -391.880598) (xy 296.486326 -391.214356) (xy 296.486238 -391.209945) (xy 296.484705 -391.201258)
			(xy 296.483278 -391.197084) (xy 296.47515 -391.174732) (xy 296.47007 -391.168128) (xy 296.454195 -391.147638)
			(xy 296.427515 -391.103197) (xy 296.407057 -391.055571) (xy 296.393192 -391.005625) (xy 296.386171 -390.954269)
			(xy 296.385742 -390.928352) (xy 296.386202 -390.902438) (xy 296.393235 -390.851087) (xy 296.4071 -390.801146)
			(xy 296.427545 -390.753518) (xy 296.454201 -390.709068) (xy 296.47007 -390.688576) (xy 296.47515 -390.681972)
			(xy 296.483278 -390.65962) (xy 296.484686 -390.655441) (xy 296.486215 -390.646757) (xy 296.486326 -390.642348)
			(xy 296.486326 -390.000236) (xy 296.486237 -389.995826) (xy 296.4847 -389.98714) (xy 296.483278 -389.982964)
			(xy 296.47515 -389.960612) (xy 296.47007 -389.954008) (xy 296.454196 -389.933517) (xy 296.427519 -389.889076)
			(xy 296.407063 -389.84145) (xy 296.3932 -389.791504) (xy 296.386183 -389.740148) (xy 296.385742 -389.714232)
			(xy 296.386204 -389.688318) (xy 296.393239 -389.636969) (xy 296.407106 -389.587029) (xy 296.427553 -389.539403)
			(xy 296.45421 -389.494955) (xy 296.47007 -389.474456) (xy 296.47515 -389.467852) (xy 296.483278 -389.4455)
			(xy 296.484684 -389.441321) (xy 296.48621 -389.432636) (xy 296.486326 -389.428228) (xy 296.486326 -389.080756)
			(xy 296.486238 -389.076345) (xy 296.484705 -389.067658) (xy 296.483278 -389.063484) (xy 296.47515 -389.041132)
			(xy 296.47007 -389.034528) (xy 296.454195 -389.014038) (xy 296.427515 -388.969597) (xy 296.407057 -388.921971)
			(xy 296.393192 -388.872025) (xy 296.386171 -388.820669) (xy 296.385742 -388.794752) (xy 296.386202 -388.768838)
			(xy 296.393235 -388.717487) (xy 296.4071 -388.667546) (xy 296.427545 -388.619918) (xy 296.454201 -388.575468)
			(xy 296.47007 -388.554976) (xy 296.47515 -388.548372) (xy 296.483278 -388.52602) (xy 296.484686 -388.521841)
			(xy 296.486215 -388.513157) (xy 296.486326 -388.508748) (xy 296.486326 -387.866636) (xy 296.486237 -387.862226)
			(xy 296.4847 -387.85354) (xy 296.483278 -387.849364) (xy 296.47515 -387.827012) (xy 296.47007 -387.820408)
			(xy 296.454196 -387.799917) (xy 296.427519 -387.755476) (xy 296.407063 -387.70785) (xy 296.3932 -387.657904)
			(xy 296.386183 -387.606548) (xy 296.385742 -387.580632) (xy 296.386204 -387.554718) (xy 296.393239 -387.503369)
			(xy 296.407106 -387.453429) (xy 296.427553 -387.405803) (xy 296.45421 -387.361355) (xy 296.47007 -387.340856)
			(xy 296.47515 -387.334252) (xy 296.483278 -387.3119) (xy 296.484684 -387.307721) (xy 296.48621 -387.299036)
			(xy 296.486326 -387.294628) (xy 296.486326 -385.677156) (xy 296.486238 -385.672745) (xy 296.484705 -385.664058)
			(xy 296.483278 -385.659884) (xy 296.47515 -385.637532) (xy 296.47007 -385.630928) (xy 296.454195 -385.610438)
			(xy 296.427515 -385.565997) (xy 296.407057 -385.518371) (xy 296.393192 -385.468425) (xy 296.386171 -385.417069)
			(xy 296.385742 -385.391152) (xy 296.386202 -385.365238) (xy 296.393235 -385.313887) (xy 296.4071 -385.263946)
			(xy 296.427545 -385.216318) (xy 296.454201 -385.171868) (xy 296.47007 -385.151376) (xy 296.47515 -385.144772)
			(xy 296.483278 -385.12242) (xy 296.484686 -385.118241) (xy 296.486215 -385.109557) (xy 296.486326 -385.105148)
			(xy 296.486326 -384.463036) (xy 296.486237 -384.458626) (xy 296.4847 -384.44994) (xy 296.483278 -384.445764)
			(xy 296.47515 -384.423412) (xy 296.47007 -384.416808) (xy 296.454196 -384.396317) (xy 296.427519 -384.351876)
			(xy 296.407063 -384.30425) (xy 296.3932 -384.254304) (xy 296.386183 -384.202948) (xy 296.385742 -384.177032)
			(xy 296.386204 -384.151118) (xy 296.393239 -384.099769) (xy 296.407106 -384.049829) (xy 296.427553 -384.002203)
			(xy 296.45421 -383.957755) (xy 296.47007 -383.937256) (xy 296.47515 -383.930652) (xy 296.483278 -383.9083)
			(xy 296.484684 -383.904121) (xy 296.48621 -383.895436) (xy 296.486326 -383.891028) (xy 296.486326 -375.520458)
			(xy 296.486757 -375.510392) (xy 296.494485 -375.491801) (xy 296.501312 -375.48439) (xy 298.205398 -373.780304)
			(xy 298.205906 -373.779796) (xy 298.212486 -373.772415) (xy 298.219925 -373.754115) (xy 298.220384 -373.744236)
			(xy 298.220384 -367.85296) (xy 298.219953 -367.842893) (xy 298.212227 -367.824301) (xy 298.205398 -367.816892)
			(xy 296.761408 -366.372902) (xy 296.754296 -366.365536) (xy 296.7355 -366.357916) (xy 282.18257 -366.357916)
			(xy 282.172502 -366.357488) (xy 282.153904 -366.349768) (xy 282.146502 -366.34293) (xy 276.603714 -360.800142)
			(xy 276.596602 -360.792776) (xy 276.577806 -360.785156) (xy 273.523456 -360.785156) (xy 273.513048 -360.785644)
			(xy 273.493936 -360.793891) (xy 273.479674 -360.809052) (xy 273.475704 -360.818684) (xy 273.460023 -360.860938)
			(xy 273.422266 -360.942783) (xy 273.377493 -361.021011) (xy 273.326048 -361.095023) (xy 273.268326 -361.16425)
			(xy 273.204768 -361.228161) (xy 273.135863 -361.286268) (xy 273.062139 -361.338123) (xy 272.984161 -361.38333)
			(xy 272.902527 -361.421542) (xy 272.817863 -361.452465) (xy 272.730818 -361.475863) (xy 272.64206 -361.491556)
			(xy 272.552269 -361.499425) (xy 272.507202 -361.499912) (xy 272.462287 -361.499423) (xy 272.372799 -361.491594)
			(xy 272.284334 -361.475995) (xy 272.197565 -361.452745) (xy 272.113152 -361.422022) (xy 272.031739 -361.384058)
			(xy 271.953944 -361.339144) (xy 271.880359 -361.28762) (xy 271.811545 -361.229878) (xy 271.748026 -361.166359)
			(xy 271.690284 -361.097546) (xy 271.638759 -361.023962) (xy 271.593844 -360.946167) (xy 271.55588 -360.864753)
			(xy 271.525156 -360.780341) (xy 271.501906 -360.693572) (xy 271.486307 -360.605107) (xy 271.478478 -360.515619)
			(xy 271.477994 -360.470704) (xy 271.478387 -360.429832) (xy 271.484853 -360.348345) (xy 271.497769 -360.267629)
			(xy 271.517053 -360.188193) (xy 271.542583 -360.110539) (xy 271.558004 -360.072686) (xy 271.5641 -360.058462)
			(xy 271.558258 -360.028236) (xy 262.106156 -350.576134) (xy 262.099314 -350.568735) (xy 262.091595 -350.550136)
			(xy 262.09117 -350.540066) (xy 262.09117 -325.32828) (xy 262.076946 -325.293228) (xy 262.070342 -325.286116)
			(xy 262.048679 -325.262208) (xy 262.010938 -325.209881) (xy 261.98012 -325.153199) (xy 261.95672 -325.093075)
			(xy 261.941113 -325.030473) (xy 261.933552 -324.9664) (xy 261.934156 -324.901885) (xy 261.942916 -324.837965)
			(xy 261.959693 -324.775667) (xy 261.984215 -324.715991) (xy 262.016089 -324.659897) (xy 262.054803 -324.608285)
			(xy 262.076946 -324.584822) (xy 262.083804 -324.57771) (xy 262.09117 -324.559422) (xy 262.09117 -324.505574)
			(xy 262.090154 -324.500494) (xy 262.088884 -324.494398) (xy 262.088064 -324.490548) (xy 262.085386 -324.483148)
			(xy 262.08355 -324.479666) (xy 262.079994 -324.473316) (xy 262.074406 -324.467728) (xy 262.074152 -324.467474)
			(xy 262.050258 -324.44345) (xy 262.008395 -324.390172) (xy 261.973978 -324.331807) (xy 261.947618 -324.269387)
			(xy 261.929782 -324.20402) (xy 261.920785 -324.136863) (xy 261.920228 -324.102984) (xy 261.920759 -324.069452)
			(xy 261.929566 -324.002968) (xy 261.947038 -323.93822) (xy 261.972872 -323.876331) (xy 262.00662 -323.818377)
			(xy 262.047694 -323.765363) (xy 262.095382 -323.718209) (xy 262.148857 -323.677736) (xy 262.177784 -323.66077)
			(xy 262.179816 -323.6595) (xy 262.192359 -323.650889) (xy 262.212125 -323.627783) (xy 262.224224 -323.599886)
			(xy 262.227584 -323.569665) (xy 262.221909 -323.539791) (xy 262.207701 -323.512907) (xy 262.197342 -323.501766)
			(xy 258.332986 -319.63741) (xy 258.326129 -319.630016) (xy 258.318377 -319.611417) (xy 258.318 -319.601342)
			(xy 258.318 -307.778404) (xy 258.317746 -307.773324) (xy 249.936254 -225.17354) (xy 249.936 -225.16846)
			(xy 249.936 -215.921082) (xy 249.935573 -215.911013) (xy 249.927854 -215.892414) (xy 249.921014 -215.885014)
			(xy 249.230642 -215.194642) (xy 249.22353 -215.187276) (xy 249.204734 -215.179656) (xy 221.761812 -215.179656)
			(xy 221.751742 -215.180078) (xy 221.73314 -215.187796) (xy 221.725744 -215.194642) (xy 220.861425 -216.058961)
			(xy 236.219994 -216.058961) (xy 236.219994 -215.995039) (xy 236.228005 -215.931621) (xy 236.243902 -215.869707)
			(xy 236.267434 -215.810274) (xy 236.298228 -215.754259) (xy 236.335801 -215.702544) (xy 236.379558 -215.655947)
			(xy 236.428811 -215.615202) (xy 236.482782 -215.580951) (xy 236.540621 -215.553734) (xy 236.601414 -215.533981)
			(xy 236.664204 -215.522003) (xy 236.728 -215.51799) (xy 236.791796 -215.522003) (xy 236.854586 -215.533981)
			(xy 236.915379 -215.553734) (xy 236.973218 -215.580951) (xy 237.027189 -215.615202) (xy 237.076442 -215.655947)
			(xy 237.120199 -215.702544) (xy 237.157772 -215.754259) (xy 237.188566 -215.810274) (xy 237.212098 -215.869707)
			(xy 237.227995 -215.931621) (xy 237.236006 -215.995039) (xy 237.236508 -216.027) (xy 237.236006 -216.058961)
			(xy 240.537994 -216.058961) (xy 240.537994 -215.995039) (xy 240.546005 -215.931621) (xy 240.561902 -215.869707)
			(xy 240.585434 -215.810274) (xy 240.616228 -215.754259) (xy 240.653801 -215.702544) (xy 240.697558 -215.655947)
			(xy 240.746811 -215.615202) (xy 240.800782 -215.580951) (xy 240.858621 -215.553734) (xy 240.919414 -215.533981)
			(xy 240.982204 -215.522003) (xy 241.046 -215.51799) (xy 241.109796 -215.522003) (xy 241.172586 -215.533981)
			(xy 241.233379 -215.553734) (xy 241.291218 -215.580951) (xy 241.345189 -215.615202) (xy 241.394442 -215.655947)
			(xy 241.438199 -215.702544) (xy 241.475772 -215.754259) (xy 241.506566 -215.810274) (xy 241.530098 -215.869707)
			(xy 241.545995 -215.931621) (xy 241.554006 -215.995039) (xy 241.554508 -216.027) (xy 241.554006 -216.058961)
			(xy 241.545995 -216.122379) (xy 241.530098 -216.184293) (xy 241.506566 -216.243726) (xy 241.475772 -216.299741)
			(xy 241.438199 -216.351456) (xy 241.394442 -216.398053) (xy 241.345189 -216.438798) (xy 241.291218 -216.473049)
			(xy 241.233379 -216.500266) (xy 241.172586 -216.520019) (xy 241.109796 -216.531997) (xy 241.046 -216.536011)
			(xy 240.982204 -216.531997) (xy 240.919414 -216.520019) (xy 240.858621 -216.500266) (xy 240.800782 -216.473049)
			(xy 240.746811 -216.438798) (xy 240.697558 -216.398053) (xy 240.653801 -216.351456) (xy 240.616228 -216.299741)
			(xy 240.585434 -216.243726) (xy 240.561902 -216.184293) (xy 240.546005 -216.122379) (xy 240.537994 -216.058961)
			(xy 237.236006 -216.058961) (xy 237.227995 -216.122379) (xy 237.212098 -216.184293) (xy 237.188566 -216.243726)
			(xy 237.157772 -216.299741) (xy 237.120199 -216.351456) (xy 237.076442 -216.398053) (xy 237.027189 -216.438798)
			(xy 236.973218 -216.473049) (xy 236.915379 -216.500266) (xy 236.854586 -216.520019) (xy 236.791796 -216.531997)
			(xy 236.728 -216.536011) (xy 236.664204 -216.531997) (xy 236.601414 -216.520019) (xy 236.540621 -216.500266)
			(xy 236.482782 -216.473049) (xy 236.428811 -216.438798) (xy 236.379558 -216.398053) (xy 236.335801 -216.351456)
			(xy 236.298228 -216.299741) (xy 236.267434 -216.243726) (xy 236.243902 -216.184293) (xy 236.228005 -216.122379)
			(xy 236.219994 -216.058961) (xy 220.861425 -216.058961) (xy 220.226425 -216.693961) (xy 227.964994 -216.693961)
			(xy 227.964994 -216.630039) (xy 227.973005 -216.566621) (xy 227.988902 -216.504707) (xy 228.012434 -216.445274)
			(xy 228.043228 -216.389259) (xy 228.080801 -216.337544) (xy 228.124558 -216.290947) (xy 228.173811 -216.250202)
			(xy 228.227782 -216.215951) (xy 228.285621 -216.188734) (xy 228.346414 -216.168981) (xy 228.409204 -216.157003)
			(xy 228.473 -216.15299) (xy 228.536796 -216.157003) (xy 228.599586 -216.168981) (xy 228.660379 -216.188734)
			(xy 228.718218 -216.215951) (xy 228.772189 -216.250202) (xy 228.821442 -216.290947) (xy 228.865199 -216.337544)
			(xy 228.902772 -216.389259) (xy 228.933566 -216.445274) (xy 228.957098 -216.504707) (xy 228.972995 -216.566621)
			(xy 228.981006 -216.630039) (xy 228.981508 -216.662) (xy 228.981006 -216.693961) (xy 232.409994 -216.693961)
			(xy 232.409994 -216.630039) (xy 232.418005 -216.566621) (xy 232.433902 -216.504707) (xy 232.457434 -216.445274)
			(xy 232.488228 -216.389259) (xy 232.525801 -216.337544) (xy 232.569558 -216.290947) (xy 232.618811 -216.250202)
			(xy 232.672782 -216.215951) (xy 232.730621 -216.188734) (xy 232.791414 -216.168981) (xy 232.854204 -216.157003)
			(xy 232.918 -216.15299) (xy 232.981796 -216.157003) (xy 233.044586 -216.168981) (xy 233.105379 -216.188734)
			(xy 233.163218 -216.215951) (xy 233.217189 -216.250202) (xy 233.266442 -216.290947) (xy 233.310199 -216.337544)
			(xy 233.347772 -216.389259) (xy 233.378566 -216.445274) (xy 233.402098 -216.504707) (xy 233.417995 -216.566621)
			(xy 233.426006 -216.630039) (xy 233.426508 -216.662) (xy 233.426006 -216.693961) (xy 233.417995 -216.757379)
			(xy 233.402098 -216.819293) (xy 233.378566 -216.878726) (xy 233.347772 -216.934741) (xy 233.310199 -216.986456)
			(xy 233.266442 -217.033053) (xy 233.217189 -217.073798) (xy 233.163218 -217.108049) (xy 233.105379 -217.135266)
			(xy 233.044586 -217.155019) (xy 232.981796 -217.166997) (xy 232.918 -217.171011) (xy 232.854204 -217.166997)
			(xy 232.791414 -217.155019) (xy 232.730621 -217.135266) (xy 232.672782 -217.108049) (xy 232.618811 -217.073798)
			(xy 232.569558 -217.033053) (xy 232.525801 -216.986456) (xy 232.488228 -216.934741) (xy 232.457434 -216.878726)
			(xy 232.433902 -216.819293) (xy 232.418005 -216.757379) (xy 232.409994 -216.693961) (xy 228.981006 -216.693961)
			(xy 228.972995 -216.757379) (xy 228.957098 -216.819293) (xy 228.933566 -216.878726) (xy 228.902772 -216.934741)
			(xy 228.865199 -216.986456) (xy 228.821442 -217.033053) (xy 228.772189 -217.073798) (xy 228.718218 -217.108049)
			(xy 228.660379 -217.135266) (xy 228.599586 -217.155019) (xy 228.536796 -217.166997) (xy 228.473 -217.171011)
			(xy 228.409204 -217.166997) (xy 228.346414 -217.155019) (xy 228.285621 -217.135266) (xy 228.227782 -217.108049)
			(xy 228.173811 -217.073798) (xy 228.124558 -217.033053) (xy 228.080801 -216.986456) (xy 228.043228 -216.934741)
			(xy 228.012434 -216.878726) (xy 227.988902 -216.819293) (xy 227.973005 -216.757379) (xy 227.964994 -216.693961)
			(xy 220.226425 -216.693961) (xy 219.881704 -217.038682) (xy 219.875218 -217.045689) (xy 219.867539 -217.063154)
			(xy 219.866776 -217.082218) (xy 219.873036 -217.100241) (xy 219.87891 -217.10777) (xy 219.897939 -217.130805)
			(xy 219.931052 -217.18054) (xy 219.95811 -217.233813) (xy 219.978739 -217.289889) (xy 219.992655 -217.347996)
			(xy 219.999667 -217.407333) (xy 220.000068 -217.437208) (xy 219.999586 -217.468543) (xy 219.991887 -217.530739)
			(xy 219.976607 -217.591518) (xy 219.953977 -217.64996) (xy 219.92434 -217.70518) (xy 219.888145 -217.756341)
			(xy 219.84594 -217.802669) (xy 219.798364 -217.843462) (xy 219.772484 -217.861134) (xy 219.761816 -217.867992)
			(xy 219.750132 -217.889328) (xy 219.74683 -217.997278) (xy 219.757244 -218.019376) (xy 219.767404 -218.026996)
			(xy 219.793888 -218.047658) (xy 219.841713 -218.094827) (xy 219.882911 -218.147883) (xy 219.916765 -218.205901)
			(xy 219.942685 -218.267871) (xy 219.960221 -218.332714) (xy 219.969067 -218.399302) (xy 219.969588 -218.432888)
			(xy 219.969155 -218.45905) (xy 232.790492 -218.45905) (xy 232.791046 -218.425493) (xy 232.799891 -218.358964)
			(xy 232.817408 -218.294176) (xy 232.843293 -218.232253) (xy 232.877095 -218.174273) (xy 232.918228 -218.12124)
			(xy 232.965978 -218.074078) (xy 232.992422 -218.053412) (xy 233.001058 -218.046808) (xy 233.011218 -218.029028)
			(xy 233.021632 -217.934032) (xy 233.015536 -217.914474) (xy 233.008678 -217.906346) (xy 232.991542 -217.88556)
			(xy 232.962697 -217.840062) (xy 232.940547 -217.790956) (xy 232.925533 -217.73922) (xy 232.917954 -217.685885)
			(xy 232.917492 -217.65895) (xy 232.917978 -217.631699) (xy 232.925734 -217.577751) (xy 232.941089 -217.525456)
			(xy 232.963731 -217.475879) (xy 232.993197 -217.430029) (xy 233.028888 -217.388838) (xy 233.070079 -217.353147)
			(xy 233.115929 -217.323681) (xy 233.165506 -217.301039) (xy 233.217801 -217.285684) (xy 233.271749 -217.277928)
			(xy 233.326251 -217.277928) (xy 233.380199 -217.285684) (xy 233.432494 -217.301039) (xy 233.45192 -217.309911)
			(xy 241.045994 -217.309911) (xy 241.045994 -217.245989) (xy 241.054005 -217.182571) (xy 241.069902 -217.120657)
			(xy 241.093434 -217.061224) (xy 241.124228 -217.005209) (xy 241.161801 -216.953494) (xy 241.205558 -216.906897)
			(xy 241.254811 -216.866152) (xy 241.308782 -216.831901) (xy 241.366621 -216.804684) (xy 241.427414 -216.784931)
			(xy 241.490204 -216.772953) (xy 241.554 -216.76894) (xy 241.617796 -216.772953) (xy 241.680586 -216.784931)
			(xy 241.741379 -216.804684) (xy 241.799218 -216.831901) (xy 241.853189 -216.866152) (xy 241.902442 -216.906897)
			(xy 241.946199 -216.953494) (xy 241.983772 -217.005209) (xy 242.014566 -217.061224) (xy 242.038098 -217.120657)
			(xy 242.053995 -217.182571) (xy 242.062006 -217.245989) (xy 242.062508 -217.27795) (xy 242.062006 -217.309911)
			(xy 242.053995 -217.373329) (xy 242.038098 -217.435243) (xy 242.014566 -217.494676) (xy 241.983772 -217.550691)
			(xy 241.946199 -217.602406) (xy 241.902442 -217.649003) (xy 241.853189 -217.689748) (xy 241.799218 -217.723999)
			(xy 241.741379 -217.751216) (xy 241.680586 -217.770969) (xy 241.617796 -217.782947) (xy 241.554 -217.786961)
			(xy 241.490204 -217.782947) (xy 241.427414 -217.770969) (xy 241.366621 -217.751216) (xy 241.308782 -217.723999)
			(xy 241.254811 -217.689748) (xy 241.205558 -217.649003) (xy 241.161801 -217.602406) (xy 241.124228 -217.550691)
			(xy 241.093434 -217.494676) (xy 241.069902 -217.435243) (xy 241.054005 -217.373329) (xy 241.045994 -217.309911)
			(xy 233.45192 -217.309911) (xy 233.482071 -217.323681) (xy 233.527921 -217.353147) (xy 233.569112 -217.388838)
			(xy 233.604803 -217.430029) (xy 233.634269 -217.475879) (xy 233.656911 -217.525456) (xy 233.672266 -217.577751)
			(xy 233.680022 -217.631699) (xy 233.680508 -217.65895) (xy 233.680046 -217.685884) (xy 233.672458 -217.739216)
			(xy 233.657439 -217.790949) (xy 233.635288 -217.840054) (xy 233.606447 -217.885552) (xy 233.589322 -217.906346)
			(xy 233.582464 -217.914474) (xy 233.576368 -217.934032) (xy 233.586782 -218.029028) (xy 233.596942 -218.046808)
			(xy 233.605578 -218.053412) (xy 233.632036 -218.074064) (xy 233.679803 -218.121217) (xy 233.720948 -218.174246)
			(xy 233.754756 -218.232229) (xy 233.780638 -218.294158) (xy 233.798145 -218.358954) (xy 233.806972 -218.42549)
			(xy 233.807508 -218.45905) (xy 233.807006 -218.491011) (xy 233.798995 -218.554429) (xy 233.783098 -218.616343)
			(xy 233.759566 -218.675776) (xy 233.728772 -218.731791) (xy 233.691199 -218.783506) (xy 233.647442 -218.830103)
			(xy 233.598189 -218.870848) (xy 233.544218 -218.905099) (xy 233.486379 -218.932316) (xy 233.425586 -218.952069)
			(xy 233.362796 -218.964047) (xy 233.299 -218.968061) (xy 233.235204 -218.964047) (xy 233.172414 -218.952069)
			(xy 233.111621 -218.932316) (xy 233.053782 -218.905099) (xy 232.999811 -218.870848) (xy 232.950558 -218.830103)
			(xy 232.906801 -218.783506) (xy 232.869228 -218.731791) (xy 232.838434 -218.675776) (xy 232.814902 -218.616343)
			(xy 232.799005 -218.554429) (xy 232.790994 -218.491011) (xy 232.790492 -218.45905) (xy 219.969155 -218.45905)
			(xy 219.969019 -218.467291) (xy 219.95974 -218.535468) (xy 219.941351 -218.601771) (xy 219.914187 -218.664988)
			(xy 219.878746 -218.723964) (xy 219.835673 -218.777621) (xy 219.811092 -218.801696) (xy 219.803218 -218.809062)
			(xy 219.79509 -218.828874) (xy 219.797376 -218.925902) (xy 219.80652 -218.945206) (xy 219.814902 -218.952318)
			(xy 219.838248 -218.973075) (xy 219.880209 -219.019356) (xy 219.916186 -219.070426) (xy 219.94564 -219.125517)
			(xy 219.968126 -219.183801) (xy 219.983306 -219.244399) (xy 219.990951 -219.306401) (xy 219.991432 -219.337636)
			(xy 219.990907 -219.370255) (xy 219.982561 -219.434958) (xy 219.972045 -219.47505) (xy 235.857542 -219.47505)
			(xy 235.858071 -219.441999) (xy 235.866653 -219.376457) (xy 235.883653 -219.312578) (xy 235.908785 -219.25144)
			(xy 235.941625 -219.194072) (xy 235.981619 -219.141442) (xy 236.028094 -219.094436) (xy 236.080266 -219.053846)
			(xy 236.108494 -219.036646) (xy 236.117638 -219.031058) (xy 236.130084 -219.014294) (xy 236.150912 -218.920822)
			(xy 236.146848 -218.900248) (xy 236.140752 -218.891358) (xy 236.12488 -218.867347) (xy 236.099721 -218.815583)
			(xy 236.082621 -218.760628) (xy 236.073969 -218.703727) (xy 236.073442 -218.67495) (xy 236.073928 -218.647699)
			(xy 236.081684 -218.593751) (xy 236.097039 -218.541456) (xy 236.119681 -218.491879) (xy 236.149147 -218.446029)
			(xy 236.184838 -218.404838) (xy 236.226029 -218.369147) (xy 236.271879 -218.339681) (xy 236.321456 -218.317039)
			(xy 236.373751 -218.301684) (xy 236.427699 -218.293928) (xy 236.482201 -218.293928) (xy 236.536149 -218.301684)
			(xy 236.588444 -218.317039) (xy 236.638021 -218.339681) (xy 236.683871 -218.369147) (xy 236.725062 -218.404838)
			(xy 236.760753 -218.446029) (xy 236.790219 -218.491879) (xy 236.812861 -218.541456) (xy 236.828216 -218.593751)
			(xy 236.835972 -218.647699) (xy 236.836458 -218.67495) (xy 236.835995 -218.701174) (xy 236.828821 -218.75313)
			(xy 236.814601 -218.803615) (xy 236.793604 -218.851677) (xy 236.766225 -218.896412) (xy 236.732978 -218.936977)
			(xy 236.71403 -218.955112) (xy 236.706156 -218.962224) (xy 236.697774 -218.981528) (xy 236.69752 -219.077286)
			(xy 236.704973 -219.094987) (xy 237.743078 -219.094987) (xy 237.748287 -219.032117) (xy 237.761232 -218.970374)
			(xy 237.781715 -218.910707) (xy 237.809421 -218.854032) (xy 237.843925 -218.801219) (xy 237.884697 -218.753079)
			(xy 237.93111 -218.710353) (xy 237.982451 -218.673695) (xy 238.037933 -218.64367) (xy 238.096702 -218.620738)
			(xy 238.157857 -218.605251) (xy 238.220457 -218.597448) (xy 238.252 -218.596972) (xy 238.282461 -218.597415)
			(xy 238.342949 -218.604674) (xy 238.37265 -218.61145) (xy 238.386877 -218.614472) (xy 238.415922 -218.613235)
			(xy 238.443441 -218.603861) (xy 238.467201 -218.58711) (xy 238.485277 -218.564341) (xy 238.496202 -218.537401)
			(xy 238.499089 -218.508473) (xy 238.496856 -218.494102) (xy 238.493898 -218.477367) (xy 238.490717 -218.443531)
			(xy 238.490506 -218.426538) (xy 238.490935 -218.399366) (xy 238.498904 -218.345608) (xy 238.514674 -218.293602)
			(xy 238.537905 -218.244472) (xy 238.568093 -218.199284) (xy 238.604585 -218.159013) (xy 238.646591 -218.124534)
			(xy 238.693201 -218.096591) (xy 238.743407 -218.075789) (xy 238.796123 -218.06258) (xy 238.850205 -218.057249)
			(xy 238.904485 -218.059911) (xy 238.957786 -218.070509) (xy 239.008956 -218.088813) (xy 239.056885 -218.114428)
			(xy 239.100538 -218.146798) (xy 239.138968 -218.185223) (xy 239.171344 -218.228871) (xy 239.196965 -218.276797)
			(xy 239.215277 -218.327964) (xy 239.225882 -218.381264) (xy 239.228552 -218.435543) (xy 239.223229 -218.489626)
			(xy 239.210027 -218.542343) (xy 239.189233 -218.592552) (xy 239.161296 -218.639167) (xy 239.126823 -218.681178)
			(xy 239.086558 -218.717675) (xy 239.041373 -218.74787) (xy 238.992247 -218.771107) (xy 238.940243 -218.786885)
			(xy 238.886486 -218.794861) (xy 238.859314 -218.795346) (xy 238.83239 -218.79433) (xy 238.817873 -218.793811)
			(xy 238.789489 -218.799904) (xy 238.763966 -218.813737) (xy 238.743367 -218.834193) (xy 238.729355 -218.859618)
			(xy 238.723063 -218.887959) (xy 238.724999 -218.916925) (xy 238.72952 -218.930728) (xy 238.739342 -218.958804)
			(xy 238.753137 -219.016664) (xy 238.760084 -219.075739) (xy 238.760508 -219.10548) (xy 238.760054 -219.137023)
			(xy 238.753576 -219.189003) (xy 239.013994 -219.189003) (xy 239.013994 -219.125081) (xy 239.022005 -219.061663)
			(xy 239.037902 -218.999749) (xy 239.061434 -218.940316) (xy 239.092228 -218.884301) (xy 239.129801 -218.832586)
			(xy 239.173558 -218.785989) (xy 239.222811 -218.745244) (xy 239.276782 -218.710993) (xy 239.334621 -218.683776)
			(xy 239.395414 -218.664023) (xy 239.458204 -218.652045) (xy 239.522 -218.648032) (xy 239.585796 -218.652045)
			(xy 239.648586 -218.664023) (xy 239.709379 -218.683776) (xy 239.767218 -218.710993) (xy 239.821189 -218.745244)
			(xy 239.870442 -218.785989) (xy 239.914199 -218.832586) (xy 239.951772 -218.884301) (xy 239.982566 -218.940316)
			(xy 240.006098 -218.999749) (xy 240.021995 -219.061663) (xy 240.030006 -219.125081) (xy 240.030508 -219.157042)
			(xy 240.030006 -219.189003) (xy 240.021995 -219.252421) (xy 240.006098 -219.314335) (xy 239.982566 -219.373768)
			(xy 239.951772 -219.429783) (xy 239.914199 -219.481498) (xy 239.870442 -219.528095) (xy 239.821189 -219.56884)
			(xy 239.767218 -219.603091) (xy 239.709379 -219.630308) (xy 239.648586 -219.650061) (xy 239.585796 -219.662039)
			(xy 239.522 -219.666053) (xy 239.458204 -219.662039) (xy 239.395414 -219.650061) (xy 239.334621 -219.630308)
			(xy 239.276782 -219.603091) (xy 239.222811 -219.56884) (xy 239.173558 -219.528095) (xy 239.129801 -219.481498)
			(xy 239.092228 -219.429783) (xy 239.061434 -219.373768) (xy 239.037902 -219.314335) (xy 239.022005 -219.252421)
			(xy 239.013994 -219.189003) (xy 238.753576 -219.189003) (xy 238.752253 -219.199623) (xy 238.736769 -219.260779)
			(xy 238.713839 -219.319549) (xy 238.683816 -219.375032) (xy 238.64716 -219.426375) (xy 238.604435 -219.472789)
			(xy 238.556297 -219.513563) (xy 238.503486 -219.548069) (xy 238.446811 -219.575777) (xy 238.387145 -219.596263)
			(xy 238.325403 -219.60921) (xy 238.262534 -219.614422) (xy 238.199502 -219.611816) (xy 238.137277 -219.601434)
			(xy 238.076814 -219.583435) (xy 238.019042 -219.558096) (xy 237.964848 -219.525804) (xy 237.915064 -219.487058)
			(xy 237.870455 -219.442451) (xy 237.831707 -219.392669) (xy 237.799414 -219.338476) (xy 237.774072 -219.280704)
			(xy 237.75607 -219.220242) (xy 237.745686 -219.158018) (xy 237.743078 -219.094987) (xy 236.704973 -219.094987)
			(xy 236.705648 -219.09659) (xy 236.713522 -219.103702) (xy 236.734948 -219.124337) (xy 236.77334 -219.169778)
			(xy 236.806169 -219.219387) (xy 236.832985 -219.272488) (xy 236.853423 -219.328354) (xy 236.867204 -219.386224)
			(xy 236.874139 -219.445306) (xy 236.874558 -219.47505) (xy 236.874056 -219.507011) (xy 236.866045 -219.570429)
			(xy 236.850148 -219.632343) (xy 236.826616 -219.691776) (xy 236.795822 -219.747791) (xy 236.758249 -219.799506)
			(xy 236.72304 -219.837) (xy 242.823492 -219.837) (xy 242.823926 -219.807334) (xy 242.830821 -219.748404)
			(xy 242.844529 -219.690677) (xy 242.864863 -219.634939) (xy 242.891547 -219.581946) (xy 242.924219 -219.53242)
			(xy 242.962434 -219.487034) (xy 242.983766 -219.466414) (xy 242.991386 -219.459302) (xy 242.999768 -219.439998)
			(xy 242.999768 -219.345002) (xy 242.991386 -219.325698) (xy 242.983766 -219.318586) (xy 242.962428 -219.297972)
			(xy 242.924218 -219.252581) (xy 242.891549 -219.203053) (xy 242.864864 -219.15006) (xy 242.844527 -219.094322)
			(xy 242.830813 -219.036596) (xy 242.82391 -218.977666) (xy 242.823492 -218.948) (xy 242.82399 -218.916198)
			(xy 242.831911 -218.85309) (xy 242.847643 -218.791463) (xy 242.870939 -218.732279) (xy 242.901435 -218.676464)
			(xy 242.938656 -218.624888) (xy 242.982019 -218.578358) (xy 243.006118 -218.557602) (xy 243.012732 -218.551577)
			(xy 243.021694 -218.536108) (xy 243.023644 -218.527376) (xy 243.028978 -218.497658) (xy 243.030154 -218.488978)
			(xy 243.027309 -218.471708) (xy 243.02339 -218.463876) (xy 243.008547 -218.43616) (xy 242.9875 -218.37692)
			(xy 242.976801 -218.314969) (xy 242.976146 -218.283536) (xy 242.976662 -218.255936) (xy 242.984889 -218.201353)
			(xy 243.001159 -218.148606) (xy 243.025109 -218.098874) (xy 243.056204 -218.053266) (xy 243.093749 -218.012802)
			(xy 243.136906 -217.978385) (xy 243.18471 -217.950786) (xy 243.236094 -217.930619) (xy 243.289909 -217.918336)
			(xy 243.344954 -217.914211) (xy 243.399999 -217.918336) (xy 243.453814 -217.930619) (xy 243.505198 -217.950786)
			(xy 243.553002 -217.978385) (xy 243.596159 -218.012802) (xy 243.633704 -218.053266) (xy 243.664799 -218.098874)
			(xy 243.688749 -218.148606) (xy 243.705019 -218.201353) (xy 243.713246 -218.255936) (xy 243.713762 -218.283536)
			(xy 243.713356 -218.308903) (xy 243.706402 -218.359159) (xy 243.69263 -218.407989) (xy 243.690535 -218.412779)
			(xy 246.776742 -218.412779) (xy 246.776742 -218.348857) (xy 246.784753 -218.285439) (xy 246.80065 -218.223525)
			(xy 246.824182 -218.164092) (xy 246.854976 -218.108077) (xy 246.892549 -218.056362) (xy 246.936306 -218.009765)
			(xy 246.985559 -217.96902) (xy 247.03953 -217.934769) (xy 247.097369 -217.907552) (xy 247.158162 -217.887799)
			(xy 247.220952 -217.875821) (xy 247.284748 -217.871808) (xy 247.348544 -217.875821) (xy 247.411334 -217.887799)
			(xy 247.472127 -217.907552) (xy 247.529966 -217.934769) (xy 247.583937 -217.96902) (xy 247.63319 -218.009765)
			(xy 247.676947 -218.056362) (xy 247.71452 -218.108077) (xy 247.745314 -218.164092) (xy 247.768846 -218.223525)
			(xy 247.784743 -218.285439) (xy 247.792754 -218.348857) (xy 247.793256 -218.380818) (xy 247.792754 -218.412779)
			(xy 247.784743 -218.476197) (xy 247.768846 -218.538111) (xy 247.745314 -218.597544) (xy 247.71452 -218.653559)
			(xy 247.676947 -218.705274) (xy 247.63319 -218.751871) (xy 247.583937 -218.792616) (xy 247.529966 -218.826867)
			(xy 247.472127 -218.854084) (xy 247.411334 -218.873837) (xy 247.348544 -218.885815) (xy 247.284748 -218.889829)
			(xy 247.220952 -218.885815) (xy 247.158162 -218.873837) (xy 247.097369 -218.854084) (xy 247.03953 -218.826867)
			(xy 246.985559 -218.792616) (xy 246.936306 -218.751871) (xy 246.892549 -218.705274) (xy 246.854976 -218.653559)
			(xy 246.824182 -218.597544) (xy 246.80065 -218.538111) (xy 246.784753 -218.476197) (xy 246.776742 -218.412779)
			(xy 243.690535 -218.412779) (xy 243.6723 -218.454472) (xy 243.659406 -218.476322) (xy 243.655115 -218.483973)
			(xy 243.651473 -218.501117) (xy 243.652294 -218.50985) (xy 243.656358 -218.539822) (xy 243.658046 -218.548591)
			(xy 243.666482 -218.564315) (xy 243.672868 -218.570556) (xy 243.695112 -218.591262) (xy 243.735026 -218.637089)
			(xy 243.769197 -218.687345) (xy 243.797136 -218.741314) (xy 243.818447 -218.798227) (xy 243.832825 -218.857274)
			(xy 243.840066 -218.917614) (xy 243.840508 -218.948) (xy 243.840074 -218.977666) (xy 243.833179 -219.036596)
			(xy 243.819471 -219.094323) (xy 243.799137 -219.150061) (xy 243.772453 -219.203054) (xy 243.739781 -219.25258)
			(xy 243.701566 -219.297966) (xy 243.680234 -219.318586) (xy 243.672614 -219.325698) (xy 243.664232 -219.345002)
			(xy 243.664232 -219.439998) (xy 243.672614 -219.459302) (xy 243.680234 -219.466414) (xy 243.701572 -219.487028)
			(xy 243.739782 -219.532419) (xy 243.772451 -219.581947) (xy 243.799136 -219.63494) (xy 243.819473 -219.690678)
			(xy 243.833187 -219.748404) (xy 243.84009 -219.807334) (xy 243.840508 -219.837) (xy 243.840006 -219.868961)
			(xy 243.831995 -219.932379) (xy 243.816098 -219.994293) (xy 243.792566 -220.053726) (xy 243.761772 -220.109741)
			(xy 243.724199 -220.161456) (xy 243.680442 -220.208053) (xy 243.631189 -220.248798) (xy 243.577218 -220.283049)
			(xy 243.519379 -220.310266) (xy 243.458586 -220.330019) (xy 243.395796 -220.341997) (xy 243.332 -220.346011)
			(xy 243.268204 -220.341997) (xy 243.205414 -220.330019) (xy 243.144621 -220.310266) (xy 243.086782 -220.283049)
			(xy 243.032811 -220.248798) (xy 242.983558 -220.208053) (xy 242.939801 -220.161456) (xy 242.902228 -220.109741)
			(xy 242.871434 -220.053726) (xy 242.847902 -219.994293) (xy 242.832005 -219.932379) (xy 242.823994 -219.868961)
			(xy 242.823492 -219.837) (xy 236.72304 -219.837) (xy 236.714492 -219.846103) (xy 236.665239 -219.886848)
			(xy 236.611268 -219.921099) (xy 236.553429 -219.948316) (xy 236.492636 -219.968069) (xy 236.429846 -219.980047)
			(xy 236.36605 -219.984061) (xy 236.302254 -219.980047) (xy 236.239464 -219.968069) (xy 236.178671 -219.948316)
			(xy 236.120832 -219.921099) (xy 236.066861 -219.886848) (xy 236.017608 -219.846103) (xy 235.973851 -219.799506)
			(xy 235.936278 -219.747791) (xy 235.905484 -219.691776) (xy 235.881952 -219.632343) (xy 235.866055 -219.570429)
			(xy 235.858044 -219.507011) (xy 235.857542 -219.47505) (xy 219.972045 -219.47505) (xy 219.966009 -219.498062)
			(xy 219.941525 -219.558532) (xy 219.909509 -219.615375) (xy 219.870488 -219.667657) (xy 219.848176 -219.691458)
			(xy 219.841993 -219.69847) (xy 219.834709 -219.715668) (xy 219.833952 -219.724986) (xy 219.832936 -219.75572)
			(xy 219.833032 -219.765103) (xy 219.839159 -219.782821) (xy 219.844874 -219.790264) (xy 219.863774 -219.813263)
			(xy 219.896657 -219.862888) (xy 219.923528 -219.916009) (xy 219.944021 -219.971901) (xy 219.957858 -220.029802)
			(xy 219.964847 -220.088921) (xy 219.96527 -220.118686) (xy 219.964768 -220.150647) (xy 219.956757 -220.214065)
			(xy 219.94086 -220.275979) (xy 219.917328 -220.335412) (xy 219.886534 -220.391427) (xy 219.848961 -220.443142)
			(xy 219.805204 -220.489739) (xy 219.755951 -220.530484) (xy 219.70198 -220.564735) (xy 219.644141 -220.591952)
			(xy 219.583348 -220.611705) (xy 219.520558 -220.623683) (xy 219.456762 -220.627697) (xy 219.392966 -220.623683)
			(xy 219.330176 -220.611705) (xy 219.269383 -220.591952) (xy 219.211544 -220.564735) (xy 219.157573 -220.530484)
			(xy 219.10832 -220.489739) (xy 219.064563 -220.443142) (xy 219.02699 -220.391427) (xy 218.996196 -220.335412)
			(xy 218.972664 -220.275979) (xy 218.956767 -220.214065) (xy 218.948756 -220.150647) (xy 218.948254 -220.118686)
			(xy 218.948777 -220.086066) (xy 218.957121 -220.021362) (xy 218.97367 -219.958256) (xy 218.998152 -219.897784)
			(xy 219.030166 -219.840938) (xy 219.069185 -219.788653) (xy 219.09151 -219.764864) (xy 219.097697 -219.757854)
			(xy 219.104991 -219.740656) (xy 219.105734 -219.731336) (xy 219.10675 -219.700602) (xy 219.106659 -219.691216)
			(xy 219.100546 -219.673488) (xy 219.094812 -219.666058) (xy 219.075916 -219.643058) (xy 219.043042 -219.593431)
			(xy 219.01618 -219.540309) (xy 218.995695 -219.484416) (xy 218.981868 -219.426517) (xy 218.974888 -219.3674)
			(xy 218.974416 -219.337636) (xy 218.97499 -219.303235) (xy 218.984278 -219.235063) (xy 219.002675 -219.168766)
			(xy 219.029845 -219.105556) (xy 219.065292 -219.046589) (xy 219.108368 -218.99294) (xy 219.132912 -218.968828)
			(xy 219.140786 -218.961462) (xy 219.148914 -218.94165) (xy 219.146628 -218.844622) (xy 219.137484 -218.825318)
			(xy 219.129102 -218.818206) (xy 219.105755 -218.797449) (xy 219.063792 -218.75117) (xy 219.027811 -218.7001)
			(xy 218.998355 -218.645009) (xy 218.975866 -218.586725) (xy 218.960683 -218.526126) (xy 218.953035 -218.464124)
			(xy 218.952572 -218.432888) (xy 218.953054 -218.401553) (xy 218.960754 -218.339359) (xy 218.976035 -218.278581)
			(xy 218.998666 -218.220141) (xy 219.028305 -218.164923) (xy 219.064502 -218.113764) (xy 219.106709 -218.067439)
			(xy 219.154287 -218.02665) (xy 219.180156 -218.008962) (xy 219.190824 -218.002104) (xy 219.202508 -217.980768)
			(xy 219.20581 -217.872818) (xy 219.195396 -217.85072) (xy 219.185236 -217.8431) (xy 219.162122 -217.824558)
			(xy 219.146882 -217.811604) (xy 219.107258 -217.813128) (xy 218.20886 -218.711526) (xy 218.201494 -218.718638)
			(xy 218.193874 -218.737434) (xy 218.193874 -221.996) (xy 229.218996 -221.996) (xy 229.223067 -221.940378)
			(xy 229.235193 -221.885941) (xy 229.255116 -221.83385) (xy 229.282412 -221.785215) (xy 229.316498 -221.741072)
			(xy 229.356647 -221.702363) (xy 229.402005 -221.669912) (xy 229.451605 -221.644411) (xy 229.504389 -221.626404)
			(xy 229.559232 -221.616274) (xy 229.614966 -221.614237) (xy 229.670403 -221.620337) (xy 229.72436 -221.634443)
			(xy 229.775689 -221.656255) (xy 229.823295 -221.685309) (xy 229.866163 -221.720984) (xy 229.90338 -221.762521)
			(xy 229.934153 -221.809034) (xy 229.957825 -221.859531) (xy 229.973893 -221.912938) (xy 229.982013 -221.968114)
			(xy 229.982522 -221.996) (xy 229.982013 -222.023886) (xy 229.973893 -222.079062) (xy 229.957825 -222.132469)
			(xy 229.934153 -222.182966) (xy 229.90338 -222.229479) (xy 229.866163 -222.271016) (xy 229.823295 -222.306691)
			(xy 229.775689 -222.335745) (xy 229.72436 -222.357557) (xy 229.670403 -222.371663) (xy 229.614966 -222.377763)
			(xy 229.559232 -222.375726) (xy 229.504389 -222.365596) (xy 229.451605 -222.347589) (xy 229.402005 -222.322088)
			(xy 229.356647 -222.289637) (xy 229.316498 -222.250928) (xy 229.282412 -222.206785) (xy 229.255116 -222.15815)
			(xy 229.235193 -222.106059) (xy 229.223067 -222.051622) (xy 229.218996 -221.996) (xy 218.193874 -221.996)
			(xy 218.193874 -222.65005) (xy 241.533932 -222.65005) (xy 241.538003 -222.594428) (xy 241.550129 -222.539991)
			(xy 241.570052 -222.4879) (xy 241.597348 -222.439265) (xy 241.631434 -222.395122) (xy 241.671583 -222.356413)
			(xy 241.716941 -222.323962) (xy 241.766541 -222.298461) (xy 241.819325 -222.280454) (xy 241.874168 -222.270324)
			(xy 241.929902 -222.268287) (xy 241.985339 -222.274387) (xy 242.039296 -222.288493) (xy 242.090625 -222.310305)
			(xy 242.138231 -222.339359) (xy 242.181099 -222.375034) (xy 242.218316 -222.416571) (xy 242.249089 -222.463084)
			(xy 242.272761 -222.513581) (xy 242.288829 -222.566988) (xy 242.296949 -222.622164) (xy 242.297458 -222.65005)
			(xy 242.296949 -222.677936) (xy 242.288829 -222.733112) (xy 242.272761 -222.786519) (xy 242.249089 -222.837016)
			(xy 242.218316 -222.883529) (xy 242.181099 -222.925066) (xy 242.138231 -222.960741) (xy 242.090625 -222.989795)
			(xy 242.039296 -223.011607) (xy 241.985339 -223.025713) (xy 241.929902 -223.031813) (xy 241.874168 -223.029776)
			(xy 241.819325 -223.019646) (xy 241.766541 -223.001639) (xy 241.716941 -222.976138) (xy 241.671583 -222.943687)
			(xy 241.631434 -222.904978) (xy 241.597348 -222.860835) (xy 241.570052 -222.8122) (xy 241.550129 -222.760109)
			(xy 241.538003 -222.705672) (xy 241.533932 -222.65005) (xy 218.193874 -222.65005) (xy 218.193874 -224.253044)
			(xy 239.40846 -224.253044) (xy 239.412531 -224.197422) (xy 239.424657 -224.142985) (xy 239.44458 -224.090894)
			(xy 239.471876 -224.042259) (xy 239.505962 -223.998116) (xy 239.546111 -223.959407) (xy 239.591469 -223.926956)
			(xy 239.641069 -223.901455) (xy 239.693853 -223.883448) (xy 239.748696 -223.873318) (xy 239.80443 -223.871281)
			(xy 239.859867 -223.877381) (xy 239.913824 -223.891487) (xy 239.965153 -223.913299) (xy 240.012759 -223.942353)
			(xy 240.055627 -223.978028) (xy 240.092844 -224.019565) (xy 240.123617 -224.066078) (xy 240.147289 -224.116575)
			(xy 240.163357 -224.169982) (xy 240.171477 -224.225158) (xy 240.171986 -224.253044) (xy 240.171754 -224.265744)
			(xy 244.254018 -224.265744) (xy 244.258089 -224.210122) (xy 244.270215 -224.155685) (xy 244.290138 -224.103594)
			(xy 244.317434 -224.054959) (xy 244.35152 -224.010816) (xy 244.391669 -223.972107) (xy 244.437027 -223.939656)
			(xy 244.486627 -223.914155) (xy 244.539411 -223.896148) (xy 244.594254 -223.886018) (xy 244.649988 -223.883981)
			(xy 244.705425 -223.890081) (xy 244.759382 -223.904187) (xy 244.810711 -223.925999) (xy 244.858317 -223.955053)
			(xy 244.901185 -223.990728) (xy 244.938402 -224.032265) (xy 244.969175 -224.078778) (xy 244.992847 -224.129275)
			(xy 245.008915 -224.182682) (xy 245.017035 -224.237858) (xy 245.017544 -224.265744) (xy 245.017035 -224.29363)
			(xy 245.008915 -224.348806) (xy 244.992847 -224.402213) (xy 244.969175 -224.45271) (xy 244.938402 -224.499223)
			(xy 244.901185 -224.54076) (xy 244.858317 -224.576435) (xy 244.810711 -224.605489) (xy 244.759382 -224.627301)
			(xy 244.705425 -224.641407) (xy 244.649988 -224.647507) (xy 244.594254 -224.64547) (xy 244.539411 -224.63534)
			(xy 244.486627 -224.617333) (xy 244.437027 -224.591832) (xy 244.391669 -224.559381) (xy 244.35152 -224.520672)
			(xy 244.317434 -224.476529) (xy 244.290138 -224.427894) (xy 244.270215 -224.375803) (xy 244.258089 -224.321366)
			(xy 244.254018 -224.265744) (xy 240.171754 -224.265744) (xy 240.171477 -224.28093) (xy 240.163357 -224.336106)
			(xy 240.147289 -224.389513) (xy 240.123617 -224.44001) (xy 240.092844 -224.486523) (xy 240.055627 -224.52806)
			(xy 240.012759 -224.563735) (xy 239.965153 -224.592789) (xy 239.913824 -224.614601) (xy 239.859867 -224.628707)
			(xy 239.80443 -224.634807) (xy 239.748696 -224.63277) (xy 239.693853 -224.62264) (xy 239.641069 -224.604633)
			(xy 239.591469 -224.579132) (xy 239.546111 -224.546681) (xy 239.505962 -224.507972) (xy 239.471876 -224.463829)
			(xy 239.44458 -224.415194) (xy 239.424657 -224.363103) (xy 239.412531 -224.308666) (xy 239.40846 -224.253044)
			(xy 218.193874 -224.253044) (xy 218.193874 -225.43643) (xy 232.69397 -225.43643) (xy 232.698041 -225.380808)
			(xy 232.710167 -225.326371) (xy 232.73009 -225.27428) (xy 232.757386 -225.225645) (xy 232.791472 -225.181502)
			(xy 232.831621 -225.142793) (xy 232.876979 -225.110342) (xy 232.926579 -225.084841) (xy 232.979363 -225.066834)
			(xy 233.034206 -225.056704) (xy 233.08994 -225.054667) (xy 233.145377 -225.060767) (xy 233.199334 -225.074873)
			(xy 233.250663 -225.096685) (xy 233.298269 -225.125739) (xy 233.341137 -225.161414) (xy 233.378354 -225.202951)
			(xy 233.378361 -225.202961) (xy 240.664994 -225.202961) (xy 240.664994 -225.139039) (xy 240.673005 -225.075621)
			(xy 240.688902 -225.013707) (xy 240.712434 -224.954274) (xy 240.743228 -224.898259) (xy 240.780801 -224.846544)
			(xy 240.824558 -224.799947) (xy 240.873811 -224.759202) (xy 240.927782 -224.724951) (xy 240.985621 -224.697734)
			(xy 241.046414 -224.677981) (xy 241.109204 -224.666003) (xy 241.173 -224.66199) (xy 241.236796 -224.666003)
			(xy 241.299586 -224.677981) (xy 241.360379 -224.697734) (xy 241.418218 -224.724951) (xy 241.472189 -224.759202)
			(xy 241.521442 -224.799947) (xy 241.565199 -224.846544) (xy 241.602772 -224.898259) (xy 241.633566 -224.954274)
			(xy 241.657098 -225.013707) (xy 241.672995 -225.075621) (xy 241.681006 -225.139039) (xy 241.681508 -225.171)
			(xy 241.681006 -225.202961) (xy 241.672995 -225.266379) (xy 241.657098 -225.328293) (xy 241.633566 -225.387726)
			(xy 241.602772 -225.443741) (xy 241.565199 -225.495456) (xy 241.521442 -225.542053) (xy 241.472189 -225.582798)
			(xy 241.418218 -225.617049) (xy 241.360379 -225.644266) (xy 241.299586 -225.664019) (xy 241.236796 -225.675997)
			(xy 241.173 -225.680011) (xy 241.109204 -225.675997) (xy 241.046414 -225.664019) (xy 240.985621 -225.644266)
			(xy 240.927782 -225.617049) (xy 240.873811 -225.582798) (xy 240.824558 -225.542053) (xy 240.780801 -225.495456)
			(xy 240.743228 -225.443741) (xy 240.712434 -225.387726) (xy 240.688902 -225.328293) (xy 240.673005 -225.266379)
			(xy 240.664994 -225.202961) (xy 233.378361 -225.202961) (xy 233.409127 -225.249464) (xy 233.432799 -225.299961)
			(xy 233.448867 -225.353368) (xy 233.456987 -225.408544) (xy 233.457496 -225.43643) (xy 233.456987 -225.464316)
			(xy 233.448867 -225.519492) (xy 233.432799 -225.572899) (xy 233.409127 -225.623396) (xy 233.378354 -225.669909)
			(xy 233.341137 -225.711446) (xy 233.298269 -225.747121) (xy 233.250663 -225.776175) (xy 233.199334 -225.797987)
			(xy 233.145377 -225.812093) (xy 233.08994 -225.818193) (xy 233.034206 -225.816156) (xy 232.979363 -225.806026)
			(xy 232.926579 -225.788019) (xy 232.876979 -225.762518) (xy 232.831621 -225.730067) (xy 232.791472 -225.691358)
			(xy 232.757386 -225.647215) (xy 232.73009 -225.59858) (xy 232.710167 -225.546489) (xy 232.698041 -225.492052)
			(xy 232.69397 -225.43643) (xy 218.193874 -225.43643) (xy 218.193874 -225.833223) (xy 235.738214 -225.833223)
			(xy 235.738218 -225.778727) (xy 235.745977 -225.724786) (xy 235.761333 -225.672499) (xy 235.783975 -225.622929)
			(xy 235.81344 -225.577086) (xy 235.849129 -225.535902) (xy 235.890316 -225.500217) (xy 235.936162 -225.470756)
			(xy 235.985734 -225.44812) (xy 236.038023 -225.432769) (xy 236.091965 -225.425015) (xy 236.146461 -225.425017)
			(xy 236.200402 -225.432774) (xy 236.252689 -225.448129) (xy 236.30226 -225.470769) (xy 236.348104 -225.500232)
			(xy 236.389289 -225.53592) (xy 236.424975 -225.577106) (xy 236.454438 -225.622951) (xy 236.477076 -225.672522)
			(xy 236.492428 -225.724811) (xy 236.500184 -225.778752) (xy 236.50067 -225.806) (xy 236.500007 -225.838115)
			(xy 236.489289 -225.901444) (xy 236.479334 -225.931984) (xy 236.474508 -225.9457) (xy 236.480604 -225.97364)
			(xy 236.563662 -226.06) (xy 236.591348 -226.066858) (xy 236.605318 -226.06254) (xy 236.632021 -226.0548)
			(xy 236.686994 -226.046515) (xy 236.714792 -226.04603) (xy 236.74442 -226.046612) (xy 236.802917 -226.056074)
			(xy 236.859152 -226.074756) (xy 236.911682 -226.102178) (xy 236.935772 -226.119436) (xy 236.9439 -226.125532)
			(xy 236.962442 -226.130612) (xy 237.052358 -226.119436) (xy 237.069376 -226.110038) (xy 237.075726 -226.102164)
			(xy 237.096443 -226.077306) (xy 237.143182 -226.032553) (xy 237.195226 -225.994096) (xy 237.25173 -225.962557)
			(xy 237.311781 -225.938446) (xy 237.374407 -225.922155) (xy 237.438595 -225.913946) (xy 237.47095 -225.913442)
			(xy 237.502918 -225.91382) (xy 237.566349 -225.921827) (xy 237.628277 -225.937722) (xy 237.687724 -225.961254)
			(xy 237.743752 -225.992051) (xy 237.795479 -226.029628) (xy 237.842088 -226.073392) (xy 237.882844 -226.122653)
			(xy 237.917104 -226.176634) (xy 237.944328 -226.234483) (xy 237.964086 -226.295289) (xy 237.976067 -226.358091)
			(xy 237.980082 -226.4219) (xy 237.97888 -226.441) (xy 239.540089 -226.441) (xy 239.544103 -226.377208)
			(xy 239.556079 -226.314422) (xy 239.57583 -226.253632) (xy 239.603043 -226.195796) (xy 239.63729 -226.141827)
			(xy 239.678031 -226.092576) (xy 239.724623 -226.048819) (xy 239.776331 -226.011245) (xy 239.832341 -225.980449)
			(xy 239.891769 -225.956915) (xy 239.953678 -225.941014) (xy 240.017091 -225.932997) (xy 240.04905 -225.932492)
			(xy 240.081431 -225.933) (xy 240.145669 -225.941222) (xy 240.208342 -225.957537) (xy 240.268434 -225.981683)
			(xy 240.324972 -226.013267) (xy 240.377039 -226.051778) (xy 240.423792 -226.096592) (xy 240.444528 -226.121468)
			(xy 240.450878 -226.129088) (xy 240.46815 -226.13874) (xy 240.557812 -226.149662) (xy 240.576862 -226.144582)
			(xy 240.58499 -226.13874) (xy 240.609139 -226.121196) (xy 240.661918 -226.093323) (xy 240.718496 -226.074313)
			(xy 240.777397 -226.06466) (xy 240.80724 -226.064064) (xy 240.834836 -226.064638) (xy 240.88941 -226.07287)
			(xy 240.942148 -226.089142) (xy 240.991872 -226.113093) (xy 241.037471 -226.144186) (xy 241.077927 -226.181728)
			(xy 241.112336 -226.22488) (xy 241.13993 -226.272678) (xy 241.160092 -226.324055) (xy 241.172373 -226.377863)
			(xy 241.176497 -226.4329) (xy 241.172373 -226.487937) (xy 241.160092 -226.541745) (xy 241.13993 -226.593122)
			(xy 241.112336 -226.64092) (xy 241.077927 -226.684072) (xy 241.037471 -226.721614) (xy 240.991872 -226.752707)
			(xy 240.942148 -226.776658) (xy 240.88941 -226.79293) (xy 240.834836 -226.801162) (xy 240.80724 -226.80168)
			(xy 240.778392 -226.801121) (xy 240.721399 -226.792134) (xy 240.666504 -226.774375) (xy 240.615048 -226.748276)
			(xy 240.59134 -226.73183) (xy 240.583212 -226.725988) (xy 240.563908 -226.721162) (xy 240.4745 -226.734116)
			(xy 240.457482 -226.744276) (xy 240.451386 -226.751896) (xy 240.430694 -226.777827) (xy 240.383658 -226.82461)
			(xy 240.330935 -226.864876) (xy 240.273421 -226.897941) (xy 240.212095 -226.923242) (xy 240.147998 -226.94035)
			(xy 240.08222 -226.948974) (xy 240.04905 -226.949508) (xy 240.017091 -226.949003) (xy 239.953678 -226.940986)
			(xy 239.891769 -226.925085) (xy 239.832341 -226.901551) (xy 239.776331 -226.870755) (xy 239.724623 -226.833181)
			(xy 239.678031 -226.789424) (xy 239.63729 -226.740173) (xy 239.603043 -226.686204) (xy 239.57583 -226.628368)
			(xy 239.556079 -226.567578) (xy 239.544103 -226.504792) (xy 239.540089 -226.441) (xy 237.97888 -226.441)
			(xy 237.976067 -226.485709) (xy 237.964086 -226.548511) (xy 237.944328 -226.609317) (xy 237.917104 -226.667166)
			(xy 237.882844 -226.721147) (xy 237.842088 -226.770408) (xy 237.795479 -226.814172) (xy 237.743752 -226.851749)
			(xy 237.687724 -226.882546) (xy 237.628277 -226.906078) (xy 237.566349 -226.921973) (xy 237.502918 -226.92998)
			(xy 237.47095 -226.930458) (xy 237.437909 -226.929915) (xy 237.372384 -226.921354) (xy 237.308518 -226.904382)
			(xy 237.247387 -226.879285) (xy 237.190019 -226.846486) (xy 237.137379 -226.806537) (xy 237.090355 -226.760109)
			(xy 237.06963 -226.73437) (xy 237.063534 -226.726242) (xy 237.04677 -226.71659) (xy 236.957108 -226.703636)
			(xy 236.938312 -226.708462) (xy 236.930184 -226.714304) (xy 236.906505 -226.73064) (xy 236.85514 -226.756538)
			(xy 236.800382 -226.774163) (xy 236.743554 -226.783091) (xy 236.714792 -226.783646) (xy 236.688449 -226.783146)
			(xy 236.636301 -226.775647) (xy 236.58575 -226.760804) (xy 236.537825 -226.738919) (xy 236.493503 -226.710436)
			(xy 236.453685 -226.675936) (xy 236.419182 -226.636121) (xy 236.390696 -226.591801) (xy 236.368806 -226.543878)
			(xy 236.353959 -226.493329) (xy 236.346456 -226.44118) (xy 236.345984 -226.414838) (xy 236.346532 -226.38503)
			(xy 236.35611 -226.32619) (xy 236.365034 -226.297744) (xy 236.369606 -226.283774) (xy 236.363256 -226.256088)
			(xy 236.278928 -226.170998) (xy 236.251242 -226.16414) (xy 236.237272 -226.168712) (xy 236.208527 -226.177447)
			(xy 236.149199 -226.186892) (xy 236.119162 -226.187508) (xy 236.091914 -226.186981) (xy 236.037974 -226.17922)
			(xy 235.985687 -226.163862) (xy 235.936118 -226.141219) (xy 235.890275 -226.111753) (xy 235.849093 -226.076062)
			(xy 235.813409 -226.034874) (xy 235.78395 -225.989027) (xy 235.761316 -225.939454) (xy 235.745966 -225.887164)
			(xy 235.738214 -225.833223) (xy 218.193874 -225.833223) (xy 218.193874 -227.457) (xy 233.17099 -227.457)
			(xy 233.175003 -227.393204) (xy 233.186981 -227.330414) (xy 233.206734 -227.269621) (xy 233.233951 -227.211782)
			(xy 233.268202 -227.157811) (xy 233.308947 -227.108558) (xy 233.355544 -227.064801) (xy 233.407259 -227.027228)
			(xy 233.463274 -226.996434) (xy 233.522707 -226.972902) (xy 233.584621 -226.957005) (xy 233.648039 -226.948994)
			(xy 233.68 -226.948492) (xy 233.710215 -226.94893) (xy 233.770218 -226.956117) (xy 233.828945 -226.970367)
			(xy 233.885569 -226.991478) (xy 233.939291 -227.019152) (xy 233.989354 -227.053) (xy 234.012486 -227.072444)
			(xy 234.019623 -227.078069) (xy 234.036678 -227.084313) (xy 234.04576 -227.084636) (xy 234.07624 -227.084636)
			(xy 234.08532 -227.084302) (xy 234.102371 -227.078059) (xy 234.109514 -227.072444) (xy 234.132649 -227.053005)
			(xy 234.182716 -227.019167) (xy 234.236439 -226.991498) (xy 234.293061 -226.970389) (xy 234.351786 -226.956137)
			(xy 234.411786 -226.948942) (xy 234.442 -226.948492) (xy 234.473961 -226.948994) (xy 234.537379 -226.957005)
			(xy 234.599293 -226.972902) (xy 234.658726 -226.996434) (xy 234.714741 -227.027228) (xy 234.766456 -227.064801)
			(xy 234.813053 -227.108558) (xy 234.853798 -227.157811) (xy 234.888049 -227.211782) (xy 234.915266 -227.269621)
			(xy 234.935019 -227.330414) (xy 234.946997 -227.393204) (xy 234.951011 -227.457) (xy 234.946997 -227.520796)
			(xy 234.935019 -227.583586) (xy 234.915266 -227.644379) (xy 234.888049 -227.702218) (xy 234.853798 -227.756189)
			(xy 234.813053 -227.805442) (xy 234.766456 -227.849199) (xy 234.714741 -227.886772) (xy 234.658726 -227.917566)
			(xy 234.599293 -227.941098) (xy 234.537379 -227.956995) (xy 234.473961 -227.965006) (xy 234.442 -227.965508)
			(xy 234.411785 -227.96507) (xy 234.351782 -227.957883) (xy 234.293055 -227.943633) (xy 234.236431 -227.922522)
			(xy 234.182709 -227.894848) (xy 234.132646 -227.861) (xy 234.109514 -227.841556) (xy 234.102377 -227.835931)
			(xy 234.085322 -227.829687) (xy 234.07624 -227.829364) (xy 234.04576 -227.829364) (xy 234.03668 -227.829698)
			(xy 234.019629 -227.835941) (xy 234.012486 -227.841556) (xy 233.989351 -227.860995) (xy 233.939284 -227.894833)
			(xy 233.885561 -227.922502) (xy 233.828939 -227.943611) (xy 233.770214 -227.957863) (xy 233.710214 -227.965058)
			(xy 233.68 -227.965508) (xy 233.648039 -227.965006) (xy 233.584621 -227.956995) (xy 233.522707 -227.941098)
			(xy 233.463274 -227.917566) (xy 233.407259 -227.886772) (xy 233.355544 -227.849199) (xy 233.308947 -227.805442)
			(xy 233.268202 -227.756189) (xy 233.233951 -227.702218) (xy 233.206734 -227.644379) (xy 233.186981 -227.583586)
			(xy 233.175003 -227.520796) (xy 233.17099 -227.457) (xy 218.193874 -227.457) (xy 218.193874 -228.740716)
			(xy 233.380803 -228.740716) (xy 233.384738 -228.686945) (xy 233.396461 -228.634321) (xy 233.415721 -228.583964)
			(xy 233.442107 -228.536947) (xy 233.475059 -228.494274) (xy 233.513872 -228.456853) (xy 233.55772 -228.425483)
			(xy 233.605668 -228.400831) (xy 233.656695 -228.383423) (xy 233.709713 -228.37363) (xy 233.763592 -228.371661)
			(xy 233.817183 -228.377558) (xy 233.869344 -228.391194) (xy 233.918964 -228.412281) (xy 233.964985 -228.440367)
			(xy 234.006427 -228.474855) (xy 234.042405 -228.515009) (xy 234.072153 -228.559973) (xy 234.095038 -228.60879)
			(xy 234.11057 -228.660419) (xy 234.11842 -228.713759) (xy 234.118912 -228.740716) (xy 234.118579 -228.758961)
			(xy 241.788944 -228.758961) (xy 241.788944 -228.695039) (xy 241.796955 -228.631621) (xy 241.812852 -228.569707)
			(xy 241.836384 -228.510274) (xy 241.867178 -228.454259) (xy 241.904751 -228.402544) (xy 241.948508 -228.355947)
			(xy 241.997761 -228.315202) (xy 242.051732 -228.280951) (xy 242.109571 -228.253734) (xy 242.170364 -228.233981)
			(xy 242.233154 -228.222003) (xy 242.29695 -228.21799) (xy 242.360746 -228.222003) (xy 242.423536 -228.233981)
			(xy 242.484329 -228.253734) (xy 242.542168 -228.280951) (xy 242.596139 -228.315202) (xy 242.645392 -228.355947)
			(xy 242.689149 -228.402544) (xy 242.726722 -228.454259) (xy 242.757516 -228.510274) (xy 242.781048 -228.569707)
			(xy 242.796945 -228.631621) (xy 242.804956 -228.695039) (xy 242.805458 -228.727) (xy 242.804956 -228.758961)
			(xy 244.367044 -228.758961) (xy 244.367044 -228.695039) (xy 244.375055 -228.631621) (xy 244.390952 -228.569707)
			(xy 244.414484 -228.510274) (xy 244.445278 -228.454259) (xy 244.482851 -228.402544) (xy 244.526608 -228.355947)
			(xy 244.575861 -228.315202) (xy 244.629832 -228.280951) (xy 244.687671 -228.253734) (xy 244.748464 -228.233981)
			(xy 244.811254 -228.222003) (xy 244.87505 -228.21799) (xy 244.938846 -228.222003) (xy 245.001636 -228.233981)
			(xy 245.062429 -228.253734) (xy 245.120268 -228.280951) (xy 245.174239 -228.315202) (xy 245.223492 -228.355947)
			(xy 245.267249 -228.402544) (xy 245.304822 -228.454259) (xy 245.335616 -228.510274) (xy 245.359148 -228.569707)
			(xy 245.375045 -228.631621) (xy 245.383056 -228.695039) (xy 245.383558 -228.727) (xy 245.383056 -228.758961)
			(xy 245.375045 -228.822379) (xy 245.359148 -228.884293) (xy 245.335616 -228.943726) (xy 245.304822 -228.999741)
			(xy 245.267249 -229.051456) (xy 245.223492 -229.098053) (xy 245.174239 -229.138798) (xy 245.120268 -229.173049)
			(xy 245.062429 -229.200266) (xy 245.001636 -229.220019) (xy 244.938846 -229.231997) (xy 244.87505 -229.236011)
			(xy 244.811254 -229.231997) (xy 244.748464 -229.220019) (xy 244.687671 -229.200266) (xy 244.629832 -229.173049)
			(xy 244.575861 -229.138798) (xy 244.526608 -229.098053) (xy 244.482851 -229.051456) (xy 244.445278 -228.999741)
			(xy 244.414484 -228.943726) (xy 244.390952 -228.884293) (xy 244.375055 -228.822379) (xy 244.367044 -228.758961)
			(xy 242.804956 -228.758961) (xy 242.796945 -228.822379) (xy 242.781048 -228.884293) (xy 242.757516 -228.943726)
			(xy 242.726722 -228.999741) (xy 242.689149 -229.051456) (xy 242.645392 -229.098053) (xy 242.596139 -229.138798)
			(xy 242.542168 -229.173049) (xy 242.484329 -229.200266) (xy 242.423536 -229.220019) (xy 242.360746 -229.231997)
			(xy 242.29695 -229.236011) (xy 242.233154 -229.231997) (xy 242.170364 -229.220019) (xy 242.109571 -229.200266)
			(xy 242.051732 -229.173049) (xy 241.997761 -229.138798) (xy 241.948508 -229.098053) (xy 241.904751 -229.051456)
			(xy 241.867178 -228.999741) (xy 241.836384 -228.943726) (xy 241.812852 -228.884293) (xy 241.796955 -228.822379)
			(xy 241.788944 -228.758961) (xy 234.118579 -228.758961) (xy 234.11842 -228.767673) (xy 234.11057 -228.821013)
			(xy 234.095038 -228.872642) (xy 234.072153 -228.921459) (xy 234.042405 -228.966423) (xy 234.006427 -229.006577)
			(xy 233.964985 -229.041065) (xy 233.918964 -229.069151) (xy 233.869344 -229.090238) (xy 233.817183 -229.103874)
			(xy 233.763592 -229.109771) (xy 233.709713 -229.107802) (xy 233.656695 -229.098009) (xy 233.605668 -229.080601)
			(xy 233.55772 -229.055949) (xy 233.513872 -229.024579) (xy 233.475059 -228.987158) (xy 233.442107 -228.944485)
			(xy 233.415721 -228.897468) (xy 233.396461 -228.847111) (xy 233.384738 -228.794487) (xy 233.380803 -228.740716)
			(xy 218.193874 -228.740716) (xy 218.193874 -230.9096) (xy 227.677997 -230.9096) (xy 227.682122 -230.854559)
			(xy 227.694404 -230.800747) (xy 227.714569 -230.749366) (xy 227.742167 -230.701565) (xy 227.77658 -230.658412)
			(xy 227.817042 -230.620869) (xy 227.862646 -230.589776) (xy 227.912376 -230.565827) (xy 227.965119 -230.549557)
			(xy 228.019698 -230.54133) (xy 228.047296 -230.540814) (xy 228.072772 -230.541226) (xy 228.123244 -230.548211)
			(xy 228.172273 -230.562075) (xy 228.218928 -230.582555) (xy 228.262321 -230.609261) (xy 228.282246 -230.625142)
			(xy 228.290628 -230.632254) (xy 228.311202 -230.637842) (xy 228.407214 -230.623872) (xy 228.425248 -230.612442)
			(xy 228.431344 -230.603298) (xy 228.449097 -230.577641) (xy 228.489862 -230.53041) (xy 228.536101 -230.488521)
			(xy 228.587118 -230.452606) (xy 228.642146 -230.423203) (xy 228.70036 -230.400756) (xy 228.760882 -230.385601)
			(xy 228.822804 -230.377966) (xy 228.854 -230.377492) (xy 228.885961 -230.377994) (xy 228.949379 -230.386005)
			(xy 229.011293 -230.401902) (xy 229.070726 -230.425434) (xy 229.126741 -230.456228) (xy 229.178456 -230.493801)
			(xy 229.225053 -230.537558) (xy 229.265798 -230.586811) (xy 229.300049 -230.640782) (xy 229.327266 -230.698621)
			(xy 229.347019 -230.759414) (xy 229.358997 -230.822204) (xy 229.363011 -230.886) (xy 229.487982 -230.886)
			(xy 229.492053 -230.830378) (xy 229.504179 -230.775941) (xy 229.524102 -230.72385) (xy 229.551398 -230.675215)
			(xy 229.585484 -230.631072) (xy 229.625633 -230.592363) (xy 229.670991 -230.559912) (xy 229.720591 -230.534411)
			(xy 229.773375 -230.516404) (xy 229.828218 -230.506274) (xy 229.883952 -230.504237) (xy 229.939389 -230.510337)
			(xy 229.993346 -230.524443) (xy 230.044675 -230.546255) (xy 230.092281 -230.575309) (xy 230.135149 -230.610984)
			(xy 230.172366 -230.652521) (xy 230.203139 -230.699034) (xy 230.226811 -230.749531) (xy 230.242879 -230.802938)
			(xy 230.250999 -230.858114) (xy 230.251508 -230.886) (xy 230.503982 -230.886) (xy 230.508053 -230.830378)
			(xy 230.520179 -230.775941) (xy 230.540102 -230.72385) (xy 230.567398 -230.675215) (xy 230.601484 -230.631072)
			(xy 230.641633 -230.592363) (xy 230.686991 -230.559912) (xy 230.736591 -230.534411) (xy 230.789375 -230.516404)
			(xy 230.844218 -230.506274) (xy 230.899952 -230.504237) (xy 230.955389 -230.510337) (xy 231.009346 -230.524443)
			(xy 231.060675 -230.546255) (xy 231.108281 -230.575309) (xy 231.151149 -230.610984) (xy 231.188366 -230.652521)
			(xy 231.219139 -230.699034) (xy 231.242811 -230.749531) (xy 231.258879 -230.802938) (xy 231.266999 -230.858114)
			(xy 231.267508 -230.886) (xy 231.39299 -230.886) (xy 231.397003 -230.822204) (xy 231.408981 -230.759414)
			(xy 231.428734 -230.698621) (xy 231.455951 -230.640782) (xy 231.490202 -230.586811) (xy 231.530947 -230.537558)
			(xy 231.577544 -230.493801) (xy 231.629259 -230.456228) (xy 231.685274 -230.425434) (xy 231.744707 -230.401902)
			(xy 231.806621 -230.386005) (xy 231.870039 -230.377994) (xy 231.902 -230.377492) (xy 231.93328 -230.377911)
			(xy 231.995369 -230.385575) (xy 232.056047 -230.400801) (xy 232.114399 -230.423358) (xy 232.169542 -230.452904)
			(xy 232.220642 -230.488995) (xy 232.266928 -230.531083) (xy 232.307699 -230.578532) (xy 232.325418 -230.604314)
			(xy 232.33287 -230.614474) (xy 232.355001 -230.62646) (xy 232.367582 -230.627174) (xy 232.452418 -230.627174)
			(xy 232.465001 -230.626494) (xy 232.48712 -230.614472) (xy 232.494582 -230.604314) (xy 232.512344 -230.578567)
			(xy 232.553124 -230.531139) (xy 232.599411 -230.489068) (xy 232.650508 -230.45299) (xy 232.705642 -230.42345)
			(xy 232.763983 -230.400892) (xy 232.824649 -230.385657) (xy 232.886725 -230.377976) (xy 232.918 -230.377492)
			(xy 232.949131 -230.377969) (xy 233.010926 -230.385571) (xy 233.071331 -230.400661) (xy 233.129441 -230.423013)
			(xy 233.184388 -230.452293) (xy 233.235349 -230.488063) (xy 233.281561 -230.529787) (xy 233.302302 -230.553006)
			(xy 233.308652 -230.560372) (xy 233.325416 -230.569008) (xy 233.4133 -230.578914) (xy 233.431588 -230.573834)
			(xy 233.439462 -230.567992) (xy 233.463424 -230.551028) (xy 233.51558 -230.524078) (xy 233.571344 -230.505723)
			(xy 233.62931 -230.496425) (xy 233.658664 -230.495856) (xy 233.686265 -230.496416) (xy 233.74085 -230.504638)
			(xy 233.7936 -230.520905) (xy 233.826947 -230.536961) (xy 234.568994 -230.536961) (xy 234.568994 -230.473039)
			(xy 234.577005 -230.409621) (xy 234.592902 -230.347707) (xy 234.616434 -230.288274) (xy 234.647228 -230.232259)
			(xy 234.684801 -230.180544) (xy 234.728558 -230.133947) (xy 234.777811 -230.093202) (xy 234.831782 -230.058951)
			(xy 234.889621 -230.031734) (xy 234.950414 -230.011981) (xy 235.013204 -230.000003) (xy 235.077 -229.99599)
			(xy 235.140796 -230.000003) (xy 235.203586 -230.011981) (xy 235.264379 -230.031734) (xy 235.322218 -230.058951)
			(xy 235.376189 -230.093202) (xy 235.425442 -230.133947) (xy 235.469199 -230.180544) (xy 235.506772 -230.232259)
			(xy 235.537566 -230.288274) (xy 235.561098 -230.347707) (xy 235.576995 -230.409621) (xy 235.585006 -230.473039)
			(xy 235.585508 -230.505) (xy 235.585006 -230.536961) (xy 237.870994 -230.536961) (xy 237.870994 -230.473039)
			(xy 237.879005 -230.409621) (xy 237.894902 -230.347707) (xy 237.918434 -230.288274) (xy 237.949228 -230.232259)
			(xy 237.986801 -230.180544) (xy 238.030558 -230.133947) (xy 238.079811 -230.093202) (xy 238.133782 -230.058951)
			(xy 238.191621 -230.031734) (xy 238.252414 -230.011981) (xy 238.315204 -230.000003) (xy 238.379 -229.99599)
			(xy 238.442796 -230.000003) (xy 238.505586 -230.011981) (xy 238.566379 -230.031734) (xy 238.624218 -230.058951)
			(xy 238.678189 -230.093202) (xy 238.727442 -230.133947) (xy 238.771199 -230.180544) (xy 238.808772 -230.232259)
			(xy 238.819075 -230.251) (xy 242.588089 -230.251) (xy 242.592103 -230.187208) (xy 242.604079 -230.124422)
			(xy 242.62383 -230.063632) (xy 242.651043 -230.005796) (xy 242.68529 -229.951827) (xy 242.726031 -229.902576)
			(xy 242.772623 -229.858819) (xy 242.824331 -229.821245) (xy 242.880341 -229.790449) (xy 242.939769 -229.766915)
			(xy 243.001678 -229.751014) (xy 243.065091 -229.742997) (xy 243.09705 -229.742492) (xy 243.130826 -229.743079)
			(xy 243.197782 -229.752034) (xy 243.262961 -229.769779) (xy 243.325216 -229.796001) (xy 243.383449 -229.830239)
			(xy 243.436633 -229.871888) (xy 243.483832 -229.920216) (xy 243.504466 -229.946962) (xy 243.512119 -229.956109)
			(xy 243.533448 -229.966708) (xy 243.54536 -229.967282) (xy 243.62664 -229.967282) (xy 243.638552 -229.96671)
			(xy 243.659883 -229.95611) (xy 243.667534 -229.946962) (xy 243.688184 -229.920231) (xy 243.735394 -229.871919)
			(xy 243.788581 -229.83028) (xy 243.846811 -229.796044) (xy 243.909058 -229.769814) (xy 243.974228 -229.75205)
			(xy 244.041176 -229.743067) (xy 244.07495 -229.742492) (xy 244.106914 -229.74297) (xy 244.17034 -229.750977)
			(xy 244.232261 -229.76687) (xy 244.291702 -229.790399) (xy 244.347726 -229.821193) (xy 244.399447 -229.858767)
			(xy 244.446052 -229.902526) (xy 244.486803 -229.951783) (xy 244.52106 -230.005758) (xy 244.548281 -230.063602)
			(xy 244.568037 -230.124401) (xy 244.580017 -230.187197) (xy 244.584032 -230.251) (xy 244.580017 -230.314803)
			(xy 244.568037 -230.377599) (xy 244.548281 -230.438398) (xy 244.52106 -230.496242) (xy 244.486803 -230.550217)
			(xy 244.446052 -230.599474) (xy 244.399447 -230.643233) (xy 244.347726 -230.680807) (xy 244.291702 -230.711601)
			(xy 244.232261 -230.73513) (xy 244.17034 -230.751023) (xy 244.106914 -230.75903) (xy 244.07495 -230.759508)
			(xy 244.041174 -230.758921) (xy 243.974218 -230.749966) (xy 243.909039 -230.732221) (xy 243.846784 -230.705999)
			(xy 243.788551 -230.671761) (xy 243.735367 -230.630112) (xy 243.688168 -230.581784) (xy 243.667534 -230.555038)
			(xy 243.659881 -230.545891) (xy 243.638552 -230.535292) (xy 243.62664 -230.534718) (xy 243.54536 -230.534718)
			(xy 243.533448 -230.53529) (xy 243.512117 -230.54589) (xy 243.504466 -230.555038) (xy 243.483816 -230.581769)
			(xy 243.436606 -230.630081) (xy 243.383419 -230.67172) (xy 243.325189 -230.705956) (xy 243.262942 -230.732186)
			(xy 243.197772 -230.74995) (xy 243.130824 -230.758933) (xy 243.09705 -230.759508) (xy 243.065091 -230.759003)
			(xy 243.001678 -230.750986) (xy 242.939769 -230.735085) (xy 242.880341 -230.711551) (xy 242.824331 -230.680755)
			(xy 242.772623 -230.643181) (xy 242.726031 -230.599424) (xy 242.68529 -230.550173) (xy 242.651043 -230.496204)
			(xy 242.62383 -230.438368) (xy 242.604079 -230.377578) (xy 242.592103 -230.314792) (xy 242.588089 -230.251)
			(xy 238.819075 -230.251) (xy 238.839566 -230.288274) (xy 238.863098 -230.347707) (xy 238.878995 -230.409621)
			(xy 238.887006 -230.473039) (xy 238.887508 -230.505) (xy 238.887006 -230.536961) (xy 238.878995 -230.600379)
			(xy 238.863098 -230.662293) (xy 238.839566 -230.721726) (xy 238.808772 -230.777741) (xy 238.771199 -230.829456)
			(xy 238.727442 -230.876053) (xy 238.678189 -230.916798) (xy 238.624218 -230.951049) (xy 238.566379 -230.978266)
			(xy 238.505586 -230.998019) (xy 238.442796 -231.009997) (xy 238.379 -231.014011) (xy 238.315204 -231.009997)
			(xy 238.252414 -230.998019) (xy 238.191621 -230.978266) (xy 238.133782 -230.951049) (xy 238.079811 -230.916798)
			(xy 238.030558 -230.876053) (xy 237.986801 -230.829456) (xy 237.949228 -230.777741) (xy 237.918434 -230.721726)
			(xy 237.894902 -230.662293) (xy 237.879005 -230.600379) (xy 237.870994 -230.536961) (xy 235.585006 -230.536961)
			(xy 235.576995 -230.600379) (xy 235.561098 -230.662293) (xy 235.537566 -230.721726) (xy 235.506772 -230.777741)
			(xy 235.469199 -230.829456) (xy 235.425442 -230.876053) (xy 235.376189 -230.916798) (xy 235.322218 -230.951049)
			(xy 235.264379 -230.978266) (xy 235.203586 -230.998019) (xy 235.140796 -231.009997) (xy 235.077 -231.014011)
			(xy 235.013204 -231.009997) (xy 234.950414 -230.998019) (xy 234.889621 -230.978266) (xy 234.831782 -230.951049)
			(xy 234.777811 -230.916798) (xy 234.728558 -230.876053) (xy 234.684801 -230.829456) (xy 234.647228 -230.777741)
			(xy 234.616434 -230.721726) (xy 234.592902 -230.662293) (xy 234.577005 -230.600379) (xy 234.568994 -230.536961)
			(xy 233.826947 -230.536961) (xy 233.843336 -230.544852) (xy 233.888948 -230.575945) (xy 233.929415 -230.61349)
			(xy 233.963834 -230.656646) (xy 233.991436 -230.704451) (xy 234.011605 -230.755836) (xy 234.023889 -230.809653)
			(xy 234.028015 -230.8647) (xy 234.023889 -230.919747) (xy 234.011605 -230.973564) (xy 233.991436 -231.024949)
			(xy 233.963834 -231.072754) (xy 233.929415 -231.11591) (xy 233.888948 -231.153455) (xy 233.843336 -231.184548)
			(xy 233.7936 -231.208495) (xy 233.74085 -231.224762) (xy 233.686265 -231.232984) (xy 233.658664 -231.233472)
			(xy 233.631941 -231.232999) (xy 233.579054 -231.225281) (xy 233.527835 -231.210011) (xy 233.479356 -231.187508)
			(xy 233.456734 -231.173274) (xy 233.448606 -231.16794) (xy 233.430064 -231.16413) (xy 233.342942 -231.178862)
			(xy 233.326686 -231.188768) (xy 233.320844 -231.196388) (xy 233.300159 -231.222392) (xy 233.253082 -231.269284)
			(xy 233.2003 -231.309647) (xy 233.142712 -231.342795) (xy 233.081298 -231.368162) (xy 233.017104 -231.385318)
			(xy 232.951223 -231.393969) (xy 232.918 -231.394508) (xy 232.88672 -231.394089) (xy 232.824631 -231.386425)
			(xy 232.763953 -231.371199) (xy 232.705601 -231.348642) (xy 232.650458 -231.319096) (xy 232.599358 -231.283005)
			(xy 232.553072 -231.240917) (xy 232.512301 -231.193468) (xy 232.494582 -231.167686) (xy 232.48713 -231.157526)
			(xy 232.464999 -231.14554) (xy 232.452418 -231.144826) (xy 232.367582 -231.144826) (xy 232.354999 -231.145506)
			(xy 232.33288 -231.157528) (xy 232.325418 -231.167686) (xy 232.307656 -231.193433) (xy 232.266876 -231.240861)
			(xy 232.220589 -231.282932) (xy 232.169492 -231.31901) (xy 232.114358 -231.34855) (xy 232.056017 -231.371108)
			(xy 231.995351 -231.386343) (xy 231.933275 -231.394024) (xy 231.902 -231.394508) (xy 231.870039 -231.394006)
			(xy 231.806621 -231.385995) (xy 231.744707 -231.370098) (xy 231.685274 -231.346566) (xy 231.629259 -231.315772)
			(xy 231.577544 -231.278199) (xy 231.530947 -231.234442) (xy 231.490202 -231.185189) (xy 231.455951 -231.131218)
			(xy 231.428734 -231.073379) (xy 231.408981 -231.012586) (xy 231.397003 -230.949796) (xy 231.39299 -230.886)
			(xy 231.267508 -230.886) (xy 231.266999 -230.913886) (xy 231.258879 -230.969062) (xy 231.242811 -231.022469)
			(xy 231.219139 -231.072966) (xy 231.188366 -231.119479) (xy 231.151149 -231.161016) (xy 231.108281 -231.196691)
			(xy 231.060675 -231.225745) (xy 231.009346 -231.247557) (xy 230.955389 -231.261663) (xy 230.899952 -231.267763)
			(xy 230.844218 -231.265726) (xy 230.789375 -231.255596) (xy 230.736591 -231.237589) (xy 230.686991 -231.212088)
			(xy 230.641633 -231.179637) (xy 230.601484 -231.140928) (xy 230.567398 -231.096785) (xy 230.540102 -231.04815)
			(xy 230.520179 -230.996059) (xy 230.508053 -230.941622) (xy 230.503982 -230.886) (xy 230.251508 -230.886)
			(xy 230.250999 -230.913886) (xy 230.242879 -230.969062) (xy 230.226811 -231.022469) (xy 230.203139 -231.072966)
			(xy 230.172366 -231.119479) (xy 230.135149 -231.161016) (xy 230.092281 -231.196691) (xy 230.044675 -231.225745)
			(xy 229.993346 -231.247557) (xy 229.939389 -231.261663) (xy 229.883952 -231.267763) (xy 229.828218 -231.265726)
			(xy 229.773375 -231.255596) (xy 229.720591 -231.237589) (xy 229.670991 -231.212088) (xy 229.625633 -231.179637)
			(xy 229.585484 -231.140928) (xy 229.551398 -231.096785) (xy 229.524102 -231.04815) (xy 229.504179 -230.996059)
			(xy 229.492053 -230.941622) (xy 229.487982 -230.886) (xy 229.363011 -230.886) (xy 229.358997 -230.949796)
			(xy 229.347019 -231.012586) (xy 229.327266 -231.073379) (xy 229.300049 -231.131218) (xy 229.265798 -231.185189)
			(xy 229.225053 -231.234442) (xy 229.178456 -231.278199) (xy 229.126741 -231.315772) (xy 229.070726 -231.346566)
			(xy 229.011293 -231.370098) (xy 228.949379 -231.385995) (xy 228.885961 -231.394006) (xy 228.854 -231.394508)
			(xy 228.820467 -231.393993) (xy 228.753982 -231.385171) (xy 228.689236 -231.367682) (xy 228.627352 -231.341829)
			(xy 228.569406 -231.308061) (xy 228.516405 -231.266965) (xy 228.46927 -231.219255) (xy 228.448616 -231.192832)
			(xy 228.442012 -231.184196) (xy 228.423216 -231.173782) (xy 228.326442 -231.1654) (xy 228.306376 -231.172258)
			(xy 228.298248 -231.179878) (xy 228.277671 -231.198302) (xy 228.232051 -231.229433) (xy 228.182297 -231.253412)
			(xy 228.129524 -231.269702) (xy 228.074911 -231.277939) (xy 228.047296 -231.27843) (xy 228.019698 -231.27787)
			(xy 227.965119 -231.269643) (xy 227.912376 -231.253373) (xy 227.862646 -231.229424) (xy 227.817042 -231.198331)
			(xy 227.77658 -231.160788) (xy 227.742167 -231.117635) (xy 227.714569 -231.069834) (xy 227.694404 -231.018453)
			(xy 227.682122 -230.964641) (xy 227.677997 -230.9096) (xy 218.193874 -230.9096) (xy 218.193874 -233.299)
			(xy 229.361492 -233.299) (xy 229.361994 -233.267039) (xy 229.370005 -233.203621) (xy 229.385902 -233.141707)
			(xy 229.409434 -233.082274) (xy 229.440228 -233.026259) (xy 229.477801 -232.974544) (xy 229.521558 -232.927947)
			(xy 229.570811 -232.887202) (xy 229.624782 -232.852951) (xy 229.682621 -232.825734) (xy 229.743414 -232.805981)
			(xy 229.806204 -232.794003) (xy 229.87 -232.78999) (xy 229.933796 -232.794003) (xy 229.996586 -232.805981)
			(xy 230.057379 -232.825734) (xy 230.115218 -232.852951) (xy 230.169189 -232.887202) (xy 230.218442 -232.927947)
			(xy 230.262199 -232.974544) (xy 230.299772 -233.026259) (xy 230.330566 -233.082274) (xy 230.354098 -233.141707)
			(xy 230.369995 -233.203621) (xy 230.378006 -233.267039) (xy 230.378508 -233.299) (xy 232.40899 -233.299)
			(xy 232.413003 -233.235204) (xy 232.424981 -233.172414) (xy 232.444734 -233.111621) (xy 232.471951 -233.053782)
			(xy 232.506202 -232.999811) (xy 232.546947 -232.950558) (xy 232.593544 -232.906801) (xy 232.645259 -232.869228)
			(xy 232.701274 -232.838434) (xy 232.760707 -232.814902) (xy 232.822621 -232.799005) (xy 232.886039 -232.790994)
			(xy 232.918 -232.790492) (xy 232.948418 -232.79091) (xy 232.949165 -232.791) (xy 234.56799 -232.791)
			(xy 234.572003 -232.727204) (xy 234.583981 -232.664414) (xy 234.603734 -232.603621) (xy 234.630951 -232.545782)
			(xy 234.665202 -232.491811) (xy 234.705947 -232.442558) (xy 234.752544 -232.398801) (xy 234.804259 -232.361228)
			(xy 234.860274 -232.330434) (xy 234.919707 -232.306902) (xy 234.981621 -232.291005) (xy 235.045039 -232.282994)
			(xy 235.077 -232.282492) (xy 235.10828 -232.282911) (xy 235.170369 -232.290575) (xy 235.231047 -232.305801)
			(xy 235.289399 -232.328358) (xy 235.344542 -232.357904) (xy 235.395642 -232.393995) (xy 235.441928 -232.436083)
			(xy 235.482699 -232.483532) (xy 235.500418 -232.509314) (xy 235.50787 -232.519474) (xy 235.530001 -232.53146)
			(xy 235.542582 -232.532174) (xy 235.627418 -232.532174) (xy 235.640001 -232.531494) (xy 235.66212 -232.519472)
			(xy 235.669582 -232.509314) (xy 235.688378 -232.483152) (xy 235.694982 -232.474262) (xy 235.699808 -232.453434)
			(xy 235.681266 -232.357422) (xy 235.66882 -232.339896) (xy 235.659422 -232.334308) (xy 235.636256 -232.319928)
			(xy 235.593997 -232.285477) (xy 235.557273 -232.245178) (xy 235.526883 -232.199911) (xy 235.50349 -232.150662)
			(xy 235.487605 -232.098505) (xy 235.479574 -232.044577) (xy 235.479082 -232.017316) (xy 235.479598 -231.989716)
			(xy 235.487825 -231.935133) (xy 235.504095 -231.882386) (xy 235.528045 -231.832654) (xy 235.55914 -231.787046)
			(xy 235.596685 -231.746582) (xy 235.639842 -231.712165) (xy 235.687646 -231.684566) (xy 235.73903 -231.664399)
			(xy 235.792845 -231.652116) (xy 235.84789 -231.647991) (xy 235.902935 -231.652116) (xy 235.95675 -231.664399)
			(xy 236.008134 -231.684566) (xy 236.055938 -231.712165) (xy 236.099095 -231.746582) (xy 236.13664 -231.787046)
			(xy 236.167735 -231.832654) (xy 236.191685 -231.882386) (xy 236.207955 -231.935133) (xy 236.216182 -231.989716)
			(xy 236.216698 -232.017316) (xy 236.216236 -232.043191) (xy 236.20898 -232.094429) (xy 236.194625 -232.144148)
			(xy 236.18444 -232.167938) (xy 236.180122 -232.178098) (xy 236.180122 -232.199434) (xy 236.22 -232.288588)
			(xy 236.236002 -232.302812) (xy 236.24667 -232.306368) (xy 236.278494 -232.317004) (xy 236.339241 -232.345507)
			(xy 236.395709 -232.381755) (xy 236.446917 -232.425119) (xy 236.491973 -232.474843) (xy 236.530094 -232.530064)
			(xy 236.560617 -232.589822) (xy 236.583012 -232.653075) (xy 236.596889 -232.718726) (xy 236.599984 -232.752138)
			(xy 236.600746 -232.761536) (xy 236.608874 -232.778808) (xy 236.673136 -232.838752) (xy 236.690662 -232.845864)
			(xy 236.700314 -232.845864) (xy 236.710756 -232.846045) (xy 236.731597 -232.847443) (xy 236.74197 -232.848658)
			(xy 236.752638 -232.849928) (xy 236.772196 -232.84434) (xy 236.845602 -232.783888) (xy 236.855 -232.7656)
			(xy 236.855762 -232.754932) (xy 236.858517 -232.723259) (xy 236.870897 -232.660899) (xy 236.890954 -232.600569)
			(xy 236.918375 -232.54321) (xy 236.952732 -232.489716) (xy 236.99349 -232.440923) (xy 237.040013 -232.397591)
			(xy 237.091574 -232.360396) (xy 237.14737 -232.329919) (xy 237.20653 -232.306636) (xy 237.268131 -232.290909)
			(xy 237.331212 -232.282983) (xy 237.363 -232.282492) (xy 237.39428 -232.282911) (xy 237.456369 -232.290575)
			(xy 237.517047 -232.305801) (xy 237.575399 -232.328358) (xy 237.630542 -232.357904) (xy 237.681642 -232.393995)
			(xy 237.727928 -232.436083) (xy 237.768699 -232.483532) (xy 237.786418 -232.509314) (xy 237.79387 -232.519474)
			(xy 237.816001 -232.53146) (xy 237.828582 -232.532174) (xy 237.913418 -232.532174) (xy 237.926001 -232.531494)
			(xy 237.94812 -232.519472) (xy 237.955582 -232.509314) (xy 237.973344 -232.483567) (xy 238.014124 -232.436139)
			(xy 238.060411 -232.394068) (xy 238.111508 -232.35799) (xy 238.166642 -232.32845) (xy 238.224983 -232.305892)
			(xy 238.285649 -232.290657) (xy 238.347725 -232.282976) (xy 238.379 -232.282492) (xy 238.409054 -232.282917)
			(xy 238.468742 -232.290014) (xy 238.527178 -232.304096) (xy 238.583546 -232.324968) (xy 238.637062 -232.352338)
			(xy 238.686978 -232.385826) (xy 238.732599 -232.424963) (xy 238.773289 -232.469205) (xy 238.791242 -232.493312)
			(xy 238.798608 -232.503472) (xy 238.821722 -232.514648) (xy 238.931704 -232.51033) (xy 238.953802 -232.497376)
			(xy 238.960406 -232.486454) (xy 238.97774 -232.458852) (xy 239.018399 -232.407909) (xy 239.065237 -232.362582)
			(xy 239.117487 -232.323615) (xy 239.174289 -232.291648) (xy 239.234712 -232.267205) (xy 239.297764 -232.250688)
			(xy 239.36241 -232.242367) (xy 239.395 -232.241852) (xy 239.427784 -232.242333) (xy 239.492809 -232.250762)
			(xy 239.55621 -232.267479) (xy 239.616937 -232.292207) (xy 239.673981 -232.324536) (xy 239.726397 -232.36393)
			(xy 239.773313 -232.409735) (xy 239.794034 -232.435146) (xy 239.801908 -232.445306) (xy 239.825276 -232.455212)
			(xy 239.935766 -232.44556) (xy 239.957102 -232.43159) (xy 239.963198 -232.42016) (xy 239.978043 -232.393576)
			(xy 240.013068 -232.343771) (xy 240.053791 -232.298505) (xy 240.099628 -232.258426) (xy 240.149924 -232.224108)
			(xy 240.203958 -232.196043) (xy 240.260957 -232.174631) (xy 240.320105 -232.16018) (xy 240.380556 -232.152897)
			(xy 240.411 -232.152444) (xy 240.443613 -232.152974) (xy 240.508305 -232.161303) (xy 240.5714 -232.177837)
			(xy 240.631863 -232.202305) (xy 240.6887 -232.234304) (xy 240.740978 -232.27331) (xy 240.787838 -232.318681)
			(xy 240.828511 -232.369672) (xy 240.845848 -232.3973) (xy 240.852452 -232.408222) (xy 240.874296 -232.421176)
			(xy 240.984532 -232.425494) (xy 241.007392 -232.414572) (xy 241.015012 -232.404158) (xy 241.03237 -232.380874)
			(xy 241.071536 -232.33799) (xy 241.115326 -232.29984) (xy 241.163172 -232.266919) (xy 241.214452 -232.239654)
			(xy 241.241326 -232.228644) (xy 241.249512 -232.224949) (xy 241.262899 -232.212996) (xy 241.267488 -232.205276)
			(xy 241.281712 -232.178352) (xy 241.285615 -232.17031) (xy 241.288082 -232.152614) (xy 241.286538 -232.143808)
			(xy 241.282719 -232.124733) (xy 241.278647 -232.086044) (xy 241.27841 -232.066592) (xy 241.278863 -232.041469)
			(xy 241.285678 -231.991687) (xy 241.299196 -231.943293) (xy 241.319164 -231.897185) (xy 241.345214 -231.854218)
			(xy 241.360706 -231.834436) (xy 241.367818 -231.825546) (xy 241.373152 -231.804718) (xy 241.356134 -231.707182)
			(xy 241.343942 -231.689148) (xy 241.33429 -231.683306) (xy 241.306559 -231.666004) (xy 241.255376 -231.625352)
			(xy 241.209823 -231.578476) (xy 241.170653 -231.526149) (xy 241.138512 -231.469235) (xy 241.113928 -231.40867)
			(xy 241.097308 -231.345455) (xy 241.088926 -231.280632) (xy 241.088418 -231.24795) (xy 241.08892 -231.215989)
			(xy 241.096931 -231.152571) (xy 241.112828 -231.090657) (xy 241.13636 -231.031224) (xy 241.167154 -230.975209)
			(xy 241.204727 -230.923494) (xy 241.248484 -230.876897) (xy 241.297737 -230.836152) (xy 241.351708 -230.801901)
			(xy 241.409547 -230.774684) (xy 241.47034 -230.754931) (xy 241.53313 -230.742953) (xy 241.596926 -230.73894)
			(xy 241.660722 -230.742953) (xy 241.723512 -230.754931) (xy 241.784305 -230.774684) (xy 241.842144 -230.801901)
			(xy 241.896115 -230.836152) (xy 241.945368 -230.876897) (xy 241.989125 -230.923494) (xy 242.026698 -230.975209)
			(xy 242.057492 -231.031224) (xy 242.081024 -231.090657) (xy 242.096921 -231.152571) (xy 242.104932 -231.215989)
			(xy 242.105434 -231.24795) (xy 242.104927 -231.28085) (xy 242.096445 -231.346102) (xy 242.079616 -231.409713)
			(xy 242.054721 -231.470623) (xy 242.022176 -231.527811) (xy 241.982526 -231.580324) (xy 241.936433 -231.627282)
			(xy 241.91087 -231.648) (xy 241.90198 -231.654858) (xy 241.892074 -231.674162) (xy 241.886994 -231.772968)
			(xy 241.895122 -231.793288) (xy 241.90325 -231.800908) (xy 241.924211 -231.821919) (xy 241.959778 -231.869426)
			(xy 241.987276 -231.922016) (xy 242.005997 -231.978332) (xy 242.015456 -232.036919) (xy 242.016026 -232.066592)
			(xy 242.015572 -232.09359) (xy 242.007682 -232.147007) (xy 241.992084 -232.198701) (xy 241.969112 -232.247568)
			(xy 241.939258 -232.29256) (xy 241.90316 -232.332716) (xy 241.882676 -232.35031) (xy 241.876057 -232.35633)
			(xy 241.867098 -232.371803) (xy 241.86515 -232.380536) (xy 241.859816 -232.410508) (xy 241.858562 -232.419416)
			(xy 241.861671 -232.43712) (xy 241.865912 -232.445052) (xy 241.865912 -232.445306) (xy 241.87091 -232.453042)
			(xy 241.885213 -232.46462) (xy 241.902677 -232.470422) (xy 241.911886 -232.470452) (xy 241.941096 -232.469182)
			(xy 241.950245 -232.468383) (xy 241.967134 -232.46121) (xy 241.980432 -232.448566) (xy 241.984784 -232.44048)
			(xy 241.998989 -232.412117) (xy 242.033384 -232.358818) (xy 242.074142 -232.310212) (xy 242.120629 -232.267053)
			(xy 242.172124 -232.230011) (xy 242.227827 -232.199663) (xy 242.286872 -232.17648) (xy 242.348342 -232.160821)
			(xy 242.411283 -232.152931) (xy 242.443 -232.152444) (xy 242.474958 -232.153042) (xy 242.53837 -232.161053)
			(xy 242.600278 -232.176948) (xy 242.659706 -232.200477) (xy 242.715716 -232.231269) (xy 242.767425 -232.268838)
			(xy 242.814018 -232.312591) (xy 242.854759 -232.361839) (xy 242.889007 -232.415805) (xy 242.916221 -232.473638)
			(xy 242.935973 -232.534426) (xy 242.947949 -232.59721) (xy 242.951963 -232.661) (xy 242.947949 -232.72479)
			(xy 242.935973 -232.787574) (xy 242.916221 -232.848362) (xy 242.889007 -232.906195) (xy 242.854759 -232.960161)
			(xy 242.814018 -233.009409) (xy 242.767425 -233.053162) (xy 242.715716 -233.090731) (xy 242.659706 -233.121523)
			(xy 242.600278 -233.145052) (xy 242.53837 -233.160947) (xy 242.474958 -233.168958) (xy 242.443 -233.16946)
			(xy 242.412968 -233.169013) (xy 242.353323 -233.161944) (xy 242.294927 -233.147893) (xy 242.238594 -233.127055)
			(xy 242.185111 -233.099721) (xy 242.135223 -233.066273) (xy 242.089627 -233.027177) (xy 242.048957 -232.982979)
			(xy 242.031012 -232.958894) (xy 242.023392 -232.94848) (xy 242.000532 -232.937558) (xy 241.890296 -232.941876)
			(xy 241.868452 -232.95483) (xy 241.861848 -232.965752) (xy 241.844493 -232.993369) (xy 241.803822 -233.044362)
			(xy 241.756964 -233.089735) (xy 241.70469 -233.128745) (xy 241.647856 -233.16075) (xy 241.587396 -233.185226)
			(xy 241.524303 -233.201769) (xy 241.459613 -233.21011) (xy 241.394387 -233.21011) (xy 241.329697 -233.201769)
			(xy 241.266604 -233.185226) (xy 241.206144 -233.16075) (xy 241.14931 -233.128745) (xy 241.097036 -233.089735)
			(xy 241.050178 -233.044362) (xy 241.009507 -232.993369) (xy 240.992152 -232.965752) (xy 240.985548 -232.95483)
			(xy 240.963704 -232.941876) (xy 240.853468 -232.937558) (xy 240.830608 -232.94848) (xy 240.822988 -232.958894)
			(xy 240.80505 -232.982983) (xy 240.764374 -233.027176) (xy 240.718773 -233.066267) (xy 240.668884 -233.099712)
			(xy 240.615401 -233.127045) (xy 240.55907 -233.147885) (xy 240.500675 -233.161942) (xy 240.441031 -233.16902)
			(xy 240.411 -233.16946) (xy 240.378216 -233.168974) (xy 240.313192 -233.160546) (xy 240.24979 -233.143829)
			(xy 240.189064 -233.119102) (xy 240.13202 -233.086773) (xy 240.079604 -233.04738) (xy 240.032687 -233.001576)
			(xy 240.011966 -232.976166) (xy 240.004092 -232.966006) (xy 239.980724 -232.9561) (xy 239.870234 -232.965752)
			(xy 239.848898 -232.979722) (xy 239.842802 -232.991152) (xy 239.827962 -233.017739) (xy 239.792935 -233.067544)
			(xy 239.752212 -233.112809) (xy 239.706374 -233.152888) (xy 239.656078 -233.187205) (xy 239.602043 -233.21527)
			(xy 239.545044 -233.236681) (xy 239.485895 -233.251132) (xy 239.425444 -233.258415) (xy 239.395 -233.258868)
			(xy 239.377802 -233.258745) (xy 239.343482 -233.256457) (xy 239.32642 -233.254296) (xy 239.317309 -233.253391)
			(xy 239.299467 -233.257447) (xy 239.291622 -233.26217) (xy 239.265968 -233.279188) (xy 239.25866 -233.284415)
			(xy 239.247992 -233.298861) (xy 239.24514 -233.307382) (xy 239.237442 -233.332736) (xy 239.215744 -233.381078)
			(xy 239.187351 -233.425815) (xy 239.152846 -233.466029) (xy 239.112941 -233.500889) (xy 239.068457 -233.529678)
			(xy 239.02031 -233.551804) (xy 238.969492 -233.56681) (xy 238.91705 -233.574388) (xy 238.890556 -233.574844)
			(xy 238.862848 -233.574324) (xy 238.808056 -233.566027) (xy 238.755121 -233.549626) (xy 238.705237 -233.52549)
			(xy 238.659525 -233.494162) (xy 238.619014 -233.456348) (xy 238.584616 -233.412899) (xy 238.557106 -233.364792)
			(xy 238.54664 -233.339132) (xy 238.543173 -233.331143) (xy 238.531891 -233.317894) (xy 238.524542 -233.313224)
			(xy 238.49838 -233.298238) (xy 238.490595 -233.294166) (xy 238.473316 -233.291052) (xy 238.464598 -233.292142)
			(xy 238.443363 -233.295559) (xy 238.400507 -233.299248) (xy 238.379 -233.299508) (xy 238.34772 -233.299089)
			(xy 238.285631 -233.291425) (xy 238.224953 -233.276199) (xy 238.166601 -233.253642) (xy 238.111458 -233.224096)
			(xy 238.060358 -233.188005) (xy 238.014072 -233.145917) (xy 237.973301 -233.098468) (xy 237.955582 -233.072686)
			(xy 237.94813 -233.062526) (xy 237.925999 -233.05054) (xy 237.913418 -233.049826) (xy 237.828582 -233.049826)
			(xy 237.815999 -233.050506) (xy 237.79388 -233.062528) (xy 237.786418 -233.072686) (xy 237.768656 -233.098433)
			(xy 237.727876 -233.145861) (xy 237.681589 -233.187932) (xy 237.630492 -233.22401) (xy 237.575358 -233.25355)
			(xy 237.517017 -233.276108) (xy 237.456351 -233.291343) (xy 237.394275 -233.299024) (xy 237.363 -233.299508)
			(xy 237.33186 -233.299076) (xy 237.27004 -233.291524) (xy 237.20961 -233.276459) (xy 237.180374 -233.265726)
			(xy 237.170468 -233.261916) (xy 237.149894 -233.262678) (xy 237.064296 -233.303318) (xy 237.050834 -233.318812)
			(xy 237.047532 -233.328972) (xy 237.039097 -233.353299) (xy 237.016482 -233.399555) (xy 236.987655 -233.442215)
			(xy 236.953174 -233.480452) (xy 236.913711 -233.513522) (xy 236.870033 -233.540783) (xy 236.822987 -233.561705)
			(xy 236.77349 -233.575881) (xy 236.722502 -233.583035) (xy 236.696758 -233.58348) (xy 236.668756 -233.582935)
			(xy 236.613399 -233.574454) (xy 236.559957 -233.55771) (xy 236.509658 -233.533085) (xy 236.463655 -233.501145)
			(xy 236.423004 -233.462624) (xy 236.388639 -233.418404) (xy 236.361346 -233.369501) (xy 236.351064 -233.34345)
			(xy 236.347762 -233.33456) (xy 236.335316 -233.320336) (xy 236.25683 -233.280458) (xy 236.238034 -233.278426)
			(xy 236.22889 -233.280966) (xy 236.195586 -233.289622) (xy 236.127406 -233.298922) (xy 236.093 -233.299508)
			(xy 236.06172 -233.299089) (xy 235.999631 -233.291425) (xy 235.938953 -233.276199) (xy 235.880601 -233.253642)
			(xy 235.825458 -233.224096) (xy 235.774358 -233.188005) (xy 235.728072 -233.145917) (xy 235.687301 -233.098468)
			(xy 235.669582 -233.072686) (xy 235.66213 -233.062526) (xy 235.639999 -233.05054) (xy 235.627418 -233.049826)
			(xy 235.542582 -233.049826) (xy 235.529999 -233.050506) (xy 235.50788 -233.062528) (xy 235.500418 -233.072686)
			(xy 235.482656 -233.098433) (xy 235.441876 -233.145861) (xy 235.395589 -233.187932) (xy 235.344492 -233.22401)
			(xy 235.289358 -233.25355) (xy 235.231017 -233.276108) (xy 235.170351 -233.291343) (xy 235.108275 -233.299024)
			(xy 235.077 -233.299508) (xy 235.045039 -233.299006) (xy 234.981621 -233.290995) (xy 234.919707 -233.275098)
			(xy 234.860274 -233.251566) (xy 234.804259 -233.220772) (xy 234.752544 -233.183199) (xy 234.705947 -233.139442)
			(xy 234.665202 -233.090189) (xy 234.630951 -233.036218) (xy 234.603734 -232.978379) (xy 234.583981 -232.917586)
			(xy 234.572003 -232.854796) (xy 234.56799 -232.791) (xy 232.949165 -232.791) (xy 233.008819 -232.798183)
			(xy 233.06792 -232.812613) (xy 233.124876 -232.833994) (xy 233.178873 -232.86202) (xy 233.229139 -232.896291)
			(xy 233.274955 -232.936316) (xy 233.315667 -232.981523) (xy 233.333544 -233.006138) (xy 233.340656 -233.016044)
			(xy 233.361484 -233.02722) (xy 233.466894 -233.030522) (xy 233.488484 -233.020616) (xy 233.496104 -233.010964)
			(xy 233.513737 -232.989822) (xy 233.554158 -232.952452) (xy 233.599686 -232.921507) (xy 233.64931 -232.897675)
			(xy 233.701924 -232.881486) (xy 233.756361 -232.873299) (xy 233.783886 -232.872788) (xy 233.810231 -232.873253)
			(xy 233.862385 -232.88075) (xy 233.912942 -232.895593) (xy 233.960871 -232.917479) (xy 234.005198 -232.945965)
			(xy 234.045019 -232.980468) (xy 234.079525 -233.020288) (xy 234.108012 -233.064613) (xy 234.129901 -233.112542)
			(xy 234.144746 -233.163097) (xy 234.152246 -233.215251) (xy 234.152694 -233.241596) (xy 234.152273 -233.26664)
			(xy 234.145479 -233.316265) (xy 234.13203 -233.364513) (xy 234.112173 -233.410496) (xy 234.086273 -233.453368)
			(xy 234.054808 -233.492339) (xy 234.03687 -233.50982) (xy 234.026964 -233.519218) (xy 234.019344 -233.54538)
			(xy 234.046014 -233.657648) (xy 234.06481 -233.67746) (xy 234.078018 -233.68127) (xy 234.109206 -233.690948)
			(xy 234.168951 -233.71731) (xy 234.22483 -233.751104) (xy 234.275923 -233.791774) (xy 234.321389 -233.83865)
			(xy 234.36048 -233.89096) (xy 234.392552 -233.947845) (xy 234.417078 -234.008367) (xy 234.433655 -234.071532)
			(xy 234.442008 -234.136298) (xy 234.442508 -234.16895) (xy 234.442006 -234.200911) (xy 234.433995 -234.264329)
			(xy 234.418098 -234.326243) (xy 234.394566 -234.385676) (xy 234.363772 -234.441691) (xy 234.326199 -234.493406)
			(xy 234.282442 -234.540003) (xy 234.233189 -234.580748) (xy 234.179218 -234.614999) (xy 234.121379 -234.642216)
			(xy 234.060586 -234.661969) (xy 233.997796 -234.673947) (xy 233.934 -234.677961) (xy 233.870204 -234.673947)
			(xy 233.807414 -234.661969) (xy 233.746621 -234.642216) (xy 233.688782 -234.614999) (xy 233.634811 -234.580748)
			(xy 233.585558 -234.540003) (xy 233.541801 -234.493406) (xy 233.504228 -234.441691) (xy 233.473434 -234.385676)
			(xy 233.449902 -234.326243) (xy 233.434005 -234.264329) (xy 233.425994 -234.200911) (xy 233.425492 -234.16895)
			(xy 233.425959 -234.138339) (xy 233.433319 -234.077561) (xy 233.447926 -234.018107) (xy 233.469568 -233.960838)
			(xy 233.497933 -233.906583) (xy 233.532609 -233.856128) (xy 233.573095 -233.810204) (xy 233.618804 -233.769475)
			(xy 233.643678 -233.751628) (xy 233.654854 -233.743754) (xy 233.666284 -233.719116) (xy 233.656378 -233.604054)
			(xy 233.640884 -233.581702) (xy 233.628438 -233.576114) (xy 233.601217 -233.562775) (xy 233.551178 -233.528567)
			(xy 233.52887 -233.508042) (xy 233.520234 -233.49966) (xy 233.497628 -233.492802) (xy 233.393488 -233.50982)
			(xy 233.374438 -233.52379) (xy 233.368596 -233.534458) (xy 233.353989 -233.561556) (xy 233.319106 -233.612283)
			(xy 233.278353 -233.658427) (xy 233.232326 -233.699312) (xy 233.181698 -233.734339) (xy 233.127211 -233.762997)
			(xy 233.069663 -233.784866) (xy 233.009895 -233.799625) (xy 232.948782 -233.807059) (xy 232.918 -233.807508)
			(xy 232.886039 -233.807006) (xy 232.822621 -233.798995) (xy 232.760707 -233.783098) (xy 232.701274 -233.759566)
			(xy 232.645259 -233.728772) (xy 232.593544 -233.691199) (xy 232.546947 -233.647442) (xy 232.506202 -233.598189)
			(xy 232.471951 -233.544218) (xy 232.444734 -233.486379) (xy 232.424981 -233.425586) (xy 232.413003 -233.362796)
			(xy 232.40899 -233.299) (xy 230.378508 -233.299) (xy 230.378096 -233.329343) (xy 230.370866 -233.389597)
			(xy 230.356521 -233.448563) (xy 230.335264 -233.505404) (xy 230.307397 -233.559313) (xy 230.273316 -233.609525)
			(xy 230.233504 -233.655327) (xy 230.188527 -233.696068) (xy 230.139024 -233.731171) (xy 230.11257 -233.74604)
			(xy 230.10241 -233.751374) (xy 230.089202 -233.769662) (xy 230.069898 -233.86923) (xy 230.075486 -233.891074)
			(xy 230.082852 -233.899964) (xy 230.098806 -233.919877) (xy 230.125596 -233.963305) (xy 230.146137 -234.010013)
			(xy 230.160035 -234.05911) (xy 230.167026 -234.109655) (xy 230.167434 -234.135168) (xy 230.166918 -234.162768)
			(xy 230.158691 -234.217351) (xy 230.142421 -234.270098) (xy 230.118471 -234.319831) (xy 230.087376 -234.365438)
			(xy 230.049831 -234.405902) (xy 230.006674 -234.440319) (xy 229.95887 -234.467918) (xy 229.907486 -234.488085)
			(xy 229.853671 -234.500368) (xy 229.798626 -234.504493) (xy 229.743581 -234.500368) (xy 229.689766 -234.488085)
			(xy 229.638382 -234.467918) (xy 229.590578 -234.440319) (xy 229.547421 -234.405902) (xy 229.509876 -234.365438)
			(xy 229.478781 -234.319831) (xy 229.454831 -234.270098) (xy 229.438561 -234.217351) (xy 229.430334 -234.162768)
			(xy 229.429818 -234.135168) (xy 229.430287 -234.108666) (xy 229.437872 -234.056208) (xy 229.452896 -234.005378)
			(xy 229.475047 -233.957225) (xy 229.503869 -233.912743) (xy 229.538768 -233.87285) (xy 229.558596 -233.85526)
			(xy 229.567232 -233.84764) (xy 229.576376 -233.827066) (xy 229.574344 -233.72572) (xy 229.564184 -233.7054)
			(xy 229.555294 -233.698288) (xy 229.529831 -233.677574) (xy 229.483917 -233.630665) (xy 229.444426 -233.578234)
			(xy 229.412013 -233.521154) (xy 229.38722 -233.460377) (xy 229.370458 -233.396913) (xy 229.362007 -233.33182)
			(xy 229.361492 -233.299) (xy 218.193874 -233.299) (xy 218.193874 -235.585) (xy 230.376982 -235.585)
			(xy 230.381053 -235.529378) (xy 230.393179 -235.474941) (xy 230.413102 -235.42285) (xy 230.440398 -235.374215)
			(xy 230.474484 -235.330072) (xy 230.514633 -235.291363) (xy 230.559991 -235.258912) (xy 230.609591 -235.233411)
			(xy 230.662375 -235.215404) (xy 230.717218 -235.205274) (xy 230.772952 -235.203237) (xy 230.828389 -235.209337)
			(xy 230.882346 -235.223443) (xy 230.933675 -235.245255) (xy 230.981281 -235.274309) (xy 231.024149 -235.309984)
			(xy 231.061366 -235.351521) (xy 231.092139 -235.398034) (xy 231.115811 -235.448531) (xy 231.131879 -235.501938)
			(xy 231.139999 -235.557114) (xy 231.140508 -235.585) (xy 231.139999 -235.612886) (xy 231.131879 -235.668062)
			(xy 231.11866 -235.712) (xy 232.789982 -235.712) (xy 232.794053 -235.656378) (xy 232.806179 -235.601941)
			(xy 232.826102 -235.54985) (xy 232.853398 -235.501215) (xy 232.887484 -235.457072) (xy 232.927633 -235.418363)
			(xy 232.972991 -235.385912) (xy 233.022591 -235.360411) (xy 233.075375 -235.342404) (xy 233.130218 -235.332274)
			(xy 233.185952 -235.330237) (xy 233.241389 -235.336337) (xy 233.295346 -235.350443) (xy 233.346675 -235.372255)
			(xy 233.394281 -235.401309) (xy 233.437149 -235.436984) (xy 233.474366 -235.478521) (xy 233.505139 -235.525034)
			(xy 233.528811 -235.575531) (xy 233.544879 -235.628938) (xy 233.552999 -235.684114) (xy 233.553508 -235.712)
			(xy 233.552999 -235.739886) (xy 233.544879 -235.795062) (xy 233.528811 -235.848469) (xy 233.505139 -235.898966)
			(xy 233.474366 -235.945479) (xy 233.437149 -235.987016) (xy 233.394281 -236.022691) (xy 233.346675 -236.051745)
			(xy 233.295346 -236.073557) (xy 233.241389 -236.087663) (xy 233.185952 -236.093763) (xy 233.130218 -236.091726)
			(xy 233.075375 -236.081596) (xy 233.022591 -236.063589) (xy 232.972991 -236.038088) (xy 232.927633 -236.005637)
			(xy 232.887484 -235.966928) (xy 232.853398 -235.922785) (xy 232.826102 -235.87415) (xy 232.806179 -235.822059)
			(xy 232.794053 -235.767622) (xy 232.789982 -235.712) (xy 231.11866 -235.712) (xy 231.115811 -235.721469)
			(xy 231.092139 -235.771966) (xy 231.061366 -235.818479) (xy 231.024149 -235.860016) (xy 230.981281 -235.895691)
			(xy 230.933675 -235.924745) (xy 230.882346 -235.946557) (xy 230.828389 -235.960663) (xy 230.772952 -235.966763)
			(xy 230.717218 -235.964726) (xy 230.662375 -235.954596) (xy 230.609591 -235.936589) (xy 230.559991 -235.911088)
			(xy 230.514633 -235.878637) (xy 230.474484 -235.839928) (xy 230.440398 -235.795785) (xy 230.413102 -235.74715)
			(xy 230.393179 -235.695059) (xy 230.381053 -235.640622) (xy 230.376982 -235.585) (xy 218.193874 -235.585)
			(xy 218.193874 -236.474) (xy 231.138982 -236.474) (xy 231.143053 -236.418378) (xy 231.155179 -236.363941)
			(xy 231.175102 -236.31185) (xy 231.202398 -236.263215) (xy 231.236484 -236.219072) (xy 231.276633 -236.180363)
			(xy 231.321991 -236.147912) (xy 231.371591 -236.122411) (xy 231.424375 -236.104404) (xy 231.479218 -236.094274)
			(xy 231.534952 -236.092237) (xy 231.590389 -236.098337) (xy 231.644346 -236.112443) (xy 231.695675 -236.134255)
			(xy 231.743281 -236.163309) (xy 231.786149 -236.198984) (xy 231.823366 -236.240521) (xy 231.854139 -236.287034)
			(xy 231.877811 -236.337531) (xy 231.893879 -236.390938) (xy 231.901999 -236.446114) (xy 231.90216 -236.45495)
			(xy 241.298982 -236.45495) (xy 241.303053 -236.399328) (xy 241.315179 -236.344891) (xy 241.335102 -236.2928)
			(xy 241.362398 -236.244165) (xy 241.396484 -236.200022) (xy 241.436633 -236.161313) (xy 241.481991 -236.128862)
			(xy 241.531591 -236.103361) (xy 241.584375 -236.085354) (xy 241.639218 -236.075224) (xy 241.694952 -236.073187)
			(xy 241.750389 -236.079287) (xy 241.804346 -236.093393) (xy 241.855675 -236.115205) (xy 241.903281 -236.144259)
			(xy 241.946149 -236.179934) (xy 241.983366 -236.221471) (xy 242.014139 -236.267984) (xy 242.037811 -236.318481)
			(xy 242.053879 -236.371888) (xy 242.061999 -236.427064) (xy 242.062508 -236.45495) (xy 242.061999 -236.482836)
			(xy 242.053879 -236.538012) (xy 242.037811 -236.591419) (xy 242.014139 -236.641916) (xy 241.983366 -236.688429)
			(xy 241.946149 -236.729966) (xy 241.903281 -236.765641) (xy 241.855675 -236.794695) (xy 241.804346 -236.816507)
			(xy 241.750389 -236.830613) (xy 241.694952 -236.836713) (xy 241.639218 -236.834676) (xy 241.584375 -236.824546)
			(xy 241.531591 -236.806539) (xy 241.481991 -236.781038) (xy 241.436633 -236.748587) (xy 241.396484 -236.709878)
			(xy 241.362398 -236.665735) (xy 241.335102 -236.6171) (xy 241.315179 -236.565009) (xy 241.303053 -236.510572)
			(xy 241.298982 -236.45495) (xy 231.90216 -236.45495) (xy 231.902508 -236.474) (xy 231.901999 -236.501886)
			(xy 231.893879 -236.557062) (xy 231.877811 -236.610469) (xy 231.854139 -236.660966) (xy 231.823366 -236.707479)
			(xy 231.786149 -236.749016) (xy 231.743281 -236.784691) (xy 231.695675 -236.813745) (xy 231.644346 -236.835557)
			(xy 231.590389 -236.849663) (xy 231.534952 -236.855763) (xy 231.479218 -236.853726) (xy 231.424375 -236.843596)
			(xy 231.371591 -236.825589) (xy 231.321991 -236.800088) (xy 231.276633 -236.767637) (xy 231.236484 -236.728928)
			(xy 231.202398 -236.684785) (xy 231.175102 -236.63615) (xy 231.155179 -236.584059) (xy 231.143053 -236.529622)
			(xy 231.138982 -236.474) (xy 218.193874 -236.474) (xy 218.193874 -237.230666) (xy 236.605316 -237.230666)
			(xy 236.609387 -237.175044) (xy 236.621513 -237.120607) (xy 236.641436 -237.068516) (xy 236.668732 -237.019881)
			(xy 236.702818 -236.975738) (xy 236.742967 -236.937029) (xy 236.788325 -236.904578) (xy 236.837925 -236.879077)
			(xy 236.890709 -236.86107) (xy 236.945552 -236.85094) (xy 237.001286 -236.848903) (xy 237.056723 -236.855003)
			(xy 237.11068 -236.869109) (xy 237.162009 -236.890921) (xy 237.209615 -236.919975) (xy 237.252483 -236.95565)
			(xy 237.2897 -236.997187) (xy 237.320473 -237.0437) (xy 237.344145 -237.094197) (xy 237.360213 -237.147604)
			(xy 237.368333 -237.20278) (xy 237.368842 -237.230666) (xy 237.368333 -237.258552) (xy 237.360213 -237.313728)
			(xy 237.344145 -237.367135) (xy 237.320473 -237.417632) (xy 237.2897 -237.464145) (xy 237.252483 -237.505682)
			(xy 237.209615 -237.541357) (xy 237.162009 -237.570411) (xy 237.11068 -237.592223) (xy 237.056723 -237.606329)
			(xy 237.001286 -237.612429) (xy 236.945552 -237.610392) (xy 236.890709 -237.600262) (xy 236.837925 -237.582255)
			(xy 236.788325 -237.556754) (xy 236.742967 -237.524303) (xy 236.702818 -237.485594) (xy 236.668732 -237.441451)
			(xy 236.641436 -237.392816) (xy 236.621513 -237.340725) (xy 236.609387 -237.286288) (xy 236.605316 -237.230666)
			(xy 218.193874 -237.230666) (xy 218.193874 -237.995163) (xy 228.559862 -237.995163) (xy 228.559862 -237.931241)
			(xy 228.567873 -237.867823) (xy 228.58377 -237.805909) (xy 228.607302 -237.746476) (xy 228.638096 -237.690461)
			(xy 228.675669 -237.638746) (xy 228.719426 -237.592149) (xy 228.768679 -237.551404) (xy 228.82265 -237.517153)
			(xy 228.880489 -237.489936) (xy 228.941282 -237.470183) (xy 229.004072 -237.458205) (xy 229.067868 -237.454192)
			(xy 229.131664 -237.458205) (xy 229.194454 -237.470183) (xy 229.255247 -237.489936) (xy 229.313086 -237.517153)
			(xy 229.367057 -237.551404) (xy 229.41631 -237.592149) (xy 229.460067 -237.638746) (xy 229.49764 -237.690461)
			(xy 229.528434 -237.746476) (xy 229.551966 -237.805909) (xy 229.567863 -237.867823) (xy 229.575874 -237.931241)
			(xy 229.576376 -237.963202) (xy 229.575874 -237.995163) (xy 229.567863 -238.058581) (xy 229.551966 -238.120495)
			(xy 229.528434 -238.179928) (xy 229.49764 -238.235943) (xy 229.460067 -238.287658) (xy 229.41631 -238.334255)
			(xy 229.367057 -238.375) (xy 229.313086 -238.409251) (xy 229.255247 -238.436468) (xy 229.194454 -238.456221)
			(xy 229.131664 -238.468199) (xy 229.067868 -238.472213) (xy 229.004072 -238.468199) (xy 228.941282 -238.456221)
			(xy 228.880489 -238.436468) (xy 228.82265 -238.409251) (xy 228.768679 -238.375) (xy 228.719426 -238.334255)
			(xy 228.675669 -238.287658) (xy 228.638096 -238.235943) (xy 228.607302 -238.179928) (xy 228.58377 -238.120495)
			(xy 228.567873 -238.058581) (xy 228.559862 -237.995163) (xy 218.193874 -237.995163) (xy 218.193874 -239.141)
			(xy 233.04399 -239.141) (xy 233.048003 -239.077204) (xy 233.059981 -239.014414) (xy 233.079734 -238.953621)
			(xy 233.106951 -238.895782) (xy 233.141202 -238.841811) (xy 233.181947 -238.792558) (xy 233.228544 -238.748801)
			(xy 233.280259 -238.711228) (xy 233.336274 -238.680434) (xy 233.395707 -238.656902) (xy 233.457621 -238.641005)
			(xy 233.521039 -238.632994) (xy 233.553 -238.632492) (xy 233.58428 -238.632911) (xy 233.646369 -238.640575)
			(xy 233.707047 -238.655801) (xy 233.765399 -238.678358) (xy 233.820542 -238.707904) (xy 233.871642 -238.743995)
			(xy 233.917928 -238.786083) (xy 233.958699 -238.833532) (xy 233.976418 -238.859314) (xy 233.98387 -238.869474)
			(xy 234.006001 -238.88146) (xy 234.018582 -238.882174) (xy 234.103418 -238.882174) (xy 234.116001 -238.881494)
			(xy 234.13812 -238.869472) (xy 234.145582 -238.859314) (xy 234.163344 -238.833567) (xy 234.204124 -238.786139)
			(xy 234.250411 -238.744068) (xy 234.301508 -238.70799) (xy 234.356642 -238.67845) (xy 234.414983 -238.655892)
			(xy 234.475649 -238.640657) (xy 234.537725 -238.632976) (xy 234.569 -238.632492) (xy 234.596987 -238.632863)
			(xy 234.652625 -238.63899) (xy 234.70725 -238.651201) (xy 234.733846 -238.659924) (xy 234.747308 -238.664496)
			(xy 234.774994 -238.658654) (xy 234.8611 -238.577374) (xy 234.868466 -238.550196) (xy 234.864656 -238.53648)
			(xy 234.858216 -238.51203) (xy 234.851336 -238.461939) (xy 234.85094 -238.436658) (xy 234.851456 -238.409058)
			(xy 234.859683 -238.354475) (xy 234.875953 -238.301728) (xy 234.899903 -238.251996) (xy 234.930998 -238.206388)
			(xy 234.968543 -238.165924) (xy 235.0117 -238.131507) (xy 235.059504 -238.103908) (xy 235.110888 -238.083741)
			(xy 235.164703 -238.071458) (xy 235.219748 -238.067333) (xy 235.274793 -238.071458) (xy 235.328608 -238.083741)
			(xy 235.379992 -238.103908) (xy 235.427796 -238.131507) (xy 235.470953 -238.165924) (xy 235.508498 -238.206388)
			(xy 235.539593 -238.251996) (xy 235.563543 -238.301728) (xy 235.579813 -238.354475) (xy 235.58804 -238.409058)
			(xy 235.588556 -238.436658) (xy 235.588248 -238.459766) (xy 235.58251 -238.505624) (xy 235.577126 -238.528098)
			(xy 235.57357 -238.541306) (xy 235.580936 -238.567214) (xy 235.663486 -238.647986) (xy 235.689394 -238.654844)
			(xy 235.702602 -238.651034) (xy 235.73603 -238.642352) (xy 235.804467 -238.633053) (xy 235.839 -238.632492)
			(xy 235.87028 -238.632911) (xy 235.932369 -238.640575) (xy 235.993047 -238.655801) (xy 236.051399 -238.678358)
			(xy 236.106542 -238.707904) (xy 236.157642 -238.743995) (xy 236.203928 -238.786083) (xy 236.244699 -238.833532)
			(xy 236.262418 -238.859314) (xy 236.26987 -238.869474) (xy 236.292001 -238.88146) (xy 236.304582 -238.882174)
			(xy 236.389418 -238.882174) (xy 236.402001 -238.881494) (xy 236.42412 -238.869472) (xy 236.431582 -238.859314)
			(xy 236.449344 -238.833567) (xy 236.490124 -238.786139) (xy 236.536411 -238.744068) (xy 236.587508 -238.70799)
			(xy 236.642642 -238.67845) (xy 236.700983 -238.655892) (xy 236.761649 -238.640657) (xy 236.823725 -238.632976)
			(xy 236.855 -238.632492) (xy 236.879864 -238.632786) (xy 236.929355 -238.637621) (xy 236.953806 -238.642144)
			(xy 236.964728 -238.64443) (xy 236.986826 -238.638842) (xy 237.065058 -238.575596) (xy 237.074964 -238.55553)
			(xy 237.074964 -238.5441) (xy 237.07604 -238.511157) (xy 237.085607 -238.445943) (xy 237.10352 -238.382512)
			(xy 237.129477 -238.321927) (xy 237.163043 -238.265202) (xy 237.203657 -238.21329) (xy 237.250637 -238.167059)
			(xy 237.303195 -238.127285) (xy 237.360452 -238.094634) (xy 237.421446 -238.069654) (xy 237.485157 -238.052763)
			(xy 237.550516 -238.044244) (xy 237.583472 -238.04372) (xy 237.614205 -238.044164) (xy 237.675222 -238.05157)
			(xy 237.734902 -238.066277) (xy 237.792373 -238.088071) (xy 237.846798 -238.116635) (xy 237.897384 -238.15155)
			(xy 237.943391 -238.192309) (xy 237.98415 -238.238316) (xy 238.019065 -238.288902) (xy 238.047629 -238.343327)
			(xy 238.069423 -238.400798) (xy 238.08413 -238.460478) (xy 238.091536 -238.521495) (xy 238.09198 -238.552228)
			(xy 238.091577 -238.582516) (xy 238.084402 -238.642666) (xy 238.070133 -238.701538) (xy 238.048972 -238.758297)
			(xy 238.021219 -238.812142) (xy 238.004604 -238.83747) (xy 237.997238 -238.848138) (xy 237.994698 -238.873792)
			(xy 238.03864 -238.976408) (xy 238.05896 -238.99241) (xy 238.071914 -238.994442) (xy 238.103879 -239.00026)
			(xy 238.166063 -239.019091) (xy 238.225344 -239.045688) (xy 238.280755 -239.079617) (xy 238.331394 -239.120327)
			(xy 238.376436 -239.167153) (xy 238.415148 -239.219335) (xy 238.4469 -239.276021) (xy 238.471175 -239.33629)
			(xy 238.487577 -239.399159) (xy 238.49584 -239.463605) (xy 238.496348 -239.496092) (xy 238.49605 -239.520181)
			(xy 238.491473 -239.568141) (xy 238.487204 -239.59185) (xy 238.484918 -239.604296) (xy 238.492284 -239.628426)
			(xy 238.569754 -239.705896) (xy 238.593884 -239.713262) (xy 238.60633 -239.710722) (xy 238.623625 -239.707619)
			(xy 238.65861 -239.704315) (xy 238.67618 -239.704118) (xy 238.705115 -239.704704) (xy 238.762273 -239.713763)
			(xy 238.789972 -239.722152) (xy 238.802418 -239.726216) (xy 238.827564 -239.721644) (xy 238.913924 -239.65154)
			(xy 238.92383 -239.628172) (xy 238.922306 -239.615218) (xy 238.921088 -239.602235) (xy 238.919816 -239.576188)
			(xy 238.919766 -239.563148) (xy 238.92028 -239.530014) (xy 238.928894 -239.464307) (xy 238.945971 -239.400276)
			(xy 238.971219 -239.339006) (xy 239.004213 -239.281534) (xy 239.044391 -239.228835) (xy 239.091075 -239.181801)
			(xy 239.143472 -239.14123) (xy 239.200696 -239.107808) (xy 239.261776 -239.082102) (xy 239.325677 -239.064548)
			(xy 239.358424 -239.059466) (xy 239.370616 -239.057688) (xy 239.389666 -239.044734) (xy 239.441482 -238.953802)
			(xy 239.443006 -238.930434) (xy 239.43818 -238.919258) (xy 239.42557 -238.8879) (xy 239.407814 -238.822686)
			(xy 239.398856 -238.755694) (xy 239.398302 -238.7219) (xy 239.398804 -238.689939) (xy 239.406815 -238.626521)
			(xy 239.422712 -238.564607) (xy 239.446244 -238.505174) (xy 239.477038 -238.449159) (xy 239.514611 -238.397444)
			(xy 239.558368 -238.350847) (xy 239.607621 -238.310102) (xy 239.661592 -238.275851) (xy 239.719431 -238.248634)
			(xy 239.780224 -238.228881) (xy 239.843014 -238.216903) (xy 239.90681 -238.21289) (xy 239.970606 -238.216903)
			(xy 240.033396 -238.228881) (xy 240.094189 -238.248634) (xy 240.152028 -238.275851) (xy 240.205999 -238.310102)
			(xy 240.255252 -238.350847) (xy 240.299009 -238.397444) (xy 240.336582 -238.449159) (xy 240.367376 -238.505174)
			(xy 240.390908 -238.564607) (xy 240.406805 -238.626521) (xy 240.414816 -238.689939) (xy 240.415318 -238.7219)
			(xy 240.41477 -238.755034) (xy 240.406161 -238.820739) (xy 240.389091 -238.88477) (xy 240.363847 -238.946041)
			(xy 240.330858 -239.003513) (xy 240.290682 -239.056213) (xy 240.244002 -239.103248) (xy 240.191606 -239.14382)
			(xy 240.134385 -239.177242) (xy 240.073306 -239.202948) (xy 240.009406 -239.220501) (xy 239.97666 -239.225582)
			(xy 239.964468 -239.22736) (xy 239.945418 -239.240314) (xy 239.893602 -239.331246) (xy 239.892078 -239.354614)
			(xy 239.896904 -239.36579) (xy 239.909502 -239.397153) (xy 239.927262 -239.462364) (xy 239.936224 -239.529355)
			(xy 239.936782 -239.563148) (xy 239.936389 -239.593881) (xy 239.928975 -239.654898) (xy 239.91426 -239.714577)
			(xy 239.892459 -239.772047) (xy 239.86389 -239.82647) (xy 239.828969 -239.877053) (xy 239.788206 -239.923058)
			(xy 239.742195 -239.963815) (xy 239.691607 -239.998728) (xy 239.63718 -240.027289) (xy 239.579706 -240.049082)
			(xy 239.520026 -240.063788) (xy 239.459007 -240.071194) (xy 239.428274 -240.071656) (xy 239.397629 -240.071214)
			(xy 239.336783 -240.063839) (xy 239.277263 -240.04921) (xy 239.219931 -240.027538) (xy 239.192562 -240.013744)
			(xy 239.181132 -240.007648) (xy 239.155732 -240.008156) (xy 239.058704 -240.062512) (xy 239.044988 -240.084102)
			(xy 239.044226 -240.097056) (xy 239.041921 -240.124739) (xy 239.030011 -240.178998) (xy 239.010099 -240.230857)
			(xy 238.982636 -240.279143) (xy 238.948242 -240.322765) (xy 238.907695 -240.360735) (xy 238.861912 -240.392196)
			(xy 238.81193 -240.416435) (xy 238.758877 -240.432905) (xy 238.703955 -240.441232) (xy 238.67618 -240.441734)
			(xy 238.649837 -240.441257) (xy 238.597686 -240.433756) (xy 238.547134 -240.418911) (xy 238.499209 -240.397023)
			(xy 238.454886 -240.368538) (xy 238.415068 -240.334036) (xy 238.380565 -240.294218) (xy 238.352079 -240.249896)
			(xy 238.330191 -240.201971) (xy 238.315345 -240.151419) (xy 238.307844 -240.099269) (xy 238.307372 -240.072926)
			(xy 238.307372 -240.067338) (xy 238.307626 -240.054638) (xy 238.296196 -240.032286) (xy 238.20628 -239.969548)
			(xy 238.181388 -239.9665) (xy 238.16945 -239.971072) (xy 238.140363 -239.981691) (xy 238.080266 -239.996617)
			(xy 238.018801 -240.004139) (xy 237.98784 -240.0046) (xy 237.957108 -240.004125) (xy 237.896093 -239.996721)
			(xy 237.836415 -239.982015) (xy 237.778945 -239.960223) (xy 237.72452 -239.931663) (xy 237.673936 -239.89675)
			(xy 237.627929 -239.855994) (xy 237.58717 -239.809989) (xy 237.552254 -239.759407) (xy 237.52369 -239.704985)
			(xy 237.501894 -239.647516) (xy 237.487185 -239.587839) (xy 237.479777 -239.526824) (xy 237.479332 -239.496092)
			(xy 237.47976 -239.465805) (xy 237.486931 -239.405656) (xy 237.501196 -239.346785) (xy 237.522351 -239.290025)
			(xy 237.550097 -239.236179) (xy 237.566708 -239.21085) (xy 237.574074 -239.200182) (xy 237.576614 -239.174528)
			(xy 237.532672 -239.071912) (xy 237.512352 -239.05591) (xy 237.499398 -239.053878) (xy 237.484666 -239.051084)
			(xy 237.473744 -239.048798) (xy 237.451646 -239.054386) (xy 237.373414 -239.117632) (xy 237.363508 -239.137698)
			(xy 237.363508 -239.149128) (xy 237.362486 -239.182073) (xy 237.352914 -239.24729) (xy 237.334997 -239.310724)
			(xy 237.309035 -239.371311) (xy 237.275464 -239.428037) (xy 237.234845 -239.47995) (xy 237.18786 -239.526181)
			(xy 237.135297 -239.565954) (xy 237.078035 -239.598603) (xy 237.017036 -239.623582) (xy 236.953321 -239.64047)
			(xy 236.887958 -239.648986) (xy 236.855 -239.649508) (xy 236.82372 -239.649089) (xy 236.761631 -239.641425)
			(xy 236.700953 -239.626199) (xy 236.642601 -239.603642) (xy 236.587458 -239.574096) (xy 236.536358 -239.538005)
			(xy 236.490072 -239.495917) (xy 236.449301 -239.448468) (xy 236.431582 -239.422686) (xy 236.42413 -239.412526)
			(xy 236.401999 -239.40054) (xy 236.389418 -239.399826) (xy 236.304582 -239.399826) (xy 236.291999 -239.400506)
			(xy 236.26988 -239.412528) (xy 236.262418 -239.422686) (xy 236.244656 -239.448433) (xy 236.203876 -239.495861)
			(xy 236.157589 -239.537932) (xy 236.106492 -239.57401) (xy 236.051358 -239.60355) (xy 235.993017 -239.626108)
			(xy 235.932351 -239.641343) (xy 235.870275 -239.649024) (xy 235.839 -239.649508) (xy 235.808269 -239.649044)
			(xy 235.747255 -239.641635) (xy 235.687579 -239.626927) (xy 235.630111 -239.605132) (xy 235.575689 -239.576569)
			(xy 235.525107 -239.541655) (xy 235.479102 -239.500898) (xy 235.438345 -239.454893) (xy 235.403431 -239.404311)
			(xy 235.374868 -239.349889) (xy 235.353073 -239.292421) (xy 235.338365 -239.232745) (xy 235.330956 -239.171731)
			(xy 235.330492 -239.141) (xy 235.331054 -239.107112) (xy 235.340063 -239.039938) (xy 235.357935 -238.974561)
			(xy 235.370624 -238.943134) (xy 235.375958 -238.930434) (xy 235.372656 -238.903764) (xy 235.30306 -238.811562)
			(xy 235.278422 -238.801148) (xy 235.264706 -238.802672) (xy 235.253512 -238.803979) (xy 235.231017 -238.805376)
			(xy 235.219748 -238.805466) (xy 235.20179 -238.805281) (xy 235.166039 -238.801848) (xy 235.148374 -238.798608)
			(xy 235.134404 -238.795814) (xy 235.107988 -238.805466) (xy 235.033566 -238.897668) (xy 235.029756 -238.925608)
			(xy 235.035598 -238.938562) (xy 235.048846 -238.97065) (xy 235.067521 -239.037511) (xy 235.076932 -239.10629)
			(xy 235.077508 -239.141) (xy 235.077044 -239.171731) (xy 235.069635 -239.232745) (xy 235.054927 -239.292421)
			(xy 235.033132 -239.349889) (xy 235.004569 -239.404311) (xy 234.969655 -239.454893) (xy 234.928898 -239.500898)
			(xy 234.882893 -239.541655) (xy 234.832311 -239.576569) (xy 234.777889 -239.605132) (xy 234.720421 -239.626927)
			(xy 234.660745 -239.641635) (xy 234.599731 -239.649044) (xy 234.569 -239.649508) (xy 234.53772 -239.649089)
			(xy 234.475631 -239.641425) (xy 234.414953 -239.626199) (xy 234.356601 -239.603642) (xy 234.301458 -239.574096)
			(xy 234.250358 -239.538005) (xy 234.204072 -239.495917) (xy 234.163301 -239.448468) (xy 234.145582 -239.422686)
			(xy 234.13813 -239.412526) (xy 234.115999 -239.40054) (xy 234.103418 -239.399826) (xy 234.018582 -239.399826)
			(xy 234.005999 -239.400506) (xy 233.98388 -239.412528) (xy 233.976418 -239.422686) (xy 233.958656 -239.448433)
			(xy 233.917876 -239.495861) (xy 233.871589 -239.537932) (xy 233.820492 -239.57401) (xy 233.765358 -239.60355)
			(xy 233.707017 -239.626108) (xy 233.646351 -239.641343) (xy 233.584275 -239.649024) (xy 233.553 -239.649508)
			(xy 233.521039 -239.649006) (xy 233.457621 -239.640995) (xy 233.395707 -239.625098) (xy 233.336274 -239.601566)
			(xy 233.280259 -239.570772) (xy 233.228544 -239.533199) (xy 233.181947 -239.489442) (xy 233.141202 -239.440189)
			(xy 233.106951 -239.386218) (xy 233.079734 -239.328379) (xy 233.059981 -239.267586) (xy 233.048003 -239.204796)
			(xy 233.04399 -239.141) (xy 218.193874 -239.141) (xy 218.193874 -240.919) (xy 229.087989 -240.919)
			(xy 229.092003 -240.855208) (xy 229.103979 -240.792422) (xy 229.12373 -240.731632) (xy 229.150943 -240.673796)
			(xy 229.18519 -240.619827) (xy 229.225931 -240.570576) (xy 229.272523 -240.526819) (xy 229.324231 -240.489245)
			(xy 229.380241 -240.458449) (xy 229.439669 -240.434915) (xy 229.501578 -240.419014) (xy 229.564991 -240.410997)
			(xy 229.59695 -240.410492) (xy 229.627265 -240.410935) (xy 229.687466 -240.418124) (xy 229.746387 -240.432418)
			(xy 229.80319 -240.453614) (xy 229.857071 -240.481412) (xy 229.907266 -240.515418) (xy 229.930452 -240.534952)
			(xy 229.93731 -240.541302) (xy 229.954328 -240.547398) (xy 230.039672 -240.547398) (xy 230.05669 -240.541302)
			(xy 230.063548 -240.534952) (xy 230.086715 -240.515392) (xy 230.136906 -240.481373) (xy 230.190789 -240.453567)
			(xy 230.247597 -240.432371) (xy 230.306524 -240.418084) (xy 230.366733 -240.410911) (xy 230.39705 -240.410492)
			(xy 230.429576 -240.410969) (xy 230.4941 -240.419247) (xy 230.55704 -240.435688) (xy 230.61737 -240.460023)
			(xy 230.674102 -240.491855) (xy 230.726311 -240.530662) (xy 230.773143 -240.575813) (xy 230.813834 -240.626568)
			(xy 230.847719 -240.682098) (xy 230.874244 -240.741497) (xy 230.892975 -240.803794) (xy 230.903608 -240.867972)
			(xy 230.905304 -240.900458) (xy 230.905558 -240.911888) (xy 230.915972 -240.931954) (xy 230.996236 -240.993422)
			(xy 231.018334 -240.998248) (xy 231.02951 -240.995708) (xy 231.049866 -240.991323) (xy 231.09124 -240.986612)
			(xy 231.11206 -240.98631) (xy 231.139238 -240.987326) (xy 231.149652 -240.988088) (xy 231.168702 -240.981738)
			(xy 231.238806 -240.920016) (xy 231.247696 -240.901982) (xy 231.248204 -240.891568) (xy 231.25036 -240.859486)
			(xy 231.261896 -240.796226) (xy 231.281317 -240.734925) (xy 231.30831 -240.676561) (xy 231.342447 -240.622066)
			(xy 231.383181 -240.57231) (xy 231.429863 -240.528087) (xy 231.481748 -240.490101) (xy 231.538009 -240.45896)
			(xy 231.597746 -240.435161) (xy 231.660007 -240.419082) (xy 231.723798 -240.410982) (xy 231.75595 -240.410492)
			(xy 231.786265 -240.410935) (xy 231.846466 -240.418124) (xy 231.905387 -240.432418) (xy 231.96219 -240.453614)
			(xy 232.016071 -240.481412) (xy 232.066266 -240.515418) (xy 232.089452 -240.534952) (xy 232.09631 -240.541302)
			(xy 232.113328 -240.547398) (xy 232.198672 -240.547398) (xy 232.21569 -240.541302) (xy 232.222548 -240.534952)
			(xy 232.245715 -240.515392) (xy 232.295906 -240.481373) (xy 232.349789 -240.453567) (xy 232.406597 -240.432371)
			(xy 232.465524 -240.418084) (xy 232.525733 -240.410911) (xy 232.55605 -240.410492) (xy 232.588014 -240.41097)
			(xy 232.65144 -240.418977) (xy 232.713361 -240.43487) (xy 232.772802 -240.458399) (xy 232.828826 -240.489193)
			(xy 232.880547 -240.526767) (xy 232.927152 -240.570526) (xy 232.967903 -240.619783) (xy 233.00216 -240.673758)
			(xy 233.029381 -240.731602) (xy 233.049137 -240.792401) (xy 233.061117 -240.855197) (xy 233.065132 -240.919)
			(xy 233.061117 -240.982803) (xy 233.049137 -241.045599) (xy 233.029381 -241.106398) (xy 233.00216 -241.164242)
			(xy 232.996601 -241.173) (xy 234.695492 -241.173) (xy 234.69593 -241.142785) (xy 234.703117 -241.082782)
			(xy 234.717367 -241.024055) (xy 234.738478 -240.967431) (xy 234.766152 -240.913709) (xy 234.8 -240.863646)
			(xy 234.819444 -240.840514) (xy 234.825069 -240.833377) (xy 234.831313 -240.816322) (xy 234.831636 -240.80724)
			(xy 234.831636 -240.77676) (xy 234.831302 -240.76768) (xy 234.825059 -240.750629) (xy 234.819444 -240.743486)
			(xy 234.800005 -240.720351) (xy 234.766167 -240.670284) (xy 234.738498 -240.616561) (xy 234.717389 -240.559939)
			(xy 234.703137 -240.501214) (xy 234.695942 -240.441214) (xy 234.695492 -240.411) (xy 234.695994 -240.379039)
			(xy 234.704005 -240.315621) (xy 234.719902 -240.253707) (xy 234.743434 -240.194274) (xy 234.774228 -240.138259)
			(xy 234.811801 -240.086544) (xy 234.855558 -240.039947) (xy 234.904811 -239.999202) (xy 234.958782 -239.964951)
			(xy 235.016621 -239.937734) (xy 235.077414 -239.917981) (xy 235.140204 -239.906003) (xy 235.204 -239.90199)
			(xy 235.267796 -239.906003) (xy 235.330586 -239.917981) (xy 235.391379 -239.937734) (xy 235.449218 -239.964951)
			(xy 235.503189 -239.999202) (xy 235.552442 -240.039947) (xy 235.596199 -240.086544) (xy 235.633772 -240.138259)
			(xy 235.664566 -240.194274) (xy 235.688098 -240.253707) (xy 235.703995 -240.315621) (xy 235.712006 -240.379039)
			(xy 235.712508 -240.411) (xy 235.71207 -240.441215) (xy 235.704883 -240.501218) (xy 235.690633 -240.559945)
			(xy 235.669522 -240.616569) (xy 235.641848 -240.670291) (xy 235.608 -240.720354) (xy 235.588556 -240.743486)
			(xy 235.582931 -240.750623) (xy 235.576687 -240.767678) (xy 235.576364 -240.77676) (xy 235.576364 -240.80724)
			(xy 235.576698 -240.81632) (xy 235.582941 -240.833371) (xy 235.588556 -240.840514) (xy 235.607995 -240.863649)
			(xy 235.641833 -240.913716) (xy 235.669502 -240.967439) (xy 235.690611 -241.024061) (xy 235.704863 -241.082786)
			(xy 235.712058 -241.142786) (xy 235.712508 -241.173) (xy 235.712069 -241.203577) (xy 235.704713 -241.264288)
			(xy 235.690133 -241.32368) (xy 235.668537 -241.380895) (xy 235.640239 -241.435109) (xy 235.605644 -241.485539)
			(xy 235.565254 -241.531458) (xy 235.51965 -241.572203) (xy 235.49483 -241.590068) (xy 235.48594 -241.596418)
			(xy 235.474764 -241.61496) (xy 235.463842 -241.71275) (xy 235.470446 -241.733578) (xy 235.477812 -241.741706)
			(xy 235.495798 -241.762165) (xy 235.526135 -241.80741) (xy 235.549482 -241.856627) (xy 235.565332 -241.908745)
			(xy 235.57334 -241.962627) (xy 235.573824 -241.989864) (xy 235.573308 -242.017464) (xy 235.565081 -242.072047)
			(xy 235.548811 -242.124794) (xy 235.524861 -242.174527) (xy 235.493766 -242.220134) (xy 235.456221 -242.260598)
			(xy 235.413064 -242.295015) (xy 235.36526 -242.322614) (xy 235.313876 -242.342781) (xy 235.260061 -242.355064)
			(xy 235.205016 -242.359189) (xy 235.149971 -242.355064) (xy 235.096156 -242.342781) (xy 235.044772 -242.322614)
			(xy 234.996968 -242.295015) (xy 234.953811 -242.260598) (xy 234.916266 -242.220134) (xy 234.885171 -242.174527)
			(xy 234.861221 -242.124794) (xy 234.844951 -242.072047) (xy 234.836724 -242.017464) (xy 234.836208 -241.989864)
			(xy 234.836646 -241.962732) (xy 234.844591 -241.909052) (xy 234.860321 -241.857117) (xy 234.883494 -241.80805)
			(xy 234.913611 -241.76291) (xy 234.931458 -241.742468) (xy 234.938824 -241.73434) (xy 234.945682 -241.713512)
			(xy 234.934252 -241.615722) (xy 234.923076 -241.59718) (xy 234.914186 -241.59083) (xy 234.889253 -241.572984)
			(xy 234.843437 -241.532232) (xy 234.802854 -241.486265) (xy 234.768094 -241.435753) (xy 234.73966 -241.381426)
			(xy 234.717966 -241.324075) (xy 234.703325 -241.264531) (xy 234.695952 -241.203659) (xy 234.695492 -241.173)
			(xy 232.996601 -241.173) (xy 232.967903 -241.218217) (xy 232.927152 -241.267474) (xy 232.880547 -241.311233)
			(xy 232.828826 -241.348807) (xy 232.772802 -241.379601) (xy 232.713361 -241.40313) (xy 232.65144 -241.419023)
			(xy 232.588014 -241.42703) (xy 232.55605 -241.427508) (xy 232.525735 -241.427065) (xy 232.465534 -241.419876)
			(xy 232.406613 -241.405582) (xy 232.34981 -241.384386) (xy 232.295929 -241.356588) (xy 232.245734 -241.322582)
			(xy 232.222548 -241.303048) (xy 232.21569 -241.296698) (xy 232.198672 -241.290602) (xy 232.113328 -241.290602)
			(xy 232.09631 -241.296698) (xy 232.089452 -241.303048) (xy 232.066285 -241.322608) (xy 232.016094 -241.356627)
			(xy 231.962211 -241.384433) (xy 231.905403 -241.405629) (xy 231.846476 -241.419916) (xy 231.786267 -241.427089)
			(xy 231.75595 -241.427508) (xy 231.728323 -241.427166) (xy 231.673391 -241.421208) (xy 231.619429 -241.409326)
			(xy 231.593136 -241.400838) (xy 231.58323 -241.397282) (xy 231.563164 -241.398806) (xy 231.479852 -241.44097)
			(xy 231.466898 -241.456464) (xy 231.463596 -241.46637) (xy 231.455367 -241.490948) (xy 231.432982 -241.537694)
			(xy 231.404269 -241.580843) (xy 231.369796 -241.619545) (xy 231.330241 -241.653037) (xy 231.286384 -241.680658)
			(xy 231.239091 -241.701863) (xy 231.189294 -241.716234) (xy 231.137975 -241.723489) (xy 231.11206 -241.723926)
			(xy 231.084981 -241.723401) (xy 231.031405 -241.715489) (xy 230.979563 -241.699826) (xy 230.930568 -241.67675)
			(xy 230.885476 -241.646755) (xy 230.845255 -241.610488) (xy 230.810771 -241.568729) (xy 230.782766 -241.522375)
			(xy 230.761841 -241.472423) (xy 230.754682 -241.446304) (xy 230.751888 -241.435128) (xy 230.73741 -241.417602)
			(xy 230.64597 -241.374422) (xy 230.623364 -241.374422) (xy 230.61295 -241.379248) (xy 230.579025 -241.394495)
			(xy 230.507817 -241.415979) (xy 230.434239 -241.426848) (xy 230.39705 -241.427508) (xy 230.366735 -241.427065)
			(xy 230.306534 -241.419876) (xy 230.247613 -241.405582) (xy 230.19081 -241.384386) (xy 230.136929 -241.356588)
			(xy 230.086734 -241.322582) (xy 230.063548 -241.303048) (xy 230.05669 -241.296698) (xy 230.039672 -241.290602)
			(xy 229.954328 -241.290602) (xy 229.93731 -241.296698) (xy 229.930452 -241.303048) (xy 229.907285 -241.322608)
			(xy 229.857094 -241.356627) (xy 229.803211 -241.384433) (xy 229.746403 -241.405629) (xy 229.687476 -241.419916)
			(xy 229.627267 -241.427089) (xy 229.59695 -241.427508) (xy 229.564991 -241.427003) (xy 229.501578 -241.418986)
			(xy 229.439669 -241.403085) (xy 229.380241 -241.379551) (xy 229.324231 -241.348755) (xy 229.272523 -241.311181)
			(xy 229.225931 -241.267424) (xy 229.18519 -241.218173) (xy 229.150943 -241.164204) (xy 229.12373 -241.106368)
			(xy 229.103979 -241.045578) (xy 229.092003 -240.982792) (xy 229.087989 -240.919) (xy 218.193874 -240.919)
			(xy 218.193874 -243.205) (xy 230.631492 -243.205) (xy 230.63193 -243.174785) (xy 230.639117 -243.114782)
			(xy 230.653367 -243.056055) (xy 230.674478 -242.999431) (xy 230.702152 -242.945709) (xy 230.736 -242.895646)
			(xy 230.755444 -242.872514) (xy 230.761069 -242.865377) (xy 230.767313 -242.848322) (xy 230.767636 -242.83924)
			(xy 230.767636 -242.80876) (xy 230.767302 -242.79968) (xy 230.761059 -242.782629) (xy 230.755444 -242.775486)
			(xy 230.736005 -242.752351) (xy 230.702167 -242.702284) (xy 230.674498 -242.648561) (xy 230.653389 -242.591939)
			(xy 230.639137 -242.533214) (xy 230.631942 -242.473214) (xy 230.631492 -242.443) (xy 230.631994 -242.411039)
			(xy 230.640005 -242.347621) (xy 230.655902 -242.285707) (xy 230.679434 -242.226274) (xy 230.710228 -242.170259)
			(xy 230.747801 -242.118544) (xy 230.791558 -242.071947) (xy 230.840811 -242.031202) (xy 230.894782 -241.996951)
			(xy 230.952621 -241.969734) (xy 231.013414 -241.949981) (xy 231.076204 -241.938003) (xy 231.14 -241.93399)
			(xy 231.203796 -241.938003) (xy 231.266586 -241.949981) (xy 231.327379 -241.969734) (xy 231.385218 -241.996951)
			(xy 231.439189 -242.031202) (xy 231.488442 -242.071947) (xy 231.532199 -242.118544) (xy 231.569772 -242.170259)
			(xy 231.600566 -242.226274) (xy 231.624098 -242.285707) (xy 231.639995 -242.347621) (xy 231.648006 -242.411039)
			(xy 231.648508 -242.443) (xy 231.64807 -242.473215) (xy 231.640883 -242.533218) (xy 231.626633 -242.591945)
			(xy 231.605522 -242.648569) (xy 231.577848 -242.702291) (xy 231.544 -242.752354) (xy 231.524556 -242.775486)
			(xy 231.518931 -242.782623) (xy 231.512687 -242.799678) (xy 231.512364 -242.80876) (xy 231.512364 -242.83924)
			(xy 231.512698 -242.84832) (xy 231.518941 -242.865371) (xy 231.524556 -242.872514) (xy 231.543995 -242.895649)
			(xy 231.577833 -242.945716) (xy 231.605502 -242.999439) (xy 231.626611 -243.056061) (xy 231.640863 -243.114786)
			(xy 231.648058 -243.174786) (xy 231.648508 -243.205) (xy 231.648046 -243.235603) (xy 231.640693 -243.296367)
			(xy 231.626104 -243.35581) (xy 231.604491 -243.413074) (xy 231.576166 -243.467332) (xy 231.541537 -243.517801)
			(xy 231.501105 -243.563752) (xy 231.478582 -243.584476) (xy 231.47147 -243.590826) (xy 231.463088 -243.606828)
			(xy 231.45242 -243.691918) (xy 231.456738 -243.709444) (xy 231.462072 -243.717318) (xy 231.477078 -243.740348)
			(xy 231.500798 -243.789934) (xy 231.516911 -243.842486) (xy 231.525063 -243.896845) (xy 231.525572 -243.924328)
			(xy 231.525237 -243.947573) (xy 231.519452 -243.993701) (xy 231.5079 -244.038732) (xy 231.499664 -244.060472)
			(xy 231.494076 -244.074188) (xy 231.49941 -244.10289) (xy 231.581706 -244.19179) (xy 231.610154 -244.199156)
			(xy 231.624124 -244.194838) (xy 231.660923 -244.18415) (xy 231.736686 -244.172674) (xy 231.775 -244.171978)
			(xy 231.806541 -244.172468) (xy 231.869139 -244.180271) (xy 231.930291 -244.195756) (xy 231.989058 -244.218688)
			(xy 232.044538 -244.248712) (xy 232.095877 -244.285368) (xy 232.142288 -244.328092) (xy 232.183058 -244.37623)
			(xy 232.217561 -244.42904) (xy 232.245266 -244.485713) (xy 232.265748 -244.545378) (xy 232.278693 -244.607118)
			(xy 232.283902 -244.669985) (xy 232.281294 -244.733013) (xy 232.270911 -244.795235) (xy 232.25291 -244.855695)
			(xy 232.22757 -244.913464) (xy 232.195278 -244.967655) (xy 232.156531 -245.017435) (xy 232.111925 -245.062041)
			(xy 232.062143 -245.100786) (xy 232.007952 -245.133076) (xy 231.950182 -245.158415) (xy 231.889722 -245.176414)
			(xy 231.8275 -245.186796) (xy 231.764471 -245.189402) (xy 231.701604 -245.184191) (xy 231.639864 -245.171244)
			(xy 231.5802 -245.15076) (xy 231.523528 -245.123054) (xy 231.470719 -245.08855) (xy 231.422582 -245.047778)
			(xy 231.379859 -245.001366) (xy 231.343204 -244.950026) (xy 231.313182 -244.894546) (xy 231.290252 -244.835778)
			(xy 231.274768 -244.774625) (xy 231.266967 -244.712027) (xy 231.266492 -244.680486) (xy 231.266979 -244.648615)
			(xy 231.274912 -244.585371) (xy 231.2907 -244.523617) (xy 231.314096 -244.464325) (xy 231.328976 -244.436138)
			(xy 231.336088 -244.423184) (xy 231.33431 -244.393974) (xy 231.263698 -244.295676) (xy 231.23652 -244.284754)
			(xy 231.222042 -244.287294) (xy 231.205862 -244.290037) (xy 231.173174 -244.292959) (xy 231.156764 -244.293136)
			(xy 231.13042 -244.292672) (xy 231.07827 -244.285169) (xy 231.027718 -244.270322) (xy 230.979792 -244.248433)
			(xy 230.93547 -244.219946) (xy 230.895652 -244.185442) (xy 230.861149 -244.145624) (xy 230.832664 -244.101301)
			(xy 230.810775 -244.053375) (xy 230.795929 -244.002822) (xy 230.788428 -243.950672) (xy 230.787956 -243.924328)
			(xy 230.788373 -243.898992) (xy 230.795328 -243.848798) (xy 230.809099 -243.800032) (xy 230.829424 -243.753614)
			(xy 230.842312 -243.731796) (xy 230.847138 -243.723668) (xy 230.85044 -243.705888) (xy 230.835962 -243.621306)
			(xy 230.826818 -243.605812) (xy 230.819452 -243.59997) (xy 230.794669 -243.579234) (xy 230.750068 -243.532473)
			(xy 230.711752 -243.480438) (xy 230.680339 -243.423966) (xy 230.656335 -243.36397) (xy 230.640127 -243.301415)
			(xy 230.631976 -243.237311) (xy 230.631492 -243.205) (xy 218.193874 -243.205) (xy 218.193874 -244.712447)
			(xy 229.996994 -244.712447) (xy 229.996994 -244.648525) (xy 230.005005 -244.585107) (xy 230.020902 -244.523193)
			(xy 230.044434 -244.46376) (xy 230.075228 -244.407745) (xy 230.112801 -244.35603) (xy 230.156558 -244.309433)
			(xy 230.205811 -244.268688) (xy 230.259782 -244.234437) (xy 230.317621 -244.20722) (xy 230.378414 -244.187467)
			(xy 230.441204 -244.175489) (xy 230.505 -244.171476) (xy 230.568796 -244.175489) (xy 230.631586 -244.187467)
			(xy 230.692379 -244.20722) (xy 230.750218 -244.234437) (xy 230.804189 -244.268688) (xy 230.853442 -244.309433)
			(xy 230.897199 -244.35603) (xy 230.934772 -244.407745) (xy 230.965566 -244.46376) (xy 230.989098 -244.523193)
			(xy 231.004995 -244.585107) (xy 231.013006 -244.648525) (xy 231.013508 -244.680486) (xy 231.013006 -244.712447)
			(xy 231.004995 -244.775865) (xy 230.989098 -244.837779) (xy 230.965566 -244.897212) (xy 230.934772 -244.953227)
			(xy 230.897199 -245.004942) (xy 230.853442 -245.051539) (xy 230.804189 -245.092284) (xy 230.750218 -245.126535)
			(xy 230.692379 -245.153752) (xy 230.631586 -245.173505) (xy 230.568796 -245.185483) (xy 230.505 -245.189497)
			(xy 230.441204 -245.185483) (xy 230.378414 -245.173505) (xy 230.317621 -245.153752) (xy 230.259782 -245.126535)
			(xy 230.205811 -245.092284) (xy 230.156558 -245.051539) (xy 230.112801 -245.004942) (xy 230.075228 -244.953227)
			(xy 230.044434 -244.897212) (xy 230.020902 -244.837779) (xy 230.005005 -244.775865) (xy 229.996994 -244.712447)
			(xy 218.193874 -244.712447) (xy 218.193874 -249.428) (xy 230.377492 -249.428) (xy 230.377953 -249.396865)
			(xy 230.385534 -249.335058) (xy 230.400607 -249.27464) (xy 230.422946 -249.216516) (xy 230.452218 -249.161554)
			(xy 230.487982 -249.11058) (xy 230.529705 -249.064355) (xy 230.576761 -249.023572) (xy 230.628446 -248.988841)
			(xy 230.683986 -248.960683) (xy 230.742549 -248.93952) (xy 230.803258 -248.925667) (xy 230.834184 -248.922032)
			(xy 230.844201 -248.920616) (xy 230.862011 -248.911055) (xy 230.868728 -248.90349) (xy 230.88854 -248.878852)
			(xy 230.89449 -248.870706) (xy 230.899995 -248.851317) (xy 230.899208 -248.84126) (xy 230.8987 -248.835418)
			(xy 230.897429 -248.826561) (xy 230.889598 -248.810487) (xy 230.876716 -248.798086) (xy 230.860356 -248.790872)
			(xy 230.851456 -248.789952) (xy 230.819712 -248.7873) (xy 230.757192 -248.775089) (xy 230.696687 -248.755161)
			(xy 230.639147 -248.727829) (xy 230.585473 -248.693521) (xy 230.536507 -248.652776) (xy 230.493015 -248.606232)
			(xy 230.45568 -248.554618) (xy 230.425087 -248.498743) (xy 230.401715 -248.439484) (xy 230.385931 -248.377769)
			(xy 230.377982 -248.314565) (xy 230.377492 -248.282714) (xy 230.378065 -248.248222) (xy 230.3874 -248.179872)
			(xy 230.405889 -248.113411) (xy 230.43319 -248.050059) (xy 230.468804 -247.990978) (xy 230.512077 -247.937254)
			(xy 230.53675 -247.913144) (xy 230.54437 -247.905778) (xy 230.552498 -247.886982) (xy 230.552498 -247.791732)
			(xy 230.54437 -247.772936) (xy 230.53675 -247.76557) (xy 230.512079 -247.741458) (xy 230.4688 -247.687737)
			(xy 230.433183 -247.628658) (xy 230.405881 -247.565306) (xy 230.387396 -247.498844) (xy 230.378068 -247.430492)
			(xy 230.377492 -247.396) (xy 230.377973 -247.362676) (xy 230.386676 -247.2966) (xy 230.403931 -247.232225)
			(xy 230.429445 -247.170655) (xy 230.46278 -247.112944) (xy 230.503366 -247.060079) (xy 230.550506 -247.012966)
			(xy 230.603395 -246.972412) (xy 230.632 -246.95531) (xy 230.64216 -246.949722) (xy 230.65486 -246.93118)
			(xy 230.671878 -246.831358) (xy 230.665782 -246.809768) (xy 230.658416 -246.801132) (xy 230.641586 -246.780941)
			(xy 230.613232 -246.736681) (xy 230.59145 -246.688844) (xy 230.576678 -246.638399) (xy 230.569218 -246.586368)
			(xy 230.568754 -246.560086) (xy 230.56927 -246.532486) (xy 230.577497 -246.477903) (xy 230.593767 -246.425156)
			(xy 230.617717 -246.375424) (xy 230.648812 -246.329816) (xy 230.686357 -246.289352) (xy 230.729514 -246.254935)
			(xy 230.777318 -246.227336) (xy 230.828702 -246.207169) (xy 230.882517 -246.194886) (xy 230.937562 -246.190761)
			(xy 230.992607 -246.194886) (xy 231.046422 -246.207169) (xy 231.097806 -246.227336) (xy 231.14561 -246.254935)
			(xy 231.188767 -246.289352) (xy 231.226312 -246.329816) (xy 231.257407 -246.375424) (xy 231.281357 -246.425156)
			(xy 231.297627 -246.477903) (xy 231.305854 -246.532486) (xy 231.30637 -246.560086) (xy 231.305935 -246.585758)
			(xy 231.298785 -246.636602) (xy 231.284649 -246.685963) (xy 231.263801 -246.732884) (xy 231.236644 -246.776459)
			(xy 231.203704 -246.815844) (xy 231.184958 -246.83339) (xy 231.176576 -246.841264) (xy 231.16794 -246.862092)
			(xy 231.172512 -246.963184) (xy 231.178787 -246.975122) (xy 232.475784 -246.975122) (xy 232.479855 -246.9195)
			(xy 232.491981 -246.865063) (xy 232.511904 -246.812972) (xy 232.5392 -246.764337) (xy 232.573286 -246.720194)
			(xy 232.613435 -246.681485) (xy 232.658793 -246.649034) (xy 232.708393 -246.623533) (xy 232.761177 -246.605526)
			(xy 232.81602 -246.595396) (xy 232.871754 -246.593359) (xy 232.927191 -246.599459) (xy 232.981148 -246.613565)
			(xy 233.032477 -246.635377) (xy 233.080083 -246.664431) (xy 233.122951 -246.700106) (xy 233.160168 -246.741643)
			(xy 233.190941 -246.788156) (xy 233.214613 -246.838653) (xy 233.230681 -246.89206) (xy 233.238801 -246.947236)
			(xy 233.23931 -246.975122) (xy 233.238801 -247.003008) (xy 233.230681 -247.058184) (xy 233.214613 -247.111591)
			(xy 233.190941 -247.162088) (xy 233.160168 -247.208601) (xy 233.122951 -247.250138) (xy 233.080083 -247.285813)
			(xy 233.032477 -247.314867) (xy 232.981148 -247.336679) (xy 232.927191 -247.350785) (xy 232.871754 -247.356885)
			(xy 232.81602 -247.354848) (xy 232.761177 -247.344718) (xy 232.708393 -247.326711) (xy 232.658793 -247.30121)
			(xy 232.613435 -247.268759) (xy 232.573286 -247.23005) (xy 232.5392 -247.185907) (xy 232.511904 -247.137272)
			(xy 232.491981 -247.085181) (xy 232.479855 -247.030744) (xy 232.475784 -246.975122) (xy 231.178787 -246.975122)
			(xy 231.182926 -246.982996) (xy 231.19207 -246.989854) (xy 231.218603 -247.010498) (xy 231.266487 -247.057685)
			(xy 231.307735 -247.110771) (xy 231.341629 -247.168829) (xy 231.367577 -247.230847) (xy 231.385127 -247.295743)
			(xy 231.393973 -247.362386) (xy 231.394508 -247.396) (xy 231.393945 -247.430492) (xy 231.384607 -247.498843)
			(xy 231.366117 -247.565304) (xy 231.338814 -247.628656) (xy 231.303198 -247.687736) (xy 231.259924 -247.74146)
			(xy 231.23525 -247.76557) (xy 231.22763 -247.772936) (xy 231.219502 -247.791732) (xy 231.219502 -247.886982)
			(xy 231.22763 -247.905778) (xy 231.23525 -247.913144) (xy 231.256794 -247.934133) (xy 231.295325 -247.98032)
			(xy 231.32814 -248.030729) (xy 231.354782 -248.084656) (xy 231.374877 -248.141349) (xy 231.388146 -248.200017)
			(xy 231.391714 -248.229882) (xy 231.392972 -248.238742) (xy 231.400806 -248.254818) (xy 231.413692 -248.267218)
			(xy 231.430057 -248.27443) (xy 231.438958 -248.275348) (xy 231.470703 -248.277988) (xy 231.506599 -248.285)
			(xy 238.251492 -248.285) (xy 238.251911 -248.25372) (xy 238.259575 -248.191631) (xy 238.274801 -248.130953)
			(xy 238.297358 -248.072601) (xy 238.326904 -248.017458) (xy 238.362995 -247.966358) (xy 238.405083 -247.920072)
			(xy 238.452532 -247.879301) (xy 238.478314 -247.861582) (xy 238.488474 -247.85413) (xy 238.50046 -247.831999)
			(xy 238.501174 -247.819418) (xy 238.501174 -247.734582) (xy 238.500494 -247.721999) (xy 238.488472 -247.69988)
			(xy 238.478314 -247.692418) (xy 238.452567 -247.674656) (xy 238.405139 -247.633876) (xy 238.363068 -247.587589)
			(xy 238.32699 -247.536492) (xy 238.29745 -247.481358) (xy 238.274892 -247.423017) (xy 238.259657 -247.362351)
			(xy 238.251976 -247.300275) (xy 238.251492 -247.269) (xy 238.251994 -247.237039) (xy 238.260005 -247.173621)
			(xy 238.275902 -247.111707) (xy 238.299434 -247.052274) (xy 238.330228 -246.996259) (xy 238.367801 -246.944544)
			(xy 238.411558 -246.897947) (xy 238.460811 -246.857202) (xy 238.514782 -246.822951) (xy 238.572621 -246.795734)
			(xy 238.633414 -246.775981) (xy 238.696204 -246.764003) (xy 238.76 -246.75999) (xy 238.823796 -246.764003)
			(xy 238.886586 -246.775981) (xy 238.947379 -246.795734) (xy 239.005218 -246.822951) (xy 239.059189 -246.857202)
			(xy 239.108442 -246.897947) (xy 239.152199 -246.944544) (xy 239.189772 -246.996259) (xy 239.220566 -247.052274)
			(xy 239.244098 -247.111707) (xy 239.259995 -247.173621) (xy 239.268006 -247.237039) (xy 239.268508 -247.269)
			(xy 239.268089 -247.30028) (xy 239.260425 -247.362369) (xy 239.245199 -247.423047) (xy 239.222642 -247.481399)
			(xy 239.193096 -247.536542) (xy 239.157005 -247.587642) (xy 239.114917 -247.633928) (xy 239.067468 -247.674699)
			(xy 239.041686 -247.692418) (xy 239.031526 -247.69987) (xy 239.01954 -247.722001) (xy 239.018826 -247.734582)
			(xy 239.018826 -247.819418) (xy 239.019506 -247.832001) (xy 239.031528 -247.85412) (xy 239.041686 -247.861582)
			(xy 239.067051 -247.878982) (xy 239.113792 -247.918968) (xy 239.134904 -247.941338) (xy 239.14227 -247.949466)
			(xy 239.16132 -247.957848) (xy 239.258094 -247.957848) (xy 239.277144 -247.949466) (xy 239.28451 -247.941338)
			(xy 239.302063 -247.92288) (xy 239.341352 -247.890463) (xy 239.384727 -247.863758) (xy 239.431361 -247.843272)
			(xy 239.48037 -247.829393) (xy 239.530822 -247.822387) (xy 239.55629 -247.821958) (xy 239.58389 -247.822515)
			(xy 239.638472 -247.830741) (xy 239.691219 -247.84701) (xy 239.740952 -247.870959) (xy 239.786561 -247.902053)
			(xy 239.827025 -247.939597) (xy 239.861441 -247.982753) (xy 239.889041 -248.030557) (xy 239.909208 -248.08194)
			(xy 239.921491 -248.135755) (xy 239.925617 -248.1908) (xy 239.921491 -248.245845) (xy 239.909208 -248.29966)
			(xy 239.889041 -248.351043) (xy 239.861441 -248.398847) (xy 239.827025 -248.442003) (xy 239.786561 -248.479547)
			(xy 239.740952 -248.510641) (xy 239.691219 -248.53459) (xy 239.638472 -248.550859) (xy 239.58389 -248.559085)
			(xy 239.55629 -248.559574) (xy 239.52895 -248.559104) (xy 239.474871 -248.551015) (xy 239.422583 -248.535019)
			(xy 239.373236 -248.511465) (xy 239.350296 -248.496582) (xy 239.341152 -248.490486) (xy 239.320578 -248.48693)
			(xy 239.226598 -248.509536) (xy 239.210088 -248.522236) (xy 239.204754 -248.531634) (xy 239.187815 -248.560939)
			(xy 239.147416 -248.615246) (xy 239.100173 -248.663717) (xy 239.046918 -248.705495) (xy 238.988594 -248.739841)
			(xy 238.926231 -248.76615) (xy 238.860929 -248.783956) (xy 238.793843 -248.792945) (xy 238.76 -248.793508)
			(xy 238.729269 -248.793044) (xy 238.668255 -248.785635) (xy 238.608579 -248.770927) (xy 238.551111 -248.749132)
			(xy 238.496689 -248.720569) (xy 238.446107 -248.685655) (xy 238.400102 -248.644898) (xy 238.359345 -248.598893)
			(xy 238.324431 -248.548311) (xy 238.295868 -248.493889) (xy 238.274073 -248.436421) (xy 238.259365 -248.376745)
			(xy 238.251956 -248.315731) (xy 238.251492 -248.285) (xy 231.506599 -248.285) (xy 231.533224 -248.290201)
			(xy 231.593728 -248.310131) (xy 231.651268 -248.337464) (xy 231.704942 -248.371773) (xy 231.753909 -248.412519)
			(xy 231.7974 -248.459064) (xy 231.834735 -248.510679) (xy 231.865328 -248.566555) (xy 231.888699 -248.625815)
			(xy 231.904483 -248.68753) (xy 231.912432 -248.750735) (xy 231.912922 -248.782586) (xy 231.91238 -248.815475)
			(xy 231.9039 -248.880704) (xy 231.887079 -248.944295) (xy 231.862199 -249.005186) (xy 231.829675 -249.06236)
			(xy 231.79005 -249.114863) (xy 231.743985 -249.161818) (xy 231.69225 -249.202441) (xy 231.635709 -249.236054)
			(xy 231.575306 -249.262095) (xy 231.512049 -249.28013) (xy 231.479598 -249.285506) (xy 231.469946 -249.28703)
			(xy 231.45369 -249.296428) (xy 231.398318 -249.365262) (xy 231.39273 -249.383296) (xy 231.393238 -249.392948)
			(xy 231.394508 -249.428) (xy 231.394004 -249.4613) (xy 231.385322 -249.527331) (xy 231.368092 -249.591663)
			(xy 231.34261 -249.653194) (xy 231.309312 -249.710872) (xy 231.268769 -249.763709) (xy 231.221674 -249.8108)
			(xy 231.168834 -249.851338) (xy 231.140254 -249.868436) (xy 231.130348 -249.874278) (xy 231.117394 -249.892566)
			(xy 231.100376 -249.992388) (xy 231.106472 -250.014232) (xy 231.114092 -250.022868) (xy 231.130923 -250.043058)
			(xy 231.159276 -250.087319) (xy 231.181059 -250.135156) (xy 231.19583 -250.185601) (xy 231.20329 -250.237632)
			(xy 231.203754 -250.263914) (xy 231.203238 -250.291514) (xy 231.195011 -250.346097) (xy 231.178741 -250.398844)
			(xy 231.154791 -250.448577) (xy 231.123696 -250.494184) (xy 231.086151 -250.534648) (xy 231.042994 -250.569065)
			(xy 231.039642 -250.571) (xy 238.251492 -250.571) (xy 238.251911 -250.53972) (xy 238.259575 -250.477631)
			(xy 238.274801 -250.416953) (xy 238.297358 -250.358601) (xy 238.326904 -250.303458) (xy 238.362995 -250.252358)
			(xy 238.405083 -250.206072) (xy 238.452532 -250.165301) (xy 238.478314 -250.147582) (xy 238.488474 -250.14013)
			(xy 238.50046 -250.117999) (xy 238.501174 -250.105418) (xy 238.501174 -250.020582) (xy 238.500494 -250.007999)
			(xy 238.488472 -249.98588) (xy 238.478314 -249.978418) (xy 238.452567 -249.960656) (xy 238.405139 -249.919876)
			(xy 238.363068 -249.873589) (xy 238.32699 -249.822492) (xy 238.29745 -249.767358) (xy 238.274892 -249.709017)
			(xy 238.259657 -249.648351) (xy 238.251976 -249.586275) (xy 238.251492 -249.555) (xy 238.251956 -249.524269)
			(xy 238.259365 -249.463255) (xy 238.274073 -249.403579) (xy 238.295868 -249.346111) (xy 238.324431 -249.291689)
			(xy 238.359345 -249.241107) (xy 238.400102 -249.195102) (xy 238.446107 -249.154345) (xy 238.496689 -249.119431)
			(xy 238.551111 -249.090868) (xy 238.608579 -249.069073) (xy 238.668255 -249.054365) (xy 238.729269 -249.046956)
			(xy 238.76 -249.046492) (xy 238.792819 -249.047038) (xy 238.85791 -249.055487) (xy 238.921372 -249.072246)
			(xy 238.982149 -249.097034) (xy 239.039229 -249.12944) (xy 239.091663 -249.168925) (xy 239.138577 -249.214831)
			(xy 239.159288 -249.240294) (xy 239.165384 -249.247914) (xy 239.18164 -249.257566) (xy 239.269524 -249.271028)
			(xy 239.287812 -249.266964) (xy 239.29594 -249.261376) (xy 239.318952 -249.246416) (xy 239.368479 -249.222759)
			(xy 239.420966 -249.206706) (xy 239.475252 -249.198612) (xy 239.502696 -249.19813) (xy 239.530301 -249.198544)
			(xy 239.584893 -249.206772) (xy 239.63765 -249.223045) (xy 239.687392 -249.246999) (xy 239.733008 -249.278099)
			(xy 239.77348 -249.315651) (xy 239.807902 -249.358815) (xy 239.835507 -249.406627) (xy 239.855677 -249.45802)
			(xy 239.867963 -249.511845) (xy 239.872089 -249.5669) (xy 239.867963 -249.621955) (xy 239.855677 -249.67578)
			(xy 239.835507 -249.727173) (xy 239.807902 -249.774985) (xy 239.77348 -249.818149) (xy 239.733008 -249.855701)
			(xy 239.687392 -249.886801) (xy 239.63765 -249.910755) (xy 239.584893 -249.927028) (xy 239.530301 -249.935256)
			(xy 239.502696 -249.935746) (xy 239.473775 -249.93519) (xy 239.416642 -249.926166) (xy 239.361616 -249.908339)
			(xy 239.310045 -249.882145) (xy 239.286288 -249.865642) (xy 239.278414 -249.8598) (xy 239.260126 -249.855228)
			(xy 239.171988 -249.865896) (xy 239.155224 -249.87504) (xy 239.149128 -249.882406) (xy 239.125371 -249.909675)
			(xy 239.071442 -249.957862) (xy 239.041686 -249.978418) (xy 239.031526 -249.98587) (xy 239.01954 -250.008001)
			(xy 239.018826 -250.020582) (xy 239.018826 -250.105418) (xy 239.019506 -250.118001) (xy 239.031528 -250.14012)
			(xy 239.041686 -250.147582) (xy 239.067433 -250.165344) (xy 239.114861 -250.206124) (xy 239.156932 -250.252411)
			(xy 239.19301 -250.303508) (xy 239.22255 -250.358642) (xy 239.245108 -250.416983) (xy 239.260343 -250.477649)
			(xy 239.268024 -250.539725) (xy 239.268508 -250.571) (xy 239.268006 -250.602961) (xy 239.259995 -250.666379)
			(xy 239.244098 -250.728293) (xy 239.220566 -250.787726) (xy 239.189772 -250.843741) (xy 239.152199 -250.895456)
			(xy 239.108442 -250.942053) (xy 239.059189 -250.982798) (xy 239.005218 -251.017049) (xy 238.947379 -251.044266)
			(xy 238.886586 -251.064019) (xy 238.823796 -251.075997) (xy 238.76 -251.080011) (xy 238.696204 -251.075997)
			(xy 238.633414 -251.064019) (xy 238.572621 -251.044266) (xy 238.514782 -251.017049) (xy 238.460811 -250.982798)
			(xy 238.411558 -250.942053) (xy 238.367801 -250.895456) (xy 238.330228 -250.843741) (xy 238.299434 -250.787726)
			(xy 238.275902 -250.728293) (xy 238.260005 -250.666379) (xy 238.251994 -250.602961) (xy 238.251492 -250.571)
			(xy 231.039642 -250.571) (xy 230.99519 -250.596664) (xy 230.943806 -250.616831) (xy 230.889991 -250.629114)
			(xy 230.834946 -250.633239) (xy 230.779901 -250.629114) (xy 230.726086 -250.616831) (xy 230.674702 -250.596664)
			(xy 230.626898 -250.569065) (xy 230.583741 -250.534648) (xy 230.546196 -250.494184) (xy 230.515101 -250.448577)
			(xy 230.491151 -250.398844) (xy 230.474881 -250.346097) (xy 230.466654 -250.291514) (xy 230.466138 -250.263914)
			(xy 230.466566 -250.238252) (xy 230.473681 -250.187423) (xy 230.487776 -250.138072) (xy 230.508579 -250.091152)
			(xy 230.535686 -250.04757) (xy 230.568575 -250.008168) (xy 230.587296 -249.99061) (xy 230.595678 -249.98299)
			(xy 230.604314 -249.962162) (xy 230.599742 -249.86107) (xy 230.589328 -249.841004) (xy 230.580184 -249.834146)
			(xy 230.553631 -249.813512) (xy 230.505698 -249.766346) (xy 230.464403 -249.713272) (xy 230.430466 -249.655216)
			(xy 230.404482 -249.593192) (xy 230.386902 -249.528284) (xy 230.378035 -249.461624) (xy 230.377492 -249.428)
			(xy 218.193874 -249.428) (xy 218.193874 -251.442728) (xy 233.11307 -251.442728) (xy 233.117141 -251.387106)
			(xy 233.129267 -251.332669) (xy 233.14919 -251.280578) (xy 233.176486 -251.231943) (xy 233.210572 -251.1878)
			(xy 233.250721 -251.149091) (xy 233.296079 -251.11664) (xy 233.345679 -251.091139) (xy 233.398463 -251.073132)
			(xy 233.453306 -251.063002) (xy 233.50904 -251.060965) (xy 233.564477 -251.067065) (xy 233.618434 -251.081171)
			(xy 233.669763 -251.102983) (xy 233.717369 -251.132037) (xy 233.760237 -251.167712) (xy 233.797454 -251.209249)
			(xy 233.828227 -251.255762) (xy 233.851899 -251.306259) (xy 233.867967 -251.359666) (xy 233.876087 -251.414842)
			(xy 233.876596 -251.442728) (xy 233.876087 -251.470614) (xy 233.867967 -251.52579) (xy 233.851899 -251.579197)
			(xy 233.828227 -251.629694) (xy 233.797454 -251.676207) (xy 233.760237 -251.717744) (xy 233.717369 -251.753419)
			(xy 233.669763 -251.782473) (xy 233.618434 -251.804285) (xy 233.564477 -251.818391) (xy 233.50904 -251.824491)
			(xy 233.453306 -251.822454) (xy 233.398463 -251.812324) (xy 233.345679 -251.794317) (xy 233.296079 -251.768816)
			(xy 233.250721 -251.736365) (xy 233.210572 -251.697656) (xy 233.176486 -251.653513) (xy 233.14919 -251.604878)
			(xy 233.129267 -251.552787) (xy 233.117141 -251.49835) (xy 233.11307 -251.442728) (xy 218.193874 -251.442728)
			(xy 218.193874 -267.495782) (xy 225.43846 -267.495782) (xy 225.442531 -267.44016) (xy 225.454657 -267.385723)
			(xy 225.47458 -267.333632) (xy 225.501876 -267.284997) (xy 225.535962 -267.240854) (xy 225.576111 -267.202145)
			(xy 225.621469 -267.169694) (xy 225.671069 -267.144193) (xy 225.723853 -267.126186) (xy 225.778696 -267.116056)
			(xy 225.83443 -267.114019) (xy 225.889867 -267.120119) (xy 225.943824 -267.134225) (xy 225.995153 -267.156037)
			(xy 226.042759 -267.185091) (xy 226.085627 -267.220766) (xy 226.122844 -267.262303) (xy 226.153617 -267.308816)
			(xy 226.177289 -267.359313) (xy 226.193357 -267.41272) (xy 226.201477 -267.467896) (xy 226.201986 -267.495782)
			(xy 226.201477 -267.523668) (xy 226.193357 -267.578844) (xy 226.177289 -267.632251) (xy 226.153617 -267.682748)
			(xy 226.122844 -267.729261) (xy 226.085627 -267.770798) (xy 226.042759 -267.806473) (xy 225.995153 -267.835527)
			(xy 225.943824 -267.857339) (xy 225.889867 -267.871445) (xy 225.83443 -267.877545) (xy 225.778696 -267.875508)
			(xy 225.723853 -267.865378) (xy 225.671069 -267.847371) (xy 225.621469 -267.82187) (xy 225.576111 -267.789419)
			(xy 225.535962 -267.75071) (xy 225.501876 -267.706567) (xy 225.47458 -267.657932) (xy 225.454657 -267.605841)
			(xy 225.442531 -267.551404) (xy 225.43846 -267.495782) (xy 218.193874 -267.495782) (xy 218.193874 -273.071082)
			(xy 221.00032 -273.071082) (xy 221.000889 -273.026595) (xy 221.009795 -272.938067) (xy 221.027487 -272.850869)
			(xy 221.053787 -272.76587) (xy 221.088435 -272.683918) (xy 221.109286 -272.644616) (xy 221.113057 -272.636991)
			(xy 221.115883 -272.620228) (xy 221.113075 -272.603463) (xy 221.109286 -272.595848) (xy 221.088414 -272.556555)
			(xy 221.053737 -272.47461) (xy 221.027424 -272.389611) (xy 221.009738 -272.302407) (xy 221.000857 -272.213872)
			(xy 221.00032 -272.169382) (xy 221.000894 -272.122986) (xy 221.010541 -272.030697) (xy 221.02974 -271.939914)
			(xy 221.058281 -271.85162) (xy 221.07652 -271.808956) (xy 221.08035 -271.799019) (xy 221.080343 -271.777748)
			(xy 221.07652 -271.767808) (xy 221.058271 -271.725148) (xy 221.029728 -271.636855) (xy 221.010536 -271.546069)
			(xy 221.000904 -271.453778) (xy 221.00032 -271.407382) (xy 221.000894 -271.360986) (xy 221.010541 -271.268697)
			(xy 221.02974 -271.177914) (xy 221.058281 -271.08962) (xy 221.07652 -271.046956) (xy 221.08035 -271.037019)
			(xy 221.080343 -271.015748) (xy 221.07652 -271.005808) (xy 221.058271 -270.963148) (xy 221.029728 -270.874855)
			(xy 221.010536 -270.784069) (xy 221.000904 -270.691778) (xy 221.00032 -270.645382) (xy 221.000889 -270.600895)
			(xy 221.009795 -270.512367) (xy 221.027487 -270.425169) (xy 221.053787 -270.34017) (xy 221.088435 -270.258218)
			(xy 221.109286 -270.218916) (xy 221.113057 -270.211291) (xy 221.115883 -270.194528) (xy 221.113075 -270.177763)
			(xy 221.109286 -270.170148) (xy 221.088414 -270.130855) (xy 221.053737 -270.04891) (xy 221.027424 -269.963911)
			(xy 221.009738 -269.876707) (xy 221.000857 -269.788172) (xy 221.00032 -269.743682) (xy 221.000735 -269.702578)
			(xy 221.008322 -269.62072) (xy 221.02343 -269.539911) (xy 221.045929 -269.460842) (xy 221.075628 -269.384185)
			(xy 221.112273 -269.310596) (xy 221.155552 -269.240702) (xy 221.205095 -269.175099) (xy 221.26048 -269.114348)
			(xy 221.321235 -269.058966) (xy 221.38684 -269.009426) (xy 221.456736 -268.96615) (xy 221.530327 -268.929509)
			(xy 221.606985 -268.899814) (xy 221.686056 -268.877319) (xy 221.766866 -268.862216) (xy 221.848724 -268.854633)
			(xy 221.889828 -268.854174) (xy 221.936223 -268.854784) (xy 222.02851 -268.864421) (xy 222.119294 -268.883609)
			(xy 222.207588 -268.91214) (xy 222.250254 -268.930374) (xy 222.260194 -268.934194) (xy 222.281462 -268.934194)
			(xy 222.291402 -268.930374) (xy 222.33406 -268.912119) (xy 222.422354 -268.883578) (xy 222.51314 -268.864388)
			(xy 222.605432 -268.854757) (xy 222.651828 -268.854174) (xy 222.698223 -268.854784) (xy 222.79051 -268.864421)
			(xy 222.881294 -268.883609) (xy 222.969588 -268.91214) (xy 223.012254 -268.930374) (xy 223.022194 -268.934194)
			(xy 223.043462 -268.934194) (xy 223.053402 -268.930374) (xy 223.09606 -268.912119) (xy 223.184354 -268.883578)
			(xy 223.27514 -268.864388) (xy 223.367432 -268.854757) (xy 223.413828 -268.854174) (xy 223.460223 -268.854784)
			(xy 223.55251 -268.864421) (xy 223.643294 -268.883609) (xy 223.731588 -268.91214) (xy 223.774254 -268.930374)
			(xy 223.784194 -268.934194) (xy 223.805462 -268.934194) (xy 223.815402 -268.930374) (xy 223.85806 -268.912119)
			(xy 223.946354 -268.883578) (xy 224.03714 -268.864388) (xy 224.129432 -268.854757) (xy 224.175828 -268.854174)
			(xy 224.218175 -268.854715) (xy 224.302485 -268.862768) (xy 224.385647 -268.878799) (xy 224.46691 -268.902662)
			(xy 224.545536 -268.934141) (xy 224.620813 -268.972951) (xy 224.692061 -269.018742) (xy 224.758634 -269.071097)
			(xy 224.819929 -269.129543) (xy 224.87539 -269.193551) (xy 224.924517 -269.262541) (xy 224.966863 -269.335888)
			(xy 225.002045 -269.412929) (xy 225.029745 -269.492964) (xy 225.049712 -269.575271) (xy 225.061765 -269.659102)
			(xy 225.065795 -269.7437) (xy 225.061765 -269.828298) (xy 225.049712 -269.912129) (xy 225.029745 -269.994436)
			(xy 225.002045 -270.074471) (xy 224.966863 -270.151512) (xy 224.924517 -270.224859) (xy 224.87539 -270.293849)
			(xy 224.819929 -270.357857) (xy 224.758634 -270.416303) (xy 224.692061 -270.468658) (xy 224.620813 -270.514449)
			(xy 224.545536 -270.553259) (xy 224.46691 -270.584738) (xy 224.385647 -270.608601) (xy 224.302485 -270.624632)
			(xy 224.218175 -270.632685) (xy 224.175828 -270.63319) (xy 224.129433 -270.632599) (xy 224.037144 -270.622956)
			(xy 223.946361 -270.603763) (xy 223.858067 -270.575227) (xy 223.815402 -270.55699) (xy 223.805462 -270.55317)
			(xy 223.784194 -270.55317) (xy 223.774254 -270.55699) (xy 223.727863 -270.576781) (xy 223.631617 -270.606952)
			(xy 223.58223 -270.617188) (xy 223.57101 -270.619926) (xy 223.552509 -270.633699) (xy 223.541913 -270.654186)
			(xy 223.541082 -270.665702) (xy 223.539577 -270.709533) (xy 223.528981 -270.796598) (xy 223.509864 -270.882197)
			(xy 223.482413 -270.965498) (xy 223.465136 -271.005808) (xy 223.461329 -271.015751) (xy 223.461322 -271.037016)
			(xy 223.465136 -271.046956) (xy 223.483377 -271.08962) (xy 223.511921 -271.177912) (xy 223.531115 -271.268696)
			(xy 223.54075 -271.360986) (xy 223.541336 -271.407382) (xy 223.540744 -271.453777) (xy 223.531102 -271.546065)
			(xy 223.511908 -271.636849) (xy 223.483372 -271.725143) (xy 223.465136 -271.767808) (xy 223.461329 -271.777751)
			(xy 223.461322 -271.799016) (xy 223.465136 -271.808956) (xy 223.482393 -271.849274) (xy 223.509841 -271.932574)
			(xy 223.528959 -272.01817) (xy 223.539562 -272.105232) (xy 223.541082 -272.149062) (xy 223.541968 -272.160564)
			(xy 223.552577 -272.181023) (xy 223.571025 -272.194836) (xy 223.58223 -272.197576) (xy 223.631618 -272.207807)
			(xy 223.727863 -272.237982) (xy 223.774254 -272.257774) (xy 223.784194 -272.261594) (xy 223.805462 -272.261594)
			(xy 223.815402 -272.257774) (xy 223.85806 -272.239519) (xy 223.946354 -272.210978) (xy 224.03714 -272.191788)
			(xy 224.129432 -272.182157) (xy 224.175828 -272.181574) (xy 224.218175 -272.182115) (xy 224.302485 -272.190168)
			(xy 224.385647 -272.206199) (xy 224.46691 -272.230062) (xy 224.545536 -272.261541) (xy 224.620813 -272.300351)
			(xy 224.692061 -272.346142) (xy 224.758634 -272.398497) (xy 224.819929 -272.456943) (xy 224.857094 -272.499836)
			(xy 231.378258 -272.499836) (xy 231.382272 -272.294152) (xy 231.394308 -272.088782) (xy 231.414347 -271.884038)
			(xy 231.44236 -271.680231) (xy 231.478303 -271.477672) (xy 231.522122 -271.27667) (xy 231.573749 -271.077531)
			(xy 231.633107 -270.880558) (xy 231.700105 -270.68605) (xy 231.774641 -270.494305) (xy 231.856601 -270.305614)
			(xy 231.945861 -270.120264) (xy 232.042284 -269.938538) (xy 232.145725 -269.760712) (xy 232.256024 -269.587058)
			(xy 232.373015 -269.417839) (xy 232.496519 -269.253313) (xy 232.626348 -269.093732) (xy 232.762305 -268.939337)
			(xy 232.904182 -268.790365) (xy 233.051763 -268.647041) (xy 233.204824 -268.509585) (xy 233.363131 -268.378205)
			(xy 233.526444 -268.253102) (xy 233.694513 -268.134465) (xy 233.867083 -268.022477) (xy 234.043891 -267.917306)
			(xy 234.224668 -267.819115) (xy 234.409138 -267.728051) (xy 234.59702 -267.644254) (xy 234.78803 -267.567851)
			(xy 234.981874 -267.498958) (xy 235.178259 -267.437681) (xy 235.376885 -267.384113) (xy 235.57745 -267.338336)
			(xy 235.779648 -267.300418) (xy 235.983172 -267.270419) (xy 236.187711 -267.248382) (xy 236.392954 -267.234343)
			(xy 236.598589 -267.228323) (xy 236.804302 -267.23033) (xy 237.00978 -267.240362) (xy 237.21471 -267.258403)
			(xy 237.41878 -267.284426) (xy 237.62168 -267.318391) (xy 237.8231 -267.360246) (xy 237.909451 -267.381736)
			(xy 247.814082 -267.381736) (xy 247.818153 -267.326114) (xy 247.830279 -267.271677) (xy 247.850202 -267.219586)
			(xy 247.877498 -267.170951) (xy 247.911584 -267.126808) (xy 247.951733 -267.088099) (xy 247.997091 -267.055648)
			(xy 248.046691 -267.030147) (xy 248.099475 -267.01214) (xy 248.154318 -267.00201) (xy 248.210052 -266.999973)
			(xy 248.265489 -267.006073) (xy 248.319446 -267.020179) (xy 248.370775 -267.041991) (xy 248.418381 -267.071045)
			(xy 248.461249 -267.10672) (xy 248.498466 -267.148257) (xy 248.529239 -267.19477) (xy 248.552911 -267.245267)
			(xy 248.568979 -267.298674) (xy 248.577099 -267.35385) (xy 248.577608 -267.381736) (xy 248.577099 -267.409622)
			(xy 248.568979 -267.464798) (xy 248.552911 -267.518205) (xy 248.529239 -267.568702) (xy 248.498466 -267.615215)
			(xy 248.461249 -267.656752) (xy 248.418381 -267.692427) (xy 248.370775 -267.721481) (xy 248.319446 -267.743293)
			(xy 248.265489 -267.757399) (xy 248.210052 -267.763499) (xy 248.154318 -267.761462) (xy 248.099475 -267.751332)
			(xy 248.046691 -267.733325) (xy 247.997091 -267.707824) (xy 247.951733 -267.675373) (xy 247.911584 -267.636664)
			(xy 247.877498 -267.592521) (xy 247.850202 -267.543886) (xy 247.830279 -267.491795) (xy 247.818153 -267.437358)
			(xy 247.814082 -267.381736) (xy 237.909451 -267.381736) (xy 238.022733 -267.409928) (xy 238.220276 -267.467362)
			(xy 238.415428 -267.532459) (xy 238.607892 -267.60512) (xy 238.797374 -267.685236) (xy 238.983585 -267.772683)
			(xy 239.166244 -267.867329) (xy 239.34507 -267.969029) (xy 239.519792 -268.077629) (xy 239.690145 -268.192964)
			(xy 239.855867 -268.314857) (xy 240.016708 -268.443123) (xy 240.172421 -268.577566) (xy 240.322771 -268.717983)
			(xy 240.467528 -268.864159) (xy 240.606471 -269.015871) (xy 240.739389 -269.172889) (xy 240.86608 -269.334974)
			(xy 240.98635 -269.501877) (xy 241.100017 -269.673347) (xy 241.206907 -269.84912) (xy 241.306858 -270.02893)
			(xy 241.399717 -270.212503) (xy 241.485344 -270.399559) (xy 241.563606 -270.589814) (xy 241.634387 -270.782977)
			(xy 241.697577 -270.978755) (xy 241.75308 -271.176849) (xy 241.800812 -271.376958) (xy 241.840701 -271.578776)
			(xy 241.872685 -271.781998) (xy 241.896715 -271.986312) (xy 241.912756 -272.191408) (xy 241.920782 -272.396975)
			(xy 241.921284 -272.499836) (xy 241.920782 -272.602697) (xy 241.912756 -272.808264) (xy 241.90311 -272.9316)
			(xy 248.823823 -272.9316) (xy 248.827853 -272.847005) (xy 248.839905 -272.763177) (xy 248.859871 -272.680873)
			(xy 248.88757 -272.60084) (xy 248.92275 -272.523803) (xy 248.965094 -272.450458) (xy 249.014218 -272.38147)
			(xy 249.069677 -272.317463) (xy 249.130969 -272.259019) (xy 249.197538 -272.206664) (xy 249.268783 -272.160874)
			(xy 249.344057 -272.122064) (xy 249.42268 -272.090584) (xy 249.503939 -272.066721) (xy 249.587098 -272.050689)
			(xy 249.671405 -272.042634) (xy 249.71375 -272.042128) (xy 249.760145 -272.042725) (xy 249.852433 -272.052366)
			(xy 249.943217 -272.071557) (xy 250.031511 -272.100092) (xy 250.074176 -272.118328) (xy 250.084116 -272.122148)
			(xy 250.105384 -272.122148) (xy 250.115324 -272.118328) (xy 250.161715 -272.098536) (xy 250.257961 -272.068366)
			(xy 250.307348 -272.05813) (xy 250.318576 -272.055423) (xy 250.337071 -272.041631) (xy 250.347664 -272.021135)
			(xy 250.348496 -272.009616) (xy 250.350009 -271.965785) (xy 250.360603 -271.878721) (xy 250.379717 -271.793122)
			(xy 250.407166 -271.709821) (xy 250.424442 -271.66951) (xy 250.428239 -271.659563) (xy 250.428253 -271.638302)
			(xy 250.424442 -271.628362) (xy 250.406212 -271.585694) (xy 250.377664 -271.497404) (xy 250.358466 -271.406621)
			(xy 250.348829 -271.314332) (xy 250.348242 -271.267936) (xy 250.348833 -271.221541) (xy 250.358475 -271.129252)
			(xy 250.377669 -271.038469) (xy 250.406205 -270.950175) (xy 250.424442 -270.90751) (xy 250.428239 -270.897563)
			(xy 250.428253 -270.876302) (xy 250.424442 -270.866362) (xy 250.407158 -270.826055) (xy 250.379718 -270.742751)
			(xy 250.360607 -270.657151) (xy 250.350012 -270.570086) (xy 250.348496 -270.526256) (xy 250.347613 -270.514753)
			(xy 250.337005 -270.494291) (xy 250.318555 -270.480479) (xy 250.307348 -270.477742) (xy 250.257959 -270.467514)
			(xy 250.161715 -270.437337) (xy 250.115324 -270.417544) (xy 250.105384 -270.413724) (xy 250.084116 -270.413724)
			(xy 250.074176 -270.417544) (xy 250.031508 -270.435774) (xy 249.943218 -270.464322) (xy 249.852434 -270.483519)
			(xy 249.760146 -270.493157) (xy 249.71375 -270.493744) (xy 249.671405 -270.493166) (xy 249.587098 -270.485111)
			(xy 249.503939 -270.469079) (xy 249.42268 -270.445216) (xy 249.344057 -270.413736) (xy 249.268783 -270.374926)
			(xy 249.197538 -270.329136) (xy 249.130969 -270.276781) (xy 249.069677 -270.218337) (xy 249.014218 -270.15433)
			(xy 248.965094 -270.085342) (xy 248.92275 -270.011997) (xy 248.88757 -269.93496) (xy 248.859871 -269.854927)
			(xy 248.839905 -269.772623) (xy 248.827853 -269.688795) (xy 248.823823 -269.6042) (xy 248.827853 -269.519605)
			(xy 248.839905 -269.435777) (xy 248.859871 -269.353473) (xy 248.88757 -269.27344) (xy 248.92275 -269.196403)
			(xy 248.965094 -269.123058) (xy 249.014218 -269.05407) (xy 249.069677 -268.990063) (xy 249.130969 -268.931619)
			(xy 249.197538 -268.879264) (xy 249.268783 -268.833474) (xy 249.344057 -268.794664) (xy 249.42268 -268.763184)
			(xy 249.503939 -268.739321) (xy 249.587098 -268.723289) (xy 249.671405 -268.715234) (xy 249.71375 -268.714728)
			(xy 249.760145 -268.715325) (xy 249.852433 -268.724966) (xy 249.943217 -268.744157) (xy 250.031511 -268.772692)
			(xy 250.074176 -268.790928) (xy 250.084116 -268.794748) (xy 250.105384 -268.794748) (xy 250.115324 -268.790928)
			(xy 250.157994 -268.772702) (xy 250.246283 -268.744153) (xy 250.337066 -268.724954) (xy 250.429355 -268.715315)
			(xy 250.47575 -268.714728) (xy 250.522145 -268.715325) (xy 250.614433 -268.724966) (xy 250.705217 -268.744157)
			(xy 250.793511 -268.772692) (xy 250.836176 -268.790928) (xy 250.846116 -268.794748) (xy 250.867384 -268.794748)
			(xy 250.877324 -268.790928) (xy 250.919994 -268.772702) (xy 251.008283 -268.744153) (xy 251.099066 -268.724954)
			(xy 251.191355 -268.715315) (xy 251.23775 -268.714728) (xy 251.284145 -268.715325) (xy 251.376433 -268.724966)
			(xy 251.467217 -268.744157) (xy 251.555511 -268.772692) (xy 251.598176 -268.790928) (xy 251.608116 -268.794748)
			(xy 251.629384 -268.794748) (xy 251.639324 -268.790928) (xy 251.681994 -268.772702) (xy 251.770283 -268.744153)
			(xy 251.861066 -268.724954) (xy 251.953355 -268.715315) (xy 251.99975 -268.714728) (xy 252.040854 -268.715119)
			(xy 252.122712 -268.722709) (xy 252.20352 -268.737819) (xy 252.28259 -268.760321) (xy 252.359245 -268.790022)
			(xy 252.432834 -268.826669) (xy 252.502727 -268.86995) (xy 252.568328 -268.919495) (xy 252.629079 -268.974882)
			(xy 252.68446 -269.035638) (xy 252.733998 -269.101244) (xy 252.777272 -269.171141) (xy 252.813913 -269.244733)
			(xy 252.843607 -269.321392) (xy 252.866101 -269.400464) (xy 252.881203 -269.481273) (xy 252.888785 -269.563132)
			(xy 252.889258 -269.604236) (xy 252.8887 -269.648724) (xy 252.879791 -269.737252) (xy 252.862097 -269.82445)
			(xy 252.835794 -269.909449) (xy 252.801144 -269.9914) (xy 252.780292 -270.030702) (xy 252.77651 -270.038322)
			(xy 252.773689 -270.055088) (xy 252.776501 -270.071855) (xy 252.780292 -270.07947) (xy 252.801169 -270.118761)
			(xy 252.835845 -270.200706) (xy 252.862158 -270.285706) (xy 252.879842 -270.372911) (xy 252.888722 -270.461446)
			(xy 252.889258 -270.505936) (xy 252.888657 -270.552331) (xy 252.879018 -270.644619) (xy 252.859827 -270.735403)
			(xy 252.831294 -270.823697) (xy 252.813058 -270.866362) (xy 252.809218 -270.876295) (xy 252.809232 -270.89757)
			(xy 252.813058 -270.90751) (xy 252.831312 -270.950169) (xy 252.859854 -271.038462) (xy 252.879045 -271.129248)
			(xy 252.888675 -271.22154) (xy 252.889258 -271.267936) (xy 252.888657 -271.314331) (xy 252.879018 -271.406619)
			(xy 252.859827 -271.497403) (xy 252.831294 -271.585697) (xy 252.813058 -271.628362) (xy 252.809218 -271.638295)
			(xy 252.809232 -271.65957) (xy 252.813058 -271.66951) (xy 252.831312 -271.712169) (xy 252.859854 -271.800462)
			(xy 252.879045 -271.891248) (xy 252.888675 -271.98354) (xy 252.889258 -272.029936) (xy 252.8887 -272.074424)
			(xy 252.879791 -272.162952) (xy 252.862097 -272.25015) (xy 252.835794 -272.335149) (xy 252.801144 -272.4171)
			(xy 252.780292 -272.456402) (xy 252.77651 -272.464022) (xy 252.773689 -272.480788) (xy 252.776501 -272.497555)
			(xy 252.780292 -272.50517) (xy 252.801169 -272.544461) (xy 252.835845 -272.626406) (xy 252.862158 -272.711406)
			(xy 252.879842 -272.798611) (xy 252.888722 -272.887146) (xy 252.889258 -272.931636) (xy 252.888768 -272.972738)
			(xy 252.88118 -273.05459) (xy 252.866073 -273.135393) (xy 252.843575 -273.214458) (xy 252.813879 -273.291109)
			(xy 252.777237 -273.364694) (xy 252.733962 -273.434585) (xy 252.684423 -273.500184) (xy 252.629043 -273.560934)
			(xy 252.568295 -273.616314) (xy 252.502696 -273.665854) (xy 252.432807 -273.70913) (xy 252.359222 -273.745773)
			(xy 252.282571 -273.775471) (xy 252.203507 -273.79797) (xy 252.122704 -273.813078) (xy 252.040852 -273.820667)
			(xy 251.99975 -273.821144) (xy 251.953355 -273.820549) (xy 251.861067 -273.810908) (xy 251.770283 -273.791716)
			(xy 251.681989 -273.763181) (xy 251.639324 -273.744944) (xy 251.629384 -273.741124) (xy 251.608116 -273.741124)
			(xy 251.598176 -273.744944) (xy 251.555508 -273.763174) (xy 251.467218 -273.791722) (xy 251.376434 -273.810919)
			(xy 251.284146 -273.820557) (xy 251.23775 -273.821144) (xy 251.191355 -273.820549) (xy 251.099067 -273.810908)
			(xy 251.008283 -273.791716) (xy 250.919989 -273.763181) (xy 250.877324 -273.744944) (xy 250.867384 -273.741124)
			(xy 250.846116 -273.741124) (xy 250.836176 -273.744944) (xy 250.793508 -273.763174) (xy 250.705218 -273.791722)
			(xy 250.614434 -273.810919) (xy 250.522146 -273.820557) (xy 250.47575 -273.821144) (xy 250.429355 -273.820549)
			(xy 250.337067 -273.810908) (xy 250.246283 -273.791716) (xy 250.157989 -273.763181) (xy 250.115324 -273.744944)
			(xy 250.105384 -273.741124) (xy 250.084116 -273.741124) (xy 250.074176 -273.744944) (xy 250.031508 -273.763174)
			(xy 249.943218 -273.791722) (xy 249.852434 -273.810919) (xy 249.760146 -273.820557) (xy 249.71375 -273.821144)
			(xy 249.671405 -273.820566) (xy 249.587098 -273.812511) (xy 249.503939 -273.796479) (xy 249.42268 -273.772616)
			(xy 249.344057 -273.741136) (xy 249.268783 -273.702326) (xy 249.197538 -273.656536) (xy 249.130969 -273.604181)
			(xy 249.069677 -273.545737) (xy 249.014218 -273.48173) (xy 248.965094 -273.412742) (xy 248.92275 -273.339397)
			(xy 248.88757 -273.26236) (xy 248.859871 -273.182327) (xy 248.839905 -273.100023) (xy 248.827853 -273.016195)
			(xy 248.823823 -272.9316) (xy 241.90311 -272.9316) (xy 241.896715 -273.01336) (xy 241.872685 -273.217674)
			(xy 241.840701 -273.420896) (xy 241.800812 -273.622714) (xy 241.75308 -273.822823) (xy 241.697577 -274.020917)
			(xy 241.634387 -274.216695) (xy 241.563606 -274.409858) (xy 241.485344 -274.600113) (xy 241.399717 -274.787169)
			(xy 241.306858 -274.970742) (xy 241.206907 -275.150552) (xy 241.100017 -275.326325) (xy 240.98635 -275.497795)
			(xy 240.86608 -275.664698) (xy 240.739389 -275.826783) (xy 240.606471 -275.983801) (xy 240.467528 -276.135513)
			(xy 240.376897 -276.227032) (xy 249.340116 -276.227032) (xy 249.340523 -276.200651) (xy 249.347785 -276.148392)
			(xy 249.362175 -276.09763) (xy 249.383419 -276.049335) (xy 249.411112 -276.004425) (xy 249.444726 -275.963757)
			(xy 249.483621 -275.928106) (xy 249.527055 -275.898152) (xy 249.550428 -275.88591) (xy 249.563636 -275.87956)
			(xy 249.578622 -275.855176) (xy 249.578622 -275.735288) (xy 249.563636 -275.710904) (xy 249.550428 -275.704554)
			(xy 249.527054 -275.692319) (xy 249.483633 -275.662353) (xy 249.44475 -275.626695) (xy 249.411146 -275.586025)
			(xy 249.38346 -275.541115) (xy 249.36222 -275.492822) (xy 249.347829 -275.442065) (xy 249.340563 -275.389811)
			(xy 249.340116 -275.363432) (xy 249.340585 -275.336179) (xy 249.348338 -275.282227) (xy 249.363692 -275.229928)
			(xy 249.386332 -275.180346) (xy 249.415799 -275.134492) (xy 249.451492 -275.093298) (xy 249.492685 -275.057604)
			(xy 249.538539 -275.028136) (xy 249.58812 -275.005494) (xy 249.640419 -274.99014) (xy 249.694371 -274.982386)
			(xy 249.721624 -274.981924) (xy 249.748882 -274.982395) (xy 249.802841 -274.990165) (xy 249.855147 -275.005529)
			(xy 249.904737 -275.028175) (xy 249.950602 -275.057643) (xy 249.991811 -275.093334) (xy 250.027525 -275.134522)
			(xy 250.04268 -275.157184) (xy 250.047513 -275.164165) (xy 250.060832 -275.174681) (xy 250.076867 -275.180239)
			(xy 250.085352 -275.180552) (xy 250.170696 -275.180552) (xy 250.179171 -275.180187) (xy 250.195181 -275.174613)
			(xy 250.208509 -275.164136) (xy 250.213368 -275.157184) (xy 250.228521 -275.134522) (xy 250.264234 -275.093335)
			(xy 250.305442 -275.057647) (xy 250.351309 -275.028184) (xy 250.4009 -275.005547) (xy 250.453208 -274.990194)
			(xy 250.507167 -274.982439) (xy 250.561681 -274.982439) (xy 250.61564 -274.990194) (xy 250.667948 -275.005547)
			(xy 250.717539 -275.028184) (xy 250.763406 -275.057647) (xy 250.804614 -275.093335) (xy 250.840327 -275.134522)
			(xy 250.85548 -275.157184) (xy 250.860313 -275.164165) (xy 250.873632 -275.174681) (xy 250.889667 -275.180239)
			(xy 250.898152 -275.180552) (xy 250.983496 -275.180552) (xy 250.991971 -275.180187) (xy 251.007981 -275.174613)
			(xy 251.021309 -275.164136) (xy 251.026168 -275.157184) (xy 251.041311 -275.134513) (xy 251.077021 -275.093319)
			(xy 251.118229 -275.057624) (xy 251.164097 -275.028157) (xy 251.213691 -275.005516) (xy 251.266002 -274.990162)
			(xy 251.319965 -274.982408) (xy 251.347224 -274.981924) (xy 251.374479 -274.982333) (xy 251.428434 -274.990094)
			(xy 251.480734 -275.005454) (xy 251.530317 -275.028102) (xy 251.576171 -275.057576) (xy 251.617365 -275.093275)
			(xy 251.653058 -275.134473) (xy 251.682525 -275.180332) (xy 251.705165 -275.229918) (xy 251.720518 -275.282221)
			(xy 251.728271 -275.336177) (xy 251.728732 -275.363432) (xy 251.728269 -275.389811) (xy 251.721013 -275.442067)
			(xy 251.70663 -275.492825) (xy 251.685393 -275.54112) (xy 251.657708 -275.586029) (xy 251.624102 -275.626698)
			(xy 251.585215 -275.662351) (xy 251.541789 -275.69231) (xy 251.51842 -275.704554) (xy 251.505212 -275.710904)
			(xy 251.490226 -275.735288) (xy 251.490226 -275.855176) (xy 251.505212 -275.87956) (xy 251.51842 -275.88591)
			(xy 251.541767 -275.898195) (xy 251.585189 -275.928152) (xy 251.624074 -275.963801) (xy 251.657682 -276.004464)
			(xy 251.685371 -276.049367) (xy 251.706616 -276.097654) (xy 251.721011 -276.148405) (xy 251.728282 -276.200655)
			(xy 251.728732 -276.227032) (xy 251.728252 -276.254283) (xy 251.720492 -276.30823) (xy 251.705134 -276.360523)
			(xy 251.682491 -276.410099) (xy 251.653023 -276.455948) (xy 251.617331 -276.497137) (xy 251.576141 -276.532828)
			(xy 251.530292 -276.562295) (xy 251.480716 -276.584937) (xy 251.428422 -276.600293) (xy 251.374475 -276.608053)
			(xy 251.347224 -276.60854) (xy 251.319967 -276.608048) (xy 251.266008 -276.600284) (xy 251.213701 -276.584925)
			(xy 251.164111 -276.562282) (xy 251.118246 -276.532817) (xy 251.077037 -276.497128) (xy 251.041323 -276.455941)
			(xy 251.026168 -276.43328) (xy 251.021348 -276.426288) (xy 251.008025 -276.415769) (xy 250.991984 -276.410218)
			(xy 250.983496 -276.409912) (xy 250.898152 -276.409912) (xy 250.889671 -276.410214) (xy 250.873655 -276.415811)
			(xy 250.860332 -276.426315) (xy 250.85548 -276.43328) (xy 250.840327 -276.455942) (xy 250.804614 -276.497129)
			(xy 250.763406 -276.532817) (xy 250.717539 -276.56228) (xy 250.667948 -276.584917) (xy 250.61564 -276.60027)
			(xy 250.561681 -276.608025) (xy 250.507167 -276.608025) (xy 250.453208 -276.60027) (xy 250.4009 -276.584917)
			(xy 250.351309 -276.56228) (xy 250.305442 -276.532817) (xy 250.264234 -276.497129) (xy 250.228521 -276.455942)
			(xy 250.213368 -276.43328) (xy 250.208548 -276.426288) (xy 250.195225 -276.415769) (xy 250.179184 -276.410218)
			(xy 250.170696 -276.409912) (xy 250.085352 -276.409912) (xy 250.076871 -276.410214) (xy 250.060855 -276.415811)
			(xy 250.047532 -276.426315) (xy 250.04268 -276.43328) (xy 250.027559 -276.455967) (xy 249.991847 -276.497163)
			(xy 249.950636 -276.532857) (xy 249.904764 -276.562323) (xy 249.855166 -276.584962) (xy 249.802851 -276.600311)
			(xy 249.748884 -276.608059) (xy 249.721624 -276.60854) (xy 249.694375 -276.608) (xy 249.640431 -276.600247)
			(xy 249.588139 -276.584897) (xy 249.538564 -276.562261) (xy 249.492715 -276.5328) (xy 249.451526 -276.497114)
			(xy 249.415834 -276.45593) (xy 249.386366 -276.410085) (xy 249.363723 -276.360513) (xy 249.348365 -276.308224)
			(xy 249.340604 -276.254281) (xy 249.340116 -276.227032) (xy 240.376897 -276.227032) (xy 240.322771 -276.281689)
			(xy 240.172421 -276.422106) (xy 240.016708 -276.556549) (xy 239.855867 -276.684815) (xy 239.690145 -276.806708)
			(xy 239.519792 -276.922043) (xy 239.34507 -277.030643) (xy 239.166244 -277.132343) (xy 238.983585 -277.226989)
			(xy 238.797374 -277.314436) (xy 238.607892 -277.394552) (xy 238.415428 -277.467213) (xy 238.220276 -277.53231)
			(xy 238.022733 -277.589744) (xy 237.8231 -277.639426) (xy 237.62168 -277.681281) (xy 237.41878 -277.715246)
			(xy 237.21471 -277.741269) (xy 237.00978 -277.75931) (xy 236.804302 -277.769342) (xy 236.598589 -277.771349)
			(xy 236.392954 -277.765329) (xy 236.187711 -277.75129) (xy 235.983172 -277.729253) (xy 235.779648 -277.699254)
			(xy 235.57745 -277.661336) (xy 235.376885 -277.615559) (xy 235.178259 -277.561991) (xy 234.981874 -277.500714)
			(xy 234.78803 -277.431821) (xy 234.59702 -277.355418) (xy 234.409138 -277.271621) (xy 234.224668 -277.180557)
			(xy 234.043891 -277.082366) (xy 233.867083 -276.977195) (xy 233.694513 -276.865207) (xy 233.526444 -276.74657)
			(xy 233.363131 -276.621467) (xy 233.204824 -276.490087) (xy 233.051763 -276.352631) (xy 232.904182 -276.209307)
			(xy 232.762305 -276.060335) (xy 232.626348 -275.90594) (xy 232.496519 -275.746359) (xy 232.373015 -275.581833)
			(xy 232.256024 -275.412614) (xy 232.145725 -275.23896) (xy 232.042284 -275.061134) (xy 231.945861 -274.879408)
			(xy 231.856601 -274.694058) (xy 231.774641 -274.505367) (xy 231.700105 -274.313622) (xy 231.633107 -274.119114)
			(xy 231.573749 -273.922141) (xy 231.522122 -273.723002) (xy 231.478303 -273.522) (xy 231.44236 -273.319441)
			(xy 231.414347 -273.115634) (xy 231.394308 -272.91089) (xy 231.382272 -272.70552) (xy 231.378258 -272.499836)
			(xy 224.857094 -272.499836) (xy 224.87539 -272.520951) (xy 224.924517 -272.589941) (xy 224.966863 -272.663288)
			(xy 225.002045 -272.740329) (xy 225.029745 -272.820364) (xy 225.049712 -272.902671) (xy 225.061765 -272.986502)
			(xy 225.065795 -273.0711) (xy 225.061765 -273.155698) (xy 225.049712 -273.239529) (xy 225.029745 -273.321836)
			(xy 225.002045 -273.401871) (xy 224.966863 -273.478912) (xy 224.924517 -273.552259) (xy 224.87539 -273.621249)
			(xy 224.819929 -273.685257) (xy 224.758634 -273.743703) (xy 224.692061 -273.796058) (xy 224.620813 -273.841849)
			(xy 224.545536 -273.880659) (xy 224.46691 -273.912138) (xy 224.385647 -273.936001) (xy 224.302485 -273.952032)
			(xy 224.218175 -273.960085) (xy 224.175828 -273.96059) (xy 224.129433 -273.959999) (xy 224.037144 -273.950356)
			(xy 223.946361 -273.931163) (xy 223.858067 -273.902627) (xy 223.815402 -273.88439) (xy 223.805462 -273.88057)
			(xy 223.784194 -273.88057) (xy 223.774254 -273.88439) (xy 223.731588 -273.902624) (xy 223.643297 -273.931171)
			(xy 223.552513 -273.950367) (xy 223.460224 -273.960004) (xy 223.413828 -273.96059) (xy 223.367433 -273.959999)
			(xy 223.275144 -273.950356) (xy 223.184361 -273.931163) (xy 223.096067 -273.902627) (xy 223.053402 -273.88439)
			(xy 223.043462 -273.88057) (xy 223.022194 -273.88057) (xy 223.012254 -273.88439) (xy 222.969588 -273.902624)
			(xy 222.881297 -273.931171) (xy 222.790513 -273.950367) (xy 222.698224 -273.960004) (xy 222.651828 -273.96059)
			(xy 222.605433 -273.959999) (xy 222.513144 -273.950356) (xy 222.422361 -273.931163) (xy 222.334067 -273.902627)
			(xy 222.291402 -273.88439) (xy 222.281462 -273.88057) (xy 222.260194 -273.88057) (xy 222.250254 -273.88439)
			(xy 222.207588 -273.902624) (xy 222.119297 -273.931171) (xy 222.028513 -273.950367) (xy 221.936224 -273.960004)
			(xy 221.889828 -273.96059) (xy 221.848725 -273.960121) (xy 221.766869 -273.952538) (xy 221.686062 -273.937435)
			(xy 221.606993 -273.91494) (xy 221.530337 -273.885245) (xy 221.456748 -273.848604) (xy 221.386854 -273.805328)
			(xy 221.321252 -273.755789) (xy 221.2605 -273.700407) (xy 221.205118 -273.639656) (xy 221.155577 -273.574054)
			(xy 221.112301 -273.50416) (xy 221.075659 -273.430572) (xy 221.045963 -273.353917) (xy 221.023467 -273.274848)
			(xy 221.008363 -273.194041) (xy 221.000779 -273.112185) (xy 221.00032 -273.071082) (xy 218.193874 -273.071082)
			(xy 218.193874 -276.366478) (xy 221.77121 -276.366478) (xy 221.771658 -276.340098) (xy 221.778914 -276.287841)
			(xy 221.793298 -276.237081) (xy 221.814536 -276.188785) (xy 221.842223 -276.143875) (xy 221.875832 -276.103207)
			(xy 221.914722 -276.067555) (xy 221.958151 -276.037599) (xy 221.981522 -276.025356) (xy 221.99473 -276.019006)
			(xy 222.009716 -275.994622) (xy 222.009716 -275.874734) (xy 221.99473 -275.85035) (xy 221.981522 -275.844)
			(xy 221.958148 -275.831765) (xy 221.914722 -275.801803) (xy 221.875835 -275.766148) (xy 221.842229 -275.725478)
			(xy 221.814542 -275.680568) (xy 221.793303 -275.632273) (xy 221.778915 -275.581514) (xy 221.771654 -275.529257)
			(xy 221.77121 -275.502878) (xy 221.771657 -275.475625) (xy 221.779417 -275.421675) (xy 221.794776 -275.369379)
			(xy 221.817421 -275.3198) (xy 221.846891 -275.273949) (xy 221.882587 -275.232759) (xy 221.923781 -275.197067)
			(xy 221.969635 -275.167602) (xy 222.019216 -275.144962) (xy 222.071514 -275.129609) (xy 222.125465 -275.121855)
			(xy 222.152718 -275.12137) (xy 222.179977 -275.121825) (xy 222.233938 -275.129595) (xy 222.286245 -275.144961)
			(xy 222.335835 -275.167609) (xy 222.3817 -275.19708) (xy 222.422908 -275.232774) (xy 222.45862 -275.273966)
			(xy 222.473774 -275.29663) (xy 222.478626 -275.303598) (xy 222.491934 -275.31412) (xy 222.507963 -275.319683)
			(xy 222.516446 -275.319998) (xy 222.60179 -275.319998) (xy 222.610267 -275.319653) (xy 222.626281 -275.314074)
			(xy 222.639607 -275.303588) (xy 222.644462 -275.29663) (xy 222.659624 -275.273972) (xy 222.695329 -275.232775)
			(xy 222.736533 -275.197079) (xy 222.782397 -275.167609) (xy 222.831989 -275.144966) (xy 222.884298 -275.12961)
			(xy 222.93826 -275.121855) (xy 222.965518 -275.12137) (xy 222.991896 -275.121843) (xy 223.044152 -275.129097)
			(xy 223.09491 -275.143479) (xy 223.143205 -275.164714) (xy 223.188114 -275.192398) (xy 223.228783 -275.226003)
			(xy 223.264437 -275.264888) (xy 223.294396 -275.308313) (xy 223.30664 -275.331682) (xy 223.31299 -275.34489)
			(xy 223.337374 -275.359876) (xy 223.457262 -275.359876) (xy 223.481646 -275.34489) (xy 223.487996 -275.331682)
			(xy 223.500217 -275.3083) (xy 223.530182 -275.264876) (xy 223.565841 -275.225991) (xy 223.606513 -275.192386)
			(xy 223.651425 -275.164701) (xy 223.699721 -275.143462) (xy 223.750481 -275.129075) (xy 223.802738 -275.121814)
			(xy 223.829118 -275.12137) (xy 223.856369 -275.121861) (xy 223.910315 -275.129619) (xy 223.962608 -275.144976)
			(xy 224.012184 -275.167617) (xy 224.058033 -275.197083) (xy 224.099223 -275.232774) (xy 224.134914 -275.273963)
			(xy 224.164381 -275.319812) (xy 224.187023 -275.369388) (xy 224.20238 -275.421681) (xy 224.210139 -275.475627)
			(xy 224.210626 -275.502878) (xy 224.210205 -275.529258) (xy 224.202942 -275.581516) (xy 224.188552 -275.632276)
			(xy 224.16731 -275.680571) (xy 224.139619 -275.72548) (xy 224.106007 -275.766148) (xy 224.067116 -275.8018)
			(xy 224.023685 -275.831757) (xy 224.000314 -275.844) (xy 223.987106 -275.85035) (xy 223.97212 -275.874734)
			(xy 223.97212 -275.994622) (xy 223.987106 -276.019006) (xy 224.000314 -276.025356) (xy 224.023678 -276.037609)
			(xy 224.067102 -276.06757) (xy 224.105987 -276.103223) (xy 224.139593 -276.143891) (xy 224.167281 -276.188799)
			(xy 224.188522 -276.23709) (xy 224.202913 -276.287846) (xy 224.210179 -276.3401) (xy 224.210626 -276.366478)
			(xy 224.210124 -276.393729) (xy 224.202371 -276.447678) (xy 224.187018 -276.499974) (xy 224.16438 -276.549553)
			(xy 224.134916 -276.595405) (xy 224.099226 -276.636598) (xy 224.058037 -276.672292) (xy 224.012188 -276.701761)
			(xy 223.962612 -276.724404) (xy 223.910317 -276.739762) (xy 223.856369 -276.747521) (xy 223.829118 -276.747986)
			(xy 223.802737 -276.74759) (xy 223.750477 -276.740326) (xy 223.699715 -276.725934) (xy 223.65142 -276.704688)
			(xy 223.60651 -276.676994) (xy 223.565842 -276.643378) (xy 223.530192 -276.604482) (xy 223.500238 -276.561047)
			(xy 223.487996 -276.537674) (xy 223.481646 -276.524466) (xy 223.457262 -276.50948) (xy 223.337374 -276.50948)
			(xy 223.31299 -276.524466) (xy 223.30664 -276.537674) (xy 223.294417 -276.561054) (xy 223.264449 -276.604475)
			(xy 223.22879 -276.643358) (xy 223.188117 -276.676962) (xy 223.143206 -276.704647) (xy 223.094912 -276.725886)
			(xy 223.044153 -276.740275) (xy 222.991897 -276.74754) (xy 222.965518 -276.747986) (xy 222.938262 -276.747478)
			(xy 222.884304 -276.739714) (xy 222.831999 -276.724356) (xy 222.78241 -276.701716) (xy 222.736544 -276.672253)
			(xy 222.695335 -276.636568) (xy 222.659618 -276.595385) (xy 222.644462 -276.572726) (xy 222.63966 -276.56572)
			(xy 222.626327 -276.555208) (xy 222.61028 -276.549662) (xy 222.60179 -276.549358) (xy 222.516446 -276.549358)
			(xy 222.507967 -276.549679) (xy 222.491954 -276.555272) (xy 222.478629 -276.565766) (xy 222.473774 -276.572726)
			(xy 222.458607 -276.59538) (xy 222.422901 -276.636574) (xy 222.381697 -276.672269) (xy 222.335833 -276.701738)
			(xy 222.286243 -276.724382) (xy 222.233936 -276.73974) (xy 222.179976 -276.747499) (xy 222.152718 -276.747986)
			(xy 222.125465 -276.747528) (xy 222.071512 -276.739773) (xy 222.019213 -276.724418) (xy 221.969632 -276.701776)
			(xy 221.923777 -276.672308) (xy 221.882584 -276.636613) (xy 221.84689 -276.59542) (xy 221.817422 -276.549565)
			(xy 221.794781 -276.499983) (xy 221.779426 -276.447684) (xy 221.771672 -276.393731) (xy 221.77121 -276.366478)
			(xy 218.193874 -276.366478) (xy 218.193874 -279.643078) (xy 221.77121 -279.643078) (xy 221.771658 -279.616698)
			(xy 221.778914 -279.564441) (xy 221.793298 -279.513681) (xy 221.814536 -279.465385) (xy 221.842223 -279.420475)
			(xy 221.875832 -279.379807) (xy 221.914722 -279.344155) (xy 221.958151 -279.314199) (xy 221.981522 -279.301956)
			(xy 221.99473 -279.295606) (xy 222.009716 -279.271222) (xy 222.009716 -279.151334) (xy 221.99473 -279.12695)
			(xy 221.981522 -279.1206) (xy 221.958148 -279.108365) (xy 221.914722 -279.078403) (xy 221.875835 -279.042748)
			(xy 221.842229 -279.002078) (xy 221.814542 -278.957168) (xy 221.793303 -278.908873) (xy 221.778915 -278.858114)
			(xy 221.771654 -278.805857) (xy 221.77121 -278.779478) (xy 221.771657 -278.752225) (xy 221.779417 -278.698275)
			(xy 221.794776 -278.645979) (xy 221.817421 -278.5964) (xy 221.846891 -278.550549) (xy 221.882587 -278.509359)
			(xy 221.923781 -278.473667) (xy 221.969635 -278.444202) (xy 222.019216 -278.421562) (xy 222.071514 -278.406209)
			(xy 222.125465 -278.398455) (xy 222.152718 -278.39797) (xy 222.179977 -278.398425) (xy 222.233938 -278.406195)
			(xy 222.286245 -278.421561) (xy 222.335835 -278.444209) (xy 222.3817 -278.47368) (xy 222.422908 -278.509374)
			(xy 222.45862 -278.550566) (xy 222.473774 -278.57323) (xy 222.478626 -278.580198) (xy 222.491934 -278.59072)
			(xy 222.507963 -278.596283) (xy 222.516446 -278.596598) (xy 222.60179 -278.596598) (xy 222.610267 -278.596253)
			(xy 222.626281 -278.590674) (xy 222.639607 -278.580188) (xy 222.644462 -278.57323) (xy 222.659624 -278.550572)
			(xy 222.695329 -278.509375) (xy 222.736533 -278.473679) (xy 222.782397 -278.444209) (xy 222.831989 -278.421566)
			(xy 222.884298 -278.40621) (xy 222.93826 -278.398455) (xy 222.965518 -278.39797) (xy 222.991896 -278.398443)
			(xy 223.044152 -278.405697) (xy 223.09491 -278.420079) (xy 223.143205 -278.441314) (xy 223.188114 -278.468998)
			(xy 223.228783 -278.502603) (xy 223.264437 -278.541488) (xy 223.294396 -278.584913) (xy 223.30664 -278.608282)
			(xy 223.31299 -278.62149) (xy 223.337374 -278.636476) (xy 223.457262 -278.636476) (xy 223.481646 -278.62149)
			(xy 223.487996 -278.608282) (xy 223.500217 -278.5849) (xy 223.530182 -278.541476) (xy 223.565841 -278.502591)
			(xy 223.606513 -278.468986) (xy 223.651425 -278.441301) (xy 223.699721 -278.420062) (xy 223.750481 -278.405675)
			(xy 223.802738 -278.398414) (xy 223.829118 -278.39797) (xy 223.856369 -278.398461) (xy 223.910315 -278.406219)
			(xy 223.962608 -278.421576) (xy 224.012184 -278.444217) (xy 224.058033 -278.473683) (xy 224.099223 -278.509374)
			(xy 224.134914 -278.550563) (xy 224.164381 -278.596412) (xy 224.187023 -278.645988) (xy 224.20238 -278.698281)
			(xy 224.210139 -278.752227) (xy 224.210626 -278.779478) (xy 224.210205 -278.805858) (xy 224.202942 -278.858116)
			(xy 224.188552 -278.908876) (xy 224.16731 -278.957171) (xy 224.139619 -279.00208) (xy 224.106007 -279.042748)
			(xy 224.067116 -279.0784) (xy 224.023685 -279.108357) (xy 224.000314 -279.1206) (xy 223.987106 -279.12695)
			(xy 223.97212 -279.151334) (xy 223.97212 -279.271222) (xy 223.987106 -279.295606) (xy 224.000314 -279.301956)
			(xy 224.023678 -279.314209) (xy 224.067102 -279.34417) (xy 224.105987 -279.379823) (xy 224.139593 -279.420491)
			(xy 224.167281 -279.465399) (xy 224.184098 -279.503632) (xy 249.340116 -279.503632) (xy 249.340523 -279.477251)
			(xy 249.347785 -279.424992) (xy 249.362175 -279.37423) (xy 249.383419 -279.325935) (xy 249.411112 -279.281025)
			(xy 249.444726 -279.240357) (xy 249.483621 -279.204706) (xy 249.527055 -279.174752) (xy 249.550428 -279.16251)
			(xy 249.563636 -279.15616) (xy 249.578622 -279.131776) (xy 249.578622 -279.011888) (xy 249.563636 -278.987504)
			(xy 249.550428 -278.981154) (xy 249.527054 -278.968919) (xy 249.483633 -278.938953) (xy 249.44475 -278.903295)
			(xy 249.411146 -278.862625) (xy 249.38346 -278.817715) (xy 249.36222 -278.769422) (xy 249.347829 -278.718665)
			(xy 249.340563 -278.666411) (xy 249.340116 -278.640032) (xy 249.340585 -278.612779) (xy 249.348338 -278.558827)
			(xy 249.363692 -278.506528) (xy 249.386332 -278.456946) (xy 249.415799 -278.411092) (xy 249.451492 -278.369898)
			(xy 249.492685 -278.334204) (xy 249.538539 -278.304736) (xy 249.58812 -278.282094) (xy 249.640419 -278.26674)
			(xy 249.694371 -278.258986) (xy 249.721624 -278.258524) (xy 249.748882 -278.258995) (xy 249.802841 -278.266765)
			(xy 249.855147 -278.282129) (xy 249.904737 -278.304775) (xy 249.950602 -278.334243) (xy 249.991811 -278.369934)
			(xy 250.027525 -278.411122) (xy 250.04268 -278.433784) (xy 250.047513 -278.440765) (xy 250.060832 -278.451281)
			(xy 250.076867 -278.456839) (xy 250.085352 -278.457152) (xy 250.170696 -278.457152) (xy 250.179171 -278.456787)
			(xy 250.195181 -278.451213) (xy 250.208509 -278.440736) (xy 250.213368 -278.433784) (xy 250.228521 -278.411122)
			(xy 250.264234 -278.369935) (xy 250.305442 -278.334247) (xy 250.351309 -278.304784) (xy 250.4009 -278.282147)
			(xy 250.453208 -278.266794) (xy 250.507167 -278.259039) (xy 250.561681 -278.259039) (xy 250.61564 -278.266794)
			(xy 250.667948 -278.282147) (xy 250.717539 -278.304784) (xy 250.763406 -278.334247) (xy 250.804614 -278.369935)
			(xy 250.840327 -278.411122) (xy 250.85548 -278.433784) (xy 250.860313 -278.440765) (xy 250.873632 -278.451281)
			(xy 250.889667 -278.456839) (xy 250.898152 -278.457152) (xy 250.983496 -278.457152) (xy 250.991971 -278.456787)
			(xy 251.007981 -278.451213) (xy 251.021309 -278.440736) (xy 251.026168 -278.433784) (xy 251.041311 -278.411113)
			(xy 251.077021 -278.369919) (xy 251.118229 -278.334224) (xy 251.164097 -278.304757) (xy 251.213691 -278.282116)
			(xy 251.266002 -278.266762) (xy 251.319965 -278.259008) (xy 251.347224 -278.258524) (xy 251.374479 -278.258933)
			(xy 251.428434 -278.266694) (xy 251.480734 -278.282054) (xy 251.530317 -278.304702) (xy 251.576171 -278.334176)
			(xy 251.617365 -278.369875) (xy 251.653058 -278.411073) (xy 251.682525 -278.456932) (xy 251.705165 -278.506518)
			(xy 251.720518 -278.558821) (xy 251.728271 -278.612777) (xy 251.728732 -278.640032) (xy 251.728269 -278.666411)
			(xy 251.721013 -278.718667) (xy 251.70663 -278.769425) (xy 251.685393 -278.81772) (xy 251.657708 -278.862629)
			(xy 251.624102 -278.903298) (xy 251.585215 -278.938951) (xy 251.541789 -278.96891) (xy 251.51842 -278.981154)
			(xy 251.505212 -278.987504) (xy 251.490226 -279.011888) (xy 251.490226 -279.131776) (xy 251.505212 -279.15616)
			(xy 251.51842 -279.16251) (xy 251.541767 -279.174795) (xy 251.585189 -279.204752) (xy 251.624074 -279.240401)
			(xy 251.657682 -279.281064) (xy 251.685371 -279.325967) (xy 251.706616 -279.374254) (xy 251.721011 -279.425005)
			(xy 251.728282 -279.477255) (xy 251.728732 -279.503632) (xy 251.728252 -279.530883) (xy 251.720492 -279.58483)
			(xy 251.705134 -279.637123) (xy 251.682491 -279.686699) (xy 251.653023 -279.732548) (xy 251.617331 -279.773737)
			(xy 251.576141 -279.809428) (xy 251.530292 -279.838895) (xy 251.480716 -279.861537) (xy 251.428422 -279.876893)
			(xy 251.374475 -279.884653) (xy 251.347224 -279.88514) (xy 251.319967 -279.884648) (xy 251.266008 -279.876884)
			(xy 251.213701 -279.861525) (xy 251.164111 -279.838882) (xy 251.118246 -279.809417) (xy 251.077037 -279.773728)
			(xy 251.041323 -279.732541) (xy 251.026168 -279.70988) (xy 251.021348 -279.702888) (xy 251.008025 -279.692369)
			(xy 250.991984 -279.686818) (xy 250.983496 -279.686512) (xy 250.898152 -279.686512) (xy 250.889671 -279.686814)
			(xy 250.873655 -279.692411) (xy 250.860332 -279.702915) (xy 250.85548 -279.70988) (xy 250.840327 -279.732542)
			(xy 250.804614 -279.773729) (xy 250.763406 -279.809417) (xy 250.717539 -279.83888) (xy 250.667948 -279.861517)
			(xy 250.61564 -279.87687) (xy 250.561681 -279.884625) (xy 250.507167 -279.884625) (xy 250.453208 -279.87687)
			(xy 250.4009 -279.861517) (xy 250.351309 -279.83888) (xy 250.305442 -279.809417) (xy 250.264234 -279.773729)
			(xy 250.228521 -279.732542) (xy 250.213368 -279.70988) (xy 250.208548 -279.702888) (xy 250.195225 -279.692369)
			(xy 250.179184 -279.686818) (xy 250.170696 -279.686512) (xy 250.085352 -279.686512) (xy 250.076871 -279.686814)
			(xy 250.060855 -279.692411) (xy 250.047532 -279.702915) (xy 250.04268 -279.70988) (xy 250.027559 -279.732567)
			(xy 249.991847 -279.773763) (xy 249.950636 -279.809457) (xy 249.904764 -279.838923) (xy 249.855166 -279.861562)
			(xy 249.802851 -279.876911) (xy 249.748884 -279.884659) (xy 249.721624 -279.88514) (xy 249.694375 -279.8846)
			(xy 249.640431 -279.876847) (xy 249.588139 -279.861497) (xy 249.538564 -279.838861) (xy 249.492715 -279.8094)
			(xy 249.451526 -279.773714) (xy 249.415834 -279.73253) (xy 249.386366 -279.686685) (xy 249.363723 -279.637113)
			(xy 249.348365 -279.584824) (xy 249.340604 -279.530881) (xy 249.340116 -279.503632) (xy 224.184098 -279.503632)
			(xy 224.188522 -279.51369) (xy 224.202913 -279.564446) (xy 224.210179 -279.6167) (xy 224.210626 -279.643078)
			(xy 224.210124 -279.670329) (xy 224.202371 -279.724278) (xy 224.187018 -279.776574) (xy 224.16438 -279.826153)
			(xy 224.134916 -279.872005) (xy 224.099226 -279.913198) (xy 224.058037 -279.948892) (xy 224.012188 -279.978361)
			(xy 223.962612 -280.001004) (xy 223.910317 -280.016362) (xy 223.856369 -280.024121) (xy 223.829118 -280.024586)
			(xy 223.802737 -280.02419) (xy 223.750477 -280.016926) (xy 223.699715 -280.002534) (xy 223.65142 -279.981288)
			(xy 223.60651 -279.953594) (xy 223.565842 -279.919978) (xy 223.530192 -279.881082) (xy 223.500238 -279.837647)
			(xy 223.487996 -279.814274) (xy 223.481646 -279.801066) (xy 223.457262 -279.78608) (xy 223.337374 -279.78608)
			(xy 223.31299 -279.801066) (xy 223.30664 -279.814274) (xy 223.294417 -279.837654) (xy 223.264449 -279.881075)
			(xy 223.22879 -279.919958) (xy 223.188117 -279.953562) (xy 223.143206 -279.981247) (xy 223.094912 -280.002486)
			(xy 223.044153 -280.016875) (xy 222.991897 -280.02414) (xy 222.965518 -280.024586) (xy 222.938262 -280.024078)
			(xy 222.884304 -280.016314) (xy 222.831999 -280.000956) (xy 222.78241 -279.978316) (xy 222.736544 -279.948853)
			(xy 222.695335 -279.913168) (xy 222.659618 -279.871985) (xy 222.644462 -279.849326) (xy 222.63966 -279.84232)
			(xy 222.626327 -279.831808) (xy 222.61028 -279.826262) (xy 222.60179 -279.825958) (xy 222.516446 -279.825958)
			(xy 222.507967 -279.826279) (xy 222.491954 -279.831872) (xy 222.478629 -279.842366) (xy 222.473774 -279.849326)
			(xy 222.458607 -279.87198) (xy 222.422901 -279.913174) (xy 222.381697 -279.948869) (xy 222.335833 -279.978338)
			(xy 222.286243 -280.000982) (xy 222.233936 -280.01634) (xy 222.179976 -280.024099) (xy 222.152718 -280.024586)
			(xy 222.125465 -280.024128) (xy 222.071512 -280.016373) (xy 222.019213 -280.001018) (xy 221.969632 -279.978376)
			(xy 221.923777 -279.948908) (xy 221.882584 -279.913213) (xy 221.84689 -279.87202) (xy 221.817422 -279.826165)
			(xy 221.794781 -279.776583) (xy 221.779426 -279.724284) (xy 221.771672 -279.670331) (xy 221.77121 -279.643078)
			(xy 218.193874 -279.643078) (xy 218.193874 -282.533344) (xy 227.710492 -282.533344) (xy 227.710984 -282.504604)
			(xy 227.719615 -282.447775) (xy 227.736672 -282.392884) (xy 227.761771 -282.341173) (xy 227.794342 -282.293812)
			(xy 227.813616 -282.272486) (xy 227.82022 -282.265374) (xy 227.827332 -282.247848) (xy 227.827332 -282.15844)
			(xy 227.82022 -282.140914) (xy 227.813616 -282.133802) (xy 227.794315 -282.112501) (xy 227.761754 -282.065132)
			(xy 227.736667 -282.013413) (xy 227.719624 -281.958517) (xy 227.711009 -281.901685) (xy 227.710492 -281.872944)
			(xy 227.710978 -281.845693) (xy 227.718734 -281.791745) (xy 227.734089 -281.73945) (xy 227.756731 -281.689873)
			(xy 227.786197 -281.644023) (xy 227.821888 -281.602832) (xy 227.863079 -281.567141) (xy 227.908929 -281.537675)
			(xy 227.958506 -281.515033) (xy 228.010801 -281.499678) (xy 228.064749 -281.491922) (xy 228.119251 -281.491922)
			(xy 228.173199 -281.499678) (xy 228.225494 -281.515033) (xy 228.275071 -281.537675) (xy 228.320921 -281.567141)
			(xy 228.362112 -281.602832) (xy 228.397803 -281.644023) (xy 228.427269 -281.689873) (xy 228.449911 -281.73945)
			(xy 228.465266 -281.791745) (xy 228.473022 -281.845693) (xy 228.473508 -281.872944) (xy 228.473009 -281.901684)
			(xy 228.46438 -281.958512) (xy 228.447324 -282.013403) (xy 228.428338 -282.052522) (xy 234.619292 -282.052522)
			(xy 234.619831 -282.023784) (xy 234.62845 -281.966957) (xy 234.645497 -281.912067) (xy 234.670585 -281.860355)
			(xy 234.703147 -281.812991) (xy 234.722416 -281.791664) (xy 234.72902 -281.784552) (xy 234.736132 -281.767026)
			(xy 234.736132 -281.677618) (xy 234.72902 -281.660092) (xy 234.722416 -281.65298) (xy 234.703152 -281.631647)
			(xy 234.670586 -281.584286) (xy 234.645492 -281.532576) (xy 234.62844 -281.477687) (xy 234.619815 -281.420861)
			(xy 234.619292 -281.392122) (xy 234.619778 -281.364871) (xy 234.627534 -281.310923) (xy 234.642889 -281.258628)
			(xy 234.665531 -281.209051) (xy 234.694997 -281.163201) (xy 234.730688 -281.12201) (xy 234.771879 -281.086319)
			(xy 234.817729 -281.056853) (xy 234.867306 -281.034211) (xy 234.919601 -281.018856) (xy 234.973549 -281.0111)
			(xy 235.028051 -281.0111) (xy 235.081999 -281.018856) (xy 235.134294 -281.034211) (xy 235.183871 -281.056853)
			(xy 235.229721 -281.086319) (xy 235.270912 -281.12201) (xy 235.306603 -281.163201) (xy 235.336069 -281.209051)
			(xy 235.358711 -281.258628) (xy 235.374066 -281.310923) (xy 235.381822 -281.364871) (xy 235.382308 -281.392122)
			(xy 235.381796 -281.420861) (xy 235.37317 -281.477689) (xy 235.356117 -281.53258) (xy 235.331023 -281.584291)
			(xy 235.298456 -281.631653) (xy 235.279184 -281.65298) (xy 235.27258 -281.660092) (xy 235.265468 -281.677618)
			(xy 235.265468 -281.767026) (xy 235.27258 -281.784552) (xy 235.279184 -281.791664) (xy 235.298469 -281.812979)
			(xy 235.331032 -281.860345) (xy 235.356122 -281.912059) (xy 235.373169 -281.966953) (xy 235.381789 -282.023782)
			(xy 235.382308 -282.052522) (xy 235.381822 -282.079773) (xy 235.381577 -282.081478) (xy 238.632492 -282.081478)
			(xy 238.633004 -282.052739) (xy 238.64163 -281.995911) (xy 238.658683 -281.94102) (xy 238.683777 -281.889309)
			(xy 238.716344 -281.841947) (xy 238.735616 -281.82062) (xy 238.74222 -281.813508) (xy 238.749332 -281.795982)
			(xy 238.749332 -281.706574) (xy 238.74222 -281.689048) (xy 238.735616 -281.681936) (xy 238.716331 -281.660621)
			(xy 238.683768 -281.613255) (xy 238.658678 -281.561541) (xy 238.641631 -281.506647) (xy 238.633011 -281.449818)
			(xy 238.632492 -281.421078) (xy 238.632978 -281.393827) (xy 238.640734 -281.339879) (xy 238.656089 -281.287584)
			(xy 238.678731 -281.238007) (xy 238.708197 -281.192157) (xy 238.743888 -281.150966) (xy 238.785079 -281.115275)
			(xy 238.830929 -281.085809) (xy 238.880506 -281.063167) (xy 238.932801 -281.047812) (xy 238.986749 -281.040056)
			(xy 239.041251 -281.040056) (xy 239.095199 -281.047812) (xy 239.147494 -281.063167) (xy 239.197071 -281.085809)
			(xy 239.242921 -281.115275) (xy 239.284112 -281.150966) (xy 239.319803 -281.192157) (xy 239.349269 -281.238007)
			(xy 239.371911 -281.287584) (xy 239.387266 -281.339879) (xy 239.395022 -281.393827) (xy 239.395508 -281.421078)
			(xy 239.394969 -281.449816) (xy 239.38635 -281.506643) (xy 239.369303 -281.561533) (xy 239.344215 -281.613245)
			(xy 239.311653 -281.660609) (xy 239.292384 -281.681936) (xy 239.28578 -281.689048) (xy 239.278668 -281.706574)
			(xy 239.278668 -281.795982) (xy 239.28578 -281.813508) (xy 239.292384 -281.82062) (xy 239.311648 -281.841953)
			(xy 239.344214 -281.889314) (xy 239.369308 -281.941024) (xy 239.38636 -281.995913) (xy 239.394985 -282.052739)
			(xy 239.395508 -282.081478) (xy 239.395022 -282.108729) (xy 239.387266 -282.162677) (xy 239.371911 -282.214972)
			(xy 239.349269 -282.264549) (xy 239.319803 -282.310399) (xy 239.284112 -282.35159) (xy 239.242921 -282.387281)
			(xy 239.236577 -282.391358) (xy 245.723918 -282.391358) (xy 245.724438 -282.362619) (xy 245.733065 -282.305793)
			(xy 245.750117 -282.250903) (xy 245.775209 -282.199191) (xy 245.807772 -282.151828) (xy 245.827042 -282.1305)
			(xy 245.833646 -282.123388) (xy 245.840758 -282.105862) (xy 245.840758 -282.016454) (xy 245.833646 -281.998928)
			(xy 245.827042 -281.991816) (xy 245.807752 -281.970506) (xy 245.775188 -281.923139) (xy 245.750099 -281.871423)
			(xy 245.733053 -281.816529) (xy 245.724436 -281.759698) (xy 245.723918 -281.730958) (xy 245.724404 -281.703707)
			(xy 245.73216 -281.649759) (xy 245.747515 -281.597464) (xy 245.770157 -281.547887) (xy 245.799623 -281.502037)
			(xy 245.835314 -281.460846) (xy 245.876505 -281.425155) (xy 245.922355 -281.395689) (xy 245.971932 -281.373047)
			(xy 246.024227 -281.357692) (xy 246.078175 -281.349936) (xy 246.132677 -281.349936) (xy 246.186625 -281.357692)
			(xy 246.23892 -281.373047) (xy 246.288497 -281.395689) (xy 246.334347 -281.425155) (xy 246.375538 -281.460846)
			(xy 246.411229 -281.502037) (xy 246.440695 -281.547887) (xy 246.463337 -281.597464) (xy 246.478692 -281.649759)
			(xy 246.486448 -281.703707) (xy 246.486934 -281.730958) (xy 246.486436 -281.759698) (xy 246.477806 -281.816526)
			(xy 246.460749 -281.871417) (xy 246.435652 -281.923128) (xy 246.403083 -281.97049) (xy 246.38381 -281.991816)
			(xy 246.377206 -281.998928) (xy 246.370094 -282.016454) (xy 246.370094 -282.105862) (xy 246.377206 -282.123388)
			(xy 246.38381 -282.1305) (xy 246.403099 -282.151811) (xy 246.435665 -282.199177) (xy 246.460755 -282.250892)
			(xy 246.477801 -282.305787) (xy 246.486417 -282.362618) (xy 246.486934 -282.391358) (xy 246.486448 -282.418609)
			(xy 246.478692 -282.472557) (xy 246.463337 -282.524852) (xy 246.440695 -282.574429) (xy 246.411229 -282.620279)
			(xy 246.375538 -282.66147) (xy 246.334347 -282.697161) (xy 246.288497 -282.726627) (xy 246.23892 -282.749269)
			(xy 246.186625 -282.764624) (xy 246.132677 -282.77238) (xy 246.078175 -282.77238) (xy 246.024227 -282.764624)
			(xy 245.971932 -282.749269) (xy 245.922355 -282.726627) (xy 245.876505 -282.697161) (xy 245.835314 -282.66147)
			(xy 245.799623 -282.620279) (xy 245.770157 -282.574429) (xy 245.747515 -282.524852) (xy 245.73216 -282.472557)
			(xy 245.724404 -282.418609) (xy 245.723918 -282.391358) (xy 239.236577 -282.391358) (xy 239.197071 -282.416747)
			(xy 239.147494 -282.439389) (xy 239.095199 -282.454744) (xy 239.041251 -282.4625) (xy 238.986749 -282.4625)
			(xy 238.932801 -282.454744) (xy 238.880506 -282.439389) (xy 238.830929 -282.416747) (xy 238.785079 -282.387281)
			(xy 238.743888 -282.35159) (xy 238.708197 -282.310399) (xy 238.678731 -282.264549) (xy 238.656089 -282.214972)
			(xy 238.640734 -282.162677) (xy 238.632978 -282.108729) (xy 238.632492 -282.081478) (xy 235.381577 -282.081478)
			(xy 235.374066 -282.133721) (xy 235.358711 -282.186016) (xy 235.336069 -282.235593) (xy 235.306603 -282.281443)
			(xy 235.270912 -282.322634) (xy 235.229721 -282.358325) (xy 235.183871 -282.387791) (xy 235.134294 -282.410433)
			(xy 235.081999 -282.425788) (xy 235.028051 -282.433544) (xy 234.973549 -282.433544) (xy 234.919601 -282.425788)
			(xy 234.867306 -282.410433) (xy 234.817729 -282.387791) (xy 234.771879 -282.358325) (xy 234.730688 -282.322634)
			(xy 234.694997 -282.281443) (xy 234.665531 -282.235593) (xy 234.642889 -282.186016) (xy 234.627534 -282.133721)
			(xy 234.619778 -282.079773) (xy 234.619292 -282.052522) (xy 228.428338 -282.052522) (xy 228.422227 -282.065114)
			(xy 228.389657 -282.112476) (xy 228.370384 -282.133802) (xy 228.36378 -282.140914) (xy 228.356668 -282.15844)
			(xy 228.356668 -282.247848) (xy 228.36378 -282.265374) (xy 228.370384 -282.272486) (xy 228.389679 -282.293792)
			(xy 228.422241 -282.34116) (xy 228.447329 -282.392877) (xy 228.464374 -282.447772) (xy 228.47299 -282.504604)
			(xy 228.473508 -282.533344) (xy 228.473022 -282.560595) (xy 228.465266 -282.614543) (xy 228.449911 -282.666838)
			(xy 228.427269 -282.716415) (xy 228.397803 -282.762265) (xy 228.362112 -282.803456) (xy 228.320921 -282.839147)
			(xy 228.275071 -282.868613) (xy 228.225494 -282.891255) (xy 228.173199 -282.90661) (xy 228.119251 -282.914366)
			(xy 228.064749 -282.914366) (xy 228.010801 -282.90661) (xy 227.958506 -282.891255) (xy 227.908929 -282.868613)
			(xy 227.863079 -282.839147) (xy 227.821888 -282.803456) (xy 227.786197 -282.762265) (xy 227.756731 -282.716415)
			(xy 227.734089 -282.666838) (xy 227.718734 -282.614543) (xy 227.710978 -282.560595) (xy 227.710492 -282.533344)
			(xy 218.193874 -282.533344) (xy 218.193874 -284.262576) (xy 227.710492 -284.262576) (xy 227.711003 -284.233837)
			(xy 227.719629 -284.177009) (xy 227.736682 -284.122118) (xy 227.761777 -284.070407) (xy 227.794344 -284.023044)
			(xy 227.813616 -284.001718) (xy 227.82022 -283.994606) (xy 227.827332 -283.97708) (xy 227.827332 -283.887672)
			(xy 227.82022 -283.870146) (xy 227.813616 -283.863034) (xy 227.79433 -283.84172) (xy 227.761767 -283.794354)
			(xy 227.736678 -283.742639) (xy 227.71963 -283.687746) (xy 227.711011 -283.630916) (xy 227.710492 -283.602176)
			(xy 227.710978 -283.574925) (xy 227.718734 -283.520977) (xy 227.734089 -283.468682) (xy 227.756731 -283.419105)
			(xy 227.786197 -283.373255) (xy 227.821888 -283.332064) (xy 227.863079 -283.296373) (xy 227.908929 -283.266907)
			(xy 227.958506 -283.244265) (xy 228.010801 -283.22891) (xy 228.064749 -283.221154) (xy 228.119251 -283.221154)
			(xy 228.173199 -283.22891) (xy 228.225494 -283.244265) (xy 228.275071 -283.266907) (xy 228.320921 -283.296373)
			(xy 228.362112 -283.332064) (xy 228.397803 -283.373255) (xy 228.427269 -283.419105) (xy 228.449911 -283.468682)
			(xy 228.465266 -283.520977) (xy 228.473022 -283.574925) (xy 228.473508 -283.602176) (xy 228.472968 -283.630914)
			(xy 228.464349 -283.687741) (xy 228.447302 -283.742631) (xy 228.422215 -283.794343) (xy 228.397343 -283.830522)
			(xy 234.619292 -283.830522) (xy 234.619831 -283.801784) (xy 234.62845 -283.744957) (xy 234.645497 -283.690067)
			(xy 234.670585 -283.638355) (xy 234.703147 -283.590991) (xy 234.722416 -283.569664) (xy 234.72902 -283.562552)
			(xy 234.736132 -283.545026) (xy 234.736132 -283.455618) (xy 234.72902 -283.438092) (xy 234.722416 -283.43098)
			(xy 234.703152 -283.409647) (xy 234.670586 -283.362286) (xy 234.645492 -283.310576) (xy 234.62844 -283.255687)
			(xy 234.619815 -283.198861) (xy 234.619292 -283.170122) (xy 234.619778 -283.142871) (xy 234.627534 -283.088923)
			(xy 234.642889 -283.036628) (xy 234.665531 -282.987051) (xy 234.694997 -282.941201) (xy 234.730688 -282.90001)
			(xy 234.771879 -282.864319) (xy 234.817729 -282.834853) (xy 234.867306 -282.812211) (xy 234.919601 -282.796856)
			(xy 234.973549 -282.7891) (xy 235.028051 -282.7891) (xy 235.081999 -282.796856) (xy 235.134294 -282.812211)
			(xy 235.183871 -282.834853) (xy 235.229721 -282.864319) (xy 235.270912 -282.90001) (xy 235.306603 -282.941201)
			(xy 235.336069 -282.987051) (xy 235.358711 -283.036628) (xy 235.374066 -283.088923) (xy 235.381822 -283.142871)
			(xy 235.382308 -283.170122) (xy 235.381796 -283.198861) (xy 235.37317 -283.255689) (xy 235.356117 -283.31058)
			(xy 235.331023 -283.362291) (xy 235.298456 -283.409653) (xy 235.279184 -283.43098) (xy 235.27258 -283.438092)
			(xy 235.265468 -283.455618) (xy 235.265468 -283.545026) (xy 235.27258 -283.562552) (xy 235.279184 -283.569664)
			(xy 235.298469 -283.590979) (xy 235.331032 -283.638345) (xy 235.356122 -283.690059) (xy 235.373169 -283.744953)
			(xy 235.381789 -283.801782) (xy 235.382308 -283.830522) (xy 235.381822 -283.857773) (xy 235.381577 -283.859478)
			(xy 238.632492 -283.859478) (xy 238.633004 -283.830739) (xy 238.64163 -283.773911) (xy 238.658683 -283.71902)
			(xy 238.683777 -283.667309) (xy 238.716344 -283.619947) (xy 238.735616 -283.59862) (xy 238.74222 -283.591508)
			(xy 238.749332 -283.573982) (xy 238.749332 -283.484574) (xy 238.74222 -283.467048) (xy 238.735616 -283.459936)
			(xy 238.716331 -283.438621) (xy 238.683768 -283.391255) (xy 238.658678 -283.339541) (xy 238.641631 -283.284647)
			(xy 238.633011 -283.227818) (xy 238.632492 -283.199078) (xy 238.632978 -283.171827) (xy 238.640734 -283.117879)
			(xy 238.656089 -283.065584) (xy 238.678731 -283.016007) (xy 238.708197 -282.970157) (xy 238.743888 -282.928966)
			(xy 238.785079 -282.893275) (xy 238.830929 -282.863809) (xy 238.880506 -282.841167) (xy 238.932801 -282.825812)
			(xy 238.986749 -282.818056) (xy 239.041251 -282.818056) (xy 239.095199 -282.825812) (xy 239.147494 -282.841167)
			(xy 239.197071 -282.863809) (xy 239.242921 -282.893275) (xy 239.284112 -282.928966) (xy 239.319803 -282.970157)
			(xy 239.349269 -283.016007) (xy 239.371911 -283.065584) (xy 239.387266 -283.117879) (xy 239.395022 -283.171827)
			(xy 239.395508 -283.199078) (xy 239.394969 -283.227816) (xy 239.38635 -283.284643) (xy 239.369303 -283.339533)
			(xy 239.344215 -283.391245) (xy 239.311653 -283.438609) (xy 239.292384 -283.459936) (xy 239.28578 -283.467048)
			(xy 239.278668 -283.484574) (xy 239.278668 -283.573982) (xy 239.28578 -283.591508) (xy 239.292384 -283.59862)
			(xy 239.311648 -283.619953) (xy 239.344214 -283.667314) (xy 239.369308 -283.719024) (xy 239.38636 -283.773913)
			(xy 239.394985 -283.830739) (xy 239.395508 -283.859478) (xy 239.395022 -283.886729) (xy 239.387266 -283.940677)
			(xy 239.371911 -283.992972) (xy 239.349269 -284.042549) (xy 239.319803 -284.088399) (xy 239.284112 -284.12959)
			(xy 239.242921 -284.165281) (xy 239.236577 -284.169358) (xy 245.723918 -284.169358) (xy 245.724438 -284.140619)
			(xy 245.733065 -284.083793) (xy 245.750117 -284.028903) (xy 245.775209 -283.977191) (xy 245.807772 -283.929828)
			(xy 245.827042 -283.9085) (xy 245.833646 -283.901388) (xy 245.840758 -283.883862) (xy 245.840758 -283.794454)
			(xy 245.833646 -283.776928) (xy 245.827042 -283.769816) (xy 245.807752 -283.748506) (xy 245.775188 -283.701139)
			(xy 245.750099 -283.649423) (xy 245.733053 -283.594529) (xy 245.724436 -283.537698) (xy 245.723918 -283.508958)
			(xy 245.724404 -283.481707) (xy 245.73216 -283.427759) (xy 245.747515 -283.375464) (xy 245.770157 -283.325887)
			(xy 245.799623 -283.280037) (xy 245.835314 -283.238846) (xy 245.876505 -283.203155) (xy 245.922355 -283.173689)
			(xy 245.971932 -283.151047) (xy 246.024227 -283.135692) (xy 246.078175 -283.127936) (xy 246.132677 -283.127936)
			(xy 246.186625 -283.135692) (xy 246.23892 -283.151047) (xy 246.288497 -283.173689) (xy 246.334347 -283.203155)
			(xy 246.375538 -283.238846) (xy 246.411229 -283.280037) (xy 246.440695 -283.325887) (xy 246.463337 -283.375464)
			(xy 246.478692 -283.427759) (xy 246.486448 -283.481707) (xy 246.486934 -283.508958) (xy 246.486436 -283.537698)
			(xy 246.477806 -283.594526) (xy 246.460749 -283.649417) (xy 246.435652 -283.701128) (xy 246.403083 -283.74849)
			(xy 246.38381 -283.769816) (xy 246.377206 -283.776928) (xy 246.370094 -283.794454) (xy 246.370094 -283.883862)
			(xy 246.377206 -283.901388) (xy 246.38381 -283.9085) (xy 246.403099 -283.929811) (xy 246.435665 -283.977177)
			(xy 246.460755 -284.028892) (xy 246.477801 -284.083787) (xy 246.486417 -284.140618) (xy 246.486934 -284.169358)
			(xy 246.486448 -284.196609) (xy 246.478692 -284.250557) (xy 246.463337 -284.302852) (xy 246.440695 -284.352429)
			(xy 246.411229 -284.398279) (xy 246.375538 -284.43947) (xy 246.334347 -284.475161) (xy 246.288497 -284.504627)
			(xy 246.23892 -284.527269) (xy 246.186625 -284.542624) (xy 246.132677 -284.55038) (xy 246.078175 -284.55038)
			(xy 246.024227 -284.542624) (xy 245.971932 -284.527269) (xy 245.922355 -284.504627) (xy 245.876505 -284.475161)
			(xy 245.835314 -284.43947) (xy 245.799623 -284.398279) (xy 245.770157 -284.352429) (xy 245.747515 -284.302852)
			(xy 245.73216 -284.250557) (xy 245.724404 -284.196609) (xy 245.723918 -284.169358) (xy 239.236577 -284.169358)
			(xy 239.197071 -284.194747) (xy 239.147494 -284.217389) (xy 239.095199 -284.232744) (xy 239.041251 -284.2405)
			(xy 238.986749 -284.2405) (xy 238.932801 -284.232744) (xy 238.880506 -284.217389) (xy 238.830929 -284.194747)
			(xy 238.785079 -284.165281) (xy 238.743888 -284.12959) (xy 238.708197 -284.088399) (xy 238.678731 -284.042549)
			(xy 238.656089 -283.992972) (xy 238.640734 -283.940677) (xy 238.632978 -283.886729) (xy 238.632492 -283.859478)
			(xy 235.381577 -283.859478) (xy 235.374066 -283.911721) (xy 235.358711 -283.964016) (xy 235.336069 -284.013593)
			(xy 235.306603 -284.059443) (xy 235.270912 -284.100634) (xy 235.229721 -284.136325) (xy 235.183871 -284.165791)
			(xy 235.134294 -284.188433) (xy 235.081999 -284.203788) (xy 235.028051 -284.211544) (xy 234.973549 -284.211544)
			(xy 234.919601 -284.203788) (xy 234.867306 -284.188433) (xy 234.817729 -284.165791) (xy 234.771879 -284.136325)
			(xy 234.730688 -284.100634) (xy 234.694997 -284.059443) (xy 234.665531 -284.013593) (xy 234.642889 -283.964016)
			(xy 234.627534 -283.911721) (xy 234.619778 -283.857773) (xy 234.619292 -283.830522) (xy 228.397343 -283.830522)
			(xy 228.389653 -283.841707) (xy 228.370384 -283.863034) (xy 228.36378 -283.870146) (xy 228.356668 -283.887672)
			(xy 228.356668 -283.97708) (xy 228.36378 -283.994606) (xy 228.370384 -284.001718) (xy 228.389647 -284.023052)
			(xy 228.422214 -284.070412) (xy 228.447307 -284.122122) (xy 228.46436 -284.177011) (xy 228.472985 -284.233838)
			(xy 228.473508 -284.262576) (xy 228.473022 -284.289827) (xy 228.465266 -284.343775) (xy 228.449911 -284.39607)
			(xy 228.427269 -284.445647) (xy 228.397803 -284.491497) (xy 228.362112 -284.532688) (xy 228.320921 -284.568379)
			(xy 228.275071 -284.597845) (xy 228.225494 -284.620487) (xy 228.173199 -284.635842) (xy 228.119251 -284.643598)
			(xy 228.064749 -284.643598) (xy 228.010801 -284.635842) (xy 227.958506 -284.620487) (xy 227.908929 -284.597845)
			(xy 227.863079 -284.568379) (xy 227.821888 -284.532688) (xy 227.786197 -284.491497) (xy 227.756731 -284.445647)
			(xy 227.734089 -284.39607) (xy 227.718734 -284.343775) (xy 227.710978 -284.289827) (xy 227.710492 -284.262576)
			(xy 218.193874 -284.262576) (xy 218.193874 -285.991808) (xy 227.710492 -285.991808) (xy 227.711023 -285.963069)
			(xy 227.719644 -285.906242) (xy 227.736692 -285.851352) (xy 227.761782 -285.79964) (xy 227.794346 -285.752277)
			(xy 227.813616 -285.73095) (xy 227.82022 -285.723838) (xy 227.827332 -285.706312) (xy 227.827332 -285.616904)
			(xy 227.82022 -285.599378) (xy 227.813616 -285.592266) (xy 227.794345 -285.570939) (xy 227.76178 -285.523577)
			(xy 227.736688 -285.471865) (xy 227.719637 -285.416974) (xy 227.711013 -285.360147) (xy 227.710492 -285.331408)
			(xy 227.710978 -285.304157) (xy 227.718734 -285.250209) (xy 227.734089 -285.197914) (xy 227.756731 -285.148337)
			(xy 227.786197 -285.102487) (xy 227.821888 -285.061296) (xy 227.863079 -285.025605) (xy 227.908929 -284.996139)
			(xy 227.958506 -284.973497) (xy 228.010801 -284.958142) (xy 228.064749 -284.950386) (xy 228.119251 -284.950386)
			(xy 228.173199 -284.958142) (xy 228.225494 -284.973497) (xy 228.275071 -284.996139) (xy 228.320921 -285.025605)
			(xy 228.362112 -285.061296) (xy 228.397803 -285.102487) (xy 228.427269 -285.148337) (xy 228.449911 -285.197914)
			(xy 228.465266 -285.250209) (xy 228.473022 -285.304157) (xy 228.473508 -285.331408) (xy 228.472987 -285.360147)
			(xy 228.464363 -285.416974) (xy 228.447313 -285.471865) (xy 228.42222 -285.523577) (xy 228.389655 -285.570939)
			(xy 228.370384 -285.592266) (xy 228.36378 -285.599378) (xy 228.360069 -285.608522) (xy 234.619292 -285.608522)
			(xy 234.619831 -285.579784) (xy 234.62845 -285.522957) (xy 234.645497 -285.468067) (xy 234.670585 -285.416355)
			(xy 234.703147 -285.368991) (xy 234.722416 -285.347664) (xy 234.72902 -285.340552) (xy 234.736132 -285.323026)
			(xy 234.736132 -285.233618) (xy 234.72902 -285.216092) (xy 234.722416 -285.20898) (xy 234.703152 -285.187647)
			(xy 234.670586 -285.140286) (xy 234.645492 -285.088576) (xy 234.62844 -285.033687) (xy 234.619815 -284.976861)
			(xy 234.619292 -284.948122) (xy 234.619778 -284.920871) (xy 234.627534 -284.866923) (xy 234.642889 -284.814628)
			(xy 234.665531 -284.765051) (xy 234.694997 -284.719201) (xy 234.730688 -284.67801) (xy 234.771879 -284.642319)
			(xy 234.817729 -284.612853) (xy 234.867306 -284.590211) (xy 234.919601 -284.574856) (xy 234.973549 -284.5671)
			(xy 235.028051 -284.5671) (xy 235.081999 -284.574856) (xy 235.134294 -284.590211) (xy 235.183871 -284.612853)
			(xy 235.229721 -284.642319) (xy 235.270912 -284.67801) (xy 235.306603 -284.719201) (xy 235.336069 -284.765051)
			(xy 235.358711 -284.814628) (xy 235.374066 -284.866923) (xy 235.381822 -284.920871) (xy 235.382308 -284.948122)
			(xy 235.381796 -284.976861) (xy 235.37317 -285.033689) (xy 235.356117 -285.08858) (xy 235.331023 -285.140291)
			(xy 235.298456 -285.187653) (xy 235.279184 -285.20898) (xy 235.27258 -285.216092) (xy 235.265468 -285.233618)
			(xy 235.265468 -285.323026) (xy 235.27258 -285.340552) (xy 235.279184 -285.347664) (xy 235.298469 -285.368979)
			(xy 235.331032 -285.416345) (xy 235.356122 -285.468059) (xy 235.373169 -285.522953) (xy 235.381789 -285.579782)
			(xy 235.382308 -285.608522) (xy 235.381822 -285.635773) (xy 235.381577 -285.637478) (xy 238.632492 -285.637478)
			(xy 238.633004 -285.608739) (xy 238.64163 -285.551911) (xy 238.658683 -285.49702) (xy 238.683777 -285.445309)
			(xy 238.716344 -285.397947) (xy 238.735616 -285.37662) (xy 238.74222 -285.369508) (xy 238.749332 -285.351982)
			(xy 238.749332 -285.262574) (xy 238.74222 -285.245048) (xy 238.735616 -285.237936) (xy 238.716331 -285.216621)
			(xy 238.683768 -285.169255) (xy 238.658678 -285.117541) (xy 238.641631 -285.062647) (xy 238.633011 -285.005818)
			(xy 238.632492 -284.977078) (xy 238.632978 -284.949827) (xy 238.640734 -284.895879) (xy 238.656089 -284.843584)
			(xy 238.678731 -284.794007) (xy 238.708197 -284.748157) (xy 238.743888 -284.706966) (xy 238.785079 -284.671275)
			(xy 238.830929 -284.641809) (xy 238.880506 -284.619167) (xy 238.932801 -284.603812) (xy 238.986749 -284.596056)
			(xy 239.041251 -284.596056) (xy 239.095199 -284.603812) (xy 239.147494 -284.619167) (xy 239.197071 -284.641809)
			(xy 239.242921 -284.671275) (xy 239.284112 -284.706966) (xy 239.319803 -284.748157) (xy 239.349269 -284.794007)
			(xy 239.371911 -284.843584) (xy 239.387266 -284.895879) (xy 239.395022 -284.949827) (xy 239.395508 -284.977078)
			(xy 239.394969 -285.005816) (xy 239.38635 -285.062643) (xy 239.369303 -285.117533) (xy 239.344215 -285.169245)
			(xy 239.311653 -285.216609) (xy 239.292384 -285.237936) (xy 239.28578 -285.245048) (xy 239.278668 -285.262574)
			(xy 239.278668 -285.351982) (xy 239.28578 -285.369508) (xy 239.292384 -285.37662) (xy 239.311648 -285.397953)
			(xy 239.344214 -285.445314) (xy 239.369308 -285.497024) (xy 239.38636 -285.551913) (xy 239.394985 -285.608739)
			(xy 239.395508 -285.637478) (xy 239.395022 -285.664729) (xy 239.387266 -285.718677) (xy 239.371911 -285.770972)
			(xy 239.349269 -285.820549) (xy 239.319803 -285.866399) (xy 239.284112 -285.90759) (xy 239.242921 -285.943281)
			(xy 239.236577 -285.947358) (xy 245.723918 -285.947358) (xy 245.724438 -285.918619) (xy 245.733065 -285.861793)
			(xy 245.750117 -285.806903) (xy 245.775209 -285.755191) (xy 245.807772 -285.707828) (xy 245.827042 -285.6865)
			(xy 245.833646 -285.679388) (xy 245.840758 -285.661862) (xy 245.840758 -285.572454) (xy 245.833646 -285.554928)
			(xy 245.827042 -285.547816) (xy 245.807752 -285.526506) (xy 245.775188 -285.479139) (xy 245.750099 -285.427423)
			(xy 245.733053 -285.372529) (xy 245.724436 -285.315698) (xy 245.723918 -285.286958) (xy 245.724404 -285.259707)
			(xy 245.73216 -285.205759) (xy 245.747515 -285.153464) (xy 245.770157 -285.103887) (xy 245.799623 -285.058037)
			(xy 245.835314 -285.016846) (xy 245.876505 -284.981155) (xy 245.922355 -284.951689) (xy 245.971932 -284.929047)
			(xy 246.024227 -284.913692) (xy 246.078175 -284.905936) (xy 246.132677 -284.905936) (xy 246.186625 -284.913692)
			(xy 246.23892 -284.929047) (xy 246.288497 -284.951689) (xy 246.334347 -284.981155) (xy 246.375538 -285.016846)
			(xy 246.411229 -285.058037) (xy 246.440695 -285.103887) (xy 246.463337 -285.153464) (xy 246.478692 -285.205759)
			(xy 246.486448 -285.259707) (xy 246.486934 -285.286958) (xy 246.486436 -285.315698) (xy 246.477806 -285.372526)
			(xy 246.460749 -285.427417) (xy 246.435652 -285.479128) (xy 246.403083 -285.52649) (xy 246.38381 -285.547816)
			(xy 246.377206 -285.554928) (xy 246.370094 -285.572454) (xy 246.370094 -285.661862) (xy 246.377206 -285.679388)
			(xy 246.38381 -285.6865) (xy 246.403099 -285.707811) (xy 246.435665 -285.755177) (xy 246.460755 -285.806892)
			(xy 246.477801 -285.861787) (xy 246.486417 -285.918618) (xy 246.486934 -285.947358) (xy 246.486448 -285.974609)
			(xy 246.478692 -286.028557) (xy 246.463337 -286.080852) (xy 246.440695 -286.130429) (xy 246.411229 -286.176279)
			(xy 246.375538 -286.21747) (xy 246.334347 -286.253161) (xy 246.288497 -286.282627) (xy 246.23892 -286.305269)
			(xy 246.186625 -286.320624) (xy 246.132677 -286.32838) (xy 246.078175 -286.32838) (xy 246.024227 -286.320624)
			(xy 245.971932 -286.305269) (xy 245.922355 -286.282627) (xy 245.876505 -286.253161) (xy 245.835314 -286.21747)
			(xy 245.799623 -286.176279) (xy 245.770157 -286.130429) (xy 245.747515 -286.080852) (xy 245.73216 -286.028557)
			(xy 245.724404 -285.974609) (xy 245.723918 -285.947358) (xy 239.236577 -285.947358) (xy 239.197071 -285.972747)
			(xy 239.147494 -285.995389) (xy 239.095199 -286.010744) (xy 239.041251 -286.0185) (xy 238.986749 -286.0185)
			(xy 238.932801 -286.010744) (xy 238.880506 -285.995389) (xy 238.830929 -285.972747) (xy 238.785079 -285.943281)
			(xy 238.743888 -285.90759) (xy 238.708197 -285.866399) (xy 238.678731 -285.820549) (xy 238.656089 -285.770972)
			(xy 238.640734 -285.718677) (xy 238.632978 -285.664729) (xy 238.632492 -285.637478) (xy 235.381577 -285.637478)
			(xy 235.374066 -285.689721) (xy 235.358711 -285.742016) (xy 235.336069 -285.791593) (xy 235.306603 -285.837443)
			(xy 235.270912 -285.878634) (xy 235.229721 -285.914325) (xy 235.183871 -285.943791) (xy 235.134294 -285.966433)
			(xy 235.081999 -285.981788) (xy 235.028051 -285.989544) (xy 234.973549 -285.989544) (xy 234.919601 -285.981788)
			(xy 234.867306 -285.966433) (xy 234.817729 -285.943791) (xy 234.771879 -285.914325) (xy 234.730688 -285.878634)
			(xy 234.694997 -285.837443) (xy 234.665531 -285.791593) (xy 234.642889 -285.742016) (xy 234.627534 -285.689721)
			(xy 234.619778 -285.635773) (xy 234.619292 -285.608522) (xy 228.360069 -285.608522) (xy 228.356668 -285.616904)
			(xy 228.356668 -285.706312) (xy 228.36378 -285.723838) (xy 228.370384 -285.73095) (xy 228.389662 -285.752271)
			(xy 228.422227 -285.799635) (xy 228.447317 -285.851348) (xy 228.464366 -285.90624) (xy 228.472988 -285.963069)
			(xy 228.473508 -285.991808) (xy 228.473022 -286.019059) (xy 228.465266 -286.073007) (xy 228.449911 -286.125302)
			(xy 228.427269 -286.174879) (xy 228.397803 -286.220729) (xy 228.362112 -286.26192) (xy 228.320921 -286.297611)
			(xy 228.275071 -286.327077) (xy 228.225494 -286.349719) (xy 228.173199 -286.365074) (xy 228.119251 -286.37283)
			(xy 228.064749 -286.37283) (xy 228.010801 -286.365074) (xy 227.958506 -286.349719) (xy 227.908929 -286.327077)
			(xy 227.863079 -286.297611) (xy 227.821888 -286.26192) (xy 227.786197 -286.220729) (xy 227.756731 -286.174879)
			(xy 227.734089 -286.125302) (xy 227.718734 -286.073007) (xy 227.710978 -286.019059) (xy 227.710492 -285.991808)
			(xy 218.193874 -285.991808) (xy 218.193874 -290.975674) (xy 219.004376 -290.975674) (xy 219.004376 -290.824026)
			(xy 219.012313 -290.672585) (xy 219.028164 -290.521767) (xy 219.051887 -290.371986) (xy 219.083417 -290.223651)
			(xy 219.122666 -290.07717) (xy 219.169528 -289.932944) (xy 219.223874 -289.791367) (xy 219.285555 -289.65283)
			(xy 219.354402 -289.51771) (xy 219.430227 -289.386378) (xy 219.51282 -289.259195) (xy 219.601957 -289.136509)
			(xy 219.697393 -289.018656) (xy 219.798865 -288.905959) (xy 219.906097 -288.798727) (xy 220.018794 -288.697255)
			(xy 220.136647 -288.601819) (xy 220.259333 -288.512682) (xy 220.386516 -288.430089) (xy 220.517848 -288.354264)
			(xy 220.652968 -288.285417) (xy 220.791505 -288.223736) (xy 220.933082 -288.16939) (xy 221.077308 -288.122528)
			(xy 221.223789 -288.083279) (xy 221.372124 -288.051749) (xy 221.521905 -288.028026) (xy 221.672723 -288.012175)
			(xy 221.824164 -288.004238) (xy 221.975812 -288.004238) (xy 222.127253 -288.012175) (xy 222.278071 -288.028026)
			(xy 222.427852 -288.051749) (xy 222.576187 -288.083279) (xy 222.722668 -288.122528) (xy 222.866894 -288.16939)
			(xy 222.913658 -288.187341) (xy 225.367336 -288.187341) (xy 225.367336 -288.123419) (xy 225.375347 -288.060001)
			(xy 225.391244 -287.998087) (xy 225.414776 -287.938654) (xy 225.44557 -287.882639) (xy 225.483143 -287.830924)
			(xy 225.5269 -287.784327) (xy 225.576153 -287.743582) (xy 225.630124 -287.709331) (xy 225.687963 -287.682114)
			(xy 225.748756 -287.662361) (xy 225.811546 -287.650383) (xy 225.875342 -287.64637) (xy 225.939138 -287.650383)
			(xy 226.001928 -287.662361) (xy 226.062721 -287.682114) (xy 226.12056 -287.709331) (xy 226.13901 -287.72104)
			(xy 227.710492 -287.72104) (xy 227.710981 -287.6923) (xy 227.719613 -287.635471) (xy 227.736671 -287.58058)
			(xy 227.76177 -287.528869) (xy 227.794342 -287.481508) (xy 227.813616 -287.460182) (xy 227.82022 -287.45307)
			(xy 227.827332 -287.435544) (xy 227.827332 -287.346136) (xy 227.82022 -287.32861) (xy 227.813616 -287.321498)
			(xy 227.794361 -287.300158) (xy 227.761793 -287.252799) (xy 227.736698 -287.201091) (xy 227.719644 -287.146203)
			(xy 227.711016 -287.089378) (xy 227.710492 -287.06064) (xy 227.710978 -287.033389) (xy 227.718734 -286.979441)
			(xy 227.734089 -286.927146) (xy 227.756731 -286.877569) (xy 227.786197 -286.831719) (xy 227.821888 -286.790528)
			(xy 227.863079 -286.754837) (xy 227.908929 -286.725371) (xy 227.958506 -286.702729) (xy 228.010801 -286.687374)
			(xy 228.064749 -286.679618) (xy 228.119251 -286.679618) (xy 228.173199 -286.687374) (xy 228.225494 -286.702729)
			(xy 228.275071 -286.725371) (xy 228.320921 -286.754837) (xy 228.362112 -286.790528) (xy 228.397803 -286.831719)
			(xy 228.427269 -286.877569) (xy 228.449911 -286.927146) (xy 228.465266 -286.979441) (xy 228.473022 -287.033389)
			(xy 228.473508 -287.06064) (xy 228.473006 -287.08938) (xy 228.464378 -287.146208) (xy 228.447323 -287.201099)
			(xy 228.422226 -287.25281) (xy 228.389657 -287.300172) (xy 228.370384 -287.321498) (xy 228.36378 -287.32861)
			(xy 228.356668 -287.346136) (xy 228.356668 -287.386522) (xy 234.619292 -287.386522) (xy 234.619831 -287.357784)
			(xy 234.62845 -287.300957) (xy 234.645497 -287.246067) (xy 234.670585 -287.194355) (xy 234.703147 -287.146991)
			(xy 234.722416 -287.125664) (xy 234.72902 -287.118552) (xy 234.736132 -287.101026) (xy 234.736132 -287.011618)
			(xy 234.72902 -286.994092) (xy 234.722416 -286.98698) (xy 234.703152 -286.965647) (xy 234.670586 -286.918286)
			(xy 234.645492 -286.866576) (xy 234.62844 -286.811687) (xy 234.619815 -286.754861) (xy 234.619292 -286.726122)
			(xy 234.619778 -286.698871) (xy 234.627534 -286.644923) (xy 234.642889 -286.592628) (xy 234.665531 -286.543051)
			(xy 234.694997 -286.497201) (xy 234.730688 -286.45601) (xy 234.771879 -286.420319) (xy 234.817729 -286.390853)
			(xy 234.867306 -286.368211) (xy 234.919601 -286.352856) (xy 234.973549 -286.3451) (xy 235.028051 -286.3451)
			(xy 235.081999 -286.352856) (xy 235.134294 -286.368211) (xy 235.183871 -286.390853) (xy 235.229721 -286.420319)
			(xy 235.270912 -286.45601) (xy 235.306603 -286.497201) (xy 235.336069 -286.543051) (xy 235.358711 -286.592628)
			(xy 235.374066 -286.644923) (xy 235.381822 -286.698871) (xy 235.382308 -286.726122) (xy 235.381796 -286.754861)
			(xy 235.37317 -286.811689) (xy 235.356117 -286.86658) (xy 235.331023 -286.918291) (xy 235.298456 -286.965653)
			(xy 235.279184 -286.98698) (xy 235.27258 -286.994092) (xy 235.265468 -287.011618) (xy 235.265468 -287.101026)
			(xy 235.27258 -287.118552) (xy 235.279184 -287.125664) (xy 235.298469 -287.146979) (xy 235.331032 -287.194345)
			(xy 235.356122 -287.246059) (xy 235.373169 -287.300953) (xy 235.381789 -287.357782) (xy 235.382308 -287.386522)
			(xy 235.381822 -287.413773) (xy 235.381577 -287.415478) (xy 238.632492 -287.415478) (xy 238.633004 -287.386739)
			(xy 238.64163 -287.329911) (xy 238.658683 -287.27502) (xy 238.683777 -287.223309) (xy 238.716344 -287.175947)
			(xy 238.735616 -287.15462) (xy 238.74222 -287.147508) (xy 238.749332 -287.129982) (xy 238.749332 -287.040574)
			(xy 238.74222 -287.023048) (xy 238.735616 -287.015936) (xy 238.716331 -286.994621) (xy 238.683768 -286.947255)
			(xy 238.658678 -286.895541) (xy 238.641631 -286.840647) (xy 238.633011 -286.783818) (xy 238.632492 -286.755078)
			(xy 238.632978 -286.727827) (xy 238.640734 -286.673879) (xy 238.656089 -286.621584) (xy 238.678731 -286.572007)
			(xy 238.708197 -286.526157) (xy 238.743888 -286.484966) (xy 238.785079 -286.449275) (xy 238.830929 -286.419809)
			(xy 238.880506 -286.397167) (xy 238.932801 -286.381812) (xy 238.986749 -286.374056) (xy 239.041251 -286.374056)
			(xy 239.095199 -286.381812) (xy 239.147494 -286.397167) (xy 239.197071 -286.419809) (xy 239.242921 -286.449275)
			(xy 239.284112 -286.484966) (xy 239.319803 -286.526157) (xy 239.349269 -286.572007) (xy 239.371911 -286.621584)
			(xy 239.387266 -286.673879) (xy 239.395022 -286.727827) (xy 239.395508 -286.755078) (xy 239.394969 -286.783816)
			(xy 239.38635 -286.840643) (xy 239.369303 -286.895533) (xy 239.344215 -286.947245) (xy 239.311653 -286.994609)
			(xy 239.292384 -287.015936) (xy 239.28578 -287.023048) (xy 239.278668 -287.040574) (xy 239.278668 -287.129982)
			(xy 239.28578 -287.147508) (xy 239.292384 -287.15462) (xy 239.311648 -287.175953) (xy 239.344214 -287.223314)
			(xy 239.369308 -287.275024) (xy 239.38636 -287.329913) (xy 239.394985 -287.386739) (xy 239.395508 -287.415478)
			(xy 239.395022 -287.442729) (xy 239.387266 -287.496677) (xy 239.371911 -287.548972) (xy 239.349269 -287.598549)
			(xy 239.319803 -287.644399) (xy 239.284112 -287.68559) (xy 239.242921 -287.721281) (xy 239.197071 -287.750747)
			(xy 239.147494 -287.773389) (xy 239.095199 -287.788744) (xy 239.041251 -287.7965) (xy 238.986749 -287.7965)
			(xy 238.932801 -287.788744) (xy 238.880506 -287.773389) (xy 238.830929 -287.750747) (xy 238.785079 -287.721281)
			(xy 238.743888 -287.68559) (xy 238.708197 -287.644399) (xy 238.678731 -287.598549) (xy 238.656089 -287.548972)
			(xy 238.640734 -287.496677) (xy 238.632978 -287.442729) (xy 238.632492 -287.415478) (xy 235.381577 -287.415478)
			(xy 235.374066 -287.467721) (xy 235.358711 -287.520016) (xy 235.336069 -287.569593) (xy 235.306603 -287.615443)
			(xy 235.270912 -287.656634) (xy 235.229721 -287.692325) (xy 235.183871 -287.721791) (xy 235.134294 -287.744433)
			(xy 235.081999 -287.759788) (xy 235.028051 -287.767544) (xy 234.973549 -287.767544) (xy 234.919601 -287.759788)
			(xy 234.867306 -287.744433) (xy 234.817729 -287.721791) (xy 234.771879 -287.692325) (xy 234.730688 -287.656634)
			(xy 234.694997 -287.615443) (xy 234.665531 -287.569593) (xy 234.642889 -287.520016) (xy 234.627534 -287.467721)
			(xy 234.619778 -287.413773) (xy 234.619292 -287.386522) (xy 228.356668 -287.386522) (xy 228.356668 -287.435544)
			(xy 228.36378 -287.45307) (xy 228.370384 -287.460182) (xy 228.389677 -287.481489) (xy 228.42224 -287.528857)
			(xy 228.447327 -287.580574) (xy 228.464373 -287.635469) (xy 228.47299 -287.6923) (xy 228.473508 -287.72104)
			(xy 228.473022 -287.748291) (xy 228.465266 -287.802239) (xy 228.449911 -287.854534) (xy 228.427269 -287.904111)
			(xy 228.397803 -287.949961) (xy 228.362112 -287.991152) (xy 228.320921 -288.026843) (xy 228.275071 -288.056309)
			(xy 228.225494 -288.078951) (xy 228.173199 -288.094306) (xy 228.119251 -288.102062) (xy 228.064749 -288.102062)
			(xy 228.010801 -288.094306) (xy 227.958506 -288.078951) (xy 227.908929 -288.056309) (xy 227.863079 -288.026843)
			(xy 227.821888 -287.991152) (xy 227.786197 -287.949961) (xy 227.756731 -287.904111) (xy 227.734089 -287.854534)
			(xy 227.718734 -287.802239) (xy 227.710978 -287.748291) (xy 227.710492 -287.72104) (xy 226.13901 -287.72104)
			(xy 226.174531 -287.743582) (xy 226.223784 -287.784327) (xy 226.267541 -287.830924) (xy 226.305114 -287.882639)
			(xy 226.335908 -287.938654) (xy 226.35944 -287.998087) (xy 226.375337 -288.060001) (xy 226.383348 -288.123419)
			(xy 226.38385 -288.15538) (xy 226.383348 -288.187341) (xy 226.375337 -288.250759) (xy 226.35944 -288.312673)
			(xy 226.335908 -288.372106) (xy 226.305114 -288.428121) (xy 226.267541 -288.479836) (xy 226.223784 -288.526433)
			(xy 226.174531 -288.567178) (xy 226.12056 -288.601429) (xy 226.062721 -288.628646) (xy 226.001928 -288.648399)
			(xy 225.939138 -288.660377) (xy 225.875342 -288.664391) (xy 225.811546 -288.660377) (xy 225.748756 -288.648399)
			(xy 225.687963 -288.628646) (xy 225.630124 -288.601429) (xy 225.576153 -288.567178) (xy 225.5269 -288.526433)
			(xy 225.483143 -288.479836) (xy 225.44557 -288.428121) (xy 225.414776 -288.372106) (xy 225.391244 -288.312673)
			(xy 225.375347 -288.250759) (xy 225.367336 -288.187341) (xy 222.913658 -288.187341) (xy 223.008471 -288.223736)
			(xy 223.147008 -288.285417) (xy 223.282128 -288.354264) (xy 223.41346 -288.430089) (xy 223.540643 -288.512682)
			(xy 223.663329 -288.601819) (xy 223.781182 -288.697255) (xy 223.893879 -288.798727) (xy 224.001111 -288.905959)
			(xy 224.0967 -289.012122) (xy 226.096574 -289.012122) (xy 226.100645 -288.9565) (xy 226.112771 -288.902063)
			(xy 226.132694 -288.849972) (xy 226.15999 -288.801337) (xy 226.194076 -288.757194) (xy 226.234225 -288.718485)
			(xy 226.279583 -288.686034) (xy 226.329183 -288.660533) (xy 226.381967 -288.642526) (xy 226.43681 -288.632396)
			(xy 226.492544 -288.630359) (xy 226.547981 -288.636459) (xy 226.601938 -288.650565) (xy 226.653267 -288.672377)
			(xy 226.700873 -288.701431) (xy 226.743741 -288.737106) (xy 226.780958 -288.778643) (xy 226.811731 -288.825156)
			(xy 226.835403 -288.875653) (xy 226.851471 -288.92906) (xy 226.859591 -288.984236) (xy 226.8601 -289.012122)
			(xy 226.859591 -289.040008) (xy 226.851471 -289.095184) (xy 226.835403 -289.148591) (xy 226.811731 -289.199088)
			(xy 226.780958 -289.245601) (xy 226.743741 -289.287138) (xy 226.700873 -289.322813) (xy 226.653267 -289.351867)
			(xy 226.601938 -289.373679) (xy 226.547981 -289.387785) (xy 226.492544 -289.393885) (xy 226.43681 -289.391848)
			(xy 226.381967 -289.381718) (xy 226.329183 -289.363711) (xy 226.279583 -289.33821) (xy 226.234225 -289.305759)
			(xy 226.194076 -289.26705) (xy 226.15999 -289.222907) (xy 226.132694 -289.174272) (xy 226.112771 -289.122181)
			(xy 226.100645 -289.067744) (xy 226.096574 -289.012122) (xy 224.0967 -289.012122) (xy 224.102583 -289.018656)
			(xy 224.198019 -289.136509) (xy 224.287156 -289.259195) (xy 224.369749 -289.386378) (xy 224.445574 -289.51771)
			(xy 224.514421 -289.65283) (xy 224.550424 -289.733693) (xy 228.722422 -289.733693) (xy 228.722422 -289.669771)
			(xy 228.730433 -289.606353) (xy 228.74633 -289.544439) (xy 228.769862 -289.485006) (xy 228.800656 -289.428991)
			(xy 228.838229 -289.377276) (xy 228.881986 -289.330679) (xy 228.931239 -289.289934) (xy 228.98521 -289.255683)
			(xy 229.043049 -289.228466) (xy 229.103842 -289.208713) (xy 229.166632 -289.196735) (xy 229.230428 -289.192722)
			(xy 229.294224 -289.196735) (xy 229.357014 -289.208713) (xy 229.417807 -289.228466) (xy 229.475646 -289.255683)
			(xy 229.529617 -289.289934) (xy 229.572431 -289.325352) (xy 232.506481 -289.325352) (xy 232.506481 -289.270848)
			(xy 232.514238 -289.216899) (xy 232.529594 -289.164603) (xy 232.552237 -289.115025) (xy 232.581705 -289.069174)
			(xy 232.617398 -289.027984) (xy 232.65859 -288.992293) (xy 232.704443 -288.962827) (xy 232.754022 -288.940187)
			(xy 232.806319 -288.924834) (xy 232.860268 -288.91708) (xy 232.88752 -288.916618) (xy 232.907095 -288.916904)
			(xy 232.946033 -288.920977) (xy 232.965244 -288.924746) (xy 232.978706 -288.92754) (xy 233.004106 -288.919158)
			(xy 233.081322 -288.833306) (xy 233.08691 -288.80689) (xy 233.082592 -288.793936) (xy 233.073955 -288.765304)
			(xy 233.064636 -288.706234) (xy 233.06405 -288.676334) (xy 233.06461 -288.649086) (xy 233.072361 -288.595143)
			(xy 233.087709 -288.542852) (xy 233.110343 -288.493278) (xy 233.139802 -288.447429) (xy 233.175486 -288.40624)
			(xy 233.216668 -288.370548) (xy 233.262511 -288.34108) (xy 233.312081 -288.318436) (xy 233.364368 -288.303077)
			(xy 233.41831 -288.295315) (xy 233.445558 -288.294826) (xy 233.470879 -288.295196) (xy 233.521084 -288.301823)
			(xy 233.545634 -288.308034) (xy 233.557318 -288.311336) (xy 233.580432 -288.306764) (xy 233.663744 -288.241486)
			(xy 233.673904 -288.22015) (xy 233.67365 -288.207958) (xy 233.67365 -288.200338) (xy 233.674136 -288.173087)
			(xy 233.681892 -288.119139) (xy 233.697247 -288.066844) (xy 233.719889 -288.017267) (xy 233.749355 -287.971417)
			(xy 233.785046 -287.930226) (xy 233.826237 -287.894535) (xy 233.872087 -287.865069) (xy 233.921664 -287.842427)
			(xy 233.973959 -287.827072) (xy 234.027907 -287.819316) (xy 234.082409 -287.819316) (xy 234.136357 -287.827072)
			(xy 234.188652 -287.842427) (xy 234.238229 -287.865069) (xy 234.284079 -287.894535) (xy 234.32527 -287.930226)
			(xy 234.360961 -287.971417) (xy 234.390427 -288.017267) (xy 234.413069 -288.066844) (xy 234.428424 -288.119139)
			(xy 234.43618 -288.173087) (xy 234.436666 -288.200338) (xy 234.436257 -288.226057) (xy 234.429376 -288.277032)
			(xy 234.42295 -288.301938) (xy 234.419902 -288.31286) (xy 234.423458 -288.334704) (xy 234.480608 -288.417762)
			(xy 234.499658 -288.428938) (xy 234.510834 -288.429954) (xy 234.526771 -288.431651) (xy 234.558309 -288.437371)
			(xy 234.573826 -288.441384) (xy 234.58551 -288.444686) (xy 234.608624 -288.440114) (xy 234.691936 -288.374836)
			(xy 234.702096 -288.3535) (xy 234.701842 -288.341308) (xy 234.701842 -288.333688) (xy 234.702368 -288.306435)
			(xy 234.710127 -288.252485) (xy 234.725485 -288.200189) (xy 234.748129 -288.15061) (xy 234.777599 -288.104759)
			(xy 234.813294 -288.063568) (xy 234.854488 -288.027877) (xy 234.900342 -287.998411) (xy 234.949923 -287.975772)
			(xy 235.002221 -287.960419) (xy 235.056172 -287.952666) (xy 235.110677 -287.952669) (xy 235.164627 -287.96043)
			(xy 235.216923 -287.975789) (xy 235.266501 -287.998435) (xy 235.312352 -288.027906) (xy 235.353541 -288.063603)
			(xy 235.389231 -288.104798) (xy 235.401005 -288.123122) (xy 237.527084 -288.123122) (xy 237.527586 -288.091161)
			(xy 237.535597 -288.027743) (xy 237.551494 -287.965829) (xy 237.575026 -287.906396) (xy 237.60582 -287.850381)
			(xy 237.643393 -287.798666) (xy 237.68715 -287.752069) (xy 237.736403 -287.711324) (xy 237.790374 -287.677073)
			(xy 237.848213 -287.649856) (xy 237.909006 -287.630103) (xy 237.971796 -287.618125) (xy 238.035592 -287.614112)
			(xy 238.099388 -287.618125) (xy 238.162178 -287.630103) (xy 238.222971 -287.649856) (xy 238.28081 -287.677073)
			(xy 238.334781 -287.711324) (xy 238.384034 -287.752069) (xy 238.427791 -287.798666) (xy 238.465364 -287.850381)
			(xy 238.496158 -287.906396) (xy 238.51969 -287.965829) (xy 238.535587 -288.027743) (xy 238.543598 -288.091161)
			(xy 238.5441 -288.123122) (xy 238.543608 -288.154979) (xy 238.53565 -288.218194) (xy 238.519862 -288.27992)
			(xy 238.496491 -288.339193) (xy 238.465902 -288.395084) (xy 238.428574 -288.446718) (xy 238.407194 -288.47034)
			(xy 238.398365 -288.480471) (xy 238.385783 -288.504201) (xy 238.379831 -288.530393) (xy 238.380923 -288.55723)
			(xy 238.388984 -288.582851) (xy 238.403453 -288.60548) (xy 238.423328 -288.623548) (xy 238.44723 -288.6358)
			(xy 238.46028 -288.638996) (xy 238.488397 -288.645517) (xy 238.542393 -288.665909) (xy 238.5927 -288.694203)
			(xy 238.638171 -288.729751) (xy 238.677767 -288.771745) (xy 238.710586 -288.819224) (xy 238.735878 -288.871105)
			(xy 238.753066 -288.926204) (xy 238.761758 -288.983263) (xy 238.762286 -289.012122) (xy 238.7618 -289.039373)
			(xy 238.754044 -289.093321) (xy 238.738689 -289.145616) (xy 238.716047 -289.195193) (xy 238.686581 -289.241043)
			(xy 238.65089 -289.282234) (xy 238.609699 -289.317925) (xy 238.563849 -289.347391) (xy 238.514272 -289.370033)
			(xy 238.461977 -289.385388) (xy 238.408029 -289.393144) (xy 238.353527 -289.393144) (xy 238.299579 -289.385388)
			(xy 238.247284 -289.370033) (xy 238.197707 -289.347391) (xy 238.151857 -289.317925) (xy 238.110666 -289.282234)
			(xy 238.074975 -289.241043) (xy 238.045509 -289.195193) (xy 238.022867 -289.145616) (xy 238.007512 -289.093321)
			(xy 237.999756 -289.039373) (xy 237.99927 -289.012122) (xy 237.999839 -288.982525) (xy 238.008985 -288.924042)
			(xy 238.02706 -288.867676) (xy 238.053631 -288.814781) (xy 238.07039 -288.79038) (xy 238.07782 -288.779191)
			(xy 238.087159 -288.754019) (xy 238.089613 -288.727284) (xy 238.085013 -288.700832) (xy 238.073676 -288.676495)
			(xy 238.056387 -288.655955) (xy 238.034341 -288.640632) (xy 238.009063 -288.631585) (xy 237.995714 -288.630106)
			(xy 237.964216 -288.627176) (xy 237.902254 -288.614419) (xy 237.842352 -288.594076) (xy 237.785435 -288.566462)
			(xy 237.732383 -288.532002) (xy 237.684014 -288.491229) (xy 237.641074 -288.444772) (xy 237.604228 -288.393348)
			(xy 237.574043 -288.337752) (xy 237.550987 -288.278841) (xy 237.535414 -288.217526) (xy 237.527566 -288.154753)
			(xy 237.527084 -288.123122) (xy 235.401005 -288.123122) (xy 235.418695 -288.150653) (xy 235.441332 -288.200235)
			(xy 235.456684 -288.252534) (xy 235.464435 -288.306485) (xy 235.46443 -288.36099) (xy 235.456668 -288.414939)
			(xy 235.441306 -288.467235) (xy 235.418659 -288.516812) (xy 235.389186 -288.562662) (xy 235.353488 -288.60385)
			(xy 235.312292 -288.639538) (xy 235.266436 -288.669001) (xy 235.216853 -288.691637) (xy 235.164554 -288.706986)
			(xy 235.110603 -288.714736) (xy 235.08335 -288.715196) (xy 235.058029 -288.714824) (xy 235.007824 -288.708198)
			(xy 234.983274 -288.701988) (xy 234.97159 -288.698686) (xy 234.948476 -288.703258) (xy 234.865164 -288.768536)
			(xy 234.855004 -288.789872) (xy 234.855258 -288.802064) (xy 234.855258 -288.809684) (xy 234.854774 -288.83597)
			(xy 234.847546 -288.888043) (xy 234.833239 -288.93863) (xy 234.812123 -288.986775) (xy 234.784599 -289.031566)
			(xy 234.751186 -289.072155) (xy 234.712519 -289.107773) (xy 234.691174 -289.12312) (xy 234.681776 -289.129724)
			(xy 234.6706 -289.149282) (xy 234.661964 -289.25012) (xy 234.669838 -289.271202) (xy 234.67822 -289.27933)
			(xy 234.696067 -289.297323) (xy 234.727292 -289.337239) (xy 234.752958 -289.380938) (xy 234.772612 -289.42765)
			(xy 234.785909 -289.476553) (xy 234.792615 -289.526787) (xy 234.793028 -289.552126) (xy 234.792563 -289.578505)
			(xy 234.785307 -289.630761) (xy 234.770924 -289.681519) (xy 234.749688 -289.729814) (xy 234.747297 -289.733693)
			(xy 240.666772 -289.733693) (xy 240.666772 -289.669771) (xy 240.674783 -289.606353) (xy 240.69068 -289.544439)
			(xy 240.714212 -289.485006) (xy 240.745006 -289.428991) (xy 240.782579 -289.377276) (xy 240.826336 -289.330679)
			(xy 240.875589 -289.289934) (xy 240.92956 -289.255683) (xy 240.987399 -289.228466) (xy 241.048192 -289.208713)
			(xy 241.110982 -289.196735) (xy 241.174778 -289.192722) (xy 241.238574 -289.196735) (xy 241.301364 -289.208713)
			(xy 241.362157 -289.228466) (xy 241.419996 -289.255683) (xy 241.473967 -289.289934) (xy 241.52322 -289.330679)
			(xy 241.566977 -289.377276) (xy 241.60455 -289.428991) (xy 241.623259 -289.463024) (xy 244.223947 -289.463024)
			(xy 244.223952 -289.408516) (xy 244.231713 -289.354563) (xy 244.247075 -289.302264) (xy 244.269723 -289.252684)
			(xy 244.299196 -289.206832) (xy 244.334896 -289.165641) (xy 244.376094 -289.12995) (xy 244.421953 -289.100485)
			(xy 244.471537 -289.077847) (xy 244.52384 -289.062497) (xy 244.577794 -289.054746) (xy 244.605048 -289.054286)
			(xy 244.60708 -289.054286) (xy 244.618002 -289.054286) (xy 244.63756 -289.045904) (xy 244.703092 -288.974022)
			(xy 244.709696 -288.953702) (xy 244.70868 -288.94278) (xy 244.706902 -288.905696) (xy 244.707352 -288.878443)
			(xy 244.715109 -288.824491) (xy 244.730466 -288.772192) (xy 244.75311 -288.722611) (xy 244.78258 -288.676758)
			(xy 244.818275 -288.635565) (xy 244.859469 -288.599871) (xy 244.905323 -288.570403) (xy 244.954905 -288.547762)
			(xy 245.007204 -288.532406) (xy 245.061157 -288.524651) (xy 245.08841 -288.524188) (xy 245.11373 -288.524568)
			(xy 245.163935 -288.531189) (xy 245.188486 -288.537396) (xy 245.20017 -288.540698) (xy 245.223284 -288.536126)
			(xy 245.306596 -288.470848) (xy 245.316756 -288.449512) (xy 245.316502 -288.43732) (xy 245.316502 -288.4297)
			(xy 245.317077 -288.40102) (xy 245.325686 -288.34431) (xy 245.342681 -288.289526) (xy 245.367678 -288.237899)
			(xy 245.400117 -288.190593) (xy 245.439266 -288.14867) (xy 245.484245 -288.113074) (xy 245.534042 -288.084607)
			(xy 245.587537 -288.063908) (xy 245.643526 -288.051443) (xy 245.672102 -288.048954) (xy 245.685564 -288.048192)
			(xy 245.707662 -288.03346) (xy 245.759732 -287.93186) (xy 245.758716 -287.905444) (xy 245.75135 -287.894014)
			(xy 245.737688 -287.871182) (xy 245.716111 -287.822545) (xy 245.7015 -287.771384) (xy 245.694138 -287.718688)
			(xy 245.693692 -287.692084) (xy 245.694208 -287.663345) (xy 245.702833 -287.606517) (xy 245.719885 -287.551627)
			(xy 245.744978 -287.499915) (xy 245.777545 -287.452553) (xy 245.796816 -287.431226) (xy 245.80342 -287.424114)
			(xy 245.810532 -287.406588) (xy 245.810532 -287.31718) (xy 245.80342 -287.299654) (xy 245.796816 -287.292542)
			(xy 245.777534 -287.271225) (xy 245.74497 -287.22386) (xy 245.71988 -287.172146) (xy 245.702832 -287.117253)
			(xy 245.694212 -287.060424) (xy 245.693692 -287.031684) (xy 245.694178 -287.004433) (xy 245.701934 -286.950485)
			(xy 245.717289 -286.89819) (xy 245.739931 -286.848613) (xy 245.769397 -286.802763) (xy 245.805088 -286.761572)
			(xy 245.846279 -286.725881) (xy 245.892129 -286.696415) (xy 245.941706 -286.673773) (xy 245.994001 -286.658418)
			(xy 246.047949 -286.650662) (xy 246.102451 -286.650662) (xy 246.156399 -286.658418) (xy 246.208694 -286.673773)
			(xy 246.258271 -286.696415) (xy 246.304121 -286.725881) (xy 246.345312 -286.761572) (xy 246.381003 -286.802763)
			(xy 246.410469 -286.848613) (xy 246.433111 -286.89819) (xy 246.448466 -286.950485) (xy 246.456222 -287.004433)
			(xy 246.456708 -287.031684) (xy 246.456172 -287.060422) (xy 246.447552 -287.117249) (xy 246.430505 -287.17214)
			(xy 246.405416 -287.223852) (xy 246.372854 -287.271215) (xy 246.353584 -287.292542) (xy 246.34698 -287.299654)
			(xy 246.339868 -287.31718) (xy 246.339868 -287.406588) (xy 246.34698 -287.424114) (xy 246.353584 -287.431226)
			(xy 246.372851 -287.452556) (xy 246.405417 -287.499918) (xy 246.43051 -287.551629) (xy 246.447561 -287.606519)
			(xy 246.456186 -287.663345) (xy 246.456708 -287.692084) (xy 246.456109 -287.720763) (xy 246.447502 -287.777471)
			(xy 246.43051 -287.832255) (xy 246.405516 -287.883881) (xy 246.37308 -287.931187) (xy 246.333934 -287.97311)
			(xy 246.288958 -288.008706) (xy 246.239163 -288.037174) (xy 246.18567 -288.057874) (xy 246.129683 -288.07034)
			(xy 246.101108 -288.07283) (xy 246.087646 -288.073592) (xy 246.065548 -288.088324) (xy 246.013478 -288.189924)
			(xy 246.014494 -288.21634) (xy 246.02186 -288.22777) (xy 246.034027 -288.247932) (xy 246.053825 -288.290662)
			(xy 246.068201 -288.335507) (xy 246.072914 -288.35858) (xy 246.074946 -288.368994) (xy 246.086884 -288.386774)
			(xy 246.16918 -288.43732) (xy 246.190262 -288.440114) (xy 246.200676 -288.437066) (xy 246.226475 -288.430141)
			(xy 246.279377 -288.422745) (xy 246.306086 -288.422334) (xy 246.331407 -288.422698) (xy 246.381612 -288.42933)
			(xy 246.406162 -288.435542) (xy 246.417846 -288.438844) (xy 246.44096 -288.434272) (xy 246.524272 -288.368994)
			(xy 246.534432 -288.347658) (xy 246.534178 -288.335466) (xy 246.534178 -288.327846) (xy 246.534606 -288.300589)
			(xy 246.542358 -288.246629) (xy 246.55771 -288.194321) (xy 246.580351 -288.144731) (xy 246.609819 -288.098868)
			(xy 246.645514 -288.057665) (xy 246.68671 -288.021962) (xy 246.732568 -287.992486) (xy 246.782153 -287.969835)
			(xy 246.834458 -287.954473) (xy 246.888417 -287.946711) (xy 246.942931 -287.946707) (xy 246.996891 -287.954462)
			(xy 247.049198 -287.969817) (xy 247.098787 -287.992461) (xy 247.144648 -288.021931) (xy 247.185849 -288.057628)
			(xy 247.22155 -288.098826) (xy 247.251024 -288.144685) (xy 247.273672 -288.194272) (xy 247.289031 -288.246578)
			(xy 247.296791 -288.300537) (xy 247.296791 -288.355051) (xy 247.289034 -288.40901) (xy 247.273676 -288.461316)
			(xy 247.25103 -288.510904) (xy 247.221557 -288.556764) (xy 247.185858 -288.597963) (xy 247.144658 -288.633662)
			(xy 247.098797 -288.663134) (xy 247.049209 -288.685779) (xy 246.996903 -288.701136) (xy 246.942943 -288.708892)
			(xy 246.915686 -288.709354) (xy 246.890365 -288.708976) (xy 246.840161 -288.702354) (xy 246.81561 -288.696146)
			(xy 246.803926 -288.692844) (xy 246.780812 -288.697416) (xy 246.6975 -288.762694) (xy 246.68734 -288.78403)
			(xy 246.687594 -288.796222) (xy 246.687594 -288.803842) (xy 246.687163 -288.829988) (xy 246.680009 -288.881788)
			(xy 246.665842 -288.932124) (xy 246.644928 -288.980051) (xy 246.617659 -289.02467) (xy 246.584547 -289.065143)
			(xy 246.565674 -289.083242) (xy 246.557292 -289.091116) (xy 246.54891 -289.112452) (xy 246.555768 -289.214052)
			(xy 246.566944 -289.234118) (xy 246.576342 -289.240722) (xy 246.597307 -289.256151) (xy 246.6353 -289.291733)
			(xy 246.668104 -289.332149) (xy 246.695111 -289.376647) (xy 246.715821 -289.424403) (xy 246.729847 -289.474531)
			(xy 246.736932 -289.5261) (xy 246.737378 -289.552126) (xy 246.73694 -289.578506) (xy 246.729684 -289.630764)
			(xy 246.715298 -289.681525) (xy 246.694059 -289.729821) (xy 246.66637 -289.774731) (xy 246.63276 -289.815399)
			(xy 246.593869 -289.851051) (xy 246.550437 -289.881006) (xy 246.527066 -289.893248) (xy 246.513858 -289.899598)
			(xy 246.498872 -289.923982) (xy 246.498872 -290.04387) (xy 246.513858 -290.068254) (xy 246.527066 -290.074604)
			(xy 246.550463 -290.086797) (xy 246.593885 -290.116769) (xy 246.632768 -290.152432) (xy 246.666371 -290.193109)
			(xy 246.694054 -290.238024) (xy 246.71529 -290.286323) (xy 246.729675 -290.337086) (xy 246.736935 -290.389345)
			(xy 246.737378 -290.415726) (xy 246.736908 -290.442984) (xy 246.729138 -290.496943) (xy 246.713773 -290.549249)
			(xy 246.691127 -290.598839) (xy 246.661659 -290.644704) (xy 246.625968 -290.685913) (xy 246.58478 -290.721627)
			(xy 246.562118 -290.736782) (xy 246.555136 -290.741615) (xy 246.54462 -290.754934) (xy 246.539063 -290.770969)
			(xy 246.53875 -290.779454) (xy 246.53875 -290.864798) (xy 246.539113 -290.873273) (xy 246.544687 -290.889284)
			(xy 246.555165 -290.902611) (xy 246.562118 -290.90747) (xy 246.584803 -290.922589) (xy 246.62599 -290.958306)
			(xy 246.64103 -290.975674) (xy 247.00432 -290.975674) (xy 247.00432 -290.824026) (xy 247.012257 -290.672585)
			(xy 247.028108 -290.521767) (xy 247.051831 -290.371986) (xy 247.083361 -290.223651) (xy 247.12261 -290.07717)
			(xy 247.169472 -289.932944) (xy 247.223818 -289.791367) (xy 247.285499 -289.65283) (xy 247.354346 -289.51771)
			(xy 247.430171 -289.386378) (xy 247.512764 -289.259195) (xy 247.601901 -289.136509) (xy 247.697337 -289.018656)
			(xy 247.798809 -288.905959) (xy 247.906041 -288.798727) (xy 248.018738 -288.697255) (xy 248.136591 -288.601819)
			(xy 248.259277 -288.512682) (xy 248.38646 -288.430089) (xy 248.517792 -288.354264) (xy 248.652912 -288.285417)
			(xy 248.791449 -288.223736) (xy 248.933026 -288.16939) (xy 249.077252 -288.122528) (xy 249.223733 -288.083279)
			(xy 249.372068 -288.051749) (xy 249.521849 -288.028026) (xy 249.672667 -288.012175) (xy 249.824108 -288.004238)
			(xy 249.975756 -288.004238) (xy 250.127197 -288.012175) (xy 250.278015 -288.028026) (xy 250.427796 -288.051749)
			(xy 250.576131 -288.083279) (xy 250.722612 -288.122528) (xy 250.866838 -288.16939) (xy 251.008415 -288.223736)
			(xy 251.146952 -288.285417) (xy 251.282072 -288.354264) (xy 251.413404 -288.430089) (xy 251.540587 -288.512682)
			(xy 251.663273 -288.601819) (xy 251.781126 -288.697255) (xy 251.893823 -288.798727) (xy 252.001055 -288.905959)
			(xy 252.102527 -289.018656) (xy 252.197963 -289.136509) (xy 252.2871 -289.259195) (xy 252.369693 -289.386378)
			(xy 252.445518 -289.51771) (xy 252.514365 -289.65283) (xy 252.576046 -289.791367) (xy 252.630392 -289.932944)
			(xy 252.677254 -290.07717) (xy 252.716503 -290.223651) (xy 252.748033 -290.371986) (xy 252.771756 -290.521767)
			(xy 252.787607 -290.672585) (xy 252.795544 -290.824026) (xy 252.79604 -290.89985) (xy 252.795544 -290.975674)
			(xy 252.787607 -291.127115) (xy 252.771756 -291.277933) (xy 252.748033 -291.427714) (xy 252.716503 -291.576049)
			(xy 252.677254 -291.72253) (xy 252.630392 -291.866756) (xy 252.576046 -292.008333) (xy 252.514365 -292.14687)
			(xy 252.445518 -292.28199) (xy 252.369693 -292.413322) (xy 252.2871 -292.540505) (xy 252.197963 -292.663191)
			(xy 252.102527 -292.781044) (xy 252.001055 -292.893741) (xy 251.893823 -293.000973) (xy 251.781126 -293.102445)
			(xy 251.663273 -293.197881) (xy 251.540587 -293.287018) (xy 251.413404 -293.369611) (xy 251.282072 -293.445436)
			(xy 251.146952 -293.514283) (xy 251.008415 -293.575964) (xy 250.866838 -293.63031) (xy 250.722612 -293.677172)
			(xy 250.576131 -293.716421) (xy 250.427796 -293.747951) (xy 250.278015 -293.771674) (xy 250.127197 -293.787525)
			(xy 249.975756 -293.795462) (xy 249.824108 -293.795462) (xy 249.672667 -293.787525) (xy 249.521849 -293.771674)
			(xy 249.372068 -293.747951) (xy 249.223733 -293.716421) (xy 249.077252 -293.677172) (xy 248.933026 -293.63031)
			(xy 248.791449 -293.575964) (xy 248.652912 -293.514283) (xy 248.517792 -293.445436) (xy 248.38646 -293.369611)
			(xy 248.259277 -293.287018) (xy 248.136591 -293.197881) (xy 248.018738 -293.102445) (xy 247.906041 -293.000973)
			(xy 247.798809 -292.893741) (xy 247.697337 -292.781044) (xy 247.601901 -292.663191) (xy 247.512764 -292.540505)
			(xy 247.430171 -292.413322) (xy 247.354346 -292.28199) (xy 247.285499 -292.14687) (xy 247.223818 -292.008333)
			(xy 247.169472 -291.866756) (xy 247.12261 -291.72253) (xy 247.083361 -291.576049) (xy 247.051831 -291.427714)
			(xy 247.028108 -291.277933) (xy 247.012257 -291.127115) (xy 247.00432 -290.975674) (xy 246.64103 -290.975674)
			(xy 246.661677 -290.999518) (xy 246.691138 -291.045388) (xy 246.713775 -291.094983) (xy 246.729126 -291.147294)
			(xy 246.736879 -291.201256) (xy 246.736877 -291.255772) (xy 246.72912 -291.309734) (xy 246.713765 -291.362043)
			(xy 246.691125 -291.411636) (xy 246.66166 -291.457504) (xy 246.62597 -291.498714) (xy 246.584781 -291.534428)
			(xy 246.562118 -291.549582) (xy 246.555136 -291.554415) (xy 246.54462 -291.567734) (xy 246.539063 -291.583769)
			(xy 246.53875 -291.592254) (xy 246.53875 -291.677598) (xy 246.539113 -291.686073) (xy 246.544687 -291.702084)
			(xy 246.555165 -291.715411) (xy 246.562118 -291.72027) (xy 246.58479 -291.735411) (xy 246.625985 -291.771121)
			(xy 246.661679 -291.81233) (xy 246.691146 -291.858198) (xy 246.713787 -291.907792) (xy 246.72914 -291.960103)
			(xy 246.736894 -292.014067) (xy 246.737378 -292.041326) (xy 246.736969 -292.068581) (xy 246.729208 -292.122535)
			(xy 246.713847 -292.174836) (xy 246.691199 -292.224418) (xy 246.661726 -292.270273) (xy 246.626026 -292.311466)
			(xy 246.584828 -292.347159) (xy 246.538969 -292.376626) (xy 246.489384 -292.399267) (xy 246.437081 -292.41462)
			(xy 246.383125 -292.422373) (xy 246.35587 -292.422834) (xy 246.326954 -292.42229) (xy 246.269783 -292.41357)
			(xy 246.214583 -292.396319) (xy 246.162621 -292.370932) (xy 246.115087 -292.337992) (xy 246.07307 -292.298253)
			(xy 246.05488 -292.275768) (xy 246.047328 -292.266996) (xy 246.026562 -292.256819) (xy 246.015002 -292.25621)
			(xy 245.934738 -292.25621) (xy 245.923172 -292.256799) (xy 245.902401 -292.26698) (xy 245.89486 -292.275768)
			(xy 245.880087 -292.294172) (xy 245.846713 -292.32754) (xy 245.828312 -292.342316) (xy 245.819549 -292.349877)
			(xy 245.809366 -292.370636) (xy 245.808754 -292.382194) (xy 245.808754 -292.462458) (xy 245.80933 -292.474026)
			(xy 245.819519 -292.494798) (xy 245.828312 -292.502336) (xy 245.850815 -292.520504) (xy 245.890549 -292.562529)
			(xy 245.923485 -292.610068) (xy 245.94887 -292.662034) (xy 245.966122 -292.717236) (xy 245.974846 -292.774409)
			(xy 245.975378 -292.803326) (xy 245.974802 -292.833588) (xy 245.965254 -292.893353) (xy 245.946387 -292.95086)
			(xy 245.918674 -293.004666) (xy 245.90121 -293.029386) (xy 245.895622 -293.037006) (xy 245.890542 -293.05504)
			(xy 245.89867 -293.141146) (xy 245.907052 -293.157656) (xy 245.91391 -293.16426) (xy 245.935548 -293.184911)
			(xy 245.974342 -293.230441) (xy 246.007526 -293.280208) (xy 246.034642 -293.333525) (xy 246.055316 -293.389655)
			(xy 246.069262 -293.447822) (xy 246.076288 -293.507224) (xy 246.076724 -293.537132) (xy 246.076222 -293.569093)
			(xy 246.068211 -293.632511) (xy 246.052314 -293.694425) (xy 246.028782 -293.753858) (xy 245.997988 -293.809873)
			(xy 245.960415 -293.861588) (xy 245.916658 -293.908185) (xy 245.867405 -293.94893) (xy 245.813434 -293.983181)
			(xy 245.755595 -294.010398) (xy 245.694802 -294.030151) (xy 245.632012 -294.042129) (xy 245.568216 -294.046143)
			(xy 245.50442 -294.042129) (xy 245.44163 -294.030151) (xy 245.380837 -294.010398) (xy 245.322998 -293.983181)
			(xy 245.269027 -293.94893) (xy 245.219774 -293.908185) (xy 245.176017 -293.861588) (xy 245.138444 -293.809873)
			(xy 245.10765 -293.753858) (xy 245.084118 -293.694425) (xy 245.068221 -293.632511) (xy 245.06021 -293.569093)
			(xy 245.059708 -293.537132) (xy 245.060233 -293.504672) (xy 245.068481 -293.440278) (xy 245.08486 -293.377458)
			(xy 245.109104 -293.317235) (xy 245.140817 -293.260588) (xy 245.179484 -293.208439) (xy 245.224476 -293.161638)
			(xy 245.249446 -293.140892) (xy 245.256812 -293.13505) (xy 245.26621 -293.119048) (xy 245.280434 -293.033704)
			(xy 245.276624 -293.015416) (xy 245.271544 -293.007542) (xy 245.257537 -292.98452) (xy 245.235417 -292.935381)
			(xy 245.220416 -292.883622) (xy 245.212832 -292.83027) (xy 245.212362 -292.803326) (xy 245.212875 -292.774409)
			(xy 245.221602 -292.717236) (xy 245.238859 -292.662036) (xy 245.264252 -292.610074) (xy 245.297197 -292.56254)
			(xy 245.336941 -292.520525) (xy 245.359428 -292.502336) (xy 245.368174 -292.494759) (xy 245.378365 -292.474012)
			(xy 245.378986 -292.462458) (xy 245.378986 -292.382194) (xy 245.378424 -292.370625) (xy 245.368224 -292.349854)
			(xy 245.359428 -292.342316) (xy 245.336958 -292.324109) (xy 245.297221 -292.282093) (xy 245.264279 -292.234562)
			(xy 245.238888 -292.182604) (xy 245.22163 -292.127409) (xy 245.212898 -292.070241) (xy 245.212362 -292.041326)
			(xy 245.212854 -292.014069) (xy 245.220618 -291.96011) (xy 245.235977 -291.907803) (xy 245.25862 -291.858213)
			(xy 245.288085 -291.812348) (xy 245.323774 -291.771139) (xy 245.364961 -291.735425) (xy 245.387622 -291.72027)
			(xy 245.394614 -291.715449) (xy 245.405133 -291.702127) (xy 245.410684 -291.686086) (xy 245.41099 -291.677598)
			(xy 245.41099 -291.592254) (xy 245.410686 -291.583773) (xy 245.405089 -291.567757) (xy 245.394587 -291.554434)
			(xy 245.387622 -291.549582) (xy 245.364983 -291.534394) (xy 245.323795 -291.498687) (xy 245.288105 -291.457482)
			(xy 245.258641 -291.41162) (xy 245.236001 -291.362032) (xy 245.220646 -291.309727) (xy 245.212889 -291.25577)
			(xy 245.212887 -291.201258) (xy 245.22064 -291.1473) (xy 245.235991 -291.094995) (xy 245.258627 -291.045405)
			(xy 245.288088 -290.99954) (xy 245.323775 -290.958333) (xy 245.364961 -290.922622) (xy 245.387622 -290.90747)
			(xy 245.394614 -290.902649) (xy 245.405133 -290.889327) (xy 245.410684 -290.873286) (xy 245.41099 -290.864798)
			(xy 245.41099 -290.779454) (xy 245.410686 -290.770973) (xy 245.405089 -290.754957) (xy 245.394587 -290.741634)
			(xy 245.387622 -290.736782) (xy 245.364937 -290.721659) (xy 245.323741 -290.685948) (xy 245.288046 -290.644737)
			(xy 245.258579 -290.598865) (xy 245.235941 -290.549268) (xy 245.220591 -290.496953) (xy 245.212843 -290.442986)
			(xy 245.212362 -290.415726) (xy 245.212793 -290.389346) (xy 245.220055 -290.337089) (xy 245.234444 -290.28633)
			(xy 245.255685 -290.238035) (xy 245.283375 -290.193126) (xy 245.316985 -290.152458) (xy 245.355875 -290.116805)
			(xy 245.399304 -290.086848) (xy 245.422674 -290.074604) (xy 245.435882 -290.068254) (xy 245.450868 -290.04387)
			(xy 245.450868 -289.923982) (xy 245.435882 -289.899598) (xy 245.422674 -289.893248) (xy 245.399309 -289.880998)
			(xy 245.355886 -289.851036) (xy 245.317001 -289.815381) (xy 245.283395 -289.774713) (xy 245.255708 -289.729806)
			(xy 245.234466 -289.681514) (xy 245.220075 -289.630758) (xy 245.212809 -289.578504) (xy 245.212362 -289.552126)
			(xy 245.21309 -289.518647) (xy 245.224839 -289.452728) (xy 245.23573 -289.421062) (xy 245.240302 -289.408616)
			(xy 245.235984 -289.382708) (xy 245.166642 -289.293808) (xy 245.142512 -289.283648) (xy 245.129304 -289.284918)
			(xy 245.119113 -289.285972) (xy 245.098655 -289.287116) (xy 245.08841 -289.287204) (xy 245.086378 -289.287204)
			(xy 245.075456 -289.287204) (xy 245.055898 -289.295586) (xy 244.990366 -289.367468) (xy 244.983762 -289.387788)
			(xy 244.984778 -289.39871) (xy 244.986556 -289.435794) (xy 244.986051 -289.463048) (xy 244.978294 -289.517002)
			(xy 244.962938 -289.569302) (xy 244.940295 -289.618884) (xy 244.910825 -289.66474) (xy 244.87513 -289.705934)
			(xy 244.833935 -289.741629) (xy 244.788079 -289.771097) (xy 244.738496 -289.79374) (xy 244.686196 -289.809096)
			(xy 244.632242 -289.816851) (xy 244.577734 -289.81685) (xy 244.523781 -289.80909) (xy 244.471481 -289.793732)
			(xy 244.4219 -289.771086) (xy 244.376046 -289.741614) (xy 244.334853 -289.705917) (xy 244.29916 -289.66472)
			(xy 244.269694 -289.618863) (xy 244.247054 -289.569279) (xy 244.231701 -289.516978) (xy 244.223947 -289.463024)
			(xy 241.623259 -289.463024) (xy 241.635344 -289.485006) (xy 241.658876 -289.544439) (xy 241.674773 -289.606353)
			(xy 241.682784 -289.669771) (xy 241.683286 -289.701732) (xy 241.682784 -289.733693) (xy 241.674773 -289.797111)
			(xy 241.658876 -289.859025) (xy 241.635344 -289.918458) (xy 241.60455 -289.974473) (xy 241.566977 -290.026188)
			(xy 241.52322 -290.072785) (xy 241.473967 -290.11353) (xy 241.419996 -290.147781) (xy 241.362157 -290.174998)
			(xy 241.301364 -290.194751) (xy 241.238574 -290.206729) (xy 241.174778 -290.210743) (xy 241.110982 -290.206729)
			(xy 241.048192 -290.194751) (xy 240.987399 -290.174998) (xy 240.92956 -290.147781) (xy 240.875589 -290.11353)
			(xy 240.826336 -290.072785) (xy 240.782579 -290.026188) (xy 240.745006 -289.974473) (xy 240.714212 -289.918458)
			(xy 240.69068 -289.859025) (xy 240.674783 -289.797111) (xy 240.666772 -289.733693) (xy 234.747297 -289.733693)
			(xy 234.722003 -289.774723) (xy 234.688397 -289.815392) (xy 234.649511 -289.851046) (xy 234.606085 -289.881004)
			(xy 234.582716 -289.893248) (xy 234.569508 -289.899598) (xy 234.554522 -289.923982) (xy 234.554522 -290.04387)
			(xy 234.569508 -290.068254) (xy 234.582716 -290.074604) (xy 234.606101 -290.08682) (xy 234.649525 -290.116785)
			(xy 234.68841 -290.152445) (xy 234.722015 -290.193118) (xy 234.7497 -290.238031) (xy 234.770938 -290.286327)
			(xy 234.785324 -290.337088) (xy 234.792585 -290.389346) (xy 234.793028 -290.415726) (xy 234.79258 -290.442985)
			(xy 234.784809 -290.496946) (xy 234.769442 -290.549254) (xy 234.746793 -290.598844) (xy 234.717321 -290.644709)
			(xy 234.681625 -290.685917) (xy 234.640432 -290.721628) (xy 234.617768 -290.736782) (xy 234.610796 -290.741629)
			(xy 234.600275 -290.75494) (xy 234.594714 -290.77097) (xy 234.5944 -290.779454) (xy 234.5944 -290.864798)
			(xy 234.59474 -290.873276) (xy 234.600321 -290.889289) (xy 234.610809 -290.902615) (xy 234.617768 -290.90747)
			(xy 234.640456 -290.922587) (xy 234.681648 -290.958301) (xy 234.717339 -290.999513) (xy 234.746804 -291.045383)
			(xy 234.769444 -291.094978) (xy 234.784797 -291.147291) (xy 234.792552 -291.201255) (xy 234.79255 -291.255773)
			(xy 234.784791 -291.309737) (xy 234.769434 -291.362048) (xy 234.746791 -291.411642) (xy 234.717322 -291.45751)
			(xy 234.681628 -291.498719) (xy 234.640433 -291.53443) (xy 234.617768 -291.549582) (xy 234.610796 -291.554429)
			(xy 234.600275 -291.56774) (xy 234.594714 -291.58377) (xy 234.5944 -291.592254) (xy 234.5944 -291.646059)
			(xy 237.335816 -291.646059) (xy 237.335816 -291.582137) (xy 237.343827 -291.518719) (xy 237.359724 -291.456805)
			(xy 237.383256 -291.397372) (xy 237.41405 -291.341357) (xy 237.451623 -291.289642) (xy 237.49538 -291.243045)
			(xy 237.544633 -291.2023) (xy 237.598604 -291.168049) (xy 237.656443 -291.140832) (xy 237.717236 -291.121079)
			(xy 237.780026 -291.109101) (xy 237.843822 -291.105088) (xy 237.907618 -291.109101) (xy 237.970408 -291.121079)
			(xy 238.031201 -291.140832) (xy 238.08904 -291.168049) (xy 238.143011 -291.2023) (xy 238.169801 -291.224462)
			(xy 240.345974 -291.224462) (xy 240.350045 -291.16884) (xy 240.362171 -291.114403) (xy 240.382094 -291.062312)
			(xy 240.40939 -291.013677) (xy 240.443476 -290.969534) (xy 240.483625 -290.930825) (xy 240.528983 -290.898374)
			(xy 240.578583 -290.872873) (xy 240.631367 -290.854866) (xy 240.68621 -290.844736) (xy 240.741944 -290.842699)
			(xy 240.797381 -290.848799) (xy 240.851338 -290.862905) (xy 240.902667 -290.884717) (xy 240.950273 -290.913771)
			(xy 240.993141 -290.949446) (xy 241.030358 -290.990983) (xy 241.061131 -291.037496) (xy 241.084803 -291.087993)
			(xy 241.100871 -291.1414) (xy 241.108991 -291.196576) (xy 241.1095 -291.224462) (xy 241.108991 -291.252348)
			(xy 241.100871 -291.307524) (xy 241.084803 -291.360931) (xy 241.061131 -291.411428) (xy 241.030358 -291.457941)
			(xy 240.993141 -291.499478) (xy 240.950273 -291.535153) (xy 240.902667 -291.564207) (xy 240.851338 -291.586019)
			(xy 240.797381 -291.600125) (xy 240.741944 -291.606225) (xy 240.68621 -291.604188) (xy 240.631367 -291.594058)
			(xy 240.578583 -291.576051) (xy 240.528983 -291.55055) (xy 240.483625 -291.518099) (xy 240.443476 -291.47939)
			(xy 240.40939 -291.435247) (xy 240.382094 -291.386612) (xy 240.362171 -291.334521) (xy 240.350045 -291.280084)
			(xy 240.345974 -291.224462) (xy 238.169801 -291.224462) (xy 238.192264 -291.243045) (xy 238.236021 -291.289642)
			(xy 238.273594 -291.341357) (xy 238.304388 -291.397372) (xy 238.32792 -291.456805) (xy 238.343817 -291.518719)
			(xy 238.351828 -291.582137) (xy 238.35233 -291.614098) (xy 238.351828 -291.646059) (xy 238.343817 -291.709477)
			(xy 238.32792 -291.771391) (xy 238.304388 -291.830824) (xy 238.273594 -291.886839) (xy 238.236021 -291.938554)
			(xy 238.192264 -291.985151) (xy 238.143011 -292.025896) (xy 238.08904 -292.060147) (xy 238.031201 -292.087364)
			(xy 237.970408 -292.107117) (xy 237.907618 -292.119095) (xy 237.843822 -292.123109) (xy 237.780026 -292.119095)
			(xy 237.717236 -292.107117) (xy 237.656443 -292.087364) (xy 237.598604 -292.060147) (xy 237.544633 -292.025896)
			(xy 237.49538 -291.985151) (xy 237.451623 -291.938554) (xy 237.41405 -291.886839) (xy 237.383256 -291.830824)
			(xy 237.359724 -291.771391) (xy 237.343827 -291.709477) (xy 237.335816 -291.646059) (xy 234.5944 -291.646059)
			(xy 234.5944 -291.677598) (xy 234.59474 -291.686076) (xy 234.600321 -291.702089) (xy 234.610809 -291.715415)
			(xy 234.617768 -291.72027) (xy 234.640429 -291.735427) (xy 234.681626 -291.771133) (xy 234.717322 -291.812338)
			(xy 234.746792 -291.858203) (xy 234.769435 -291.907795) (xy 234.784789 -291.960105) (xy 234.792544 -292.014068)
			(xy 234.793028 -292.041326) (xy 234.792546 -292.068577) (xy 234.784787 -292.122524) (xy 234.769429 -292.174817)
			(xy 234.746787 -292.224393) (xy 234.71732 -292.270243) (xy 234.681628 -292.311432) (xy 234.66333 -292.327287)
			(xy 240.107464 -292.327287) (xy 240.107464 -292.263365) (xy 240.115475 -292.199947) (xy 240.131372 -292.138033)
			(xy 240.154904 -292.0786) (xy 240.185698 -292.022585) (xy 240.223271 -291.97087) (xy 240.267028 -291.924273)
			(xy 240.316281 -291.883528) (xy 240.370252 -291.849277) (xy 240.428091 -291.82206) (xy 240.488884 -291.802307)
			(xy 240.551674 -291.790329) (xy 240.61547 -291.786316) (xy 240.679266 -291.790329) (xy 240.742056 -291.802307)
			(xy 240.802849 -291.82206) (xy 240.860688 -291.849277) (xy 240.914659 -291.883528) (xy 240.963912 -291.924273)
			(xy 241.007669 -291.97087) (xy 241.045242 -292.022585) (xy 241.076036 -292.0786) (xy 241.099568 -292.138033)
			(xy 241.115465 -292.199947) (xy 241.123476 -292.263365) (xy 241.123978 -292.295326) (xy 241.123476 -292.327287)
			(xy 241.115465 -292.390705) (xy 241.099568 -292.452619) (xy 241.076036 -292.512052) (xy 241.045242 -292.568067)
			(xy 241.007669 -292.619782) (xy 240.963912 -292.666379) (xy 240.914659 -292.707124) (xy 240.860688 -292.741375)
			(xy 240.802849 -292.768592) (xy 240.742056 -292.788345) (xy 240.679266 -292.800323) (xy 240.61547 -292.804337)
			(xy 240.551674 -292.800323) (xy 240.488884 -292.788345) (xy 240.428091 -292.768592) (xy 240.370252 -292.741375)
			(xy 240.316281 -292.707124) (xy 240.267028 -292.666379) (xy 240.223271 -292.619782) (xy 240.185698 -292.568067)
			(xy 240.154904 -292.512052) (xy 240.131372 -292.452619) (xy 240.115475 -292.390705) (xy 240.107464 -292.327287)
			(xy 234.66333 -292.327287) (xy 234.640438 -292.347123) (xy 234.594588 -292.37659) (xy 234.545012 -292.399232)
			(xy 234.492718 -292.414588) (xy 234.438771 -292.422347) (xy 234.41152 -292.422834) (xy 234.382602 -292.422326)
			(xy 234.32543 -292.413599) (xy 234.270229 -292.39634) (xy 234.218267 -292.370947) (xy 234.170734 -292.338)
			(xy 234.128719 -292.298255) (xy 234.11053 -292.275768) (xy 234.102956 -292.267019) (xy 234.082206 -292.25683)
			(xy 234.070652 -292.25621) (xy 233.990388 -292.25621) (xy 233.978819 -292.25677) (xy 233.958048 -292.266972)
			(xy 233.95051 -292.275768) (xy 233.935732 -292.294168) (xy 233.902361 -292.327538) (xy 233.883962 -292.342316)
			(xy 233.875191 -292.349869) (xy 233.865014 -292.370635) (xy 233.864404 -292.382194) (xy 233.864404 -292.462458)
			(xy 233.864997 -292.474023) (xy 233.875175 -292.494794) (xy 233.883962 -292.502336) (xy 233.906455 -292.520516)
			(xy 233.946191 -292.562537) (xy 233.97913 -292.610074) (xy 234.004517 -292.662037) (xy 234.021771 -292.717237)
			(xy 234.030496 -292.774409) (xy 234.031028 -292.803326) (xy 234.030461 -292.833588) (xy 234.020913 -292.893354)
			(xy 234.002043 -292.950862) (xy 233.974326 -293.004667) (xy 233.95686 -293.029386) (xy 233.951272 -293.037006)
			(xy 233.946192 -293.05504) (xy 233.95432 -293.141146) (xy 233.962702 -293.157656) (xy 233.96956 -293.16426)
			(xy 233.991188 -293.184921) (xy 234.029984 -293.230449) (xy 234.063171 -293.280213) (xy 234.090289 -293.333528)
			(xy 234.110965 -293.389657) (xy 234.124912 -293.447823) (xy 234.131938 -293.507224) (xy 234.132374 -293.537132)
			(xy 234.131872 -293.569093) (xy 234.123861 -293.632511) (xy 234.118285 -293.654226) (xy 239.602262 -293.654226)
			(xy 239.606333 -293.598604) (xy 239.618459 -293.544167) (xy 239.638382 -293.492076) (xy 239.665678 -293.443441)
			(xy 239.699764 -293.399298) (xy 239.739913 -293.360589) (xy 239.785271 -293.328138) (xy 239.834871 -293.302637)
			(xy 239.887655 -293.28463) (xy 239.942498 -293.2745) (xy 239.998232 -293.272463) (xy 240.053669 -293.278563)
			(xy 240.107626 -293.292669) (xy 240.158955 -293.314481) (xy 240.206561 -293.343535) (xy 240.249429 -293.37921)
			(xy 240.286646 -293.420747) (xy 240.317419 -293.46726) (xy 240.341091 -293.517757) (xy 240.357159 -293.571164)
			(xy 240.365279 -293.62634) (xy 240.365788 -293.654226) (xy 240.365279 -293.682112) (xy 240.357159 -293.737288)
			(xy 240.341091 -293.790695) (xy 240.317419 -293.841192) (xy 240.286646 -293.887705) (xy 240.249429 -293.929242)
			(xy 240.206561 -293.964917) (xy 240.158955 -293.993971) (xy 240.107626 -294.015783) (xy 240.053669 -294.029889)
			(xy 239.998232 -294.035989) (xy 239.942498 -294.033952) (xy 239.887655 -294.023822) (xy 239.834871 -294.005815)
			(xy 239.785271 -293.980314) (xy 239.739913 -293.947863) (xy 239.699764 -293.909154) (xy 239.665678 -293.865011)
			(xy 239.638382 -293.816376) (xy 239.618459 -293.764285) (xy 239.606333 -293.709848) (xy 239.602262 -293.654226)
			(xy 234.118285 -293.654226) (xy 234.107964 -293.694425) (xy 234.084432 -293.753858) (xy 234.053638 -293.809873)
			(xy 234.016065 -293.861588) (xy 233.972308 -293.908185) (xy 233.923055 -293.94893) (xy 233.869084 -293.983181)
			(xy 233.811245 -294.010398) (xy 233.750452 -294.030151) (xy 233.687662 -294.042129) (xy 233.623866 -294.046143)
			(xy 233.56007 -294.042129) (xy 233.49728 -294.030151) (xy 233.436487 -294.010398) (xy 233.378648 -293.983181)
			(xy 233.324677 -293.94893) (xy 233.275424 -293.908185) (xy 233.231667 -293.861588) (xy 233.194094 -293.809873)
			(xy 233.1633 -293.753858) (xy 233.139768 -293.694425) (xy 233.123871 -293.632511) (xy 233.11586 -293.569093)
			(xy 233.115358 -293.537132) (xy 233.115864 -293.504671) (xy 233.124113 -293.440276) (xy 233.140494 -293.377455)
			(xy 233.16474 -293.317231) (xy 233.196457 -293.260584) (xy 233.235128 -293.208436) (xy 233.280123 -293.161637)
			(xy 233.305096 -293.140892) (xy 233.312462 -293.13505) (xy 233.32186 -293.119048) (xy 233.336084 -293.033704)
			(xy 233.332274 -293.015416) (xy 233.327194 -293.007542) (xy 233.313192 -292.984517) (xy 233.29107 -292.935379)
			(xy 233.276067 -292.883622) (xy 233.268482 -292.83027) (xy 233.268012 -292.803326) (xy 233.268545 -292.77441)
			(xy 233.27727 -292.717239) (xy 233.294525 -292.66204) (xy 233.319914 -292.610078) (xy 233.352855 -292.562544)
			(xy 233.392594 -292.520527) (xy 233.415078 -292.502336) (xy 233.423832 -292.494767) (xy 233.434017 -292.474013)
			(xy 233.434636 -292.462458) (xy 233.434636 -292.382194) (xy 233.434091 -292.370622) (xy 233.423881 -292.34985)
			(xy 233.415078 -292.342316) (xy 233.392598 -292.324122) (xy 233.352863 -292.282102) (xy 233.319924 -292.234567)
			(xy 233.294536 -292.182607) (xy 233.277279 -292.12741) (xy 233.268548 -292.070242) (xy 233.268012 -292.041326)
			(xy 233.268527 -292.01407) (xy 233.27629 -291.960113) (xy 233.291647 -291.907808) (xy 233.314286 -291.858219)
			(xy 233.343747 -291.812353) (xy 233.379431 -291.771143) (xy 233.420613 -291.735427) (xy 233.443272 -291.72027)
			(xy 233.450274 -291.715463) (xy 233.460787 -291.702132) (xy 233.466335 -291.686087) (xy 233.46664 -291.677598)
			(xy 233.46664 -291.592254) (xy 233.466315 -291.583775) (xy 233.460724 -291.567763) (xy 233.450231 -291.554438)
			(xy 233.443272 -291.549582) (xy 233.420636 -291.534393) (xy 233.379452 -291.498683) (xy 233.343767 -291.457477)
			(xy 233.314307 -291.411614) (xy 233.29167 -291.362027) (xy 233.276318 -291.309724) (xy 233.268561 -291.255769)
			(xy 233.268559 -291.201259) (xy 233.276312 -291.147304) (xy 233.29166 -291.094999) (xy 233.314293 -291.04541)
			(xy 233.34375 -290.999546) (xy 233.379432 -290.958337) (xy 233.420613 -290.922624) (xy 233.443272 -290.90747)
			(xy 233.450274 -290.902663) (xy 233.460787 -290.889332) (xy 233.466335 -290.873287) (xy 233.46664 -290.864798)
			(xy 233.46664 -290.779454) (xy 233.466315 -290.770975) (xy 233.460724 -290.754963) (xy 233.450231 -290.741638)
			(xy 233.443272 -290.736782) (xy 233.420575 -290.721676) (xy 233.379382 -290.68596) (xy 233.34369 -290.644745)
			(xy 233.314225 -290.598871) (xy 233.291589 -290.549271) (xy 233.27624 -290.496955) (xy 233.268493 -290.442987)
			(xy 233.268012 -290.415726) (xy 233.268416 -290.389345) (xy 233.275679 -290.337086) (xy 233.290069 -290.286324)
			(xy 233.311314 -290.238029) (xy 233.339007 -290.193119) (xy 233.372622 -290.152451) (xy 233.411517 -290.1168)
			(xy 233.454951 -290.086846) (xy 233.478324 -290.074604) (xy 233.491532 -290.068254) (xy 233.506518 -290.04387)
			(xy 233.506518 -289.923982) (xy 233.491532 -289.899598) (xy 233.478324 -289.893248) (xy 233.454701 -289.880863)
			(xy 233.410838 -289.850516) (xy 233.371625 -289.81436) (xy 233.337824 -289.7731) (xy 233.310093 -289.727539)
			(xy 233.288972 -289.678561) (xy 233.281474 -289.652964) (xy 233.278172 -289.640518) (xy 233.2609 -289.62223)
			(xy 233.156252 -289.587432) (xy 233.131614 -289.59175) (xy 233.121454 -289.599624) (xy 233.101322 -289.61477)
			(xy 233.057794 -289.640138) (xy 233.011303 -289.659549) (xy 232.962659 -289.672663) (xy 232.912711 -289.679253)
			(xy 232.88752 -289.679634) (xy 232.860268 -289.67912) (xy 232.806319 -289.671366) (xy 232.754022 -289.656013)
			(xy 232.704443 -289.633373) (xy 232.65859 -289.603907) (xy 232.617398 -289.568216) (xy 232.581705 -289.527026)
			(xy 232.552237 -289.481175) (xy 232.529594 -289.431597) (xy 232.514238 -289.379301) (xy 232.506481 -289.325352)
			(xy 229.572431 -289.325352) (xy 229.57887 -289.330679) (xy 229.622627 -289.377276) (xy 229.6602 -289.428991)
			(xy 229.690994 -289.485006) (xy 229.714526 -289.544439) (xy 229.730423 -289.606353) (xy 229.738434 -289.669771)
			(xy 229.738936 -289.701732) (xy 229.738434 -289.733693) (xy 229.730423 -289.797111) (xy 229.714526 -289.859025)
			(xy 229.690994 -289.918458) (xy 229.6602 -289.974473) (xy 229.622627 -290.026188) (xy 229.57887 -290.072785)
			(xy 229.529617 -290.11353) (xy 229.475646 -290.147781) (xy 229.417807 -290.174998) (xy 229.357014 -290.194751)
			(xy 229.294224 -290.206729) (xy 229.230428 -290.210743) (xy 229.166632 -290.206729) (xy 229.103842 -290.194751)
			(xy 229.043049 -290.174998) (xy 228.98521 -290.147781) (xy 228.931239 -290.11353) (xy 228.881986 -290.072785)
			(xy 228.838229 -290.026188) (xy 228.800656 -289.974473) (xy 228.769862 -289.918458) (xy 228.74633 -289.859025)
			(xy 228.730433 -289.797111) (xy 228.722422 -289.733693) (xy 224.550424 -289.733693) (xy 224.576102 -289.791367)
			(xy 224.630448 -289.932944) (xy 224.67731 -290.07717) (xy 224.716559 -290.223651) (xy 224.748089 -290.371986)
			(xy 224.771812 -290.521767) (xy 224.787663 -290.672585) (xy 224.7956 -290.824026) (xy 224.796096 -290.89985)
			(xy 224.7956 -290.975674) (xy 224.787663 -291.127115) (xy 224.777432 -291.224462) (xy 228.401624 -291.224462)
			(xy 228.405695 -291.16884) (xy 228.417821 -291.114403) (xy 228.437744 -291.062312) (xy 228.46504 -291.013677)
			(xy 228.499126 -290.969534) (xy 228.539275 -290.930825) (xy 228.584633 -290.898374) (xy 228.634233 -290.872873)
			(xy 228.687017 -290.854866) (xy 228.74186 -290.844736) (xy 228.797594 -290.842699) (xy 228.853031 -290.848799)
			(xy 228.906988 -290.862905) (xy 228.958317 -290.884717) (xy 229.005923 -290.913771) (xy 229.048791 -290.949446)
			(xy 229.086008 -290.990983) (xy 229.116781 -291.037496) (xy 229.140453 -291.087993) (xy 229.156521 -291.1414)
			(xy 229.164641 -291.196576) (xy 229.16515 -291.224462) (xy 229.164641 -291.252348) (xy 229.156521 -291.307524)
			(xy 229.140453 -291.360931) (xy 229.116781 -291.411428) (xy 229.086008 -291.457941) (xy 229.048791 -291.499478)
			(xy 229.005923 -291.535153) (xy 228.958317 -291.564207) (xy 228.906988 -291.586019) (xy 228.853031 -291.600125)
			(xy 228.797594 -291.606225) (xy 228.74186 -291.604188) (xy 228.687017 -291.594058) (xy 228.634233 -291.576051)
			(xy 228.584633 -291.55055) (xy 228.539275 -291.518099) (xy 228.499126 -291.47939) (xy 228.46504 -291.435247)
			(xy 228.437744 -291.386612) (xy 228.417821 -291.334521) (xy 228.405695 -291.280084) (xy 228.401624 -291.224462)
			(xy 224.777432 -291.224462) (xy 224.771812 -291.277933) (xy 224.748089 -291.427714) (xy 224.716559 -291.576049)
			(xy 224.67731 -291.72253) (xy 224.630448 -291.866756) (xy 224.576102 -292.008333) (xy 224.514421 -292.14687)
			(xy 224.445574 -292.28199) (xy 224.419422 -292.327287) (xy 228.163114 -292.327287) (xy 228.163114 -292.263365)
			(xy 228.171125 -292.199947) (xy 228.187022 -292.138033) (xy 228.210554 -292.0786) (xy 228.241348 -292.022585)
			(xy 228.278921 -291.97087) (xy 228.322678 -291.924273) (xy 228.371931 -291.883528) (xy 228.425902 -291.849277)
			(xy 228.483741 -291.82206) (xy 228.544534 -291.802307) (xy 228.607324 -291.790329) (xy 228.67112 -291.786316)
			(xy 228.734916 -291.790329) (xy 228.797706 -291.802307) (xy 228.858499 -291.82206) (xy 228.916338 -291.849277)
			(xy 228.970309 -291.883528) (xy 229.019562 -291.924273) (xy 229.063319 -291.97087) (xy 229.100892 -292.022585)
			(xy 229.131686 -292.0786) (xy 229.155218 -292.138033) (xy 229.171115 -292.199947) (xy 229.179126 -292.263365)
			(xy 229.179628 -292.295326) (xy 229.179126 -292.327287) (xy 229.171115 -292.390705) (xy 229.155218 -292.452619)
			(xy 229.131686 -292.512052) (xy 229.100892 -292.568067) (xy 229.063319 -292.619782) (xy 229.019562 -292.666379)
			(xy 228.970309 -292.707124) (xy 228.916338 -292.741375) (xy 228.858499 -292.768592) (xy 228.797706 -292.788345)
			(xy 228.734916 -292.800323) (xy 228.67112 -292.804337) (xy 228.607324 -292.800323) (xy 228.544534 -292.788345)
			(xy 228.483741 -292.768592) (xy 228.425902 -292.741375) (xy 228.371931 -292.707124) (xy 228.322678 -292.666379)
			(xy 228.278921 -292.619782) (xy 228.241348 -292.568067) (xy 228.210554 -292.512052) (xy 228.187022 -292.452619)
			(xy 228.171125 -292.390705) (xy 228.163114 -292.327287) (xy 224.419422 -292.327287) (xy 224.369749 -292.413322)
			(xy 224.287156 -292.540505) (xy 224.198019 -292.663191) (xy 224.102583 -292.781044) (xy 224.001111 -292.893741)
			(xy 223.893879 -293.000973) (xy 223.781182 -293.102445) (xy 223.663329 -293.197881) (xy 223.540643 -293.287018)
			(xy 223.41346 -293.369611) (xy 223.282128 -293.445436) (xy 223.147008 -293.514283) (xy 223.008471 -293.575964)
			(xy 222.866894 -293.63031) (xy 222.793288 -293.654226) (xy 227.647498 -293.654226) (xy 227.651569 -293.598604)
			(xy 227.663695 -293.544167) (xy 227.683618 -293.492076) (xy 227.710914 -293.443441) (xy 227.745 -293.399298)
			(xy 227.785149 -293.360589) (xy 227.830507 -293.328138) (xy 227.880107 -293.302637) (xy 227.932891 -293.28463)
			(xy 227.987734 -293.2745) (xy 228.043468 -293.272463) (xy 228.098905 -293.278563) (xy 228.152862 -293.292669)
			(xy 228.204191 -293.314481) (xy 228.251797 -293.343535) (xy 228.294665 -293.37921) (xy 228.331882 -293.420747)
			(xy 228.362655 -293.46726) (xy 228.386327 -293.517757) (xy 228.402395 -293.571164) (xy 228.410515 -293.62634)
			(xy 228.411024 -293.654226) (xy 228.410515 -293.682112) (xy 228.402395 -293.737288) (xy 228.386327 -293.790695)
			(xy 228.362655 -293.841192) (xy 228.331882 -293.887705) (xy 228.294665 -293.929242) (xy 228.251797 -293.964917)
			(xy 228.204191 -293.993971) (xy 228.152862 -294.015783) (xy 228.098905 -294.029889) (xy 228.043468 -294.035989)
			(xy 227.987734 -294.033952) (xy 227.932891 -294.023822) (xy 227.880107 -294.005815) (xy 227.830507 -293.980314)
			(xy 227.785149 -293.947863) (xy 227.745 -293.909154) (xy 227.710914 -293.865011) (xy 227.683618 -293.816376)
			(xy 227.663695 -293.764285) (xy 227.651569 -293.709848) (xy 227.647498 -293.654226) (xy 222.793288 -293.654226)
			(xy 222.722668 -293.677172) (xy 222.576187 -293.716421) (xy 222.427852 -293.747951) (xy 222.278071 -293.771674)
			(xy 222.127253 -293.787525) (xy 221.975812 -293.795462) (xy 221.824164 -293.795462) (xy 221.672723 -293.787525)
			(xy 221.521905 -293.771674) (xy 221.372124 -293.747951) (xy 221.223789 -293.716421) (xy 221.077308 -293.677172)
			(xy 220.933082 -293.63031) (xy 220.791505 -293.575964) (xy 220.652968 -293.514283) (xy 220.517848 -293.445436)
			(xy 220.386516 -293.369611) (xy 220.259333 -293.287018) (xy 220.136647 -293.197881) (xy 220.018794 -293.102445)
			(xy 219.906097 -293.000973) (xy 219.798865 -292.893741) (xy 219.697393 -292.781044) (xy 219.601957 -292.663191)
			(xy 219.51282 -292.540505) (xy 219.430227 -292.413322) (xy 219.354402 -292.28199) (xy 219.285555 -292.14687)
			(xy 219.223874 -292.008333) (xy 219.169528 -291.866756) (xy 219.122666 -291.72253) (xy 219.083417 -291.576049)
			(xy 219.051887 -291.427714) (xy 219.028164 -291.277933) (xy 219.012313 -291.127115) (xy 219.004376 -290.975674)
			(xy 218.193874 -290.975674) (xy 218.193874 -294.277796) (xy 229.862124 -294.277796) (xy 229.866195 -294.222174)
			(xy 229.878321 -294.167737) (xy 229.898244 -294.115646) (xy 229.92554 -294.067011) (xy 229.959626 -294.022868)
			(xy 229.999775 -293.984159) (xy 230.045133 -293.951708) (xy 230.094733 -293.926207) (xy 230.147517 -293.9082)
			(xy 230.20236 -293.89807) (xy 230.258094 -293.896033) (xy 230.313531 -293.902133) (xy 230.367488 -293.916239)
			(xy 230.418817 -293.938051) (xy 230.466423 -293.967105) (xy 230.509291 -294.00278) (xy 230.546508 -294.044317)
			(xy 230.577281 -294.09083) (xy 230.600953 -294.141327) (xy 230.617021 -294.194734) (xy 230.625141 -294.24991)
			(xy 230.62565 -294.277796) (xy 241.806474 -294.277796) (xy 241.810545 -294.222174) (xy 241.822671 -294.167737)
			(xy 241.842594 -294.115646) (xy 241.86989 -294.067011) (xy 241.903976 -294.022868) (xy 241.944125 -293.984159)
			(xy 241.989483 -293.951708) (xy 242.039083 -293.926207) (xy 242.091867 -293.9082) (xy 242.14671 -293.89807)
			(xy 242.202444 -293.896033) (xy 242.257881 -293.902133) (xy 242.311838 -293.916239) (xy 242.363167 -293.938051)
			(xy 242.410773 -293.967105) (xy 242.453641 -294.00278) (xy 242.490858 -294.044317) (xy 242.521631 -294.09083)
			(xy 242.545303 -294.141327) (xy 242.561371 -294.194734) (xy 242.569491 -294.24991) (xy 242.57 -294.277796)
			(xy 242.569491 -294.305682) (xy 242.561371 -294.360858) (xy 242.545303 -294.414265) (xy 242.521631 -294.464762)
			(xy 242.490858 -294.511275) (xy 242.453641 -294.552812) (xy 242.410773 -294.588487) (xy 242.363167 -294.617541)
			(xy 242.311838 -294.639353) (xy 242.257881 -294.653459) (xy 242.202444 -294.659559) (xy 242.14671 -294.657522)
			(xy 242.091867 -294.647392) (xy 242.039083 -294.629385) (xy 241.989483 -294.603884) (xy 241.944125 -294.571433)
			(xy 241.903976 -294.532724) (xy 241.86989 -294.488581) (xy 241.842594 -294.439946) (xy 241.822671 -294.387855)
			(xy 241.810545 -294.333418) (xy 241.806474 -294.277796) (xy 230.62565 -294.277796) (xy 230.625141 -294.305682)
			(xy 230.617021 -294.360858) (xy 230.600953 -294.414265) (xy 230.577281 -294.464762) (xy 230.546508 -294.511275)
			(xy 230.509291 -294.552812) (xy 230.466423 -294.588487) (xy 230.418817 -294.617541) (xy 230.367488 -294.639353)
			(xy 230.313531 -294.653459) (xy 230.258094 -294.659559) (xy 230.20236 -294.657522) (xy 230.147517 -294.647392)
			(xy 230.094733 -294.629385) (xy 230.045133 -294.603884) (xy 229.999775 -294.571433) (xy 229.959626 -294.532724)
			(xy 229.92554 -294.488581) (xy 229.898244 -294.439946) (xy 229.878321 -294.387855) (xy 229.866195 -294.333418)
			(xy 229.862124 -294.277796) (xy 218.193874 -294.277796) (xy 218.193874 -311.28208) (xy 225.10623 -311.28208)
			(xy 225.106647 -311.251864) (xy 225.113837 -311.19186) (xy 225.12809 -311.133132) (xy 225.149205 -311.076508)
			(xy 225.176883 -311.022787) (xy 225.210736 -310.972725) (xy 225.230182 -310.949594) (xy 225.235808 -310.942457)
			(xy 225.242052 -310.925403) (xy 225.242374 -310.91632) (xy 225.242374 -310.88584) (xy 225.242063 -310.876757)
			(xy 225.235806 -310.859706) (xy 225.230182 -310.852566) (xy 225.21074 -310.829433) (xy 225.1769 -310.779367)
			(xy 225.149232 -310.725643) (xy 225.128123 -310.66902) (xy 225.113872 -310.610295) (xy 225.106679 -310.550295)
			(xy 225.10623 -310.52008) (xy 225.106647 -310.489864) (xy 225.113837 -310.42986) (xy 225.12809 -310.371132)
			(xy 225.149205 -310.314508) (xy 225.176883 -310.260787) (xy 225.210736 -310.210725) (xy 225.230182 -310.187594)
			(xy 225.235808 -310.180457) (xy 225.242052 -310.163403) (xy 225.242374 -310.15432) (xy 225.242374 -310.12384)
			(xy 225.242063 -310.114757) (xy 225.235806 -310.097706) (xy 225.230182 -310.090566) (xy 225.21074 -310.067433)
			(xy 225.1769 -310.017367) (xy 225.149232 -309.963643) (xy 225.128123 -309.90702) (xy 225.113872 -309.848295)
			(xy 225.106679 -309.788295) (xy 225.10623 -309.75808) (xy 225.106619 -309.727346) (xy 225.114031 -309.666326)
			(xy 225.128744 -309.606645) (xy 225.150543 -309.549173) (xy 225.179112 -309.494747) (xy 225.214032 -309.444162)
			(xy 225.254795 -309.398154) (xy 225.300807 -309.357396) (xy 225.351397 -309.322481) (xy 225.405826 -309.293919)
			(xy 225.463301 -309.272126) (xy 225.522984 -309.25742) (xy 225.584004 -309.250015) (xy 225.614738 -309.249572)
			(xy 225.644953 -309.250027) (xy 225.704955 -309.257209) (xy 225.763683 -309.271453) (xy 225.820307 -309.292561)
			(xy 225.87403 -309.320233) (xy 225.924092 -309.35408) (xy 225.947224 -309.373524) (xy 225.954352 -309.379163)
			(xy 225.971414 -309.385398) (xy 225.980498 -309.385716) (xy 226.010978 -309.385716) (xy 226.020061 -309.385405)
			(xy 226.037112 -309.379147) (xy 226.044252 -309.373524) (xy 226.067383 -309.35408) (xy 226.11745 -309.32024)
			(xy 226.171173 -309.29257) (xy 226.227797 -309.271462) (xy 226.286522 -309.257211) (xy 226.346523 -309.25002)
			(xy 226.376738 -309.249572) (xy 226.407469 -309.25002) (xy 226.468483 -309.257432) (xy 226.528158 -309.272145)
			(xy 226.585625 -309.293942) (xy 226.640046 -309.322507) (xy 226.690627 -309.357423) (xy 226.736632 -309.398181)
			(xy 226.777388 -309.444187) (xy 226.812302 -309.494769) (xy 226.840865 -309.549191) (xy 226.862661 -309.606659)
			(xy 226.877371 -309.666335) (xy 226.884781 -309.727349) (xy 226.885246 -309.75808) (xy 226.884811 -309.788296)
			(xy 226.877625 -309.848299) (xy 226.863376 -309.907027) (xy 226.842265 -309.963651) (xy 226.814589 -310.017373)
			(xy 226.780739 -310.067435) (xy 226.761294 -310.090566) (xy 226.755682 -310.097713) (xy 226.74943 -310.11476)
			(xy 226.749102 -310.12384) (xy 226.749102 -310.15432) (xy 226.749438 -310.163401) (xy 226.755678 -310.180452)
			(xy 226.761294 -310.187594) (xy 226.780714 -310.210745) (xy 226.814556 -310.260807) (xy 226.842229 -310.314527)
			(xy 226.863342 -310.371146) (xy 226.877597 -310.429869) (xy 226.884795 -310.489866) (xy 226.885246 -310.52008)
			(xy 226.884811 -310.550296) (xy 226.877625 -310.610299) (xy 226.863376 -310.669027) (xy 226.842265 -310.725651)
			(xy 226.814589 -310.779373) (xy 226.780739 -310.829435) (xy 226.761294 -310.852566) (xy 226.755682 -310.859713)
			(xy 226.74943 -310.87676) (xy 226.749102 -310.88584) (xy 226.749102 -310.91632) (xy 226.749438 -310.925401)
			(xy 226.755678 -310.942452) (xy 226.761294 -310.949594) (xy 226.780714 -310.972745) (xy 226.814556 -311.022807)
			(xy 226.842229 -311.076527) (xy 226.863342 -311.133146) (xy 226.877597 -311.191869) (xy 226.884795 -311.251866)
			(xy 226.885246 -311.28208) (xy 231.152954 -311.28208) (xy 231.153365 -311.251864) (xy 231.160555 -311.19186)
			(xy 231.174809 -311.133131) (xy 231.195925 -311.076507) (xy 231.223605 -311.022786) (xy 231.257459 -310.972725)
			(xy 231.276906 -310.949594) (xy 231.282535 -310.942459) (xy 231.288777 -310.925403) (xy 231.289098 -310.91632)
			(xy 231.289098 -310.88584) (xy 231.288782 -310.876758) (xy 231.282528 -310.859707) (xy 231.276906 -310.852566)
			(xy 231.257467 -310.82943) (xy 231.223627 -310.779365) (xy 231.195957 -310.725642) (xy 231.174848 -310.669019)
			(xy 231.160596 -310.610294) (xy 231.153403 -310.550295) (xy 231.152954 -310.52008) (xy 231.153365 -310.489864)
			(xy 231.160555 -310.42986) (xy 231.174809 -310.371131) (xy 231.195925 -310.314507) (xy 231.223605 -310.260786)
			(xy 231.257459 -310.210725) (xy 231.276906 -310.187594) (xy 231.282535 -310.180459) (xy 231.288777 -310.163403)
			(xy 231.289098 -310.15432) (xy 231.289098 -310.12384) (xy 231.288782 -310.114758) (xy 231.282528 -310.097707)
			(xy 231.276906 -310.090566) (xy 231.257467 -310.06743) (xy 231.223627 -310.017365) (xy 231.195957 -309.963642)
			(xy 231.174848 -309.907019) (xy 231.160596 -309.848294) (xy 231.153403 -309.788295) (xy 231.152954 -309.75808)
			(xy 231.153437 -309.72735) (xy 231.160847 -309.666338) (xy 231.175557 -309.606665) (xy 231.197352 -309.549199)
			(xy 231.225914 -309.494779) (xy 231.260827 -309.444198) (xy 231.301582 -309.398194) (xy 231.347584 -309.357438)
			(xy 231.398164 -309.322523) (xy 231.452583 -309.293959) (xy 231.510048 -309.272162) (xy 231.569721 -309.25745)
			(xy 231.630732 -309.250038) (xy 231.661462 -309.249572) (xy 231.691678 -309.250013) (xy 231.75168 -309.257197)
			(xy 231.810408 -309.271445) (xy 231.867033 -309.292555) (xy 231.920755 -309.32023) (xy 231.970817 -309.354079)
			(xy 231.993948 -309.373524) (xy 232.001098 -309.37913) (xy 232.018143 -309.385385) (xy 232.027222 -309.385716)
			(xy 232.057702 -309.385716) (xy 232.066781 -309.385368) (xy 232.083832 -309.379136) (xy 232.090976 -309.373524)
			(xy 232.114098 -309.354068) (xy 232.164166 -309.32023) (xy 232.217892 -309.292562) (xy 232.274517 -309.271455)
			(xy 232.333245 -309.257207) (xy 232.393247 -309.250019) (xy 232.423462 -309.249572) (xy 232.454193 -309.250073)
			(xy 232.515206 -309.257477) (xy 232.574882 -309.272182) (xy 232.632351 -309.293972) (xy 232.686773 -309.322531)
			(xy 232.737357 -309.357442) (xy 232.783364 -309.398195) (xy 232.824122 -309.444197) (xy 232.859039 -309.494777)
			(xy 232.887604 -309.549196) (xy 232.909401 -309.606663) (xy 232.924112 -309.666337) (xy 232.931523 -309.72735)
			(xy 232.93197 -309.75808) (xy 232.93153 -309.788295) (xy 232.924344 -309.848298) (xy 232.910096 -309.907026)
			(xy 232.888985 -309.96365) (xy 232.861311 -310.017372) (xy 232.827463 -310.067434) (xy 232.808018 -310.090566)
			(xy 232.802409 -310.097715) (xy 232.796155 -310.11476) (xy 232.795826 -310.12384) (xy 232.795826 -310.15432)
			(xy 232.796157 -310.163401) (xy 232.8024 -310.180452) (xy 232.808018 -310.187594) (xy 232.827442 -310.210742)
			(xy 232.861283 -310.260805) (xy 232.888954 -310.314525) (xy 232.910066 -310.371145) (xy 232.924321 -310.429868)
			(xy 232.931519 -310.489866) (xy 232.93197 -310.52008) (xy 232.93153 -310.550295) (xy 232.924344 -310.610298)
			(xy 232.910096 -310.669026) (xy 232.888985 -310.72565) (xy 232.861311 -310.779372) (xy 232.827463 -310.829434)
			(xy 232.808018 -310.852566) (xy 232.802409 -310.859715) (xy 232.796155 -310.87676) (xy 232.795826 -310.88584)
			(xy 232.795826 -310.91632) (xy 232.796157 -310.925401) (xy 232.8024 -310.942452) (xy 232.808018 -310.949594)
			(xy 232.827442 -310.972742) (xy 232.861283 -311.022805) (xy 232.888954 -311.076525) (xy 232.910066 -311.133145)
			(xy 232.924321 -311.191868) (xy 232.931519 -311.251866) (xy 232.93197 -311.28208) (xy 239.039146 -311.28208)
			(xy 239.039559 -311.251864) (xy 239.046749 -311.19186) (xy 239.061003 -311.133132) (xy 239.082118 -311.076508)
			(xy 239.109798 -311.022786) (xy 239.143651 -310.972725) (xy 239.163098 -310.949594) (xy 239.168726 -310.942458)
			(xy 239.174969 -310.925403) (xy 239.17529 -310.91632) (xy 239.17529 -310.88584) (xy 239.174975 -310.876757)
			(xy 239.168721 -310.859706) (xy 239.163098 -310.852566) (xy 239.143658 -310.829431) (xy 239.109818 -310.779365)
			(xy 239.082149 -310.725643) (xy 239.06104 -310.66902) (xy 239.046788 -310.610295) (xy 239.039595 -310.550295)
			(xy 239.039146 -310.52008) (xy 239.039559 -310.489864) (xy 239.046749 -310.42986) (xy 239.061003 -310.371132)
			(xy 239.082118 -310.314508) (xy 239.109798 -310.260786) (xy 239.143651 -310.210725) (xy 239.163098 -310.187594)
			(xy 239.168726 -310.180458) (xy 239.174969 -310.163403) (xy 239.17529 -310.15432) (xy 239.17529 -310.12384)
			(xy 239.174975 -310.114757) (xy 239.168721 -310.097706) (xy 239.163098 -310.090566) (xy 239.143658 -310.067431)
			(xy 239.109818 -310.017365) (xy 239.082149 -309.963643) (xy 239.06104 -309.90702) (xy 239.046788 -309.848295)
			(xy 239.039595 -309.788295) (xy 239.039146 -309.75808) (xy 239.039637 -309.72735) (xy 239.047047 -309.666339)
			(xy 239.061756 -309.606666) (xy 239.083551 -309.549201) (xy 239.112112 -309.494781) (xy 239.147025 -309.444201)
			(xy 239.187779 -309.398197) (xy 239.23378 -309.357441) (xy 239.284359 -309.322526) (xy 239.338777 -309.293961)
			(xy 239.396241 -309.272164) (xy 239.455914 -309.257452) (xy 239.516924 -309.250039) (xy 239.547654 -309.249572)
			(xy 239.577869 -309.250018) (xy 239.637872 -309.257201) (xy 239.6966 -309.271448) (xy 239.753224 -309.292557)
			(xy 239.806946 -309.320231) (xy 239.857008 -309.354079) (xy 239.88014 -309.373524) (xy 239.887293 -309.379127)
			(xy 239.904335 -309.385384) (xy 239.913414 -309.385716) (xy 239.943894 -309.385716) (xy 239.952973 -309.385364)
			(xy 239.970024 -309.379135) (xy 239.977168 -309.373524) (xy 240.000293 -309.354072) (xy 240.050361 -309.320233)
			(xy 240.104086 -309.292565) (xy 240.16071 -309.271458) (xy 240.219437 -309.257209) (xy 240.279439 -309.250019)
			(xy 240.309654 -309.249572) (xy 240.340384 -309.250081) (xy 240.401398 -309.257484) (xy 240.461074 -309.272187)
			(xy 240.518542 -309.293977) (xy 240.572965 -309.322535) (xy 240.623548 -309.357445) (xy 240.669555 -309.398198)
			(xy 240.710314 -309.4442) (xy 240.745231 -309.494779) (xy 240.773796 -309.549198) (xy 240.795593 -309.606663)
			(xy 240.810304 -309.666337) (xy 240.817715 -309.72735) (xy 240.818162 -309.75808) (xy 240.817724 -309.788296)
			(xy 240.810538 -309.848298) (xy 240.796289 -309.907026) (xy 240.775178 -309.96365) (xy 240.747504 -310.017372)
			(xy 240.713655 -310.067434) (xy 240.69421 -310.090566) (xy 240.6886 -310.097714) (xy 240.682346 -310.11476)
			(xy 240.682018 -310.12384) (xy 240.682018 -310.15432) (xy 240.68235 -310.163401) (xy 240.688593 -310.180452)
			(xy 240.69421 -310.187594) (xy 240.713632 -310.210743) (xy 240.747474 -310.260806) (xy 240.775146 -310.314526)
			(xy 240.796258 -310.371146) (xy 240.810513 -310.429868) (xy 240.817711 -310.489866) (xy 240.818162 -310.52008)
			(xy 240.817724 -310.550296) (xy 240.810538 -310.610298) (xy 240.796289 -310.669026) (xy 240.775178 -310.72565)
			(xy 240.747504 -310.779372) (xy 240.713655 -310.829434) (xy 240.69421 -310.852566) (xy 240.6886 -310.859714)
			(xy 240.682346 -310.87676) (xy 240.682018 -310.88584) (xy 240.682018 -310.91632) (xy 240.68235 -310.925401)
			(xy 240.688593 -310.942452) (xy 240.69421 -310.949594) (xy 240.713632 -310.972743) (xy 240.747474 -311.022806)
			(xy 240.775146 -311.076526) (xy 240.796258 -311.133146) (xy 240.810513 -311.191868) (xy 240.817711 -311.251866)
			(xy 240.818162 -311.28208) (xy 245.08587 -311.28208) (xy 245.086277 -311.251863) (xy 245.093468 -311.191859)
			(xy 245.107722 -311.133131) (xy 245.128839 -311.076507) (xy 245.156519 -311.022785) (xy 245.190374 -310.972725)
			(xy 245.209822 -310.949594) (xy 245.215453 -310.94246) (xy 245.221693 -310.925403) (xy 245.222014 -310.91632)
			(xy 245.222014 -310.88584) (xy 245.221694 -310.876758) (xy 245.215442 -310.859707) (xy 245.209822 -310.852566)
			(xy 245.190386 -310.829428) (xy 245.156545 -310.779363) (xy 245.128874 -310.725641) (xy 245.107764 -310.669019)
			(xy 245.093512 -310.610294) (xy 245.086319 -310.550294) (xy 245.08587 -310.52008) (xy 245.086277 -310.489863)
			(xy 245.093468 -310.429859) (xy 245.107722 -310.371131) (xy 245.128839 -310.314507) (xy 245.156519 -310.260785)
			(xy 245.190374 -310.210725) (xy 245.209822 -310.187594) (xy 245.215453 -310.18046) (xy 245.221693 -310.163403)
			(xy 245.222014 -310.15432) (xy 245.222014 -310.12384) (xy 245.221694 -310.114758) (xy 245.215442 -310.097707)
			(xy 245.209822 -310.090566) (xy 245.190386 -310.067428) (xy 245.156545 -310.017363) (xy 245.128874 -309.963641)
			(xy 245.107764 -309.907019) (xy 245.093512 -309.848294) (xy 245.086319 -309.788294) (xy 245.08587 -309.75808)
			(xy 245.086337 -309.727349) (xy 245.093748 -309.666337) (xy 245.108458 -309.606662) (xy 245.130253 -309.549195)
			(xy 245.158817 -309.494774) (xy 245.193731 -309.444193) (xy 245.234487 -309.398189) (xy 245.280491 -309.357432)
			(xy 245.331073 -309.322518) (xy 245.385493 -309.293954) (xy 245.44296 -309.272158) (xy 245.502635 -309.257448)
			(xy 245.563647 -309.250037) (xy 245.594378 -309.249572) (xy 245.624594 -309.250003) (xy 245.684597 -309.257189)
			(xy 245.743325 -309.271439) (xy 245.799949 -309.292551) (xy 245.853671 -309.320227) (xy 245.903733 -309.354078)
			(xy 245.926864 -309.373524) (xy 245.93401 -309.379137) (xy 245.951058 -309.385388) (xy 245.960138 -309.385716)
			(xy 245.990618 -309.385716) (xy 245.999698 -309.385376) (xy 246.016749 -309.379138) (xy 246.023892 -309.373524)
			(xy 246.047046 -309.354108) (xy 246.097107 -309.320265) (xy 246.150826 -309.292591) (xy 246.207445 -309.271478)
			(xy 246.266167 -309.257221) (xy 246.326164 -309.250023) (xy 246.356378 -309.249572) (xy 246.387109 -309.250058)
			(xy 246.448123 -309.257464) (xy 246.507799 -309.27217) (xy 246.565268 -309.293962) (xy 246.619691 -309.322523)
			(xy 246.670274 -309.357435) (xy 246.716281 -309.39819) (xy 246.757039 -309.444193) (xy 246.791955 -309.494773)
			(xy 246.82052 -309.549194) (xy 246.842317 -309.606661) (xy 246.857028 -309.666336) (xy 246.864439 -309.727349)
			(xy 246.864886 -309.75808) (xy 246.864442 -309.788295) (xy 246.857256 -309.848298) (xy 246.843008 -309.907025)
			(xy 246.821899 -309.963649) (xy 246.794225 -310.017371) (xy 246.760378 -310.067434) (xy 246.740934 -310.090566)
			(xy 246.735315 -310.097707) (xy 246.729069 -310.114759) (xy 246.728742 -310.12384) (xy 246.728742 -310.15432)
			(xy 246.729069 -310.163401) (xy 246.735314 -310.180453) (xy 246.740934 -310.187594) (xy 246.76036 -310.21074)
			(xy 246.794201 -310.260804) (xy 246.821872 -310.314524) (xy 246.842983 -310.371145) (xy 246.857238 -310.429868)
			(xy 246.864435 -310.489866) (xy 246.864886 -310.52008) (xy 246.864442 -310.550295) (xy 246.857256 -310.610298)
			(xy 246.843008 -310.669025) (xy 246.821899 -310.725649) (xy 246.794225 -310.779371) (xy 246.760378 -310.829434)
			(xy 246.740934 -310.852566) (xy 246.735315 -310.859707) (xy 246.729069 -310.876759) (xy 246.728742 -310.88584)
			(xy 246.728742 -310.91632) (xy 246.729069 -310.925401) (xy 246.735314 -310.942453) (xy 246.740934 -310.949594)
			(xy 246.76036 -310.97274) (xy 246.794201 -311.022804) (xy 246.821872 -311.076524) (xy 246.842983 -311.133145)
			(xy 246.857238 -311.191868) (xy 246.864435 -311.251866) (xy 246.864886 -311.28208) (xy 246.864444 -311.312813)
			(xy 246.857037 -311.37383) (xy 246.842329 -311.433509) (xy 246.820534 -311.49098) (xy 246.791971 -311.545405)
			(xy 246.757055 -311.59599) (xy 246.716296 -311.641998) (xy 246.670289 -311.682756) (xy 246.619704 -311.717672)
			(xy 246.565278 -311.746235) (xy 246.507807 -311.768029) (xy 246.448128 -311.782737) (xy 246.387111 -311.790144)
			(xy 246.356378 -311.790588) (xy 246.326162 -311.790168) (xy 246.266159 -311.782978) (xy 246.207431 -311.768725)
			(xy 246.150807 -311.747611) (xy 246.097085 -311.719933) (xy 246.047024 -311.686082) (xy 246.023892 -311.666636)
			(xy 246.016762 -311.660999) (xy 245.999702 -311.654764) (xy 245.990618 -311.654444) (xy 245.960138 -311.654444)
			(xy 245.951054 -311.65475) (xy 245.934003 -311.66101) (xy 245.926864 -311.666636) (xy 245.903735 -311.686082)
			(xy 245.853667 -311.71992) (xy 245.799943 -311.747588) (xy 245.743319 -311.768696) (xy 245.684593 -311.782947)
			(xy 245.624593 -311.790139) (xy 245.594378 -311.790588) (xy 245.563646 -311.790165) (xy 245.50263 -311.782753)
			(xy 245.442952 -311.768041) (xy 245.385483 -311.746243) (xy 245.33106 -311.717677) (xy 245.280477 -311.682759)
			(xy 245.234472 -311.641999) (xy 245.193715 -311.59599) (xy 245.158801 -311.545404) (xy 245.13024 -311.490979)
			(xy 245.108446 -311.433508) (xy 245.093739 -311.373829) (xy 245.086333 -311.312812) (xy 245.08587 -311.28208)
			(xy 240.818162 -311.28208) (xy 240.817743 -311.312813) (xy 240.810336 -311.373832) (xy 240.795627 -311.433513)
			(xy 240.773831 -311.490986) (xy 240.745266 -311.545412) (xy 240.710349 -311.595998) (xy 240.669588 -311.642006)
			(xy 240.623578 -311.682765) (xy 240.57299 -311.71768) (xy 240.518562 -311.746242) (xy 240.461089 -311.768035)
			(xy 240.401407 -311.782741) (xy 240.340387 -311.790145) (xy 240.309654 -311.790588) (xy 240.279439 -311.790123)
			(xy 240.219438 -311.782942) (xy 240.160711 -311.768698) (xy 240.104087 -311.747592) (xy 240.050364 -311.719922)
			(xy 240.000301 -311.686078) (xy 239.977168 -311.666636) (xy 239.970017 -311.661031) (xy 239.952973 -311.654776)
			(xy 239.943894 -311.654444) (xy 239.913414 -311.654444) (xy 239.904329 -311.654739) (xy 239.887278 -311.661006)
			(xy 239.88014 -311.666636) (xy 239.85702 -311.686094) (xy 239.80695 -311.71993) (xy 239.753224 -311.747597)
			(xy 239.696598 -311.768703) (xy 239.637871 -311.782951) (xy 239.577869 -311.790141) (xy 239.547654 -311.790588)
			(xy 239.516921 -311.790188) (xy 239.455904 -311.782773) (xy 239.396226 -311.768059) (xy 239.338756 -311.746258)
			(xy 239.284334 -311.71769) (xy 239.233751 -311.68277) (xy 239.187746 -311.642007) (xy 239.14699 -311.595997)
			(xy 239.112076 -311.54541) (xy 239.083515 -311.490983) (xy 239.061721 -311.433511) (xy 239.047015 -311.373831)
			(xy 239.039608 -311.312813) (xy 239.039146 -311.28208) (xy 232.93197 -311.28208) (xy 232.931543 -311.312813)
			(xy 232.924136 -311.373831) (xy 232.909428 -311.433512) (xy 232.887632 -311.490984) (xy 232.859068 -311.54541)
			(xy 232.824151 -311.595996) (xy 232.78339 -311.642003) (xy 232.737381 -311.682762) (xy 232.686795 -311.717677)
			(xy 232.632368 -311.74624) (xy 232.574895 -311.768033) (xy 232.515214 -311.78274) (xy 232.454195 -311.790145)
			(xy 232.423462 -311.790588) (xy 232.393247 -311.790118) (xy 232.333246 -311.782938) (xy 232.274519 -311.768695)
			(xy 232.217895 -311.74759) (xy 232.164172 -311.719921) (xy 232.114109 -311.686078) (xy 232.090976 -311.666636)
			(xy 232.083851 -311.660993) (xy 232.066787 -311.654761) (xy 232.057702 -311.654444) (xy 232.027222 -311.654444)
			(xy 232.018138 -311.654742) (xy 232.001086 -311.661007) (xy 231.993948 -311.666636) (xy 231.970825 -311.68609)
			(xy 231.920756 -311.719927) (xy 231.86703 -311.747594) (xy 231.810405 -311.7687) (xy 231.751678 -311.782949)
			(xy 231.691677 -311.79014) (xy 231.661462 -311.790588) (xy 231.630729 -311.79018) (xy 231.569713 -311.782767)
			(xy 231.510035 -311.768053) (xy 231.452565 -311.746253) (xy 231.398142 -311.717686) (xy 231.347559 -311.682766)
			(xy 231.301554 -311.642005) (xy 231.260798 -311.595995) (xy 231.225884 -311.545408) (xy 231.197323 -311.490982)
			(xy 231.17553 -311.43351) (xy 231.160823 -311.37383) (xy 231.153416 -311.312813) (xy 231.152954 -311.28208)
			(xy 226.885246 -311.28208) (xy 226.884725 -311.312809) (xy 226.87732 -311.37382) (xy 226.862615 -311.433493)
			(xy 226.840824 -311.490958) (xy 226.812266 -311.545378) (xy 226.777356 -311.595959) (xy 226.736604 -311.641963)
			(xy 226.690605 -311.68272) (xy 226.640028 -311.717636) (xy 226.585611 -311.7462) (xy 226.528148 -311.767997)
			(xy 226.468477 -311.782709) (xy 226.407467 -311.790122) (xy 226.376738 -311.790588) (xy 226.346523 -311.790133)
			(xy 226.286521 -311.782949) (xy 226.227794 -311.768703) (xy 226.17117 -311.747596) (xy 226.117448 -311.719924)
			(xy 226.067384 -311.686079) (xy 226.044252 -311.666636) (xy 226.037105 -311.661025) (xy 226.020058 -311.654774)
			(xy 226.010978 -311.654444) (xy 225.980498 -311.654444) (xy 225.971417 -311.654779) (xy 225.954366 -311.661019)
			(xy 225.947224 -311.666636) (xy 225.92411 -311.686101) (xy 225.874039 -311.719937) (xy 225.820311 -311.747602)
			(xy 225.763685 -311.768707) (xy 225.704956 -311.782953) (xy 225.644954 -311.790141) (xy 225.614738 -311.790588)
			(xy 225.584006 -311.790127) (xy 225.522989 -311.782722) (xy 225.463311 -311.768016) (xy 225.40584 -311.746223)
			(xy 225.351415 -311.717662) (xy 225.30083 -311.682748) (xy 225.254822 -311.64199) (xy 225.214063 -311.595984)
			(xy 225.179148 -311.545401) (xy 225.150584 -311.490977) (xy 225.128789 -311.433507) (xy 225.114081 -311.373828)
			(xy 225.106674 -311.312812) (xy 225.10623 -311.28208) (xy 218.193874 -311.28208) (xy 218.193874 -313.838844)
			(xy 222.22587 -313.838844) (xy 222.226315 -313.808629) (xy 222.233498 -313.748626) (xy 222.247745 -313.689898)
			(xy 222.268855 -313.633274) (xy 222.296529 -313.579552) (xy 222.330377 -313.52949) (xy 222.349822 -313.506358)
			(xy 222.355426 -313.499206) (xy 222.361682 -313.482163) (xy 222.362014 -313.473084) (xy 222.362014 -313.442604)
			(xy 222.361663 -313.433525) (xy 222.355433 -313.416474) (xy 222.349822 -313.40933) (xy 222.330369 -313.386206)
			(xy 222.29653 -313.336138) (xy 222.268862 -313.282413) (xy 222.247755 -313.225788) (xy 222.233506 -313.167061)
			(xy 222.226317 -313.107059) (xy 222.22587 -313.076844) (xy 222.226315 -313.046629) (xy 222.233498 -312.986626)
			(xy 222.247745 -312.927898) (xy 222.268855 -312.871274) (xy 222.296529 -312.817552) (xy 222.330377 -312.76749)
			(xy 222.349822 -312.744358) (xy 222.355426 -312.737206) (xy 222.361682 -312.720163) (xy 222.362014 -312.711084)
			(xy 222.362014 -312.680604) (xy 222.361663 -312.671525) (xy 222.355433 -312.654474) (xy 222.349822 -312.64733)
			(xy 222.330369 -312.624206) (xy 222.29653 -312.574138) (xy 222.268862 -312.520413) (xy 222.247755 -312.463788)
			(xy 222.233506 -312.405061) (xy 222.226317 -312.345059) (xy 222.22587 -312.314844) (xy 222.226372 -312.282883)
			(xy 222.234383 -312.219465) (xy 222.25028 -312.157551) (xy 222.273812 -312.098118) (xy 222.304606 -312.042103)
			(xy 222.342179 -311.990388) (xy 222.385936 -311.943791) (xy 222.435189 -311.903046) (xy 222.48916 -311.868795)
			(xy 222.546999 -311.841578) (xy 222.607792 -311.821825) (xy 222.670582 -311.809847) (xy 222.734378 -311.805834)
			(xy 222.798174 -311.809847) (xy 222.860964 -311.821825) (xy 222.921757 -311.841578) (xy 222.979596 -311.868795)
			(xy 223.033567 -311.903046) (xy 223.08282 -311.943791) (xy 223.126577 -311.990388) (xy 223.16415 -312.042103)
			(xy 223.194944 -312.098118) (xy 223.218476 -312.157551) (xy 223.234373 -312.219465) (xy 223.242384 -312.282883)
			(xy 223.242886 -312.314844) (xy 223.24242 -312.345059) (xy 223.235239 -312.40506) (xy 223.220995 -312.463787)
			(xy 223.19989 -312.520411) (xy 223.17222 -312.574134) (xy 223.138376 -312.624197) (xy 223.118934 -312.64733)
			(xy 223.11333 -312.654482) (xy 223.107075 -312.671525) (xy 223.106742 -312.680604) (xy 223.106742 -312.711084)
			(xy 223.107038 -312.720169) (xy 223.113305 -312.73722) (xy 223.118934 -312.744358) (xy 223.13839 -312.767479)
			(xy 223.172227 -312.817549) (xy 223.199894 -312.871275) (xy 223.221 -312.9279) (xy 223.235248 -312.986627)
			(xy 223.242438 -313.046629) (xy 223.242886 -313.076844) (xy 223.24242 -313.107059) (xy 223.235239 -313.16706)
			(xy 223.220995 -313.225787) (xy 223.19989 -313.282411) (xy 223.17222 -313.336134) (xy 223.138376 -313.386197)
			(xy 223.118934 -313.40933) (xy 223.11333 -313.416482) (xy 223.107075 -313.433525) (xy 223.106742 -313.442604)
			(xy 223.106742 -313.473084) (xy 223.107038 -313.482169) (xy 223.113305 -313.49922) (xy 223.118934 -313.506358)
			(xy 223.13839 -313.529479) (xy 223.172227 -313.579549) (xy 223.199894 -313.633275) (xy 223.221 -313.6899)
			(xy 223.235248 -313.748627) (xy 223.242438 -313.808629) (xy 223.242886 -313.838844) (xy 223.242459 -313.869219)
			(xy 223.240709 -313.883802) (xy 223.441768 -313.883802) (xy 223.442189 -313.853586) (xy 223.449377 -313.793582)
			(xy 223.463628 -313.734854) (xy 223.484742 -313.67823) (xy 223.512421 -313.624508) (xy 223.546273 -313.574447)
			(xy 223.56572 -313.551316) (xy 223.571341 -313.544176) (xy 223.577587 -313.527124) (xy 223.577912 -313.518042)
			(xy 223.577912 -313.487562) (xy 223.577582 -313.478481) (xy 223.571337 -313.46143) (xy 223.56572 -313.454288)
			(xy 223.546294 -313.431142) (xy 223.512452 -313.381079) (xy 223.48478 -313.327359) (xy 223.463668 -313.270738)
			(xy 223.449414 -313.212015) (xy 223.442218 -313.152016) (xy 223.441768 -313.121802) (xy 223.442189 -313.091586)
			(xy 223.449377 -313.031582) (xy 223.463628 -312.972854) (xy 223.484742 -312.91623) (xy 223.512421 -312.862508)
			(xy 223.546273 -312.812447) (xy 223.56572 -312.789316) (xy 223.571341 -312.782176) (xy 223.577587 -312.765124)
			(xy 223.577912 -312.756042) (xy 223.577912 -312.725562) (xy 223.577582 -312.716481) (xy 223.571337 -312.69943)
			(xy 223.56572 -312.692288) (xy 223.546294 -312.669142) (xy 223.512452 -312.619079) (xy 223.48478 -312.565359)
			(xy 223.463668 -312.508738) (xy 223.449414 -312.450015) (xy 223.442218 -312.390016) (xy 223.441768 -312.359802)
			(xy 223.44227 -312.327841) (xy 223.450281 -312.264423) (xy 223.466178 -312.202509) (xy 223.48971 -312.143076)
			(xy 223.520504 -312.087061) (xy 223.558077 -312.035346) (xy 223.601834 -311.988749) (xy 223.651087 -311.948004)
			(xy 223.705058 -311.913753) (xy 223.762897 -311.886536) (xy 223.82369 -311.866783) (xy 223.88648 -311.854805)
			(xy 223.950276 -311.850792) (xy 224.014072 -311.854805) (xy 224.076862 -311.866783) (xy 224.137655 -311.886536)
			(xy 224.195494 -311.913753) (xy 224.249465 -311.948004) (xy 224.298718 -311.988749) (xy 224.342475 -312.035346)
			(xy 224.380048 -312.087061) (xy 224.410842 -312.143076) (xy 224.434374 -312.202509) (xy 224.450271 -312.264423)
			(xy 224.458282 -312.327841) (xy 224.458784 -312.359802) (xy 224.458353 -312.390018) (xy 224.451165 -312.450021)
			(xy 224.436915 -312.508748) (xy 224.415803 -312.565372) (xy 224.388127 -312.619094) (xy 224.354277 -312.669156)
			(xy 224.334832 -312.692288) (xy 224.329215 -312.699432) (xy 224.322965 -312.716481) (xy 224.32264 -312.725562)
			(xy 224.32264 -312.756042) (xy 224.322957 -312.765124) (xy 224.329209 -312.782176) (xy 224.334832 -312.789316)
			(xy 224.354268 -312.812454) (xy 224.388108 -312.862519) (xy 224.415777 -312.916242) (xy 224.436887 -312.972864)
			(xy 224.451139 -313.031588) (xy 224.458334 -313.091588) (xy 224.458784 -313.121802) (xy 224.458353 -313.152018)
			(xy 224.451165 -313.212021) (xy 224.436915 -313.270748) (xy 224.415803 -313.327372) (xy 224.388127 -313.381094)
			(xy 224.354277 -313.431156) (xy 224.334832 -313.454288) (xy 224.329215 -313.461432) (xy 224.322965 -313.478481)
			(xy 224.32264 -313.487562) (xy 224.32264 -313.518042) (xy 224.322957 -313.527124) (xy 224.329209 -313.544176)
			(xy 224.334832 -313.551316) (xy 224.354268 -313.574454) (xy 224.388108 -313.624519) (xy 224.415777 -313.678242)
			(xy 224.436887 -313.734864) (xy 224.451139 -313.793588) (xy 224.458334 -313.853588) (xy 224.458784 -313.883802)
			(xy 224.458185 -313.918498) (xy 224.457473 -313.92368) (xy 224.71507 -313.92368) (xy 224.715477 -313.893463)
			(xy 224.722668 -313.833459) (xy 224.736922 -313.774731) (xy 224.758039 -313.718107) (xy 224.785719 -313.664385)
			(xy 224.819574 -313.614325) (xy 224.839022 -313.591194) (xy 224.844653 -313.58406) (xy 224.850893 -313.567003)
			(xy 224.851214 -313.55792) (xy 224.851214 -313.52744) (xy 224.850894 -313.518358) (xy 224.844642 -313.501307)
			(xy 224.839022 -313.494166) (xy 224.819586 -313.471028) (xy 224.785745 -313.420963) (xy 224.758074 -313.367241)
			(xy 224.736964 -313.310619) (xy 224.722712 -313.251894) (xy 224.715519 -313.191894) (xy 224.71507 -313.16168)
			(xy 224.715477 -313.131463) (xy 224.722668 -313.071459) (xy 224.736922 -313.012731) (xy 224.758039 -312.956107)
			(xy 224.785719 -312.902385) (xy 224.819574 -312.852325) (xy 224.839022 -312.829194) (xy 224.844653 -312.82206)
			(xy 224.850893 -312.805003) (xy 224.851214 -312.79592) (xy 224.851214 -312.76544) (xy 224.850894 -312.756358)
			(xy 224.844642 -312.739307) (xy 224.839022 -312.732166) (xy 224.819586 -312.709028) (xy 224.785745 -312.658963)
			(xy 224.758074 -312.605241) (xy 224.736964 -312.548619) (xy 224.722712 -312.489894) (xy 224.715519 -312.429894)
			(xy 224.71507 -312.39968) (xy 224.715572 -312.367719) (xy 224.723583 -312.304301) (xy 224.73948 -312.242387)
			(xy 224.763012 -312.182954) (xy 224.793806 -312.126939) (xy 224.831379 -312.075224) (xy 224.875136 -312.028627)
			(xy 224.924389 -311.987882) (xy 224.97836 -311.953631) (xy 225.036199 -311.926414) (xy 225.096992 -311.906661)
			(xy 225.159782 -311.894683) (xy 225.223578 -311.89067) (xy 225.287374 -311.894683) (xy 225.350164 -311.906661)
			(xy 225.410957 -311.926414) (xy 225.468796 -311.953631) (xy 225.522767 -311.987882) (xy 225.57202 -312.028627)
			(xy 225.615777 -312.075224) (xy 225.65335 -312.126939) (xy 225.684144 -312.182954) (xy 225.707676 -312.242387)
			(xy 225.723573 -312.304301) (xy 225.731584 -312.367719) (xy 225.732086 -312.39968) (xy 225.731642 -312.429895)
			(xy 225.724456 -312.489898) (xy 225.710208 -312.548625) (xy 225.689099 -312.605249) (xy 225.661425 -312.658971)
			(xy 225.627578 -312.709034) (xy 225.608134 -312.732166) (xy 225.602515 -312.739307) (xy 225.596269 -312.756359)
			(xy 225.595942 -312.76544) (xy 225.595942 -312.79592) (xy 225.596269 -312.805001) (xy 225.602514 -312.822053)
			(xy 225.608134 -312.829194) (xy 225.62756 -312.85234) (xy 225.661401 -312.902404) (xy 225.689072 -312.956124)
			(xy 225.710183 -313.012745) (xy 225.724438 -313.071468) (xy 225.731635 -313.131466) (xy 225.732086 -313.16168)
			(xy 225.731642 -313.191895) (xy 225.724456 -313.251898) (xy 225.710208 -313.310625) (xy 225.689099 -313.367249)
			(xy 225.661425 -313.420971) (xy 225.627578 -313.471034) (xy 225.608134 -313.494166) (xy 225.602515 -313.501307)
			(xy 225.596269 -313.518359) (xy 225.595942 -313.52744) (xy 225.595942 -313.55792) (xy 225.596269 -313.567001)
			(xy 225.602514 -313.584053) (xy 225.608134 -313.591194) (xy 225.62756 -313.61434) (xy 225.661401 -313.664404)
			(xy 225.689072 -313.718124) (xy 225.710183 -313.774745) (xy 225.724438 -313.833468) (xy 225.731635 -313.893466)
			(xy 225.732086 -313.92368) (xy 225.731584 -313.955641) (xy 225.723573 -314.019059) (xy 225.707676 -314.080973)
			(xy 225.684144 -314.140406) (xy 225.65335 -314.196421) (xy 225.615777 -314.248136) (xy 225.57202 -314.294733)
			(xy 225.522767 -314.335478) (xy 225.468796 -314.369729) (xy 225.410957 -314.396946) (xy 225.350164 -314.416699)
			(xy 225.287374 -314.428677) (xy 225.223578 -314.432691) (xy 225.159782 -314.428677) (xy 225.096992 -314.416699)
			(xy 225.036199 -314.396946) (xy 224.97836 -314.369729) (xy 224.924389 -314.335478) (xy 224.875136 -314.294733)
			(xy 224.831379 -314.248136) (xy 224.793806 -314.196421) (xy 224.763012 -314.140406) (xy 224.73948 -314.080973)
			(xy 224.723583 -314.019059) (xy 224.715572 -313.955641) (xy 224.71507 -313.92368) (xy 224.457473 -313.92368)
			(xy 224.448738 -313.987244) (xy 224.430033 -314.054068) (xy 224.402418 -314.117728) (xy 224.366406 -314.177044)
			(xy 224.344992 -314.20435) (xy 224.33915 -314.211462) (xy 224.333308 -314.228734) (xy 224.33661 -314.314332)
			(xy 224.343468 -314.330842) (xy 224.349818 -314.3377) (xy 224.37131 -314.36134) (xy 224.40884 -314.413048)
			(xy 224.439599 -314.469048) (xy 224.463102 -314.528459) (xy 224.478981 -314.590346) (xy 224.486985 -314.653734)
			(xy 224.487486 -314.68568) (xy 224.487042 -314.715895) (xy 224.479856 -314.775898) (xy 224.465608 -314.834625)
			(xy 224.444499 -314.891249) (xy 224.416825 -314.944971) (xy 224.382978 -314.995034) (xy 224.363534 -315.018166)
			(xy 224.357915 -315.025307) (xy 224.351669 -315.042359) (xy 224.351342 -315.05144) (xy 224.351342 -315.08192)
			(xy 224.351669 -315.091001) (xy 224.357914 -315.108053) (xy 224.363534 -315.115194) (xy 224.38296 -315.13834)
			(xy 224.416801 -315.188404) (xy 224.444472 -315.242124) (xy 224.465583 -315.298745) (xy 224.479838 -315.357468)
			(xy 224.487035 -315.417466) (xy 224.487486 -315.44768) (xy 227.30587 -315.44768) (xy 227.306277 -315.417463)
			(xy 227.313468 -315.357459) (xy 227.327722 -315.298731) (xy 227.348839 -315.242107) (xy 227.376519 -315.188385)
			(xy 227.410374 -315.138325) (xy 227.429822 -315.115194) (xy 227.435453 -315.10806) (xy 227.441693 -315.091003)
			(xy 227.442014 -315.08192) (xy 227.442014 -315.05144) (xy 227.441694 -315.042358) (xy 227.435442 -315.025307)
			(xy 227.429822 -315.018166) (xy 227.410386 -314.995028) (xy 227.376545 -314.944963) (xy 227.348874 -314.891241)
			(xy 227.327764 -314.834619) (xy 227.313512 -314.775894) (xy 227.306319 -314.715894) (xy 227.30587 -314.68568)
			(xy 227.306352 -314.653881) (xy 227.31427 -314.590779) (xy 227.329994 -314.529157) (xy 227.353277 -314.469975)
			(xy 227.383756 -314.414158) (xy 227.420957 -314.362576) (xy 227.442268 -314.33897) (xy 227.448304 -314.331901)
			(xy 227.455339 -314.314714) (xy 227.455984 -314.305442) (xy 227.456746 -314.274962) (xy 227.456543 -314.265623)
			(xy 227.4503 -314.248036) (xy 227.444554 -314.240672) (xy 227.425466 -314.217612) (xy 227.392217 -314.167829)
			(xy 227.365047 -314.114486) (xy 227.344332 -314.058319) (xy 227.33036 -314.000108) (xy 227.323324 -313.940658)
			(xy 227.322888 -313.910726) (xy 227.323342 -313.880511) (xy 227.330526 -313.820509) (xy 227.344773 -313.761782)
			(xy 227.365881 -313.705158) (xy 227.393552 -313.651436) (xy 227.427397 -313.601373) (xy 227.44684 -313.57824)
			(xy 227.452454 -313.571095) (xy 227.458704 -313.554047) (xy 227.459032 -313.544966) (xy 227.459032 -313.514486)
			(xy 227.458686 -313.505407) (xy 227.452452 -313.488356) (xy 227.44684 -313.481212) (xy 227.427429 -313.458054)
			(xy 227.393584 -313.407994) (xy 227.36591 -313.354276) (xy 227.344795 -313.297658) (xy 227.330538 -313.238936)
			(xy 227.32334 -313.178939) (xy 227.322888 -313.148726) (xy 227.323342 -313.118511) (xy 227.330526 -313.058509)
			(xy 227.344773 -312.999782) (xy 227.365881 -312.943158) (xy 227.393552 -312.889436) (xy 227.427397 -312.839373)
			(xy 227.44684 -312.81624) (xy 227.452454 -312.809095) (xy 227.458704 -312.792047) (xy 227.459032 -312.782966)
			(xy 227.459032 -312.752486) (xy 227.458686 -312.743407) (xy 227.452452 -312.726356) (xy 227.44684 -312.719212)
			(xy 227.427429 -312.696054) (xy 227.393584 -312.645994) (xy 227.36591 -312.592276) (xy 227.344795 -312.535658)
			(xy 227.330538 -312.476936) (xy 227.32334 -312.416939) (xy 227.322888 -312.386726) (xy 227.32339 -312.354765)
			(xy 227.331401 -312.291347) (xy 227.347298 -312.229433) (xy 227.37083 -312.17) (xy 227.401624 -312.113985)
			(xy 227.439197 -312.06227) (xy 227.482954 -312.015673) (xy 227.532207 -311.974928) (xy 227.586178 -311.940677)
			(xy 227.644017 -311.91346) (xy 227.70481 -311.893707) (xy 227.7676 -311.881729) (xy 227.831396 -311.877716)
			(xy 227.895192 -311.881729) (xy 227.957982 -311.893707) (xy 228.018775 -311.91346) (xy 228.076614 -311.940677)
			(xy 228.130585 -311.974928) (xy 228.179838 -312.015673) (xy 228.223595 -312.06227) (xy 228.261168 -312.113985)
			(xy 228.291962 -312.17) (xy 228.315494 -312.229433) (xy 228.331391 -312.291347) (xy 228.339402 -312.354765)
			(xy 228.339904 -312.386726) (xy 228.339483 -312.416942) (xy 228.332292 -312.476945) (xy 228.31804 -312.535673)
			(xy 228.296926 -312.592297) (xy 228.269248 -312.646018) (xy 228.235398 -312.69608) (xy 228.215952 -312.719212)
			(xy 228.210315 -312.726342) (xy 228.204079 -312.743402) (xy 228.20376 -312.752486) (xy 228.20376 -312.782966)
			(xy 228.204082 -312.792048) (xy 228.210333 -312.809098) (xy 228.215952 -312.81624) (xy 228.235403 -312.839366)
			(xy 228.26924 -312.889435) (xy 228.296907 -312.943159) (xy 228.318014 -312.999784) (xy 228.332264 -313.05851)
			(xy 228.339455 -313.118511) (xy 228.339904 -313.148726) (xy 228.339483 -313.178942) (xy 228.332292 -313.238945)
			(xy 228.31804 -313.297673) (xy 228.296926 -313.354297) (xy 228.269248 -313.408018) (xy 228.235398 -313.45808)
			(xy 228.215952 -313.481212) (xy 228.210315 -313.488342) (xy 228.204079 -313.505402) (xy 228.20376 -313.514486)
			(xy 228.20376 -313.544966) (xy 228.204082 -313.554048) (xy 228.210333 -313.571098) (xy 228.215952 -313.57824)
			(xy 228.235403 -313.601366) (xy 228.26924 -313.651435) (xy 228.296907 -313.705159) (xy 228.318014 -313.761784)
			(xy 228.332264 -313.82051) (xy 228.339455 -313.880511) (xy 228.339904 -313.910726) (xy 228.339433 -313.942525)
			(xy 228.331513 -314.005628) (xy 228.315788 -314.067251) (xy 228.292503 -314.126433) (xy 228.262021 -314.18225)
			(xy 228.224818 -314.233831) (xy 228.203506 -314.257436) (xy 228.197464 -314.2645) (xy 228.190433 -314.281691)
			(xy 228.18979 -314.290964) (xy 228.189028 -314.321444) (xy 228.189234 -314.330783) (xy 228.195476 -314.348369)
			(xy 228.20122 -314.355734) (xy 228.220307 -314.378795) (xy 228.253557 -314.428577) (xy 228.280727 -314.481921)
			(xy 228.301442 -314.538087) (xy 228.315414 -314.596298) (xy 228.32245 -314.655748) (xy 228.322886 -314.68568)
			(xy 228.322442 -314.715895) (xy 228.315256 -314.775898) (xy 228.301008 -314.834625) (xy 228.279899 -314.891249)
			(xy 228.252225 -314.944971) (xy 228.218378 -314.995034) (xy 228.198934 -315.018166) (xy 228.193315 -315.025307)
			(xy 228.187069 -315.042359) (xy 228.186742 -315.05144) (xy 228.186742 -315.08192) (xy 228.187069 -315.091001)
			(xy 228.193314 -315.108053) (xy 228.198934 -315.115194) (xy 228.21836 -315.13834) (xy 228.252201 -315.188404)
			(xy 228.279872 -315.242124) (xy 228.300983 -315.298745) (xy 228.315238 -315.357468) (xy 228.322435 -315.417466)
			(xy 228.322886 -315.44768) (xy 229.36327 -315.44768) (xy 229.363677 -315.417463) (xy 229.370868 -315.357459)
			(xy 229.385122 -315.298731) (xy 229.406239 -315.242107) (xy 229.433919 -315.188385) (xy 229.467774 -315.138325)
			(xy 229.487222 -315.115194) (xy 229.492853 -315.10806) (xy 229.499093 -315.091003) (xy 229.499414 -315.08192)
			(xy 229.499414 -315.05144) (xy 229.499094 -315.042358) (xy 229.492842 -315.025307) (xy 229.487222 -315.018166)
			(xy 229.467786 -314.995028) (xy 229.433945 -314.944963) (xy 229.406274 -314.891241) (xy 229.385164 -314.834619)
			(xy 229.370912 -314.775894) (xy 229.363719 -314.715894) (xy 229.36327 -314.68568) (xy 229.363679 -314.655698)
			(xy 229.37073 -314.596149) (xy 229.384734 -314.537842) (xy 229.405494 -314.481585) (xy 229.432724 -314.428159)
			(xy 229.466046 -314.378305) (xy 229.48519 -314.355226) (xy 229.490771 -314.348135) (xy 229.497021 -314.331222)
			(xy 229.497382 -314.322206) (xy 229.497382 -314.29198) (xy 229.497089 -314.282983) (xy 229.490972 -314.266065)
			(xy 229.485444 -314.25896) (xy 229.466321 -314.235893) (xy 229.433032 -314.186072) (xy 229.405822 -314.132687)
			(xy 229.385067 -314.076477) (xy 229.371055 -314.018219) (xy 229.363979 -313.958719) (xy 229.363524 -313.92876)
			(xy 229.36399 -313.898545) (xy 229.37117 -313.838544) (xy 229.385414 -313.779817) (xy 229.40652 -313.723193)
			(xy 229.43419 -313.66947) (xy 229.468034 -313.619407) (xy 229.487476 -313.596274) (xy 229.49311 -313.589142)
			(xy 229.499349 -313.572084) (xy 229.499668 -313.563) (xy 229.499668 -313.53252) (xy 229.499368 -313.523436)
			(xy 229.493104 -313.506385) (xy 229.487476 -313.499246) (xy 229.468023 -313.476122) (xy 229.434185 -313.426053)
			(xy 229.406518 -313.372328) (xy 229.385412 -313.315703) (xy 229.371162 -313.256976) (xy 229.363972 -313.196975)
			(xy 229.363524 -313.16676) (xy 229.36399 -313.136545) (xy 229.37117 -313.076544) (xy 229.385414 -313.017817)
			(xy 229.40652 -312.961193) (xy 229.43419 -312.90747) (xy 229.468034 -312.857407) (xy 229.487476 -312.834274)
			(xy 229.49311 -312.827142) (xy 229.499349 -312.810084) (xy 229.499668 -312.801) (xy 229.499668 -312.77052)
			(xy 229.499368 -312.761436) (xy 229.493104 -312.744385) (xy 229.487476 -312.737246) (xy 229.468023 -312.714122)
			(xy 229.434185 -312.664053) (xy 229.406518 -312.610328) (xy 229.385412 -312.553703) (xy 229.371162 -312.494976)
			(xy 229.363972 -312.434975) (xy 229.363524 -312.40476) (xy 229.364026 -312.372799) (xy 229.372037 -312.309381)
			(xy 229.387934 -312.247467) (xy 229.411466 -312.188034) (xy 229.44226 -312.132019) (xy 229.479833 -312.080304)
			(xy 229.52359 -312.033707) (xy 229.572843 -311.992962) (xy 229.626814 -311.958711) (xy 229.684653 -311.931494)
			(xy 229.745446 -311.911741) (xy 229.808236 -311.899763) (xy 229.872032 -311.89575) (xy 229.935828 -311.899763)
			(xy 229.998618 -311.911741) (xy 230.059411 -311.931494) (xy 230.11725 -311.958711) (xy 230.171221 -311.992962)
			(xy 230.220474 -312.033707) (xy 230.264231 -312.080304) (xy 230.301804 -312.132019) (xy 230.332598 -312.188034)
			(xy 230.35613 -312.247467) (xy 230.372027 -312.309381) (xy 230.380038 -312.372799) (xy 230.38054 -312.40476)
			(xy 230.380095 -312.434975) (xy 230.372911 -312.494978) (xy 230.358664 -312.553706) (xy 230.337555 -312.61033)
			(xy 230.309881 -312.664052) (xy 230.276033 -312.714114) (xy 230.256588 -312.737246) (xy 230.250984 -312.744398)
			(xy 230.244727 -312.761441) (xy 230.244396 -312.77052) (xy 230.244396 -312.801) (xy 230.244742 -312.810079)
			(xy 230.250975 -312.82713) (xy 230.256588 -312.834274) (xy 230.276045 -312.857395) (xy 230.309883 -312.907464)
			(xy 230.33755 -312.96119) (xy 230.358656 -313.017815) (xy 230.372904 -313.076543) (xy 230.380093 -313.136545)
			(xy 230.38054 -313.16676) (xy 230.380095 -313.196975) (xy 230.372911 -313.256978) (xy 230.358664 -313.315706)
			(xy 230.337555 -313.37233) (xy 230.309881 -313.426052) (xy 230.276033 -313.476114) (xy 230.256588 -313.499246)
			(xy 230.250984 -313.506398) (xy 230.244727 -313.523441) (xy 230.244396 -313.53252) (xy 230.244396 -313.563)
			(xy 230.244742 -313.572079) (xy 230.250975 -313.58913) (xy 230.256588 -313.596274) (xy 230.276045 -313.619395)
			(xy 230.309883 -313.669464) (xy 230.33755 -313.72319) (xy 230.358656 -313.779815) (xy 230.372904 -313.838543)
			(xy 230.380093 -313.898545) (xy 230.380465 -313.92368) (xy 230.81107 -313.92368) (xy 230.811477 -313.893463)
			(xy 230.818668 -313.833459) (xy 230.832922 -313.774731) (xy 230.854039 -313.718107) (xy 230.881719 -313.664385)
			(xy 230.915574 -313.614325) (xy 230.935022 -313.591194) (xy 230.940653 -313.58406) (xy 230.946893 -313.567003)
			(xy 230.947214 -313.55792) (xy 230.947214 -313.52744) (xy 230.946894 -313.518358) (xy 230.940642 -313.501307)
			(xy 230.935022 -313.494166) (xy 230.915586 -313.471028) (xy 230.881745 -313.420963) (xy 230.854074 -313.367241)
			(xy 230.832964 -313.310619) (xy 230.818712 -313.251894) (xy 230.811519 -313.191894) (xy 230.81107 -313.16168)
			(xy 230.811477 -313.131463) (xy 230.818668 -313.071459) (xy 230.832922 -313.012731) (xy 230.854039 -312.956107)
			(xy 230.881719 -312.902385) (xy 230.915574 -312.852325) (xy 230.935022 -312.829194) (xy 230.940653 -312.82206)
			(xy 230.946893 -312.805003) (xy 230.947214 -312.79592) (xy 230.947214 -312.76544) (xy 230.946894 -312.756358)
			(xy 230.940642 -312.739307) (xy 230.935022 -312.732166) (xy 230.915586 -312.709028) (xy 230.881745 -312.658963)
			(xy 230.854074 -312.605241) (xy 230.832964 -312.548619) (xy 230.818712 -312.489894) (xy 230.811519 -312.429894)
			(xy 230.81107 -312.39968) (xy 230.811572 -312.367719) (xy 230.819583 -312.304301) (xy 230.83548 -312.242387)
			(xy 230.859012 -312.182954) (xy 230.889806 -312.126939) (xy 230.927379 -312.075224) (xy 230.971136 -312.028627)
			(xy 231.020389 -311.987882) (xy 231.07436 -311.953631) (xy 231.132199 -311.926414) (xy 231.192992 -311.906661)
			(xy 231.255782 -311.894683) (xy 231.319578 -311.89067) (xy 231.383374 -311.894683) (xy 231.446164 -311.906661)
			(xy 231.506957 -311.926414) (xy 231.564796 -311.953631) (xy 231.618767 -311.987882) (xy 231.66802 -312.028627)
			(xy 231.711777 -312.075224) (xy 231.74935 -312.126939) (xy 231.780144 -312.182954) (xy 231.803676 -312.242387)
			(xy 231.819573 -312.304301) (xy 231.827584 -312.367719) (xy 231.828086 -312.39968) (xy 231.827642 -312.429895)
			(xy 231.820456 -312.489898) (xy 231.806208 -312.548625) (xy 231.785099 -312.605249) (xy 231.757425 -312.658971)
			(xy 231.723578 -312.709034) (xy 231.704134 -312.732166) (xy 231.698515 -312.739307) (xy 231.692269 -312.756359)
			(xy 231.691942 -312.76544) (xy 231.691942 -312.79592) (xy 231.692269 -312.805001) (xy 231.698514 -312.822053)
			(xy 231.704134 -312.829194) (xy 231.72356 -312.85234) (xy 231.757401 -312.902404) (xy 231.785072 -312.956124)
			(xy 231.806183 -313.012745) (xy 231.820438 -313.071468) (xy 231.827635 -313.131466) (xy 231.828086 -313.16168)
			(xy 231.827642 -313.191895) (xy 231.820456 -313.251898) (xy 231.806208 -313.310625) (xy 231.785099 -313.367249)
			(xy 231.757425 -313.420971) (xy 231.723578 -313.471034) (xy 231.704134 -313.494166) (xy 231.698515 -313.501307)
			(xy 231.692269 -313.518359) (xy 231.691942 -313.52744) (xy 231.691942 -313.55792) (xy 231.692269 -313.567001)
			(xy 231.698514 -313.584053) (xy 231.704134 -313.591194) (xy 231.72356 -313.61434) (xy 231.757401 -313.664404)
			(xy 231.785072 -313.718124) (xy 231.806183 -313.774745) (xy 231.820438 -313.833468) (xy 231.827635 -313.893466)
			(xy 231.828086 -313.92368) (xy 231.827584 -313.955641) (xy 231.819573 -314.019059) (xy 231.803676 -314.080973)
			(xy 231.780144 -314.140406) (xy 231.74935 -314.196421) (xy 231.711777 -314.248136) (xy 231.66802 -314.294733)
			(xy 231.618767 -314.335478) (xy 231.564796 -314.369729) (xy 231.506957 -314.396946) (xy 231.446164 -314.416699)
			(xy 231.383374 -314.428677) (xy 231.319578 -314.432691) (xy 231.255782 -314.428677) (xy 231.192992 -314.416699)
			(xy 231.132199 -314.396946) (xy 231.07436 -314.369729) (xy 231.020389 -314.335478) (xy 230.971136 -314.294733)
			(xy 230.927379 -314.248136) (xy 230.889806 -314.196421) (xy 230.859012 -314.140406) (xy 230.83548 -314.080973)
			(xy 230.819583 -314.019059) (xy 230.811572 -313.955641) (xy 230.81107 -313.92368) (xy 230.380465 -313.92368)
			(xy 230.38054 -313.92876) (xy 230.380093 -313.958741) (xy 230.373049 -314.018289) (xy 230.359053 -314.076595)
			(xy 230.338299 -314.132851) (xy 230.311076 -314.186278) (xy 230.277761 -314.236134) (xy 230.25862 -314.259214)
			(xy 230.253012 -314.266286) (xy 230.24678 -314.283214) (xy 230.246428 -314.292234) (xy 230.246428 -314.32246)
			(xy 230.246699 -314.331459) (xy 230.252831 -314.348378) (xy 230.258366 -314.35548) (xy 230.27751 -314.37853)
			(xy 230.310796 -314.428356) (xy 230.338002 -314.481744) (xy 230.358753 -314.537957) (xy 230.372762 -314.596218)
			(xy 230.379834 -314.65572) (xy 230.380286 -314.68568) (xy 230.379842 -314.715895) (xy 230.372656 -314.775898)
			(xy 230.358408 -314.834625) (xy 230.337299 -314.891249) (xy 230.309625 -314.944971) (xy 230.275778 -314.995034)
			(xy 230.256334 -315.018166) (xy 230.250715 -315.025307) (xy 230.244469 -315.042359) (xy 230.244142 -315.05144)
			(xy 230.244142 -315.08192) (xy 230.244469 -315.091001) (xy 230.250714 -315.108053) (xy 230.256334 -315.115194)
			(xy 230.27576 -315.13834) (xy 230.309601 -315.188404) (xy 230.337272 -315.242124) (xy 230.358383 -315.298745)
			(xy 230.372638 -315.357468) (xy 230.379835 -315.417466) (xy 230.380286 -315.44768) (xy 233.19867 -315.44768)
			(xy 233.199077 -315.417463) (xy 233.206268 -315.357459) (xy 233.220522 -315.298731) (xy 233.241639 -315.242107)
			(xy 233.269319 -315.188385) (xy 233.303174 -315.138325) (xy 233.322622 -315.115194) (xy 233.328253 -315.10806)
			(xy 233.334493 -315.091003) (xy 233.334814 -315.08192) (xy 233.334814 -315.05144) (xy 233.334494 -315.042358)
			(xy 233.328242 -315.025307) (xy 233.322622 -315.018166) (xy 233.303186 -314.995028) (xy 233.269345 -314.944963)
			(xy 233.241674 -314.891241) (xy 233.220564 -314.834619) (xy 233.206312 -314.775894) (xy 233.199119 -314.715894)
			(xy 233.19867 -314.68568) (xy 233.199077 -314.655463) (xy 233.206268 -314.595459) (xy 233.220522 -314.536731)
			(xy 233.241639 -314.480107) (xy 233.269319 -314.426385) (xy 233.303174 -314.376325) (xy 233.322622 -314.353194)
			(xy 233.328253 -314.34606) (xy 233.334493 -314.329003) (xy 233.334814 -314.31992) (xy 233.334814 -314.28944)
			(xy 233.334494 -314.280358) (xy 233.328242 -314.263307) (xy 233.322622 -314.256166) (xy 233.303186 -314.233028)
			(xy 233.269345 -314.182963) (xy 233.241674 -314.129241) (xy 233.220564 -314.072619) (xy 233.206312 -314.013894)
			(xy 233.199119 -313.953894) (xy 233.19867 -313.92368) (xy 233.199077 -313.893463) (xy 233.206268 -313.833459)
			(xy 233.220522 -313.774731) (xy 233.241639 -313.718107) (xy 233.269319 -313.664385) (xy 233.303174 -313.614325)
			(xy 233.322622 -313.591194) (xy 233.328253 -313.58406) (xy 233.334493 -313.567003) (xy 233.334814 -313.55792)
			(xy 233.334814 -313.52744) (xy 233.334494 -313.518358) (xy 233.328242 -313.501307) (xy 233.322622 -313.494166)
			(xy 233.303186 -313.471028) (xy 233.269345 -313.420963) (xy 233.241674 -313.367241) (xy 233.220564 -313.310619)
			(xy 233.206312 -313.251894) (xy 233.199119 -313.191894) (xy 233.19867 -313.16168) (xy 233.199077 -313.131463)
			(xy 233.206268 -313.071459) (xy 233.220522 -313.012731) (xy 233.241639 -312.956107) (xy 233.269319 -312.902385)
			(xy 233.303174 -312.852325) (xy 233.322622 -312.829194) (xy 233.328253 -312.82206) (xy 233.334493 -312.805003)
			(xy 233.334814 -312.79592) (xy 233.334814 -312.76544) (xy 233.334494 -312.756358) (xy 233.328242 -312.739307)
			(xy 233.322622 -312.732166) (xy 233.303186 -312.709028) (xy 233.269345 -312.658963) (xy 233.241674 -312.605241)
			(xy 233.220564 -312.548619) (xy 233.206312 -312.489894) (xy 233.199119 -312.429894) (xy 233.19867 -312.39968)
			(xy 233.199172 -312.367719) (xy 233.207183 -312.304301) (xy 233.22308 -312.242387) (xy 233.246612 -312.182954)
			(xy 233.277406 -312.126939) (xy 233.314979 -312.075224) (xy 233.358736 -312.028627) (xy 233.407989 -311.987882)
			(xy 233.46196 -311.953631) (xy 233.519799 -311.926414) (xy 233.580592 -311.906661) (xy 233.643382 -311.894683)
			(xy 233.707178 -311.89067) (xy 233.770974 -311.894683) (xy 233.833764 -311.906661) (xy 233.894557 -311.926414)
			(xy 233.952396 -311.953631) (xy 234.006367 -311.987882) (xy 234.05562 -312.028627) (xy 234.099377 -312.075224)
			(xy 234.13695 -312.126939) (xy 234.167744 -312.182954) (xy 234.191276 -312.242387) (xy 234.207173 -312.304301)
			(xy 234.215184 -312.367719) (xy 234.215686 -312.39968) (xy 234.215242 -312.429895) (xy 234.208056 -312.489898)
			(xy 234.193808 -312.548625) (xy 234.172699 -312.605249) (xy 234.145025 -312.658971) (xy 234.111178 -312.709034)
			(xy 234.091734 -312.732166) (xy 234.086115 -312.739307) (xy 234.079869 -312.756359) (xy 234.079542 -312.76544)
			(xy 234.079542 -312.79592) (xy 234.079869 -312.805001) (xy 234.086114 -312.822053) (xy 234.091734 -312.829194)
			(xy 234.11116 -312.85234) (xy 234.145001 -312.902404) (xy 234.172672 -312.956124) (xy 234.193783 -313.012745)
			(xy 234.208038 -313.071468) (xy 234.215235 -313.131466) (xy 234.215686 -313.16168) (xy 234.215242 -313.191895)
			(xy 234.208056 -313.251898) (xy 234.193808 -313.310625) (xy 234.172699 -313.367249) (xy 234.145025 -313.420971)
			(xy 234.111178 -313.471034) (xy 234.091734 -313.494166) (xy 234.086115 -313.501307) (xy 234.079869 -313.518359)
			(xy 234.079542 -313.52744) (xy 234.079542 -313.55792) (xy 234.079869 -313.567001) (xy 234.086114 -313.584053)
			(xy 234.091734 -313.591194) (xy 234.11116 -313.61434) (xy 234.145001 -313.664404) (xy 234.172672 -313.718124)
			(xy 234.193783 -313.774745) (xy 234.208038 -313.833468) (xy 234.208683 -313.838844) (xy 237.207806 -313.838844)
			(xy 237.208266 -313.808629) (xy 237.215449 -313.748628) (xy 237.229694 -313.689901) (xy 237.2508 -313.633277)
			(xy 237.278471 -313.579554) (xy 237.312315 -313.529491) (xy 237.331758 -313.506358) (xy 237.337366 -313.499209)
			(xy 237.343619 -313.482164) (xy 237.34395 -313.473084) (xy 237.34395 -313.442604) (xy 237.343613 -313.433523)
			(xy 237.337375 -313.416472) (xy 237.331758 -313.40933) (xy 237.312295 -313.386214) (xy 237.278459 -313.336143)
			(xy 237.250793 -313.282416) (xy 237.229689 -313.22579) (xy 237.215442 -313.167062) (xy 237.208253 -313.10706)
			(xy 237.207806 -313.076844) (xy 237.208266 -313.046629) (xy 237.215449 -312.986628) (xy 237.229694 -312.927901)
			(xy 237.2508 -312.871277) (xy 237.278471 -312.817554) (xy 237.312315 -312.767491) (xy 237.331758 -312.744358)
			(xy 237.337366 -312.737209) (xy 237.343619 -312.720164) (xy 237.34395 -312.711084) (xy 237.34395 -312.680604)
			(xy 237.343613 -312.671523) (xy 237.337375 -312.654472) (xy 237.331758 -312.64733) (xy 237.312295 -312.624214)
			(xy 237.278459 -312.574143) (xy 237.250793 -312.520416) (xy 237.229689 -312.46379) (xy 237.215442 -312.405062)
			(xy 237.208253 -312.34506) (xy 237.207806 -312.314844) (xy 237.208308 -312.282883) (xy 237.216319 -312.219465)
			(xy 237.232216 -312.157551) (xy 237.255748 -312.098118) (xy 237.286542 -312.042103) (xy 237.324115 -311.990388)
			(xy 237.367872 -311.943791) (xy 237.417125 -311.903046) (xy 237.471096 -311.868795) (xy 237.528935 -311.841578)
			(xy 237.589728 -311.821825) (xy 237.652518 -311.809847) (xy 237.716314 -311.805834) (xy 237.78011 -311.809847)
			(xy 237.8429 -311.821825) (xy 237.903693 -311.841578) (xy 237.961532 -311.868795) (xy 238.015503 -311.903046)
			(xy 238.064756 -311.943791) (xy 238.108513 -311.990388) (xy 238.146086 -312.042103) (xy 238.17688 -312.098118)
			(xy 238.200412 -312.157551) (xy 238.216309 -312.219465) (xy 238.22432 -312.282883) (xy 238.224822 -312.314844)
			(xy 238.224348 -312.345058) (xy 238.217167 -312.405059) (xy 238.202924 -312.463786) (xy 238.18182 -312.52041)
			(xy 238.154152 -312.574133) (xy 238.120311 -312.624197) (xy 238.10087 -312.64733) (xy 238.09527 -312.654485)
			(xy 238.089012 -312.671526) (xy 238.088678 -312.680604) (xy 238.088678 -312.711084) (xy 238.088988 -312.720167)
			(xy 238.095246 -312.737218) (xy 238.10087 -312.744358) (xy 238.120316 -312.767488) (xy 238.154156 -312.817554)
			(xy 238.181825 -312.871278) (xy 238.202934 -312.927902) (xy 238.217184 -312.986628) (xy 238.224374 -313.046629)
			(xy 238.224822 -313.076844) (xy 238.224348 -313.107058) (xy 238.217167 -313.167059) (xy 238.202924 -313.225786)
			(xy 238.18182 -313.28241) (xy 238.154152 -313.336133) (xy 238.120311 -313.386197) (xy 238.10087 -313.40933)
			(xy 238.09527 -313.416485) (xy 238.089012 -313.433526) (xy 238.088678 -313.442604) (xy 238.088678 -313.473084)
			(xy 238.088988 -313.482167) (xy 238.095246 -313.499218) (xy 238.10087 -313.506358) (xy 238.120316 -313.529488)
			(xy 238.154156 -313.579554) (xy 238.181825 -313.633278) (xy 238.202934 -313.689902) (xy 238.217184 -313.748628)
			(xy 238.224374 -313.808629) (xy 238.224822 -313.838844) (xy 238.22438 -313.869219) (xy 238.22263 -313.883802)
			(xy 238.423704 -313.883802) (xy 238.42414 -313.853586) (xy 238.431327 -313.793584) (xy 238.445577 -313.734857)
			(xy 238.466688 -313.678233) (xy 238.494363 -313.62451) (xy 238.528212 -313.574448) (xy 238.547656 -313.551316)
			(xy 238.553282 -313.544179) (xy 238.559524 -313.527124) (xy 238.559848 -313.518042) (xy 238.559848 -313.487562)
			(xy 238.559532 -313.478479) (xy 238.553279 -313.461428) (xy 238.547656 -313.454288) (xy 238.52822 -313.43115)
			(xy 238.494381 -313.381085) (xy 238.466711 -313.327362) (xy 238.445602 -313.27074) (xy 238.431349 -313.212016)
			(xy 238.424154 -313.152016) (xy 238.423704 -313.121802) (xy 238.42414 -313.091586) (xy 238.431327 -313.031584)
			(xy 238.445577 -312.972857) (xy 238.466688 -312.916233) (xy 238.494363 -312.86251) (xy 238.528212 -312.812448)
			(xy 238.547656 -312.789316) (xy 238.553282 -312.782179) (xy 238.559524 -312.765124) (xy 238.559848 -312.756042)
			(xy 238.559848 -312.725562) (xy 238.559532 -312.716479) (xy 238.553279 -312.699428) (xy 238.547656 -312.692288)
			(xy 238.52822 -312.66915) (xy 238.494381 -312.619085) (xy 238.466711 -312.565362) (xy 238.445602 -312.50874)
			(xy 238.431349 -312.450016) (xy 238.424154 -312.390016) (xy 238.423704 -312.359802) (xy 238.424206 -312.327841)
			(xy 238.432217 -312.264423) (xy 238.448114 -312.202509) (xy 238.471646 -312.143076) (xy 238.50244 -312.087061)
			(xy 238.540013 -312.035346) (xy 238.58377 -311.988749) (xy 238.633023 -311.948004) (xy 238.686994 -311.913753)
			(xy 238.744833 -311.886536) (xy 238.805626 -311.866783) (xy 238.868416 -311.854805) (xy 238.932212 -311.850792)
			(xy 238.996008 -311.854805) (xy 239.058798 -311.866783) (xy 239.119591 -311.886536) (xy 239.17743 -311.913753)
			(xy 239.231401 -311.948004) (xy 239.280654 -311.988749) (xy 239.324411 -312.035346) (xy 239.361984 -312.087061)
			(xy 239.392778 -312.143076) (xy 239.41631 -312.202509) (xy 239.432207 -312.264423) (xy 239.440218 -312.327841)
			(xy 239.44072 -312.359802) (xy 239.440281 -312.390017) (xy 239.433093 -312.45002) (xy 239.418844 -312.508747)
			(xy 239.397733 -312.565371) (xy 239.370059 -312.619093) (xy 239.336212 -312.669156) (xy 239.316768 -312.692288)
			(xy 239.311144 -312.699426) (xy 239.3049 -312.71648) (xy 239.304576 -312.725562) (xy 239.304576 -312.756042)
			(xy 239.304907 -312.765123) (xy 239.311151 -312.782173) (xy 239.316768 -312.789316) (xy 239.336194 -312.812462)
			(xy 239.370037 -312.862525) (xy 239.397709 -312.916245) (xy 239.41882 -312.972866) (xy 239.433074 -313.031589)
			(xy 239.44027 -313.091588) (xy 239.44072 -313.121802) (xy 239.440281 -313.152017) (xy 239.433093 -313.21202)
			(xy 239.418844 -313.270747) (xy 239.397733 -313.327371) (xy 239.370059 -313.381093) (xy 239.336212 -313.431156)
			(xy 239.316768 -313.454288) (xy 239.311144 -313.461426) (xy 239.3049 -313.47848) (xy 239.304576 -313.487562)
			(xy 239.304576 -313.518042) (xy 239.304907 -313.527123) (xy 239.311151 -313.544173) (xy 239.316768 -313.551316)
			(xy 239.336194 -313.574462) (xy 239.370037 -313.624525) (xy 239.397709 -313.678245) (xy 239.41882 -313.734866)
			(xy 239.433074 -313.793589) (xy 239.44027 -313.853588) (xy 239.44072 -313.883802) (xy 239.440113 -313.918498)
			(xy 239.439401 -313.92368) (xy 239.697006 -313.92368) (xy 239.697428 -313.893464) (xy 239.704618 -313.833461)
			(xy 239.718871 -313.774733) (xy 239.739984 -313.718109) (xy 239.767662 -313.664388) (xy 239.801512 -313.614326)
			(xy 239.820958 -313.591194) (xy 239.826593 -313.584063) (xy 239.83283 -313.567004) (xy 239.83315 -313.55792)
			(xy 239.83315 -313.52744) (xy 239.832844 -313.518356) (xy 239.826584 -313.501305) (xy 239.820958 -313.494166)
			(xy 239.801512 -313.471037) (xy 239.767674 -313.420969) (xy 239.740006 -313.367245) (xy 239.718898 -313.310621)
			(xy 239.704648 -313.251895) (xy 239.697455 -313.191895) (xy 239.697006 -313.16168) (xy 239.697428 -313.131464)
			(xy 239.704618 -313.071461) (xy 239.718871 -313.012733) (xy 239.739984 -312.956109) (xy 239.767662 -312.902388)
			(xy 239.801512 -312.852326) (xy 239.820958 -312.829194) (xy 239.826593 -312.822063) (xy 239.83283 -312.805004)
			(xy 239.83315 -312.79592) (xy 239.83315 -312.76544) (xy 239.832844 -312.756356) (xy 239.826584 -312.739305)
			(xy 239.820958 -312.732166) (xy 239.801512 -312.709037) (xy 239.767674 -312.658969) (xy 239.740006 -312.605245)
			(xy 239.718898 -312.548621) (xy 239.704648 -312.489895) (xy 239.697455 -312.429895) (xy 239.697006 -312.39968)
			(xy 239.697508 -312.367719) (xy 239.705519 -312.304301) (xy 239.721416 -312.242387) (xy 239.744948 -312.182954)
			(xy 239.775742 -312.126939) (xy 239.813315 -312.075224) (xy 239.857072 -312.028627) (xy 239.906325 -311.987882)
			(xy 239.960296 -311.953631) (xy 240.018135 -311.926414) (xy 240.078928 -311.906661) (xy 240.141718 -311.894683)
			(xy 240.205514 -311.89067) (xy 240.26931 -311.894683) (xy 240.3321 -311.906661) (xy 240.392893 -311.926414)
			(xy 240.450732 -311.953631) (xy 240.504703 -311.987882) (xy 240.553956 -312.028627) (xy 240.597713 -312.075224)
			(xy 240.635286 -312.126939) (xy 240.66608 -312.182954) (xy 240.689612 -312.242387) (xy 240.705509 -312.304301)
			(xy 240.71352 -312.367719) (xy 240.714022 -312.39968) (xy 240.713569 -312.429895) (xy 240.706384 -312.489897)
			(xy 240.692137 -312.548624) (xy 240.671029 -312.605247) (xy 240.643358 -312.65897) (xy 240.609513 -312.709033)
			(xy 240.59007 -312.732166) (xy 240.584455 -312.739311) (xy 240.578206 -312.756359) (xy 240.577878 -312.76544)
			(xy 240.577878 -312.79592) (xy 240.578219 -312.805) (xy 240.584456 -312.822051) (xy 240.59007 -312.829194)
			(xy 240.609486 -312.852348) (xy 240.64333 -312.902409) (xy 240.671003 -312.956128) (xy 240.692117 -313.012747)
			(xy 240.706373 -313.071469) (xy 240.713571 -313.131466) (xy 240.714022 -313.16168) (xy 240.713569 -313.191895)
			(xy 240.706384 -313.251897) (xy 240.692137 -313.310624) (xy 240.671029 -313.367247) (xy 240.643358 -313.42097)
			(xy 240.609513 -313.471033) (xy 240.59007 -313.494166) (xy 240.584455 -313.501311) (xy 240.578206 -313.518359)
			(xy 240.577878 -313.52744) (xy 240.577878 -313.55792) (xy 240.578219 -313.567) (xy 240.584456 -313.584051)
			(xy 240.59007 -313.591194) (xy 240.609486 -313.614348) (xy 240.64333 -313.664409) (xy 240.671003 -313.718128)
			(xy 240.692117 -313.774747) (xy 240.706373 -313.833469) (xy 240.713571 -313.893466) (xy 240.714022 -313.92368)
			(xy 240.71352 -313.955641) (xy 240.705509 -314.019059) (xy 240.689612 -314.080973) (xy 240.66608 -314.140406)
			(xy 240.635286 -314.196421) (xy 240.597713 -314.248136) (xy 240.553956 -314.294733) (xy 240.504703 -314.335478)
			(xy 240.450732 -314.369729) (xy 240.392893 -314.396946) (xy 240.3321 -314.416699) (xy 240.26931 -314.428677)
			(xy 240.205514 -314.432691) (xy 240.141718 -314.428677) (xy 240.078928 -314.416699) (xy 240.018135 -314.396946)
			(xy 239.960296 -314.369729) (xy 239.906325 -314.335478) (xy 239.857072 -314.294733) (xy 239.813315 -314.248136)
			(xy 239.775742 -314.196421) (xy 239.744948 -314.140406) (xy 239.721416 -314.080973) (xy 239.705519 -314.019059)
			(xy 239.697508 -313.955641) (xy 239.697006 -313.92368) (xy 239.439401 -313.92368) (xy 239.430667 -313.987243)
			(xy 239.411964 -314.054066) (xy 239.384351 -314.117727) (xy 239.34834 -314.177043) (xy 239.326928 -314.20435)
			(xy 239.321086 -314.211462) (xy 239.315244 -314.228734) (xy 239.318546 -314.314332) (xy 239.325404 -314.330842)
			(xy 239.331754 -314.3377) (xy 239.353252 -314.361335) (xy 239.39078 -314.413044) (xy 239.421537 -314.469046)
			(xy 239.44504 -314.528458) (xy 239.460918 -314.590345) (xy 239.468921 -314.653734) (xy 239.469422 -314.68568)
			(xy 239.468969 -314.715895) (xy 239.461784 -314.775897) (xy 239.447537 -314.834624) (xy 239.426429 -314.891247)
			(xy 239.398758 -314.94497) (xy 239.364913 -314.995033) (xy 239.34547 -315.018166) (xy 239.339855 -315.025311)
			(xy 239.333606 -315.042359) (xy 239.333278 -315.05144) (xy 239.333278 -315.08192) (xy 239.333619 -315.091)
			(xy 239.339856 -315.108051) (xy 239.34547 -315.115194) (xy 239.364886 -315.138348) (xy 239.39873 -315.188409)
			(xy 239.426403 -315.242128) (xy 239.447517 -315.298747) (xy 239.461773 -315.357469) (xy 239.468971 -315.417466)
			(xy 239.469422 -315.44768) (xy 242.287806 -315.44768) (xy 242.288228 -315.417464) (xy 242.295418 -315.357461)
			(xy 242.309671 -315.298733) (xy 242.330784 -315.242109) (xy 242.358462 -315.188388) (xy 242.392312 -315.138326)
			(xy 242.411758 -315.115194) (xy 242.417393 -315.108063) (xy 242.42363 -315.091004) (xy 242.42395 -315.08192)
			(xy 242.42395 -315.05144) (xy 242.423644 -315.042356) (xy 242.417384 -315.025305) (xy 242.411758 -315.018166)
			(xy 242.392312 -314.995037) (xy 242.358474 -314.944969) (xy 242.330806 -314.891245) (xy 242.309698 -314.834621)
			(xy 242.295448 -314.775895) (xy 242.288255 -314.715895) (xy 242.287806 -314.68568) (xy 242.288278 -314.653881)
			(xy 242.296197 -314.590778) (xy 242.311922 -314.529155) (xy 242.335207 -314.469973) (xy 242.365689 -314.414156)
			(xy 242.402892 -314.362575) (xy 242.424204 -314.33897) (xy 242.430245 -314.331905) (xy 242.437277 -314.314715)
			(xy 242.43792 -314.305442) (xy 242.438682 -314.274962) (xy 242.438471 -314.265624) (xy 242.432232 -314.248038)
			(xy 242.42649 -314.240672) (xy 242.407407 -314.217607) (xy 242.374157 -314.167826) (xy 242.346985 -314.114484)
			(xy 242.32627 -314.058318) (xy 242.312297 -314.000107) (xy 242.30526 -313.940658) (xy 242.304824 -313.910726)
			(xy 242.305269 -313.880511) (xy 242.312454 -313.820508) (xy 242.326702 -313.761781) (xy 242.347811 -313.705157)
			(xy 242.375485 -313.651435) (xy 242.409332 -313.601372) (xy 242.428776 -313.57824) (xy 242.434382 -313.571089)
			(xy 242.440638 -313.554045) (xy 242.440968 -313.544966) (xy 242.440968 -313.514486) (xy 242.440636 -313.505405)
			(xy 242.434394 -313.488354) (xy 242.428776 -313.481212) (xy 242.409354 -313.458063) (xy 242.375513 -313.408)
			(xy 242.347841 -313.35428) (xy 242.326729 -313.29766) (xy 242.312473 -313.238938) (xy 242.305276 -313.17894)
			(xy 242.304824 -313.148726) (xy 242.305269 -313.118511) (xy 242.312454 -313.058508) (xy 242.326702 -312.999781)
			(xy 242.347811 -312.943157) (xy 242.375485 -312.889435) (xy 242.409332 -312.839372) (xy 242.428776 -312.81624)
			(xy 242.434382 -312.809089) (xy 242.440638 -312.792045) (xy 242.440968 -312.782966) (xy 242.440968 -312.752486)
			(xy 242.440636 -312.743405) (xy 242.434394 -312.726354) (xy 242.428776 -312.719212) (xy 242.409354 -312.696063)
			(xy 242.375513 -312.646) (xy 242.347841 -312.59228) (xy 242.326729 -312.53566) (xy 242.312473 -312.476938)
			(xy 242.305276 -312.41694) (xy 242.304824 -312.386726) (xy 242.305326 -312.354765) (xy 242.313337 -312.291347)
			(xy 242.329234 -312.229433) (xy 242.352766 -312.17) (xy 242.38356 -312.113985) (xy 242.421133 -312.06227)
			(xy 242.46489 -312.015673) (xy 242.514143 -311.974928) (xy 242.568114 -311.940677) (xy 242.625953 -311.91346)
			(xy 242.686746 -311.893707) (xy 242.749536 -311.881729) (xy 242.813332 -311.877716) (xy 242.877128 -311.881729)
			(xy 242.939918 -311.893707) (xy 243.000711 -311.91346) (xy 243.05855 -311.940677) (xy 243.112521 -311.974928)
			(xy 243.161774 -312.015673) (xy 243.205531 -312.06227) (xy 243.243104 -312.113985) (xy 243.273898 -312.17)
			(xy 243.29743 -312.229433) (xy 243.313327 -312.291347) (xy 243.321338 -312.354765) (xy 243.32184 -312.386726)
			(xy 243.321434 -312.416943) (xy 243.314243 -312.476947) (xy 243.299988 -312.535675) (xy 243.278871 -312.592299)
			(xy 243.25119 -312.646021) (xy 243.217336 -312.696081) (xy 243.197888 -312.719212) (xy 243.192256 -312.726345)
			(xy 243.186016 -312.743402) (xy 243.185696 -312.752486) (xy 243.185696 -312.782966) (xy 243.186011 -312.792048)
			(xy 243.192266 -312.809099) (xy 243.197888 -312.81624) (xy 243.217329 -312.839374) (xy 243.251169 -312.88944)
			(xy 243.278838 -312.943163) (xy 243.299948 -312.999786) (xy 243.314199 -313.058511) (xy 243.321391 -313.118511)
			(xy 243.32184 -313.148726) (xy 243.321434 -313.178943) (xy 243.314243 -313.238947) (xy 243.299988 -313.297675)
			(xy 243.278871 -313.354299) (xy 243.25119 -313.408021) (xy 243.217336 -313.458081) (xy 243.197888 -313.481212)
			(xy 243.192256 -313.488345) (xy 243.186016 -313.505402) (xy 243.185696 -313.514486) (xy 243.185696 -313.544966)
			(xy 243.186011 -313.554048) (xy 243.192266 -313.571099) (xy 243.197888 -313.57824) (xy 243.217329 -313.601374)
			(xy 243.251169 -313.65144) (xy 243.278838 -313.705163) (xy 243.299948 -313.761786) (xy 243.314199 -313.820511)
			(xy 243.321391 -313.880511) (xy 243.32184 -313.910726) (xy 243.32136 -313.942525) (xy 243.31344 -314.005627)
			(xy 243.297716 -314.067249) (xy 243.274433 -314.126431) (xy 243.243953 -314.182248) (xy 243.206753 -314.23383)
			(xy 243.185442 -314.257436) (xy 243.179405 -314.264504) (xy 243.17237 -314.281692) (xy 243.171726 -314.290964)
			(xy 243.170964 -314.321444) (xy 243.171162 -314.330783) (xy 243.177408 -314.348371) (xy 243.183156 -314.355734)
			(xy 243.202249 -314.378791) (xy 243.235497 -314.428574) (xy 243.262666 -314.481919) (xy 243.283379 -314.538086)
			(xy 243.297351 -314.596298) (xy 243.304386 -314.655748) (xy 243.304822 -314.68568) (xy 243.304369 -314.715895)
			(xy 243.297184 -314.775897) (xy 243.282937 -314.834624) (xy 243.261829 -314.891247) (xy 243.234158 -314.94497)
			(xy 243.200313 -314.995033) (xy 243.18087 -315.018166) (xy 243.175255 -315.025311) (xy 243.169006 -315.042359)
			(xy 243.168678 -315.05144) (xy 243.168678 -315.08192) (xy 243.169019 -315.091) (xy 243.175256 -315.108051)
			(xy 243.18087 -315.115194) (xy 243.200286 -315.138348) (xy 243.23413 -315.188409) (xy 243.261803 -315.242128)
			(xy 243.282917 -315.298747) (xy 243.297173 -315.357469) (xy 243.304371 -315.417466) (xy 243.304822 -315.44768)
			(xy 244.345206 -315.44768) (xy 244.345628 -315.417464) (xy 244.352818 -315.357461) (xy 244.367071 -315.298733)
			(xy 244.388184 -315.242109) (xy 244.415862 -315.188388) (xy 244.449712 -315.138326) (xy 244.469158 -315.115194)
			(xy 244.474793 -315.108063) (xy 244.48103 -315.091004) (xy 244.48135 -315.08192) (xy 244.48135 -315.05144)
			(xy 244.481044 -315.042356) (xy 244.474784 -315.025305) (xy 244.469158 -315.018166) (xy 244.449712 -314.995037)
			(xy 244.415874 -314.944969) (xy 244.388206 -314.891245) (xy 244.367098 -314.834621) (xy 244.352848 -314.775895)
			(xy 244.345655 -314.715895) (xy 244.345206 -314.68568) (xy 244.345606 -314.655697) (xy 244.352658 -314.596148)
			(xy 244.366663 -314.53784) (xy 244.387425 -314.481584) (xy 244.414657 -314.428158) (xy 244.447981 -314.378304)
			(xy 244.467126 -314.355226) (xy 244.472711 -314.348138) (xy 244.478958 -314.331222) (xy 244.479318 -314.322206)
			(xy 244.479318 -314.29198) (xy 244.479017 -314.282984) (xy 244.472905 -314.266066) (xy 244.46738 -314.25896)
			(xy 244.448263 -314.235889) (xy 244.414972 -314.186069) (xy 244.387761 -314.132685) (xy 244.367005 -314.076476)
			(xy 244.352992 -314.018219) (xy 244.345915 -313.958719) (xy 244.34546 -313.92876) (xy 244.345917 -313.898545)
			(xy 244.353098 -313.838543) (xy 244.367343 -313.779815) (xy 244.38845 -313.723191) (xy 244.416122 -313.669469)
			(xy 244.449968 -313.619406) (xy 244.469412 -313.596274) (xy 244.47505 -313.589145) (xy 244.481286 -313.572084)
			(xy 244.481604 -313.563) (xy 244.481604 -313.53252) (xy 244.481296 -313.523437) (xy 244.475036 -313.506386)
			(xy 244.469412 -313.499246) (xy 244.449965 -313.476117) (xy 244.416125 -313.42605) (xy 244.388457 -313.372326)
			(xy 244.367349 -313.315702) (xy 244.353099 -313.256976) (xy 244.345908 -313.196975) (xy 244.34546 -313.16676)
			(xy 244.345917 -313.136545) (xy 244.353098 -313.076543) (xy 244.367343 -313.017815) (xy 244.38845 -312.961191)
			(xy 244.416122 -312.907469) (xy 244.449968 -312.857406) (xy 244.469412 -312.834274) (xy 244.47505 -312.827145)
			(xy 244.481286 -312.810084) (xy 244.481604 -312.801) (xy 244.481604 -312.77052) (xy 244.481296 -312.761437)
			(xy 244.475036 -312.744386) (xy 244.469412 -312.737246) (xy 244.449965 -312.714117) (xy 244.416125 -312.66405)
			(xy 244.388457 -312.610326) (xy 244.367349 -312.553702) (xy 244.353099 -312.494976) (xy 244.345908 -312.434975)
			(xy 244.34546 -312.40476) (xy 244.345962 -312.372799) (xy 244.353973 -312.309381) (xy 244.36987 -312.247467)
			(xy 244.393402 -312.188034) (xy 244.424196 -312.132019) (xy 244.461769 -312.080304) (xy 244.505526 -312.033707)
			(xy 244.554779 -311.992962) (xy 244.60875 -311.958711) (xy 244.666589 -311.931494) (xy 244.727382 -311.911741)
			(xy 244.790172 -311.899763) (xy 244.853968 -311.89575) (xy 244.917764 -311.899763) (xy 244.980554 -311.911741)
			(xy 245.041347 -311.931494) (xy 245.099186 -311.958711) (xy 245.153157 -311.992962) (xy 245.20241 -312.033707)
			(xy 245.246167 -312.080304) (xy 245.28374 -312.132019) (xy 245.314534 -312.188034) (xy 245.338066 -312.247467)
			(xy 245.353963 -312.309381) (xy 245.361974 -312.372799) (xy 245.362476 -312.40476) (xy 245.362022 -312.434975)
			(xy 245.354839 -312.494977) (xy 245.340593 -312.553704) (xy 245.319485 -312.610328) (xy 245.291813 -312.664051)
			(xy 245.257967 -312.714114) (xy 245.238524 -312.737246) (xy 245.232924 -312.744401) (xy 245.226664 -312.761442)
			(xy 245.226332 -312.77052) (xy 245.226332 -312.801) (xy 245.226671 -312.81008) (xy 245.232908 -312.827132)
			(xy 245.238524 -312.834274) (xy 245.257986 -312.85739) (xy 245.291823 -312.907461) (xy 245.319489 -312.961188)
			(xy 245.340594 -313.017814) (xy 245.354841 -313.076542) (xy 245.362029 -313.136544) (xy 245.362476 -313.16676)
			(xy 245.362022 -313.196975) (xy 245.354839 -313.256977) (xy 245.340593 -313.315704) (xy 245.319485 -313.372328)
			(xy 245.291813 -313.426051) (xy 245.257967 -313.476114) (xy 245.238524 -313.499246) (xy 245.232924 -313.506401)
			(xy 245.226664 -313.523442) (xy 245.226332 -313.53252) (xy 245.226332 -313.563) (xy 245.226671 -313.57208)
			(xy 245.232908 -313.589132) (xy 245.238524 -313.596274) (xy 245.257986 -313.61939) (xy 245.291823 -313.669461)
			(xy 245.319489 -313.723188) (xy 245.340594 -313.779814) (xy 245.354841 -313.838542) (xy 245.362029 -313.898544)
			(xy 245.362401 -313.92368) (xy 245.793006 -313.92368) (xy 245.793428 -313.893464) (xy 245.800618 -313.833461)
			(xy 245.814871 -313.774733) (xy 245.835984 -313.718109) (xy 245.863662 -313.664388) (xy 245.897512 -313.614326)
			(xy 245.916958 -313.591194) (xy 245.922593 -313.584063) (xy 245.92883 -313.567004) (xy 245.92915 -313.55792)
			(xy 245.92915 -313.52744) (xy 245.928844 -313.518356) (xy 245.922584 -313.501305) (xy 245.916958 -313.494166)
			(xy 245.897512 -313.471037) (xy 245.863674 -313.420969) (xy 245.836006 -313.367245) (xy 245.814898 -313.310621)
			(xy 245.800648 -313.251895) (xy 245.793455 -313.191895) (xy 245.793006 -313.16168) (xy 245.793428 -313.131464)
			(xy 245.800618 -313.071461) (xy 245.814871 -313.012733) (xy 245.835984 -312.956109) (xy 245.863662 -312.902388)
			(xy 245.897512 -312.852326) (xy 245.916958 -312.829194) (xy 245.922593 -312.822063) (xy 245.92883 -312.805004)
			(xy 245.92915 -312.79592) (xy 245.92915 -312.76544) (xy 245.928844 -312.756356) (xy 245.922584 -312.739305)
			(xy 245.916958 -312.732166) (xy 245.897512 -312.709037) (xy 245.863674 -312.658969) (xy 245.836006 -312.605245)
			(xy 245.814898 -312.548621) (xy 245.800648 -312.489895) (xy 245.793455 -312.429895) (xy 245.793006 -312.39968)
			(xy 245.793508 -312.367719) (xy 245.801519 -312.304301) (xy 245.817416 -312.242387) (xy 245.840948 -312.182954)
			(xy 245.871742 -312.126939) (xy 245.909315 -312.075224) (xy 245.953072 -312.028627) (xy 246.002325 -311.987882)
			(xy 246.056296 -311.953631) (xy 246.114135 -311.926414) (xy 246.174928 -311.906661) (xy 246.237718 -311.894683)
			(xy 246.301514 -311.89067) (xy 246.36531 -311.894683) (xy 246.4281 -311.906661) (xy 246.488893 -311.926414)
			(xy 246.546732 -311.953631) (xy 246.600703 -311.987882) (xy 246.649956 -312.028627) (xy 246.693713 -312.075224)
			(xy 246.731286 -312.126939) (xy 246.76208 -312.182954) (xy 246.785612 -312.242387) (xy 246.801509 -312.304301)
			(xy 246.80952 -312.367719) (xy 246.810022 -312.39968) (xy 246.809569 -312.429895) (xy 246.802384 -312.489897)
			(xy 246.788137 -312.548624) (xy 246.767029 -312.605247) (xy 246.739358 -312.65897) (xy 246.705513 -312.709033)
			(xy 246.68607 -312.732166) (xy 246.680455 -312.739311) (xy 246.674206 -312.756359) (xy 246.673878 -312.76544)
			(xy 246.673878 -312.79592) (xy 246.674219 -312.805) (xy 246.680456 -312.822051) (xy 246.68607 -312.829194)
			(xy 246.705486 -312.852348) (xy 246.73933 -312.902409) (xy 246.767003 -312.956128) (xy 246.788117 -313.012747)
			(xy 246.802373 -313.071469) (xy 246.809571 -313.131466) (xy 246.810022 -313.16168) (xy 246.809569 -313.191895)
			(xy 246.802384 -313.251897) (xy 246.788137 -313.310624) (xy 246.767029 -313.367247) (xy 246.739358 -313.42097)
			(xy 246.705513 -313.471033) (xy 246.68607 -313.494166) (xy 246.680455 -313.501311) (xy 246.674206 -313.518359)
			(xy 246.673878 -313.52744) (xy 246.673878 -313.55792) (xy 246.674219 -313.567) (xy 246.680456 -313.584051)
			(xy 246.68607 -313.591194) (xy 246.705486 -313.614348) (xy 246.73933 -313.664409) (xy 246.767003 -313.718128)
			(xy 246.788117 -313.774747) (xy 246.802373 -313.833469) (xy 246.809571 -313.893466) (xy 246.810022 -313.92368)
			(xy 246.80952 -313.955641) (xy 246.801509 -314.019059) (xy 246.785612 -314.080973) (xy 246.76208 -314.140406)
			(xy 246.731286 -314.196421) (xy 246.693713 -314.248136) (xy 246.649956 -314.294733) (xy 246.600703 -314.335478)
			(xy 246.546732 -314.369729) (xy 246.488893 -314.396946) (xy 246.4281 -314.416699) (xy 246.36531 -314.428677)
			(xy 246.301514 -314.432691) (xy 246.237718 -314.428677) (xy 246.174928 -314.416699) (xy 246.114135 -314.396946)
			(xy 246.056296 -314.369729) (xy 246.002325 -314.335478) (xy 245.953072 -314.294733) (xy 245.909315 -314.248136)
			(xy 245.871742 -314.196421) (xy 245.840948 -314.140406) (xy 245.817416 -314.080973) (xy 245.801519 -314.019059)
			(xy 245.793508 -313.955641) (xy 245.793006 -313.92368) (xy 245.362401 -313.92368) (xy 245.362476 -313.92876)
			(xy 245.362045 -313.958742) (xy 245.354999 -314.01829) (xy 245.341001 -314.076597) (xy 245.320245 -314.132854)
			(xy 245.293019 -314.18628) (xy 245.259699 -314.236135) (xy 245.240556 -314.259214) (xy 245.234952 -314.266289)
			(xy 245.228717 -314.283215) (xy 245.228364 -314.292234) (xy 245.228364 -314.32246) (xy 245.228628 -314.33146)
			(xy 245.234764 -314.348379) (xy 245.240302 -314.35548) (xy 245.259435 -314.378539) (xy 245.292725 -314.428361)
			(xy 245.319934 -314.481747) (xy 245.340687 -314.537959) (xy 245.354697 -314.596219) (xy 245.361769 -314.65572)
			(xy 245.362222 -314.68568) (xy 245.361769 -314.715895) (xy 245.354584 -314.775897) (xy 245.340337 -314.834624)
			(xy 245.319229 -314.891247) (xy 245.291558 -314.94497) (xy 245.257713 -314.995033) (xy 245.23827 -315.018166)
			(xy 245.232655 -315.025311) (xy 245.226406 -315.042359) (xy 245.226078 -315.05144) (xy 245.226078 -315.08192)
			(xy 245.226419 -315.091) (xy 245.232656 -315.108051) (xy 245.23827 -315.115194) (xy 245.257686 -315.138348)
			(xy 245.29153 -315.188409) (xy 245.319203 -315.242128) (xy 245.340317 -315.298747) (xy 245.354573 -315.357469)
			(xy 245.361771 -315.417466) (xy 245.362222 -315.44768) (xy 248.180606 -315.44768) (xy 248.181028 -315.417464)
			(xy 248.188218 -315.357461) (xy 248.202471 -315.298733) (xy 248.223584 -315.242109) (xy 248.251262 -315.188388)
			(xy 248.285112 -315.138326) (xy 248.304558 -315.115194) (xy 248.310193 -315.108063) (xy 248.31643 -315.091004)
			(xy 248.31675 -315.08192) (xy 248.31675 -315.05144) (xy 248.316444 -315.042356) (xy 248.310184 -315.025305)
			(xy 248.304558 -315.018166) (xy 248.285112 -314.995037) (xy 248.251274 -314.944969) (xy 248.223606 -314.891245)
			(xy 248.202498 -314.834621) (xy 248.188248 -314.775895) (xy 248.181055 -314.715895) (xy 248.180606 -314.68568)
			(xy 248.181028 -314.655464) (xy 248.188218 -314.595461) (xy 248.202471 -314.536733) (xy 248.223584 -314.480109)
			(xy 248.251262 -314.426388) (xy 248.285112 -314.376326) (xy 248.304558 -314.353194) (xy 248.310193 -314.346063)
			(xy 248.31643 -314.329004) (xy 248.31675 -314.31992) (xy 248.31675 -314.28944) (xy 248.316444 -314.280356)
			(xy 248.310184 -314.263305) (xy 248.304558 -314.256166) (xy 248.285112 -314.233037) (xy 248.251274 -314.182969)
			(xy 248.223606 -314.129245) (xy 248.202498 -314.072621) (xy 248.188248 -314.013895) (xy 248.181055 -313.953895)
			(xy 248.180606 -313.92368) (xy 248.181028 -313.893464) (xy 248.188218 -313.833461) (xy 248.202471 -313.774733)
			(xy 248.223584 -313.718109) (xy 248.251262 -313.664388) (xy 248.285112 -313.614326) (xy 248.304558 -313.591194)
			(xy 248.310193 -313.584063) (xy 248.31643 -313.567004) (xy 248.31675 -313.55792) (xy 248.31675 -313.52744)
			(xy 248.316444 -313.518356) (xy 248.310184 -313.501305) (xy 248.304558 -313.494166) (xy 248.285112 -313.471037)
			(xy 248.251274 -313.420969) (xy 248.223606 -313.367245) (xy 248.202498 -313.310621) (xy 248.188248 -313.251895)
			(xy 248.181055 -313.191895) (xy 248.180606 -313.16168) (xy 248.181028 -313.131464) (xy 248.188218 -313.071461)
			(xy 248.202471 -313.012733) (xy 248.223584 -312.956109) (xy 248.251262 -312.902388) (xy 248.285112 -312.852326)
			(xy 248.304558 -312.829194) (xy 248.310193 -312.822063) (xy 248.31643 -312.805004) (xy 248.31675 -312.79592)
			(xy 248.31675 -312.76544) (xy 248.316444 -312.756356) (xy 248.310184 -312.739305) (xy 248.304558 -312.732166)
			(xy 248.285112 -312.709037) (xy 248.251274 -312.658969) (xy 248.223606 -312.605245) (xy 248.202498 -312.548621)
			(xy 248.188248 -312.489895) (xy 248.181055 -312.429895) (xy 248.180606 -312.39968) (xy 248.181108 -312.367719)
			(xy 248.189119 -312.304301) (xy 248.205016 -312.242387) (xy 248.228548 -312.182954) (xy 248.259342 -312.126939)
			(xy 248.296915 -312.075224) (xy 248.340672 -312.028627) (xy 248.389925 -311.987882) (xy 248.443896 -311.953631)
			(xy 248.501735 -311.926414) (xy 248.562528 -311.906661) (xy 248.625318 -311.894683) (xy 248.689114 -311.89067)
			(xy 248.75291 -311.894683) (xy 248.8157 -311.906661) (xy 248.876493 -311.926414) (xy 248.934332 -311.953631)
			(xy 248.988303 -311.987882) (xy 249.037556 -312.028627) (xy 249.081313 -312.075224) (xy 249.118886 -312.126939)
			(xy 249.14968 -312.182954) (xy 249.173212 -312.242387) (xy 249.189109 -312.304301) (xy 249.19712 -312.367719)
			(xy 249.197622 -312.39968) (xy 249.197169 -312.429895) (xy 249.189984 -312.489897) (xy 249.175737 -312.548624)
			(xy 249.154629 -312.605247) (xy 249.126958 -312.65897) (xy 249.093113 -312.709033) (xy 249.07367 -312.732166)
			(xy 249.068055 -312.739311) (xy 249.061806 -312.756359) (xy 249.061478 -312.76544) (xy 249.061478 -312.79592)
			(xy 249.061819 -312.805) (xy 249.068056 -312.822051) (xy 249.07367 -312.829194) (xy 249.093086 -312.852348)
			(xy 249.12693 -312.902409) (xy 249.154603 -312.956128) (xy 249.175717 -313.012747) (xy 249.189973 -313.071469)
			(xy 249.197171 -313.131466) (xy 249.197622 -313.16168) (xy 249.197169 -313.191895) (xy 249.189984 -313.251897)
			(xy 249.175737 -313.310624) (xy 249.154629 -313.367247) (xy 249.126958 -313.42097) (xy 249.093113 -313.471033)
			(xy 249.07367 -313.494166) (xy 249.068055 -313.501311) (xy 249.061806 -313.518359) (xy 249.061478 -313.52744)
			(xy 249.061478 -313.55792) (xy 249.061819 -313.567) (xy 249.068056 -313.584051) (xy 249.07367 -313.591194)
			(xy 249.093086 -313.614348) (xy 249.12693 -313.664409) (xy 249.154603 -313.718128) (xy 249.175717 -313.774747)
			(xy 249.189973 -313.833469) (xy 249.197171 -313.893466) (xy 249.197622 -313.92368) (xy 249.197169 -313.953895)
			(xy 249.189984 -314.013897) (xy 249.175737 -314.072624) (xy 249.154629 -314.129247) (xy 249.126958 -314.18297)
			(xy 249.093113 -314.233033) (xy 249.07367 -314.256166) (xy 249.068055 -314.263311) (xy 249.061806 -314.280359)
			(xy 249.061478 -314.28944) (xy 249.061478 -314.31992) (xy 249.061819 -314.329) (xy 249.068056 -314.346051)
			(xy 249.07367 -314.353194) (xy 249.093086 -314.376348) (xy 249.12693 -314.426409) (xy 249.154603 -314.480128)
			(xy 249.175717 -314.536747) (xy 249.189973 -314.595469) (xy 249.197171 -314.655466) (xy 249.197622 -314.68568)
			(xy 249.197169 -314.715895) (xy 249.189984 -314.775897) (xy 249.175737 -314.834624) (xy 249.154629 -314.891247)
			(xy 249.126958 -314.94497) (xy 249.093113 -314.995033) (xy 249.07367 -315.018166) (xy 249.068055 -315.025311)
			(xy 249.061806 -315.042359) (xy 249.061478 -315.05144) (xy 249.061478 -315.08192) (xy 249.061819 -315.091)
			(xy 249.068056 -315.108051) (xy 249.07367 -315.115194) (xy 249.093086 -315.138348) (xy 249.12693 -315.188409)
			(xy 249.154603 -315.242128) (xy 249.175717 -315.298747) (xy 249.189973 -315.357469) (xy 249.197171 -315.417466)
			(xy 249.197622 -315.44768) (xy 249.19712 -315.479641) (xy 249.189109 -315.543059) (xy 249.173212 -315.604973)
			(xy 249.14968 -315.664406) (xy 249.118886 -315.720421) (xy 249.081313 -315.772136) (xy 249.037556 -315.818733)
			(xy 248.988303 -315.859478) (xy 248.934332 -315.893729) (xy 248.876493 -315.920946) (xy 248.8157 -315.940699)
			(xy 248.75291 -315.952677) (xy 248.689114 -315.956691) (xy 248.625318 -315.952677) (xy 248.562528 -315.940699)
			(xy 248.501735 -315.920946) (xy 248.443896 -315.893729) (xy 248.389925 -315.859478) (xy 248.340672 -315.818733)
			(xy 248.296915 -315.772136) (xy 248.259342 -315.720421) (xy 248.228548 -315.664406) (xy 248.205016 -315.604973)
			(xy 248.189119 -315.543059) (xy 248.181108 -315.479641) (xy 248.180606 -315.44768) (xy 245.362222 -315.44768)
			(xy 245.36172 -315.479641) (xy 245.353709 -315.543059) (xy 245.337812 -315.604973) (xy 245.31428 -315.664406)
			(xy 245.283486 -315.720421) (xy 245.245913 -315.772136) (xy 245.202156 -315.818733) (xy 245.152903 -315.859478)
			(xy 245.098932 -315.893729) (xy 245.041093 -315.920946) (xy 244.9803 -315.940699) (xy 244.91751 -315.952677)
			(xy 244.853714 -315.956691) (xy 244.789918 -315.952677) (xy 244.727128 -315.940699) (xy 244.666335 -315.920946)
			(xy 244.608496 -315.893729) (xy 244.554525 -315.859478) (xy 244.505272 -315.818733) (xy 244.461515 -315.772136)
			(xy 244.423942 -315.720421) (xy 244.393148 -315.664406) (xy 244.369616 -315.604973) (xy 244.353719 -315.543059)
			(xy 244.345708 -315.479641) (xy 244.345206 -315.44768) (xy 243.304822 -315.44768) (xy 243.30432 -315.479641)
			(xy 243.296309 -315.543059) (xy 243.280412 -315.604973) (xy 243.25688 -315.664406) (xy 243.226086 -315.720421)
			(xy 243.188513 -315.772136) (xy 243.144756 -315.818733) (xy 243.095503 -315.859478) (xy 243.041532 -315.893729)
			(xy 242.983693 -315.920946) (xy 242.9229 -315.940699) (xy 242.86011 -315.952677) (xy 242.796314 -315.956691)
			(xy 242.732518 -315.952677) (xy 242.669728 -315.940699) (xy 242.608935 -315.920946) (xy 242.551096 -315.893729)
			(xy 242.497125 -315.859478) (xy 242.447872 -315.818733) (xy 242.404115 -315.772136) (xy 242.366542 -315.720421)
			(xy 242.335748 -315.664406) (xy 242.312216 -315.604973) (xy 242.296319 -315.543059) (xy 242.288308 -315.479641)
			(xy 242.287806 -315.44768) (xy 239.469422 -315.44768) (xy 239.46892 -315.479641) (xy 239.460909 -315.543059)
			(xy 239.445012 -315.604973) (xy 239.42148 -315.664406) (xy 239.390686 -315.720421) (xy 239.353113 -315.772136)
			(xy 239.309356 -315.818733) (xy 239.260103 -315.859478) (xy 239.206132 -315.893729) (xy 239.148293 -315.920946)
			(xy 239.0875 -315.940699) (xy 239.02471 -315.952677) (xy 238.960914 -315.956691) (xy 238.897118 -315.952677)
			(xy 238.834328 -315.940699) (xy 238.773535 -315.920946) (xy 238.715696 -315.893729) (xy 238.661725 -315.859478)
			(xy 238.612472 -315.818733) (xy 238.568715 -315.772136) (xy 238.531142 -315.720421) (xy 238.500348 -315.664406)
			(xy 238.476816 -315.604973) (xy 238.460919 -315.543059) (xy 238.452908 -315.479641) (xy 238.452406 -315.44768)
			(xy 238.452828 -315.417464) (xy 238.460018 -315.357461) (xy 238.474271 -315.298733) (xy 238.495384 -315.242109)
			(xy 238.523062 -315.188388) (xy 238.556912 -315.138326) (xy 238.576358 -315.115194) (xy 238.581993 -315.108063)
			(xy 238.58823 -315.091004) (xy 238.58855 -315.08192) (xy 238.58855 -315.05144) (xy 238.588244 -315.042356)
			(xy 238.581984 -315.025305) (xy 238.576358 -315.018166) (xy 238.556912 -314.995037) (xy 238.523074 -314.944969)
			(xy 238.495406 -314.891245) (xy 238.474298 -314.834621) (xy 238.460048 -314.775895) (xy 238.452855 -314.715895)
			(xy 238.452406 -314.68568) (xy 238.452997 -314.650984) (xy 238.462446 -314.582237) (xy 238.481153 -314.515414)
			(xy 238.508769 -314.451753) (xy 238.544784 -314.392438) (xy 238.566198 -314.365132) (xy 238.57204 -314.35802)
			(xy 238.577882 -314.340748) (xy 238.57458 -314.25515) (xy 238.567722 -314.23864) (xy 238.561372 -314.231782)
			(xy 238.539869 -314.208151) (xy 238.502341 -314.156441) (xy 238.471584 -314.100439) (xy 238.448082 -314.041026)
			(xy 238.432206 -313.979138) (xy 238.424204 -313.915748) (xy 238.423704 -313.883802) (xy 238.22263 -313.883802)
			(xy 238.217141 -313.929535) (xy 238.202772 -313.98856) (xy 238.181477 -314.045455) (xy 238.153559 -314.099409)
			(xy 238.119416 -314.149655) (xy 238.079532 -314.195478) (xy 238.034477 -314.236227) (xy 238.009938 -314.254134)
			(xy 237.999778 -314.261246) (xy 237.988348 -314.283344) (xy 237.988856 -314.391294) (xy 238.000286 -314.413392)
			(xy 238.010446 -314.420504) (xy 238.035349 -314.438352) (xy 238.081113 -314.479091) (xy 238.121648 -314.525036)
			(xy 238.156367 -314.575519) (xy 238.184767 -314.62981) (xy 238.206436 -314.68712) (xy 238.22106 -314.746619)
			(xy 238.228426 -314.807445) (xy 238.228886 -314.83808) (xy 238.228384 -314.870041) (xy 238.220373 -314.933459)
			(xy 238.204476 -314.995373) (xy 238.180944 -315.054806) (xy 238.15015 -315.110821) (xy 238.112577 -315.162536)
			(xy 238.06882 -315.209133) (xy 238.019567 -315.249878) (xy 237.965596 -315.284129) (xy 237.907757 -315.311346)
			(xy 237.846964 -315.331099) (xy 237.784174 -315.343077) (xy 237.720378 -315.347091) (xy 237.656582 -315.343077)
			(xy 237.593792 -315.331099) (xy 237.532999 -315.311346) (xy 237.47516 -315.284129) (xy 237.421189 -315.249878)
			(xy 237.371936 -315.209133) (xy 237.328179 -315.162536) (xy 237.290606 -315.110821) (xy 237.259812 -315.054806)
			(xy 237.23628 -314.995373) (xy 237.220383 -314.933459) (xy 237.212372 -314.870041) (xy 237.21187 -314.83808)
			(xy 237.212334 -314.807706) (xy 237.219569 -314.747391) (xy 237.233935 -314.688366) (xy 237.255227 -314.631472)
			(xy 237.283142 -314.577518) (xy 237.317283 -314.527271) (xy 237.357163 -314.481447) (xy 237.402217 -314.440698)
			(xy 237.426754 -314.42279) (xy 237.436914 -314.415678) (xy 237.448344 -314.39358) (xy 237.447836 -314.28563)
			(xy 237.436406 -314.263532) (xy 237.426246 -314.25642) (xy 237.401352 -314.23856) (xy 237.355589 -314.197822)
			(xy 237.315053 -314.151879) (xy 237.280333 -314.101397) (xy 237.251932 -314.047109) (xy 237.230262 -313.9898)
			(xy 237.215636 -313.930302) (xy 237.208267 -313.869478) (xy 237.207806 -313.838844) (xy 234.208683 -313.838844)
			(xy 234.215235 -313.893466) (xy 234.215686 -313.92368) (xy 234.215242 -313.953895) (xy 234.208056 -314.013898)
			(xy 234.193808 -314.072625) (xy 234.172699 -314.129249) (xy 234.145025 -314.182971) (xy 234.111178 -314.233034)
			(xy 234.091734 -314.256166) (xy 234.086115 -314.263307) (xy 234.079869 -314.280359) (xy 234.079542 -314.28944)
			(xy 234.079542 -314.31992) (xy 234.079869 -314.329001) (xy 234.086114 -314.346053) (xy 234.091734 -314.353194)
			(xy 234.11116 -314.37634) (xy 234.145001 -314.426404) (xy 234.172672 -314.480124) (xy 234.193783 -314.536745)
			(xy 234.208038 -314.595468) (xy 234.215235 -314.655466) (xy 234.215686 -314.68568) (xy 234.215242 -314.715895)
			(xy 234.208056 -314.775898) (xy 234.193808 -314.834625) (xy 234.172699 -314.891249) (xy 234.145025 -314.944971)
			(xy 234.111178 -314.995034) (xy 234.091734 -315.018166) (xy 234.086115 -315.025307) (xy 234.079869 -315.042359)
			(xy 234.079542 -315.05144) (xy 234.079542 -315.08192) (xy 234.079869 -315.091001) (xy 234.086114 -315.108053)
			(xy 234.091734 -315.115194) (xy 234.11116 -315.13834) (xy 234.145001 -315.188404) (xy 234.172672 -315.242124)
			(xy 234.193783 -315.298745) (xy 234.208038 -315.357468) (xy 234.215235 -315.417466) (xy 234.215686 -315.44768)
			(xy 234.215184 -315.479641) (xy 234.207173 -315.543059) (xy 234.191276 -315.604973) (xy 234.167744 -315.664406)
			(xy 234.13695 -315.720421) (xy 234.099377 -315.772136) (xy 234.05562 -315.818733) (xy 234.006367 -315.859478)
			(xy 233.952396 -315.893729) (xy 233.894557 -315.920946) (xy 233.833764 -315.940699) (xy 233.770974 -315.952677)
			(xy 233.707178 -315.956691) (xy 233.643382 -315.952677) (xy 233.580592 -315.940699) (xy 233.519799 -315.920946)
			(xy 233.46196 -315.893729) (xy 233.407989 -315.859478) (xy 233.358736 -315.818733) (xy 233.314979 -315.772136)
			(xy 233.277406 -315.720421) (xy 233.246612 -315.664406) (xy 233.22308 -315.604973) (xy 233.207183 -315.543059)
			(xy 233.199172 -315.479641) (xy 233.19867 -315.44768) (xy 230.380286 -315.44768) (xy 230.379784 -315.479641)
			(xy 230.371773 -315.543059) (xy 230.355876 -315.604973) (xy 230.332344 -315.664406) (xy 230.30155 -315.720421)
			(xy 230.263977 -315.772136) (xy 230.22022 -315.818733) (xy 230.170967 -315.859478) (xy 230.116996 -315.893729)
			(xy 230.059157 -315.920946) (xy 229.998364 -315.940699) (xy 229.935574 -315.952677) (xy 229.871778 -315.956691)
			(xy 229.807982 -315.952677) (xy 229.745192 -315.940699) (xy 229.684399 -315.920946) (xy 229.62656 -315.893729)
			(xy 229.572589 -315.859478) (xy 229.523336 -315.818733) (xy 229.479579 -315.772136) (xy 229.442006 -315.720421)
			(xy 229.411212 -315.664406) (xy 229.38768 -315.604973) (xy 229.371783 -315.543059) (xy 229.363772 -315.479641)
			(xy 229.36327 -315.44768) (xy 228.322886 -315.44768) (xy 228.322384 -315.479641) (xy 228.314373 -315.543059)
			(xy 228.298476 -315.604973) (xy 228.274944 -315.664406) (xy 228.24415 -315.720421) (xy 228.206577 -315.772136)
			(xy 228.16282 -315.818733) (xy 228.113567 -315.859478) (xy 228.059596 -315.893729) (xy 228.001757 -315.920946)
			(xy 227.940964 -315.940699) (xy 227.878174 -315.952677) (xy 227.814378 -315.956691) (xy 227.750582 -315.952677)
			(xy 227.687792 -315.940699) (xy 227.626999 -315.920946) (xy 227.56916 -315.893729) (xy 227.515189 -315.859478)
			(xy 227.465936 -315.818733) (xy 227.422179 -315.772136) (xy 227.384606 -315.720421) (xy 227.353812 -315.664406)
			(xy 227.33028 -315.604973) (xy 227.314383 -315.543059) (xy 227.306372 -315.479641) (xy 227.30587 -315.44768)
			(xy 224.487486 -315.44768) (xy 224.486984 -315.479641) (xy 224.478973 -315.543059) (xy 224.463076 -315.604973)
			(xy 224.439544 -315.664406) (xy 224.40875 -315.720421) (xy 224.371177 -315.772136) (xy 224.32742 -315.818733)
			(xy 224.278167 -315.859478) (xy 224.224196 -315.893729) (xy 224.166357 -315.920946) (xy 224.105564 -315.940699)
			(xy 224.042774 -315.952677) (xy 223.978978 -315.956691) (xy 223.915182 -315.952677) (xy 223.852392 -315.940699)
			(xy 223.791599 -315.920946) (xy 223.73376 -315.893729) (xy 223.679789 -315.859478) (xy 223.630536 -315.818733)
			(xy 223.586779 -315.772136) (xy 223.549206 -315.720421) (xy 223.518412 -315.664406) (xy 223.49488 -315.604973)
			(xy 223.478983 -315.543059) (xy 223.470972 -315.479641) (xy 223.47047 -315.44768) (xy 223.470877 -315.417463)
			(xy 223.478068 -315.357459) (xy 223.492322 -315.298731) (xy 223.513439 -315.242107) (xy 223.541119 -315.188385)
			(xy 223.574974 -315.138325) (xy 223.594422 -315.115194) (xy 223.600053 -315.10806) (xy 223.606293 -315.091003)
			(xy 223.606614 -315.08192) (xy 223.606614 -315.05144) (xy 223.606294 -315.042358) (xy 223.600042 -315.025307)
			(xy 223.594422 -315.018166) (xy 223.574986 -314.995028) (xy 223.541145 -314.944963) (xy 223.513474 -314.891241)
			(xy 223.492364 -314.834619) (xy 223.478112 -314.775894) (xy 223.470919 -314.715894) (xy 223.47047 -314.68568)
			(xy 223.471069 -314.650984) (xy 223.480518 -314.582238) (xy 223.499223 -314.515415) (xy 223.526837 -314.451755)
			(xy 223.562849 -314.392438) (xy 223.584262 -314.365132) (xy 223.590104 -314.35802) (xy 223.595946 -314.340748)
			(xy 223.592644 -314.25515) (xy 223.585786 -314.23864) (xy 223.579436 -314.231782) (xy 223.557927 -314.208156)
			(xy 223.520401 -314.156445) (xy 223.489646 -314.100441) (xy 223.466145 -314.041027) (xy 223.450269 -313.979138)
			(xy 223.442268 -313.915748) (xy 223.441768 -313.883802) (xy 223.240709 -313.883802) (xy 223.23522 -313.929537)
			(xy 223.22085 -313.988563) (xy 223.199553 -314.045458) (xy 223.171633 -314.099413) (xy 223.137487 -314.149658)
			(xy 223.097601 -314.195481) (xy 223.052542 -314.236228) (xy 223.028002 -314.254134) (xy 223.017842 -314.261246)
			(xy 223.006412 -314.283344) (xy 223.00692 -314.391294) (xy 223.01835 -314.413392) (xy 223.02851 -314.420504)
			(xy 223.053428 -314.438332) (xy 223.099188 -314.479076) (xy 223.139721 -314.525025) (xy 223.174437 -314.575512)
			(xy 223.202835 -314.629805) (xy 223.224502 -314.687117) (xy 223.239125 -314.746618) (xy 223.24649 -314.807444)
			(xy 223.24695 -314.83808) (xy 223.246448 -314.870041) (xy 223.238437 -314.933459) (xy 223.22254 -314.995373)
			(xy 223.199008 -315.054806) (xy 223.168214 -315.110821) (xy 223.130641 -315.162536) (xy 223.086884 -315.209133)
			(xy 223.037631 -315.249878) (xy 222.98366 -315.284129) (xy 222.925821 -315.311346) (xy 222.865028 -315.331099)
			(xy 222.802238 -315.343077) (xy 222.738442 -315.347091) (xy 222.674646 -315.343077) (xy 222.611856 -315.331099)
			(xy 222.551063 -315.311346) (xy 222.493224 -315.284129) (xy 222.439253 -315.249878) (xy 222.39 -315.209133)
			(xy 222.346243 -315.162536) (xy 222.30867 -315.110821) (xy 222.277876 -315.054806) (xy 222.254344 -314.995373)
			(xy 222.238447 -314.933459) (xy 222.230436 -314.870041) (xy 222.229934 -314.83808) (xy 222.230371 -314.807705)
			(xy 222.237608 -314.747388) (xy 222.251976 -314.688361) (xy 222.27327 -314.631466) (xy 222.301189 -314.577511)
			(xy 222.335334 -314.527265) (xy 222.37522 -314.481443) (xy 222.420278 -314.440696) (xy 222.444818 -314.42279)
			(xy 222.454978 -314.415678) (xy 222.466408 -314.39358) (xy 222.4659 -314.28563) (xy 222.45447 -314.263532)
			(xy 222.44431 -314.25642) (xy 222.419408 -314.238571) (xy 222.373646 -314.19783) (xy 222.333112 -314.151885)
			(xy 222.298394 -314.101401) (xy 222.269994 -314.047111) (xy 222.248325 -313.989802) (xy 222.2337 -313.930304)
			(xy 222.226331 -313.869479) (xy 222.22587 -313.838844) (xy 218.193874 -313.838844) (xy 218.193874 -317.452459)
			(xy 218.45117 -317.452459) (xy 218.45117 -317.388537) (xy 218.459181 -317.325119) (xy 218.475078 -317.263205)
			(xy 218.49861 -317.203772) (xy 218.529404 -317.147757) (xy 218.566977 -317.096042) (xy 218.610734 -317.049445)
			(xy 218.659987 -317.0087) (xy 218.713958 -316.974449) (xy 218.771797 -316.947232) (xy 218.83259 -316.927479)
			(xy 218.89538 -316.915501) (xy 218.959176 -316.911488) (xy 219.022972 -316.915501) (xy 219.085762 -316.927479)
			(xy 219.146555 -316.947232) (xy 219.204394 -316.974449) (xy 219.258365 -317.0087) (xy 219.307618 -317.049445)
			(xy 219.351375 -317.096042) (xy 219.388948 -317.147757) (xy 219.419742 -317.203772) (xy 219.420773 -317.206376)
			(xy 222.497902 -317.206376) (xy 222.501973 -317.150754) (xy 222.514099 -317.096317) (xy 222.534022 -317.044226)
			(xy 222.561318 -316.995591) (xy 222.595404 -316.951448) (xy 222.635553 -316.912739) (xy 222.680911 -316.880288)
			(xy 222.730511 -316.854787) (xy 222.783295 -316.83678) (xy 222.838138 -316.82665) (xy 222.893872 -316.824613)
			(xy 222.949309 -316.830713) (xy 223.003266 -316.844819) (xy 223.054595 -316.866631) (xy 223.102201 -316.895685)
			(xy 223.145069 -316.93136) (xy 223.182286 -316.972897) (xy 223.213059 -317.01941) (xy 223.236731 -317.069907)
			(xy 223.252799 -317.123314) (xy 223.260919 -317.17849) (xy 223.261428 -317.206376) (xy 223.261076 -317.22568)
			(xy 223.59747 -317.22568) (xy 223.598019 -317.196764) (xy 223.606738 -317.139593) (xy 223.623988 -317.084394)
			(xy 223.649374 -317.032431) (xy 223.682314 -316.984897) (xy 223.722052 -316.94288) (xy 223.744536 -316.92469)
			(xy 223.753304 -316.917134) (xy 223.763483 -316.896371) (xy 223.764094 -316.884812) (xy 223.764094 -316.804548)
			(xy 223.763498 -316.792983) (xy 223.753322 -316.772212) (xy 223.744536 -316.76467) (xy 223.722046 -316.746487)
			(xy 223.682309 -316.704467) (xy 223.64937 -316.65693) (xy 223.623982 -316.604967) (xy 223.606728 -316.549768)
			(xy 223.598003 -316.492597) (xy 223.59747 -316.46368) (xy 223.597956 -316.436429) (xy 223.605712 -316.382481)
			(xy 223.621067 -316.330186) (xy 223.643709 -316.280609) (xy 223.673175 -316.234759) (xy 223.708866 -316.193568)
			(xy 223.750057 -316.157877) (xy 223.795907 -316.128411) (xy 223.845484 -316.105769) (xy 223.897779 -316.090414)
			(xy 223.951727 -316.082658) (xy 224.006229 -316.082658) (xy 224.060177 -316.090414) (xy 224.112472 -316.105769)
			(xy 224.162049 -316.128411) (xy 224.207899 -316.157877) (xy 224.24909 -316.193568) (xy 224.284781 -316.234759)
			(xy 224.314247 -316.280609) (xy 224.336889 -316.330186) (xy 224.352244 -316.382481) (xy 224.36 -316.436429)
			(xy 224.360486 -316.46368) (xy 224.359959 -316.492597) (xy 224.351232 -316.549768) (xy 224.333976 -316.604966)
			(xy 224.308586 -316.656928) (xy 224.275644 -316.704462) (xy 224.235905 -316.74648) (xy 224.21342 -316.76467)
			(xy 224.204663 -316.772236) (xy 224.19448 -316.792992) (xy 224.193862 -316.804548) (xy 224.193862 -316.884812)
			(xy 224.194404 -316.896384) (xy 224.204617 -316.917156) (xy 224.21342 -316.92469) (xy 224.235903 -316.942882)
			(xy 224.275637 -316.984902) (xy 224.308576 -317.032437) (xy 224.333964 -317.084398) (xy 224.351221 -317.139595)
			(xy 224.35995 -317.196764) (xy 224.360486 -317.22568) (xy 224.360097 -317.252376) (xy 224.352672 -317.305248)
			(xy 224.33795 -317.35657) (xy 224.316218 -317.405338) (xy 224.287901 -317.450601) (xy 224.253551 -317.491476)
			(xy 224.233994 -317.509652) (xy 224.225358 -317.517272) (xy 224.216468 -317.5381) (xy 224.22104 -317.6397)
			(xy 224.231454 -317.659512) (xy 224.240852 -317.66637) (xy 224.264132 -317.684509) (xy 224.305326 -317.726766)
			(xy 224.339526 -317.77486) (xy 224.365916 -317.827644) (xy 224.383868 -317.883861) (xy 224.392954 -317.942171)
			(xy 224.393506 -317.971678) (xy 224.39302 -317.998929) (xy 224.385264 -318.052877) (xy 224.369909 -318.105172)
			(xy 224.347267 -318.154749) (xy 224.317801 -318.200599) (xy 224.28211 -318.24179) (xy 224.240919 -318.277481)
			(xy 224.195069 -318.306947) (xy 224.145492 -318.329589) (xy 224.093197 -318.344944) (xy 224.039249 -318.3527)
			(xy 223.984747 -318.3527) (xy 223.930799 -318.344944) (xy 223.878504 -318.329589) (xy 223.828927 -318.306947)
			(xy 223.783077 -318.277481) (xy 223.741886 -318.24179) (xy 223.706195 -318.200599) (xy 223.676729 -318.154749)
			(xy 223.654087 -318.105172) (xy 223.638732 -318.052877) (xy 223.630976 -317.998929) (xy 223.63049 -317.971678)
			(xy 223.630926 -317.944984) (xy 223.638343 -317.892114) (xy 223.653056 -317.840794) (xy 223.674779 -317.792025)
			(xy 223.703087 -317.746761) (xy 223.737429 -317.705884) (xy 223.756982 -317.687706) (xy 223.765618 -317.680086)
			(xy 223.774508 -317.659258) (xy 223.769936 -317.557658) (xy 223.759522 -317.537846) (xy 223.750124 -317.530988)
			(xy 223.726862 -317.512827) (xy 223.685658 -317.47058) (xy 223.651451 -317.422493) (xy 223.625056 -317.369712)
			(xy 223.607103 -317.313496) (xy 223.598019 -317.255186) (xy 223.59747 -317.22568) (xy 223.261076 -317.22568)
			(xy 223.260919 -317.234262) (xy 223.252799 -317.289438) (xy 223.236731 -317.342845) (xy 223.213059 -317.393342)
			(xy 223.182286 -317.439855) (xy 223.145069 -317.481392) (xy 223.102201 -317.517067) (xy 223.054595 -317.546121)
			(xy 223.003266 -317.567933) (xy 222.949309 -317.582039) (xy 222.893872 -317.588139) (xy 222.838138 -317.586102)
			(xy 222.783295 -317.575972) (xy 222.730511 -317.557965) (xy 222.680911 -317.532464) (xy 222.635553 -317.500013)
			(xy 222.595404 -317.461304) (xy 222.561318 -317.417161) (xy 222.534022 -317.368526) (xy 222.514099 -317.316435)
			(xy 222.501973 -317.261998) (xy 222.497902 -317.206376) (xy 219.420773 -317.206376) (xy 219.443274 -317.263205)
			(xy 219.459171 -317.325119) (xy 219.467182 -317.388537) (xy 219.467684 -317.420498) (xy 219.467182 -317.452459)
			(xy 219.459171 -317.515877) (xy 219.443274 -317.577791) (xy 219.419742 -317.637224) (xy 219.388948 -317.693239)
			(xy 219.351375 -317.744954) (xy 219.307618 -317.791551) (xy 219.258365 -317.832296) (xy 219.204394 -317.866547)
			(xy 219.146555 -317.893764) (xy 219.085762 -317.913517) (xy 219.022972 -317.925495) (xy 218.959176 -317.929509)
			(xy 218.89538 -317.925495) (xy 218.83259 -317.913517) (xy 218.771797 -317.893764) (xy 218.713958 -317.866547)
			(xy 218.659987 -317.832296) (xy 218.610734 -317.791551) (xy 218.566977 -317.744954) (xy 218.529404 -317.693239)
			(xy 218.49861 -317.637224) (xy 218.475078 -317.577791) (xy 218.459181 -317.515877) (xy 218.45117 -317.452459)
			(xy 218.193874 -317.452459) (xy 218.193874 -317.702692) (xy 218.194346 -317.712564) (xy 218.201806 -317.730846)
			(xy 218.208352 -317.738252) (xy 218.208606 -317.738506) (xy 219.378784 -318.908684) (xy 219.385303 -318.91466)
			(xy 219.401309 -318.922152) (xy 219.418907 -318.92376) (xy 219.427552 -318.921892) (xy 219.52585 -318.895984)
			(xy 219.5449 -318.877188) (xy 219.548456 -318.86398) (xy 219.55778 -318.832215) (xy 219.583535 -318.771229)
			(xy 219.616989 -318.714102) (xy 219.657575 -318.661801) (xy 219.704607 -318.61521) (xy 219.757288 -318.575119)
			(xy 219.814728 -318.542205) (xy 219.875954 -318.517026) (xy 219.939931 -318.500007) (xy 220.005575 -318.491436)
			(xy 220.038676 -318.490854) (xy 220.069409 -318.491316) (xy 220.130427 -318.498722) (xy 220.190107 -318.513429)
			(xy 220.247579 -318.535222) (xy 220.302006 -318.563783) (xy 220.352593 -318.598696) (xy 220.398603 -318.639453)
			(xy 220.439365 -318.685458) (xy 220.452497 -318.70448) (xy 224.841553 -318.70448) (xy 224.845286 -318.651226)
			(xy 224.856405 -318.599012) (xy 224.874694 -318.548858) (xy 224.899795 -318.501743) (xy 224.931219 -318.458587)
			(xy 224.968352 -318.420232) (xy 224.989136 -318.403478) (xy 224.997909 -318.395927) (xy 225.008085 -318.37516)
			(xy 225.008694 -318.3636) (xy 225.008694 -318.283336) (xy 225.008105 -318.271771) (xy 224.997924 -318.250999)
			(xy 224.989136 -318.243458) (xy 224.96664 -318.225282) (xy 224.926904 -318.18326) (xy 224.893965 -318.135722)
			(xy 224.868579 -318.083758) (xy 224.851326 -318.028557) (xy 224.842602 -317.971385) (xy 224.84207 -317.942468)
			(xy 224.842556 -317.915217) (xy 224.850312 -317.861269) (xy 224.865667 -317.808974) (xy 224.888309 -317.759397)
			(xy 224.917775 -317.713547) (xy 224.953466 -317.672356) (xy 224.994657 -317.636665) (xy 225.040507 -317.607199)
			(xy 225.090084 -317.584557) (xy 225.142379 -317.569202) (xy 225.196327 -317.561446) (xy 225.250829 -317.561446)
			(xy 225.304777 -317.569202) (xy 225.357072 -317.584557) (xy 225.406649 -317.607199) (xy 225.452499 -317.636665)
			(xy 225.49369 -317.672356) (xy 225.529381 -317.713547) (xy 225.558847 -317.759397) (xy 225.581489 -317.808974)
			(xy 225.596844 -317.861269) (xy 225.6046 -317.915217) (xy 225.605086 -317.942468) (xy 225.60455 -317.971384)
			(xy 225.595825 -318.028555) (xy 225.578571 -318.083754) (xy 225.553183 -318.135715) (xy 225.520242 -318.18325)
			(xy 225.480504 -318.225267) (xy 225.45802 -318.243458) (xy 225.449268 -318.251029) (xy 225.439083 -318.271781)
			(xy 225.438462 -318.283336) (xy 225.438462 -318.3636) (xy 225.439011 -318.375171) (xy 225.449218 -318.395943)
			(xy 225.45802 -318.403478) (xy 225.478772 -318.420269) (xy 225.515904 -318.458617) (xy 225.547327 -318.501766)
			(xy 225.572428 -318.548875) (xy 225.590717 -318.599024) (xy 225.601836 -318.651232) (xy 225.605569 -318.70448)
			(xy 227.229153 -318.70448) (xy 227.232886 -318.651226) (xy 227.244005 -318.599012) (xy 227.262294 -318.548858)
			(xy 227.287395 -318.501743) (xy 227.318819 -318.458587) (xy 227.355952 -318.420232) (xy 227.376736 -318.403478)
			(xy 227.385509 -318.395927) (xy 227.395685 -318.37516) (xy 227.396294 -318.3636) (xy 227.396294 -318.283336)
			(xy 227.395705 -318.271771) (xy 227.385524 -318.250999) (xy 227.376736 -318.243458) (xy 227.35424 -318.225282)
			(xy 227.314504 -318.18326) (xy 227.281565 -318.135722) (xy 227.256179 -318.083758) (xy 227.238926 -318.028557)
			(xy 227.230202 -317.971385) (xy 227.22967 -317.942468) (xy 227.230166 -317.914873) (xy 227.238135 -317.860261)
			(xy 227.253888 -317.807366) (xy 227.277095 -317.757293) (xy 227.307274 -317.711084) (xy 227.343794 -317.669704)
			(xy 227.385893 -317.634017) (xy 227.432695 -317.604766) (xy 227.457762 -317.593218) (xy 227.468176 -317.588646)
			(xy 227.482908 -317.571628) (xy 227.510594 -317.474092) (xy 227.507038 -317.451994) (xy 227.500434 -317.442342)
			(xy 227.484484 -317.418332) (xy 227.459233 -317.366514) (xy 227.442074 -317.311486) (xy 227.433397 -317.254501)
			(xy 227.43287 -317.22568) (xy 227.433419 -317.196764) (xy 227.442138 -317.139593) (xy 227.459388 -317.084394)
			(xy 227.484774 -317.032431) (xy 227.517714 -316.984897) (xy 227.557452 -316.94288) (xy 227.579936 -316.92469)
			(xy 227.588704 -316.917134) (xy 227.598883 -316.896371) (xy 227.599494 -316.884812) (xy 227.599494 -316.804548)
			(xy 227.598898 -316.792983) (xy 227.588722 -316.772212) (xy 227.579936 -316.76467) (xy 227.557446 -316.746487)
			(xy 227.517709 -316.704467) (xy 227.48477 -316.65693) (xy 227.459382 -316.604967) (xy 227.442128 -316.549768)
			(xy 227.433403 -316.492597) (xy 227.43287 -316.46368) (xy 227.433356 -316.436429) (xy 227.441112 -316.382481)
			(xy 227.456467 -316.330186) (xy 227.479109 -316.280609) (xy 227.508575 -316.234759) (xy 227.544266 -316.193568)
			(xy 227.585457 -316.157877) (xy 227.631307 -316.128411) (xy 227.680884 -316.105769) (xy 227.733179 -316.090414)
			(xy 227.787127 -316.082658) (xy 227.841629 -316.082658) (xy 227.895577 -316.090414) (xy 227.947872 -316.105769)
			(xy 227.997449 -316.128411) (xy 228.043299 -316.157877) (xy 228.08449 -316.193568) (xy 228.120181 -316.234759)
			(xy 228.149647 -316.280609) (xy 228.172289 -316.330186) (xy 228.187644 -316.382481) (xy 228.1954 -316.436429)
			(xy 228.195886 -316.46368) (xy 228.195359 -316.492597) (xy 228.186632 -316.549768) (xy 228.169376 -316.604966)
			(xy 228.143986 -316.656928) (xy 228.111044 -316.704462) (xy 228.071305 -316.74648) (xy 228.04882 -316.76467)
			(xy 228.040063 -316.772236) (xy 228.02988 -316.792992) (xy 228.029262 -316.804548) (xy 228.029262 -316.884812)
			(xy 228.029804 -316.896384) (xy 228.040017 -316.917156) (xy 228.04882 -316.92469) (xy 228.071303 -316.942882)
			(xy 228.111037 -316.984902) (xy 228.143976 -317.032437) (xy 228.169364 -317.084398) (xy 228.186621 -317.139595)
			(xy 228.19535 -317.196764) (xy 228.195886 -317.22568) (xy 229.49027 -317.22568) (xy 229.490819 -317.196764)
			(xy 229.499538 -317.139593) (xy 229.516788 -317.084394) (xy 229.542174 -317.032431) (xy 229.575114 -316.984897)
			(xy 229.614852 -316.94288) (xy 229.637336 -316.92469) (xy 229.646104 -316.917134) (xy 229.656283 -316.896371)
			(xy 229.656894 -316.884812) (xy 229.656894 -316.804548) (xy 229.656298 -316.792983) (xy 229.646122 -316.772212)
			(xy 229.637336 -316.76467) (xy 229.614846 -316.746487) (xy 229.575109 -316.704467) (xy 229.54217 -316.65693)
			(xy 229.516782 -316.604967) (xy 229.499528 -316.549768) (xy 229.490803 -316.492597) (xy 229.49027 -316.46368)
			(xy 229.490756 -316.436429) (xy 229.498512 -316.382481) (xy 229.513867 -316.330186) (xy 229.536509 -316.280609)
			(xy 229.565975 -316.234759) (xy 229.601666 -316.193568) (xy 229.642857 -316.157877) (xy 229.688707 -316.128411)
			(xy 229.738284 -316.105769) (xy 229.790579 -316.090414) (xy 229.844527 -316.082658) (xy 229.899029 -316.082658)
			(xy 229.952977 -316.090414) (xy 230.005272 -316.105769) (xy 230.054849 -316.128411) (xy 230.100699 -316.157877)
			(xy 230.14189 -316.193568) (xy 230.177581 -316.234759) (xy 230.207047 -316.280609) (xy 230.229689 -316.330186)
			(xy 230.245044 -316.382481) (xy 230.2528 -316.436429) (xy 230.253286 -316.46368) (xy 230.252759 -316.492597)
			(xy 230.244032 -316.549768) (xy 230.226776 -316.604966) (xy 230.201386 -316.656928) (xy 230.168444 -316.704462)
			(xy 230.128705 -316.74648) (xy 230.10622 -316.76467) (xy 230.097463 -316.772236) (xy 230.08728 -316.792992)
			(xy 230.086662 -316.804548) (xy 230.086662 -316.884812) (xy 230.087204 -316.896384) (xy 230.097417 -316.917156)
			(xy 230.10622 -316.92469) (xy 230.128703 -316.942882) (xy 230.168437 -316.984902) (xy 230.201376 -317.032437)
			(xy 230.226764 -317.084398) (xy 230.244021 -317.139595) (xy 230.25275 -317.196764) (xy 230.253286 -317.22568)
			(xy 230.25281 -317.25315) (xy 230.244932 -317.307521) (xy 230.229336 -317.3602) (xy 230.206345 -317.410097)
			(xy 230.176434 -317.456179) (xy 230.140221 -317.497495) (xy 230.098457 -317.533188) (xy 230.075486 -317.54826)
			(xy 230.064056 -317.555372) (xy 230.05161 -317.57874) (xy 230.053896 -317.692786) (xy 230.067358 -317.715646)
			(xy 230.079042 -317.72225) (xy 230.103569 -317.736959) (xy 230.148324 -317.772561) (xy 230.187265 -317.814443)
			(xy 230.219521 -317.861668) (xy 230.244368 -317.913176) (xy 230.261251 -317.967816) (xy 230.269791 -318.024364)
			(xy 230.270304 -318.052958) (xy 230.269818 -318.080209) (xy 230.262062 -318.134157) (xy 230.246707 -318.186452)
			(xy 230.224065 -318.236029) (xy 230.194599 -318.281879) (xy 230.158908 -318.32307) (xy 230.117717 -318.358761)
			(xy 230.071867 -318.388227) (xy 230.02229 -318.410869) (xy 229.969995 -318.426224) (xy 229.916047 -318.43398)
			(xy 229.861545 -318.43398) (xy 229.807597 -318.426224) (xy 229.755302 -318.410869) (xy 229.705725 -318.388227)
			(xy 229.659875 -318.358761) (xy 229.618684 -318.32307) (xy 229.582993 -318.281879) (xy 229.553527 -318.236029)
			(xy 229.530885 -318.186452) (xy 229.51553 -318.134157) (xy 229.507774 -318.080209) (xy 229.507288 -318.052958)
			(xy 229.507805 -318.02549) (xy 229.515677 -317.971121) (xy 229.531267 -317.918444) (xy 229.554252 -317.868547)
			(xy 229.584156 -317.822464) (xy 229.620362 -317.781147) (xy 229.66212 -317.745451) (xy 229.685088 -317.730378)
			(xy 229.696518 -317.723266) (xy 229.708964 -317.699898) (xy 229.706678 -317.585852) (xy 229.693216 -317.562992)
			(xy 229.681532 -317.556388) (xy 229.656995 -317.541695) (xy 229.612236 -317.506093) (xy 229.573292 -317.46421)
			(xy 229.541036 -317.416983) (xy 229.51619 -317.365471) (xy 229.499312 -317.310827) (xy 229.490779 -317.254276)
			(xy 229.49027 -317.22568) (xy 228.195886 -317.22568) (xy 228.195372 -317.253275) (xy 228.187409 -317.307887)
			(xy 228.171662 -317.360783) (xy 228.148458 -317.410858) (xy 228.118281 -317.457067) (xy 228.081763 -317.498447)
			(xy 228.039663 -317.534134) (xy 227.992862 -317.563383) (xy 227.967794 -317.57493) (xy 227.95738 -317.579502)
			(xy 227.942648 -317.59652) (xy 227.914962 -317.694056) (xy 227.918518 -317.716154) (xy 227.925122 -317.725806)
			(xy 227.941088 -317.749807) (xy 227.966335 -317.801627) (xy 227.98349 -317.856659) (xy 227.992162 -317.913646)
			(xy 227.992686 -317.942468) (xy 227.99215 -317.971384) (xy 227.983425 -318.028555) (xy 227.966171 -318.083754)
			(xy 227.940783 -318.135715) (xy 227.907842 -318.18325) (xy 227.868104 -318.225267) (xy 227.84562 -318.243458)
			(xy 227.836868 -318.251029) (xy 227.826683 -318.271781) (xy 227.826062 -318.283336) (xy 227.826062 -318.3636)
			(xy 227.826611 -318.375171) (xy 227.836818 -318.395943) (xy 227.84562 -318.403478) (xy 227.866372 -318.420269)
			(xy 227.903504 -318.458617) (xy 227.934927 -318.501766) (xy 227.960028 -318.548875) (xy 227.978317 -318.599024)
			(xy 227.989436 -318.651232) (xy 227.993169 -318.70448) (xy 230.937553 -318.70448) (xy 230.941286 -318.651226)
			(xy 230.952405 -318.599012) (xy 230.970694 -318.548858) (xy 230.995795 -318.501743) (xy 231.027219 -318.458587)
			(xy 231.064352 -318.420232) (xy 231.085136 -318.403478) (xy 231.093909 -318.395927) (xy 231.104085 -318.37516)
			(xy 231.104694 -318.3636) (xy 231.104694 -318.283336) (xy 231.104105 -318.271771) (xy 231.093924 -318.250999)
			(xy 231.085136 -318.243458) (xy 231.06264 -318.225282) (xy 231.022904 -318.18326) (xy 230.989965 -318.135722)
			(xy 230.964579 -318.083758) (xy 230.947326 -318.028557) (xy 230.938602 -317.971385) (xy 230.93807 -317.942468)
			(xy 230.938556 -317.915217) (xy 230.946312 -317.861269) (xy 230.961667 -317.808974) (xy 230.984309 -317.759397)
			(xy 231.013775 -317.713547) (xy 231.049466 -317.672356) (xy 231.090657 -317.636665) (xy 231.136507 -317.607199)
			(xy 231.186084 -317.584557) (xy 231.238379 -317.569202) (xy 231.292327 -317.561446) (xy 231.346829 -317.561446)
			(xy 231.400777 -317.569202) (xy 231.453072 -317.584557) (xy 231.502649 -317.607199) (xy 231.548499 -317.636665)
			(xy 231.58969 -317.672356) (xy 231.625381 -317.713547) (xy 231.654847 -317.759397) (xy 231.677489 -317.808974)
			(xy 231.692844 -317.861269) (xy 231.7006 -317.915217) (xy 231.701086 -317.942468) (xy 231.70055 -317.971384)
			(xy 231.691825 -318.028555) (xy 231.674571 -318.083754) (xy 231.649183 -318.135715) (xy 231.616242 -318.18325)
			(xy 231.576504 -318.225267) (xy 231.55402 -318.243458) (xy 231.545268 -318.251029) (xy 231.535083 -318.271781)
			(xy 231.534462 -318.283336) (xy 231.534462 -318.3636) (xy 231.535011 -318.375171) (xy 231.545218 -318.395943)
			(xy 231.55402 -318.403478) (xy 231.574772 -318.420269) (xy 231.611904 -318.458617) (xy 231.643327 -318.501766)
			(xy 231.668428 -318.548875) (xy 231.686717 -318.599024) (xy 231.697836 -318.651232) (xy 231.701569 -318.70448)
			(xy 233.325153 -318.70448) (xy 233.328886 -318.651226) (xy 233.340005 -318.599012) (xy 233.358294 -318.548858)
			(xy 233.383395 -318.501743) (xy 233.414819 -318.458587) (xy 233.451952 -318.420232) (xy 233.472736 -318.403478)
			(xy 233.481509 -318.395927) (xy 233.491685 -318.37516) (xy 233.492294 -318.3636) (xy 233.492294 -318.283336)
			(xy 233.491705 -318.271771) (xy 233.481524 -318.250999) (xy 233.472736 -318.243458) (xy 233.45024 -318.225282)
			(xy 233.410504 -318.18326) (xy 233.377565 -318.135722) (xy 233.352179 -318.083758) (xy 233.334926 -318.028557)
			(xy 233.326202 -317.971385) (xy 233.32567 -317.942468) (xy 233.326099 -317.915886) (xy 233.33349 -317.863237)
			(xy 233.348124 -317.812126) (xy 233.369717 -317.763544) (xy 233.397851 -317.718433) (xy 233.431979 -317.677668)
			(xy 233.4514 -317.659512) (xy 233.458918 -317.651892) (xy 233.467592 -317.632353) (xy 233.468164 -317.621666)
			(xy 233.468164 -317.546482) (xy 233.467712 -317.535762) (xy 233.459049 -317.516158) (xy 233.4514 -317.508636)
			(xy 233.431978 -317.490482) (xy 233.397855 -317.449715) (xy 233.369728 -317.404603) (xy 233.348141 -317.35602)
			(xy 233.333514 -317.304909) (xy 233.32613 -317.252261) (xy 233.32567 -317.22568) (xy 233.326219 -317.196764)
			(xy 233.334938 -317.139593) (xy 233.352188 -317.084394) (xy 233.377574 -317.032431) (xy 233.410514 -316.984897)
			(xy 233.450252 -316.94288) (xy 233.472736 -316.92469) (xy 233.481504 -316.917134) (xy 233.491683 -316.896371)
			(xy 233.492294 -316.884812) (xy 233.492294 -316.804548) (xy 233.491698 -316.792983) (xy 233.481522 -316.772212)
			(xy 233.472736 -316.76467) (xy 233.450246 -316.746487) (xy 233.410509 -316.704467) (xy 233.37757 -316.65693)
			(xy 233.352182 -316.604967) (xy 233.334928 -316.549768) (xy 233.326203 -316.492597) (xy 233.32567 -316.46368)
			(xy 233.326156 -316.436429) (xy 233.333912 -316.382481) (xy 233.349267 -316.330186) (xy 233.371909 -316.280609)
			(xy 233.401375 -316.234759) (xy 233.437066 -316.193568) (xy 233.478257 -316.157877) (xy 233.524107 -316.128411)
			(xy 233.573684 -316.105769) (xy 233.625979 -316.090414) (xy 233.679927 -316.082658) (xy 233.734429 -316.082658)
			(xy 233.788377 -316.090414) (xy 233.840672 -316.105769) (xy 233.890249 -316.128411) (xy 233.936099 -316.157877)
			(xy 233.97729 -316.193568) (xy 234.012981 -316.234759) (xy 234.042447 -316.280609) (xy 234.065089 -316.330186)
			(xy 234.080444 -316.382481) (xy 234.0882 -316.436429) (xy 234.088686 -316.46368) (xy 234.088159 -316.492597)
			(xy 234.079432 -316.549768) (xy 234.062176 -316.604966) (xy 234.036786 -316.656928) (xy 234.003844 -316.704462)
			(xy 233.964105 -316.74648) (xy 233.94162 -316.76467) (xy 233.932863 -316.772236) (xy 233.92268 -316.792992)
			(xy 233.922062 -316.804548) (xy 233.922062 -316.884812) (xy 233.922604 -316.896384) (xy 233.932817 -316.917156)
			(xy 233.94162 -316.92469) (xy 233.964103 -316.942882) (xy 234.003837 -316.984902) (xy 234.036776 -317.032437)
			(xy 234.062164 -317.084398) (xy 234.079421 -317.139595) (xy 234.08815 -317.196764) (xy 234.088328 -317.206376)
			(xy 237.479838 -317.206376) (xy 237.483909 -317.150754) (xy 237.496035 -317.096317) (xy 237.515958 -317.044226)
			(xy 237.543254 -316.995591) (xy 237.57734 -316.951448) (xy 237.617489 -316.912739) (xy 237.662847 -316.880288)
			(xy 237.712447 -316.854787) (xy 237.765231 -316.83678) (xy 237.820074 -316.82665) (xy 237.875808 -316.824613)
			(xy 237.931245 -316.830713) (xy 237.985202 -316.844819) (xy 238.036531 -316.866631) (xy 238.084137 -316.895685)
			(xy 238.127005 -316.93136) (xy 238.164222 -316.972897) (xy 238.194995 -317.01941) (xy 238.218667 -317.069907)
			(xy 238.234735 -317.123314) (xy 238.242855 -317.17849) (xy 238.243364 -317.206376) (xy 238.243012 -317.22568)
			(xy 238.579406 -317.22568) (xy 238.579979 -317.196765) (xy 238.588697 -317.139596) (xy 238.605943 -317.084398)
			(xy 238.631325 -317.032436) (xy 238.664259 -316.984901) (xy 238.703991 -316.942882) (xy 238.726472 -316.92469)
			(xy 238.735246 -316.91714) (xy 238.74542 -316.896372) (xy 238.74603 -316.884812) (xy 238.74603 -316.804548)
			(xy 238.745456 -316.79298) (xy 238.735266 -316.772207) (xy 238.726472 -316.76467) (xy 238.703968 -316.746503)
			(xy 238.664236 -316.704477) (xy 238.6313 -316.656937) (xy 238.605915 -316.604971) (xy 238.588663 -316.54977)
			(xy 238.579939 -316.492597) (xy 238.579406 -316.46368) (xy 238.579892 -316.436429) (xy 238.587648 -316.382481)
			(xy 238.603003 -316.330186) (xy 238.625645 -316.280609) (xy 238.655111 -316.234759) (xy 238.690802 -316.193568)
			(xy 238.731993 -316.157877) (xy 238.777843 -316.128411) (xy 238.82742 -316.105769) (xy 238.879715 -316.090414)
			(xy 238.933663 -316.082658) (xy 238.988165 -316.082658) (xy 239.042113 -316.090414) (xy 239.094408 -316.105769)
			(xy 239.143985 -316.128411) (xy 239.189835 -316.157877) (xy 239.231026 -316.193568) (xy 239.266717 -316.234759)
			(xy 239.296183 -316.280609) (xy 239.318825 -316.330186) (xy 239.33418 -316.382481) (xy 239.341936 -316.436429)
			(xy 239.342422 -316.46368) (xy 239.341919 -316.492598) (xy 239.333191 -316.549771) (xy 239.315932 -316.604972)
			(xy 239.290538 -316.656934) (xy 239.25759 -316.704467) (xy 239.217844 -316.746482) (xy 239.195356 -316.76467)
			(xy 239.186605 -316.772242) (xy 239.176417 -316.792993) (xy 239.175798 -316.804548) (xy 239.175798 -316.884812)
			(xy 239.176362 -316.896381) (xy 239.186561 -316.917151) (xy 239.195356 -316.92469) (xy 239.217826 -316.942898)
			(xy 239.257564 -316.984913) (xy 239.290506 -317.032444) (xy 239.315897 -317.084402) (xy 239.333155 -317.139597)
			(xy 239.341886 -317.196765) (xy 239.342422 -317.22568) (xy 239.342021 -317.252375) (xy 239.334597 -317.305247)
			(xy 239.319876 -317.356567) (xy 239.298146 -317.405336) (xy 239.269832 -317.450599) (xy 239.235486 -317.491475)
			(xy 239.21593 -317.509652) (xy 239.207294 -317.517272) (xy 239.198404 -317.5381) (xy 239.202976 -317.6397)
			(xy 239.21339 -317.659512) (xy 239.222788 -317.66637) (xy 239.246075 -317.684499) (xy 239.287267 -317.726759)
			(xy 239.321465 -317.774855) (xy 239.347854 -317.827641) (xy 239.365805 -317.88386) (xy 239.37489 -317.942171)
			(xy 239.375442 -317.971678) (xy 239.374956 -317.998929) (xy 239.3672 -318.052877) (xy 239.351845 -318.105172)
			(xy 239.329203 -318.154749) (xy 239.299737 -318.200599) (xy 239.264046 -318.24179) (xy 239.222855 -318.277481)
			(xy 239.177005 -318.306947) (xy 239.127428 -318.329589) (xy 239.075133 -318.344944) (xy 239.021185 -318.3527)
			(xy 238.966683 -318.3527) (xy 238.912735 -318.344944) (xy 238.86044 -318.329589) (xy 238.810863 -318.306947)
			(xy 238.765013 -318.277481) (xy 238.723822 -318.24179) (xy 238.688131 -318.200599) (xy 238.658665 -318.154749)
			(xy 238.636023 -318.105172) (xy 238.620668 -318.052877) (xy 238.612912 -317.998929) (xy 238.612426 -317.971678)
			(xy 238.612883 -317.944985) (xy 238.620299 -317.892117) (xy 238.635009 -317.840798) (xy 238.656728 -317.79203)
			(xy 238.685032 -317.746764) (xy 238.719367 -317.705885) (xy 238.738918 -317.687706) (xy 238.747554 -317.680086)
			(xy 238.756444 -317.659258) (xy 238.751872 -317.557658) (xy 238.741458 -317.537846) (xy 238.73206 -317.530988)
			(xy 238.708805 -317.512817) (xy 238.6676 -317.470574) (xy 238.633391 -317.422489) (xy 238.606994 -317.369709)
			(xy 238.589039 -317.313495) (xy 238.579955 -317.255186) (xy 238.579406 -317.22568) (xy 238.243012 -317.22568)
			(xy 238.242855 -317.234262) (xy 238.234735 -317.289438) (xy 238.218667 -317.342845) (xy 238.194995 -317.393342)
			(xy 238.164222 -317.439855) (xy 238.127005 -317.481392) (xy 238.084137 -317.517067) (xy 238.036531 -317.546121)
			(xy 237.985202 -317.567933) (xy 237.931245 -317.582039) (xy 237.875808 -317.588139) (xy 237.820074 -317.586102)
			(xy 237.765231 -317.575972) (xy 237.712447 -317.557965) (xy 237.662847 -317.532464) (xy 237.617489 -317.500013)
			(xy 237.57734 -317.461304) (xy 237.543254 -317.417161) (xy 237.515958 -317.368526) (xy 237.496035 -317.316435)
			(xy 237.483909 -317.261998) (xy 237.479838 -317.206376) (xy 234.088328 -317.206376) (xy 234.088686 -317.22568)
			(xy 234.088204 -317.25226) (xy 234.080821 -317.304906) (xy 234.066196 -317.356015) (xy 234.044613 -317.404597)
			(xy 234.01649 -317.449709) (xy 233.982372 -317.490477) (xy 233.962956 -317.508636) (xy 233.955411 -317.516232)
			(xy 233.946754 -317.53579) (xy 233.946192 -317.546482) (xy 233.946192 -317.621666) (xy 233.946601 -317.632392)
			(xy 233.955292 -317.651997) (xy 233.962956 -317.659512) (xy 233.982363 -317.677681) (xy 234.016485 -317.718445)
			(xy 234.044614 -317.763555) (xy 234.066202 -317.812135) (xy 234.080833 -317.863243) (xy 234.088223 -317.915888)
			(xy 234.088686 -317.942468) (xy 234.08815 -317.971384) (xy 234.079425 -318.028555) (xy 234.062171 -318.083754)
			(xy 234.036783 -318.135715) (xy 234.003842 -318.18325) (xy 233.964104 -318.225267) (xy 233.94162 -318.243458)
			(xy 233.932868 -318.251029) (xy 233.922683 -318.271781) (xy 233.922062 -318.283336) (xy 233.922062 -318.3636)
			(xy 233.922611 -318.375171) (xy 233.932818 -318.395943) (xy 233.94162 -318.403478) (xy 233.962372 -318.420269)
			(xy 233.999504 -318.458617) (xy 234.030927 -318.501766) (xy 234.056028 -318.548875) (xy 234.074317 -318.599024)
			(xy 234.085436 -318.651232) (xy 234.089169 -318.70448) (xy 239.823475 -318.70448) (xy 239.827208 -318.651225)
			(xy 239.838329 -318.59901) (xy 239.856619 -318.548855) (xy 239.881723 -318.50174) (xy 239.91315 -318.458584)
			(xy 239.950286 -318.420231) (xy 239.971072 -318.403478) (xy 239.979851 -318.395934) (xy 239.990022 -318.375161)
			(xy 239.99063 -318.3636) (xy 239.99063 -318.283336) (xy 239.990063 -318.271767) (xy 239.979869 -318.250994)
			(xy 239.971072 -318.243458) (xy 239.948563 -318.225298) (xy 239.90883 -318.183271) (xy 239.875895 -318.135729)
			(xy 239.850511 -318.083762) (xy 239.833261 -318.028559) (xy 239.824538 -317.971386) (xy 239.824006 -317.942468)
			(xy 239.824492 -317.915217) (xy 239.832248 -317.861269) (xy 239.847603 -317.808974) (xy 239.870245 -317.759397)
			(xy 239.899711 -317.713547) (xy 239.935402 -317.672356) (xy 239.976593 -317.636665) (xy 240.022443 -317.607199)
			(xy 240.07202 -317.584557) (xy 240.124315 -317.569202) (xy 240.178263 -317.561446) (xy 240.232765 -317.561446)
			(xy 240.286713 -317.569202) (xy 240.339008 -317.584557) (xy 240.388585 -317.607199) (xy 240.434435 -317.636665)
			(xy 240.475626 -317.672356) (xy 240.511317 -317.713547) (xy 240.540783 -317.759397) (xy 240.563425 -317.808974)
			(xy 240.57878 -317.861269) (xy 240.586536 -317.915217) (xy 240.587022 -317.942468) (xy 240.58651 -317.971386)
			(xy 240.577784 -318.028558) (xy 240.560527 -318.083759) (xy 240.535134 -318.135721) (xy 240.502188 -318.183255)
			(xy 240.462443 -318.225269) (xy 240.439956 -318.243458) (xy 240.43121 -318.251035) (xy 240.42102 -318.271783)
			(xy 240.420398 -318.283336) (xy 240.420398 -318.3636) (xy 240.420969 -318.375168) (xy 240.431163 -318.395939)
			(xy 240.439956 -318.403478) (xy 240.460707 -318.420269) (xy 240.497835 -318.458619) (xy 240.529256 -318.501769)
			(xy 240.554354 -318.548878) (xy 240.572641 -318.599026) (xy 240.583759 -318.651233) (xy 240.587492 -318.70448)
			(xy 242.211075 -318.70448) (xy 242.214808 -318.651225) (xy 242.225929 -318.59901) (xy 242.244219 -318.548855)
			(xy 242.269323 -318.50174) (xy 242.30075 -318.458584) (xy 242.337886 -318.420231) (xy 242.358672 -318.403478)
			(xy 242.367451 -318.395934) (xy 242.377622 -318.375161) (xy 242.37823 -318.3636) (xy 242.37823 -318.283336)
			(xy 242.377663 -318.271767) (xy 242.367469 -318.250994) (xy 242.358672 -318.243458) (xy 242.336163 -318.225298)
			(xy 242.29643 -318.183271) (xy 242.263495 -318.135729) (xy 242.238111 -318.083762) (xy 242.220861 -318.028559)
			(xy 242.212138 -317.971386) (xy 242.211606 -317.942468) (xy 242.212081 -317.914872) (xy 242.220051 -317.860258)
			(xy 242.235805 -317.807362) (xy 242.259015 -317.757287) (xy 242.289197 -317.711078) (xy 242.32572 -317.669699)
			(xy 242.367824 -317.634013) (xy 242.414629 -317.604764) (xy 242.439698 -317.593218) (xy 242.450112 -317.588646)
			(xy 242.464844 -317.571628) (xy 242.49253 -317.474092) (xy 242.488974 -317.451994) (xy 242.48237 -317.442342)
			(xy 242.466424 -317.418329) (xy 242.441172 -317.366513) (xy 242.424011 -317.311485) (xy 242.415334 -317.254501)
			(xy 242.414806 -317.22568) (xy 242.415379 -317.196765) (xy 242.424097 -317.139596) (xy 242.441343 -317.084398)
			(xy 242.466725 -317.032436) (xy 242.499659 -316.984901) (xy 242.539391 -316.942882) (xy 242.561872 -316.92469)
			(xy 242.570646 -316.91714) (xy 242.58082 -316.896372) (xy 242.58143 -316.884812) (xy 242.58143 -316.804548)
			(xy 242.580856 -316.79298) (xy 242.570666 -316.772207) (xy 242.561872 -316.76467) (xy 242.539368 -316.746503)
			(xy 242.499636 -316.704477) (xy 242.4667 -316.656937) (xy 242.441315 -316.604971) (xy 242.424063 -316.54977)
			(xy 242.415339 -316.492597) (xy 242.414806 -316.46368) (xy 242.415292 -316.436429) (xy 242.423048 -316.382481)
			(xy 242.438403 -316.330186) (xy 242.461045 -316.280609) (xy 242.490511 -316.234759) (xy 242.526202 -316.193568)
			(xy 242.567393 -316.157877) (xy 242.613243 -316.128411) (xy 242.66282 -316.105769) (xy 242.715115 -316.090414)
			(xy 242.769063 -316.082658) (xy 242.823565 -316.082658) (xy 242.877513 -316.090414) (xy 242.929808 -316.105769)
			(xy 242.979385 -316.128411) (xy 243.025235 -316.157877) (xy 243.066426 -316.193568) (xy 243.102117 -316.234759)
			(xy 243.131583 -316.280609) (xy 243.154225 -316.330186) (xy 243.16958 -316.382481) (xy 243.177336 -316.436429)
			(xy 243.177822 -316.46368) (xy 243.177319 -316.492598) (xy 243.168591 -316.549771) (xy 243.151332 -316.604972)
			(xy 243.125938 -316.656934) (xy 243.09299 -316.704467) (xy 243.053244 -316.746482) (xy 243.030756 -316.76467)
			(xy 243.022005 -316.772242) (xy 243.011817 -316.792993) (xy 243.011198 -316.804548) (xy 243.011198 -316.884812)
			(xy 243.011762 -316.896381) (xy 243.021961 -316.917151) (xy 243.030756 -316.92469) (xy 243.053226 -316.942898)
			(xy 243.092964 -316.984913) (xy 243.125906 -317.032444) (xy 243.151297 -317.084402) (xy 243.168555 -317.139597)
			(xy 243.177286 -317.196765) (xy 243.177822 -317.22568) (xy 244.472206 -317.22568) (xy 244.472779 -317.196765)
			(xy 244.481497 -317.139596) (xy 244.498743 -317.084398) (xy 244.524125 -317.032436) (xy 244.557059 -316.984901)
			(xy 244.596791 -316.942882) (xy 244.619272 -316.92469) (xy 244.628046 -316.91714) (xy 244.63822 -316.896372)
			(xy 244.63883 -316.884812) (xy 244.63883 -316.804548) (xy 244.638256 -316.79298) (xy 244.628066 -316.772207)
			(xy 244.619272 -316.76467) (xy 244.596768 -316.746503) (xy 244.557036 -316.704477) (xy 244.5241 -316.656937)
			(xy 244.498715 -316.604971) (xy 244.481463 -316.54977) (xy 244.472739 -316.492597) (xy 244.472206 -316.46368)
			(xy 244.472692 -316.436429) (xy 244.480448 -316.382481) (xy 244.495803 -316.330186) (xy 244.518445 -316.280609)
			(xy 244.547911 -316.234759) (xy 244.583602 -316.193568) (xy 244.624793 -316.157877) (xy 244.670643 -316.128411)
			(xy 244.72022 -316.105769) (xy 244.772515 -316.090414) (xy 244.826463 -316.082658) (xy 244.880965 -316.082658)
			(xy 244.934913 -316.090414) (xy 244.987208 -316.105769) (xy 245.036785 -316.128411) (xy 245.082635 -316.157877)
			(xy 245.123826 -316.193568) (xy 245.159517 -316.234759) (xy 245.188983 -316.280609) (xy 245.211625 -316.330186)
			(xy 245.22698 -316.382481) (xy 245.234736 -316.436429) (xy 245.235222 -316.46368) (xy 245.234719 -316.492598)
			(xy 245.225991 -316.549771) (xy 245.208732 -316.604972) (xy 245.183338 -316.656934) (xy 245.15039 -316.704467)
			(xy 245.110644 -316.746482) (xy 245.088156 -316.76467) (xy 245.079405 -316.772242) (xy 245.069217 -316.792993)
			(xy 245.068598 -316.804548) (xy 245.068598 -316.884812) (xy 245.069162 -316.896381) (xy 245.079361 -316.917151)
			(xy 245.088156 -316.92469) (xy 245.110626 -316.942898) (xy 245.150364 -316.984913) (xy 245.183306 -317.032444)
			(xy 245.208697 -317.084402) (xy 245.225955 -317.139597) (xy 245.234686 -317.196765) (xy 245.235222 -317.22568)
			(xy 245.23473 -317.253149) (xy 245.226852 -317.307519) (xy 245.211258 -317.360196) (xy 245.188269 -317.410093)
			(xy 245.158361 -317.456175) (xy 245.122152 -317.497492) (xy 245.080391 -317.533187) (xy 245.057422 -317.54826)
			(xy 245.045992 -317.555372) (xy 245.033546 -317.57874) (xy 245.035832 -317.692786) (xy 245.049294 -317.715646)
			(xy 245.060978 -317.72225) (xy 245.08549 -317.736983) (xy 245.130248 -317.772578) (xy 245.169193 -317.814455)
			(xy 245.201451 -317.861676) (xy 245.226301 -317.913181) (xy 245.243186 -317.967819) (xy 245.251727 -318.024365)
			(xy 245.25224 -318.052958) (xy 245.251754 -318.080209) (xy 245.243998 -318.134157) (xy 245.228643 -318.186452)
			(xy 245.206001 -318.236029) (xy 245.176535 -318.281879) (xy 245.140844 -318.32307) (xy 245.099653 -318.358761)
			(xy 245.053803 -318.388227) (xy 245.004226 -318.410869) (xy 244.951931 -318.426224) (xy 244.897983 -318.43398)
			(xy 244.843481 -318.43398) (xy 244.789533 -318.426224) (xy 244.737238 -318.410869) (xy 244.687661 -318.388227)
			(xy 244.641811 -318.358761) (xy 244.60062 -318.32307) (xy 244.564929 -318.281879) (xy 244.535463 -318.236029)
			(xy 244.512821 -318.186452) (xy 244.497466 -318.134157) (xy 244.48971 -318.080209) (xy 244.489224 -318.052958)
			(xy 244.489724 -318.025489) (xy 244.497597 -317.971119) (xy 244.513189 -317.91844) (xy 244.536176 -317.868543)
			(xy 244.566084 -317.82246) (xy 244.602293 -317.781144) (xy 244.644055 -317.74545) (xy 244.667024 -317.730378)
			(xy 244.678454 -317.723266) (xy 244.6909 -317.699898) (xy 244.688614 -317.585852) (xy 244.675152 -317.562992)
			(xy 244.663468 -317.556388) (xy 244.638916 -317.541719) (xy 244.59416 -317.506111) (xy 244.55522 -317.464222)
			(xy 244.522967 -317.416991) (xy 244.498124 -317.365475) (xy 244.481247 -317.310829) (xy 244.472714 -317.254276)
			(xy 244.472206 -317.22568) (xy 243.177822 -317.22568) (xy 243.177287 -317.253274) (xy 243.169325 -317.307884)
			(xy 243.153579 -317.360778) (xy 243.130377 -317.410852) (xy 243.100204 -317.457061) (xy 243.063689 -317.498441)
			(xy 243.021593 -317.53413) (xy 242.974796 -317.563381) (xy 242.94973 -317.57493) (xy 242.939316 -317.579502)
			(xy 242.924584 -317.59652) (xy 242.896898 -317.694056) (xy 242.900454 -317.716154) (xy 242.907058 -317.725806)
			(xy 242.923028 -317.749804) (xy 242.948274 -317.801626) (xy 242.965428 -317.856658) (xy 242.974098 -317.913646)
			(xy 242.974622 -317.942468) (xy 242.97411 -317.971386) (xy 242.965384 -318.028558) (xy 242.948127 -318.083759)
			(xy 242.922734 -318.135721) (xy 242.889788 -318.183255) (xy 242.850043 -318.225269) (xy 242.827556 -318.243458)
			(xy 242.81881 -318.251035) (xy 242.80862 -318.271783) (xy 242.807998 -318.283336) (xy 242.807998 -318.3636)
			(xy 242.808569 -318.375168) (xy 242.818763 -318.395939) (xy 242.827556 -318.403478) (xy 242.848307 -318.420269)
			(xy 242.885435 -318.458619) (xy 242.916856 -318.501769) (xy 242.941954 -318.548878) (xy 242.960241 -318.599026)
			(xy 242.971359 -318.651233) (xy 242.975092 -318.70448) (xy 245.919475 -318.70448) (xy 245.923208 -318.651225)
			(xy 245.934329 -318.59901) (xy 245.952619 -318.548855) (xy 245.977723 -318.50174) (xy 246.00915 -318.458584)
			(xy 246.046286 -318.420231) (xy 246.067072 -318.403478) (xy 246.075851 -318.395934) (xy 246.086022 -318.375161)
			(xy 246.08663 -318.3636) (xy 246.08663 -318.283336) (xy 246.086063 -318.271767) (xy 246.075869 -318.250994)
			(xy 246.067072 -318.243458) (xy 246.044563 -318.225298) (xy 246.00483 -318.183271) (xy 245.971895 -318.135729)
			(xy 245.946511 -318.083762) (xy 245.929261 -318.028559) (xy 245.920538 -317.971386) (xy 245.920006 -317.942468)
			(xy 245.920492 -317.915217) (xy 245.928248 -317.861269) (xy 245.943603 -317.808974) (xy 245.966245 -317.759397)
			(xy 245.995711 -317.713547) (xy 246.031402 -317.672356) (xy 246.072593 -317.636665) (xy 246.118443 -317.607199)
			(xy 246.16802 -317.584557) (xy 246.220315 -317.569202) (xy 246.274263 -317.561446) (xy 246.328765 -317.561446)
			(xy 246.382713 -317.569202) (xy 246.435008 -317.584557) (xy 246.484585 -317.607199) (xy 246.530435 -317.636665)
			(xy 246.571626 -317.672356) (xy 246.607317 -317.713547) (xy 246.636783 -317.759397) (xy 246.659425 -317.808974)
			(xy 246.67478 -317.861269) (xy 246.682536 -317.915217) (xy 246.683022 -317.942468) (xy 246.68251 -317.971386)
			(xy 246.673784 -318.028558) (xy 246.656527 -318.083759) (xy 246.631134 -318.135721) (xy 246.598188 -318.183255)
			(xy 246.558443 -318.225269) (xy 246.535956 -318.243458) (xy 246.52721 -318.251035) (xy 246.51702 -318.271783)
			(xy 246.516398 -318.283336) (xy 246.516398 -318.3636) (xy 246.516969 -318.375168) (xy 246.527163 -318.395939)
			(xy 246.535956 -318.403478) (xy 246.556707 -318.420269) (xy 246.593835 -318.458619) (xy 246.625256 -318.501769)
			(xy 246.650354 -318.548878) (xy 246.668641 -318.599026) (xy 246.679759 -318.651233) (xy 246.683492 -318.70448)
			(xy 248.307075 -318.70448) (xy 248.310808 -318.651225) (xy 248.321929 -318.59901) (xy 248.340219 -318.548855)
			(xy 248.365323 -318.50174) (xy 248.39675 -318.458584) (xy 248.433886 -318.420231) (xy 248.454672 -318.403478)
			(xy 248.463451 -318.395934) (xy 248.473622 -318.375161) (xy 248.47423 -318.3636) (xy 248.47423 -318.283336)
			(xy 248.473663 -318.271767) (xy 248.463469 -318.250994) (xy 248.454672 -318.243458) (xy 248.432163 -318.225298)
			(xy 248.39243 -318.183271) (xy 248.359495 -318.135729) (xy 248.334111 -318.083762) (xy 248.316861 -318.028559)
			(xy 248.308138 -317.971386) (xy 248.307606 -317.942468) (xy 248.308023 -317.915885) (xy 248.315415 -317.863236)
			(xy 248.33005 -317.812124) (xy 248.351646 -317.763541) (xy 248.379782 -317.718431) (xy 248.413913 -317.677667)
			(xy 248.433336 -317.659512) (xy 248.440859 -317.651897) (xy 248.449528 -317.632354) (xy 248.4501 -317.621666)
			(xy 248.4501 -317.546482) (xy 248.449667 -317.535759) (xy 248.440993 -317.516154) (xy 248.433336 -317.508636)
			(xy 248.413902 -317.490495) (xy 248.379783 -317.449724) (xy 248.351658 -317.404608) (xy 248.330074 -317.356023)
			(xy 248.315449 -317.304911) (xy 248.308066 -317.252262) (xy 248.307606 -317.22568) (xy 248.308179 -317.196765)
			(xy 248.316897 -317.139596) (xy 248.334143 -317.084398) (xy 248.359525 -317.032436) (xy 248.392459 -316.984901)
			(xy 248.432191 -316.942882) (xy 248.454672 -316.92469) (xy 248.463446 -316.91714) (xy 248.47362 -316.896372)
			(xy 248.47423 -316.884812) (xy 248.47423 -316.804548) (xy 248.473656 -316.79298) (xy 248.463466 -316.772207)
			(xy 248.454672 -316.76467) (xy 248.432168 -316.746503) (xy 248.392436 -316.704477) (xy 248.3595 -316.656937)
			(xy 248.334115 -316.604971) (xy 248.316863 -316.54977) (xy 248.308139 -316.492597) (xy 248.307606 -316.46368)
			(xy 248.308092 -316.436429) (xy 248.315848 -316.382481) (xy 248.331203 -316.330186) (xy 248.353845 -316.280609)
			(xy 248.383311 -316.234759) (xy 248.419002 -316.193568) (xy 248.460193 -316.157877) (xy 248.506043 -316.128411)
			(xy 248.55562 -316.105769) (xy 248.607915 -316.090414) (xy 248.661863 -316.082658) (xy 248.716365 -316.082658)
			(xy 248.770313 -316.090414) (xy 248.822608 -316.105769) (xy 248.872185 -316.128411) (xy 248.918035 -316.157877)
			(xy 248.959226 -316.193568) (xy 248.994917 -316.234759) (xy 249.024383 -316.280609) (xy 249.047025 -316.330186)
			(xy 249.06238 -316.382481) (xy 249.070136 -316.436429) (xy 249.070622 -316.46368) (xy 249.070119 -316.492598)
			(xy 249.061391 -316.549771) (xy 249.044132 -316.604972) (xy 249.018738 -316.656934) (xy 248.98579 -316.704467)
			(xy 248.946044 -316.746482) (xy 248.923556 -316.76467) (xy 248.914805 -316.772242) (xy 248.904617 -316.792993)
			(xy 248.903998 -316.804548) (xy 248.903998 -316.884812) (xy 248.904562 -316.896381) (xy 248.914761 -316.917151)
			(xy 248.923556 -316.92469) (xy 248.946026 -316.942898) (xy 248.985764 -316.984913) (xy 249.018706 -317.032444)
			(xy 249.044097 -317.084402) (xy 249.061355 -317.139597) (xy 249.070086 -317.196765) (xy 249.070622 -317.22568)
			(xy 249.070161 -317.252261) (xy 249.062777 -317.304908) (xy 249.048149 -317.356019) (xy 249.026562 -317.404601)
			(xy 248.998434 -317.449713) (xy 248.964311 -317.490479) (xy 248.944892 -317.508636) (xy 248.937352 -317.516237)
			(xy 248.928691 -317.53579) (xy 248.928128 -317.546482) (xy 248.928128 -317.621666) (xy 248.928556 -317.632389)
			(xy 248.937236 -317.651993) (xy 248.944892 -317.659512) (xy 248.964287 -317.677694) (xy 248.998413 -317.718454)
			(xy 249.026544 -317.763561) (xy 249.048135 -317.812138) (xy 249.062768 -317.863244) (xy 249.070159 -317.915888)
			(xy 249.070622 -317.942468) (xy 249.07011 -317.971386) (xy 249.061384 -318.028558) (xy 249.044127 -318.083759)
			(xy 249.018734 -318.135721) (xy 248.985788 -318.183255) (xy 248.946043 -318.225269) (xy 248.923556 -318.243458)
			(xy 248.91481 -318.251035) (xy 248.90462 -318.271783) (xy 248.903998 -318.283336) (xy 248.903998 -318.3636)
			(xy 248.904569 -318.375168) (xy 248.914763 -318.395939) (xy 248.923556 -318.403478) (xy 248.944307 -318.420269)
			(xy 248.981435 -318.458619) (xy 249.012856 -318.501769) (xy 249.037954 -318.548878) (xy 249.056241 -318.599026)
			(xy 249.067359 -318.651233) (xy 249.071092 -318.70448) (xy 249.067365 -318.757728) (xy 249.056252 -318.809936)
			(xy 249.03797 -318.860086) (xy 249.012877 -318.907197) (xy 248.981461 -318.950351) (xy 248.944336 -318.988704)
			(xy 248.923556 -319.005458) (xy 248.91481 -319.013035) (xy 248.90462 -319.033783) (xy 248.903998 -319.045336)
			(xy 248.903998 -319.1256) (xy 248.904569 -319.137168) (xy 248.914763 -319.157939) (xy 248.923556 -319.165478)
			(xy 248.94602 -319.183693) (xy 248.985758 -319.225706) (xy 249.018701 -319.273236) (xy 249.044093 -319.325193)
			(xy 249.061353 -319.380387) (xy 249.070085 -319.437553) (xy 249.070622 -319.466468) (xy 249.070136 -319.493719)
			(xy 249.06238 -319.547667) (xy 249.047025 -319.599962) (xy 249.024383 -319.649539) (xy 248.994917 -319.695389)
			(xy 248.959226 -319.73658) (xy 248.918035 -319.772271) (xy 248.872185 -319.801737) (xy 248.822608 -319.824379)
			(xy 248.770313 -319.839734) (xy 248.716365 -319.84749) (xy 248.661863 -319.84749) (xy 248.607915 -319.839734)
			(xy 248.55562 -319.824379) (xy 248.506043 -319.801737) (xy 248.460193 -319.772271) (xy 248.419002 -319.73658)
			(xy 248.383311 -319.695389) (xy 248.353845 -319.649539) (xy 248.331203 -319.599962) (xy 248.315848 -319.547667)
			(xy 248.308092 -319.493719) (xy 248.307606 -319.466468) (xy 248.308171 -319.437553) (xy 248.31689 -319.380384)
			(xy 248.334138 -319.325186) (xy 248.359521 -319.273224) (xy 248.392457 -319.225689) (xy 248.43219 -319.18367)
			(xy 248.454672 -319.165478) (xy 248.463451 -319.157934) (xy 248.473622 -319.137161) (xy 248.47423 -319.1256)
			(xy 248.47423 -319.045336) (xy 248.473663 -319.033767) (xy 248.463469 -319.012994) (xy 248.454672 -319.005458)
			(xy 248.433857 -318.988743) (xy 248.396725 -318.950386) (xy 248.365302 -318.907227) (xy 248.340203 -318.860109)
			(xy 248.321918 -318.809952) (xy 248.310803 -318.757736) (xy 248.307075 -318.70448) (xy 246.683492 -318.70448)
			(xy 246.679765 -318.757728) (xy 246.668652 -318.809936) (xy 246.65037 -318.860086) (xy 246.625277 -318.907197)
			(xy 246.593861 -318.950351) (xy 246.556736 -318.988704) (xy 246.535956 -319.005458) (xy 246.52721 -319.013035)
			(xy 246.51702 -319.033783) (xy 246.516398 -319.045336) (xy 246.516398 -319.1256) (xy 246.516969 -319.137168)
			(xy 246.527163 -319.157939) (xy 246.535956 -319.165478) (xy 246.55842 -319.183693) (xy 246.598158 -319.225706)
			(xy 246.631101 -319.273236) (xy 246.656493 -319.325193) (xy 246.673753 -319.380387) (xy 246.682485 -319.437553)
			(xy 246.683022 -319.466468) (xy 246.682536 -319.493719) (xy 246.67478 -319.547667) (xy 246.659425 -319.599962)
			(xy 246.636783 -319.649539) (xy 246.607317 -319.695389) (xy 246.571626 -319.73658) (xy 246.530435 -319.772271)
			(xy 246.484585 -319.801737) (xy 246.435008 -319.824379) (xy 246.382713 -319.839734) (xy 246.328765 -319.84749)
			(xy 246.274263 -319.84749) (xy 246.220315 -319.839734) (xy 246.16802 -319.824379) (xy 246.118443 -319.801737)
			(xy 246.072593 -319.772271) (xy 246.031402 -319.73658) (xy 245.995711 -319.695389) (xy 245.966245 -319.649539)
			(xy 245.943603 -319.599962) (xy 245.928248 -319.547667) (xy 245.920492 -319.493719) (xy 245.920006 -319.466468)
			(xy 245.920571 -319.437553) (xy 245.92929 -319.380384) (xy 245.946538 -319.325186) (xy 245.971921 -319.273224)
			(xy 246.004857 -319.225689) (xy 246.04459 -319.18367) (xy 246.067072 -319.165478) (xy 246.075851 -319.157934)
			(xy 246.086022 -319.137161) (xy 246.08663 -319.1256) (xy 246.08663 -319.045336) (xy 246.086063 -319.033767)
			(xy 246.075869 -319.012994) (xy 246.067072 -319.005458) (xy 246.046257 -318.988743) (xy 246.009125 -318.950386)
			(xy 245.977702 -318.907227) (xy 245.952603 -318.860109) (xy 245.934318 -318.809952) (xy 245.923203 -318.757736)
			(xy 245.919475 -318.70448) (xy 242.975092 -318.70448) (xy 242.971365 -318.757728) (xy 242.960252 -318.809936)
			(xy 242.94197 -318.860086) (xy 242.916877 -318.907197) (xy 242.885461 -318.950351) (xy 242.848336 -318.988704)
			(xy 242.827556 -319.005458) (xy 242.81881 -319.013035) (xy 242.80862 -319.033783) (xy 242.807998 -319.045336)
			(xy 242.807998 -319.1256) (xy 242.808569 -319.137168) (xy 242.818763 -319.157939) (xy 242.827556 -319.165478)
			(xy 242.85002 -319.183693) (xy 242.889758 -319.225706) (xy 242.922701 -319.273236) (xy 242.948093 -319.325193)
			(xy 242.965353 -319.380387) (xy 242.974085 -319.437553) (xy 242.974622 -319.466468) (xy 242.974136 -319.493719)
			(xy 242.96638 -319.547667) (xy 242.951025 -319.599962) (xy 242.928383 -319.649539) (xy 242.898917 -319.695389)
			(xy 242.863226 -319.73658) (xy 242.822035 -319.772271) (xy 242.776185 -319.801737) (xy 242.726608 -319.824379)
			(xy 242.674313 -319.839734) (xy 242.620365 -319.84749) (xy 242.565863 -319.84749) (xy 242.511915 -319.839734)
			(xy 242.45962 -319.824379) (xy 242.410043 -319.801737) (xy 242.364193 -319.772271) (xy 242.323002 -319.73658)
			(xy 242.287311 -319.695389) (xy 242.257845 -319.649539) (xy 242.235203 -319.599962) (xy 242.219848 -319.547667)
			(xy 242.212092 -319.493719) (xy 242.211606 -319.466468) (xy 242.212171 -319.437553) (xy 242.22089 -319.380384)
			(xy 242.238138 -319.325186) (xy 242.263521 -319.273224) (xy 242.296457 -319.225689) (xy 242.33619 -319.18367)
			(xy 242.358672 -319.165478) (xy 242.367451 -319.157934) (xy 242.377622 -319.137161) (xy 242.37823 -319.1256)
			(xy 242.37823 -319.045336) (xy 242.377663 -319.033767) (xy 242.367469 -319.012994) (xy 242.358672 -319.005458)
			(xy 242.337857 -318.988743) (xy 242.300725 -318.950386) (xy 242.269302 -318.907227) (xy 242.244203 -318.860109)
			(xy 242.225918 -318.809952) (xy 242.214803 -318.757736) (xy 242.211075 -318.70448) (xy 240.587492 -318.70448)
			(xy 240.583765 -318.757728) (xy 240.572652 -318.809936) (xy 240.55437 -318.860086) (xy 240.529277 -318.907197)
			(xy 240.497861 -318.950351) (xy 240.460736 -318.988704) (xy 240.439956 -319.005458) (xy 240.43121 -319.013035)
			(xy 240.42102 -319.033783) (xy 240.420398 -319.045336) (xy 240.420398 -319.1256) (xy 240.420969 -319.137168)
			(xy 240.431163 -319.157939) (xy 240.439956 -319.165478) (xy 240.46242 -319.183693) (xy 240.502158 -319.225706)
			(xy 240.535101 -319.273236) (xy 240.560493 -319.325193) (xy 240.577753 -319.380387) (xy 240.586485 -319.437553)
			(xy 240.587022 -319.466468) (xy 240.586536 -319.493719) (xy 240.57878 -319.547667) (xy 240.563425 -319.599962)
			(xy 240.540783 -319.649539) (xy 240.511317 -319.695389) (xy 240.475626 -319.73658) (xy 240.434435 -319.772271)
			(xy 240.388585 -319.801737) (xy 240.339008 -319.824379) (xy 240.286713 -319.839734) (xy 240.232765 -319.84749)
			(xy 240.178263 -319.84749) (xy 240.124315 -319.839734) (xy 240.07202 -319.824379) (xy 240.022443 -319.801737)
			(xy 239.976593 -319.772271) (xy 239.935402 -319.73658) (xy 239.899711 -319.695389) (xy 239.870245 -319.649539)
			(xy 239.847603 -319.599962) (xy 239.832248 -319.547667) (xy 239.824492 -319.493719) (xy 239.824006 -319.466468)
			(xy 239.824571 -319.437553) (xy 239.83329 -319.380384) (xy 239.850538 -319.325186) (xy 239.875921 -319.273224)
			(xy 239.908857 -319.225689) (xy 239.94859 -319.18367) (xy 239.971072 -319.165478) (xy 239.979851 -319.157934)
			(xy 239.990022 -319.137161) (xy 239.99063 -319.1256) (xy 239.99063 -319.045336) (xy 239.990063 -319.033767)
			(xy 239.979869 -319.012994) (xy 239.971072 -319.005458) (xy 239.950257 -318.988743) (xy 239.913125 -318.950386)
			(xy 239.881702 -318.907227) (xy 239.856603 -318.860109) (xy 239.838318 -318.809952) (xy 239.827203 -318.757736)
			(xy 239.823475 -318.70448) (xy 234.089169 -318.70448) (xy 234.085442 -318.757729) (xy 234.074328 -318.809938)
			(xy 234.056044 -318.860089) (xy 234.030948 -318.9072) (xy 233.999529 -318.950353) (xy 233.962401 -318.988705)
			(xy 233.94162 -319.005458) (xy 233.932868 -319.013029) (xy 233.922683 -319.033781) (xy 233.922062 -319.045336)
			(xy 233.922062 -319.1256) (xy 233.922611 -319.137171) (xy 233.932818 -319.157943) (xy 233.94162 -319.165478)
			(xy 233.964097 -319.183676) (xy 234.003832 -319.225695) (xy 234.036771 -319.273229) (xy 234.06216 -319.325188)
			(xy 234.079418 -319.380384) (xy 234.08815 -319.437553) (xy 234.088686 -319.466468) (xy 234.0882 -319.493719)
			(xy 234.080444 -319.547667) (xy 234.065089 -319.599962) (xy 234.042447 -319.649539) (xy 234.012981 -319.695389)
			(xy 233.97729 -319.73658) (xy 233.936099 -319.772271) (xy 233.890249 -319.801737) (xy 233.840672 -319.824379)
			(xy 233.788377 -319.839734) (xy 233.734429 -319.84749) (xy 233.679927 -319.84749) (xy 233.625979 -319.839734)
			(xy 233.573684 -319.824379) (xy 233.524107 -319.801737) (xy 233.478257 -319.772271) (xy 233.437066 -319.73658)
			(xy 233.401375 -319.695389) (xy 233.371909 -319.649539) (xy 233.349267 -319.599962) (xy 233.333912 -319.547667)
			(xy 233.326156 -319.493719) (xy 233.32567 -319.466468) (xy 233.326211 -319.437552) (xy 233.334931 -319.38038)
			(xy 233.352183 -319.325181) (xy 233.377571 -319.273218) (xy 233.410512 -319.225684) (xy 233.450251 -319.183668)
			(xy 233.472736 -319.165478) (xy 233.481509 -319.157927) (xy 233.491685 -319.13716) (xy 233.492294 -319.1256)
			(xy 233.492294 -319.045336) (xy 233.491705 -319.033771) (xy 233.481524 -319.012999) (xy 233.472736 -319.005458)
			(xy 233.451923 -318.988742) (xy 233.414794 -318.950383) (xy 233.383374 -318.907224) (xy 233.358278 -318.860106)
			(xy 233.339994 -318.80995) (xy 233.32888 -318.757735) (xy 233.325153 -318.70448) (xy 231.701569 -318.70448)
			(xy 231.697842 -318.757729) (xy 231.686728 -318.809938) (xy 231.668444 -318.860089) (xy 231.643348 -318.9072)
			(xy 231.611929 -318.950353) (xy 231.574801 -318.988705) (xy 231.55402 -319.005458) (xy 231.545268 -319.013029)
			(xy 231.535083 -319.033781) (xy 231.534462 -319.045336) (xy 231.534462 -319.1256) (xy 231.535011 -319.137171)
			(xy 231.545218 -319.157943) (xy 231.55402 -319.165478) (xy 231.576497 -319.183676) (xy 231.616232 -319.225695)
			(xy 231.649171 -319.273229) (xy 231.67456 -319.325188) (xy 231.691818 -319.380384) (xy 231.70055 -319.437553)
			(xy 231.701086 -319.466468) (xy 231.7006 -319.493719) (xy 231.692844 -319.547667) (xy 231.677489 -319.599962)
			(xy 231.654847 -319.649539) (xy 231.625381 -319.695389) (xy 231.58969 -319.73658) (xy 231.548499 -319.772271)
			(xy 231.502649 -319.801737) (xy 231.453072 -319.824379) (xy 231.400777 -319.839734) (xy 231.346829 -319.84749)
			(xy 231.292327 -319.84749) (xy 231.238379 -319.839734) (xy 231.186084 -319.824379) (xy 231.136507 -319.801737)
			(xy 231.090657 -319.772271) (xy 231.049466 -319.73658) (xy 231.013775 -319.695389) (xy 230.984309 -319.649539)
			(xy 230.961667 -319.599962) (xy 230.946312 -319.547667) (xy 230.938556 -319.493719) (xy 230.93807 -319.466468)
			(xy 230.938611 -319.437552) (xy 230.947331 -319.38038) (xy 230.964583 -319.325181) (xy 230.989971 -319.273218)
			(xy 231.022912 -319.225684) (xy 231.062651 -319.183668) (xy 231.085136 -319.165478) (xy 231.093909 -319.157927)
			(xy 231.104085 -319.13716) (xy 231.104694 -319.1256) (xy 231.104694 -319.045336) (xy 231.104105 -319.033771)
			(xy 231.093924 -319.012999) (xy 231.085136 -319.005458) (xy 231.064323 -318.988742) (xy 231.027194 -318.950383)
			(xy 230.995774 -318.907224) (xy 230.970678 -318.860106) (xy 230.952394 -318.80995) (xy 230.94128 -318.757735)
			(xy 230.937553 -318.70448) (xy 227.993169 -318.70448) (xy 227.989442 -318.757729) (xy 227.978328 -318.809938)
			(xy 227.960044 -318.860089) (xy 227.934948 -318.9072) (xy 227.903529 -318.950353) (xy 227.866401 -318.988705)
			(xy 227.84562 -319.005458) (xy 227.836868 -319.013029) (xy 227.826683 -319.033781) (xy 227.826062 -319.045336)
			(xy 227.826062 -319.1256) (xy 227.826611 -319.137171) (xy 227.836818 -319.157943) (xy 227.84562 -319.165478)
			(xy 227.868097 -319.183676) (xy 227.907832 -319.225695) (xy 227.940771 -319.273229) (xy 227.96616 -319.325188)
			(xy 227.983418 -319.380384) (xy 227.99215 -319.437553) (xy 227.992686 -319.466468) (xy 227.9922 -319.493719)
			(xy 227.984444 -319.547667) (xy 227.969089 -319.599962) (xy 227.946447 -319.649539) (xy 227.916981 -319.695389)
			(xy 227.88129 -319.73658) (xy 227.840099 -319.772271) (xy 227.794249 -319.801737) (xy 227.744672 -319.824379)
			(xy 227.692377 -319.839734) (xy 227.638429 -319.84749) (xy 227.583927 -319.84749) (xy 227.529979 -319.839734)
			(xy 227.477684 -319.824379) (xy 227.428107 -319.801737) (xy 227.382257 -319.772271) (xy 227.341066 -319.73658)
			(xy 227.305375 -319.695389) (xy 227.275909 -319.649539) (xy 227.253267 -319.599962) (xy 227.237912 -319.547667)
			(xy 227.230156 -319.493719) (xy 227.22967 -319.466468) (xy 227.230211 -319.437552) (xy 227.238931 -319.38038)
			(xy 227.256183 -319.325181) (xy 227.281571 -319.273218) (xy 227.314512 -319.225684) (xy 227.354251 -319.183668)
			(xy 227.376736 -319.165478) (xy 227.385509 -319.157927) (xy 227.395685 -319.13716) (xy 227.396294 -319.1256)
			(xy 227.396294 -319.045336) (xy 227.395705 -319.033771) (xy 227.385524 -319.012999) (xy 227.376736 -319.005458)
			(xy 227.355923 -318.988742) (xy 227.318794 -318.950383) (xy 227.287374 -318.907224) (xy 227.262278 -318.860106)
			(xy 227.243994 -318.80995) (xy 227.23288 -318.757735) (xy 227.229153 -318.70448) (xy 225.605569 -318.70448)
			(xy 225.601842 -318.757729) (xy 225.590728 -318.809938) (xy 225.572444 -318.860089) (xy 225.547348 -318.9072)
			(xy 225.515929 -318.950353) (xy 225.478801 -318.988705) (xy 225.45802 -319.005458) (xy 225.449268 -319.013029)
			(xy 225.439083 -319.033781) (xy 225.438462 -319.045336) (xy 225.438462 -319.1256) (xy 225.439011 -319.137171)
			(xy 225.449218 -319.157943) (xy 225.45802 -319.165478) (xy 225.480497 -319.183676) (xy 225.520232 -319.225695)
			(xy 225.553171 -319.273229) (xy 225.57856 -319.325188) (xy 225.595818 -319.380384) (xy 225.60455 -319.437553)
			(xy 225.605086 -319.466468) (xy 225.6046 -319.493719) (xy 225.596844 -319.547667) (xy 225.581489 -319.599962)
			(xy 225.558847 -319.649539) (xy 225.529381 -319.695389) (xy 225.49369 -319.73658) (xy 225.452499 -319.772271)
			(xy 225.406649 -319.801737) (xy 225.357072 -319.824379) (xy 225.304777 -319.839734) (xy 225.250829 -319.84749)
			(xy 225.196327 -319.84749) (xy 225.142379 -319.839734) (xy 225.090084 -319.824379) (xy 225.040507 -319.801737)
			(xy 224.994657 -319.772271) (xy 224.953466 -319.73658) (xy 224.917775 -319.695389) (xy 224.888309 -319.649539)
			(xy 224.865667 -319.599962) (xy 224.850312 -319.547667) (xy 224.842556 -319.493719) (xy 224.84207 -319.466468)
			(xy 224.842611 -319.437552) (xy 224.851331 -319.38038) (xy 224.868583 -319.325181) (xy 224.893971 -319.273218)
			(xy 224.926912 -319.225684) (xy 224.966651 -319.183668) (xy 224.989136 -319.165478) (xy 224.997909 -319.157927)
			(xy 225.008085 -319.13716) (xy 225.008694 -319.1256) (xy 225.008694 -319.045336) (xy 225.008105 -319.033771)
			(xy 224.997924 -319.012999) (xy 224.989136 -319.005458) (xy 224.968323 -318.988742) (xy 224.931194 -318.950383)
			(xy 224.899774 -318.907224) (xy 224.874678 -318.860106) (xy 224.856394 -318.80995) (xy 224.84528 -318.757735)
			(xy 224.841553 -318.70448) (xy 220.452497 -318.70448) (xy 220.474285 -318.736041) (xy 220.502853 -318.790464)
			(xy 220.524653 -318.847934) (xy 220.539367 -318.907612) (xy 220.54678 -318.968629) (xy 220.547184 -318.999362)
			(xy 220.546649 -319.032462) (xy 220.538053 -319.098102) (xy 220.521014 -319.162072) (xy 220.495821 -319.223291)
			(xy 220.4629 -319.280724) (xy 220.422805 -319.333402) (xy 220.376216 -319.380433) (xy 220.32392 -319.421023)
			(xy 220.2668 -319.454486) (xy 220.205821 -319.480256) (xy 220.174058 -319.489582) (xy 220.16085 -319.493138)
			(xy 220.142054 -319.512188) (xy 220.116146 -319.610486) (xy 220.114257 -319.619129) (xy 220.115855 -319.636734)
			(xy 220.123375 -319.652732) (xy 220.129354 -319.659254) (xy 221.336573 -320.866473) (xy 247.984766 -320.866473)
			(xy 247.984766 -320.802551) (xy 247.992777 -320.739133) (xy 248.008674 -320.677219) (xy 248.032206 -320.617786)
			(xy 248.063 -320.561771) (xy 248.100573 -320.510056) (xy 248.14433 -320.463459) (xy 248.193583 -320.422714)
			(xy 248.247554 -320.388463) (xy 248.305393 -320.361246) (xy 248.366186 -320.341493) (xy 248.428976 -320.329515)
			(xy 248.492772 -320.325502) (xy 248.556568 -320.329515) (xy 248.619358 -320.341493) (xy 248.680151 -320.361246)
			(xy 248.73799 -320.388463) (xy 248.791961 -320.422714) (xy 248.841214 -320.463459) (xy 248.884971 -320.510056)
			(xy 248.922544 -320.561771) (xy 248.953338 -320.617786) (xy 248.97687 -320.677219) (xy 248.992767 -320.739133)
			(xy 249.000778 -320.802551) (xy 249.00128 -320.834512) (xy 249.000778 -320.866473) (xy 248.992767 -320.929891)
			(xy 248.97687 -320.991805) (xy 248.953338 -321.051238) (xy 248.922544 -321.107253) (xy 248.884971 -321.158968)
			(xy 248.841214 -321.205565) (xy 248.791961 -321.24631) (xy 248.73799 -321.280561) (xy 248.680151 -321.307778)
			(xy 248.619358 -321.327531) (xy 248.556568 -321.339509) (xy 248.492772 -321.343523) (xy 248.428976 -321.339509)
			(xy 248.366186 -321.327531) (xy 248.305393 -321.307778) (xy 248.247554 -321.280561) (xy 248.193583 -321.24631)
			(xy 248.14433 -321.205565) (xy 248.100573 -321.158968) (xy 248.063 -321.107253) (xy 248.032206 -321.051238)
			(xy 248.008674 -320.991805) (xy 247.992777 -320.929891) (xy 247.984766 -320.866473) (xy 221.336573 -320.866473)
			(xy 222.142261 -321.672161) (xy 232.438442 -321.672161) (xy 232.438442 -321.608239) (xy 232.446453 -321.544821)
			(xy 232.46235 -321.482907) (xy 232.485882 -321.423474) (xy 232.516676 -321.367459) (xy 232.554249 -321.315744)
			(xy 232.598006 -321.269147) (xy 232.647259 -321.228402) (xy 232.70123 -321.194151) (xy 232.759069 -321.166934)
			(xy 232.819862 -321.147181) (xy 232.882652 -321.135203) (xy 232.946448 -321.13119) (xy 233.010244 -321.135203)
			(xy 233.073034 -321.147181) (xy 233.133827 -321.166934) (xy 233.191666 -321.194151) (xy 233.245637 -321.228402)
			(xy 233.29489 -321.269147) (xy 233.338647 -321.315744) (xy 233.37622 -321.367459) (xy 233.407014 -321.423474)
			(xy 233.430546 -321.482907) (xy 233.446443 -321.544821) (xy 233.454454 -321.608239) (xy 233.454956 -321.6402)
			(xy 233.454768 -321.652138) (xy 235.520736 -321.652138) (xy 235.524807 -321.596516) (xy 235.536933 -321.542079)
			(xy 235.556856 -321.489988) (xy 235.584152 -321.441353) (xy 235.618238 -321.39721) (xy 235.658387 -321.358501)
			(xy 235.703745 -321.32605) (xy 235.753345 -321.300549) (xy 235.806129 -321.282542) (xy 235.860972 -321.272412)
			(xy 235.916706 -321.270375) (xy 235.972143 -321.276475) (xy 236.0261 -321.290581) (xy 236.077429 -321.312393)
			(xy 236.125035 -321.341447) (xy 236.167903 -321.377122) (xy 236.20512 -321.418659) (xy 236.235893 -321.465172)
			(xy 236.23888 -321.471544) (xy 238.503968 -321.471544) (xy 238.50447 -321.439583) (xy 238.512481 -321.376165)
			(xy 238.528378 -321.314251) (xy 238.55191 -321.254818) (xy 238.582704 -321.198803) (xy 238.620277 -321.147088)
			(xy 238.664034 -321.100491) (xy 238.713287 -321.059746) (xy 238.767258 -321.025495) (xy 238.825097 -320.998278)
			(xy 238.88589 -320.978525) (xy 238.94868 -320.966547) (xy 239.012476 -320.962534) (xy 239.076272 -320.966547)
			(xy 239.139062 -320.978525) (xy 239.199855 -320.998278) (xy 239.257694 -321.025495) (xy 239.311665 -321.059746)
			(xy 239.360918 -321.100491) (xy 239.404675 -321.147088) (xy 239.442248 -321.198803) (xy 239.473042 -321.254818)
			(xy 239.496574 -321.314251) (xy 239.512471 -321.376165) (xy 239.520482 -321.439583) (xy 239.520984 -321.471544)
			(xy 239.520399 -321.505335) (xy 239.511436 -321.572319) (xy 239.493687 -321.637529) (xy 239.467464 -321.699815)
			(xy 239.433228 -321.758084) (xy 239.391583 -321.811309) (xy 239.384739 -321.818) (xy 242.187982 -321.818)
			(xy 242.192053 -321.762378) (xy 242.204179 -321.707941) (xy 242.224102 -321.65585) (xy 242.251398 -321.607215)
			(xy 242.285484 -321.563072) (xy 242.325633 -321.524363) (xy 242.370991 -321.491912) (xy 242.420591 -321.466411)
			(xy 242.473375 -321.448404) (xy 242.528218 -321.438274) (xy 242.583952 -321.436237) (xy 242.639389 -321.442337)
			(xy 242.693346 -321.456443) (xy 242.744675 -321.478255) (xy 242.792281 -321.507309) (xy 242.835149 -321.542984)
			(xy 242.872366 -321.584521) (xy 242.903139 -321.631034) (xy 242.926811 -321.681531) (xy 242.942879 -321.734938)
			(xy 242.950999 -321.790114) (xy 242.951508 -321.818) (xy 242.950999 -321.845886) (xy 242.942879 -321.901062)
			(xy 242.926811 -321.954469) (xy 242.903139 -322.004966) (xy 242.872366 -322.051479) (xy 242.835149 -322.093016)
			(xy 242.792281 -322.128691) (xy 242.744675 -322.157745) (xy 242.693346 -322.179557) (xy 242.639389 -322.193663)
			(xy 242.583952 -322.199763) (xy 242.528218 -322.197726) (xy 242.473375 -322.187596) (xy 242.420591 -322.169589)
			(xy 242.370991 -322.144088) (xy 242.325633 -322.111637) (xy 242.285484 -322.072928) (xy 242.251398 -322.028785)
			(xy 242.224102 -321.98015) (xy 242.204179 -321.928059) (xy 242.192053 -321.873622) (xy 242.187982 -321.818)
			(xy 239.384739 -321.818) (xy 239.343259 -321.858554) (xy 239.316514 -321.879214) (xy 239.306862 -321.886326)
			(xy 239.296194 -321.907916) (xy 239.296448 -322.013834) (xy 239.30737 -322.035424) (xy 239.317276 -322.042536)
			(xy 239.344475 -322.063121) (xy 239.393624 -322.11042) (xy 239.436008 -322.163865) (xy 239.470865 -322.222498)
			(xy 239.497569 -322.285266) (xy 239.515641 -322.35104) (xy 239.524755 -322.41864) (xy 239.525302 -322.452746)
			(xy 239.5248 -322.484707) (xy 239.516789 -322.548125) (xy 239.500892 -322.610039) (xy 239.47736 -322.669472)
			(xy 239.446566 -322.725487) (xy 239.408993 -322.777202) (xy 239.365236 -322.823799) (xy 239.352905 -322.834)
			(xy 242.187982 -322.834) (xy 242.192053 -322.778378) (xy 242.204179 -322.723941) (xy 242.224102 -322.67185)
			(xy 242.251398 -322.623215) (xy 242.285484 -322.579072) (xy 242.325633 -322.540363) (xy 242.370991 -322.507912)
			(xy 242.420591 -322.482411) (xy 242.473375 -322.464404) (xy 242.528218 -322.454274) (xy 242.583952 -322.452237)
			(xy 242.639389 -322.458337) (xy 242.693346 -322.472443) (xy 242.744675 -322.494255) (xy 242.792281 -322.523309)
			(xy 242.835149 -322.558984) (xy 242.872366 -322.600521) (xy 242.903139 -322.647034) (xy 242.926811 -322.697531)
			(xy 242.942879 -322.750938) (xy 242.950999 -322.806114) (xy 242.951508 -322.834) (xy 242.950999 -322.861886)
			(xy 242.942879 -322.917062) (xy 242.926811 -322.970469) (xy 242.903139 -323.020966) (xy 242.872366 -323.067479)
			(xy 242.835149 -323.109016) (xy 242.792281 -323.144691) (xy 242.744675 -323.173745) (xy 242.693346 -323.195557)
			(xy 242.639389 -323.209663) (xy 242.583952 -323.215763) (xy 242.528218 -323.213726) (xy 242.473375 -323.203596)
			(xy 242.420591 -323.185589) (xy 242.370991 -323.160088) (xy 242.325633 -323.127637) (xy 242.285484 -323.088928)
			(xy 242.251398 -323.044785) (xy 242.224102 -322.99615) (xy 242.204179 -322.944059) (xy 242.192053 -322.889622)
			(xy 242.187982 -322.834) (xy 239.352905 -322.834) (xy 239.315983 -322.864544) (xy 239.262012 -322.898795)
			(xy 239.204173 -322.926012) (xy 239.14338 -322.945765) (xy 239.08059 -322.957743) (xy 239.016794 -322.961757)
			(xy 238.952998 -322.957743) (xy 238.890208 -322.945765) (xy 238.829415 -322.926012) (xy 238.771576 -322.898795)
			(xy 238.717605 -322.864544) (xy 238.668352 -322.823799) (xy 238.624595 -322.777202) (xy 238.587022 -322.725487)
			(xy 238.556228 -322.669472) (xy 238.532696 -322.610039) (xy 238.516799 -322.548125) (xy 238.508788 -322.484707)
			(xy 238.508286 -322.452746) (xy 238.508836 -322.418954) (xy 238.517801 -322.351967) (xy 238.535554 -322.286755)
			(xy 238.561782 -322.224467) (xy 238.596024 -322.166199) (xy 238.637677 -322.112976) (xy 238.686007 -322.065733)
			(xy 238.712756 -322.045076) (xy 238.722408 -322.037964) (xy 238.733076 -322.016374) (xy 238.732822 -321.910456)
			(xy 238.7219 -321.888866) (xy 238.711994 -321.881754) (xy 238.684784 -321.861184) (xy 238.635636 -321.813881)
			(xy 238.593254 -321.760433) (xy 238.558399 -321.701797) (xy 238.531697 -321.639028) (xy 238.513627 -321.573252)
			(xy 238.504514 -321.505651) (xy 238.503968 -321.471544) (xy 236.23888 -321.471544) (xy 236.259565 -321.515669)
			(xy 236.275633 -321.569076) (xy 236.283753 -321.624252) (xy 236.284262 -321.652138) (xy 236.283753 -321.680024)
			(xy 236.275633 -321.7352) (xy 236.259565 -321.788607) (xy 236.235893 -321.839104) (xy 236.20512 -321.885617)
			(xy 236.167903 -321.927154) (xy 236.125035 -321.962829) (xy 236.077429 -321.991883) (xy 236.0261 -322.013695)
			(xy 235.972143 -322.027801) (xy 235.916706 -322.033901) (xy 235.860972 -322.031864) (xy 235.806129 -322.021734)
			(xy 235.753345 -322.003727) (xy 235.703745 -321.978226) (xy 235.658387 -321.945775) (xy 235.618238 -321.907066)
			(xy 235.584152 -321.862923) (xy 235.556856 -321.814288) (xy 235.536933 -321.762197) (xy 235.524807 -321.70776)
			(xy 235.520736 -321.652138) (xy 233.454768 -321.652138) (xy 233.454454 -321.672161) (xy 233.446443 -321.735579)
			(xy 233.430546 -321.797493) (xy 233.407014 -321.856926) (xy 233.37622 -321.912941) (xy 233.338647 -321.964656)
			(xy 233.29489 -322.011253) (xy 233.245637 -322.051998) (xy 233.191666 -322.086249) (xy 233.133827 -322.113466)
			(xy 233.073034 -322.133219) (xy 233.010244 -322.145197) (xy 232.946448 -322.149211) (xy 232.882652 -322.145197)
			(xy 232.819862 -322.133219) (xy 232.759069 -322.113466) (xy 232.70123 -322.086249) (xy 232.647259 -322.051998)
			(xy 232.598006 -322.011253) (xy 232.554249 -321.964656) (xy 232.516676 -321.912941) (xy 232.485882 -321.856926)
			(xy 232.46235 -321.797493) (xy 232.446453 -321.735579) (xy 232.438442 -321.672161) (xy 222.142261 -321.672161)
			(xy 222.64878 -322.17868) (xy 229.228902 -322.17868) (xy 229.232973 -322.123058) (xy 229.245099 -322.068621)
			(xy 229.265022 -322.01653) (xy 229.292318 -321.967895) (xy 229.326404 -321.923752) (xy 229.366553 -321.885043)
			(xy 229.411911 -321.852592) (xy 229.461511 -321.827091) (xy 229.514295 -321.809084) (xy 229.569138 -321.798954)
			(xy 229.624872 -321.796917) (xy 229.680309 -321.803017) (xy 229.734266 -321.817123) (xy 229.785595 -321.838935)
			(xy 229.833201 -321.867989) (xy 229.876069 -321.903664) (xy 229.913286 -321.945201) (xy 229.944059 -321.991714)
			(xy 229.967731 -322.042211) (xy 229.983799 -322.095618) (xy 229.991919 -322.150794) (xy 229.992428 -322.17868)
			(xy 229.991919 -322.206566) (xy 229.983799 -322.261742) (xy 229.967731 -322.315149) (xy 229.944059 -322.365646)
			(xy 229.913286 -322.412159) (xy 229.876069 -322.453696) (xy 229.833201 -322.489371) (xy 229.785595 -322.518425)
			(xy 229.734266 -322.540237) (xy 229.680309 -322.554343) (xy 229.624872 -322.560443) (xy 229.569138 -322.558406)
			(xy 229.514295 -322.548276) (xy 229.461511 -322.530269) (xy 229.411911 -322.504768) (xy 229.366553 -322.472317)
			(xy 229.326404 -322.433608) (xy 229.292318 -322.389465) (xy 229.265022 -322.34083) (xy 229.245099 -322.288739)
			(xy 229.232973 -322.234302) (xy 229.228902 -322.17868) (xy 222.64878 -322.17868) (xy 223.733868 -323.263768)
			(xy 229.240078 -323.263768) (xy 229.244149 -323.208146) (xy 229.256275 -323.153709) (xy 229.276198 -323.101618)
			(xy 229.303494 -323.052983) (xy 229.33758 -323.00884) (xy 229.377729 -322.970131) (xy 229.423087 -322.93768)
			(xy 229.472687 -322.912179) (xy 229.525471 -322.894172) (xy 229.580314 -322.884042) (xy 229.636048 -322.882005)
			(xy 229.691485 -322.888105) (xy 229.745442 -322.902211) (xy 229.796771 -322.924023) (xy 229.844377 -322.953077)
			(xy 229.887245 -322.988752) (xy 229.924462 -323.030289) (xy 229.955235 -323.076802) (xy 229.978907 -323.127299)
			(xy 229.994975 -323.180706) (xy 230.003095 -323.235882) (xy 230.003604 -323.263768) (xy 230.003095 -323.291654)
			(xy 229.994975 -323.34683) (xy 229.978907 -323.400237) (xy 229.955235 -323.450734) (xy 229.924462 -323.497247)
			(xy 229.887245 -323.538784) (xy 229.844377 -323.574459) (xy 229.796771 -323.603513) (xy 229.745442 -323.625325)
			(xy 229.691485 -323.639431) (xy 229.636048 -323.645531) (xy 229.580314 -323.643494) (xy 229.525471 -323.633364)
			(xy 229.472687 -323.615357) (xy 229.423087 -323.589856) (xy 229.377729 -323.557405) (xy 229.33758 -323.518696)
			(xy 229.303494 -323.474553) (xy 229.276198 -323.425918) (xy 229.256275 -323.373827) (xy 229.244149 -323.31939)
			(xy 229.240078 -323.263768) (xy 223.733868 -323.263768) (xy 224.383854 -323.913754) (xy 232.44175 -323.913754)
			(xy 232.442263 -323.881462) (xy 232.450427 -323.817396) (xy 232.466644 -323.754882) (xy 232.490651 -323.694926)
			(xy 232.522062 -323.638495) (xy 232.56037 -323.5865) (xy 232.604958 -323.539778) (xy 232.655107 -323.499082)
			(xy 232.710008 -323.465069) (xy 232.739184 -323.45122) (xy 232.751884 -323.445378) (xy 232.767886 -323.422264)
			(xy 232.775252 -323.304662) (xy 232.762552 -323.27977) (xy 232.75036 -323.272404) (xy 232.723216 -323.254933)
			(xy 232.673127 -323.214212) (xy 232.628592 -323.167481) (xy 232.590329 -323.11549) (xy 232.558952 -323.059076)
			(xy 232.534965 -322.999145) (xy 232.518754 -322.93666) (xy 232.51058 -322.872627) (xy 232.510076 -322.84035)
			(xy 232.510578 -322.808389) (xy 232.518589 -322.744971) (xy 232.534486 -322.683057) (xy 232.558018 -322.623624)
			(xy 232.588812 -322.567609) (xy 232.626385 -322.515894) (xy 232.670142 -322.469297) (xy 232.719395 -322.428552)
			(xy 232.773366 -322.394301) (xy 232.831205 -322.367084) (xy 232.891998 -322.347331) (xy 232.954788 -322.335353)
			(xy 233.018584 -322.33134) (xy 233.08238 -322.335353) (xy 233.14517 -322.347331) (xy 233.205963 -322.367084)
			(xy 233.263802 -322.394301) (xy 233.317773 -322.428552) (xy 233.367026 -322.469297) (xy 233.410783 -322.515894)
			(xy 233.448356 -322.567609) (xy 233.47915 -322.623624) (xy 233.502682 -322.683057) (xy 233.50283 -322.683632)
			(xy 235.558836 -322.683632) (xy 235.562907 -322.62801) (xy 235.575033 -322.573573) (xy 235.594956 -322.521482)
			(xy 235.622252 -322.472847) (xy 235.656338 -322.428704) (xy 235.696487 -322.389995) (xy 235.741845 -322.357544)
			(xy 235.791445 -322.332043) (xy 235.844229 -322.314036) (xy 235.899072 -322.303906) (xy 235.954806 -322.301869)
			(xy 236.010243 -322.307969) (xy 236.0642 -322.322075) (xy 236.115529 -322.343887) (xy 236.163135 -322.372941)
			(xy 236.206003 -322.408616) (xy 236.24322 -322.450153) (xy 236.273993 -322.496666) (xy 236.297665 -322.547163)
			(xy 236.313733 -322.60057) (xy 236.321853 -322.655746) (xy 236.322362 -322.683632) (xy 236.321853 -322.711518)
			(xy 236.313733 -322.766694) (xy 236.297665 -322.820101) (xy 236.273993 -322.870598) (xy 236.24322 -322.917111)
			(xy 236.206003 -322.958648) (xy 236.163135 -322.994323) (xy 236.115529 -323.023377) (xy 236.0642 -323.045189)
			(xy 236.010243 -323.059295) (xy 235.954806 -323.065395) (xy 235.899072 -323.063358) (xy 235.844229 -323.053228)
			(xy 235.791445 -323.035221) (xy 235.741845 -323.00972) (xy 235.696487 -322.977269) (xy 235.656338 -322.93856)
			(xy 235.622252 -322.894417) (xy 235.594956 -322.845782) (xy 235.575033 -322.793691) (xy 235.562907 -322.739254)
			(xy 235.558836 -322.683632) (xy 233.50283 -322.683632) (xy 233.518579 -322.744971) (xy 233.52659 -322.808389)
			(xy 233.527092 -322.84035) (xy 233.526616 -322.872643) (xy 233.51845 -322.936712) (xy 233.502231 -322.999229)
			(xy 233.478221 -323.059187) (xy 233.446805 -323.115618) (xy 233.408492 -323.167614) (xy 233.363899 -323.214335)
			(xy 233.313744 -323.255028) (xy 233.258837 -323.289038) (xy 233.229658 -323.302884) (xy 233.216958 -323.308726)
			(xy 233.200956 -323.33184) (xy 233.19359 -323.449442) (xy 233.20629 -323.474334) (xy 233.218482 -323.4817)
			(xy 233.245638 -323.499154) (xy 233.295725 -323.539879) (xy 233.340257 -323.586613) (xy 233.378519 -323.638607)
			(xy 233.409894 -323.695023) (xy 233.43034 -323.746114) (xy 235.54639 -323.746114) (xy 235.550461 -323.690492)
			(xy 235.562587 -323.636055) (xy 235.58251 -323.583964) (xy 235.609806 -323.535329) (xy 235.643892 -323.491186)
			(xy 235.684041 -323.452477) (xy 235.729399 -323.420026) (xy 235.778999 -323.394525) (xy 235.831783 -323.376518)
			(xy 235.886626 -323.366388) (xy 235.94236 -323.364351) (xy 235.997797 -323.370451) (xy 236.051754 -323.384557)
			(xy 236.103083 -323.406369) (xy 236.150689 -323.435423) (xy 236.193557 -323.471098) (xy 236.230774 -323.512635)
			(xy 236.261547 -323.559148) (xy 236.285219 -323.609645) (xy 236.301287 -323.663052) (xy 236.309407 -323.718228)
			(xy 236.309916 -323.746114) (xy 236.309407 -323.774) (xy 236.301287 -323.829176) (xy 236.295022 -323.85)
			(xy 242.187982 -323.85) (xy 242.192053 -323.794378) (xy 242.204179 -323.739941) (xy 242.224102 -323.68785)
			(xy 242.251398 -323.639215) (xy 242.285484 -323.595072) (xy 242.325633 -323.556363) (xy 242.370991 -323.523912)
			(xy 242.420591 -323.498411) (xy 242.473375 -323.480404) (xy 242.528218 -323.470274) (xy 242.583952 -323.468237)
			(xy 242.639389 -323.474337) (xy 242.693346 -323.488443) (xy 242.744675 -323.510255) (xy 242.792281 -323.539309)
			(xy 242.835149 -323.574984) (xy 242.872366 -323.616521) (xy 242.903139 -323.663034) (xy 242.926811 -323.713531)
			(xy 242.942879 -323.766938) (xy 242.950999 -323.822114) (xy 242.951508 -323.85) (xy 244.220492 -323.85)
			(xy 244.221001 -323.819154) (xy 244.228477 -323.757915) (xy 244.243305 -323.698031) (xy 244.265269 -323.64038)
			(xy 244.294045 -323.58581) (xy 244.329212 -323.535121) (xy 244.370252 -323.48906) (xy 244.416563 -323.448301)
			(xy 244.467465 -323.413443) (xy 244.52221 -323.385) (xy 244.579993 -323.363387) (xy 244.609874 -323.355716)
			(xy 244.623336 -323.352414) (xy 244.642894 -323.333618) (xy 244.675406 -323.222874) (xy 244.668802 -323.196204)
			(xy 244.659404 -323.186552) (xy 244.637288 -323.162772) (xy 244.598598 -323.110615) (xy 244.566862 -323.053956)
			(xy 244.542597 -322.993719) (xy 244.526198 -322.930883) (xy 244.517931 -322.86647) (xy 244.517418 -322.834)
			(xy 244.517845 -322.8035) (xy 244.525153 -322.742938) (xy 244.539653 -322.683685) (xy 244.561136 -322.626592)
			(xy 244.589294 -322.572479) (xy 244.623722 -322.522122) (xy 244.663927 -322.476244) (xy 244.686328 -322.45554)
			(xy 244.69598 -322.44665) (xy 244.704616 -322.422266) (xy 244.686074 -322.311776) (xy 244.670072 -322.291456)
			(xy 244.65788 -322.286376) (xy 244.627613 -322.273007) (xy 244.570536 -322.239533) (xy 244.518281 -322.198941)
			(xy 244.471732 -322.151915) (xy 244.431675 -322.099249) (xy 244.398786 -322.041833) (xy 244.37362 -321.980637)
			(xy 244.356603 -321.916694) (xy 244.348023 -321.851084) (xy 244.347492 -321.818) (xy 244.347994 -321.786039)
			(xy 244.356005 -321.722621) (xy 244.371902 -321.660707) (xy 244.395434 -321.601274) (xy 244.426228 -321.545259)
			(xy 244.463801 -321.493544) (xy 244.507558 -321.446947) (xy 244.556811 -321.406202) (xy 244.610782 -321.371951)
			(xy 244.668621 -321.344734) (xy 244.729414 -321.324981) (xy 244.792204 -321.313003) (xy 244.856 -321.30899)
			(xy 244.919796 -321.313003) (xy 244.982586 -321.324981) (xy 245.043379 -321.344734) (xy 245.101218 -321.371951)
			(xy 245.155189 -321.406202) (xy 245.197166 -321.440928) (xy 249.087988 -321.440928) (xy 249.090594 -321.377898)
			(xy 249.100977 -321.315675) (xy 249.118976 -321.255214) (xy 249.144315 -321.197443) (xy 249.176606 -321.143251)
			(xy 249.215352 -321.093468) (xy 249.259958 -321.048861) (xy 249.309739 -321.010114) (xy 249.363931 -320.977822)
			(xy 249.421701 -320.95248) (xy 249.482161 -320.93448) (xy 249.544384 -320.924096) (xy 249.607414 -320.921488)
			(xy 249.670282 -320.926697) (xy 249.732023 -320.939642) (xy 249.791689 -320.960124) (xy 249.848363 -320.98783)
			(xy 249.901174 -321.022333) (xy 249.949313 -321.063103) (xy 249.992038 -321.109514) (xy 250.028695 -321.160855)
			(xy 250.05872 -321.216335) (xy 250.081652 -321.275102) (xy 250.097139 -321.336255) (xy 250.104942 -321.398854)
			(xy 250.105418 -321.430396) (xy 250.105302 -321.446506) (xy 250.103268 -321.478662) (xy 250.101354 -321.494658)
			(xy 250.09983 -321.506596) (xy 250.107704 -321.528948) (xy 250.18238 -321.602354) (xy 250.204986 -321.60972)
			(xy 250.216924 -321.607942) (xy 250.235236 -321.605437) (xy 250.272102 -321.602766) (xy 250.290584 -321.602608)
			(xy 250.322126 -321.603051) (xy 250.384726 -321.610852) (xy 250.44588 -321.626336) (xy 250.504649 -321.649266)
			(xy 250.560131 -321.679289) (xy 250.611473 -321.715944) (xy 250.657887 -321.758668) (xy 250.69866 -321.806805)
			(xy 250.726885 -321.850004) (xy 253.591058 -321.850004) (xy 253.595129 -321.794382) (xy 253.607255 -321.739945)
			(xy 253.627178 -321.687854) (xy 253.654474 -321.639219) (xy 253.68856 -321.595076) (xy 253.728709 -321.556367)
			(xy 253.774067 -321.523916) (xy 253.823667 -321.498415) (xy 253.876451 -321.480408) (xy 253.931294 -321.470278)
			(xy 253.987028 -321.468241) (xy 254.042465 -321.474341) (xy 254.096422 -321.488447) (xy 254.147751 -321.510259)
			(xy 254.195357 -321.539313) (xy 254.238225 -321.574988) (xy 254.275442 -321.616525) (xy 254.306215 -321.663038)
			(xy 254.329887 -321.713535) (xy 254.345955 -321.766942) (xy 254.354075 -321.822118) (xy 254.354584 -321.850004)
			(xy 254.354075 -321.87789) (xy 254.345955 -321.933066) (xy 254.329887 -321.986473) (xy 254.306215 -322.03697)
			(xy 254.275442 -322.083483) (xy 254.238225 -322.12502) (xy 254.195357 -322.160695) (xy 254.147751 -322.189749)
			(xy 254.096422 -322.211561) (xy 254.042465 -322.225667) (xy 253.987028 -322.231767) (xy 253.931294 -322.22973)
			(xy 253.876451 -322.2196) (xy 253.823667 -322.201593) (xy 253.774067 -322.176092) (xy 253.728709 -322.143641)
			(xy 253.68856 -322.104932) (xy 253.654474 -322.060789) (xy 253.627178 -322.012154) (xy 253.607255 -321.960063)
			(xy 253.595129 -321.905626) (xy 253.591058 -321.850004) (xy 250.726885 -321.850004) (xy 250.733165 -321.859616)
			(xy 250.760873 -321.916289) (xy 250.781358 -321.975955) (xy 250.794306 -322.037696) (xy 250.799517 -322.100564)
			(xy 250.796912 -322.163594) (xy 250.786531 -322.225818) (xy 250.768533 -322.28628) (xy 250.743194 -322.344052)
			(xy 250.710904 -322.398245) (xy 250.672159 -322.448029) (xy 250.627553 -322.492637) (xy 250.577772 -322.531386)
			(xy 250.52358 -322.563679) (xy 250.46581 -322.589022) (xy 250.405349 -322.607024) (xy 250.343126 -322.617409)
			(xy 250.280096 -322.620018) (xy 250.217227 -322.614811) (xy 250.155485 -322.601867) (xy 250.095819 -322.581385)
			(xy 250.039144 -322.553681) (xy 249.986331 -322.519179) (xy 249.938191 -322.478409) (xy 249.895464 -322.431998)
			(xy 249.858806 -322.380658) (xy 249.828779 -322.325178) (xy 249.805846 -322.266411) (xy 249.790358 -322.205257)
			(xy 249.782553 -322.142658) (xy 249.782076 -322.111116) (xy 249.782193 -322.095006) (xy 249.784226 -322.06285)
			(xy 249.78614 -322.046854) (xy 249.787664 -322.034916) (xy 249.77979 -322.012564) (xy 249.705114 -321.939158)
			(xy 249.682508 -321.931792) (xy 249.67057 -321.93357) (xy 249.652258 -321.936076) (xy 249.615392 -321.938747)
			(xy 249.59691 -321.938904) (xy 249.565368 -321.938443) (xy 249.502769 -321.930641) (xy 249.441616 -321.915156)
			(xy 249.382847 -321.892226) (xy 249.327366 -321.862203) (xy 249.276025 -321.825547) (xy 249.229613 -321.782823)
			(xy 249.188841 -321.734685) (xy 249.154337 -321.681875) (xy 249.12663 -321.625202) (xy 249.106145 -321.565536)
			(xy 249.093199 -321.503796) (xy 249.087988 -321.440928) (xy 245.197166 -321.440928) (xy 245.204442 -321.446947)
			(xy 245.248199 -321.493544) (xy 245.285772 -321.545259) (xy 245.316566 -321.601274) (xy 245.340098 -321.660707)
			(xy 245.355995 -321.722621) (xy 245.364006 -321.786039) (xy 245.364508 -321.818) (xy 245.364072 -321.8485)
			(xy 245.356765 -321.909061) (xy 245.342266 -321.968313) (xy 245.320784 -322.025406) (xy 245.292627 -322.07952)
			(xy 245.258201 -322.129877) (xy 245.217998 -322.175755) (xy 245.195598 -322.19646) (xy 245.185946 -322.20535)
			(xy 245.17731 -322.229734) (xy 245.195852 -322.340224) (xy 245.211854 -322.360544) (xy 245.224046 -322.365624)
			(xy 245.254319 -322.37898) (xy 245.311395 -322.412456) (xy 245.363649 -322.453051) (xy 245.410197 -322.500079)
			(xy 245.450253 -322.552747) (xy 245.483141 -322.610164) (xy 245.508306 -322.671361) (xy 245.525323 -322.735305)
			(xy 245.533904 -322.800915) (xy 245.534434 -322.834) (xy 245.533905 -322.864846) (xy 245.52643 -322.926082)
			(xy 245.511603 -322.985965) (xy 245.48964 -323.043615) (xy 245.460865 -323.098184) (xy 245.425701 -323.148872)
			(xy 245.384663 -323.194934) (xy 245.338354 -323.235694) (xy 245.287455 -323.270552) (xy 245.232713 -323.298997)
			(xy 245.174932 -323.320611) (xy 245.145052 -323.328284) (xy 245.13159 -323.331586) (xy 245.112032 -323.350382)
			(xy 245.090718 -323.422983) (xy 250.505462 -323.422983) (xy 250.505462 -323.359061) (xy 250.513473 -323.295643)
			(xy 250.52937 -323.233729) (xy 250.552902 -323.174296) (xy 250.583696 -323.118281) (xy 250.621269 -323.066566)
			(xy 250.665026 -323.019969) (xy 250.714279 -322.979224) (xy 250.76825 -322.944973) (xy 250.826089 -322.917756)
			(xy 250.886882 -322.898003) (xy 250.949672 -322.886025) (xy 251.013468 -322.882012) (xy 251.077264 -322.886025)
			(xy 251.140054 -322.898003) (xy 251.200847 -322.917756) (xy 251.258686 -322.944973) (xy 251.312657 -322.979224)
			(xy 251.36191 -323.019969) (xy 251.364495 -323.022722) (xy 256.385058 -323.022722) (xy 256.389129 -322.9671)
			(xy 256.401255 -322.912663) (xy 256.421178 -322.860572) (xy 256.448474 -322.811937) (xy 256.48256 -322.767794)
			(xy 256.522709 -322.729085) (xy 256.568067 -322.696634) (xy 256.617667 -322.671133) (xy 256.670451 -322.653126)
			(xy 256.725294 -322.642996) (xy 256.781028 -322.640959) (xy 256.836465 -322.647059) (xy 256.890422 -322.661165)
			(xy 256.941751 -322.682977) (xy 256.989357 -322.712031) (xy 257.032225 -322.747706) (xy 257.069442 -322.789243)
			(xy 257.100215 -322.835756) (xy 257.123887 -322.886253) (xy 257.139955 -322.93966) (xy 257.148075 -322.994836)
			(xy 257.148584 -323.022722) (xy 257.148075 -323.050608) (xy 257.139955 -323.105784) (xy 257.123887 -323.159191)
			(xy 257.100215 -323.209688) (xy 257.069442 -323.256201) (xy 257.032225 -323.297738) (xy 256.989357 -323.333413)
			(xy 256.941751 -323.362467) (xy 256.890422 -323.384279) (xy 256.836465 -323.398385) (xy 256.781028 -323.404485)
			(xy 256.725294 -323.402448) (xy 256.670451 -323.392318) (xy 256.617667 -323.374311) (xy 256.568067 -323.34881)
			(xy 256.522709 -323.316359) (xy 256.48256 -323.27765) (xy 256.448474 -323.233507) (xy 256.421178 -323.184872)
			(xy 256.401255 -323.132781) (xy 256.389129 -323.078344) (xy 256.385058 -323.022722) (xy 251.364495 -323.022722)
			(xy 251.405667 -323.066566) (xy 251.44324 -323.118281) (xy 251.474034 -323.174296) (xy 251.497566 -323.233729)
			(xy 251.513463 -323.295643) (xy 251.521474 -323.359061) (xy 251.521976 -323.391022) (xy 251.521474 -323.422983)
			(xy 251.513463 -323.486401) (xy 251.497566 -323.548315) (xy 251.474034 -323.607748) (xy 251.44324 -323.663763)
			(xy 251.405667 -323.715478) (xy 251.36191 -323.762075) (xy 251.312657 -323.80282) (xy 251.258686 -323.837071)
			(xy 251.200847 -323.864288) (xy 251.140054 -323.884041) (xy 251.077264 -323.896019) (xy 251.013468 -323.900033)
			(xy 250.949672 -323.896019) (xy 250.886882 -323.884041) (xy 250.826089 -323.864288) (xy 250.76825 -323.837071)
			(xy 250.714279 -323.80282) (xy 250.665026 -323.762075) (xy 250.621269 -323.715478) (xy 250.583696 -323.663763)
			(xy 250.552902 -323.607748) (xy 250.52937 -323.548315) (xy 250.513473 -323.486401) (xy 250.505462 -323.422983)
			(xy 245.090718 -323.422983) (xy 245.07952 -323.461126) (xy 245.086124 -323.487796) (xy 245.095522 -323.497448)
			(xy 245.117643 -323.521224) (xy 245.156332 -323.573383) (xy 245.188066 -323.630042) (xy 245.21233 -323.69028)
			(xy 245.228728 -323.753117) (xy 245.236995 -323.817529) (xy 245.237508 -323.85) (xy 245.237054 -323.880464)
			(xy 245.229752 -323.940953) (xy 245.215289 -324.00014) (xy 245.204996 -324.028816) (xy 245.199916 -324.042532)
			(xy 245.200415 -324.045072) (xy 256.377692 -324.045072) (xy 256.381763 -323.98945) (xy 256.393889 -323.935013)
			(xy 256.413812 -323.882922) (xy 256.441108 -323.834287) (xy 256.475194 -323.790144) (xy 256.515343 -323.751435)
			(xy 256.560701 -323.718984) (xy 256.610301 -323.693483) (xy 256.663085 -323.675476) (xy 256.717928 -323.665346)
			(xy 256.773662 -323.663309) (xy 256.829099 -323.669409) (xy 256.883056 -323.683515) (xy 256.934385 -323.705327)
			(xy 256.981991 -323.734381) (xy 257.024859 -323.770056) (xy 257.062076 -323.811593) (xy 257.092849 -323.858106)
			(xy 257.116521 -323.908603) (xy 257.132589 -323.96201) (xy 257.140709 -324.017186) (xy 257.141218 -324.045072)
			(xy 257.140709 -324.072958) (xy 257.132589 -324.128134) (xy 257.116521 -324.181541) (xy 257.092849 -324.232038)
			(xy 257.062076 -324.278551) (xy 257.024859 -324.320088) (xy 256.981991 -324.355763) (xy 256.934385 -324.384817)
			(xy 256.883056 -324.406629) (xy 256.829099 -324.420735) (xy 256.773662 -324.426835) (xy 256.717928 -324.424798)
			(xy 256.663085 -324.414668) (xy 256.610301 -324.396661) (xy 256.560701 -324.37116) (xy 256.515343 -324.338709)
			(xy 256.475194 -324.3) (xy 256.441108 -324.255857) (xy 256.413812 -324.207222) (xy 256.393889 -324.155131)
			(xy 256.381763 -324.100694) (xy 256.377692 -324.045072) (xy 245.200415 -324.045072) (xy 245.205504 -324.07098)
			(xy 245.287546 -324.15861) (xy 245.315486 -324.16623) (xy 245.329456 -324.161912) (xy 245.365249 -324.151807)
			(xy 245.438828 -324.140969) (xy 245.476014 -324.140322) (xy 245.507554 -324.140782) (xy 245.570148 -324.148586)
			(xy 245.631297 -324.164073) (xy 245.69006 -324.187004) (xy 245.745536 -324.217027) (xy 245.796873 -324.253682)
			(xy 245.843281 -324.296405) (xy 245.884048 -324.34454) (xy 245.918549 -324.397348) (xy 245.946253 -324.454018)
			(xy 245.966734 -324.51368) (xy 245.979679 -324.575416) (xy 245.984888 -324.63828) (xy 245.982281 -324.701305)
			(xy 245.971899 -324.763524) (xy 245.953901 -324.823981) (xy 245.928562 -324.881748) (xy 245.896274 -324.935937)
			(xy 245.85753 -324.985715) (xy 245.812927 -325.03032) (xy 245.778966 -325.056754) (xy 256.397758 -325.056754)
			(xy 256.401829 -325.001132) (xy 256.413955 -324.946695) (xy 256.433878 -324.894604) (xy 256.461174 -324.845969)
			(xy 256.49526 -324.801826) (xy 256.535409 -324.763117) (xy 256.580767 -324.730666) (xy 256.630367 -324.705165)
			(xy 256.683151 -324.687158) (xy 256.737994 -324.677028) (xy 256.793728 -324.674991) (xy 256.849165 -324.681091)
			(xy 256.903122 -324.695197) (xy 256.954451 -324.717009) (xy 257.002057 -324.746063) (xy 257.044925 -324.781738)
			(xy 257.082142 -324.823275) (xy 257.112915 -324.869788) (xy 257.136587 -324.920285) (xy 257.152655 -324.973692)
			(xy 257.160775 -325.028868) (xy 257.161284 -325.056754) (xy 257.160775 -325.08464) (xy 257.152655 -325.139816)
			(xy 257.136587 -325.193223) (xy 257.112915 -325.24372) (xy 257.082142 -325.290233) (xy 257.044925 -325.33177)
			(xy 257.002057 -325.367445) (xy 256.954451 -325.396499) (xy 256.903122 -325.418311) (xy 256.849165 -325.432417)
			(xy 256.793728 -325.438517) (xy 256.737994 -325.43648) (xy 256.683151 -325.42635) (xy 256.630367 -325.408343)
			(xy 256.580767 -325.382842) (xy 256.535409 -325.350391) (xy 256.49526 -325.311682) (xy 256.461174 -325.267539)
			(xy 256.433878 -325.218904) (xy 256.413955 -325.166813) (xy 256.401829 -325.112376) (xy 256.397758 -325.056754)
			(xy 245.778966 -325.056754) (xy 245.76315 -325.069065) (xy 245.708962 -325.101355) (xy 245.651196 -325.126695)
			(xy 245.59074 -325.144695) (xy 245.528521 -325.15508) (xy 245.465496 -325.157688) (xy 245.402632 -325.152481)
			(xy 245.340895 -325.139538) (xy 245.281233 -325.119059) (xy 245.224562 -325.091357) (xy 245.171753 -325.056858)
			(xy 245.123617 -325.016092) (xy 245.080892 -324.969685) (xy 245.044236 -324.91835) (xy 245.014211 -324.862875)
			(xy 244.991278 -324.804112) (xy 244.975789 -324.742964) (xy 244.967983 -324.68037) (xy 244.967506 -324.64883)
			(xy 244.967968 -324.618366) (xy 244.975266 -324.557877) (xy 244.989727 -324.49869) (xy 245.000018 -324.470014)
			(xy 245.005098 -324.456298) (xy 244.99951 -324.42785) (xy 244.917468 -324.34022) (xy 244.889528 -324.3326)
			(xy 244.875558 -324.336918) (xy 244.839765 -324.347021) (xy 244.766186 -324.35786) (xy 244.729 -324.358508)
			(xy 244.698269 -324.358044) (xy 244.637255 -324.350635) (xy 244.577579 -324.335927) (xy 244.520111 -324.314132)
			(xy 244.465689 -324.285569) (xy 244.415107 -324.250655) (xy 244.369102 -324.209898) (xy 244.328345 -324.163893)
			(xy 244.293431 -324.113311) (xy 244.264868 -324.058889) (xy 244.243073 -324.001421) (xy 244.228365 -323.941745)
			(xy 244.220956 -323.880731) (xy 244.220492 -323.85) (xy 242.951508 -323.85) (xy 242.950999 -323.877886)
			(xy 242.942879 -323.933062) (xy 242.926811 -323.986469) (xy 242.903139 -324.036966) (xy 242.872366 -324.083479)
			(xy 242.835149 -324.125016) (xy 242.792281 -324.160691) (xy 242.744675 -324.189745) (xy 242.693346 -324.211557)
			(xy 242.639389 -324.225663) (xy 242.583952 -324.231763) (xy 242.528218 -324.229726) (xy 242.473375 -324.219596)
			(xy 242.420591 -324.201589) (xy 242.370991 -324.176088) (xy 242.325633 -324.143637) (xy 242.285484 -324.104928)
			(xy 242.251398 -324.060785) (xy 242.224102 -324.01215) (xy 242.204179 -323.960059) (xy 242.192053 -323.905622)
			(xy 242.187982 -323.85) (xy 236.295022 -323.85) (xy 236.285219 -323.882583) (xy 236.261547 -323.93308)
			(xy 236.230774 -323.979593) (xy 236.193557 -324.02113) (xy 236.150689 -324.056805) (xy 236.103083 -324.085859)
			(xy 236.051754 -324.107671) (xy 235.997797 -324.121777) (xy 235.94236 -324.127877) (xy 235.886626 -324.12584)
			(xy 235.831783 -324.11571) (xy 235.778999 -324.097703) (xy 235.729399 -324.072202) (xy 235.684041 -324.039751)
			(xy 235.643892 -324.001042) (xy 235.609806 -323.956899) (xy 235.58251 -323.908264) (xy 235.562587 -323.856173)
			(xy 235.550461 -323.801736) (xy 235.54639 -323.746114) (xy 233.43034 -323.746114) (xy 233.433879 -323.754956)
			(xy 233.450089 -323.817442) (xy 233.458263 -323.881477) (xy 233.458766 -323.913754) (xy 233.458227 -323.947343)
			(xy 233.449387 -324.013937) (xy 233.431854 -324.078786) (xy 233.405935 -324.140762) (xy 233.37208 -324.198786)
			(xy 233.330879 -324.251845) (xy 233.28305 -324.299018) (xy 233.229425 -324.339481) (xy 233.200448 -324.356476)
			(xy 233.188256 -324.363334) (xy 233.17454 -324.38721) (xy 233.175302 -324.503796) (xy 233.189526 -324.527418)
			(xy 233.201718 -324.534276) (xy 233.228082 -324.549152) (xy 233.277406 -324.584252) (xy 233.322212 -324.624961)
			(xy 233.361867 -324.670702) (xy 233.39581 -324.720828) (xy 233.423561 -324.774631) (xy 233.430454 -324.793102)
			(xy 235.578648 -324.793102) (xy 235.582719 -324.73748) (xy 235.594845 -324.683043) (xy 235.614768 -324.630952)
			(xy 235.642064 -324.582317) (xy 235.67615 -324.538174) (xy 235.716299 -324.499465) (xy 235.761657 -324.467014)
			(xy 235.811257 -324.441513) (xy 235.864041 -324.423506) (xy 235.918884 -324.413376) (xy 235.974618 -324.411339)
			(xy 236.030055 -324.417439) (xy 236.084012 -324.431545) (xy 236.135341 -324.453357) (xy 236.182947 -324.482411)
			(xy 236.225815 -324.518086) (xy 236.263032 -324.559623) (xy 236.293805 -324.606136) (xy 236.317477 -324.656633)
			(xy 236.333545 -324.71004) (xy 236.341665 -324.765216) (xy 236.342174 -324.793102) (xy 236.341665 -324.820988)
			(xy 236.333545 -324.876164) (xy 236.317477 -324.929571) (xy 236.293805 -324.980068) (xy 236.263032 -325.026581)
			(xy 236.225815 -325.068118) (xy 236.182947 -325.103793) (xy 236.135341 -325.132847) (xy 236.084012 -325.154659)
			(xy 236.030055 -325.168765) (xy 235.974618 -325.174865) (xy 235.918884 -325.172828) (xy 235.864041 -325.162698)
			(xy 235.811257 -325.144691) (xy 235.761657 -325.11919) (xy 235.716299 -325.086739) (xy 235.67615 -325.04803)
			(xy 235.642064 -325.003887) (xy 235.614768 -324.955252) (xy 235.594845 -324.903161) (xy 235.582719 -324.848724)
			(xy 235.578648 -324.793102) (xy 233.430454 -324.793102) (xy 233.444726 -324.831348) (xy 233.459007 -324.890177)
			(xy 233.466201 -324.950285) (xy 233.46664 -324.980554) (xy 233.466241 -325.011065) (xy 233.458939 -325.071648)
			(xy 233.444435 -325.130921) (xy 233.422937 -325.18803) (xy 233.394755 -325.242154) (xy 233.360294 -325.292514)
			(xy 233.320051 -325.338385) (xy 233.274604 -325.379106) (xy 233.224608 -325.414092) (xy 233.197908 -325.428864)
			(xy 233.185208 -325.435722) (xy 233.17073 -325.461122) (xy 233.17581 -325.582026) (xy 233.19232 -325.605902)
			(xy 233.205782 -325.611744) (xy 233.235794 -325.625236) (xy 233.292357 -325.658859) (xy 233.344113 -325.699494)
			(xy 233.390197 -325.746463) (xy 233.429841 -325.798982) (xy 233.462382 -325.856174) (xy 233.47792 -325.894192)
			(xy 235.54004 -325.894192) (xy 235.544111 -325.83857) (xy 235.556237 -325.784133) (xy 235.57616 -325.732042)
			(xy 235.603456 -325.683407) (xy 235.637542 -325.639264) (xy 235.677691 -325.600555) (xy 235.723049 -325.568104)
			(xy 235.772649 -325.542603) (xy 235.825433 -325.524596) (xy 235.880276 -325.514466) (xy 235.93601 -325.512429)
			(xy 235.991447 -325.518529) (xy 236.045404 -325.532635) (xy 236.096733 -325.554447) (xy 236.144339 -325.583501)
			(xy 236.187207 -325.619176) (xy 236.224424 -325.660713) (xy 236.255197 -325.707226) (xy 236.278869 -325.757723)
			(xy 236.294937 -325.81113) (xy 236.303057 -325.866306) (xy 236.303566 -325.894192) (xy 236.303057 -325.922078)
			(xy 236.294937 -325.977254) (xy 236.278869 -326.030661) (xy 236.255197 -326.081158) (xy 236.224424 -326.127671)
			(xy 236.187207 -326.169208) (xy 236.144339 -326.204883) (xy 236.096733 -326.233937) (xy 236.045404 -326.255749)
			(xy 235.991447 -326.269855) (xy 235.93601 -326.275955) (xy 235.880276 -326.273918) (xy 235.825433 -326.263788)
			(xy 235.772649 -326.245781) (xy 235.723049 -326.22028) (xy 235.677691 -326.187829) (xy 235.637542 -326.14912)
			(xy 235.603456 -326.104977) (xy 235.57616 -326.056342) (xy 235.556237 -326.004251) (xy 235.544111 -325.949814)
			(xy 235.54004 -325.894192) (xy 233.47792 -325.894192) (xy 233.487277 -325.917085) (xy 233.50411 -325.980697)
			(xy 233.512601 -326.045949) (xy 233.513122 -326.07885) (xy 233.51262 -326.110811) (xy 233.504609 -326.174229)
			(xy 233.488712 -326.236143) (xy 233.46518 -326.295576) (xy 233.434386 -326.351591) (xy 233.396813 -326.403306)
			(xy 233.353056 -326.449903) (xy 233.303803 -326.490648) (xy 233.249832 -326.524899) (xy 233.191993 -326.552116)
			(xy 233.1312 -326.571869) (xy 233.06841 -326.583847) (xy 233.004614 -326.587861) (xy 232.940818 -326.583847)
			(xy 232.878028 -326.571869) (xy 232.817235 -326.552116) (xy 232.759396 -326.524899) (xy 232.705425 -326.490648)
			(xy 232.656172 -326.449903) (xy 232.612415 -326.403306) (xy 232.574842 -326.351591) (xy 232.544048 -326.295576)
			(xy 232.520516 -326.236143) (xy 232.504619 -326.174229) (xy 232.496608 -326.110811) (xy 232.496106 -326.07885)
			(xy 232.496537 -326.04834) (xy 232.503837 -325.987759) (xy 232.518339 -325.928489) (xy 232.539834 -325.871381)
			(xy 232.568012 -325.817257) (xy 232.602469 -325.766898) (xy 232.642707 -325.721026) (xy 232.688149 -325.680303)
			(xy 232.73814 -325.645314) (xy 232.764838 -325.63054) (xy 232.777538 -325.623682) (xy 232.792016 -325.598282)
			(xy 232.786936 -325.477378) (xy 232.770426 -325.453502) (xy 232.756964 -325.44766) (xy 232.726942 -325.434191)
			(xy 232.67038 -325.400564) (xy 232.618626 -325.359924) (xy 232.572544 -325.312951) (xy 232.532902 -325.260429)
			(xy 232.500363 -325.203235) (xy 232.475469 -325.142322) (xy 232.458636 -325.078708) (xy 232.450145 -325.013455)
			(xy 232.449624 -324.980554) (xy 232.450174 -324.946965) (xy 232.459013 -324.880373) (xy 232.476545 -324.815523)
			(xy 232.502463 -324.753548) (xy 232.536316 -324.695524) (xy 232.577515 -324.642464) (xy 232.625343 -324.595292)
			(xy 232.678966 -324.554828) (xy 232.707942 -324.537832) (xy 232.720134 -324.530974) (xy 232.73385 -324.507098)
			(xy 232.733088 -324.390512) (xy 232.718864 -324.36689) (xy 232.706672 -324.360032) (xy 232.680309 -324.345154)
			(xy 232.630986 -324.310054) (xy 232.58618 -324.269345) (xy 232.546525 -324.223604) (xy 232.512582 -324.173478)
			(xy 232.484831 -324.119676) (xy 232.463666 -324.062959) (xy 232.449384 -324.004131) (xy 232.44219 -323.944023)
			(xy 232.44175 -323.913754) (xy 224.383854 -323.913754) (xy 224.819972 -324.349872) (xy 229.22052 -324.349872)
			(xy 229.224591 -324.29425) (xy 229.236717 -324.239813) (xy 229.25664 -324.187722) (xy 229.283936 -324.139087)
			(xy 229.318022 -324.094944) (xy 229.358171 -324.056235) (xy 229.403529 -324.023784) (xy 229.453129 -323.998283)
			(xy 229.505913 -323.980276) (xy 229.560756 -323.970146) (xy 229.61649 -323.968109) (xy 229.671927 -323.974209)
			(xy 229.725884 -323.988315) (xy 229.777213 -324.010127) (xy 229.824819 -324.039181) (xy 229.867687 -324.074856)
			(xy 229.904904 -324.116393) (xy 229.935677 -324.162906) (xy 229.959349 -324.213403) (xy 229.975417 -324.26681)
			(xy 229.983537 -324.321986) (xy 229.984046 -324.349872) (xy 229.983537 -324.377758) (xy 229.975417 -324.432934)
			(xy 229.959349 -324.486341) (xy 229.935677 -324.536838) (xy 229.904904 -324.583351) (xy 229.867687 -324.624888)
			(xy 229.824819 -324.660563) (xy 229.777213 -324.689617) (xy 229.725884 -324.711429) (xy 229.671927 -324.725535)
			(xy 229.61649 -324.731635) (xy 229.560756 -324.729598) (xy 229.505913 -324.719468) (xy 229.453129 -324.701461)
			(xy 229.403529 -324.67596) (xy 229.358171 -324.643509) (xy 229.318022 -324.6048) (xy 229.283936 -324.560657)
			(xy 229.25664 -324.512022) (xy 229.236717 -324.459931) (xy 229.224591 -324.405494) (xy 229.22052 -324.349872)
			(xy 224.819972 -324.349872) (xy 225.895662 -325.425562) (xy 229.208328 -325.425562) (xy 229.212399 -325.36994)
			(xy 229.224525 -325.315503) (xy 229.244448 -325.263412) (xy 229.271744 -325.214777) (xy 229.30583 -325.170634)
			(xy 229.345979 -325.131925) (xy 229.391337 -325.099474) (xy 229.440937 -325.073973) (xy 229.493721 -325.055966)
			(xy 229.548564 -325.045836) (xy 229.604298 -325.043799) (xy 229.659735 -325.049899) (xy 229.713692 -325.064005)
			(xy 229.765021 -325.085817) (xy 229.812627 -325.114871) (xy 229.855495 -325.150546) (xy 229.892712 -325.192083)
			(xy 229.923485 -325.238596) (xy 229.947157 -325.289093) (xy 229.963225 -325.3425) (xy 229.971345 -325.397676)
			(xy 229.971854 -325.425562) (xy 229.971345 -325.453448) (xy 229.963225 -325.508624) (xy 229.947157 -325.562031)
			(xy 229.923485 -325.612528) (xy 229.892712 -325.659041) (xy 229.855495 -325.700578) (xy 229.812627 -325.736253)
			(xy 229.765021 -325.765307) (xy 229.713692 -325.787119) (xy 229.659735 -325.801225) (xy 229.604298 -325.807325)
			(xy 229.548564 -325.805288) (xy 229.493721 -325.795158) (xy 229.440937 -325.777151) (xy 229.391337 -325.75165)
			(xy 229.345979 -325.719199) (xy 229.30583 -325.68049) (xy 229.271744 -325.636347) (xy 229.244448 -325.587712)
			(xy 229.224525 -325.535621) (xy 229.212399 -325.481184) (xy 229.208328 -325.425562) (xy 225.895662 -325.425562)
			(xy 226.96678 -326.49668) (xy 229.220012 -326.49668) (xy 229.224083 -326.441058) (xy 229.236209 -326.386621)
			(xy 229.256132 -326.33453) (xy 229.283428 -326.285895) (xy 229.317514 -326.241752) (xy 229.357663 -326.203043)
			(xy 229.403021 -326.170592) (xy 229.452621 -326.145091) (xy 229.505405 -326.127084) (xy 229.560248 -326.116954)
			(xy 229.615982 -326.114917) (xy 229.671419 -326.121017) (xy 229.725376 -326.135123) (xy 229.776705 -326.156935)
			(xy 229.824311 -326.185989) (xy 229.867179 -326.221664) (xy 229.904396 -326.263201) (xy 229.935169 -326.309714)
			(xy 229.958841 -326.360211) (xy 229.974909 -326.413618) (xy 229.983029 -326.468794) (xy 229.983538 -326.49668)
			(xy 229.983029 -326.524566) (xy 229.974909 -326.579742) (xy 229.958841 -326.633149) (xy 229.935169 -326.683646)
			(xy 229.904396 -326.730159) (xy 229.867179 -326.771696) (xy 229.824311 -326.807371) (xy 229.776705 -326.836425)
			(xy 229.725376 -326.858237) (xy 229.671419 -326.872343) (xy 229.615982 -326.878443) (xy 229.560248 -326.876406)
			(xy 229.505405 -326.866276) (xy 229.452621 -326.848269) (xy 229.403021 -326.822768) (xy 229.357663 -326.790317)
			(xy 229.317514 -326.751608) (xy 229.283428 -326.707465) (xy 229.256132 -326.65883) (xy 229.236209 -326.606739)
			(xy 229.224083 -326.552302) (xy 229.220012 -326.49668) (xy 226.96678 -326.49668) (xy 227.521262 -327.051162)
			(xy 227.528103 -327.058562) (xy 227.535821 -327.077161) (xy 227.536248 -327.08723) (xy 227.536248 -327.56602)
			(xy 229.214424 -327.56602) (xy 229.218495 -327.510398) (xy 229.230621 -327.455961) (xy 229.250544 -327.40387)
			(xy 229.27784 -327.355235) (xy 229.311926 -327.311092) (xy 229.352075 -327.272383) (xy 229.397433 -327.239932)
			(xy 229.447033 -327.214431) (xy 229.499817 -327.196424) (xy 229.55466 -327.186294) (xy 229.610394 -327.184257)
			(xy 229.665831 -327.190357) (xy 229.719788 -327.204463) (xy 229.771117 -327.226275) (xy 229.818723 -327.255329)
			(xy 229.861591 -327.291004) (xy 229.898808 -327.332541) (xy 229.929581 -327.379054) (xy 229.953253 -327.429551)
			(xy 229.969321 -327.482958) (xy 229.977441 -327.538134) (xy 229.97795 -327.56602) (xy 229.977441 -327.593906)
			(xy 229.969321 -327.649082) (xy 229.953253 -327.702489) (xy 229.929581 -327.752986) (xy 229.898808 -327.799499)
			(xy 229.861591 -327.841036) (xy 229.818723 -327.876711) (xy 229.771117 -327.905765) (xy 229.719788 -327.927577)
			(xy 229.665831 -327.941683) (xy 229.610394 -327.947783) (xy 229.55466 -327.945746) (xy 229.499817 -327.935616)
			(xy 229.447033 -327.917609) (xy 229.397433 -327.892108) (xy 229.352075 -327.859657) (xy 229.311926 -327.820948)
			(xy 229.27784 -327.776805) (xy 229.250544 -327.72817) (xy 229.230621 -327.676079) (xy 229.218495 -327.621642)
			(xy 229.214424 -327.56602) (xy 227.536248 -327.56602) (xy 227.536248 -328.25182) (xy 232.382822 -328.25182)
			(xy 232.383345 -328.218264) (xy 232.392159 -328.151735) (xy 232.40965 -328.086943) (xy 232.435514 -328.025017)
			(xy 232.469301 -327.967031) (xy 232.510424 -327.913995) (xy 232.558167 -327.866831) (xy 232.611701 -327.826359)
			(xy 232.640632 -327.809352) (xy 232.65257 -327.802748) (xy 232.666032 -327.780396) (xy 232.669842 -327.666858)
			(xy 232.657904 -327.64349) (xy 232.646728 -327.636124) (xy 232.620747 -327.618478) (xy 232.572966 -327.577715)
			(xy 232.53057 -327.531376) (xy 232.494205 -327.480167) (xy 232.464426 -327.424869) (xy 232.441686 -327.366323)
			(xy 232.426331 -327.305422) (xy 232.418595 -327.243093) (xy 232.418128 -327.21169) (xy 232.41863 -327.179729)
			(xy 232.426641 -327.116311) (xy 232.442538 -327.054397) (xy 232.46607 -326.994964) (xy 232.496864 -326.938949)
			(xy 232.534437 -326.887234) (xy 232.578194 -326.840637) (xy 232.627447 -326.799892) (xy 232.681418 -326.765641)
			(xy 232.739257 -326.738424) (xy 232.80005 -326.718671) (xy 232.86284 -326.706693) (xy 232.926636 -326.70268)
			(xy 232.990432 -326.706693) (xy 233.053222 -326.718671) (xy 233.114015 -326.738424) (xy 233.171854 -326.765641)
			(xy 233.225825 -326.799892) (xy 233.275078 -326.840637) (xy 233.318835 -326.887234) (xy 233.356408 -326.938949)
			(xy 233.360846 -326.947022) (xy 235.565694 -326.947022) (xy 235.569765 -326.8914) (xy 235.581891 -326.836963)
			(xy 235.601814 -326.784872) (xy 235.62911 -326.736237) (xy 235.663196 -326.692094) (xy 235.703345 -326.653385)
			(xy 235.748703 -326.620934) (xy 235.798303 -326.595433) (xy 235.851087 -326.577426) (xy 235.90593 -326.567296)
			(xy 235.961664 -326.565259) (xy 236.017101 -326.571359) (xy 236.071058 -326.585465) (xy 236.122387 -326.607277)
			(xy 236.169993 -326.636331) (xy 236.212861 -326.672006) (xy 236.250078 -326.713543) (xy 236.280851 -326.760056)
			(xy 236.304523 -326.810553) (xy 236.320591 -326.86396) (xy 236.328711 -326.919136) (xy 236.32922 -326.947022)
			(xy 236.328711 -326.974908) (xy 236.320591 -327.030084) (xy 236.304523 -327.083491) (xy 236.280851 -327.133988)
			(xy 236.250078 -327.180501) (xy 236.212861 -327.222038) (xy 236.169993 -327.257713) (xy 236.122387 -327.286767)
			(xy 236.071058 -327.308579) (xy 236.017101 -327.322685) (xy 235.961664 -327.328785) (xy 235.90593 -327.326748)
			(xy 235.851087 -327.316618) (xy 235.798303 -327.298611) (xy 235.748703 -327.27311) (xy 235.703345 -327.240659)
			(xy 235.663196 -327.20195) (xy 235.62911 -327.157807) (xy 235.601814 -327.109172) (xy 235.581891 -327.057081)
			(xy 235.569765 -327.002644) (xy 235.565694 -326.947022) (xy 233.360846 -326.947022) (xy 233.387202 -326.994964)
			(xy 233.410734 -327.054397) (xy 233.426631 -327.116311) (xy 233.434642 -327.179729) (xy 233.435144 -327.21169)
			(xy 233.434647 -327.245247) (xy 233.42583 -327.311778) (xy 233.408336 -327.376571) (xy 233.382469 -327.438498)
			(xy 233.348679 -327.496484) (xy 233.307552 -327.549519) (xy 233.259805 -327.596682) (xy 233.206267 -327.637153)
			(xy 233.177334 -327.654158) (xy 233.165396 -327.660762) (xy 233.151934 -327.683114) (xy 233.151414 -327.698608)
			(xy 238.484918 -327.698608) (xy 238.485394 -327.66603) (xy 238.493734 -327.601411) (xy 238.510253 -327.538384)
			(xy 238.534682 -327.477981) (xy 238.566619 -327.42119) (xy 238.605544 -327.368939) (xy 238.650819 -327.322084)
			(xy 238.701704 -327.28139) (xy 238.729266 -327.264014) (xy 238.740442 -327.25741) (xy 238.753142 -327.23582)
			(xy 238.757714 -327.12533) (xy 238.746792 -327.102724) (xy 238.736124 -327.095104) (xy 238.712145 -327.07713)
			(xy 238.668154 -327.036432) (xy 238.629249 -326.990847) (xy 238.595968 -326.941009) (xy 238.568772 -326.887605)
			(xy 238.548038 -326.831377) (xy 238.534053 -326.773103) (xy 238.52701 -326.713589) (xy 238.526574 -326.683624)
			(xy 238.527001 -326.652229) (xy 238.534719 -326.589915) (xy 238.550053 -326.529026) (xy 238.572769 -326.470489)
			(xy 238.602521 -326.415196) (xy 238.638856 -326.363987) (xy 238.681222 -326.317644) (xy 238.728973 -326.276871)
			(xy 238.75492 -326.25919) (xy 238.765842 -326.252078) (xy 238.77778 -326.229218) (xy 238.77651 -326.117712)
			(xy 238.76381 -326.09536) (xy 238.752888 -326.088248) (xy 238.725877 -326.070764) (xy 238.676036 -326.030071)
			(xy 238.63173 -325.983411) (xy 238.59367 -325.931531) (xy 238.562464 -325.875261) (xy 238.538612 -325.815502)
			(xy 238.522494 -325.75321) (xy 238.51437 -325.689382) (xy 238.513874 -325.65721) (xy 238.514409 -325.625263)
			(xy 238.522424 -325.561872) (xy 238.538315 -325.499985) (xy 238.561834 -325.440575) (xy 238.592609 -325.38458)
			(xy 238.630155 -325.33288) (xy 238.673881 -325.286291) (xy 238.723099 -325.245545) (xy 238.777033 -325.211286)
			(xy 238.80572 -325.197216) (xy 238.817658 -325.191628) (xy 238.832898 -325.170292) (xy 238.845852 -325.058024)
			(xy 238.835692 -325.033894) (xy 238.825278 -325.025766) (xy 238.799907 -325.005056) (xy 238.754228 -324.958121)
			(xy 238.714948 -324.905714) (xy 238.682715 -324.848701) (xy 238.658063 -324.788024) (xy 238.641399 -324.724686)
			(xy 238.632999 -324.659733) (xy 238.632492 -324.626986) (xy 238.632994 -324.595025) (xy 238.641005 -324.531607)
			(xy 238.656902 -324.469693) (xy 238.680434 -324.41026) (xy 238.711228 -324.354245) (xy 238.748801 -324.30253)
			(xy 238.792558 -324.255933) (xy 238.841811 -324.215188) (xy 238.895782 -324.180937) (xy 238.953621 -324.15372)
			(xy 239.014414 -324.133967) (xy 239.077204 -324.121989) (xy 239.141 -324.117976) (xy 239.204796 -324.121989)
			(xy 239.267586 -324.133967) (xy 239.328379 -324.15372) (xy 239.386218 -324.180937) (xy 239.440189 -324.215188)
			(xy 239.489442 -324.255933) (xy 239.533199 -324.30253) (xy 239.570772 -324.354245) (xy 239.601566 -324.41026)
			(xy 239.625098 -324.469693) (xy 239.640995 -324.531607) (xy 239.649006 -324.595025) (xy 239.649508 -324.626986)
			(xy 239.64898 -324.658934) (xy 239.640965 -324.722325) (xy 239.625073 -324.784213) (xy 239.601554 -324.843623)
			(xy 239.589256 -324.866) (xy 242.187982 -324.866) (xy 242.192053 -324.810378) (xy 242.204179 -324.755941)
			(xy 242.224102 -324.70385) (xy 242.251398 -324.655215) (xy 242.285484 -324.611072) (xy 242.325633 -324.572363)
			(xy 242.370991 -324.539912) (xy 242.420591 -324.514411) (xy 242.473375 -324.496404) (xy 242.528218 -324.486274)
			(xy 242.583952 -324.484237) (xy 242.639389 -324.490337) (xy 242.693346 -324.504443) (xy 242.744675 -324.526255)
			(xy 242.792281 -324.555309) (xy 242.835149 -324.590984) (xy 242.872366 -324.632521) (xy 242.903139 -324.679034)
			(xy 242.926811 -324.729531) (xy 242.942879 -324.782938) (xy 242.950999 -324.838114) (xy 242.951508 -324.866)
			(xy 242.950999 -324.893886) (xy 242.942879 -324.949062) (xy 242.926811 -325.002469) (xy 242.903139 -325.052966)
			(xy 242.872366 -325.099479) (xy 242.835149 -325.141016) (xy 242.792281 -325.176691) (xy 242.744675 -325.205745)
			(xy 242.693346 -325.227557) (xy 242.639389 -325.241663) (xy 242.583952 -325.247763) (xy 242.528218 -325.245726)
			(xy 242.473375 -325.235596) (xy 242.420591 -325.217589) (xy 242.370991 -325.192088) (xy 242.325633 -325.159637)
			(xy 242.285484 -325.120928) (xy 242.251398 -325.076785) (xy 242.224102 -325.02815) (xy 242.204179 -324.976059)
			(xy 242.192053 -324.921622) (xy 242.187982 -324.866) (xy 239.589256 -324.866) (xy 239.570779 -324.899618)
			(xy 239.533232 -324.951318) (xy 239.489504 -324.997907) (xy 239.440285 -325.038652) (xy 239.38635 -325.072911)
			(xy 239.357662 -325.08698) (xy 239.345724 -325.092568) (xy 239.330484 -325.113904) (xy 239.31753 -325.226172)
			(xy 239.32769 -325.250302) (xy 239.338104 -325.25843) (xy 239.363469 -325.279147) (xy 239.409149 -325.32608)
			(xy 239.448431 -325.378485) (xy 239.480664 -325.435497) (xy 239.505317 -325.496173) (xy 239.521982 -325.559511)
			(xy 239.530383 -325.624463) (xy 239.53089 -325.65721) (xy 239.530428 -325.688604) (xy 239.522717 -325.750917)
			(xy 239.50739 -325.811806) (xy 239.48468 -325.870343) (xy 239.454933 -325.925637) (xy 239.418601 -325.976846)
			(xy 239.376238 -326.02319) (xy 239.32849 -326.063963) (xy 239.302544 -326.081644) (xy 239.291622 -326.088756)
			(xy 239.279684 -326.111616) (xy 239.280954 -326.223122) (xy 239.293654 -326.245474) (xy 239.304576 -326.252586)
			(xy 239.331594 -326.27006) (xy 239.381437 -326.310753) (xy 239.425743 -326.357414) (xy 239.463804 -326.409295)
			(xy 239.495009 -326.465566) (xy 239.51886 -326.525327) (xy 239.534975 -326.587621) (xy 239.543096 -326.651452)
			(xy 239.54359 -326.683624) (xy 239.543057 -326.7162) (xy 239.534725 -326.780817) (xy 239.518214 -326.843842)
			(xy 239.493794 -326.904244) (xy 239.461865 -326.961036) (xy 239.422947 -327.013287) (xy 239.404557 -327.032323)
			(xy 240.064284 -327.032323) (xy 240.064284 -326.968401) (xy 240.072295 -326.904983) (xy 240.088192 -326.843069)
			(xy 240.111724 -326.783636) (xy 240.142518 -326.727621) (xy 240.180091 -326.675906) (xy 240.223848 -326.629309)
			(xy 240.273101 -326.588564) (xy 240.327072 -326.554313) (xy 240.384911 -326.527096) (xy 240.445704 -326.507343)
			(xy 240.508494 -326.495365) (xy 240.57229 -326.491352) (xy 240.636086 -326.495365) (xy 240.698876 -326.507343)
			(xy 240.759669 -326.527096) (xy 240.817508 -326.554313) (xy 240.871479 -326.588564) (xy 240.920732 -326.629309)
			(xy 240.964489 -326.675906) (xy 241.002062 -326.727621) (xy 241.032856 -326.783636) (xy 241.056388 -326.843069)
			(xy 241.070492 -326.898) (xy 242.061492 -326.898) (xy 242.061911 -326.86672) (xy 242.069575 -326.804631)
			(xy 242.084801 -326.743953) (xy 242.107358 -326.685601) (xy 242.136904 -326.630458) (xy 242.172995 -326.579358)
			(xy 242.215083 -326.533072) (xy 242.262532 -326.492301) (xy 242.288314 -326.474582) (xy 242.298474 -326.46713)
			(xy 242.31046 -326.444999) (xy 242.311174 -326.432418) (xy 242.311174 -326.347582) (xy 242.310494 -326.334999)
			(xy 242.298472 -326.31288) (xy 242.288314 -326.305418) (xy 242.262567 -326.287656) (xy 242.215139 -326.246876)
			(xy 242.173068 -326.200589) (xy 242.13699 -326.149492) (xy 242.10745 -326.094358) (xy 242.084892 -326.036017)
			(xy 242.069657 -325.975351) (xy 242.061976 -325.913275) (xy 242.061492 -325.882) (xy 242.061994 -325.850039)
			(xy 242.070005 -325.786621) (xy 242.085902 -325.724707) (xy 242.109434 -325.665274) (xy 242.140228 -325.609259)
			(xy 242.177801 -325.557544) (xy 242.221558 -325.510947) (xy 242.270811 -325.470202) (xy 242.324782 -325.435951)
			(xy 242.382621 -325.408734) (xy 242.443414 -325.388981) (xy 242.506204 -325.377003) (xy 242.57 -325.37299)
			(xy 242.633796 -325.377003) (xy 242.696586 -325.388981) (xy 242.757379 -325.408734) (xy 242.815218 -325.435951)
			(xy 242.869189 -325.470202) (xy 242.918442 -325.510947) (xy 242.962199 -325.557544) (xy 242.999772 -325.609259)
			(xy 243.030566 -325.665274) (xy 243.054098 -325.724707) (xy 243.069995 -325.786621) (xy 243.078006 -325.850039)
			(xy 243.078508 -325.882) (xy 243.078089 -325.91328) (xy 243.070425 -325.975369) (xy 243.055199 -326.036047)
			(xy 243.032642 -326.094399) (xy 243.003096 -326.149542) (xy 242.967005 -326.200642) (xy 242.924917 -326.246928)
			(xy 242.877468 -326.287699) (xy 242.851686 -326.305418) (xy 242.841526 -326.31287) (xy 242.82954 -326.335001)
			(xy 242.828826 -326.347582) (xy 242.828826 -326.432418) (xy 242.829506 -326.445001) (xy 242.841528 -326.46712)
			(xy 242.851686 -326.474582) (xy 242.877433 -326.492344) (xy 242.924861 -326.533124) (xy 242.954763 -326.566022)
			(xy 253.441454 -326.566022) (xy 253.441872 -326.539798) (xy 253.449066 -326.487846) (xy 253.463308 -326.437369)
			(xy 253.484329 -326.389318) (xy 253.511732 -326.344599) (xy 253.545003 -326.304054) (xy 253.583513 -326.268449)
			(xy 253.604776 -326.253094) (xy 253.616005 -326.244752) (xy 253.633731 -326.22312) (xy 253.644926 -326.197493)
			(xy 253.648751 -326.16979) (xy 253.64492 -326.142087) (xy 253.63372 -326.116462) (xy 253.61599 -326.094834)
			(xy 253.604776 -326.08647) (xy 253.583521 -326.07115) (xy 253.545072 -326.035555) (xy 253.511857 -325.995031)
			(xy 253.484503 -325.950342) (xy 253.463523 -325.90233) (xy 253.449314 -325.851897) (xy 253.442142 -325.799994)
			(xy 253.441708 -325.773796) (xy 253.442194 -325.746545) (xy 253.44995 -325.692597) (xy 253.465305 -325.640302)
			(xy 253.487947 -325.590725) (xy 253.517413 -325.544875) (xy 253.553104 -325.503684) (xy 253.594295 -325.467993)
			(xy 253.640145 -325.438527) (xy 253.689722 -325.415885) (xy 253.742017 -325.40053) (xy 253.795965 -325.392774)
			(xy 253.850467 -325.392774) (xy 253.904415 -325.40053) (xy 253.95671 -325.415885) (xy 254.006287 -325.438527)
			(xy 254.052137 -325.467993) (xy 254.093328 -325.503684) (xy 254.129019 -325.544875) (xy 254.158485 -325.590725)
			(xy 254.181127 -325.640302) (xy 254.196482 -325.692597) (xy 254.204238 -325.746545) (xy 254.204724 -325.773796)
			(xy 254.204286 -325.800019) (xy 254.197092 -325.851969) (xy 254.182851 -325.902444) (xy 254.161832 -325.950494)
			(xy 254.134432 -325.995213) (xy 254.101167 -326.035759) (xy 254.062662 -326.071367) (xy 254.041402 -326.086724)
			(xy 254.030157 -326.095046) (xy 254.012435 -326.116683) (xy 254.001244 -326.142315) (xy 253.997422 -326.170021)
			(xy 254.001255 -326.197725) (xy 254.012457 -326.223352) (xy 254.030188 -326.244982) (xy 254.041402 -326.253348)
			(xy 254.062661 -326.268664) (xy 254.101111 -326.304259) (xy 254.134326 -326.344783) (xy 254.16168 -326.389473)
			(xy 254.182659 -326.437486) (xy 254.196867 -326.48792) (xy 254.204037 -326.539824) (xy 254.20447 -326.566022)
			(xy 254.203984 -326.593273) (xy 254.196228 -326.647221) (xy 254.180873 -326.699516) (xy 254.158231 -326.749093)
			(xy 254.128765 -326.794943) (xy 254.093074 -326.836134) (xy 254.051883 -326.871825) (xy 254.006033 -326.901291)
			(xy 253.956456 -326.923933) (xy 253.904161 -326.939288) (xy 253.850213 -326.947044) (xy 253.795711 -326.947044)
			(xy 253.741763 -326.939288) (xy 253.689468 -326.923933) (xy 253.639891 -326.901291) (xy 253.594041 -326.871825)
			(xy 253.55285 -326.836134) (xy 253.517159 -326.794943) (xy 253.487693 -326.749093) (xy 253.465051 -326.699516)
			(xy 253.449696 -326.647221) (xy 253.44194 -326.593273) (xy 253.441454 -326.566022) (xy 242.954763 -326.566022)
			(xy 242.966932 -326.579411) (xy 243.00301 -326.630508) (xy 243.03255 -326.685642) (xy 243.055108 -326.743983)
			(xy 243.070343 -326.804649) (xy 243.078024 -326.866725) (xy 243.078508 -326.898) (xy 243.078006 -326.929961)
			(xy 243.069995 -326.993379) (xy 243.054098 -327.055293) (xy 243.030566 -327.114726) (xy 242.999772 -327.170741)
			(xy 242.977772 -327.201022) (xy 245.640858 -327.201022) (xy 245.644929 -327.1454) (xy 245.657055 -327.090963)
			(xy 245.676978 -327.038872) (xy 245.704274 -326.990237) (xy 245.73836 -326.946094) (xy 245.778509 -326.907385)
			(xy 245.823867 -326.874934) (xy 245.873467 -326.849433) (xy 245.926251 -326.831426) (xy 245.981094 -326.821296)
			(xy 246.036828 -326.819259) (xy 246.092265 -326.825359) (xy 246.146222 -326.839465) (xy 246.197551 -326.861277)
			(xy 246.245157 -326.890331) (xy 246.288025 -326.926006) (xy 246.325242 -326.967543) (xy 246.356015 -327.014056)
			(xy 246.379687 -327.064553) (xy 246.395755 -327.11796) (xy 246.403875 -327.173136) (xy 246.404384 -327.201022)
			(xy 246.403875 -327.228908) (xy 246.395755 -327.284084) (xy 246.379687 -327.337491) (xy 246.356015 -327.387988)
			(xy 246.325242 -327.434501) (xy 246.301848 -327.46061) (xy 253.441198 -327.46061) (xy 253.445269 -327.404988)
			(xy 253.457395 -327.350551) (xy 253.477318 -327.29846) (xy 253.504614 -327.249825) (xy 253.5387 -327.205682)
			(xy 253.578849 -327.166973) (xy 253.624207 -327.134522) (xy 253.673807 -327.109021) (xy 253.726591 -327.091014)
			(xy 253.781434 -327.080884) (xy 253.837168 -327.078847) (xy 253.892605 -327.084947) (xy 253.946562 -327.099053)
			(xy 253.997891 -327.120865) (xy 254.045497 -327.149919) (xy 254.088365 -327.185594) (xy 254.125582 -327.227131)
			(xy 254.156355 -327.273644) (xy 254.180027 -327.324141) (xy 254.196095 -327.377548) (xy 254.204215 -327.432724)
			(xy 254.204724 -327.46061) (xy 254.204215 -327.488496) (xy 254.196095 -327.543672) (xy 254.180027 -327.597079)
			(xy 254.156355 -327.647576) (xy 254.125582 -327.694089) (xy 254.088365 -327.735626) (xy 254.045497 -327.771301)
			(xy 254.039182 -327.775155) (xy 257.954439 -327.775155) (xy 257.954439 -327.720645) (xy 257.962197 -327.666689)
			(xy 257.977555 -327.614387) (xy 258.0002 -327.564803) (xy 258.029672 -327.518947) (xy 258.06537 -327.477752)
			(xy 258.106568 -327.442056) (xy 258.152426 -327.412588) (xy 258.202011 -327.389946) (xy 258.254315 -327.374591)
			(xy 258.308271 -327.366837) (xy 258.335526 -327.366376) (xy 258.358882 -327.366733) (xy 258.405241 -327.372469)
			(xy 258.427982 -327.377806) (xy 258.437126 -327.380092) (xy 258.455414 -327.377806) (xy 258.532376 -327.337166)
			(xy 258.544568 -327.323196) (xy 258.54787 -327.314306) (xy 258.558409 -327.287241) (xy 258.586538 -327.236428)
			(xy 258.622045 -327.190466) (xy 258.66411 -327.150419) (xy 258.711761 -327.117213) (xy 258.763894 -327.091614)
			(xy 258.819307 -327.074215) (xy 258.876716 -327.065418) (xy 258.905756 -327.064878) (xy 258.93388 -327.065364)
			(xy 258.989516 -327.073639) (xy 259.043331 -327.09) (xy 259.094157 -327.114094) (xy 259.140891 -327.145395)
			(xy 259.162042 -327.163938) (xy 259.169408 -327.170542) (xy 259.187188 -327.177146) (xy 259.276088 -327.175876)
			(xy 259.293614 -327.168764) (xy 259.300726 -327.161906) (xy 259.322162 -327.142138) (xy 259.369933 -327.108705)
			(xy 259.422234 -327.082926) (xy 259.477846 -327.065401) (xy 259.535478 -327.056537) (xy 259.564632 -327.055988)
			(xy 259.591881 -327.056484) (xy 259.645825 -327.064244) (xy 259.698116 -327.079602) (xy 259.747688 -327.102245)
			(xy 259.793534 -327.131711) (xy 259.83472 -327.167403) (xy 259.870408 -327.208592) (xy 259.899871 -327.25444)
			(xy 259.922509 -327.304014) (xy 259.937863 -327.356306) (xy 259.945618 -327.41025) (xy 259.945618 -327.46475)
			(xy 259.937863 -327.518694) (xy 259.922509 -327.570986) (xy 259.899871 -327.62056) (xy 259.870408 -327.666408)
			(xy 259.83472 -327.707597) (xy 259.793534 -327.743289) (xy 259.747688 -327.772755) (xy 259.698116 -327.795398)
			(xy 259.645825 -327.810756) (xy 259.591881 -327.818516) (xy 259.564632 -327.819004) (xy 259.536509 -327.818504)
			(xy 259.480875 -327.81023) (xy 259.42706 -327.79387) (xy 259.376234 -327.76978) (xy 259.329499 -327.738484)
			(xy 259.308346 -327.719944) (xy 259.30098 -327.71334) (xy 259.2832 -327.706736) (xy 259.1943 -327.708006)
			(xy 259.176774 -327.715118) (xy 259.169662 -327.721976) (xy 259.148228 -327.741746) (xy 259.100457 -327.77518)
			(xy 259.048156 -327.800959) (xy 258.992542 -327.818484) (xy 258.934911 -327.827345) (xy 258.905756 -327.827894)
			(xy 258.8824 -327.827523) (xy 258.836042 -327.821796) (xy 258.8133 -327.816464) (xy 258.804156 -327.814178)
			(xy 258.785868 -327.816464) (xy 258.708906 -327.857104) (xy 258.696714 -327.871074) (xy 258.693412 -327.879964)
			(xy 258.682872 -327.907029) (xy 258.654745 -327.957844) (xy 258.619239 -328.003807) (xy 258.577174 -328.043855)
			(xy 258.529524 -328.077062) (xy 258.477389 -328.10266) (xy 258.421976 -328.120058) (xy 258.364566 -328.128853)
			(xy 258.335526 -328.129392) (xy 258.308271 -328.128963) (xy 258.254315 -328.121209) (xy 258.202011 -328.105854)
			(xy 258.152426 -328.083212) (xy 258.106568 -328.053744) (xy 258.06537 -328.018048) (xy 258.029672 -327.976853)
			(xy 258.0002 -327.930997) (xy 257.977555 -327.881413) (xy 257.962197 -327.829111) (xy 257.954439 -327.775155)
			(xy 254.039182 -327.775155) (xy 253.997891 -327.800355) (xy 253.946562 -327.822167) (xy 253.892605 -327.836273)
			(xy 253.837168 -327.842373) (xy 253.781434 -327.840336) (xy 253.726591 -327.830206) (xy 253.673807 -327.812199)
			(xy 253.624207 -327.786698) (xy 253.578849 -327.754247) (xy 253.5387 -327.715538) (xy 253.504614 -327.671395)
			(xy 253.477318 -327.62276) (xy 253.457395 -327.570669) (xy 253.445269 -327.516232) (xy 253.441198 -327.46061)
			(xy 246.301848 -327.46061) (xy 246.288025 -327.476038) (xy 246.245157 -327.511713) (xy 246.197551 -327.540767)
			(xy 246.146222 -327.562579) (xy 246.092265 -327.576685) (xy 246.036828 -327.582785) (xy 245.981094 -327.580748)
			(xy 245.926251 -327.570618) (xy 245.873467 -327.552611) (xy 245.823867 -327.52711) (xy 245.778509 -327.494659)
			(xy 245.73836 -327.45595) (xy 245.704274 -327.411807) (xy 245.676978 -327.363172) (xy 245.657055 -327.311081)
			(xy 245.644929 -327.256644) (xy 245.640858 -327.201022) (xy 242.977772 -327.201022) (xy 242.962199 -327.222456)
			(xy 242.918442 -327.269053) (xy 242.869189 -327.309798) (xy 242.815218 -327.344049) (xy 242.757379 -327.371266)
			(xy 242.696586 -327.391019) (xy 242.633796 -327.402997) (xy 242.57 -327.407011) (xy 242.506204 -327.402997)
			(xy 242.443414 -327.391019) (xy 242.382621 -327.371266) (xy 242.324782 -327.344049) (xy 242.270811 -327.309798)
			(xy 242.221558 -327.269053) (xy 242.177801 -327.222456) (xy 242.140228 -327.170741) (xy 242.109434 -327.114726)
			(xy 242.085902 -327.055293) (xy 242.070005 -326.993379) (xy 242.061994 -326.929961) (xy 242.061492 -326.898)
			(xy 241.070492 -326.898) (xy 241.072285 -326.904983) (xy 241.080296 -326.968401) (xy 241.080798 -327.000362)
			(xy 241.080296 -327.032323) (xy 241.072285 -327.095741) (xy 241.056388 -327.157655) (xy 241.032856 -327.217088)
			(xy 241.002062 -327.273103) (xy 240.964489 -327.324818) (xy 240.920732 -327.371415) (xy 240.871479 -327.41216)
			(xy 240.817508 -327.446411) (xy 240.759669 -327.473628) (xy 240.698876 -327.493381) (xy 240.636086 -327.505359)
			(xy 240.57229 -327.509373) (xy 240.508494 -327.505359) (xy 240.445704 -327.493381) (xy 240.384911 -327.473628)
			(xy 240.327072 -327.446411) (xy 240.273101 -327.41216) (xy 240.223848 -327.371415) (xy 240.180091 -327.324818)
			(xy 240.142518 -327.273103) (xy 240.111724 -327.217088) (xy 240.088192 -327.157655) (xy 240.072295 -327.095741)
			(xy 240.064284 -327.032323) (xy 239.404557 -327.032323) (xy 239.377679 -327.060144) (xy 239.326801 -327.10084)
			(xy 239.299242 -327.118218) (xy 239.288066 -327.124822) (xy 239.275366 -327.146412) (xy 239.270794 -327.256902)
			(xy 239.281716 -327.279508) (xy 239.292384 -327.287128) (xy 239.31638 -327.30508) (xy 239.36037 -327.345782)
			(xy 239.399274 -327.39137) (xy 239.432553 -327.441212) (xy 239.459747 -327.494618) (xy 239.480478 -327.550849)
			(xy 239.49446 -327.609126) (xy 239.5015 -327.668642) (xy 239.501934 -327.698608) (xy 239.50141 -327.730215)
			(xy 239.49357 -327.79294) (xy 239.478013 -327.854209) (xy 239.454979 -327.913076) (xy 239.424822 -327.968633)
			(xy 239.388009 -328.020021) (xy 239.345109 -328.066448) (xy 239.296782 -328.107197) (xy 239.27054 -328.12482)
			(xy 239.259872 -328.131932) (xy 239.247426 -328.154792) (xy 239.247934 -328.266044) (xy 239.26038 -328.28865)
			(xy 239.271302 -328.295762) (xy 239.297922 -328.31334) (xy 239.347014 -328.354075) (xy 239.390623 -328.400632)
			(xy 239.428063 -328.45228) (xy 239.458747 -328.508207) (xy 239.482192 -328.567534) (xy 239.498028 -328.629328)
			(xy 239.506009 -328.692618) (xy 239.506506 -328.724514) (xy 239.506004 -328.756475) (xy 239.497993 -328.819893)
			(xy 239.482096 -328.881807) (xy 239.458564 -328.94124) (xy 239.42777 -328.997255) (xy 239.390197 -329.04897)
			(xy 239.34644 -329.095567) (xy 239.297187 -329.136312) (xy 239.243216 -329.170563) (xy 239.185377 -329.19778)
			(xy 239.124584 -329.217533) (xy 239.061794 -329.229511) (xy 238.997998 -329.233525) (xy 238.934202 -329.229511)
			(xy 238.871412 -329.217533) (xy 238.810619 -329.19778) (xy 238.75278 -329.170563) (xy 238.698809 -329.136312)
			(xy 238.649556 -329.095567) (xy 238.605799 -329.04897) (xy 238.568226 -328.997255) (xy 238.537432 -328.94124)
			(xy 238.5139 -328.881807) (xy 238.498003 -328.819893) (xy 238.489992 -328.756475) (xy 238.48949 -328.724514)
			(xy 238.489943 -328.692905) (xy 238.497792 -328.630176) (xy 238.513359 -328.568905) (xy 238.536404 -328.510037)
			(xy 238.56657 -328.454481) (xy 238.603393 -328.403093) (xy 238.646303 -328.356669) (xy 238.694638 -328.315923)
			(xy 238.720884 -328.298302) (xy 238.731552 -328.29119) (xy 238.743998 -328.26833) (xy 238.74349 -328.157078)
			(xy 238.731044 -328.134472) (xy 238.720122 -328.12736) (xy 238.693472 -328.109826) (xy 238.644379 -328.069086)
			(xy 238.600771 -328.022522) (xy 238.563332 -327.970868) (xy 238.532652 -327.914934) (xy 238.509213 -327.855601)
			(xy 238.493383 -327.793801) (xy 238.485411 -327.730506) (xy 238.484918 -327.698608) (xy 233.151414 -327.698608)
			(xy 233.148124 -327.796652) (xy 233.160062 -327.82002) (xy 233.171238 -327.827386) (xy 233.197216 -327.845036)
			(xy 233.244998 -327.885798) (xy 233.287396 -327.932136) (xy 233.323761 -327.983343) (xy 233.353541 -328.038641)
			(xy 233.371822 -328.085704) (xy 235.560106 -328.085704) (xy 235.564177 -328.030082) (xy 235.576303 -327.975645)
			(xy 235.596226 -327.923554) (xy 235.623522 -327.874919) (xy 235.657608 -327.830776) (xy 235.697757 -327.792067)
			(xy 235.743115 -327.759616) (xy 235.792715 -327.734115) (xy 235.845499 -327.716108) (xy 235.900342 -327.705978)
			(xy 235.956076 -327.703941) (xy 236.011513 -327.710041) (xy 236.06547 -327.724147) (xy 236.116799 -327.745959)
			(xy 236.164405 -327.775013) (xy 236.207273 -327.810688) (xy 236.24449 -327.852225) (xy 236.275263 -327.898738)
			(xy 236.298935 -327.949235) (xy 236.315003 -328.002642) (xy 236.323123 -328.057818) (xy 236.323632 -328.085704)
			(xy 236.323123 -328.11359) (xy 236.315003 -328.168766) (xy 236.298935 -328.222173) (xy 236.275263 -328.27267)
			(xy 236.24449 -328.319183) (xy 236.207273 -328.36072) (xy 236.164405 -328.396395) (xy 236.116799 -328.425449)
			(xy 236.06547 -328.447261) (xy 236.011513 -328.461367) (xy 235.956076 -328.467467) (xy 235.900342 -328.46543)
			(xy 235.845499 -328.4553) (xy 235.792715 -328.437293) (xy 235.743115 -328.411792) (xy 235.697757 -328.379341)
			(xy 235.657608 -328.340632) (xy 235.623522 -328.296489) (xy 235.596226 -328.247854) (xy 235.576303 -328.195763)
			(xy 235.564177 -328.141326) (xy 235.560106 -328.085704) (xy 233.371822 -328.085704) (xy 233.376282 -328.097187)
			(xy 233.391637 -328.158088) (xy 233.399372 -328.220417) (xy 233.399838 -328.25182) (xy 233.399313 -328.28397)
			(xy 233.391194 -328.347756) (xy 233.375099 -328.410009) (xy 233.351287 -328.469738) (xy 233.320136 -328.525989)
			(xy 233.282144 -328.577865) (xy 233.237916 -328.624538) (xy 233.188158 -328.665265) (xy 233.133664 -328.699396)
			(xy 233.10469 -328.713338) (xy 233.090974 -328.719688) (xy 233.074972 -328.745088) (xy 233.076496 -328.86777)
			(xy 233.093006 -328.892662) (xy 233.106722 -328.898758) (xy 233.136596 -328.91232) (xy 233.192907 -328.945988)
			(xy 233.24442 -328.986621) (xy 233.290278 -329.033541) (xy 233.329719 -329.085971) (xy 233.362088 -329.143039)
			(xy 233.37433 -329.173078) (xy 235.579664 -329.173078) (xy 235.583735 -329.117456) (xy 235.595861 -329.063019)
			(xy 235.615784 -329.010928) (xy 235.64308 -328.962293) (xy 235.677166 -328.91815) (xy 235.717315 -328.879441)
			(xy 235.762673 -328.84699) (xy 235.812273 -328.821489) (xy 235.865057 -328.803482) (xy 235.9199 -328.793352)
			(xy 235.975634 -328.791315) (xy 236.031071 -328.797415) (xy 236.085028 -328.811521) (xy 236.136357 -328.833333)
			(xy 236.183963 -328.862387) (xy 236.226831 -328.898062) (xy 236.264048 -328.939599) (xy 236.294821 -328.986112)
			(xy 236.318493 -329.036609) (xy 236.334561 -329.090016) (xy 236.342681 -329.145192) (xy 236.34319 -329.173078)
			(xy 236.342681 -329.200964) (xy 236.334561 -329.25614) (xy 236.318493 -329.309547) (xy 236.294821 -329.360044)
			(xy 236.264048 -329.406557) (xy 236.226831 -329.448094) (xy 236.183963 -329.483769) (xy 236.136357 -329.512823)
			(xy 236.085028 -329.534635) (xy 236.031071 -329.548741) (xy 235.975634 -329.554841) (xy 235.9199 -329.552804)
			(xy 235.865057 -329.542674) (xy 235.812273 -329.524667) (xy 235.762673 -329.499166) (xy 235.717315 -329.466715)
			(xy 235.677166 -329.428006) (xy 235.64308 -329.383863) (xy 235.615784 -329.335228) (xy 235.595861 -329.283137)
			(xy 235.583735 -329.2287) (xy 235.579664 -329.173078) (xy 233.37433 -329.173078) (xy 233.386848 -329.203796)
			(xy 233.403586 -329.267234) (xy 233.412025 -329.332298) (xy 233.412538 -329.365102) (xy 233.412036 -329.397063)
			(xy 233.404025 -329.460481) (xy 233.388128 -329.522395) (xy 233.364596 -329.581828) (xy 233.333802 -329.637843)
			(xy 233.296229 -329.689558) (xy 233.283481 -329.703133) (xy 248.215906 -329.703133) (xy 248.215906 -329.639211)
			(xy 248.223917 -329.575793) (xy 248.239814 -329.513879) (xy 248.263346 -329.454446) (xy 248.29414 -329.398431)
			(xy 248.331713 -329.346716) (xy 248.37547 -329.300119) (xy 248.424723 -329.259374) (xy 248.478694 -329.225123)
			(xy 248.536533 -329.197906) (xy 248.597326 -329.178153) (xy 248.660116 -329.166175) (xy 248.723912 -329.162162)
			(xy 248.787708 -329.166175) (xy 248.850498 -329.178153) (xy 248.911291 -329.197906) (xy 248.96913 -329.225123)
			(xy 249.023101 -329.259374) (xy 249.072354 -329.300119) (xy 249.116111 -329.346716) (xy 249.153684 -329.398431)
			(xy 249.184478 -329.454446) (xy 249.20801 -329.513879) (xy 249.223907 -329.575793) (xy 249.231918 -329.639211)
			(xy 249.23242 -329.671172) (xy 249.231918 -329.703133) (xy 249.223907 -329.766551) (xy 249.20801 -329.828465)
			(xy 249.184478 -329.887898) (xy 249.153684 -329.943913) (xy 249.116111 -329.995628) (xy 249.072354 -330.042225)
			(xy 249.023101 -330.08297) (xy 248.96913 -330.117221) (xy 248.911291 -330.144438) (xy 248.850498 -330.164191)
			(xy 248.787708 -330.176169) (xy 248.723912 -330.180183) (xy 248.660116 -330.176169) (xy 248.597326 -330.164191)
			(xy 248.536533 -330.144438) (xy 248.478694 -330.117221) (xy 248.424723 -330.08297) (xy 248.37547 -330.042225)
			(xy 248.331713 -329.995628) (xy 248.29414 -329.943913) (xy 248.263346 -329.887898) (xy 248.239814 -329.828465)
			(xy 248.223917 -329.766551) (xy 248.215906 -329.703133) (xy 233.283481 -329.703133) (xy 233.252472 -329.736155)
			(xy 233.203219 -329.7769) (xy 233.149248 -329.811151) (xy 233.091409 -329.838368) (xy 233.030616 -329.858121)
			(xy 232.967826 -329.870099) (xy 232.90403 -329.874113) (xy 232.840234 -329.870099) (xy 232.777444 -329.858121)
			(xy 232.716651 -329.838368) (xy 232.658812 -329.811151) (xy 232.604841 -329.7769) (xy 232.555588 -329.736155)
			(xy 232.511831 -329.689558) (xy 232.474258 -329.637843) (xy 232.443464 -329.581828) (xy 232.419932 -329.522395)
			(xy 232.404035 -329.460481) (xy 232.396024 -329.397063) (xy 232.395522 -329.365102) (xy 232.396088 -329.332953)
			(xy 232.404204 -329.26917) (xy 232.420295 -329.206919) (xy 232.444103 -329.147192) (xy 232.475248 -329.090942)
			(xy 232.513235 -329.039065) (xy 232.557457 -328.992391) (xy 232.60721 -328.951662) (xy 232.661699 -328.917528)
			(xy 232.69067 -328.903584) (xy 232.704386 -328.897234) (xy 232.720388 -328.871834) (xy 232.718864 -328.749152)
			(xy 232.702354 -328.72426) (xy 232.688638 -328.718164) (xy 232.658763 -328.704604) (xy 232.602454 -328.670933)
			(xy 232.550943 -328.6303) (xy 232.505086 -328.583378) (xy 232.465646 -328.530948) (xy 232.433277 -328.473881)
			(xy 232.408517 -328.413124) (xy 232.391777 -328.349687) (xy 232.383336 -328.284624) (xy 232.382822 -328.25182)
			(xy 227.536248 -328.25182) (xy 227.536248 -328.638662) (xy 229.145336 -328.638662) (xy 229.149407 -328.58304)
			(xy 229.161533 -328.528603) (xy 229.181456 -328.476512) (xy 229.208752 -328.427877) (xy 229.242838 -328.383734)
			(xy 229.282987 -328.345025) (xy 229.328345 -328.312574) (xy 229.377945 -328.287073) (xy 229.430729 -328.269066)
			(xy 229.485572 -328.258936) (xy 229.541306 -328.256899) (xy 229.596743 -328.262999) (xy 229.6507 -328.277105)
			(xy 229.702029 -328.298917) (xy 229.749635 -328.327971) (xy 229.792503 -328.363646) (xy 229.82972 -328.405183)
			(xy 229.860493 -328.451696) (xy 229.884165 -328.502193) (xy 229.900233 -328.5556) (xy 229.908353 -328.610776)
			(xy 229.908862 -328.638662) (xy 229.908353 -328.666548) (xy 229.900233 -328.721724) (xy 229.884165 -328.775131)
			(xy 229.860493 -328.825628) (xy 229.82972 -328.872141) (xy 229.792503 -328.913678) (xy 229.749635 -328.949353)
			(xy 229.702029 -328.978407) (xy 229.6507 -329.000219) (xy 229.596743 -329.014325) (xy 229.541306 -329.020425)
			(xy 229.485572 -329.018388) (xy 229.430729 -329.008258) (xy 229.377945 -328.990251) (xy 229.328345 -328.96475)
			(xy 229.282987 -328.932299) (xy 229.242838 -328.89359) (xy 229.208752 -328.849447) (xy 229.181456 -328.800812)
			(xy 229.161533 -328.748721) (xy 229.149407 -328.694284) (xy 229.145336 -328.638662) (xy 227.536248 -328.638662)
			(xy 227.536248 -329.698858) (xy 229.155242 -329.698858) (xy 229.159313 -329.643236) (xy 229.171439 -329.588799)
			(xy 229.191362 -329.536708) (xy 229.218658 -329.488073) (xy 229.252744 -329.44393) (xy 229.292893 -329.405221)
			(xy 229.338251 -329.37277) (xy 229.387851 -329.347269) (xy 229.440635 -329.329262) (xy 229.495478 -329.319132)
			(xy 229.551212 -329.317095) (xy 229.606649 -329.323195) (xy 229.660606 -329.337301) (xy 229.711935 -329.359113)
			(xy 229.759541 -329.388167) (xy 229.802409 -329.423842) (xy 229.839626 -329.465379) (xy 229.870399 -329.511892)
			(xy 229.894071 -329.562389) (xy 229.910139 -329.615796) (xy 229.918259 -329.670972) (xy 229.918768 -329.698858)
			(xy 229.918259 -329.726744) (xy 229.910139 -329.78192) (xy 229.894071 -329.835327) (xy 229.870399 -329.885824)
			(xy 229.839626 -329.932337) (xy 229.802409 -329.973874) (xy 229.759541 -330.009549) (xy 229.711935 -330.038603)
			(xy 229.660606 -330.060415) (xy 229.606649 -330.074521) (xy 229.551212 -330.080621) (xy 229.495478 -330.078584)
			(xy 229.440635 -330.068454) (xy 229.387851 -330.050447) (xy 229.338251 -330.024946) (xy 229.292893 -329.992495)
			(xy 229.252744 -329.953786) (xy 229.218658 -329.909643) (xy 229.191362 -329.861008) (xy 229.171439 -329.808917)
			(xy 229.159313 -329.75448) (xy 229.155242 -329.698858) (xy 227.536248 -329.698858) (xy 227.536248 -331.724)
			(xy 234.314492 -331.724) (xy 234.314911 -331.69272) (xy 234.322575 -331.630631) (xy 234.337801 -331.569953)
			(xy 234.360358 -331.511601) (xy 234.389904 -331.456458) (xy 234.425995 -331.405358) (xy 234.468083 -331.359072)
			(xy 234.515532 -331.318301) (xy 234.541314 -331.300582) (xy 234.551474 -331.29313) (xy 234.56346 -331.270999)
			(xy 234.564174 -331.258418) (xy 234.564174 -331.173582) (xy 234.563494 -331.160999) (xy 234.551472 -331.13888)
			(xy 234.541314 -331.131418) (xy 234.515567 -331.113656) (xy 234.468139 -331.072876) (xy 234.426068 -331.026589)
			(xy 234.38999 -330.975492) (xy 234.36045 -330.920358) (xy 234.337892 -330.862017) (xy 234.322657 -330.801351)
			(xy 234.314976 -330.739275) (xy 234.314492 -330.708) (xy 234.314994 -330.676039) (xy 234.323005 -330.612621)
			(xy 234.338902 -330.550707) (xy 234.362434 -330.491274) (xy 234.393228 -330.435259) (xy 234.430801 -330.383544)
			(xy 234.474558 -330.336947) (xy 234.523811 -330.296202) (xy 234.577782 -330.261951) (xy 234.635621 -330.234734)
			(xy 234.696414 -330.214981) (xy 234.759204 -330.203003) (xy 234.823 -330.19899) (xy 234.886796 -330.203003)
			(xy 234.949586 -330.214981) (xy 235.010379 -330.234734) (xy 235.068218 -330.261951) (xy 235.122189 -330.296202)
			(xy 235.171442 -330.336947) (xy 235.215199 -330.383544) (xy 235.252772 -330.435259) (xy 235.283566 -330.491274)
			(xy 235.307098 -330.550707) (xy 235.322995 -330.612621) (xy 235.331006 -330.676039) (xy 235.331508 -330.708)
			(xy 235.331089 -330.73928) (xy 235.323425 -330.801369) (xy 235.308199 -330.862047) (xy 235.285642 -330.920399)
			(xy 235.256096 -330.975542) (xy 235.220005 -331.026642) (xy 235.177917 -331.072928) (xy 235.130468 -331.113699)
			(xy 235.104686 -331.131418) (xy 235.094526 -331.13887) (xy 235.08254 -331.161001) (xy 235.081826 -331.173582)
			(xy 235.081826 -331.258418) (xy 235.082506 -331.271001) (xy 235.094528 -331.29312) (xy 235.104686 -331.300582)
			(xy 235.130433 -331.318344) (xy 235.159108 -331.343) (xy 237.870492 -331.343) (xy 237.870975 -331.314081)
			(xy 237.879707 -331.256907) (xy 237.896969 -331.201706) (xy 237.922367 -331.149744) (xy 237.955319 -331.102211)
			(xy 237.995068 -331.060197) (xy 238.017558 -331.04201) (xy 238.026321 -331.034449) (xy 238.036501 -331.013689)
			(xy 238.037116 -331.002132) (xy 238.037116 -330.921868) (xy 238.036501 -330.910306) (xy 238.026337 -330.889535)
			(xy 238.017558 -330.88199) (xy 237.995061 -330.863815) (xy 237.955329 -330.821791) (xy 237.922392 -330.774252)
			(xy 237.897007 -330.722288) (xy 237.879753 -330.667088) (xy 237.871026 -330.609917) (xy 237.870492 -330.581)
			(xy 237.870978 -330.553749) (xy 237.878734 -330.499801) (xy 237.894089 -330.447506) (xy 237.916731 -330.397929)
			(xy 237.946197 -330.352079) (xy 237.981888 -330.310888) (xy 238.023079 -330.275197) (xy 238.068929 -330.245731)
			(xy 238.118506 -330.223089) (xy 238.170801 -330.207734) (xy 238.224749 -330.199978) (xy 238.279251 -330.199978)
			(xy 238.333199 -330.207734) (xy 238.385494 -330.223089) (xy 238.435071 -330.245731) (xy 238.480921 -330.275197)
			(xy 238.522112 -330.310888) (xy 238.557803 -330.352079) (xy 238.587269 -330.397929) (xy 238.609911 -330.447506)
			(xy 238.625266 -330.499801) (xy 238.633022 -330.553749) (xy 238.633508 -330.581) (xy 238.633025 -330.609919)
			(xy 238.624293 -330.667093) (xy 238.607031 -330.722294) (xy 238.581633 -330.774256) (xy 238.548681 -330.821789)
			(xy 238.508932 -330.863803) (xy 238.486442 -330.88199) (xy 238.477679 -330.889551) (xy 238.467499 -330.910311)
			(xy 238.466884 -330.921868) (xy 238.466884 -331.002132) (xy 238.467499 -331.013694) (xy 238.477663 -331.034465)
			(xy 238.486442 -331.04201) (xy 238.508939 -331.060185) (xy 238.548671 -331.102209) (xy 238.581608 -331.149748)
			(xy 238.606993 -331.201712) (xy 238.624247 -331.256912) (xy 238.632974 -331.314083) (xy 238.633508 -331.343)
			(xy 238.633322 -331.353414) (xy 239.74298 -331.353414) (xy 239.743453 -331.32267) (xy 239.750875 -331.261631)
			(xy 239.765601 -331.201932) (xy 239.787415 -331.144444) (xy 239.816 -331.090004) (xy 239.850938 -331.039406)
			(xy 239.870996 -331.016102) (xy 239.876774 -331.008943) (xy 239.8833 -330.991763) (xy 239.883696 -330.982574)
			(xy 239.883696 -330.95184) (xy 239.883268 -330.942655) (xy 239.876767 -330.92547) (xy 239.870996 -330.918312)
			(xy 239.850945 -330.895) (xy 239.81599 -330.844412) (xy 239.787393 -330.789975) (xy 239.765572 -330.732487)
			(xy 239.750844 -330.672787) (xy 239.743427 -330.611745) (xy 239.74298 -330.581) (xy 239.743482 -330.549039)
			(xy 239.751493 -330.485621) (xy 239.76739 -330.423707) (xy 239.790922 -330.364274) (xy 239.821716 -330.308259)
			(xy 239.859289 -330.256544) (xy 239.903046 -330.209947) (xy 239.952299 -330.169202) (xy 240.00627 -330.134951)
			(xy 240.064109 -330.107734) (xy 240.124902 -330.087981) (xy 240.187692 -330.076003) (xy 240.251488 -330.07199)
			(xy 240.315284 -330.076003) (xy 240.378074 -330.087981) (xy 240.438867 -330.107734) (xy 240.496706 -330.134951)
			(xy 240.550677 -330.169202) (xy 240.59993 -330.209947) (xy 240.616179 -330.227251) (xy 244.982978 -330.227251)
			(xy 244.982978 -330.172749) (xy 244.990734 -330.118801) (xy 245.006089 -330.066506) (xy 245.028731 -330.016929)
			(xy 245.058197 -329.971079) (xy 245.093888 -329.929888) (xy 245.135079 -329.894197) (xy 245.180929 -329.864731)
			(xy 245.230506 -329.842089) (xy 245.282801 -329.826734) (xy 245.336749 -329.818978) (xy 245.364 -329.818492)
			(xy 245.39137 -329.81896) (xy 245.445549 -329.826778) (xy 245.498052 -329.842266) (xy 245.547799 -329.865108)
			(xy 245.593766 -329.894831) (xy 245.614698 -329.912472) (xy 245.62181 -329.918568) (xy 245.638828 -329.924918)
			(xy 245.724172 -329.924918) (xy 245.74119 -329.918568) (xy 245.748302 -329.912472) (xy 245.769235 -329.894831)
			(xy 245.815203 -329.865107) (xy 245.864949 -329.842261) (xy 245.917451 -329.826765) (xy 245.971629 -329.818936)
			(xy 246.026371 -329.818936) (xy 246.080549 -329.826765) (xy 246.133051 -329.842261) (xy 246.182797 -329.865107)
			(xy 246.228765 -329.894831) (xy 246.249698 -329.912472) (xy 246.25681 -329.918568) (xy 246.273828 -329.924918)
			(xy 246.359172 -329.924918) (xy 246.37619 -329.918568) (xy 246.383302 -329.912472) (xy 246.404219 -329.894814)
			(xy 246.450196 -329.865106) (xy 246.499948 -329.842274) (xy 246.552452 -329.826787) (xy 246.60663 -329.818964)
			(xy 246.634 -329.818492) (xy 246.661251 -329.818978) (xy 246.715199 -329.826734) (xy 246.767494 -329.842089)
			(xy 246.817071 -329.864731) (xy 246.862921 -329.894197) (xy 246.904112 -329.929888) (xy 246.939803 -329.971079)
			(xy 246.969269 -330.016929) (xy 246.991911 -330.066506) (xy 247.007266 -330.118801) (xy 247.015022 -330.172749)
			(xy 247.015022 -330.227251) (xy 247.007266 -330.281199) (xy 246.991911 -330.333494) (xy 246.969269 -330.383071)
			(xy 246.939803 -330.428921) (xy 246.904112 -330.470112) (xy 246.862921 -330.505803) (xy 246.817071 -330.535269)
			(xy 246.767494 -330.557911) (xy 246.715199 -330.573266) (xy 246.661404 -330.581) (xy 256.005076 -330.581)
			(xy 256.005578 -330.549039) (xy 256.013589 -330.485621) (xy 256.029486 -330.423707) (xy 256.053018 -330.364274)
			(xy 256.083812 -330.308259) (xy 256.121385 -330.256544) (xy 256.165142 -330.209947) (xy 256.214395 -330.169202)
			(xy 256.268366 -330.134951) (xy 256.326205 -330.107734) (xy 256.386998 -330.087981) (xy 256.449788 -330.076003)
			(xy 256.513584 -330.07199) (xy 256.57738 -330.076003) (xy 256.64017 -330.087981) (xy 256.700963 -330.107734)
			(xy 256.758802 -330.134951) (xy 256.812773 -330.169202) (xy 256.862026 -330.209947) (xy 256.905783 -330.256544)
			(xy 256.943356 -330.308259) (xy 256.97415 -330.364274) (xy 256.997682 -330.423707) (xy 257.013579 -330.485621)
			(xy 257.02159 -330.549039) (xy 257.022092 -330.581) (xy 257.021583 -330.612204) (xy 257.013931 -330.674141)
			(xy 256.998755 -330.734676) (xy 256.976282 -330.792898) (xy 256.946851 -330.847931) (xy 256.910905 -330.898947)
			(xy 256.868983 -330.945179) (xy 256.821718 -330.985931) (xy 256.810081 -330.993961) (xy 257.555994 -330.993961)
			(xy 257.555994 -330.930039) (xy 257.564005 -330.866621) (xy 257.579902 -330.804707) (xy 257.603434 -330.745274)
			(xy 257.634228 -330.689259) (xy 257.671801 -330.637544) (xy 257.715558 -330.590947) (xy 257.764811 -330.550202)
			(xy 257.818782 -330.515951) (xy 257.876621 -330.488734) (xy 257.937414 -330.468981) (xy 258.000204 -330.457003)
			(xy 258.064 -330.45299) (xy 258.127796 -330.457003) (xy 258.190586 -330.468981) (xy 258.251379 -330.488734)
			(xy 258.309218 -330.515951) (xy 258.363189 -330.550202) (xy 258.412442 -330.590947) (xy 258.456199 -330.637544)
			(xy 258.493772 -330.689259) (xy 258.524566 -330.745274) (xy 258.548098 -330.804707) (xy 258.563995 -330.866621)
			(xy 258.572006 -330.930039) (xy 258.572508 -330.962) (xy 258.572006 -330.993961) (xy 258.563995 -331.057379)
			(xy 258.548098 -331.119293) (xy 258.524566 -331.178726) (xy 258.493772 -331.234741) (xy 258.456199 -331.286456)
			(xy 258.412442 -331.333053) (xy 258.363189 -331.373798) (xy 258.309218 -331.408049) (xy 258.251379 -331.435266)
			(xy 258.190586 -331.455019) (xy 258.127796 -331.466997) (xy 258.064 -331.471011) (xy 258.000204 -331.466997)
			(xy 257.937414 -331.455019) (xy 257.876621 -331.435266) (xy 257.818782 -331.408049) (xy 257.764811 -331.373798)
			(xy 257.715558 -331.333053) (xy 257.671801 -331.286456) (xy 257.634228 -331.234741) (xy 257.603434 -331.178726)
			(xy 257.579902 -331.119293) (xy 257.564005 -331.057379) (xy 257.555994 -330.993961) (xy 256.810081 -330.993961)
			(xy 256.796032 -331.003656) (xy 256.785364 -331.011022) (xy 256.773426 -331.03312) (xy 256.77368 -331.14361)
			(xy 256.785618 -331.165708) (xy 256.79654 -331.173074) (xy 256.825068 -331.192646) (xy 256.877067 -331.23828)
			(xy 256.92239 -331.290551) (xy 256.960196 -331.348491) (xy 256.989786 -331.411027) (xy 257.000756 -331.443838)
			(xy 257.004058 -331.454506) (xy 257.018536 -331.470508) (xy 257.10896 -331.510132) (xy 257.13055 -331.509878)
			(xy 257.14071 -331.505306) (xy 257.166079 -331.493999) (xy 257.219277 -331.478044) (xy 257.27423 -331.469989)
			(xy 257.302 -331.469492) (xy 257.329251 -331.469978) (xy 257.383199 -331.477734) (xy 257.435494 -331.493089)
			(xy 257.485071 -331.515731) (xy 257.530921 -331.545197) (xy 257.572112 -331.580888) (xy 257.607803 -331.622079)
			(xy 257.637269 -331.667929) (xy 257.659911 -331.717506) (xy 257.675266 -331.769801) (xy 257.683022 -331.823749)
			(xy 257.683022 -331.878251) (xy 257.675266 -331.932199) (xy 257.659911 -331.984494) (xy 257.637269 -332.034071)
			(xy 257.607803 -332.079921) (xy 257.572112 -332.121112) (xy 257.530921 -332.156803) (xy 257.485071 -332.186269)
			(xy 257.435494 -332.208911) (xy 257.383199 -332.224266) (xy 257.329251 -332.232022) (xy 257.302 -332.232508)
			(xy 257.273045 -332.231997) (xy 257.215802 -332.223237) (xy 257.160538 -332.205934) (xy 257.108521 -332.180485)
			(xy 257.060942 -332.147473) (xy 257.018894 -332.107655) (xy 256.983341 -332.061944) (xy 256.968752 -332.036928)
			(xy 256.963418 -332.027276) (xy 256.945892 -332.014322) (xy 256.849626 -331.993748) (xy 256.82829 -331.99832)
			(xy 256.8194 -332.004924) (xy 256.793003 -332.023959) (xy 256.736265 -332.055838) (xy 256.675921 -332.080214)
			(xy 256.61296 -332.096689) (xy 256.548411 -332.104992) (xy 256.51587 -332.105508) (xy 256.485138 -332.105072)
			(xy 256.424124 -332.09766) (xy 256.364447 -332.082948) (xy 256.306979 -332.06115) (xy 256.252557 -332.032585)
			(xy 256.201975 -331.997668) (xy 256.15597 -331.956909) (xy 256.115214 -331.910901) (xy 256.0803 -331.860317)
			(xy 256.051737 -331.805894) (xy 256.029943 -331.748424) (xy 256.015234 -331.688747) (xy 256.007826 -331.627732)
			(xy 256.007362 -331.597) (xy 256.007847 -331.565795) (xy 256.0155 -331.503856) (xy 256.030678 -331.443319)
			(xy 256.053153 -331.385097) (xy 256.082588 -331.330063) (xy 256.118538 -331.279048) (xy 256.160464 -331.232817)
			(xy 256.207734 -331.192067) (xy 256.233422 -331.174344) (xy 256.24409 -331.166978) (xy 256.256028 -331.14488)
			(xy 256.255774 -331.03439) (xy 256.243836 -331.012292) (xy 256.232914 -331.004926) (xy 256.207024 -330.987249)
			(xy 256.159392 -330.94649) (xy 256.117133 -330.900182) (xy 256.08089 -330.849029) (xy 256.051213 -330.793808)
			(xy 256.028551 -330.735356) (xy 256.013249 -330.674561) (xy 256.00554 -330.612346) (xy 256.005076 -330.581)
			(xy 246.661404 -330.581) (xy 246.661251 -330.581022) (xy 246.634 -330.581508) (xy 246.60663 -330.58104)
			(xy 246.552451 -330.573222) (xy 246.499948 -330.557734) (xy 246.450201 -330.534892) (xy 246.404234 -330.505169)
			(xy 246.383302 -330.487528) (xy 246.37619 -330.481432) (xy 246.359172 -330.475082) (xy 246.273828 -330.475082)
			(xy 246.25681 -330.481432) (xy 246.249698 -330.487528) (xy 246.228765 -330.505169) (xy 246.182797 -330.534893)
			(xy 246.133051 -330.557739) (xy 246.080549 -330.573235) (xy 246.026371 -330.581064) (xy 245.971629 -330.581064)
			(xy 245.917451 -330.573235) (xy 245.864949 -330.557739) (xy 245.815203 -330.534893) (xy 245.769235 -330.505169)
			(xy 245.748302 -330.487528) (xy 245.74119 -330.481432) (xy 245.724172 -330.475082) (xy 245.638828 -330.475082)
			(xy 245.62181 -330.481432) (xy 245.614698 -330.487528) (xy 245.593781 -330.505186) (xy 245.547804 -330.534894)
			(xy 245.498052 -330.557726) (xy 245.445548 -330.573213) (xy 245.39137 -330.581036) (xy 245.364 -330.581508)
			(xy 245.336749 -330.581022) (xy 245.282801 -330.573266) (xy 245.230506 -330.557911) (xy 245.180929 -330.535269)
			(xy 245.135079 -330.505803) (xy 245.093888 -330.470112) (xy 245.058197 -330.428921) (xy 245.028731 -330.383071)
			(xy 245.006089 -330.333494) (xy 244.990734 -330.281199) (xy 244.982978 -330.227251) (xy 240.616179 -330.227251)
			(xy 240.643687 -330.256544) (xy 240.68126 -330.308259) (xy 240.712054 -330.364274) (xy 240.735586 -330.423707)
			(xy 240.751483 -330.485621) (xy 240.759494 -330.549039) (xy 240.759996 -330.581) (xy 240.759537 -330.611745)
			(xy 240.752113 -330.672784) (xy 240.737385 -330.732483) (xy 240.715568 -330.789972) (xy 240.686981 -330.844412)
			(xy 240.652039 -330.895009) (xy 240.63198 -330.918312) (xy 240.626194 -330.925464) (xy 240.619673 -330.942649)
			(xy 240.61928 -330.95184) (xy 240.61928 -330.982574) (xy 240.619707 -330.991759) (xy 240.62621 -331.008944)
			(xy 240.63198 -331.016102) (xy 240.652034 -331.039411) (xy 240.686989 -331.09) (xy 240.715586 -331.144437)
			(xy 240.737407 -331.201925) (xy 240.752134 -331.261627) (xy 240.75955 -331.322669) (xy 240.759996 -331.353414)
			(xy 240.759494 -331.385375) (xy 240.751483 -331.448793) (xy 240.735586 -331.510707) (xy 240.712054 -331.57014)
			(xy 240.68126 -331.626155) (xy 240.643687 -331.67787) (xy 240.59993 -331.724467) (xy 240.550677 -331.765212)
			(xy 240.496706 -331.799463) (xy 240.438867 -331.82668) (xy 240.378074 -331.846433) (xy 240.315284 -331.858411)
			(xy 240.251488 -331.862425) (xy 240.187692 -331.858411) (xy 240.124902 -331.846433) (xy 240.064109 -331.82668)
			(xy 240.00627 -331.799463) (xy 239.952299 -331.765212) (xy 239.903046 -331.724467) (xy 239.859289 -331.67787)
			(xy 239.821716 -331.626155) (xy 239.790922 -331.57014) (xy 239.76739 -331.510707) (xy 239.751493 -331.448793)
			(xy 239.743482 -331.385375) (xy 239.74298 -331.353414) (xy 238.633322 -331.353414) (xy 238.633022 -331.370251)
			(xy 238.625266 -331.424199) (xy 238.609911 -331.476494) (xy 238.587269 -331.526071) (xy 238.557803 -331.571921)
			(xy 238.522112 -331.613112) (xy 238.480921 -331.648803) (xy 238.435071 -331.678269) (xy 238.385494 -331.700911)
			(xy 238.333199 -331.716266) (xy 238.279251 -331.724022) (xy 238.224749 -331.724022) (xy 238.170801 -331.716266)
			(xy 238.118506 -331.700911) (xy 238.068929 -331.678269) (xy 238.023079 -331.648803) (xy 237.981888 -331.613112)
			(xy 237.946197 -331.571921) (xy 237.916731 -331.526071) (xy 237.894089 -331.476494) (xy 237.878734 -331.424199)
			(xy 237.870978 -331.370251) (xy 237.870492 -331.343) (xy 235.159108 -331.343) (xy 235.177861 -331.359124)
			(xy 235.219932 -331.405411) (xy 235.25601 -331.456508) (xy 235.28555 -331.511642) (xy 235.308108 -331.569983)
			(xy 235.323343 -331.630649) (xy 235.331024 -331.692725) (xy 235.331508 -331.724) (xy 235.331006 -331.755961)
			(xy 235.322995 -331.819379) (xy 235.307098 -331.881293) (xy 235.283566 -331.940726) (xy 235.252772 -331.996741)
			(xy 235.215199 -332.048456) (xy 235.171442 -332.095053) (xy 235.122189 -332.135798) (xy 235.068218 -332.170049)
			(xy 235.010379 -332.197266) (xy 234.949586 -332.217019) (xy 234.886796 -332.228997) (xy 234.823 -332.233011)
			(xy 234.759204 -332.228997) (xy 234.696414 -332.217019) (xy 234.635621 -332.197266) (xy 234.577782 -332.170049)
			(xy 234.523811 -332.135798) (xy 234.474558 -332.095053) (xy 234.430801 -332.048456) (xy 234.393228 -331.996741)
			(xy 234.362434 -331.940726) (xy 234.338902 -331.881293) (xy 234.323005 -331.819379) (xy 234.314994 -331.755961)
			(xy 234.314492 -331.724) (xy 227.536248 -331.724) (xy 227.536248 -332.771961) (xy 231.266994 -332.771961)
			(xy 231.266994 -332.708039) (xy 231.275005 -332.644621) (xy 231.290902 -332.582707) (xy 231.314434 -332.523274)
			(xy 231.345228 -332.467259) (xy 231.382801 -332.415544) (xy 231.426558 -332.368947) (xy 231.475811 -332.328202)
			(xy 231.529782 -332.293951) (xy 231.587621 -332.266734) (xy 231.648414 -332.246981) (xy 231.711204 -332.235003)
			(xy 231.775 -332.23099) (xy 231.838796 -332.235003) (xy 231.901586 -332.246981) (xy 231.962379 -332.266734)
			(xy 232.020218 -332.293951) (xy 232.074189 -332.328202) (xy 232.123442 -332.368947) (xy 232.167199 -332.415544)
			(xy 232.204772 -332.467259) (xy 232.235566 -332.523274) (xy 232.259098 -332.582707) (xy 232.274995 -332.644621)
			(xy 232.283006 -332.708039) (xy 232.283508 -332.74) (xy 234.313982 -332.74) (xy 234.318053 -332.684378)
			(xy 234.330179 -332.629941) (xy 234.350102 -332.57785) (xy 234.377398 -332.529215) (xy 234.411484 -332.485072)
			(xy 234.451633 -332.446363) (xy 234.496991 -332.413912) (xy 234.546591 -332.388411) (xy 234.599375 -332.370404)
			(xy 234.654218 -332.360274) (xy 234.709952 -332.358237) (xy 234.765389 -332.364337) (xy 234.819346 -332.378443)
			(xy 234.870675 -332.400255) (xy 234.918281 -332.429309) (xy 234.961149 -332.464984) (xy 234.998366 -332.506521)
			(xy 235.029139 -332.553034) (xy 235.052811 -332.603531) (xy 235.05566 -332.613) (xy 237.869982 -332.613)
			(xy 237.874053 -332.557378) (xy 237.886179 -332.502941) (xy 237.906102 -332.45085) (xy 237.933398 -332.402215)
			(xy 237.967484 -332.358072) (xy 238.007633 -332.319363) (xy 238.052991 -332.286912) (xy 238.102591 -332.261411)
			(xy 238.155375 -332.243404) (xy 238.210218 -332.233274) (xy 238.265952 -332.231237) (xy 238.321389 -332.237337)
			(xy 238.375346 -332.251443) (xy 238.426675 -332.273255) (xy 238.474281 -332.302309) (xy 238.517149 -332.337984)
			(xy 238.554366 -332.379521) (xy 238.585139 -332.426034) (xy 238.608811 -332.476531) (xy 238.624879 -332.529938)
			(xy 238.632999 -332.585114) (xy 238.633508 -332.613) (xy 238.632999 -332.640886) (xy 238.632399 -332.644961)
			(xy 239.678712 -332.644961) (xy 239.678712 -332.581039) (xy 239.686723 -332.517621) (xy 239.70262 -332.455707)
			(xy 239.726152 -332.396274) (xy 239.756946 -332.340259) (xy 239.794519 -332.288544) (xy 239.838276 -332.241947)
			(xy 239.887529 -332.201202) (xy 239.9415 -332.166951) (xy 239.999339 -332.139734) (xy 240.060132 -332.119981)
			(xy 240.122922 -332.108003) (xy 240.186718 -332.10399) (xy 240.202774 -332.105) (xy 247.267982 -332.105)
			(xy 247.272053 -332.049378) (xy 247.284179 -331.994941) (xy 247.304102 -331.94285) (xy 247.331398 -331.894215)
			(xy 247.365484 -331.850072) (xy 247.405633 -331.811363) (xy 247.450991 -331.778912) (xy 247.500591 -331.753411)
			(xy 247.553375 -331.735404) (xy 247.608218 -331.725274) (xy 247.663952 -331.723237) (xy 247.719389 -331.729337)
			(xy 247.773346 -331.743443) (xy 247.824675 -331.765255) (xy 247.872281 -331.794309) (xy 247.915149 -331.829984)
			(xy 247.952366 -331.871521) (xy 247.983139 -331.918034) (xy 248.006811 -331.968531) (xy 248.022879 -332.021938)
			(xy 248.030999 -332.077114) (xy 248.031508 -332.105) (xy 248.030999 -332.132886) (xy 248.030399 -332.136961)
			(xy 248.919994 -332.136961) (xy 248.919994 -332.073039) (xy 248.928005 -332.009621) (xy 248.943902 -331.947707)
			(xy 248.967434 -331.888274) (xy 248.998228 -331.832259) (xy 249.035801 -331.780544) (xy 249.079558 -331.733947)
			(xy 249.128811 -331.693202) (xy 249.182782 -331.658951) (xy 249.240621 -331.631734) (xy 249.301414 -331.611981)
			(xy 249.364204 -331.600003) (xy 249.428 -331.59599) (xy 249.491796 -331.600003) (xy 249.554586 -331.611981)
			(xy 249.615379 -331.631734) (xy 249.673218 -331.658951) (xy 249.727189 -331.693202) (xy 249.776442 -331.733947)
			(xy 249.820199 -331.780544) (xy 249.857772 -331.832259) (xy 249.888566 -331.888274) (xy 249.912098 -331.947707)
			(xy 249.927995 -332.009621) (xy 249.936006 -332.073039) (xy 249.936508 -332.105) (xy 249.936006 -332.136961)
			(xy 249.927995 -332.200379) (xy 249.912098 -332.262293) (xy 249.888566 -332.321726) (xy 249.857772 -332.377741)
			(xy 249.820199 -332.429456) (xy 249.776442 -332.476053) (xy 249.727189 -332.516798) (xy 249.673218 -332.551049)
			(xy 249.615379 -332.578266) (xy 249.554586 -332.598019) (xy 249.491796 -332.609997) (xy 249.428 -332.614011)
			(xy 249.364204 -332.609997) (xy 249.301414 -332.598019) (xy 249.240621 -332.578266) (xy 249.182782 -332.551049)
			(xy 249.128811 -332.516798) (xy 249.079558 -332.476053) (xy 249.035801 -332.429456) (xy 248.998228 -332.377741)
			(xy 248.967434 -332.321726) (xy 248.943902 -332.262293) (xy 248.928005 -332.200379) (xy 248.919994 -332.136961)
			(xy 248.030399 -332.136961) (xy 248.022879 -332.188062) (xy 248.006811 -332.241469) (xy 247.983139 -332.291966)
			(xy 247.952366 -332.338479) (xy 247.915149 -332.380016) (xy 247.872281 -332.415691) (xy 247.824675 -332.444745)
			(xy 247.773346 -332.466557) (xy 247.719389 -332.480663) (xy 247.663952 -332.486763) (xy 247.608218 -332.484726)
			(xy 247.553375 -332.474596) (xy 247.500591 -332.456589) (xy 247.450991 -332.431088) (xy 247.405633 -332.398637)
			(xy 247.365484 -332.359928) (xy 247.331398 -332.315785) (xy 247.304102 -332.26715) (xy 247.284179 -332.215059)
			(xy 247.272053 -332.160622) (xy 247.267982 -332.105) (xy 240.202774 -332.105) (xy 240.250514 -332.108003)
			(xy 240.313304 -332.119981) (xy 240.374097 -332.139734) (xy 240.431936 -332.166951) (xy 240.485907 -332.201202)
			(xy 240.53516 -332.241947) (xy 240.578917 -332.288544) (xy 240.61649 -332.340259) (xy 240.647284 -332.396274)
			(xy 240.670816 -332.455707) (xy 240.686713 -332.517621) (xy 240.694724 -332.581039) (xy 240.695226 -332.613)
			(xy 240.694724 -332.644961) (xy 240.686713 -332.708379) (xy 240.670816 -332.770293) (xy 240.647284 -332.829726)
			(xy 240.61649 -332.885741) (xy 240.578917 -332.937456) (xy 240.53516 -332.984053) (xy 240.485907 -333.024798)
			(xy 240.431936 -333.059049) (xy 240.374097 -333.086266) (xy 240.313304 -333.106019) (xy 240.250514 -333.117997)
			(xy 240.186718 -333.122011) (xy 240.122922 -333.117997) (xy 240.060132 -333.106019) (xy 239.999339 -333.086266)
			(xy 239.9415 -333.059049) (xy 239.887529 -333.024798) (xy 239.838276 -332.984053) (xy 239.794519 -332.937456)
			(xy 239.756946 -332.885741) (xy 239.726152 -332.829726) (xy 239.70262 -332.770293) (xy 239.686723 -332.708379)
			(xy 239.678712 -332.644961) (xy 238.632399 -332.644961) (xy 238.624879 -332.696062) (xy 238.608811 -332.749469)
			(xy 238.585139 -332.799966) (xy 238.554366 -332.846479) (xy 238.517149 -332.888016) (xy 238.474281 -332.923691)
			(xy 238.426675 -332.952745) (xy 238.375346 -332.974557) (xy 238.321389 -332.988663) (xy 238.265952 -332.994763)
			(xy 238.210218 -332.992726) (xy 238.155375 -332.982596) (xy 238.102591 -332.964589) (xy 238.052991 -332.939088)
			(xy 238.007633 -332.906637) (xy 237.967484 -332.867928) (xy 237.933398 -332.823785) (xy 237.906102 -332.77515)
			(xy 237.886179 -332.723059) (xy 237.874053 -332.668622) (xy 237.869982 -332.613) (xy 235.05566 -332.613)
			(xy 235.068879 -332.656938) (xy 235.076999 -332.712114) (xy 235.077508 -332.74) (xy 235.076999 -332.767886)
			(xy 235.068879 -332.823062) (xy 235.052811 -332.876469) (xy 235.029139 -332.926966) (xy 234.998366 -332.973479)
			(xy 234.961149 -333.015016) (xy 234.918281 -333.050691) (xy 234.870675 -333.079745) (xy 234.819346 -333.101557)
			(xy 234.765389 -333.115663) (xy 234.709952 -333.121763) (xy 234.654218 -333.119726) (xy 234.599375 -333.109596)
			(xy 234.546591 -333.091589) (xy 234.496991 -333.066088) (xy 234.451633 -333.033637) (xy 234.411484 -332.994928)
			(xy 234.377398 -332.950785) (xy 234.350102 -332.90215) (xy 234.330179 -332.850059) (xy 234.318053 -332.795622)
			(xy 234.313982 -332.74) (xy 232.283508 -332.74) (xy 232.283006 -332.771961) (xy 232.274995 -332.835379)
			(xy 232.259098 -332.897293) (xy 232.235566 -332.956726) (xy 232.204772 -333.012741) (xy 232.167199 -333.064456)
			(xy 232.123442 -333.111053) (xy 232.074189 -333.151798) (xy 232.020218 -333.186049) (xy 231.962379 -333.213266)
			(xy 231.901586 -333.233019) (xy 231.838796 -333.244997) (xy 231.775 -333.249011) (xy 231.711204 -333.244997)
			(xy 231.648414 -333.233019) (xy 231.587621 -333.213266) (xy 231.529782 -333.186049) (xy 231.475811 -333.151798)
			(xy 231.426558 -333.111053) (xy 231.382801 -333.064456) (xy 231.345228 -333.012741) (xy 231.314434 -332.956726)
			(xy 231.290902 -332.897293) (xy 231.275005 -332.835379) (xy 231.266994 -332.771961) (xy 227.536248 -332.771961)
			(xy 227.536248 -333.406961) (xy 232.663994 -333.406961) (xy 232.663994 -333.343039) (xy 232.672005 -333.279621)
			(xy 232.687902 -333.217707) (xy 232.711434 -333.158274) (xy 232.742228 -333.102259) (xy 232.779801 -333.050544)
			(xy 232.823558 -333.003947) (xy 232.872811 -332.963202) (xy 232.926782 -332.928951) (xy 232.984621 -332.901734)
			(xy 233.045414 -332.881981) (xy 233.108204 -332.870003) (xy 233.172 -332.86599) (xy 233.235796 -332.870003)
			(xy 233.298586 -332.881981) (xy 233.359379 -332.901734) (xy 233.417218 -332.928951) (xy 233.471189 -332.963202)
			(xy 233.520442 -333.003947) (xy 233.564199 -333.050544) (xy 233.601772 -333.102259) (xy 233.632566 -333.158274)
			(xy 233.656098 -333.217707) (xy 233.671995 -333.279621) (xy 233.680006 -333.343039) (xy 233.680508 -333.375)
			(xy 233.680006 -333.406961) (xy 233.671995 -333.470379) (xy 233.656098 -333.532293) (xy 233.632566 -333.591726)
			(xy 233.601772 -333.647741) (xy 233.564199 -333.699456) (xy 233.520442 -333.746053) (xy 233.471189 -333.786798)
			(xy 233.417218 -333.821049) (xy 233.359379 -333.848266) (xy 233.298586 -333.868019) (xy 233.235796 -333.879997)
			(xy 233.172 -333.884011) (xy 233.108204 -333.879997) (xy 233.045414 -333.868019) (xy 232.984621 -333.848266)
			(xy 232.926782 -333.821049) (xy 232.872811 -333.786798) (xy 232.823558 -333.746053) (xy 232.779801 -333.699456)
			(xy 232.742228 -333.647741) (xy 232.711434 -333.591726) (xy 232.687902 -333.532293) (xy 232.672005 -333.470379)
			(xy 232.663994 -333.406961) (xy 227.536248 -333.406961) (xy 227.536248 -334.099408) (xy 234.558078 -334.099408)
			(xy 234.55858 -334.067447) (xy 234.566591 -334.004029) (xy 234.582488 -333.942115) (xy 234.60602 -333.882682)
			(xy 234.636814 -333.826667) (xy 234.674387 -333.774952) (xy 234.718144 -333.728355) (xy 234.767397 -333.68761)
			(xy 234.821368 -333.653359) (xy 234.879207 -333.626142) (xy 234.94 -333.606389) (xy 235.00279 -333.594411)
			(xy 235.066586 -333.590398) (xy 235.130382 -333.594411) (xy 235.193172 -333.606389) (xy 235.253965 -333.626142)
			(xy 235.311804 -333.653359) (xy 235.365775 -333.68761) (xy 235.415028 -333.728355) (xy 235.458785 -333.774952)
			(xy 235.496358 -333.826667) (xy 235.527152 -333.882682) (xy 235.550684 -333.942115) (xy 235.566581 -334.004029)
			(xy 235.574592 -334.067447) (xy 235.575094 -334.099408) (xy 235.573824 -334.133952) (xy 235.573316 -334.14462)
			(xy 235.580174 -334.164432) (xy 235.64596 -334.234282) (xy 235.665264 -334.24241) (xy 235.678726 -334.24241)
			(xy 235.705979 -334.242854) (xy 235.711722 -334.24368) (xy 236.610906 -334.24368) (xy 236.611449 -334.214834)
			(xy 236.620125 -334.157797) (xy 236.63729 -334.102718) (xy 236.662554 -334.050851) (xy 236.69534 -334.003379)
			(xy 236.7349 -333.961387) (xy 236.780332 -333.925829) (xy 236.830601 -333.897519) (xy 236.88456 -333.877101)
			(xy 236.912658 -333.870554) (xy 236.922056 -333.868522) (xy 236.937804 -333.858108) (xy 236.988858 -333.786734)
			(xy 236.99343 -333.768446) (xy 236.992414 -333.759048) (xy 236.990644 -333.743679) (xy 236.988738 -333.712796)
			(xy 236.988604 -333.697326) (xy 236.989106 -333.665365) (xy 236.997117 -333.601947) (xy 237.013014 -333.540033)
			(xy 237.036546 -333.4806) (xy 237.06734 -333.424585) (xy 237.104913 -333.37287) (xy 237.14867 -333.326273)
			(xy 237.197923 -333.285528) (xy 237.251894 -333.251277) (xy 237.309733 -333.22406) (xy 237.370526 -333.204307)
			(xy 237.433316 -333.192329) (xy 237.497112 -333.188316) (xy 237.560908 -333.192329) (xy 237.623698 -333.204307)
			(xy 237.684491 -333.22406) (xy 237.74233 -333.251277) (xy 237.796301 -333.285528) (xy 237.845554 -333.326273)
			(xy 237.889311 -333.37287) (xy 237.926884 -333.424585) (xy 237.957678 -333.4806) (xy 237.98121 -333.540033)
			(xy 237.997107 -333.601947) (xy 238.005118 -333.665365) (xy 238.00562 -333.697326) (xy 238.005168 -333.727441)
			(xy 237.998054 -333.78725) (xy 237.983928 -333.845801) (xy 237.962988 -333.902275) (xy 237.956489 -333.914961)
			(xy 240.195094 -333.914961) (xy 240.195094 -333.851039) (xy 240.203105 -333.787621) (xy 240.219002 -333.725707)
			(xy 240.242534 -333.666274) (xy 240.273328 -333.610259) (xy 240.310901 -333.558544) (xy 240.354658 -333.511947)
			(xy 240.403911 -333.471202) (xy 240.457882 -333.436951) (xy 240.515721 -333.409734) (xy 240.576514 -333.389981)
			(xy 240.639304 -333.378003) (xy 240.7031 -333.37399) (xy 240.766896 -333.378003) (xy 240.829686 -333.389981)
			(xy 240.890479 -333.409734) (xy 240.915353 -333.421439) (xy 246.483626 -333.421439) (xy 246.483626 -333.357517)
			(xy 246.491637 -333.294099) (xy 246.507534 -333.232185) (xy 246.531066 -333.172752) (xy 246.56186 -333.116737)
			(xy 246.599433 -333.065022) (xy 246.64319 -333.018425) (xy 246.692443 -332.97768) (xy 246.746414 -332.943429)
			(xy 246.804253 -332.916212) (xy 246.865046 -332.896459) (xy 246.927836 -332.884481) (xy 246.991632 -332.880468)
			(xy 247.055428 -332.884481) (xy 247.118218 -332.896459) (xy 247.125918 -332.898961) (xy 253.326894 -332.898961)
			(xy 253.326894 -332.835039) (xy 253.334905 -332.771621) (xy 253.350802 -332.709707) (xy 253.374334 -332.650274)
			(xy 253.405128 -332.594259) (xy 253.442701 -332.542544) (xy 253.486458 -332.495947) (xy 253.535711 -332.455202)
			(xy 253.589682 -332.420951) (xy 253.647521 -332.393734) (xy 253.708314 -332.373981) (xy 253.771104 -332.362003)
			(xy 253.8349 -332.35799) (xy 253.898696 -332.362003) (xy 253.961486 -332.373981) (xy 254.022279 -332.393734)
			(xy 254.080118 -332.420951) (xy 254.134089 -332.455202) (xy 254.183342 -332.495947) (xy 254.227099 -332.542544)
			(xy 254.264672 -332.594259) (xy 254.295466 -332.650274) (xy 254.318998 -332.709707) (xy 254.334895 -332.771621)
			(xy 254.342906 -332.835039) (xy 254.343408 -332.867) (xy 256.323082 -332.867) (xy 256.327153 -332.811378)
			(xy 256.339279 -332.756941) (xy 256.359202 -332.70485) (xy 256.386498 -332.656215) (xy 256.420584 -332.612072)
			(xy 256.460733 -332.573363) (xy 256.506091 -332.540912) (xy 256.555691 -332.515411) (xy 256.608475 -332.497404)
			(xy 256.663318 -332.487274) (xy 256.719052 -332.485237) (xy 256.774489 -332.491337) (xy 256.828446 -332.505443)
			(xy 256.879775 -332.527255) (xy 256.927381 -332.556309) (xy 256.970249 -332.591984) (xy 257.007466 -332.633521)
			(xy 257.038239 -332.680034) (xy 257.061911 -332.730531) (xy 257.077979 -332.783938) (xy 257.086099 -332.839114)
			(xy 257.086608 -332.867) (xy 257.086099 -332.894886) (xy 257.077979 -332.950062) (xy 257.061911 -333.003469)
			(xy 257.038239 -333.053966) (xy 257.007466 -333.100479) (xy 256.970249 -333.142016) (xy 256.927381 -333.177691)
			(xy 256.879775 -333.206745) (xy 256.828446 -333.228557) (xy 256.774489 -333.242663) (xy 256.719052 -333.248763)
			(xy 256.663318 -333.246726) (xy 256.608475 -333.236596) (xy 256.555691 -333.218589) (xy 256.506091 -333.193088)
			(xy 256.460733 -333.160637) (xy 256.420584 -333.121928) (xy 256.386498 -333.077785) (xy 256.359202 -333.02915)
			(xy 256.339279 -332.977059) (xy 256.327153 -332.922622) (xy 256.323082 -332.867) (xy 254.343408 -332.867)
			(xy 254.342906 -332.898961) (xy 254.334895 -332.962379) (xy 254.318998 -333.024293) (xy 254.295466 -333.083726)
			(xy 254.264672 -333.139741) (xy 254.227099 -333.191456) (xy 254.183342 -333.238053) (xy 254.134089 -333.278798)
			(xy 254.080118 -333.313049) (xy 254.022279 -333.340266) (xy 253.961486 -333.360019) (xy 253.898696 -333.371997)
			(xy 253.8349 -333.376011) (xy 253.771104 -333.371997) (xy 253.708314 -333.360019) (xy 253.647521 -333.340266)
			(xy 253.589682 -333.313049) (xy 253.535711 -333.278798) (xy 253.486458 -333.238053) (xy 253.442701 -333.191456)
			(xy 253.405128 -333.139741) (xy 253.374334 -333.083726) (xy 253.350802 -333.024293) (xy 253.334905 -332.962379)
			(xy 253.326894 -332.898961) (xy 247.125918 -332.898961) (xy 247.179011 -332.916212) (xy 247.23685 -332.943429)
			(xy 247.290821 -332.97768) (xy 247.340074 -333.018425) (xy 247.383831 -333.065022) (xy 247.421404 -333.116737)
			(xy 247.452198 -333.172752) (xy 247.47573 -333.232185) (xy 247.491627 -333.294099) (xy 247.499638 -333.357517)
			(xy 247.50014 -333.389478) (xy 247.499638 -333.421439) (xy 247.491627 -333.484857) (xy 247.47573 -333.546771)
			(xy 247.452198 -333.606204) (xy 247.421404 -333.662219) (xy 247.383831 -333.713934) (xy 247.340074 -333.760531)
			(xy 247.290821 -333.801276) (xy 247.23685 -333.835527) (xy 247.179011 -333.862744) (xy 247.118218 -333.882497)
			(xy 247.055428 -333.894475) (xy 246.991632 -333.898489) (xy 246.927836 -333.894475) (xy 246.865046 -333.882497)
			(xy 246.804253 -333.862744) (xy 246.746414 -333.835527) (xy 246.692443 -333.801276) (xy 246.64319 -333.760531)
			(xy 246.599433 -333.713934) (xy 246.56186 -333.662219) (xy 246.531066 -333.606204) (xy 246.507534 -333.546771)
			(xy 246.491637 -333.484857) (xy 246.483626 -333.421439) (xy 240.915353 -333.421439) (xy 240.948318 -333.436951)
			(xy 241.002289 -333.471202) (xy 241.051542 -333.511947) (xy 241.095299 -333.558544) (xy 241.132872 -333.610259)
			(xy 241.163666 -333.666274) (xy 241.187198 -333.725707) (xy 241.203095 -333.787621) (xy 241.211106 -333.851039)
			(xy 241.211608 -333.883) (xy 241.211106 -333.914961) (xy 241.203095 -333.978379) (xy 241.187198 -334.040293)
			(xy 241.186538 -334.041961) (xy 253.326894 -334.041961) (xy 253.326894 -333.978039) (xy 253.334905 -333.914621)
			(xy 253.350802 -333.852707) (xy 253.374334 -333.793274) (xy 253.405128 -333.737259) (xy 253.442701 -333.685544)
			(xy 253.486458 -333.638947) (xy 253.535711 -333.598202) (xy 253.589682 -333.563951) (xy 253.647521 -333.536734)
			(xy 253.708314 -333.516981) (xy 253.771104 -333.505003) (xy 253.8349 -333.50099) (xy 253.898696 -333.505003)
			(xy 253.961486 -333.516981) (xy 254.022279 -333.536734) (xy 254.080118 -333.563951) (xy 254.134089 -333.598202)
			(xy 254.183342 -333.638947) (xy 254.227099 -333.685544) (xy 254.264672 -333.737259) (xy 254.295466 -333.793274)
			(xy 254.318998 -333.852707) (xy 254.334895 -333.914621) (xy 254.342906 -333.978039) (xy 254.343408 -334.01)
			(xy 254.342906 -334.041961) (xy 254.334895 -334.105379) (xy 254.318998 -334.167293) (xy 254.295466 -334.226726)
			(xy 254.264672 -334.282741) (xy 254.227099 -334.334456) (xy 254.183342 -334.381053) (xy 254.134089 -334.421798)
			(xy 254.080118 -334.456049) (xy 254.022279 -334.483266) (xy 253.961486 -334.503019) (xy 253.898696 -334.514997)
			(xy 253.8349 -334.519011) (xy 253.771104 -334.514997) (xy 253.708314 -334.503019) (xy 253.647521 -334.483266)
			(xy 253.589682 -334.456049) (xy 253.535711 -334.421798) (xy 253.486458 -334.381053) (xy 253.442701 -334.334456)
			(xy 253.405128 -334.282741) (xy 253.374334 -334.226726) (xy 253.350802 -334.167293) (xy 253.334905 -334.105379)
			(xy 253.326894 -334.041961) (xy 241.186538 -334.041961) (xy 241.163666 -334.099726) (xy 241.132872 -334.155741)
			(xy 241.095299 -334.207456) (xy 241.051542 -334.254053) (xy 241.002289 -334.294798) (xy 240.948318 -334.329049)
			(xy 240.890479 -334.356266) (xy 240.829686 -334.376019) (xy 240.766896 -334.387997) (xy 240.7031 -334.392011)
			(xy 240.639304 -334.387997) (xy 240.576514 -334.376019) (xy 240.515721 -334.356266) (xy 240.457882 -334.329049)
			(xy 240.403911 -334.294798) (xy 240.354658 -334.254053) (xy 240.310901 -334.207456) (xy 240.273328 -334.155741)
			(xy 240.242534 -334.099726) (xy 240.219002 -334.040293) (xy 240.203105 -333.978379) (xy 240.195094 -333.914961)
			(xy 237.956489 -333.914961) (xy 237.935527 -333.955882) (xy 237.90193 -334.005871) (xy 237.862665 -334.051544)
			(xy 237.840774 -334.07223) (xy 237.832138 -334.080104) (xy 237.823502 -334.10144) (xy 237.831122 -334.204564)
			(xy 237.842552 -334.224376) (xy 237.852204 -334.23098) (xy 237.877525 -334.248772) (xy 237.924097 -334.289528)
			(xy 237.965378 -334.335636) (xy 238.000756 -334.386413) (xy 238.029709 -334.44111) (xy 238.051809 -334.498916)
			(xy 238.066728 -334.558978) (xy 238.074246 -334.620407) (xy 238.074708 -334.65135) (xy 238.074291 -334.682082)
			(xy 238.066877 -334.743098) (xy 238.052163 -334.802774) (xy 238.030363 -334.860243) (xy 238.001795 -334.914665)
			(xy 237.966877 -334.965247) (xy 237.926116 -335.011251) (xy 237.880107 -335.052008) (xy 237.871482 -335.057961)
			(xy 240.195094 -335.057961) (xy 240.195094 -334.994039) (xy 240.203105 -334.930621) (xy 240.219002 -334.868707)
			(xy 240.242534 -334.809274) (xy 240.273328 -334.753259) (xy 240.310901 -334.701544) (xy 240.354658 -334.654947)
			(xy 240.403911 -334.614202) (xy 240.457882 -334.579951) (xy 240.515721 -334.552734) (xy 240.576514 -334.532981)
			(xy 240.639304 -334.521003) (xy 240.7031 -334.51699) (xy 240.766896 -334.521003) (xy 240.829686 -334.532981)
			(xy 240.890479 -334.552734) (xy 240.948318 -334.579951) (xy 241.002289 -334.614202) (xy 241.051542 -334.654947)
			(xy 241.095299 -334.701544) (xy 241.132872 -334.753259) (xy 241.163666 -334.809274) (xy 241.187198 -334.868707)
			(xy 241.203095 -334.930621) (xy 241.211106 -334.994039) (xy 241.211608 -335.026) (xy 241.211106 -335.057961)
			(xy 241.203095 -335.121379) (xy 241.191987 -335.164641) (xy 253.326894 -335.164641) (xy 253.326894 -335.100719)
			(xy 253.334905 -335.037301) (xy 253.350802 -334.975387) (xy 253.374334 -334.915954) (xy 253.405128 -334.859939)
			(xy 253.442701 -334.808224) (xy 253.486458 -334.761627) (xy 253.535711 -334.720882) (xy 253.589682 -334.686631)
			(xy 253.647521 -334.659414) (xy 253.708314 -334.639661) (xy 253.771104 -334.627683) (xy 253.8349 -334.62367)
			(xy 253.898696 -334.627683) (xy 253.961486 -334.639661) (xy 254.022279 -334.659414) (xy 254.080118 -334.686631)
			(xy 254.134089 -334.720882) (xy 254.183342 -334.761627) (xy 254.227099 -334.808224) (xy 254.264672 -334.859939)
			(xy 254.295466 -334.915954) (xy 254.318998 -334.975387) (xy 254.334895 -335.037301) (xy 254.342906 -335.100719)
			(xy 254.343408 -335.13268) (xy 254.342906 -335.164641) (xy 254.334895 -335.228059) (xy 254.318998 -335.289973)
			(xy 254.295466 -335.349406) (xy 254.264672 -335.405421) (xy 254.227099 -335.457136) (xy 254.183342 -335.503733)
			(xy 254.134089 -335.544478) (xy 254.080118 -335.578729) (xy 254.022279 -335.605946) (xy 253.961486 -335.625699)
			(xy 253.898696 -335.637677) (xy 253.8349 -335.641691) (xy 253.771104 -335.637677) (xy 253.708314 -335.625699)
			(xy 253.647521 -335.605946) (xy 253.589682 -335.578729) (xy 253.535711 -335.544478) (xy 253.486458 -335.503733)
			(xy 253.442701 -335.457136) (xy 253.405128 -335.405421) (xy 253.374334 -335.349406) (xy 253.350802 -335.289973)
			(xy 253.334905 -335.228059) (xy 253.326894 -335.164641) (xy 241.191987 -335.164641) (xy 241.187198 -335.183293)
			(xy 241.163666 -335.242726) (xy 241.132872 -335.298741) (xy 241.095299 -335.350456) (xy 241.051542 -335.397053)
			(xy 241.002289 -335.437798) (xy 240.948318 -335.472049) (xy 240.890479 -335.499266) (xy 240.829686 -335.519019)
			(xy 240.766896 -335.530997) (xy 240.7031 -335.535011) (xy 240.639304 -335.530997) (xy 240.576514 -335.519019)
			(xy 240.515721 -335.499266) (xy 240.457882 -335.472049) (xy 240.403911 -335.437798) (xy 240.354658 -335.397053)
			(xy 240.310901 -335.350456) (xy 240.273328 -335.298741) (xy 240.242534 -335.242726) (xy 240.219002 -335.183293)
			(xy 240.203105 -335.121379) (xy 240.195094 -335.057961) (xy 237.871482 -335.057961) (xy 237.829522 -335.086921)
			(xy 237.775097 -335.115484) (xy 237.717627 -335.137278) (xy 237.657948 -335.151986) (xy 237.596932 -335.159394)
			(xy 237.5662 -335.159858) (xy 237.534637 -335.159433) (xy 237.472 -335.151597) (xy 237.410814 -335.136069)
			(xy 237.35202 -335.113089) (xy 237.296521 -335.08301) (xy 237.245172 -335.046295) (xy 237.198761 -335.003507)
			(xy 237.158001 -334.955304) (xy 237.12352 -334.902428) (xy 237.095847 -334.845691) (xy 237.075408 -334.785966)
			(xy 237.062517 -334.724171) (xy 237.05947 -334.692752) (xy 237.058192 -334.683388) (xy 237.049863 -334.666446)
			(xy 237.043214 -334.659732) (xy 237.020354 -334.63865) (xy 237.013254 -334.632693) (xy 236.996074 -334.625784)
			(xy 236.986826 -334.625188) (xy 236.959834 -334.624383) (xy 236.906492 -334.615975) (xy 236.854867 -334.600131)
			(xy 236.805991 -334.577168) (xy 236.760841 -334.547543) (xy 236.720319 -334.511849) (xy 236.685234 -334.470798)
			(xy 236.656286 -334.425211) (xy 236.634054 -334.375998) (xy 236.618983 -334.324143) (xy 236.611372 -334.270681)
			(xy 236.610906 -334.24368) (xy 235.711722 -334.24368) (xy 235.759929 -334.250614) (xy 235.812226 -334.265974)
			(xy 235.861804 -334.288619) (xy 235.907655 -334.31809) (xy 235.948846 -334.353786) (xy 235.984537 -334.39498)
			(xy 236.014002 -334.440835) (xy 236.036642 -334.490416) (xy 236.051995 -334.542714) (xy 236.059749 -334.596665)
			(xy 236.060234 -334.623918) (xy 236.059753 -334.651065) (xy 236.052054 -334.704811) (xy 236.036813 -334.756922)
			(xy 236.014338 -334.806347) (xy 235.985083 -334.852086) (xy 235.94964 -334.893216) (xy 235.908724 -334.928906)
			(xy 235.863162 -334.958435) (xy 235.813873 -334.981206) (xy 235.761854 -334.996761) (xy 235.708156 -335.004783)
			(xy 235.681012 -335.005426) (xy 235.671614 -335.005426) (xy 235.65485 -335.01203) (xy 235.590842 -335.068418)
			(xy 235.582206 -335.084166) (xy 235.580936 -335.093564) (xy 235.575966 -335.126432) (xy 235.558634 -335.190606)
			(xy 235.533086 -335.251974) (xy 235.499758 -335.309489) (xy 235.459218 -335.36217) (xy 235.412158 -335.409118)
			(xy 235.359381 -335.449532) (xy 235.301787 -335.482723) (xy 235.240359 -335.508125) (xy 235.176143 -335.525304)
			(xy 235.110237 -335.533967) (xy 235.077 -335.534508) (xy 235.046269 -335.534044) (xy 234.985255 -335.526635)
			(xy 234.925579 -335.511927) (xy 234.868111 -335.490132) (xy 234.813689 -335.461569) (xy 234.763107 -335.426655)
			(xy 234.717102 -335.385898) (xy 234.676345 -335.339893) (xy 234.641431 -335.289311) (xy 234.612868 -335.234889)
			(xy 234.591073 -335.177421) (xy 234.576365 -335.117745) (xy 234.568956 -335.056731) (xy 234.568492 -335.026)
			(xy 234.568997 -334.995064) (xy 234.576504 -334.933648) (xy 234.591406 -334.873597) (xy 234.613483 -334.815798)
			(xy 234.64241 -334.761104) (xy 234.677758 -334.710323) (xy 234.719006 -334.664206) (xy 234.741974 -334.643476)
			(xy 234.750356 -334.63611) (xy 234.759246 -334.616044) (xy 234.75823 -334.516476) (xy 234.748578 -334.49641)
			(xy 234.740196 -334.489298) (xy 234.716136 -334.468576) (xy 234.672892 -334.422074) (xy 234.635778 -334.370548)
			(xy 234.605371 -334.314801) (xy 234.582144 -334.2557) (xy 234.566459 -334.194167) (xy 234.558561 -334.131159)
			(xy 234.558078 -334.099408) (xy 227.536248 -334.099408) (xy 227.536248 -335.9658) (xy 231.731589 -335.9658)
			(xy 231.735603 -335.902005) (xy 231.74758 -335.839217) (xy 231.767332 -335.778425) (xy 231.794548 -335.720587)
			(xy 231.828798 -335.666617) (xy 231.869541 -335.617365) (xy 231.916137 -335.573607) (xy 231.967849 -335.536034)
			(xy 232.023862 -335.505239) (xy 232.083293 -335.481707) (xy 232.145205 -335.465808) (xy 232.208622 -335.457795)
			(xy 232.240582 -335.457292) (xy 232.271924 -335.457748) (xy 232.334132 -335.465459) (xy 232.394922 -335.480752)
			(xy 232.453373 -335.503397) (xy 232.508599 -335.533051) (xy 232.53446 -335.550764) (xy 232.544366 -335.557876)
			(xy 232.568242 -335.561432) (xy 232.668826 -335.528666) (xy 232.685844 -335.511648) (xy 232.689654 -335.500218)
			(xy 232.700129 -335.470222) (xy 232.727559 -335.412911) (xy 232.761918 -335.359465) (xy 232.80267 -335.310719)
			(xy 232.849179 -335.267431) (xy 232.900721 -335.230277) (xy 232.956492 -335.199836) (xy 233.015621 -335.176584)
			(xy 233.077188 -335.160882) (xy 233.140231 -335.152976) (xy 233.172 -335.152492) (xy 233.206492 -335.153055)
			(xy 233.274843 -335.162393) (xy 233.341304 -335.180883) (xy 233.404656 -335.208186) (xy 233.463736 -335.243802)
			(xy 233.51746 -335.287076) (xy 233.54157 -335.31175) (xy 233.54825 -335.318272) (xy 233.56507 -335.326341)
			(xy 233.574336 -335.327498) (xy 233.605324 -335.330038) (xy 233.614472 -335.330347) (xy 233.632044 -335.325276)
			(xy 233.639614 -335.320132) (xy 233.664485 -335.302408) (xy 233.71866 -335.274226) (xy 233.776631 -335.255026)
			(xy 233.836918 -335.245298) (xy 233.867452 -335.244694) (xy 233.894704 -335.2452) (xy 233.948653 -335.25295)
			(xy 234.00095 -335.2683) (xy 234.050531 -335.290938) (xy 234.096384 -335.320401) (xy 234.137577 -335.35609)
			(xy 234.173272 -335.397279) (xy 234.20274 -335.443129) (xy 234.225383 -335.492706) (xy 234.24074 -335.545002)
			(xy 234.248497 -335.59895) (xy 234.24896 -335.626202) (xy 234.248781 -335.64209) (xy 234.24611 -335.673754)
			(xy 234.243626 -335.689448) (xy 234.242102 -335.698846) (xy 234.245912 -335.717388) (xy 234.29341 -335.790794)
			(xy 234.30865 -335.80197) (xy 234.318048 -335.804256) (xy 234.350165 -335.81337) (xy 234.411912 -335.838748)
			(xy 234.469809 -335.871986) (xy 234.52286 -335.912512) (xy 234.570153 -335.959631) (xy 234.610875 -336.012533)
			(xy 234.641365 -336.065195) (xy 236.020034 -336.065195) (xy 236.022643 -336.002172) (xy 236.033028 -335.939956)
			(xy 236.051029 -335.879503) (xy 236.076369 -335.82174) (xy 236.108659 -335.767555) (xy 236.147403 -335.71778)
			(xy 236.192007 -335.673179) (xy 236.241784 -335.634439) (xy 236.295972 -335.602152) (xy 236.353736 -335.576816)
			(xy 236.414191 -335.55882) (xy 236.476408 -335.54844) (xy 236.539431 -335.545834) (xy 236.602292 -335.551045)
			(xy 236.664026 -335.56399) (xy 236.723684 -335.584472) (xy 236.780351 -335.612176) (xy 236.833157 -335.646677)
			(xy 236.881289 -335.687444) (xy 236.924009 -335.733851) (xy 236.960661 -335.785187) (xy 236.990682 -335.840661)
			(xy 237.01361 -335.899423) (xy 237.029094 -335.960569) (xy 237.036896 -336.023162) (xy 237.037372 -336.0547)
			(xy 237.036967 -336.084051) (xy 237.03022 -336.142364) (xy 237.02391 -336.171032) (xy 237.021116 -336.182462)
			(xy 237.025432 -336.200961) (xy 240.195094 -336.200961) (xy 240.195094 -336.137039) (xy 240.203105 -336.073621)
			(xy 240.219002 -336.011707) (xy 240.242534 -335.952274) (xy 240.273328 -335.896259) (xy 240.310901 -335.844544)
			(xy 240.354658 -335.797947) (xy 240.403911 -335.757202) (xy 240.457882 -335.722951) (xy 240.515721 -335.695734)
			(xy 240.576514 -335.675981) (xy 240.639304 -335.664003) (xy 240.7031 -335.65999) (xy 240.766896 -335.664003)
			(xy 240.829686 -335.675981) (xy 240.890479 -335.695734) (xy 240.948318 -335.722951) (xy 241.002289 -335.757202)
			(xy 241.051542 -335.797947) (xy 241.095299 -335.844544) (xy 241.132872 -335.896259) (xy 241.163666 -335.952274)
			(xy 241.187198 -336.011707) (xy 241.203095 -336.073621) (xy 241.211106 -336.137039) (xy 241.211608 -336.169)
			(xy 241.211106 -336.200961) (xy 241.203095 -336.264379) (xy 241.197204 -336.287321) (xy 253.326894 -336.287321)
			(xy 253.326894 -336.223399) (xy 253.334905 -336.159981) (xy 253.350802 -336.098067) (xy 253.374334 -336.038634)
			(xy 253.405128 -335.982619) (xy 253.442701 -335.930904) (xy 253.486458 -335.884307) (xy 253.535711 -335.843562)
			(xy 253.589682 -335.809311) (xy 253.647521 -335.782094) (xy 253.708314 -335.762341) (xy 253.771104 -335.750363)
			(xy 253.8349 -335.74635) (xy 253.898696 -335.750363) (xy 253.961486 -335.762341) (xy 254.022279 -335.782094)
			(xy 254.080118 -335.809311) (xy 254.134089 -335.843562) (xy 254.183342 -335.884307) (xy 254.227099 -335.930904)
			(xy 254.264672 -335.982619) (xy 254.295466 -336.038634) (xy 254.318998 -336.098067) (xy 254.334895 -336.159981)
			(xy 254.342906 -336.223399) (xy 254.343408 -336.25536) (xy 254.342906 -336.287321) (xy 254.334895 -336.350739)
			(xy 254.318998 -336.412653) (xy 254.295466 -336.472086) (xy 254.264672 -336.528101) (xy 254.227099 -336.579816)
			(xy 254.183342 -336.626413) (xy 254.134089 -336.667158) (xy 254.080118 -336.701409) (xy 254.022279 -336.728626)
			(xy 253.961486 -336.748379) (xy 253.898696 -336.760357) (xy 253.8349 -336.764371) (xy 253.771104 -336.760357)
			(xy 253.708314 -336.748379) (xy 253.647521 -336.728626) (xy 253.589682 -336.701409) (xy 253.535711 -336.667158)
			(xy 253.486458 -336.626413) (xy 253.442701 -336.579816) (xy 253.405128 -336.528101) (xy 253.374334 -336.472086)
			(xy 253.350802 -336.412653) (xy 253.334905 -336.350739) (xy 253.326894 -336.287321) (xy 241.197204 -336.287321)
			(xy 241.187198 -336.326293) (xy 241.163666 -336.385726) (xy 241.132872 -336.441741) (xy 241.095299 -336.493456)
			(xy 241.051542 -336.540053) (xy 241.002289 -336.580798) (xy 240.948318 -336.615049) (xy 240.890479 -336.642266)
			(xy 240.829686 -336.662019) (xy 240.766896 -336.673997) (xy 240.7031 -336.678011) (xy 240.639304 -336.673997)
			(xy 240.576514 -336.662019) (xy 240.515721 -336.642266) (xy 240.457882 -336.615049) (xy 240.403911 -336.580798)
			(xy 240.354658 -336.540053) (xy 240.310901 -336.493456) (xy 240.273328 -336.441741) (xy 240.242534 -336.385726)
			(xy 240.219002 -336.326293) (xy 240.203105 -336.264379) (xy 240.195094 -336.200961) (xy 237.025432 -336.200961)
			(xy 237.02645 -336.205322) (xy 237.091474 -336.286094) (xy 237.112556 -336.296) (xy 237.124494 -336.295746)
			(xy 237.130844 -336.295746) (xy 237.15809 -336.296327) (xy 237.212026 -336.304088) (xy 237.264309 -336.319445)
			(xy 237.313875 -336.342086) (xy 237.359714 -336.37155) (xy 237.400894 -336.407237) (xy 237.436577 -336.448421)
			(xy 237.466035 -336.494264) (xy 237.488671 -336.543832) (xy 237.504022 -336.596117) (xy 237.511776 -336.650054)
			(xy 237.511776 -336.704546) (xy 237.504022 -336.758483) (xy 237.488671 -336.810768) (xy 237.466035 -336.860336)
			(xy 237.436577 -336.906179) (xy 237.400894 -336.947363) (xy 237.359714 -336.98305) (xy 237.313875 -337.012514)
			(xy 237.264309 -337.035155) (xy 237.212026 -337.050512) (xy 237.15809 -337.058273) (xy 237.130844 -337.058762)
			(xy 237.109254 -337.058254) (xy 237.095538 -337.057492) (xy 237.071408 -337.06943) (xy 237.007908 -337.165696)
			(xy 237.006384 -337.192366) (xy 237.01248 -337.204812) (xy 237.025095 -337.231209) (xy 237.04486 -337.286276)
			(xy 237.058187 -337.343244) (xy 237.05827 -337.343961) (xy 240.195094 -337.343961) (xy 240.195094 -337.280039)
			(xy 240.203105 -337.216621) (xy 240.219002 -337.154707) (xy 240.242534 -337.095274) (xy 240.273328 -337.039259)
			(xy 240.310901 -336.987544) (xy 240.354658 -336.940947) (xy 240.403911 -336.900202) (xy 240.457882 -336.865951)
			(xy 240.515721 -336.838734) (xy 240.576514 -336.818981) (xy 240.639304 -336.807003) (xy 240.7031 -336.80299)
			(xy 240.766896 -336.807003) (xy 240.829686 -336.818981) (xy 240.890479 -336.838734) (xy 240.948318 -336.865951)
			(xy 241.002289 -336.900202) (xy 241.051542 -336.940947) (xy 241.095299 -336.987544) (xy 241.132872 -337.039259)
			(xy 241.163666 -337.095274) (xy 241.187198 -337.154707) (xy 241.203095 -337.216621) (xy 241.211106 -337.280039)
			(xy 241.211608 -337.312) (xy 241.211106 -337.343961) (xy 241.203095 -337.407379) (xy 241.202422 -337.410001)
			(xy 253.326894 -337.410001) (xy 253.326894 -337.346079) (xy 253.334905 -337.282661) (xy 253.350802 -337.220747)
			(xy 253.374334 -337.161314) (xy 253.405128 -337.105299) (xy 253.442701 -337.053584) (xy 253.486458 -337.006987)
			(xy 253.535711 -336.966242) (xy 253.589682 -336.931991) (xy 253.647521 -336.904774) (xy 253.708314 -336.885021)
			(xy 253.771104 -336.873043) (xy 253.8349 -336.86903) (xy 253.898696 -336.873043) (xy 253.961486 -336.885021)
			(xy 254.022279 -336.904774) (xy 254.080118 -336.931991) (xy 254.134089 -336.966242) (xy 254.183342 -337.006987)
			(xy 254.227099 -337.053584) (xy 254.264672 -337.105299) (xy 254.295466 -337.161314) (xy 254.318998 -337.220747)
			(xy 254.334895 -337.282661) (xy 254.342906 -337.346079) (xy 254.343408 -337.37804) (xy 254.342906 -337.410001)
			(xy 254.334895 -337.473419) (xy 254.318998 -337.535333) (xy 254.295466 -337.594766) (xy 254.264672 -337.650781)
			(xy 254.227099 -337.702496) (xy 254.183342 -337.749093) (xy 254.134089 -337.789838) (xy 254.080118 -337.824089)
			(xy 254.022279 -337.851306) (xy 253.961486 -337.871059) (xy 253.898696 -337.883037) (xy 253.8349 -337.887051)
			(xy 253.771104 -337.883037) (xy 253.708314 -337.871059) (xy 253.647521 -337.851306) (xy 253.589682 -337.824089)
			(xy 253.535711 -337.789838) (xy 253.486458 -337.749093) (xy 253.442701 -337.702496) (xy 253.405128 -337.650781)
			(xy 253.374334 -337.594766) (xy 253.350802 -337.535333) (xy 253.334905 -337.473419) (xy 253.326894 -337.410001)
			(xy 241.202422 -337.410001) (xy 241.187198 -337.469293) (xy 241.163666 -337.528726) (xy 241.132872 -337.584741)
			(xy 241.095299 -337.636456) (xy 241.051542 -337.683053) (xy 241.002289 -337.723798) (xy 240.948318 -337.758049)
			(xy 240.890479 -337.785266) (xy 240.829686 -337.805019) (xy 240.766896 -337.816997) (xy 240.7031 -337.821011)
			(xy 240.639304 -337.816997) (xy 240.576514 -337.805019) (xy 240.515721 -337.785266) (xy 240.457882 -337.758049)
			(xy 240.403911 -337.723798) (xy 240.354658 -337.683053) (xy 240.310901 -337.636456) (xy 240.273328 -337.584741)
			(xy 240.242534 -337.528726) (xy 240.219002 -337.469293) (xy 240.203105 -337.407379) (xy 240.195094 -337.343961)
			(xy 237.05827 -337.343961) (xy 237.064899 -337.401365) (xy 237.065312 -337.430618) (xy 237.064813 -337.462158)
			(xy 237.057009 -337.524753) (xy 237.041521 -337.585901) (xy 237.01859 -337.644665) (xy 236.988565 -337.700141)
			(xy 236.95191 -337.751477) (xy 236.909186 -337.797884) (xy 236.861049 -337.838651) (xy 236.80824 -337.873151)
			(xy 236.75157 -337.900853) (xy 236.691907 -337.921333) (xy 236.63017 -337.934277) (xy 236.567306 -337.939484)
			(xy 236.50428 -337.936876) (xy 236.442061 -337.926492) (xy 236.381605 -337.908491) (xy 236.323839 -337.883151)
			(xy 236.269651 -337.85086) (xy 236.219873 -337.812115) (xy 236.17527 -337.76751) (xy 236.136527 -337.717731)
			(xy 236.104239 -337.663541) (xy 236.078901 -337.605775) (xy 236.060903 -337.545317) (xy 236.050522 -337.483098)
			(xy 236.047916 -337.420072) (xy 236.053126 -337.357208) (xy 236.066072 -337.295471) (xy 236.086555 -337.23581)
			(xy 236.11426 -337.17914) (xy 236.148762 -337.126333) (xy 236.189531 -337.078198) (xy 236.235941 -337.035476)
			(xy 236.287278 -336.998823) (xy 236.342755 -336.968801) (xy 236.40152 -336.945872) (xy 236.462669 -336.930387)
			(xy 236.525264 -336.922585) (xy 236.556804 -336.92211) (xy 236.581217 -336.922418) (xy 236.629815 -336.927122)
			(xy 236.653832 -336.931508) (xy 236.667294 -336.934048) (xy 236.692694 -336.925412) (xy 236.768386 -336.838544)
			(xy 236.77372 -336.812128) (xy 236.769402 -336.799174) (xy 236.760059 -336.769562) (xy 236.74997 -336.708298)
			(xy 236.749336 -336.677254) (xy 236.749844 -336.658204) (xy 236.750352 -336.646266) (xy 236.741208 -336.62493)
			(xy 236.662722 -336.556858) (xy 236.640116 -336.551016) (xy 236.628432 -336.553302) (xy 236.603801 -336.557937)
			(xy 236.553925 -336.562896) (xy 236.528864 -336.563208) (xy 236.497326 -336.562694) (xy 236.434734 -336.554888)
			(xy 236.373588 -336.539399) (xy 236.314828 -336.516467) (xy 236.259356 -336.486442) (xy 236.208023 -336.449786)
			(xy 236.161619 -336.407063) (xy 236.120855 -336.358928) (xy 236.086359 -336.30612) (xy 236.058659 -336.249451)
			(xy 236.038181 -336.189791) (xy 236.025239 -336.128056) (xy 236.020034 -336.065195) (xy 234.641365 -336.065195)
			(xy 234.644325 -336.070307) (xy 234.669929 -336.131961) (xy 234.687248 -336.196435) (xy 234.695982 -336.26262)
			(xy 234.696508 -336.296) (xy 234.696089 -336.32728) (xy 234.688425 -336.389369) (xy 234.673199 -336.450047)
			(xy 234.650642 -336.508399) (xy 234.621096 -336.563542) (xy 234.585005 -336.614642) (xy 234.542917 -336.660928)
			(xy 234.495468 -336.701699) (xy 234.469686 -336.719418) (xy 234.459526 -336.72687) (xy 234.44754 -336.749001)
			(xy 234.446826 -336.761582) (xy 234.446826 -336.846418) (xy 234.447506 -336.859001) (xy 234.459528 -336.88112)
			(xy 234.469686 -336.888582) (xy 234.495433 -336.906344) (xy 234.542861 -336.947124) (xy 234.584932 -336.993411)
			(xy 234.62101 -337.044508) (xy 234.65055 -337.099642) (xy 234.673108 -337.157983) (xy 234.688343 -337.218649)
			(xy 234.696024 -337.280725) (xy 234.696508 -337.312) (xy 234.696006 -337.343961) (xy 234.687995 -337.407379)
			(xy 234.672098 -337.469293) (xy 234.648566 -337.528726) (xy 234.617772 -337.584741) (xy 234.580199 -337.636456)
			(xy 234.536442 -337.683053) (xy 234.487189 -337.723798) (xy 234.433218 -337.758049) (xy 234.375379 -337.785266)
			(xy 234.314586 -337.805019) (xy 234.251796 -337.816997) (xy 234.188 -337.821011) (xy 234.124204 -337.816997)
			(xy 234.061414 -337.805019) (xy 234.000621 -337.785266) (xy 233.942782 -337.758049) (xy 233.888811 -337.723798)
			(xy 233.839558 -337.683053) (xy 233.795801 -337.636456) (xy 233.758228 -337.584741) (xy 233.727434 -337.528726)
			(xy 233.703902 -337.469293) (xy 233.688005 -337.407379) (xy 233.679994 -337.343961) (xy 233.679492 -337.312)
			(xy 233.679911 -337.28072) (xy 233.687575 -337.218631) (xy 233.702801 -337.157953) (xy 233.725358 -337.099601)
			(xy 233.754904 -337.044458) (xy 233.790995 -336.993358) (xy 233.833083 -336.947072) (xy 233.880532 -336.906301)
			(xy 233.906314 -336.888582) (xy 233.916474 -336.88113) (xy 233.92846 -336.858999) (xy 233.929174 -336.846418)
			(xy 233.929174 -336.761582) (xy 233.928494 -336.748999) (xy 233.916472 -336.72688) (xy 233.906314 -336.719418)
			(xy 233.880567 -336.701656) (xy 233.833139 -336.660876) (xy 233.791068 -336.614589) (xy 233.75499 -336.563492)
			(xy 233.72545 -336.508358) (xy 233.702892 -336.450017) (xy 233.687657 -336.389351) (xy 233.679976 -336.327275)
			(xy 233.679492 -336.296) (xy 233.680089 -336.260403) (xy 233.690046 -336.189907) (xy 233.709723 -336.121485)
			(xy 233.723688 -336.088736) (xy 233.727498 -336.0801) (xy 233.728514 -336.06105) (xy 233.701082 -335.977992)
			(xy 233.68889 -335.963514) (xy 233.680508 -335.958942) (xy 233.671364 -335.953354) (xy 233.663264 -335.948993)
			(xy 233.64517 -335.945739) (xy 233.636058 -335.947004) (xy 233.605832 -335.952592) (xy 233.596645 -335.954611)
			(xy 233.580599 -335.964405) (xy 233.57459 -335.971642) (xy 233.553887 -335.997597) (xy 233.506833 -336.044435)
			(xy 233.454083 -336.084751) (xy 233.396534 -336.117859) (xy 233.335167 -336.143195) (xy 233.271024 -336.160329)
			(xy 233.205196 -336.16897) (xy 233.172 -336.169508) (xy 233.140659 -336.169009) (xy 233.078453 -336.161309)
			(xy 233.017664 -336.146025) (xy 232.959212 -336.12339) (xy 232.903984 -336.093745) (xy 232.878122 -336.076036)
			(xy 232.868216 -336.068924) (xy 232.84434 -336.065368) (xy 232.743756 -336.098134) (xy 232.726738 -336.115152)
			(xy 232.722928 -336.126582) (xy 232.712382 -336.156551) (xy 232.684958 -336.213859) (xy 232.650606 -336.267302)
			(xy 232.609862 -336.316048) (xy 232.56336 -336.359337) (xy 232.511827 -336.396493) (xy 232.456065 -336.426937)
			(xy 232.396943 -336.450195) (xy 232.335385 -336.465904) (xy 232.272348 -336.473819) (xy 232.240582 -336.474308)
			(xy 232.208622 -336.473805) (xy 232.145205 -336.465792) (xy 232.083293 -336.449893) (xy 232.023862 -336.426361)
			(xy 231.967849 -336.395566) (xy 231.916137 -336.357993) (xy 231.869541 -336.314235) (xy 231.828798 -336.264983)
			(xy 231.794548 -336.211013) (xy 231.767332 -336.153175) (xy 231.74758 -336.092383) (xy 231.735603 -336.029595)
			(xy 231.731589 -335.9658) (xy 227.536248 -335.9658) (xy 227.536248 -337.6552) (xy 231.764222 -337.6552)
			(xy 231.768237 -337.591392) (xy 231.780218 -337.52859) (xy 231.799976 -337.467785) (xy 231.827199 -337.409937)
			(xy 231.861459 -337.355956) (xy 231.902214 -337.306696) (xy 231.948823 -337.262932) (xy 232.000549 -337.225355)
			(xy 232.056577 -337.194558) (xy 232.116023 -337.171027) (xy 232.17795 -337.155132) (xy 232.241381 -337.147124)
			(xy 232.273348 -337.146646) (xy 232.303866 -337.147067) (xy 232.364464 -337.154357) (xy 232.423754 -337.16885)
			(xy 232.480882 -337.190338) (xy 232.535026 -337.218511) (xy 232.585408 -337.252965) (xy 232.631301 -337.293203)
			(xy 232.672047 -337.338647) (xy 232.707058 -337.388643) (xy 232.735831 -337.442471) (xy 232.747312 -337.47075)
			(xy 232.751376 -337.481672) (xy 232.767886 -337.497166) (xy 232.86466 -337.528408) (xy 232.887012 -337.525614)
			(xy 232.896918 -337.519264) (xy 232.921598 -337.503896) (xy 232.973775 -337.478242) (xy 233.028535 -337.458704)
			(xy 233.085166 -337.445535) (xy 233.142929 -337.438907) (xy 233.172 -337.438492) (xy 233.203961 -337.438994)
			(xy 233.267379 -337.447005) (xy 233.329293 -337.462902) (xy 233.388726 -337.486434) (xy 233.444741 -337.517228)
			(xy 233.496456 -337.554801) (xy 233.543053 -337.598558) (xy 233.583798 -337.647811) (xy 233.618049 -337.701782)
			(xy 233.645266 -337.759621) (xy 233.665019 -337.820414) (xy 233.676997 -337.883204) (xy 233.681011 -337.947)
			(xy 233.676997 -338.010796) (xy 233.665019 -338.073586) (xy 233.645266 -338.134379) (xy 233.618049 -338.192218)
			(xy 233.583798 -338.246189) (xy 233.543053 -338.295442) (xy 233.496456 -338.339199) (xy 233.444741 -338.376772)
			(xy 233.388726 -338.407566) (xy 233.329293 -338.431098) (xy 233.267379 -338.446995) (xy 233.203961 -338.455006)
			(xy 233.172 -338.455508) (xy 233.141485 -338.455011) (xy 233.08089 -338.447728) (xy 233.021604 -338.433242)
			(xy 232.964478 -338.411762) (xy 232.910335 -338.383596) (xy 232.859954 -338.349151) (xy 232.81406 -338.308921)
			(xy 232.773312 -338.263486) (xy 232.738298 -338.213499) (xy 232.70952 -338.159679) (xy 232.698036 -338.131404)
			(xy 232.693972 -338.120482) (xy 232.677462 -338.104988) (xy 232.580688 -338.073746) (xy 232.558336 -338.07654)
			(xy 232.54843 -338.08289) (xy 232.523741 -338.098244) (xy 232.471567 -338.123899) (xy 232.416808 -338.14344)
			(xy 232.36018 -338.156612) (xy 232.302418 -338.163244) (xy 232.273348 -338.163662) (xy 232.241381 -338.163276)
			(xy 232.17795 -338.155268) (xy 232.116023 -338.139373) (xy 232.056577 -338.115842) (xy 232.000549 -338.085045)
			(xy 231.948823 -338.047468) (xy 231.902214 -338.003704) (xy 231.861459 -337.954444) (xy 231.827199 -337.900463)
			(xy 231.799976 -337.842615) (xy 231.780218 -337.78181) (xy 231.768237 -337.719008) (xy 231.764222 -337.6552)
			(xy 227.536248 -337.6552) (xy 227.536248 -340.306914) (xy 227.535821 -340.316982) (xy 227.528097 -340.335578)
			(xy 227.521262 -340.342982) (xy 227.319844 -340.5444) (xy 231.737193 -340.5444) (xy 231.741207 -340.480607)
			(xy 231.753184 -340.41782) (xy 231.772935 -340.357029) (xy 231.80015 -340.299193) (xy 231.834398 -340.245223)
			(xy 231.87514 -340.195972) (xy 231.921734 -340.152214) (xy 231.973444 -340.114642) (xy 232.029456 -340.083846)
			(xy 232.088885 -340.060313) (xy 232.150796 -340.044414) (xy 232.21421 -340.0364) (xy 232.24617 -340.035896)
			(xy 232.27689 -340.036384) (xy 232.337883 -340.043779) (xy 232.397541 -340.058466) (xy 232.454997 -340.080231)
			(xy 232.509413 -340.108757) (xy 232.534968 -340.125812) (xy 232.544874 -340.13267) (xy 232.568242 -340.135972)
			(xy 232.668572 -340.10219) (xy 232.685082 -340.085426) (xy 232.688892 -340.073996) (xy 232.699327 -340.043881)
			(xy 232.726665 -339.986306) (xy 232.760985 -339.932599) (xy 232.801747 -339.883602) (xy 232.848313 -339.840084)
			(xy 232.899952 -339.802725) (xy 232.955856 -339.772113) (xy 233.015146 -339.748727) (xy 233.076894 -339.732934)
			(xy 233.140132 -339.724982) (xy 233.172 -339.724492) (xy 233.203961 -339.724994) (xy 233.267379 -339.733005)
			(xy 233.329293 -339.748902) (xy 233.388726 -339.772434) (xy 233.444741 -339.803228) (xy 233.496456 -339.840801)
			(xy 233.543053 -339.884558) (xy 233.583798 -339.933811) (xy 233.618049 -339.987782) (xy 233.645266 -340.045621)
			(xy 233.665019 -340.106414) (xy 233.676997 -340.169204) (xy 233.681011 -340.233) (xy 233.676997 -340.296796)
			(xy 233.665019 -340.359586) (xy 233.645266 -340.420379) (xy 233.618049 -340.478218) (xy 233.583798 -340.532189)
			(xy 233.543053 -340.581442) (xy 233.496456 -340.625199) (xy 233.444741 -340.662772) (xy 233.388726 -340.693566)
			(xy 233.329293 -340.717098) (xy 233.267379 -340.732995) (xy 233.203961 -340.741006) (xy 233.172 -340.741508)
			(xy 233.14128 -340.741035) (xy 233.080286 -340.733636) (xy 233.020627 -340.718945) (xy 232.963172 -340.697177)
			(xy 232.908756 -340.668648) (xy 232.883202 -340.651592) (xy 232.873296 -340.644734) (xy 232.849928 -340.641432)
			(xy 232.749598 -340.675214) (xy 232.733088 -340.691978) (xy 232.729278 -340.703408) (xy 232.718785 -340.733502)
			(xy 232.691451 -340.791073) (xy 232.657137 -340.844778) (xy 232.61638 -340.893774) (xy 232.569821 -340.937293)
			(xy 232.518189 -340.974653) (xy 232.462293 -341.005268) (xy 232.403009 -341.028659) (xy 232.341268 -341.044458)
			(xy 232.278036 -341.052418) (xy 232.24617 -341.052912) (xy 232.21421 -341.0524) (xy 232.150796 -341.044386)
			(xy 232.088885 -341.028487) (xy 232.029456 -341.004954) (xy 231.973444 -340.974158) (xy 231.921734 -340.936586)
			(xy 231.87514 -340.892828) (xy 231.834398 -340.843577) (xy 231.80015 -340.789607) (xy 231.772935 -340.731771)
			(xy 231.753184 -340.67098) (xy 231.741207 -340.608193) (xy 231.737193 -340.5444) (xy 227.319844 -340.5444)
			(xy 226.732846 -341.131398) (xy 226.725226 -341.147908) (xy 226.724718 -341.157052) (xy 226.721771 -341.189833)
			(xy 226.708484 -341.254295) (xy 226.686994 -341.316506) (xy 226.657657 -341.375424) (xy 226.620966 -341.430065)
			(xy 226.577532 -341.479517) (xy 226.528082 -341.522953) (xy 226.473442 -341.559647) (xy 226.414525 -341.588985)
			(xy 226.352316 -341.610479) (xy 226.287854 -341.623768) (xy 226.255072 -341.626698) (xy 226.245928 -341.627206)
			(xy 226.229418 -341.634826) (xy 225.554583 -342.309661) (xy 231.718098 -342.309661) (xy 231.718098 -342.245739)
			(xy 231.726109 -342.182321) (xy 231.742006 -342.120407) (xy 231.765538 -342.060974) (xy 231.796332 -342.004959)
			(xy 231.833905 -341.953244) (xy 231.877662 -341.906647) (xy 231.926915 -341.865902) (xy 231.980886 -341.831651)
			(xy 232.038725 -341.804434) (xy 232.099518 -341.784681) (xy 232.162308 -341.772703) (xy 232.226104 -341.76869)
			(xy 232.2899 -341.772703) (xy 232.35269 -341.784681) (xy 232.413483 -341.804434) (xy 232.471322 -341.831651)
			(xy 232.525293 -341.865902) (xy 232.574546 -341.906647) (xy 232.618303 -341.953244) (xy 232.655876 -342.004959)
			(xy 232.68667 -342.060974) (xy 232.710202 -342.120407) (xy 232.726099 -342.182321) (xy 232.73411 -342.245739)
			(xy 232.734612 -342.2777) (xy 232.73411 -342.309661) (xy 232.726099 -342.373079) (xy 232.710202 -342.434993)
			(xy 232.68667 -342.494426) (xy 232.655876 -342.550441) (xy 232.618303 -342.602156) (xy 232.574546 -342.648753)
			(xy 232.547957 -342.670749) (xy 233.237414 -342.670749) (xy 233.237416 -342.616235) (xy 233.245175 -342.562277)
			(xy 233.260535 -342.509972) (xy 233.283183 -342.460385) (xy 233.312657 -342.414527) (xy 233.348358 -342.37333)
			(xy 233.389559 -342.337633) (xy 233.43542 -342.308164) (xy 233.485009 -342.285521) (xy 233.537316 -342.270167)
			(xy 233.591275 -342.262413) (xy 233.618532 -342.261952) (xy 233.639106 -342.26246) (xy 233.652822 -342.263222)
			(xy 233.676698 -342.25103) (xy 233.739944 -342.154002) (xy 233.741214 -342.127332) (xy 233.734864 -342.114886)
			(xy 233.721654 -342.087988) (xy 233.700943 -342.031753) (xy 233.686971 -341.973477) (xy 233.67993 -341.913964)
			(xy 233.679492 -341.884) (xy 233.679911 -341.85272) (xy 233.687575 -341.790631) (xy 233.702801 -341.729953)
			(xy 233.725358 -341.671601) (xy 233.754904 -341.616458) (xy 233.790995 -341.565358) (xy 233.833083 -341.519072)
			(xy 233.880532 -341.478301) (xy 233.906314 -341.460582) (xy 233.916474 -341.45313) (xy 233.92846 -341.430999)
			(xy 233.929174 -341.418418) (xy 233.929174 -341.333582) (xy 233.928494 -341.320999) (xy 233.916472 -341.29888)
			(xy 233.906314 -341.291418) (xy 233.880567 -341.273656) (xy 233.833139 -341.232876) (xy 233.791068 -341.186589)
			(xy 233.75499 -341.135492) (xy 233.72545 -341.080358) (xy 233.702892 -341.022017) (xy 233.687657 -340.961351)
			(xy 233.679976 -340.899275) (xy 233.679492 -340.868) (xy 233.679956 -340.837269) (xy 233.687365 -340.776255)
			(xy 233.702073 -340.716579) (xy 233.723868 -340.659111) (xy 233.752431 -340.604689) (xy 233.787345 -340.554107)
			(xy 233.828102 -340.508102) (xy 233.874107 -340.467345) (xy 233.924689 -340.432431) (xy 233.979111 -340.403868)
			(xy 234.036579 -340.382073) (xy 234.096255 -340.367365) (xy 234.157269 -340.359956) (xy 234.188 -340.359492)
			(xy 234.188254 -340.359492) (xy 234.198273 -340.359043) (xy 234.216791 -340.351386) (xy 234.230965 -340.337223)
			(xy 234.238635 -340.318711) (xy 234.239054 -340.308692) (xy 234.239054 -340.304628) (xy 234.238292 -340.30031)
			(xy 234.235901 -340.284864) (xy 234.233358 -340.253709) (xy 234.233212 -340.23808) (xy 234.233708 -340.210224)
			(xy 234.241835 -340.155107) (xy 234.257884 -340.101755) (xy 234.281514 -340.051302) (xy 234.312224 -340.004817)
			(xy 234.349363 -339.963288) (xy 234.392141 -339.927595) (xy 234.439651 -339.898497) (xy 234.490886 -339.876611)
			(xy 234.517692 -339.869018) (xy 234.527598 -339.866478) (xy 234.544108 -339.854032) (xy 234.589828 -339.772498)
			(xy 234.592368 -339.751924) (xy 234.58932 -339.742018) (xy 234.579577 -339.706814) (xy 234.569124 -339.634522)
			(xy 234.568492 -339.598) (xy 234.568911 -339.56672) (xy 234.576575 -339.504631) (xy 234.591801 -339.443953)
			(xy 234.614358 -339.385601) (xy 234.643904 -339.330458) (xy 234.679995 -339.279358) (xy 234.722083 -339.233072)
			(xy 234.769532 -339.192301) (xy 234.795314 -339.174582) (xy 234.805474 -339.16713) (xy 234.81746 -339.144999)
			(xy 234.818174 -339.132418) (xy 234.818174 -339.047582) (xy 234.817494 -339.034999) (xy 234.805472 -339.01288)
			(xy 234.795314 -339.005418) (xy 234.769567 -338.987656) (xy 234.722139 -338.946876) (xy 234.680068 -338.900589)
			(xy 234.64399 -338.849492) (xy 234.61445 -338.794358) (xy 234.591892 -338.736017) (xy 234.576657 -338.675351)
			(xy 234.568976 -338.613275) (xy 234.568492 -338.582) (xy 234.568994 -338.550039) (xy 234.577005 -338.486621)
			(xy 234.592902 -338.424707) (xy 234.616434 -338.365274) (xy 234.647228 -338.309259) (xy 234.684801 -338.257544)
			(xy 234.728558 -338.210947) (xy 234.777811 -338.170202) (xy 234.831782 -338.135951) (xy 234.889621 -338.108734)
			(xy 234.950414 -338.088981) (xy 235.013204 -338.077003) (xy 235.077 -338.07299) (xy 235.140796 -338.077003)
			(xy 235.203586 -338.088981) (xy 235.264379 -338.108734) (xy 235.322218 -338.135951) (xy 235.376189 -338.170202)
			(xy 235.425442 -338.210947) (xy 235.469199 -338.257544) (xy 235.506772 -338.309259) (xy 235.537566 -338.365274)
			(xy 235.561098 -338.424707) (xy 235.576995 -338.486621) (xy 235.577038 -338.486961) (xy 240.195094 -338.486961)
			(xy 240.195094 -338.423039) (xy 240.203105 -338.359621) (xy 240.219002 -338.297707) (xy 240.242534 -338.238274)
			(xy 240.273328 -338.182259) (xy 240.310901 -338.130544) (xy 240.354658 -338.083947) (xy 240.403911 -338.043202)
			(xy 240.457882 -338.008951) (xy 240.515721 -337.981734) (xy 240.576514 -337.961981) (xy 240.639304 -337.950003)
			(xy 240.7031 -337.94599) (xy 240.766896 -337.950003) (xy 240.829686 -337.961981) (xy 240.890479 -337.981734)
			(xy 240.948318 -338.008951) (xy 241.002289 -338.043202) (xy 241.051542 -338.083947) (xy 241.095299 -338.130544)
			(xy 241.132872 -338.182259) (xy 241.163666 -338.238274) (xy 241.187198 -338.297707) (xy 241.203095 -338.359621)
			(xy 241.211106 -338.423039) (xy 241.211608 -338.455) (xy 241.211106 -338.486961) (xy 241.203405 -338.547921)
			(xy 253.326894 -338.547921) (xy 253.326894 -338.483999) (xy 253.334905 -338.420581) (xy 253.350802 -338.358667)
			(xy 253.374334 -338.299234) (xy 253.405128 -338.243219) (xy 253.442701 -338.191504) (xy 253.486458 -338.144907)
			(xy 253.535711 -338.104162) (xy 253.589682 -338.069911) (xy 253.647521 -338.042694) (xy 253.708314 -338.022941)
			(xy 253.771104 -338.010963) (xy 253.8349 -338.00695) (xy 253.898696 -338.010963) (xy 253.961486 -338.022941)
			(xy 254.022279 -338.042694) (xy 254.080118 -338.069911) (xy 254.134089 -338.104162) (xy 254.183342 -338.144907)
			(xy 254.227099 -338.191504) (xy 254.264672 -338.243219) (xy 254.295466 -338.299234) (xy 254.318998 -338.358667)
			(xy 254.334895 -338.420581) (xy 254.342906 -338.483999) (xy 254.343408 -338.51596) (xy 254.342906 -338.547921)
			(xy 254.334895 -338.611339) (xy 254.318998 -338.673253) (xy 254.295466 -338.732686) (xy 254.264672 -338.788701)
			(xy 254.227099 -338.840416) (xy 254.183342 -338.887013) (xy 254.134089 -338.927758) (xy 254.080118 -338.962009)
			(xy 254.022279 -338.989226) (xy 253.961486 -339.008979) (xy 253.898696 -339.020957) (xy 253.8349 -339.024971)
			(xy 253.771104 -339.020957) (xy 253.708314 -339.008979) (xy 253.647521 -338.989226) (xy 253.589682 -338.962009)
			(xy 253.535711 -338.927758) (xy 253.486458 -338.887013) (xy 253.442701 -338.840416) (xy 253.405128 -338.788701)
			(xy 253.374334 -338.732686) (xy 253.350802 -338.673253) (xy 253.334905 -338.611339) (xy 253.326894 -338.547921)
			(xy 241.203405 -338.547921) (xy 241.203095 -338.550379) (xy 241.187198 -338.612293) (xy 241.163666 -338.671726)
			(xy 241.132872 -338.727741) (xy 241.095299 -338.779456) (xy 241.051542 -338.826053) (xy 241.002289 -338.866798)
			(xy 240.948318 -338.901049) (xy 240.890479 -338.928266) (xy 240.829686 -338.948019) (xy 240.766896 -338.959997)
			(xy 240.7031 -338.964011) (xy 240.639304 -338.959997) (xy 240.576514 -338.948019) (xy 240.515721 -338.928266)
			(xy 240.457882 -338.901049) (xy 240.403911 -338.866798) (xy 240.354658 -338.826053) (xy 240.310901 -338.779456)
			(xy 240.273328 -338.727741) (xy 240.242534 -338.671726) (xy 240.219002 -338.612293) (xy 240.203105 -338.550379)
			(xy 240.195094 -338.486961) (xy 235.577038 -338.486961) (xy 235.585006 -338.550039) (xy 235.585508 -338.582)
			(xy 235.585089 -338.61328) (xy 235.577425 -338.675369) (xy 235.562199 -338.736047) (xy 235.539642 -338.794399)
			(xy 235.510096 -338.849542) (xy 235.474005 -338.900642) (xy 235.431917 -338.946928) (xy 235.384468 -338.987699)
			(xy 235.358686 -339.005418) (xy 235.348526 -339.01287) (xy 235.33654 -339.035001) (xy 235.335826 -339.047582)
			(xy 235.335826 -339.132418) (xy 235.336506 -339.145001) (xy 235.348528 -339.16712) (xy 235.358686 -339.174582)
			(xy 235.384433 -339.192344) (xy 235.431861 -339.233124) (xy 235.473932 -339.279411) (xy 235.51001 -339.330508)
			(xy 235.53955 -339.385642) (xy 235.562108 -339.443983) (xy 235.577343 -339.504649) (xy 235.585024 -339.566725)
			(xy 235.585508 -339.598) (xy 235.58501 -339.629961) (xy 240.195094 -339.629961) (xy 240.195094 -339.566039)
			(xy 240.203105 -339.502621) (xy 240.219002 -339.440707) (xy 240.242534 -339.381274) (xy 240.273328 -339.325259)
			(xy 240.310901 -339.273544) (xy 240.354658 -339.226947) (xy 240.403911 -339.186202) (xy 240.457882 -339.151951)
			(xy 240.515721 -339.124734) (xy 240.576514 -339.104981) (xy 240.639304 -339.093003) (xy 240.7031 -339.08899)
			(xy 240.719156 -339.09) (xy 256.539492 -339.09) (xy 256.540029 -339.060845) (xy 256.54893 -339.003218)
			(xy 256.566493 -338.947616) (xy 256.59231 -338.895332) (xy 256.625779 -338.847584) (xy 256.666123 -338.805484)
			(xy 256.712402 -338.77001) (xy 256.763538 -338.741989) (xy 256.818342 -338.722073) (xy 256.846832 -338.715858)
			(xy 256.856738 -338.713826) (xy 256.873248 -338.702904) (xy 256.92481 -338.628482) (xy 256.929128 -338.609178)
			(xy 256.92735 -338.599526) (xy 256.924136 -338.578784) (xy 256.9207 -338.536948) (xy 256.920492 -338.51596)
			(xy 256.920965 -338.483111) (xy 256.929424 -338.417961) (xy 256.94621 -338.354443) (xy 256.971041 -338.293619)
			(xy 257.003505 -338.236503) (xy 257.043059 -338.184047) (xy 257.089043 -338.137126) (xy 257.114548 -338.116418)
			(xy 257.126232 -338.107274) (xy 257.135884 -338.079334) (xy 257.107944 -337.960716) (xy 257.086862 -337.940142)
			(xy 257.07213 -337.937094) (xy 257.041279 -337.930185) (xy 256.981433 -337.909804) (xy 256.924574 -337.882163)
			(xy 256.871578 -337.84769) (xy 256.823263 -337.806916) (xy 256.780372 -337.760469) (xy 256.743567 -337.709065)
			(xy 256.713416 -337.653496) (xy 256.690383 -337.59462) (xy 256.674824 -337.533343) (xy 256.666977 -337.470611)
			(xy 256.666492 -337.439) (xy 256.666943 -337.407234) (xy 256.674879 -337.3442) (xy 256.690604 -337.282644)
			(xy 256.713873 -337.223526) (xy 256.744322 -337.167767) (xy 256.781479 -337.116233) (xy 256.824764 -337.069727)
			(xy 256.873503 -337.028975) (xy 256.926938 -336.994609) (xy 256.984237 -336.967165) (xy 257.014218 -336.956654)
			(xy 257.024124 -336.953352) (xy 257.039872 -336.939128) (xy 257.079496 -336.852514) (xy 257.080004 -336.831432)
			(xy 257.07594 -336.82178) (xy 257.066915 -336.798723) (xy 257.05424 -336.750859) (xy 257.047867 -336.701757)
			(xy 257.047492 -336.677) (xy 257.047886 -336.652244) (xy 257.054261 -336.603144) (xy 257.066929 -336.555281)
			(xy 257.07594 -336.53222) (xy 257.080004 -336.522568) (xy 257.079496 -336.501486) (xy 257.039872 -336.414872)
			(xy 257.024124 -336.400648) (xy 257.014218 -336.397346) (xy 256.984222 -336.386871) (xy 256.926911 -336.359441)
			(xy 256.873465 -336.325082) (xy 256.824719 -336.28433) (xy 256.781431 -336.237821) (xy 256.744277 -336.186279)
			(xy 256.713836 -336.130508) (xy 256.690584 -336.071379) (xy 256.674882 -336.009812) (xy 256.666976 -335.946769)
			(xy 256.666492 -335.915) (xy 256.666974 -335.882215) (xy 256.675407 -335.817191) (xy 256.692132 -335.753791)
			(xy 256.716872 -335.693068) (xy 256.749216 -335.636032) (xy 256.788626 -335.583628) (xy 256.834449 -335.536729)
			(xy 256.885923 -335.496111) (xy 256.942192 -335.462451) (xy 256.972054 -335.44891) (xy 256.982468 -335.444338)
			(xy 256.9972 -335.42732) (xy 257.025394 -335.330292) (xy 257.021838 -335.308194) (xy 257.015488 -335.298542)
			(xy 256.998848 -335.27322) (xy 256.971024 -335.219394) (xy 256.949805 -335.162638) (xy 256.935493 -335.10376)
			(xy 256.928292 -335.043596) (xy 256.927858 -335.0133) (xy 256.928318 -334.983182) (xy 256.935418 -334.923366)
			(xy 256.949531 -334.864808) (xy 256.97046 -334.808325) (xy 256.997911 -334.754708) (xy 257.031501 -334.704708)
			(xy 257.050794 -334.681576) (xy 257.056271 -334.674779) (xy 257.062629 -334.658534) (xy 257.06324 -334.649826)
			(xy 257.064002 -334.620108) (xy 257.063896 -334.61135) (xy 257.058431 -334.59472) (xy 257.053334 -334.587596)
			(xy 257.033276 -334.560801) (xy 256.999643 -334.502932) (xy 256.973895 -334.441149) (xy 256.956479 -334.376521)
			(xy 256.947695 -334.310167) (xy 256.947162 -334.2767) (xy 256.947619 -334.244387) (xy 256.955818 -334.180284)
			(xy 256.972072 -334.117735) (xy 256.996119 -334.05775) (xy 257.027571 -334.001295) (xy 257.065922 -333.949278)
			(xy 257.110553 -333.902539) (xy 257.160746 -333.861831) (xy 257.187954 -333.844392) (xy 257.198876 -333.837788)
			(xy 257.211322 -333.816452) (xy 257.21691 -333.70774) (xy 257.206496 -333.685134) (xy 257.196336 -333.677514)
			(xy 257.173591 -333.659332) (xy 257.133393 -333.617205) (xy 257.100056 -333.569463) (xy 257.074353 -333.517214)
			(xy 257.056879 -333.461669) (xy 257.04804 -333.404114) (xy 257.047492 -333.375) (xy 257.047978 -333.347749)
			(xy 257.055734 -333.293801) (xy 257.071089 -333.241506) (xy 257.093731 -333.191929) (xy 257.123197 -333.146079)
			(xy 257.158888 -333.104888) (xy 257.200079 -333.069197) (xy 257.245929 -333.039731) (xy 257.295506 -333.017089)
			(xy 257.347801 -333.001734) (xy 257.401749 -332.993978) (xy 257.456251 -332.993978) (xy 257.510199 -333.001734)
			(xy 257.562494 -333.017089) (xy 257.612071 -333.039731) (xy 257.657921 -333.069197) (xy 257.699112 -333.104888)
			(xy 257.734803 -333.146079) (xy 257.764269 -333.191929) (xy 257.786911 -333.241506) (xy 257.802266 -333.293801)
			(xy 257.810022 -333.347749) (xy 257.810508 -333.375) (xy 257.810009 -333.402224) (xy 257.80225 -333.456116)
			(xy 257.786903 -333.508357) (xy 257.764281 -333.557883) (xy 257.734844 -333.603688) (xy 257.699191 -333.644839)
			(xy 257.678936 -333.663036) (xy 257.669538 -333.671418) (xy 257.660394 -333.694532) (xy 257.672332 -333.802736)
			(xy 257.686302 -333.82331) (xy 257.697224 -333.829406) (xy 257.723757 -333.844238) (xy 257.773435 -333.879268)
			(xy 257.818579 -333.919974) (xy 257.858545 -333.965775) (xy 257.892762 -334.016016) (xy 257.920741 -334.069981)
			(xy 257.942083 -334.126898) (xy 257.956482 -334.185954) (xy 257.963734 -334.246307) (xy 257.964178 -334.2767)
			(xy 257.963734 -334.306818) (xy 257.956632 -334.366635) (xy 257.942517 -334.425195) (xy 257.921586 -334.481678)
			(xy 257.894131 -334.535294) (xy 257.860537 -334.585293) (xy 257.841242 -334.608424) (xy 257.835769 -334.615224)
			(xy 257.829408 -334.631466) (xy 257.828796 -334.640174) (xy 257.828034 -334.669892) (xy 257.828133 -334.678651)
			(xy 257.833603 -334.69528) (xy 257.838702 -334.702404) (xy 257.858751 -334.729205) (xy 257.892387 -334.787072)
			(xy 257.918138 -334.848853) (xy 257.935556 -334.91348) (xy 257.944341 -334.979834) (xy 257.944874 -335.0133)
			(xy 257.944352 -335.046083) (xy 257.935921 -335.111104) (xy 257.919198 -335.174501) (xy 257.894462 -335.235222)
			(xy 257.862123 -335.292257) (xy 257.822718 -335.344661) (xy 257.776901 -335.391562) (xy 257.725434 -335.432182)
			(xy 257.669171 -335.465846) (xy 257.639312 -335.47939) (xy 257.628898 -335.483962) (xy 257.614166 -335.50098)
			(xy 257.585972 -335.598008) (xy 257.589528 -335.620106) (xy 257.595878 -335.629758) (xy 257.612514 -335.655082)
			(xy 257.64034 -335.708908) (xy 257.66156 -335.765663) (xy 257.675872 -335.824541) (xy 257.683074 -335.884704)
			(xy 257.683508 -335.915) (xy 257.683077 -335.945791) (xy 257.675632 -336.00692) (xy 257.660851 -336.066701)
			(xy 257.63895 -336.124256) (xy 257.610251 -336.178741) (xy 257.593084 -336.204306) (xy 257.586988 -336.213196)
			(xy 257.582924 -336.23377) (xy 257.603244 -336.326988) (xy 257.615436 -336.344006) (xy 257.62458 -336.34934)
			(xy 257.648487 -336.364218) (xy 257.692048 -336.399896) (xy 257.729896 -336.441586) (xy 257.761209 -336.488383)
			(xy 257.785309 -336.539272) (xy 257.801672 -336.59315) (xy 257.809943 -336.648846) (xy 257.809943 -336.705154)
			(xy 257.801672 -336.76085) (xy 257.785309 -336.814728) (xy 257.761209 -336.865617) (xy 257.729896 -336.912414)
			(xy 257.692048 -336.954104) (xy 257.648487 -336.989782) (xy 257.62458 -337.00466) (xy 257.615436 -337.009994)
			(xy 257.603244 -337.027012) (xy 257.582924 -337.12023) (xy 257.586988 -337.140804) (xy 257.593084 -337.149694)
			(xy 257.61025 -337.175257) (xy 257.638915 -337.229755) (xy 257.660798 -337.287312) (xy 257.675579 -337.347089)
			(xy 257.683042 -337.408212) (xy 257.683508 -337.439) (xy 257.683006 -337.471848) (xy 257.674552 -337.536997)
			(xy 257.657772 -337.600514) (xy 257.632945 -337.661338) (xy 257.600486 -337.718454) (xy 257.560936 -337.770911)
			(xy 257.514955 -337.817834) (xy 257.489452 -337.838542) (xy 257.477768 -337.847686) (xy 257.468116 -337.875626)
			(xy 257.496056 -337.994244) (xy 257.517138 -338.014818) (xy 257.53187 -338.017866) (xy 257.562735 -338.024719)
			(xy 257.622584 -338.045103) (xy 257.679446 -338.072748) (xy 257.732444 -338.107226) (xy 257.78076 -338.148006)
			(xy 257.823651 -338.194459) (xy 257.860454 -338.245869) (xy 257.890603 -338.301444) (xy 257.913632 -338.360327)
			(xy 257.929186 -338.421609) (xy 257.937026 -338.484347) (xy 257.937508 -338.51596) (xy 257.937025 -338.546691)
			(xy 257.929621 -338.607706) (xy 257.914916 -338.667384) (xy 257.893124 -338.724853) (xy 257.864564 -338.779277)
			(xy 257.829652 -338.829862) (xy 257.788897 -338.875869) (xy 257.742893 -338.916627) (xy 257.692311 -338.951544)
			(xy 257.63789 -338.980108) (xy 257.580422 -339.001904) (xy 257.520746 -339.016614) (xy 257.459731 -339.024022)
			(xy 257.429 -339.024468) (xy 257.41717 -339.02438) (xy 257.393539 -339.023238) (xy 257.381756 -339.022182)
			(xy 257.371085 -339.021765) (xy 257.350875 -339.028591) (xy 257.34264 -339.03539) (xy 257.302 -339.072474)
			(xy 257.302508 -339.085174) (xy 257.343402 -339.120226) (xy 257.351465 -339.126583) (xy 257.370991 -339.132873)
			(xy 257.381248 -339.132418) (xy 257.393158 -339.131358) (xy 257.417044 -339.130215) (xy 257.429 -339.130132)
			(xy 257.460541 -339.130568) (xy 257.523137 -339.13837) (xy 257.584288 -339.153855) (xy 257.643054 -339.176785)
			(xy 257.698532 -339.206808) (xy 257.749871 -339.243463) (xy 257.796282 -339.286186) (xy 257.837052 -339.334321)
			(xy 257.871555 -339.38713) (xy 257.899261 -339.443801) (xy 257.919744 -339.503464) (xy 257.932691 -339.565202)
			(xy 257.937902 -339.628067) (xy 257.935296 -339.691094) (xy 257.924915 -339.753315) (xy 257.906918 -339.813774)
			(xy 257.881581 -339.871543) (xy 257.849292 -339.925734) (xy 257.810549 -339.975516) (xy 257.765946 -340.020122)
			(xy 257.716167 -340.05887) (xy 257.661979 -340.091162) (xy 257.604212 -340.116504) (xy 257.543754 -340.134506)
			(xy 257.481534 -340.144892) (xy 257.418507 -340.147502) (xy 257.355641 -340.142297) (xy 257.293902 -340.129355)
			(xy 257.234238 -340.108876) (xy 257.177565 -340.081174) (xy 257.124753 -340.046676) (xy 257.076615 -340.005909)
			(xy 257.033888 -339.959502) (xy 256.997229 -339.908166) (xy 256.967202 -339.85269) (xy 256.944268 -339.793926)
			(xy 256.928778 -339.732776) (xy 256.92097 -339.67018) (xy 256.920492 -339.63864) (xy 256.920582 -339.622851)
			(xy 256.922488 -339.591332) (xy 256.924302 -339.575648) (xy 256.925572 -339.565996) (xy 256.921 -339.547708)
			(xy 256.869438 -339.475826) (xy 256.85369 -339.465666) (xy 256.844038 -339.463634) (xy 256.815752 -339.457211)
			(xy 256.761366 -339.437058) (xy 256.710659 -339.408903) (xy 256.664799 -339.373395) (xy 256.624844 -339.331353)
			(xy 256.591715 -339.283746) (xy 256.566175 -339.231671) (xy 256.548815 -339.176331) (xy 256.540033 -339.119)
			(xy 256.539492 -339.09) (xy 240.719156 -339.09) (xy 240.766896 -339.093003) (xy 240.829686 -339.104981)
			(xy 240.890479 -339.124734) (xy 240.948318 -339.151951) (xy 241.002289 -339.186202) (xy 241.051542 -339.226947)
			(xy 241.095299 -339.273544) (xy 241.132872 -339.325259) (xy 241.163666 -339.381274) (xy 241.187198 -339.440707)
			(xy 241.203095 -339.502621) (xy 241.211106 -339.566039) (xy 241.211608 -339.598) (xy 241.211106 -339.629961)
			(xy 241.205972 -339.670601) (xy 253.326894 -339.670601) (xy 253.326894 -339.606679) (xy 253.334905 -339.543261)
			(xy 253.350802 -339.481347) (xy 253.374334 -339.421914) (xy 253.405128 -339.365899) (xy 253.442701 -339.314184)
			(xy 253.486458 -339.267587) (xy 253.535711 -339.226842) (xy 253.589682 -339.192591) (xy 253.647521 -339.165374)
			(xy 253.708314 -339.145621) (xy 253.771104 -339.133643) (xy 253.8349 -339.12963) (xy 253.898696 -339.133643)
			(xy 253.961486 -339.145621) (xy 254.022279 -339.165374) (xy 254.080118 -339.192591) (xy 254.134089 -339.226842)
			(xy 254.183342 -339.267587) (xy 254.227099 -339.314184) (xy 254.264672 -339.365899) (xy 254.295466 -339.421914)
			(xy 254.318998 -339.481347) (xy 254.334895 -339.543261) (xy 254.342906 -339.606679) (xy 254.343408 -339.63864)
			(xy 254.342906 -339.670601) (xy 254.334895 -339.734019) (xy 254.318998 -339.795933) (xy 254.295466 -339.855366)
			(xy 254.264672 -339.911381) (xy 254.227099 -339.963096) (xy 254.183342 -340.009693) (xy 254.134089 -340.050438)
			(xy 254.080118 -340.084689) (xy 254.022279 -340.111906) (xy 253.961486 -340.131659) (xy 253.898696 -340.143637)
			(xy 253.8349 -340.147651) (xy 253.771104 -340.143637) (xy 253.708314 -340.131659) (xy 253.647521 -340.111906)
			(xy 253.589682 -340.084689) (xy 253.535711 -340.050438) (xy 253.486458 -340.009693) (xy 253.442701 -339.963096)
			(xy 253.405128 -339.911381) (xy 253.374334 -339.855366) (xy 253.350802 -339.795933) (xy 253.334905 -339.734019)
			(xy 253.326894 -339.670601) (xy 241.205972 -339.670601) (xy 241.203095 -339.693379) (xy 241.187198 -339.755293)
			(xy 241.163666 -339.814726) (xy 241.132872 -339.870741) (xy 241.095299 -339.922456) (xy 241.051542 -339.969053)
			(xy 241.002289 -340.009798) (xy 240.948318 -340.044049) (xy 240.890479 -340.071266) (xy 240.829686 -340.091019)
			(xy 240.766896 -340.102997) (xy 240.7031 -340.107011) (xy 240.639304 -340.102997) (xy 240.576514 -340.091019)
			(xy 240.515721 -340.071266) (xy 240.457882 -340.044049) (xy 240.403911 -340.009798) (xy 240.354658 -339.969053)
			(xy 240.310901 -339.922456) (xy 240.273328 -339.870741) (xy 240.242534 -339.814726) (xy 240.219002 -339.755293)
			(xy 240.203105 -339.693379) (xy 240.195094 -339.629961) (xy 235.58501 -339.629961) (xy 235.585 -339.630606)
			(xy 235.576663 -339.695283) (xy 235.560127 -339.758363) (xy 235.535661 -339.818811) (xy 235.503668 -339.875636)
			(xy 235.464674 -339.927904) (xy 235.419317 -339.974758) (xy 235.368342 -340.015429) (xy 235.312586 -340.04925)
			(xy 235.252964 -340.075665) (xy 235.190454 -340.094242) (xy 235.126082 -340.104674) (xy 235.09351 -340.106254)
			(xy 235.08335 -340.106508) (xy 235.064554 -340.115144) (xy 235.001562 -340.184486) (xy 234.994704 -340.20379)
			(xy 234.995466 -340.214204) (xy 234.996228 -340.23808) (xy 234.995817 -340.26431) (xy 234.988619 -340.316273)
			(xy 234.974371 -340.366761) (xy 234.95334 -340.41482) (xy 234.925924 -340.459545) (xy 234.892638 -340.500093)
			(xy 234.854112 -340.535698) (xy 234.811072 -340.56569) (xy 234.764328 -340.589502) (xy 234.739688 -340.598506)
			(xy 234.73029 -340.601808) (xy 234.715558 -340.614508) (xy 234.67441 -340.694518) (xy 234.672632 -340.713822)
			(xy 234.675426 -340.723474) (xy 234.685274 -340.758791) (xy 234.68734 -340.772961) (xy 240.195094 -340.772961)
			(xy 240.195094 -340.709039) (xy 240.203105 -340.645621) (xy 240.219002 -340.583707) (xy 240.242534 -340.524274)
			(xy 240.273328 -340.468259) (xy 240.310901 -340.416544) (xy 240.354658 -340.369947) (xy 240.403911 -340.329202)
			(xy 240.457882 -340.294951) (xy 240.515721 -340.267734) (xy 240.576514 -340.247981) (xy 240.639304 -340.236003)
			(xy 240.7031 -340.23199) (xy 240.766896 -340.236003) (xy 240.829686 -340.247981) (xy 240.890479 -340.267734)
			(xy 240.948318 -340.294951) (xy 241.002289 -340.329202) (xy 241.051542 -340.369947) (xy 241.095299 -340.416544)
			(xy 241.098692 -340.421214) (xy 245.362982 -340.421214) (xy 245.367053 -340.365592) (xy 245.379179 -340.311155)
			(xy 245.399102 -340.259064) (xy 245.426398 -340.210429) (xy 245.460484 -340.166286) (xy 245.500633 -340.127577)
			(xy 245.545991 -340.095126) (xy 245.595591 -340.069625) (xy 245.648375 -340.051618) (xy 245.703218 -340.041488)
			(xy 245.758952 -340.039451) (xy 245.814389 -340.045551) (xy 245.868346 -340.059657) (xy 245.919675 -340.081469)
			(xy 245.967281 -340.110523) (xy 246.010149 -340.146198) (xy 246.047366 -340.187735) (xy 246.078139 -340.234248)
			(xy 246.101811 -340.284745) (xy 246.117879 -340.338152) (xy 246.125999 -340.393328) (xy 246.126508 -340.421214)
			(xy 246.125999 -340.4491) (xy 246.117879 -340.504276) (xy 246.101811 -340.557683) (xy 246.078139 -340.60818)
			(xy 246.047366 -340.654693) (xy 246.010149 -340.69623) (xy 245.967281 -340.731905) (xy 245.919675 -340.760959)
			(xy 245.868346 -340.782771) (xy 245.828144 -340.793281) (xy 253.326894 -340.793281) (xy 253.326894 -340.729359)
			(xy 253.334905 -340.665941) (xy 253.350802 -340.604027) (xy 253.374334 -340.544594) (xy 253.405128 -340.488579)
			(xy 253.442701 -340.436864) (xy 253.486458 -340.390267) (xy 253.535711 -340.349522) (xy 253.589682 -340.315271)
			(xy 253.647521 -340.288054) (xy 253.708314 -340.268301) (xy 253.771104 -340.256323) (xy 253.8349 -340.25231)
			(xy 253.898696 -340.256323) (xy 253.961486 -340.268301) (xy 254.022279 -340.288054) (xy 254.080118 -340.315271)
			(xy 254.134089 -340.349522) (xy 254.183342 -340.390267) (xy 254.227099 -340.436864) (xy 254.264672 -340.488579)
			(xy 254.295466 -340.544594) (xy 254.318998 -340.604027) (xy 254.334895 -340.665941) (xy 254.342906 -340.729359)
			(xy 254.343408 -340.76132) (xy 254.342906 -340.793281) (xy 254.334895 -340.856699) (xy 254.318998 -340.918613)
			(xy 254.295466 -340.978046) (xy 254.264672 -341.034061) (xy 254.227099 -341.085776) (xy 254.183342 -341.132373)
			(xy 254.134089 -341.173118) (xy 254.080118 -341.207369) (xy 254.022279 -341.234586) (xy 253.961486 -341.254339)
			(xy 253.898696 -341.266317) (xy 253.8349 -341.270331) (xy 253.771104 -341.266317) (xy 253.708314 -341.254339)
			(xy 253.647521 -341.234586) (xy 253.589682 -341.207369) (xy 253.535711 -341.173118) (xy 253.486458 -341.132373)
			(xy 253.442701 -341.085776) (xy 253.405128 -341.034061) (xy 253.374334 -340.978046) (xy 253.350802 -340.918613)
			(xy 253.334905 -340.856699) (xy 253.326894 -340.793281) (xy 245.828144 -340.793281) (xy 245.814389 -340.796877)
			(xy 245.758952 -340.802977) (xy 245.703218 -340.80094) (xy 245.648375 -340.79081) (xy 245.595591 -340.772803)
			(xy 245.545991 -340.747302) (xy 245.500633 -340.714851) (xy 245.460484 -340.676142) (xy 245.426398 -340.631999)
			(xy 245.399102 -340.583364) (xy 245.379179 -340.531273) (xy 245.367053 -340.476836) (xy 245.362982 -340.421214)
			(xy 241.098692 -340.421214) (xy 241.132872 -340.468259) (xy 241.163666 -340.524274) (xy 241.187198 -340.583707)
			(xy 241.203095 -340.645621) (xy 241.211106 -340.709039) (xy 241.211608 -340.741) (xy 241.211106 -340.772961)
			(xy 241.203095 -340.836379) (xy 241.187198 -340.898293) (xy 241.163666 -340.957726) (xy 241.132872 -341.013741)
			(xy 241.095299 -341.065456) (xy 241.051542 -341.112053) (xy 241.002289 -341.152798) (xy 240.948318 -341.187049)
			(xy 240.890479 -341.214266) (xy 240.829686 -341.234019) (xy 240.766896 -341.245997) (xy 240.7031 -341.250011)
			(xy 240.639304 -341.245997) (xy 240.576514 -341.234019) (xy 240.515721 -341.214266) (xy 240.457882 -341.187049)
			(xy 240.403911 -341.152798) (xy 240.354658 -341.112053) (xy 240.310901 -341.065456) (xy 240.273328 -341.013741)
			(xy 240.242534 -340.957726) (xy 240.219002 -340.898293) (xy 240.203105 -340.836379) (xy 240.195094 -340.772961)
			(xy 234.68734 -340.772961) (xy 234.695853 -340.831341) (xy 234.696508 -340.868) (xy 234.696089 -340.89928)
			(xy 234.688425 -340.961369) (xy 234.673199 -341.022047) (xy 234.650642 -341.080399) (xy 234.621096 -341.135542)
			(xy 234.585005 -341.186642) (xy 234.542917 -341.232928) (xy 234.495468 -341.273699) (xy 234.469686 -341.291418)
			(xy 234.459526 -341.29887) (xy 234.44754 -341.321001) (xy 234.446826 -341.333582) (xy 234.446826 -341.418418)
			(xy 234.447506 -341.431001) (xy 234.459528 -341.45312) (xy 234.469686 -341.460582) (xy 234.495433 -341.478344)
			(xy 234.542861 -341.519124) (xy 234.584932 -341.565411) (xy 234.62101 -341.616508) (xy 234.65055 -341.671642)
			(xy 234.673108 -341.729983) (xy 234.688343 -341.790649) (xy 234.696024 -341.852725) (xy 234.696508 -341.884)
			(xy 234.696044 -341.914731) (xy 234.695895 -341.915961) (xy 240.195094 -341.915961) (xy 240.195094 -341.852039)
			(xy 240.203105 -341.788621) (xy 240.219002 -341.726707) (xy 240.242534 -341.667274) (xy 240.273328 -341.611259)
			(xy 240.310901 -341.559544) (xy 240.354658 -341.512947) (xy 240.403911 -341.472202) (xy 240.457882 -341.437951)
			(xy 240.515721 -341.410734) (xy 240.576514 -341.390981) (xy 240.639304 -341.379003) (xy 240.7031 -341.37499)
			(xy 240.766896 -341.379003) (xy 240.829686 -341.390981) (xy 240.890479 -341.410734) (xy 240.948318 -341.437951)
			(xy 241.002289 -341.472202) (xy 241.051542 -341.512947) (xy 241.095299 -341.559544) (xy 241.132872 -341.611259)
			(xy 241.163666 -341.667274) (xy 241.187198 -341.726707) (xy 241.203095 -341.788621) (xy 241.211106 -341.852039)
			(xy 241.211608 -341.884) (xy 241.211106 -341.915961) (xy 253.326894 -341.915961) (xy 253.326894 -341.852039)
			(xy 253.334905 -341.788621) (xy 253.350802 -341.726707) (xy 253.374334 -341.667274) (xy 253.405128 -341.611259)
			(xy 253.442701 -341.559544) (xy 253.486458 -341.512947) (xy 253.535711 -341.472202) (xy 253.589682 -341.437951)
			(xy 253.647521 -341.410734) (xy 253.708314 -341.390981) (xy 253.771104 -341.379003) (xy 253.8349 -341.37499)
			(xy 253.898696 -341.379003) (xy 253.961486 -341.390981) (xy 254.022279 -341.410734) (xy 254.080118 -341.437951)
			(xy 254.134089 -341.472202) (xy 254.183342 -341.512947) (xy 254.227099 -341.559544) (xy 254.264672 -341.611259)
			(xy 254.295466 -341.667274) (xy 254.318998 -341.726707) (xy 254.334895 -341.788621) (xy 254.342906 -341.852039)
			(xy 254.343408 -341.884) (xy 254.342906 -341.915961) (xy 254.334895 -341.979379) (xy 254.318998 -342.041293)
			(xy 254.295466 -342.100726) (xy 254.264672 -342.156741) (xy 254.227099 -342.208456) (xy 254.183342 -342.255053)
			(xy 254.171318 -342.265) (xy 256.666492 -342.265) (xy 256.666943 -342.233234) (xy 256.674879 -342.1702)
			(xy 256.690604 -342.108644) (xy 256.713873 -342.049526) (xy 256.744322 -341.993767) (xy 256.781479 -341.942233)
			(xy 256.824764 -341.895727) (xy 256.873503 -341.854975) (xy 256.926938 -341.820609) (xy 256.984237 -341.793165)
			(xy 257.014218 -341.782654) (xy 257.024124 -341.779352) (xy 257.039872 -341.765128) (xy 257.079496 -341.678514)
			(xy 257.080004 -341.657432) (xy 257.07594 -341.64778) (xy 257.066915 -341.624723) (xy 257.05424 -341.576859)
			(xy 257.047867 -341.527757) (xy 257.047492 -341.503) (xy 257.04818 -341.469659) (xy 257.059814 -341.403998)
			(xy 257.070606 -341.372444) (xy 257.074162 -341.362792) (xy 257.073146 -341.342726) (xy 257.033014 -341.258652)
			(xy 257.018028 -341.24519) (xy 257.008376 -341.241634) (xy 256.9788 -341.230911) (xy 256.922353 -341.203126)
			(xy 256.869767 -341.168588) (xy 256.821844 -341.127826) (xy 256.779317 -341.081462) (xy 256.742835 -341.030205)
			(xy 256.712957 -340.974838) (xy 256.690139 -340.916208) (xy 256.674729 -340.85521) (xy 256.666964 -340.792777)
			(xy 256.666492 -340.76132) (xy 256.666994 -340.729359) (xy 256.675005 -340.665941) (xy 256.690902 -340.604027)
			(xy 256.714434 -340.544594) (xy 256.745228 -340.488579) (xy 256.782801 -340.436864) (xy 256.826558 -340.390267)
			(xy 256.875811 -340.349522) (xy 256.929782 -340.315271) (xy 256.987621 -340.288054) (xy 257.048414 -340.268301)
			(xy 257.111204 -340.256323) (xy 257.175 -340.25231) (xy 257.238796 -340.256323) (xy 257.301586 -340.268301)
			(xy 257.362379 -340.288054) (xy 257.420218 -340.315271) (xy 257.474189 -340.349522) (xy 257.523442 -340.390267)
			(xy 257.567199 -340.436864) (xy 257.604772 -340.488579) (xy 257.635566 -340.544594) (xy 257.659098 -340.604027)
			(xy 257.674995 -340.665941) (xy 257.683006 -340.729359) (xy 257.683508 -340.76132) (xy 257.683078 -340.790665)
			(xy 257.676329 -340.848967) (xy 257.662911 -340.906103) (xy 257.643003 -340.961314) (xy 257.616869 -341.013865)
			(xy 257.601212 -341.038688) (xy 257.595624 -341.047324) (xy 257.591814 -341.067136) (xy 257.61188 -341.158068)
			(xy 257.623564 -341.174578) (xy 257.6322 -341.180166) (xy 257.655205 -341.195255) (xy 257.697085 -341.230929)
			(xy 257.733404 -341.272251) (xy 257.763407 -341.318363) (xy 257.786472 -341.368308) (xy 257.80212 -341.42105)
			(xy 257.810026 -341.475493) (xy 257.810508 -341.503) (xy 257.809974 -341.531154) (xy 257.80169 -341.58685)
			(xy 257.785319 -341.640726) (xy 257.761213 -341.691613) (xy 257.729896 -341.73841) (xy 257.692047 -341.7801)
			(xy 257.648486 -341.81578) (xy 257.62458 -341.83066) (xy 257.615436 -341.835994) (xy 257.603244 -341.853012)
			(xy 257.582924 -341.94623) (xy 257.586988 -341.966804) (xy 257.593084 -341.975694) (xy 257.61025 -342.001257)
			(xy 257.638915 -342.055755) (xy 257.660798 -342.113312) (xy 257.675579 -342.173089) (xy 257.683042 -342.234212)
			(xy 257.683508 -342.265) (xy 257.683006 -342.296961) (xy 257.674995 -342.360379) (xy 257.659098 -342.422293)
			(xy 257.635566 -342.481726) (xy 257.604772 -342.537741) (xy 257.567199 -342.589456) (xy 257.523442 -342.636053)
			(xy 257.474189 -342.676798) (xy 257.420218 -342.711049) (xy 257.362379 -342.738266) (xy 257.301586 -342.758019)
			(xy 257.238796 -342.769997) (xy 257.175 -342.774011) (xy 257.111204 -342.769997) (xy 257.048414 -342.758019)
			(xy 256.987621 -342.738266) (xy 256.929782 -342.711049) (xy 256.875811 -342.676798) (xy 256.826558 -342.636053)
			(xy 256.782801 -342.589456) (xy 256.745228 -342.537741) (xy 256.714434 -342.481726) (xy 256.690902 -342.422293)
			(xy 256.675005 -342.360379) (xy 256.666994 -342.296961) (xy 256.666492 -342.265) (xy 254.171318 -342.265)
			(xy 254.134089 -342.295798) (xy 254.080118 -342.330049) (xy 254.022279 -342.357266) (xy 253.961486 -342.377019)
			(xy 253.898696 -342.388997) (xy 253.8349 -342.393011) (xy 253.771104 -342.388997) (xy 253.708314 -342.377019)
			(xy 253.647521 -342.357266) (xy 253.589682 -342.330049) (xy 253.535711 -342.295798) (xy 253.486458 -342.255053)
			(xy 253.442701 -342.208456) (xy 253.405128 -342.156741) (xy 253.374334 -342.100726) (xy 253.350802 -342.041293)
			(xy 253.334905 -341.979379) (xy 253.326894 -341.915961) (xy 241.211106 -341.915961) (xy 241.203095 -341.979379)
			(xy 241.187198 -342.041293) (xy 241.163666 -342.100726) (xy 241.132872 -342.156741) (xy 241.095299 -342.208456)
			(xy 241.051542 -342.255053) (xy 241.002289 -342.295798) (xy 240.948318 -342.330049) (xy 240.890479 -342.357266)
			(xy 240.829686 -342.377019) (xy 240.766896 -342.388997) (xy 240.7031 -342.393011) (xy 240.639304 -342.388997)
			(xy 240.576514 -342.377019) (xy 240.515721 -342.357266) (xy 240.457882 -342.330049) (xy 240.403911 -342.295798)
			(xy 240.354658 -342.255053) (xy 240.310901 -342.208456) (xy 240.273328 -342.156741) (xy 240.242534 -342.100726)
			(xy 240.219002 -342.041293) (xy 240.203105 -341.979379) (xy 240.195094 -341.915961) (xy 234.695895 -341.915961)
			(xy 234.688635 -341.975745) (xy 234.673927 -342.035421) (xy 234.652132 -342.092889) (xy 234.623569 -342.147311)
			(xy 234.588655 -342.197893) (xy 234.547898 -342.243898) (xy 234.501893 -342.284655) (xy 234.451311 -342.319569)
			(xy 234.396889 -342.348132) (xy 234.339421 -342.369927) (xy 234.279745 -342.384635) (xy 234.218731 -342.392044)
			(xy 234.188 -342.392508) (xy 234.16417 -342.392249) (xy 234.11672 -342.387795) (xy 234.093258 -342.383618)
			(xy 234.079542 -342.381078) (xy 234.054396 -342.389968) (xy 233.978958 -342.477598) (xy 233.973878 -342.504014)
			(xy 233.97845 -342.516968) (xy 233.988506 -342.547621) (xy 233.999363 -342.611207) (xy 234.00004 -342.64346)
			(xy 233.999588 -342.670717) (xy 233.991835 -342.724676) (xy 233.976482 -342.776983) (xy 233.95384 -342.826573)
			(xy 233.924372 -342.872435) (xy 233.888676 -342.913636) (xy 233.84748 -342.949338) (xy 233.801622 -342.978813)
			(xy 233.752036 -343.001462) (xy 233.699731 -343.016823) (xy 233.645773 -343.024584) (xy 233.591259 -343.024586)
			(xy 233.5373 -343.01683) (xy 233.484994 -343.001473) (xy 233.435406 -342.978829) (xy 233.389546 -342.949357)
			(xy 233.348347 -342.913659) (xy 233.312648 -342.872461) (xy 233.283175 -342.826601) (xy 233.26053 -342.777013)
			(xy 233.245172 -342.724708) (xy 233.237414 -342.670749) (xy 232.547957 -342.670749) (xy 232.525293 -342.689498)
			(xy 232.471322 -342.723749) (xy 232.413483 -342.750966) (xy 232.35269 -342.770719) (xy 232.2899 -342.782697)
			(xy 232.226104 -342.786711) (xy 232.162308 -342.782697) (xy 232.099518 -342.770719) (xy 232.038725 -342.750966)
			(xy 231.980886 -342.723749) (xy 231.926915 -342.689498) (xy 231.877662 -342.648753) (xy 231.833905 -342.602156)
			(xy 231.796332 -342.550441) (xy 231.765538 -342.494426) (xy 231.742006 -342.434993) (xy 231.726109 -342.373079)
			(xy 231.718098 -342.309661) (xy 225.554583 -342.309661) (xy 222.794576 -345.069668) (xy 222.787178 -345.076514)
			(xy 222.768579 -345.084245) (xy 222.758508 -345.084654) (xy 222.084138 -345.084654) (xy 222.074149 -345.085186)
			(xy 222.055712 -345.092896) (xy 222.048324 -345.09964) (xy 221.001887 -346.146077) (xy 243.411496 -346.146077)
			(xy 243.411496 -346.082155) (xy 243.419507 -346.018737) (xy 243.435404 -345.956823) (xy 243.458936 -345.89739)
			(xy 243.48973 -345.841375) (xy 243.527303 -345.78966) (xy 243.57106 -345.743063) (xy 243.620313 -345.702318)
			(xy 243.674284 -345.668067) (xy 243.732123 -345.64085) (xy 243.792916 -345.621097) (xy 243.855706 -345.609119)
			(xy 243.919502 -345.605106) (xy 243.983298 -345.609119) (xy 244.046088 -345.621097) (xy 244.106881 -345.64085)
			(xy 244.16472 -345.668067) (xy 244.218691 -345.702318) (xy 244.267944 -345.743063) (xy 244.311701 -345.78966)
			(xy 244.349274 -345.841375) (xy 244.380068 -345.89739) (xy 244.4036 -345.956823) (xy 244.409541 -345.979961)
			(xy 252.221994 -345.979961) (xy 252.221994 -345.916039) (xy 252.230005 -345.852621) (xy 252.245902 -345.790707)
			(xy 252.269434 -345.731274) (xy 252.300228 -345.675259) (xy 252.337801 -345.623544) (xy 252.381558 -345.576947)
			(xy 252.430811 -345.536202) (xy 252.484782 -345.501951) (xy 252.542621 -345.474734) (xy 252.603414 -345.454981)
			(xy 252.666204 -345.443003) (xy 252.73 -345.43899) (xy 252.793796 -345.443003) (xy 252.856586 -345.454981)
			(xy 252.917379 -345.474734) (xy 252.975218 -345.501951) (xy 253.029189 -345.536202) (xy 253.078442 -345.576947)
			(xy 253.122199 -345.623544) (xy 253.159772 -345.675259) (xy 253.187645 -345.725961) (xy 257.555994 -345.725961)
			(xy 257.555994 -345.662039) (xy 257.564005 -345.598621) (xy 257.579902 -345.536707) (xy 257.603434 -345.477274)
			(xy 257.634228 -345.421259) (xy 257.671801 -345.369544) (xy 257.715558 -345.322947) (xy 257.764811 -345.282202)
			(xy 257.818782 -345.247951) (xy 257.876621 -345.220734) (xy 257.937414 -345.200981) (xy 258.000204 -345.189003)
			(xy 258.064 -345.18499) (xy 258.127796 -345.189003) (xy 258.190586 -345.200981) (xy 258.251379 -345.220734)
			(xy 258.309218 -345.247951) (xy 258.363189 -345.282202) (xy 258.412442 -345.322947) (xy 258.456199 -345.369544)
			(xy 258.493772 -345.421259) (xy 258.524566 -345.477274) (xy 258.548098 -345.536707) (xy 258.563995 -345.598621)
			(xy 258.572006 -345.662039) (xy 258.572508 -345.694) (xy 258.572006 -345.725961) (xy 258.563995 -345.789379)
			(xy 258.548098 -345.851293) (xy 258.524566 -345.910726) (xy 258.493772 -345.966741) (xy 258.456199 -346.018456)
			(xy 258.412442 -346.065053) (xy 258.363189 -346.105798) (xy 258.309218 -346.140049) (xy 258.251379 -346.167266)
			(xy 258.190586 -346.187019) (xy 258.127796 -346.198997) (xy 258.064 -346.203011) (xy 258.000204 -346.198997)
			(xy 257.937414 -346.187019) (xy 257.876621 -346.167266) (xy 257.818782 -346.140049) (xy 257.764811 -346.105798)
			(xy 257.715558 -346.065053) (xy 257.671801 -346.018456) (xy 257.634228 -345.966741) (xy 257.603434 -345.910726)
			(xy 257.579902 -345.851293) (xy 257.564005 -345.789379) (xy 257.555994 -345.725961) (xy 253.187645 -345.725961)
			(xy 253.190566 -345.731274) (xy 253.214098 -345.790707) (xy 253.229995 -345.852621) (xy 253.238006 -345.916039)
			(xy 253.238508 -345.948) (xy 253.238006 -345.979961) (xy 253.229995 -346.043379) (xy 253.214098 -346.105293)
			(xy 253.190566 -346.164726) (xy 253.159772 -346.220741) (xy 253.122199 -346.272456) (xy 253.078442 -346.319053)
			(xy 253.029189 -346.359798) (xy 252.975218 -346.394049) (xy 252.917379 -346.421266) (xy 252.856586 -346.441019)
			(xy 252.793796 -346.452997) (xy 252.73 -346.457011) (xy 252.666204 -346.452997) (xy 252.603414 -346.441019)
			(xy 252.542621 -346.421266) (xy 252.484782 -346.394049) (xy 252.430811 -346.359798) (xy 252.381558 -346.319053)
			(xy 252.337801 -346.272456) (xy 252.300228 -346.220741) (xy 252.269434 -346.164726) (xy 252.245902 -346.105293)
			(xy 252.230005 -346.043379) (xy 252.221994 -345.979961) (xy 244.409541 -345.979961) (xy 244.419497 -346.018737)
			(xy 244.427508 -346.082155) (xy 244.42801 -346.114116) (xy 244.427508 -346.146077) (xy 244.419497 -346.209495)
			(xy 244.4036 -346.271409) (xy 244.380068 -346.330842) (xy 244.349274 -346.386857) (xy 244.311701 -346.438572)
			(xy 244.267944 -346.485169) (xy 244.218691 -346.525914) (xy 244.16472 -346.560165) (xy 244.106881 -346.587382)
			(xy 244.046088 -346.607135) (xy 243.983298 -346.619113) (xy 243.919502 -346.623127) (xy 243.855706 -346.619113)
			(xy 243.792916 -346.607135) (xy 243.732123 -346.587382) (xy 243.674284 -346.560165) (xy 243.620313 -346.525914)
			(xy 243.57106 -346.485169) (xy 243.527303 -346.438572) (xy 243.48973 -346.386857) (xy 243.458936 -346.330842)
			(xy 243.435404 -346.271409) (xy 243.419507 -346.209495) (xy 243.411496 -346.146077) (xy 221.001887 -346.146077)
			(xy 216.362026 -350.785938) (xy 216.355218 -350.793284) (xy 216.347496 -350.811747) (xy 216.34704 -350.821752)
			(xy 216.34704 -352.49993) (xy 231.378258 -352.49993) (xy 231.382272 -352.294246) (xy 231.394308 -352.088876)
			(xy 231.414347 -351.884132) (xy 231.44236 -351.680325) (xy 231.478303 -351.477766) (xy 231.522122 -351.276764)
			(xy 231.573749 -351.077625) (xy 231.633107 -350.880652) (xy 231.700105 -350.686144) (xy 231.774641 -350.494399)
			(xy 231.856601 -350.305708) (xy 231.945861 -350.120358) (xy 232.042284 -349.938632) (xy 232.145725 -349.760806)
			(xy 232.256024 -349.587152) (xy 232.373015 -349.417933) (xy 232.496519 -349.253407) (xy 232.626348 -349.093826)
			(xy 232.762305 -348.939431) (xy 232.904182 -348.790459) (xy 233.051763 -348.647135) (xy 233.204824 -348.509679)
			(xy 233.363131 -348.378299) (xy 233.526444 -348.253196) (xy 233.694513 -348.134559) (xy 233.867083 -348.022571)
			(xy 234.043891 -347.9174) (xy 234.224668 -347.819209) (xy 234.409138 -347.728145) (xy 234.59702 -347.644348)
			(xy 234.78803 -347.567945) (xy 234.981874 -347.499052) (xy 235.178259 -347.437775) (xy 235.376885 -347.384207)
			(xy 235.57745 -347.33843) (xy 235.779648 -347.300512) (xy 235.983172 -347.270513) (xy 236.187711 -347.248476)
			(xy 236.392954 -347.234437) (xy 236.598589 -347.228417) (xy 236.804302 -347.230424) (xy 237.00978 -347.240456)
			(xy 237.21471 -347.258497) (xy 237.41878 -347.28452) (xy 237.62168 -347.318485) (xy 237.8231 -347.36034)
			(xy 238.022733 -347.410022) (xy 238.199722 -347.46148) (xy 252.348098 -347.46148) (xy 252.353307 -347.398614)
			(xy 252.366253 -347.336874) (xy 252.386736 -347.27721) (xy 252.414441 -347.220538) (xy 252.448944 -347.167728)
			(xy 252.489714 -347.119591) (xy 252.536125 -347.076866) (xy 252.587464 -347.040211) (xy 252.642943 -347.010187)
			(xy 252.70171 -346.987256) (xy 252.762861 -346.97177) (xy 252.825459 -346.963968) (xy 252.857 -346.963492)
			(xy 252.878082 -346.964) (xy 252.889004 -346.964508) (xy 252.908562 -346.956888) (xy 252.976888 -346.888562)
			(xy 252.984508 -346.869004) (xy 252.984 -346.858082) (xy 252.983492 -346.837) (xy 252.983968 -346.805459)
			(xy 252.99177 -346.742861) (xy 253.007256 -346.68171) (xy 253.030187 -346.622943) (xy 253.060211 -346.567464)
			(xy 253.096866 -346.516125) (xy 253.139591 -346.469714) (xy 253.187728 -346.428944) (xy 253.240538 -346.394441)
			(xy 253.29721 -346.366736) (xy 253.356874 -346.346253) (xy 253.418614 -346.333307) (xy 253.48148 -346.328098)
			(xy 253.544509 -346.330705) (xy 253.60673 -346.341088) (xy 253.66719 -346.359088) (xy 253.724959 -346.384427)
			(xy 253.77915 -346.416718) (xy 253.82893 -346.455464) (xy 253.873536 -346.50007) (xy 253.912282 -346.54985)
			(xy 253.944573 -346.604041) (xy 253.969912 -346.66181) (xy 253.987912 -346.72227) (xy 253.998295 -346.784491)
			(xy 254.000902 -346.84752) (xy 253.995693 -346.910386) (xy 253.982747 -346.972126) (xy 253.962264 -347.03179)
			(xy 253.934559 -347.088462) (xy 253.900056 -347.141272) (xy 253.859286 -347.189409) (xy 253.812875 -347.232134)
			(xy 253.761536 -347.268789) (xy 253.706057 -347.298813) (xy 253.64729 -347.321744) (xy 253.586139 -347.33723)
			(xy 253.523541 -347.345032) (xy 253.492 -347.345508) (xy 253.470918 -347.345) (xy 253.459996 -347.344492)
			(xy 253.440438 -347.352112) (xy 253.372112 -347.420438) (xy 253.364492 -347.439996) (xy 253.365 -347.450918)
			(xy 253.365508 -347.472) (xy 253.365032 -347.503541) (xy 253.35723 -347.566139) (xy 253.341744 -347.62729)
			(xy 253.318813 -347.686057) (xy 253.288789 -347.741536) (xy 253.252134 -347.792875) (xy 253.209409 -347.839286)
			(xy 253.161272 -347.880056) (xy 253.108462 -347.914559) (xy 253.05179 -347.942264) (xy 252.992126 -347.962747)
			(xy 252.930386 -347.975693) (xy 252.86752 -347.980902) (xy 252.804491 -347.978295) (xy 252.74227 -347.967912)
			(xy 252.68181 -347.949912) (xy 252.624041 -347.924573) (xy 252.56985 -347.892282) (xy 252.52007 -347.853536)
			(xy 252.475464 -347.80893) (xy 252.436718 -347.75915) (xy 252.404427 -347.704959) (xy 252.379088 -347.64719)
			(xy 252.361088 -347.58673) (xy 252.350705 -347.524509) (xy 252.348098 -347.46148) (xy 238.199722 -347.46148)
			(xy 238.220276 -347.467456) (xy 238.415428 -347.532553) (xy 238.607892 -347.605214) (xy 238.797374 -347.68533)
			(xy 238.983585 -347.772777) (xy 239.166244 -347.867423) (xy 239.34507 -347.969123) (xy 239.519792 -348.077723)
			(xy 239.690145 -348.193058) (xy 239.855867 -348.314951) (xy 240.016708 -348.443217) (xy 240.172421 -348.57766)
			(xy 240.322771 -348.718077) (xy 240.467528 -348.864253) (xy 240.606471 -349.015965) (xy 240.739389 -349.172983)
			(xy 240.86608 -349.335068) (xy 240.98635 -349.501971) (xy 241.100017 -349.673441) (xy 241.206907 -349.849214)
			(xy 241.306858 -350.029024) (xy 241.399717 -350.212597) (xy 241.485344 -350.399653) (xy 241.563606 -350.589908)
			(xy 241.634387 -350.783071) (xy 241.697577 -350.978849) (xy 241.75308 -351.176943) (xy 241.800812 -351.377052)
			(xy 241.840701 -351.57887) (xy 241.872685 -351.782092) (xy 241.896715 -351.986406) (xy 241.912756 -352.191502)
			(xy 241.920782 -352.397069) (xy 241.921284 -352.49993) (xy 241.920782 -352.602791) (xy 241.912756 -352.808358)
			(xy 241.896715 -353.013454) (xy 241.872685 -353.217768) (xy 241.840701 -353.42099) (xy 241.800812 -353.622808)
			(xy 241.75308 -353.822917) (xy 241.697577 -354.021011) (xy 241.634387 -354.216789) (xy 241.563606 -354.409952)
			(xy 241.485344 -354.600207) (xy 241.399717 -354.787263) (xy 241.306858 -354.970836) (xy 241.206907 -355.150646)
			(xy 241.100017 -355.326419) (xy 240.98635 -355.497889) (xy 240.86608 -355.664792) (xy 240.739389 -355.826877)
			(xy 240.606471 -355.983895) (xy 240.467528 -356.135607) (xy 240.322771 -356.281783) (xy 240.172421 -356.4222)
			(xy 240.016708 -356.556643) (xy 239.855867 -356.684909) (xy 239.690145 -356.806802) (xy 239.519792 -356.922137)
			(xy 239.34507 -357.030737) (xy 239.166244 -357.132437) (xy 238.983585 -357.227083) (xy 238.797374 -357.31453)
			(xy 238.607892 -357.394646) (xy 238.415428 -357.467307) (xy 238.220276 -357.532404) (xy 238.022733 -357.589838)
			(xy 237.8231 -357.63952) (xy 237.62168 -357.681375) (xy 237.41878 -357.71534) (xy 237.21471 -357.741363)
			(xy 237.00978 -357.759404) (xy 236.804302 -357.769436) (xy 236.598589 -357.771443) (xy 236.392954 -357.765423)
			(xy 236.187711 -357.751384) (xy 235.983172 -357.729347) (xy 235.779648 -357.699348) (xy 235.57745 -357.66143)
			(xy 235.376885 -357.615653) (xy 235.178259 -357.562085) (xy 234.981874 -357.500808) (xy 234.78803 -357.431915)
			(xy 234.59702 -357.355512) (xy 234.409138 -357.271715) (xy 234.224668 -357.180651) (xy 234.043891 -357.08246)
			(xy 233.867083 -356.977289) (xy 233.694513 -356.865301) (xy 233.526444 -356.746664) (xy 233.363131 -356.621561)
			(xy 233.204824 -356.490181) (xy 233.051763 -356.352725) (xy 232.904182 -356.209401) (xy 232.762305 -356.060429)
			(xy 232.626348 -355.906034) (xy 232.496519 -355.746453) (xy 232.373015 -355.581927) (xy 232.256024 -355.412708)
			(xy 232.145725 -355.239054) (xy 232.042284 -355.061228) (xy 231.945861 -354.879502) (xy 231.856601 -354.694152)
			(xy 231.774641 -354.505461) (xy 231.700105 -354.313716) (xy 231.633107 -354.119208) (xy 231.573749 -353.922235)
			(xy 231.522122 -353.723096) (xy 231.478303 -353.522094) (xy 231.44236 -353.319535) (xy 231.414347 -353.115728)
			(xy 231.394308 -352.910984) (xy 231.382272 -352.705614) (xy 231.378258 -352.49993) (xy 216.34704 -352.49993)
			(xy 216.34704 -354.488496) (xy 216.347464 -354.498566) (xy 216.355181 -354.517167) (xy 216.362026 -354.524564)
			(xy 216.763854 -354.926392) (xy 216.772236 -354.930202) (xy 216.877529 -354.978297) (xy 217.08496 -355.08111)
			(xy 217.288537 -355.191356) (xy 217.487995 -355.308891) (xy 217.683072 -355.433562) (xy 217.873513 -355.565206)
			(xy 218.05907 -355.703649) (xy 218.239499 -355.848712) (xy 218.414565 -356.000204) (xy 218.584038 -356.157928)
			(xy 218.747698 -356.321677) (xy 218.905329 -356.491236) (xy 219.056725 -356.666384) (xy 219.20169 -356.846893)
			(xy 219.340032 -357.032525) (xy 219.471571 -357.223038) (xy 219.596136 -357.418184) (xy 219.713562 -357.617705)
			(xy 219.823697 -357.821343) (xy 219.926397 -358.02883) (xy 219.974414 -358.134158) (xy 219.974414 -358.252014)
			(xy 221.738698 -358.252014) (xy 221.739177 -358.220503) (xy 221.74697 -358.157963) (xy 221.762426 -358.096865)
			(xy 221.785308 -358.038142) (xy 221.815266 -357.982695) (xy 221.851841 -357.931371) (xy 221.87281 -357.907844)
			(xy 221.87916 -357.900986) (xy 221.886018 -357.883714) (xy 221.887542 -357.797354) (xy 221.881192 -357.779828)
			(xy 221.874842 -357.772716) (xy 221.855455 -357.749586) (xy 221.82173 -357.699531) (xy 221.794164 -357.645838)
			(xy 221.773144 -357.589261) (xy 221.758966 -357.530594) (xy 221.751827 -357.470662) (xy 221.751398 -357.440484)
			(xy 221.7519 -357.408523) (xy 221.759911 -357.345105) (xy 221.775808 -357.283191) (xy 221.79934 -357.223758)
			(xy 221.830134 -357.167743) (xy 221.867707 -357.116028) (xy 221.911464 -357.069431) (xy 221.960717 -357.028686)
			(xy 222.014688 -356.994435) (xy 222.072527 -356.967218) (xy 222.13332 -356.947465) (xy 222.19611 -356.935487)
			(xy 222.259906 -356.931474) (xy 222.323702 -356.935487) (xy 222.386492 -356.947465) (xy 222.447285 -356.967218)
			(xy 222.505124 -356.994435) (xy 222.559095 -357.028686) (xy 222.608348 -357.069431) (xy 222.652105 -357.116028)
			(xy 222.689678 -357.167743) (xy 222.720472 -357.223758) (xy 222.744004 -357.283191) (xy 222.759901 -357.345105)
			(xy 222.767912 -357.408523) (xy 222.768414 -357.440484) (xy 222.76793 -357.471995) (xy 222.760138 -357.534534)
			(xy 222.744683 -357.595633) (xy 222.721802 -357.654355) (xy 222.691845 -357.709803) (xy 222.65527 -357.761127)
			(xy 222.634302 -357.784654) (xy 222.627952 -357.791512) (xy 222.621094 -357.808784) (xy 222.61957 -357.895144)
			(xy 222.62592 -357.91267) (xy 222.63227 -357.919782) (xy 222.651658 -357.942911) (xy 222.685382 -357.992967)
			(xy 222.712948 -358.04666) (xy 222.733967 -358.103237) (xy 222.748146 -358.161904) (xy 222.755285 -358.221836)
			(xy 222.755714 -358.252014) (xy 222.755212 -358.283975) (xy 222.747201 -358.347393) (xy 222.731304 -358.409307)
			(xy 222.707772 -358.46874) (xy 222.676978 -358.524755) (xy 222.639405 -358.57647) (xy 222.595648 -358.623067)
			(xy 222.546395 -358.663812) (xy 222.492424 -358.698063) (xy 222.434585 -358.72528) (xy 222.373792 -358.745033)
			(xy 222.311002 -358.757011) (xy 222.247206 -358.761025) (xy 222.18341 -358.757011) (xy 222.12062 -358.745033)
			(xy 222.059827 -358.72528) (xy 222.001988 -358.698063) (xy 221.948017 -358.663812) (xy 221.898764 -358.623067)
			(xy 221.855007 -358.57647) (xy 221.817434 -358.524755) (xy 221.78664 -358.46874) (xy 221.763108 -358.409307)
			(xy 221.747211 -358.347393) (xy 221.7392 -358.283975) (xy 221.738698 -358.252014) (xy 219.974414 -358.252014)
			(xy 219.974414 -361.118404) (xy 223.844358 -361.118404) (xy 223.84477 -361.08805) (xy 223.851988 -361.027774)
			(xy 223.866332 -360.968786) (xy 223.8876 -360.911927) (xy 223.915488 -360.858005) (xy 223.9496 -360.807788)
			(xy 223.989449 -360.761991) (xy 224.034468 -360.721265) (xy 224.058988 -360.703368) (xy 224.068894 -360.69651)
			(xy 224.08007 -360.675682) (xy 224.082864 -360.569764) (xy 224.072704 -360.548428) (xy 224.063052 -360.540808)
			(xy 224.037629 -360.520103) (xy 223.991832 -360.47318) (xy 223.952446 -360.42076) (xy 223.920124 -360.363713)
			(xy 223.895403 -360.302984) (xy 223.878691 -360.239582) (xy 223.870268 -360.174558) (xy 223.869758 -360.141774)
			(xy 223.87026 -360.109813) (xy 223.878271 -360.046395) (xy 223.894168 -359.984481) (xy 223.9177 -359.925048)
			(xy 223.948494 -359.869033) (xy 223.986067 -359.817318) (xy 224.029824 -359.770721) (xy 224.079077 -359.729976)
			(xy 224.133048 -359.695725) (xy 224.190887 -359.668508) (xy 224.25168 -359.648755) (xy 224.31447 -359.636777)
			(xy 224.378266 -359.632764) (xy 224.442062 -359.636777) (xy 224.504852 -359.648755) (xy 224.565645 -359.668508)
			(xy 224.623484 -359.695725) (xy 224.677455 -359.729976) (xy 224.726708 -359.770721) (xy 224.770465 -359.817318)
			(xy 224.808038 -359.869033) (xy 224.838832 -359.925048) (xy 224.862364 -359.984481) (xy 224.878261 -360.046395)
			(xy 224.886272 -360.109813) (xy 224.886774 -360.141774) (xy 224.886332 -360.172127) (xy 224.879117 -360.232401)
			(xy 224.864776 -360.291388) (xy 224.843512 -360.348247) (xy 224.815628 -360.402168) (xy 224.781521 -360.452386)
			(xy 224.741677 -360.498184) (xy 224.696661 -360.538911) (xy 224.672144 -360.55681) (xy 224.662238 -360.563668)
			(xy 224.651062 -360.584496) (xy 224.648268 -360.690414) (xy 224.658428 -360.71175) (xy 224.66808 -360.71937)
			(xy 224.693499 -360.740079) (xy 224.716918 -360.764074) (xy 253.856497 -360.764074) (xy 253.860504 -360.57917)
			(xy 253.872517 -360.394612) (xy 253.892513 -360.210748) (xy 253.920455 -360.027924) (xy 253.956291 -359.846481)
			(xy 253.999953 -359.66676) (xy 254.05136 -359.4891) (xy 254.110414 -359.313834) (xy 254.177005 -359.14129)
			(xy 254.251008 -358.971793) (xy 254.332284 -358.805661) (xy 254.42068 -358.643205) (xy 254.516031 -358.484731)
			(xy 254.618157 -358.330536) (xy 254.726866 -358.18091) (xy 254.841955 -358.036134) (xy 254.963208 -357.896479)
			(xy 255.090397 -357.762208) (xy 255.223282 -357.633572) (xy 255.361616 -357.510813) (xy 255.505137 -357.394163)
			(xy 255.653576 -357.283839) (xy 255.806656 -357.180048) (xy 255.964087 -357.082986) (xy 256.125576 -356.992836)
			(xy 256.290818 -356.909765) (xy 256.459504 -356.83393) (xy 256.631316 -356.765474) (xy 256.805932 -356.704524)
			(xy 256.983025 -356.651197) (xy 257.162262 -356.60559) (xy 257.343306 -356.567791) (xy 257.525817 -356.53787)
			(xy 257.709454 -356.515883) (xy 257.89387 -356.501871) (xy 258.07872 -356.495861) (xy 258.263657 -356.497865)
			(xy 258.448334 -356.507878) (xy 258.632404 -356.525881) (xy 258.81552 -356.551842) (xy 258.997341 -356.58571)
			(xy 259.177524 -356.627422) (xy 259.35573 -356.676901) (xy 259.531626 -356.734053) (xy 259.704881 -356.798771)
			(xy 259.87517 -356.870934) (xy 260.042173 -356.950405) (xy 260.205577 -357.037036) (xy 260.365074 -357.130665)
			(xy 260.520366 -357.231114) (xy 260.671161 -357.338197) (xy 260.817176 -357.451711) (xy 260.958136 -357.571443)
			(xy 261.093777 -357.69717) (xy 261.223845 -357.828654) (xy 261.348095 -357.96565) (xy 261.466293 -358.107899)
			(xy 261.578219 -358.255134) (xy 261.683662 -358.40708) (xy 261.782423 -358.563451) (xy 261.874318 -358.723954)
			(xy 261.959174 -358.888286) (xy 262.036832 -359.056141) (xy 262.107145 -359.227201) (xy 262.169982 -359.401147)
			(xy 262.225226 -359.577652) (xy 262.272771 -359.756384) (xy 262.312529 -359.937008) (xy 262.344426 -360.119185)
			(xy 262.368401 -360.302572) (xy 262.384409 -360.486826) (xy 262.392421 -360.6716) (xy 262.392922 -360.764074)
			(xy 262.392421 -360.856548) (xy 262.384409 -361.041322) (xy 262.368401 -361.225576) (xy 262.344426 -361.408963)
			(xy 262.312529 -361.59114) (xy 262.272771 -361.771764) (xy 262.225226 -361.950496) (xy 262.169982 -362.127001)
			(xy 262.107145 -362.300947) (xy 262.036832 -362.472007) (xy 261.959174 -362.639862) (xy 261.874318 -362.804194)
			(xy 261.782423 -362.964697) (xy 261.753366 -363.010704) (xy 271.47749 -363.010704) (xy 271.481519 -362.919698)
			(xy 271.493576 -362.829404) (xy 271.513566 -362.740529) (xy 271.541332 -362.653769) (xy 271.576658 -362.569802)
			(xy 271.619266 -362.489286) (xy 271.668824 -362.41285) (xy 271.724943 -362.341094) (xy 271.787184 -362.274578)
			(xy 271.855061 -362.213823) (xy 271.928041 -362.159305) (xy 272.005554 -362.111451) (xy 272.086993 -362.070634)
			(xy 272.171721 -362.037175) (xy 272.259075 -362.011334) (xy 272.34837 -361.993316) (xy 272.438908 -361.983259)
			(xy 272.529981 -361.981244) (xy 272.620876 -361.987286) (xy 272.710881 -362.001337) (xy 272.799292 -362.023288)
			(xy 272.885417 -362.052967) (xy 272.968582 -362.090141) (xy 273.048136 -362.13452) (xy 273.123456 -362.185757)
			(xy 273.193954 -362.24345) (xy 273.259076 -362.307147) (xy 273.318314 -362.376351) (xy 273.371204 -362.45052)
			(xy 273.417333 -362.529072) (xy 273.456338 -362.611395) (xy 273.487915 -362.696842) (xy 273.511816 -362.784746)
			(xy 273.527855 -362.874418) (xy 273.535906 -362.965156) (xy 273.53641 -363.010704) (xy 273.535906 -363.056252)
			(xy 273.527855 -363.14699) (xy 273.511816 -363.236662) (xy 273.487915 -363.324566) (xy 273.456338 -363.410013)
			(xy 273.417333 -363.492336) (xy 273.371204 -363.570888) (xy 273.318314 -363.645057) (xy 273.259076 -363.714261)
			(xy 273.193954 -363.777958) (xy 273.123456 -363.835651) (xy 273.048136 -363.886888) (xy 272.968582 -363.931267)
			(xy 272.885417 -363.968441) (xy 272.799292 -363.99812) (xy 272.710881 -364.020071) (xy 272.620876 -364.034122)
			(xy 272.529981 -364.040164) (xy 272.438908 -364.038149) (xy 272.34837 -364.028092) (xy 272.259075 -364.010074)
			(xy 272.171721 -363.984233) (xy 272.086993 -363.950774) (xy 272.005554 -363.909957) (xy 271.928041 -363.862103)
			(xy 271.855061 -363.807585) (xy 271.787184 -363.74683) (xy 271.724943 -363.680314) (xy 271.668824 -363.608558)
			(xy 271.619266 -363.532122) (xy 271.576658 -363.451606) (xy 271.541332 -363.367639) (xy 271.513566 -363.280879)
			(xy 271.493576 -363.192004) (xy 271.481519 -363.10171) (xy 271.47749 -363.010704) (xy 261.753366 -363.010704)
			(xy 261.683662 -363.121068) (xy 261.578219 -363.273014) (xy 261.466293 -363.420249) (xy 261.348095 -363.562498)
			(xy 261.223845 -363.699494) (xy 261.093777 -363.830978) (xy 260.958136 -363.956705) (xy 260.817176 -364.076437)
			(xy 260.671161 -364.189951) (xy 260.629625 -364.219447) (xy 268.260316 -364.219447) (xy 268.260316 -364.155525)
			(xy 268.268327 -364.092107) (xy 268.284224 -364.030193) (xy 268.307756 -363.97076) (xy 268.33855 -363.914745)
			(xy 268.376123 -363.86303) (xy 268.41988 -363.816433) (xy 268.469133 -363.775688) (xy 268.523104 -363.741437)
			(xy 268.580943 -363.71422) (xy 268.641736 -363.694467) (xy 268.704526 -363.682489) (xy 268.768322 -363.678476)
			(xy 268.832118 -363.682489) (xy 268.894908 -363.694467) (xy 268.955701 -363.71422) (xy 269.01354 -363.741437)
			(xy 269.067511 -363.775688) (xy 269.116764 -363.816433) (xy 269.160521 -363.86303) (xy 269.198094 -363.914745)
			(xy 269.228888 -363.97076) (xy 269.25242 -364.030193) (xy 269.268317 -364.092107) (xy 269.276328 -364.155525)
			(xy 269.27683 -364.187486) (xy 269.276328 -364.219447) (xy 269.268317 -364.282865) (xy 269.25242 -364.344779)
			(xy 269.228888 -364.404212) (xy 269.198094 -364.460227) (xy 269.160521 -364.511942) (xy 269.116764 -364.558539)
			(xy 269.067511 -364.599284) (xy 269.01354 -364.633535) (xy 268.955701 -364.660752) (xy 268.894908 -364.680505)
			(xy 268.832118 -364.692483) (xy 268.768322 -364.696497) (xy 268.704526 -364.692483) (xy 268.641736 -364.680505)
			(xy 268.580943 -364.660752) (xy 268.523104 -364.633535) (xy 268.469133 -364.599284) (xy 268.41988 -364.558539)
			(xy 268.376123 -364.511942) (xy 268.33855 -364.460227) (xy 268.307756 -364.404212) (xy 268.284224 -364.344779)
			(xy 268.268327 -364.282865) (xy 268.260316 -364.219447) (xy 260.629625 -364.219447) (xy 260.520366 -364.297034)
			(xy 260.365074 -364.397483) (xy 260.205577 -364.491112) (xy 260.042173 -364.577743) (xy 259.87517 -364.657214)
			(xy 259.704881 -364.729377) (xy 259.531626 -364.794095) (xy 259.35573 -364.851247) (xy 259.177524 -364.900726)
			(xy 258.997341 -364.942438) (xy 258.81552 -364.976306) (xy 258.632404 -365.002267) (xy 258.448334 -365.02027)
			(xy 258.263657 -365.030283) (xy 258.07872 -365.032287) (xy 257.89387 -365.026277) (xy 257.709454 -365.012265)
			(xy 257.525817 -364.990278) (xy 257.343306 -364.960357) (xy 257.162262 -364.922558) (xy 256.983025 -364.876951)
			(xy 256.805932 -364.823624) (xy 256.631316 -364.762674) (xy 256.459504 -364.694218) (xy 256.290818 -364.618383)
			(xy 256.125576 -364.535312) (xy 255.964087 -364.445162) (xy 255.806656 -364.3481) (xy 255.653576 -364.244309)
			(xy 255.505137 -364.133985) (xy 255.361616 -364.017335) (xy 255.223282 -363.894576) (xy 255.090397 -363.76594)
			(xy 254.963208 -363.631669) (xy 254.841955 -363.492014) (xy 254.726866 -363.347238) (xy 254.618157 -363.197612)
			(xy 254.516031 -363.043417) (xy 254.42068 -362.884943) (xy 254.332284 -362.722487) (xy 254.251008 -362.556355)
			(xy 254.177005 -362.386858) (xy 254.110414 -362.214314) (xy 254.05136 -362.039048) (xy 253.999953 -361.861388)
			(xy 253.956291 -361.681667) (xy 253.920455 -361.500224) (xy 253.892513 -361.3174) (xy 253.872517 -361.133536)
			(xy 253.860504 -360.948978) (xy 253.856497 -360.764074) (xy 224.716918 -360.764074) (xy 224.739295 -360.787002)
			(xy 224.77868 -360.839422) (xy 224.811002 -360.896469) (xy 224.835724 -360.957196) (xy 224.852437 -361.020597)
			(xy 224.860863 -361.085621) (xy 224.861374 -361.118404) (xy 224.860872 -361.150365) (xy 224.852861 -361.213783)
			(xy 224.836964 -361.275697) (xy 224.813432 -361.33513) (xy 224.782638 -361.391145) (xy 224.745065 -361.44286)
			(xy 224.701308 -361.489457) (xy 224.652055 -361.530202) (xy 224.598084 -361.564453) (xy 224.540245 -361.59167)
			(xy 224.479452 -361.611423) (xy 224.416662 -361.623401) (xy 224.352866 -361.627415) (xy 224.28907 -361.623401)
			(xy 224.22628 -361.611423) (xy 224.165487 -361.59167) (xy 224.107648 -361.564453) (xy 224.053677 -361.530202)
			(xy 224.004424 -361.489457) (xy 223.960667 -361.44286) (xy 223.923094 -361.391145) (xy 223.8923 -361.33513)
			(xy 223.868768 -361.275697) (xy 223.852871 -361.213783) (xy 223.84486 -361.150365) (xy 223.844358 -361.118404)
			(xy 219.974414 -361.118404) (xy 219.974414 -361.982215) (xy 222.86569 -361.982215) (xy 222.86569 -361.918293)
			(xy 222.873701 -361.854875) (xy 222.889598 -361.792961) (xy 222.91313 -361.733528) (xy 222.943924 -361.677513)
			(xy 222.981497 -361.625798) (xy 223.025254 -361.579201) (xy 223.074507 -361.538456) (xy 223.128478 -361.504205)
			(xy 223.186317 -361.476988) (xy 223.24711 -361.457235) (xy 223.3099 -361.445257) (xy 223.373696 -361.441244)
			(xy 223.437492 -361.445257) (xy 223.500282 -361.457235) (xy 223.561075 -361.476988) (xy 223.618914 -361.504205)
			(xy 223.672885 -361.538456) (xy 223.722138 -361.579201) (xy 223.765895 -361.625798) (xy 223.803468 -361.677513)
			(xy 223.834262 -361.733528) (xy 223.857794 -361.792961) (xy 223.873691 -361.854875) (xy 223.881702 -361.918293)
			(xy 223.882204 -361.950254) (xy 223.881702 -361.982215) (xy 223.873691 -362.045633) (xy 223.857794 -362.107547)
			(xy 223.834262 -362.16698) (xy 223.803468 -362.222995) (xy 223.765895 -362.27471) (xy 223.722138 -362.321307)
			(xy 223.672885 -362.362052) (xy 223.618914 -362.396303) (xy 223.561075 -362.42352) (xy 223.500282 -362.443273)
			(xy 223.437492 -362.455251) (xy 223.373696 -362.459265) (xy 223.3099 -362.455251) (xy 223.24711 -362.443273)
			(xy 223.186317 -362.42352) (xy 223.128478 -362.396303) (xy 223.074507 -362.362052) (xy 223.025254 -362.321307)
			(xy 222.981497 -362.27471) (xy 222.943924 -362.222995) (xy 222.91313 -362.16698) (xy 222.889598 -362.107547)
			(xy 222.873701 -362.045633) (xy 222.86569 -361.982215) (xy 219.974414 -361.982215) (xy 219.974414 -363.602778)
			(xy 224.128838 -363.602778) (xy 224.129307 -363.570652) (xy 224.137415 -363.506913) (xy 224.153486 -363.444703)
			(xy 224.177266 -363.385013) (xy 224.208373 -363.328793) (xy 224.246314 -363.276939) (xy 224.290485 -363.230277)
			(xy 224.34018 -363.189549) (xy 224.39461 -363.155405) (xy 224.452906 -363.128389) (xy 224.514141 -363.108931)
			(xy 224.545652 -363.102652) (xy 224.55505 -363.100874) (xy 224.570798 -363.091222) (xy 224.624138 -363.022642)
			(xy 224.629472 -363.004862) (xy 224.62871 -362.995464) (xy 224.62744 -362.959142) (xy 224.627942 -362.927181)
			(xy 224.635953 -362.863763) (xy 224.65185 -362.801849) (xy 224.675382 -362.742416) (xy 224.706176 -362.686401)
			(xy 224.743749 -362.634686) (xy 224.787506 -362.588089) (xy 224.836759 -362.547344) (xy 224.89073 -362.513093)
			(xy 224.948569 -362.485876) (xy 225.009362 -362.466123) (xy 225.072152 -362.454145) (xy 225.135948 -362.450132)
			(xy 225.199744 -362.454145) (xy 225.262534 -362.466123) (xy 225.323327 -362.485876) (xy 225.381166 -362.513093)
			(xy 225.435137 -362.547344) (xy 225.48439 -362.588089) (xy 225.528147 -362.634686) (xy 225.56572 -362.686401)
			(xy 225.596514 -362.742416) (xy 225.620046 -362.801849) (xy 225.635943 -362.863763) (xy 225.643954 -362.927181)
			(xy 225.644456 -362.959142) (xy 225.643918 -362.991266) (xy 225.63582 -363.055003) (xy 225.619758 -363.117211)
			(xy 225.595987 -363.176901) (xy 225.564887 -363.233121) (xy 225.526953 -363.284976) (xy 225.482789 -363.331639)
			(xy 225.433099 -363.372368) (xy 225.378674 -363.406513) (xy 225.320382 -363.43353) (xy 225.259151 -363.452989)
			(xy 225.227642 -363.459268) (xy 225.218244 -363.461046) (xy 225.202496 -363.470698) (xy 225.149156 -363.539278)
			(xy 225.143822 -363.557058) (xy 225.144584 -363.566456) (xy 225.145854 -363.602778) (xy 225.145683 -363.613657)
			(xy 246.799094 -363.613657) (xy 246.799094 -363.549735) (xy 246.807105 -363.486317) (xy 246.823002 -363.424403)
			(xy 246.846534 -363.36497) (xy 246.877328 -363.308955) (xy 246.914901 -363.25724) (xy 246.958658 -363.210643)
			(xy 247.007911 -363.169898) (xy 247.061882 -363.135647) (xy 247.119721 -363.10843) (xy 247.180514 -363.088677)
			(xy 247.243304 -363.076699) (xy 247.3071 -363.072686) (xy 247.370896 -363.076699) (xy 247.433686 -363.088677)
			(xy 247.494479 -363.10843) (xy 247.552318 -363.135647) (xy 247.606289 -363.169898) (xy 247.655542 -363.210643)
			(xy 247.699299 -363.25724) (xy 247.736872 -363.308955) (xy 247.767666 -363.36497) (xy 247.791198 -363.424403)
			(xy 247.807095 -363.486317) (xy 247.815106 -363.549735) (xy 247.815608 -363.581696) (xy 247.815106 -363.613657)
			(xy 247.807095 -363.677075) (xy 247.791198 -363.738989) (xy 247.767666 -363.798422) (xy 247.736872 -363.854437)
			(xy 247.699299 -363.906152) (xy 247.655542 -363.952749) (xy 247.606289 -363.993494) (xy 247.552318 -364.027745)
			(xy 247.494479 -364.054962) (xy 247.433686 -364.074715) (xy 247.370896 -364.086693) (xy 247.3071 -364.090707)
			(xy 247.243304 -364.086693) (xy 247.180514 -364.074715) (xy 247.119721 -364.054962) (xy 247.061882 -364.027745)
			(xy 247.007911 -363.993494) (xy 246.958658 -363.952749) (xy 246.914901 -363.906152) (xy 246.877328 -363.854437)
			(xy 246.846534 -363.798422) (xy 246.823002 -363.738989) (xy 246.807105 -363.677075) (xy 246.799094 -363.613657)
			(xy 225.145683 -363.613657) (xy 225.145352 -363.634739) (xy 225.137341 -363.698157) (xy 225.121444 -363.760071)
			(xy 225.097912 -363.819504) (xy 225.067118 -363.875519) (xy 225.029545 -363.927234) (xy 224.985788 -363.973831)
			(xy 224.936535 -364.014576) (xy 224.882564 -364.048827) (xy 224.824725 -364.076044) (xy 224.763932 -364.095797)
			(xy 224.701142 -364.107775) (xy 224.637346 -364.111789) (xy 224.57355 -364.107775) (xy 224.51076 -364.095797)
			(xy 224.449967 -364.076044) (xy 224.392128 -364.048827) (xy 224.338157 -364.014576) (xy 224.288904 -363.973831)
			(xy 224.245147 -363.927234) (xy 224.207574 -363.875519) (xy 224.17678 -363.819504) (xy 224.153248 -363.760071)
			(xy 224.137351 -363.698157) (xy 224.12934 -363.634739) (xy 224.128838 -363.602778) (xy 219.974414 -363.602778)
			(xy 219.974414 -366.226459) (xy 220.783373 -366.226459) (xy 220.783373 -366.098741) (xy 220.791393 -365.971275)
			(xy 220.8074 -365.844564) (xy 220.831332 -365.719108) (xy 220.863094 -365.595402) (xy 220.902561 -365.473935)
			(xy 220.949578 -365.355185) (xy 221.003958 -365.239623) (xy 221.065486 -365.127702) (xy 221.133921 -365.019866)
			(xy 221.208992 -364.91654) (xy 221.290403 -364.818132) (xy 221.377832 -364.725029) (xy 221.470935 -364.6376)
			(xy 221.569343 -364.55619) (xy 221.67267 -364.481119) (xy 221.780506 -364.412684) (xy 221.892426 -364.351156)
			(xy 222.007989 -364.296776) (xy 222.126739 -364.24976) (xy 222.248206 -364.210293) (xy 222.371912 -364.178531)
			(xy 222.497368 -364.154599) (xy 222.624079 -364.138592) (xy 222.751545 -364.130573) (xy 222.815404 -364.130082)
			(xy 222.879318 -364.130518) (xy 223.006893 -364.138558) (xy 223.133711 -364.154599) (xy 223.259271 -364.178577)
			(xy 223.383075 -364.210399) (xy 223.504634 -364.249939) (xy 223.623469 -364.297039) (xy 223.739109 -364.351514)
			(xy 223.851096 -364.413148) (xy 223.95899 -364.481699) (xy 224.062362 -364.556894) (xy 224.160804 -364.638436)
			(xy 224.253927 -364.726004) (xy 224.341363 -364.819251) (xy 224.422767 -364.917809) (xy 224.455289 -364.962651)
			(xy 224.819712 -364.962651) (xy 224.819712 -364.898729) (xy 224.827723 -364.835311) (xy 224.84362 -364.773397)
			(xy 224.867152 -364.713964) (xy 224.897946 -364.657949) (xy 224.935519 -364.606234) (xy 224.979276 -364.559637)
			(xy 225.028529 -364.518892) (xy 225.0825 -364.484641) (xy 225.140339 -364.457424) (xy 225.201132 -364.437671)
			(xy 225.263922 -364.425693) (xy 225.327718 -364.42168) (xy 225.391514 -364.425693) (xy 225.454304 -364.437671)
			(xy 225.515097 -364.457424) (xy 225.572936 -364.484641) (xy 225.626907 -364.518892) (xy 225.67616 -364.559637)
			(xy 225.719917 -364.606234) (xy 225.75749 -364.657949) (xy 225.788284 -364.713964) (xy 225.811816 -364.773397)
			(xy 225.827713 -364.835311) (xy 225.835724 -364.898729) (xy 225.836226 -364.93069) (xy 225.835724 -364.962651)
			(xy 225.827713 -365.026069) (xy 225.811816 -365.087983) (xy 225.788284 -365.147416) (xy 225.758996 -365.200692)
			(xy 228.296724 -365.200692) (xy 228.297176 -365.170819) (xy 228.304178 -365.111483) (xy 228.318085 -365.053377)
			(xy 228.338704 -364.997301) (xy 228.365753 -364.944027) (xy 228.398857 -364.89429) (xy 228.417882 -364.871254)
			(xy 228.424933 -364.862133) (xy 228.430715 -364.839839) (xy 228.426188 -364.817256) (xy 228.41966 -364.807754)
			(xy 228.400124 -364.781135) (xy 228.367366 -364.723805) (xy 228.342303 -364.662718) (xy 228.325355 -364.598902)
			(xy 228.316809 -364.533428) (xy 228.316282 -364.500414) (xy 228.316784 -364.468453) (xy 228.324795 -364.405035)
			(xy 228.340692 -364.343121) (xy 228.364224 -364.283688) (xy 228.395018 -364.227673) (xy 228.432591 -364.175958)
			(xy 228.476348 -364.129361) (xy 228.525601 -364.088616) (xy 228.579572 -364.054365) (xy 228.637411 -364.027148)
			(xy 228.698204 -364.007395) (xy 228.760994 -363.995417) (xy 228.82479 -363.991404) (xy 228.888586 -363.995417)
			(xy 228.951376 -364.007395) (xy 229.012169 -364.027148) (xy 229.070008 -364.054365) (xy 229.123979 -364.088616)
			(xy 229.173232 -364.129361) (xy 229.216989 -364.175958) (xy 229.254562 -364.227673) (xy 229.285356 -364.283688)
			(xy 229.308888 -364.343121) (xy 229.324785 -364.405035) (xy 229.332796 -364.468453) (xy 229.333298 -364.500414)
			(xy 229.332844 -364.530287) (xy 229.325842 -364.589622) (xy 229.311935 -364.647728) (xy 229.291316 -364.703804)
			(xy 229.264268 -364.757078) (xy 229.231164 -364.806816) (xy 229.21214 -364.829852) (xy 229.205083 -364.83897)
			(xy 229.199299 -364.861266) (xy 229.203831 -364.88385) (xy 229.210362 -364.893352) (xy 229.229891 -364.919976)
			(xy 229.262652 -364.977304) (xy 229.287718 -365.038389) (xy 229.304667 -365.102205) (xy 229.313213 -365.167678)
			(xy 229.31374 -365.200692) (xy 229.313238 -365.232653) (xy 229.305227 -365.296071) (xy 229.28933 -365.357985)
			(xy 229.265798 -365.417418) (xy 229.235004 -365.473433) (xy 229.197431 -365.525148) (xy 229.153674 -365.571745)
			(xy 229.104421 -365.61249) (xy 229.05045 -365.646741) (xy 228.992611 -365.673958) (xy 228.931818 -365.693711)
			(xy 228.869028 -365.705689) (xy 228.805232 -365.709703) (xy 228.741436 -365.705689) (xy 228.678646 -365.693711)
			(xy 228.617853 -365.673958) (xy 228.560014 -365.646741) (xy 228.506043 -365.61249) (xy 228.45679 -365.571745)
			(xy 228.413033 -365.525148) (xy 228.37546 -365.473433) (xy 228.344666 -365.417418) (xy 228.321134 -365.357985)
			(xy 228.305237 -365.296071) (xy 228.297226 -365.232653) (xy 228.296724 -365.200692) (xy 225.758996 -365.200692)
			(xy 225.75749 -365.203431) (xy 225.719917 -365.255146) (xy 225.67616 -365.301743) (xy 225.626907 -365.342488)
			(xy 225.572936 -365.376739) (xy 225.515097 -365.403956) (xy 225.454304 -365.423709) (xy 225.391514 -365.435687)
			(xy 225.327718 -365.439701) (xy 225.263922 -365.435687) (xy 225.201132 -365.423709) (xy 225.140339 -365.403956)
			(xy 225.0825 -365.376739) (xy 225.028529 -365.342488) (xy 224.979276 -365.301743) (xy 224.935519 -365.255146)
			(xy 224.897946 -365.203431) (xy 224.867152 -365.147416) (xy 224.84362 -365.087983) (xy 224.827723 -365.026069)
			(xy 224.819712 -364.962651) (xy 224.455289 -364.962651) (xy 224.497816 -365.021287) (xy 224.566214 -365.129277)
			(xy 224.62769 -365.241352) (xy 224.682001 -365.357068) (xy 224.705926 -365.416338) (xy 224.708776 -365.423026)
			(xy 224.717693 -365.434505) (xy 224.723452 -365.438944) (xy 224.747454 -365.456904) (xy 224.791499 -365.497574)
			(xy 224.830453 -365.543143) (xy 224.863778 -365.592977) (xy 224.891009 -365.646384) (xy 224.91177 -365.702624)
			(xy 224.925772 -365.760916) (xy 224.932821 -365.820449) (xy 224.933256 -365.850424) (xy 224.932666 -365.886025)
			(xy 224.931243 -365.8961) (xy 230.641412 -365.8961) (xy 230.645426 -365.832306) (xy 230.657404 -365.769518)
			(xy 230.677157 -365.708726) (xy 230.704373 -365.650889) (xy 230.738624 -365.59692) (xy 230.779369 -365.547669)
			(xy 230.825965 -365.503913) (xy 230.877678 -365.466343) (xy 230.933693 -365.43555) (xy 230.993125 -365.412021)
			(xy 231.055037 -365.396126) (xy 231.118454 -365.388116) (xy 231.150414 -365.387636) (xy 231.180288 -365.388082)
			(xy 231.239623 -365.395085) (xy 231.29773 -365.408992) (xy 231.353806 -365.429613) (xy 231.407079 -365.456663)
			(xy 231.456816 -365.489768) (xy 231.479852 -365.508794) (xy 231.487218 -365.51489) (xy 231.50449 -365.520986)
			(xy 231.592374 -365.518192) (xy 231.609392 -365.510826) (xy 231.61625 -365.504222) (xy 231.640051 -365.481821)
			(xy 231.692382 -365.442661) (xy 231.749299 -365.410529) (xy 231.809864 -365.385954) (xy 231.873078 -365.369341)
			(xy 231.9379 -365.360964) (xy 231.97058 -365.360458) (xy 232.002541 -365.361006) (xy 232.065959 -365.369015)
			(xy 232.127874 -365.38491) (xy 232.187308 -365.408439) (xy 232.243324 -365.439232) (xy 232.295039 -365.476804)
			(xy 232.341637 -365.52056) (xy 232.382383 -365.569812) (xy 232.416635 -365.623783) (xy 232.443852 -365.681621)
			(xy 232.463606 -365.742414) (xy 232.475584 -365.805204) (xy 232.479598 -365.869) (xy 232.475584 -365.932796)
			(xy 232.463606 -365.995586) (xy 232.443852 -366.056379) (xy 232.416635 -366.114217) (xy 232.382383 -366.168188)
			(xy 232.341637 -366.21744) (xy 232.295039 -366.261196) (xy 232.243324 -366.298768) (xy 232.187308 -366.329561)
			(xy 232.127874 -366.35309) (xy 232.065959 -366.368985) (xy 232.002541 -366.376994) (xy 231.97058 -366.377474)
			(xy 231.940706 -366.377029) (xy 231.881371 -366.370026) (xy 231.823265 -366.356118) (xy 231.767188 -366.335497)
			(xy 231.713915 -366.308447) (xy 231.664178 -366.275341) (xy 231.641142 -366.256316) (xy 231.633776 -366.25022)
			(xy 231.616504 -366.244124) (xy 231.52862 -366.246918) (xy 231.511602 -366.254284) (xy 231.504744 -366.260888)
			(xy 231.480947 -366.283293) (xy 231.428615 -366.322453) (xy 231.371697 -366.354584) (xy 231.311132 -366.379159)
			(xy 231.247917 -366.395771) (xy 231.183095 -366.404147) (xy 231.150414 -366.404652) (xy 231.118454 -366.404084)
			(xy 231.055037 -366.396074) (xy 230.993125 -366.380179) (xy 230.933693 -366.35665) (xy 230.877678 -366.325857)
			(xy 230.825965 -366.288287) (xy 230.779369 -366.244531) (xy 230.738624 -366.19528) (xy 230.704373 -366.141311)
			(xy 230.677157 -366.083474) (xy 230.657404 -366.022682) (xy 230.645426 -365.959894) (xy 230.641412 -365.8961)
			(xy 224.931243 -365.8961) (xy 224.92271 -365.956528) (xy 224.903009 -366.024951) (xy 224.87395 -366.089953)
			(xy 224.855532 -366.120426) (xy 224.851899 -366.126685) (xy 224.848027 -366.140622) (xy 224.847912 -366.147858)
			(xy 224.847912 -366.16259) (xy 224.847411 -366.225485) (xy 224.839639 -366.351034) (xy 224.824117 -366.475862)
			(xy 224.800906 -366.599491) (xy 224.770094 -366.721448) (xy 224.731798 -366.841266) (xy 224.686166 -366.958487)
			(xy 224.660206 -367.015776) (xy 224.655126 -367.026698) (xy 224.655634 -367.049558) (xy 224.701862 -367.141506)
			(xy 224.719896 -367.155476) (xy 224.73158 -367.158016) (xy 224.749001 -367.161886) (xy 224.783092 -367.172446)
			(xy 224.799652 -367.179098) (xy 224.813114 -367.184686) (xy 224.841308 -367.180114) (xy 224.931986 -367.101628)
			(xy 224.940622 -367.07445) (xy 224.937066 -367.060226) (xy 224.929706 -367.02938) (xy 224.921805 -366.966458)
			(xy 224.921318 -366.93475) (xy 224.921821 -366.903213) (xy 224.929628 -366.840624) (xy 224.945118 -366.779482)
			(xy 224.96805 -366.720725) (xy 224.998075 -366.665255) (xy 225.03473 -366.613926) (xy 225.077452 -366.567524)
			(xy 225.125586 -366.526763) (xy 225.178391 -366.492268) (xy 225.235058 -366.46457) (xy 225.294715 -366.444093)
			(xy 225.356448 -366.431153) (xy 225.419306 -366.425948) (xy 225.482326 -366.428557) (xy 225.544539 -366.438941)
			(xy 225.60499 -366.456941) (xy 225.662751 -366.48228) (xy 225.716934 -366.514568) (xy 225.766707 -366.55331)
			(xy 225.811306 -366.597911) (xy 225.850046 -366.647686) (xy 225.882331 -366.70187) (xy 225.907667 -366.759632)
			(xy 225.925664 -366.820084) (xy 225.936045 -366.882298) (xy 225.938652 -366.945318) (xy 225.933443 -367.008176)
			(xy 225.9219 -367.063231) (xy 271.555712 -367.063231) (xy 271.555712 -366.999309) (xy 271.563723 -366.935891)
			(xy 271.57962 -366.873977) (xy 271.603152 -366.814544) (xy 271.633946 -366.758529) (xy 271.671519 -366.706814)
			(xy 271.715276 -366.660217) (xy 271.764529 -366.619472) (xy 271.8185 -366.585221) (xy 271.876339 -366.558004)
			(xy 271.937132 -366.538251) (xy 271.999922 -366.526273) (xy 272.063718 -366.52226) (xy 272.127514 -366.526273)
			(xy 272.190304 -366.538251) (xy 272.251097 -366.558004) (xy 272.308936 -366.585221) (xy 272.362907 -366.619472)
			(xy 272.41216 -366.660217) (xy 272.455917 -366.706814) (xy 272.49349 -366.758529) (xy 272.524284 -366.814544)
			(xy 272.547816 -366.873977) (xy 272.563713 -366.935891) (xy 272.571724 -366.999309) (xy 272.572226 -367.03127)
			(xy 272.571744 -367.061961) (xy 295.001182 -367.061961) (xy 295.001182 -366.998039) (xy 295.009193 -366.934621)
			(xy 295.02509 -366.872707) (xy 295.048622 -366.813274) (xy 295.079416 -366.757259) (xy 295.116989 -366.705544)
			(xy 295.160746 -366.658947) (xy 295.209999 -366.618202) (xy 295.26397 -366.583951) (xy 295.321809 -366.556734)
			(xy 295.382602 -366.536981) (xy 295.445392 -366.525003) (xy 295.509188 -366.52099) (xy 295.572984 -366.525003)
			(xy 295.635774 -366.536981) (xy 295.696567 -366.556734) (xy 295.754406 -366.583951) (xy 295.808377 -366.618202)
			(xy 295.85763 -366.658947) (xy 295.901387 -366.705544) (xy 295.93896 -366.757259) (xy 295.969754 -366.813274)
			(xy 295.993286 -366.872707) (xy 296.009183 -366.934621) (xy 296.017194 -366.998039) (xy 296.017696 -367.03)
			(xy 296.017194 -367.061961) (xy 296.009183 -367.125379) (xy 295.993286 -367.187293) (xy 295.969754 -367.246726)
			(xy 295.93896 -367.302741) (xy 295.901387 -367.354456) (xy 295.85763 -367.401053) (xy 295.808377 -367.441798)
			(xy 295.754406 -367.476049) (xy 295.696567 -367.503266) (xy 295.635774 -367.523019) (xy 295.572984 -367.534997)
			(xy 295.509188 -367.539011) (xy 295.445392 -367.534997) (xy 295.382602 -367.523019) (xy 295.321809 -367.503266)
			(xy 295.26397 -367.476049) (xy 295.209999 -367.441798) (xy 295.160746 -367.401053) (xy 295.116989 -367.354456)
			(xy 295.079416 -367.302741) (xy 295.048622 -367.246726) (xy 295.02509 -367.187293) (xy 295.009193 -367.125379)
			(xy 295.001182 -367.061961) (xy 272.571744 -367.061961) (xy 272.571724 -367.063231) (xy 272.563713 -367.126649)
			(xy 272.547816 -367.188563) (xy 272.524284 -367.247996) (xy 272.49349 -367.304011) (xy 272.455917 -367.355726)
			(xy 272.41216 -367.402323) (xy 272.362907 -367.443068) (xy 272.308936 -367.477319) (xy 272.251097 -367.504536)
			(xy 272.190304 -367.524289) (xy 272.127514 -367.536267) (xy 272.063718 -367.540281) (xy 271.999922 -367.536267)
			(xy 271.937132 -367.524289) (xy 271.876339 -367.504536) (xy 271.8185 -367.477319) (xy 271.764529 -367.443068)
			(xy 271.715276 -367.402323) (xy 271.671519 -367.355726) (xy 271.633946 -367.304011) (xy 271.603152 -367.247996)
			(xy 271.57962 -367.188563) (xy 271.563723 -367.126649) (xy 271.555712 -367.063231) (xy 225.9219 -367.063231)
			(xy 225.9205 -367.069908) (xy 225.900021 -367.129564) (xy 225.87232 -367.18623) (xy 225.837823 -367.239034)
			(xy 225.797059 -367.287165) (xy 225.750656 -367.329885) (xy 225.699324 -367.366538) (xy 225.643853 -367.39656)
			(xy 225.585095 -367.41949) (xy 225.523952 -367.434976) (xy 225.461363 -367.442781) (xy 225.429826 -367.443258)
			(xy 225.397414 -367.442745) (xy 225.333112 -367.434547) (xy 225.270374 -367.418242) (xy 225.210216 -367.394096)
			(xy 225.181668 -367.378742) (xy 225.168968 -367.37163) (xy 225.14052 -367.372646) (xy 225.041206 -367.44021)
			(xy 225.029522 -367.466372) (xy 225.031554 -367.48085) (xy 225.033121 -367.493427) (xy 225.034771 -367.518722)
			(xy 225.034856 -367.531396) (xy 225.034319 -367.558645) (xy 225.026564 -367.612588) (xy 225.011212 -367.664879)
			(xy 224.988575 -367.714453) (xy 224.959113 -367.760301) (xy 224.923427 -367.80149) (xy 224.882243 -367.837182)
			(xy 224.836399 -367.86665) (xy 224.786828 -367.889294) (xy 224.734539 -367.904653) (xy 224.680597 -367.912415)
			(xy 224.653348 -367.912904) (xy 224.615248 -367.910872) (xy 224.602294 -367.909602) (xy 224.578672 -367.919508)
			(xy 224.509076 -368.006122) (xy 224.506031 -368.021827) (xy 230.498136 -368.021827) (xy 230.498136 -367.957905)
			(xy 230.506147 -367.894487) (xy 230.522044 -367.832573) (xy 230.545576 -367.77314) (xy 230.57637 -367.717125)
			(xy 230.613943 -367.66541) (xy 230.6577 -367.618813) (xy 230.706953 -367.578068) (xy 230.760924 -367.543817)
			(xy 230.818763 -367.5166) (xy 230.879556 -367.496847) (xy 230.942346 -367.484869) (xy 231.006142 -367.480856)
			(xy 231.069938 -367.484869) (xy 231.132728 -367.496847) (xy 231.193521 -367.5166) (xy 231.25136 -367.543817)
			(xy 231.305331 -367.578068) (xy 231.354584 -367.618813) (xy 231.398341 -367.66541) (xy 231.435914 -367.717125)
			(xy 231.466708 -367.77314) (xy 231.49024 -367.832573) (xy 231.502311 -367.879587) (xy 238.016028 -367.879587)
			(xy 238.016028 -367.815665) (xy 238.024039 -367.752247) (xy 238.039936 -367.690333) (xy 238.063468 -367.6309)
			(xy 238.094262 -367.574885) (xy 238.131835 -367.52317) (xy 238.175592 -367.476573) (xy 238.224845 -367.435828)
			(xy 238.278816 -367.401577) (xy 238.336655 -367.37436) (xy 238.397448 -367.354607) (xy 238.460238 -367.342629)
			(xy 238.524034 -367.338616) (xy 238.58783 -367.342629) (xy 238.65062 -367.354607) (xy 238.711413 -367.37436)
			(xy 238.769252 -367.401577) (xy 238.823223 -367.435828) (xy 238.872476 -367.476573) (xy 238.916233 -367.52317)
			(xy 238.953806 -367.574885) (xy 238.9846 -367.6309) (xy 239.008132 -367.690333) (xy 239.024029 -367.752247)
			(xy 239.03204 -367.815665) (xy 239.032542 -367.847626) (xy 239.03204 -367.879587) (xy 239.028896 -367.904479)
			(xy 239.294664 -367.904479) (xy 239.294664 -367.840557) (xy 239.302675 -367.777139) (xy 239.318572 -367.715225)
			(xy 239.342104 -367.655792) (xy 239.372898 -367.599777) (xy 239.410471 -367.548062) (xy 239.454228 -367.501465)
			(xy 239.503481 -367.46072) (xy 239.557452 -367.426469) (xy 239.615291 -367.399252) (xy 239.676084 -367.379499)
			(xy 239.738874 -367.367521) (xy 239.80267 -367.363508) (xy 239.866466 -367.367521) (xy 239.929256 -367.379499)
			(xy 239.990049 -367.399252) (xy 240.047888 -367.426469) (xy 240.101859 -367.46072) (xy 240.151112 -367.501465)
			(xy 240.194869 -367.548062) (xy 240.232442 -367.599777) (xy 240.263236 -367.655792) (xy 240.286768 -367.715225)
			(xy 240.302665 -367.777139) (xy 240.310676 -367.840557) (xy 240.311178 -367.872518) (xy 240.310676 -367.904479)
			(xy 240.310034 -367.909559) (xy 240.592858 -367.909559) (xy 240.592858 -367.845637) (xy 240.600869 -367.782219)
			(xy 240.616766 -367.720305) (xy 240.640298 -367.660872) (xy 240.671092 -367.604857) (xy 240.708665 -367.553142)
			(xy 240.752422 -367.506545) (xy 240.801675 -367.4658) (xy 240.855646 -367.431549) (xy 240.913485 -367.404332)
			(xy 240.974278 -367.384579) (xy 241.037068 -367.372601) (xy 241.100864 -367.368588) (xy 241.16466 -367.372601)
			(xy 241.22745 -367.384579) (xy 241.288243 -367.404332) (xy 241.346082 -367.431549) (xy 241.400053 -367.4658)
			(xy 241.449306 -367.506545) (xy 241.493063 -367.553142) (xy 241.530636 -367.604857) (xy 241.56143 -367.660872)
			(xy 241.584962 -367.720305) (xy 241.600859 -367.782219) (xy 241.60887 -367.845637) (xy 241.609253 -367.87)
			(xy 241.944346 -367.87) (xy 241.948361 -367.806198) (xy 241.96034 -367.743401) (xy 241.980095 -367.682602)
			(xy 242.007315 -367.624758) (xy 242.04157 -367.570781) (xy 242.082321 -367.521524) (xy 242.128923 -367.477763)
			(xy 242.180643 -367.440187) (xy 242.236665 -367.40939) (xy 242.296104 -367.385858) (xy 242.358025 -367.369961)
			(xy 242.42145 -367.36195) (xy 242.453414 -367.36147) (xy 242.483827 -367.361886) (xy 242.54422 -367.36914)
			(xy 242.603316 -367.383544) (xy 242.660274 -367.404891) (xy 242.71428 -367.432878) (xy 242.764564 -367.467104)
			(xy 242.810407 -367.507082) (xy 242.831112 -367.529364) (xy 242.838732 -367.538) (xy 242.860322 -367.54689)
			(xy 242.963446 -367.540032) (xy 242.983766 -367.528348) (xy 242.99037 -367.518696) (xy 243.008192 -367.493534)
			(xy 243.04894 -367.447258) (xy 243.094987 -367.40625) (xy 243.145657 -367.371115) (xy 243.200205 -367.342367)
			(xy 243.257831 -367.320429) (xy 243.317687 -367.305623) (xy 243.378894 -367.298167) (xy 243.409724 -367.297716)
			(xy 243.44012 -367.298167) (xy 243.500477 -367.305421) (xy 243.559538 -367.319823) (xy 243.61646 -367.341167)
			(xy 243.67043 -367.369148) (xy 243.720676 -367.403366) (xy 243.766482 -367.443334) (xy 243.787168 -367.46561)
			(xy 243.793772 -367.472722) (xy 243.81079 -367.481358) (xy 243.899182 -367.488978) (xy 243.91747 -367.483644)
			(xy 243.92509 -367.477548) (xy 243.951986 -367.457257) (xy 244.010132 -367.423222) (xy 244.072263 -367.397163)
			(xy 244.137291 -367.379536) (xy 244.204077 -367.370648) (xy 244.237764 -367.370106) (xy 244.269039 -367.370578)
			(xy 244.331121 -367.378211) (xy 244.391797 -367.393403) (xy 244.450151 -367.415924) (xy 244.505301 -367.445434)
			(xy 244.531134 -367.46307) (xy 244.538529 -367.467919) (xy 244.555573 -367.472598) (xy 244.564408 -367.472214)
			(xy 244.59438 -367.469928) (xy 244.603224 -367.468816) (xy 244.61936 -367.461277) (xy 244.625876 -367.455196)
			(xy 244.649781 -367.43231) (xy 244.702454 -367.392246) (xy 244.759881 -367.359357) (xy 244.821092 -367.3342)
			(xy 244.885049 -367.3172) (xy 244.950673 -367.308645) (xy 244.983762 -367.30813) (xy 245.012775 -367.308551)
			(xy 245.070423 -367.315162) (xy 245.126944 -367.328289) (xy 245.181604 -367.347763) (xy 245.233693 -367.37333)
			(xy 245.258336 -367.388648) (xy 245.267259 -367.393737) (xy 245.287502 -367.39711) (xy 245.307461 -367.392333)
			(xy 245.315994 -367.386616) (xy 245.342342 -367.367731) (xy 245.398921 -367.336088) (xy 245.459064 -367.311895)
			(xy 245.521794 -367.295545) (xy 245.586095 -367.287303) (xy 245.618508 -367.286794) (xy 245.652845 -367.287357)
			(xy 245.720894 -367.2966) (xy 245.78708 -367.314918) (xy 245.850199 -367.341977) (xy 245.909101 -367.377284)
			(xy 245.936262 -367.3983) (xy 245.945719 -367.405067) (xy 245.968411 -367.410033) (xy 245.990979 -367.40453)
			(xy 246.00027 -367.397538) (xy 246.023155 -367.379078) (xy 246.072409 -367.346968) (xy 246.12504 -367.320756)
			(xy 246.180344 -367.300793) (xy 246.237583 -367.287345) (xy 246.295991 -367.280593) (xy 246.32539 -367.28019)
			(xy 246.357353 -367.280674) (xy 246.420774 -367.288685) (xy 246.482691 -367.304582) (xy 246.542128 -367.328113)
			(xy 246.598146 -367.358909) (xy 246.649863 -367.396482) (xy 246.696463 -367.440242) (xy 246.737211 -367.489497)
			(xy 246.771464 -367.54347) (xy 246.798683 -367.601312) (xy 246.818437 -367.662108) (xy 246.830416 -367.724901)
			(xy 246.83443 -367.7887) (xy 246.830416 -367.852499) (xy 246.818437 -367.915292) (xy 246.798683 -367.976088)
			(xy 246.771464 -368.03393) (xy 246.737211 -368.087903) (xy 246.696463 -368.137158) (xy 246.649863 -368.180918)
			(xy 246.598146 -368.218491) (xy 246.542128 -368.249287) (xy 246.482691 -368.272818) (xy 246.420774 -368.288715)
			(xy 246.357353 -368.296726) (xy 246.32539 -368.297206) (xy 246.291053 -368.296645) (xy 246.223004 -368.287401)
			(xy 246.156818 -368.269083) (xy 246.093699 -368.242023) (xy 246.034797 -368.206716) (xy 246.007636 -368.1857)
			(xy 245.99818 -368.178932) (xy 245.975488 -368.173966) (xy 245.952919 -368.179469) (xy 245.943628 -368.186462)
			(xy 245.920744 -368.204923) (xy 245.87149 -368.237033) (xy 245.818858 -368.263245) (xy 245.763554 -368.283208)
			(xy 245.706315 -368.296655) (xy 245.647907 -368.303407) (xy 245.618508 -368.30381) (xy 245.589495 -368.303397)
			(xy 245.531847 -368.296784) (xy 245.475326 -368.283654) (xy 245.420666 -368.264179) (xy 245.368577 -368.23861)
			(xy 245.343934 -368.223292) (xy 245.335021 -368.218184) (xy 245.314772 -368.214824) (xy 245.294811 -368.219607)
			(xy 245.286276 -368.225324) (xy 245.25991 -368.244183) (xy 245.203336 -368.27583) (xy 245.143198 -368.300027)
			(xy 245.080471 -368.316383) (xy 245.016174 -368.324632) (xy 244.983762 -368.325146) (xy 244.952487 -368.32467)
			(xy 244.890405 -368.317039) (xy 244.829729 -368.301849) (xy 244.771374 -368.279328) (xy 244.716224 -368.249818)
			(xy 244.690392 -368.232182) (xy 244.682987 -368.227349) (xy 244.665951 -368.222659) (xy 244.657118 -368.223038)
			(xy 244.627146 -368.225324) (xy 244.618293 -368.226389) (xy 244.602159 -368.23396) (xy 244.59565 -368.240056)
			(xy 244.57177 -368.262969) (xy 244.519092 -368.303031) (xy 244.46166 -368.335918) (xy 244.400444 -368.36107)
			(xy 244.336482 -368.378064) (xy 244.270855 -368.386612) (xy 244.237764 -368.387122) (xy 244.207368 -368.386667)
			(xy 244.147012 -368.379412) (xy 244.087951 -368.36501) (xy 244.03103 -368.343666) (xy 243.97706 -368.315686)
			(xy 243.926813 -368.281469) (xy 243.881007 -368.241503) (xy 243.86032 -368.219228) (xy 243.853716 -368.212116)
			(xy 243.836698 -368.20348) (xy 243.748306 -368.19586) (xy 243.730018 -368.201194) (xy 243.722398 -368.20729)
			(xy 243.69551 -368.227592) (xy 243.637361 -368.261623) (xy 243.575228 -368.28768) (xy 243.510199 -368.305305)
			(xy 243.443412 -368.31419) (xy 243.409724 -368.314732) (xy 243.379311 -368.314289) (xy 243.31892 -368.307039)
			(xy 243.259824 -368.29264) (xy 243.202867 -368.271297) (xy 243.14886 -368.243315) (xy 243.098576 -368.209092)
			(xy 243.052731 -368.169118) (xy 243.032026 -368.146838) (xy 243.024406 -368.138202) (xy 243.002816 -368.129312)
			(xy 242.899692 -368.13617) (xy 242.879372 -368.147854) (xy 242.872768 -368.157506) (xy 242.854987 -368.182697)
			(xy 242.814232 -368.228973) (xy 242.768179 -368.269979) (xy 242.717503 -368.305112) (xy 242.662949 -368.333856)
			(xy 242.605318 -368.355789) (xy 242.545457 -368.37059) (xy 242.484246 -368.378039) (xy 242.453414 -368.378486)
			(xy 242.42145 -368.37805) (xy 242.358025 -368.370039) (xy 242.296104 -368.354142) (xy 242.236665 -368.33061)
			(xy 242.180643 -368.299813) (xy 242.128923 -368.262237) (xy 242.082321 -368.218476) (xy 242.04157 -368.169219)
			(xy 242.007315 -368.115242) (xy 241.980095 -368.057398) (xy 241.96034 -367.996599) (xy 241.948361 -367.933802)
			(xy 241.944346 -367.87) (xy 241.609253 -367.87) (xy 241.609372 -367.877598) (xy 241.60887 -367.909559)
			(xy 241.600859 -367.972977) (xy 241.584962 -368.034891) (xy 241.56143 -368.094324) (xy 241.530636 -368.150339)
			(xy 241.493063 -368.202054) (xy 241.449306 -368.248651) (xy 241.400053 -368.289396) (xy 241.346082 -368.323647)
			(xy 241.288243 -368.350864) (xy 241.22745 -368.370617) (xy 241.16466 -368.382595) (xy 241.100864 -368.386609)
			(xy 241.037068 -368.382595) (xy 240.974278 -368.370617) (xy 240.913485 -368.350864) (xy 240.855646 -368.323647)
			(xy 240.801675 -368.289396) (xy 240.752422 -368.248651) (xy 240.708665 -368.202054) (xy 240.671092 -368.150339)
			(xy 240.640298 -368.094324) (xy 240.616766 -368.034891) (xy 240.600869 -367.972977) (xy 240.592858 -367.909559)
			(xy 240.310034 -367.909559) (xy 240.302665 -367.967897) (xy 240.286768 -368.029811) (xy 240.263236 -368.089244)
			(xy 240.232442 -368.145259) (xy 240.194869 -368.196974) (xy 240.151112 -368.243571) (xy 240.101859 -368.284316)
			(xy 240.047888 -368.318567) (xy 239.990049 -368.345784) (xy 239.929256 -368.365537) (xy 239.866466 -368.377515)
			(xy 239.80267 -368.381529) (xy 239.738874 -368.377515) (xy 239.676084 -368.365537) (xy 239.615291 -368.345784)
			(xy 239.557452 -368.318567) (xy 239.503481 -368.284316) (xy 239.454228 -368.243571) (xy 239.410471 -368.196974)
			(xy 239.372898 -368.145259) (xy 239.342104 -368.089244) (xy 239.318572 -368.029811) (xy 239.302675 -367.967897)
			(xy 239.294664 -367.904479) (xy 239.028896 -367.904479) (xy 239.024029 -367.943005) (xy 239.008132 -368.004919)
			(xy 238.9846 -368.064352) (xy 238.953806 -368.120367) (xy 238.916233 -368.172082) (xy 238.872476 -368.218679)
			(xy 238.823223 -368.259424) (xy 238.769252 -368.293675) (xy 238.711413 -368.320892) (xy 238.65062 -368.340645)
			(xy 238.58783 -368.352623) (xy 238.524034 -368.356637) (xy 238.460238 -368.352623) (xy 238.397448 -368.340645)
			(xy 238.336655 -368.320892) (xy 238.278816 -368.293675) (xy 238.224845 -368.259424) (xy 238.175592 -368.218679)
			(xy 238.131835 -368.172082) (xy 238.094262 -368.120367) (xy 238.063468 -368.064352) (xy 238.039936 -368.004919)
			(xy 238.024039 -367.943005) (xy 238.016028 -367.879587) (xy 231.502311 -367.879587) (xy 231.506137 -367.894487)
			(xy 231.514148 -367.957905) (xy 231.51465 -367.989866) (xy 231.514148 -368.021827) (xy 231.506137 -368.085245)
			(xy 231.49024 -368.147159) (xy 231.466708 -368.206592) (xy 231.435914 -368.262607) (xy 231.398341 -368.314322)
			(xy 231.354584 -368.360919) (xy 231.305331 -368.401664) (xy 231.25136 -368.435915) (xy 231.193521 -368.463132)
			(xy 231.132728 -368.482885) (xy 231.069938 -368.494863) (xy 231.006142 -368.498877) (xy 230.942346 -368.494863)
			(xy 230.879556 -368.482885) (xy 230.818763 -368.463132) (xy 230.760924 -368.435915) (xy 230.706953 -368.401664)
			(xy 230.6577 -368.360919) (xy 230.613943 -368.314322) (xy 230.57637 -368.262607) (xy 230.545576 -368.206592)
			(xy 230.522044 -368.147159) (xy 230.506147 -368.085245) (xy 230.498136 -368.021827) (xy 224.506031 -368.021827)
			(xy 224.50425 -368.031014) (xy 224.508314 -368.04346) (xy 224.519893 -368.081669) (xy 224.532401 -368.160516)
			(xy 224.533206 -368.200432) (xy 224.532774 -368.231164) (xy 224.525362 -368.292179) (xy 224.510649 -368.351855)
			(xy 224.488851 -368.409324) (xy 224.460285 -368.463746) (xy 224.425368 -368.514328) (xy 224.384609 -368.560333)
			(xy 224.338601 -368.601089) (xy 224.288017 -368.636003) (xy 224.233593 -368.664565) (xy 224.176123 -368.68636)
			(xy 224.116445 -368.701068) (xy 224.05543 -368.708476) (xy 224.024698 -368.70894) (xy 223.991758 -368.708467)
			(xy 223.92643 -368.699971) (xy 223.862745 -368.68311) (xy 223.801772 -368.658164) (xy 223.744531 -368.625553)
			(xy 223.691981 -368.585823) (xy 223.645002 -368.539638) (xy 223.604382 -368.487773) (xy 223.5708 -368.431096)
			(xy 223.544819 -368.370556) (xy 223.526874 -368.307168) (xy 223.517266 -368.241994) (xy 223.51619 -368.209068)
			(xy 223.515936 -368.19713) (xy 223.505268 -368.176048) (xy 223.42094 -368.114072) (xy 223.397572 -368.110008)
			(xy 223.386142 -368.11331) (xy 223.3305 -368.129165) (xy 223.217775 -368.155289) (xy 223.103747 -368.174957)
			(xy 222.988784 -368.188104) (xy 222.87326 -368.194689) (xy 222.815404 -368.195098) (xy 222.751545 -368.194627)
			(xy 222.624079 -368.186608) (xy 222.497368 -368.170601) (xy 222.371912 -368.146669) (xy 222.248206 -368.114907)
			(xy 222.126739 -368.07544) (xy 222.007989 -368.028424) (xy 221.892426 -367.974044) (xy 221.780506 -367.912516)
			(xy 221.67267 -367.844081) (xy 221.569343 -367.76901) (xy 221.470935 -367.6876) (xy 221.377832 -367.600171)
			(xy 221.290403 -367.507068) (xy 221.208992 -367.40866) (xy 221.133921 -367.305334) (xy 221.065486 -367.197498)
			(xy 221.003958 -367.085577) (xy 220.949578 -366.970015) (xy 220.902561 -366.851265) (xy 220.863094 -366.729798)
			(xy 220.831332 -366.606092) (xy 220.8074 -366.480636) (xy 220.791393 -366.353925) (xy 220.783373 -366.226459)
			(xy 219.974414 -366.226459) (xy 219.974414 -369.039097) (xy 245.74982 -369.039097) (xy 245.74982 -368.975175)
			(xy 245.757831 -368.911757) (xy 245.773728 -368.849843) (xy 245.79726 -368.79041) (xy 245.828054 -368.734395)
			(xy 245.865627 -368.68268) (xy 245.909384 -368.636083) (xy 245.958637 -368.595338) (xy 246.012608 -368.561087)
			(xy 246.070447 -368.53387) (xy 246.13124 -368.514117) (xy 246.19403 -368.502139) (xy 246.257826 -368.498126)
			(xy 246.321622 -368.502139) (xy 246.384412 -368.514117) (xy 246.445205 -368.53387) (xy 246.503044 -368.561087)
			(xy 246.557015 -368.595338) (xy 246.606268 -368.636083) (xy 246.646737 -368.679179) (xy 247.320556 -368.679179)
			(xy 247.320556 -368.615257) (xy 247.328567 -368.551839) (xy 247.344464 -368.489925) (xy 247.367996 -368.430492)
			(xy 247.39879 -368.374477) (xy 247.436363 -368.322762) (xy 247.48012 -368.276165) (xy 247.529373 -368.23542)
			(xy 247.583344 -368.201169) (xy 247.641183 -368.173952) (xy 247.701976 -368.154199) (xy 247.764766 -368.142221)
			(xy 247.828562 -368.138208) (xy 247.892358 -368.142221) (xy 247.955148 -368.154199) (xy 248.015941 -368.173952)
			(xy 248.07378 -368.201169) (xy 248.127751 -368.23542) (xy 248.177004 -368.276165) (xy 248.220761 -368.322762)
			(xy 248.258334 -368.374477) (xy 248.289128 -368.430492) (xy 248.31266 -368.489925) (xy 248.328557 -368.551839)
			(xy 248.336568 -368.615257) (xy 248.33707 -368.647218) (xy 248.336568 -368.679179) (xy 248.330857 -368.724391)
			(xy 248.60986 -368.724391) (xy 248.60986 -368.660469) (xy 248.617871 -368.597051) (xy 248.633768 -368.535137)
			(xy 248.6573 -368.475704) (xy 248.688094 -368.419689) (xy 248.725667 -368.367974) (xy 248.769424 -368.321377)
			(xy 248.818677 -368.280632) (xy 248.872648 -368.246381) (xy 248.930487 -368.219164) (xy 248.99128 -368.199411)
			(xy 249.05407 -368.187433) (xy 249.117866 -368.18342) (xy 249.181662 -368.187433) (xy 249.244452 -368.199411)
			(xy 249.305245 -368.219164) (xy 249.363084 -368.246381) (xy 249.417055 -368.280632) (xy 249.466308 -368.321377)
			(xy 249.510065 -368.367974) (xy 249.547638 -368.419689) (xy 249.578432 -368.475704) (xy 249.601964 -368.535137)
			(xy 249.617861 -368.597051) (xy 249.625872 -368.660469) (xy 249.626374 -368.69243) (xy 249.625872 -368.724391)
			(xy 249.617861 -368.787809) (xy 249.610854 -368.8151) (xy 271.35018 -368.8151) (xy 271.354195 -368.751299)
			(xy 271.366174 -368.688505) (xy 271.38593 -368.627707) (xy 271.41315 -368.569865) (xy 271.447406 -368.51589)
			(xy 271.488157 -368.466635) (xy 271.534759 -368.422877) (xy 271.58648 -368.385304) (xy 271.642501 -368.354511)
			(xy 271.701941 -368.330982) (xy 271.763861 -368.315089) (xy 271.827284 -368.307082) (xy 271.859248 -368.306604)
			(xy 271.893816 -368.307209) (xy 271.962313 -368.316585) (xy 272.028907 -368.335157) (xy 272.09237 -368.362582)
			(xy 272.151531 -368.398356) (xy 272.17878 -368.419634) (xy 272.186072 -368.425017) (xy 272.203246 -368.430758)
			(xy 272.212308 -368.43081) (xy 272.242788 -368.429794) (xy 272.251845 -368.429102) (xy 272.268638 -368.422219)
			(xy 272.275554 -368.416332) (xy 272.299077 -368.395313) (xy 272.350425 -368.358668) (xy 272.405911 -368.328652)
			(xy 272.464682 -368.305727) (xy 272.525837 -368.290245) (xy 272.588436 -368.282442) (xy 272.619978 -368.281966)
			(xy 272.653018 -368.282473) (xy 272.718543 -368.291025) (xy 272.782406 -368.308) (xy 272.843529 -368.333112)
			(xy 272.900881 -368.365937) (xy 272.953492 -368.405921) (xy 272.977356 -368.428778) (xy 272.985738 -368.43716)
			(xy 273.007328 -368.444526) (xy 273.109436 -368.432588) (xy 273.12874 -368.420396) (xy 273.134836 -368.41049)
			(xy 273.15236 -368.38353) (xy 273.193105 -368.333786) (xy 273.239794 -368.289574) (xy 273.291682 -368.251597)
			(xy 273.347942 -368.220462) (xy 273.407678 -368.196664) (xy 273.469936 -368.180584) (xy 273.533724 -368.172478)
			(xy 273.565874 -368.171984) (xy 273.597837 -368.172479) (xy 273.661259 -368.180488) (xy 273.723177 -368.196383)
			(xy 273.746236 -368.205512) (xy 290.223954 -368.205512) (xy 290.228025 -368.14989) (xy 290.240151 -368.095453)
			(xy 290.260074 -368.043362) (xy 290.28737 -367.994727) (xy 290.321456 -367.950584) (xy 290.361605 -367.911875)
			(xy 290.406963 -367.879424) (xy 290.456563 -367.853923) (xy 290.509347 -367.835916) (xy 290.56419 -367.825786)
			(xy 290.619924 -367.823749) (xy 290.675361 -367.829849) (xy 290.729318 -367.843955) (xy 290.780647 -367.865767)
			(xy 290.828253 -367.894821) (xy 290.871121 -367.930496) (xy 290.908338 -367.972033) (xy 290.939111 -368.018546)
			(xy 290.962783 -368.069043) (xy 290.978851 -368.12245) (xy 290.986971 -368.177626) (xy 290.98748 -368.205512)
			(xy 290.986971 -368.233398) (xy 290.978851 -368.288574) (xy 290.962783 -368.341981) (xy 290.939111 -368.392478)
			(xy 290.908338 -368.438991) (xy 290.871121 -368.480528) (xy 290.828253 -368.516203) (xy 290.780647 -368.545257)
			(xy 290.729318 -368.567069) (xy 290.675361 -368.581175) (xy 290.619924 -368.587275) (xy 290.56419 -368.585238)
			(xy 290.509347 -368.575108) (xy 290.456563 -368.557101) (xy 290.406963 -368.5316) (xy 290.361605 -368.499149)
			(xy 290.321456 -368.46044) (xy 290.28737 -368.416297) (xy 290.260074 -368.367662) (xy 290.240151 -368.315571)
			(xy 290.228025 -368.261134) (xy 290.223954 -368.205512) (xy 273.746236 -368.205512) (xy 273.782615 -368.219914)
			(xy 273.838634 -368.250708) (xy 273.890353 -368.288281) (xy 273.936954 -368.33204) (xy 273.977703 -368.381295)
			(xy 274.011957 -368.435269) (xy 274.039176 -368.49311) (xy 274.058931 -368.553907) (xy 274.070909 -368.6167)
			(xy 274.074924 -368.6805) (xy 274.070909 -368.7443) (xy 274.058931 -368.807093) (xy 274.039176 -368.86789)
			(xy 274.011957 -368.925731) (xy 273.977703 -368.979705) (xy 273.936954 -369.02896) (xy 273.890353 -369.072719)
			(xy 273.838634 -369.110292) (xy 273.782615 -369.141086) (xy 273.723177 -369.164617) (xy 273.661259 -369.180512)
			(xy 273.620192 -369.185698) (xy 288.630866 -369.185698) (xy 288.634937 -369.130076) (xy 288.647063 -369.075639)
			(xy 288.666986 -369.023548) (xy 288.694282 -368.974913) (xy 288.728368 -368.93077) (xy 288.768517 -368.892061)
			(xy 288.813875 -368.85961) (xy 288.863475 -368.834109) (xy 288.916259 -368.816102) (xy 288.971102 -368.805972)
			(xy 289.026836 -368.803935) (xy 289.082273 -368.810035) (xy 289.13623 -368.824141) (xy 289.187559 -368.845953)
			(xy 289.235165 -368.875007) (xy 289.278033 -368.910682) (xy 289.31525 -368.952219) (xy 289.346023 -368.998732)
			(xy 289.369695 -369.049229) (xy 289.385763 -369.102636) (xy 289.393883 -369.157812) (xy 289.394392 -369.185698)
			(xy 289.393883 -369.213584) (xy 289.385763 -369.26876) (xy 289.369695 -369.322167) (xy 289.346023 -369.372664)
			(xy 289.31525 -369.419177) (xy 289.278033 -369.460714) (xy 289.235165 -369.496389) (xy 289.187559 -369.525443)
			(xy 289.13623 -369.547255) (xy 289.082273 -369.561361) (xy 289.026836 -369.567461) (xy 288.971102 -369.565424)
			(xy 288.916259 -369.555294) (xy 288.863475 -369.537287) (xy 288.813875 -369.511786) (xy 288.768517 -369.479335)
			(xy 288.728368 -369.440626) (xy 288.694282 -369.396483) (xy 288.666986 -369.347848) (xy 288.647063 -369.295757)
			(xy 288.634937 -369.24132) (xy 288.630866 -369.185698) (xy 273.620192 -369.185698) (xy 273.597837 -369.188521)
			(xy 273.565874 -369.189) (xy 273.532835 -369.188441) (xy 273.467313 -369.179897) (xy 273.403452 -369.16293)
			(xy 273.342329 -369.137828) (xy 273.284977 -369.105013) (xy 273.232362 -369.06504) (xy 273.208496 -369.042188)
			(xy 273.200114 -369.033806) (xy 273.178524 -369.02644) (xy 273.076416 -369.038378) (xy 273.057112 -369.05057)
			(xy 273.051016 -369.060476) (xy 273.033547 -369.087473) (xy 272.992792 -369.137214) (xy 272.946093 -369.181423)
			(xy 272.894197 -369.219395) (xy 272.837929 -369.250525) (xy 272.778187 -369.274317) (xy 272.715923 -369.290391)
			(xy 272.652131 -369.298491) (xy 272.619978 -369.298982) (xy 272.585409 -369.298422) (xy 272.51691 -369.289036)
			(xy 272.450315 -369.270453) (xy 272.386852 -369.243018) (xy 272.327693 -369.207235) (xy 272.300446 -369.185952)
			(xy 272.293176 -369.180536) (xy 272.275985 -369.174816) (xy 272.266918 -369.174776) (xy 272.236438 -369.175792)
			(xy 272.227377 -369.176453) (xy 272.210585 -369.183358) (xy 272.203672 -369.189254) (xy 272.180136 -369.210258)
			(xy 272.128791 -369.246906) (xy 272.073308 -369.276924) (xy 272.01454 -369.299851) (xy 271.953387 -369.315337)
			(xy 271.890789 -369.323142) (xy 271.859248 -369.32362) (xy 271.827284 -369.323118) (xy 271.763861 -369.315111)
			(xy 271.701941 -369.299218) (xy 271.642501 -369.275689) (xy 271.58648 -369.244896) (xy 271.534759 -369.207323)
			(xy 271.488157 -369.163565) (xy 271.447406 -369.11431) (xy 271.41315 -369.060335) (xy 271.38593 -369.002493)
			(xy 271.366174 -368.941695) (xy 271.354195 -368.878901) (xy 271.35018 -368.8151) (xy 249.610854 -368.8151)
			(xy 249.601964 -368.849723) (xy 249.578432 -368.909156) (xy 249.547638 -368.965171) (xy 249.510065 -369.016886)
			(xy 249.466308 -369.063483) (xy 249.417055 -369.104228) (xy 249.363084 -369.138479) (xy 249.305245 -369.165696)
			(xy 249.244452 -369.185449) (xy 249.181662 -369.197427) (xy 249.117866 -369.201441) (xy 249.05407 -369.197427)
			(xy 248.99128 -369.185449) (xy 248.930487 -369.165696) (xy 248.872648 -369.138479) (xy 248.818677 -369.104228)
			(xy 248.769424 -369.063483) (xy 248.725667 -369.016886) (xy 248.688094 -368.965171) (xy 248.6573 -368.909156)
			(xy 248.633768 -368.849723) (xy 248.617871 -368.787809) (xy 248.60986 -368.724391) (xy 248.330857 -368.724391)
			(xy 248.328557 -368.742597) (xy 248.31266 -368.804511) (xy 248.289128 -368.863944) (xy 248.258334 -368.919959)
			(xy 248.220761 -368.971674) (xy 248.177004 -369.018271) (xy 248.127751 -369.059016) (xy 248.07378 -369.093267)
			(xy 248.015941 -369.120484) (xy 247.955148 -369.140237) (xy 247.892358 -369.152215) (xy 247.828562 -369.156229)
			(xy 247.764766 -369.152215) (xy 247.701976 -369.140237) (xy 247.641183 -369.120484) (xy 247.583344 -369.093267)
			(xy 247.529373 -369.059016) (xy 247.48012 -369.018271) (xy 247.436363 -368.971674) (xy 247.39879 -368.919959)
			(xy 247.367996 -368.863944) (xy 247.344464 -368.804511) (xy 247.328567 -368.742597) (xy 247.320556 -368.679179)
			(xy 246.646737 -368.679179) (xy 246.650025 -368.68268) (xy 246.687598 -368.734395) (xy 246.718392 -368.79041)
			(xy 246.741924 -368.849843) (xy 246.757821 -368.911757) (xy 246.765832 -368.975175) (xy 246.766334 -369.007136)
			(xy 246.765832 -369.039097) (xy 246.757821 -369.102515) (xy 246.741924 -369.164429) (xy 246.718392 -369.223862)
			(xy 246.687598 -369.279877) (xy 246.650025 -369.331592) (xy 246.606268 -369.378189) (xy 246.557015 -369.418934)
			(xy 246.503044 -369.453185) (xy 246.445205 -369.480402) (xy 246.384412 -369.500155) (xy 246.321622 -369.512133)
			(xy 246.257826 -369.516147) (xy 246.19403 -369.512133) (xy 246.13124 -369.500155) (xy 246.070447 -369.480402)
			(xy 246.012608 -369.453185) (xy 245.958637 -369.418934) (xy 245.909384 -369.378189) (xy 245.865627 -369.331592)
			(xy 245.828054 -369.279877) (xy 245.79726 -369.223862) (xy 245.773728 -369.164429) (xy 245.757831 -369.102515)
			(xy 245.74982 -369.039097) (xy 219.974414 -369.039097) (xy 219.974414 -369.974071) (xy 228.695752 -369.974071)
			(xy 228.695752 -369.910149) (xy 228.703763 -369.846731) (xy 228.71966 -369.784817) (xy 228.743192 -369.725384)
			(xy 228.773986 -369.669369) (xy 228.811559 -369.617654) (xy 228.855316 -369.571057) (xy 228.904569 -369.530312)
			(xy 228.95854 -369.496061) (xy 229.016379 -369.468844) (xy 229.077172 -369.449091) (xy 229.139962 -369.437113)
			(xy 229.203758 -369.4331) (xy 229.267554 -369.437113) (xy 229.330344 -369.449091) (xy 229.391137 -369.468844)
			(xy 229.448976 -369.496061) (xy 229.502947 -369.530312) (xy 229.5522 -369.571057) (xy 229.595957 -369.617654)
			(xy 229.63353 -369.669369) (xy 229.664324 -369.725384) (xy 229.687856 -369.784817) (xy 229.703753 -369.846731)
			(xy 229.711764 -369.910149) (xy 229.712266 -369.94211) (xy 229.711764 -369.974071) (xy 229.703753 -370.037489)
			(xy 229.687856 -370.099403) (xy 229.664324 -370.158836) (xy 229.63353 -370.214851) (xy 229.595957 -370.266566)
			(xy 229.5522 -370.313163) (xy 229.502947 -370.353908) (xy 229.448976 -370.388159) (xy 229.391137 -370.415376)
			(xy 229.330344 -370.435129) (xy 229.267554 -370.447107) (xy 229.203758 -370.451121) (xy 229.139962 -370.447107)
			(xy 229.077172 -370.435129) (xy 229.016379 -370.415376) (xy 228.95854 -370.388159) (xy 228.904569 -370.353908)
			(xy 228.855316 -370.313163) (xy 228.811559 -370.266566) (xy 228.773986 -370.214851) (xy 228.743192 -370.158836)
			(xy 228.71966 -370.099403) (xy 228.703763 -370.037489) (xy 228.695752 -369.974071) (xy 219.974414 -369.974071)
			(xy 219.974414 -369.981988) (xy 219.974835 -369.992059) (xy 219.982548 -370.010665) (xy 219.9894 -370.018056)
			(xy 221.429897 -371.458553) (xy 237.538967 -371.458553) (xy 237.538967 -371.404047) (xy 237.546725 -371.350096)
			(xy 237.562081 -371.297798) (xy 237.584725 -371.248218) (xy 237.614194 -371.202365) (xy 237.649889 -371.161173)
			(xy 237.691083 -371.125481) (xy 237.736937 -371.096014) (xy 237.786519 -371.073374) (xy 237.838817 -371.05802)
			(xy 237.892769 -371.050266) (xy 237.920022 -371.049804) (xy 237.948488 -371.050285) (xy 238.004788 -371.058744)
			(xy 238.059208 -371.07547) (xy 238.11054 -371.100093) (xy 238.157646 -371.132067) (xy 238.199481 -371.170682)
			(xy 238.21771 -371.192552) (xy 238.224314 -371.200934) (xy 238.243364 -371.21084) (xy 238.340138 -371.216682)
			(xy 238.360204 -371.209062) (xy 238.367824 -371.201696) (xy 238.378746 -371.191536) (xy 238.387128 -371.183916)
			(xy 238.395764 -371.163596) (xy 238.392462 -371.06352) (xy 238.382556 -371.043708) (xy 238.37392 -371.036596)
			(xy 238.351914 -371.018403) (xy 238.313077 -370.976551) (xy 238.280904 -370.929383) (xy 238.256112 -370.877951)
			(xy 238.239256 -370.8234) (xy 238.23071 -370.766947) (xy 238.230156 -370.7384) (xy 238.230719 -370.709342)
			(xy 238.23955 -370.651901) (xy 238.256993 -370.596465) (xy 238.282643 -370.544316) (xy 238.315907 -370.496661)
			(xy 238.335566 -370.475256) (xy 238.34217 -370.468144) (xy 238.349536 -370.45011) (xy 238.349536 -370.360194)
			(xy 238.34217 -370.34216) (xy 238.335566 -370.335048) (xy 238.315921 -370.313628) (xy 238.282638 -370.265986)
			(xy 238.256976 -370.213841) (xy 238.23953 -370.158405) (xy 238.230704 -370.100962) (xy 238.230156 -370.071904)
			(xy 238.230681 -370.044654) (xy 238.238436 -369.99071) (xy 238.253789 -369.938418) (xy 238.276427 -369.888843)
			(xy 238.30589 -369.842995) (xy 238.341577 -369.801805) (xy 238.382763 -369.766114) (xy 238.428608 -369.736646)
			(xy 238.478181 -369.714003) (xy 238.530471 -369.698645) (xy 238.584415 -369.690884) (xy 238.611664 -369.690396)
			(xy 238.641678 -369.690999) (xy 238.700964 -369.700406) (xy 238.758047 -369.718977) (xy 238.811519 -369.746255)
			(xy 238.860062 -369.781567) (xy 238.881666 -369.80241) (xy 238.888778 -369.809522) (xy 238.906558 -369.817142)
			(xy 238.997236 -369.818666) (xy 239.01527 -369.811808) (xy 239.022636 -369.80495) (xy 239.043931 -369.785911)
			(xy 239.091131 -369.753742) (xy 239.142597 -369.728966) (xy 239.197181 -369.712136) (xy 239.253664 -369.703628)
			(xy 239.282224 -369.703096) (xy 239.311204 -369.703591) (xy 239.368496 -369.712356) (xy 239.423806 -369.729681)
			(xy 239.475861 -369.755168) (xy 239.523464 -369.788232) (xy 239.565523 -369.828111) (xy 239.583722 -369.85067)
			(xy 239.591342 -369.860576) (xy 239.614202 -369.87099) (xy 239.723422 -369.864132) (xy 239.744758 -369.850924)
			(xy 239.751362 -369.840256) (xy 239.766161 -369.816189) (xy 239.801781 -369.772335) (xy 239.843482 -369.734218)
			(xy 239.890352 -369.702673) (xy 239.941365 -369.67839) (xy 239.995402 -369.661901) (xy 240.051281 -369.653568)
			(xy 240.07953 -369.653058) (xy 240.109324 -369.65364) (xy 240.168188 -369.662895) (xy 240.224896 -369.681191)
			(xy 240.27807 -369.708083) (xy 240.326415 -369.742917) (xy 240.368755 -369.784845) (xy 240.38687 -369.808506)
			(xy 240.394236 -369.818412) (xy 240.415572 -369.829334) (xy 240.521998 -369.82908) (xy 240.543588 -369.818412)
			(xy 240.5507 -369.808506) (xy 240.568788 -369.78473) (xy 240.611148 -369.742606) (xy 240.659557 -369.707601)
			(xy 240.712831 -369.680572) (xy 240.769669 -369.662179) (xy 240.828678 -369.652872) (xy 240.858548 -369.652296)
			(xy 240.888564 -369.652846) (xy 240.947853 -369.662266) (xy 241.004936 -369.680849) (xy 241.058407 -369.708139)
			(xy 241.106948 -369.743462) (xy 241.12855 -369.76431) (xy 241.135662 -369.771422) (xy 241.153442 -369.779042)
			(xy 241.24412 -369.780566) (xy 241.262154 -369.773708) (xy 241.26952 -369.76685) (xy 241.290821 -369.747819)
			(xy 241.338019 -369.715649) (xy 241.389484 -369.690871) (xy 241.444067 -369.674039) (xy 241.500548 -369.665529)
			(xy 241.529108 -369.664996) (xy 241.558048 -369.665518) (xy 241.615266 -369.674254) (xy 241.670511 -369.691523)
			(xy 241.722517 -369.716931) (xy 241.770094 -369.749895) (xy 241.79149 -369.76939) (xy 241.798856 -369.776502)
			(xy 241.81816 -369.783868) (xy 241.911632 -369.779804) (xy 241.930174 -369.770914) (xy 241.937032 -369.763294)
			(xy 241.955222 -369.743572) (xy 241.99617 -369.708908) (xy 242.04157 -369.680321) (xy 242.090526 -369.658372)
			(xy 242.142072 -369.643496) (xy 242.195195 -369.635986) (xy 242.22202 -369.635532) (xy 242.249275 -369.635936)
			(xy 242.30323 -369.643697) (xy 242.355532 -369.659058) (xy 242.405115 -369.681705) (xy 242.45097 -369.711179)
			(xy 242.492163 -369.746879) (xy 242.527857 -369.788078) (xy 242.557323 -369.833938) (xy 242.579963 -369.883524)
			(xy 242.595316 -369.935828) (xy 242.603068 -369.989785) (xy 242.603528 -370.01704) (xy 242.60316 -370.037317)
			(xy 246.698764 -370.037317) (xy 246.698764 -369.973395) (xy 246.706775 -369.909977) (xy 246.722672 -369.848063)
			(xy 246.746204 -369.78863) (xy 246.776998 -369.732615) (xy 246.814571 -369.6809) (xy 246.858328 -369.634303)
			(xy 246.907581 -369.593558) (xy 246.961552 -369.559307) (xy 247.019391 -369.53209) (xy 247.080184 -369.512337)
			(xy 247.142974 -369.500359) (xy 247.20677 -369.496346) (xy 247.270566 -369.500359) (xy 247.333356 -369.512337)
			(xy 247.394149 -369.53209) (xy 247.451988 -369.559307) (xy 247.505959 -369.593558) (xy 247.555212 -369.634303)
			(xy 247.598969 -369.6809) (xy 247.636542 -369.732615) (xy 247.667336 -369.78863) (xy 247.690868 -369.848063)
			(xy 247.706765 -369.909977) (xy 247.714776 -369.973395) (xy 247.715278 -370.005356) (xy 247.714776 -370.037317)
			(xy 247.706765 -370.100735) (xy 247.690868 -370.162649) (xy 247.667336 -370.222082) (xy 247.636542 -370.278097)
			(xy 247.598969 -370.329812) (xy 247.555212 -370.376409) (xy 247.505959 -370.417154) (xy 247.451988 -370.451405)
			(xy 247.394149 -370.478622) (xy 247.333356 -370.498375) (xy 247.270566 -370.510353) (xy 247.20677 -370.514367)
			(xy 247.142974 -370.510353) (xy 247.080184 -370.498375) (xy 247.019391 -370.478622) (xy 246.961552 -370.451405)
			(xy 246.907581 -370.417154) (xy 246.858328 -370.376409) (xy 246.814571 -370.329812) (xy 246.776998 -370.278097)
			(xy 246.746204 -370.222082) (xy 246.722672 -370.162649) (xy 246.706775 -370.100735) (xy 246.698764 -370.037317)
			(xy 242.60316 -370.037317) (xy 242.603037 -370.0441) (xy 242.595379 -370.097676) (xy 242.580222 -370.149631)
			(xy 242.557872 -370.198921) (xy 242.528777 -370.244556) (xy 242.493522 -370.285618) (xy 242.47348 -370.303806)
			(xy 242.465352 -370.311172) (xy 242.456208 -370.330984) (xy 242.4557 -370.428774) (xy 242.46459 -370.44884)
			(xy 242.472718 -370.455952) (xy 242.492308 -370.474079) (xy 242.526727 -370.514871) (xy 242.541298 -370.537232)
			(xy 242.547902 -370.547646) (xy 242.568984 -370.560092) (xy 242.67541 -370.56695) (xy 242.698016 -370.557298)
			(xy 242.705636 -370.547646) (xy 242.723841 -370.526328) (xy 242.765478 -370.488792) (xy 242.812156 -370.457747)
			(xy 242.862872 -370.433861) (xy 242.916535 -370.417647) (xy 242.971992 -370.409454) (xy 243.000022 -370.408962)
			(xy 243.027272 -370.409457) (xy 243.081218 -370.417216) (xy 243.133511 -370.432572) (xy 243.183086 -370.455214)
			(xy 243.228935 -370.48468) (xy 243.270124 -370.52037) (xy 243.305816 -370.561558) (xy 243.335282 -370.607407)
			(xy 243.357925 -370.656982) (xy 243.373282 -370.709274) (xy 243.381042 -370.76322) (xy 243.38153 -370.79047)
			(xy 243.381084 -370.815921) (xy 243.374289 -370.866367) (xy 243.372896 -370.871453) (xy 247.910598 -370.871453)
			(xy 247.910598 -370.807531) (xy 247.918609 -370.744113) (xy 247.934506 -370.682199) (xy 247.958038 -370.622766)
			(xy 247.988832 -370.566751) (xy 248.026405 -370.515036) (xy 248.070162 -370.468439) (xy 248.119415 -370.427694)
			(xy 248.173386 -370.393443) (xy 248.231225 -370.366226) (xy 248.292018 -370.346473) (xy 248.354808 -370.334495)
			(xy 248.418604 -370.330482) (xy 248.4824 -370.334495) (xy 248.54519 -370.346473) (xy 248.605983 -370.366226)
			(xy 248.663822 -370.393443) (xy 248.717793 -370.427694) (xy 248.767046 -370.468439) (xy 248.810803 -370.515036)
			(xy 248.848376 -370.566751) (xy 248.87917 -370.622766) (xy 248.902702 -370.682199) (xy 248.918599 -370.744113)
			(xy 248.92661 -370.807531) (xy 248.927112 -370.839492) (xy 248.92661 -370.871453) (xy 248.918599 -370.934871)
			(xy 248.902702 -370.996785) (xy 248.87917 -371.056218) (xy 248.848376 -371.112233) (xy 248.810803 -371.163948)
			(xy 248.767046 -371.210545) (xy 248.717793 -371.25129) (xy 248.663822 -371.285541) (xy 248.605983 -371.312758)
			(xy 248.54519 -371.332511) (xy 248.4824 -371.344489) (xy 248.418604 -371.348503) (xy 248.354808 -371.344489)
			(xy 248.292018 -371.332511) (xy 248.231225 -371.312758) (xy 248.173386 -371.285541) (xy 248.119415 -371.25129)
			(xy 248.070162 -371.210545) (xy 248.026405 -371.163948) (xy 247.988832 -371.112233) (xy 247.958038 -371.056218)
			(xy 247.934506 -370.996785) (xy 247.918609 -370.934871) (xy 247.910598 -370.871453) (xy 243.372896 -370.871453)
			(xy 243.360844 -370.915461) (xy 243.351304 -370.93906) (xy 243.346478 -370.950998) (xy 243.34851 -370.975636)
			(xy 243.407438 -371.067584) (xy 243.428774 -371.079776) (xy 243.441728 -371.080284) (xy 243.468384 -371.081618)
			(xy 243.520964 -371.090763) (xy 243.571756 -371.107149) (xy 243.619767 -371.130456) (xy 243.66406 -371.160228)
			(xy 243.70377 -371.195886) (xy 243.738121 -371.236731) (xy 243.766442 -371.281966) (xy 243.78818 -371.330708)
			(xy 243.802911 -371.382004) (xy 243.810346 -371.434853) (xy 243.81079 -371.461538) (xy 243.810304 -371.488789)
			(xy 243.802548 -371.542737) (xy 243.80065 -371.5492) (xy 291.773357 -371.5492) (xy 291.777371 -371.485402)
			(xy 291.789349 -371.422611) (xy 291.809102 -371.361815) (xy 291.836318 -371.303975) (xy 291.870569 -371.250001)
			(xy 291.911315 -371.200746) (xy 291.957912 -371.156986) (xy 292.009626 -371.119411) (xy 292.065642 -371.088613)
			(xy 292.125076 -371.065079) (xy 292.186991 -371.049179) (xy 292.25041 -371.041164) (xy 292.282372 -371.04066)
			(xy 292.317104 -371.041239) (xy 292.38592 -371.050708) (xy 292.452805 -371.069458) (xy 292.516515 -371.097142)
			(xy 292.575861 -371.133243) (xy 292.603174 -371.154706) (xy 292.610497 -371.160183) (xy 292.627812 -371.166029)
			(xy 292.636956 -371.166136) (xy 292.667436 -371.16512) (xy 292.676499 -371.164468) (xy 292.693292 -371.157559)
			(xy 292.700202 -371.151658) (xy 292.723749 -371.130444) (xy 292.775221 -371.093462) (xy 292.830891 -371.063163)
			(xy 292.889894 -371.040018) (xy 292.951317 -371.024385) (xy 293.014206 -371.016507) (xy 293.045896 -371.016022)
			(xy 293.07786 -371.016443) (xy 293.141285 -371.024455) (xy 293.203206 -371.040353) (xy 293.262645 -371.063886)
			(xy 293.318667 -371.094684) (xy 293.370386 -371.13226) (xy 293.416989 -371.176022) (xy 293.457738 -371.22528)
			(xy 293.491993 -371.279257) (xy 293.519213 -371.337101) (xy 293.538968 -371.397901) (xy 293.550947 -371.460697)
			(xy 293.554962 -371.5245) (xy 293.550947 -371.588303) (xy 293.538968 -371.651099) (xy 293.534289 -371.6655)
			(xy 294.32149 -371.6655) (xy 294.325503 -371.601704) (xy 294.337481 -371.538914) (xy 294.357234 -371.478121)
			(xy 294.384451 -371.420282) (xy 294.418702 -371.366311) (xy 294.459447 -371.317058) (xy 294.506044 -371.273301)
			(xy 294.557759 -371.235728) (xy 294.613774 -371.204934) (xy 294.673207 -371.181402) (xy 294.735121 -371.165505)
			(xy 294.798539 -371.157494) (xy 294.8305 -371.156992) (xy 294.861218 -371.157446) (xy 294.922206 -371.164858)
			(xy 294.981856 -371.179564) (xy 295.039301 -371.201347) (xy 295.093703 -371.229892) (xy 295.144271 -371.264782)
			(xy 295.190268 -371.305509) (xy 295.210992 -371.328188) (xy 295.218104 -371.336316) (xy 295.237662 -371.345206)
			(xy 295.334182 -371.346476) (xy 295.353994 -371.338348) (xy 295.36136 -371.330474) (xy 295.381968 -371.309084)
			(xy 295.427367 -371.27078) (xy 295.476918 -371.238024) (xy 295.529946 -371.21126) (xy 295.585729 -371.190853)
			(xy 295.64351 -371.17708) (xy 295.702501 -371.170129) (xy 295.7322 -371.169692) (xy 295.764161 -371.170194)
			(xy 295.827579 -371.178205) (xy 295.889493 -371.194102) (xy 295.948926 -371.217634) (xy 296.004941 -371.248428)
			(xy 296.056656 -371.286001) (xy 296.103253 -371.329758) (xy 296.143998 -371.379011) (xy 296.178249 -371.432982)
			(xy 296.205466 -371.490821) (xy 296.225219 -371.551614) (xy 296.237197 -371.614404) (xy 296.241211 -371.6782)
			(xy 296.237197 -371.741996) (xy 296.225219 -371.804786) (xy 296.205466 -371.865579) (xy 296.178249 -371.923418)
			(xy 296.143998 -371.977389) (xy 296.103253 -372.026642) (xy 296.056656 -372.070399) (xy 296.004941 -372.107972)
			(xy 295.948926 -372.138766) (xy 295.889493 -372.162298) (xy 295.827579 -372.178195) (xy 295.764161 -372.186206)
			(xy 295.7322 -372.186708) (xy 295.701482 -372.186254) (xy 295.640494 -372.178842) (xy 295.580844 -372.164136)
			(xy 295.523399 -372.142353) (xy 295.468997 -372.113808) (xy 295.418429 -372.078918) (xy 295.372432 -372.038191)
			(xy 295.351708 -372.015512) (xy 295.344596 -372.007384) (xy 295.325038 -371.998494) (xy 295.228518 -371.997224)
			(xy 295.208706 -372.005352) (xy 295.20134 -372.013226) (xy 295.180732 -372.034616) (xy 295.135333 -372.07292)
			(xy 295.085782 -372.105676) (xy 295.032754 -372.13244) (xy 294.976971 -372.152847) (xy 294.91919 -372.16662)
			(xy 294.860199 -372.173571) (xy 294.8305 -372.174008) (xy 294.798539 -372.173506) (xy 294.735121 -372.165495)
			(xy 294.673207 -372.149598) (xy 294.613774 -372.126066) (xy 294.557759 -372.095272) (xy 294.506044 -372.057699)
			(xy 294.459447 -372.013942) (xy 294.418702 -371.964689) (xy 294.384451 -371.910718) (xy 294.357234 -371.852879)
			(xy 294.337481 -371.792086) (xy 294.325503 -371.729296) (xy 294.32149 -371.6655) (xy 293.534289 -371.6655)
			(xy 293.519213 -371.711899) (xy 293.491993 -371.769743) (xy 293.457738 -371.82372) (xy 293.416989 -371.872978)
			(xy 293.370386 -371.91674) (xy 293.318667 -371.954316) (xy 293.262645 -371.985114) (xy 293.203206 -372.008647)
			(xy 293.141285 -372.024545) (xy 293.07786 -372.032557) (xy 293.045896 -372.033038) (xy 293.011164 -372.032447)
			(xy 292.942346 -372.022987) (xy 292.875457 -372.004245) (xy 292.811744 -371.976568) (xy 292.752393 -371.940473)
			(xy 292.725094 -371.918992) (xy 292.717753 -371.913544) (xy 292.700452 -371.90768) (xy 292.691312 -371.907562)
			(xy 292.660832 -371.908578) (xy 292.651767 -371.909216) (xy 292.634975 -371.916135) (xy 292.628066 -371.92204)
			(xy 292.604491 -371.943221) (xy 292.553025 -371.980207) (xy 292.497361 -372.010511) (xy 292.438364 -372.033662)
			(xy 292.376946 -372.049301) (xy 292.314061 -372.057187) (xy 292.282372 -372.057676) (xy 292.25041 -372.057236)
			(xy 292.186991 -372.049221) (xy 292.125076 -372.033321) (xy 292.065642 -372.009787) (xy 292.009626 -371.978989)
			(xy 291.957912 -371.941414) (xy 291.911315 -371.897654) (xy 291.870569 -371.848399) (xy 291.836318 -371.794425)
			(xy 291.809102 -371.736585) (xy 291.789349 -371.675789) (xy 291.777371 -371.612998) (xy 291.773357 -371.5492)
			(xy 243.80065 -371.5492) (xy 243.787193 -371.595032) (xy 243.764551 -371.644609) (xy 243.735085 -371.690459)
			(xy 243.699394 -371.73165) (xy 243.658203 -371.767341) (xy 243.612353 -371.796807) (xy 243.562776 -371.819449)
			(xy 243.510481 -371.834804) (xy 243.456533 -371.84256) (xy 243.402031 -371.84256) (xy 243.348083 -371.834804)
			(xy 243.295788 -371.819449) (xy 243.246211 -371.796807) (xy 243.200361 -371.767341) (xy 243.15917 -371.73165)
			(xy 243.123479 -371.690459) (xy 243.094013 -371.644609) (xy 243.071371 -371.595032) (xy 243.056016 -371.542737)
			(xy 243.04826 -371.488789) (xy 243.047774 -371.461538) (xy 243.048222 -371.436087) (xy 243.055016 -371.385641)
			(xy 243.068461 -371.336547) (xy 243.078 -371.312948) (xy 243.082826 -371.30101) (xy 243.080794 -371.276372)
			(xy 243.021866 -371.184424) (xy 243.00053 -371.172232) (xy 242.987576 -371.171724) (xy 242.96099 -371.170394)
			(xy 242.908547 -371.161279) (xy 242.85788 -371.144962) (xy 242.809975 -371.121757) (xy 242.765761 -371.092118)
			(xy 242.726098 -371.056618) (xy 242.691756 -371.015948) (xy 242.677188 -370.99367) (xy 242.670584 -370.983256)
			(xy 242.649502 -370.97081) (xy 242.543076 -370.963952) (xy 242.52047 -370.973604) (xy 242.51285 -370.983256)
			(xy 242.494653 -371.004581) (xy 242.453014 -371.042117) (xy 242.406334 -371.07316) (xy 242.355617 -371.097045)
			(xy 242.301952 -371.113258) (xy 242.246494 -371.121449) (xy 242.218464 -371.12194) (xy 242.191914 -371.121462)
			(xy 242.139329 -371.114089) (xy 242.088275 -371.099493) (xy 242.039741 -371.077954) (xy 241.994664 -371.049889)
			(xy 241.953917 -371.015842) (xy 241.935762 -370.996464) (xy 241.92865 -370.988844) (xy 241.910362 -370.980208)
			(xy 241.817144 -370.976398) (xy 241.798348 -370.98351) (xy 241.790728 -370.990622) (xy 241.769394 -371.010045)
			(xy 241.721929 -371.04284) (xy 241.670066 -371.068114) (xy 241.61499 -371.08529) (xy 241.557955 -371.093978)
			(xy 241.529108 -371.094508) (xy 241.499092 -371.09395) (xy 241.439802 -371.084537) (xy 241.382718 -371.065956)
			(xy 241.329246 -371.038667) (xy 241.280707 -371.003343) (xy 241.259106 -370.982494) (xy 241.251994 -370.975382)
			(xy 241.234214 -370.967762) (xy 241.143536 -370.966238) (xy 241.125502 -370.973096) (xy 241.118136 -370.979954)
			(xy 241.096853 -370.999007) (xy 241.04965 -371.031174) (xy 240.99818 -371.055947) (xy 240.943593 -371.072774)
			(xy 240.887109 -371.081278) (xy 240.858548 -371.081808) (xy 240.828753 -371.081256) (xy 240.769887 -371.071997)
			(xy 240.713177 -371.053695) (xy 240.660003 -371.026798) (xy 240.611659 -370.991958) (xy 240.569321 -370.950024)
			(xy 240.551208 -370.92636) (xy 240.543842 -370.916454) (xy 240.522506 -370.905532) (xy 240.41608 -370.905786)
			(xy 240.39449 -370.916454) (xy 240.387378 -370.92636) (xy 240.369293 -370.950139) (xy 240.326934 -370.992265)
			(xy 240.278525 -371.027271) (xy 240.225249 -371.0543) (xy 240.168411 -371.072691) (xy 240.1094 -371.081995)
			(xy 240.07953 -371.08257) (xy 240.050553 -371.082011) (xy 239.993264 -371.073256) (xy 239.937957 -371.055941)
			(xy 239.885903 -371.030466) (xy 239.838297 -370.997416) (xy 239.796234 -370.957549) (xy 239.778032 -370.934996)
			(xy 239.770412 -370.92509) (xy 239.747552 -370.914676) (xy 239.638332 -370.921534) (xy 239.616996 -370.934742)
			(xy 239.610392 -370.94541) (xy 239.595543 -370.969445) (xy 239.559933 -371.0133) (xy 239.518241 -371.05142)
			(xy 239.471379 -371.08297) (xy 239.420374 -371.107258) (xy 239.366344 -371.123754) (xy 239.31047 -371.132094)
			(xy 239.282224 -371.132608) (xy 239.252208 -371.13204) (xy 239.192919 -371.122629) (xy 239.135835 -371.104051)
			(xy 239.082363 -371.076764) (xy 239.033824 -371.041442) (xy 239.012222 -371.020594) (xy 239.00511 -371.013482)
			(xy 238.98733 -371.005862) (xy 238.896652 -371.004338) (xy 238.878618 -371.011196) (xy 238.871252 -371.018054)
			(xy 238.867696 -371.021102) (xy 238.859314 -371.028722) (xy 238.850678 -371.049042) (xy 238.85398 -371.149118)
			(xy 238.863886 -371.16893) (xy 238.872522 -371.176042) (xy 238.894486 -371.194284) (xy 238.933329 -371.236123)
			(xy 238.965509 -371.283281) (xy 238.990308 -371.334704) (xy 239.007172 -371.389247) (xy 239.015727 -371.445693)
			(xy 239.016286 -371.474238) (xy 239.015857 -371.501491) (xy 239.008095 -371.555442) (xy 238.992734 -371.607739)
			(xy 238.970087 -371.657318) (xy 238.940615 -371.703169) (xy 238.904917 -371.74436) (xy 238.863721 -371.780051)
			(xy 238.817865 -371.809516) (xy 238.768283 -371.832155) (xy 238.715983 -371.847508) (xy 238.662031 -371.855262)
			(xy 238.634778 -371.855746) (xy 238.606313 -371.855247) (xy 238.550014 -371.846789) (xy 238.495595 -371.830065)
			(xy 238.444263 -371.805446) (xy 238.397157 -371.773476) (xy 238.35532 -371.734866) (xy 238.33709 -371.712998)
			(xy 238.330486 -371.704616) (xy 238.311436 -371.69471) (xy 238.214662 -371.688868) (xy 238.194596 -371.696488)
			(xy 238.186976 -371.703854) (xy 238.165432 -371.724136) (xy 238.117285 -371.758524) (xy 238.064405 -371.785064)
			(xy 238.008061 -371.803121) (xy 237.949605 -371.812261) (xy 237.920022 -371.81282) (xy 237.892769 -371.812334)
			(xy 237.838817 -371.80458) (xy 237.786519 -371.789226) (xy 237.736937 -371.766586) (xy 237.691083 -371.737119)
			(xy 237.649889 -371.701427) (xy 237.614194 -371.660235) (xy 237.584725 -371.614382) (xy 237.562081 -371.564802)
			(xy 237.546725 -371.512504) (xy 237.538967 -371.458553) (xy 221.429897 -371.458553) (xy 222.121984 -372.15064)
			(xy 222.129384 -372.15748) (xy 222.147983 -372.165193) (xy 222.158052 -372.165626) (xy 276.372066 -372.165626)
			(xy 276.38213 -372.166062) (xy 276.400715 -372.173796) (xy 276.408134 -372.180612) (xy 277.145242 -372.91772)
			(xy 277.14575 -372.918228) (xy 277.15313 -372.924814) (xy 277.171429 -372.932269) (xy 277.18131 -372.932706)
			(xy 277.191724 -372.932706) (xy 278.215695 -373.956834) (xy 282.726384 -373.956834) (xy 282.726932 -373.921878)
			(xy 282.736502 -373.852623) (xy 282.755467 -373.785332) (xy 282.78347 -373.721272) (xy 282.819982 -373.661651)
			(xy 282.8417 -373.634254) (xy 282.846984 -373.627247) (xy 282.852965 -373.610761) (xy 282.853384 -373.601996)
			(xy 282.853384 -373.448072) (xy 282.853019 -373.439296) (xy 282.847034 -373.422794) (xy 282.8417 -373.415814)
			(xy 282.819993 -373.38841) (xy 282.783495 -373.328786) (xy 282.755501 -373.264726) (xy 282.736539 -373.197438)
			(xy 282.726965 -373.128188) (xy 282.726384 -373.093234) (xy 282.72687 -373.062503) (xy 282.734274 -373.001488)
			(xy 282.748979 -372.941811) (xy 282.770771 -372.884342) (xy 282.799331 -372.829919) (xy 282.834243 -372.779335)
			(xy 282.874998 -372.733328) (xy 282.921002 -372.692569) (xy 282.971583 -372.657653) (xy 283.026004 -372.629088)
			(xy 283.083471 -372.607292) (xy 283.143147 -372.592582) (xy 283.204161 -372.585172) (xy 283.234892 -372.584726)
			(xy 283.266082 -372.585189) (xy 283.32799 -372.592857) (xy 283.388497 -372.60803) (xy 283.446697 -372.630481)
			(xy 283.501719 -372.659874) (xy 283.5275 -372.677436) (xy 283.535882 -372.683278) (xy 283.555186 -372.687596)
			(xy 283.645864 -372.672102) (xy 283.662628 -372.661688) (xy 283.668724 -372.653306) (xy 283.68559 -372.630707)
			(xy 283.72522 -372.590594) (xy 283.770676 -372.557229) (xy 283.820824 -372.531447) (xy 283.874408 -372.513891)
			(xy 283.93009 -372.505) (xy 283.958284 -372.504462) (xy 283.984934 -372.504994) (xy 284.037638 -372.512936)
			(xy 284.08857 -372.528644) (xy 284.136592 -372.551768) (xy 284.180631 -372.581792) (xy 284.219703 -372.618043)
			(xy 284.252935 -372.659714) (xy 284.279585 -372.705872) (xy 284.299058 -372.755487) (xy 284.310919 -372.80745)
			(xy 284.314902 -372.8606) (xy 284.310919 -372.91375) (xy 284.299058 -372.965713) (xy 284.279585 -373.015328)
			(xy 284.252935 -373.061486) (xy 284.219703 -373.103157) (xy 284.180631 -373.139408) (xy 284.136592 -373.169432)
			(xy 284.08857 -373.192556) (xy 284.037638 -373.208264) (xy 283.984934 -373.216206) (xy 283.958284 -373.216678)
			(xy 283.929106 -373.216064) (xy 283.871539 -373.206483) (xy 283.84373 -373.197628) (xy 283.834078 -373.194326)
			(xy 283.814266 -373.195596) (xy 283.731462 -373.235982) (xy 283.718508 -373.250714) (xy 283.715206 -373.26062)
			(xy 283.704972 -373.288638) (xy 283.678876 -373.342277) (xy 283.64668 -373.392492) (xy 283.628084 -373.415814)
			(xy 283.622782 -373.422809) (xy 283.61681 -373.439304) (xy 283.6164 -373.448072) (xy 283.6164 -373.601996)
			(xy 283.616763 -373.610773) (xy 283.622747 -373.627276) (xy 283.628084 -373.634254) (xy 283.651625 -373.664095)
			(xy 283.673014 -373.699997) (xy 292.81729 -373.699997) (xy 292.81729 -373.636075) (xy 292.825301 -373.572657)
			(xy 292.841198 -373.510743) (xy 292.86473 -373.45131) (xy 292.895524 -373.395295) (xy 292.933097 -373.34358)
			(xy 292.976854 -373.296983) (xy 293.026107 -373.256238) (xy 293.080078 -373.221987) (xy 293.137917 -373.19477)
			(xy 293.19871 -373.175017) (xy 293.2615 -373.163039) (xy 293.325296 -373.159026) (xy 293.389092 -373.163039)
			(xy 293.451882 -373.175017) (xy 293.512675 -373.19477) (xy 293.570514 -373.221987) (xy 293.624485 -373.256238)
			(xy 293.673738 -373.296983) (xy 293.717495 -373.34358) (xy 293.755068 -373.395295) (xy 293.785862 -373.45131)
			(xy 293.809394 -373.510743) (xy 293.825291 -373.572657) (xy 293.833302 -373.636075) (xy 293.833804 -373.668036)
			(xy 293.83331 -373.699489) (xy 293.949876 -373.699489) (xy 293.949876 -373.635567) (xy 293.957887 -373.572149)
			(xy 293.973784 -373.510235) (xy 293.997316 -373.450802) (xy 294.02811 -373.394787) (xy 294.065683 -373.343072)
			(xy 294.10944 -373.296475) (xy 294.158693 -373.25573) (xy 294.212664 -373.221479) (xy 294.270503 -373.194262)
			(xy 294.331296 -373.174509) (xy 294.394086 -373.162531) (xy 294.457882 -373.158518) (xy 294.521678 -373.162531)
			(xy 294.584468 -373.174509) (xy 294.645261 -373.194262) (xy 294.7031 -373.221479) (xy 294.757071 -373.25573)
			(xy 294.806324 -373.296475) (xy 294.850081 -373.343072) (xy 294.887654 -373.394787) (xy 294.918448 -373.450802)
			(xy 294.94198 -373.510235) (xy 294.957877 -373.572149) (xy 294.965888 -373.635567) (xy 294.96639 -373.667528)
			(xy 294.965888 -373.699489) (xy 294.957877 -373.762907) (xy 294.94198 -373.824821) (xy 294.918448 -373.884254)
			(xy 294.887654 -373.940269) (xy 294.850081 -373.991984) (xy 294.806324 -374.038581) (xy 294.757071 -374.079326)
			(xy 294.7031 -374.113577) (xy 294.645261 -374.140794) (xy 294.584468 -374.160547) (xy 294.521678 -374.172525)
			(xy 294.457882 -374.176539) (xy 294.394086 -374.172525) (xy 294.331296 -374.160547) (xy 294.270503 -374.140794)
			(xy 294.212664 -374.113577) (xy 294.158693 -374.079326) (xy 294.10944 -374.038581) (xy 294.065683 -373.991984)
			(xy 294.02811 -373.940269) (xy 293.997316 -373.884254) (xy 293.973784 -373.824821) (xy 293.957887 -373.762907)
			(xy 293.949876 -373.699489) (xy 293.83331 -373.699489) (xy 293.833302 -373.699997) (xy 293.825291 -373.763415)
			(xy 293.809394 -373.825329) (xy 293.785862 -373.884762) (xy 293.755068 -373.940777) (xy 293.717495 -373.992492)
			(xy 293.673738 -374.039089) (xy 293.624485 -374.079834) (xy 293.570514 -374.114085) (xy 293.512675 -374.141302)
			(xy 293.451882 -374.161055) (xy 293.389092 -374.173033) (xy 293.325296 -374.177047) (xy 293.2615 -374.173033)
			(xy 293.19871 -374.161055) (xy 293.137917 -374.141302) (xy 293.080078 -374.114085) (xy 293.026107 -374.079834)
			(xy 292.976854 -374.039089) (xy 292.933097 -373.992492) (xy 292.895524 -373.940777) (xy 292.86473 -373.884762)
			(xy 292.841198 -373.825329) (xy 292.825301 -373.763415) (xy 292.81729 -373.699997) (xy 283.673014 -373.699997)
			(xy 283.690526 -373.72939) (xy 283.705554 -373.764302) (xy 283.70911 -373.773192) (xy 283.72181 -373.786654)
			(xy 283.80055 -373.8245) (xy 283.818838 -373.826024) (xy 283.828236 -373.823484) (xy 283.852709 -373.816762)
			(xy 283.902937 -373.809493) (xy 283.928312 -373.809006) (xy 283.954962 -373.809477) (xy 284.007666 -373.817422)
			(xy 284.058597 -373.833134) (xy 284.106618 -373.856261) (xy 284.150655 -373.886286) (xy 284.189726 -373.92254)
			(xy 284.222957 -373.964212) (xy 284.249606 -374.010371) (xy 284.269078 -374.059986) (xy 284.280939 -374.111949)
			(xy 284.284922 -374.1651) (xy 284.280939 -374.218251) (xy 284.269078 -374.270214) (xy 284.249606 -374.319829)
			(xy 284.222957 -374.365988) (xy 284.189726 -374.40766) (xy 284.150655 -374.443914) (xy 284.106618 -374.473939)
			(xy 284.058597 -374.497066) (xy 284.007666 -374.512778) (xy 283.954962 -374.520723) (xy 283.928312 -374.521222)
			(xy 283.902525 -374.520738) (xy 283.851493 -374.513282) (xy 283.802071 -374.498537) (xy 283.755296 -374.476814)
			(xy 283.712145 -374.448566) (xy 283.673524 -374.414387) (xy 283.656532 -374.394984) (xy 283.650182 -374.387872)
			(xy 283.633926 -374.378982) (xy 283.547566 -374.367044) (xy 283.529532 -374.371362) (xy 283.521658 -374.376696)
			(xy 283.496235 -374.393514) (xy 283.442159 -374.421652) (xy 283.385105 -374.443116) (xy 283.325892 -374.457599)
			(xy 283.265371 -374.464893) (xy 283.234892 -374.465342) (xy 283.204162 -374.464852) (xy 283.143151 -374.457443)
			(xy 283.083477 -374.442734) (xy 283.026011 -374.420941) (xy 282.971591 -374.392379) (xy 282.92101 -374.357467)
			(xy 282.875006 -374.316713) (xy 282.834249 -374.270711) (xy 282.799334 -374.220132) (xy 282.77077 -374.165713)
			(xy 282.748973 -374.108248) (xy 282.734262 -374.048575) (xy 282.72685 -373.987564) (xy 282.726384 -373.956834)
			(xy 278.215695 -373.956834) (xy 278.84628 -374.587516) (xy 278.852145 -374.593804) (xy 278.859687 -374.609247)
			(xy 278.861012 -374.617742) (xy 278.861012 -374.617996) (xy 278.862299 -374.626411) (xy 278.869695 -374.641732)
			(xy 278.87549 -374.647968) (xy 280.71191 -376.484388) (xy 280.718768 -376.491782) (xy 280.726521 -376.510381)
			(xy 280.726896 -376.520456) (xy 280.726896 -378.470668) (xy 285.209742 -378.470668) (xy 285.210303 -378.437329)
			(xy 285.219017 -378.371223) (xy 285.23629 -378.306822) (xy 285.261827 -378.245228) (xy 285.295191 -378.187497)
			(xy 285.335809 -378.134619) (xy 285.382986 -378.0875) (xy 285.409132 -378.066808) (xy 285.415944 -378.061125)
			(xy 285.425558 -378.046236) (xy 285.429504 -378.028958) (xy 285.427306 -378.011371) (xy 285.42361 -378.003308)
			(xy 285.410334 -377.976396) (xy 285.389515 -377.920113) (xy 285.375477 -377.861767) (xy 285.368417 -377.802173)
			(xy 285.367984 -377.772168) (xy 285.368487 -377.741122) (xy 285.376047 -377.679492) (xy 285.391052 -377.619241)
			(xy 285.413277 -377.561263) (xy 285.442393 -377.506421) (xy 285.477967 -377.45553) (xy 285.51947 -377.409346)
			(xy 285.566284 -377.368557) (xy 285.617715 -377.333768) (xy 285.672997 -377.305496) (xy 285.701994 -377.294394)
			(xy 285.710478 -377.290954) (xy 285.724409 -377.279099) (xy 285.729172 -377.27128) (xy 285.743904 -377.24461)
			(xy 285.747965 -377.23641) (xy 285.750575 -377.218314) (xy 285.748984 -377.209304) (xy 285.743398 -377.182345)
			(xy 285.737417 -377.127613) (xy 285.737046 -377.100084) (xy 285.737548 -377.068123) (xy 285.745559 -377.004705)
			(xy 285.761456 -376.942791) (xy 285.784988 -376.883358) (xy 285.815782 -376.827343) (xy 285.853355 -376.775628)
			(xy 285.897112 -376.729031) (xy 285.946365 -376.688286) (xy 286.000336 -376.654035) (xy 286.058175 -376.626818)
			(xy 286.118968 -376.607065) (xy 286.181758 -376.595087) (xy 286.245554 -376.591074) (xy 286.30935 -376.595087)
			(xy 286.37214 -376.607065) (xy 286.432933 -376.626818) (xy 286.490772 -376.654035) (xy 286.544743 -376.688286)
			(xy 286.593996 -376.729031) (xy 286.637753 -376.775628) (xy 286.675326 -376.827343) (xy 286.70612 -376.883358)
			(xy 286.729652 -376.942791) (xy 286.745549 -377.004705) (xy 286.75356 -377.068123) (xy 286.754062 -377.100084)
			(xy 286.753575 -377.13113) (xy 286.746009 -377.192759) (xy 286.731 -377.25301) (xy 286.713559 -377.2985)
			(xy 286.886326 -377.2985) (xy 286.890341 -377.234695) (xy 286.90232 -377.171897) (xy 286.922076 -377.111095)
			(xy 286.949297 -377.053249) (xy 286.983554 -376.99927) (xy 287.024305 -376.950011) (xy 287.07091 -376.906248)
			(xy 287.122631 -376.868671) (xy 287.178655 -376.837873) (xy 287.238097 -376.814339) (xy 287.30002 -376.798442)
			(xy 287.363447 -376.79043) (xy 287.395412 -376.78995) (xy 287.425223 -376.790387) (xy 287.484431 -376.797394)
			(xy 287.513522 -376.80392) (xy 287.522778 -376.805647) (xy 287.541409 -376.803027) (xy 287.549844 -376.79884)
			(xy 287.576768 -376.783854) (xy 287.584847 -376.778946) (xy 287.596989 -376.764478) (xy 287.60039 -376.75566)
			(xy 287.610915 -376.725725) (xy 287.63839 -376.668526) (xy 287.672771 -376.615191) (xy 287.713524 -376.566551)
			(xy 287.760013 -376.523362) (xy 287.811517 -376.486295) (xy 287.867235 -376.455927) (xy 287.926299 -376.432731)
			(xy 287.987791 -376.417067) (xy 288.050754 -376.409179) (xy 288.082482 -376.408696) (xy 288.114445 -376.409168)
			(xy 288.177868 -376.417178) (xy 288.239787 -376.433074) (xy 288.299225 -376.456605) (xy 288.355245 -376.487401)
			(xy 288.406964 -376.524975) (xy 288.453565 -376.568735) (xy 288.494314 -376.617991) (xy 288.528568 -376.671965)
			(xy 288.555788 -376.729808) (xy 288.575542 -376.790605) (xy 288.587521 -376.8534) (xy 288.591536 -376.9172)
			(xy 288.587521 -376.981) (xy 288.575542 -377.043795) (xy 288.555788 -377.104592) (xy 288.528568 -377.162435)
			(xy 288.494314 -377.216409) (xy 288.453565 -377.265665) (xy 288.406964 -377.309425) (xy 288.355245 -377.346999)
			(xy 288.299225 -377.377795) (xy 288.239787 -377.401326) (xy 288.177868 -377.417222) (xy 288.114445 -377.425232)
			(xy 288.082482 -377.425712) (xy 288.052671 -377.425277) (xy 287.993463 -377.418269) (xy 287.964372 -377.411742)
			(xy 287.955116 -377.410016) (xy 287.936485 -377.412637) (xy 287.92805 -377.416822) (xy 287.901126 -377.431808)
			(xy 287.89303 -377.436692) (xy 287.880896 -377.451176) (xy 287.877504 -377.460002) (xy 287.86702 -377.489952)
			(xy 287.839538 -377.54715) (xy 287.805151 -377.600483) (xy 287.764393 -377.649122) (xy 287.717898 -377.692309)
			(xy 287.66639 -377.729374) (xy 287.610669 -377.759739) (xy 287.551602 -377.782934) (xy 287.490107 -377.798597)
			(xy 287.427141 -377.806484) (xy 287.395412 -377.806966) (xy 287.363447 -377.80657) (xy 287.30002 -377.798558)
			(xy 287.238097 -377.782661) (xy 287.178655 -377.759127) (xy 287.122631 -377.728329) (xy 287.07091 -377.690752)
			(xy 287.024305 -377.646989) (xy 286.983554 -377.59773) (xy 286.949297 -377.543751) (xy 286.922076 -377.485905)
			(xy 286.90232 -377.425103) (xy 286.890341 -377.362305) (xy 286.886326 -377.2985) (xy 286.713559 -377.2985)
			(xy 286.708771 -377.310987) (xy 286.679653 -377.365828) (xy 286.644078 -377.416718) (xy 286.602574 -377.462901)
			(xy 286.55576 -377.503691) (xy 286.50433 -377.538481) (xy 286.449048 -377.566754) (xy 286.420052 -377.577858)
			(xy 286.411568 -377.581296) (xy 286.397638 -377.593154) (xy 286.392874 -377.600972) (xy 286.378142 -377.627642)
			(xy 286.374053 -377.63583) (xy 286.371462 -377.653936) (xy 286.373062 -377.662948) (xy 286.378641 -377.689908)
			(xy 286.384627 -377.744639) (xy 286.385 -377.772168) (xy 286.384448 -377.805507) (xy 286.375731 -377.871613)
			(xy 286.358455 -377.936014) (xy 286.332916 -377.997607) (xy 286.299551 -378.055337) (xy 286.258932 -378.108215)
			(xy 286.211756 -378.155336) (xy 286.18561 -378.176028) (xy 286.178764 -378.181672) (xy 286.169161 -378.196579)
			(xy 286.165226 -378.213868) (xy 286.167432 -378.231462) (xy 286.171132 -378.239528) (xy 286.18438 -378.266453)
			(xy 286.205208 -378.322731) (xy 286.219253 -378.381073) (xy 286.226322 -378.440664) (xy 286.226758 -378.470668)
			(xy 286.226256 -378.502629) (xy 286.218245 -378.566047) (xy 286.202348 -378.627961) (xy 286.178816 -378.687394)
			(xy 286.148022 -378.743409) (xy 286.110449 -378.795124) (xy 286.066692 -378.841721) (xy 286.017439 -378.882466)
			(xy 285.963468 -378.916717) (xy 285.905629 -378.943934) (xy 285.883156 -378.951236) (xy 289.295332 -378.951236)
			(xy 289.295786 -378.920539) (xy 289.303192 -378.859593) (xy 289.317888 -378.799984) (xy 289.339661 -378.74258)
			(xy 289.368192 -378.688219) (xy 289.385248 -378.662692) (xy 289.390685 -378.653922) (xy 289.39482 -378.63373)
			(xy 289.390709 -378.613533) (xy 289.385248 -378.60478) (xy 289.368212 -378.579243) (xy 289.339702 -378.524875)
			(xy 289.317938 -378.467473) (xy 289.303237 -378.407869) (xy 289.295813 -378.34693) (xy 289.295332 -378.316236)
			(xy 289.295772 -378.285503) (xy 289.303177 -378.224485) (xy 289.317884 -378.164805) (xy 289.339678 -378.107333)
			(xy 289.368241 -378.052907) (xy 289.403157 -378.002321) (xy 289.443916 -377.956313) (xy 289.489924 -377.915554)
			(xy 289.54051 -377.880639) (xy 289.594936 -377.852076) (xy 289.652409 -377.830282) (xy 289.712089 -377.815576)
			(xy 289.773107 -377.808171) (xy 289.80384 -377.807728) (xy 289.834537 -377.808195) (xy 289.895482 -377.815598)
			(xy 289.955091 -377.830292) (xy 290.012495 -377.852061) (xy 290.066857 -377.880589) (xy 290.092384 -377.897644)
			(xy 290.101136 -377.903115) (xy 290.12134 -377.907243) (xy 290.141544 -377.903115) (xy 290.150296 -377.897644)
			(xy 290.17584 -377.880618) (xy 290.230206 -377.852106) (xy 290.287606 -377.830341) (xy 290.347208 -377.815637)
			(xy 290.408146 -377.80821) (xy 290.43884 -377.807728) (xy 290.469537 -377.808195) (xy 290.530482 -377.815598)
			(xy 290.590091 -377.830292) (xy 290.647495 -377.852061) (xy 290.701857 -377.880589) (xy 290.727384 -377.897644)
			(xy 290.736136 -377.903115) (xy 290.75634 -377.907243) (xy 290.776544 -377.903115) (xy 290.785296 -377.897644)
			(xy 290.81084 -377.880618) (xy 290.865206 -377.852106) (xy 290.922606 -377.830341) (xy 290.982208 -377.815637)
			(xy 291.043146 -377.80821) (xy 291.07384 -377.807728) (xy 291.104537 -377.808195) (xy 291.165482 -377.815598)
			(xy 291.225091 -377.830292) (xy 291.282495 -377.852061) (xy 291.336857 -377.880589) (xy 291.362384 -377.897644)
			(xy 291.371136 -377.903115) (xy 291.39134 -377.907243) (xy 291.411544 -377.903115) (xy 291.420296 -377.897644)
			(xy 291.44584 -377.880618) (xy 291.500206 -377.852106) (xy 291.557606 -377.830341) (xy 291.617208 -377.815637)
			(xy 291.678146 -377.80821) (xy 291.70884 -377.807728) (xy 291.739537 -377.808195) (xy 291.800482 -377.815598)
			(xy 291.860091 -377.830292) (xy 291.917495 -377.852061) (xy 291.971857 -377.880589) (xy 291.997384 -377.897644)
			(xy 292.006136 -377.903115) (xy 292.02634 -377.907243) (xy 292.046544 -377.903115) (xy 292.055296 -377.897644)
			(xy 292.08084 -377.880618) (xy 292.135206 -377.852106) (xy 292.192606 -377.830341) (xy 292.252208 -377.815637)
			(xy 292.313146 -377.80821) (xy 292.34384 -377.807728) (xy 292.374537 -377.808195) (xy 292.435482 -377.815598)
			(xy 292.495091 -377.830292) (xy 292.552495 -377.852061) (xy 292.606857 -377.880589) (xy 292.632384 -377.897644)
			(xy 292.641136 -377.903115) (xy 292.66134 -377.907243) (xy 292.681544 -377.903115) (xy 292.690296 -377.897644)
			(xy 292.71584 -377.880618) (xy 292.770206 -377.852106) (xy 292.827606 -377.830341) (xy 292.887208 -377.815637)
			(xy 292.948146 -377.80821) (xy 292.97884 -377.807728) (xy 293.009537 -377.808195) (xy 293.070482 -377.815598)
			(xy 293.130091 -377.830292) (xy 293.187495 -377.852061) (xy 293.241857 -377.880589) (xy 293.267384 -377.897644)
			(xy 293.276136 -377.903115) (xy 293.29634 -377.907243) (xy 293.316544 -377.903115) (xy 293.325296 -377.897644)
			(xy 293.35084 -377.880618) (xy 293.405206 -377.852106) (xy 293.462606 -377.830341) (xy 293.522208 -377.815637)
			(xy 293.583146 -377.80821) (xy 293.61384 -377.807728) (xy 293.644537 -377.808195) (xy 293.705482 -377.815598)
			(xy 293.765091 -377.830292) (xy 293.822495 -377.852061) (xy 293.876857 -377.880589) (xy 293.902384 -377.897644)
			(xy 293.911136 -377.903115) (xy 293.93134 -377.907243) (xy 293.951544 -377.903115) (xy 293.960296 -377.897644)
			(xy 293.98584 -377.880618) (xy 294.040206 -377.852106) (xy 294.097606 -377.830341) (xy 294.157208 -377.815637)
			(xy 294.218146 -377.80821) (xy 294.24884 -377.807728) (xy 294.279573 -377.808118) (xy 294.340591 -377.815532)
			(xy 294.40027 -377.830246) (xy 294.457741 -377.852047) (xy 294.512165 -377.880616) (xy 294.562748 -377.915537)
			(xy 294.608753 -377.9563) (xy 294.64951 -378.002312) (xy 294.684423 -378.0529) (xy 294.712984 -378.107328)
			(xy 294.734776 -378.164802) (xy 294.749482 -378.224484) (xy 294.756887 -378.285503) (xy 294.757348 -378.316236)
			(xy 294.756883 -378.346933) (xy 294.74948 -378.407878) (xy 294.734787 -378.467487) (xy 294.713016 -378.524891)
			(xy 294.684487 -378.579253) (xy 294.667432 -378.60478) (xy 294.661926 -378.613514) (xy 294.657805 -378.63373)
			(xy 294.66195 -378.653941) (xy 294.667432 -378.662692) (xy 294.684453 -378.688239) (xy 294.712967 -378.742604)
			(xy 294.734733 -378.800003) (xy 294.749438 -378.859605) (xy 294.756865 -378.920542) (xy 294.757348 -378.951236)
			(xy 294.756878 -378.981966) (xy 294.749466 -379.042978) (xy 294.734755 -379.102652) (xy 294.712959 -379.160118)
			(xy 294.684395 -379.214538) (xy 294.649481 -379.265118) (xy 294.608725 -379.311122) (xy 294.562722 -379.351879)
			(xy 294.512141 -379.386793) (xy 294.457722 -379.415357) (xy 294.400256 -379.437154) (xy 294.340582 -379.451866)
			(xy 294.27957 -379.459278) (xy 294.24884 -379.459744) (xy 294.218144 -379.459274) (xy 294.157199 -379.45187)
			(xy 294.09759 -379.437177) (xy 294.040186 -379.415408) (xy 293.985824 -379.386882) (xy 293.960296 -379.369828)
			(xy 293.951544 -379.364357) (xy 293.93134 -379.360229) (xy 293.911136 -379.364357) (xy 293.902384 -379.369828)
			(xy 293.876844 -379.386859) (xy 293.822477 -379.415371) (xy 293.765076 -379.437136) (xy 293.705473 -379.451838)
			(xy 293.644534 -379.459263) (xy 293.61384 -379.459744) (xy 293.583144 -379.459274) (xy 293.522199 -379.45187)
			(xy 293.46259 -379.437177) (xy 293.405186 -379.415408) (xy 293.350824 -379.386882) (xy 293.325296 -379.369828)
			(xy 293.316544 -379.364357) (xy 293.29634 -379.360229) (xy 293.276136 -379.364357) (xy 293.267384 -379.369828)
			(xy 293.241844 -379.386859) (xy 293.187477 -379.415371) (xy 293.130076 -379.437136) (xy 293.070473 -379.451838)
			(xy 293.009534 -379.459263) (xy 292.97884 -379.459744) (xy 292.948144 -379.459274) (xy 292.887199 -379.45187)
			(xy 292.82759 -379.437177) (xy 292.770186 -379.415408) (xy 292.715824 -379.386882) (xy 292.690296 -379.369828)
			(xy 292.681544 -379.364357) (xy 292.66134 -379.360229) (xy 292.641136 -379.364357) (xy 292.632384 -379.369828)
			(xy 292.606844 -379.386859) (xy 292.552477 -379.415371) (xy 292.495076 -379.437136) (xy 292.435473 -379.451838)
			(xy 292.374534 -379.459263) (xy 292.34384 -379.459744) (xy 292.313144 -379.459274) (xy 292.252199 -379.45187)
			(xy 292.19259 -379.437177) (xy 292.135186 -379.415408) (xy 292.080824 -379.386882) (xy 292.055296 -379.369828)
			(xy 292.046544 -379.364357) (xy 292.02634 -379.360229) (xy 292.006136 -379.364357) (xy 291.997384 -379.369828)
			(xy 291.971844 -379.386859) (xy 291.917477 -379.415371) (xy 291.860076 -379.437136) (xy 291.800473 -379.451838)
			(xy 291.739534 -379.459263) (xy 291.70884 -379.459744) (xy 291.678144 -379.459274) (xy 291.617199 -379.45187)
			(xy 291.55759 -379.437177) (xy 291.500186 -379.415408) (xy 291.445824 -379.386882) (xy 291.420296 -379.369828)
			(xy 291.411544 -379.364357) (xy 291.39134 -379.360229) (xy 291.371136 -379.364357) (xy 291.362384 -379.369828)
			(xy 291.336844 -379.386859) (xy 291.282477 -379.415371) (xy 291.225076 -379.437136) (xy 291.165473 -379.451838)
			(xy 291.104534 -379.459263) (xy 291.07384 -379.459744) (xy 291.043144 -379.459274) (xy 290.982199 -379.45187)
			(xy 290.92259 -379.437177) (xy 290.865186 -379.415408) (xy 290.810824 -379.386882) (xy 290.785296 -379.369828)
			(xy 290.776544 -379.364357) (xy 290.75634 -379.360229) (xy 290.736136 -379.364357) (xy 290.727384 -379.369828)
			(xy 290.701844 -379.386859) (xy 290.647477 -379.415371) (xy 290.590076 -379.437136) (xy 290.530473 -379.451838)
			(xy 290.469534 -379.459263) (xy 290.43884 -379.459744) (xy 290.408144 -379.459274) (xy 290.347199 -379.45187)
			(xy 290.28759 -379.437177) (xy 290.230186 -379.415408) (xy 290.175824 -379.386882) (xy 290.150296 -379.369828)
			(xy 290.141544 -379.364357) (xy 290.12134 -379.360229) (xy 290.101136 -379.364357) (xy 290.092384 -379.369828)
			(xy 290.066844 -379.386859) (xy 290.012477 -379.415371) (xy 289.955076 -379.437136) (xy 289.895473 -379.451838)
			(xy 289.834534 -379.459263) (xy 289.80384 -379.459744) (xy 289.77311 -379.459225) (xy 289.712098 -379.451821)
			(xy 289.652423 -379.437118) (xy 289.594956 -379.415328) (xy 289.540533 -379.386771) (xy 289.48995 -379.351861)
			(xy 289.443944 -379.31111) (xy 289.403185 -379.265109) (xy 289.368269 -379.214532) (xy 289.339703 -379.160114)
			(xy 289.317905 -379.10265) (xy 289.303192 -379.042977) (xy 289.29578 -378.981966) (xy 289.295332 -378.951236)
			(xy 285.883156 -378.951236) (xy 285.844836 -378.963687) (xy 285.782046 -378.975665) (xy 285.71825 -378.979679)
			(xy 285.654454 -378.975665) (xy 285.591664 -378.963687) (xy 285.530871 -378.943934) (xy 285.473032 -378.916717)
			(xy 285.419061 -378.882466) (xy 285.369808 -378.841721) (xy 285.326051 -378.795124) (xy 285.288478 -378.743409)
			(xy 285.257684 -378.687394) (xy 285.234152 -378.627961) (xy 285.218255 -378.566047) (xy 285.210244 -378.502629)
			(xy 285.209742 -378.470668) (xy 280.726896 -378.470668) (xy 280.726896 -384.87858) (xy 286.799027 -384.87858)
			(xy 286.803034 -384.693676) (xy 286.815047 -384.509118) (xy 286.835043 -384.325254) (xy 286.862985 -384.14243)
			(xy 286.898821 -383.960987) (xy 286.942483 -383.781266) (xy 286.99389 -383.603606) (xy 287.052944 -383.42834)
			(xy 287.119535 -383.255796) (xy 287.193538 -383.086299) (xy 287.274814 -382.920167) (xy 287.36321 -382.757711)
			(xy 287.458561 -382.599237) (xy 287.560687 -382.445042) (xy 287.669396 -382.295416) (xy 287.784485 -382.15064)
			(xy 287.905738 -382.010985) (xy 288.032927 -381.876714) (xy 288.165812 -381.748078) (xy 288.304146 -381.625319)
			(xy 288.447667 -381.508669) (xy 288.596106 -381.398345) (xy 288.749186 -381.294554) (xy 288.906617 -381.197492)
			(xy 289.068106 -381.107342) (xy 289.233348 -381.024271) (xy 289.402034 -380.948436) (xy 289.573846 -380.87998)
			(xy 289.748462 -380.81903) (xy 289.925555 -380.765703) (xy 290.104792 -380.720096) (xy 290.285836 -380.682297)
			(xy 290.468347 -380.652376) (xy 290.651984 -380.630389) (xy 290.8364 -380.616377) (xy 291.02125 -380.610367)
			(xy 291.206187 -380.612371) (xy 291.390864 -380.622384) (xy 291.574934 -380.640387) (xy 291.75805 -380.666348)
			(xy 291.939871 -380.700216) (xy 292.120054 -380.741928) (xy 292.29826 -380.791407) (xy 292.474156 -380.848559)
			(xy 292.647411 -380.913277) (xy 292.8177 -380.98544) (xy 292.984703 -381.064911) (xy 293.148107 -381.151542)
			(xy 293.307604 -381.245171) (xy 293.462896 -381.34562) (xy 293.613691 -381.452703) (xy 293.759706 -381.566217)
			(xy 293.900666 -381.685949) (xy 294.036307 -381.811676) (xy 294.166375 -381.94316) (xy 294.290625 -382.080156)
			(xy 294.408823 -382.222405) (xy 294.520749 -382.36964) (xy 294.626192 -382.521586) (xy 294.724953 -382.677957)
			(xy 294.816848 -382.83846) (xy 294.901704 -383.002792) (xy 294.979362 -383.170647) (xy 295.049675 -383.341707)
			(xy 295.112512 -383.515653) (xy 295.167756 -383.692158) (xy 295.215301 -383.87089) (xy 295.255059 -384.051514)
			(xy 295.286956 -384.233691) (xy 295.310931 -384.417078) (xy 295.326939 -384.601332) (xy 295.334951 -384.786106)
			(xy 295.335452 -384.87858) (xy 295.334951 -384.971054) (xy 295.326939 -385.155828) (xy 295.310931 -385.340082)
			(xy 295.286956 -385.523469) (xy 295.255059 -385.705646) (xy 295.215301 -385.88627) (xy 295.167756 -386.065002)
			(xy 295.112512 -386.241507) (xy 295.049675 -386.415453) (xy 294.979362 -386.586513) (xy 294.901704 -386.754368)
			(xy 294.816848 -386.9187) (xy 294.724953 -387.079203) (xy 294.626192 -387.235574) (xy 294.520749 -387.38752)
			(xy 294.408823 -387.534755) (xy 294.290625 -387.677004) (xy 294.166375 -387.814) (xy 294.036307 -387.945484)
			(xy 293.900666 -388.071211) (xy 293.759706 -388.190943) (xy 293.613691 -388.304457) (xy 293.462896 -388.41154)
			(xy 293.307604 -388.511989) (xy 293.148107 -388.605618) (xy 292.984703 -388.692249) (xy 292.8177 -388.77172)
			(xy 292.647411 -388.843883) (xy 292.474156 -388.908601) (xy 292.29826 -388.965753) (xy 292.120054 -389.015232)
			(xy 291.939871 -389.056944) (xy 291.75805 -389.090812) (xy 291.574934 -389.116773) (xy 291.390864 -389.134776)
			(xy 291.206187 -389.144789) (xy 291.02125 -389.146793) (xy 290.8364 -389.140783) (xy 290.651984 -389.126771)
			(xy 290.468347 -389.104784) (xy 290.285836 -389.074863) (xy 290.104792 -389.037064) (xy 289.925555 -388.991457)
			(xy 289.748462 -388.93813) (xy 289.573846 -388.87718) (xy 289.402034 -388.808724) (xy 289.233348 -388.732889)
			(xy 289.068106 -388.649818) (xy 288.906617 -388.559668) (xy 288.749186 -388.462606) (xy 288.596106 -388.358815)
			(xy 288.447667 -388.248491) (xy 288.304146 -388.131841) (xy 288.165812 -388.009082) (xy 288.032927 -387.880446)
			(xy 287.905738 -387.746175) (xy 287.784485 -387.60652) (xy 287.669396 -387.461744) (xy 287.560687 -387.312118)
			(xy 287.458561 -387.157923) (xy 287.36321 -386.999449) (xy 287.274814 -386.836993) (xy 287.193538 -386.670861)
			(xy 287.119535 -386.501364) (xy 287.052944 -386.32882) (xy 286.99389 -386.153554) (xy 286.942483 -385.975894)
			(xy 286.898821 -385.796173) (xy 286.862985 -385.61473) (xy 286.835043 -385.431906) (xy 286.815047 -385.248042)
			(xy 286.803034 -385.063484) (xy 286.799027 -384.87858) (xy 280.726896 -384.87858) (xy 280.726896 -391.23112)
			(xy 280.727323 -391.241189) (xy 280.735042 -391.259788) (xy 280.741882 -391.267188) (xy 281.867864 -392.39317)
			(xy 281.874703 -392.400571) (xy 281.881853 -392.417808) (xy 289.316922 -392.417808) (xy 289.317364 -392.387111)
			(xy 289.324773 -392.326165) (xy 289.339472 -392.266555) (xy 289.361247 -392.209152) (xy 289.389781 -392.15479)
			(xy 289.406838 -392.129264) (xy 289.4123 -392.120507) (xy 289.416428 -392.100307) (xy 289.412305 -392.080105)
			(xy 289.406838 -392.071352) (xy 289.389789 -392.045823) (xy 289.361281 -391.991453) (xy 289.33952 -391.934049)
			(xy 289.324822 -391.874443) (xy 289.317401 -391.813503) (xy 289.316922 -391.782808) (xy 289.317364 -391.752111)
			(xy 289.324773 -391.691165) (xy 289.339472 -391.631555) (xy 289.361247 -391.574152) (xy 289.389781 -391.51979)
			(xy 289.406838 -391.494264) (xy 289.4123 -391.485507) (xy 289.416428 -391.465307) (xy 289.412305 -391.445105)
			(xy 289.406838 -391.436352) (xy 289.389789 -391.410823) (xy 289.361281 -391.356453) (xy 289.33952 -391.299049)
			(xy 289.324822 -391.239443) (xy 289.317401 -391.178503) (xy 289.316922 -391.147808) (xy 289.317364 -391.117111)
			(xy 289.324773 -391.056165) (xy 289.339472 -390.996555) (xy 289.361247 -390.939152) (xy 289.389781 -390.88479)
			(xy 289.406838 -390.859264) (xy 289.4123 -390.850507) (xy 289.416428 -390.830307) (xy 289.412305 -390.810105)
			(xy 289.406838 -390.801352) (xy 289.389789 -390.775823) (xy 289.361281 -390.721453) (xy 289.33952 -390.664049)
			(xy 289.324822 -390.604443) (xy 289.317401 -390.543503) (xy 289.316922 -390.512808) (xy 289.317364 -390.482111)
			(xy 289.324773 -390.421165) (xy 289.339472 -390.361555) (xy 289.361247 -390.304152) (xy 289.389781 -390.24979)
			(xy 289.406838 -390.224264) (xy 289.4123 -390.215507) (xy 289.416428 -390.195307) (xy 289.412305 -390.175105)
			(xy 289.406838 -390.166352) (xy 289.389789 -390.140823) (xy 289.361281 -390.086453) (xy 289.33952 -390.029049)
			(xy 289.324822 -389.969443) (xy 289.317401 -389.908503) (xy 289.316922 -389.877808) (xy 289.317345 -389.847075)
			(xy 289.324754 -389.786057) (xy 289.339463 -389.726377) (xy 289.361259 -389.668905) (xy 289.389825 -389.614479)
			(xy 289.424742 -389.563894) (xy 289.465502 -389.517887) (xy 289.511512 -389.477128) (xy 289.562098 -389.442213)
			(xy 289.616525 -389.41365) (xy 289.673998 -389.391857) (xy 289.733678 -389.37715) (xy 289.794697 -389.369744)
			(xy 289.82543 -389.3693) (xy 289.856126 -389.369777) (xy 289.917071 -389.377179) (xy 289.97668 -389.39187)
			(xy 290.034084 -389.413637) (xy 290.088446 -389.442163) (xy 290.113974 -389.459216) (xy 290.122726 -389.464687)
			(xy 290.14293 -389.468815) (xy 290.163134 -389.464687) (xy 290.171886 -389.459216) (xy 290.19743 -389.442191)
			(xy 290.251796 -389.41368) (xy 290.309197 -389.391914) (xy 290.368799 -389.377211) (xy 290.429736 -389.369783)
			(xy 290.46043 -389.3693) (xy 290.491126 -389.369777) (xy 290.552071 -389.377179) (xy 290.61168 -389.39187)
			(xy 290.669084 -389.413637) (xy 290.723446 -389.442163) (xy 290.748974 -389.459216) (xy 290.757726 -389.464687)
			(xy 290.77793 -389.468815) (xy 290.798134 -389.464687) (xy 290.806886 -389.459216) (xy 290.83243 -389.442191)
			(xy 290.886796 -389.41368) (xy 290.944197 -389.391914) (xy 291.003799 -389.377211) (xy 291.064736 -389.369783)
			(xy 291.09543 -389.3693) (xy 291.126126 -389.369777) (xy 291.187071 -389.377179) (xy 291.24668 -389.39187)
			(xy 291.304084 -389.413637) (xy 291.358446 -389.442163) (xy 291.383974 -389.459216) (xy 291.392726 -389.464687)
			(xy 291.41293 -389.468815) (xy 291.433134 -389.464687) (xy 291.441886 -389.459216) (xy 291.46743 -389.442191)
			(xy 291.521796 -389.41368) (xy 291.579197 -389.391914) (xy 291.638799 -389.377211) (xy 291.699736 -389.369783)
			(xy 291.73043 -389.3693) (xy 291.761126 -389.369777) (xy 291.822071 -389.377179) (xy 291.88168 -389.39187)
			(xy 291.939084 -389.413637) (xy 291.993446 -389.442163) (xy 292.018974 -389.459216) (xy 292.027726 -389.464687)
			(xy 292.04793 -389.468815) (xy 292.068134 -389.464687) (xy 292.076886 -389.459216) (xy 292.10243 -389.442191)
			(xy 292.156796 -389.41368) (xy 292.214197 -389.391914) (xy 292.273799 -389.377211) (xy 292.334736 -389.369783)
			(xy 292.36543 -389.3693) (xy 292.396126 -389.369777) (xy 292.457071 -389.377179) (xy 292.51668 -389.39187)
			(xy 292.574084 -389.413637) (xy 292.628446 -389.442163) (xy 292.653974 -389.459216) (xy 292.662726 -389.464687)
			(xy 292.68293 -389.468815) (xy 292.703134 -389.464687) (xy 292.711886 -389.459216) (xy 292.73743 -389.442191)
			(xy 292.791796 -389.41368) (xy 292.849197 -389.391914) (xy 292.908799 -389.377211) (xy 292.969736 -389.369783)
			(xy 293.00043 -389.3693) (xy 293.031162 -389.369728) (xy 293.092177 -389.37714) (xy 293.151854 -389.391852)
			(xy 293.209323 -389.413651) (xy 293.263745 -389.442217) (xy 293.314328 -389.477134) (xy 293.360333 -389.517894)
			(xy 293.401089 -389.563902) (xy 293.436003 -389.614487) (xy 293.464565 -389.668912) (xy 293.486359 -389.726382)
			(xy 293.501067 -389.78606) (xy 293.508474 -389.847076) (xy 293.508938 -389.877808) (xy 293.508443 -389.908504)
			(xy 293.501045 -389.969447) (xy 293.486357 -390.029056) (xy 293.464594 -390.08646) (xy 293.436073 -390.140824)
			(xy 293.419022 -390.166352) (xy 293.413541 -390.175099) (xy 293.409413 -390.195307) (xy 293.413546 -390.215513)
			(xy 293.419022 -390.224264) (xy 293.436074 -390.249792) (xy 293.464582 -390.304162) (xy 293.486343 -390.361566)
			(xy 293.50104 -390.421172) (xy 293.50846 -390.482113) (xy 293.508938 -390.512808) (xy 293.508443 -390.543504)
			(xy 293.501045 -390.604447) (xy 293.486357 -390.664056) (xy 293.464594 -390.72146) (xy 293.436073 -390.775824)
			(xy 293.419022 -390.801352) (xy 293.413541 -390.810099) (xy 293.409413 -390.830307) (xy 293.413546 -390.850513)
			(xy 293.419022 -390.859264) (xy 293.436074 -390.884792) (xy 293.464582 -390.939162) (xy 293.486343 -390.996566)
			(xy 293.50104 -391.056172) (xy 293.50846 -391.117113) (xy 293.508938 -391.147808) (xy 293.508443 -391.178504)
			(xy 293.501045 -391.239447) (xy 293.486357 -391.299056) (xy 293.464594 -391.35646) (xy 293.436073 -391.410824)
			(xy 293.419022 -391.436352) (xy 293.413541 -391.445099) (xy 293.409413 -391.465307) (xy 293.413546 -391.485513)
			(xy 293.419022 -391.494264) (xy 293.436074 -391.519792) (xy 293.464582 -391.574162) (xy 293.486343 -391.631566)
			(xy 293.50104 -391.691172) (xy 293.50846 -391.752113) (xy 293.508938 -391.782808) (xy 293.508443 -391.813504)
			(xy 293.501045 -391.874447) (xy 293.486357 -391.934056) (xy 293.464594 -391.99146) (xy 293.436073 -392.045824)
			(xy 293.419022 -392.071352) (xy 293.413541 -392.080099) (xy 293.409413 -392.100307) (xy 293.413546 -392.120513)
			(xy 293.419022 -392.129264) (xy 293.436074 -392.154792) (xy 293.464582 -392.209162) (xy 293.486343 -392.266566)
			(xy 293.50104 -392.326172) (xy 293.50846 -392.387113) (xy 293.508938 -392.417808) (xy 293.508451 -392.448538)
			(xy 293.501043 -392.50955) (xy 293.486334 -392.569224) (xy 293.46454 -392.62669) (xy 293.435979 -392.68111)
			(xy 293.401066 -392.731692) (xy 293.360311 -392.777696) (xy 293.314309 -392.818452) (xy 293.263729 -392.853367)
			(xy 293.20931 -392.881931) (xy 293.151845 -392.903728) (xy 293.092172 -392.918439) (xy 293.03116 -392.92585)
			(xy 293.00043 -392.926316) (xy 292.969733 -392.925856) (xy 292.908788 -392.91845) (xy 292.849179 -392.903755)
			(xy 292.791775 -392.881984) (xy 292.737413 -392.853455) (xy 292.711886 -392.8364) (xy 292.703134 -392.830929)
			(xy 292.68293 -392.826801) (xy 292.662726 -392.830929) (xy 292.653974 -392.8364) (xy 292.628442 -392.853444)
			(xy 292.574072 -392.881952) (xy 292.516669 -392.903713) (xy 292.457064 -392.918412) (xy 292.396125 -392.925836)
			(xy 292.36543 -392.926316) (xy 292.334733 -392.925856) (xy 292.273788 -392.91845) (xy 292.214179 -392.903755)
			(xy 292.156775 -392.881984) (xy 292.102413 -392.853455) (xy 292.076886 -392.8364) (xy 292.068134 -392.830929)
			(xy 292.04793 -392.826801) (xy 292.027726 -392.830929) (xy 292.018974 -392.8364) (xy 291.993442 -392.853444)
			(xy 291.939072 -392.881952) (xy 291.881669 -392.903713) (xy 291.822064 -392.918412) (xy 291.761125 -392.925836)
			(xy 291.73043 -392.926316) (xy 291.699733 -392.925856) (xy 291.638788 -392.91845) (xy 291.579179 -392.903755)
			(xy 291.521775 -392.881984) (xy 291.467413 -392.853455) (xy 291.441886 -392.8364) (xy 291.433134 -392.830929)
			(xy 291.41293 -392.826801) (xy 291.392726 -392.830929) (xy 291.383974 -392.8364) (xy 291.358442 -392.853444)
			(xy 291.304072 -392.881952) (xy 291.246669 -392.903713) (xy 291.187064 -392.918412) (xy 291.126125 -392.925836)
			(xy 291.09543 -392.926316) (xy 291.064733 -392.925856) (xy 291.003788 -392.91845) (xy 290.944179 -392.903755)
			(xy 290.886775 -392.881984) (xy 290.832413 -392.853455) (xy 290.806886 -392.8364) (xy 290.798134 -392.830929)
			(xy 290.77793 -392.826801) (xy 290.757726 -392.830929) (xy 290.748974 -392.8364) (xy 290.723442 -392.853444)
			(xy 290.669072 -392.881952) (xy 290.611669 -392.903713) (xy 290.552064 -392.918412) (xy 290.491125 -392.925836)
			(xy 290.46043 -392.926316) (xy 290.429733 -392.925856) (xy 290.368788 -392.91845) (xy 290.309179 -392.903755)
			(xy 290.251775 -392.881984) (xy 290.197413 -392.853455) (xy 290.171886 -392.8364) (xy 290.163134 -392.830929)
			(xy 290.14293 -392.826801) (xy 290.122726 -392.830929) (xy 290.113974 -392.8364) (xy 290.088442 -392.853444)
			(xy 290.034072 -392.881952) (xy 289.976669 -392.903713) (xy 289.917064 -392.918412) (xy 289.856125 -392.925836)
			(xy 289.82543 -392.926316) (xy 289.794699 -392.925834) (xy 289.733684 -392.918429) (xy 289.674007 -392.903723)
			(xy 289.616538 -392.881931) (xy 289.562114 -392.853371) (xy 289.51153 -392.818458) (xy 289.465524 -392.777703)
			(xy 289.424765 -392.731699) (xy 289.389849 -392.681118) (xy 289.361284 -392.626697) (xy 289.339488 -392.569229)
			(xy 289.324778 -392.509553) (xy 289.317368 -392.448539) (xy 289.316922 -392.417808) (xy 281.881853 -392.417808)
			(xy 281.882418 -392.419169) (xy 281.88285 -392.429238) (xy 281.88285 -393.137855) (xy 282.07436 -393.137855)
			(xy 282.07436 -393.073933) (xy 282.082371 -393.010515) (xy 282.098268 -392.948601) (xy 282.1218 -392.889168)
			(xy 282.152594 -392.833153) (xy 282.190167 -392.781438) (xy 282.233924 -392.734841) (xy 282.283177 -392.694096)
			(xy 282.337148 -392.659845) (xy 282.394987 -392.632628) (xy 282.45578 -392.612875) (xy 282.51857 -392.600897)
			(xy 282.582366 -392.596884) (xy 282.646162 -392.600897) (xy 282.708952 -392.612875) (xy 282.769745 -392.632628)
			(xy 282.827584 -392.659845) (xy 282.881555 -392.694096) (xy 282.930808 -392.734841) (xy 282.974565 -392.781438)
			(xy 283.012138 -392.833153) (xy 283.042932 -392.889168) (xy 283.066464 -392.948601) (xy 283.082361 -393.010515)
			(xy 283.090372 -393.073933) (xy 283.090874 -393.105894) (xy 283.090372 -393.137855) (xy 283.082361 -393.201273)
			(xy 283.066464 -393.263187) (xy 283.042932 -393.32262) (xy 283.012138 -393.378635) (xy 282.974565 -393.43035)
			(xy 282.930808 -393.476947) (xy 282.881555 -393.517692) (xy 282.827584 -393.551943) (xy 282.769745 -393.57916)
			(xy 282.708952 -393.598913) (xy 282.646162 -393.610891) (xy 282.582366 -393.614905) (xy 282.51857 -393.610891)
			(xy 282.45578 -393.598913) (xy 282.394987 -393.57916) (xy 282.337148 -393.551943) (xy 282.283177 -393.517692)
			(xy 282.233924 -393.476947) (xy 282.190167 -393.43035) (xy 282.152594 -393.378635) (xy 282.1218 -393.32262)
			(xy 282.098268 -393.263187) (xy 282.082371 -393.201273) (xy 282.07436 -393.137855) (xy 281.88285 -393.137855)
			(xy 281.88285 -394.070078) (xy 283.861 -394.070078) (xy 283.865071 -394.014456) (xy 283.877197 -393.960019)
			(xy 283.89712 -393.907928) (xy 283.924416 -393.859293) (xy 283.958502 -393.81515) (xy 283.998651 -393.776441)
			(xy 284.044009 -393.74399) (xy 284.093609 -393.718489) (xy 284.146393 -393.700482) (xy 284.201236 -393.690352)
			(xy 284.25697 -393.688315) (xy 284.312407 -393.694415) (xy 284.366364 -393.708521) (xy 284.417693 -393.730333)
			(xy 284.465299 -393.759387) (xy 284.508167 -393.795062) (xy 284.545384 -393.836599) (xy 284.576157 -393.883112)
			(xy 284.599829 -393.933609) (xy 284.615897 -393.987016) (xy 284.61758 -393.99845) (xy 294.51046 -393.99845)
			(xy 294.510873 -393.968733) (xy 294.517813 -393.909705) (xy 294.531581 -393.851888) (xy 294.55199 -393.796068)
			(xy 294.578761 -393.743004) (xy 294.611531 -393.69342) (xy 294.649853 -393.647991) (xy 294.671242 -393.627356)
			(xy 294.678608 -393.620498) (xy 294.686736 -393.603226) (xy 294.692324 -393.514072) (xy 294.686228 -393.49553)
			(xy 294.679878 -393.488164) (xy 294.663231 -393.467504) (xy 294.635233 -393.422437) (xy 294.61376 -393.373921)
			(xy 294.599228 -393.322894) (xy 294.591918 -393.270344) (xy 294.591486 -393.243816) (xy 294.59201 -393.216113)
			(xy 294.600049 -393.161294) (xy 294.615932 -393.108213) (xy 294.639324 -393.057987) (xy 294.669733 -393.011673)
			(xy 294.706521 -392.970243) (xy 294.748914 -392.934568) (xy 294.796021 -392.9054) (xy 294.84685 -392.88335)
			(xy 294.900334 -392.868884) (xy 294.927782 -392.865102) (xy 294.937688 -392.863832) (xy 294.954198 -392.854942)
			(xy 295.011856 -392.78687) (xy 295.017698 -392.768836) (xy 295.017444 -392.75893) (xy 295.016682 -392.73353)
			(xy 295.017136 -392.701987) (xy 295.024936 -392.639384) (xy 295.040419 -392.578226) (xy 295.063349 -392.519454)
			(xy 295.093372 -392.463969) (xy 295.130028 -392.412624) (xy 295.172753 -392.366208) (xy 295.220892 -392.325433)
			(xy 295.273705 -392.290925) (xy 295.33038 -392.263216) (xy 295.390048 -392.242729) (xy 295.451792 -392.22978)
			(xy 295.514663 -392.224569) (xy 295.577696 -392.227174) (xy 295.639923 -392.237555) (xy 295.700387 -392.255555)
			(xy 295.758161 -392.280895) (xy 295.812357 -392.313187) (xy 295.862142 -392.351935) (xy 295.906752 -392.396543)
			(xy 295.945502 -392.446327) (xy 295.977796 -392.500521) (xy 296.003138 -392.558294) (xy 296.02114 -392.618758)
			(xy 296.031524 -392.680984) (xy 296.034132 -392.744017) (xy 296.028922 -392.806889) (xy 296.015976 -392.868633)
			(xy 295.995492 -392.928301) (xy 295.967785 -392.984978) (xy 295.933279 -393.037792) (xy 295.892506 -393.085932)
			(xy 295.846091 -393.12866) (xy 295.794748 -393.165317) (xy 295.739264 -393.195343) (xy 295.680493 -393.218275)
			(xy 295.619336 -393.233761) (xy 295.556733 -393.241563) (xy 295.52519 -393.242038) (xy 295.508759 -393.241884)
			(xy 295.475967 -393.239723) (xy 295.459658 -393.23772) (xy 295.450006 -393.23645) (xy 295.431718 -393.241276)
			(xy 295.359328 -393.293092) (xy 295.348914 -393.30884) (xy 295.347136 -393.318746) (xy 295.342089 -393.342115)
			(xy 295.326919 -393.387455) (xy 295.3062 -393.430544) (xy 295.293542 -393.450826) (xy 295.288208 -393.458954)
			(xy 295.284398 -393.478004) (xy 295.300654 -393.565634) (xy 295.311068 -393.582144) (xy 295.318942 -393.587732)
			(xy 295.346205 -393.60832) (xy 295.39547 -393.655652) (xy 295.437957 -393.709153) (xy 295.4729 -393.767859)
			(xy 295.499672 -393.830714) (xy 295.517789 -393.896586) (xy 295.526927 -393.964291) (xy 295.527476 -393.99845)
			(xy 295.526974 -394.030411) (xy 295.518963 -394.093829) (xy 295.503066 -394.155743) (xy 295.479534 -394.215176)
			(xy 295.44874 -394.271191) (xy 295.411167 -394.322906) (xy 295.36741 -394.369503) (xy 295.318157 -394.410248)
			(xy 295.264186 -394.444499) (xy 295.206347 -394.471716) (xy 295.145554 -394.491469) (xy 295.082764 -394.503447)
			(xy 295.018968 -394.507461) (xy 294.955172 -394.503447) (xy 294.892382 -394.491469) (xy 294.831589 -394.471716)
			(xy 294.77375 -394.444499) (xy 294.719779 -394.410248) (xy 294.670526 -394.369503) (xy 294.626769 -394.322906)
			(xy 294.589196 -394.271191) (xy 294.558402 -394.215176) (xy 294.53487 -394.155743) (xy 294.518973 -394.093829)
			(xy 294.510962 -394.030411) (xy 294.51046 -393.99845) (xy 284.61758 -393.99845) (xy 284.624017 -394.042192)
			(xy 284.624526 -394.070078) (xy 284.624017 -394.097964) (xy 284.615897 -394.15314) (xy 284.599829 -394.206547)
			(xy 284.576157 -394.257044) (xy 284.545384 -394.303557) (xy 284.508167 -394.345094) (xy 284.465299 -394.380769)
			(xy 284.417693 -394.409823) (xy 284.366364 -394.431635) (xy 284.312407 -394.445741) (xy 284.25697 -394.451841)
			(xy 284.201236 -394.449804) (xy 284.146393 -394.439674) (xy 284.093609 -394.421667) (xy 284.044009 -394.396166)
			(xy 283.998651 -394.363715) (xy 283.958502 -394.325006) (xy 283.924416 -394.280863) (xy 283.89712 -394.232228)
			(xy 283.877197 -394.180137) (xy 283.865071 -394.1257) (xy 283.861 -394.070078) (xy 281.88285 -394.070078)
			(xy 281.88285 -394.556234) (xy 287.918904 -394.556234) (xy 287.922975 -394.500612) (xy 287.935101 -394.446175)
			(xy 287.955024 -394.394084) (xy 287.98232 -394.345449) (xy 288.016406 -394.301306) (xy 288.056555 -394.262597)
			(xy 288.101913 -394.230146) (xy 288.151513 -394.204645) (xy 288.204297 -394.186638) (xy 288.25914 -394.176508)
			(xy 288.314874 -394.174471) (xy 288.370311 -394.180571) (xy 288.424268 -394.194677) (xy 288.475597 -394.216489)
			(xy 288.523203 -394.245543) (xy 288.566071 -394.281218) (xy 288.603288 -394.322755) (xy 288.634061 -394.369268)
			(xy 288.657733 -394.419765) (xy 288.673801 -394.473172) (xy 288.681921 -394.528348) (xy 288.68243 -394.556234)
			(xy 288.681921 -394.58412) (xy 288.673801 -394.639296) (xy 288.657733 -394.692703) (xy 288.634061 -394.7432)
			(xy 288.603288 -394.789713) (xy 288.566071 -394.83125) (xy 288.523203 -394.866925) (xy 288.475597 -394.895979)
			(xy 288.424268 -394.917791) (xy 288.370311 -394.931897) (xy 288.314874 -394.937997) (xy 288.25914 -394.93596)
			(xy 288.204297 -394.92583) (xy 288.151513 -394.907823) (xy 288.101913 -394.882322) (xy 288.056555 -394.849871)
			(xy 288.016406 -394.811162) (xy 287.98232 -394.767019) (xy 287.955024 -394.718384) (xy 287.935101 -394.666293)
			(xy 287.922975 -394.611856) (xy 287.918904 -394.556234) (xy 281.88285 -394.556234) (xy 281.88285 -395.343083)
			(xy 283.83458 -395.343083) (xy 283.83458 -395.279161) (xy 283.842591 -395.215743) (xy 283.858488 -395.153829)
			(xy 283.88202 -395.094396) (xy 283.912814 -395.038381) (xy 283.950387 -394.986666) (xy 283.994144 -394.940069)
			(xy 284.043397 -394.899324) (xy 284.097368 -394.865073) (xy 284.155207 -394.837856) (xy 284.216 -394.818103)
			(xy 284.27879 -394.806125) (xy 284.342586 -394.802112) (xy 284.406382 -394.806125) (xy 284.469172 -394.818103)
			(xy 284.529965 -394.837856) (xy 284.587804 -394.865073) (xy 284.641775 -394.899324) (xy 284.691028 -394.940069)
			(xy 284.734785 -394.986666) (xy 284.772358 -395.038381) (xy 284.803152 -395.094396) (xy 284.826684 -395.153829)
			(xy 284.842581 -395.215743) (xy 284.848002 -395.258657) (xy 292.070421 -395.258657) (xy 292.070421 -395.204143)
			(xy 292.07818 -395.150184) (xy 292.093539 -395.097879) (xy 292.116186 -395.048292) (xy 292.14566 -395.002433)
			(xy 292.181361 -394.961235) (xy 292.222562 -394.925538) (xy 292.268423 -394.896069) (xy 292.318012 -394.873426)
			(xy 292.370319 -394.858072) (xy 292.424279 -394.850318) (xy 292.451536 -394.849858) (xy 292.480512 -394.850422)
			(xy 292.537797 -394.859202) (xy 292.593091 -394.876553) (xy 292.645122 -394.902075) (xy 292.669214 -394.918184)
			(xy 292.677342 -394.923772) (xy 292.69563 -394.92809) (xy 292.783514 -394.915644) (xy 292.800024 -394.906246)
			(xy 292.80612 -394.898626) (xy 292.826876 -394.873816) (xy 292.873641 -394.829124) (xy 292.925693 -394.790721)
			(xy 292.982194 -394.759226) (xy 293.042232 -394.735147) (xy 293.104837 -394.718873) (xy 293.169001 -394.710666)
			(xy 293.201344 -394.710158) (xy 293.230878 -394.710582) (xy 293.289552 -394.717396) (xy 293.347041 -394.730963)
			(xy 293.402572 -394.751098) (xy 293.455395 -394.777532) (xy 293.5048 -394.809908) (xy 293.527734 -394.828522)
			(xy 293.534635 -394.833887) (xy 293.551009 -394.839977) (xy 293.559738 -394.84046) (xy 293.58971 -394.840714)
			(xy 293.598524 -394.840409) (xy 293.615148 -394.834553) (xy 293.622222 -394.829284) (xy 293.649509 -394.807843)
			(xy 293.708825 -394.771823) (xy 293.772489 -394.744207) (xy 293.839319 -394.725509) (xy 293.908072 -394.716078)
			(xy 293.94277 -394.715492) (xy 293.973501 -394.715966) (xy 294.034517 -394.723371) (xy 294.094194 -394.738077)
			(xy 294.151664 -394.75987) (xy 294.206088 -394.788431) (xy 294.256672 -394.823344) (xy 294.302679 -394.8641)
			(xy 294.343438 -394.910104) (xy 294.378354 -394.960686) (xy 294.406918 -395.015109) (xy 294.428714 -395.072577)
			(xy 294.443424 -395.132254) (xy 294.450832 -395.193269) (xy 294.451278 -395.224) (xy 294.450836 -395.254943)
			(xy 294.443347 -395.316375) (xy 294.428457 -395.376444) (xy 294.406385 -395.43426) (xy 294.377458 -395.48897)
			(xy 294.342103 -395.539764) (xy 294.300844 -395.58589) (xy 294.254291 -395.626667) (xy 294.203132 -395.661491)
			(xy 294.148124 -395.689847) (xy 294.090081 -395.711316) (xy 294.02986 -395.72558) (xy 293.999158 -395.72946)
			(xy 293.987474 -395.73073) (xy 293.96817 -395.742922) (xy 293.913306 -395.82979) (xy 293.910766 -395.85265)
			(xy 293.914576 -395.863572) (xy 293.923526 -395.890516) (xy 293.936089 -395.945887) (xy 293.942393 -396.002315)
			(xy 293.94277 -396.030704) (xy 293.942268 -396.062665) (xy 293.934257 -396.126083) (xy 293.91836 -396.187997)
			(xy 293.894828 -396.24743) (xy 293.864034 -396.303445) (xy 293.826461 -396.35516) (xy 293.782704 -396.401757)
			(xy 293.733451 -396.442502) (xy 293.67948 -396.476753) (xy 293.621641 -396.50397) (xy 293.560848 -396.523723)
			(xy 293.498058 -396.535701) (xy 293.434262 -396.539715) (xy 293.370466 -396.535701) (xy 293.307676 -396.523723)
			(xy 293.246883 -396.50397) (xy 293.189044 -396.476753) (xy 293.135073 -396.442502) (xy 293.08582 -396.401757)
			(xy 293.042063 -396.35516) (xy 293.00449 -396.303445) (xy 292.973696 -396.24743) (xy 292.950164 -396.187997)
			(xy 292.934267 -396.126083) (xy 292.926256 -396.062665) (xy 292.925754 -396.030704) (xy 292.926194 -395.999843)
			(xy 292.93364 -395.938571) (xy 292.948458 -395.878654) (xy 292.97043 -395.820975) (xy 292.984428 -395.793468)
			(xy 292.989254 -395.784578) (xy 292.991032 -395.765274) (xy 292.96614 -395.678406) (xy 292.954456 -395.663166)
			(xy 292.94582 -395.65834) (xy 292.921862 -395.64395) (xy 292.87692 -395.610727) (xy 292.835893 -395.572775)
			(xy 292.817296 -395.551914) (xy 292.810946 -395.544548) (xy 292.794182 -395.535658) (xy 292.70579 -395.52626)
			(xy 292.687502 -395.53134) (xy 292.679628 -395.537182) (xy 292.654741 -395.554957) (xy 292.60052 -395.583237)
			(xy 292.542481 -395.602505) (xy 292.482112 -395.612266) (xy 292.451536 -395.612874) (xy 292.424279 -395.612482)
			(xy 292.370319 -395.604728) (xy 292.318012 -395.589374) (xy 292.268423 -395.566731) (xy 292.222562 -395.537262)
			(xy 292.181361 -395.501565) (xy 292.14566 -395.460367) (xy 292.116186 -395.414508) (xy 292.093539 -395.364921)
			(xy 292.07818 -395.312616) (xy 292.070421 -395.258657) (xy 284.848002 -395.258657) (xy 284.850592 -395.279161)
			(xy 284.851094 -395.311122) (xy 284.850592 -395.343083) (xy 284.842581 -395.406501) (xy 284.826684 -395.468415)
			(xy 284.803152 -395.527848) (xy 284.772358 -395.583863) (xy 284.734785 -395.635578) (xy 284.691028 -395.682175)
			(xy 284.641775 -395.72292) (xy 284.587804 -395.757171) (xy 284.529965 -395.784388) (xy 284.469172 -395.804141)
			(xy 284.406382 -395.816119) (xy 284.342586 -395.820133) (xy 284.27879 -395.816119) (xy 284.216 -395.804141)
			(xy 284.155207 -395.784388) (xy 284.097368 -395.757171) (xy 284.043397 -395.72292) (xy 283.994144 -395.682175)
			(xy 283.950387 -395.635578) (xy 283.912814 -395.583863) (xy 283.88202 -395.527848) (xy 283.858488 -395.468415)
			(xy 283.842591 -395.406501) (xy 283.83458 -395.343083) (xy 281.88285 -395.343083) (xy 281.88285 -395.423136)
			(xy 281.883348 -395.437497) (xy 281.89136 -395.465079) (xy 281.906738 -395.489337) (xy 281.928266 -395.508351)
			(xy 281.954238 -395.520614) (xy 281.982599 -395.525156) (xy 282.011102 -395.521617) (xy 282.037491 -395.510278)
			(xy 282.048966 -395.501622) (xy 282.076385 -395.479823) (xy 282.136077 -395.443169) (xy 282.200235 -395.415055)
			(xy 282.267645 -395.396014) (xy 282.33703 -395.386406) (xy 282.372054 -395.385798) (xy 282.404037 -395.386276)
			(xy 282.467498 -395.394288) (xy 282.529455 -395.410191) (xy 282.58893 -395.433734) (xy 282.644986 -395.464546)
			(xy 282.696737 -395.502141) (xy 282.743368 -395.545926) (xy 282.784143 -395.595211) (xy 282.818419 -395.649217)
			(xy 282.845655 -395.707094) (xy 282.865423 -395.767929) (xy 282.877409 -395.830761) (xy 282.881426 -395.8946)
			(xy 282.877409 -395.958439) (xy 282.865423 -396.021271) (xy 282.845655 -396.082106) (xy 282.818419 -396.139983)
			(xy 282.784143 -396.193989) (xy 282.743368 -396.243274) (xy 282.696737 -396.287059) (xy 282.644986 -396.324654)
			(xy 282.58893 -396.355466) (xy 282.529455 -396.379009) (xy 282.467498 -396.394912) (xy 282.404037 -396.402924)
			(xy 282.372054 -396.403322) (xy 282.337031 -396.402734) (xy 282.267648 -396.393113) (xy 282.200242 -396.374061)
			(xy 282.136089 -396.345938) (xy 282.076403 -396.309275) (xy 282.048966 -396.287498) (xy 282.037549 -396.278747)
			(xy 282.011133 -396.267394) (xy 281.9826 -396.26385) (xy 281.954209 -396.268397) (xy 281.92821 -396.280674)
			(xy 281.906661 -396.29971) (xy 281.891269 -396.323995) (xy 281.883253 -396.351608) (xy 281.88285 -396.365984)
			(xy 281.88285 -396.980367) (xy 289.7223 -396.980367) (xy 289.7223 -396.916445) (xy 289.730311 -396.853027)
			(xy 289.746208 -396.791113) (xy 289.76974 -396.73168) (xy 289.800534 -396.675665) (xy 289.838107 -396.62395)
			(xy 289.881864 -396.577353) (xy 289.931117 -396.536608) (xy 289.985088 -396.502357) (xy 290.042927 -396.47514)
			(xy 290.10372 -396.455387) (xy 290.16651 -396.443409) (xy 290.230306 -396.439396) (xy 290.294102 -396.443409)
			(xy 290.356892 -396.455387) (xy 290.417685 -396.47514) (xy 290.475524 -396.502357) (xy 290.529495 -396.536608)
			(xy 290.578748 -396.577353) (xy 290.622505 -396.62395) (xy 290.660078 -396.675665) (xy 290.690872 -396.73168)
			(xy 290.714404 -396.791113) (xy 290.730301 -396.853027) (xy 290.738312 -396.916445) (xy 290.738814 -396.948406)
			(xy 290.738312 -396.980367) (xy 290.737221 -396.989003) (xy 291.03675 -396.989003) (xy 291.03675 -396.925081)
			(xy 291.044761 -396.861663) (xy 291.060658 -396.799749) (xy 291.08419 -396.740316) (xy 291.114984 -396.684301)
			(xy 291.152557 -396.632586) (xy 291.196314 -396.585989) (xy 291.245567 -396.545244) (xy 291.299538 -396.510993)
			(xy 291.357377 -396.483776) (xy 291.41817 -396.464023) (xy 291.48096 -396.452045) (xy 291.544756 -396.448032)
			(xy 291.608552 -396.452045) (xy 291.671342 -396.464023) (xy 291.732135 -396.483776) (xy 291.789974 -396.510993)
			(xy 291.843945 -396.545244) (xy 291.893198 -396.585989) (xy 291.936955 -396.632586) (xy 291.974528 -396.684301)
			(xy 292.005322 -396.740316) (xy 292.028854 -396.799749) (xy 292.044751 -396.861663) (xy 292.052762 -396.925081)
			(xy 292.053264 -396.957042) (xy 292.052762 -396.989003) (xy 292.044751 -397.052421) (xy 292.028854 -397.114335)
			(xy 292.005322 -397.173768) (xy 291.974528 -397.229783) (xy 291.936955 -397.281498) (xy 291.893198 -397.328095)
			(xy 291.843945 -397.36884) (xy 291.789974 -397.403091) (xy 291.732135 -397.430308) (xy 291.671342 -397.450061)
			(xy 291.608552 -397.462039) (xy 291.544756 -397.466053) (xy 291.48096 -397.462039) (xy 291.41817 -397.450061)
			(xy 291.357377 -397.430308) (xy 291.299538 -397.403091) (xy 291.245567 -397.36884) (xy 291.196314 -397.328095)
			(xy 291.152557 -397.281498) (xy 291.114984 -397.229783) (xy 291.08419 -397.173768) (xy 291.060658 -397.114335)
			(xy 291.044761 -397.052421) (xy 291.03675 -396.989003) (xy 290.737221 -396.989003) (xy 290.730301 -397.043785)
			(xy 290.714404 -397.105699) (xy 290.690872 -397.165132) (xy 290.660078 -397.221147) (xy 290.622505 -397.272862)
			(xy 290.578748 -397.319459) (xy 290.529495 -397.360204) (xy 290.475524 -397.394455) (xy 290.417685 -397.421672)
			(xy 290.356892 -397.441425) (xy 290.294102 -397.453403) (xy 290.230306 -397.457417) (xy 290.16651 -397.453403)
			(xy 290.10372 -397.441425) (xy 290.042927 -397.421672) (xy 289.985088 -397.394455) (xy 289.931117 -397.360204)
			(xy 289.881864 -397.319459) (xy 289.838107 -397.272862) (xy 289.800534 -397.221147) (xy 289.76974 -397.165132)
			(xy 289.746208 -397.105699) (xy 289.730311 -397.043785) (xy 289.7223 -396.980367) (xy 281.88285 -396.980367)
			(xy 281.88285 -397.688773) (xy 295.282106 -397.688773) (xy 295.282106 -397.624851) (xy 295.290117 -397.561433)
			(xy 295.306014 -397.499519) (xy 295.329546 -397.440086) (xy 295.36034 -397.384071) (xy 295.397913 -397.332356)
			(xy 295.44167 -397.285759) (xy 295.490923 -397.245014) (xy 295.544894 -397.210763) (xy 295.602733 -397.183546)
			(xy 295.663526 -397.163793) (xy 295.726316 -397.151815) (xy 295.790112 -397.147802) (xy 295.853908 -397.151815)
			(xy 295.916698 -397.163793) (xy 295.977491 -397.183546) (xy 296.03533 -397.210763) (xy 296.089301 -397.245014)
			(xy 296.138554 -397.285759) (xy 296.182311 -397.332356) (xy 296.219884 -397.384071) (xy 296.250678 -397.440086)
			(xy 296.27421 -397.499519) (xy 296.290107 -397.561433) (xy 296.298118 -397.624851) (xy 296.29862 -397.656812)
			(xy 296.298118 -397.688773) (xy 296.290107 -397.752191) (xy 296.27421 -397.814105) (xy 296.250678 -397.873538)
			(xy 296.219884 -397.929553) (xy 296.182311 -397.981268) (xy 296.138554 -398.027865) (xy 296.089301 -398.06861)
			(xy 296.03533 -398.102861) (xy 295.977491 -398.130078) (xy 295.916698 -398.149831) (xy 295.853908 -398.161809)
			(xy 295.790112 -398.165823) (xy 295.726316 -398.161809) (xy 295.663526 -398.149831) (xy 295.602733 -398.130078)
			(xy 295.544894 -398.102861) (xy 295.490923 -398.06861) (xy 295.44167 -398.027865) (xy 295.397913 -397.981268)
			(xy 295.36034 -397.929553) (xy 295.329546 -397.873538) (xy 295.306014 -397.814105) (xy 295.290117 -397.752191)
			(xy 295.282106 -397.688773) (xy 281.88285 -397.688773) (xy 281.88285 -398.6639) (xy 288.480811 -398.6639)
			(xy 288.484825 -398.600109) (xy 288.496801 -398.537324) (xy 288.516552 -398.476536) (xy 288.543765 -398.418701)
			(xy 288.578013 -398.364734) (xy 288.618753 -398.315484) (xy 288.665346 -398.271728) (xy 288.717054 -398.234157)
			(xy 288.773064 -398.203363) (xy 288.832491 -398.179831) (xy 288.894399 -398.163932) (xy 288.957812 -398.155918)
			(xy 288.98977 -398.155414) (xy 289.019756 -398.155867) (xy 289.079314 -398.162912) (xy 289.137627 -398.176921)
			(xy 289.193886 -398.197697) (xy 289.247308 -398.224952) (xy 289.272472 -398.241266) (xy 289.279974 -398.245821)
			(xy 289.296982 -398.250109) (xy 289.305746 -398.249648) (xy 289.335464 -398.2466) (xy 289.34416 -398.245372)
			(xy 289.36001 -398.237837) (xy 289.366452 -398.231868) (xy 289.390358 -398.208625) (xy 289.443219 -398.167983)
			(xy 289.500938 -398.134599) (xy 289.562526 -398.109045) (xy 289.626925 -398.091761) (xy 289.693031 -398.083042)
			(xy 289.72637 -398.082516) (xy 289.758335 -398.082947) (xy 289.821762 -398.090956) (xy 289.883684 -398.106852)
			(xy 289.943126 -398.130384) (xy 289.999149 -398.16118) (xy 290.050871 -398.198755) (xy 290.097476 -398.242517)
			(xy 290.138227 -398.291775) (xy 290.172484 -398.345752) (xy 290.199705 -398.403597) (xy 290.219461 -398.464398)
			(xy 290.230641 -398.523) (xy 291.45552 -398.523) (xy 291.459535 -398.459194) (xy 291.471515 -398.396394)
			(xy 291.491271 -398.335591) (xy 291.518493 -398.277744) (xy 291.55275 -398.223765) (xy 291.593503 -398.174505)
			(xy 291.640108 -398.130741) (xy 291.691831 -398.093164) (xy 291.747856 -398.062366) (xy 291.807299 -398.038832)
			(xy 291.869224 -398.022935) (xy 291.932652 -398.014924) (xy 291.964618 -398.014444) (xy 291.995318 -398.014951)
			(xy 292.056271 -398.022346) (xy 292.11589 -398.037027) (xy 292.173307 -398.058781) (xy 292.227687 -398.08729)
			(xy 292.278238 -398.12214) (xy 292.324225 -398.162823) (xy 292.364979 -398.208748) (xy 292.399906 -398.259246)
			(xy 292.428498 -398.313582) (xy 292.45034 -398.370965) (xy 292.465113 -398.430562) (xy 292.469316 -398.460976)
			(xy 292.470586 -398.47139) (xy 292.481 -398.48917) (xy 292.557454 -398.545812) (xy 292.57752 -398.550384)
			(xy 292.587934 -398.548352) (xy 292.604623 -398.545588) (xy 292.638328 -398.542664) (xy 292.655244 -398.54251)
			(xy 292.682494 -398.542963) (xy 292.73644 -398.550725) (xy 292.788732 -398.566084) (xy 292.838306 -398.588729)
			(xy 292.884153 -398.618198) (xy 292.92534 -398.653891) (xy 292.961028 -398.695082) (xy 292.990492 -398.740933)
			(xy 293.013131 -398.790509) (xy 293.028485 -398.842803) (xy 293.03624 -398.896749) (xy 293.03624 -398.951251)
			(xy 293.028485 -399.005197) (xy 293.013131 -399.057491) (xy 292.990492 -399.107067) (xy 292.961028 -399.152918)
			(xy 292.92534 -399.194109) (xy 292.884153 -399.229802) (xy 292.838306 -399.259271) (xy 292.788732 -399.281916)
			(xy 292.73644 -399.297275) (xy 292.682494 -399.305037) (xy 292.655244 -399.305526) (xy 292.625921 -399.304981)
			(xy 292.567969 -399.295985) (xy 292.512076 -399.27823) (xy 292.459557 -399.252133) (xy 292.411648 -399.218309)
			(xy 292.369478 -399.177553) (xy 292.334039 -399.130826) (xy 292.306165 -399.079228) (xy 292.295834 -399.05178)
			(xy 292.292278 -399.04162) (xy 292.278308 -399.026634) (xy 292.191186 -398.98828) (xy 292.170612 -398.988026)
			(xy 292.16096 -398.99209) (xy 292.129753 -399.004577) (xy 292.064864 -399.022118) (xy 291.998227 -399.030941)
			(xy 291.964618 -399.03146) (xy 291.932652 -399.031076) (xy 291.869224 -399.023065) (xy 291.807299 -399.007168)
			(xy 291.747856 -398.983634) (xy 291.691831 -398.952836) (xy 291.640108 -398.915259) (xy 291.593503 -398.871495)
			(xy 291.55275 -398.822235) (xy 291.518493 -398.768256) (xy 291.491271 -398.710409) (xy 291.471515 -398.649606)
			(xy 291.459535 -398.586806) (xy 291.45552 -398.523) (xy 290.230641 -398.523) (xy 290.231441 -398.527196)
			(xy 290.235456 -398.591) (xy 290.231441 -398.654804) (xy 290.219461 -398.717602) (xy 290.199705 -398.778403)
			(xy 290.172484 -398.836248) (xy 290.138227 -398.890225) (xy 290.097476 -398.939483) (xy 290.050871 -398.983245)
			(xy 289.999149 -399.02082) (xy 289.943126 -399.051616) (xy 289.883684 -399.075148) (xy 289.821762 -399.091044)
			(xy 289.758335 -399.099053) (xy 289.72637 -399.099532) (xy 289.696382 -399.099118) (xy 289.636823 -399.092065)
			(xy 289.578509 -399.078048) (xy 289.522251 -399.057263) (xy 289.468831 -399.029998) (xy 289.443668 -399.01368)
			(xy 289.436178 -399.009102) (xy 289.419161 -399.004827) (xy 289.410394 -399.005298) (xy 289.380676 -399.008346)
			(xy 289.371981 -399.009581) (xy 289.35613 -399.01711) (xy 289.349688 -399.023078) (xy 289.325754 -399.046292)
			(xy 289.272901 -399.086939) (xy 289.215188 -399.120328) (xy 289.153605 -399.145887) (xy 289.08921 -399.163177)
			(xy 289.023108 -399.171901) (xy 288.98977 -399.17243) (xy 288.957812 -399.171882) (xy 288.894399 -399.163868)
			(xy 288.832491 -399.147969) (xy 288.773064 -399.124437) (xy 288.717054 -399.093643) (xy 288.665346 -399.056072)
			(xy 288.618753 -399.012316) (xy 288.578013 -398.963066) (xy 288.543765 -398.909099) (xy 288.516552 -398.851264)
			(xy 288.496801 -398.790476) (xy 288.484825 -398.727691) (xy 288.480811 -398.6639) (xy 281.88285 -398.6639)
			(xy 281.88285 -399.341153) (xy 287.595263 -399.341153) (xy 287.595263 -399.286647) (xy 287.60302 -399.232697)
			(xy 287.618377 -399.180399) (xy 287.641019 -399.130819) (xy 287.670488 -399.084967) (xy 287.706182 -399.043775)
			(xy 287.747375 -399.008082) (xy 287.793228 -398.978615) (xy 287.842808 -398.955973) (xy 287.895106 -398.940618)
			(xy 287.949057 -398.932863) (xy 287.97631 -398.9324) (xy 288.003347 -398.932919) (xy 288.056876 -398.940569)
			(xy 288.10879 -398.955699) (xy 288.158048 -398.978007) (xy 288.203662 -399.007046) (xy 288.24472 -399.042234)
			(xy 288.280399 -399.082867) (xy 288.309984 -399.128129) (xy 288.332882 -399.177115) (xy 288.348635 -399.228843)
			(xy 288.353246 -399.255488) (xy 288.355024 -399.26641) (xy 288.366962 -399.284698) (xy 288.449766 -399.33753)
			(xy 288.471356 -399.340578) (xy 288.482024 -399.33753) (xy 288.507939 -399.330514) (xy 288.561098 -399.322997)
			(xy 288.587942 -399.322544) (xy 288.615192 -399.323039) (xy 288.669137 -399.3308) (xy 288.721429 -399.346158)
			(xy 288.771003 -399.3688) (xy 288.816851 -399.398266) (xy 288.858039 -399.433957) (xy 288.89373 -399.475144)
			(xy 288.923197 -399.520992) (xy 288.94584 -399.570566) (xy 288.961199 -399.622857) (xy 288.968961 -399.676802)
			(xy 288.96945 -399.704052) (xy 288.969226 -399.722459) (xy 288.965668 -399.7591) (xy 288.962338 -399.777204)
			(xy 288.960052 -399.78965) (xy 288.967164 -399.81378) (xy 289.044126 -399.891504) (xy 289.068256 -399.89887)
			(xy 289.080702 -399.896584) (xy 289.103793 -399.89253) (xy 289.150478 -399.888207) (xy 289.17392 -399.887948)
			(xy 289.20465 -399.888437) (xy 289.265661 -399.895847) (xy 289.325334 -399.910557) (xy 289.3828 -399.932351)
			(xy 289.437219 -399.960913) (xy 289.4878 -399.995825) (xy 289.533804 -400.036579) (xy 289.57456 -400.082581)
			(xy 289.609475 -400.13316) (xy 289.638039 -400.187579) (xy 289.659836 -400.245043) (xy 289.674549 -400.304715)
			(xy 289.681961 -400.365726) (xy 289.682428 -400.396456) (xy 289.681928 -400.42818) (xy 289.674017 -400.491134)
			(xy 289.658337 -400.552614) (xy 289.635132 -400.611668) (xy 289.604762 -400.667376) (xy 289.567699 -400.718874)
			(xy 289.524518 -400.765362) (xy 289.475891 -400.806119) (xy 289.422571 -400.840511) (xy 289.365389 -400.868003)
			(xy 289.335464 -400.878548) (xy 289.32505 -400.882104) (xy 289.309302 -400.896582) (xy 289.270694 -400.987006)
			(xy 289.271202 -401.008342) (xy 289.275774 -401.018248) (xy 289.287296 -401.043829) (xy 289.303577 -401.097518)
			(xy 289.311831 -401.153011) (xy 289.31235 -401.181062) (xy 289.311864 -401.208313) (xy 289.304108 -401.262261)
			(xy 289.288753 -401.314556) (xy 289.266111 -401.364133) (xy 289.236645 -401.409983) (xy 289.200954 -401.451174)
			(xy 289.159763 -401.486865) (xy 289.113913 -401.516331) (xy 289.064336 -401.538973) (xy 289.012041 -401.554328)
			(xy 288.958093 -401.562084) (xy 288.903591 -401.562084) (xy 288.849643 -401.554328) (xy 288.797348 -401.538973)
			(xy 288.747771 -401.516331) (xy 288.701921 -401.486865) (xy 288.66073 -401.451174) (xy 288.625039 -401.409983)
			(xy 288.595573 -401.364133) (xy 288.572931 -401.314556) (xy 288.557576 -401.262261) (xy 288.54982 -401.208313)
			(xy 288.549334 -401.181062) (xy 288.549908 -401.152658) (xy 288.558342 -401.09648) (xy 288.575006 -401.042171)
			(xy 288.599529 -400.990929) (xy 288.631373 -400.943885) (xy 288.669833 -400.902076) (xy 288.714062 -400.866426)
			(xy 288.73831 -400.851624) (xy 288.747962 -400.846036) (xy 288.760154 -400.828764) (xy 288.779458 -400.732498)
			(xy 288.774886 -400.71167) (xy 288.768028 -400.70278) (xy 288.748615 -400.676228) (xy 288.716095 -400.619053)
			(xy 288.69122 -400.558162) (xy 288.674403 -400.494572) (xy 288.665927 -400.429344) (xy 288.665412 -400.396456)
			(xy 288.665866 -400.366758) (xy 288.672819 -400.30777) (xy 288.686592 -400.249993) (xy 288.6964 -400.221958)
			(xy 288.700718 -400.21002) (xy 288.697162 -400.185128) (xy 288.633408 -400.096228) (xy 288.610802 -400.085052)
			(xy 288.598102 -400.085306) (xy 288.587942 -400.08556) (xy 288.560903 -400.085119) (xy 288.507368 -400.077462)
			(xy 288.455451 -400.062323) (xy 288.406191 -400.040006) (xy 288.360575 -400.010959) (xy 288.319517 -399.975762)
			(xy 288.28384 -399.935121) (xy 288.254257 -399.88985) (xy 288.231362 -399.840856) (xy 288.215614 -399.78912)
			(xy 288.211006 -399.762472) (xy 288.209228 -399.75155) (xy 288.19729 -399.733262) (xy 288.114486 -399.68043)
			(xy 288.092896 -399.677382) (xy 288.082228 -399.68043) (xy 288.056311 -399.687437) (xy 288.003154 -399.694959)
			(xy 287.97631 -399.695416) (xy 287.949057 -399.694937) (xy 287.895106 -399.687182) (xy 287.842808 -399.671827)
			(xy 287.793228 -399.649185) (xy 287.747375 -399.619718) (xy 287.706182 -399.584025) (xy 287.670488 -399.542833)
			(xy 287.641019 -399.496981) (xy 287.618377 -399.447401) (xy 287.60302 -399.395103) (xy 287.595263 -399.341153)
			(xy 281.88285 -399.341153) (xy 281.88285 -404.215092) (xy 283.497274 -404.215092) (xy 283.497857 -404.180137)
			(xy 283.507419 -404.110884) (xy 283.526376 -404.043593) (xy 283.554371 -403.979533) (xy 283.590875 -403.91991)
			(xy 283.61259 -403.892512) (xy 283.617854 -403.885509) (xy 283.623705 -403.869009) (xy 283.62402 -403.860254)
			(xy 283.62402 -403.70633) (xy 283.623637 -403.697585) (xy 283.617814 -403.681094) (xy 283.61259 -403.674072)
			(xy 283.590863 -403.646684) (xy 283.554368 -403.587055) (xy 283.526378 -403.522992) (xy 283.507421 -403.4557)
			(xy 283.497852 -403.386447) (xy 283.497274 -403.351492) (xy 283.497764 -403.32) (xy 283.505533 -403.257496)
			(xy 283.520964 -403.196431) (xy 283.543819 -403.137739) (xy 283.57375 -403.082321) (xy 283.610297 -403.031024)
			(xy 283.6529 -402.984634) (xy 283.676598 -402.963888) (xy 283.684472 -402.95703) (xy 283.693616 -402.93925)
			(xy 283.700474 -402.846032) (xy 283.69387 -402.826982) (xy 283.687012 -402.819108) (xy 283.669122 -402.798081)
			(xy 283.638929 -402.751863) (xy 283.615714 -402.701775) (xy 283.599961 -402.648864) (xy 283.591999 -402.594235)
			(xy 283.591508 -402.566632) (xy 283.591994 -402.539381) (xy 283.59975 -402.485433) (xy 283.615105 -402.433138)
			(xy 283.637747 -402.383561) (xy 283.667213 -402.337711) (xy 283.702904 -402.29652) (xy 283.744095 -402.260829)
			(xy 283.789945 -402.231363) (xy 283.839522 -402.208721) (xy 283.891817 -402.193366) (xy 283.945765 -402.18561)
			(xy 284.000267 -402.18561) (xy 284.054215 -402.193366) (xy 284.10651 -402.208721) (xy 284.156087 -402.231363)
			(xy 284.201937 -402.260829) (xy 284.243128 -402.29652) (xy 284.278819 -402.337711) (xy 284.308285 -402.383561)
			(xy 284.330927 -402.433138) (xy 284.346282 -402.485433) (xy 284.354038 -402.539381) (xy 284.354524 -402.566632)
			(xy 284.353951 -402.597168) (xy 284.344223 -402.65746) (xy 284.32502 -402.715435) (xy 284.296831 -402.769612)
			(xy 284.279086 -402.79447) (xy 284.272736 -402.802852) (xy 284.26791 -402.82241) (xy 284.282388 -402.914612)
			(xy 284.293056 -402.93163) (xy 284.301438 -402.937726) (xy 284.325787 -402.955622) (xy 284.370435 -402.996347)
			(xy 284.395499 -403.025356) (xy 289.79241 -403.025356) (xy 289.792964 -402.9904) (xy 289.802532 -402.921145)
			(xy 289.821496 -402.853854) (xy 289.849497 -402.789794) (xy 289.886008 -402.730173) (xy 289.907726 -402.702776)
			(xy 289.913009 -402.695785) (xy 289.918847 -402.679276) (xy 289.919156 -402.670518) (xy 289.919156 -402.516594)
			(xy 289.918803 -402.507846) (xy 289.91296 -402.491354) (xy 289.907726 -402.484336) (xy 289.886033 -402.456921)
			(xy 289.849532 -402.3973) (xy 289.821535 -402.333244) (xy 289.802569 -402.265958) (xy 289.792993 -402.19671)
			(xy 289.79241 -402.161756) (xy 289.792994 -402.12798) (xy 289.801948 -402.061024) (xy 289.819693 -401.995844)
			(xy 289.845916 -401.933589) (xy 289.880154 -401.875356) (xy 289.921805 -401.822172) (xy 289.970133 -401.774974)
			(xy 289.99688 -401.75434) (xy 290.004754 -401.748244) (xy 290.014914 -401.731734) (xy 290.0299 -401.643596)
			(xy 290.02609 -401.624546) (xy 290.020502 -401.616418) (xy 290.005351 -401.592809) (xy 289.981427 -401.542071)
			(xy 289.965188 -401.488377) (xy 289.956985 -401.432884) (xy 289.956494 -401.404836) (xy 289.95698 -401.377585)
			(xy 289.964736 -401.323637) (xy 289.980091 -401.271342) (xy 290.002733 -401.221765) (xy 290.032199 -401.175915)
			(xy 290.06789 -401.134724) (xy 290.109081 -401.099033) (xy 290.154931 -401.069567) (xy 290.204508 -401.046925)
			(xy 290.256803 -401.03157) (xy 290.310751 -401.023814) (xy 290.365253 -401.023814) (xy 290.419201 -401.03157)
			(xy 290.471496 -401.046925) (xy 290.521073 -401.069567) (xy 290.566923 -401.099033) (xy 290.608114 -401.134724)
			(xy 290.643805 -401.175915) (xy 290.673271 -401.221765) (xy 290.695913 -401.271342) (xy 290.711268 -401.323637)
			(xy 290.719024 -401.377585) (xy 290.71951 -401.404836) (xy 290.719072 -401.431011) (xy 290.711902 -401.482867)
			(xy 290.697702 -401.533254) (xy 290.676739 -401.581223) (xy 290.649407 -401.625872) (xy 290.63315 -401.64639)
			(xy 290.627054 -401.65401) (xy 290.621212 -401.672552) (xy 290.627816 -401.76196) (xy 290.636198 -401.779232)
			(xy 290.64331 -401.785836) (xy 290.665381 -401.8065) (xy 290.704945 -401.852221) (xy 290.738805 -401.902312)
			(xy 290.766485 -401.956067) (xy 290.787592 -402.012726) (xy 290.801829 -402.071488) (xy 290.808995 -402.131525)
			(xy 290.809426 -402.161756) (xy 290.80887 -402.196712) (xy 290.799302 -402.265966) (xy 290.780338 -402.333257)
			(xy 290.752337 -402.397317) (xy 290.715827 -402.456939) (xy 290.69411 -402.484336) (xy 290.688867 -402.491354)
			(xy 290.683003 -402.507842) (xy 290.68268 -402.516594) (xy 290.68268 -402.670518) (xy 290.68304 -402.679265)
			(xy 290.688879 -402.695756) (xy 290.69411 -402.702776) (xy 290.715813 -402.730182) (xy 290.752312 -402.789806)
			(xy 290.780307 -402.853865) (xy 290.79927 -402.921152) (xy 290.808844 -402.990402) (xy 290.809426 -403.025356)
			(xy 290.809337 -403.037951) (xy 290.808068 -403.063108) (xy 290.806886 -403.075648) (xy 290.80587 -403.0853)
			(xy 290.811458 -403.10435) (xy 290.867846 -403.175216) (xy 290.885118 -403.185122) (xy 290.89477 -403.186392)
			(xy 290.921973 -403.190398) (xy 290.974909 -403.205275) (xy 291.02516 -403.227599) (xy 291.071683 -403.25691)
			(xy 291.113514 -403.292598) (xy 291.149786 -403.333925) (xy 291.179746 -403.380032) (xy 291.202773 -403.429964)
			(xy 291.218391 -403.482686) (xy 291.226274 -403.537105) (xy 291.226748 -403.564598) (xy 291.22622 -403.591847)
			(xy 291.218465 -403.645792) (xy 291.203112 -403.698083) (xy 291.192619 -403.721062) (xy 291.534594 -403.721062)
			(xy 291.538665 -403.66544) (xy 291.550791 -403.611003) (xy 291.570714 -403.558912) (xy 291.59801 -403.510277)
			(xy 291.632096 -403.466134) (xy 291.672245 -403.427425) (xy 291.717603 -403.394974) (xy 291.767203 -403.369473)
			(xy 291.819987 -403.351466) (xy 291.87483 -403.341336) (xy 291.930564 -403.339299) (xy 291.986001 -403.345399)
			(xy 292.039958 -403.359505) (xy 292.091287 -403.381317) (xy 292.138893 -403.410371) (xy 292.181761 -403.446046)
			(xy 292.218978 -403.487583) (xy 292.249751 -403.534096) (xy 292.273423 -403.584593) (xy 292.289491 -403.638)
			(xy 292.297611 -403.693176) (xy 292.29812 -403.721062) (xy 292.297611 -403.748948) (xy 292.289491 -403.804124)
			(xy 292.273423 -403.857531) (xy 292.249751 -403.908028) (xy 292.218978 -403.954541) (xy 292.181761 -403.996078)
			(xy 292.138893 -404.031753) (xy 292.091287 -404.060807) (xy 292.039958 -404.082619) (xy 291.986001 -404.096725)
			(xy 291.930564 -404.102825) (xy 291.87483 -404.100788) (xy 291.819987 -404.090658) (xy 291.767203 -404.072651)
			(xy 291.717603 -404.04715) (xy 291.672245 -404.014699) (xy 291.632096 -403.97599) (xy 291.59801 -403.931847)
			(xy 291.570714 -403.883212) (xy 291.550791 -403.831121) (xy 291.538665 -403.776684) (xy 291.534594 -403.721062)
			(xy 291.192619 -403.721062) (xy 291.180474 -403.747658) (xy 291.151012 -403.793506) (xy 291.115325 -403.834695)
			(xy 291.07414 -403.870387) (xy 291.028295 -403.899854) (xy 290.978722 -403.922498) (xy 290.926433 -403.937856)
			(xy 290.872489 -403.945617) (xy 290.84524 -403.946106) (xy 290.817933 -403.945605) (xy 290.763881 -403.937796)
			(xy 290.711494 -403.922361) (xy 290.661843 -403.899615) (xy 290.615942 -403.870022) (xy 290.574728 -403.834188)
			(xy 290.539044 -403.792845) (xy 290.509619 -403.746836) (xy 290.487054 -403.697102) (xy 290.47181 -403.644659)
			(xy 290.467542 -403.617684) (xy 290.466018 -403.608032) (xy 290.456112 -403.59076) (xy 290.384738 -403.535134)
			(xy 290.365688 -403.5298) (xy 290.355782 -403.530816) (xy 290.342109 -403.532224) (xy 290.314662 -403.53375)
			(xy 290.300918 -403.533864) (xy 290.270185 -403.533445) (xy 290.209166 -403.526038) (xy 290.149485 -403.511329)
			(xy 290.092012 -403.489533) (xy 290.037586 -403.460968) (xy 289.987 -403.42605) (xy 289.940993 -403.385289)
			(xy 289.900234 -403.339279) (xy 289.865319 -403.288692) (xy 289.836756 -403.234264) (xy 289.814963 -403.17679)
			(xy 289.800257 -403.117109) (xy 289.792853 -403.056089) (xy 289.79241 -403.025356) (xy 284.395499 -403.025356)
			(xy 284.409944 -403.042074) (xy 284.443757 -403.09216) (xy 284.471398 -403.1459) (xy 284.492476 -403.202536)
			(xy 284.506696 -403.261271) (xy 284.513857 -403.321276) (xy 284.51429 -403.351492) (xy 284.513706 -403.386447)
			(xy 284.504145 -403.4557) (xy 284.485189 -403.522992) (xy 284.457194 -403.587052) (xy 284.420689 -403.646674)
			(xy 284.398974 -403.674072) (xy 284.393712 -403.681077) (xy 284.387861 -403.697575) (xy 284.387544 -403.70633)
			(xy 284.387544 -403.860254) (xy 284.387875 -403.869004) (xy 284.393733 -403.885496) (xy 284.398974 -403.892512)
			(xy 284.420689 -403.91991) (xy 284.457187 -403.979536) (xy 284.48518 -404.043596) (xy 284.50414 -404.110886)
			(xy 284.510292 -404.155402) (xy 294.265856 -404.155402) (xy 294.269927 -404.09978) (xy 294.282053 -404.045343)
			(xy 294.301976 -403.993252) (xy 294.329272 -403.944617) (xy 294.363358 -403.900474) (xy 294.403507 -403.861765)
			(xy 294.448865 -403.829314) (xy 294.498465 -403.803813) (xy 294.551249 -403.785806) (xy 294.606092 -403.775676)
			(xy 294.661826 -403.773639) (xy 294.717263 -403.779739) (xy 294.77122 -403.793845) (xy 294.822549 -403.815657)
			(xy 294.870155 -403.844711) (xy 294.913023 -403.880386) (xy 294.95024 -403.921923) (xy 294.981013 -403.968436)
			(xy 295.004685 -404.018933) (xy 295.020753 -404.07234) (xy 295.028873 -404.127516) (xy 295.029382 -404.155402)
			(xy 295.028873 -404.183288) (xy 295.020753 -404.238464) (xy 295.004685 -404.291871) (xy 294.981013 -404.342368)
			(xy 294.95024 -404.388881) (xy 294.913023 -404.430418) (xy 294.870155 -404.466093) (xy 294.822549 -404.495147)
			(xy 294.77122 -404.516959) (xy 294.717263 -404.531065) (xy 294.661826 -404.537165) (xy 294.606092 -404.535128)
			(xy 294.551249 -404.524998) (xy 294.498465 -404.506991) (xy 294.448865 -404.48149) (xy 294.403507 -404.449039)
			(xy 294.363358 -404.41033) (xy 294.329272 -404.366187) (xy 294.301976 -404.317552) (xy 294.282053 -404.265461)
			(xy 294.269927 -404.211024) (xy 294.265856 -404.155402) (xy 284.510292 -404.155402) (xy 284.513711 -404.180137)
			(xy 284.51429 -404.215092) (xy 284.513769 -404.248552) (xy 284.504998 -404.314895) (xy 284.487594 -404.379512)
			(xy 284.461858 -404.441285) (xy 284.428235 -404.499145) (xy 284.387308 -404.55209) (xy 284.363922 -404.576026)
			(xy 284.357589 -404.58285) (xy 284.3499 -404.599786) (xy 284.348936 -404.609046) (xy 284.347158 -404.63978)
			(xy 284.346998 -404.648906) (xy 284.352324 -404.666349) (xy 284.357572 -404.673816) (xy 284.372438 -404.693877)
			(xy 284.397383 -404.737131) (xy 284.416475 -404.783269) (xy 284.429389 -404.831501) (xy 284.435903 -404.881006)
			(xy 284.436312 -404.905972) (xy 284.435826 -404.933223) (xy 284.42807 -404.987171) (xy 284.412715 -405.039466)
			(xy 284.390073 -405.089043) (xy 284.360607 -405.134893) (xy 284.324916 -405.176084) (xy 284.283725 -405.211775)
			(xy 284.237875 -405.241241) (xy 284.188298 -405.263883) (xy 284.136003 -405.279238) (xy 284.082055 -405.286994)
			(xy 284.027553 -405.286994) (xy 283.973605 -405.279238) (xy 283.92131 -405.263883) (xy 283.871733 -405.241241)
			(xy 283.825883 -405.211775) (xy 283.784692 -405.176084) (xy 283.749001 -405.134893) (xy 283.719535 -405.089043)
			(xy 283.696893 -405.039466) (xy 283.681538 -404.987171) (xy 283.673782 -404.933223) (xy 283.673296 -404.905972)
			(xy 283.673632 -404.881505) (xy 283.679867 -404.832969) (xy 283.692269 -404.785632) (xy 283.710634 -404.740275)
			(xy 283.722318 -404.718774) (xy 283.726426 -404.710658) (xy 283.729301 -404.69271) (xy 283.727906 -404.683722)
			(xy 283.721556 -404.653496) (xy 283.719299 -404.644518) (xy 283.709407 -404.628889) (xy 283.702252 -404.623016)
			(xy 283.675449 -404.602365) (xy 283.626992 -404.555144) (xy 283.585227 -404.501911) (xy 283.550893 -404.443608)
			(xy 283.524598 -404.381266) (xy 283.506805 -404.315986) (xy 283.49783 -404.248923) (xy 283.497274 -404.215092)
			(xy 281.88285 -404.215092) (xy 281.88285 -407.556716) (xy 282.40863 -407.556716) (xy 282.40916 -407.524427)
			(xy 282.417344 -407.460369) (xy 282.433571 -407.397862) (xy 282.45758 -407.337912) (xy 282.488983 -407.281483)
			(xy 282.527276 -407.229483) (xy 282.571844 -407.182748) (xy 282.59659 -407.162) (xy 282.604464 -407.155396)
			(xy 282.614116 -407.137616) (xy 282.622752 -407.044906) (xy 282.616656 -407.025602) (xy 282.610052 -407.017728)
			(xy 282.593089 -406.996981) (xy 282.564562 -406.951614) (xy 282.542663 -406.902703) (xy 282.527822 -406.851208)
			(xy 282.520332 -406.798143) (xy 282.519882 -406.771348) (xy 282.520368 -406.744097) (xy 282.528124 -406.690149)
			(xy 282.543479 -406.637854) (xy 282.566121 -406.588277) (xy 282.595587 -406.542427) (xy 282.631278 -406.501236)
			(xy 282.672469 -406.465545) (xy 282.718319 -406.436079) (xy 282.767896 -406.413437) (xy 282.820191 -406.398082)
			(xy 282.874139 -406.390326) (xy 282.928641 -406.390326) (xy 282.982589 -406.398082) (xy 283.034884 -406.413437)
			(xy 283.084461 -406.436079) (xy 283.130311 -406.465545) (xy 283.171502 -406.501236) (xy 283.207193 -406.542427)
			(xy 283.236659 -406.588277) (xy 283.259301 -406.637854) (xy 283.274656 -406.690149) (xy 283.282412 -406.744097)
			(xy 283.282898 -406.771348) (xy 283.282496 -406.796605) (xy 283.275835 -406.846677) (xy 283.262622 -406.895432)
			(xy 283.24309 -406.942016) (xy 283.217579 -406.985614) (xy 283.20238 -407.00579) (xy 283.19603 -407.013918)
			(xy 283.190696 -407.033476) (xy 283.203142 -407.125932) (xy 283.213302 -407.143204) (xy 283.221684 -407.149554)
			(xy 283.239718 -407.163524) (xy 283.246711 -407.168829) (xy 283.263207 -407.174799) (xy 283.271976 -407.175208)
			(xy 283.4259 -407.175208) (xy 283.434677 -407.174846) (xy 283.451179 -407.168861) (xy 283.458158 -407.163524)
			(xy 283.463492 -407.159206) (xy 283.471366 -407.15311) (xy 283.481018 -407.135838) (xy 283.492194 -407.045414)
			(xy 283.487114 -407.026364) (xy 283.481018 -407.01849) (xy 283.462746 -406.993424) (xy 283.433715 -406.938612)
			(xy 283.413926 -406.879827) (xy 283.403899 -406.818617) (xy 283.403294 -406.787604) (xy 283.40378 -406.760353)
			(xy 283.411536 -406.706405) (xy 283.426891 -406.65411) (xy 283.449533 -406.604533) (xy 283.478999 -406.558683)
			(xy 283.51469 -406.517492) (xy 283.555881 -406.481801) (xy 283.601731 -406.452335) (xy 283.651308 -406.429693)
			(xy 283.703603 -406.414338) (xy 283.757551 -406.406582) (xy 283.812053 -406.406582) (xy 283.866001 -406.414338)
			(xy 283.918296 -406.429693) (xy 283.967873 -406.452335) (xy 284.013723 -406.481801) (xy 284.054914 -406.517492)
			(xy 284.090605 -406.558683) (xy 284.120071 -406.604533) (xy 284.142713 -406.65411) (xy 284.158068 -406.706405)
			(xy 284.165824 -406.760353) (xy 284.16631 -406.787604) (xy 284.165912 -406.812802) (xy 284.159267 -406.862759)
			(xy 284.146095 -406.911404) (xy 284.126625 -406.957888) (xy 284.101196 -407.001399) (xy 284.086046 -407.021538)
			(xy 284.07995 -407.029412) (xy 284.074616 -407.048462) (xy 284.084776 -407.138886) (xy 284.094428 -407.156412)
			(xy 284.102048 -407.162762) (xy 284.126719 -407.183475) (xy 284.171096 -407.230175) (xy 284.209222 -407.282101)
			(xy 284.24049 -407.338425) (xy 284.264399 -407.398245) (xy 284.268541 -407.414222) (xy 286.974788 -407.414222)
			(xy 286.975385 -407.379267) (xy 286.984943 -407.310015) (xy 287.003897 -407.242724) (xy 287.031889 -407.178663)
			(xy 287.06839 -407.119041) (xy 287.090104 -407.091642) (xy 287.095394 -407.084639) (xy 287.101371 -407.06815)
			(xy 287.101788 -407.059384) (xy 287.101788 -406.90546) (xy 287.101401 -406.896685) (xy 287.095434 -406.880182)
			(xy 287.090104 -406.873202) (xy 287.068393 -406.845802) (xy 287.031895 -406.786176) (xy 287.003902 -406.722116)
			(xy 286.984941 -406.654827) (xy 286.975368 -406.585577) (xy 286.974788 -406.550622) (xy 286.975252 -406.52087)
			(xy 286.982198 -406.461773) (xy 286.996 -406.403892) (xy 287.016467 -406.348019) (xy 287.043319 -406.294919)
			(xy 287.076189 -406.245318) (xy 287.114627 -406.199895) (xy 287.136078 -406.179274) (xy 287.142188 -406.173009)
			(xy 287.150117 -406.157423) (xy 287.151572 -406.148794) (xy 287.155636 -406.119076) (xy 287.156392 -406.110467)
			(xy 287.152767 -406.093584) (xy 287.148524 -406.086056) (xy 287.135348 -406.063581) (xy 287.114622 -406.015782)
			(xy 287.100603 -405.965605) (xy 287.093553 -405.913986) (xy 287.093152 -405.887936) (xy 287.093638 -405.860685)
			(xy 287.101394 -405.806737) (xy 287.116749 -405.754442) (xy 287.139391 -405.704865) (xy 287.168857 -405.659015)
			(xy 287.204548 -405.617824) (xy 287.245739 -405.582133) (xy 287.291589 -405.552667) (xy 287.341166 -405.530025)
			(xy 287.393461 -405.51467) (xy 287.447409 -405.506914) (xy 287.501911 -405.506914) (xy 287.555859 -405.51467)
			(xy 287.608154 -405.530025) (xy 287.657731 -405.552667) (xy 287.703581 -405.582133) (xy 287.744772 -405.617824)
			(xy 287.780463 -405.659015) (xy 287.809929 -405.704865) (xy 287.832571 -405.754442) (xy 287.847926 -405.806737)
			(xy 287.855682 -405.860685) (xy 287.856168 -405.887936) (xy 287.855781 -405.912728) (xy 287.849364 -405.961895)
			(xy 287.836641 -406.009819) (xy 287.817828 -406.055696) (xy 287.810488 -406.069038) (xy 289.134042 -406.069038)
			(xy 289.134549 -406.036357) (xy 289.14292 -405.971533) (xy 289.159529 -405.908317) (xy 289.184103 -405.84775)
			(xy 289.216235 -405.790832) (xy 289.255396 -405.7385) (xy 289.277806 -405.714708) (xy 289.284664 -405.70785)
			(xy 289.29203 -405.690324) (xy 289.29457 -405.602694) (xy 289.28822 -405.58466) (xy 289.28187 -405.577548)
			(xy 289.262529 -405.554414) (xy 289.228843 -405.504401) (xy 289.201315 -405.450751) (xy 289.180333 -405.394219)
			(xy 289.166192 -405.335601) (xy 289.159091 -405.27572) (xy 289.15868 -405.24557) (xy 289.159182 -405.213609)
			(xy 289.167193 -405.150191) (xy 289.18309 -405.088277) (xy 289.206622 -405.028844) (xy 289.237416 -404.972829)
			(xy 289.274989 -404.921114) (xy 289.318746 -404.874517) (xy 289.367999 -404.833772) (xy 289.42197 -404.799521)
			(xy 289.479809 -404.772304) (xy 289.540602 -404.752551) (xy 289.603392 -404.740573) (xy 289.667188 -404.73656)
			(xy 289.730984 -404.740573) (xy 289.793774 -404.752551) (xy 289.854567 -404.772304) (xy 289.912406 -404.799521)
			(xy 289.966377 -404.833772) (xy 290.01563 -404.874517) (xy 290.059387 -404.921114) (xy 290.09696 -404.972829)
			(xy 290.127754 -405.028844) (xy 290.151286 -405.088277) (xy 290.167183 -405.150191) (xy 290.175194 -405.213609)
			(xy 290.175696 -405.24557) (xy 290.175183 -405.278251) (xy 290.166812 -405.343074) (xy 290.150203 -405.40629)
			(xy 290.125631 -405.466856) (xy 290.0935 -405.523775) (xy 290.054341 -405.576107) (xy 290.031932 -405.5999)
			(xy 290.025074 -405.606758) (xy 290.017708 -405.624284) (xy 290.015168 -405.711914) (xy 290.021518 -405.729948)
			(xy 290.027868 -405.73706) (xy 290.047219 -405.760186) (xy 290.080903 -405.810201) (xy 290.108429 -405.863853)
			(xy 290.129409 -405.920386) (xy 290.143548 -405.979006) (xy 290.150647 -406.038887) (xy 290.151058 -406.069038)
			(xy 290.150556 -406.100999) (xy 290.142545 -406.164417) (xy 290.126648 -406.226331) (xy 290.103116 -406.285764)
			(xy 290.072322 -406.341779) (xy 290.034749 -406.393494) (xy 289.990992 -406.440091) (xy 289.941739 -406.480836)
			(xy 289.887768 -406.515087) (xy 289.829929 -406.542304) (xy 289.769136 -406.562057) (xy 289.706346 -406.574035)
			(xy 289.64255 -406.578049) (xy 289.578754 -406.574035) (xy 289.515964 -406.562057) (xy 289.455171 -406.542304)
			(xy 289.397332 -406.515087) (xy 289.343361 -406.480836) (xy 289.294108 -406.440091) (xy 289.250351 -406.393494)
			(xy 289.212778 -406.341779) (xy 289.181984 -406.285764) (xy 289.158452 -406.226331) (xy 289.142555 -406.164417)
			(xy 289.134544 -406.100999) (xy 289.134042 -406.069038) (xy 287.810488 -406.069038) (xy 287.805876 -406.07742)
			(xy 287.801869 -406.085093) (xy 287.798738 -406.102102) (xy 287.79978 -406.110694) (xy 287.804352 -406.140158)
			(xy 287.806074 -406.148804) (xy 287.814515 -406.164265) (xy 287.820862 -406.170384) (xy 287.843502 -406.191112)
			(xy 287.88417 -406.237089) (xy 287.919009 -406.287628) (xy 287.947509 -406.341993) (xy 287.969258 -406.399394)
			(xy 287.983939 -406.458995) (xy 287.991338 -406.519931) (xy 287.991804 -406.550622) (xy 287.991234 -406.585578)
			(xy 287.981669 -406.654831) (xy 287.96271 -406.722122) (xy 287.934712 -406.786183) (xy 287.898204 -406.845804)
			(xy 287.876488 -406.873202) (xy 287.871191 -406.880201) (xy 287.865216 -406.896692) (xy 287.864804 -406.90546)
			(xy 287.864804 -407.059384) (xy 287.865171 -407.068161) (xy 287.871152 -407.084663) (xy 287.876488 -407.091642)
			(xy 287.898219 -407.119028) (xy 287.934714 -407.178657) (xy 287.962703 -407.242721) (xy 287.98166 -407.310013)
			(xy 287.991227 -407.379266) (xy 287.991804 -407.414222) (xy 287.9914 -407.444414) (xy 287.984236 -407.504371)
			(xy 287.970024 -407.563058) (xy 287.948963 -407.61965) (xy 287.92135 -407.67335) (xy 287.887573 -407.723404)
			(xy 287.848107 -407.769105) (xy 287.803508 -407.809813) (xy 287.779206 -407.827734) (xy 287.770316 -407.834338)
			(xy 287.759394 -407.853134) (xy 287.749488 -407.951178) (xy 287.7566 -407.971752) (xy 287.763966 -407.97988)
			(xy 287.78317 -408.001185) (xy 287.815636 -408.048467) (xy 287.840659 -408.100076) (xy 287.857674 -408.154849)
			(xy 287.8663 -408.211553) (xy 287.866836 -408.24023) (xy 287.86635 -408.267481) (xy 287.858594 -408.321429)
			(xy 287.843239 -408.373724) (xy 287.820597 -408.423301) (xy 287.791131 -408.469151) (xy 287.75544 -408.510342)
			(xy 287.714249 -408.546033) (xy 287.668399 -408.575499) (xy 287.618822 -408.598141) (xy 287.566527 -408.613496)
			(xy 287.512579 -408.621252) (xy 287.458077 -408.621252) (xy 287.404129 -408.613496) (xy 287.351834 -408.598141)
			(xy 287.302257 -408.575499) (xy 287.256407 -408.546033) (xy 287.215216 -408.510342) (xy 287.179525 -408.469151)
			(xy 287.150059 -408.423301) (xy 287.127417 -408.373724) (xy 287.112062 -408.321429) (xy 287.104306 -408.267481)
			(xy 287.10382 -408.24023) (xy 287.104357 -408.211729) (xy 287.112843 -408.155363) (xy 287.129631 -408.10089)
			(xy 287.154345 -408.049524) (xy 287.186435 -408.002414) (xy 287.20542 -407.98115) (xy 287.212786 -407.973022)
			(xy 287.219644 -407.952448) (xy 287.209484 -407.854404) (xy 287.198562 -407.835608) (xy 287.189418 -407.829258)
			(xy 287.16489 -407.811376) (xy 287.119887 -407.770636) (xy 287.080052 -407.72483) (xy 287.045952 -407.674609)
			(xy 287.018071 -407.620687) (xy 286.996805 -407.56383) (xy 286.982457 -407.504846) (xy 286.97523 -407.444574)
			(xy 286.974788 -407.414222) (xy 284.268541 -407.414222) (xy 284.280566 -407.460605) (xy 284.288733 -407.524506)
			(xy 284.289246 -407.556716) (xy 284.288759 -407.587446) (xy 284.281349 -407.648457) (xy 284.26664 -407.708131)
			(xy 284.244846 -407.765597) (xy 284.216284 -407.820017) (xy 284.181372 -407.870597) (xy 284.140617 -407.916601)
			(xy 284.094615 -407.957358) (xy 284.044036 -407.992273) (xy 283.989617 -408.020837) (xy 283.932152 -408.042634)
			(xy 283.872479 -408.057345) (xy 283.811468 -408.064758) (xy 283.780738 -408.065224) (xy 283.745782 -408.064672)
			(xy 283.676527 -408.055102) (xy 283.609236 -408.036138) (xy 283.545177 -408.008137) (xy 283.485555 -407.971626)
			(xy 283.458158 -407.949908) (xy 283.451149 -407.944626) (xy 283.434665 -407.938644) (xy 283.4259 -407.938224)
			(xy 283.271976 -407.938224) (xy 283.2632 -407.938589) (xy 283.246698 -407.944574) (xy 283.239718 -407.949908)
			(xy 283.212314 -407.971614) (xy 283.152689 -408.008112) (xy 283.08863 -408.036106) (xy 283.021342 -408.055069)
			(xy 282.952092 -408.064643) (xy 282.917138 -408.065224) (xy 282.886407 -408.064727) (xy 282.825394 -408.057323)
			(xy 282.765717 -408.042618) (xy 282.708248 -408.020827) (xy 282.653825 -407.992268) (xy 282.603242 -407.957357)
			(xy 282.557235 -407.916603) (xy 282.516476 -407.870601) (xy 282.48156 -407.820021) (xy 282.452995 -407.765601)
			(xy 282.431198 -407.708134) (xy 282.416487 -407.64846) (xy 282.409077 -407.587447) (xy 282.40863 -407.556716)
			(xy 281.88285 -407.556716) (xy 281.88285 -409.268422) (xy 281.882421 -409.278489) (xy 281.874696 -409.297083)
			(xy 281.867864 -409.30449) (xy 281.177492 -409.994862) (xy 288.80689 -409.994862) (xy 288.807478 -409.960258)
			(xy 288.816877 -409.891693) (xy 288.835495 -409.825037) (xy 288.862988 -409.761525) (xy 288.898848 -409.702333)
			(xy 288.920174 -409.675076) (xy 288.927054 -409.665709) (xy 288.932254 -409.643078) (xy 288.927035 -409.620451)
			(xy 288.920174 -409.611068) (xy 288.898843 -409.583817) (xy 288.863008 -409.524612) (xy 288.835528 -409.461098)
			(xy 288.816907 -409.394445) (xy 288.807491 -409.325884) (xy 288.80689 -409.291282) (xy 288.807392 -409.259321)
			(xy 288.815403 -409.195903) (xy 288.8313 -409.133989) (xy 288.854832 -409.074556) (xy 288.885626 -409.018541)
			(xy 288.923199 -408.966826) (xy 288.966956 -408.920229) (xy 289.016209 -408.879484) (xy 289.07018 -408.845233)
			(xy 289.128019 -408.818016) (xy 289.188812 -408.798263) (xy 289.251602 -408.786285) (xy 289.315398 -408.782272)
			(xy 289.379194 -408.786285) (xy 289.441984 -408.798263) (xy 289.502777 -408.818016) (xy 289.560616 -408.845233)
			(xy 289.614587 -408.879484) (xy 289.66384 -408.920229) (xy 289.707597 -408.966826) (xy 289.74517 -409.018541)
			(xy 289.775964 -409.074556) (xy 289.799496 -409.133989) (xy 289.815393 -409.195903) (xy 289.823404 -409.259321)
			(xy 289.823906 -409.291282) (xy 289.823343 -409.325886) (xy 289.813939 -409.394453) (xy 289.795315 -409.461109)
			(xy 289.767816 -409.524621) (xy 289.731951 -409.583812) (xy 289.710622 -409.611068) (xy 289.703783 -409.620463)
			(xy 289.698557 -409.643078) (xy 289.703764 -409.665697) (xy 289.710622 -409.675076) (xy 289.731927 -409.702347)
			(xy 289.767766 -409.761546) (xy 289.795252 -409.825055) (xy 289.813878 -409.891704) (xy 289.823301 -409.960261)
			(xy 289.823906 -409.994862) (xy 289.823404 -410.026823) (xy 289.815393 -410.090241) (xy 289.799496 -410.152155)
			(xy 289.775964 -410.211588) (xy 289.74517 -410.267603) (xy 289.707597 -410.319318) (xy 289.66384 -410.365915)
			(xy 289.614587 -410.40666) (xy 289.560616 -410.440911) (xy 289.502777 -410.468128) (xy 289.441984 -410.487881)
			(xy 289.379194 -410.499859) (xy 289.315398 -410.503873) (xy 289.251602 -410.499859) (xy 289.188812 -410.487881)
			(xy 289.128019 -410.468128) (xy 289.07018 -410.440911) (xy 289.016209 -410.40666) (xy 288.966956 -410.365915)
			(xy 288.923199 -410.319318) (xy 288.885626 -410.267603) (xy 288.854832 -410.211588) (xy 288.8313 -410.152155)
			(xy 288.815403 -410.090241) (xy 288.807392 -410.026823) (xy 288.80689 -409.994862) (xy 281.177492 -409.994862)
			(xy 280.524204 -410.64815) (xy 280.517365 -410.655551) (xy 280.509648 -410.674149) (xy 280.509218 -410.684218)
			(xy 280.509218 -410.79039) (xy 280.508797 -410.800461) (xy 280.501088 -410.81907) (xy 280.494232 -410.826458)
			(xy 280.494232 -411.364176) (xy 280.493727 -411.374227) (xy 280.486007 -411.392789) (xy 280.479246 -411.400244)
			(xy 280.321766 -411.557724) (xy 282.928058 -411.557724) (xy 282.932129 -411.502102) (xy 282.944255 -411.447665)
			(xy 282.964178 -411.395574) (xy 282.991474 -411.346939) (xy 283.02556 -411.302796) (xy 283.065709 -411.264087)
			(xy 283.111067 -411.231636) (xy 283.160667 -411.206135) (xy 283.213451 -411.188128) (xy 283.268294 -411.177998)
			(xy 283.324028 -411.175961) (xy 283.379465 -411.182061) (xy 283.410544 -411.190186) (xy 288.83356 -411.190186)
			(xy 288.834062 -411.158225) (xy 288.842073 -411.094807) (xy 288.85797 -411.032893) (xy 288.881502 -410.97346)
			(xy 288.912296 -410.917445) (xy 288.949869 -410.86573) (xy 288.993626 -410.819133) (xy 289.042879 -410.778388)
			(xy 289.09685 -410.744137) (xy 289.154689 -410.71692) (xy 289.215482 -410.697167) (xy 289.278272 -410.685189)
			(xy 289.342068 -410.681176) (xy 289.405864 -410.685189) (xy 289.468654 -410.697167) (xy 289.529447 -410.71692)
			(xy 289.587286 -410.744137) (xy 289.641257 -410.778388) (xy 289.69051 -410.819133) (xy 289.734267 -410.86573)
			(xy 289.77184 -410.917445) (xy 289.802634 -410.97346) (xy 289.826166 -411.032893) (xy 289.842063 -411.094807)
			(xy 289.850074 -411.158225) (xy 289.850576 -411.190186) (xy 289.850052 -411.223559) (xy 289.841303 -411.28973)
			(xy 289.823966 -411.354186) (xy 289.798341 -411.415818) (xy 289.764867 -411.473564) (xy 289.744912 -411.50032)
			(xy 289.738305 -411.509708) (xy 289.733649 -411.532171) (xy 289.739238 -411.554421) (xy 289.746182 -411.563566)
			(xy 289.768027 -411.591027) (xy 289.804791 -411.650793) (xy 289.832985 -411.715048) (xy 289.852071 -411.782571)
			(xy 289.861688 -411.852077) (xy 289.86226 -411.887162) (xy 289.8617 -411.920295) (xy 289.85309 -411.985998)
			(xy 289.836023 -412.050028) (xy 289.810789 -412.111301) (xy 289.777814 -412.16878) (xy 289.737657 -412.221491)
			(xy 289.690997 -412.268544) (xy 289.638623 -412.309141) (xy 289.610292 -412.326328) (xy 289.601402 -412.331408)
			(xy 289.589464 -412.347156) (xy 289.565842 -412.43631) (xy 289.568382 -412.455868) (xy 289.573462 -412.464758)
			(xy 289.585567 -412.486572) (xy 289.604641 -412.532669) (xy 289.617555 -412.580857) (xy 289.62409 -412.630314)
			(xy 289.624516 -412.655258) (xy 289.62403 -412.682509) (xy 289.616274 -412.736457) (xy 289.600919 -412.788752)
			(xy 289.578277 -412.838329) (xy 289.548811 -412.884179) (xy 289.51312 -412.92537) (xy 289.471929 -412.961061)
			(xy 289.426079 -412.990527) (xy 289.376502 -413.013169) (xy 289.324207 -413.028524) (xy 289.270259 -413.03628)
			(xy 289.215757 -413.03628) (xy 289.161809 -413.028524) (xy 289.109514 -413.013169) (xy 289.059937 -412.990527)
			(xy 289.014087 -412.961061) (xy 288.972896 -412.92537) (xy 288.937205 -412.884179) (xy 288.907739 -412.838329)
			(xy 288.885097 -412.788752) (xy 288.869742 -412.736457) (xy 288.861986 -412.682509) (xy 288.8615 -412.655258)
			(xy 288.861928 -412.629517) (xy 288.86886 -412.578504) (xy 288.882594 -412.528887) (xy 288.902879 -412.48157)
			(xy 288.929346 -412.437412) (xy 288.961514 -412.397217) (xy 288.979864 -412.37916) (xy 288.98723 -412.372048)
			(xy 288.995358 -412.354014) (xy 288.997644 -412.261812) (xy 288.990786 -412.24327) (xy 288.983674 -412.235904)
			(xy 288.962046 -412.212265) (xy 288.924309 -412.160483) (xy 288.893377 -412.104371) (xy 288.86974 -412.044817)
			(xy 288.853773 -411.982765) (xy 288.845727 -411.919199) (xy 288.845244 -411.887162) (xy 288.84579 -411.853789)
			(xy 288.854533 -411.787619) (xy 288.871864 -411.723163) (xy 288.897485 -411.661531) (xy 288.930955 -411.603784)
			(xy 288.950908 -411.577028) (xy 288.957469 -411.567613) (xy 288.962136 -411.545167) (xy 288.95657 -411.522927)
			(xy 288.949638 -411.513782) (xy 288.927772 -411.486338) (xy 288.89101 -411.426567) (xy 288.862821 -411.362308)
			(xy 288.843739 -411.294781) (xy 288.834129 -411.225272) (xy 288.83356 -411.190186) (xy 283.410544 -411.190186)
			(xy 283.433422 -411.196167) (xy 283.484751 -411.217979) (xy 283.532357 -411.247033) (xy 283.575225 -411.282708)
			(xy 283.612442 -411.324245) (xy 283.643215 -411.370758) (xy 283.666887 -411.421255) (xy 283.682955 -411.474662)
			(xy 283.691075 -411.529838) (xy 283.691584 -411.557724) (xy 283.691075 -411.58561) (xy 283.682955 -411.640786)
			(xy 283.666887 -411.694193) (xy 283.664896 -411.69844) (xy 287.188654 -411.69844) (xy 287.192725 -411.642818)
			(xy 287.204851 -411.588381) (xy 287.224774 -411.53629) (xy 287.25207 -411.487655) (xy 287.286156 -411.443512)
			(xy 287.326305 -411.404803) (xy 287.371663 -411.372352) (xy 287.421263 -411.346851) (xy 287.474047 -411.328844)
			(xy 287.52889 -411.318714) (xy 287.584624 -411.316677) (xy 287.640061 -411.322777) (xy 287.694018 -411.336883)
			(xy 287.745347 -411.358695) (xy 287.792953 -411.387749) (xy 287.835821 -411.423424) (xy 287.873038 -411.464961)
			(xy 287.903811 -411.511474) (xy 287.927483 -411.561971) (xy 287.943551 -411.615378) (xy 287.951671 -411.670554)
			(xy 287.95218 -411.69844) (xy 287.951671 -411.726326) (xy 287.943551 -411.781502) (xy 287.927483 -411.834909)
			(xy 287.903811 -411.885406) (xy 287.873038 -411.931919) (xy 287.835821 -411.973456) (xy 287.792953 -412.009131)
			(xy 287.745347 -412.038185) (xy 287.694018 -412.059997) (xy 287.640061 -412.074103) (xy 287.584624 -412.080203)
			(xy 287.52889 -412.078166) (xy 287.474047 -412.068036) (xy 287.421263 -412.050029) (xy 287.371663 -412.024528)
			(xy 287.326305 -411.992077) (xy 287.286156 -411.953368) (xy 287.25207 -411.909225) (xy 287.224774 -411.86059)
			(xy 287.204851 -411.808499) (xy 287.192725 -411.754062) (xy 287.188654 -411.69844) (xy 283.664896 -411.69844)
			(xy 283.643215 -411.74469) (xy 283.612442 -411.791203) (xy 283.575225 -411.83274) (xy 283.532357 -411.868415)
			(xy 283.484751 -411.897469) (xy 283.433422 -411.919281) (xy 283.379465 -411.933387) (xy 283.324028 -411.939487)
			(xy 283.268294 -411.93745) (xy 283.213451 -411.92732) (xy 283.160667 -411.909313) (xy 283.111067 -411.883812)
			(xy 283.065709 -411.851361) (xy 283.02556 -411.812652) (xy 282.991474 -411.768509) (xy 282.964178 -411.719874)
			(xy 282.944255 -411.667783) (xy 282.932129 -411.613346) (xy 282.928058 -411.557724) (xy 280.321766 -411.557724)
			(xy 280.071068 -411.808422) (xy 280.067004 -411.84322) (xy 280.076402 -411.85846) (xy 280.09444 -411.888724)
			(xy 280.122913 -411.953168) (xy 280.142221 -412.020924) (xy 280.151995 -412.090696) (xy 280.152602 -412.125922)
			(xy 280.152109 -412.157812) (xy 280.144139 -412.221093) (xy 280.128315 -412.28288) (xy 280.104885 -412.342202)
			(xy 280.074218 -412.398126) (xy 280.036795 -412.449774) (xy 279.993205 -412.496334) (xy 279.944132 -412.537075)
			(xy 279.890347 -412.571357) (xy 279.832697 -412.59864) (xy 279.772085 -412.618497) (xy 279.740868 -412.625032)
			(xy 279.732062 -412.627079) (xy 279.716601 -412.636428) (xy 279.705371 -412.650581) (xy 279.70226 -412.659068)
			(xy 279.691215 -412.690612) (xy 279.662009 -412.750729) (xy 279.625189 -412.806508) (xy 279.581387 -412.85699)
			(xy 279.556718 -412.87954) (xy 279.548616 -412.887493) (xy 279.539654 -412.908321) (xy 279.539446 -412.919672)
			(xy 279.539954 -412.940246) (xy 279.539454 -412.972563) (xy 279.53127 -413.036676) (xy 279.515026 -413.099235)
			(xy 279.490986 -413.159231) (xy 279.459536 -413.215696) (xy 279.421184 -413.267721) (xy 279.376548 -413.314466)
			(xy 279.326348 -413.355177) (xy 279.271393 -413.389198) (xy 279.21257 -413.41598) (xy 279.150827 -413.435092)
			(xy 279.119076 -413.441134) (xy 279.105868 -413.44342) (xy 279.085802 -413.459676) (xy 279.042876 -413.563308)
			(xy 279.045924 -413.588962) (xy 279.053544 -413.599884) (xy 279.071165 -413.625695) (xy 279.100654 -413.680798)
			(xy 279.123166 -413.739101) (xy 279.138361 -413.799723) (xy 279.146011 -413.861751) (xy 279.146508 -413.893)
			(xy 279.146044 -413.923731) (xy 279.138635 -413.984745) (xy 279.123927 -414.044421) (xy 279.102132 -414.101889)
			(xy 279.077511 -414.1488) (xy 282.519546 -414.1488) (xy 282.523561 -414.084995) (xy 282.535541 -414.022197)
			(xy 282.555298 -413.961395) (xy 282.58252 -413.903549) (xy 282.616777 -413.849572) (xy 282.65753 -413.800313)
			(xy 282.704136 -413.756552) (xy 282.755859 -413.718977) (xy 282.811884 -413.688181) (xy 282.871327 -413.66465)
			(xy 282.933251 -413.648756) (xy 282.996678 -413.640748) (xy 283.028644 -413.64027) (xy 283.063271 -413.640854)
			(xy 283.131885 -413.650253) (xy 283.198589 -413.668871) (xy 283.262152 -413.696365) (xy 283.321399 -413.732225)
			(xy 283.348684 -413.753554) (xy 283.355887 -413.758928) (xy 283.372877 -413.764747) (xy 283.39083 -413.764336)
			(xy 283.407535 -413.757745) (xy 283.41447 -413.75203) (xy 283.437799 -413.731875) (xy 283.488475 -413.696761)
			(xy 283.543028 -413.668039) (xy 283.600657 -413.646131) (xy 283.660513 -413.631358) (xy 283.721717 -413.623938)
			(xy 283.752544 -413.623506) (xy 283.784504 -413.623983) (xy 283.84792 -413.631999) (xy 283.909831 -413.6479)
			(xy 283.969261 -413.671434) (xy 284.025273 -413.702232) (xy 284.076983 -413.739806) (xy 284.123577 -413.783564)
			(xy 284.16432 -413.832817) (xy 284.198568 -413.886788) (xy 284.225783 -413.944625) (xy 284.245534 -414.005418)
			(xy 284.257511 -414.068206) (xy 284.261525 -414.132) (xy 284.257511 -414.195794) (xy 284.245534 -414.258582)
			(xy 284.225783 -414.319375) (xy 284.198568 -414.377212) (xy 284.16432 -414.431183) (xy 284.123577 -414.480436)
			(xy 284.076983 -414.524194) (xy 284.025273 -414.561768) (xy 283.969261 -414.592566) (xy 283.909831 -414.6161)
			(xy 283.84792 -414.632001) (xy 283.784504 -414.640017) (xy 283.752544 -414.640522) (xy 283.717917 -414.639946)
			(xy 283.649303 -414.630545) (xy 283.582598 -414.611925) (xy 283.519035 -414.58443) (xy 283.459789 -414.548568)
			(xy 283.432504 -414.527238) (xy 283.425308 -414.521853) (xy 283.408315 -414.516037) (xy 283.390359 -414.516451)
			(xy 283.373653 -414.523046) (xy 283.366718 -414.528762) (xy 283.343393 -414.548922) (xy 283.292716 -414.584035)
			(xy 283.238162 -414.612756) (xy 283.180533 -414.634664) (xy 283.120676 -414.649436) (xy 283.059471 -414.656855)
			(xy 283.028644 -414.657286) (xy 282.996678 -414.656852) (xy 282.933251 -414.648844) (xy 282.871327 -414.63295)
			(xy 282.811884 -414.609419) (xy 282.755859 -414.578623) (xy 282.704136 -414.541048) (xy 282.65753 -414.497287)
			(xy 282.616777 -414.448028) (xy 282.58252 -414.394051) (xy 282.555298 -414.336205) (xy 282.535541 -414.275403)
			(xy 282.523561 -414.212605) (xy 282.519546 -414.1488) (xy 279.077511 -414.1488) (xy 279.073569 -414.156311)
			(xy 279.038655 -414.206893) (xy 278.997898 -414.252898) (xy 278.951893 -414.293655) (xy 278.901311 -414.328569)
			(xy 278.846889 -414.357132) (xy 278.789421 -414.378927) (xy 278.729745 -414.393635) (xy 278.668731 -414.401044)
			(xy 278.638 -414.401508) (xy 278.60448 -414.400972) (xy 278.538023 -414.392163) (xy 278.473299 -414.374698)
			(xy 278.411431 -414.348879) (xy 278.353492 -414.315155) (xy 278.300487 -414.27411) (xy 278.276558 -414.250632)
			(xy 278.267668 -414.241742) (xy 278.244554 -414.234122) (xy 278.138382 -414.251394) (xy 278.118824 -414.265872)
			(xy 278.113236 -414.277048) (xy 278.097748 -414.30708) (xy 278.060007 -414.36313) (xy 278.015172 -414.413685)
			(xy 277.964034 -414.457853) (xy 277.907495 -414.494858) (xy 277.87727 -414.509966) (xy 277.864835 -414.516389)
			(xy 277.843806 -414.534844) (xy 277.828578 -414.558315) (xy 277.820297 -414.585039) (xy 277.819584 -414.613009)
			(xy 277.826493 -414.64012) (xy 277.840505 -414.664337) (xy 277.860567 -414.683839) (xy 277.872698 -414.690814)
			(xy 277.899027 -414.705643) (xy 277.948299 -414.740626) (xy 277.993076 -414.781205) (xy 278.032727 -414.826805)
			(xy 278.066693 -414.876784) (xy 278.080978 -414.903412) (xy 278.086566 -414.91408) (xy 278.105108 -414.927796)
			(xy 278.207724 -414.946592) (xy 278.23033 -414.940242) (xy 278.23922 -414.932114) (xy 278.262603 -414.911708)
			(xy 278.313459 -414.876136) (xy 278.368269 -414.847022) (xy 278.426216 -414.824801) (xy 278.486439 -414.809804)
			(xy 278.548041 -414.802253) (xy 278.579072 -414.801812) (xy 278.611034 -414.802291) (xy 278.674455 -414.8103)
			(xy 278.736372 -414.826194) (xy 278.795808 -414.849724) (xy 278.851827 -414.880518) (xy 278.903544 -414.91809)
			(xy 278.950144 -414.961848) (xy 278.990892 -415.011101) (xy 279.025146 -415.065074) (xy 279.052364 -415.122914)
			(xy 279.072119 -415.18371) (xy 279.084098 -415.246502) (xy 279.087487 -415.300371) (xy 285.123122 -415.300371)
			(xy 285.123122 -415.236449) (xy 285.131133 -415.173031) (xy 285.14703 -415.111117) (xy 285.170562 -415.051684)
			(xy 285.201356 -414.995669) (xy 285.238929 -414.943954) (xy 285.282686 -414.897357) (xy 285.331939 -414.856612)
			(xy 285.38591 -414.822361) (xy 285.443749 -414.795144) (xy 285.504542 -414.775391) (xy 285.567332 -414.763413)
			(xy 285.631128 -414.7594) (xy 285.694924 -414.763413) (xy 285.757714 -414.775391) (xy 285.818507 -414.795144)
			(xy 285.876346 -414.822361) (xy 285.930317 -414.856612) (xy 285.97957 -414.897357) (xy 286.023327 -414.943954)
			(xy 286.0609 -414.995669) (xy 286.091694 -415.051684) (xy 286.115226 -415.111117) (xy 286.131123 -415.173031)
			(xy 286.134888 -415.202835) (xy 287.269168 -415.202835) (xy 287.269168 -415.138913) (xy 287.277179 -415.075495)
			(xy 287.293076 -415.013581) (xy 287.316608 -414.954148) (xy 287.347402 -414.898133) (xy 287.384975 -414.846418)
			(xy 287.428732 -414.799821) (xy 287.477985 -414.759076) (xy 287.531956 -414.724825) (xy 287.589795 -414.697608)
			(xy 287.650588 -414.677855) (xy 287.713378 -414.665877) (xy 287.777174 -414.661864) (xy 287.84097 -414.665877)
			(xy 287.90376 -414.677855) (xy 287.964553 -414.697608) (xy 288.022392 -414.724825) (xy 288.076363 -414.759076)
			(xy 288.125616 -414.799821) (xy 288.169373 -414.846418) (xy 288.206946 -414.898133) (xy 288.23774 -414.954148)
			(xy 288.261272 -415.013581) (xy 288.277169 -415.075495) (xy 288.28518 -415.138913) (xy 288.285682 -415.170874)
			(xy 288.28518 -415.202835) (xy 288.277169 -415.266253) (xy 288.261272 -415.328167) (xy 288.23774 -415.3876)
			(xy 288.206946 -415.443615) (xy 288.169373 -415.49533) (xy 288.125616 -415.541927) (xy 288.076363 -415.582672)
			(xy 288.022392 -415.616923) (xy 287.964553 -415.64414) (xy 287.90376 -415.663893) (xy 287.84097 -415.675871)
			(xy 287.777174 -415.679885) (xy 287.713378 -415.675871) (xy 287.650588 -415.663893) (xy 287.589795 -415.64414)
			(xy 287.531956 -415.616923) (xy 287.477985 -415.582672) (xy 287.428732 -415.541927) (xy 287.384975 -415.49533)
			(xy 287.347402 -415.443615) (xy 287.316608 -415.3876) (xy 287.293076 -415.328167) (xy 287.277179 -415.266253)
			(xy 287.269168 -415.202835) (xy 286.134888 -415.202835) (xy 286.139134 -415.236449) (xy 286.139636 -415.26841)
			(xy 286.139134 -415.300371) (xy 286.131123 -415.363789) (xy 286.115226 -415.425703) (xy 286.091694 -415.485136)
			(xy 286.0609 -415.541151) (xy 286.023327 -415.592866) (xy 285.97957 -415.639463) (xy 285.930317 -415.680208)
			(xy 285.876346 -415.714459) (xy 285.818507 -415.741676) (xy 285.757714 -415.761429) (xy 285.694924 -415.773407)
			(xy 285.631128 -415.777421) (xy 285.567332 -415.773407) (xy 285.504542 -415.761429) (xy 285.443749 -415.741676)
			(xy 285.38591 -415.714459) (xy 285.331939 -415.680208) (xy 285.282686 -415.639463) (xy 285.238929 -415.592866)
			(xy 285.201356 -415.541151) (xy 285.170562 -415.485136) (xy 285.14703 -415.425703) (xy 285.131133 -415.363789)
			(xy 285.123122 -415.300371) (xy 279.087487 -415.300371) (xy 279.088112 -415.3103) (xy 279.084098 -415.374098)
			(xy 279.072119 -415.43689) (xy 279.052364 -415.497686) (xy 279.025146 -415.555526) (xy 278.990892 -415.609499)
			(xy 278.950144 -415.658752) (xy 278.903544 -415.70251) (xy 278.851827 -415.740082) (xy 278.795808 -415.770876)
			(xy 278.736372 -415.794406) (xy 278.674455 -415.8103) (xy 278.611034 -415.818309) (xy 278.579072 -415.818828)
			(xy 278.548209 -415.818373) (xy 278.486937 -415.810896) (xy 278.427021 -415.796057) (xy 278.369342 -415.774072)
			(xy 278.314749 -415.745267) (xy 278.264045 -415.710063) (xy 278.217976 -415.668981) (xy 278.17722 -415.622622)
			(xy 278.142376 -415.571671) (xy 278.127714 -415.544508) (xy 278.122126 -415.53384) (xy 278.103584 -415.520124)
			(xy 278.000968 -415.501582) (xy 277.978616 -415.507932) (xy 277.969726 -415.515806) (xy 277.946306 -415.53624)
			(xy 277.895372 -415.571862) (xy 277.84048 -415.60102) (xy 277.782447 -415.623278) (xy 277.722136 -415.638306)
			(xy 277.660444 -415.64588) (xy 277.629366 -415.646362) (xy 277.598621 -415.645896) (xy 277.53758 -415.63848)
			(xy 277.477877 -415.623761) (xy 277.420384 -415.601954) (xy 277.365939 -415.573375) (xy 277.315335 -415.538443)
			(xy 277.26931 -415.497666) (xy 277.228536 -415.451639) (xy 277.193607 -415.401032) (xy 277.165032 -415.346585)
			(xy 277.143228 -415.28909) (xy 277.128513 -415.229387) (xy 277.121102 -415.168345) (xy 277.120604 -415.1376)
			(xy 277.121065 -415.107003) (xy 277.128414 -415.046251) (xy 277.142994 -414.986819) (xy 277.164595 -414.929563)
			(xy 277.192905 -414.875311) (xy 277.227516 -414.824844) (xy 277.267928 -414.778891) (xy 277.313558 -414.738116)
			(xy 277.363748 -414.703105) (xy 277.417773 -414.674364) (xy 277.474855 -414.652309) (xy 277.504398 -414.644332)
			(xy 277.512197 -414.642057) (xy 277.525925 -414.633386) (xy 277.531322 -414.627314) (xy 277.535386 -414.622488)
			(xy 277.542258 -414.61325) (xy 277.547645 -414.590888) (xy 277.54277 -414.56841) (xy 277.536148 -414.558988)
			(xy 277.528274 -414.548828) (xy 277.515574 -414.539938) (xy 277.507954 -414.537652) (xy 277.486636 -414.530881)
			(xy 277.445172 -414.514096) (xy 277.42515 -414.504124) (xy 277.410418 -414.496504) (xy 277.377906 -414.501584)
			(xy 276.14753 -415.73196) (xy 276.140164 -415.739072) (xy 276.132544 -415.757868) (xy 276.132544 -417.014385)
			(xy 284.219894 -417.014385) (xy 284.219894 -416.961087) (xy 284.227837 -416.908383) (xy 284.243547 -416.857453)
			(xy 284.266673 -416.809432) (xy 284.296697 -416.765395) (xy 284.332949 -416.726324) (xy 284.37462 -416.693093)
			(xy 284.420778 -416.666444) (xy 284.470392 -416.646972) (xy 284.522354 -416.635112) (xy 284.575504 -416.631129)
			(xy 284.628654 -416.635112) (xy 284.680616 -416.646972) (xy 284.73023 -416.666444) (xy 284.776388 -416.693093)
			(xy 284.818059 -416.726324) (xy 284.854311 -416.765395) (xy 284.884335 -416.809432) (xy 284.907461 -416.857453)
			(xy 284.923171 -416.908383) (xy 284.931114 -416.961087) (xy 284.931612 -416.987736) (xy 284.931114 -417.014385)
			(xy 284.928434 -417.032165) (xy 285.518088 -417.032165) (xy 285.518088 -416.978867) (xy 285.526031 -416.926163)
			(xy 285.541741 -416.875233) (xy 285.564867 -416.827212) (xy 285.594891 -416.783175) (xy 285.631143 -416.744104)
			(xy 285.672814 -416.710873) (xy 285.718972 -416.684224) (xy 285.768586 -416.664752) (xy 285.820548 -416.652892)
			(xy 285.873698 -416.648909) (xy 285.926848 -416.652892) (xy 285.97881 -416.664752) (xy 286.028424 -416.684224)
			(xy 286.074582 -416.710873) (xy 286.116253 -416.744104) (xy 286.152505 -416.783175) (xy 286.182529 -416.827212)
			(xy 286.205655 -416.875233) (xy 286.221365 -416.926163) (xy 286.229308 -416.978867) (xy 286.229806 -417.005516)
			(xy 286.229313 -417.031911) (xy 286.860478 -417.031911) (xy 286.860478 -416.978613) (xy 286.868421 -416.925909)
			(xy 286.884131 -416.874979) (xy 286.907257 -416.826958) (xy 286.937281 -416.782921) (xy 286.973533 -416.74385)
			(xy 287.015204 -416.710619) (xy 287.061362 -416.68397) (xy 287.110976 -416.664498) (xy 287.162938 -416.652638)
			(xy 287.216088 -416.648655) (xy 287.269238 -416.652638) (xy 287.3212 -416.664498) (xy 287.370814 -416.68397)
			(xy 287.416972 -416.710619) (xy 287.458643 -416.74385) (xy 287.494895 -416.782921) (xy 287.524919 -416.826958)
			(xy 287.548045 -416.874979) (xy 287.563755 -416.925909) (xy 287.571698 -416.978613) (xy 287.572196 -417.005262)
			(xy 287.571698 -417.031911) (xy 287.563755 -417.084615) (xy 287.548045 -417.135545) (xy 287.524919 -417.183566)
			(xy 287.494895 -417.227603) (xy 287.458643 -417.266674) (xy 287.416972 -417.299905) (xy 287.370814 -417.326554)
			(xy 287.3212 -417.346026) (xy 287.269238 -417.357886) (xy 287.216088 -417.36187) (xy 287.162938 -417.357886)
			(xy 287.110976 -417.346026) (xy 287.061362 -417.326554) (xy 287.015204 -417.299905) (xy 286.973533 -417.266674)
			(xy 286.937281 -417.227603) (xy 286.907257 -417.183566) (xy 286.884131 -417.135545) (xy 286.868421 -417.084615)
			(xy 286.860478 -417.031911) (xy 286.229313 -417.031911) (xy 286.229308 -417.032165) (xy 286.221365 -417.084869)
			(xy 286.205655 -417.135799) (xy 286.182529 -417.18382) (xy 286.152505 -417.227857) (xy 286.116253 -417.266928)
			(xy 286.074582 -417.300159) (xy 286.028424 -417.326808) (xy 285.97881 -417.34628) (xy 285.926848 -417.35814)
			(xy 285.873698 -417.362124) (xy 285.820548 -417.35814) (xy 285.768586 -417.34628) (xy 285.718972 -417.326808)
			(xy 285.672814 -417.300159) (xy 285.631143 -417.266928) (xy 285.594891 -417.227857) (xy 285.564867 -417.18382)
			(xy 285.541741 -417.135799) (xy 285.526031 -417.084869) (xy 285.518088 -417.032165) (xy 284.928434 -417.032165)
			(xy 284.923171 -417.067089) (xy 284.907461 -417.118019) (xy 284.884335 -417.16604) (xy 284.854311 -417.210077)
			(xy 284.818059 -417.249148) (xy 284.776388 -417.282379) (xy 284.73023 -417.309028) (xy 284.680616 -417.3285)
			(xy 284.628654 -417.34036) (xy 284.575504 -417.344344) (xy 284.522354 -417.34036) (xy 284.470392 -417.3285)
			(xy 284.420778 -417.309028) (xy 284.37462 -417.282379) (xy 284.332949 -417.249148) (xy 284.296697 -417.210077)
			(xy 284.266673 -417.16604) (xy 284.243547 -417.118019) (xy 284.227837 -417.067089) (xy 284.219894 -417.014385)
			(xy 276.132544 -417.014385) (xy 276.132544 -417.48075) (xy 276.514814 -417.48075) (xy 276.5153 -417.453499)
			(xy 276.523056 -417.399551) (xy 276.538411 -417.347256) (xy 276.561053 -417.297679) (xy 276.590519 -417.251829)
			(xy 276.62621 -417.210638) (xy 276.667401 -417.174947) (xy 276.713251 -417.145481) (xy 276.762828 -417.122839)
			(xy 276.815123 -417.107484) (xy 276.869071 -417.099728) (xy 276.923573 -417.099728) (xy 276.977521 -417.107484)
			(xy 277.029816 -417.122839) (xy 277.079393 -417.145481) (xy 277.125243 -417.174947) (xy 277.166434 -417.210638)
			(xy 277.202125 -417.251829) (xy 277.231591 -417.297679) (xy 277.254233 -417.347256) (xy 277.269588 -417.399551)
			(xy 277.275529 -417.440872) (xy 278.121108 -417.440872) (xy 278.125179 -417.38525) (xy 278.137305 -417.330813)
			(xy 278.157228 -417.278722) (xy 278.184524 -417.230087) (xy 278.21861 -417.185944) (xy 278.258759 -417.147235)
			(xy 278.304117 -417.114784) (xy 278.353717 -417.089283) (xy 278.406501 -417.071276) (xy 278.461344 -417.061146)
			(xy 278.517078 -417.059109) (xy 278.572515 -417.065209) (xy 278.626472 -417.079315) (xy 278.677801 -417.101127)
			(xy 278.725407 -417.130181) (xy 278.768275 -417.165856) (xy 278.805492 -417.207393) (xy 278.836265 -417.253906)
			(xy 278.859937 -417.304403) (xy 278.876005 -417.35781) (xy 278.884125 -417.412986) (xy 278.884634 -417.440872)
			(xy 278.884125 -417.468758) (xy 278.876005 -417.523934) (xy 278.859937 -417.577341) (xy 278.836265 -417.627838)
			(xy 278.805492 -417.674351) (xy 278.768275 -417.715888) (xy 278.725407 -417.751563) (xy 278.677801 -417.780617)
			(xy 278.626472 -417.802429) (xy 278.572515 -417.816535) (xy 278.517078 -417.822635) (xy 278.461344 -417.820598)
			(xy 278.406501 -417.810468) (xy 278.353717 -417.792461) (xy 278.304117 -417.76696) (xy 278.258759 -417.734509)
			(xy 278.21861 -417.6958) (xy 278.184524 -417.651657) (xy 278.157228 -417.603022) (xy 278.137305 -417.550931)
			(xy 278.125179 -417.496494) (xy 278.121108 -417.440872) (xy 277.275529 -417.440872) (xy 277.277344 -417.453499)
			(xy 277.27783 -417.48075) (xy 277.277467 -417.504687) (xy 277.271498 -417.552187) (xy 277.259622 -417.598564)
			(xy 277.25116 -417.620958) (xy 277.247604 -417.630102) (xy 277.247604 -417.649914) (xy 277.282402 -417.73348)
			(xy 277.296118 -417.74745) (xy 277.305262 -417.751514) (xy 277.335191 -417.765056) (xy 277.391623 -417.798684)
			(xy 277.443254 -417.8393) (xy 277.489224 -417.886227) (xy 277.528767 -417.938684) (xy 277.561224 -417.995797)
			(xy 277.586055 -418.056614) (xy 277.602847 -418.120123) (xy 277.611319 -418.185266) (xy 277.61184 -418.218112)
			(xy 277.611256 -418.253067) (xy 277.609983 -418.262287) (xy 284.17519 -418.262287) (xy 284.17519 -418.208989)
			(xy 284.183133 -418.156285) (xy 284.198843 -418.105355) (xy 284.221969 -418.057334) (xy 284.251993 -418.013297)
			(xy 284.288245 -417.974226) (xy 284.329916 -417.940995) (xy 284.376074 -417.914346) (xy 284.425688 -417.894874)
			(xy 284.47765 -417.883014) (xy 284.5308 -417.879031) (xy 284.58395 -417.883014) (xy 284.635912 -417.894874)
			(xy 284.685526 -417.914346) (xy 284.731684 -417.940995) (xy 284.773355 -417.974226) (xy 284.809607 -418.013297)
			(xy 284.839631 -418.057334) (xy 284.862757 -418.105355) (xy 284.878467 -418.156285) (xy 284.88641 -418.208989)
			(xy 284.886908 -418.235638) (xy 284.88641 -418.262287) (xy 284.878467 -418.314991) (xy 284.867145 -418.351695)
			(xy 286.838126 -418.351695) (xy 286.838126 -418.298397) (xy 286.846069 -418.245693) (xy 286.861779 -418.194763)
			(xy 286.884905 -418.146742) (xy 286.914929 -418.102705) (xy 286.951181 -418.063634) (xy 286.992852 -418.030403)
			(xy 287.03901 -418.003754) (xy 287.088624 -417.984282) (xy 287.140586 -417.972422) (xy 287.193736 -417.968439)
			(xy 287.246886 -417.972422) (xy 287.298848 -417.984282) (xy 287.348462 -418.003754) (xy 287.39462 -418.030403)
			(xy 287.436291 -418.063634) (xy 287.472543 -418.102705) (xy 287.502567 -418.146742) (xy 287.525693 -418.194763)
			(xy 287.541403 -418.245693) (xy 287.549346 -418.298397) (xy 287.549844 -418.325046) (xy 287.549346 -418.351695)
			(xy 287.541403 -418.404399) (xy 287.525693 -418.455329) (xy 287.502567 -418.50335) (xy 287.472543 -418.547387)
			(xy 287.448871 -418.5729) (xy 288.426739 -418.5729) (xy 288.430752 -418.509113) (xy 288.442728 -418.446332)
			(xy 288.462478 -418.385546) (xy 288.48969 -418.327715) (xy 288.523935 -418.273751) (xy 288.564673 -418.224504)
			(xy 288.611263 -418.180751) (xy 288.662968 -418.143181) (xy 288.718974 -418.112389) (xy 288.778398 -418.088858)
			(xy 288.840303 -418.07296) (xy 288.903711 -418.064946) (xy 288.935668 -418.064442) (xy 288.971156 -418.065025)
			(xy 289.041441 -418.074903) (xy 289.109666 -418.094471) (xy 289.174503 -418.123348) (xy 289.204908 -418.141658)
			(xy 289.214814 -418.147754) (xy 289.237674 -418.150294) (xy 289.334702 -418.116004) (xy 289.350958 -418.099748)
			(xy 289.354768 -418.088572) (xy 289.364983 -418.060326) (xy 289.391124 -418.006245) (xy 289.423451 -417.955619)
			(xy 289.442144 -417.932108) (xy 289.447441 -417.925109) (xy 289.453415 -417.908618) (xy 289.453828 -417.89985)
			(xy 289.453828 -417.745926) (xy 289.453449 -417.737151) (xy 289.447475 -417.720648) (xy 289.442144 -417.713668)
			(xy 289.420423 -417.686275) (xy 289.383925 -417.626648) (xy 289.355933 -417.562586) (xy 289.336975 -417.495296)
			(xy 289.327406 -417.426043) (xy 289.326828 -417.391088) (xy 289.327379 -417.358939) (xy 289.335497 -417.295155)
			(xy 289.351589 -417.232903) (xy 289.375399 -417.173176) (xy 289.406547 -417.116925) (xy 289.444535 -417.065049)
			(xy 289.488759 -417.018375) (xy 289.538513 -416.977647) (xy 289.593004 -416.943514) (xy 289.621976 -416.92957)
			(xy 289.632136 -416.924744) (xy 289.646614 -416.90798) (xy 289.673284 -416.811206) (xy 289.669474 -416.789362)
			(xy 289.663124 -416.779964) (xy 289.647364 -416.756017) (xy 289.622391 -416.704417) (xy 289.605422 -416.64966)
			(xy 289.596839 -416.592981) (xy 289.596322 -416.564318) (xy 289.596808 -416.537067) (xy 289.604564 -416.483119)
			(xy 289.619919 -416.430824) (xy 289.642561 -416.381247) (xy 289.672027 -416.335397) (xy 289.707718 -416.294206)
			(xy 289.748909 -416.258515) (xy 289.794759 -416.229049) (xy 289.844336 -416.206407) (xy 289.896631 -416.191052)
			(xy 289.950579 -416.183296) (xy 290.005081 -416.183296) (xy 290.059029 -416.191052) (xy 290.111324 -416.206407)
			(xy 290.160901 -416.229049) (xy 290.206751 -416.258515) (xy 290.247942 -416.294206) (xy 290.283633 -416.335397)
			(xy 290.313099 -416.381247) (xy 290.335741 -416.430824) (xy 290.351096 -416.483119) (xy 290.358852 -416.537067)
			(xy 290.359338 -416.564318) (xy 290.358948 -416.589999) (xy 290.35207 -416.640897) (xy 290.338429 -416.690413)
			(xy 290.318271 -416.737653) (xy 290.291959 -416.781762) (xy 290.259969 -416.821944) (xy 290.22288 -416.857473)
			(xy 290.202366 -416.872928) (xy 290.192968 -416.879532) (xy 290.1823 -416.898836) (xy 290.174934 -416.998912)
			(xy 290.182808 -417.01974) (xy 290.190936 -417.027614) (xy 290.214675 -417.051622) (xy 290.256268 -417.104805)
			(xy 290.290456 -417.163025) (xy 290.316639 -417.225258) (xy 290.334354 -417.290408) (xy 290.343292 -417.35733)
			(xy 290.343844 -417.391088) (xy 290.343246 -417.426043) (xy 290.333687 -417.495295) (xy 290.314733 -417.562585)
			(xy 290.286742 -417.626646) (xy 290.250241 -417.686269) (xy 290.228528 -417.713668) (xy 290.223238 -417.720671)
			(xy 290.21726 -417.73716) (xy 290.216844 -417.745926) (xy 290.216844 -417.89985) (xy 290.21724 -417.908624)
			(xy 290.223203 -417.925126) (xy 290.228528 -417.932108) (xy 290.250249 -417.959501) (xy 290.286744 -418.019129)
			(xy 290.314735 -418.083191) (xy 290.333694 -418.150481) (xy 290.343264 -418.219733) (xy 290.343844 -418.254688)
			(xy 290.343491 -418.282344) (xy 290.337504 -418.33733) (xy 290.331906 -418.364416) (xy 290.32962 -418.37483)
			(xy 290.33343 -418.39515) (xy 290.387024 -418.47389) (xy 290.404296 -418.484812) (xy 290.414964 -418.48659)
			(xy 290.440587 -418.491137) (xy 290.490351 -418.506359) (xy 290.537587 -418.528197) (xy 290.58142 -418.556249)
			(xy 290.621038 -418.589993) (xy 290.655706 -418.628804) (xy 290.684782 -418.671964) (xy 290.69665 -418.695124)
			(xy 290.702492 -418.706808) (xy 290.723574 -418.721794) (xy 290.834826 -418.733986) (xy 290.858702 -418.724334)
			(xy 290.867084 -418.71392) (xy 290.885312 -418.692133) (xy 290.927107 -418.653663) (xy 290.974143 -418.621814)
			(xy 291.02538 -418.597289) (xy 291.079686 -418.58063) (xy 291.135862 -418.572205) (xy 291.164264 -418.57168)
			(xy 291.191515 -418.572189) (xy 291.245464 -418.579941) (xy 291.29776 -418.595291) (xy 291.34734 -418.617929)
			(xy 291.393192 -418.647392) (xy 291.434385 -418.683081) (xy 291.470079 -418.724269) (xy 291.499548 -418.770118)
			(xy 291.522192 -418.819695) (xy 291.537549 -418.871989) (xy 291.545308 -418.925937) (xy 291.545772 -418.953188)
			(xy 291.545332 -418.979234) (xy 291.538257 -419.030842) (xy 291.524235 -419.08101) (xy 291.503528 -419.128808)
			(xy 291.4904 -419.151308) (xy 291.48588 -419.159562) (xy 291.482488 -419.178057) (xy 291.483796 -419.187376)
			(xy 291.489892 -419.217856) (xy 291.492072 -419.227216) (xy 291.502406 -419.243406) (xy 291.509958 -419.249352)
			(xy 291.533966 -419.267305) (xy 291.578009 -419.307977) (xy 291.616963 -419.353546) (xy 291.650287 -419.403381)
			(xy 291.677518 -419.45679) (xy 291.698279 -419.51303) (xy 291.71228 -419.571323) (xy 291.719327 -419.630857)
			(xy 291.719762 -419.660832) (xy 291.719185 -419.695787) (xy 291.70962 -419.76504) (xy 291.690661 -419.832331)
			(xy 291.662665 -419.896391) (xy 291.626161 -419.956013) (xy 291.604446 -419.983412) (xy 291.599164 -419.990404)
			(xy 291.593326 -420.006912) (xy 291.593016 -420.01567) (xy 291.593016 -420.169594) (xy 291.59338 -420.178341)
			(xy 291.599216 -420.194832) (xy 291.604446 -420.201852) (xy 291.626144 -420.229263) (xy 291.662642 -420.288886)
			(xy 291.690637 -420.352943) (xy 291.709602 -420.42023) (xy 291.719179 -420.489478) (xy 291.719623 -420.516122)
			(xy 292.906778 -420.516122) (xy 292.909385 -420.45309) (xy 292.919769 -420.390864) (xy 292.93777 -420.330401)
			(xy 292.963112 -420.272628) (xy 292.995405 -420.218434) (xy 293.034154 -420.168651) (xy 293.078763 -420.124043)
			(xy 293.128548 -420.085296) (xy 293.182743 -420.053004) (xy 293.240516 -420.027664) (xy 293.30098 -420.009665)
			(xy 293.363205 -419.999284) (xy 293.426238 -419.996679) (xy 293.489108 -420.00189) (xy 293.550851 -420.014839)
			(xy 293.610518 -420.035326) (xy 293.667193 -420.063035) (xy 293.720004 -420.097543) (xy 293.768142 -420.138317)
			(xy 293.810867 -420.184734) (xy 293.847522 -420.236078) (xy 293.877544 -420.291562) (xy 293.900473 -420.350334)
			(xy 293.915955 -420.411491) (xy 293.923754 -420.474093) (xy 293.924228 -420.505636) (xy 293.923867 -420.532374)
			(xy 293.918244 -420.585554) (xy 293.907063 -420.637848) (xy 293.899082 -420.66337) (xy 293.89451 -420.677594)
			(xy 293.901622 -420.705788) (xy 293.990268 -420.789354) (xy 294.01897 -420.794942) (xy 294.03294 -420.789354)
			(xy 294.062691 -420.77817) (xy 294.124277 -420.762455) (xy 294.187342 -420.754537) (xy 294.219122 -420.754048)
			(xy 294.251872 -420.75454) (xy 294.316829 -420.762969) (xy 294.380164 -420.77967) (xy 294.440831 -420.804368)
			(xy 294.497822 -420.836653) (xy 294.550195 -420.875991) (xy 294.597082 -420.921729) (xy 294.637705 -420.973111)
			(xy 294.654986 -421.000936) (xy 294.662606 -421.013128) (xy 294.687498 -421.026336) (xy 294.80637 -421.018716)
			(xy 294.829484 -421.00246) (xy 294.835326 -420.989252) (xy 294.84685 -420.96417) (xy 294.876088 -420.917353)
			(xy 294.91177 -420.87524) (xy 294.953151 -420.838712) (xy 294.999366 -420.808531) (xy 295.04945 -420.785329)
			(xy 295.102355 -420.76959) (xy 295.156977 -420.761643) (xy 295.184576 -420.76116) (xy 295.21082 -420.761574)
			(xy 295.262812 -420.768759) (xy 295.313327 -420.78301) (xy 295.361409 -420.804057) (xy 295.406148 -420.831502)
			(xy 295.446699 -420.864827) (xy 295.482293 -420.9034) (xy 295.512258 -420.946493) (xy 295.536027 -420.993289)
			(xy 295.545002 -421.017954) (xy 295.549574 -421.030908) (xy 295.570656 -421.048942) (xy 295.685464 -421.069008)
			(xy 295.711118 -421.059356) (xy 295.720008 -421.048688) (xy 295.740753 -421.023936) (xy 295.787479 -420.979355)
			(xy 295.839476 -420.94105) (xy 295.895905 -420.90964) (xy 295.955859 -420.885629) (xy 296.01837 -420.869405)
			(xy 296.082433 -420.861229) (xy 296.114724 -420.860728) (xy 296.146686 -420.861159) (xy 296.210107 -420.869174)
			(xy 296.272022 -420.885074) (xy 296.331457 -420.908608) (xy 296.387474 -420.939406) (xy 296.439189 -420.976982)
			(xy 296.485787 -421.020742) (xy 296.526533 -421.069998) (xy 296.560785 -421.123972) (xy 296.588002 -421.181813)
			(xy 296.607755 -421.242609) (xy 296.619733 -421.305401) (xy 296.623747 -421.3692) (xy 296.619733 -421.432999)
			(xy 296.607755 -421.495791) (xy 296.588002 -421.556587) (xy 296.560785 -421.614428) (xy 296.526533 -421.668402)
			(xy 296.485787 -421.717658) (xy 296.439189 -421.761418) (xy 296.387474 -421.798994) (xy 296.331457 -421.829792)
			(xy 296.272022 -421.853326) (xy 296.210107 -421.869226) (xy 296.146686 -421.877241) (xy 296.114724 -421.877744)
			(xy 296.083133 -421.877219) (xy 296.02044 -421.869372) (xy 295.959203 -421.853819) (xy 295.900363 -421.830801)
			(xy 295.844827 -421.800673) (xy 295.793451 -421.763897) (xy 295.747025 -421.721041) (xy 295.706265 -421.672765)
			(xy 295.671799 -421.619811) (xy 295.644158 -421.562997) (xy 295.623766 -421.503196) (xy 295.616884 -421.47236)
			(xy 295.61409 -421.458644) (xy 295.595548 -421.438324) (xy 295.484296 -421.403526) (xy 295.457372 -421.409622)
			(xy 295.447212 -421.419274) (xy 295.425831 -421.438856) (xy 295.378245 -421.471975) (xy 295.326192 -421.497506)
			(xy 295.270873 -421.51486) (xy 295.213564 -421.523637) (xy 295.184576 -421.524176) (xy 295.15563 -421.523645)
			(xy 295.098404 -421.514888) (xy 295.043155 -421.497594) (xy 294.991149 -421.472159) (xy 294.943579 -421.439166)
			(xy 294.901533 -421.39937) (xy 294.883332 -421.376856) (xy 294.874442 -421.365426) (xy 294.848026 -421.355266)
			(xy 294.730932 -421.37711) (xy 294.710104 -421.395906) (xy 294.705786 -421.409622) (xy 294.695953 -421.440588)
			(xy 294.669394 -421.499885) (xy 294.635497 -421.555315) (xy 294.594815 -421.605975) (xy 294.548011 -421.65104)
			(xy 294.495847 -421.689776) (xy 294.439174 -421.721551) (xy 294.378915 -421.745847) (xy 294.316052 -421.762269)
			(xy 294.251608 -421.770548) (xy 294.219122 -421.771064) (xy 294.188389 -421.770642) (xy 294.12737 -421.763235)
			(xy 294.067689 -421.748526) (xy 294.010216 -421.72673) (xy 293.95579 -421.698166) (xy 293.905205 -421.663248)
			(xy 293.859197 -421.622488) (xy 293.818438 -421.576478) (xy 293.783523 -421.525891) (xy 293.75496 -421.471463)
			(xy 293.733167 -421.41399) (xy 293.718461 -421.354308) (xy 293.711057 -421.293289) (xy 293.710614 -421.262556)
			(xy 293.710971 -421.235818) (xy 293.716596 -421.182638) (xy 293.727778 -421.130343) (xy 293.73576 -421.104822)
			(xy 293.740332 -421.090598) (xy 293.73322 -421.062404) (xy 293.644574 -420.978838) (xy 293.615872 -420.97325)
			(xy 293.601902 -420.978838) (xy 293.572147 -420.99001) (xy 293.510563 -421.005729) (xy 293.447499 -421.013652)
			(xy 293.41572 -421.014144) (xy 293.384177 -421.013653) (xy 293.321575 -421.005852) (xy 293.260419 -420.990368)
			(xy 293.201648 -420.967437) (xy 293.146165 -420.937413) (xy 293.094821 -420.900757) (xy 293.048406 -420.858031)
			(xy 293.007633 -420.809892) (xy 292.973127 -420.757079) (xy 292.945419 -420.700403) (xy 292.924935 -420.640735)
			(xy 292.911988 -420.578992) (xy 292.906778 -420.516122) (xy 291.719623 -420.516122) (xy 291.719762 -420.524432)
			(xy 291.719274 -420.555431) (xy 291.711728 -420.616969) (xy 291.696753 -420.677131) (xy 291.67457 -420.735025)
			(xy 291.64551 -420.789791) (xy 291.610004 -420.840615) (xy 291.568579 -420.886743) (xy 291.545518 -420.907464)
			(xy 291.53866 -420.91356) (xy 291.530024 -420.929562) (xy 291.518086 -421.013382) (xy 291.521896 -421.030908)
			(xy 291.526722 -421.038782) (xy 291.54092 -421.061871) (xy 291.563326 -421.111226) (xy 291.578519 -421.163256)
			(xy 291.586191 -421.216913) (xy 291.586666 -421.244014) (xy 291.58618 -421.271265) (xy 291.578424 -421.325213)
			(xy 291.563069 -421.377508) (xy 291.540427 -421.427085) (xy 291.510961 -421.472935) (xy 291.47527 -421.514126)
			(xy 291.434079 -421.549817) (xy 291.388229 -421.579283) (xy 291.338652 -421.601925) (xy 291.286357 -421.61728)
			(xy 291.232409 -421.625036) (xy 291.177907 -421.625036) (xy 291.123959 -421.61728) (xy 291.071664 -421.601925)
			(xy 291.022087 -421.579283) (xy 290.976237 -421.549817) (xy 290.935046 -421.514126) (xy 290.899355 -421.472935)
			(xy 290.869889 -421.427085) (xy 290.847247 -421.377508) (xy 290.831892 -421.325213) (xy 290.824136 -421.271265)
			(xy 290.82365 -421.244014) (xy 290.824142 -421.216112) (xy 290.832292 -421.160906) (xy 290.848404 -421.107478)
			(xy 290.872135 -421.056971) (xy 290.88715 -421.033448) (xy 290.89223 -421.025574) (xy 290.896294 -421.008048)
			(xy 290.885626 -420.923974) (xy 290.877244 -420.907972) (xy 290.870386 -420.901876) (xy 290.848169 -420.881142)
			(xy 290.80825 -420.835322) (xy 290.774076 -420.785071) (xy 290.746132 -420.731107) (xy 290.724817 -420.674198)
			(xy 290.710435 -420.615154) (xy 290.70319 -420.554817) (xy 290.702746 -420.524432) (xy 290.703301 -420.489476)
			(xy 290.712871 -420.420222) (xy 290.731835 -420.352931) (xy 290.759836 -420.288871) (xy 290.796345 -420.22925)
			(xy 290.818062 -420.201852) (xy 290.823318 -420.194843) (xy 290.829172 -420.178348) (xy 290.829492 -420.169594)
			(xy 290.829492 -420.01567) (xy 290.829143 -420.006922) (xy 290.823296 -419.990431) (xy 290.818062 -419.983412)
			(xy 290.796349 -419.956013) (xy 290.759853 -419.896387) (xy 290.73186 -419.832326) (xy 290.7129 -419.765037)
			(xy 290.703327 -419.695787) (xy 290.702746 -419.660832) (xy 290.703326 -419.626471) (xy 290.712571 -419.558375)
			(xy 290.730897 -419.492143) (xy 290.75797 -419.428979) (xy 290.793298 -419.370034) (xy 290.836239 -419.316381)
			(xy 290.860734 -419.292278) (xy 290.867408 -419.285397) (xy 290.875498 -419.268032) (xy 290.876482 -419.258496)
			(xy 290.87826 -419.227508) (xy 290.878413 -419.218147) (xy 290.87282 -419.200298) (xy 290.867338 -419.19271)
			(xy 290.854249 -419.176023) (xy 290.831466 -419.14025) (xy 290.821872 -419.121336) (xy 290.81603 -419.109652)
			(xy 290.794948 -419.094666) (xy 290.683696 -419.082474) (xy 290.65982 -419.092126) (xy 290.651438 -419.10254)
			(xy 290.633188 -419.124308) (xy 290.591399 -419.162781) (xy 290.544368 -419.194633) (xy 290.493135 -419.219162)
			(xy 290.438832 -419.235825) (xy 290.382659 -419.244254) (xy 290.354258 -419.24478) (xy 290.327016 -419.244362)
			(xy 290.273087 -419.236606) (xy 290.220809 -419.221257) (xy 290.171247 -419.198627) (xy 290.125408 -419.169177)
			(xy 290.084224 -419.133506) (xy 290.048533 -419.09234) (xy 290.019061 -419.046515) (xy 289.996408 -418.996963)
			(xy 289.981034 -418.944693) (xy 289.973251 -418.890768) (xy 289.97275 -418.863526) (xy 289.97275 -418.852858)
			(xy 289.964622 -418.834062) (xy 289.89528 -418.768784) (xy 289.875976 -418.761672) (xy 289.865308 -418.762434)
			(xy 289.835336 -418.763196) (xy 289.799848 -418.76262) (xy 289.729562 -418.752741) (xy 289.661336 -418.733172)
			(xy 289.596501 -418.704292) (xy 289.566096 -418.68598) (xy 289.55619 -418.679884) (xy 289.53333 -418.677344)
			(xy 289.436302 -418.711634) (xy 289.420046 -418.72789) (xy 289.416236 -418.739066) (xy 289.405481 -418.768663)
			(xy 289.377729 -418.82519) (xy 289.343207 -418.877857) (xy 289.302445 -418.925856) (xy 289.256066 -418.968454)
			(xy 289.204781 -419.004996) (xy 289.149375 -419.034925) (xy 289.090697 -419.05778) (xy 289.029645 -419.073213)
			(xy 288.967154 -419.080987) (xy 288.935668 -419.081458) (xy 288.903711 -419.080854) (xy 288.840303 -419.07284)
			(xy 288.778398 -419.056942) (xy 288.718974 -419.033411) (xy 288.662968 -419.002619) (xy 288.611263 -418.965049)
			(xy 288.564673 -418.921296) (xy 288.523935 -418.872049) (xy 288.48969 -418.818085) (xy 288.462478 -418.760254)
			(xy 288.442728 -418.699468) (xy 288.430752 -418.636687) (xy 288.426739 -418.5729) (xy 287.448871 -418.5729)
			(xy 287.436291 -418.586458) (xy 287.39462 -418.619689) (xy 287.348462 -418.646338) (xy 287.298848 -418.66581)
			(xy 287.246886 -418.67767) (xy 287.193736 -418.681654) (xy 287.140586 -418.67767) (xy 287.088624 -418.66581)
			(xy 287.03901 -418.646338) (xy 286.992852 -418.619689) (xy 286.951181 -418.586458) (xy 286.914929 -418.547387)
			(xy 286.884905 -418.50335) (xy 286.861779 -418.455329) (xy 286.846069 -418.404399) (xy 286.838126 -418.351695)
			(xy 284.867145 -418.351695) (xy 284.862757 -418.365921) (xy 284.839631 -418.413942) (xy 284.809607 -418.457979)
			(xy 284.773355 -418.49705) (xy 284.731684 -418.530281) (xy 284.685526 -418.55693) (xy 284.635912 -418.576402)
			(xy 284.58395 -418.588262) (xy 284.5308 -418.592246) (xy 284.47765 -418.588262) (xy 284.425688 -418.576402)
			(xy 284.376074 -418.55693) (xy 284.329916 -418.530281) (xy 284.288245 -418.49705) (xy 284.251993 -418.457979)
			(xy 284.221969 -418.413942) (xy 284.198843 -418.365921) (xy 284.183133 -418.314991) (xy 284.17519 -418.262287)
			(xy 277.609983 -418.262287) (xy 277.601694 -418.32232) (xy 277.582737 -418.389611) (xy 277.554742 -418.453671)
			(xy 277.518238 -418.513294) (xy 277.496524 -418.540692) (xy 277.491224 -418.547689) (xy 277.485252 -418.564182)
			(xy 277.48484 -418.57295) (xy 277.48484 -418.726874) (xy 277.485225 -418.735649) (xy 277.491195 -418.752151)
			(xy 277.496524 -418.759132) (xy 277.518255 -418.786517) (xy 277.554749 -418.846147) (xy 277.582738 -418.910211)
			(xy 277.601694 -418.977503) (xy 277.611262 -419.046756) (xy 277.61184 -419.081712) (xy 277.611379 -419.114031)
			(xy 277.603186 -419.178148) (xy 277.586933 -419.240709) (xy 277.562883 -419.300707) (xy 277.531422 -419.357172)
			(xy 277.49306 -419.409195) (xy 277.448414 -419.455937) (xy 277.423626 -419.476682) (xy 277.415498 -419.483286)
			(xy 277.405846 -419.501066) (xy 277.397464 -419.594538) (xy 277.400739 -419.604909) (xy 282.318454 -419.604909)
			(xy 282.318454 -419.540987) (xy 282.326465 -419.477569) (xy 282.342362 -419.415655) (xy 282.365894 -419.356222)
			(xy 282.396688 -419.300207) (xy 282.434261 -419.248492) (xy 282.478018 -419.201895) (xy 282.527271 -419.16115)
			(xy 282.581242 -419.126899) (xy 282.639081 -419.099682) (xy 282.699874 -419.079929) (xy 282.762664 -419.067951)
			(xy 282.82646 -419.063938) (xy 282.890256 -419.067951) (xy 282.953046 -419.079929) (xy 283.013839 -419.099682)
			(xy 283.071678 -419.126899) (xy 283.125649 -419.16115) (xy 283.174902 -419.201895) (xy 283.218659 -419.248492)
			(xy 283.256232 -419.300207) (xy 283.287026 -419.356222) (xy 283.310558 -419.415655) (xy 283.326455 -419.477569)
			(xy 283.334466 -419.540987) (xy 283.334968 -419.572948) (xy 283.334466 -419.604909) (xy 283.329522 -419.644047)
			(xy 284.27552 -419.644047) (xy 284.27552 -419.590749) (xy 284.283463 -419.538045) (xy 284.299173 -419.487115)
			(xy 284.322299 -419.439094) (xy 284.352323 -419.395057) (xy 284.388575 -419.355986) (xy 284.430246 -419.322755)
			(xy 284.476404 -419.296106) (xy 284.526018 -419.276634) (xy 284.57798 -419.264774) (xy 284.63113 -419.260791)
			(xy 284.68428 -419.264774) (xy 284.736242 -419.276634) (xy 284.785856 -419.296106) (xy 284.832014 -419.322755)
			(xy 284.873685 -419.355986) (xy 284.909937 -419.395057) (xy 284.939961 -419.439094) (xy 284.963087 -419.487115)
			(xy 284.978797 -419.538045) (xy 284.98674 -419.590749) (xy 284.987238 -419.617398) (xy 284.98674 -419.644047)
			(xy 284.980921 -419.682655) (xy 285.590224 -419.682655) (xy 285.590224 -419.629357) (xy 285.598167 -419.576653)
			(xy 285.613877 -419.525723) (xy 285.637003 -419.477702) (xy 285.667027 -419.433665) (xy 285.703279 -419.394594)
			(xy 285.74495 -419.361363) (xy 285.791108 -419.334714) (xy 285.840722 -419.315242) (xy 285.892684 -419.303382)
			(xy 285.945834 -419.299399) (xy 285.998984 -419.303382) (xy 286.050946 -419.315242) (xy 286.10056 -419.334714)
			(xy 286.146718 -419.361363) (xy 286.188389 -419.394594) (xy 286.224641 -419.433665) (xy 286.254665 -419.477702)
			(xy 286.277791 -419.525723) (xy 286.293501 -419.576653) (xy 286.301444 -419.629357) (xy 286.301942 -419.656006)
			(xy 286.301444 -419.682655) (xy 286.72662 -419.682655) (xy 286.72662 -419.629357) (xy 286.734563 -419.576653)
			(xy 286.750273 -419.525723) (xy 286.773399 -419.477702) (xy 286.803423 -419.433665) (xy 286.839675 -419.394594)
			(xy 286.881346 -419.361363) (xy 286.927504 -419.334714) (xy 286.977118 -419.315242) (xy 287.02908 -419.303382)
			(xy 287.08223 -419.299399) (xy 287.13538 -419.303382) (xy 287.187342 -419.315242) (xy 287.236956 -419.334714)
			(xy 287.283114 -419.361363) (xy 287.324785 -419.394594) (xy 287.361037 -419.433665) (xy 287.391061 -419.477702)
			(xy 287.414187 -419.525723) (xy 287.429897 -419.576653) (xy 287.43784 -419.629357) (xy 287.438338 -419.656006)
			(xy 287.43784 -419.682655) (xy 287.429897 -419.735359) (xy 287.414187 -419.786289) (xy 287.391061 -419.83431)
			(xy 287.361037 -419.878347) (xy 287.324785 -419.917418) (xy 287.283114 -419.950649) (xy 287.236956 -419.977298)
			(xy 287.187342 -419.99677) (xy 287.13538 -420.00863) (xy 287.08223 -420.012614) (xy 287.02908 -420.00863)
			(xy 286.977118 -419.99677) (xy 286.927504 -419.977298) (xy 286.881346 -419.950649) (xy 286.839675 -419.917418)
			(xy 286.803423 -419.878347) (xy 286.773399 -419.83431) (xy 286.750273 -419.786289) (xy 286.734563 -419.735359)
			(xy 286.72662 -419.682655) (xy 286.301444 -419.682655) (xy 286.293501 -419.735359) (xy 286.277791 -419.786289)
			(xy 286.254665 -419.83431) (xy 286.224641 -419.878347) (xy 286.188389 -419.917418) (xy 286.146718 -419.950649)
			(xy 286.10056 -419.977298) (xy 286.050946 -419.99677) (xy 285.998984 -420.00863) (xy 285.945834 -420.012614)
			(xy 285.892684 -420.00863) (xy 285.840722 -419.99677) (xy 285.791108 -419.977298) (xy 285.74495 -419.950649)
			(xy 285.703279 -419.917418) (xy 285.667027 -419.878347) (xy 285.637003 -419.83431) (xy 285.613877 -419.786289)
			(xy 285.598167 -419.735359) (xy 285.590224 -419.682655) (xy 284.980921 -419.682655) (xy 284.978797 -419.696751)
			(xy 284.963087 -419.747681) (xy 284.939961 -419.795702) (xy 284.909937 -419.839739) (xy 284.873685 -419.87881)
			(xy 284.832014 -419.912041) (xy 284.785856 -419.93869) (xy 284.736242 -419.958162) (xy 284.68428 -419.970022)
			(xy 284.63113 -419.974006) (xy 284.57798 -419.970022) (xy 284.526018 -419.958162) (xy 284.476404 -419.93869)
			(xy 284.430246 -419.912041) (xy 284.388575 -419.87881) (xy 284.352323 -419.839739) (xy 284.322299 -419.795702)
			(xy 284.299173 -419.747681) (xy 284.283463 -419.696751) (xy 284.27552 -419.644047) (xy 283.329522 -419.644047)
			(xy 283.326455 -419.668327) (xy 283.310558 -419.730241) (xy 283.287026 -419.789674) (xy 283.256232 -419.845689)
			(xy 283.218659 -419.897404) (xy 283.174902 -419.944001) (xy 283.125649 -419.984746) (xy 283.071678 -420.018997)
			(xy 283.013839 -420.046214) (xy 282.953046 -420.065967) (xy 282.890256 -420.077945) (xy 282.82646 -420.081959)
			(xy 282.762664 -420.077945) (xy 282.699874 -420.065967) (xy 282.639081 -420.046214) (xy 282.581242 -420.018997)
			(xy 282.527271 -419.984746) (xy 282.478018 -419.944001) (xy 282.434261 -419.897404) (xy 282.396688 -419.845689)
			(xy 282.365894 -419.789674) (xy 282.342362 -419.730241) (xy 282.326465 -419.668327) (xy 282.318454 -419.604909)
			(xy 277.400739 -419.604909) (xy 277.40356 -419.613842) (xy 277.410418 -419.621716) (xy 277.427649 -419.642546)
			(xy 277.456653 -419.688164) (xy 277.478928 -419.73742) (xy 277.494027 -419.789326) (xy 277.501647 -419.842845)
			(xy 277.502112 -419.869874) (xy 277.501626 -419.897125) (xy 277.49387 -419.951073) (xy 277.478515 -420.003368)
			(xy 277.455873 -420.052945) (xy 277.426407 -420.098795) (xy 277.390716 -420.139986) (xy 277.349525 -420.175677)
			(xy 277.303675 -420.205143) (xy 277.254098 -420.227785) (xy 277.201803 -420.24314) (xy 277.147855 -420.250896)
			(xy 277.093353 -420.250896) (xy 277.039405 -420.24314) (xy 276.98711 -420.227785) (xy 276.937533 -420.205143)
			(xy 276.891683 -420.175677) (xy 276.850492 -420.139986) (xy 276.814801 -420.098795) (xy 276.785335 -420.052945)
			(xy 276.762693 -420.003368) (xy 276.747338 -419.951073) (xy 276.739582 -419.897125) (xy 276.739096 -419.869874)
			(xy 276.739489 -419.844522) (xy 276.746168 -419.794261) (xy 276.759458 -419.74533) (xy 276.779124 -419.698596)
			(xy 276.804817 -419.654885) (xy 276.820122 -419.63467) (xy 276.826726 -419.626288) (xy 276.83206 -419.606984)
			(xy 276.81936 -419.51402) (xy 276.8092 -419.496748) (xy 276.800818 -419.490398) (xy 276.773871 -419.469784)
			(xy 276.725181 -419.422536) (xy 276.68321 -419.36923) (xy 276.648704 -419.310814) (xy 276.622276 -419.248327)
			(xy 276.604396 -419.18288) (xy 276.595381 -419.115635) (xy 276.594824 -419.081712) (xy 276.595407 -419.046757)
			(xy 276.604968 -418.977503) (xy 276.623924 -418.910212) (xy 276.651919 -418.846152) (xy 276.688425 -418.78653)
			(xy 276.71014 -418.759132) (xy 276.715427 -418.752126) (xy 276.721407 -418.73564) (xy 276.721824 -418.726874)
			(xy 276.721824 -418.57295) (xy 276.721435 -418.564176) (xy 276.715468 -418.547673) (xy 276.71014 -418.540692)
			(xy 276.688429 -418.513291) (xy 276.65193 -418.453666) (xy 276.623936 -418.389607) (xy 276.604975 -418.322318)
			(xy 276.595404 -418.253067) (xy 276.594824 -418.218112) (xy 276.595315 -418.186829) (xy 276.602994 -418.124736)
			(xy 276.618236 -418.064055) (xy 276.640811 -418.005704) (xy 276.670378 -417.950565) (xy 276.688042 -417.924742)
			(xy 276.69363 -417.916614) (xy 276.698202 -417.89731) (xy 276.684232 -417.807902) (xy 276.674072 -417.791138)
			(xy 276.666198 -417.785042) (xy 276.643129 -417.766858) (xy 276.602259 -417.724671) (xy 276.568339 -417.676719)
			(xy 276.542169 -417.624134) (xy 276.524369 -417.56816) (xy 276.515358 -417.510118) (xy 276.514814 -417.48075)
			(xy 276.132544 -417.48075) (xy 276.132544 -421.3776) (xy 284.122086 -421.3776) (xy 284.126101 -421.313801)
			(xy 284.138079 -421.251009) (xy 284.157834 -421.190213) (xy 284.185053 -421.132372) (xy 284.219306 -421.0784)
			(xy 284.260055 -421.029146) (xy 284.306656 -420.985388) (xy 284.358373 -420.947815) (xy 284.414392 -420.917022)
			(xy 284.473829 -420.893492) (xy 284.535746 -420.877598) (xy 284.599168 -420.869589) (xy 284.63113 -420.86911)
			(xy 284.664273 -420.869633) (xy 284.729997 -420.878254) (xy 284.794043 -420.895345) (xy 284.855324 -420.920616)
			(xy 284.912799 -420.953639) (xy 284.965494 -420.993853) (xy 285.012515 -421.040576) (xy 285.033212 -421.066468)
			(xy 285.040812 -421.075282) (xy 285.061719 -421.085459) (xy 285.073344 -421.086026) (xy 285.153862 -421.086026)
			(xy 285.165501 -421.085534) (xy 285.186411 -421.075315) (xy 285.193994 -421.066468) (xy 285.214698 -421.040582)
			(xy 285.261718 -420.993861) (xy 285.314412 -420.953648) (xy 285.371887 -420.920626) (xy 285.433166 -420.895356)
			(xy 285.497211 -420.878266) (xy 285.562933 -420.869647) (xy 285.596076 -420.86911) (xy 285.626808 -420.86956)
			(xy 285.687825 -420.876966) (xy 285.747504 -420.891674) (xy 285.804975 -420.913468) (xy 285.8594 -420.942031)
			(xy 285.909985 -420.976946) (xy 285.955992 -421.017704) (xy 285.996751 -421.063711) (xy 286.031666 -421.114295)
			(xy 286.06023 -421.16872) (xy 286.082024 -421.22619) (xy 286.096732 -421.285869) (xy 286.104139 -421.346886)
			(xy 286.104584 -421.377618) (xy 286.104096 -421.409339) (xy 286.104066 -421.409579) (xy 287.123118 -421.409579)
			(xy 287.123118 -421.345657) (xy 287.131129 -421.282239) (xy 287.147026 -421.220325) (xy 287.170558 -421.160892)
			(xy 287.201352 -421.104877) (xy 287.238925 -421.053162) (xy 287.282682 -421.006565) (xy 287.331935 -420.96582)
			(xy 287.385906 -420.931569) (xy 287.443745 -420.904352) (xy 287.504538 -420.884599) (xy 287.567328 -420.872621)
			(xy 287.631124 -420.868608) (xy 287.69492 -420.872621) (xy 287.75771 -420.884599) (xy 287.818503 -420.904352)
			(xy 287.876342 -420.931569) (xy 287.930313 -420.96582) (xy 287.979566 -421.006565) (xy 288.023323 -421.053162)
			(xy 288.060896 -421.104877) (xy 288.09169 -421.160892) (xy 288.115222 -421.220325) (xy 288.131119 -421.282239)
			(xy 288.13913 -421.345657) (xy 288.139632 -421.377618) (xy 288.13913 -421.409579) (xy 288.131119 -421.472997)
			(xy 288.115222 -421.534911) (xy 288.09169 -421.594344) (xy 288.060896 -421.650359) (xy 288.023323 -421.702074)
			(xy 287.979566 -421.748671) (xy 287.930313 -421.789416) (xy 287.876342 -421.823667) (xy 287.818503 -421.850884)
			(xy 287.75771 -421.870637) (xy 287.69492 -421.882615) (xy 287.631124 -421.886629) (xy 287.567328 -421.882615)
			(xy 287.504538 -421.870637) (xy 287.443745 -421.850884) (xy 287.385906 -421.823667) (xy 287.331935 -421.789416)
			(xy 287.282682 -421.748671) (xy 287.238925 -421.702074) (xy 287.201352 -421.650359) (xy 287.170558 -421.594344)
			(xy 287.147026 -421.534911) (xy 287.131129 -421.472997) (xy 287.123118 -421.409579) (xy 286.104066 -421.409579)
			(xy 286.096199 -421.472288) (xy 286.080529 -421.533764) (xy 286.057329 -421.592812) (xy 286.026962 -421.648514)
			(xy 286.008826 -421.674544) (xy 286.00146 -421.684958) (xy 285.998158 -421.70985) (xy 286.036512 -421.812974)
			(xy 286.055308 -421.829484) (xy 286.067754 -421.832532) (xy 286.095594 -421.839604) (xy 286.149589 -421.859204)
			(xy 286.20103 -421.884766) (xy 286.249261 -421.915966) (xy 286.271716 -421.933878) (xy 286.278705 -421.939164)
			(xy 286.295216 -421.944999) (xy 286.303974 -421.945308) (xy 286.457898 -421.945308) (xy 286.466644 -421.944941)
			(xy 286.483136 -421.939106) (xy 286.490156 -421.933878) (xy 286.517568 -421.912182) (xy 286.577191 -421.875682)
			(xy 286.641248 -421.847687) (xy 286.708534 -421.828722) (xy 286.777782 -421.819145) (xy 286.812736 -421.818562)
			(xy 286.843467 -421.819022) (xy 286.904479 -421.826434) (xy 286.964154 -421.841145) (xy 287.02162 -421.862942)
			(xy 287.076041 -421.891506) (xy 287.126622 -421.926422) (xy 287.172626 -421.967178) (xy 287.213382 -422.013183)
			(xy 287.248297 -422.063764) (xy 287.27686 -422.118185) (xy 287.298656 -422.175652) (xy 287.313367 -422.235327)
			(xy 287.320779 -422.296339) (xy 287.321244 -422.32707) (xy 287.320699 -422.359021) (xy 287.312685 -422.422419)
			(xy 287.296792 -422.484314) (xy 287.273271 -422.54373) (xy 287.259729 -422.56837) (xy 292.02507 -422.56837)
			(xy 292.025572 -422.536409) (xy 292.033583 -422.472991) (xy 292.04948 -422.411077) (xy 292.073012 -422.351644)
			(xy 292.103806 -422.295629) (xy 292.141379 -422.243914) (xy 292.185136 -422.197317) (xy 292.234389 -422.156572)
			(xy 292.28836 -422.122321) (xy 292.346199 -422.095104) (xy 292.406992 -422.075351) (xy 292.469782 -422.063373)
			(xy 292.533578 -422.05936) (xy 292.597374 -422.063373) (xy 292.660164 -422.075351) (xy 292.69288 -422.085981)
			(xy 301.83175 -422.085981) (xy 301.83175 -422.022059) (xy 301.839761 -421.958641) (xy 301.855658 -421.896727)
			(xy 301.87919 -421.837294) (xy 301.909984 -421.781279) (xy 301.947557 -421.729564) (xy 301.991314 -421.682967)
			(xy 302.040567 -421.642222) (xy 302.094538 -421.607971) (xy 302.152377 -421.580754) (xy 302.21317 -421.561001)
			(xy 302.27596 -421.549023) (xy 302.339756 -421.54501) (xy 302.403552 -421.549023) (xy 302.466342 -421.561001)
			(xy 302.527135 -421.580754) (xy 302.584974 -421.607971) (xy 302.638945 -421.642222) (xy 302.688198 -421.682967)
			(xy 302.731955 -421.729564) (xy 302.769528 -421.781279) (xy 302.800322 -421.837294) (xy 302.823854 -421.896727)
			(xy 302.839751 -421.958641) (xy 302.847762 -422.022059) (xy 302.848264 -422.05402) (xy 302.847762 -422.085981)
			(xy 302.839751 -422.149399) (xy 302.823854 -422.211313) (xy 302.800322 -422.270746) (xy 302.769528 -422.326761)
			(xy 302.731955 -422.378476) (xy 302.688198 -422.425073) (xy 302.638945 -422.465818) (xy 302.584974 -422.500069)
			(xy 302.527135 -422.527286) (xy 302.466342 -422.547039) (xy 302.403552 -422.559017) (xy 302.339756 -422.563031)
			(xy 302.27596 -422.559017) (xy 302.21317 -422.547039) (xy 302.152377 -422.527286) (xy 302.094538 -422.500069)
			(xy 302.040567 -422.465818) (xy 301.991314 -422.425073) (xy 301.947557 -422.378476) (xy 301.909984 -422.326761)
			(xy 301.87919 -422.270746) (xy 301.855658 -422.211313) (xy 301.839761 -422.149399) (xy 301.83175 -422.085981)
			(xy 292.69288 -422.085981) (xy 292.720957 -422.095104) (xy 292.778796 -422.122321) (xy 292.832767 -422.156572)
			(xy 292.88202 -422.197317) (xy 292.925777 -422.243914) (xy 292.96335 -422.295629) (xy 292.994144 -422.351644)
			(xy 293.017676 -422.411077) (xy 293.033573 -422.472991) (xy 293.041584 -422.536409) (xy 293.042086 -422.56837)
			(xy 293.041583 -422.600623) (xy 293.033438 -422.664611) (xy 293.017262 -422.727055) (xy 292.993316 -422.78695)
			(xy 292.961984 -422.843334) (xy 292.94328 -422.869614) (xy 292.938081 -422.877292) (xy 292.933139 -422.895151)
			(xy 292.933628 -422.904412) (xy 292.936422 -422.934892) (xy 292.937638 -422.944026) (xy 292.945721 -422.960568)
			(xy 292.95217 -422.96715) (xy 292.973545 -422.987763) (xy 293.011812 -423.033174) (xy 293.023197 -423.050419)
			(xy 294.052746 -423.050419) (xy 294.052746 -422.986497) (xy 294.060757 -422.923079) (xy 294.076654 -422.861165)
			(xy 294.100186 -422.801732) (xy 294.13098 -422.745717) (xy 294.168553 -422.694002) (xy 294.21231 -422.647405)
			(xy 294.261563 -422.60666) (xy 294.315534 -422.572409) (xy 294.373373 -422.545192) (xy 294.434166 -422.525439)
			(xy 294.496956 -422.513461) (xy 294.560752 -422.509448) (xy 294.624548 -422.513461) (xy 294.687338 -422.525439)
			(xy 294.748131 -422.545192) (xy 294.80597 -422.572409) (xy 294.859941 -422.60666) (xy 294.909194 -422.647405)
			(xy 294.952951 -422.694002) (xy 294.990524 -422.745717) (xy 295.021318 -422.801732) (xy 295.04485 -422.861165)
			(xy 295.060747 -422.923079) (xy 295.068758 -422.986497) (xy 295.06926 -423.018458) (xy 295.068758 -423.050419)
			(xy 295.060747 -423.113837) (xy 295.04485 -423.175751) (xy 295.021318 -423.235184) (xy 295.004062 -423.266573)
			(xy 296.442886 -423.266573) (xy 296.442886 -423.202651) (xy 296.450897 -423.139233) (xy 296.466794 -423.077319)
			(xy 296.490326 -423.017886) (xy 296.52112 -422.961871) (xy 296.558693 -422.910156) (xy 296.60245 -422.863559)
			(xy 296.651703 -422.822814) (xy 296.705674 -422.788563) (xy 296.763513 -422.761346) (xy 296.824306 -422.741593)
			(xy 296.887096 -422.729615) (xy 296.950892 -422.725602) (xy 297.014688 -422.729615) (xy 297.077478 -422.741593)
			(xy 297.138271 -422.761346) (xy 297.19611 -422.788563) (xy 297.250081 -422.822814) (xy 297.299334 -422.863559)
			(xy 297.343091 -422.910156) (xy 297.380664 -422.961871) (xy 297.411458 -423.017886) (xy 297.43499 -423.077319)
			(xy 297.450887 -423.139233) (xy 297.458898 -423.202651) (xy 297.4594 -423.234612) (xy 297.458898 -423.266573)
			(xy 297.45809 -423.272966) (xy 299.13148 -423.272966) (xy 299.135551 -423.217344) (xy 299.147677 -423.162907)
			(xy 299.1676 -423.110816) (xy 299.194896 -423.062181) (xy 299.228982 -423.018038) (xy 299.269131 -422.979329)
			(xy 299.314489 -422.946878) (xy 299.364089 -422.921377) (xy 299.416873 -422.90337) (xy 299.471716 -422.89324)
			(xy 299.52745 -422.891203) (xy 299.582887 -422.897303) (xy 299.636844 -422.911409) (xy 299.688173 -422.933221)
			(xy 299.735779 -422.962275) (xy 299.778647 -422.99795) (xy 299.815864 -423.039487) (xy 299.846637 -423.086)
			(xy 299.870309 -423.136497) (xy 299.886377 -423.189904) (xy 299.892882 -423.234104) (xy 302.615344 -423.234104)
			(xy 302.619415 -423.178482) (xy 302.631541 -423.124045) (xy 302.651464 -423.071954) (xy 302.67876 -423.023319)
			(xy 302.712846 -422.979176) (xy 302.752995 -422.940467) (xy 302.798353 -422.908016) (xy 302.847953 -422.882515)
			(xy 302.900737 -422.864508) (xy 302.95558 -422.854378) (xy 303.011314 -422.852341) (xy 303.066751 -422.858441)
			(xy 303.120708 -422.872547) (xy 303.172037 -422.894359) (xy 303.219643 -422.923413) (xy 303.262511 -422.959088)
			(xy 303.299728 -423.000625) (xy 303.330501 -423.047138) (xy 303.354173 -423.097635) (xy 303.370241 -423.151042)
			(xy 303.378361 -423.206218) (xy 303.37887 -423.234104) (xy 303.378361 -423.26199) (xy 303.370241 -423.317166)
			(xy 303.354173 -423.370573) (xy 303.330501 -423.42107) (xy 303.299728 -423.467583) (xy 303.262511 -423.50912)
			(xy 303.219643 -423.544795) (xy 303.172037 -423.573849) (xy 303.120708 -423.595661) (xy 303.066751 -423.609767)
			(xy 303.011314 -423.615867) (xy 302.95558 -423.61383) (xy 302.900737 -423.6037) (xy 302.847953 -423.585693)
			(xy 302.798353 -423.560192) (xy 302.752995 -423.527741) (xy 302.712846 -423.489032) (xy 302.67876 -423.444889)
			(xy 302.651464 -423.396254) (xy 302.631541 -423.344163) (xy 302.619415 -423.289726) (xy 302.615344 -423.234104)
			(xy 299.892882 -423.234104) (xy 299.894497 -423.24508) (xy 299.895006 -423.272966) (xy 299.894497 -423.300852)
			(xy 299.886377 -423.356028) (xy 299.870309 -423.409435) (xy 299.846637 -423.459932) (xy 299.815864 -423.506445)
			(xy 299.778647 -423.547982) (xy 299.735779 -423.583657) (xy 299.688173 -423.612711) (xy 299.636844 -423.634523)
			(xy 299.582887 -423.648629) (xy 299.52745 -423.654729) (xy 299.471716 -423.652692) (xy 299.416873 -423.642562)
			(xy 299.364089 -423.624555) (xy 299.314489 -423.599054) (xy 299.269131 -423.566603) (xy 299.228982 -423.527894)
			(xy 299.194896 -423.483751) (xy 299.1676 -423.435116) (xy 299.147677 -423.383025) (xy 299.135551 -423.328588)
			(xy 299.13148 -423.272966) (xy 297.45809 -423.272966) (xy 297.450887 -423.329991) (xy 297.43499 -423.391905)
			(xy 297.411458 -423.451338) (xy 297.380664 -423.507353) (xy 297.343091 -423.559068) (xy 297.299334 -423.605665)
			(xy 297.250081 -423.64641) (xy 297.19611 -423.680661) (xy 297.189686 -423.683684) (xy 298.183298 -423.683684)
			(xy 298.187369 -423.628062) (xy 298.199495 -423.573625) (xy 298.219418 -423.521534) (xy 298.246714 -423.472899)
			(xy 298.2808 -423.428756) (xy 298.320949 -423.390047) (xy 298.366307 -423.357596) (xy 298.415907 -423.332095)
			(xy 298.468691 -423.314088) (xy 298.523534 -423.303958) (xy 298.579268 -423.301921) (xy 298.634705 -423.308021)
			(xy 298.688662 -423.322127) (xy 298.739991 -423.343939) (xy 298.787597 -423.372993) (xy 298.830465 -423.408668)
			(xy 298.867682 -423.450205) (xy 298.898455 -423.496718) (xy 298.922127 -423.547215) (xy 298.938195 -423.600622)
			(xy 298.946315 -423.655798) (xy 298.946824 -423.683684) (xy 298.946315 -423.71157) (xy 298.938195 -423.766746)
			(xy 298.922127 -423.820153) (xy 298.898455 -423.87065) (xy 298.867682 -423.917163) (xy 298.830465 -423.9587)
			(xy 298.787597 -423.994375) (xy 298.739991 -424.023429) (xy 298.688662 -424.045241) (xy 298.634705 -424.059347)
			(xy 298.579268 -424.065447) (xy 298.523534 -424.06341) (xy 298.468691 -424.05328) (xy 298.415907 -424.035273)
			(xy 298.366307 -424.009772) (xy 298.320949 -423.977321) (xy 298.2808 -423.938612) (xy 298.246714 -423.894469)
			(xy 298.219418 -423.845834) (xy 298.199495 -423.793743) (xy 298.187369 -423.739306) (xy 298.183298 -423.683684)
			(xy 297.189686 -423.683684) (xy 297.138271 -423.707878) (xy 297.077478 -423.727631) (xy 297.014688 -423.739609)
			(xy 296.950892 -423.743623) (xy 296.887096 -423.739609) (xy 296.824306 -423.727631) (xy 296.763513 -423.707878)
			(xy 296.705674 -423.680661) (xy 296.651703 -423.64641) (xy 296.60245 -423.605665) (xy 296.558693 -423.559068)
			(xy 296.52112 -423.507353) (xy 296.490326 -423.451338) (xy 296.466794 -423.391905) (xy 296.450897 -423.329991)
			(xy 296.442886 -423.266573) (xy 295.004062 -423.266573) (xy 294.990524 -423.291199) (xy 294.952951 -423.342914)
			(xy 294.909194 -423.389511) (xy 294.859941 -423.430256) (xy 294.80597 -423.464507) (xy 294.748131 -423.491724)
			(xy 294.687338 -423.511477) (xy 294.624548 -423.523455) (xy 294.560752 -423.527469) (xy 294.496956 -423.523455)
			(xy 294.434166 -423.511477) (xy 294.373373 -423.491724) (xy 294.315534 -423.464507) (xy 294.261563 -423.430256)
			(xy 294.21231 -423.389511) (xy 294.168553 -423.342914) (xy 294.13098 -423.291199) (xy 294.100186 -423.235184)
			(xy 294.076654 -423.175751) (xy 294.060757 -423.113837) (xy 294.052746 -423.050419) (xy 293.023197 -423.050419)
			(xy 293.044531 -423.082732) (xy 293.071257 -423.135762) (xy 293.091627 -423.191544) (xy 293.105363 -423.249318)
			(xy 293.112278 -423.308298) (xy 293.112698 -423.33799) (xy 293.112245 -423.369865) (xy 293.104305 -423.433117)
			(xy 293.088511 -423.494878) (xy 293.06511 -423.554176) (xy 293.034472 -423.610079) (xy 293.016178 -423.636186)
			(xy 293.0112 -423.643612) (xy 293.006251 -423.660779) (xy 293.006526 -423.669714) (xy 293.008812 -423.699686)
			(xy 293.009773 -423.70855) (xy 293.017069 -423.724809) (xy 293.023036 -423.731436) (xy 293.04544 -423.755234)
			(xy 293.084598 -423.807566) (xy 293.116729 -423.864484) (xy 293.141303 -423.92505) (xy 293.157916 -423.988264)
			(xy 293.166293 -424.053086) (xy 293.1668 -424.085766) (xy 293.166333 -424.115864) (xy 293.159236 -424.175641)
			(xy 293.145124 -424.23416) (xy 293.124196 -424.290602) (xy 293.096745 -424.344175) (xy 293.063156 -424.394129)
			(xy 293.043864 -424.417236) (xy 293.038455 -424.424055) (xy 293.032234 -424.440299) (xy 293.031672 -424.448986)
			(xy 293.03091 -424.47845) (xy 293.031051 -424.487116) (xy 293.036364 -424.503601) (xy 293.041324 -424.510708)
			(xy 293.061001 -424.537412) (xy 293.094018 -424.594944) (xy 293.119277 -424.656279) (xy 293.136348 -424.720378)
			(xy 293.144942 -424.786151) (xy 293.145464 -424.819318) (xy 293.144962 -424.851279) (xy 293.136951 -424.914697)
			(xy 293.129941 -424.942) (xy 294.056054 -424.942) (xy 294.056526 -424.911455) (xy 294.063834 -424.850804)
			(xy 294.078358 -424.791465) (xy 294.099887 -424.734295) (xy 294.128113 -424.680116) (xy 294.162627 -424.62971)
			(xy 294.202932 -424.583803) (xy 294.248448 -424.543057) (xy 294.273224 -424.525186) (xy 294.282368 -424.518836)
			(xy 294.29329 -424.500294) (xy 294.304466 -424.402758) (xy 294.297862 -424.382184) (xy 294.290496 -424.374056)
			(xy 294.272149 -424.352935) (xy 294.24122 -424.306317) (xy 294.217434 -424.25568) (xy 294.201304 -424.20211)
			(xy 294.193174 -424.146759) (xy 294.192706 -424.118786) (xy 294.193192 -424.091535) (xy 294.200948 -424.037587)
			(xy 294.216303 -423.985292) (xy 294.238945 -423.935715) (xy 294.268411 -423.889865) (xy 294.304102 -423.848674)
			(xy 294.345293 -423.812983) (xy 294.391143 -423.783517) (xy 294.44072 -423.760875) (xy 294.493015 -423.74552)
			(xy 294.546963 -423.737764) (xy 294.601465 -423.737764) (xy 294.655413 -423.74552) (xy 294.707708 -423.760875)
			(xy 294.757285 -423.783517) (xy 294.803135 -423.812983) (xy 294.844326 -423.848674) (xy 294.880017 -423.889865)
			(xy 294.909483 -423.935715) (xy 294.932125 -423.985292) (xy 294.94748 -424.037587) (xy 294.955236 -424.091535)
			(xy 294.955722 -424.118786) (xy 294.9552 -424.147656) (xy 294.946521 -424.204739) (xy 294.929551 -424.2592)
			(xy 299.562837 -424.2592) (xy 299.566851 -424.195411) (xy 299.578827 -424.132628) (xy 299.598578 -424.071841)
			(xy 299.625791 -424.014008) (xy 299.660038 -423.960043) (xy 299.700779 -423.910795) (xy 299.747371 -423.867041)
			(xy 299.799079 -423.829472) (xy 299.855088 -423.79868) (xy 299.914514 -423.77515) (xy 299.976421 -423.759254)
			(xy 300.039832 -423.751242) (xy 300.07179 -423.75074) (xy 300.106744 -423.751341) (xy 300.175996 -423.7609)
			(xy 300.243287 -423.779853) (xy 300.307347 -423.807844) (xy 300.366971 -423.844344) (xy 300.39437 -423.866056)
			(xy 300.40152 -423.871454) (xy 300.418434 -423.877318) (xy 300.42739 -423.877486) (xy 300.457616 -423.876978)
			(xy 300.466608 -423.876468) (xy 300.48339 -423.869956) (xy 300.490382 -423.864278) (xy 300.513699 -423.844189)
			(xy 300.564316 -423.809171) (xy 300.618789 -423.78052) (xy 300.676323 -423.758655) (xy 300.736076 -423.743897)
			(xy 300.797174 -423.73646) (xy 300.827948 -423.736008) (xy 300.859908 -423.736481) (xy 300.923324 -423.744498)
			(xy 300.985234 -423.760399) (xy 301.044664 -423.783934) (xy 301.100676 -423.814731) (xy 301.152386 -423.852305)
			(xy 301.19898 -423.896064) (xy 301.239722 -423.945317) (xy 301.273971 -423.999288) (xy 301.301185 -424.057126)
			(xy 301.320936 -424.117918) (xy 301.332913 -424.180706) (xy 301.336927 -424.2445) (xy 301.332913 -424.308294)
			(xy 301.320936 -424.371082) (xy 301.301185 -424.431874) (xy 301.273971 -424.489712) (xy 301.239722 -424.543683)
			(xy 301.19898 -424.592936) (xy 301.152386 -424.636695) (xy 301.100676 -424.674269) (xy 301.044664 -424.705066)
			(xy 300.985234 -424.728601) (xy 300.923324 -424.744502) (xy 300.859908 -424.752519) (xy 300.827948 -424.753024)
			(xy 300.792992 -424.752467) (xy 300.723738 -424.742898) (xy 300.656447 -424.723935) (xy 300.592387 -424.695935)
			(xy 300.532766 -424.659425) (xy 300.505368 -424.637708) (xy 300.498239 -424.632279) (xy 300.481309 -424.626435)
			(xy 300.472348 -424.626278) (xy 300.442122 -424.626786) (xy 300.433133 -424.627322) (xy 300.416352 -424.633817)
			(xy 300.409356 -424.639486) (xy 300.386058 -424.659599) (xy 300.335438 -424.694615) (xy 300.280961 -424.723263)
			(xy 300.223423 -424.745124) (xy 300.163666 -424.759878) (xy 300.102565 -424.767308) (xy 300.07179 -424.767756)
			(xy 300.039832 -424.767158) (xy 299.976421 -424.759146) (xy 299.914514 -424.74325) (xy 299.855088 -424.71972)
			(xy 299.799079 -424.688928) (xy 299.747371 -424.651359) (xy 299.700779 -424.607605) (xy 299.660038 -424.558357)
			(xy 299.625791 -424.504392) (xy 299.598578 -424.446559) (xy 299.578827 -424.385772) (xy 299.566851 -424.322989)
			(xy 299.562837 -424.2592) (xy 294.929551 -424.2592) (xy 294.929344 -424.259865) (xy 294.90406 -424.311774)
			(xy 294.871247 -424.359284) (xy 294.851836 -424.38066) (xy 294.844216 -424.388534) (xy 294.837104 -424.409108)
			(xy 294.845994 -424.506644) (xy 294.856662 -424.525694) (xy 294.865552 -424.532044) (xy 294.892677 -424.552662)
			(xy 294.941712 -424.599968) (xy 294.983993 -424.653396) (xy 295.018763 -424.711991) (xy 295.045401 -424.774702)
			(xy 295.063429 -424.840408) (xy 295.072524 -424.907933) (xy 295.07307 -424.942) (xy 295.072568 -424.973961)
			(xy 295.064557 -425.037379) (xy 295.04866 -425.099293) (xy 295.025128 -425.158726) (xy 294.994334 -425.214741)
			(xy 294.956761 -425.266456) (xy 294.913004 -425.313053) (xy 294.863751 -425.353798) (xy 294.80978 -425.388049)
			(xy 294.751941 -425.415266) (xy 294.691148 -425.435019) (xy 294.628358 -425.446997) (xy 294.564562 -425.451011)
			(xy 294.500766 -425.446997) (xy 294.437976 -425.435019) (xy 294.377183 -425.415266) (xy 294.319344 -425.388049)
			(xy 294.265373 -425.353798) (xy 294.21612 -425.313053) (xy 294.172363 -425.266456) (xy 294.13479 -425.214741)
			(xy 294.103996 -425.158726) (xy 294.080464 -425.099293) (xy 294.064567 -425.037379) (xy 294.056556 -424.973961)
			(xy 294.056054 -424.942) (xy 293.129941 -424.942) (xy 293.121054 -424.976611) (xy 293.097522 -425.036044)
			(xy 293.066728 -425.092059) (xy 293.029155 -425.143774) (xy 292.985398 -425.190371) (xy 292.936145 -425.231116)
			(xy 292.882174 -425.265367) (xy 292.824335 -425.292584) (xy 292.763542 -425.312337) (xy 292.700752 -425.324315)
			(xy 292.636956 -425.328329) (xy 292.57316 -425.324315) (xy 292.51037 -425.312337) (xy 292.449577 -425.292584)
			(xy 292.391738 -425.265367) (xy 292.337767 -425.231116) (xy 292.288514 -425.190371) (xy 292.244757 -425.143774)
			(xy 292.207184 -425.092059) (xy 292.17639 -425.036044) (xy 292.152858 -424.976611) (xy 292.136961 -424.914697)
			(xy 292.12895 -424.851279) (xy 292.128448 -424.819318) (xy 292.128918 -424.78922) (xy 292.136017 -424.729444)
			(xy 292.150129 -424.670925) (xy 292.171056 -424.614484) (xy 292.198506 -424.56091) (xy 292.232094 -424.510956)
			(xy 292.251384 -424.487848) (xy 292.256753 -424.481001) (xy 292.263 -424.464778) (xy 292.263576 -424.456098)
			(xy 292.264338 -424.426634) (xy 292.264214 -424.417967) (xy 292.258891 -424.401481) (xy 292.253924 -424.394376)
			(xy 292.234232 -424.367682) (xy 292.201219 -424.310147) (xy 292.175964 -424.248809) (xy 292.158896 -424.184708)
			(xy 292.150304 -424.118933) (xy 292.149784 -424.085766) (xy 292.150269 -424.053892) (xy 292.158202 -423.990642)
			(xy 292.17399 -423.928881) (xy 292.197383 -423.869582) (xy 292.228014 -423.813678) (xy 292.246304 -423.78757)
			(xy 292.251299 -423.780154) (xy 292.256238 -423.762979) (xy 292.255956 -423.754042) (xy 292.25367 -423.72407)
			(xy 292.252688 -423.715209) (xy 292.245407 -423.698949) (xy 292.239446 -423.69232) (xy 292.217035 -423.668528)
			(xy 292.177875 -423.616196) (xy 292.145744 -423.559277) (xy 292.12117 -423.49871) (xy 292.10456 -423.435494)
			(xy 292.096186 -423.370671) (xy 292.095682 -423.33799) (xy 292.096169 -423.305737) (xy 292.104319 -423.241748)
			(xy 292.120498 -423.179304) (xy 292.144448 -423.119409) (xy 292.175783 -423.063025) (xy 292.194488 -423.036746)
			(xy 292.199657 -423.029049) (xy 292.204618 -423.011206) (xy 292.20414 -423.001948) (xy 292.201346 -422.971468)
			(xy 292.20011 -422.962338) (xy 292.192043 -422.945793) (xy 292.185598 -422.93921) (xy 292.164246 -422.918574)
			(xy 292.125979 -422.873167) (xy 292.093258 -422.823613) (xy 292.066529 -422.770586) (xy 292.046156 -422.714809)
			(xy 292.032415 -422.657038) (xy 292.025493 -422.598061) (xy 292.02507 -422.56837) (xy 287.259729 -422.56837)
			(xy 287.242492 -422.599732) (xy 287.20494 -422.651436) (xy 287.161206 -422.69803) (xy 287.111981 -422.738777)
			(xy 287.085278 -422.75633) (xy 287.075118 -422.762934) (xy 287.062672 -422.783508) (xy 287.055052 -422.888918)
			(xy 287.064196 -422.91127) (xy 287.07334 -422.919144) (xy 287.093771 -422.937331) (xy 287.129702 -422.978573)
			(xy 287.159373 -423.024524) (xy 287.182176 -423.074243) (xy 287.197643 -423.126709) (xy 287.205457 -423.180847)
			(xy 287.205928 -423.208196) (xy 287.205442 -423.235447) (xy 287.197686 -423.289395) (xy 287.182331 -423.34169)
			(xy 287.159689 -423.391267) (xy 287.130223 -423.437117) (xy 287.094532 -423.478308) (xy 287.053341 -423.513999)
			(xy 287.007491 -423.543465) (xy 286.957914 -423.566107) (xy 286.905619 -423.581462) (xy 286.851671 -423.589218)
			(xy 286.797169 -423.589218) (xy 286.743221 -423.581462) (xy 286.690926 -423.566107) (xy 286.641349 -423.543465)
			(xy 286.595499 -423.513999) (xy 286.554308 -423.478308) (xy 286.518617 -423.437117) (xy 286.489151 -423.391267)
			(xy 286.466509 -423.34169) (xy 286.451154 -423.289395) (xy 286.443398 -423.235447) (xy 286.442912 -423.208196)
			(xy 286.443366 -423.181688) (xy 286.450714 -423.129183) (xy 286.465253 -423.078199) (xy 286.486706 -423.029716)
			(xy 286.514658 -422.984667) (xy 286.548572 -422.943917) (xy 286.56788 -422.925748) (xy 286.57677 -422.91762)
			(xy 286.585406 -422.895268) (xy 286.574992 -422.789858) (xy 286.562038 -422.769792) (xy 286.551624 -422.763442)
			(xy 286.53557 -422.75366) (xy 286.504805 -422.732045) (xy 286.490156 -422.720262) (xy 286.483144 -422.715011)
			(xy 286.466651 -422.709154) (xy 286.457898 -422.708832) (xy 286.303974 -422.708832) (xy 286.295225 -422.709178)
			(xy 286.278734 -422.715026) (xy 286.271716 -422.720262) (xy 286.260052 -422.729709) (xy 286.235779 -422.747374)
			(xy 286.223202 -422.755568) (xy 286.213296 -422.761664) (xy 286.201358 -422.781222) (xy 286.190182 -422.883076)
			(xy 286.197802 -422.904666) (xy 286.20593 -422.912794) (xy 286.226652 -422.934415) (xy 286.261827 -422.982878)
			(xy 286.288995 -423.036244) (xy 286.307487 -423.0932) (xy 286.316849 -423.152347) (xy 286.317436 -423.182288)
			(xy 286.31695 -423.209539) (xy 286.309194 -423.263487) (xy 286.293839 -423.315782) (xy 286.271197 -423.365359)
			(xy 286.241731 -423.411209) (xy 286.20604 -423.4524) (xy 286.164849 -423.488091) (xy 286.118999 -423.517557)
			(xy 286.069422 -423.540199) (xy 286.017127 -423.555554) (xy 285.963179 -423.56331) (xy 285.908677 -423.56331)
			(xy 285.854729 -423.555554) (xy 285.802434 -423.540199) (xy 285.752857 -423.517557) (xy 285.707007 -423.488091)
			(xy 285.665816 -423.4524) (xy 285.630125 -423.411209) (xy 285.600659 -423.365359) (xy 285.578017 -423.315782)
			(xy 285.562662 -423.263487) (xy 285.554906 -423.209539) (xy 285.55442 -423.182288) (xy 285.554873 -423.156367)
			(xy 285.561905 -423.105005) (xy 285.575825 -423.055067) (xy 285.596376 -423.007473) (xy 285.62318 -422.963099)
			(xy 285.655744 -422.922761) (xy 285.674308 -422.904666) (xy 285.68269 -422.896538) (xy 285.691072 -422.875202)
			(xy 285.683198 -422.773094) (xy 285.671514 -422.753282) (xy 285.662116 -422.746678) (xy 285.636886 -422.728895)
			(xy 285.590512 -422.688153) (xy 285.549415 -422.642094) (xy 285.5142 -422.591396) (xy 285.485385 -422.536806)
			(xy 285.463395 -422.479127) (xy 285.448554 -422.419209) (xy 285.44108 -422.357934) (xy 285.440628 -422.32707)
			(xy 285.441107 -422.295349) (xy 285.449006 -422.2324) (xy 285.464678 -422.170923) (xy 285.487879 -422.111875)
			(xy 285.518249 -422.056173) (xy 285.536386 -422.030144) (xy 285.543752 -422.01973) (xy 285.547054 -421.994838)
			(xy 285.5087 -421.891714) (xy 285.489904 -421.875204) (xy 285.477458 -421.872156) (xy 285.444121 -421.86354)
			(xy 285.379958 -421.83856) (xy 285.31975 -421.805154) (xy 285.264598 -421.763933) (xy 285.215509 -421.71565)
			(xy 285.193994 -421.688768) (xy 285.186385 -421.679963) (xy 285.165486 -421.669779) (xy 285.153862 -421.66921)
			(xy 285.073344 -421.66921) (xy 285.061709 -421.669728) (xy 285.0408 -421.679931) (xy 285.033212 -421.688768)
			(xy 285.012487 -421.714637) (xy 284.965473 -421.761362) (xy 284.912783 -421.801578) (xy 284.855312 -421.834602)
			(xy 284.794035 -421.859875) (xy 284.729993 -421.876967) (xy 284.664272 -421.885588) (xy 284.63113 -421.886126)
			(xy 284.599168 -421.885611) (xy 284.535746 -421.877602) (xy 284.473829 -421.861708) (xy 284.414392 -421.838178)
			(xy 284.358373 -421.807385) (xy 284.306656 -421.769812) (xy 284.260055 -421.726054) (xy 284.219306 -421.6768)
			(xy 284.185053 -421.622828) (xy 284.157834 -421.564987) (xy 284.138079 -421.504191) (xy 284.126101 -421.441399)
			(xy 284.122086 -421.3776) (xy 276.132544 -421.3776) (xy 276.132544 -421.920416) (xy 276.132381 -421.925242)
			(xy 276.13046 -421.934703) (xy 276.128734 -421.939212) (xy 276.128734 -421.939466) (xy 276.124924 -421.949118)
			(xy 276.124924 -424.441366) (xy 283.081982 -424.441366) (xy 283.086053 -424.385744) (xy 283.098179 -424.331307)
			(xy 283.118102 -424.279216) (xy 283.145398 -424.230581) (xy 283.179484 -424.186438) (xy 283.219633 -424.147729)
			(xy 283.264991 -424.115278) (xy 283.314591 -424.089777) (xy 283.367375 -424.07177) (xy 283.422218 -424.06164)
			(xy 283.477952 -424.059603) (xy 283.533389 -424.065703) (xy 283.587346 -424.079809) (xy 283.638675 -424.101621)
			(xy 283.686281 -424.130675) (xy 283.729149 -424.16635) (xy 283.766366 -424.207887) (xy 283.797139 -424.2544)
			(xy 283.820811 -424.304897) (xy 283.836879 -424.358304) (xy 283.844999 -424.41348) (xy 283.845508 -424.441366)
			(xy 283.844999 -424.469252) (xy 283.836879 -424.524428) (xy 283.820811 -424.577835) (xy 283.797139 -424.628332)
			(xy 283.766366 -424.674845) (xy 283.747069 -424.696382) (xy 287.199578 -424.696382) (xy 287.200081 -424.668641)
			(xy 287.208094 -424.61374) (xy 287.223976 -424.560579) (xy 287.247394 -424.510281) (xy 287.277852 -424.463907)
			(xy 287.314708 -424.422435) (xy 287.357184 -424.38674) (xy 287.404383 -424.357577) (xy 287.45531 -424.33556)
			(xy 287.50889 -424.321155) (xy 287.536382 -424.317414) (xy 287.54832 -424.316144) (xy 287.568132 -424.30319)
			(xy 287.621218 -424.212766) (xy 287.622996 -424.189144) (xy 287.618424 -424.177968) (xy 287.606309 -424.147153)
			(xy 287.589246 -424.083176) (xy 287.580621 -424.017526) (xy 287.58007 -423.98442) (xy 287.580546 -423.952877)
			(xy 287.588347 -423.890276) (xy 287.603832 -423.82912) (xy 287.626762 -423.770349) (xy 287.656786 -423.714866)
			(xy 287.693442 -423.663523) (xy 287.736168 -423.617108) (xy 287.784306 -423.576335) (xy 287.837119 -423.541829)
			(xy 287.893794 -423.514121) (xy 287.953461 -423.493636) (xy 288.015204 -423.480689) (xy 288.078074 -423.475478)
			(xy 288.141106 -423.478085) (xy 288.203331 -423.488468) (xy 288.263794 -423.506468) (xy 288.321566 -423.531809)
			(xy 288.37576 -423.564101) (xy 288.425544 -423.602849) (xy 288.470152 -423.647458) (xy 288.5089 -423.697241)
			(xy 288.541192 -423.751435) (xy 288.566533 -423.809208) (xy 288.584533 -423.869671) (xy 288.594916 -423.931896)
			(xy 288.597522 -423.994928) (xy 288.592311 -424.057798) (xy 288.579364 -424.119541) (xy 288.558878 -424.179208)
			(xy 288.53117 -424.235883) (xy 288.496664 -424.288695) (xy 288.455891 -424.336834) (xy 288.409476 -424.379559)
			(xy 288.358132 -424.416215) (xy 288.302649 -424.446239) (xy 288.243878 -424.469169) (xy 288.182722 -424.484653)
			(xy 288.120121 -424.492454) (xy 288.088578 -424.492928) (xy 288.059114 -424.492166) (xy 288.046922 -424.491404)
			(xy 288.025332 -424.500548) (xy 287.990844 -424.540934) (xy 289.2077 -424.540934) (xy 289.211771 -424.485312)
			(xy 289.223897 -424.430875) (xy 289.24382 -424.378784) (xy 289.271116 -424.330149) (xy 289.305202 -424.286006)
			(xy 289.345351 -424.247297) (xy 289.390709 -424.214846) (xy 289.440309 -424.189345) (xy 289.493093 -424.171338)
			(xy 289.547936 -424.161208) (xy 289.60367 -424.159171) (xy 289.659107 -424.165271) (xy 289.713064 -424.179377)
			(xy 289.764393 -424.201189) (xy 289.811999 -424.230243) (xy 289.854867 -424.265918) (xy 289.892084 -424.307455)
			(xy 289.922857 -424.353968) (xy 289.946529 -424.404465) (xy 289.962597 -424.457872) (xy 289.963495 -424.463972)
			(xy 290.22116 -424.463972) (xy 290.225231 -424.40835) (xy 290.237357 -424.353913) (xy 290.25728 -424.301822)
			(xy 290.284576 -424.253187) (xy 290.318662 -424.209044) (xy 290.358811 -424.170335) (xy 290.404169 -424.137884)
			(xy 290.453769 -424.112383) (xy 290.506553 -424.094376) (xy 290.561396 -424.084246) (xy 290.61713 -424.082209)
			(xy 290.672567 -424.088309) (xy 290.726524 -424.102415) (xy 290.777853 -424.124227) (xy 290.825459 -424.153281)
			(xy 290.868327 -424.188956) (xy 290.905544 -424.230493) (xy 290.936317 -424.277006) (xy 290.959989 -424.327503)
			(xy 290.976057 -424.38091) (xy 290.984177 -424.436086) (xy 290.984686 -424.463972) (xy 290.984177 -424.491858)
			(xy 290.976057 -424.547034) (xy 290.959989 -424.600441) (xy 290.936317 -424.650938) (xy 290.905544 -424.697451)
			(xy 290.868327 -424.738988) (xy 290.825459 -424.774663) (xy 290.777853 -424.803717) (xy 290.726524 -424.825529)
			(xy 290.672567 -424.839635) (xy 290.61713 -424.845735) (xy 290.561396 -424.843698) (xy 290.506553 -424.833568)
			(xy 290.453769 -424.815561) (xy 290.404169 -424.79006) (xy 290.358811 -424.757609) (xy 290.318662 -424.7189)
			(xy 290.284576 -424.674757) (xy 290.25728 -424.626122) (xy 290.237357 -424.574031) (xy 290.225231 -424.519594)
			(xy 290.22116 -424.463972) (xy 289.963495 -424.463972) (xy 289.970717 -424.513048) (xy 289.971226 -424.540934)
			(xy 289.970717 -424.56882) (xy 289.962597 -424.623996) (xy 289.946529 -424.677403) (xy 289.922857 -424.7279)
			(xy 289.892084 -424.774413) (xy 289.854867 -424.81595) (xy 289.811999 -424.851625) (xy 289.764393 -424.880679)
			(xy 289.713064 -424.902491) (xy 289.659107 -424.916597) (xy 289.60367 -424.922697) (xy 289.547936 -424.92066)
			(xy 289.493093 -424.91053) (xy 289.440309 -424.892523) (xy 289.390709 -424.867022) (xy 289.345351 -424.834571)
			(xy 289.305202 -424.795862) (xy 289.271116 -424.751719) (xy 289.24382 -424.703084) (xy 289.223897 -424.650993)
			(xy 289.211771 -424.596556) (xy 289.2077 -424.540934) (xy 287.990844 -424.540934) (xy 287.957006 -424.580558)
			(xy 287.951164 -424.603418) (xy 287.953958 -424.615102) (xy 287.958029 -424.635174) (xy 287.962353 -424.675903)
			(xy 287.962594 -424.696382) (xy 287.96212 -424.723555) (xy 287.954404 -424.77735) (xy 287.939141 -424.829508)
			(xy 287.916637 -424.878975) (xy 287.902396 -424.902122) (xy 287.895792 -424.912536) (xy 287.893252 -424.936412)
			(xy 287.932368 -425.03598) (xy 287.950402 -425.051982) (xy 287.96234 -425.055284) (xy 287.995149 -425.064367)
			(xy 288.058174 -425.090106) (xy 288.117194 -425.124034) (xy 288.171152 -425.165545) (xy 288.219079 -425.213893)
			(xy 288.260117 -425.268212) (xy 288.2773 -425.2976) (xy 288.282634 -425.306998) (xy 288.29889 -425.319444)
			(xy 288.390584 -425.342812) (xy 288.410904 -425.33951) (xy 288.419794 -425.333922) (xy 288.450289 -425.315481)
			(xy 288.51536 -425.286423) (xy 288.58385 -425.266732) (xy 288.654418 -425.256793) (xy 288.69005 -425.256198)
			(xy 288.722015 -425.256664) (xy 288.785441 -425.264671) (xy 288.847363 -425.280564) (xy 288.906805 -425.304094)
			(xy 288.962829 -425.334888) (xy 289.014551 -425.372462) (xy 289.061156 -425.416222) (xy 289.101908 -425.465479)
			(xy 289.136165 -425.519455) (xy 289.163387 -425.5773) (xy 289.183143 -425.6381) (xy 289.195123 -425.700897)
			(xy 289.199138 -425.7647) (xy 289.195123 -425.828503) (xy 289.186514 -425.873629) (xy 289.396418 -425.873629)
			(xy 289.396418 -425.809707) (xy 289.404429 -425.746289) (xy 289.420326 -425.684375) (xy 289.443858 -425.624942)
			(xy 289.474652 -425.568927) (xy 289.512225 -425.517212) (xy 289.555982 -425.470615) (xy 289.605235 -425.42987)
			(xy 289.659206 -425.395619) (xy 289.717045 -425.368402) (xy 289.777838 -425.348649) (xy 289.840628 -425.336671)
			(xy 289.904424 -425.332658) (xy 289.96822 -425.336671) (xy 290.03101 -425.348649) (xy 290.091803 -425.368402)
			(xy 290.149642 -425.395619) (xy 290.203613 -425.42987) (xy 290.252866 -425.470615) (xy 290.296623 -425.517212)
			(xy 290.334196 -425.568927) (xy 290.36499 -425.624942) (xy 290.379782 -425.662301) (xy 301.962814 -425.662301)
			(xy 301.962814 -425.598379) (xy 301.970825 -425.534961) (xy 301.986722 -425.473047) (xy 302.010254 -425.413614)
			(xy 302.041048 -425.357599) (xy 302.078621 -425.305884) (xy 302.122378 -425.259287) (xy 302.171631 -425.218542)
			(xy 302.225602 -425.184291) (xy 302.283441 -425.157074) (xy 302.344234 -425.137321) (xy 302.407024 -425.125343)
			(xy 302.47082 -425.12133) (xy 302.534616 -425.125343) (xy 302.597406 -425.137321) (xy 302.658199 -425.157074)
			(xy 302.716038 -425.184291) (xy 302.770009 -425.218542) (xy 302.819262 -425.259287) (xy 302.863019 -425.305884)
			(xy 302.900592 -425.357599) (xy 302.931386 -425.413614) (xy 302.954918 -425.473047) (xy 302.970815 -425.534961)
			(xy 302.978826 -425.598379) (xy 302.97906 -425.613279) (xy 304.11394 -425.613279) (xy 304.11394 -425.549357)
			(xy 304.121951 -425.485939) (xy 304.137848 -425.424025) (xy 304.16138 -425.364592) (xy 304.192174 -425.308577)
			(xy 304.229747 -425.256862) (xy 304.273504 -425.210265) (xy 304.322757 -425.16952) (xy 304.376728 -425.135269)
			(xy 304.434567 -425.108052) (xy 304.49536 -425.088299) (xy 304.55815 -425.076321) (xy 304.621946 -425.072308)
			(xy 304.685742 -425.076321) (xy 304.748532 -425.088299) (xy 304.809325 -425.108052) (xy 304.867164 -425.135269)
			(xy 304.921135 -425.16952) (xy 304.970388 -425.210265) (xy 305.014145 -425.256862) (xy 305.051718 -425.308577)
			(xy 305.082512 -425.364592) (xy 305.106044 -425.424025) (xy 305.121941 -425.485939) (xy 305.129952 -425.549357)
			(xy 305.130454 -425.581318) (xy 305.129952 -425.613279) (xy 305.121941 -425.676697) (xy 305.106044 -425.738611)
			(xy 305.082512 -425.798044) (xy 305.051718 -425.854059) (xy 305.014145 -425.905774) (xy 304.970388 -425.952371)
			(xy 304.921135 -425.993116) (xy 304.867164 -426.027367) (xy 304.809325 -426.054584) (xy 304.748532 -426.074337)
			(xy 304.685742 -426.086315) (xy 304.621946 -426.090329) (xy 304.55815 -426.086315) (xy 304.49536 -426.074337)
			(xy 304.434567 -426.054584) (xy 304.376728 -426.027367) (xy 304.322757 -425.993116) (xy 304.273504 -425.952371)
			(xy 304.229747 -425.905774) (xy 304.192174 -425.854059) (xy 304.16138 -425.798044) (xy 304.137848 -425.738611)
			(xy 304.121951 -425.676697) (xy 304.11394 -425.613279) (xy 302.97906 -425.613279) (xy 302.979328 -425.63034)
			(xy 302.978826 -425.662301) (xy 302.970815 -425.725719) (xy 302.954918 -425.787633) (xy 302.931386 -425.847066)
			(xy 302.900592 -425.903081) (xy 302.863019 -425.954796) (xy 302.819262 -426.001393) (xy 302.770009 -426.042138)
			(xy 302.716038 -426.076389) (xy 302.658199 -426.103606) (xy 302.597406 -426.123359) (xy 302.534616 -426.135337)
			(xy 302.47082 -426.139351) (xy 302.407024 -426.135337) (xy 302.344234 -426.123359) (xy 302.283441 -426.103606)
			(xy 302.225602 -426.076389) (xy 302.171631 -426.042138) (xy 302.122378 -426.001393) (xy 302.078621 -425.954796)
			(xy 302.041048 -425.903081) (xy 302.010254 -425.847066) (xy 301.986722 -425.787633) (xy 301.970825 -425.725719)
			(xy 301.962814 -425.662301) (xy 290.379782 -425.662301) (xy 290.388522 -425.684375) (xy 290.404419 -425.746289)
			(xy 290.41243 -425.809707) (xy 290.412932 -425.841668) (xy 290.41243 -425.873629) (xy 290.404419 -425.937047)
			(xy 290.388522 -425.998961) (xy 290.36499 -426.058394) (xy 290.334196 -426.114409) (xy 290.296623 -426.166124)
			(xy 290.252866 -426.212721) (xy 290.203613 -426.253466) (xy 290.149642 -426.287717) (xy 290.091803 -426.314934)
			(xy 290.03101 -426.334687) (xy 289.96822 -426.346665) (xy 289.904424 -426.350679) (xy 289.840628 -426.346665)
			(xy 289.777838 -426.334687) (xy 289.717045 -426.314934) (xy 289.659206 -426.287717) (xy 289.605235 -426.253466)
			(xy 289.555982 -426.212721) (xy 289.512225 -426.166124) (xy 289.474652 -426.114409) (xy 289.443858 -426.058394)
			(xy 289.420326 -425.998961) (xy 289.404429 -425.937047) (xy 289.396418 -425.873629) (xy 289.186514 -425.873629)
			(xy 289.183143 -425.8913) (xy 289.163387 -425.9521) (xy 289.136165 -426.009945) (xy 289.101908 -426.063921)
			(xy 289.061156 -426.113178) (xy 289.014551 -426.156938) (xy 288.962829 -426.194512) (xy 288.906805 -426.225306)
			(xy 288.847363 -426.248836) (xy 288.785441 -426.264729) (xy 288.722015 -426.272736) (xy 288.69005 -426.273214)
			(xy 288.656426 -426.272697) (xy 288.589766 -426.263827) (xy 288.524856 -426.246249) (xy 288.46283 -426.220269)
			(xy 288.404768 -426.186341) (xy 288.351685 -426.145056) (xy 288.304507 -426.097135) (xy 288.264056 -426.043414)
			(xy 288.247074 -426.014388) (xy 288.24174 -426.00499) (xy 288.225484 -425.992544) (xy 288.13379 -425.969176)
			(xy 288.11347 -425.972478) (xy 288.10458 -425.978066) (xy 288.074067 -425.996475) (xy 288.009003 -426.025541)
			(xy 287.940518 -426.045241) (xy 287.869955 -426.05519) (xy 287.834324 -426.05579) (xy 287.803592 -426.05534)
			(xy 287.742575 -426.047934) (xy 287.682896 -426.033226) (xy 287.625425 -426.011432) (xy 287.571 -425.982869)
			(xy 287.520415 -425.947954) (xy 287.474408 -425.907196) (xy 287.433649 -425.861189) (xy 287.398734 -425.810605)
			(xy 287.37017 -425.75618) (xy 287.348376 -425.69871) (xy 287.333668 -425.639031) (xy 287.326261 -425.578014)
			(xy 287.325816 -425.547282) (xy 287.326288 -425.516005) (xy 287.333927 -425.453921) (xy 287.349124 -425.393242)
			(xy 287.371651 -425.334886) (xy 287.401165 -425.279734) (xy 287.437223 -425.228619) (xy 287.457896 -425.205144)
			(xy 287.466278 -425.196) (xy 287.472628 -425.172886) (xy 287.450784 -425.067984) (xy 287.435798 -425.049442)
			(xy 287.424622 -425.044362) (xy 287.399812 -425.032739) (xy 287.353577 -425.003342) (xy 287.312022 -424.967635)
			(xy 287.276 -424.926352) (xy 287.246252 -424.880343) (xy 287.223389 -424.830552) (xy 287.207882 -424.778003)
			(xy 287.200049 -424.723777) (xy 287.199578 -424.696382) (xy 283.747069 -424.696382) (xy 283.729149 -424.716382)
			(xy 283.686281 -424.752057) (xy 283.638675 -424.781111) (xy 283.587346 -424.802923) (xy 283.533389 -424.817029)
			(xy 283.477952 -424.823129) (xy 283.422218 -424.821092) (xy 283.367375 -424.810962) (xy 283.314591 -424.792955)
			(xy 283.264991 -424.767454) (xy 283.219633 -424.735003) (xy 283.179484 -424.696294) (xy 283.145398 -424.652151)
			(xy 283.118102 -424.603516) (xy 283.098179 -424.551425) (xy 283.086053 -424.496988) (xy 283.081982 -424.441366)
			(xy 276.124924 -424.441366) (xy 276.124924 -426.237865) (xy 284.634934 -426.237865) (xy 284.634934 -426.173943)
			(xy 284.642945 -426.110525) (xy 284.658842 -426.048611) (xy 284.682374 -425.989178) (xy 284.713168 -425.933163)
			(xy 284.750741 -425.881448) (xy 284.794498 -425.834851) (xy 284.843751 -425.794106) (xy 284.897722 -425.759855)
			(xy 284.955561 -425.732638) (xy 285.016354 -425.712885) (xy 285.079144 -425.700907) (xy 285.14294 -425.696894)
			(xy 285.206736 -425.700907) (xy 285.269526 -425.712885) (xy 285.330319 -425.732638) (xy 285.388158 -425.759855)
			(xy 285.442129 -425.794106) (xy 285.491382 -425.834851) (xy 285.535139 -425.881448) (xy 285.572712 -425.933163)
			(xy 285.603506 -425.989178) (xy 285.627038 -426.048611) (xy 285.642935 -426.110525) (xy 285.650946 -426.173943)
			(xy 285.651448 -426.205904) (xy 285.650946 -426.237865) (xy 285.642935 -426.301283) (xy 285.627038 -426.363197)
			(xy 285.603506 -426.42263) (xy 285.572712 -426.478645) (xy 285.535139 -426.53036) (xy 285.491382 -426.576957)
			(xy 285.442129 -426.617702) (xy 285.388158 -426.651953) (xy 285.330319 -426.67917) (xy 285.269526 -426.698923)
			(xy 285.206736 -426.710901) (xy 285.14294 -426.714915) (xy 285.079144 -426.710901) (xy 285.016354 -426.698923)
			(xy 284.955561 -426.67917) (xy 284.897722 -426.651953) (xy 284.843751 -426.617702) (xy 284.794498 -426.576957)
			(xy 284.750741 -426.53036) (xy 284.713168 -426.478645) (xy 284.682374 -426.42263) (xy 284.658842 -426.363197)
			(xy 284.642945 -426.301283) (xy 284.634934 -426.237865) (xy 276.124924 -426.237865) (xy 276.124924 -427.261528)
			(xy 280.287982 -427.261528) (xy 280.292053 -427.205906) (xy 280.304179 -427.151469) (xy 280.324102 -427.099378)
			(xy 280.351398 -427.050743) (xy 280.385484 -427.0066) (xy 280.425633 -426.967891) (xy 280.470991 -426.93544)
			(xy 280.520591 -426.909939) (xy 280.573375 -426.891932) (xy 280.628218 -426.881802) (xy 280.683952 -426.879765)
			(xy 280.739389 -426.885865) (xy 280.793346 -426.899971) (xy 280.844675 -426.921783) (xy 280.892281 -426.950837)
			(xy 280.935149 -426.986512) (xy 280.972366 -427.028049) (xy 281.003139 -427.074562) (xy 281.026811 -427.125059)
			(xy 281.042879 -427.178466) (xy 281.050999 -427.233642) (xy 281.051151 -427.24197) (xy 284.174944 -427.24197)
			(xy 284.179015 -427.186348) (xy 284.191141 -427.131911) (xy 284.211064 -427.07982) (xy 284.23836 -427.031185)
			(xy 284.272446 -426.987042) (xy 284.312595 -426.948333) (xy 284.357953 -426.915882) (xy 284.407553 -426.890381)
			(xy 284.460337 -426.872374) (xy 284.51518 -426.862244) (xy 284.570914 -426.860207) (xy 284.626351 -426.866307)
			(xy 284.680308 -426.880413) (xy 284.731637 -426.902225) (xy 284.779243 -426.931279) (xy 284.822111 -426.966954)
			(xy 284.859328 -427.008491) (xy 284.890101 -427.055004) (xy 284.913773 -427.105501) (xy 284.929841 -427.158908)
			(xy 284.937961 -427.214084) (xy 284.93847 -427.24197) (xy 284.937961 -427.269856) (xy 284.929841 -427.325032)
			(xy 284.913773 -427.378439) (xy 284.890101 -427.428936) (xy 284.859328 -427.475449) (xy 284.822111 -427.516986)
			(xy 284.779243 -427.552661) (xy 284.731637 -427.581715) (xy 284.680308 -427.603527) (xy 284.626351 -427.617633)
			(xy 284.570914 -427.623733) (xy 284.51518 -427.621696) (xy 284.460337 -427.611566) (xy 284.407553 -427.593559)
			(xy 284.357953 -427.568058) (xy 284.312595 -427.535607) (xy 284.272446 -427.496898) (xy 284.23836 -427.452755)
			(xy 284.211064 -427.40412) (xy 284.191141 -427.352029) (xy 284.179015 -427.297592) (xy 284.174944 -427.24197)
			(xy 281.051151 -427.24197) (xy 281.051508 -427.261528) (xy 281.050999 -427.289414) (xy 281.042879 -427.34459)
			(xy 281.026811 -427.397997) (xy 281.003139 -427.448494) (xy 280.972366 -427.495007) (xy 280.935149 -427.536544)
			(xy 280.892281 -427.572219) (xy 280.844675 -427.601273) (xy 280.793346 -427.623085) (xy 280.739389 -427.637191)
			(xy 280.683952 -427.643291) (xy 280.628218 -427.641254) (xy 280.573375 -427.631124) (xy 280.520591 -427.613117)
			(xy 280.470991 -427.587616) (xy 280.425633 -427.555165) (xy 280.385484 -427.516456) (xy 280.351398 -427.472313)
			(xy 280.324102 -427.423678) (xy 280.304179 -427.371587) (xy 280.292053 -427.31715) (xy 280.287982 -427.261528)
			(xy 276.124924 -427.261528) (xy 276.124924 -427.763643) (xy 285.011108 -427.763643) (xy 285.011108 -427.699721)
			(xy 285.019119 -427.636303) (xy 285.035016 -427.574389) (xy 285.058548 -427.514956) (xy 285.089342 -427.458941)
			(xy 285.126915 -427.407226) (xy 285.170672 -427.360629) (xy 285.219925 -427.319884) (xy 285.273896 -427.285633)
			(xy 285.331735 -427.258416) (xy 285.392528 -427.238663) (xy 285.455318 -427.226685) (xy 285.519114 -427.222672)
			(xy 285.58291 -427.226685) (xy 285.6457 -427.238663) (xy 285.706493 -427.258416) (xy 285.764332 -427.285633)
			(xy 285.818303 -427.319884) (xy 285.867556 -427.360629) (xy 285.911313 -427.407226) (xy 285.948886 -427.458941)
			(xy 285.97968 -427.514956) (xy 286.003212 -427.574389) (xy 286.019109 -427.636303) (xy 286.02712 -427.699721)
			(xy 286.027622 -427.731682) (xy 286.02712 -427.763643) (xy 286.019109 -427.827061) (xy 286.003212 -427.888975)
			(xy 285.97968 -427.948408) (xy 285.948886 -428.004423) (xy 285.915075 -428.05096) (xy 288.54095 -428.05096)
			(xy 288.545021 -427.995338) (xy 288.557147 -427.940901) (xy 288.57707 -427.88881) (xy 288.604366 -427.840175)
			(xy 288.638452 -427.796032) (xy 288.678601 -427.757323) (xy 288.723959 -427.724872) (xy 288.773559 -427.699371)
			(xy 288.826343 -427.681364) (xy 288.881186 -427.671234) (xy 288.93692 -427.669197) (xy 288.992357 -427.675297)
			(xy 289.046314 -427.689403) (xy 289.097643 -427.711215) (xy 289.145249 -427.740269) (xy 289.188117 -427.775944)
			(xy 289.225334 -427.817481) (xy 289.256107 -427.863994) (xy 289.279779 -427.914491) (xy 289.295847 -427.967898)
			(xy 289.303967 -428.023074) (xy 289.304476 -428.05096) (xy 289.303967 -428.078846) (xy 289.295847 -428.134022)
			(xy 289.279779 -428.187429) (xy 289.256107 -428.237926) (xy 289.225334 -428.284439) (xy 289.188117 -428.325976)
			(xy 289.145249 -428.361651) (xy 289.097643 -428.390705) (xy 289.046314 -428.412517) (xy 288.992357 -428.426623)
			(xy 288.93692 -428.432723) (xy 288.881186 -428.430686) (xy 288.826343 -428.420556) (xy 288.773559 -428.402549)
			(xy 288.723959 -428.377048) (xy 288.678601 -428.344597) (xy 288.638452 -428.305888) (xy 288.604366 -428.261745)
			(xy 288.57707 -428.21311) (xy 288.557147 -428.161019) (xy 288.545021 -428.106582) (xy 288.54095 -428.05096)
			(xy 285.915075 -428.05096) (xy 285.911313 -428.056138) (xy 285.867556 -428.102735) (xy 285.818303 -428.14348)
			(xy 285.764332 -428.177731) (xy 285.706493 -428.204948) (xy 285.6457 -428.224701) (xy 285.58291 -428.236679)
			(xy 285.519114 -428.240693) (xy 285.455318 -428.236679) (xy 285.392528 -428.224701) (xy 285.331735 -428.204948)
			(xy 285.273896 -428.177731) (xy 285.219925 -428.14348) (xy 285.170672 -428.102735) (xy 285.126915 -428.056138)
			(xy 285.089342 -428.004423) (xy 285.058548 -427.948408) (xy 285.035016 -427.888975) (xy 285.019119 -427.827061)
			(xy 285.011108 -427.763643) (xy 276.124924 -427.763643) (xy 276.124924 -428.40656) (xy 276.125316 -428.416083)
			(xy 276.132224 -428.433834) (xy 276.138386 -428.441104) (xy 276.158198 -428.462694) (xy 276.166834 -428.467012)
			(xy 276.189186 -428.478442) (xy 276.198076 -428.479458) (xy 276.228395 -428.48378) (xy 276.28778 -428.498756)
			(xy 276.344937 -428.520754) (xy 276.39904 -428.549455) (xy 276.449305 -428.584444) (xy 276.495006 -428.625215)
			(xy 276.535481 -428.671178) (xy 276.570146 -428.721668) (xy 276.598497 -428.775954) (xy 276.620126 -428.833252)
			(xy 276.634719 -428.892732) (xy 276.639422 -428.931654) (xy 286.368155 -428.931654) (xy 286.368155 -428.877146)
			(xy 286.375913 -428.823191) (xy 286.391271 -428.770891) (xy 286.413916 -428.721308) (xy 286.443388 -428.675453)
			(xy 286.479085 -428.63426) (xy 286.520282 -428.598566) (xy 286.56614 -428.569099) (xy 286.615724 -428.546459)
			(xy 286.668027 -428.531106) (xy 286.721981 -428.523353) (xy 286.749236 -428.522892) (xy 286.776818 -428.523349)
			(xy 286.831406 -428.531307) (xy 286.884281 -428.547037) (xy 286.934342 -428.570212) (xy 286.980547 -428.60035)
			(xy 287.021934 -428.636823) (xy 287.057642 -428.678872) (xy 287.086928 -428.725621) (xy 287.109181 -428.776099)
			(xy 287.117028 -428.802546) (xy 287.121126 -428.815957) (xy 287.135669 -428.839927) (xy 287.156176 -428.859047)
			(xy 287.181104 -428.871879) (xy 287.20858 -428.877458) (xy 287.236539 -428.875366) (xy 287.262879 -428.865759)
			(xy 287.274508 -428.857918) (xy 287.30062 -428.839623) (xy 287.356519 -428.808954) (xy 287.415812 -428.785512)
			(xy 287.47757 -428.769664) (xy 287.540825 -428.761659) (xy 287.572704 -428.761144) (xy 287.604662 -428.761742)
			(xy 287.668074 -428.769753) (xy 287.729981 -428.785649) (xy 287.789408 -428.809178) (xy 287.845418 -428.83997)
			(xy 287.897127 -428.877539) (xy 287.943719 -428.921293) (xy 287.98446 -428.970541) (xy 288.018708 -429.024507)
			(xy 288.045922 -429.082339) (xy 288.065673 -429.143127) (xy 288.077649 -429.20591) (xy 288.081663 -429.2697)
			(xy 288.077649 -429.33349) (xy 288.065673 -429.396273) (xy 288.045922 -429.457061) (xy 288.018708 -429.514893)
			(xy 287.98446 -429.568859) (xy 287.943719 -429.618107) (xy 287.897127 -429.661861) (xy 287.845418 -429.69943)
			(xy 287.789408 -429.730222) (xy 287.729981 -429.753751) (xy 287.668074 -429.769647) (xy 287.604662 -429.777658)
			(xy 287.572704 -429.77816) (xy 287.541727 -429.777625) (xy 287.480233 -429.770099) (xy 287.420108 -429.755156)
			(xy 287.362244 -429.733019) (xy 287.307499 -429.704016) (xy 287.256683 -429.668576) (xy 287.210549 -429.627225)
			(xy 287.169781 -429.580575) (xy 287.134983 -429.529317) (xy 287.106671 -429.474211) (xy 287.085263 -429.416074)
			(xy 287.071078 -429.355766) (xy 287.067244 -429.325024) (xy 287.065217 -429.311165) (xy 287.054686 -429.285226)
			(xy 287.037514 -429.263116) (xy 287.01499 -429.24649) (xy 286.9888 -429.236597) (xy 286.96091 -429.234178)
			(xy 286.933408 -429.239413) (xy 286.920686 -429.245268) (xy 286.893932 -429.258059) (xy 286.837467 -429.276165)
			(xy 286.778884 -429.285339) (xy 286.749236 -429.285908) (xy 286.721981 -429.285447) (xy 286.668027 -429.277694)
			(xy 286.615724 -429.262341) (xy 286.56614 -429.239701) (xy 286.520282 -429.210234) (xy 286.479085 -429.17454)
			(xy 286.443388 -429.133347) (xy 286.413916 -429.087492) (xy 286.391271 -429.037909) (xy 286.375913 -428.985609)
			(xy 286.368155 -428.931654) (xy 276.639422 -428.931654) (xy 276.642066 -428.953534) (xy 276.642576 -428.984156)
			(xy 276.642576 -428.98441) (xy 276.642273 -429.009535) (xy 276.637311 -429.059538) (xy 276.63267 -429.084232)
			(xy 276.630638 -429.093884) (xy 276.634194 -429.112934) (xy 276.681946 -429.188372) (xy 276.69744 -429.199802)
			(xy 276.707092 -429.202088) (xy 276.734191 -429.209451) (xy 276.78603 -429.231039) (xy 276.834148 -429.259986)
			(xy 276.877508 -429.295668) (xy 276.915175 -429.337315) (xy 276.946336 -429.384029) (xy 276.97032 -429.434804)
			(xy 276.986609 -429.488543) (xy 276.994853 -429.544089) (xy 276.995382 -429.572166) (xy 276.994921 -429.599439)
			(xy 276.994247 -429.604127) (xy 278.665426 -429.604127) (xy 278.665426 -429.540205) (xy 278.673437 -429.476787)
			(xy 278.689334 -429.414873) (xy 278.712866 -429.35544) (xy 278.74366 -429.299425) (xy 278.781233 -429.24771)
			(xy 278.82499 -429.201113) (xy 278.874243 -429.160368) (xy 278.928214 -429.126117) (xy 278.986053 -429.0989)
			(xy 279.046846 -429.079147) (xy 279.109636 -429.067169) (xy 279.173432 -429.063156) (xy 279.237228 -429.067169)
			(xy 279.300018 -429.079147) (xy 279.360811 -429.0989) (xy 279.41865 -429.126117) (xy 279.472621 -429.160368)
			(xy 279.521874 -429.201113) (xy 279.565631 -429.24771) (xy 279.603204 -429.299425) (xy 279.633998 -429.35544)
			(xy 279.65753 -429.414873) (xy 279.673427 -429.476787) (xy 279.681438 -429.540205) (xy 279.68194 -429.572166)
			(xy 279.681438 -429.604127) (xy 279.673427 -429.667545) (xy 279.65753 -429.729459) (xy 279.633998 -429.788892)
			(xy 279.603204 -429.844907) (xy 279.565631 -429.896622) (xy 279.521874 -429.943219) (xy 279.472621 -429.983964)
			(xy 279.41865 -430.018215) (xy 279.360811 -430.045432) (xy 279.300018 -430.065185) (xy 279.237228 -430.077163)
			(xy 279.173432 -430.081177) (xy 279.109636 -430.077163) (xy 279.046846 -430.065185) (xy 278.986053 -430.045432)
			(xy 278.928214 -430.018215) (xy 278.874243 -429.983964) (xy 278.82499 -429.943219) (xy 278.781233 -429.896622)
			(xy 278.74366 -429.844907) (xy 278.712866 -429.788892) (xy 278.689334 -429.729459) (xy 278.673437 -429.667545)
			(xy 278.665426 -429.604127) (xy 276.994247 -429.604127) (xy 276.987163 -429.653431) (xy 276.9718 -429.705769)
			(xy 276.949144 -429.755387) (xy 276.919658 -429.801277) (xy 276.883941 -429.842503) (xy 276.84272 -429.878225)
			(xy 276.796835 -429.907718) (xy 276.747219 -429.930381) (xy 276.694884 -429.945751) (xy 276.640893 -429.953517)
			(xy 276.61362 -429.953928) (xy 276.586362 -429.953444) (xy 276.532401 -429.945691) (xy 276.480091 -429.93034)
			(xy 276.430497 -429.907703) (xy 276.384628 -429.87824) (xy 276.343418 -429.842552) (xy 276.307704 -429.801364)
			(xy 276.278213 -429.755514) (xy 276.255544 -429.705934) (xy 276.24016 -429.653634) (xy 276.232373 -429.599678)
			(xy 276.231858 -429.57242) (xy 276.231858 -429.571912) (xy 276.231858 -429.565562) (xy 276.23144 -429.555713)
			(xy 276.224114 -429.537432) (xy 276.217634 -429.530002) (xy 276.21357 -429.525684) (xy 276.205296 -429.517761)
			(xy 276.18387 -429.509716) (xy 276.172422 -429.51019) (xy 276.172168 -429.51019) (xy 276.163347 -429.511379)
			(xy 276.147232 -429.518907) (xy 276.140672 -429.524922) (xy 276.13991 -429.525684) (xy 276.133076 -429.533087)
			(xy 276.12537 -429.551685) (xy 276.124924 -429.561752) (xy 276.124924 -430.791366) (xy 277.234902 -430.791366)
			(xy 277.238973 -430.735744) (xy 277.251099 -430.681307) (xy 277.271022 -430.629216) (xy 277.298318 -430.580581)
			(xy 277.332404 -430.536438) (xy 277.372553 -430.497729) (xy 277.417911 -430.465278) (xy 277.467511 -430.439777)
			(xy 277.520295 -430.42177) (xy 277.575138 -430.41164) (xy 277.630872 -430.409603) (xy 277.686309 -430.415703)
			(xy 277.740266 -430.429809) (xy 277.791595 -430.451621) (xy 277.839201 -430.480675) (xy 277.882069 -430.51635)
			(xy 277.919286 -430.557887) (xy 277.950059 -430.6044) (xy 277.973731 -430.654897) (xy 277.989799 -430.708304)
			(xy 277.997919 -430.76348) (xy 277.998428 -430.791366) (xy 277.997919 -430.819252) (xy 277.989799 -430.874428)
			(xy 277.973731 -430.927835) (xy 277.950059 -430.978332) (xy 277.919286 -431.024845) (xy 277.882069 -431.066382)
			(xy 277.839201 -431.102057) (xy 277.791595 -431.131111) (xy 277.740266 -431.152923) (xy 277.686309 -431.167029)
			(xy 277.630872 -431.173129) (xy 277.575138 -431.171092) (xy 277.520295 -431.160962) (xy 277.467511 -431.142955)
			(xy 277.417911 -431.117454) (xy 277.372553 -431.085003) (xy 277.332404 -431.046294) (xy 277.298318 -431.002151)
			(xy 277.271022 -430.953516) (xy 277.251099 -430.901425) (xy 277.238973 -430.846988) (xy 277.234902 -430.791366)
			(xy 276.124924 -430.791366) (xy 276.124924 -433.963826) (xy 277.872188 -433.963826) (xy 277.876259 -433.908204)
			(xy 277.888385 -433.853767) (xy 277.908308 -433.801676) (xy 277.935604 -433.753041) (xy 277.96969 -433.708898)
			(xy 278.009839 -433.670189) (xy 278.055197 -433.637738) (xy 278.104797 -433.612237) (xy 278.157581 -433.59423)
			(xy 278.212424 -433.5841) (xy 278.268158 -433.582063) (xy 278.323595 -433.588163) (xy 278.377552 -433.602269)
			(xy 278.428881 -433.624081) (xy 278.476487 -433.653135) (xy 278.519355 -433.68881) (xy 278.556572 -433.730347)
			(xy 278.587345 -433.77686) (xy 278.611017 -433.827357) (xy 278.627085 -433.880764) (xy 278.635205 -433.93594)
			(xy 278.635714 -433.963826) (xy 278.635205 -433.991712) (xy 278.627085 -434.046888) (xy 278.611017 -434.100295)
			(xy 278.587345 -434.150792) (xy 278.556572 -434.197305) (xy 278.519355 -434.238842) (xy 278.476487 -434.274517)
			(xy 278.428881 -434.303571) (xy 278.377552 -434.325383) (xy 278.323595 -434.339489) (xy 278.268158 -434.345589)
			(xy 278.212424 -434.343552) (xy 278.157581 -434.333422) (xy 278.104797 -434.315415) (xy 278.055197 -434.289914)
			(xy 278.009839 -434.257463) (xy 277.96969 -434.218754) (xy 277.935604 -434.174611) (xy 277.908308 -434.125976)
			(xy 277.888385 -434.073885) (xy 277.876259 -434.019448) (xy 277.872188 -433.963826) (xy 276.124924 -433.963826)
			(xy 276.124924 -434.655976) (xy 282.434284 -434.655976) (xy 282.434786 -434.624015) (xy 282.442797 -434.560597)
			(xy 282.458694 -434.498683) (xy 282.482226 -434.43925) (xy 282.51302 -434.383235) (xy 282.550593 -434.33152)
			(xy 282.59435 -434.284923) (xy 282.643603 -434.244178) (xy 282.697574 -434.209927) (xy 282.755413 -434.18271)
			(xy 282.816206 -434.162957) (xy 282.878996 -434.150979) (xy 282.942792 -434.146966) (xy 283.006588 -434.150979)
			(xy 283.069378 -434.162957) (xy 283.130171 -434.18271) (xy 283.18801 -434.209927) (xy 283.241981 -434.244178)
			(xy 283.291234 -434.284923) (xy 283.334991 -434.33152) (xy 283.372564 -434.383235) (xy 283.403358 -434.43925)
			(xy 283.42689 -434.498683) (xy 283.442787 -434.560597) (xy 283.450798 -434.624015) (xy 283.4513 -434.655976)
			(xy 283.450818 -434.688126) (xy 283.442721 -434.751915) (xy 283.42664 -434.814173) (xy 283.402834 -434.873904)
			(xy 283.371681 -434.930154) (xy 283.33368 -434.982025) (xy 283.289439 -435.028686) (xy 283.264864 -435.049422)
			(xy 283.257244 -435.055772) (xy 283.247846 -435.07279) (xy 283.236924 -435.162452) (xy 283.242004 -435.180994)
			(xy 283.2481 -435.189122) (xy 283.266003 -435.21406) (xy 283.294466 -435.268448) (xy 283.31386 -435.326689)
			(xy 283.323685 -435.387283) (xy 283.3243 -435.417976) (xy 283.323814 -435.445227) (xy 283.316058 -435.499175)
			(xy 283.300703 -435.55147) (xy 283.278061 -435.601047) (xy 283.248595 -435.646897) (xy 283.212904 -435.688088)
			(xy 283.171713 -435.723779) (xy 283.125863 -435.753245) (xy 283.076286 -435.775887) (xy 283.023991 -435.791242)
			(xy 282.970043 -435.798998) (xy 282.915541 -435.798998) (xy 282.861593 -435.791242) (xy 282.809298 -435.775887)
			(xy 282.759721 -435.753245) (xy 282.713871 -435.723779) (xy 282.67268 -435.688088) (xy 282.636989 -435.646897)
			(xy 282.607523 -435.601047) (xy 282.584881 -435.55147) (xy 282.569526 -435.499175) (xy 282.56177 -435.445227)
			(xy 282.561284 -435.417976) (xy 282.561895 -435.387283) (xy 282.57172 -435.326688) (xy 282.591114 -435.268446)
			(xy 282.619576 -435.214057) (xy 282.637484 -435.189122) (xy 282.64358 -435.180994) (xy 282.64866 -435.162452)
			(xy 282.637738 -435.07279) (xy 282.62834 -435.055772) (xy 282.62072 -435.049422) (xy 282.596158 -435.028674)
			(xy 282.551932 -434.982004) (xy 282.513943 -434.930131) (xy 282.482795 -434.873883) (xy 282.458986 -434.814157)
			(xy 282.442896 -434.751906) (xy 282.434781 -434.688124) (xy 282.434284 -434.655976) (xy 276.124924 -434.655976)
			(xy 276.124924 -434.825902) (xy 276.124501 -434.835973) (xy 276.116789 -434.854579) (xy 276.109938 -434.86197)
			(xy 274.650845 -436.321063) (xy 276.104713 -436.321063) (xy 276.109924 -436.258198) (xy 276.122871 -436.19646)
			(xy 276.143356 -436.136798) (xy 276.171062 -436.080128) (xy 276.205566 -436.027321) (xy 276.246337 -435.979187)
			(xy 276.292748 -435.936465) (xy 276.344088 -435.899812) (xy 276.399566 -435.869792) (xy 276.458333 -435.846864)
			(xy 276.519483 -435.831381) (xy 276.58208 -435.82358) (xy 276.61362 -435.823106) (xy 276.643941 -435.823541)
			(xy 276.704153 -435.830737) (xy 276.763084 -435.845037) (xy 276.819899 -435.866237) (xy 276.847046 -435.879748)
			(xy 276.860035 -435.885953) (xy 276.88826 -435.891548) (xy 276.916925 -435.889045) (xy 276.943753 -435.878643)
			(xy 276.966614 -435.861169) (xy 276.983691 -435.838011) (xy 276.993629 -435.811007) (xy 276.995128 -435.79669)
			(xy 276.997674 -435.768169) (xy 277.010192 -435.712296) (xy 277.030921 -435.658921) (xy 277.059397 -435.609245)
			(xy 277.094978 -435.564384) (xy 277.136866 -435.525346) (xy 277.184119 -435.493009) (xy 277.235675 -435.468098)
			(xy 277.290375 -435.451174) (xy 277.346991 -435.442618) (xy 277.37562 -435.442106) (xy 277.402871 -435.442565)
			(xy 277.456819 -435.450324) (xy 277.509113 -435.465682) (xy 277.55869 -435.488325) (xy 277.604539 -435.517793)
			(xy 277.645729 -435.553486) (xy 277.681419 -435.594677) (xy 277.710885 -435.640528) (xy 277.733525 -435.690106)
			(xy 277.74888 -435.742401) (xy 277.756636 -435.796349) (xy 277.756636 -435.850851) (xy 277.74888 -435.904799)
			(xy 277.733525 -435.957094) (xy 277.710885 -436.006672) (xy 277.681419 -436.052523) (xy 277.645729 -436.093714)
			(xy 277.604539 -436.129407) (xy 277.55869 -436.158875) (xy 277.509113 -436.181518) (xy 277.456819 -436.196876)
			(xy 277.402871 -436.204635) (xy 277.37562 -436.205122) (xy 277.344647 -436.204558) (xy 277.283508 -436.194598)
			(xy 277.253954 -436.18531) (xy 277.240167 -436.181197) (xy 277.211436 -436.179973) (xy 277.183505 -436.186814)
			(xy 277.158592 -436.201178) (xy 277.138677 -436.221923) (xy 277.125342 -436.247401) (xy 277.119646 -436.275588)
			(xy 277.12035 -436.289958) (xy 277.122128 -436.331614) (xy 277.121617 -436.363154) (xy 277.113813 -436.42575)
			(xy 277.098326 -436.4869) (xy 277.075394 -436.545664) (xy 277.04537 -436.601141) (xy 277.029252 -436.623714)
			(xy 282.066236 -436.623714) (xy 282.070307 -436.568092) (xy 282.082433 -436.513655) (xy 282.102356 -436.461564)
			(xy 282.129652 -436.412929) (xy 282.163738 -436.368786) (xy 282.203887 -436.330077) (xy 282.249245 -436.297626)
			(xy 282.298845 -436.272125) (xy 282.351629 -436.254118) (xy 282.406472 -436.243988) (xy 282.462206 -436.241951)
			(xy 282.517643 -436.248051) (xy 282.5716 -436.262157) (xy 282.622929 -436.283969) (xy 282.670535 -436.313023)
			(xy 282.713403 -436.348698) (xy 282.75062 -436.390235) (xy 282.781393 -436.436748) (xy 282.805065 -436.487245)
			(xy 282.821133 -436.540652) (xy 282.829253 -436.595828) (xy 282.829762 -436.623714) (xy 282.829253 -436.6516)
			(xy 282.821133 -436.706776) (xy 282.805065 -436.760183) (xy 282.781393 -436.81068) (xy 282.75062 -436.857193)
			(xy 282.713403 -436.89873) (xy 282.670535 -436.934405) (xy 282.622929 -436.963459) (xy 282.5716 -436.985271)
			(xy 282.517643 -436.999377) (xy 282.462206 -437.005477) (xy 282.406472 -437.00344) (xy 282.351629 -436.99331)
			(xy 282.298845 -436.975303) (xy 282.249245 -436.949802) (xy 282.203887 -436.917351) (xy 282.163738 -436.878642)
			(xy 282.129652 -436.834499) (xy 282.102356 -436.785864) (xy 282.082433 -436.733773) (xy 282.070307 -436.679336)
			(xy 282.066236 -436.623714) (xy 277.029252 -436.623714) (xy 277.008713 -436.652478) (xy 276.965989 -436.698887)
			(xy 276.917852 -436.739654) (xy 276.865042 -436.774154) (xy 276.80837 -436.801857) (xy 276.748707 -436.822338)
			(xy 276.686969 -436.835281) (xy 276.624103 -436.840488) (xy 276.561077 -436.837879) (xy 276.498857 -436.827495)
			(xy 276.4384 -436.809494) (xy 276.380633 -436.784153) (xy 276.326444 -436.751861) (xy 276.276666 -436.713114)
			(xy 276.232063 -436.668508) (xy 276.19332 -436.618727) (xy 276.161032 -436.564537) (xy 276.135695 -436.506769)
			(xy 276.117698 -436.44631) (xy 276.107317 -436.384089) (xy 276.104713 -436.321063) (xy 274.650845 -436.321063)
			(xy 273.920204 -437.051704) (xy 273.912805 -437.058551) (xy 273.894208 -437.066286) (xy 273.884136 -437.06669)
			(xy 229.27437 -437.06669) (xy 229.264385 -437.067233) (xy 229.24596 -437.074953) (xy 229.238556 -437.081676)
			(xy 229.22103 -437.099202) (xy 229.213628 -437.106037) (xy 229.195029 -437.113746) (xy 229.184962 -437.114188)
			(xy 207.192118 -437.114188) (xy 207.182055 -437.11375) (xy 207.163473 -437.106013) (xy 207.15605 -437.099202)
			(xy 207.138524 -437.081676) (xy 207.131178 -437.074869) (xy 207.112715 -437.067152) (xy 207.10271 -437.06669)
			(xy 198.415656 -437.06669) (xy 198.40559 -437.066259) (xy 198.386998 -437.058532) (xy 198.379588 -437.051704)
			(xy 195.38823 -434.060346) (xy 195.381389 -434.052946) (xy 195.373669 -434.034347) (xy 195.373244 -434.024278)
			(xy 195.373244 -431.009044) (xy 195.372794 -430.998888) (xy 195.364936 -430.980158) (xy 195.358004 -430.972722)
			(xy 195.298568 -430.91481) (xy 195.279772 -430.907444) (xy 195.269358 -430.907698) (xy 195.258182 -430.907698)
			(xy 195.226222 -430.907195) (xy 195.162807 -430.899182) (xy 195.100896 -430.883284) (xy 195.041466 -430.859752)
			(xy 194.985454 -430.828957) (xy 194.933743 -430.791385) (xy 194.887149 -430.747629) (xy 194.846406 -430.698377)
			(xy 194.812157 -430.644408) (xy 194.784942 -430.586572) (xy 194.76519 -430.52578) (xy 194.753213 -430.462993)
			(xy 194.749199 -430.3992) (xy 194.753213 -430.335407) (xy 194.76519 -430.27262) (xy 194.784942 -430.211828)
			(xy 194.812157 -430.153992) (xy 194.846406 -430.100023) (xy 194.887149 -430.050771) (xy 194.933743 -430.007015)
			(xy 194.985454 -429.969443) (xy 195.041466 -429.938648) (xy 195.100896 -429.915116) (xy 195.162807 -429.899218)
			(xy 195.226222 -429.891205) (xy 195.258182 -429.890682) (xy 195.269358 -429.890682) (xy 195.279772 -429.890936)
			(xy 195.298568 -429.88357) (xy 195.358004 -429.825658) (xy 195.364959 -429.818235) (xy 195.372837 -429.799499)
			(xy 195.373244 -429.789336) (xy 195.373244 -429.297846) (xy 195.372744 -429.287008) (xy 195.363792 -429.267267)
			(xy 195.355972 -429.259746) (xy 195.289932 -429.202088) (xy 195.269104 -429.195738) (xy 195.257928 -429.197262)
			(xy 195.240929 -429.199413) (xy 195.206736 -429.201698) (xy 195.189602 -429.201834) (xy 195.157638 -429.201353)
			(xy 195.094214 -429.193341) (xy 195.032294 -429.177443) (xy 194.972855 -429.15391) (xy 194.916834 -429.123112)
			(xy 194.865115 -429.085536) (xy 194.818514 -429.041775) (xy 194.777764 -428.992517) (xy 194.74351 -428.938541)
			(xy 194.71629 -428.880697) (xy 194.696536 -428.819898) (xy 194.684557 -428.757102) (xy 194.680542 -428.6933)
			(xy 194.684557 -428.629498) (xy 194.696536 -428.566702) (xy 194.71629 -428.505903) (xy 194.74351 -428.448059)
			(xy 194.777764 -428.394083) (xy 194.818514 -428.344825) (xy 194.865115 -428.301064) (xy 194.916834 -428.263488)
			(xy 194.972855 -428.23269) (xy 195.032294 -428.209157) (xy 195.094214 -428.193259) (xy 195.157638 -428.185247)
			(xy 195.189602 -428.184818) (xy 195.206736 -428.184954) (xy 195.240928 -428.187243) (xy 195.257928 -428.18939)
			(xy 195.269104 -428.190914) (xy 195.289932 -428.184564) (xy 195.355972 -428.126906) (xy 195.363775 -428.119372)
			(xy 195.372732 -428.099639) (xy 195.373244 -428.088806) (xy 195.373244 -426.180504) (xy 195.37277 -426.170271)
			(xy 195.364779 -426.151427) (xy 195.350092 -426.137172) (xy 195.340732 -426.133006) (xy 195.237862 -426.093128)
			(xy 195.207128 -426.100494) (xy 195.196714 -426.111924) (xy 195.178563 -426.13117) (xy 195.137868 -426.16497)
			(xy 195.092893 -426.192822) (xy 195.0445 -426.214192) (xy 194.993619 -426.228669) (xy 194.941225 -426.235976)
			(xy 194.914774 -426.236384) (xy 194.887526 -426.235896) (xy 194.833584 -426.228137) (xy 194.781296 -426.212781)
			(xy 194.731725 -426.190139) (xy 194.685881 -426.160674) (xy 194.644697 -426.124985) (xy 194.60901 -426.083798)
			(xy 194.579548 -426.037952) (xy 194.55691 -425.98838) (xy 194.541557 -425.93609) (xy 194.533802 -425.882148)
			(xy 194.533802 -425.827652) (xy 194.541557 -425.77371) (xy 194.55691 -425.72142) (xy 194.579548 -425.671848)
			(xy 194.60901 -425.626002) (xy 194.644697 -425.584815) (xy 194.685881 -425.549126) (xy 194.731725 -425.519661)
			(xy 194.781296 -425.497019) (xy 194.833584 -425.481663) (xy 194.887526 -425.473904) (xy 194.914774 -425.473368)
			(xy 194.941221 -425.473823) (xy 194.993606 -425.481138) (xy 195.04448 -425.495617) (xy 195.092867 -425.516983)
			(xy 195.137839 -425.544826) (xy 195.178535 -425.578613) (xy 195.196714 -425.597828) (xy 195.207128 -425.609258)
			(xy 195.237862 -425.616624) (xy 195.340732 -425.576746) (xy 195.350127 -425.572636) (xy 195.364843 -425.55838)
			(xy 195.372786 -425.539495) (xy 195.373244 -425.529248) (xy 195.373244 -414.32607) (xy 195.372814 -414.316003)
			(xy 195.365086 -414.297412) (xy 195.358258 -414.290002) (xy 193.94297 -412.874714) (xy 193.93557 -412.867871)
			(xy 193.916972 -412.860145) (xy 193.906902 -412.859728) (xy 193.573908 -412.859728) (xy 193.563041 -412.860282)
			(xy 193.543288 -412.869354) (xy 193.535808 -412.877254) (xy 193.47815 -412.943294) (xy 193.4718 -412.964122)
			(xy 193.473324 -412.975298) (xy 193.475576 -412.992609) (xy 193.477992 -413.027438) (xy 193.47815 -413.044894)
			(xy 193.477648 -413.076855) (xy 193.469637 -413.140273) (xy 193.45374 -413.202187) (xy 193.430208 -413.26162)
			(xy 193.399414 -413.317635) (xy 193.361841 -413.36935) (xy 193.318084 -413.415947) (xy 193.268831 -413.456692)
			(xy 193.21486 -413.490943) (xy 193.157021 -413.51816) (xy 193.096228 -413.537913) (xy 193.033438 -413.549891)
			(xy 192.969642 -413.553905) (xy 192.905846 -413.549891) (xy 192.843056 -413.537913) (xy 192.782263 -413.51816)
			(xy 192.724424 -413.490943) (xy 192.670453 -413.456692) (xy 192.6212 -413.415947) (xy 192.577443 -413.36935)
			(xy 192.53987 -413.317635) (xy 192.509076 -413.26162) (xy 192.485544 -413.202187) (xy 192.469647 -413.140273)
			(xy 192.461636 -413.076855) (xy 192.461134 -413.044894) (xy 192.461291 -413.027438) (xy 192.463706 -412.992609)
			(xy 192.46596 -412.975298) (xy 192.467484 -412.964122) (xy 192.461134 -412.943294) (xy 192.403476 -412.877254)
			(xy 192.395978 -412.869371) (xy 192.37624 -412.86027) (xy 192.365376 -412.859728) (xy 189.431422 -412.859728)
			(xy 189.422678 -412.860046) (xy 189.406181 -412.865839) (xy 189.392583 -412.87683) (xy 189.387734 -412.884112)
			(xy 189.335918 -412.969964) (xy 189.335156 -412.996634) (xy 189.341252 -413.008318) (xy 189.355043 -413.035688)
			(xy 189.376708 -413.093021) (xy 189.39133 -413.15254) (xy 189.398699 -413.213385) (xy 189.399164 -413.24403)
			(xy 189.398662 -413.275991) (xy 189.390651 -413.339409) (xy 189.374754 -413.401323) (xy 189.351222 -413.460756)
			(xy 189.320428 -413.516771) (xy 189.28551 -413.564832) (xy 189.930276 -413.564832) (xy 189.934347 -413.50921)
			(xy 189.946473 -413.454773) (xy 189.966396 -413.402682) (xy 189.993692 -413.354047) (xy 190.027778 -413.309904)
			(xy 190.067927 -413.271195) (xy 190.113285 -413.238744) (xy 190.162885 -413.213243) (xy 190.215669 -413.195236)
			(xy 190.270512 -413.185106) (xy 190.326246 -413.183069) (xy 190.381683 -413.189169) (xy 190.43564 -413.203275)
			(xy 190.486969 -413.225087) (xy 190.534575 -413.254141) (xy 190.577443 -413.289816) (xy 190.61466 -413.331353)
			(xy 190.645433 -413.377866) (xy 190.669105 -413.428363) (xy 190.685173 -413.48177) (xy 190.693293 -413.536946)
			(xy 190.693802 -413.564832) (xy 190.693293 -413.592718) (xy 190.685173 -413.647894) (xy 190.669105 -413.701301)
			(xy 190.645433 -413.751798) (xy 190.61466 -413.798311) (xy 190.577443 -413.839848) (xy 190.534575 -413.875523)
			(xy 190.486969 -413.904577) (xy 190.43564 -413.926389) (xy 190.381683 -413.940495) (xy 190.326246 -413.946595)
			(xy 190.270512 -413.944558) (xy 190.215669 -413.934428) (xy 190.162885 -413.916421) (xy 190.113285 -413.89092)
			(xy 190.067927 -413.858469) (xy 190.027778 -413.81976) (xy 189.993692 -413.775617) (xy 189.966396 -413.726982)
			(xy 189.946473 -413.674891) (xy 189.934347 -413.620454) (xy 189.930276 -413.564832) (xy 189.28551 -413.564832)
			(xy 189.282855 -413.568486) (xy 189.239098 -413.615083) (xy 189.189845 -413.655828) (xy 189.135874 -413.690079)
			(xy 189.078035 -413.717296) (xy 189.017242 -413.737049) (xy 188.954452 -413.749027) (xy 188.890656 -413.753041)
			(xy 188.82686 -413.749027) (xy 188.76407 -413.737049) (xy 188.703277 -413.717296) (xy 188.645438 -413.690079)
			(xy 188.591467 -413.655828) (xy 188.542214 -413.615083) (xy 188.498457 -413.568486) (xy 188.460884 -413.516771)
			(xy 188.43009 -413.460756) (xy 188.406558 -413.401323) (xy 188.390661 -413.339409) (xy 188.38265 -413.275991)
			(xy 188.382148 -413.24403) (xy 188.382605 -413.213385) (xy 188.389968 -413.152538) (xy 188.404591 -413.093017)
			(xy 188.426261 -413.035685) (xy 188.44006 -413.008318) (xy 188.446156 -412.996634) (xy 188.445394 -412.969964)
			(xy 188.393578 -412.884112) (xy 188.388733 -412.876818) (xy 188.375149 -412.86579) (xy 188.358641 -412.859989)
			(xy 188.34989 -412.859728) (xy 187.48502 -412.859728) (xy 187.476186 -412.860105) (xy 187.459555 -412.866073)
			(xy 187.452508 -412.871412) (xy 187.427029 -412.891917) (xy 187.371776 -412.926911) (xy 187.312493 -412.954535)
			(xy 187.250158 -412.974332) (xy 187.218066 -412.980632) (xy 187.210446 -412.981902) (xy 187.19673 -412.989268)
			(xy 186.35599 -413.830008) (xy 186.349135 -413.837403) (xy 186.341389 -413.856002) (xy 186.341004 -413.866076)
			(xy 186.341004 -415.597043) (xy 190.949574 -415.597043) (xy 190.949574 -415.533121) (xy 190.957585 -415.469703)
			(xy 190.973482 -415.407789) (xy 190.997014 -415.348356) (xy 191.027808 -415.292341) (xy 191.065381 -415.240626)
			(xy 191.109138 -415.194029) (xy 191.158391 -415.153284) (xy 191.212362 -415.119033) (xy 191.270201 -415.091816)
			(xy 191.330994 -415.072063) (xy 191.393784 -415.060085) (xy 191.45758 -415.056072) (xy 191.521376 -415.060085)
			(xy 191.584166 -415.072063) (xy 191.644959 -415.091816) (xy 191.702798 -415.119033) (xy 191.756769 -415.153284)
			(xy 191.806022 -415.194029) (xy 191.849779 -415.240626) (xy 191.887352 -415.292341) (xy 191.918146 -415.348356)
			(xy 191.941678 -415.407789) (xy 191.957575 -415.469703) (xy 191.965586 -415.533121) (xy 191.966088 -415.565082)
			(xy 191.965586 -415.597043) (xy 191.957575 -415.660461) (xy 191.941678 -415.722375) (xy 191.918146 -415.781808)
			(xy 191.887352 -415.837823) (xy 191.849779 -415.889538) (xy 191.806022 -415.936135) (xy 191.756769 -415.97688)
			(xy 191.702798 -416.011131) (xy 191.644959 -416.038348) (xy 191.584166 -416.058101) (xy 191.521376 -416.070079)
			(xy 191.45758 -416.074093) (xy 191.393784 -416.070079) (xy 191.330994 -416.058101) (xy 191.270201 -416.038348)
			(xy 191.212362 -416.011131) (xy 191.158391 -415.97688) (xy 191.109138 -415.936135) (xy 191.065381 -415.889538)
			(xy 191.027808 -415.837823) (xy 190.997014 -415.781808) (xy 190.973482 -415.722375) (xy 190.957585 -415.660461)
			(xy 190.949574 -415.597043) (xy 186.341004 -415.597043) (xy 186.341004 -416.162236) (xy 193.041522 -416.162236)
			(xy 193.045593 -416.106614) (xy 193.057719 -416.052177) (xy 193.077642 -416.000086) (xy 193.104938 -415.951451)
			(xy 193.139024 -415.907308) (xy 193.179173 -415.868599) (xy 193.224531 -415.836148) (xy 193.274131 -415.810647)
			(xy 193.326915 -415.79264) (xy 193.381758 -415.78251) (xy 193.437492 -415.780473) (xy 193.492929 -415.786573)
			(xy 193.546886 -415.800679) (xy 193.598215 -415.822491) (xy 193.645821 -415.851545) (xy 193.688689 -415.88722)
			(xy 193.725906 -415.928757) (xy 193.756679 -415.97527) (xy 193.780351 -416.025767) (xy 193.796419 -416.079174)
			(xy 193.804539 -416.13435) (xy 193.805048 -416.162236) (xy 193.804539 -416.190122) (xy 193.796419 -416.245298)
			(xy 193.780351 -416.298705) (xy 193.756679 -416.349202) (xy 193.725906 -416.395715) (xy 193.688689 -416.437252)
			(xy 193.645821 -416.472927) (xy 193.598215 -416.501981) (xy 193.546886 -416.523793) (xy 193.492929 -416.537899)
			(xy 193.437492 -416.543999) (xy 193.381758 -416.541962) (xy 193.326915 -416.531832) (xy 193.274131 -416.513825)
			(xy 193.224531 -416.488324) (xy 193.179173 -416.455873) (xy 193.139024 -416.417164) (xy 193.104938 -416.373021)
			(xy 193.077642 -416.324386) (xy 193.057719 -416.272295) (xy 193.045593 -416.217858) (xy 193.041522 -416.162236)
			(xy 186.341004 -416.162236) (xy 186.341004 -416.780218) (xy 186.340577 -416.790287) (xy 186.332859 -416.808887)
			(xy 186.326018 -416.816286) (xy 185.7375 -417.404804) (xy 188.349888 -417.404804) (xy 188.353959 -417.349182)
			(xy 188.366085 -417.294745) (xy 188.386008 -417.242654) (xy 188.413304 -417.194019) (xy 188.44739 -417.149876)
			(xy 188.487539 -417.111167) (xy 188.532897 -417.078716) (xy 188.582497 -417.053215) (xy 188.635281 -417.035208)
			(xy 188.690124 -417.025078) (xy 188.745858 -417.023041) (xy 188.801295 -417.029141) (xy 188.855252 -417.043247)
			(xy 188.906581 -417.065059) (xy 188.954187 -417.094113) (xy 188.997055 -417.129788) (xy 189.034272 -417.171325)
			(xy 189.065045 -417.217838) (xy 189.088717 -417.268335) (xy 189.104785 -417.321742) (xy 189.112905 -417.376918)
			(xy 189.113414 -417.404804) (xy 189.112905 -417.43269) (xy 189.104785 -417.487866) (xy 189.088717 -417.541273)
			(xy 189.065045 -417.59177) (xy 189.034272 -417.638283) (xy 188.997055 -417.67982) (xy 188.954187 -417.715495)
			(xy 188.906581 -417.744549) (xy 188.855252 -417.766361) (xy 188.801295 -417.780467) (xy 188.745858 -417.786567)
			(xy 188.690124 -417.78453) (xy 188.635281 -417.7744) (xy 188.582497 -417.756393) (xy 188.532897 -417.730892)
			(xy 188.487539 -417.698441) (xy 188.44739 -417.659732) (xy 188.413304 -417.615589) (xy 188.386008 -417.566954)
			(xy 188.366085 -417.514863) (xy 188.353959 -417.460426) (xy 188.349888 -417.404804) (xy 185.7375 -417.404804)
			(xy 184.743852 -418.398452) (xy 184.736453 -418.405296) (xy 184.717854 -418.413021) (xy 184.707784 -418.413438)
			(xy 180.91404 -418.413438) (xy 180.903975 -418.413873) (xy 180.88539 -418.421607) (xy 180.877972 -418.428424)
			(xy 180.577996 -418.7284) (xy 186.344087 -418.7284) (xy 186.348101 -418.664606) (xy 186.360078 -418.601819)
			(xy 186.379829 -418.541027) (xy 186.407044 -418.48319) (xy 186.441293 -418.42922) (xy 186.482035 -418.379968)
			(xy 186.528629 -418.336211) (xy 186.58034 -418.298638) (xy 186.636352 -418.267842) (xy 186.695782 -418.244308)
			(xy 186.757693 -418.228409) (xy 186.821108 -418.220394) (xy 186.853068 -418.21989) (xy 186.884149 -418.220365)
			(xy 186.945846 -418.227949) (xy 187.00616 -418.242996) (xy 187.064189 -418.265282) (xy 187.11907 -418.294475)
			(xy 187.169985 -418.330138) (xy 187.216172 -418.37174) (xy 187.256946 -418.418662) (xy 187.274708 -418.444172)
			(xy 187.282836 -418.45611) (xy 187.30849 -418.468048) (xy 187.4266 -418.454332) (xy 187.448952 -418.436806)
			(xy 187.454032 -418.423344) (xy 187.465311 -418.394753) (xy 187.493888 -418.340335) (xy 187.528815 -418.289757)
			(xy 187.569583 -418.243757) (xy 187.615597 -418.203005) (xy 187.666187 -418.168096) (xy 187.720615 -418.139538)
			(xy 187.778089 -418.117748) (xy 187.837769 -418.103043) (xy 187.898787 -418.095638) (xy 187.92952 -418.095176)
			(xy 187.96337 -418.095719) (xy 188.030471 -418.104694) (xy 188.095787 -418.122497) (xy 188.158162 -418.148812)
			(xy 188.216493 -418.183173) (xy 188.243464 -418.203634) (xy 188.250582 -418.208768) (xy 188.267203 -418.214361)
			(xy 188.275976 -418.214556) (xy 188.305948 -418.213794) (xy 188.314694 -418.213243) (xy 188.33106 -418.207014)
			(xy 188.337952 -418.201602) (xy 188.361037 -418.182328) (xy 188.410971 -418.148809) (xy 188.46451 -418.121416)
			(xy 188.520908 -418.100531) (xy 188.579376 -418.086446) (xy 188.639098 -418.079358) (xy 188.669168 -418.07892)
			(xy 188.701133 -418.079343) (xy 188.764561 -418.087352) (xy 188.826484 -418.103248) (xy 188.885926 -418.126779)
			(xy 188.94195 -418.157576) (xy 188.993673 -418.195151) (xy 189.040278 -418.238914) (xy 189.08103 -418.288172)
			(xy 189.115287 -418.34215) (xy 189.142509 -418.399996) (xy 189.162265 -418.460797) (xy 189.174245 -418.523595)
			(xy 189.17826 -418.5874) (xy 189.174245 -418.651205) (xy 189.162265 -418.714003) (xy 189.142509 -418.774804)
			(xy 189.115287 -418.83265) (xy 189.08103 -418.886628) (xy 189.040278 -418.935886) (xy 188.993673 -418.979649)
			(xy 188.94195 -419.017224) (xy 188.885926 -419.048021) (xy 188.826484 -419.071552) (xy 188.764561 -419.087448)
			(xy 188.701133 -419.095457) (xy 188.669168 -419.095936) (xy 188.635318 -419.095397) (xy 188.568217 -419.086421)
			(xy 188.502901 -419.068617) (xy 188.440526 -419.042301) (xy 188.382195 -419.007939) (xy 188.355224 -418.987478)
			(xy 188.348108 -418.98234) (xy 188.331486 -418.976749) (xy 188.322712 -418.976556) (xy 188.29274 -418.977318)
			(xy 188.283993 -418.97786) (xy 188.267627 -418.984095) (xy 188.260736 -418.98951) (xy 188.237619 -419.008744)
			(xy 188.187693 -419.042267) (xy 188.13416 -419.069666) (xy 188.077768 -419.090558) (xy 188.019305 -419.104651)
			(xy 187.959589 -419.111749) (xy 187.92952 -419.112192) (xy 187.898438 -419.111734) (xy 187.83674 -419.104148)
			(xy 187.776426 -419.089099) (xy 187.718396 -419.066811) (xy 187.663515 -419.037616) (xy 187.612601 -419.00195)
			(xy 187.566414 -418.960345) (xy 187.525642 -418.913421) (xy 187.50788 -418.88791) (xy 187.499752 -418.875972)
			(xy 187.474098 -418.864034) (xy 187.355988 -418.87775) (xy 187.333636 -418.895276) (xy 187.328556 -418.908738)
			(xy 187.317193 -418.937294) (xy 187.288624 -418.99171) (xy 187.253707 -419.042286) (xy 187.212949 -419.088287)
			(xy 187.166944 -419.12904) (xy 187.116364 -419.163952) (xy 187.061945 -419.192515) (xy 187.00448 -419.214311)
			(xy 186.944808 -419.229024) (xy 186.883798 -419.236439) (xy 186.853068 -419.236906) (xy 186.821108 -419.236406)
			(xy 186.757693 -419.228391) (xy 186.695782 -419.212492) (xy 186.636352 -419.188958) (xy 186.58034 -419.158162)
			(xy 186.528629 -419.120589) (xy 186.482035 -419.076832) (xy 186.441293 -419.02758) (xy 186.407044 -418.97361)
			(xy 186.379829 -418.915773) (xy 186.360078 -418.854981) (xy 186.348101 -418.792194) (xy 186.344087 -418.7284)
			(xy 180.577996 -418.7284) (xy 179.44719 -419.859206) (xy 179.439354 -419.867876) (xy 179.431817 -419.889971)
			(xy 179.432712 -419.901624) (xy 179.44465 -419.993572) (xy 179.457604 -420.012876) (xy 179.468018 -420.018972)
			(xy 179.492443 -420.033717) (xy 179.53702 -420.06932) (xy 179.575801 -420.111163) (xy 179.607921 -420.158313)
			(xy 179.632664 -420.209718) (xy 179.649479 -420.264235) (xy 179.657991 -420.320647) (xy 179.658518 -420.349172)
			(xy 179.658127 -420.373314) (xy 179.652007 -420.421209) (xy 179.646326 -420.444676) (xy 179.643278 -420.45636)
			(xy 179.648104 -420.47922) (xy 179.704492 -420.552118) (xy 179.712084 -420.560943) (xy 179.732994 -420.571117)
			(xy 179.744624 -420.571676) (xy 179.813458 -420.571676) (xy 179.825082 -420.571107) (xy 179.845981 -420.560923)
			(xy 179.85359 -420.552118) (xy 179.910232 -420.479474) (xy 179.915058 -420.456868) (xy 179.91201 -420.445184)
			(xy 179.906545 -420.422139) (xy 179.900691 -420.375139) (xy 179.900326 -420.351458) (xy 179.900812 -420.324207)
			(xy 179.908568 -420.270259) (xy 179.923923 -420.217964) (xy 179.946565 -420.168387) (xy 179.976031 -420.122537)
			(xy 180.011722 -420.081346) (xy 180.052913 -420.045655) (xy 180.098763 -420.016189) (xy 180.14834 -419.993547)
			(xy 180.200635 -419.978192) (xy 180.254583 -419.970436) (xy 180.309085 -419.970436) (xy 180.363033 -419.978192)
			(xy 180.415328 -419.993547) (xy 180.464905 -420.016189) (xy 180.510755 -420.045655) (xy 180.551946 -420.081346)
			(xy 180.587637 -420.122537) (xy 180.617103 -420.168387) (xy 180.639745 -420.217964) (xy 180.6551 -420.270259)
			(xy 180.662856 -420.324207) (xy 180.663342 -420.351458) (xy 180.662988 -420.37514) (xy 180.657133 -420.422141)
			(xy 180.651658 -420.445184) (xy 180.64861 -420.456868) (xy 180.653436 -420.479474) (xy 180.710078 -420.552118)
			(xy 180.717669 -420.560945) (xy 180.738579 -420.571125) (xy 180.75021 -420.571676) (xy 181.840378 -420.571676)
			(xy 181.851999 -420.571103) (xy 181.872892 -420.560914) (xy 181.88051 -420.552118) (xy 181.936898 -420.47922)
			(xy 181.941724 -420.45636) (xy 181.938676 -420.44493) (xy 181.933063 -420.421584) (xy 181.927072 -420.373943)
			(xy 181.926738 -420.349934) (xy 181.927224 -420.322683) (xy 181.93498 -420.268735) (xy 181.950335 -420.21644)
			(xy 181.972977 -420.166863) (xy 182.002443 -420.121013) (xy 182.038134 -420.079822) (xy 182.079325 -420.044131)
			(xy 182.125175 -420.014665) (xy 182.174752 -419.992023) (xy 182.227047 -419.976668) (xy 182.280995 -419.968912)
			(xy 182.335497 -419.968912) (xy 182.389445 -419.976668) (xy 182.44174 -419.992023) (xy 182.491317 -420.014665)
			(xy 182.537167 -420.044131) (xy 182.578358 -420.079822) (xy 182.614049 -420.121013) (xy 182.643515 -420.166863)
			(xy 182.666157 -420.21644) (xy 182.681512 -420.268735) (xy 182.689268 -420.322683) (xy 182.689754 -420.349934)
			(xy 182.689255 -420.377643) (xy 182.681231 -420.432476) (xy 182.665357 -420.485571) (xy 182.641967 -420.53581)
			(xy 182.611554 -420.582136) (xy 182.574757 -420.623573) (xy 182.553864 -420.64178) (xy 182.545736 -420.648892)
			(xy 182.536338 -420.667434) (xy 182.532782 -420.753286) (xy 182.532832 -420.763851) (xy 182.540447 -420.783532)
			(xy 182.547514 -420.791386) (xy 182.828946 -421.072564) (xy 182.83616 -421.079202) (xy 182.854161 -421.086922)
			(xy 182.873743 -421.08733) (xy 182.883048 -421.084248) (xy 182.983886 -421.04564) (xy 183.001412 -421.02151)
			(xy 183.002174 -421.006524) (xy 183.004432 -420.974472) (xy 183.016022 -420.911272) (xy 183.035481 -420.850035)
			(xy 183.0625 -420.791737) (xy 183.096648 -420.737307) (xy 183.13738 -420.687614) (xy 183.184049 -420.643447)
			(xy 183.23591 -420.605512) (xy 183.292137 -420.574413) (xy 183.351834 -420.550644) (xy 183.41405 -420.534586)
			(xy 183.477793 -420.526494) (xy 183.50992 -420.525956) (xy 183.542103 -420.526446) (xy 183.605956 -420.534561)
			(xy 183.668273 -420.550672) (xy 183.728058 -420.574521) (xy 183.784354 -420.605726) (xy 183.836261 -420.643788)
			(xy 183.882948 -420.688098) (xy 183.923667 -420.737947) (xy 183.957769 -420.792537) (xy 183.984706 -420.850996)
			(xy 183.994806 -420.881556) (xy 183.999124 -420.895272) (xy 184.020714 -420.914068) (xy 184.13857 -420.933626)
			(xy 184.164986 -420.922958) (xy 184.173622 -420.911274) (xy 184.19174 -420.887656) (xy 184.234067 -420.845809)
			(xy 184.282378 -420.81104) (xy 184.335502 -420.784194) (xy 184.39215 -420.765922) (xy 184.450947 -420.756667)
			(xy 184.480708 -420.75608) (xy 184.50796 -420.756566) (xy 184.561908 -420.764324) (xy 184.614204 -420.77968)
			(xy 184.663782 -420.802323) (xy 184.709632 -420.83179) (xy 184.750823 -420.867483) (xy 184.786515 -420.908674)
			(xy 184.815981 -420.954526) (xy 184.838622 -421.004104) (xy 184.853978 -421.0564) (xy 184.861734 -421.110348)
			(xy 184.861734 -421.1447) (xy 185.11469 -421.1447) (xy 185.118761 -421.089078) (xy 185.130887 -421.034641)
			(xy 185.15081 -420.98255) (xy 185.178106 -420.933915) (xy 185.212192 -420.889772) (xy 185.252341 -420.851063)
			(xy 185.297699 -420.818612) (xy 185.347299 -420.793111) (xy 185.400083 -420.775104) (xy 185.454926 -420.764974)
			(xy 185.51066 -420.762937) (xy 185.566097 -420.769037) (xy 185.620054 -420.783143) (xy 185.671383 -420.804955)
			(xy 185.718989 -420.834009) (xy 185.761857 -420.869684) (xy 185.799074 -420.911221) (xy 185.829847 -420.957734)
			(xy 185.853519 -421.008231) (xy 185.869587 -421.061638) (xy 185.873438 -421.087804) (xy 186.288932 -421.087804)
			(xy 186.293003 -421.032182) (xy 186.305129 -420.977745) (xy 186.325052 -420.925654) (xy 186.352348 -420.877019)
			(xy 186.386434 -420.832876) (xy 186.426583 -420.794167) (xy 186.471941 -420.761716) (xy 186.521541 -420.736215)
			(xy 186.574325 -420.718208) (xy 186.629168 -420.708078) (xy 186.684902 -420.706041) (xy 186.740339 -420.712141)
			(xy 186.794296 -420.726247) (xy 186.845625 -420.748059) (xy 186.893231 -420.777113) (xy 186.936099 -420.812788)
			(xy 186.973316 -420.854325) (xy 187.004089 -420.900838) (xy 187.027761 -420.951335) (xy 187.030686 -420.961058)
			(xy 188.527942 -420.961058) (xy 188.532013 -420.905436) (xy 188.544139 -420.850999) (xy 188.564062 -420.798908)
			(xy 188.591358 -420.750273) (xy 188.625444 -420.70613) (xy 188.665593 -420.667421) (xy 188.710951 -420.63497)
			(xy 188.760551 -420.609469) (xy 188.813335 -420.591462) (xy 188.868178 -420.581332) (xy 188.923912 -420.579295)
			(xy 188.979349 -420.585395) (xy 189.033306 -420.599501) (xy 189.084635 -420.621313) (xy 189.132241 -420.650367)
			(xy 189.175109 -420.686042) (xy 189.212326 -420.727579) (xy 189.243099 -420.774092) (xy 189.266771 -420.824589)
			(xy 189.282839 -420.877996) (xy 189.290959 -420.933172) (xy 189.291468 -420.961058) (xy 189.290959 -420.988944)
			(xy 189.282839 -421.04412) (xy 189.266771 -421.097527) (xy 189.243099 -421.148024) (xy 189.212326 -421.194537)
			(xy 189.175109 -421.236074) (xy 189.132241 -421.271749) (xy 189.084635 -421.300803) (xy 189.033306 -421.322615)
			(xy 188.979349 -421.336721) (xy 188.923912 -421.342821) (xy 188.868178 -421.340784) (xy 188.813335 -421.330654)
			(xy 188.760551 -421.312647) (xy 188.710951 -421.287146) (xy 188.665593 -421.254695) (xy 188.625444 -421.215986)
			(xy 188.591358 -421.171843) (xy 188.564062 -421.123208) (xy 188.544139 -421.071117) (xy 188.532013 -421.01668)
			(xy 188.527942 -420.961058) (xy 187.030686 -420.961058) (xy 187.043829 -421.004742) (xy 187.051949 -421.059918)
			(xy 187.052458 -421.087804) (xy 187.051949 -421.11569) (xy 187.043829 -421.170866) (xy 187.027761 -421.224273)
			(xy 187.004089 -421.27477) (xy 186.973316 -421.321283) (xy 186.936099 -421.36282) (xy 186.893231 -421.398495)
			(xy 186.847947 -421.426132) (xy 190.504316 -421.426132) (xy 190.508387 -421.37051) (xy 190.520513 -421.316073)
			(xy 190.540436 -421.263982) (xy 190.567732 -421.215347) (xy 190.601818 -421.171204) (xy 190.641967 -421.132495)
			(xy 190.687325 -421.100044) (xy 190.736925 -421.074543) (xy 190.789709 -421.056536) (xy 190.844552 -421.046406)
			(xy 190.900286 -421.044369) (xy 190.955723 -421.050469) (xy 191.00968 -421.064575) (xy 191.061009 -421.086387)
			(xy 191.108615 -421.115441) (xy 191.151483 -421.151116) (xy 191.1887 -421.192653) (xy 191.219473 -421.239166)
			(xy 191.243145 -421.289663) (xy 191.259213 -421.34307) (xy 191.267333 -421.398246) (xy 191.267842 -421.426132)
			(xy 191.267333 -421.454018) (xy 191.259213 -421.509194) (xy 191.243145 -421.562601) (xy 191.219473 -421.613098)
			(xy 191.1887 -421.659611) (xy 191.151483 -421.701148) (xy 191.108615 -421.736823) (xy 191.061009 -421.765877)
			(xy 191.00968 -421.787689) (xy 190.955723 -421.801795) (xy 190.900286 -421.807895) (xy 190.844552 -421.805858)
			(xy 190.789709 -421.795728) (xy 190.736925 -421.777721) (xy 190.687325 -421.75222) (xy 190.641967 -421.719769)
			(xy 190.601818 -421.68106) (xy 190.567732 -421.636917) (xy 190.540436 -421.588282) (xy 190.520513 -421.536191)
			(xy 190.508387 -421.481754) (xy 190.504316 -421.426132) (xy 186.847947 -421.426132) (xy 186.845625 -421.427549)
			(xy 186.794296 -421.449361) (xy 186.740339 -421.463467) (xy 186.684902 -421.469567) (xy 186.629168 -421.46753)
			(xy 186.574325 -421.4574) (xy 186.521541 -421.439393) (xy 186.471941 -421.413892) (xy 186.426583 -421.381441)
			(xy 186.386434 -421.342732) (xy 186.352348 -421.298589) (xy 186.325052 -421.249954) (xy 186.305129 -421.197863)
			(xy 186.293003 -421.143426) (xy 186.288932 -421.087804) (xy 185.873438 -421.087804) (xy 185.877707 -421.116814)
			(xy 185.878216 -421.1447) (xy 185.877707 -421.172586) (xy 185.869587 -421.227762) (xy 185.853519 -421.281169)
			(xy 185.829847 -421.331666) (xy 185.799074 -421.378179) (xy 185.761857 -421.419716) (xy 185.718989 -421.455391)
			(xy 185.671383 -421.484445) (xy 185.620054 -421.506257) (xy 185.566097 -421.520363) (xy 185.51066 -421.526463)
			(xy 185.454926 -421.524426) (xy 185.400083 -421.514296) (xy 185.347299 -421.496289) (xy 185.297699 -421.470788)
			(xy 185.252341 -421.438337) (xy 185.212192 -421.399628) (xy 185.178106 -421.355485) (xy 185.15081 -421.30685)
			(xy 185.130887 -421.254759) (xy 185.118761 -421.200322) (xy 185.11469 -421.1447) (xy 184.861734 -421.1447)
			(xy 184.861734 -421.164852) (xy 184.853978 -421.2188) (xy 184.838622 -421.271096) (xy 184.815981 -421.320674)
			(xy 184.786515 -421.366526) (xy 184.750823 -421.407717) (xy 184.709632 -421.44341) (xy 184.663782 -421.472877)
			(xy 184.614204 -421.49552) (xy 184.561908 -421.510876) (xy 184.50796 -421.518634) (xy 184.480708 -421.519096)
			(xy 184.453342 -421.518618) (xy 184.399174 -421.510781) (xy 184.346682 -421.495281) (xy 184.296945 -421.472438)
			(xy 184.250984 -421.442719) (xy 184.209743 -421.406736) (xy 184.174069 -421.365226) (xy 184.144695 -421.319044)
			(xy 184.132982 -421.294306) (xy 184.126886 -421.281098) (xy 184.103264 -421.265096) (xy 183.984138 -421.259508)
			(xy 183.958992 -421.273224) (xy 183.95188 -421.285924) (xy 183.935757 -421.313276) (xy 183.897734 -421.364124)
			(xy 183.853678 -421.409845) (xy 183.804274 -421.449726) (xy 183.75029 -421.483149) (xy 183.692566 -421.509592)
			(xy 183.632 -421.528645) (xy 183.569533 -421.540011) (xy 183.53786 -421.54221) (xy 183.522874 -421.542972)
			(xy 183.498744 -421.560498) (xy 183.460136 -421.661336) (xy 183.457074 -421.670647) (xy 183.457476 -421.690227)
			(xy 183.465176 -421.708233) (xy 183.47182 -421.715438) (xy 183.560466 -421.804084) (xy 183.577539 -421.821787)
			(xy 183.606462 -421.861563) (xy 183.628797 -421.905379) (xy 183.643995 -421.952152) (xy 183.651679 -422.000728)
			(xy 183.65216 -422.025318) (xy 183.65216 -422.48836) (xy 183.652644 -422.498324) (xy 183.660226 -422.516753)
			(xy 183.666892 -422.524174) (xy 184.989975 -423.847355) (xy 190.380537 -423.847355) (xy 190.380537 -423.792845)
			(xy 190.388295 -423.73889) (xy 190.403653 -423.686588) (xy 190.426298 -423.637004) (xy 190.455769 -423.591147)
			(xy 190.491466 -423.549952) (xy 190.532664 -423.514257) (xy 190.578521 -423.484788) (xy 190.628106 -423.462146)
			(xy 190.680409 -423.446791) (xy 190.734365 -423.439036) (xy 190.76162 -423.438574) (xy 190.790085 -423.439068)
			(xy 190.846385 -423.447525) (xy 190.900804 -423.46425) (xy 190.952136 -423.488871) (xy 190.999242 -423.520841)
			(xy 191.041078 -423.559453) (xy 191.059308 -423.581322) (xy 191.065658 -423.58945) (xy 191.083438 -423.599102)
			(xy 191.175386 -423.608754) (xy 191.19469 -423.603166) (xy 191.202564 -423.596562) (xy 191.229885 -423.575066)
			(xy 191.289277 -423.538935) (xy 191.353041 -423.51124) (xy 191.419985 -423.4925) (xy 191.48886 -423.483063)
			(xy 191.52362 -423.482516) (xy 191.554353 -423.482919) (xy 191.615372 -423.49033) (xy 191.675052 -423.505043)
			(xy 191.732524 -423.526842) (xy 191.786949 -423.555409) (xy 191.837534 -423.590328) (xy 191.883541 -423.63109)
			(xy 191.924299 -423.677101) (xy 191.959214 -423.727689) (xy 191.987776 -423.782116) (xy 192.002173 -423.820082)
			(xy 193.173602 -423.820082) (xy 193.177673 -423.76446) (xy 193.189799 -423.710023) (xy 193.209722 -423.657932)
			(xy 193.237018 -423.609297) (xy 193.271104 -423.565154) (xy 193.311253 -423.526445) (xy 193.356611 -423.493994)
			(xy 193.406211 -423.468493) (xy 193.458995 -423.450486) (xy 193.513838 -423.440356) (xy 193.569572 -423.438319)
			(xy 193.625009 -423.444419) (xy 193.678966 -423.458525) (xy 193.730295 -423.480337) (xy 193.777901 -423.509391)
			(xy 193.820769 -423.545066) (xy 193.857986 -423.586603) (xy 193.888759 -423.633116) (xy 193.912431 -423.683613)
			(xy 193.928499 -423.73702) (xy 193.936619 -423.792196) (xy 193.937128 -423.820082) (xy 193.936619 -423.847968)
			(xy 193.928499 -423.903144) (xy 193.912431 -423.956551) (xy 193.888759 -424.007048) (xy 193.857986 -424.053561)
			(xy 193.820769 -424.095098) (xy 193.777901 -424.130773) (xy 193.730295 -424.159827) (xy 193.678966 -424.181639)
			(xy 193.625009 -424.195745) (xy 193.569572 -424.201845) (xy 193.513838 -424.199808) (xy 193.458995 -424.189678)
			(xy 193.406211 -424.171671) (xy 193.356611 -424.14617) (xy 193.311253 -424.113719) (xy 193.271104 -424.07501)
			(xy 193.237018 -424.030867) (xy 193.209722 -423.982232) (xy 193.189799 -423.930141) (xy 193.177673 -423.875704)
			(xy 193.173602 -423.820082) (xy 192.002173 -423.820082) (xy 192.00957 -423.83959) (xy 192.024278 -423.899271)
			(xy 192.031684 -423.960291) (xy 192.032128 -423.991024) (xy 192.031706 -424.020827) (xy 192.024726 -424.080023)
			(xy 192.010876 -424.137998) (xy 191.990346 -424.193958) (xy 191.963417 -424.247134) (xy 191.947292 -424.272202)
			(xy 191.940688 -424.282108) (xy 191.93764 -424.305222) (xy 191.970914 -424.404028) (xy 191.987424 -424.420538)
			(xy 191.9986 -424.424348) (xy 192.023261 -424.433298) (xy 192.070009 -424.457111) (xy 192.113053 -424.487106)
			(xy 192.15158 -424.522718) (xy 192.184862 -424.563273) (xy 192.212273 -424.608007) (xy 192.233294 -424.656076)
			(xy 192.247529 -424.706572) (xy 192.254709 -424.758542) (xy 192.25514 -424.784774) (xy 192.254654 -424.812025)
			(xy 192.246898 -424.865973) (xy 192.231543 -424.918268) (xy 192.208901 -424.967845) (xy 192.179435 -425.013695)
			(xy 192.143744 -425.054886) (xy 192.102553 -425.090577) (xy 192.056703 -425.120043) (xy 192.007126 -425.142685)
			(xy 191.954831 -425.15804) (xy 191.900883 -425.165796) (xy 191.846381 -425.165796) (xy 191.792433 -425.15804)
			(xy 191.740138 -425.142685) (xy 191.690561 -425.120043) (xy 191.644711 -425.090577) (xy 191.60352 -425.054886)
			(xy 191.567829 -425.013695) (xy 191.538363 -424.967845) (xy 191.515721 -424.918268) (xy 191.500366 -424.865973)
			(xy 191.49261 -424.812025) (xy 191.492124 -424.784774) (xy 191.492538 -424.758915) (xy 191.499488 -424.707666)
			(xy 191.513299 -424.657827) (xy 191.523112 -424.633898) (xy 191.527938 -424.622976) (xy 191.526668 -424.599862)
			(xy 191.476376 -424.508676) (xy 191.457326 -424.495214) (xy 191.445388 -424.493436) (xy 191.414971 -424.488306)
			(xy 191.355612 -424.471519) (xy 191.298721 -424.447672) (xy 191.245133 -424.417116) (xy 191.195637 -424.3803)
			(xy 191.15096 -424.337764) (xy 191.111759 -424.290134) (xy 191.078609 -424.238111) (xy 191.064896 -424.21048)
			(xy 191.060578 -424.201336) (xy 191.045592 -424.187874) (xy 190.957962 -424.157394) (xy 190.937896 -424.158664)
			(xy 190.928752 -424.162982) (xy 190.902589 -424.175155) (xy 190.847513 -424.192364) (xy 190.790471 -424.201063)
			(xy 190.76162 -424.20159) (xy 190.734365 -424.201164) (xy 190.680409 -424.193409) (xy 190.628106 -424.178054)
			(xy 190.578521 -424.155412) (xy 190.532664 -424.125943) (xy 190.491466 -424.090248) (xy 190.455769 -424.049053)
			(xy 190.426298 -424.003196) (xy 190.403653 -423.953612) (xy 190.388295 -423.90131) (xy 190.380537 -423.847355)
			(xy 184.989975 -423.847355) (xy 186.566298 -425.423795) (xy 189.54851 -425.423795) (xy 189.54851 -425.359873)
			(xy 189.556521 -425.296455) (xy 189.572418 -425.234541) (xy 189.59595 -425.175108) (xy 189.626744 -425.119093)
			(xy 189.664317 -425.067378) (xy 189.708074 -425.020781) (xy 189.757327 -424.980036) (xy 189.811298 -424.945785)
			(xy 189.869137 -424.918568) (xy 189.92993 -424.898815) (xy 189.99272 -424.886837) (xy 190.056516 -424.882824)
			(xy 190.120312 -424.886837) (xy 190.183102 -424.898815) (xy 190.243895 -424.918568) (xy 190.301734 -424.945785)
			(xy 190.355705 -424.980036) (xy 190.404958 -425.020781) (xy 190.448715 -425.067378) (xy 190.486288 -425.119093)
			(xy 190.517082 -425.175108) (xy 190.540614 -425.234541) (xy 190.556511 -425.296455) (xy 190.564522 -425.359873)
			(xy 190.565024 -425.391834) (xy 190.564522 -425.423795) (xy 190.556511 -425.487213) (xy 190.540614 -425.549127)
			(xy 190.517082 -425.60856) (xy 190.486288 -425.664575) (xy 190.448715 -425.71629) (xy 190.404958 -425.762887)
			(xy 190.355705 -425.803632) (xy 190.301734 -425.837883) (xy 190.243895 -425.8651) (xy 190.183102 -425.884853)
			(xy 190.120312 -425.896831) (xy 190.056516 -425.900845) (xy 189.99272 -425.896831) (xy 189.92993 -425.884853)
			(xy 189.869137 -425.8651) (xy 189.811298 -425.837883) (xy 189.757327 -425.803632) (xy 189.708074 -425.762887)
			(xy 189.664317 -425.71629) (xy 189.626744 -425.664575) (xy 189.59595 -425.60856) (xy 189.572418 -425.549127)
			(xy 189.556521 -425.487213) (xy 189.54851 -425.423795) (xy 186.566298 -425.423795) (xy 187.09894 -425.956476)
			(xy 187.106907 -425.963606) (xy 187.126857 -425.971219) (xy 187.137548 -425.971208) (xy 187.223908 -425.966636)
			(xy 187.242704 -425.956984) (xy 187.249816 -425.948602) (xy 187.268023 -425.926959) (xy 187.309737 -425.888767)
			(xy 187.356633 -425.857153) (xy 187.407683 -425.832811) (xy 187.461768 -425.816274) (xy 187.517702 -425.807905)
			(xy 187.54598 -425.807378) (xy 187.573235 -425.80784) (xy 187.62719 -425.815594) (xy 187.679492 -425.830949)
			(xy 187.729077 -425.853592) (xy 187.774934 -425.88306) (xy 187.816131 -425.918755) (xy 187.851828 -425.95995)
			(xy 187.881299 -426.005806) (xy 187.903944 -426.055389) (xy 187.919301 -426.10769) (xy 187.927059 -426.161645)
			(xy 187.927059 -426.216155) (xy 187.919301 -426.27011) (xy 187.903944 -426.322411) (xy 187.881299 -426.371994)
			(xy 187.851828 -426.41785) (xy 187.816131 -426.459045) (xy 187.774934 -426.49474) (xy 187.729077 -426.524208)
			(xy 187.679492 -426.546851) (xy 187.62719 -426.562206) (xy 187.573235 -426.56996) (xy 187.54598 -426.570394)
			(xy 187.51169 -426.56887) (xy 187.501022 -426.567854) (xy 187.480956 -426.574712) (xy 187.462972 -426.591179)
			(xy 189.588896 -426.591179) (xy 189.588896 -426.527257) (xy 189.596907 -426.463839) (xy 189.612804 -426.401925)
			(xy 189.636336 -426.342492) (xy 189.66713 -426.286477) (xy 189.704703 -426.234762) (xy 189.74846 -426.188165)
			(xy 189.797713 -426.14742) (xy 189.851684 -426.113169) (xy 189.909523 -426.085952) (xy 189.970316 -426.066199)
			(xy 190.033106 -426.054221) (xy 190.096902 -426.050208) (xy 190.160698 -426.054221) (xy 190.223488 -426.066199)
			(xy 190.284281 -426.085952) (xy 190.34212 -426.113169) (xy 190.396091 -426.14742) (xy 190.445344 -426.188165)
			(xy 190.489101 -426.234762) (xy 190.526674 -426.286477) (xy 190.557468 -426.342492) (xy 190.581 -426.401925)
			(xy 190.596897 -426.463839) (xy 190.604908 -426.527257) (xy 190.60541 -426.559218) (xy 190.604908 -426.591179)
			(xy 190.596897 -426.654597) (xy 190.581 -426.716511) (xy 190.557468 -426.775944) (xy 190.526674 -426.831959)
			(xy 190.489101 -426.883674) (xy 190.445344 -426.930271) (xy 190.396091 -426.971016) (xy 190.34212 -427.005267)
			(xy 190.284281 -427.032484) (xy 190.223488 -427.052237) (xy 190.160698 -427.064215) (xy 190.096902 -427.068229)
			(xy 190.033106 -427.064215) (xy 189.970316 -427.052237) (xy 189.909523 -427.032484) (xy 189.851684 -427.005267)
			(xy 189.797713 -426.971016) (xy 189.74846 -426.930271) (xy 189.704703 -426.883674) (xy 189.66713 -426.831959)
			(xy 189.636336 -426.775944) (xy 189.612804 -426.716511) (xy 189.596907 -426.654597) (xy 189.588896 -426.591179)
			(xy 187.462972 -426.591179) (xy 187.41771 -426.632624) (xy 187.410313 -426.640147) (xy 187.401798 -426.659427)
			(xy 187.4012 -426.669962) (xy 187.4012 -427.150022) (xy 187.401678 -427.159988) (xy 187.409255 -427.178424)
			(xy 187.415932 -427.185836) (xy 188.078872 -427.848776) (xy 192.03746 -427.848776) (xy 192.041531 -427.793154)
			(xy 192.053657 -427.738717) (xy 192.07358 -427.686626) (xy 192.100876 -427.637991) (xy 192.134962 -427.593848)
			(xy 192.175111 -427.555139) (xy 192.220469 -427.522688) (xy 192.270069 -427.497187) (xy 192.322853 -427.47918)
			(xy 192.377696 -427.46905) (xy 192.43343 -427.467013) (xy 192.488867 -427.473113) (xy 192.542824 -427.487219)
			(xy 192.594153 -427.509031) (xy 192.641759 -427.538085) (xy 192.684627 -427.57376) (xy 192.721844 -427.615297)
			(xy 192.752617 -427.66181) (xy 192.776289 -427.712307) (xy 192.792357 -427.765714) (xy 192.800477 -427.82089)
			(xy 192.800986 -427.848776) (xy 192.800477 -427.876662) (xy 192.792357 -427.931838) (xy 192.776289 -427.985245)
			(xy 192.752617 -428.035742) (xy 192.721844 -428.082255) (xy 192.684627 -428.123792) (xy 192.641759 -428.159467)
			(xy 192.594153 -428.188521) (xy 192.542824 -428.210333) (xy 192.488867 -428.224439) (xy 192.43343 -428.230539)
			(xy 192.377696 -428.228502) (xy 192.322853 -428.218372) (xy 192.270069 -428.200365) (xy 192.220469 -428.174864)
			(xy 192.175111 -428.142413) (xy 192.134962 -428.103704) (xy 192.100876 -428.059561) (xy 192.07358 -428.010926)
			(xy 192.053657 -427.958835) (xy 192.041531 -427.904398) (xy 192.03746 -427.848776) (xy 188.078872 -427.848776)
			(xy 189.75324 -429.523144) (xy 189.773052 -429.530764) (xy 189.783974 -429.530256) (xy 189.811406 -429.529494)
			(xy 189.842137 -429.529958) (xy 189.90315 -429.537367) (xy 189.962825 -429.552077) (xy 189.985543 -429.560693)
			(xy 190.547492 -429.560693) (xy 190.547492 -429.496771) (xy 190.555503 -429.433353) (xy 190.5714 -429.371439)
			(xy 190.594932 -429.312006) (xy 190.625726 -429.255991) (xy 190.663299 -429.204276) (xy 190.707056 -429.157679)
			(xy 190.756309 -429.116934) (xy 190.81028 -429.082683) (xy 190.868119 -429.055466) (xy 190.928912 -429.035713)
			(xy 190.991702 -429.023735) (xy 191.055498 -429.019722) (xy 191.119294 -429.023735) (xy 191.182084 -429.035713)
			(xy 191.242877 -429.055466) (xy 191.300716 -429.082683) (xy 191.354687 -429.116934) (xy 191.40394 -429.157679)
			(xy 191.447697 -429.204276) (xy 191.48527 -429.255991) (xy 191.516064 -429.312006) (xy 191.539596 -429.371439)
			(xy 191.555493 -429.433353) (xy 191.563504 -429.496771) (xy 191.564006 -429.528732) (xy 191.563504 -429.560693)
			(xy 191.555493 -429.624111) (xy 191.539596 -429.686025) (xy 191.516064 -429.745458) (xy 191.48527 -429.801473)
			(xy 191.447697 -429.853188) (xy 191.40394 -429.899785) (xy 191.354687 -429.94053) (xy 191.300716 -429.974781)
			(xy 191.242877 -430.001998) (xy 191.182084 -430.021751) (xy 191.119294 -430.033729) (xy 191.055498 -430.037743)
			(xy 190.991702 -430.033729) (xy 190.928912 -430.021751) (xy 190.868119 -430.001998) (xy 190.81028 -429.974781)
			(xy 190.756309 -429.94053) (xy 190.707056 -429.899785) (xy 190.663299 -429.853188) (xy 190.625726 -429.801473)
			(xy 190.594932 -429.745458) (xy 190.5714 -429.686025) (xy 190.555503 -429.624111) (xy 190.547492 -429.560693)
			(xy 189.985543 -429.560693) (xy 190.020293 -429.573872) (xy 190.074714 -429.602435) (xy 190.125295 -429.637349)
			(xy 190.171299 -429.678106) (xy 190.212055 -429.724111) (xy 190.246969 -429.774693) (xy 190.275531 -429.829115)
			(xy 190.297326 -429.886582) (xy 190.312034 -429.946258) (xy 190.319442 -430.007271) (xy 190.319914 -430.038002)
			(xy 190.319403 -430.070435) (xy 190.311154 -430.134775) (xy 190.294789 -430.197543) (xy 190.270575 -430.257721)
			(xy 190.238905 -430.314331) (xy 190.200293 -430.366453) (xy 190.155366 -430.413242) (xy 190.13043 -430.433988)
			(xy 190.123586 -430.440044) (xy 190.114339 -430.455793) (xy 190.112396 -430.464722) (xy 190.107062 -430.494694)
			(xy 190.105893 -430.503763) (xy 190.109283 -430.52172) (xy 190.113666 -430.529746) (xy 190.13108 -430.559672)
			(xy 190.158539 -430.62323) (xy 190.177126 -430.689926) (xy 190.186496 -430.758525) (xy 190.187072 -430.793144)
			(xy 190.18657 -430.825105) (xy 190.178559 -430.888523) (xy 190.169538 -430.923657) (xy 191.810888 -430.923657)
			(xy 191.810888 -430.859735) (xy 191.818899 -430.796317) (xy 191.834796 -430.734403) (xy 191.858328 -430.67497)
			(xy 191.889122 -430.618955) (xy 191.926695 -430.56724) (xy 191.970452 -430.520643) (xy 192.019705 -430.479898)
			(xy 192.073676 -430.445647) (xy 192.131515 -430.41843) (xy 192.192308 -430.398677) (xy 192.255098 -430.386699)
			(xy 192.318894 -430.382686) (xy 192.38269 -430.386699) (xy 192.44548 -430.398677) (xy 192.506273 -430.41843)
			(xy 192.564112 -430.445647) (xy 192.618083 -430.479898) (xy 192.667336 -430.520643) (xy 192.711093 -430.56724)
			(xy 192.748666 -430.618955) (xy 192.77946 -430.67497) (xy 192.802992 -430.734403) (xy 192.818889 -430.796317)
			(xy 192.8269 -430.859735) (xy 192.827402 -430.891696) (xy 192.8269 -430.923657) (xy 192.818889 -430.987075)
			(xy 192.802992 -431.048989) (xy 192.77946 -431.108422) (xy 192.748666 -431.164437) (xy 192.711093 -431.216152)
			(xy 192.667336 -431.262749) (xy 192.618083 -431.303494) (xy 192.564112 -431.337745) (xy 192.506273 -431.364962)
			(xy 192.44548 -431.384715) (xy 192.38269 -431.396693) (xy 192.318894 -431.400707) (xy 192.255098 -431.396693)
			(xy 192.192308 -431.384715) (xy 192.131515 -431.364962) (xy 192.073676 -431.337745) (xy 192.019705 -431.303494)
			(xy 191.970452 -431.262749) (xy 191.926695 -431.216152) (xy 191.889122 -431.164437) (xy 191.858328 -431.108422)
			(xy 191.834796 -431.048989) (xy 191.818899 -430.987075) (xy 191.810888 -430.923657) (xy 190.169538 -430.923657)
			(xy 190.162662 -430.950437) (xy 190.13913 -431.00987) (xy 190.108336 -431.065885) (xy 190.070763 -431.1176)
			(xy 190.027006 -431.164197) (xy 189.977753 -431.204942) (xy 189.923782 -431.239193) (xy 189.865943 -431.26641)
			(xy 189.80515 -431.286163) (xy 189.74236 -431.298141) (xy 189.678564 -431.302155) (xy 189.614768 -431.298141)
			(xy 189.551978 -431.286163) (xy 189.491185 -431.26641) (xy 189.433346 -431.239193) (xy 189.379375 -431.204942)
			(xy 189.330122 -431.164197) (xy 189.286365 -431.1176) (xy 189.248792 -431.065885) (xy 189.217998 -431.00987)
			(xy 189.194466 -430.950437) (xy 189.178569 -430.888523) (xy 189.170558 -430.825105) (xy 189.170056 -430.793144)
			(xy 189.170564 -430.760709) (xy 189.178808 -430.696366) (xy 189.195167 -430.633593) (xy 189.219377 -430.57341)
			(xy 189.251043 -430.516795) (xy 189.289651 -430.464666) (xy 189.334576 -430.417871) (xy 189.35954 -430.397158)
			(xy 189.366381 -430.3911) (xy 189.375617 -430.37535) (xy 189.377574 -430.366424) (xy 189.382908 -430.336452)
			(xy 189.384086 -430.327381) (xy 189.380708 -430.309417) (xy 189.376304 -430.3014) (xy 189.358889 -430.271475)
			(xy 189.331425 -430.207917) (xy 189.312833 -430.141221) (xy 189.303458 -430.072621) (xy 189.302898 -430.038002)
			(xy 189.302965 -430.025153) (xy 189.304236 -429.999487) (xy 189.305438 -429.986694) (xy 189.306708 -429.97501)
			(xy 189.299088 -429.953928) (xy 186.867038 -427.521878) (xy 186.849961 -427.504177) (xy 186.82103 -427.464402)
			(xy 186.798686 -427.420587) (xy 186.783479 -427.373814) (xy 186.775785 -427.325236) (xy 186.775344 -427.300644)
			(xy 186.775344 -426.538644) (xy 186.774861 -426.52868) (xy 186.767281 -426.510249) (xy 186.760612 -426.50283)
			(xy 183.117998 -422.860216) (xy 183.10221 -422.843853) (xy 183.07505 -422.807386) (xy 183.063896 -422.787572)
			(xy 183.057292 -422.77538) (xy 183.033416 -422.760902) (xy 183.019192 -422.760902) (xy 183.009186 -422.761392)
			(xy 182.990697 -422.769053) (xy 182.976547 -422.783205) (xy 182.96889 -422.801695) (xy 182.968392 -422.811702)
			(xy 182.968392 -426.986446) (xy 182.968941 -426.99746) (xy 182.978171 -427.017463) (xy 182.986172 -427.025054)
			(xy 183.009707 -427.045785) (xy 183.052005 -427.092096) (xy 183.088286 -427.143258) (xy 183.117997 -427.198495)
			(xy 183.140688 -427.256967) (xy 183.156015 -427.317786) (xy 183.163744 -427.380028) (xy 183.164226 -427.411388)
			(xy 183.163777 -427.441885) (xy 183.158462 -427.486021) (xy 183.804046 -427.486021) (xy 183.804046 -427.422099)
			(xy 183.812057 -427.358681) (xy 183.827954 -427.296767) (xy 183.851486 -427.237334) (xy 183.88228 -427.181319)
			(xy 183.919853 -427.129604) (xy 183.96361 -427.083007) (xy 184.012863 -427.042262) (xy 184.066834 -427.008011)
			(xy 184.124673 -426.980794) (xy 184.185466 -426.961041) (xy 184.248256 -426.949063) (xy 184.312052 -426.94505)
			(xy 184.375848 -426.949063) (xy 184.438638 -426.961041) (xy 184.499431 -426.980794) (xy 184.55727 -427.008011)
			(xy 184.611241 -427.042262) (xy 184.660494 -427.083007) (xy 184.704251 -427.129604) (xy 184.741824 -427.181319)
			(xy 184.772618 -427.237334) (xy 184.79615 -427.296767) (xy 184.812047 -427.358681) (xy 184.820058 -427.422099)
			(xy 184.82056 -427.45406) (xy 184.820058 -427.486021) (xy 184.819673 -427.489069) (xy 185.000132 -427.489069)
			(xy 185.000132 -427.425147) (xy 185.008143 -427.361729) (xy 185.02404 -427.299815) (xy 185.047572 -427.240382)
			(xy 185.078366 -427.184367) (xy 185.115939 -427.132652) (xy 185.159696 -427.086055) (xy 185.208949 -427.04531)
			(xy 185.26292 -427.011059) (xy 185.320759 -426.983842) (xy 185.381552 -426.964089) (xy 185.444342 -426.952111)
			(xy 185.508138 -426.948098) (xy 185.571934 -426.952111) (xy 185.634724 -426.964089) (xy 185.695517 -426.983842)
			(xy 185.753356 -427.011059) (xy 185.807327 -427.04531) (xy 185.85658 -427.086055) (xy 185.900337 -427.132652)
			(xy 185.93791 -427.184367) (xy 185.968704 -427.240382) (xy 185.992236 -427.299815) (xy 186.008133 -427.361729)
			(xy 186.016144 -427.425147) (xy 186.016646 -427.457108) (xy 186.016144 -427.489069) (xy 186.008133 -427.552487)
			(xy 185.992236 -427.614401) (xy 185.968704 -427.673834) (xy 185.93791 -427.729849) (xy 185.900337 -427.781564)
			(xy 185.85658 -427.828161) (xy 185.807327 -427.868906) (xy 185.753356 -427.903157) (xy 185.695517 -427.930374)
			(xy 185.634724 -427.950127) (xy 185.571934 -427.962105) (xy 185.508138 -427.966119) (xy 185.444342 -427.962105)
			(xy 185.381552 -427.950127) (xy 185.320759 -427.930374) (xy 185.26292 -427.903157) (xy 185.208949 -427.868906)
			(xy 185.159696 -427.828161) (xy 185.115939 -427.781564) (xy 185.078366 -427.729849) (xy 185.047572 -427.673834)
			(xy 185.02404 -427.614401) (xy 185.008143 -427.552487) (xy 185.000132 -427.489069) (xy 184.819673 -427.489069)
			(xy 184.812047 -427.549439) (xy 184.79615 -427.611353) (xy 184.772618 -427.670786) (xy 184.741824 -427.726801)
			(xy 184.704251 -427.778516) (xy 184.660494 -427.825113) (xy 184.611241 -427.865858) (xy 184.55727 -427.900109)
			(xy 184.499431 -427.927326) (xy 184.438638 -427.947079) (xy 184.375848 -427.959057) (xy 184.312052 -427.963071)
			(xy 184.248256 -427.959057) (xy 184.185466 -427.947079) (xy 184.124673 -427.927326) (xy 184.066834 -427.900109)
			(xy 184.012863 -427.865858) (xy 183.96361 -427.825113) (xy 183.919853 -427.778516) (xy 183.88228 -427.726801)
			(xy 183.851486 -427.670786) (xy 183.827954 -427.611353) (xy 183.812057 -427.549439) (xy 183.804046 -427.486021)
			(xy 183.158462 -427.486021) (xy 183.156484 -427.502442) (xy 183.142001 -427.561692) (xy 183.120536 -427.618785)
			(xy 183.092396 -427.6729) (xy 183.057987 -427.723262) (xy 183.017802 -427.769148) (xy 182.972417 -427.809898)
			(xy 182.922485 -427.844928) (xy 182.868721 -427.873734) (xy 182.811899 -427.895904) (xy 182.782464 -427.903894)
			(xy 182.769002 -427.907196) (xy 182.749698 -427.9265) (xy 182.722774 -428.024798) (xy 182.720789 -428.033517)
			(xy 182.722348 -428.051319) (xy 182.729908 -428.067512) (xy 182.735982 -428.074074) (xy 183.275224 -428.613316)
			(xy 183.316626 -428.61357) (xy 183.331612 -428.598838) (xy 183.355459 -428.576139) (xy 183.407985 -428.536443)
			(xy 183.465193 -428.503857) (xy 183.526127 -428.478924) (xy 183.589769 -428.462061) (xy 183.655055 -428.453551)
			(xy 183.687974 -428.453042) (xy 183.719934 -428.453521) (xy 183.783351 -428.46153) (xy 183.845264 -428.477423)
			(xy 183.904697 -428.500952) (xy 183.960712 -428.531744) (xy 184.012426 -428.569314) (xy 184.059023 -428.613069)
			(xy 184.099769 -428.66232) (xy 184.13402 -428.716289) (xy 184.161237 -428.774126) (xy 184.18099 -428.834917)
			(xy 184.192968 -428.897706) (xy 184.196982 -428.9615) (xy 184.192968 -429.025294) (xy 184.18099 -429.088083)
			(xy 184.161237 -429.148874) (xy 184.13402 -429.206711) (xy 184.099769 -429.26068) (xy 184.059023 -429.309931)
			(xy 184.012426 -429.353686) (xy 183.969717 -429.384714) (xy 184.645298 -429.384714) (xy 184.649369 -429.329092)
			(xy 184.661495 -429.274655) (xy 184.681418 -429.222564) (xy 184.708714 -429.173929) (xy 184.7428 -429.129786)
			(xy 184.782949 -429.091077) (xy 184.828307 -429.058626) (xy 184.877907 -429.033125) (xy 184.930691 -429.015118)
			(xy 184.985534 -429.004988) (xy 185.041268 -429.002951) (xy 185.096705 -429.009051) (xy 185.150662 -429.023157)
			(xy 185.201991 -429.044969) (xy 185.249597 -429.074023) (xy 185.292465 -429.109698) (xy 185.329682 -429.151235)
			(xy 185.360455 -429.197748) (xy 185.384127 -429.248245) (xy 185.400195 -429.301652) (xy 185.408315 -429.356828)
			(xy 185.408824 -429.384714) (xy 185.408315 -429.4126) (xy 185.406102 -429.42764) (xy 185.656218 -429.42764)
			(xy 185.660289 -429.372018) (xy 185.672415 -429.317581) (xy 185.692338 -429.26549) (xy 185.719634 -429.216855)
			(xy 185.75372 -429.172712) (xy 185.793869 -429.134003) (xy 185.839227 -429.101552) (xy 185.888827 -429.076051)
			(xy 185.941611 -429.058044) (xy 185.996454 -429.047914) (xy 186.052188 -429.045877) (xy 186.107625 -429.051977)
			(xy 186.161582 -429.066083) (xy 186.212911 -429.087895) (xy 186.260517 -429.116949) (xy 186.303385 -429.152624)
			(xy 186.340602 -429.194161) (xy 186.371375 -429.240674) (xy 186.395047 -429.291171) (xy 186.411115 -429.344578)
			(xy 186.419235 -429.399754) (xy 186.419744 -429.42764) (xy 186.419235 -429.455526) (xy 186.411115 -429.510702)
			(xy 186.395047 -429.564109) (xy 186.371375 -429.614606) (xy 186.340602 -429.661119) (xy 186.303385 -429.702656)
			(xy 186.260517 -429.738331) (xy 186.212911 -429.767385) (xy 186.161582 -429.789197) (xy 186.107625 -429.803303)
			(xy 186.052188 -429.809403) (xy 185.996454 -429.807366) (xy 185.941611 -429.797236) (xy 185.888827 -429.779229)
			(xy 185.839227 -429.753728) (xy 185.793869 -429.721277) (xy 185.75372 -429.682568) (xy 185.719634 -429.638425)
			(xy 185.692338 -429.58979) (xy 185.672415 -429.537699) (xy 185.660289 -429.483262) (xy 185.656218 -429.42764)
			(xy 185.406102 -429.42764) (xy 185.400195 -429.467776) (xy 185.384127 -429.521183) (xy 185.360455 -429.57168)
			(xy 185.329682 -429.618193) (xy 185.292465 -429.65973) (xy 185.249597 -429.695405) (xy 185.201991 -429.724459)
			(xy 185.150662 -429.746271) (xy 185.096705 -429.760377) (xy 185.041268 -429.766477) (xy 184.985534 -429.76444)
			(xy 184.930691 -429.75431) (xy 184.877907 -429.736303) (xy 184.828307 -429.710802) (xy 184.782949 -429.678351)
			(xy 184.7428 -429.639642) (xy 184.708714 -429.595499) (xy 184.681418 -429.546864) (xy 184.661495 -429.494773)
			(xy 184.649369 -429.440336) (xy 184.645298 -429.384714) (xy 183.969717 -429.384714) (xy 183.960712 -429.391256)
			(xy 183.904697 -429.422048) (xy 183.845264 -429.445577) (xy 183.783351 -429.46147) (xy 183.719934 -429.469479)
			(xy 183.687974 -429.470058) (xy 183.656611 -429.469597) (xy 183.594362 -429.461884) (xy 183.533535 -429.446567)
			(xy 183.475057 -429.423878) (xy 183.419816 -429.394163) (xy 183.368654 -429.357874) (xy 183.322349 -429.315562)
			(xy 183.30164 -429.292004) (xy 183.294274 -429.283622) (xy 183.274208 -429.274224) (xy 183.18099 -429.274224)
			(xy 183.156413 -429.273757) (xy 183.10786 -429.266099) (xy 183.061102 -429.250941) (xy 183.01729 -429.228656)
			(xy 182.977502 -429.199794) (xy 182.959756 -429.182784) (xy 181.78526 -428.008288) (xy 181.768213 -427.990574)
			(xy 181.739345 -427.950783) (xy 181.717061 -427.906964) (xy 181.701912 -427.860197) (xy 181.69427 -427.811634)
			(xy 181.69382 -427.787054) (xy 181.69382 -422.605454) (xy 181.693293 -422.595462) (xy 181.685596 -422.577013)
			(xy 181.678834 -422.56964) (xy 181.004972 -421.895778) (xy 180.997629 -421.888963) (xy 180.979166 -421.881229)
			(xy 180.969158 -421.880792) (xy 178.711352 -421.880792) (xy 178.689181 -421.880421) (xy 178.645278 -421.874204)
			(xy 178.602687 -421.861873) (xy 178.58232 -421.853106) (xy 178.569874 -421.847518) (xy 178.542696 -421.850058)
			(xy 178.44897 -421.91813) (xy 178.438048 -421.943022) (xy 178.439572 -421.956738) (xy 178.441016 -421.970726)
			(xy 178.442542 -421.99881) (xy 178.44262 -422.012872) (xy 178.44262 -422.01338) (xy 178.443037 -422.023402)
			(xy 178.450704 -422.041923) (xy 178.464877 -422.056096) (xy 178.483398 -422.063763) (xy 178.49342 -422.06418)
			(xy 178.505104 -422.06418) (xy 178.515518 -422.0591) (xy 178.541615 -422.047013) (xy 178.596532 -422.02994)
			(xy 178.653387 -422.021286) (xy 178.682142 -422.020746) (xy 178.709395 -422.021235) (xy 178.763344 -422.028997)
			(xy 178.81564 -422.044358) (xy 178.865218 -422.067004) (xy 178.911069 -422.096475) (xy 178.952259 -422.132171)
			(xy 178.98795 -422.173365) (xy 179.017416 -422.219219) (xy 179.040057 -422.268799) (xy 179.055412 -422.321097)
			(xy 179.063168 -422.375047) (xy 179.063168 -422.429553) (xy 179.055412 -422.483503) (xy 179.040057 -422.535801)
			(xy 179.017416 -422.585381) (xy 178.98795 -422.631235) (xy 178.952259 -422.672429) (xy 178.911069 -422.708125)
			(xy 178.865218 -422.737596) (xy 178.81564 -422.760242) (xy 178.763344 -422.775603) (xy 178.709395 -422.783365)
			(xy 178.682142 -422.783762) (xy 178.655456 -422.783311) (xy 178.602606 -422.775861) (xy 178.551311 -422.761115)
			(xy 178.502573 -422.739361) (xy 178.457344 -422.711024) (xy 178.416509 -422.676657) (xy 178.380864 -422.636932)
			(xy 178.351106 -422.592625) (xy 178.327817 -422.544601) (xy 178.319176 -422.519348) (xy 178.31562 -422.50868)
			(xy 178.300126 -422.49217) (xy 178.206908 -422.454578) (xy 178.184302 -422.455594) (xy 178.174396 -422.460928)
			(xy 178.146596 -422.475314) (xy 178.088231 -422.497936) (xy 178.027529 -422.513214) (xy 177.96541 -422.520919)
			(xy 177.934112 -422.52138) (xy 177.901611 -422.520866) (xy 177.83714 -422.512585) (xy 177.774249 -422.496157)
			(xy 177.713964 -422.471849) (xy 177.657267 -422.440059) (xy 177.605084 -422.401303) (xy 177.581306 -422.37914)
			(xy 177.574452 -422.373063) (xy 177.557659 -422.365781) (xy 177.54854 -422.364916) (xy 177.51806 -422.363646)
			(xy 177.508865 -422.363617) (xy 177.49141 -422.369346) (xy 177.484024 -422.374822) (xy 177.456829 -422.395891)
			(xy 177.397842 -422.431292) (xy 177.334624 -422.458421) (xy 177.268326 -422.476786) (xy 177.200159 -422.48605)
			(xy 177.165762 -422.486582) (xy 177.133804 -422.486078) (xy 177.070393 -422.478063) (xy 177.008486 -422.462164)
			(xy 176.94906 -422.438631) (xy 176.893052 -422.407837) (xy 176.841345 -422.370266) (xy 176.794754 -422.326511)
			(xy 176.754014 -422.277261) (xy 176.719768 -422.223294) (xy 176.692555 -422.165461) (xy 176.672805 -422.104673)
			(xy 176.660829 -422.04189) (xy 176.656815 -421.9781) (xy 176.660829 -421.91431) (xy 176.672805 -421.851527)
			(xy 176.692555 -421.790739) (xy 176.719768 -421.732906) (xy 176.754014 -421.678939) (xy 176.794754 -421.629689)
			(xy 176.841345 -421.585934) (xy 176.893052 -421.548363) (xy 176.94906 -421.517569) (xy 177.008486 -421.494036)
			(xy 177.070393 -421.478137) (xy 177.133804 -421.470122) (xy 177.165762 -421.469566) (xy 177.198263 -421.470079)
			(xy 177.262735 -421.478357) (xy 177.325627 -421.494784) (xy 177.385913 -421.519091) (xy 177.442611 -421.550882)
			(xy 177.494794 -421.589639) (xy 177.518568 -421.611806) (xy 177.525423 -421.617882) (xy 177.542215 -421.625166)
			(xy 177.551334 -421.62603) (xy 177.581814 -421.6273) (xy 177.59101 -421.627333) (xy 177.608468 -421.621606)
			(xy 177.61585 -421.616124) (xy 177.621184 -421.61206) (xy 177.621184 -421.48887) (xy 177.620704 -421.478905)
			(xy 177.613124 -421.460473) (xy 177.606452 -421.453056) (xy 176.461674 -420.308278) (xy 176.454331 -420.301463)
			(xy 176.435868 -420.293728) (xy 176.42586 -420.293292) (xy 175.47209 -420.293292) (xy 175.462021 -420.292867)
			(xy 175.44342 -420.285149) (xy 175.436022 -420.278306) (xy 173.136306 -417.97859) (xy 173.129461 -417.971191)
			(xy 173.121729 -417.952593) (xy 173.12132 -417.942522) (xy 173.12132 -417.365942) (xy 173.1209 -417.357085)
			(xy 173.1148 -417.340449) (xy 173.109382 -417.33343) (xy 173.090704 -417.310475) (xy 173.058208 -417.261012)
			(xy 173.031668 -417.208114) (xy 173.011442 -417.152495) (xy 172.997804 -417.094906) (xy 172.990936 -417.036123)
			(xy 172.99051 -417.006532) (xy 172.990906 -416.976937) (xy 172.997746 -416.918145) (xy 173.011372 -416.860547)
			(xy 173.0316 -416.804922) (xy 173.058155 -416.752025) (xy 173.090678 -416.702572) (xy 173.109382 -416.679634)
			(xy 173.114842 -416.672639) (xy 173.12095 -416.655989) (xy 173.12132 -416.647122) (xy 173.12132 -415.34588)
			(xy 173.120894 -415.335811) (xy 173.113177 -415.31721) (xy 173.106334 -415.309812) (xy 171.839636 -414.043114)
			(xy 171.832214 -414.036329) (xy 171.813617 -414.02872) (xy 171.803568 -414.028382) (xy 171.721018 -414.028636)
			(xy 171.702476 -414.03651) (xy 171.695364 -414.043876) (xy 171.673695 -414.065121) (xy 171.624876 -414.101159)
			(xy 171.570968 -414.129018) (xy 171.51333 -414.147993) (xy 171.453416 -414.157608) (xy 171.423076 -414.158176)
			(xy 171.395825 -414.157711) (xy 171.341878 -414.149951) (xy 171.289585 -414.134593) (xy 171.24001 -414.111948)
			(xy 171.194162 -414.082479) (xy 171.152975 -414.046785) (xy 171.117287 -414.005593) (xy 171.087825 -413.959741)
			(xy 171.065188 -413.910162) (xy 171.049837 -413.857867) (xy 171.042085 -413.803919) (xy 171.041568 -413.776668)
			(xy 171.042157 -413.746329) (xy 171.051768 -413.686418) (xy 171.070743 -413.628785) (xy 171.098603 -413.574882)
			(xy 171.134646 -413.526069) (xy 171.155868 -413.50438) (xy 171.163234 -413.497268) (xy 171.171108 -413.478726)
			(xy 171.171362 -413.396176) (xy 171.17091 -413.38615) (xy 171.163313 -413.367597) (xy 171.15663 -413.360108)
			(xy 170.52163 -412.725108) (xy 170.514228 -412.718272) (xy 170.49563 -412.710562) (xy 170.485562 -412.710122)
			(xy 170.297602 -412.710122) (xy 170.285983 -412.710699) (xy 170.265096 -412.720893) (xy 170.25747 -412.72968)
			(xy 170.200828 -412.80207) (xy 170.196002 -412.82493) (xy 170.19905 -412.83636) (xy 170.206181 -412.86685)
			(xy 170.213818 -412.929002) (xy 170.21429 -412.960312) (xy 170.213788 -412.992273) (xy 170.205777 -413.055691)
			(xy 170.18988 -413.117605) (xy 170.166348 -413.177038) (xy 170.135554 -413.233053) (xy 170.097981 -413.284768)
			(xy 170.054224 -413.331365) (xy 170.004971 -413.37211) (xy 169.951 -413.406361) (xy 169.893161 -413.433578)
			(xy 169.832368 -413.453331) (xy 169.769578 -413.465309) (xy 169.705782 -413.469323) (xy 169.641986 -413.465309)
			(xy 169.579196 -413.453331) (xy 169.518403 -413.433578) (xy 169.460564 -413.406361) (xy 169.406593 -413.37211)
			(xy 169.35734 -413.331365) (xy 169.313583 -413.284768) (xy 169.27601 -413.233053) (xy 169.245216 -413.177038)
			(xy 169.221684 -413.117605) (xy 169.205787 -413.055691) (xy 169.197776 -412.992273) (xy 169.197274 -412.960312)
			(xy 169.197703 -412.929) (xy 169.205346 -412.866844) (xy 169.212514 -412.83636) (xy 169.215562 -412.82493)
			(xy 169.210736 -412.80207) (xy 169.154094 -412.72968) (xy 169.146507 -412.720841) (xy 169.125598 -412.710632)
			(xy 169.113962 -412.710122) (xy 168.448482 -412.710122) (xy 168.439375 -412.710507) (xy 168.422304 -412.716861)
			(xy 168.408494 -412.728739) (xy 168.403778 -412.736538) (xy 168.354248 -412.826962) (xy 168.355264 -412.854394)
			(xy 168.36263 -412.866332) (xy 168.377763 -412.890847) (xy 168.403011 -412.942634) (xy 168.422242 -412.996943)
			(xy 168.435207 -413.053079) (xy 168.441742 -413.110321) (xy 168.442132 -413.139128) (xy 168.44163 -413.171089)
			(xy 168.433619 -413.234507) (xy 168.417722 -413.296421) (xy 168.39419 -413.355854) (xy 168.363396 -413.411869)
			(xy 168.325823 -413.463584) (xy 168.282066 -413.510181) (xy 168.232813 -413.550926) (xy 168.178842 -413.585177)
			(xy 168.121003 -413.612394) (xy 168.06021 -413.632147) (xy 167.99742 -413.644125) (xy 167.933624 -413.648139)
			(xy 167.869828 -413.644125) (xy 167.807038 -413.632147) (xy 167.746245 -413.612394) (xy 167.688406 -413.585177)
			(xy 167.634435 -413.550926) (xy 167.585182 -413.510181) (xy 167.541425 -413.463584) (xy 167.503852 -413.411869)
			(xy 167.473058 -413.355854) (xy 167.449526 -413.296421) (xy 167.433629 -413.234507) (xy 167.425618 -413.171089)
			(xy 167.425116 -413.139128) (xy 167.425531 -413.110322) (xy 167.43207 -413.053083) (xy 167.445032 -412.996949)
			(xy 167.464252 -412.942638) (xy 167.489485 -412.890845) (xy 167.504618 -412.866332) (xy 167.511984 -412.854394)
			(xy 167.513 -412.826962) (xy 167.46347 -412.736538) (xy 167.458783 -412.728706) (xy 167.444997 -412.716767)
			(xy 167.427887 -412.710453) (xy 167.418766 -412.710122) (xy 166.145972 -412.710122) (xy 166.135905 -412.710551)
			(xy 166.117309 -412.718275) (xy 166.109904 -412.725108) (xy 165.288214 -413.546798) (xy 166.59555 -413.546798)
			(xy 166.599621 -413.491176) (xy 166.611747 -413.436739) (xy 166.63167 -413.384648) (xy 166.658966 -413.336013)
			(xy 166.693052 -413.29187) (xy 166.733201 -413.253161) (xy 166.778559 -413.22071) (xy 166.828159 -413.195209)
			(xy 166.880943 -413.177202) (xy 166.935786 -413.167072) (xy 166.99152 -413.165035) (xy 167.046957 -413.171135)
			(xy 167.100914 -413.185241) (xy 167.152243 -413.207053) (xy 167.199849 -413.236107) (xy 167.242717 -413.271782)
			(xy 167.279934 -413.313319) (xy 167.310707 -413.359832) (xy 167.334379 -413.410329) (xy 167.350447 -413.463736)
			(xy 167.358567 -413.518912) (xy 167.359076 -413.546798) (xy 167.358567 -413.574684) (xy 167.350447 -413.62986)
			(xy 167.334379 -413.683267) (xy 167.310707 -413.733764) (xy 167.279934 -413.780277) (xy 167.242717 -413.821814)
			(xy 167.199849 -413.857489) (xy 167.152243 -413.886543) (xy 167.100914 -413.908355) (xy 167.046957 -413.922461)
			(xy 166.99152 -413.928561) (xy 166.935786 -413.926524) (xy 166.880943 -413.916394) (xy 166.828159 -413.898387)
			(xy 166.778559 -413.872886) (xy 166.733201 -413.840435) (xy 166.693052 -413.801726) (xy 166.658966 -413.757583)
			(xy 166.63167 -413.708948) (xy 166.611747 -413.656857) (xy 166.599621 -413.60242) (xy 166.59555 -413.546798)
			(xy 165.288214 -413.546798) (xy 164.722048 -414.112964) (xy 165.295578 -414.112964) (xy 165.299649 -414.057342)
			(xy 165.311775 -414.002905) (xy 165.331698 -413.950814) (xy 165.358994 -413.902179) (xy 165.39308 -413.858036)
			(xy 165.433229 -413.819327) (xy 165.478587 -413.786876) (xy 165.528187 -413.761375) (xy 165.580971 -413.743368)
			(xy 165.635814 -413.733238) (xy 165.691548 -413.731201) (xy 165.746985 -413.737301) (xy 165.800942 -413.751407)
			(xy 165.852271 -413.773219) (xy 165.899877 -413.802273) (xy 165.942745 -413.837948) (xy 165.979962 -413.879485)
			(xy 166.010735 -413.925998) (xy 166.034407 -413.976495) (xy 166.050475 -414.029902) (xy 166.058595 -414.085078)
			(xy 166.059104 -414.112964) (xy 166.058595 -414.14085) (xy 166.050475 -414.196026) (xy 166.034407 -414.249433)
			(xy 166.010735 -414.29993) (xy 165.979962 -414.346443) (xy 165.942745 -414.38798) (xy 165.899877 -414.423655)
			(xy 165.852271 -414.452709) (xy 165.800942 -414.474521) (xy 165.746985 -414.488627) (xy 165.691548 -414.494727)
			(xy 165.635814 -414.49269) (xy 165.580971 -414.48256) (xy 165.528187 -414.464553) (xy 165.478587 -414.439052)
			(xy 165.433229 -414.406601) (xy 165.39308 -414.367892) (xy 165.358994 -414.323749) (xy 165.331698 -414.275114)
			(xy 165.311775 -414.223023) (xy 165.299649 -414.168586) (xy 165.295578 -414.112964) (xy 164.722048 -414.112964)
			(xy 162.293089 -416.541923) (xy 162.846506 -416.541923) (xy 162.846506 -416.478001) (xy 162.854517 -416.414583)
			(xy 162.870414 -416.352669) (xy 162.893946 -416.293236) (xy 162.92474 -416.237221) (xy 162.962313 -416.185506)
			(xy 163.00607 -416.138909) (xy 163.055323 -416.098164) (xy 163.109294 -416.063913) (xy 163.167133 -416.036696)
			(xy 163.227926 -416.016943) (xy 163.290716 -416.004965) (xy 163.354512 -416.000952) (xy 163.418308 -416.004965)
			(xy 163.481098 -416.016943) (xy 163.541891 -416.036696) (xy 163.59973 -416.063913) (xy 163.648599 -416.094926)
			(xy 167.39565 -416.094926) (xy 167.399721 -416.039304) (xy 167.411847 -415.984867) (xy 167.43177 -415.932776)
			(xy 167.459066 -415.884141) (xy 167.493152 -415.839998) (xy 167.533301 -415.801289) (xy 167.578659 -415.768838)
			(xy 167.628259 -415.743337) (xy 167.681043 -415.72533) (xy 167.735886 -415.7152) (xy 167.79162 -415.713163)
			(xy 167.847057 -415.719263) (xy 167.901014 -415.733369) (xy 167.952343 -415.755181) (xy 167.999949 -415.784235)
			(xy 168.042817 -415.81991) (xy 168.080034 -415.861447) (xy 168.110807 -415.90796) (xy 168.134479 -415.958457)
			(xy 168.150547 -416.011864) (xy 168.158667 -416.06704) (xy 168.159176 -416.094926) (xy 168.158667 -416.122812)
			(xy 168.150547 -416.177988) (xy 168.134479 -416.231395) (xy 168.110807 -416.281892) (xy 168.080034 -416.328405)
			(xy 168.042817 -416.369942) (xy 167.999949 -416.405617) (xy 167.952343 -416.434671) (xy 167.901014 -416.456483)
			(xy 167.847057 -416.470589) (xy 167.79162 -416.476689) (xy 167.735886 -416.474652) (xy 167.681043 -416.464522)
			(xy 167.628259 -416.446515) (xy 167.578659 -416.421014) (xy 167.533301 -416.388563) (xy 167.493152 -416.349854)
			(xy 167.459066 -416.305711) (xy 167.43177 -416.257076) (xy 167.411847 -416.204985) (xy 167.399721 -416.150548)
			(xy 167.39565 -416.094926) (xy 163.648599 -416.094926) (xy 163.653701 -416.098164) (xy 163.702954 -416.138909)
			(xy 163.746711 -416.185506) (xy 163.784284 -416.237221) (xy 163.815078 -416.293236) (xy 163.83861 -416.352669)
			(xy 163.854507 -416.414583) (xy 163.862518 -416.478001) (xy 163.86302 -416.509962) (xy 163.862518 -416.541923)
			(xy 163.854507 -416.605341) (xy 163.83861 -416.667255) (xy 163.815078 -416.726688) (xy 163.784284 -416.782703)
			(xy 163.753641 -416.824879) (xy 169.582586 -416.824879) (xy 169.582586 -416.760957) (xy 169.590597 -416.697539)
			(xy 169.606494 -416.635625) (xy 169.630026 -416.576192) (xy 169.66082 -416.520177) (xy 169.698393 -416.468462)
			(xy 169.74215 -416.421865) (xy 169.791403 -416.38112) (xy 169.845374 -416.346869) (xy 169.903213 -416.319652)
			(xy 169.964006 -416.299899) (xy 170.026796 -416.287921) (xy 170.090592 -416.283908) (xy 170.154388 -416.287921)
			(xy 170.217178 -416.299899) (xy 170.277971 -416.319652) (xy 170.33581 -416.346869) (xy 170.38708 -416.379406)
			(xy 170.80941 -416.379406) (xy 170.813481 -416.323784) (xy 170.825607 -416.269347) (xy 170.84553 -416.217256)
			(xy 170.872826 -416.168621) (xy 170.906912 -416.124478) (xy 170.947061 -416.085769) (xy 170.992419 -416.053318)
			(xy 171.042019 -416.027817) (xy 171.094803 -416.00981) (xy 171.149646 -415.99968) (xy 171.20538 -415.997643)
			(xy 171.260817 -416.003743) (xy 171.314774 -416.017849) (xy 171.366103 -416.039661) (xy 171.413709 -416.068715)
			(xy 171.456577 -416.10439) (xy 171.493794 -416.145927) (xy 171.524567 -416.19244) (xy 171.548239 -416.242937)
			(xy 171.564307 -416.296344) (xy 171.572427 -416.35152) (xy 171.572936 -416.379406) (xy 171.572427 -416.407292)
			(xy 171.564307 -416.462468) (xy 171.548239 -416.515875) (xy 171.524567 -416.566372) (xy 171.493794 -416.612885)
			(xy 171.456577 -416.654422) (xy 171.413709 -416.690097) (xy 171.366103 -416.719151) (xy 171.314774 -416.740963)
			(xy 171.260817 -416.755069) (xy 171.20538 -416.761169) (xy 171.149646 -416.759132) (xy 171.094803 -416.749002)
			(xy 171.042019 -416.730995) (xy 170.992419 -416.705494) (xy 170.947061 -416.673043) (xy 170.906912 -416.634334)
			(xy 170.872826 -416.590191) (xy 170.84553 -416.541556) (xy 170.825607 -416.489465) (xy 170.813481 -416.435028)
			(xy 170.80941 -416.379406) (xy 170.38708 -416.379406) (xy 170.389781 -416.38112) (xy 170.439034 -416.421865)
			(xy 170.482791 -416.468462) (xy 170.520364 -416.520177) (xy 170.551158 -416.576192) (xy 170.57469 -416.635625)
			(xy 170.590587 -416.697539) (xy 170.598598 -416.760957) (xy 170.5991 -416.792918) (xy 170.598598 -416.824879)
			(xy 170.590587 -416.888297) (xy 170.57469 -416.950211) (xy 170.551158 -417.009644) (xy 170.520364 -417.065659)
			(xy 170.482791 -417.117374) (xy 170.439034 -417.163971) (xy 170.389781 -417.204716) (xy 170.33581 -417.238967)
			(xy 170.277971 -417.266184) (xy 170.217178 -417.285937) (xy 170.154388 -417.297915) (xy 170.090592 -417.301929)
			(xy 170.026796 -417.297915) (xy 169.964006 -417.285937) (xy 169.903213 -417.266184) (xy 169.845374 -417.238967)
			(xy 169.791403 -417.204716) (xy 169.74215 -417.163971) (xy 169.698393 -417.117374) (xy 169.66082 -417.065659)
			(xy 169.630026 -417.009644) (xy 169.606494 -416.950211) (xy 169.590597 -416.888297) (xy 169.582586 -416.824879)
			(xy 163.753641 -416.824879) (xy 163.746711 -416.834418) (xy 163.702954 -416.881015) (xy 163.653701 -416.92176)
			(xy 163.59973 -416.956011) (xy 163.541891 -416.983228) (xy 163.481098 -417.002981) (xy 163.418308 -417.014959)
			(xy 163.354512 -417.018973) (xy 163.290716 -417.014959) (xy 163.227926 -417.002981) (xy 163.167133 -416.983228)
			(xy 163.109294 -416.956011) (xy 163.055323 -416.92176) (xy 163.00607 -416.881015) (xy 162.962313 -416.834418)
			(xy 162.92474 -416.782703) (xy 162.893946 -416.726688) (xy 162.870414 -416.667255) (xy 162.854517 -416.605341)
			(xy 162.846506 -416.541923) (xy 162.293089 -416.541923) (xy 162.18916 -416.645852) (xy 162.182315 -416.65325)
			(xy 162.17459 -416.671849) (xy 162.174174 -416.68192) (xy 162.174174 -417.685474) (xy 162.174813 -417.698031)
			(xy 162.186671 -417.720164) (xy 162.19678 -417.727638) (xy 162.277806 -417.78174) (xy 162.302698 -417.78428)
			(xy 162.314636 -417.7792) (xy 162.345603 -417.766985) (xy 162.409913 -417.74979) (xy 162.475915 -417.741125)
			(xy 162.5092 -417.740592) (xy 162.541161 -417.741094) (xy 162.604579 -417.749105) (xy 162.666493 -417.765002)
			(xy 162.725926 -417.788534) (xy 162.781941 -417.819328) (xy 162.833656 -417.856901) (xy 162.880253 -417.900658)
			(xy 162.920998 -417.949911) (xy 162.955249 -418.003882) (xy 162.982466 -418.061721) (xy 163.002219 -418.122514)
			(xy 163.014197 -418.185304) (xy 163.017681 -418.240675) (xy 163.297864 -418.240675) (xy 163.297864 -418.176753)
			(xy 163.305875 -418.113335) (xy 163.321772 -418.051421) (xy 163.345304 -417.991988) (xy 163.376098 -417.935973)
			(xy 163.413671 -417.884258) (xy 163.457428 -417.837661) (xy 163.506681 -417.796916) (xy 163.560652 -417.762665)
			(xy 163.618491 -417.735448) (xy 163.679284 -417.715695) (xy 163.742074 -417.703717) (xy 163.80587 -417.699704)
			(xy 163.869666 -417.703717) (xy 163.932456 -417.715695) (xy 163.993249 -417.735448) (xy 164.051088 -417.762665)
			(xy 164.105059 -417.796916) (xy 164.154312 -417.837661) (xy 164.198069 -417.884258) (xy 164.235642 -417.935973)
			(xy 164.266436 -417.991988) (xy 164.289968 -418.051421) (xy 164.292192 -418.060081) (xy 168.003468 -418.060081)
			(xy 168.003468 -417.996159) (xy 168.011479 -417.932741) (xy 168.027376 -417.870827) (xy 168.050908 -417.811394)
			(xy 168.081702 -417.755379) (xy 168.119275 -417.703664) (xy 168.163032 -417.657067) (xy 168.212285 -417.616322)
			(xy 168.266256 -417.582071) (xy 168.324095 -417.554854) (xy 168.384888 -417.535101) (xy 168.447678 -417.523123)
			(xy 168.511474 -417.51911) (xy 168.57527 -417.523123) (xy 168.63806 -417.535101) (xy 168.698853 -417.554854)
			(xy 168.756692 -417.582071) (xy 168.810663 -417.616322) (xy 168.859916 -417.657067) (xy 168.903673 -417.703664)
			(xy 168.941246 -417.755379) (xy 168.97204 -417.811394) (xy 168.995572 -417.870827) (xy 169.011469 -417.932741)
			(xy 169.01948 -417.996159) (xy 169.019982 -418.02812) (xy 169.01948 -418.060081) (xy 169.011469 -418.123499)
			(xy 168.995572 -418.185413) (xy 168.97204 -418.244846) (xy 168.955343 -418.275219) (xy 169.463206 -418.275219)
			(xy 169.463206 -418.211297) (xy 169.471217 -418.147879) (xy 169.487114 -418.085965) (xy 169.510646 -418.026532)
			(xy 169.54144 -417.970517) (xy 169.579013 -417.918802) (xy 169.62277 -417.872205) (xy 169.672023 -417.83146)
			(xy 169.725994 -417.797209) (xy 169.783833 -417.769992) (xy 169.844626 -417.750239) (xy 169.907416 -417.738261)
			(xy 169.971212 -417.734248) (xy 170.035008 -417.738261) (xy 170.097798 -417.750239) (xy 170.158591 -417.769992)
			(xy 170.21643 -417.797209) (xy 170.270401 -417.83146) (xy 170.319654 -417.872205) (xy 170.363411 -417.918802)
			(xy 170.400984 -417.970517) (xy 170.431778 -418.026532) (xy 170.45531 -418.085965) (xy 170.471207 -418.147879)
			(xy 170.479218 -418.211297) (xy 170.47972 -418.243258) (xy 170.479218 -418.275219) (xy 170.471207 -418.338637)
			(xy 170.45531 -418.400551) (xy 170.431778 -418.459984) (xy 170.400984 -418.515999) (xy 170.374924 -418.551868)
			(xy 170.937426 -418.551868) (xy 170.941497 -418.496246) (xy 170.953623 -418.441809) (xy 170.973546 -418.389718)
			(xy 171.000842 -418.341083) (xy 171.034928 -418.29694) (xy 171.075077 -418.258231) (xy 171.120435 -418.22578)
			(xy 171.170035 -418.200279) (xy 171.222819 -418.182272) (xy 171.277662 -418.172142) (xy 171.333396 -418.170105)
			(xy 171.388833 -418.176205) (xy 171.44279 -418.190311) (xy 171.494119 -418.212123) (xy 171.541725 -418.241177)
			(xy 171.584593 -418.276852) (xy 171.62181 -418.318389) (xy 171.652583 -418.364902) (xy 171.676255 -418.415399)
			(xy 171.692323 -418.468806) (xy 171.700443 -418.523982) (xy 171.700952 -418.551868) (xy 171.700443 -418.579754)
			(xy 171.692323 -418.63493) (xy 171.676255 -418.688337) (xy 171.652583 -418.738834) (xy 171.62181 -418.785347)
			(xy 171.584593 -418.826884) (xy 171.541725 -418.862559) (xy 171.494119 -418.891613) (xy 171.44279 -418.913425)
			(xy 171.388833 -418.927531) (xy 171.333396 -418.933631) (xy 171.277662 -418.931594) (xy 171.222819 -418.921464)
			(xy 171.170035 -418.903457) (xy 171.120435 -418.877956) (xy 171.075077 -418.845505) (xy 171.034928 -418.806796)
			(xy 171.000842 -418.762653) (xy 170.973546 -418.714018) (xy 170.953623 -418.661927) (xy 170.941497 -418.60749)
			(xy 170.937426 -418.551868) (xy 170.374924 -418.551868) (xy 170.363411 -418.567714) (xy 170.319654 -418.614311)
			(xy 170.270401 -418.655056) (xy 170.21643 -418.689307) (xy 170.158591 -418.716524) (xy 170.097798 -418.736277)
			(xy 170.035008 -418.748255) (xy 169.971212 -418.752269) (xy 169.907416 -418.748255) (xy 169.844626 -418.736277)
			(xy 169.783833 -418.716524) (xy 169.725994 -418.689307) (xy 169.672023 -418.655056) (xy 169.62277 -418.614311)
			(xy 169.579013 -418.567714) (xy 169.54144 -418.515999) (xy 169.510646 -418.459984) (xy 169.487114 -418.400551)
			(xy 169.471217 -418.338637) (xy 169.463206 -418.275219) (xy 168.955343 -418.275219) (xy 168.941246 -418.300861)
			(xy 168.903673 -418.352576) (xy 168.859916 -418.399173) (xy 168.810663 -418.439918) (xy 168.756692 -418.474169)
			(xy 168.698853 -418.501386) (xy 168.63806 -418.521139) (xy 168.57527 -418.533117) (xy 168.511474 -418.537131)
			(xy 168.447678 -418.533117) (xy 168.384888 -418.521139) (xy 168.324095 -418.501386) (xy 168.266256 -418.474169)
			(xy 168.212285 -418.439918) (xy 168.163032 -418.399173) (xy 168.119275 -418.352576) (xy 168.081702 -418.300861)
			(xy 168.050908 -418.244846) (xy 168.027376 -418.185413) (xy 168.011479 -418.123499) (xy 168.003468 -418.060081)
			(xy 164.292192 -418.060081) (xy 164.305865 -418.113335) (xy 164.313876 -418.176753) (xy 164.314378 -418.208714)
			(xy 164.313876 -418.240675) (xy 164.305865 -418.304093) (xy 164.289968 -418.366007) (xy 164.266436 -418.42544)
			(xy 164.235642 -418.481455) (xy 164.198069 -418.53317) (xy 164.154312 -418.579767) (xy 164.105059 -418.620512)
			(xy 164.051088 -418.654763) (xy 163.993249 -418.68198) (xy 163.932456 -418.701733) (xy 163.869666 -418.713711)
			(xy 163.80587 -418.717725) (xy 163.742074 -418.713711) (xy 163.679284 -418.701733) (xy 163.618491 -418.68198)
			(xy 163.560652 -418.654763) (xy 163.506681 -418.620512) (xy 163.457428 -418.579767) (xy 163.413671 -418.53317)
			(xy 163.376098 -418.481455) (xy 163.345304 -418.42544) (xy 163.321772 -418.366007) (xy 163.305875 -418.304093)
			(xy 163.297864 -418.240675) (xy 163.017681 -418.240675) (xy 163.018211 -418.2491) (xy 163.014197 -418.312896)
			(xy 163.002219 -418.375686) (xy 162.982466 -418.436479) (xy 162.955249 -418.494318) (xy 162.920998 -418.548289)
			(xy 162.880253 -418.597542) (xy 162.833656 -418.641299) (xy 162.781941 -418.678872) (xy 162.725926 -418.709666)
			(xy 162.666493 -418.733198) (xy 162.604579 -418.749095) (xy 162.541161 -418.757106) (xy 162.5092 -418.757608)
			(xy 162.475913 -418.757106) (xy 162.409905 -418.748449) (xy 162.345593 -418.731244) (xy 162.314636 -418.719)
			(xy 162.302698 -418.71392) (xy 162.277806 -418.71646) (xy 162.19678 -418.770562) (xy 162.186708 -418.778073)
			(xy 162.174829 -418.800181) (xy 162.174174 -418.812726) (xy 162.174174 -418.83965) (xy 162.174606 -418.849717)
			(xy 162.18233 -418.86831) (xy 162.18916 -418.875718) (xy 162.403536 -419.090094) (xy 162.724336 -419.090094)
			(xy 162.728407 -419.034472) (xy 162.740533 -418.980035) (xy 162.760456 -418.927944) (xy 162.787752 -418.879309)
			(xy 162.821838 -418.835166) (xy 162.861987 -418.796457) (xy 162.907345 -418.764006) (xy 162.956945 -418.738505)
			(xy 163.009729 -418.720498) (xy 163.064572 -418.710368) (xy 163.120306 -418.708331) (xy 163.175743 -418.714431)
			(xy 163.2297 -418.728537) (xy 163.281029 -418.750349) (xy 163.328635 -418.779403) (xy 163.371503 -418.815078)
			(xy 163.40872 -418.856615) (xy 163.439493 -418.903128) (xy 163.463165 -418.953625) (xy 163.479233 -419.007032)
			(xy 163.487353 -419.062208) (xy 163.487862 -419.090094) (xy 163.487353 -419.11798) (xy 163.485289 -419.132004)
			(xy 164.532056 -419.132004) (xy 164.532546 -419.104729) (xy 164.540314 -419.050736) (xy 164.555694 -418.9984)
			(xy 164.57837 -418.948787) (xy 164.607881 -418.90291) (xy 164.643626 -418.861704) (xy 164.684874 -418.826009)
			(xy 164.730786 -418.796552) (xy 164.780426 -418.773935) (xy 164.83278 -418.758618) (xy 164.859716 -418.754306)
			(xy 164.869368 -418.753036) (xy 164.885878 -418.743638) (xy 164.941758 -418.674804) (xy 164.947346 -418.65677)
			(xy 164.946584 -418.646864) (xy 164.945822 -418.62121) (xy 164.946265 -418.593956) (xy 164.954021 -418.540003)
			(xy 164.969377 -418.487703) (xy 164.992021 -418.438121) (xy 165.021491 -418.392266) (xy 165.057187 -418.351072)
			(xy 165.098382 -418.315379) (xy 165.144238 -418.285911) (xy 165.193822 -418.26327) (xy 165.246122 -418.247917)
			(xy 165.300076 -418.240163) (xy 165.32733 -418.239702) (xy 165.356276 -418.240238) (xy 165.413501 -418.248995)
			(xy 165.46875 -418.266288) (xy 165.520755 -418.291723) (xy 165.568326 -418.324715) (xy 165.610373 -418.364509)
			(xy 165.628574 -418.387022) (xy 165.634162 -418.394388) (xy 165.649148 -418.403786) (xy 165.731698 -418.421058)
			(xy 165.74897 -418.418518) (xy 165.757098 -418.413946) (xy 165.785123 -418.399304) (xy 165.844014 -418.376287)
			(xy 165.905307 -418.360753) (xy 165.968053 -418.352942) (xy 165.999668 -418.352478) (xy 166.031631 -418.352985)
			(xy 166.095053 -418.360993) (xy 166.156971 -418.376888) (xy 166.216408 -418.400417) (xy 166.272428 -418.431211)
			(xy 166.324146 -418.468784) (xy 166.370747 -418.512542) (xy 166.411496 -418.561797) (xy 166.44575 -418.61577)
			(xy 166.47297 -418.673611) (xy 166.492725 -418.734408) (xy 166.504703 -418.797201) (xy 166.508718 -418.861)
			(xy 166.504703 -418.924799) (xy 166.492725 -418.987592) (xy 166.47297 -419.048389) (xy 166.44575 -419.10623)
			(xy 166.411496 -419.160203) (xy 166.370747 -419.209458) (xy 166.324146 -419.253216) (xy 166.272428 -419.290789)
			(xy 166.216408 -419.321583) (xy 166.156971 -419.345112) (xy 166.095053 -419.361007) (xy 166.031631 -419.369015)
			(xy 165.999668 -419.369494) (xy 165.966261 -419.368948) (xy 165.900025 -419.360187) (xy 165.835504 -419.342834)
			(xy 165.77381 -419.317186) (xy 165.716002 -419.283685) (xy 165.663076 -419.242908) (xy 165.615941 -419.195554)
			(xy 165.575408 -419.14244) (xy 165.542175 -419.084478) (xy 165.529006 -419.053772) (xy 165.52545 -419.045136)
			(xy 165.513766 -419.032182) (xy 165.438836 -418.99332) (xy 165.42131 -418.991034) (xy 165.41242 -418.993066)
			(xy 165.381178 -418.998908) (xy 165.371526 -419.000178) (xy 165.355016 -419.009576) (xy 165.299136 -419.07841)
			(xy 165.293548 -419.096444) (xy 165.29431 -419.10635) (xy 165.295072 -419.132004) (xy 165.294586 -419.159255)
			(xy 165.28683 -419.213203) (xy 165.271475 -419.265498) (xy 165.248833 -419.315075) (xy 165.219367 -419.360925)
			(xy 165.183676 -419.402116) (xy 165.142485 -419.437807) (xy 165.096635 -419.467273) (xy 165.047058 -419.489915)
			(xy 164.994763 -419.50527) (xy 164.940815 -419.513026) (xy 164.886313 -419.513026) (xy 164.832365 -419.50527)
			(xy 164.78007 -419.489915) (xy 164.730493 -419.467273) (xy 164.684643 -419.437807) (xy 164.643452 -419.402116)
			(xy 164.607761 -419.360925) (xy 164.578295 -419.315075) (xy 164.555653 -419.265498) (xy 164.540298 -419.213203)
			(xy 164.532542 -419.159255) (xy 164.532056 -419.132004) (xy 163.485289 -419.132004) (xy 163.479233 -419.173156)
			(xy 163.463165 -419.226563) (xy 163.439493 -419.27706) (xy 163.40872 -419.323573) (xy 163.371503 -419.36511)
			(xy 163.328635 -419.400785) (xy 163.281029 -419.429839) (xy 163.2297 -419.451651) (xy 163.175743 -419.465757)
			(xy 163.120306 -419.471857) (xy 163.064572 -419.46982) (xy 163.009729 -419.45969) (xy 162.956945 -419.441683)
			(xy 162.907345 -419.416182) (xy 162.861987 -419.383731) (xy 162.821838 -419.345022) (xy 162.787752 -419.300879)
			(xy 162.760456 -419.252244) (xy 162.740533 -419.200153) (xy 162.728407 -419.145716) (xy 162.724336 -419.090094)
			(xy 162.403536 -419.090094) (xy 162.966146 -419.652704) (xy 162.998912 -419.65753) (xy 163.013644 -419.64991)
			(xy 163.041063 -419.636056) (xy 163.09851 -419.614287) (xy 163.158161 -419.599595) (xy 163.219147 -419.592193)
			(xy 163.249864 -419.591744) (xy 163.27986 -419.592185) (xy 163.339435 -419.599251) (xy 163.397765 -419.613278)
			(xy 163.45404 -419.63407) (xy 163.507477 -419.661339) (xy 163.557335 -419.694705) (xy 163.60292 -419.733706)
			(xy 163.6436 -419.7778) (xy 163.661598 -419.801802) (xy 163.670602 -419.813424) (xy 163.693892 -419.831347)
			(xy 163.721326 -419.841885) (xy 163.750625 -419.844163) (xy 163.779358 -419.837993) (xy 163.805139 -419.823885)
			(xy 163.815776 -419.81374) (xy 163.986718 -419.642798) (xy 163.994118 -419.635955) (xy 164.012716 -419.628227)
			(xy 164.022786 -419.627812) (xy 165.161214 -419.627812) (xy 165.171283 -419.628238) (xy 165.189882 -419.635957)
			(xy 165.197282 -419.642798) (xy 165.619684 -420.0652) (xy 165.626667 -420.071601) (xy 165.644024 -420.079155)
			(xy 165.66294 -420.079877) (xy 165.672008 -420.077138) (xy 165.772338 -420.042848) (xy 165.790372 -420.020242)
			(xy 165.79215 -420.005764) (xy 165.796386 -419.975379) (xy 165.811216 -419.915848) (xy 165.833102 -419.858534)
			(xy 165.861727 -419.80427) (xy 165.896673 -419.753845) (xy 165.937433 -419.707992) (xy 165.983415 -419.667378)
			(xy 166.03395 -419.632591) (xy 166.088305 -419.604139) (xy 166.145688 -419.582435) (xy 166.205266 -419.567794)
			(xy 166.266173 -419.560429) (xy 166.296848 -419.559994) (xy 166.327577 -419.560461) (xy 166.388587 -419.567874)
			(xy 166.448258 -419.582587) (xy 166.505721 -419.604385) (xy 166.560137 -419.632949) (xy 166.610714 -419.667864)
			(xy 166.656714 -419.708621) (xy 166.697466 -419.754625) (xy 166.732377 -419.805206) (xy 166.760936 -419.859625)
			(xy 166.782728 -419.91709) (xy 166.797435 -419.976763) (xy 166.804842 -420.037773) (xy 166.805356 -420.068502)
			(xy 166.80489 -420.099172) (xy 166.797501 -420.160065) (xy 166.782842 -420.219628) (xy 166.775812 -420.2382)
			(xy 167.229742 -420.2382) (xy 167.233757 -420.174398) (xy 167.245736 -420.111602) (xy 167.265491 -420.050802)
			(xy 167.29271 -419.992958) (xy 167.326965 -419.938982) (xy 167.367715 -419.889724) (xy 167.414317 -419.845962)
			(xy 167.466037 -419.808386) (xy 167.522058 -419.777589) (xy 167.581497 -419.754056) (xy 167.643417 -419.738158)
			(xy 167.706842 -419.730147) (xy 167.738806 -419.729666) (xy 167.769249 -419.730098) (xy 167.8297 -419.737362)
			(xy 167.888849 -419.751798) (xy 167.94585 -419.773198) (xy 167.999885 -419.801257) (xy 168.05018 -419.835572)
			(xy 168.096014 -419.87565) (xy 168.13673 -419.920919) (xy 168.154604 -419.945566) (xy 168.16197 -419.955726)
			(xy 168.18356 -419.966902) (xy 168.291764 -419.967156) (xy 168.313354 -419.95598) (xy 168.32072 -419.945566)
			(xy 168.33833 -419.921403) (xy 168.378332 -419.87696) (xy 168.423267 -419.837514) (xy 168.472518 -419.803608)
			(xy 168.525404 -419.77571) (xy 168.581196 -419.754205) (xy 168.639124 -419.739388) (xy 168.6687 -419.735)
			(xy 168.677341 -419.733455) (xy 168.692928 -419.725413) (xy 168.69918 -419.719252) (xy 168.719754 -419.697154)
			(xy 168.725384 -419.690596) (xy 168.732273 -419.674757) (xy 168.733216 -419.666166) (xy 168.73583 -419.637676)
			(xy 168.748405 -419.581868) (xy 168.769175 -419.528563) (xy 168.797672 -419.478959) (xy 168.833258 -419.434166)
			(xy 168.875134 -419.395191) (xy 168.922362 -419.362907) (xy 168.973882 -419.338039) (xy 169.028538 -419.321144)
			(xy 169.085104 -419.312601) (xy 169.113708 -419.31209) (xy 169.140493 -419.312549) (xy 169.193536 -419.320044)
			(xy 169.24501 -419.334886) (xy 169.2939 -419.356783) (xy 169.339247 -419.385304) (xy 169.380158 -419.419889)
			(xy 169.415828 -419.459856) (xy 169.445557 -419.504421) (xy 169.468758 -419.552706) (xy 169.484977 -419.603762)
			(xy 169.489882 -419.630098) (xy 169.49166 -419.63975) (xy 169.501566 -419.65626) (xy 169.573956 -419.710108)
			(xy 169.592498 -419.715188) (xy 169.602404 -419.713918) (xy 169.6179 -419.712134) (xy 169.649036 -419.710229)
			(xy 169.664634 -419.710108) (xy 169.697346 -419.710586) (xy 169.762228 -419.718981) (xy 169.825498 -419.735628)
			(xy 169.886111 -419.760251) (xy 169.943065 -419.792445) (xy 169.995419 -419.831678) (xy 170.019218 -419.854126)
			(xy 170.025848 -419.860092) (xy 170.042109 -419.867394) (xy 170.059886 -419.868699) (xy 170.077039 -419.863849)
			(xy 170.084496 -419.858952) (xy 170.10126 -419.847268) (xy 170.111166 -419.840664) (xy 170.12285 -419.820344)
			(xy 170.130216 -419.716458) (xy 170.121326 -419.694868) (xy 170.112436 -419.686994) (xy 170.089952 -419.666265)
			(xy 170.049574 -419.620336) (xy 170.014993 -419.569897) (xy 169.986708 -419.515677) (xy 169.965128 -419.458457)
			(xy 169.950562 -419.399062) (xy 169.943222 -419.338349) (xy 169.942764 -419.307772) (xy 169.943266 -419.275811)
			(xy 169.951277 -419.212393) (xy 169.967174 -419.150479) (xy 169.990706 -419.091046) (xy 170.0215 -419.035031)
			(xy 170.059073 -418.983316) (xy 170.10283 -418.936719) (xy 170.152083 -418.895974) (xy 170.206054 -418.861723)
			(xy 170.263893 -418.834506) (xy 170.324686 -418.814753) (xy 170.387476 -418.802775) (xy 170.451272 -418.798762)
			(xy 170.515068 -418.802775) (xy 170.577858 -418.814753) (xy 170.638651 -418.834506) (xy 170.69649 -418.861723)
			(xy 170.750461 -418.895974) (xy 170.799714 -418.936719) (xy 170.843471 -418.983316) (xy 170.881044 -419.035031)
			(xy 170.911838 -419.091046) (xy 170.93537 -419.150479) (xy 170.951267 -419.212393) (xy 170.959278 -419.275811)
			(xy 170.95978 -419.307772) (xy 170.959308 -419.338968) (xy 170.951667 -419.400889) (xy 170.936509 -419.461411)
			(xy 170.914061 -419.519624) (xy 170.88466 -419.574653) (xy 170.848748 -419.625673) (xy 170.806865 -419.671917)
			(xy 170.75964 -419.712689) (xy 170.733974 -419.730428) (xy 170.724068 -419.737032) (xy 170.712384 -419.757352)
			(xy 170.705018 -419.861238) (xy 170.713908 -419.882828) (xy 170.722798 -419.890702) (xy 170.745286 -419.911426)
			(xy 170.785663 -419.957356) (xy 170.820243 -420.007796) (xy 170.848526 -420.062018) (xy 170.870106 -420.119239)
			(xy 170.884672 -420.178634) (xy 170.892012 -420.239347) (xy 170.89247 -420.269924) (xy 170.892085 -420.300658)
			(xy 170.884673 -420.361678) (xy 170.869959 -420.421359) (xy 170.848159 -420.478832) (xy 170.819591 -420.533257)
			(xy 170.78467 -420.583843) (xy 170.743906 -420.62985) (xy 170.697894 -420.670608) (xy 170.647304 -420.705523)
			(xy 170.592875 -420.734085) (xy 170.5354 -420.755878) (xy 170.475717 -420.770584) (xy 170.414696 -420.777989)
			(xy 170.383962 -420.778432) (xy 170.351251 -420.777945) (xy 170.286369 -420.76955) (xy 170.2231 -420.752905)
			(xy 170.162487 -420.728283) (xy 170.105533 -420.696091) (xy 170.053177 -420.656861) (xy 170.029378 -420.634414)
			(xy 170.022777 -420.628404) (xy 170.006501 -420.62109) (xy 169.988704 -420.619784) (xy 169.971535 -420.624644)
			(xy 169.9641 -420.629588) (xy 169.937918 -420.648049) (xy 169.881813 -420.678978) (xy 169.822267 -420.702615)
			(xy 169.760224 -420.718585) (xy 169.696667 -420.726637) (xy 169.664634 -420.727124) (xy 169.633993 -420.726682)
			(xy 169.573158 -420.719307) (xy 169.51365 -420.704671) (xy 169.456333 -420.682988) (xy 169.402039 -420.654571)
			(xy 169.351555 -420.619833) (xy 169.305613 -420.579277) (xy 169.284904 -420.55669) (xy 169.277284 -420.548308)
			(xy 169.256964 -420.539418) (xy 169.157142 -420.541704) (xy 169.13733 -420.551356) (xy 169.130218 -420.560246)
			(xy 169.109485 -420.584926) (xy 169.062765 -420.629335) (xy 169.010808 -420.667485) (xy 168.954447 -420.698763)
			(xy 168.894586 -420.722669) (xy 168.832183 -420.738818) (xy 168.768239 -420.746952) (xy 168.73601 -420.747444)
			(xy 168.705568 -420.746996) (xy 168.645118 -420.739734) (xy 168.585969 -420.7253) (xy 168.528968 -420.703902)
			(xy 168.474933 -420.675845) (xy 168.424638 -420.641533) (xy 168.378804 -420.601457) (xy 168.338086 -420.55619)
			(xy 168.320212 -420.531544) (xy 168.312846 -420.521384) (xy 168.291256 -420.510208) (xy 168.183052 -420.509954)
			(xy 168.161462 -420.52113) (xy 168.154096 -420.531544) (xy 168.136231 -420.556128) (xy 168.09551 -420.601239)
			(xy 168.0497 -420.641174) (xy 167.999454 -420.67536) (xy 167.945491 -420.703312) (xy 167.88858 -420.724629)
			(xy 167.829533 -420.739008) (xy 167.769192 -420.746244) (xy 167.738806 -420.746682) (xy 167.706842 -420.746253)
			(xy 167.643417 -420.738242) (xy 167.581497 -420.722344) (xy 167.522058 -420.698811) (xy 167.466037 -420.668014)
			(xy 167.414317 -420.630438) (xy 167.367715 -420.586676) (xy 167.326965 -420.537418) (xy 167.29271 -420.483442)
			(xy 167.265491 -420.425598) (xy 167.245736 -420.364798) (xy 167.233757 -420.302002) (xy 167.229742 -420.2382)
			(xy 166.775812 -420.2382) (xy 166.761127 -420.276995) (xy 166.73267 -420.331334) (xy 166.697884 -420.381857)
			(xy 166.657275 -420.42783) (xy 166.611432 -420.468585) (xy 166.56102 -420.503531) (xy 166.506772 -420.532161)
			(xy 166.449474 -420.554059) (xy 166.389958 -420.568907) (xy 166.359586 -420.5732) (xy 166.345108 -420.574978)
			(xy 166.322502 -420.593012) (xy 166.288212 -420.693342) (xy 166.285495 -420.702413) (xy 166.286231 -420.721322)
			(xy 166.293753 -420.738686) (xy 166.30015 -420.745666) (xy 166.362634 -420.80815) (xy 166.36948 -420.815548)
			(xy 166.377206 -420.834147) (xy 166.37762 -420.844218) (xy 166.37762 -420.907464) (xy 173.080932 -420.907464)
			(xy 173.085003 -420.851842) (xy 173.097129 -420.797405) (xy 173.117052 -420.745314) (xy 173.144348 -420.696679)
			(xy 173.178434 -420.652536) (xy 173.218583 -420.613827) (xy 173.263941 -420.581376) (xy 173.313541 -420.555875)
			(xy 173.366325 -420.537868) (xy 173.421168 -420.527738) (xy 173.476902 -420.525701) (xy 173.532339 -420.531801)
			(xy 173.586296 -420.545907) (xy 173.637625 -420.567719) (xy 173.685231 -420.596773) (xy 173.728099 -420.632448)
			(xy 173.765316 -420.673985) (xy 173.796089 -420.720498) (xy 173.819761 -420.770995) (xy 173.835829 -420.824402)
			(xy 173.843949 -420.879578) (xy 173.844458 -420.907464) (xy 173.843949 -420.93535) (xy 173.835829 -420.990526)
			(xy 173.819761 -421.043933) (xy 173.796089 -421.09443) (xy 173.765316 -421.140943) (xy 173.728099 -421.18248)
			(xy 173.685231 -421.218155) (xy 173.637625 -421.247209) (xy 173.586296 -421.269021) (xy 173.532339 -421.283127)
			(xy 173.476902 -421.289227) (xy 173.421168 -421.28719) (xy 173.366325 -421.27706) (xy 173.313541 -421.259053)
			(xy 173.263941 -421.233552) (xy 173.218583 -421.201101) (xy 173.178434 -421.162392) (xy 173.144348 -421.118249)
			(xy 173.117052 -421.069614) (xy 173.097129 -421.017523) (xy 173.085003 -420.963086) (xy 173.080932 -420.907464)
			(xy 166.37762 -420.907464) (xy 166.37762 -422.103042) (xy 166.378038 -422.113766) (xy 166.386724 -422.13337)
			(xy 166.394384 -422.140888) (xy 166.458646 -422.1988) (xy 166.478966 -422.205404) (xy 166.489888 -422.204134)
			(xy 166.503247 -422.202812) (xy 166.530058 -422.201415) (xy 166.543482 -422.20134) (xy 166.578507 -422.201924)
			(xy 166.647895 -422.211536) (xy 166.715306 -422.23058) (xy 166.779466 -422.258696) (xy 166.83916 -422.295352)
			(xy 166.86657 -422.317164) (xy 166.873758 -422.322489) (xy 166.890648 -422.328339) (xy 166.89959 -422.328594)
			(xy 166.929562 -422.32834) (xy 166.938561 -422.327853) (xy 166.955353 -422.321346) (xy 166.962328 -422.31564)
			(xy 166.985539 -422.296) (xy 167.035812 -422.261799) (xy 167.089804 -422.233835) (xy 167.146744 -422.212505)
			(xy 167.20582 -422.198113) (xy 167.26619 -422.190865) (xy 167.296592 -422.190418) (xy 167.328553 -422.190898)
			(xy 167.391971 -422.198909) (xy 167.453885 -422.214805) (xy 167.513319 -422.238336) (xy 167.569334 -422.26913)
			(xy 167.621049 -422.306702) (xy 167.632731 -422.317672) (xy 170.681902 -422.317672) (xy 170.685973 -422.26205)
			(xy 170.698099 -422.207613) (xy 170.718022 -422.155522) (xy 170.745318 -422.106887) (xy 170.779404 -422.062744)
			(xy 170.819553 -422.024035) (xy 170.864911 -421.991584) (xy 170.914511 -421.966083) (xy 170.967295 -421.948076)
			(xy 171.022138 -421.937946) (xy 171.077872 -421.935909) (xy 171.133309 -421.942009) (xy 171.187266 -421.956115)
			(xy 171.238595 -421.977927) (xy 171.286201 -422.006981) (xy 171.329069 -422.042656) (xy 171.366286 -422.084193)
			(xy 171.397059 -422.130706) (xy 171.420731 -422.181203) (xy 171.436799 -422.23461) (xy 171.444919 -422.289786)
			(xy 171.445428 -422.317672) (xy 171.444919 -422.345558) (xy 171.439871 -422.379859) (xy 171.733712 -422.379859)
			(xy 171.733712 -422.315937) (xy 171.741723 -422.252519) (xy 171.75762 -422.190605) (xy 171.781152 -422.131172)
			(xy 171.811946 -422.075157) (xy 171.849519 -422.023442) (xy 171.893276 -421.976845) (xy 171.942529 -421.9361)
			(xy 171.9965 -421.901849) (xy 172.054339 -421.874632) (xy 172.115132 -421.854879) (xy 172.177922 -421.842901)
			(xy 172.241718 -421.838888) (xy 172.305514 -421.842901) (xy 172.368304 -421.854879) (xy 172.429097 -421.874632)
			(xy 172.486936 -421.901849) (xy 172.540907 -421.9361) (xy 172.59016 -421.976845) (xy 172.633917 -422.023442)
			(xy 172.67149 -422.075157) (xy 172.702284 -422.131172) (xy 172.725816 -422.190605) (xy 172.741713 -422.252519)
			(xy 172.749724 -422.315937) (xy 172.750226 -422.347898) (xy 172.749724 -422.379859) (xy 172.741713 -422.443277)
			(xy 172.725816 -422.505191) (xy 172.702284 -422.564624) (xy 172.67149 -422.620639) (xy 172.633917 -422.672354)
			(xy 172.59016 -422.718951) (xy 172.540907 -422.759696) (xy 172.486936 -422.793947) (xy 172.429097 -422.821164)
			(xy 172.368304 -422.840917) (xy 172.305514 -422.852895) (xy 172.241718 -422.856909) (xy 172.177922 -422.852895)
			(xy 172.115132 -422.840917) (xy 172.054339 -422.821164) (xy 171.9965 -422.793947) (xy 171.942529 -422.759696)
			(xy 171.893276 -422.718951) (xy 171.849519 -422.672354) (xy 171.811946 -422.620639) (xy 171.781152 -422.564624)
			(xy 171.75762 -422.505191) (xy 171.741723 -422.443277) (xy 171.733712 -422.379859) (xy 171.439871 -422.379859)
			(xy 171.436799 -422.400734) (xy 171.420731 -422.454141) (xy 171.397059 -422.504638) (xy 171.366286 -422.551151)
			(xy 171.329069 -422.592688) (xy 171.286201 -422.628363) (xy 171.238595 -422.657417) (xy 171.187266 -422.679229)
			(xy 171.133309 -422.693335) (xy 171.077872 -422.699435) (xy 171.022138 -422.697398) (xy 170.967295 -422.687268)
			(xy 170.914511 -422.669261) (xy 170.864911 -422.64376) (xy 170.819553 -422.611309) (xy 170.779404 -422.5726)
			(xy 170.745318 -422.528457) (xy 170.718022 -422.479822) (xy 170.698099 -422.427731) (xy 170.685973 -422.373294)
			(xy 170.681902 -422.317672) (xy 167.632731 -422.317672) (xy 167.667646 -422.350459) (xy 167.708392 -422.399711)
			(xy 167.742644 -422.453682) (xy 167.769861 -422.511521) (xy 167.789614 -422.572314) (xy 167.801592 -422.635104)
			(xy 167.805606 -422.6989) (xy 167.801592 -422.762696) (xy 167.789614 -422.825486) (xy 167.769861 -422.886279)
			(xy 167.742644 -422.944118) (xy 167.708392 -422.998089) (xy 167.667646 -423.047341) (xy 167.621049 -423.091098)
			(xy 167.569334 -423.12867) (xy 167.513319 -423.159464) (xy 167.453885 -423.182995) (xy 167.391971 -423.198891)
			(xy 167.328553 -423.206902) (xy 167.296592 -423.207434) (xy 167.261568 -423.206848) (xy 167.192182 -423.197233)
			(xy 167.124773 -423.178185) (xy 167.060616 -423.150066) (xy 167.000926 -423.113407) (xy 166.973504 -423.09161)
			(xy 166.966318 -423.086282) (xy 166.949426 -423.080432) (xy 166.940484 -423.08018) (xy 166.910512 -423.080434)
			(xy 166.901515 -423.080925) (xy 166.884726 -423.087435) (xy 166.877746 -423.093134) (xy 166.854535 -423.112774)
			(xy 166.804262 -423.146973) (xy 166.75027 -423.174937) (xy 166.69333 -423.196265) (xy 166.634254 -423.210655)
			(xy 166.573884 -423.2179) (xy 166.543482 -423.218356) (xy 166.530058 -423.218274) (xy 166.503247 -423.216878)
			(xy 166.489888 -423.215562) (xy 166.478966 -423.214292) (xy 166.458646 -423.220896) (xy 166.394384 -423.278808)
			(xy 166.386845 -423.286408) (xy 166.378196 -423.305963) (xy 166.37762 -423.316654) (xy 166.37762 -423.39387)
			(xy 166.378185 -423.40554) (xy 166.3885 -423.426473) (xy 166.397432 -423.434002) (xy 166.470584 -423.49039)
			(xy 166.493444 -423.495216) (xy 166.505128 -423.491914) (xy 166.528955 -423.486059) (xy 166.577623 -423.479821)
			(xy 166.602156 -423.479468) (xy 166.629413 -423.479928) (xy 166.683372 -423.48768) (xy 166.735678 -423.503033)
			(xy 166.785267 -423.525675) (xy 166.831129 -423.555144) (xy 166.872329 -423.59084) (xy 166.90803 -423.632036)
			(xy 166.937504 -423.677894) (xy 166.960151 -423.72748) (xy 166.97551 -423.779785) (xy 166.983269 -423.833743)
			(xy 166.983269 -423.888257) (xy 166.97551 -423.942215) (xy 166.960151 -423.99452) (xy 166.937504 -424.044106)
			(xy 166.90803 -424.089964) (xy 166.872329 -424.13116) (xy 166.831129 -424.166856) (xy 166.785267 -424.196325)
			(xy 166.735678 -424.218967) (xy 166.683372 -424.23432) (xy 166.629413 -424.242072) (xy 166.602156 -424.242484)
			(xy 166.575956 -424.242055) (xy 166.524048 -424.234894) (xy 166.473608 -424.2207) (xy 166.425583 -424.19974)
			(xy 166.380877 -424.172407) (xy 166.360348 -424.156124) (xy 166.345108 -424.143678) (xy 166.305992 -424.14571)
			(xy 165.5318 -424.919902) (xy 165.52529 -424.927045) (xy 165.517705 -424.944803) (xy 165.517068 -424.954446)
			(xy 165.515036 -425.034202) (xy 165.52164 -425.05249) (xy 165.528244 -425.059856) (xy 165.54874 -425.083273)
			(xy 165.584483 -425.134218) (xy 165.613751 -425.18914) (xy 165.636105 -425.24722) (xy 165.651214 -425.307591)
			(xy 165.658851 -425.369354) (xy 165.659308 -425.40047) (xy 165.659088 -425.4157) (xy 167.519078 -425.4157)
			(xy 167.523092 -425.351902) (xy 167.535071 -425.28911) (xy 167.554825 -425.228314) (xy 167.582043 -425.170474)
			(xy 167.616296 -425.116501) (xy 167.657043 -425.067247) (xy 167.703643 -425.023488) (xy 167.755359 -424.985915)
			(xy 167.811377 -424.95512) (xy 167.870813 -424.931589) (xy 167.932729 -424.915693) (xy 167.99615 -424.907682)
			(xy 168.028112 -424.907202) (xy 168.060271 -424.907691) (xy 168.124075 -424.915813) (xy 168.186347 -424.931912)
			(xy 168.246092 -424.955733) (xy 168.302358 -424.986895) (xy 168.328594 -425.0055) (xy 168.337683 -425.011549)
			(xy 168.359036 -425.016005) (xy 168.380309 -425.011187) (xy 168.3893 -425.004992) (xy 168.415911 -424.985504)
			(xy 168.473206 -424.952824) (xy 168.534243 -424.927822) (xy 168.598 -424.910917) (xy 168.663406 -424.902392)
			(xy 168.696386 -424.901868) (xy 168.728347 -424.902396) (xy 168.791766 -424.910406) (xy 168.853681 -424.926302)
			(xy 168.913116 -424.949832) (xy 168.969132 -424.980626) (xy 169.020848 -425.018198) (xy 169.067446 -425.061955)
			(xy 169.108192 -425.111208) (xy 169.142445 -425.16518) (xy 169.169662 -425.223019) (xy 169.189416 -425.283813)
			(xy 169.198579 -425.331847) (xy 170.52518 -425.331847) (xy 170.52518 -425.267925) (xy 170.533191 -425.204507)
			(xy 170.549088 -425.142593) (xy 170.57262 -425.08316) (xy 170.603414 -425.027145) (xy 170.640987 -424.97543)
			(xy 170.684744 -424.928833) (xy 170.733997 -424.888088) (xy 170.787968 -424.853837) (xy 170.845807 -424.82662)
			(xy 170.9066 -424.806867) (xy 170.96939 -424.794889) (xy 171.033186 -424.790876) (xy 171.096982 -424.794889)
			(xy 171.159772 -424.806867) (xy 171.220565 -424.82662) (xy 171.278404 -424.853837) (xy 171.332375 -424.888088)
			(xy 171.381628 -424.928833) (xy 171.425385 -424.97543) (xy 171.462958 -425.027145) (xy 171.493752 -425.08316)
			(xy 171.517284 -425.142593) (xy 171.533181 -425.204507) (xy 171.541192 -425.267925) (xy 171.541694 -425.299886)
			(xy 171.541192 -425.331847) (xy 171.533181 -425.395265) (xy 171.517284 -425.457179) (xy 171.493752 -425.516612)
			(xy 171.487085 -425.52874) (xy 173.642782 -425.52874) (xy 173.643221 -425.498279) (xy 173.650497 -425.437792)
			(xy 173.664948 -425.378608) (xy 173.686369 -425.321576) (xy 173.714452 -425.267512) (xy 173.748794 -425.217191)
			(xy 173.768512 -425.193968) (xy 173.774023 -425.187117) (xy 173.780381 -425.170738) (xy 173.780958 -425.161964)
			(xy 173.781974 -425.132246) (xy 173.781889 -425.123424) (xy 173.776429 -425.106662) (xy 173.771306 -425.09948)
			(xy 173.751094 -425.072598) (xy 173.717135 -425.014547) (xy 173.691131 -424.952522) (xy 173.673538 -424.887609)
			(xy 173.664663 -424.820942) (xy 173.664118 -424.787314) (xy 173.664582 -424.755594) (xy 173.672477 -424.692646)
			(xy 173.688145 -424.631171) (xy 173.711343 -424.572124) (xy 173.741709 -424.516423) (xy 173.778773 -424.464935)
			(xy 173.800008 -424.441366) (xy 173.806029 -424.434155) (xy 173.81294 -424.416708) (xy 173.81347 -424.40733)
			(xy 173.813724 -424.376342) (xy 173.813349 -424.36694) (xy 173.806705 -424.349353) (xy 173.80077 -424.342052)
			(xy 173.780496 -424.318675) (xy 173.745138 -424.267889) (xy 173.716202 -424.21319) (xy 173.694116 -424.155384)
			(xy 173.679206 -424.095326) (xy 173.671691 -424.033903) (xy 173.67123 -424.002962) (xy 173.671732 -423.971001)
			(xy 173.679743 -423.907583) (xy 173.69564 -423.845669) (xy 173.719172 -423.786236) (xy 173.749966 -423.730221)
			(xy 173.787539 -423.678506) (xy 173.831296 -423.631909) (xy 173.880549 -423.591164) (xy 173.93452 -423.556913)
			(xy 173.992359 -423.529696) (xy 174.053152 -423.509943) (xy 174.115942 -423.497965) (xy 174.179738 -423.493952)
			(xy 174.243534 -423.497965) (xy 174.306324 -423.509943) (xy 174.367117 -423.529696) (xy 174.424956 -423.556913)
			(xy 174.478927 -423.591164) (xy 174.52818 -423.631909) (xy 174.571937 -423.678506) (xy 174.60951 -423.730221)
			(xy 174.640304 -423.786236) (xy 174.663836 -423.845669) (xy 174.679733 -423.907583) (xy 174.687744 -423.971001)
			(xy 174.688246 -424.002962) (xy 174.687777 -424.034682) (xy 174.679884 -424.09763) (xy 174.664218 -424.159106)
			(xy 174.641021 -424.218153) (xy 174.610655 -424.273854) (xy 174.573591 -424.325341) (xy 174.552356 -424.34891)
			(xy 174.546299 -424.356094) (xy 174.53941 -424.373562) (xy 174.538894 -424.382946) (xy 174.53864 -424.413934)
			(xy 174.539035 -424.423334) (xy 174.545666 -424.44092) (xy 174.551594 -424.448224) (xy 174.571899 -424.471576)
			(xy 174.607254 -424.522367) (xy 174.636186 -424.577071) (xy 174.658267 -424.634882) (xy 174.673171 -424.694945)
			(xy 174.680677 -424.756372) (xy 174.681134 -424.787314) (xy 174.680664 -424.817774) (xy 174.673394 -424.87826)
			(xy 174.658948 -424.937443) (xy 174.637533 -424.994475) (xy 174.609456 -425.04854) (xy 174.575119 -425.098862)
			(xy 174.555404 -425.122086) (xy 174.549914 -425.128951) (xy 174.543544 -425.145319) (xy 174.542958 -425.15409)
			(xy 174.542046 -425.18076) (xy 175.635412 -425.18076) (xy 175.635857 -425.150329) (xy 175.643131 -425.089904)
			(xy 175.657559 -425.030777) (xy 175.678935 -424.973793) (xy 175.706954 -424.919765) (xy 175.741215 -424.869463)
			(xy 175.760888 -424.846242) (xy 175.766301 -424.839554) (xy 175.772662 -424.823578) (xy 175.773334 -424.815)
			(xy 175.774604 -424.785536) (xy 175.774551 -424.777) (xy 175.769638 -424.760666) (xy 175.764952 -424.753532)
			(xy 175.746553 -424.727386) (xy 175.715761 -424.671356) (xy 175.692242 -424.611906) (xy 175.676366 -424.549975)
			(xy 175.668386 -424.486541) (xy 175.667924 -424.454574) (xy 175.668426 -424.422613) (xy 175.676437 -424.359195)
			(xy 175.692334 -424.297281) (xy 175.715866 -424.237848) (xy 175.74666 -424.181833) (xy 175.784233 -424.130118)
			(xy 175.82799 -424.083521) (xy 175.877243 -424.042776) (xy 175.931214 -424.008525) (xy 175.989053 -423.981308)
			(xy 176.049846 -423.961555) (xy 176.112636 -423.949577) (xy 176.176432 -423.945564) (xy 176.240228 -423.949577)
			(xy 176.303018 -423.961555) (xy 176.363811 -423.981308) (xy 176.42165 -424.008525) (xy 176.475621 -424.042776)
			(xy 176.524874 -424.083521) (xy 176.568631 -424.130118) (xy 176.606204 -424.181833) (xy 176.636998 -424.237848)
			(xy 176.66053 -424.297281) (xy 176.676427 -424.359195) (xy 176.684438 -424.422613) (xy 176.68494 -424.454574)
			(xy 176.684468 -424.485004) (xy 176.677201 -424.545429) (xy 176.662779 -424.604555) (xy 176.641408 -424.66154)
			(xy 176.613394 -424.715569) (xy 176.579135 -424.765871) (xy 176.559464 -424.789092) (xy 176.554043 -424.795775)
			(xy 176.547686 -424.811754) (xy 176.547018 -424.820334) (xy 176.545748 -424.849798) (xy 176.545777 -424.858336)
			(xy 176.550706 -424.87467) (xy 176.5554 -424.881802) (xy 176.57382 -424.907933) (xy 176.604607 -424.963968)
			(xy 176.628122 -425.023422) (xy 176.643993 -425.085356) (xy 176.651968 -425.148792) (xy 176.652428 -425.18076)
			(xy 176.651926 -425.212721) (xy 176.643915 -425.276139) (xy 176.628018 -425.338053) (xy 176.604486 -425.397486)
			(xy 176.573692 -425.453501) (xy 176.536119 -425.505216) (xy 176.492362 -425.551813) (xy 176.443109 -425.592558)
			(xy 176.389138 -425.626809) (xy 176.331299 -425.654026) (xy 176.270506 -425.673779) (xy 176.207716 -425.685757)
			(xy 176.14392 -425.689771) (xy 176.080124 -425.685757) (xy 176.017334 -425.673779) (xy 175.956541 -425.654026)
			(xy 175.898702 -425.626809) (xy 175.844731 -425.592558) (xy 175.795478 -425.551813) (xy 175.751721 -425.505216)
			(xy 175.714148 -425.453501) (xy 175.683354 -425.397486) (xy 175.659822 -425.338053) (xy 175.643925 -425.276139)
			(xy 175.635914 -425.212721) (xy 175.635412 -425.18076) (xy 174.542046 -425.18076) (xy 174.541942 -425.183808)
			(xy 174.542046 -425.192629) (xy 174.547493 -425.20939) (xy 174.55261 -425.216574) (xy 174.572849 -425.243436)
			(xy 174.606803 -425.301494) (xy 174.632801 -425.363523) (xy 174.650388 -425.428441) (xy 174.659256 -425.495111)
			(xy 174.659798 -425.52874) (xy 174.659296 -425.560701) (xy 174.651285 -425.624119) (xy 174.635388 -425.686033)
			(xy 174.611856 -425.745466) (xy 174.581062 -425.801481) (xy 174.543489 -425.853196) (xy 174.499732 -425.899793)
			(xy 174.450479 -425.940538) (xy 174.396508 -425.974789) (xy 174.338669 -426.002006) (xy 174.277876 -426.021759)
			(xy 174.215086 -426.033737) (xy 174.15129 -426.037751) (xy 174.087494 -426.033737) (xy 174.024704 -426.021759)
			(xy 173.963911 -426.002006) (xy 173.906072 -425.974789) (xy 173.852101 -425.940538) (xy 173.802848 -425.899793)
			(xy 173.759091 -425.853196) (xy 173.721518 -425.801481) (xy 173.690724 -425.745466) (xy 173.667192 -425.686033)
			(xy 173.651295 -425.624119) (xy 173.643284 -425.560701) (xy 173.642782 -425.52874) (xy 171.487085 -425.52874)
			(xy 171.462958 -425.572627) (xy 171.425385 -425.624342) (xy 171.381628 -425.670939) (xy 171.332375 -425.711684)
			(xy 171.278404 -425.745935) (xy 171.220565 -425.773152) (xy 171.159772 -425.792905) (xy 171.096982 -425.804883)
			(xy 171.033186 -425.808897) (xy 170.96939 -425.804883) (xy 170.9066 -425.792905) (xy 170.845807 -425.773152)
			(xy 170.787968 -425.745935) (xy 170.733997 -425.711684) (xy 170.684744 -425.670939) (xy 170.640987 -425.624342)
			(xy 170.603414 -425.572627) (xy 170.57262 -425.516612) (xy 170.549088 -425.457179) (xy 170.533191 -425.395265)
			(xy 170.52518 -425.331847) (xy 169.198579 -425.331847) (xy 169.201394 -425.346603) (xy 169.205408 -425.4104)
			(xy 169.201394 -425.474197) (xy 169.189416 -425.536987) (xy 169.169662 -425.597781) (xy 169.142445 -425.65562)
			(xy 169.108192 -425.709592) (xy 169.067446 -425.758845) (xy 169.020848 -425.802602) (xy 168.969132 -425.840174)
			(xy 168.913116 -425.870968) (xy 168.853681 -425.894498) (xy 168.791766 -425.910394) (xy 168.728347 -425.918404)
			(xy 168.696386 -425.918884) (xy 168.664226 -425.918399) (xy 168.600422 -425.910277) (xy 168.538151 -425.894176)
			(xy 168.478405 -425.870355) (xy 168.42214 -425.839192) (xy 168.395904 -425.820586) (xy 168.386815 -425.814537)
			(xy 168.365463 -425.810083) (xy 168.344189 -425.8149) (xy 168.335198 -425.821094) (xy 168.308586 -425.840581)
			(xy 168.251292 -425.873262) (xy 168.190254 -425.898264) (xy 168.126498 -425.915169) (xy 168.061092 -425.923694)
			(xy 168.028112 -425.924218) (xy 167.99615 -425.923718) (xy 167.932729 -425.915707) (xy 167.870813 -425.899811)
			(xy 167.811377 -425.87628) (xy 167.755359 -425.845485) (xy 167.703643 -425.807912) (xy 167.657043 -425.764153)
			(xy 167.616296 -425.714899) (xy 167.582043 -425.660926) (xy 167.554825 -425.603086) (xy 167.535071 -425.54229)
			(xy 167.523092 -425.479498) (xy 167.519078 -425.4157) (xy 165.659088 -425.4157) (xy 165.658864 -425.431203)
			(xy 165.651458 -425.492222) (xy 165.636752 -425.551903) (xy 165.614958 -425.609376) (xy 165.586395 -425.663803)
			(xy 165.55148 -425.714391) (xy 165.510722 -425.7604) (xy 165.464714 -425.801161) (xy 165.414129 -425.83608)
			(xy 165.359704 -425.864645) (xy 165.302232 -425.886443) (xy 165.242552 -425.901153) (xy 165.181533 -425.908562)
			(xy 165.1508 -425.908978) (xy 165.117241 -425.90844) (xy 165.050704 -425.899613) (xy 164.985907 -425.882112)
			(xy 164.923974 -425.856242) (xy 164.865982 -425.822451) (xy 164.839142 -425.802298) (xy 164.829887 -425.795845)
			(xy 164.8079 -425.790917) (xy 164.785913 -425.795845) (xy 164.776658 -425.802298) (xy 164.753152 -425.819978)
			(xy 164.70281 -425.850399) (xy 164.649297 -425.874814) (xy 164.593325 -425.892895) (xy 164.564568 -425.899072)
			(xy 164.556948 -425.900596) (xy 164.544248 -425.907454) (xy 163.586922 -426.86478) (xy 163.579139 -426.873263)
			(xy 163.571472 -426.894946) (xy 163.57219 -426.906436) (xy 163.58235 -426.99686) (xy 163.594542 -427.016418)
			(xy 163.604448 -427.022514) (xy 163.631225 -427.040048) (xy 163.680573 -427.080811) (xy 163.724419 -427.127442)
			(xy 163.762069 -427.179205) (xy 163.792928 -427.235281) (xy 163.816511 -427.294785) (xy 163.832443 -427.356778)
			(xy 163.840474 -427.420279) (xy 163.840805 -427.4439) (xy 164.082982 -427.4439) (xy 164.087053 -427.388278)
			(xy 164.099179 -427.333841) (xy 164.119102 -427.28175) (xy 164.146398 -427.233115) (xy 164.180484 -427.188972)
			(xy 164.220633 -427.150263) (xy 164.265991 -427.117812) (xy 164.315591 -427.092311) (xy 164.368375 -427.074304)
			(xy 164.423218 -427.064174) (xy 164.478952 -427.062137) (xy 164.534389 -427.068237) (xy 164.588346 -427.082343)
			(xy 164.639675 -427.104155) (xy 164.687281 -427.133209) (xy 164.730149 -427.168884) (xy 164.767366 -427.210421)
			(xy 164.798139 -427.256934) (xy 164.821811 -427.307431) (xy 164.837879 -427.360838) (xy 164.845999 -427.416014)
			(xy 164.846508 -427.4439) (xy 164.845999 -427.471786) (xy 164.837879 -427.526962) (xy 164.821811 -427.580369)
			(xy 164.821388 -427.581271) (xy 165.39311 -427.581271) (xy 165.39311 -427.517349) (xy 165.401121 -427.453931)
			(xy 165.417018 -427.392017) (xy 165.44055 -427.332584) (xy 165.471344 -427.276569) (xy 165.508917 -427.224854)
			(xy 165.552674 -427.178257) (xy 165.601927 -427.137512) (xy 165.655898 -427.103261) (xy 165.713737 -427.076044)
			(xy 165.77453 -427.056291) (xy 165.83732 -427.044313) (xy 165.901116 -427.0403) (xy 165.964912 -427.044313)
			(xy 166.027702 -427.056291) (xy 166.088495 -427.076044) (xy 166.146334 -427.103261) (xy 166.200305 -427.137512)
			(xy 166.249558 -427.178257) (xy 166.293315 -427.224854) (xy 166.330888 -427.276569) (xy 166.340353 -427.293786)
			(xy 173.731172 -427.293786) (xy 173.735243 -427.238164) (xy 173.747369 -427.183727) (xy 173.767292 -427.131636)
			(xy 173.794588 -427.083001) (xy 173.828674 -427.038858) (xy 173.868823 -427.000149) (xy 173.914181 -426.967698)
			(xy 173.963781 -426.942197) (xy 174.016565 -426.92419) (xy 174.071408 -426.91406) (xy 174.127142 -426.912023)
			(xy 174.182579 -426.918123) (xy 174.236536 -426.932229) (xy 174.287865 -426.954041) (xy 174.335471 -426.983095)
			(xy 174.378339 -427.01877) (xy 174.415556 -427.060307) (xy 174.446329 -427.10682) (xy 174.470001 -427.157317)
			(xy 174.486069 -427.210724) (xy 174.494189 -427.2659) (xy 174.494698 -427.293786) (xy 174.494605 -427.298866)
			(xy 180.555898 -427.298866) (xy 180.559969 -427.243244) (xy 180.572095 -427.188807) (xy 180.592018 -427.136716)
			(xy 180.619314 -427.088081) (xy 180.6534 -427.043938) (xy 180.693549 -427.005229) (xy 180.738907 -426.972778)
			(xy 180.788507 -426.947277) (xy 180.841291 -426.92927) (xy 180.896134 -426.91914) (xy 180.951868 -426.917103)
			(xy 181.007305 -426.923203) (xy 181.061262 -426.937309) (xy 181.112591 -426.959121) (xy 181.160197 -426.988175)
			(xy 181.203065 -427.02385) (xy 181.240282 -427.065387) (xy 181.271055 -427.1119) (xy 181.294727 -427.162397)
			(xy 181.310795 -427.215804) (xy 181.318915 -427.27098) (xy 181.319424 -427.298866) (xy 181.318915 -427.326752)
			(xy 181.310795 -427.381928) (xy 181.294727 -427.435335) (xy 181.271055 -427.485832) (xy 181.240282 -427.532345)
			(xy 181.203065 -427.573882) (xy 181.160197 -427.609557) (xy 181.112591 -427.638611) (xy 181.061262 -427.660423)
			(xy 181.007305 -427.674529) (xy 180.951868 -427.680629) (xy 180.896134 -427.678592) (xy 180.841291 -427.668462)
			(xy 180.788507 -427.650455) (xy 180.738907 -427.624954) (xy 180.693549 -427.592503) (xy 180.6534 -427.553794)
			(xy 180.619314 -427.509651) (xy 180.592018 -427.461016) (xy 180.572095 -427.408925) (xy 180.559969 -427.354488)
			(xy 180.555898 -427.298866) (xy 174.494605 -427.298866) (xy 174.494189 -427.321672) (xy 174.486069 -427.376848)
			(xy 174.470001 -427.430255) (xy 174.446329 -427.480752) (xy 174.415556 -427.527265) (xy 174.378339 -427.568802)
			(xy 174.335471 -427.604477) (xy 174.287865 -427.633531) (xy 174.236536 -427.655343) (xy 174.182579 -427.669449)
			(xy 174.127142 -427.675549) (xy 174.071408 -427.673512) (xy 174.016565 -427.663382) (xy 173.963781 -427.645375)
			(xy 173.914181 -427.619874) (xy 173.868823 -427.587423) (xy 173.828674 -427.548714) (xy 173.794588 -427.504571)
			(xy 173.767292 -427.455936) (xy 173.747369 -427.403845) (xy 173.735243 -427.349408) (xy 173.731172 -427.293786)
			(xy 166.340353 -427.293786) (xy 166.361682 -427.332584) (xy 166.385214 -427.392017) (xy 166.401111 -427.453931)
			(xy 166.409122 -427.517349) (xy 166.409624 -427.54931) (xy 166.409122 -427.581271) (xy 166.401111 -427.644689)
			(xy 166.385214 -427.706603) (xy 166.361682 -427.766036) (xy 166.330888 -427.822051) (xy 166.293315 -427.873766)
			(xy 166.249558 -427.920363) (xy 166.200305 -427.961108) (xy 166.146334 -427.995359) (xy 166.088495 -428.022576)
			(xy 166.027702 -428.042329) (xy 165.964912 -428.054307) (xy 165.901116 -428.058321) (xy 165.83732 -428.054307)
			(xy 165.77453 -428.042329) (xy 165.713737 -428.022576) (xy 165.655898 -427.995359) (xy 165.601927 -427.961108)
			(xy 165.552674 -427.920363) (xy 165.508917 -427.873766) (xy 165.471344 -427.822051) (xy 165.44055 -427.766036)
			(xy 165.417018 -427.706603) (xy 165.401121 -427.644689) (xy 165.39311 -427.581271) (xy 164.821388 -427.581271)
			(xy 164.798139 -427.630866) (xy 164.767366 -427.677379) (xy 164.730149 -427.718916) (xy 164.687281 -427.754591)
			(xy 164.639675 -427.783645) (xy 164.588346 -427.805457) (xy 164.534389 -427.819563) (xy 164.478952 -427.825663)
			(xy 164.423218 -427.823626) (xy 164.368375 -427.813496) (xy 164.315591 -427.795489) (xy 164.265991 -427.769988)
			(xy 164.220633 -427.737537) (xy 164.180484 -427.698828) (xy 164.146398 -427.654685) (xy 164.119102 -427.60605)
			(xy 164.099179 -427.553959) (xy 164.087053 -427.499522) (xy 164.082982 -427.4439) (xy 163.840805 -427.4439)
			(xy 163.840922 -427.452282) (xy 163.840477 -427.483015) (xy 163.833071 -427.544033) (xy 163.818363 -427.603714)
			(xy 163.796569 -427.661187) (xy 163.768006 -427.715613) (xy 163.73309 -427.7662) (xy 163.692332 -427.81221)
			(xy 163.646325 -427.852971) (xy 163.595741 -427.887889) (xy 163.541316 -427.916455) (xy 163.483845 -427.938253)
			(xy 163.424165 -427.952965) (xy 163.363147 -427.960375) (xy 163.332414 -427.96079) (xy 163.300411 -427.960308)
			(xy 163.236911 -427.952282) (xy 163.174918 -427.936356) (xy 163.115413 -427.912779) (xy 163.059335 -427.881926)
			(xy 163.007569 -427.844283) (xy 162.960933 -427.800444) (xy 162.920164 -427.751102) (xy 162.902646 -427.724316)
			(xy 162.89655 -427.71441) (xy 162.876992 -427.702218) (xy 162.786568 -427.692058) (xy 162.775079 -427.691334)
			(xy 162.7534 -427.699011) (xy 162.744912 -427.70679) (xy 162.458654 -427.993048) (xy 162.451809 -428.000447)
			(xy 162.444084 -428.019045) (xy 162.443668 -428.029116) (xy 162.443668 -428.577967) (xy 164.632126 -428.577967)
			(xy 164.632126 -428.514045) (xy 164.640137 -428.450627) (xy 164.656034 -428.388713) (xy 164.679566 -428.32928)
			(xy 164.71036 -428.273265) (xy 164.747933 -428.22155) (xy 164.79169 -428.174953) (xy 164.840943 -428.134208)
			(xy 164.894914 -428.099957) (xy 164.952753 -428.07274) (xy 165.013546 -428.052987) (xy 165.076336 -428.041009)
			(xy 165.140132 -428.036996) (xy 165.203928 -428.041009) (xy 165.266718 -428.052987) (xy 165.327511 -428.07274)
			(xy 165.38535 -428.099957) (xy 165.439321 -428.134208) (xy 165.488574 -428.174953) (xy 165.532331 -428.22155)
			(xy 165.547589 -428.242551) (xy 176.250576 -428.242551) (xy 176.250576 -428.188049) (xy 176.258332 -428.134101)
			(xy 176.273688 -428.081806) (xy 176.296329 -428.032228) (xy 176.325795 -427.986377) (xy 176.361487 -427.945187)
			(xy 176.402677 -427.909495) (xy 176.448528 -427.880029) (xy 176.498106 -427.857388) (xy 176.550401 -427.842032)
			(xy 176.604349 -427.834276) (xy 176.6316 -427.83379) (xy 176.658438 -427.834271) (xy 176.711584 -427.841807)
			(xy 176.763144 -427.85673) (xy 176.78781 -427.867318) (xy 176.79797 -427.87189) (xy 176.819814 -427.871636)
			(xy 176.909476 -427.830488) (xy 176.9237 -427.814232) (xy 176.927002 -427.803564) (xy 176.935157 -427.777603)
			(xy 176.957836 -427.728139) (xy 176.987316 -427.682401) (xy 177.022998 -427.641318) (xy 177.064157 -427.605724)
			(xy 177.109959 -427.576343) (xy 177.159472 -427.55377) (xy 177.21169 -427.538466) (xy 177.265554 -427.530739)
			(xy 177.292762 -427.53026) (xy 177.320014 -427.530785) (xy 177.373965 -427.538537) (xy 177.426263 -427.553888)
			(xy 177.475844 -427.576526) (xy 177.521698 -427.605991) (xy 177.562891 -427.641682) (xy 177.598586 -427.682872)
			(xy 177.628055 -427.728723) (xy 177.638803 -427.752256) (xy 178.780946 -427.752256) (xy 178.785017 -427.696634)
			(xy 178.797143 -427.642197) (xy 178.817066 -427.590106) (xy 178.844362 -427.541471) (xy 178.878448 -427.497328)
			(xy 178.918597 -427.458619) (xy 178.963955 -427.426168) (xy 179.013555 -427.400667) (xy 179.066339 -427.38266)
			(xy 179.121182 -427.37253) (xy 179.176916 -427.370493) (xy 179.232353 -427.376593) (xy 179.28631 -427.390699)
			(xy 179.337639 -427.412511) (xy 179.385245 -427.441565) (xy 179.428113 -427.47724) (xy 179.46533 -427.518777)
			(xy 179.496103 -427.56529) (xy 179.519775 -427.615787) (xy 179.535843 -427.669194) (xy 179.543963 -427.72437)
			(xy 179.544472 -427.752256) (xy 179.543963 -427.780142) (xy 179.535843 -427.835318) (xy 179.519775 -427.888725)
			(xy 179.496103 -427.939222) (xy 179.46533 -427.985735) (xy 179.428113 -428.027272) (xy 179.385245 -428.062947)
			(xy 179.337639 -428.092001) (xy 179.28631 -428.113813) (xy 179.232353 -428.127919) (xy 179.176916 -428.134019)
			(xy 179.121182 -428.131982) (xy 179.066339 -428.121852) (xy 179.013555 -428.103845) (xy 178.963955 -428.078344)
			(xy 178.918597 -428.045893) (xy 178.878448 -428.007184) (xy 178.844362 -427.963041) (xy 178.817066 -427.914406)
			(xy 178.797143 -427.862315) (xy 178.785017 -427.807878) (xy 178.780946 -427.752256) (xy 177.638803 -427.752256)
			(xy 177.650699 -427.778301) (xy 177.666055 -427.830598) (xy 177.673813 -427.884548) (xy 177.673813 -427.939052)
			(xy 177.666055 -427.993002) (xy 177.650699 -428.045299) (xy 177.628055 -428.094877) (xy 177.598586 -428.140728)
			(xy 177.562891 -428.181918) (xy 177.521698 -428.217609) (xy 177.475844 -428.247074) (xy 177.426263 -428.269712)
			(xy 177.373965 -428.285063) (xy 177.320014 -428.292815) (xy 177.292762 -428.293276) (xy 177.265923 -428.292811)
			(xy 177.212777 -428.285269) (xy 177.161217 -428.27034) (xy 177.136552 -428.259748) (xy 177.126392 -428.255176)
			(xy 177.104548 -428.25543) (xy 177.014886 -428.296578) (xy 177.000662 -428.312834) (xy 176.99736 -428.323502)
			(xy 176.989217 -428.349468) (xy 176.96654 -428.398934) (xy 176.93706 -428.444675) (xy 176.901377 -428.485759)
			(xy 176.860216 -428.521354) (xy 176.814412 -428.550735) (xy 176.764897 -428.573305) (xy 176.712675 -428.588607)
			(xy 176.658809 -428.596329) (xy 176.6316 -428.596806) (xy 176.604349 -428.596324) (xy 176.550401 -428.588568)
			(xy 176.498106 -428.573212) (xy 176.448528 -428.550571) (xy 176.402677 -428.521105) (xy 176.361487 -428.485413)
			(xy 176.325795 -428.444223) (xy 176.296329 -428.398372) (xy 176.273688 -428.348794) (xy 176.258332 -428.296499)
			(xy 176.250576 -428.242551) (xy 165.547589 -428.242551) (xy 165.569904 -428.273265) (xy 165.600698 -428.32928)
			(xy 165.62423 -428.388713) (xy 165.640127 -428.450627) (xy 165.648138 -428.514045) (xy 165.64864 -428.546006)
			(xy 165.648138 -428.577967) (xy 165.640127 -428.641385) (xy 165.62423 -428.703299) (xy 165.600698 -428.762732)
			(xy 165.569904 -428.818747) (xy 165.532331 -428.870462) (xy 165.488574 -428.917059) (xy 165.439321 -428.957804)
			(xy 165.38535 -428.992055) (xy 165.327511 -429.019272) (xy 165.266718 -429.039025) (xy 165.203928 -429.051003)
			(xy 165.140132 -429.055017) (xy 165.076336 -429.051003) (xy 165.013546 -429.039025) (xy 164.952753 -429.019272)
			(xy 164.894914 -428.992055) (xy 164.840943 -428.957804) (xy 164.79169 -428.917059) (xy 164.747933 -428.870462)
			(xy 164.71036 -428.818747) (xy 164.679566 -428.762732) (xy 164.656034 -428.703299) (xy 164.640137 -428.641385)
			(xy 164.632126 -428.577967) (xy 162.443668 -428.577967) (xy 162.443668 -429.459644) (xy 170.212256 -429.459644)
			(xy 170.216327 -429.404022) (xy 170.228453 -429.349585) (xy 170.248376 -429.297494) (xy 170.275672 -429.248859)
			(xy 170.309758 -429.204716) (xy 170.349907 -429.166007) (xy 170.395265 -429.133556) (xy 170.444865 -429.108055)
			(xy 170.497649 -429.090048) (xy 170.552492 -429.079918) (xy 170.608226 -429.077881) (xy 170.663663 -429.083981)
			(xy 170.71762 -429.098087) (xy 170.768949 -429.119899) (xy 170.816555 -429.148953) (xy 170.859423 -429.184628)
			(xy 170.89664 -429.226165) (xy 170.927413 -429.272678) (xy 170.951085 -429.323175) (xy 170.967153 -429.376582)
			(xy 170.975273 -429.431758) (xy 170.975782 -429.459644) (xy 170.975273 -429.48753) (xy 170.967153 -429.542706)
			(xy 170.951085 -429.596113) (xy 170.927413 -429.64661) (xy 170.89664 -429.693123) (xy 170.859423 -429.73466)
			(xy 170.816555 -429.770335) (xy 170.768949 -429.799389) (xy 170.71762 -429.821201) (xy 170.663663 -429.835307)
			(xy 170.608226 -429.841407) (xy 170.552492 -429.83937) (xy 170.497649 -429.82924) (xy 170.444865 -429.811233)
			(xy 170.395265 -429.785732) (xy 170.349907 -429.753281) (xy 170.309758 -429.714572) (xy 170.275672 -429.670429)
			(xy 170.248376 -429.621794) (xy 170.228453 -429.569703) (xy 170.216327 -429.515266) (xy 170.212256 -429.459644)
			(xy 162.443668 -429.459644) (xy 162.443668 -431.3936) (xy 167.09009 -431.3936) (xy 167.090584 -431.361738)
			(xy 167.098546 -431.298513) (xy 167.114345 -431.236778) (xy 167.137734 -431.177502) (xy 167.168346 -431.121612)
			(xy 167.205702 -431.069985) (xy 167.249215 -431.02343) (xy 167.298204 -430.982676) (xy 167.324786 -430.965102)
			(xy 167.337263 -430.956505) (xy 167.356824 -430.933381) (xy 167.368757 -430.905543) (xy 167.372017 -430.875431)
			(xy 167.366316 -430.845685) (xy 167.352156 -430.818911) (xy 167.330776 -430.797457) (xy 167.317674 -430.789842)
			(xy 167.291883 -430.775503) (xy 167.244654 -430.740129) (xy 167.203439 -430.697901) (xy 167.169222 -430.649827)
			(xy 167.142821 -430.597055) (xy 167.124865 -430.540846) (xy 167.115783 -430.482542) (xy 167.115236 -430.453038)
			(xy 167.115722 -430.425787) (xy 167.123478 -430.371839) (xy 167.138833 -430.319544) (xy 167.161475 -430.269967)
			(xy 167.190941 -430.224117) (xy 167.226632 -430.182926) (xy 167.267823 -430.147235) (xy 167.313673 -430.117769)
			(xy 167.36325 -430.095127) (xy 167.415545 -430.079772) (xy 167.469493 -430.072016) (xy 167.523995 -430.072016)
			(xy 167.555949 -430.07661) (xy 187.209682 -430.07661) (xy 187.213753 -430.020988) (xy 187.225879 -429.966551)
			(xy 187.245802 -429.91446) (xy 187.273098 -429.865825) (xy 187.307184 -429.821682) (xy 187.347333 -429.782973)
			(xy 187.392691 -429.750522) (xy 187.442291 -429.725021) (xy 187.495075 -429.707014) (xy 187.549918 -429.696884)
			(xy 187.605652 -429.694847) (xy 187.661089 -429.700947) (xy 187.715046 -429.715053) (xy 187.766375 -429.736865)
			(xy 187.813981 -429.765919) (xy 187.856849 -429.801594) (xy 187.894066 -429.843131) (xy 187.924839 -429.889644)
			(xy 187.948511 -429.940141) (xy 187.964579 -429.993548) (xy 187.972699 -430.048724) (xy 187.973208 -430.07661)
			(xy 187.972699 -430.104496) (xy 187.964579 -430.159672) (xy 187.948511 -430.213079) (xy 187.924839 -430.263576)
			(xy 187.894066 -430.310089) (xy 187.856849 -430.351626) (xy 187.813981 -430.387301) (xy 187.766375 -430.416355)
			(xy 187.715046 -430.438167) (xy 187.661089 -430.452273) (xy 187.605652 -430.458373) (xy 187.549918 -430.456336)
			(xy 187.495075 -430.446206) (xy 187.442291 -430.428199) (xy 187.392691 -430.402698) (xy 187.347333 -430.370247)
			(xy 187.307184 -430.331538) (xy 187.273098 -430.287395) (xy 187.245802 -430.23876) (xy 187.225879 -430.186669)
			(xy 187.213753 -430.132232) (xy 187.209682 -430.07661) (xy 167.555949 -430.07661) (xy 167.577943 -430.079772)
			(xy 167.630238 -430.095127) (xy 167.679815 -430.117769) (xy 167.725665 -430.147235) (xy 167.766856 -430.182926)
			(xy 167.802547 -430.224117) (xy 167.832013 -430.269967) (xy 167.854655 -430.319544) (xy 167.87001 -430.371839)
			(xy 167.877766 -430.425787) (xy 167.878252 -430.453038) (xy 167.877769 -430.480583) (xy 167.869859 -430.535103)
			(xy 167.85418 -430.587915) (xy 167.831059 -430.637918) (xy 167.800978 -430.684071) (xy 167.764565 -430.725411)
			(xy 167.743886 -430.743614) (xy 167.732754 -430.753914) (xy 167.716434 -430.77945) (xy 167.708306 -430.808646)
			(xy 167.708604 -430.820279) (xy 169.926248 -430.820279) (xy 169.926248 -430.756357) (xy 169.934259 -430.692939)
			(xy 169.950156 -430.631025) (xy 169.973688 -430.571592) (xy 170.004482 -430.515577) (xy 170.042055 -430.463862)
			(xy 170.085812 -430.417265) (xy 170.135065 -430.37652) (xy 170.189036 -430.342269) (xy 170.246875 -430.315052)
			(xy 170.307668 -430.295299) (xy 170.370458 -430.283321) (xy 170.434254 -430.279308) (xy 170.49805 -430.283321)
			(xy 170.56084 -430.295299) (xy 170.621633 -430.315052) (xy 170.679472 -430.342269) (xy 170.733443 -430.37652)
			(xy 170.782696 -430.417265) (xy 170.826453 -430.463862) (xy 170.864026 -430.515577) (xy 170.89482 -430.571592)
			(xy 170.918352 -430.631025) (xy 170.934249 -430.692939) (xy 170.94226 -430.756357) (xy 170.942762 -430.788318)
			(xy 170.94226 -430.820279) (xy 170.934249 -430.883697) (xy 170.918352 -430.945611) (xy 170.89482 -431.005044)
			(xy 170.864026 -431.061059) (xy 170.826453 -431.112774) (xy 170.782696 -431.159371) (xy 170.733443 -431.200116)
			(xy 170.679472 -431.234367) (xy 170.621633 -431.261584) (xy 170.56084 -431.281337) (xy 170.49805 -431.293315)
			(xy 170.434254 -431.297329) (xy 170.370458 -431.293315) (xy 170.307668 -431.281337) (xy 170.246875 -431.261584)
			(xy 170.189036 -431.234367) (xy 170.135065 -431.200116) (xy 170.085812 -431.159371) (xy 170.042055 -431.112774)
			(xy 170.004482 -431.061059) (xy 169.973688 -431.005044) (xy 169.950156 -430.945611) (xy 169.934259 -430.883697)
			(xy 169.926248 -430.820279) (xy 167.708604 -430.820279) (xy 167.709083 -430.838942) (xy 167.718695 -430.867683)
			(xy 167.736302 -430.89235) (xy 167.760359 -430.91078) (xy 167.774366 -430.916588) (xy 167.803274 -430.927707)
			(xy 167.858371 -430.956005) (xy 167.90962 -430.990789) (xy 167.956263 -431.031542) (xy 167.997609 -431.077661)
			(xy 168.033044 -431.128462) (xy 168.062044 -431.183192) (xy 168.084178 -431.241041) (xy 168.099119 -431.301151)
			(xy 168.106646 -431.362631) (xy 168.107106 -431.3936) (xy 168.106604 -431.425561) (xy 168.098593 -431.488979)
			(xy 168.082696 -431.550893) (xy 168.059164 -431.610326) (xy 168.02837 -431.666341) (xy 167.990797 -431.718056)
			(xy 167.94704 -431.764653) (xy 167.897787 -431.805398) (xy 167.843816 -431.839649) (xy 167.785977 -431.866866)
			(xy 167.725184 -431.886619) (xy 167.662394 -431.898597) (xy 167.598598 -431.902611) (xy 167.534802 -431.898597)
			(xy 167.472012 -431.886619) (xy 167.411219 -431.866866) (xy 167.35338 -431.839649) (xy 167.299409 -431.805398)
			(xy 167.250156 -431.764653) (xy 167.206399 -431.718056) (xy 167.168826 -431.666341) (xy 167.138032 -431.610326)
			(xy 167.1145 -431.550893) (xy 167.098603 -431.488979) (xy 167.090592 -431.425561) (xy 167.09009 -431.3936)
			(xy 162.443668 -431.3936) (xy 162.443668 -431.44313) (xy 162.467798 -431.471578) (xy 162.48634 -431.474626)
			(xy 162.518452 -431.480344) (xy 162.580982 -431.498897) (xy 162.640628 -431.525293) (xy 162.69641 -431.559098)
			(xy 162.747411 -431.599757) (xy 162.792796 -431.646603) (xy 162.831819 -431.698867) (xy 162.863839 -431.755691)
			(xy 162.888332 -431.816143) (xy 162.904894 -431.87923) (xy 162.913255 -431.943918) (xy 162.913822 -431.97653)
			(xy 162.913356 -432.00726) (xy 162.905945 -432.068272) (xy 162.891234 -432.127946) (xy 162.869437 -432.185411)
			(xy 162.840873 -432.239831) (xy 162.805959 -432.290411) (xy 162.765202 -432.336413) (xy 162.719198 -432.377169)
			(xy 162.668617 -432.412082) (xy 162.614197 -432.440644) (xy 162.55673 -432.462438) (xy 162.497056 -432.477148)
			(xy 162.436044 -432.484557) (xy 162.405314 -432.485038) (xy 162.375362 -432.484603) (xy 162.315872 -432.477564)
			(xy 162.257623 -432.463582) (xy 162.20142 -432.442849) (xy 162.148044 -432.415655) (xy 162.098234 -432.382376)
			(xy 162.052681 -432.343473) (xy 162.012016 -432.299485) (xy 161.994088 -432.275488) (xy 161.987484 -432.266598)
			(xy 161.96818 -432.255676) (xy 161.879788 -432.248818) (xy 161.868757 -432.248479) (xy 161.848082 -432.25613)
			(xy 161.83991 -432.26355) (xy 161.513266 -432.590194) (xy 168.27322 -432.590194) (xy 168.277291 -432.534572)
			(xy 168.289417 -432.480135) (xy 168.30934 -432.428044) (xy 168.336636 -432.379409) (xy 168.370722 -432.335266)
			(xy 168.410871 -432.296557) (xy 168.456229 -432.264106) (xy 168.505829 -432.238605) (xy 168.558613 -432.220598)
			(xy 168.613456 -432.210468) (xy 168.66919 -432.208431) (xy 168.724627 -432.214531) (xy 168.778584 -432.228637)
			(xy 168.829913 -432.250449) (xy 168.877519 -432.279503) (xy 168.920387 -432.315178) (xy 168.957604 -432.356715)
			(xy 168.988377 -432.403228) (xy 169.012049 -432.453725) (xy 169.028117 -432.507132) (xy 169.036237 -432.562308)
			(xy 169.036746 -432.590194) (xy 169.036237 -432.61808) (xy 169.028117 -432.673256) (xy 169.012049 -432.726663)
			(xy 168.988377 -432.77716) (xy 168.957604 -432.823673) (xy 168.920387 -432.86521) (xy 168.877519 -432.900885)
			(xy 168.829913 -432.929939) (xy 168.778584 -432.951751) (xy 168.724627 -432.965857) (xy 168.66919 -432.971957)
			(xy 168.613456 -432.96992) (xy 168.558613 -432.95979) (xy 168.505829 -432.941783) (xy 168.456229 -432.916282)
			(xy 168.410871 -432.883831) (xy 168.370722 -432.845122) (xy 168.336636 -432.800979) (xy 168.30934 -432.752344)
			(xy 168.289417 -432.700253) (xy 168.277291 -432.645816) (xy 168.27322 -432.590194) (xy 161.513266 -432.590194)
			(xy 160.687004 -433.416456) (xy 160.680166 -433.423857) (xy 160.672451 -433.442456) (xy 160.672018 -433.452524)
			(xy 160.672018 -434.155596) (xy 164.598096 -434.155596) (xy 164.598608 -434.127101) (xy 164.607065 -434.070743)
			(xy 164.62382 -434.016273) (xy 164.648499 -433.964905) (xy 164.680552 -433.917785) (xy 164.719265 -433.875963)
			(xy 164.763774 -433.840372) (xy 164.813086 -433.811805) (xy 164.866102 -433.7909) (xy 164.893752 -433.783994)
			(xy 164.907058 -433.78039) (xy 164.93124 -433.767182) (xy 164.951016 -433.747995) (xy 164.964947 -433.724222)
			(xy 164.972022 -433.697592) (xy 164.971727 -433.670039) (xy 164.964083 -433.643567) (xy 164.957252 -433.631594)
			(xy 164.939385 -433.601408) (xy 164.911172 -433.537187) (xy 164.892059 -433.469697) (xy 164.882407 -433.40022)
			(xy 164.881814 -433.365148) (xy 164.882316 -433.333187) (xy 164.890327 -433.269769) (xy 164.906224 -433.207855)
			(xy 164.929756 -433.148422) (xy 164.96055 -433.092407) (xy 164.998123 -433.040692) (xy 165.04188 -432.994095)
			(xy 165.091133 -432.95335) (xy 165.145104 -432.919099) (xy 165.202943 -432.891882) (xy 165.263736 -432.872129)
			(xy 165.326526 -432.860151) (xy 165.390322 -432.856138) (xy 165.454118 -432.860151) (xy 165.516908 -432.872129)
			(xy 165.577701 -432.891882) (xy 165.63554 -432.919099) (xy 165.689511 -432.95335) (xy 165.738764 -432.994095)
			(xy 165.782521 -433.040692) (xy 165.820094 -433.092407) (xy 165.850888 -433.148422) (xy 165.87442 -433.207855)
			(xy 165.890317 -433.269769) (xy 165.898328 -433.333187) (xy 165.89883 -433.365148) (xy 165.898284 -433.397153)
			(xy 165.890233 -433.460656) (xy 165.874277 -433.522646) (xy 165.850669 -433.582145) (xy 165.832382 -433.615338)
			(xy 166.816278 -433.615338) (xy 166.81678 -433.583377) (xy 166.824791 -433.519959) (xy 166.840688 -433.458045)
			(xy 166.86422 -433.398612) (xy 166.895014 -433.342597) (xy 166.932587 -433.290882) (xy 166.976344 -433.244285)
			(xy 167.025597 -433.20354) (xy 167.079568 -433.169289) (xy 167.137407 -433.142072) (xy 167.1982 -433.122319)
			(xy 167.26099 -433.110341) (xy 167.324786 -433.106328) (xy 167.388582 -433.110341) (xy 167.401907 -433.112883)
			(xy 169.088048 -433.112883) (xy 169.088048 -433.048961) (xy 169.096059 -432.985543) (xy 169.111956 -432.923629)
			(xy 169.135488 -432.864196) (xy 169.166282 -432.808181) (xy 169.203855 -432.756466) (xy 169.247612 -432.709869)
			(xy 169.296865 -432.669124) (xy 169.350836 -432.634873) (xy 169.408675 -432.607656) (xy 169.469468 -432.587903)
			(xy 169.532258 -432.575925) (xy 169.596054 -432.571912) (xy 169.65985 -432.575925) (xy 169.72264 -432.587903)
			(xy 169.783433 -432.607656) (xy 169.841272 -432.634873) (xy 169.895243 -432.669124) (xy 169.944496 -432.709869)
			(xy 169.988253 -432.756466) (xy 170.025826 -432.808181) (xy 170.05662 -432.864196) (xy 170.080152 -432.923629)
			(xy 170.096049 -432.985543) (xy 170.10406 -433.048961) (xy 170.104562 -433.080922) (xy 170.10406 -433.112883)
			(xy 170.096049 -433.176301) (xy 170.080152 -433.238215) (xy 170.05662 -433.297648) (xy 170.025826 -433.353663)
			(xy 169.988253 -433.405378) (xy 169.944496 -433.451975) (xy 169.895243 -433.49272) (xy 169.841272 -433.526971)
			(xy 169.783433 -433.554188) (xy 169.72264 -433.573941) (xy 169.65985 -433.585919) (xy 169.596054 -433.589933)
			(xy 169.532258 -433.585919) (xy 169.469468 -433.573941) (xy 169.408675 -433.554188) (xy 169.350836 -433.526971)
			(xy 169.296865 -433.49272) (xy 169.247612 -433.451975) (xy 169.203855 -433.405378) (xy 169.166282 -433.353663)
			(xy 169.135488 -433.297648) (xy 169.111956 -433.238215) (xy 169.096059 -433.176301) (xy 169.088048 -433.112883)
			(xy 167.401907 -433.112883) (xy 167.451372 -433.122319) (xy 167.512165 -433.142072) (xy 167.570004 -433.169289)
			(xy 167.623975 -433.20354) (xy 167.673228 -433.244285) (xy 167.716985 -433.290882) (xy 167.754558 -433.342597)
			(xy 167.785352 -433.398612) (xy 167.808884 -433.458045) (xy 167.824781 -433.519959) (xy 167.832792 -433.583377)
			(xy 167.833294 -433.615338) (xy 167.832853 -433.6456) (xy 167.825665 -433.705695) (xy 167.811396 -433.764513)
			(xy 167.790247 -433.821221) (xy 167.762517 -433.875019) (xy 167.745918 -433.900326) (xy 167.741295 -433.907809)
			(xy 167.736868 -433.924815) (xy 167.737282 -433.9336) (xy 167.740076 -433.963318) (xy 167.741272 -433.971989)
			(xy 167.748655 -433.987842) (xy 167.754554 -433.994306) (xy 167.777437 -434.018184) (xy 167.81747 -434.070827)
			(xy 167.85034 -434.128216) (xy 167.875493 -434.189382) (xy 167.892504 -434.253293) (xy 167.901086 -434.31887)
			(xy 167.90162 -434.351938) (xy 167.901118 -434.383899) (xy 167.893107 -434.447317) (xy 167.87721 -434.509231)
			(xy 167.853678 -434.568664) (xy 167.822884 -434.624679) (xy 167.785311 -434.676394) (xy 167.741554 -434.722991)
			(xy 167.692301 -434.763736) (xy 167.63833 -434.797987) (xy 167.580491 -434.825204) (xy 167.519698 -434.844957)
			(xy 167.456908 -434.856935) (xy 167.393112 -434.860949) (xy 167.329316 -434.856935) (xy 167.266526 -434.844957)
			(xy 167.205733 -434.825204) (xy 167.147894 -434.797987) (xy 167.093923 -434.763736) (xy 167.04467 -434.722991)
			(xy 167.000913 -434.676394) (xy 166.96334 -434.624679) (xy 166.932546 -434.568664) (xy 166.909014 -434.509231)
			(xy 166.893117 -434.447317) (xy 166.885106 -434.383899) (xy 166.884604 -434.351938) (xy 166.885033 -434.321676)
			(xy 166.892224 -434.26158) (xy 166.906496 -434.202762) (xy 166.927647 -434.146054) (xy 166.95538 -434.092257)
			(xy 166.97198 -434.06695) (xy 166.976613 -434.059473) (xy 166.981034 -434.042462) (xy 166.980616 -434.033676)
			(xy 166.977822 -434.003958) (xy 166.976637 -433.995285) (xy 166.969247 -433.979433) (xy 166.963344 -433.97297)
			(xy 166.940449 -433.949103) (xy 166.900418 -433.896457) (xy 166.867549 -433.839066) (xy 166.842398 -433.777898)
			(xy 166.825389 -433.713985) (xy 166.81681 -433.648407) (xy 166.816278 -433.615338) (xy 165.832382 -433.615338)
			(xy 165.819781 -433.63821) (xy 165.782101 -433.689956) (xy 165.738227 -433.736565) (xy 165.68885 -433.7773)
			(xy 165.634752 -433.811517) (xy 165.576788 -433.838675) (xy 165.515874 -433.858345) (xy 165.452973 -433.870216)
			(xy 165.421056 -433.87264) (xy 165.407331 -433.874007) (xy 165.381262 -433.88296) (xy 165.358545 -433.898571)
			(xy 165.340841 -433.919697) (xy 165.329445 -433.944795) (xy 165.32519 -433.972029) (xy 165.328389 -433.999407)
			(xy 165.333172 -434.01234) (xy 165.342022 -434.035174) (xy 165.354462 -434.08254) (xy 165.360734 -434.13111)
			(xy 165.361112 -434.155596) (xy 165.360626 -434.182847) (xy 165.35287 -434.236795) (xy 165.337515 -434.28909)
			(xy 165.314873 -434.338667) (xy 165.285407 -434.384517) (xy 165.249716 -434.425708) (xy 165.208525 -434.461399)
			(xy 165.162675 -434.490865) (xy 165.113098 -434.513507) (xy 165.060803 -434.528862) (xy 165.006855 -434.536618)
			(xy 164.952353 -434.536618) (xy 164.898405 -434.528862) (xy 164.84611 -434.513507) (xy 164.796533 -434.490865)
			(xy 164.750683 -434.461399) (xy 164.709492 -434.425708) (xy 164.673801 -434.384517) (xy 164.644335 -434.338667)
			(xy 164.621693 -434.28909) (xy 164.606338 -434.236795) (xy 164.598582 -434.182847) (xy 164.598096 -434.155596)
			(xy 160.672018 -434.155596) (xy 160.672018 -434.831193) (xy 160.901882 -434.831193) (xy 160.901882 -434.767271)
			(xy 160.909893 -434.703853) (xy 160.92579 -434.641939) (xy 160.949322 -434.582506) (xy 160.980116 -434.526491)
			(xy 161.017689 -434.474776) (xy 161.061446 -434.428179) (xy 161.110699 -434.387434) (xy 161.16467 -434.353183)
			(xy 161.222509 -434.325966) (xy 161.283302 -434.306213) (xy 161.346092 -434.294235) (xy 161.409888 -434.290222)
			(xy 161.473684 -434.294235) (xy 161.536474 -434.306213) (xy 161.597267 -434.325966) (xy 161.655106 -434.353183)
			(xy 161.709077 -434.387434) (xy 161.75833 -434.428179) (xy 161.802087 -434.474776) (xy 161.83966 -434.526491)
			(xy 161.870454 -434.582506) (xy 161.893986 -434.641939) (xy 161.909883 -434.703853) (xy 161.917894 -434.767271)
			(xy 161.918396 -434.799232) (xy 161.917894 -434.831193) (xy 161.909883 -434.894611) (xy 161.893986 -434.956525)
			(xy 161.870454 -435.015958) (xy 161.83966 -435.071973) (xy 161.802087 -435.123688) (xy 161.75833 -435.170285)
			(xy 161.709077 -435.21103) (xy 161.655106 -435.245281) (xy 161.597267 -435.272498) (xy 161.536474 -435.292251)
			(xy 161.473684 -435.304229) (xy 161.409888 -435.308243) (xy 161.346092 -435.304229) (xy 161.283302 -435.292251)
			(xy 161.222509 -435.272498) (xy 161.16467 -435.245281) (xy 161.110699 -435.21103) (xy 161.061446 -435.170285)
			(xy 161.017689 -435.123688) (xy 160.980116 -435.071973) (xy 160.949322 -435.015958) (xy 160.92579 -434.956525)
			(xy 160.909893 -434.894611) (xy 160.901882 -434.831193) (xy 160.672018 -434.831193) (xy 160.672018 -435.537208)
			(xy 167.01862 -435.537208) (xy 167.021228 -435.474184) (xy 167.031612 -435.411966) (xy 167.049611 -435.35151)
			(xy 167.07495 -435.293745) (xy 167.10724 -435.239558) (xy 167.145984 -435.18978) (xy 167.190588 -435.145177)
			(xy 167.240366 -435.106434) (xy 167.294554 -435.074146) (xy 167.35232 -435.048808) (xy 167.412776 -435.030809)
			(xy 167.474994 -435.020427) (xy 167.538018 -435.01782) (xy 167.600881 -435.023029) (xy 167.662617 -435.035973)
			(xy 167.722278 -435.056455) (xy 167.778948 -435.084158) (xy 167.831755 -435.118658) (xy 167.87989 -435.159425)
			(xy 167.922612 -435.205833) (xy 167.959266 -435.257169) (xy 167.989289 -435.312644) (xy 168.01222 -435.371407)
			(xy 168.027706 -435.432555) (xy 168.03551 -435.495149) (xy 168.035986 -435.526688) (xy 168.03563 -435.554231)
			(xy 168.029651 -435.608991) (xy 168.017783 -435.662783) (xy 168.009316 -435.688994) (xy 168.005506 -435.700678)
			(xy 168.009062 -435.724808) (xy 168.072054 -435.81193) (xy 168.093898 -435.822852) (xy 168.10863 -435.822852)
			(xy 168.13588 -435.82335) (xy 168.189825 -435.831109) (xy 168.242117 -435.846466) (xy 168.291692 -435.869108)
			(xy 168.33754 -435.898574) (xy 168.378729 -435.934264) (xy 168.41442 -435.975452) (xy 168.443887 -436.021299)
			(xy 168.46653 -436.070873) (xy 168.481889 -436.123165) (xy 168.48965 -436.17711) (xy 168.490138 -436.20436)
			(xy 168.48966 -436.232293) (xy 168.481511 -436.287561) (xy 168.465396 -436.341052) (xy 168.441659 -436.391625)
			(xy 168.426638 -436.41518) (xy 168.42105 -436.423816) (xy 168.41724 -436.443374) (xy 168.436036 -436.534306)
			(xy 168.447212 -436.550816) (xy 168.455848 -436.556404) (xy 168.482091 -436.574011) (xy 168.530376 -436.614787)
			(xy 168.573236 -436.661231) (xy 168.610011 -436.712627) (xy 168.640136 -436.768185) (xy 168.663144 -436.827046)
			(xy 168.678682 -436.888305) (xy 168.68651 -436.951017) (xy 168.686988 -436.982616) (xy 168.686577 -437.013349)
			(xy 168.679166 -437.074367) (xy 168.664455 -437.134047) (xy 168.642656 -437.191519) (xy 168.61409 -437.245943)
			(xy 168.579171 -437.296528) (xy 168.53841 -437.342535) (xy 168.4924 -437.383293) (xy 168.441813 -437.418208)
			(xy 168.387386 -437.446771) (xy 168.329913 -437.468565) (xy 168.270232 -437.483273) (xy 168.209213 -437.49068)
			(xy 168.17848 -437.491124) (xy 168.144934 -437.490606) (xy 168.078421 -437.481811) (xy 168.045892 -437.473598)
			(xy 168.03624 -437.471058) (xy 168.016682 -437.473344) (xy 167.937434 -437.517286) (xy 167.924988 -437.53278)
			(xy 167.922194 -437.542432) (xy 167.913857 -437.568213) (xy 167.891023 -437.617347) (xy 167.861467 -437.662757)
			(xy 167.825784 -437.703528) (xy 167.784692 -437.738841) (xy 167.739016 -437.767984) (xy 167.689678 -437.790373)
			(xy 167.637667 -437.805555) (xy 167.584032 -437.813227) (xy 167.556942 -437.813704) (xy 167.529687 -437.813252)
			(xy 167.475731 -437.805499) (xy 167.423427 -437.790147) (xy 167.373842 -437.767506) (xy 167.327983 -437.738039)
			(xy 167.286785 -437.702345) (xy 167.251086 -437.661151) (xy 167.221614 -437.615295) (xy 167.198968 -437.565712)
			(xy 167.18361 -437.51341) (xy 167.175851 -437.459455) (xy 167.175851 -437.404945) (xy 167.18361 -437.35099)
			(xy 167.198968 -437.298688) (xy 167.221614 -437.249105) (xy 167.251086 -437.203249) (xy 167.286785 -437.162055)
			(xy 167.327983 -437.126361) (xy 167.373842 -437.096894) (xy 167.423427 -437.074253) (xy 167.475731 -437.058901)
			(xy 167.529687 -437.051148) (xy 167.556942 -437.050688) (xy 167.566594 -437.050688) (xy 167.576754 -437.050942)
			(xy 167.595042 -437.044084) (xy 167.661844 -436.982616) (xy 167.670226 -436.964836) (xy 167.670734 -436.95493)
			(xy 167.672967 -436.922761) (xy 167.68459 -436.859331) (xy 167.70414 -436.79788) (xy 167.731304 -436.739394)
			(xy 167.765645 -436.684813) (xy 167.806612 -436.635012) (xy 167.829738 -436.612538) (xy 167.837104 -436.60568)
			(xy 167.845232 -436.587138) (xy 167.847518 -436.494682) (xy 167.840406 -436.475886) (xy 167.833294 -436.46852)
			(xy 167.81348 -436.447078) (xy 167.779967 -436.399275) (xy 167.754126 -436.346925) (xy 167.736558 -436.291251)
			(xy 167.727674 -436.23355) (xy 167.727122 -436.20436) (xy 167.727273 -436.189181) (xy 167.729691 -436.158919)
			(xy 167.731948 -436.143908) (xy 167.73398 -436.131716) (xy 167.72636 -436.108348) (xy 167.649906 -436.03291)
			(xy 167.626538 -436.025544) (xy 167.614346 -436.02783) (xy 167.592797 -436.0313) (xy 167.549303 -436.034985)
			(xy 167.527478 -436.035196) (xy 167.495939 -436.034709) (xy 167.433345 -436.026904) (xy 167.372197 -436.011417)
			(xy 167.313435 -435.988485) (xy 167.25796 -435.958461) (xy 167.206625 -435.921806) (xy 167.160218 -435.879082)
			(xy 167.119452 -435.830947) (xy 167.084953 -435.778139) (xy 167.057251 -435.721469) (xy 167.036771 -435.661808)
			(xy 167.023828 -435.600072) (xy 167.01862 -435.537208) (xy 160.672018 -435.537208) (xy 160.672018 -436.430166)
			(xy 165.86784 -436.430166) (xy 165.871911 -436.374544) (xy 165.884037 -436.320107) (xy 165.90396 -436.268016)
			(xy 165.931256 -436.219381) (xy 165.965342 -436.175238) (xy 166.005491 -436.136529) (xy 166.050849 -436.104078)
			(xy 166.100449 -436.078577) (xy 166.153233 -436.06057) (xy 166.208076 -436.05044) (xy 166.26381 -436.048403)
			(xy 166.319247 -436.054503) (xy 166.373204 -436.068609) (xy 166.424533 -436.090421) (xy 166.472139 -436.119475)
			(xy 166.515007 -436.15515) (xy 166.552224 -436.196687) (xy 166.582997 -436.2432) (xy 166.606669 -436.293697)
			(xy 166.622737 -436.347104) (xy 166.630857 -436.40228) (xy 166.631366 -436.430166) (xy 166.630857 -436.458052)
			(xy 166.622737 -436.513228) (xy 166.606669 -436.566635) (xy 166.582997 -436.617132) (xy 166.552224 -436.663645)
			(xy 166.515007 -436.705182) (xy 166.472139 -436.740857) (xy 166.424533 -436.769911) (xy 166.373204 -436.791723)
			(xy 166.319247 -436.805829) (xy 166.26381 -436.811929) (xy 166.208076 -436.809892) (xy 166.153233 -436.799762)
			(xy 166.100449 -436.781755) (xy 166.050849 -436.756254) (xy 166.005491 -436.723803) (xy 165.965342 -436.685094)
			(xy 165.931256 -436.640951) (xy 165.90396 -436.592316) (xy 165.884037 -436.540225) (xy 165.871911 -436.485788)
			(xy 165.86784 -436.430166) (xy 160.672018 -436.430166) (xy 160.672018 -437.27243) (xy 160.961322 -437.27243)
			(xy 160.965393 -437.216808) (xy 160.977519 -437.162371) (xy 160.997442 -437.11028) (xy 161.024738 -437.061645)
			(xy 161.058824 -437.017502) (xy 161.098973 -436.978793) (xy 161.144331 -436.946342) (xy 161.193931 -436.920841)
			(xy 161.246715 -436.902834) (xy 161.301558 -436.892704) (xy 161.357292 -436.890667) (xy 161.412729 -436.896767)
			(xy 161.466686 -436.910873) (xy 161.518015 -436.932685) (xy 161.565621 -436.961739) (xy 161.608489 -436.997414)
			(xy 161.645706 -437.038951) (xy 161.676479 -437.085464) (xy 161.700151 -437.135961) (xy 161.716219 -437.189368)
			(xy 161.724339 -437.244544) (xy 161.724848 -437.27243) (xy 161.724339 -437.300316) (xy 161.716219 -437.355492)
			(xy 161.700151 -437.408899) (xy 161.676479 -437.459396) (xy 161.645706 -437.505909) (xy 161.608489 -437.547446)
			(xy 161.565621 -437.583121) (xy 161.518015 -437.612175) (xy 161.466686 -437.633987) (xy 161.412729 -437.648093)
			(xy 161.357292 -437.654193) (xy 161.301558 -437.652156) (xy 161.246715 -437.642026) (xy 161.193931 -437.624019)
			(xy 161.144331 -437.598518) (xy 161.098973 -437.566067) (xy 161.058824 -437.527358) (xy 161.024738 -437.483215)
			(xy 160.997442 -437.43458) (xy 160.977519 -437.382489) (xy 160.965393 -437.328052) (xy 160.961322 -437.27243)
			(xy 160.672018 -437.27243) (xy 160.672018 -438.241905) (xy 163.315644 -438.241905) (xy 163.315644 -438.177983)
			(xy 163.323655 -438.114565) (xy 163.339552 -438.052651) (xy 163.363084 -437.993218) (xy 163.393878 -437.937203)
			(xy 163.431451 -437.885488) (xy 163.475208 -437.838891) (xy 163.524461 -437.798146) (xy 163.578432 -437.763895)
			(xy 163.636271 -437.736678) (xy 163.697064 -437.716925) (xy 163.759854 -437.704947) (xy 163.82365 -437.700934)
			(xy 163.887446 -437.704947) (xy 163.950236 -437.716925) (xy 164.011029 -437.736678) (xy 164.068868 -437.763895)
			(xy 164.122839 -437.798146) (xy 164.172092 -437.838891) (xy 164.215849 -437.885488) (xy 164.253422 -437.937203)
			(xy 164.284216 -437.993218) (xy 164.307748 -438.052651) (xy 164.323645 -438.114565) (xy 164.331656 -438.177983)
			(xy 164.332158 -438.209944) (xy 164.331656 -438.241905) (xy 164.323645 -438.305323) (xy 164.307748 -438.367237)
			(xy 164.284216 -438.42667) (xy 164.253422 -438.482685) (xy 164.215849 -438.5344) (xy 164.172092 -438.580997)
			(xy 164.122839 -438.621742) (xy 164.068868 -438.655993) (xy 164.011029 -438.68321) (xy 163.950236 -438.702963)
			(xy 163.887446 -438.714941) (xy 163.82365 -438.718955) (xy 163.759854 -438.714941) (xy 163.697064 -438.702963)
			(xy 163.636271 -438.68321) (xy 163.578432 -438.655993) (xy 163.524461 -438.621742) (xy 163.475208 -438.580997)
			(xy 163.431451 -438.5344) (xy 163.393878 -438.482685) (xy 163.363084 -438.42667) (xy 163.339552 -438.367237)
			(xy 163.323655 -438.305323) (xy 163.315644 -438.241905) (xy 160.672018 -438.241905) (xy 160.672018 -438.912)
			(xy 165.863014 -438.912) (xy 165.867085 -438.856378) (xy 165.879211 -438.801941) (xy 165.899134 -438.74985)
			(xy 165.92643 -438.701215) (xy 165.960516 -438.657072) (xy 166.000665 -438.618363) (xy 166.046023 -438.585912)
			(xy 166.095623 -438.560411) (xy 166.148407 -438.542404) (xy 166.20325 -438.532274) (xy 166.258984 -438.530237)
			(xy 166.314421 -438.536337) (xy 166.368378 -438.550443) (xy 166.419707 -438.572255) (xy 166.467313 -438.601309)
			(xy 166.510181 -438.636984) (xy 166.547398 -438.678521) (xy 166.578171 -438.725034) (xy 166.601843 -438.775531)
			(xy 166.617911 -438.828938) (xy 166.626031 -438.884114) (xy 166.62654 -438.912) (xy 166.626031 -438.939886)
			(xy 166.617911 -438.995062) (xy 166.601843 -439.048469) (xy 166.578171 -439.098966) (xy 166.547398 -439.145479)
			(xy 166.510181 -439.187016) (xy 166.467313 -439.222691) (xy 166.419707 -439.251745) (xy 166.368378 -439.273557)
			(xy 166.314421 -439.287663) (xy 166.258984 -439.293763) (xy 166.20325 -439.291726) (xy 166.148407 -439.281596)
			(xy 166.095623 -439.263589) (xy 166.046023 -439.238088) (xy 166.000665 -439.205637) (xy 165.960516 -439.166928)
			(xy 165.92643 -439.122785) (xy 165.899134 -439.07415) (xy 165.879211 -439.022059) (xy 165.867085 -438.967622)
			(xy 165.863014 -438.912) (xy 160.672018 -438.912) (xy 160.672018 -439.649616) (xy 160.672444 -439.659685)
			(xy 160.680165 -439.678283) (xy 160.687004 -439.685684) (xy 161.141664 -440.140344) (xy 167.175434 -440.140344)
			(xy 167.175982 -440.111978) (xy 167.184385 -440.055871) (xy 167.200996 -440.001624) (xy 167.225451 -439.950433)
			(xy 167.257212 -439.903423) (xy 167.295578 -439.86163) (xy 167.339706 -439.825974) (xy 167.363902 -439.81116)
			(xy 167.37203 -439.806588) (xy 167.38346 -439.792618) (xy 167.410638 -439.711592) (xy 167.409876 -439.693558)
			(xy 167.40632 -439.684922) (xy 167.394064 -439.653969) (xy 167.376864 -439.589655) (xy 167.368212 -439.523645)
			(xy 167.367712 -439.490358) (xy 167.368163 -439.457509) (xy 167.37661 -439.392356) (xy 167.393384 -439.328835)
			(xy 167.418204 -439.268006) (xy 167.450657 -439.210883) (xy 167.490202 -439.158419) (xy 167.536179 -439.11149)
			(xy 167.58782 -439.070877) (xy 167.644265 -439.037259) (xy 167.704573 -439.011195) (xy 167.736012 -439.001662)
			(xy 167.744902 -438.999122) (xy 167.75938 -438.9882) (xy 167.805862 -438.917334) (xy 167.809926 -438.899808)
			(xy 167.808656 -438.890664) (xy 167.807098 -438.87815) (xy 167.805446 -438.852983) (xy 167.805354 -438.840372)
			(xy 167.80584 -438.813121) (xy 167.813596 -438.759173) (xy 167.828951 -438.706878) (xy 167.851593 -438.657301)
			(xy 167.881059 -438.611451) (xy 167.91675 -438.57026) (xy 167.957941 -438.534569) (xy 168.003791 -438.505103)
			(xy 168.053368 -438.482461) (xy 168.105663 -438.467106) (xy 168.159611 -438.45935) (xy 168.214113 -438.45935)
			(xy 168.268061 -438.467106) (xy 168.320356 -438.482461) (xy 168.369933 -438.505103) (xy 168.415783 -438.534569)
			(xy 168.456974 -438.57026) (xy 168.492665 -438.611451) (xy 168.522131 -438.657301) (xy 168.544773 -438.706878)
			(xy 168.560128 -438.759173) (xy 168.567884 -438.813121) (xy 168.56837 -438.840372) (xy 168.567921 -438.86828)
			(xy 168.559796 -438.923502) (xy 168.543716 -438.976953) (xy 168.520023 -439.027491) (xy 168.489222 -439.07404)
			(xy 168.45197 -439.115607) (xy 168.409062 -439.151305) (xy 168.38549 -439.166254) (xy 168.377362 -439.17108)
			(xy 168.366186 -439.185304) (xy 168.340278 -439.265822) (xy 168.34104 -439.283856) (xy 168.344596 -439.292492)
			(xy 168.35727 -439.323924) (xy 168.375121 -439.389303) (xy 168.384149 -439.456472) (xy 168.384728 -439.490358)
			(xy 168.384152 -439.523561) (xy 168.375513 -439.589403) (xy 168.358376 -439.653561) (xy 168.333033 -439.714941)
			(xy 168.299916 -439.7725) (xy 168.259587 -439.825258) (xy 168.212733 -439.872317) (xy 168.160152 -439.912877)
			(xy 168.102738 -439.946246) (xy 168.04147 -439.971858) (xy 168.00957 -439.981086) (xy 168.000426 -439.983626)
			(xy 167.985694 -439.99404) (xy 167.93845 -440.06516) (xy 167.934132 -440.082686) (xy 167.935402 -440.092084)
			(xy 167.936838 -440.104097) (xy 167.938364 -440.128246) (xy 167.93845 -440.140344) (xy 167.937964 -440.167595)
			(xy 167.930208 -440.221543) (xy 167.914853 -440.273838) (xy 167.892211 -440.323415) (xy 167.862745 -440.369265)
			(xy 167.827054 -440.410456) (xy 167.785863 -440.446147) (xy 167.740013 -440.475613) (xy 167.690436 -440.498255)
			(xy 167.638141 -440.51361) (xy 167.584193 -440.521366) (xy 167.529691 -440.521366) (xy 167.475743 -440.51361)
			(xy 167.423448 -440.498255) (xy 167.373871 -440.475613) (xy 167.328021 -440.446147) (xy 167.28683 -440.410456)
			(xy 167.251139 -440.369265) (xy 167.221673 -440.323415) (xy 167.199031 -440.273838) (xy 167.183676 -440.221543)
			(xy 167.17592 -440.167595) (xy 167.175434 -440.140344) (xy 161.141664 -440.140344) (xy 161.681414 -440.680094)
			(xy 161.688813 -440.686939) (xy 161.707411 -440.694669) (xy 161.717482 -440.69508)
		)
		(stroke
			(width 0)
			(type solid)
		)
		(fill yes)
		(layer "In15.Cu")
		(net "P3V3_AUX")
	)
	(gr_poly
		(pts
			(xy 78.086966 -252.120654) (xy 78.099351 -252.119804) (xy 78.121068 -252.107832) (xy 78.128368 -252.097794)
			(xy 78.130654 -252.09373) (xy 78.171802 -252.011434) (xy 78.174767 -252.004931) (xy 78.17735 -251.99088)
			(xy 78.176882 -251.983748) (xy 78.175612 -251.969778) (xy 78.166976 -251.958348) (xy 78.166976 -251.95784)
			(xy 78.152693 -251.938034) (xy 78.129946 -251.894828) (xy 78.114365 -251.848553) (xy 78.106346 -251.800387)
			(xy 78.105762 -251.775976) (xy 78.105762 -251.768356) (xy 78.106755 -251.743431) (xy 78.115842 -251.694385)
			(xy 78.13278 -251.647469) (xy 78.157117 -251.603929) (xy 78.188207 -251.564924) (xy 78.225223 -251.531489)
			(xy 78.26718 -251.504515) (xy 78.312964 -251.484719) (xy 78.361356 -251.472626) (xy 78.41107 -251.46856)
			(xy 78.460784 -251.472626) (xy 78.509176 -251.484719) (xy 78.55496 -251.504515) (xy 78.596917 -251.531489)
			(xy 78.633933 -251.564924) (xy 78.665023 -251.603929) (xy 78.68936 -251.647469) (xy 78.706298 -251.694385)
			(xy 78.715385 -251.743431) (xy 78.716378 -251.768356) (xy 78.716378 -251.77496) (xy 78.715851 -251.7995)
			(xy 78.707925 -251.847938) (xy 78.692351 -251.894484) (xy 78.66953 -251.937938) (xy 78.655164 -251.95784)
			(xy 78.655164 -251.958348) (xy 78.65491 -251.958602) (xy 78.651024 -251.964222) (xy 78.646129 -251.976971)
			(xy 78.645258 -251.983748) (xy 78.644496 -251.99086) (xy 78.647036 -252.00483) (xy 78.691486 -252.09373)
			(xy 78.693772 -252.097794) (xy 78.701103 -252.107799) (xy 78.722801 -252.119762) (xy 78.735174 -252.120654)
			(xy 79.966058 -252.120654) (xy 79.967074 -252.120654) (xy 79.979458 -252.119802) (xy 80.001172 -252.107829)
			(xy 80.008476 -252.097794) (xy 80.010762 -252.09373) (xy 80.05191 -252.011434) (xy 80.054874 -252.004931)
			(xy 80.057458 -251.99088) (xy 80.05699 -251.983748) (xy 80.05572 -251.969778) (xy 80.047084 -251.958348)
			(xy 80.047084 -251.95784) (xy 80.032801 -251.938034) (xy 80.010053 -251.894828) (xy 79.994472 -251.848553)
			(xy 79.986453 -251.800387) (xy 79.98587 -251.775976) (xy 79.98587 -251.768356) (xy 79.986863 -251.743431)
			(xy 79.99595 -251.694385) (xy 80.012888 -251.647469) (xy 80.037225 -251.603929) (xy 80.068315 -251.564924)
			(xy 80.105331 -251.531489) (xy 80.147288 -251.504515) (xy 80.193072 -251.484719) (xy 80.241464 -251.472626)
			(xy 80.291178 -251.46856) (xy 80.340892 -251.472626) (xy 80.389284 -251.484719) (xy 80.435068 -251.504515)
			(xy 80.477025 -251.531489) (xy 80.514041 -251.564924) (xy 80.545131 -251.603929) (xy 80.569468 -251.647469)
			(xy 80.586406 -251.694385) (xy 80.595493 -251.743431) (xy 80.596486 -251.768356) (xy 80.596486 -251.77496)
			(xy 80.595959 -251.7995) (xy 80.588033 -251.847938) (xy 80.57246 -251.894484) (xy 80.549639 -251.937939)
			(xy 80.535272 -251.95784) (xy 80.535272 -251.958348) (xy 80.535018 -251.958602) (xy 80.531132 -251.964222)
			(xy 80.526235 -251.976971) (xy 80.525366 -251.983748) (xy 80.524604 -251.99086) (xy 80.527144 -252.00483)
			(xy 80.571594 -252.09373) (xy 80.57388 -252.097794) (xy 80.581297 -252.107715) (xy 80.602936 -252.119685)
			(xy 80.615282 -252.120654) (xy 80.901032 -252.120654) (xy 80.910372 -252.120181) (xy 80.927785 -252.113399)
			(xy 80.941631 -252.100851) (xy 80.946244 -252.092714) (xy 80.987138 -252.01118) (xy 80.990037 -252.00486)
			(xy 80.992603 -251.991199) (xy 80.992218 -251.984256) (xy 80.991964 -251.9807) (xy 80.974063 -251.959012)
			(xy 80.945449 -251.910609) (xy 80.925852 -251.857906) (xy 80.915892 -251.802566) (xy 80.915256 -251.774452)
			(xy 80.915743 -251.749642) (xy 80.923505 -251.700634) (xy 80.938838 -251.653444) (xy 80.961365 -251.609233)
			(xy 80.99053 -251.56909) (xy 81.025616 -251.534004) (xy 81.065759 -251.504839) (xy 81.10997 -251.482312)
			(xy 81.15716 -251.466979) (xy 81.206168 -251.459217) (xy 81.255788 -251.459217) (xy 81.304796 -251.466979)
			(xy 81.351986 -251.482312) (xy 81.396197 -251.504839) (xy 81.43634 -251.534004) (xy 81.471426 -251.56909)
			(xy 81.500591 -251.609233) (xy 81.523118 -251.653444) (xy 81.538451 -251.700634) (xy 81.546213 -251.749642)
			(xy 81.5467 -251.774452) (xy 81.546174 -251.800715) (xy 81.537472 -251.852514) (xy 81.520318 -251.902159)
			(xy 81.495183 -251.94828) (xy 81.47939 -251.96927) (xy 81.475022 -251.97527) (xy 81.469605 -251.989079)
			(xy 81.468722 -251.996448) (xy 81.468468 -251.99848) (xy 81.515712 -252.092714) (xy 81.52028 -252.100886)
			(xy 81.534122 -252.113467) (xy 81.551571 -252.120207) (xy 81.560924 -252.120654) (xy 81.845912 -252.120654)
			(xy 81.846928 -252.120654) (xy 81.859305 -252.11979) (xy 81.880999 -252.107805) (xy 81.88833 -252.097794)
			(xy 81.890616 -252.09373) (xy 81.931764 -252.011434) (xy 81.93473 -252.004931) (xy 81.937316 -251.99088)
			(xy 81.936844 -251.983748) (xy 81.935574 -251.969778) (xy 81.926938 -251.958348) (xy 81.926938 -251.95784)
			(xy 81.912656 -251.938034) (xy 81.889912 -251.894827) (xy 81.874333 -251.848552) (xy 81.866315 -251.800387)
			(xy 81.865724 -251.775976) (xy 81.865724 -251.768356) (xy 81.866717 -251.743431) (xy 81.875804 -251.694385)
			(xy 81.892742 -251.647469) (xy 81.917079 -251.603929) (xy 81.948169 -251.564924) (xy 81.985185 -251.531489)
			(xy 82.027142 -251.504515) (xy 82.072926 -251.484719) (xy 82.121318 -251.472626) (xy 82.171032 -251.46856)
			(xy 82.220746 -251.472626) (xy 82.269138 -251.484719) (xy 82.314922 -251.504515) (xy 82.356879 -251.531489)
			(xy 82.393895 -251.564924) (xy 82.424985 -251.603929) (xy 82.449322 -251.647469) (xy 82.46626 -251.694385)
			(xy 82.475347 -251.743431) (xy 82.47634 -251.768356) (xy 82.47634 -251.77496) (xy 82.475813 -251.799501)
			(xy 82.467889 -251.847939) (xy 82.452317 -251.894487) (xy 82.4295 -251.937944) (xy 82.415126 -251.95784)
			(xy 82.415126 -251.958348) (xy 82.414872 -251.958602) (xy 82.410983 -251.96422) (xy 82.406081 -251.97697)
			(xy 82.40522 -251.983748) (xy 82.404458 -251.99086) (xy 82.406998 -252.00483) (xy 82.451448 -252.09373)
			(xy 82.453734 -252.097794) (xy 82.461062 -252.107806) (xy 82.482759 -252.119784) (xy 82.495136 -252.120654)
			(xy 82.785966 -252.120654) (xy 82.786982 -252.120654) (xy 82.799365 -252.1198) (xy 82.821076 -252.107825)
			(xy 82.828384 -252.097794) (xy 82.83067 -252.09373) (xy 82.871818 -252.011434) (xy 82.874782 -252.00493)
			(xy 82.877365 -251.99088) (xy 82.876898 -251.983748) (xy 82.875628 -251.969778) (xy 82.866992 -251.958348)
			(xy 82.866992 -251.95784) (xy 82.852708 -251.938034) (xy 82.829961 -251.894828) (xy 82.814378 -251.848553)
			(xy 82.806359 -251.800388) (xy 82.805778 -251.775976) (xy 82.805778 -251.768356) (xy 82.806771 -251.743431)
			(xy 82.815858 -251.694385) (xy 82.832796 -251.647469) (xy 82.857133 -251.603929) (xy 82.888223 -251.564924)
			(xy 82.925239 -251.531489) (xy 82.967196 -251.504515) (xy 83.01298 -251.484719) (xy 83.061372 -251.472626)
			(xy 83.111086 -251.46856) (xy 83.1608 -251.472626) (xy 83.209192 -251.484719) (xy 83.254976 -251.504515)
			(xy 83.296933 -251.531489) (xy 83.333949 -251.564924) (xy 83.365039 -251.603929) (xy 83.389376 -251.647469)
			(xy 83.406314 -251.694385) (xy 83.415401 -251.743431) (xy 83.416394 -251.768356) (xy 83.416394 -251.77496)
			(xy 83.415867 -251.7995) (xy 83.407941 -251.847938) (xy 83.392368 -251.894485) (xy 83.369548 -251.937939)
			(xy 83.35518 -251.95784) (xy 83.35518 -251.958348) (xy 83.354926 -251.958602) (xy 83.351039 -251.964221)
			(xy 83.346142 -251.976971) (xy 83.345274 -251.983748) (xy 83.344512 -251.99086) (xy 83.347052 -252.00483)
			(xy 83.391502 -252.09373) (xy 83.393788 -252.097794) (xy 83.401113 -252.107813) (xy 83.422809 -252.119812)
			(xy 83.43519 -252.120654) (xy 83.721194 -252.120654) (xy 83.730538 -252.120187) (xy 83.747961 -252.113414)
			(xy 83.761818 -252.100867) (xy 83.766406 -252.092714) (xy 83.8073 -252.01118) (xy 83.810201 -252.00486)
			(xy 83.812769 -251.991199) (xy 83.81238 -251.984256) (xy 83.812126 -251.9807) (xy 83.794278 -251.959063)
			(xy 83.76575 -251.910776) (xy 83.746219 -251.858202) (xy 83.7363 -251.803002) (xy 83.735672 -251.77496)
			(xy 83.735672 -251.774452) (xy 83.736158 -251.749662) (xy 83.743914 -251.700694) (xy 83.759235 -251.653541)
			(xy 83.781744 -251.609366) (xy 83.810886 -251.569255) (xy 83.845943 -251.534198) (xy 83.886054 -251.505056)
			(xy 83.930229 -251.482547) (xy 83.977382 -251.467226) (xy 84.02635 -251.45947) (xy 84.07593 -251.45947)
			(xy 84.124898 -251.467226) (xy 84.172051 -251.482547) (xy 84.216226 -251.505056) (xy 84.256337 -251.534198)
			(xy 84.291394 -251.569255) (xy 84.320536 -251.609366) (xy 84.343045 -251.653541) (xy 84.358366 -251.700694)
			(xy 84.366122 -251.749662) (xy 84.366608 -251.774452) (xy 84.366608 -251.77496) (xy 84.366086 -251.801179)
			(xy 84.357417 -251.852896) (xy 84.340328 -251.902472) (xy 84.315287 -251.948545) (xy 84.299552 -251.969524)
			(xy 84.295238 -251.975482) (xy 84.289823 -251.989152) (xy 84.288884 -251.996448) (xy 84.28863 -251.99848)
			(xy 84.335874 -252.092714) (xy 84.34044 -252.100891) (xy 84.354281 -252.113482) (xy 84.371731 -252.120235)
			(xy 84.381086 -252.120654) (xy 84.66582 -252.120654) (xy 84.666836 -252.120654) (xy 84.679212 -252.119789)
			(xy 84.700903 -252.107801) (xy 84.708238 -252.097794) (xy 84.710524 -252.09373) (xy 84.751672 -252.011434)
			(xy 84.754638 -252.004931) (xy 84.757224 -251.99088) (xy 84.756752 -251.983748) (xy 84.755482 -251.969778)
			(xy 84.746846 -251.958348) (xy 84.746846 -251.95784) (xy 84.732564 -251.938034) (xy 84.70982 -251.894827)
			(xy 84.69424 -251.848552) (xy 84.686222 -251.800387) (xy 84.685632 -251.775976) (xy 84.685632 -251.768356)
			(xy 84.686625 -251.743431) (xy 84.695712 -251.694385) (xy 84.71265 -251.647469) (xy 84.736987 -251.603929)
			(xy 84.768077 -251.564924) (xy 84.805093 -251.531489) (xy 84.84705 -251.504515) (xy 84.892834 -251.484719)
			(xy 84.941226 -251.472626) (xy 84.99094 -251.46856) (xy 85.040654 -251.472626) (xy 85.089046 -251.484719)
			(xy 85.13483 -251.504515) (xy 85.176787 -251.531489) (xy 85.213803 -251.564924) (xy 85.244893 -251.603929)
			(xy 85.26923 -251.647469) (xy 85.286168 -251.694385) (xy 85.295255 -251.743431) (xy 85.296248 -251.768356)
			(xy 85.296248 -251.77496) (xy 85.295721 -251.799501) (xy 85.287797 -251.84794) (xy 85.272226 -251.894487)
			(xy 85.249409 -251.937944) (xy 85.235034 -251.95784) (xy 85.235034 -251.958348) (xy 85.23478 -251.958602)
			(xy 85.230896 -251.964223) (xy 85.226004 -251.976972) (xy 85.225128 -251.983748) (xy 85.224366 -251.99086)
			(xy 85.226906 -252.00483) (xy 85.271356 -252.09373) (xy 85.273642 -252.097794) (xy 85.280971 -252.107804)
			(xy 85.302668 -252.11978) (xy 85.315044 -252.120654) (xy 85.605874 -252.120654) (xy 85.60689 -252.120654)
			(xy 85.619272 -252.119798) (xy 85.64098 -252.107822) (xy 85.648292 -252.097794) (xy 85.650578 -252.09373)
			(xy 85.691726 -252.011434) (xy 85.694694 -252.004931) (xy 85.697282 -251.99088) (xy 85.696806 -251.983748)
			(xy 85.695536 -251.969778) (xy 85.6869 -251.958348) (xy 85.6869 -251.95784) (xy 85.672616 -251.938034)
			(xy 85.649868 -251.894829) (xy 85.634285 -251.848553) (xy 85.626265 -251.800388) (xy 85.625686 -251.775976)
			(xy 85.625686 -251.768356) (xy 85.626679 -251.743431) (xy 85.635766 -251.694385) (xy 85.652704 -251.647469)
			(xy 85.677041 -251.603929) (xy 85.708131 -251.564924) (xy 85.745147 -251.531489) (xy 85.787104 -251.504515)
			(xy 85.832888 -251.484719) (xy 85.88128 -251.472626) (xy 85.930994 -251.46856) (xy 85.980708 -251.472626)
			(xy 86.0291 -251.484719) (xy 86.074884 -251.504515) (xy 86.116841 -251.531489) (xy 86.153857 -251.564924)
			(xy 86.184947 -251.603929) (xy 86.209284 -251.647469) (xy 86.226222 -251.694385) (xy 86.235309 -251.743431)
			(xy 86.236302 -251.768356) (xy 86.236302 -251.77496) (xy 86.235775 -251.7995) (xy 86.22785 -251.847939)
			(xy 86.212277 -251.894485) (xy 86.189457 -251.93794) (xy 86.175088 -251.95784) (xy 86.175088 -251.958348)
			(xy 86.174834 -251.958602) (xy 86.170947 -251.964221) (xy 86.166049 -251.976971) (xy 86.165182 -251.983748)
			(xy 86.16442 -251.99086) (xy 86.16696 -252.00483) (xy 86.21141 -252.09373) (xy 86.213696 -252.097794)
			(xy 86.221022 -252.107812) (xy 86.242718 -252.119806) (xy 86.255098 -252.120654) (xy 86.545928 -252.120654)
			(xy 86.546944 -252.120654) (xy 86.559319 -252.119787) (xy 86.581007 -252.107798) (xy 86.588346 -252.097794)
			(xy 86.590632 -252.09373) (xy 86.63178 -252.011434) (xy 86.634746 -252.004931) (xy 86.637331 -251.99088)
			(xy 86.63686 -251.983748) (xy 86.63559 -251.969778) (xy 86.626954 -251.958348) (xy 86.626954 -251.95784)
			(xy 86.612672 -251.938034) (xy 86.589927 -251.894827) (xy 86.574347 -251.848552) (xy 86.566329 -251.800387)
			(xy 86.56574 -251.775976) (xy 86.56574 -251.768356) (xy 86.566733 -251.743431) (xy 86.57582 -251.694385)
			(xy 86.592758 -251.647469) (xy 86.617095 -251.603929) (xy 86.648185 -251.564924) (xy 86.685201 -251.531489)
			(xy 86.727158 -251.504515) (xy 86.772942 -251.484719) (xy 86.821334 -251.472626) (xy 86.871048 -251.46856)
			(xy 86.920762 -251.472626) (xy 86.969154 -251.484719) (xy 87.014938 -251.504515) (xy 87.056895 -251.531489)
			(xy 87.093911 -251.564924) (xy 87.125001 -251.603929) (xy 87.149338 -251.647469) (xy 87.166276 -251.694385)
			(xy 87.175363 -251.743431) (xy 87.176356 -251.768356) (xy 87.176356 -251.77496) (xy 87.175829 -251.799501)
			(xy 87.167905 -251.84794) (xy 87.152334 -251.894487) (xy 87.129518 -251.937945) (xy 87.115142 -251.95784)
			(xy 87.115142 -251.958348) (xy 87.114888 -251.958602) (xy 87.111004 -251.964223) (xy 87.10611 -251.976972)
			(xy 87.105236 -251.983748) (xy 87.104474 -251.99086) (xy 87.107014 -252.00483) (xy 87.151464 -252.09373)
			(xy 87.15375 -252.097794) (xy 87.161079 -252.107803) (xy 87.182777 -252.119775) (xy 87.195152 -252.120654)
			(xy 87.481156 -252.120654) (xy 87.490494 -252.120177) (xy 87.5079 -252.11339) (xy 87.521739 -252.10084)
			(xy 87.526368 -252.092714) (xy 87.567262 -252.01118) (xy 87.570165 -252.004861) (xy 87.572735 -251.991199)
			(xy 87.572342 -251.984256) (xy 87.572088 -251.9807) (xy 87.554191 -251.95901) (xy 87.525584 -251.910606)
			(xy 87.505992 -251.857903) (xy 87.496034 -251.802565) (xy 87.49538 -251.774452) (xy 87.495867 -251.749642)
			(xy 87.503629 -251.700634) (xy 87.518962 -251.653444) (xy 87.541489 -251.609233) (xy 87.570654 -251.56909)
			(xy 87.60574 -251.534004) (xy 87.645883 -251.504839) (xy 87.690094 -251.482312) (xy 87.737284 -251.466979)
			(xy 87.786292 -251.459217) (xy 87.835912 -251.459217) (xy 87.88492 -251.466979) (xy 87.93211 -251.482312)
			(xy 87.976321 -251.504839) (xy 88.016464 -251.534004) (xy 88.05155 -251.56909) (xy 88.080715 -251.609233)
			(xy 88.103242 -251.653444) (xy 88.118575 -251.700634) (xy 88.126337 -251.749642) (xy 88.126824 -251.774452)
			(xy 88.126298 -251.800715) (xy 88.117597 -251.852515) (xy 88.100444 -251.90216) (xy 88.075311 -251.948283)
			(xy 88.059514 -251.96927) (xy 88.055144 -251.975269) (xy 88.049725 -251.989079) (xy 88.048846 -251.996448)
			(xy 88.048592 -251.99848) (xy 88.095836 -252.092714) (xy 88.100401 -252.100895) (xy 88.114239 -252.113496)
			(xy 88.13169 -252.120262) (xy 88.141048 -252.120654) (xy 88.426036 -252.120654) (xy 88.427052 -252.120654)
			(xy 88.439439 -252.119807) (xy 88.461161 -252.107839) (xy 88.468454 -252.097794) (xy 88.47074 -252.09373)
			(xy 88.511888 -252.011434) (xy 88.514853 -252.004931) (xy 88.517438 -251.99088) (xy 88.516968 -251.983748)
			(xy 88.515698 -251.969778) (xy 88.507062 -251.958348) (xy 88.507062 -251.95784) (xy 88.49278 -251.938034)
			(xy 88.470034 -251.894827) (xy 88.454453 -251.848552) (xy 88.446435 -251.800387) (xy 88.445848 -251.775976)
			(xy 88.445848 -251.768356) (xy 88.446841 -251.743431) (xy 88.455928 -251.694385) (xy 88.472866 -251.647469)
			(xy 88.497203 -251.603929) (xy 88.528293 -251.564924) (xy 88.565309 -251.531489) (xy 88.607266 -251.504515)
			(xy 88.65305 -251.484719) (xy 88.701442 -251.472626) (xy 88.751156 -251.46856) (xy 88.80087 -251.472626)
			(xy 88.849262 -251.484719) (xy 88.895046 -251.504515) (xy 88.937003 -251.531489) (xy 88.974019 -251.564924)
			(xy 89.005109 -251.603929) (xy 89.029446 -251.647469) (xy 89.046384 -251.694385) (xy 89.055471 -251.743431)
			(xy 89.056464 -251.768356) (xy 89.056464 -251.77496) (xy 89.055937 -251.7995) (xy 89.048011 -251.847938)
			(xy 89.032436 -251.894483) (xy 89.009615 -251.937937) (xy 88.99525 -251.95784) (xy 88.99525 -251.958348)
			(xy 88.994996 -251.958602) (xy 88.991111 -251.964222) (xy 88.986217 -251.976972) (xy 88.985344 -251.983748)
			(xy 88.984582 -251.99086) (xy 88.987122 -252.00483) (xy 89.031572 -252.09373) (xy 89.033858 -252.097794)
			(xy 89.041188 -252.107802) (xy 89.062886 -252.119771) (xy 89.07526 -252.120654) (xy 89.365836 -252.120654)
			(xy 89.366852 -252.120654) (xy 89.379239 -252.119807) (xy 89.400961 -252.107839) (xy 89.408254 -252.097794)
			(xy 89.41054 -252.09373) (xy 89.451688 -252.011434) (xy 89.454653 -252.004931) (xy 89.457238 -251.99088)
			(xy 89.456768 -251.983748) (xy 89.455498 -251.969778) (xy 89.446862 -251.958348) (xy 89.446862 -251.95784)
			(xy 89.43258 -251.938034) (xy 89.409834 -251.894827) (xy 89.394253 -251.848552) (xy 89.386235 -251.800387)
			(xy 89.385648 -251.775976) (xy 89.385648 -251.768356) (xy 89.386641 -251.743431) (xy 89.395728 -251.694385)
			(xy 89.412666 -251.647469) (xy 89.437003 -251.603929) (xy 89.468093 -251.564924) (xy 89.505109 -251.531489)
			(xy 89.547066 -251.504515) (xy 89.59285 -251.484719) (xy 89.641242 -251.472626) (xy 89.690956 -251.46856)
			(xy 89.74067 -251.472626) (xy 89.789062 -251.484719) (xy 89.834846 -251.504515) (xy 89.876803 -251.531489)
			(xy 89.913819 -251.564924) (xy 89.944909 -251.603929) (xy 89.969246 -251.647469) (xy 89.986184 -251.694385)
			(xy 89.995271 -251.743431) (xy 89.996264 -251.768356) (xy 89.996264 -251.77496) (xy 89.995737 -251.7995)
			(xy 89.987811 -251.847938) (xy 89.972236 -251.894483) (xy 89.949415 -251.937937) (xy 89.93505 -251.95784)
			(xy 89.93505 -251.958348) (xy 89.934796 -251.958602) (xy 89.930911 -251.964222) (xy 89.926017 -251.976972)
			(xy 89.925144 -251.983748) (xy 89.924382 -251.99086) (xy 89.926922 -252.00483) (xy 89.971372 -252.09373)
			(xy 89.973658 -252.097794) (xy 89.980988 -252.107802) (xy 90.002686 -252.119771) (xy 90.01506 -252.120654)
			(xy 90.301064 -252.120654) (xy 90.310401 -252.120175) (xy 90.327805 -252.113387) (xy 90.341642 -252.100837)
			(xy 90.346276 -252.092714) (xy 90.38717 -252.01118) (xy 90.390072 -252.004861) (xy 90.392642 -251.991199)
			(xy 90.39225 -251.984256) (xy 90.391996 -251.9807) (xy 90.374099 -251.959011) (xy 90.34549 -251.910606)
			(xy 90.325898 -251.857903) (xy 90.31594 -251.802565) (xy 90.315288 -251.774452) (xy 90.315775 -251.749642)
			(xy 90.323537 -251.700634) (xy 90.33887 -251.653444) (xy 90.361397 -251.609233) (xy 90.390562 -251.56909)
			(xy 90.425648 -251.534004) (xy 90.465791 -251.504839) (xy 90.510002 -251.482312) (xy 90.557192 -251.466979)
			(xy 90.6062 -251.459217) (xy 90.65582 -251.459217) (xy 90.704828 -251.466979) (xy 90.752018 -251.482312)
			(xy 90.796229 -251.504839) (xy 90.836372 -251.534004) (xy 90.871458 -251.56909) (xy 90.900623 -251.609233)
			(xy 90.92315 -251.653444) (xy 90.938483 -251.700634) (xy 90.946245 -251.749642) (xy 90.946732 -251.774452)
			(xy 90.946206 -251.800715) (xy 90.937506 -251.852515) (xy 90.920352 -251.902161) (xy 90.89522 -251.948283)
			(xy 90.879422 -251.96927) (xy 90.875052 -251.975269) (xy 90.869632 -251.989078) (xy 90.868754 -251.996448)
			(xy 90.8685 -251.99848) (xy 90.915744 -252.092714) (xy 90.920309 -252.100894) (xy 90.934148 -252.113493)
			(xy 90.951599 -252.120256) (xy 90.960956 -252.120654) (xy 91.245944 -252.120654) (xy 91.24696 -252.120654)
			(xy 91.259346 -252.119805) (xy 91.281065 -252.107835) (xy 91.288362 -252.097794) (xy 91.290648 -252.09373)
			(xy 91.331796 -252.011434) (xy 91.334761 -252.004931) (xy 91.337345 -251.99088) (xy 91.336876 -251.983748)
			(xy 91.335606 -251.969778) (xy 91.32697 -251.958348) (xy 91.32697 -251.95784) (xy 91.312687 -251.938034)
			(xy 91.289941 -251.894828) (xy 91.27436 -251.848552) (xy 91.266341 -251.800387) (xy 91.265756 -251.775976)
			(xy 91.265756 -251.768356) (xy 91.266749 -251.743431) (xy 91.275836 -251.694385) (xy 91.292774 -251.647469)
			(xy 91.317111 -251.603929) (xy 91.348201 -251.564924) (xy 91.385217 -251.531489) (xy 91.427174 -251.504515)
			(xy 91.472958 -251.484719) (xy 91.52135 -251.472626) (xy 91.571064 -251.46856) (xy 91.620778 -251.472626)
			(xy 91.66917 -251.484719) (xy 91.714954 -251.504515) (xy 91.756911 -251.531489) (xy 91.793927 -251.564924)
			(xy 91.825017 -251.603929) (xy 91.849354 -251.647469) (xy 91.866292 -251.694385) (xy 91.875379 -251.743431)
			(xy 91.876372 -251.768356) (xy 91.876372 -251.77496) (xy 91.875845 -251.7995) (xy 91.867919 -251.847938)
			(xy 91.852345 -251.894484) (xy 91.829524 -251.937938) (xy 91.815158 -251.95784) (xy 91.815158 -251.958348)
			(xy 91.814904 -251.958602) (xy 91.811019 -251.964222) (xy 91.806124 -251.976972) (xy 91.805252 -251.983748)
			(xy 91.80449 -251.99086) (xy 91.80703 -252.00483) (xy 91.85148 -252.09373) (xy 91.853766 -252.097794)
			(xy 91.861097 -252.1078) (xy 91.882794 -252.119765) (xy 91.895168 -252.120654) (xy 92.185998 -252.120654)
			(xy 92.187014 -252.120654) (xy 92.199393 -252.119793) (xy 92.221092 -252.107811) (xy 92.228416 -252.097794)
			(xy 92.230702 -252.09373) (xy 92.27185 -252.011434) (xy 92.274817 -252.004931) (xy 92.277403 -251.99088)
			(xy 92.27693 -251.983748) (xy 92.27566 -251.969778) (xy 92.267024 -251.958348) (xy 92.267024 -251.95784)
			(xy 92.252743 -251.938033) (xy 92.23 -251.894826) (xy 92.214421 -251.848551) (xy 92.206404 -251.800387)
			(xy 92.20581 -251.775976) (xy 92.20581 -251.768356) (xy 92.206803 -251.743431) (xy 92.21589 -251.694385)
			(xy 92.232828 -251.647469) (xy 92.257165 -251.603929) (xy 92.288255 -251.564924) (xy 92.325271 -251.531489)
			(xy 92.367228 -251.504515) (xy 92.413012 -251.484719) (xy 92.461404 -251.472626) (xy 92.511118 -251.46856)
			(xy 92.560832 -251.472626) (xy 92.609224 -251.484719) (xy 92.655008 -251.504515) (xy 92.696965 -251.531489)
			(xy 92.733981 -251.564924) (xy 92.765071 -251.603929) (xy 92.789408 -251.647469) (xy 92.806346 -251.694385)
			(xy 92.815433 -251.743431) (xy 92.816426 -251.768356) (xy 92.816426 -251.77496) (xy 92.815899 -251.799501)
			(xy 92.807974 -251.847939) (xy 92.792402 -251.894486) (xy 92.769584 -251.937942) (xy 92.755212 -251.95784)
			(xy 92.755212 -251.958348) (xy 92.754958 -251.958602) (xy 92.75107 -251.964221) (xy 92.746169 -251.97697)
			(xy 92.745306 -251.983748) (xy 92.744544 -251.99086) (xy 92.747084 -252.00483) (xy 92.791534 -252.09373)
			(xy 92.79382 -252.097794) (xy 92.801147 -252.107808) (xy 92.822844 -252.119793) (xy 92.835222 -252.120654)
			(xy 93.125798 -252.120654) (xy 93.126814 -252.120654) (xy 93.139193 -252.119793) (xy 93.160892 -252.107811)
			(xy 93.168216 -252.097794) (xy 93.170502 -252.09373) (xy 93.21165 -252.011434) (xy 93.214617 -252.004931)
			(xy 93.217203 -251.99088) (xy 93.21673 -251.983748) (xy 93.21546 -251.969778) (xy 93.206824 -251.958348)
			(xy 93.206824 -251.95784) (xy 93.192543 -251.938033) (xy 93.1698 -251.894826) (xy 93.154221 -251.848551)
			(xy 93.146204 -251.800387) (xy 93.14561 -251.775976) (xy 93.14561 -251.768356) (xy 93.146603 -251.743431)
			(xy 93.15569 -251.694385) (xy 93.172628 -251.647469) (xy 93.196965 -251.603929) (xy 93.228055 -251.564924)
			(xy 93.265071 -251.531489) (xy 93.307028 -251.504515) (xy 93.352812 -251.484719) (xy 93.401204 -251.472626)
			(xy 93.450918 -251.46856) (xy 93.500632 -251.472626) (xy 93.549024 -251.484719) (xy 93.594808 -251.504515)
			(xy 93.636765 -251.531489) (xy 93.673781 -251.564924) (xy 93.704871 -251.603929) (xy 93.729208 -251.647469)
			(xy 93.746146 -251.694385) (xy 93.755233 -251.743431) (xy 93.756226 -251.768356) (xy 93.756226 -251.77496)
			(xy 93.755699 -251.799501) (xy 93.747774 -251.847939) (xy 93.732202 -251.894486) (xy 93.709384 -251.937942)
			(xy 93.695012 -251.95784) (xy 93.695012 -251.958348) (xy 93.694758 -251.958602) (xy 93.69087 -251.964221)
			(xy 93.685969 -251.97697) (xy 93.685106 -251.983748) (xy 93.684344 -251.99086) (xy 93.686884 -252.00483)
			(xy 93.731334 -252.09373) (xy 93.73362 -252.097794) (xy 93.740947 -252.107808) (xy 93.762644 -252.119793)
			(xy 93.775022 -252.120654) (xy 94.061026 -252.120654) (xy 94.070367 -252.120182) (xy 94.087781 -252.113401)
			(xy 94.101629 -252.100853) (xy 94.106238 -252.092714) (xy 94.147132 -252.01118) (xy 94.150031 -252.00486)
			(xy 94.152598 -251.991199) (xy 94.152212 -251.984256) (xy 94.151958 -251.9807) (xy 94.134108 -251.959063)
			(xy 94.105578 -251.910777) (xy 94.086044 -251.858204) (xy 94.076124 -251.803003) (xy 94.075504 -251.77496)
			(xy 94.075504 -251.774452) (xy 94.07599 -251.749662) (xy 94.083746 -251.700694) (xy 94.099067 -251.653541)
			(xy 94.121576 -251.609366) (xy 94.150718 -251.569255) (xy 94.185775 -251.534198) (xy 94.225886 -251.505056)
			(xy 94.270061 -251.482547) (xy 94.317214 -251.467226) (xy 94.366182 -251.45947) (xy 94.415762 -251.45947)
			(xy 94.46473 -251.467226) (xy 94.511883 -251.482547) (xy 94.556058 -251.505056) (xy 94.596169 -251.534198)
			(xy 94.631226 -251.569255) (xy 94.660368 -251.609366) (xy 94.682877 -251.653541) (xy 94.698198 -251.700694)
			(xy 94.705954 -251.749662) (xy 94.70644 -251.774452) (xy 94.70644 -251.77496) (xy 94.705918 -251.801179)
			(xy 94.697248 -251.852895) (xy 94.680155 -251.902468) (xy 94.65511 -251.948538) (xy 94.639384 -251.969524)
			(xy 94.635067 -251.975481) (xy 94.629649 -251.989151) (xy 94.628716 -251.996448) (xy 94.628462 -251.99848)
			(xy 94.675706 -252.092714) (xy 94.680274 -252.100887) (xy 94.694116 -252.113469) (xy 94.711565 -252.120211)
			(xy 94.720918 -252.120654) (xy 95.005906 -252.120654) (xy 95.006922 -252.120654) (xy 95.0193 -252.119792)
			(xy 95.040996 -252.107808) (xy 95.048324 -252.097794) (xy 95.05061 -252.09373) (xy 95.091758 -252.011434)
			(xy 95.094725 -252.004931) (xy 95.097311 -251.99088) (xy 95.096838 -251.983748) (xy 95.095568 -251.969778)
			(xy 95.086932 -251.958348) (xy 95.086932 -251.95784) (xy 95.072651 -251.938034) (xy 95.049907 -251.894827)
			(xy 95.034328 -251.848551) (xy 95.02631 -251.800387) (xy 95.025718 -251.775976) (xy 95.025718 -251.768356)
			(xy 95.026711 -251.743431) (xy 95.035798 -251.694385) (xy 95.052736 -251.647469) (xy 95.077073 -251.603929)
			(xy 95.108163 -251.564924) (xy 95.145179 -251.531489) (xy 95.187136 -251.504515) (xy 95.23292 -251.484719)
			(xy 95.281312 -251.472626) (xy 95.331026 -251.46856) (xy 95.38074 -251.472626) (xy 95.429132 -251.484719)
			(xy 95.474916 -251.504515) (xy 95.516873 -251.531489) (xy 95.553889 -251.564924) (xy 95.584979 -251.603929)
			(xy 95.609316 -251.647469) (xy 95.626254 -251.694385) (xy 95.635341 -251.743431) (xy 95.636334 -251.768356)
			(xy 95.636334 -251.77496) (xy 95.635807 -251.799501) (xy 95.627882 -251.847939) (xy 95.612311 -251.894486)
			(xy 95.589493 -251.937943) (xy 95.57512 -251.95784) (xy 95.57512 -251.958348) (xy 95.574866 -251.958602)
			(xy 95.570977 -251.964221) (xy 95.566076 -251.97697) (xy 95.565214 -251.983748) (xy 95.564452 -251.99086)
			(xy 95.566992 -252.00483) (xy 95.611442 -252.09373) (xy 95.613728 -252.097794) (xy 95.621056 -252.107806)
			(xy 95.642753 -252.119788) (xy 95.65513 -252.120654) (xy 95.94596 -252.120654) (xy 95.946976 -252.120654)
			(xy 95.95936 -252.119801) (xy 95.981073 -252.107828) (xy 95.988378 -252.097794) (xy 95.990664 -252.09373)
			(xy 96.031812 -252.011434) (xy 96.034776 -252.004931) (xy 96.037359 -251.99088) (xy 96.036892 -251.983748)
			(xy 96.035622 -251.969778) (xy 96.026986 -251.958348) (xy 96.026986 -251.95784) (xy 96.012703 -251.938034)
			(xy 95.989955 -251.894828) (xy 95.974373 -251.848553) (xy 95.966354 -251.800387) (xy 95.965772 -251.775976)
			(xy 95.965772 -251.768356) (xy 95.966765 -251.743431) (xy 95.975852 -251.694385) (xy 95.99279 -251.647469)
			(xy 96.017127 -251.603929) (xy 96.048217 -251.564924) (xy 96.085233 -251.531489) (xy 96.12719 -251.504515)
			(xy 96.172974 -251.484719) (xy 96.221366 -251.472626) (xy 96.27108 -251.46856) (xy 96.320794 -251.472626)
			(xy 96.369186 -251.484719) (xy 96.41497 -251.504515) (xy 96.456927 -251.531489) (xy 96.493943 -251.564924)
			(xy 96.525033 -251.603929) (xy 96.54937 -251.647469) (xy 96.566308 -251.694385) (xy 96.575395 -251.743431)
			(xy 96.576388 -251.768356) (xy 96.576388 -251.77496) (xy 96.575861 -251.7995) (xy 96.567935 -251.847938)
			(xy 96.552362 -251.894484) (xy 96.529542 -251.937939) (xy 96.515174 -251.95784) (xy 96.515174 -251.958348)
			(xy 96.51492 -251.958602) (xy 96.511034 -251.964222) (xy 96.506137 -251.976971) (xy 96.505268 -251.983748)
			(xy 96.504506 -251.99086) (xy 96.507046 -252.00483) (xy 96.551496 -252.09373) (xy 96.553782 -252.097794)
			(xy 96.561199 -252.107715) (xy 96.582838 -252.119684) (xy 96.595184 -252.120654) (xy 96.886014 -252.120654)
			(xy 96.88703 -252.120654) (xy 96.899407 -252.11979) (xy 96.9211 -252.107804) (xy 96.928432 -252.097794)
			(xy 96.930718 -252.09373) (xy 96.971866 -252.011434) (xy 96.974832 -252.004931) (xy 96.977418 -251.99088)
			(xy 96.976946 -251.983748) (xy 96.975676 -251.969778) (xy 96.96704 -251.958348) (xy 96.96704 -251.95784)
			(xy 96.952758 -251.938034) (xy 96.930014 -251.894827) (xy 96.914435 -251.848552) (xy 96.906417 -251.800387)
			(xy 96.905826 -251.775976) (xy 96.905826 -251.768356) (xy 96.906819 -251.743431) (xy 96.915906 -251.694385)
			(xy 96.932844 -251.647469) (xy 96.957181 -251.603929) (xy 96.988271 -251.564924) (xy 97.025287 -251.531489)
			(xy 97.067244 -251.504515) (xy 97.113028 -251.484719) (xy 97.16142 -251.472626) (xy 97.211134 -251.46856)
			(xy 97.260848 -251.472626) (xy 97.30924 -251.484719) (xy 97.355024 -251.504515) (xy 97.396981 -251.531489)
			(xy 97.433997 -251.564924) (xy 97.465087 -251.603929) (xy 97.489424 -251.647469) (xy 97.506362 -251.694385)
			(xy 97.515449 -251.743431) (xy 97.516442 -251.768356) (xy 97.516442 -251.77496) (xy 97.515915 -251.799501)
			(xy 97.507991 -251.847939) (xy 97.492419 -251.894487) (xy 97.469602 -251.937944) (xy 97.455228 -251.95784)
			(xy 97.455228 -251.958348) (xy 97.454974 -251.958602) (xy 97.451084 -251.96422) (xy 97.446182 -251.97697)
			(xy 97.445322 -251.983748) (xy 97.44456 -251.99086) (xy 97.4471 -252.00483) (xy 97.49155 -252.09373)
			(xy 97.493836 -252.097794) (xy 97.501164 -252.107805) (xy 97.522862 -252.119783) (xy 97.535238 -252.120654)
			(xy 97.825814 -252.120654) (xy 97.82683 -252.120654) (xy 97.839207 -252.11979) (xy 97.8609 -252.107804)
			(xy 97.868232 -252.097794) (xy 97.870518 -252.09373) (xy 97.911666 -252.011434) (xy 97.914632 -252.004931)
			(xy 97.917218 -251.99088) (xy 97.916746 -251.983748) (xy 97.915476 -251.969778) (xy 97.90684 -251.958348)
			(xy 97.90684 -251.95784) (xy 97.892558 -251.938034) (xy 97.869814 -251.894827) (xy 97.854235 -251.848552)
			(xy 97.846217 -251.800387) (xy 97.845626 -251.775976) (xy 97.845626 -251.768356) (xy 97.846619 -251.743431)
			(xy 97.855706 -251.694385) (xy 97.872644 -251.647469) (xy 97.896981 -251.603929) (xy 97.928071 -251.564924)
			(xy 97.965087 -251.531489) (xy 98.007044 -251.504515) (xy 98.052828 -251.484719) (xy 98.10122 -251.472626)
			(xy 98.150934 -251.46856) (xy 98.200648 -251.472626) (xy 98.24904 -251.484719) (xy 98.294824 -251.504515)
			(xy 98.336781 -251.531489) (xy 98.373797 -251.564924) (xy 98.404887 -251.603929) (xy 98.429224 -251.647469)
			(xy 98.446162 -251.694385) (xy 98.455249 -251.743431) (xy 98.456242 -251.768356) (xy 98.456242 -251.77496)
			(xy 98.455715 -251.799501) (xy 98.447791 -251.847939) (xy 98.432219 -251.894487) (xy 98.409402 -251.937944)
			(xy 98.395028 -251.95784) (xy 98.395028 -251.958348) (xy 98.394774 -251.958602) (xy 98.390884 -251.96422)
			(xy 98.385982 -251.97697) (xy 98.385122 -251.983748) (xy 98.38436 -251.99086) (xy 98.3869 -252.00483)
			(xy 98.43135 -252.09373) (xy 98.433636 -252.097794) (xy 98.440964 -252.107805) (xy 98.462662 -252.119783)
			(xy 98.475038 -252.120654) (xy 98.765868 -252.120654) (xy 98.766884 -252.120654) (xy 98.779267 -252.1198)
			(xy 98.800977 -252.107825) (xy 98.808286 -252.097794) (xy 98.810572 -252.09373) (xy 98.85172 -252.011434)
			(xy 98.854688 -252.004931) (xy 98.857276 -251.99088) (xy 98.8568 -251.983748) (xy 98.85553 -251.969778)
			(xy 98.846894 -251.958348) (xy 98.846894 -251.95784) (xy 98.83261 -251.938034) (xy 98.809862 -251.894828)
			(xy 98.79428 -251.848553) (xy 98.786261 -251.800388) (xy 98.78568 -251.775976) (xy 98.78568 -251.768356)
			(xy 98.786673 -251.743431) (xy 98.79576 -251.694385) (xy 98.812698 -251.647469) (xy 98.837035 -251.603929)
			(xy 98.868125 -251.564924) (xy 98.905141 -251.531489) (xy 98.947098 -251.504515) (xy 98.992882 -251.484719)
			(xy 99.041274 -251.472626) (xy 99.090988 -251.46856) (xy 99.140702 -251.472626) (xy 99.189094 -251.484719)
			(xy 99.234878 -251.504515) (xy 99.276835 -251.531489) (xy 99.313851 -251.564924) (xy 99.344941 -251.603929)
			(xy 99.369278 -251.647469) (xy 99.386216 -251.694385) (xy 99.395303 -251.743431) (xy 99.396296 -251.768356)
			(xy 99.396296 -251.77496) (xy 99.395769 -251.7995) (xy 99.387843 -251.847939) (xy 99.37227 -251.894485)
			(xy 99.349451 -251.93794) (xy 99.335082 -251.95784) (xy 99.335082 -251.958348) (xy 99.334828 -251.958602)
			(xy 99.330941 -251.964221) (xy 99.326044 -251.976971) (xy 99.325176 -251.983748) (xy 99.324414 -251.99086)
			(xy 99.326954 -252.00483) (xy 99.371404 -252.09373) (xy 99.37369 -252.097794) (xy 99.381015 -252.107813)
			(xy 99.402711 -252.11981) (xy 99.415092 -252.120654) (xy 99.705922 -252.120654) (xy 99.706938 -252.120654)
			(xy 99.719314 -252.119788) (xy 99.741004 -252.107801) (xy 99.74834 -252.097794) (xy 99.750626 -252.09373)
			(xy 99.791774 -252.011434) (xy 99.79474 -252.004931) (xy 99.797325 -251.99088) (xy 99.796854 -251.983748)
			(xy 99.795584 -251.969778) (xy 99.786948 -251.958348) (xy 99.786948 -251.95784) (xy 99.772666 -251.938034)
			(xy 99.749922 -251.894827) (xy 99.734342 -251.848552) (xy 99.726324 -251.800387) (xy 99.725734 -251.775976)
			(xy 99.725734 -251.768356) (xy 99.726727 -251.743431) (xy 99.735814 -251.694385) (xy 99.752752 -251.647469)
			(xy 99.777089 -251.603929) (xy 99.808179 -251.564924) (xy 99.845195 -251.531489) (xy 99.887152 -251.504515)
			(xy 99.932936 -251.484719) (xy 99.981328 -251.472626) (xy 100.031042 -251.46856) (xy 100.080756 -251.472626)
			(xy 100.129148 -251.484719) (xy 100.174932 -251.504515) (xy 100.216889 -251.531489) (xy 100.253905 -251.564924)
			(xy 100.284995 -251.603929) (xy 100.309332 -251.647469) (xy 100.32627 -251.694385) (xy 100.335357 -251.743431)
			(xy 100.33635 -251.768356) (xy 100.33635 -251.77496) (xy 100.335823 -251.799501) (xy 100.327899 -251.84794)
			(xy 100.312328 -251.894487) (xy 100.289511 -251.937944) (xy 100.275136 -251.95784) (xy 100.275136 -251.958348)
			(xy 100.274882 -251.958602) (xy 100.270998 -251.964223) (xy 100.266105 -251.976972) (xy 100.26523 -251.983748)
			(xy 100.264468 -251.99086) (xy 100.267008 -252.00483) (xy 100.311458 -252.09373) (xy 100.313744 -252.097794)
			(xy 100.321073 -252.107804) (xy 100.34277 -252.119779) (xy 100.355146 -252.120654) (xy 100.636578 -252.120654)
			(xy 100.64496 -252.119892) (xy 100.652567 -252.118382) (xy 100.666408 -252.111403) (xy 100.672138 -252.106176)
			(xy 100.72243 -252.055884) (xy 100.728832 -252.048899) (xy 100.736408 -252.031546) (xy 100.737162 -252.022102)
			(xy 100.738432 -251.99213) (xy 100.738178 -251.984002) (xy 100.723101 -251.966667) (xy 100.697666 -251.92841)
			(xy 100.678094 -251.886846) (xy 100.664805 -251.842869) (xy 100.658084 -251.797422) (xy 100.65766 -251.774452)
			(xy 100.658147 -251.749824) (xy 100.665859 -251.701177) (xy 100.681085 -251.654334) (xy 100.703451 -251.610449)
			(xy 100.732406 -251.570604) (xy 100.767237 -251.535777) (xy 100.807087 -251.506828) (xy 100.850975 -251.484468)
			(xy 100.897819 -251.469248) (xy 100.946468 -251.461543) (xy 100.971096 -251.461016) (xy 100.994065 -251.461438)
			(xy 101.039507 -251.46818) (xy 101.083481 -251.481475) (xy 101.125046 -251.501039) (xy 101.163314 -251.526455)
			(xy 101.180646 -251.541534) (xy 101.186742 -251.541788) (xy 101.213158 -251.540772) (xy 101.218746 -251.540518)
			(xy 101.228187 -251.539752) (xy 101.245535 -251.532176) (xy 101.252528 -251.525786) (xy 101.363526 -251.414788)
			(xy 101.364542 -251.413772) (xy 101.371794 -251.405181) (xy 101.378782 -251.383839) (xy 101.378004 -251.372624)
			(xy 101.377496 -251.370084) (xy 101.377496 -251.369576) (xy 101.36632 -251.316236) (xy 101.35997 -251.285502)
			(xy 101.357828 -251.276924) (xy 101.348588 -251.261865) (xy 101.341936 -251.256038) (xy 101.33584 -251.251212)
			(xy 101.328728 -251.248418) (xy 101.304682 -251.238344) (xy 101.260159 -251.211226) (xy 101.220891 -251.176938)
			(xy 101.188018 -251.136478) (xy 101.162496 -251.091021) (xy 101.145066 -251.04189) (xy 101.136236 -250.990512)
			(xy 101.135688 -250.964446) (xy 101.136131 -250.94045) (xy 101.143632 -250.893049) (xy 101.158456 -250.847405)
			(xy 101.180239 -250.804642) (xy 101.208444 -250.765814) (xy 101.242376 -250.731876) (xy 101.2812 -250.703665)
			(xy 101.323959 -250.681875) (xy 101.3696 -250.667043) (xy 101.417 -250.659535) (xy 101.440996 -250.659138)
			(xy 101.464875 -250.659599) (xy 101.51205 -250.667034) (xy 101.557493 -250.681721) (xy 101.600096 -250.703305)
			(xy 101.638818 -250.731257) (xy 101.672717 -250.764897) (xy 101.700966 -250.803404) (xy 101.722876 -250.845839)
			(xy 101.737912 -250.891168) (xy 101.745708 -250.938285) (xy 101.746304 -250.96216) (xy 101.746304 -250.9647)
			(xy 101.745683 -250.991966) (xy 101.735979 -251.045628) (xy 101.727 -251.07138) (xy 101.725023 -251.07713)
			(xy 101.723618 -251.089204) (xy 101.724206 -251.095256) (xy 101.72573 -251.107702) (xy 101.782118 -251.188982)
			(xy 101.789653 -251.197784) (xy 101.810425 -251.207993) (xy 101.821996 -251.20854) (xy 102.940104 -251.20854)
			(xy 102.952435 -251.207955) (xy 102.974283 -251.196517) (xy 102.98176 -251.186696) (xy 103.029258 -251.117862)
			(xy 103.032618 -251.112744) (xy 103.036991 -251.101311) (xy 103.037894 -251.095256) (xy 103.039418 -251.083064)
			(xy 103.0351 -251.07138) (xy 103.026261 -251.046182) (xy 103.016545 -250.993678) (xy 103.015796 -250.966986)
			(xy 103.015796 -250.96216) (xy 103.016496 -250.937029) (xy 103.025102 -250.887499) (xy 103.041706 -250.840048)
			(xy 103.065859 -250.795959) (xy 103.096909 -250.756421) (xy 103.134015 -250.722505) (xy 103.176177 -250.695125)
			(xy 103.222254 -250.675021) (xy 103.271002 -250.662738) (xy 103.321104 -250.658606) (xy 103.371206 -250.662738)
			(xy 103.419954 -250.675021) (xy 103.466031 -250.695125) (xy 103.508193 -250.722505) (xy 103.545299 -250.756421)
			(xy 103.576349 -250.795959) (xy 103.600502 -250.840048) (xy 103.617106 -250.887499) (xy 103.625712 -250.937029)
			(xy 103.626412 -250.96216) (xy 103.626412 -250.9647) (xy 103.625791 -250.991966) (xy 103.616088 -251.045628)
			(xy 103.607108 -251.07138) (xy 103.605131 -251.07713) (xy 103.603726 -251.089204) (xy 103.604314 -251.095256)
			(xy 103.605838 -251.107702) (xy 103.662226 -251.188982) (xy 103.669761 -251.197783) (xy 103.690533 -251.207988)
			(xy 103.702104 -251.20854) (xy 104.819958 -251.20854) (xy 104.832283 -251.207943) (xy 104.854111 -251.196492)
			(xy 104.861614 -251.186696) (xy 104.909112 -251.117862) (xy 104.912474 -251.112745) (xy 104.916852 -251.101313)
			(xy 104.917748 -251.095256) (xy 104.919272 -251.083064) (xy 104.914954 -251.07138) (xy 104.906116 -251.046182)
			(xy 104.896402 -250.993678) (xy 104.89565 -250.966986) (xy 104.89565 -250.96216) (xy 104.89635 -250.937029)
			(xy 104.904956 -250.887499) (xy 104.92156 -250.840048) (xy 104.945713 -250.795959) (xy 104.976763 -250.756421)
			(xy 105.013869 -250.722505) (xy 105.056031 -250.695125) (xy 105.102108 -250.675021) (xy 105.150856 -250.662738)
			(xy 105.200958 -250.658606) (xy 105.25106 -250.662738) (xy 105.299808 -250.675021) (xy 105.345885 -250.695125)
			(xy 105.388047 -250.722505) (xy 105.425153 -250.756421) (xy 105.456203 -250.795959) (xy 105.480356 -250.840048)
			(xy 105.49696 -250.887499) (xy 105.505566 -250.937029) (xy 105.506266 -250.96216) (xy 105.506266 -250.9647)
			(xy 105.505645 -250.991966) (xy 105.495944 -251.045629) (xy 105.486962 -251.07138) (xy 105.484983 -251.07713)
			(xy 105.483577 -251.089204) (xy 105.484168 -251.095256) (xy 105.485692 -251.107702) (xy 105.54208 -251.188982)
			(xy 105.549619 -251.197773) (xy 105.570391 -251.207957) (xy 105.581958 -251.20854) (xy 106.700066 -251.20854)
			(xy 106.71239 -251.207942) (xy 106.734215 -251.196489) (xy 106.741722 -251.186696) (xy 106.78922 -251.117862)
			(xy 106.792582 -251.112744) (xy 106.796959 -251.101312) (xy 106.797856 -251.095256) (xy 106.79938 -251.083064)
			(xy 106.795062 -251.07138) (xy 106.786224 -251.046182) (xy 106.776509 -250.993678) (xy 106.775758 -250.966986)
			(xy 106.775758 -250.96216) (xy 106.776458 -250.937029) (xy 106.785064 -250.887499) (xy 106.801668 -250.840048)
			(xy 106.825821 -250.795959) (xy 106.856871 -250.756421) (xy 106.893977 -250.722505) (xy 106.936139 -250.695125)
			(xy 106.982216 -250.675021) (xy 107.030964 -250.662738) (xy 107.081066 -250.658606) (xy 107.131168 -250.662738)
			(xy 107.179916 -250.675021) (xy 107.225993 -250.695125) (xy 107.268155 -250.722505) (xy 107.305261 -250.756421)
			(xy 107.336311 -250.795959) (xy 107.360464 -250.840048) (xy 107.377068 -250.887499) (xy 107.385674 -250.937029)
			(xy 107.386374 -250.96216) (xy 107.386374 -250.9647) (xy 107.385753 -250.991966) (xy 107.376052 -251.045629)
			(xy 107.36707 -251.07138) (xy 107.365091 -251.077129) (xy 107.363684 -251.089204) (xy 107.364276 -251.095256)
			(xy 107.3658 -251.107702) (xy 107.422188 -251.188982) (xy 107.429727 -251.197772) (xy 107.4505 -251.207953)
			(xy 107.462066 -251.20854) (xy 108.580174 -251.20854) (xy 108.592497 -251.20794) (xy 108.614319 -251.196485)
			(xy 108.62183 -251.186696) (xy 108.669328 -251.117862) (xy 108.67269 -251.112744) (xy 108.677065 -251.101312)
			(xy 108.677964 -251.095256) (xy 108.679488 -251.083064) (xy 108.67517 -251.07138) (xy 108.666332 -251.046182)
			(xy 108.656617 -250.993678) (xy 108.655866 -250.966986) (xy 108.655866 -250.96216) (xy 108.656566 -250.937029)
			(xy 108.665172 -250.887499) (xy 108.681776 -250.840048) (xy 108.705929 -250.795959) (xy 108.736979 -250.756421)
			(xy 108.774085 -250.722505) (xy 108.816247 -250.695125) (xy 108.862324 -250.675021) (xy 108.911072 -250.662738)
			(xy 108.961174 -250.658606) (xy 109.011276 -250.662738) (xy 109.060024 -250.675021) (xy 109.106101 -250.695125)
			(xy 109.148263 -250.722505) (xy 109.185369 -250.756421) (xy 109.216419 -250.795959) (xy 109.240572 -250.840048)
			(xy 109.257176 -250.887499) (xy 109.265782 -250.937029) (xy 109.266482 -250.96216) (xy 109.266482 -250.9647)
			(xy 109.265861 -250.991966) (xy 109.25616 -251.045629) (xy 109.247178 -251.07138) (xy 109.245199 -251.077129)
			(xy 109.243792 -251.089204) (xy 109.244384 -251.095256) (xy 109.245908 -251.107702) (xy 109.302296 -251.188982)
			(xy 109.309836 -251.197771) (xy 109.330608 -251.207948) (xy 109.342174 -251.20854) (xy 109.519974 -251.20854)
			(xy 109.532297 -251.20794) (xy 109.554119 -251.196485) (xy 109.56163 -251.186696) (xy 109.609128 -251.117862)
			(xy 109.61249 -251.112744) (xy 109.616865 -251.101312) (xy 109.617764 -251.095256) (xy 109.619288 -251.083064)
			(xy 109.61497 -251.07138) (xy 109.606132 -251.046182) (xy 109.596417 -250.993678) (xy 109.595666 -250.966986)
			(xy 109.595666 -250.96216) (xy 109.596366 -250.937029) (xy 109.604972 -250.887499) (xy 109.621576 -250.840048)
			(xy 109.645729 -250.795959) (xy 109.676779 -250.756421) (xy 109.713885 -250.722505) (xy 109.756047 -250.695125)
			(xy 109.802124 -250.675021) (xy 109.850872 -250.662738) (xy 109.900974 -250.658606) (xy 109.951076 -250.662738)
			(xy 109.999824 -250.675021) (xy 110.045901 -250.695125) (xy 110.088063 -250.722505) (xy 110.125169 -250.756421)
			(xy 110.156219 -250.795959) (xy 110.180372 -250.840048) (xy 110.196976 -250.887499) (xy 110.205582 -250.937029)
			(xy 110.206282 -250.96216) (xy 110.206282 -250.9647) (xy 110.205661 -250.991966) (xy 110.19596 -251.045629)
			(xy 110.186978 -251.07138) (xy 110.184999 -251.077129) (xy 110.183592 -251.089204) (xy 110.184184 -251.095256)
			(xy 110.185708 -251.107702) (xy 110.242096 -251.188982) (xy 110.249636 -251.197771) (xy 110.270408 -251.207948)
			(xy 110.281974 -251.20854) (xy 111.040418 -251.20854) (xy 111.045729 -251.208349) (xy 111.056101 -251.206046)
			(xy 111.060992 -251.203968) (xy 111.0869 -251.191522) (xy 111.09452 -251.185426) (xy 111.09833 -251.180854)
			(xy 111.116257 -251.160154) (xy 111.157526 -251.124165) (xy 111.203984 -251.095181) (xy 111.254452 -251.073937)
			(xy 111.307652 -251.060971) (xy 111.362236 -251.056612) (xy 111.41682 -251.060971) (xy 111.47002 -251.073937)
			(xy 111.520488 -251.095181) (xy 111.566946 -251.124165) (xy 111.608215 -251.160154) (xy 111.626142 -251.180854)
			(xy 111.629952 -251.185426) (xy 111.637572 -251.191522) (xy 111.66348 -251.203968) (xy 111.668372 -251.206043)
			(xy 111.678744 -251.208341) (xy 111.684054 -251.20854) (xy 111.954818 -251.20854) (xy 111.960129 -251.208349)
			(xy 111.970501 -251.206046) (xy 111.975392 -251.203968) (xy 112.0013 -251.191522) (xy 112.00892 -251.185426)
			(xy 112.01273 -251.180854) (xy 112.030657 -251.160154) (xy 112.071926 -251.124165) (xy 112.118384 -251.095181)
			(xy 112.168852 -251.073937) (xy 112.222052 -251.060971) (xy 112.276636 -251.056612) (xy 112.33122 -251.060971)
			(xy 112.38442 -251.073937) (xy 112.434888 -251.095181) (xy 112.481346 -251.124165) (xy 112.522615 -251.160154)
			(xy 112.540542 -251.180854) (xy 112.544352 -251.185426) (xy 112.551972 -251.191522) (xy 112.57788 -251.203968)
			(xy 112.582772 -251.206043) (xy 112.593144 -251.208341) (xy 112.598454 -251.20854) (xy 113.27384 -251.20854)
			(xy 113.286167 -251.207947) (xy 113.308001 -251.196501) (xy 113.315496 -251.186696) (xy 113.362994 -251.117862)
			(xy 113.366358 -251.112745) (xy 113.370736 -251.101313) (xy 113.37163 -251.095256) (xy 113.373154 -251.083064)
			(xy 113.368836 -251.07138) (xy 113.359996 -251.046182) (xy 113.350279 -250.993679) (xy 113.349532 -250.966986)
			(xy 113.349532 -250.96216) (xy 113.350232 -250.937029) (xy 113.358838 -250.887499) (xy 113.375442 -250.840048)
			(xy 113.399595 -250.795959) (xy 113.430645 -250.756421) (xy 113.467751 -250.722505) (xy 113.509913 -250.695125)
			(xy 113.55599 -250.675021) (xy 113.604738 -250.662738) (xy 113.65484 -250.658606) (xy 113.704942 -250.662738)
			(xy 113.75369 -250.675021) (xy 113.799767 -250.695125) (xy 113.841929 -250.722505) (xy 113.879035 -250.756421)
			(xy 113.910085 -250.795959) (xy 113.934238 -250.840048) (xy 113.950842 -250.887499) (xy 113.959448 -250.937029)
			(xy 113.960148 -250.96216) (xy 113.960148 -250.9647) (xy 113.959527 -250.991966) (xy 113.949825 -251.045629)
			(xy 113.940844 -251.07138) (xy 113.938866 -251.07713) (xy 113.93746 -251.089204) (xy 113.93805 -251.095256)
			(xy 113.939574 -251.107702) (xy 113.995962 -251.188982) (xy 114.003499 -251.197777) (xy 114.024272 -251.207968)
			(xy 114.03584 -251.20854) (xy 114.21364 -251.20854) (xy 114.225967 -251.207947) (xy 114.247801 -251.196501)
			(xy 114.255296 -251.186696) (xy 114.302794 -251.117862) (xy 114.306158 -251.112745) (xy 114.310536 -251.101313)
			(xy 114.31143 -251.095256) (xy 114.312954 -251.083064) (xy 114.308636 -251.07138) (xy 114.299796 -251.046182)
			(xy 114.290079 -250.993679) (xy 114.289332 -250.966986) (xy 114.289332 -250.96216) (xy 114.290032 -250.937029)
			(xy 114.298638 -250.887499) (xy 114.315242 -250.840048) (xy 114.339395 -250.795959) (xy 114.370445 -250.756421)
			(xy 114.407551 -250.722505) (xy 114.449713 -250.695125) (xy 114.49579 -250.675021) (xy 114.544538 -250.662738)
			(xy 114.59464 -250.658606) (xy 114.644742 -250.662738) (xy 114.69349 -250.675021) (xy 114.739567 -250.695125)
			(xy 114.781729 -250.722505) (xy 114.818835 -250.756421) (xy 114.849885 -250.795959) (xy 114.874038 -250.840048)
			(xy 114.890642 -250.887499) (xy 114.899248 -250.937029) (xy 114.899948 -250.96216) (xy 114.899948 -250.9647)
			(xy 114.899327 -250.991966) (xy 114.889625 -251.045629) (xy 114.880644 -251.07138) (xy 114.878666 -251.07713)
			(xy 114.87726 -251.089204) (xy 114.87785 -251.095256) (xy 114.879374 -251.107702) (xy 114.935762 -251.188982)
			(xy 114.943299 -251.197777) (xy 114.964072 -251.207968) (xy 114.97564 -251.20854) (xy 115.153694 -251.20854)
			(xy 115.166027 -251.207957) (xy 115.187878 -251.196522) (xy 115.19535 -251.186696) (xy 115.242848 -251.117862)
			(xy 115.246208 -251.112744) (xy 115.250582 -251.101312) (xy 115.251484 -251.095256) (xy 115.253008 -251.083064)
			(xy 115.24869 -251.07138) (xy 115.239851 -251.046182) (xy 115.230136 -250.993678) (xy 115.229386 -250.966986)
			(xy 115.229386 -250.96216) (xy 115.230086 -250.937029) (xy 115.238692 -250.887499) (xy 115.255296 -250.840048)
			(xy 115.279449 -250.795959) (xy 115.310499 -250.756421) (xy 115.347605 -250.722505) (xy 115.389767 -250.695125)
			(xy 115.435844 -250.675021) (xy 115.484592 -250.662738) (xy 115.534694 -250.658606) (xy 115.584796 -250.662738)
			(xy 115.633544 -250.675021) (xy 115.679621 -250.695125) (xy 115.721783 -250.722505) (xy 115.758889 -250.756421)
			(xy 115.789939 -250.795959) (xy 115.814092 -250.840048) (xy 115.830696 -250.887499) (xy 115.839302 -250.937029)
			(xy 115.840002 -250.96216) (xy 115.840002 -250.9647) (xy 115.839381 -250.991966) (xy 115.829677 -251.045628)
			(xy 115.820698 -251.07138) (xy 115.818721 -251.07713) (xy 115.817316 -251.089204) (xy 115.817904 -251.095256)
			(xy 115.819428 -251.107702) (xy 115.875816 -251.188982) (xy 115.88335 -251.197784) (xy 115.904122 -251.207994)
			(xy 115.915694 -251.20854) (xy 117.033802 -251.20854) (xy 117.046134 -251.207955) (xy 117.067982 -251.196518)
			(xy 117.075458 -251.186696) (xy 117.122956 -251.117862) (xy 117.126316 -251.112744) (xy 117.130689 -251.101311)
			(xy 117.131592 -251.095256) (xy 117.133116 -251.083064) (xy 117.128798 -251.07138) (xy 117.119959 -251.046182)
			(xy 117.110243 -250.993678) (xy 117.109494 -250.966986) (xy 117.109494 -250.96216) (xy 117.110194 -250.937029)
			(xy 117.1188 -250.887499) (xy 117.135404 -250.840048) (xy 117.159557 -250.795959) (xy 117.190607 -250.756421)
			(xy 117.227713 -250.722505) (xy 117.269875 -250.695125) (xy 117.315952 -250.675021) (xy 117.3647 -250.662738)
			(xy 117.414802 -250.658606) (xy 117.464904 -250.662738) (xy 117.513652 -250.675021) (xy 117.559729 -250.695125)
			(xy 117.601891 -250.722505) (xy 117.638997 -250.756421) (xy 117.670047 -250.795959) (xy 117.6942 -250.840048)
			(xy 117.710804 -250.887499) (xy 117.71941 -250.937029) (xy 117.72011 -250.96216) (xy 117.72011 -250.9647)
			(xy 117.719489 -250.991966) (xy 117.709786 -251.045628) (xy 117.700806 -251.07138) (xy 117.698829 -251.07713)
			(xy 117.697424 -251.089204) (xy 117.698012 -251.095256) (xy 117.699536 -251.107702) (xy 117.755924 -251.188982)
			(xy 117.763459 -251.197783) (xy 117.784231 -251.207989) (xy 117.795802 -251.20854) (xy 117.973856 -251.20854)
			(xy 117.986181 -251.207944) (xy 118.00801 -251.196493) (xy 118.015512 -251.186696) (xy 118.06301 -251.117862)
			(xy 118.066373 -251.112745) (xy 118.07075 -251.101313) (xy 118.071646 -251.095256) (xy 118.07317 -251.083064)
			(xy 118.068852 -251.07138) (xy 118.060014 -251.046182) (xy 118.0503 -250.993678) (xy 118.049548 -250.966986)
			(xy 118.049548 -250.96216) (xy 118.050248 -250.937029) (xy 118.058854 -250.887499) (xy 118.075458 -250.840048)
			(xy 118.099611 -250.795959) (xy 118.130661 -250.756421) (xy 118.167767 -250.722505) (xy 118.209929 -250.695125)
			(xy 118.256006 -250.675021) (xy 118.304754 -250.662738) (xy 118.354856 -250.658606) (xy 118.404958 -250.662738)
			(xy 118.453706 -250.675021) (xy 118.499783 -250.695125) (xy 118.541945 -250.722505) (xy 118.579051 -250.756421)
			(xy 118.610101 -250.795959) (xy 118.634254 -250.840048) (xy 118.650858 -250.887499) (xy 118.659464 -250.937029)
			(xy 118.660164 -250.96216) (xy 118.660164 -250.9647) (xy 118.659543 -250.991966) (xy 118.649841 -251.045629)
			(xy 118.64086 -251.07138) (xy 118.638881 -251.07713) (xy 118.637475 -251.089204) (xy 118.638066 -251.095256)
			(xy 118.63959 -251.107702) (xy 118.695978 -251.188982) (xy 118.703517 -251.197774) (xy 118.724289 -251.207958)
			(xy 118.735856 -251.20854) (xy 118.913656 -251.20854) (xy 118.925981 -251.207944) (xy 118.94781 -251.196493)
			(xy 118.955312 -251.186696) (xy 119.00281 -251.117862) (xy 119.006173 -251.112745) (xy 119.01055 -251.101313)
			(xy 119.011446 -251.095256) (xy 119.01297 -251.083064) (xy 119.008652 -251.07138) (xy 118.999814 -251.046182)
			(xy 118.9901 -250.993678) (xy 118.989348 -250.966986) (xy 118.989348 -250.96216) (xy 118.990048 -250.937029)
			(xy 118.998654 -250.887499) (xy 119.015258 -250.840048) (xy 119.039411 -250.795959) (xy 119.070461 -250.756421)
			(xy 119.107567 -250.722505) (xy 119.149729 -250.695125) (xy 119.195806 -250.675021) (xy 119.244554 -250.662738)
			(xy 119.294656 -250.658606) (xy 119.344758 -250.662738) (xy 119.393506 -250.675021) (xy 119.439583 -250.695125)
			(xy 119.481745 -250.722505) (xy 119.518851 -250.756421) (xy 119.549901 -250.795959) (xy 119.574054 -250.840048)
			(xy 119.590658 -250.887499) (xy 119.599264 -250.937029) (xy 119.599964 -250.96216) (xy 119.599964 -250.9647)
			(xy 119.599343 -250.991966) (xy 119.589641 -251.045629) (xy 119.58066 -251.07138) (xy 119.578681 -251.07713)
			(xy 119.577275 -251.089204) (xy 119.577866 -251.095256) (xy 119.57939 -251.107702) (xy 119.635778 -251.188982)
			(xy 119.643317 -251.197774) (xy 119.664089 -251.207958) (xy 119.675656 -251.20854) (xy 120.793764 -251.20854)
			(xy 120.806088 -251.207942) (xy 120.827914 -251.19649) (xy 120.83542 -251.186696) (xy 120.882918 -251.117862)
			(xy 120.88628 -251.112745) (xy 120.890657 -251.101313) (xy 120.891554 -251.095256) (xy 120.893078 -251.083064)
			(xy 120.88876 -251.07138) (xy 120.879922 -251.046182) (xy 120.870207 -250.993678) (xy 120.869456 -250.966986)
			(xy 120.869456 -250.96216) (xy 120.870156 -250.937029) (xy 120.878762 -250.887499) (xy 120.895366 -250.840048)
			(xy 120.919519 -250.795959) (xy 120.950569 -250.756421) (xy 120.987675 -250.722505) (xy 121.029837 -250.695125)
			(xy 121.075914 -250.675021) (xy 121.124662 -250.662738) (xy 121.174764 -250.658606) (xy 121.224866 -250.662738)
			(xy 121.273614 -250.675021) (xy 121.319691 -250.695125) (xy 121.361853 -250.722505) (xy 121.398959 -250.756421)
			(xy 121.430009 -250.795959) (xy 121.454162 -250.840048) (xy 121.470766 -250.887499) (xy 121.479372 -250.937029)
			(xy 121.480072 -250.96216) (xy 121.480072 -250.9647) (xy 121.479451 -250.991966) (xy 121.46975 -251.045629)
			(xy 121.460768 -251.07138) (xy 121.458789 -251.077129) (xy 121.457382 -251.089204) (xy 121.457974 -251.095256)
			(xy 121.459498 -251.107702) (xy 121.515886 -251.188982) (xy 121.523425 -251.197772) (xy 121.544198 -251.207954)
			(xy 121.555764 -251.20854) (xy 121.733818 -251.20854) (xy 121.746148 -251.207952) (xy 121.76799 -251.196511)
			(xy 121.775474 -251.186696) (xy 121.822972 -251.117862) (xy 121.826331 -251.112743) (xy 121.830703 -251.101311)
			(xy 121.831608 -251.095256) (xy 121.833132 -251.083064) (xy 121.828814 -251.07138) (xy 121.819975 -251.046182)
			(xy 121.810258 -250.993679) (xy 121.80951 -250.966986) (xy 121.80951 -250.96216) (xy 121.81021 -250.937029)
			(xy 121.818816 -250.887499) (xy 121.83542 -250.840048) (xy 121.859573 -250.795959) (xy 121.890623 -250.756421)
			(xy 121.927729 -250.722505) (xy 121.969891 -250.695125) (xy 122.015968 -250.675021) (xy 122.064716 -250.662738)
			(xy 122.114818 -250.658606) (xy 122.16492 -250.662738) (xy 122.213668 -250.675021) (xy 122.259745 -250.695125)
			(xy 122.301907 -250.722505) (xy 122.339013 -250.756421) (xy 122.370063 -250.795959) (xy 122.394216 -250.840048)
			(xy 122.41082 -250.887499) (xy 122.419426 -250.937029) (xy 122.420126 -250.96216) (xy 122.420126 -250.9647)
			(xy 122.419505 -250.991966) (xy 122.409802 -251.045628) (xy 122.400822 -251.07138) (xy 122.398844 -251.07713)
			(xy 122.397439 -251.089204) (xy 122.398028 -251.095256) (xy 122.399552 -251.107702) (xy 122.45594 -251.188982)
			(xy 122.463476 -251.19778) (xy 122.484248 -251.20798) (xy 122.495818 -251.20854) (xy 122.673618 -251.20854)
			(xy 122.685948 -251.207952) (xy 122.70779 -251.196511) (xy 122.715274 -251.186696) (xy 122.762772 -251.117862)
			(xy 122.766131 -251.112743) (xy 122.770503 -251.101311) (xy 122.771408 -251.095256) (xy 122.772932 -251.083064)
			(xy 122.768614 -251.07138) (xy 122.759775 -251.046182) (xy 122.750058 -250.993679) (xy 122.74931 -250.966986)
			(xy 122.74931 -250.96216) (xy 122.75001 -250.937029) (xy 122.758616 -250.887499) (xy 122.77522 -250.840048)
			(xy 122.799373 -250.795959) (xy 122.830423 -250.756421) (xy 122.867529 -250.722505) (xy 122.909691 -250.695125)
			(xy 122.955768 -250.675021) (xy 123.004516 -250.662738) (xy 123.054618 -250.658606) (xy 123.10472 -250.662738)
			(xy 123.153468 -250.675021) (xy 123.199545 -250.695125) (xy 123.241707 -250.722505) (xy 123.278813 -250.756421)
			(xy 123.309863 -250.795959) (xy 123.334016 -250.840048) (xy 123.35062 -250.887499) (xy 123.359226 -250.937029)
			(xy 123.359926 -250.96216) (xy 123.359926 -250.9647) (xy 123.359305 -250.991966) (xy 123.349602 -251.045628)
			(xy 123.340622 -251.07138) (xy 123.338644 -251.07713) (xy 123.337239 -251.089204) (xy 123.337828 -251.095256)
			(xy 123.339352 -251.107702) (xy 123.39574 -251.188982) (xy 123.403276 -251.19778) (xy 123.424048 -251.20798)
			(xy 123.435618 -251.20854) (xy 124.553726 -251.20854) (xy 124.566055 -251.20795) (xy 124.587894 -251.196507)
			(xy 124.595382 -251.186696) (xy 124.64288 -251.117862) (xy 124.646238 -251.112743) (xy 124.65061 -251.101311)
			(xy 124.651516 -251.095256) (xy 124.65304 -251.083064) (xy 124.648722 -251.07138) (xy 124.639882 -251.046182)
			(xy 124.630166 -250.993679) (xy 124.629418 -250.966986) (xy 124.629418 -250.96216) (xy 124.630118 -250.937029)
			(xy 124.638724 -250.887499) (xy 124.655328 -250.840048) (xy 124.679481 -250.795959) (xy 124.710531 -250.756421)
			(xy 124.747637 -250.722505) (xy 124.789799 -250.695125) (xy 124.835876 -250.675021) (xy 124.884624 -250.662738)
			(xy 124.934726 -250.658606) (xy 124.984828 -250.662738) (xy 125.033576 -250.675021) (xy 125.079653 -250.695125)
			(xy 125.121815 -250.722505) (xy 125.158921 -250.756421) (xy 125.189971 -250.795959) (xy 125.214124 -250.840048)
			(xy 125.230728 -250.887499) (xy 125.239334 -250.937029) (xy 125.240034 -250.96216) (xy 125.240034 -250.9647)
			(xy 125.239413 -250.991966) (xy 125.22971 -251.045628) (xy 125.22073 -251.07138) (xy 125.218752 -251.07713)
			(xy 125.217347 -251.089204) (xy 125.217936 -251.095256) (xy 125.21946 -251.107702) (xy 125.275848 -251.188982)
			(xy 125.283385 -251.197779) (xy 125.304157 -251.207975) (xy 125.315726 -251.20854) (xy 125.49378 -251.20854)
			(xy 125.506114 -251.20796) (xy 125.52797 -251.196528) (xy 125.535436 -251.186696) (xy 125.582934 -251.117862)
			(xy 125.586295 -251.112744) (xy 125.59067 -251.101312) (xy 125.59157 -251.095256) (xy 125.593094 -251.083064)
			(xy 125.588776 -251.07138) (xy 125.579938 -251.046182) (xy 125.570222 -250.993678) (xy 125.569472 -250.966986)
			(xy 125.569472 -250.96216) (xy 125.570109 -250.938283) (xy 125.577892 -250.891161) (xy 125.592916 -250.845824)
			(xy 125.614817 -250.80338) (xy 125.643059 -250.764864) (xy 125.676954 -250.731214) (xy 125.715675 -250.703253)
			(xy 125.758277 -250.681662) (xy 125.803721 -250.666967) (xy 125.850899 -250.659527) (xy 125.87478 -250.659138)
			(xy 125.898773 -250.659583) (xy 125.946168 -250.667087) (xy 125.991805 -250.681915) (xy 126.034561 -250.7037)
			(xy 126.073382 -250.731906) (xy 126.107311 -250.765838) (xy 126.135514 -250.804661) (xy 126.157295 -250.847419)
			(xy 126.172119 -250.893057) (xy 126.179619 -250.940453) (xy 126.180088 -250.964446) (xy 126.180088 -250.97105)
			(xy 126.180342 -250.971812) (xy 126.18149 -250.981023) (xy 126.189482 -250.997758) (xy 126.202933 -251.010525)
			(xy 126.21133 -251.014484) (xy 126.297944 -251.050806) (xy 126.307388 -251.054346) (xy 126.32754 -251.054441)
			(xy 126.346156 -251.046723) (xy 126.35357 -251.039884) (xy 126.524766 -250.868688) (xy 126.528576 -250.858274)
			(xy 126.53823 -250.833815) (xy 126.564683 -250.788376) (xy 126.598527 -250.748138) (xy 126.638763 -250.714292)
			(xy 126.684201 -250.687837) (xy 126.708662 -250.678188) (xy 126.719076 -250.674378) (xy 126.800356 -250.593098)
			(xy 126.805562 -250.587352) (xy 126.812555 -250.573523) (xy 126.814072 -250.56592) (xy 126.814834 -250.557538)
			(xy 126.814834 -249.696986) (xy 126.814452 -249.687884) (xy 126.808063 -249.670839) (xy 126.802388 -249.663712)
			(xy 126.796546 -249.656854) (xy 126.780544 -249.647964) (xy 126.7714 -249.646694) (xy 126.747467 -249.642788)
			(xy 126.701161 -249.628399) (xy 126.657711 -249.606873) (xy 126.618208 -249.578752) (xy 126.583645 -249.544741)
			(xy 126.554891 -249.505697) (xy 126.532669 -249.462599) (xy 126.517535 -249.416531) (xy 126.509872 -249.36865)
			(xy 126.509871 -249.32016) (xy 126.517533 -249.272279) (xy 126.532665 -249.22621) (xy 126.554886 -249.183112)
			(xy 126.583639 -249.144066) (xy 126.618201 -249.110055) (xy 126.657703 -249.081932) (xy 126.701152 -249.060405)
			(xy 126.747458 -249.046014) (xy 126.7714 -249.042174) (xy 126.771654 -249.042174) (xy 126.780505 -249.040483)
			(xy 126.796261 -249.031764) (xy 126.802388 -249.025156) (xy 126.808484 -249.018298) (xy 126.814834 -249.00128)
			(xy 126.814834 -248.685558) (xy 126.81448 -248.67687) (xy 126.808623 -248.66051) (xy 126.803404 -248.653554)
			(xy 126.800102 -248.649744) (xy 126.455678 -248.30532) (xy 126.454408 -248.30405) (xy 126.451047 -248.301085)
			(xy 126.443508 -248.296241) (xy 126.439422 -248.294398) (xy 126.43021 -248.291028) (xy 126.410614 -248.290753)
			(xy 126.401322 -248.29389) (xy 126.383796 -248.300748) (xy 126.376938 -248.30659) (xy 126.347016 -248.331757)
			(xy 126.282928 -248.37655) (xy 126.214627 -248.414611) (xy 126.142816 -248.445546) (xy 126.068237 -248.469035)
			(xy 125.99166 -248.484837) (xy 125.913875 -248.492788) (xy 125.87478 -248.49328) (xy 125.576838 -248.49328)
			(xy 125.536786 -248.492723) (xy 125.457122 -248.484321) (xy 125.417834 -248.476516) (xy 125.415294 -248.476008)
			(xy 125.404626 -248.474992) (xy 125.394212 -248.476008) (xy 125.391672 -248.476516) (xy 125.352386 -248.484333)
			(xy 125.272721 -248.492728) (xy 125.232668 -248.49328) (xy 124.934726 -248.49328) (xy 124.907802 -248.492772)
			(xy 124.875544 -248.49074) (xy 124.870793 -248.490468) (xy 124.861333 -248.491496) (xy 124.856748 -248.492772)
			(xy 124.847604 -248.495566) (xy 124.785628 -248.545096) (xy 124.781899 -248.548211) (xy 124.775632 -248.555633)
			(xy 124.773182 -248.559828) (xy 124.76861 -248.567956) (xy 124.767086 -248.577608) (xy 124.767086 -248.577862)
			(xy 124.763182 -248.601792) (xy 124.748796 -248.648092) (xy 124.727273 -248.691536) (xy 124.699154 -248.731032)
			(xy 124.665146 -248.765588) (xy 124.626103 -248.794334) (xy 124.583008 -248.816547) (xy 124.536944 -248.83167)
			(xy 124.489068 -248.839321) (xy 124.464826 -248.839736) (xy 124.440833 -248.839267) (xy 124.393436 -248.831765)
			(xy 124.347797 -248.81694) (xy 124.305039 -248.795158) (xy 124.266214 -248.766956) (xy 124.232279 -248.733027)
			(xy 124.20407 -248.694208) (xy 124.182281 -248.651453) (xy 124.167448 -248.605816) (xy 124.159937 -248.558421)
			(xy 124.159518 -248.534428) (xy 124.159938 -248.511465) (xy 124.166828 -248.46606) (xy 124.180441 -248.422198)
			(xy 124.200471 -248.380871) (xy 124.226466 -248.34301) (xy 124.257838 -248.309471) (xy 124.275596 -248.294906)
			(xy 124.277374 -248.293382) (xy 124.291344 -248.269506) (xy 124.293619 -248.265405) (xy 124.296807 -248.256586)
			(xy 124.297694 -248.25198) (xy 124.307092 -248.193052) (xy 124.308141 -248.184313) (xy 124.304899 -248.167027)
			(xy 124.300742 -248.15927) (xy 124.29871 -248.156222) (xy 124.288895 -248.141487) (xy 124.270472 -248.11125)
			(xy 124.26188 -248.09577) (xy 124.261372 -248.095262) (xy 124.253752 -248.081546) (xy 124.253752 -248.081038)
			(xy 124.241306 -248.056654) (xy 124.236988 -248.04751) (xy 124.230384 -248.041414) (xy 124.226767 -248.038219)
			(xy 124.218587 -248.0331) (xy 124.214128 -248.031254) (xy 124.14885 -248.006108) (xy 124.1425 -248.004076)
			(xy 124.135339 -248.002664) (xy 124.120772 -248.003445) (xy 124.113798 -248.0056) (xy 124.111258 -248.006616)
			(xy 124.088955 -248.015319) (xy 124.042398 -248.02646) (xy 123.994672 -248.030204) (xy 123.946946 -248.02646)
			(xy 123.900389 -248.015319) (xy 123.878086 -248.006616) (xy 123.875546 -248.0056) (xy 123.868585 -248.003375)
			(xy 123.853999 -248.002592) (xy 123.846844 -248.004076) (xy 123.840494 -248.006108) (xy 123.775216 -248.031254)
			(xy 123.770748 -248.033083) (xy 123.762559 -248.038196) (xy 123.75896 -248.041414) (xy 123.752102 -248.047764)
			(xy 123.749816 -248.05259) (xy 123.747784 -248.056908) (xy 123.730365 -248.092112) (xy 123.689369 -248.159114)
			(xy 123.641752 -248.221584) (xy 123.58801 -248.27887) (xy 123.528704 -248.330376) (xy 123.464453 -248.375562)
			(xy 123.395928 -248.413958) (xy 123.323843 -248.445163) (xy 123.248951 -248.468851) (xy 123.172034 -248.484776)
			(xy 123.093893 -248.49277) (xy 123.054618 -248.49328) (xy 122.756676 -248.49328) (xy 122.716624 -248.492724)
			(xy 122.636959 -248.484327) (xy 122.597672 -248.476516) (xy 122.595132 -248.476008) (xy 122.584464 -248.474992)
			(xy 122.57405 -248.476008) (xy 122.57151 -248.476516) (xy 122.532224 -248.484335) (xy 122.452559 -248.492734)
			(xy 122.412506 -248.49328) (xy 122.114818 -248.49328) (xy 122.068844 -248.491756) (xy 122.055382 -248.49074)
			(xy 122.05063 -248.490464) (xy 122.041169 -248.491486) (xy 122.036586 -248.492772) (xy 122.027442 -248.495566)
			(xy 121.965212 -248.54535) (xy 121.96161 -248.548318) (xy 121.955473 -248.555349) (xy 121.95302 -248.55932)
			(xy 121.948194 -248.567702) (xy 121.946924 -248.577608) (xy 121.943037 -248.601553) (xy 121.928679 -248.647887)
			(xy 121.907175 -248.691368) (xy 121.879066 -248.730902) (xy 121.845059 -248.765492) (xy 121.806009 -248.79427)
			(xy 121.7629 -248.81651) (xy 121.716816 -248.831654) (xy 121.668918 -248.839319) (xy 121.644664 -248.839736)
			(xy 121.620674 -248.839263) (xy 121.573285 -248.831752) (xy 121.527654 -248.816922) (xy 121.484904 -248.795137)
			(xy 121.446088 -248.766934) (xy 121.412161 -248.733006) (xy 121.383959 -248.694189) (xy 121.362175 -248.651439)
			(xy 121.347346 -248.605807) (xy 121.339837 -248.558418) (xy 121.339356 -248.534428) (xy 121.339356 -248.523506)
			(xy 121.340857 -248.496838) (xy 121.352008 -248.444607) (xy 121.372067 -248.395107) (xy 121.400422 -248.349847)
			(xy 121.436211 -248.310204) (xy 121.456958 -248.293382) (xy 121.465086 -248.287032) (xy 121.469658 -248.279412)
			(xy 121.47199 -248.275201) (xy 121.475177 -248.26612) (xy 121.476008 -248.261378) (xy 121.478802 -248.243344)
			(xy 121.48693 -248.19229) (xy 121.487587 -248.187538) (xy 121.487335 -248.177949) (xy 121.486422 -248.17324)
			(xy 121.48439 -248.164604) (xy 121.478802 -248.156222) (xy 121.462899 -248.132358) (xy 121.434296 -248.082648)
			(xy 121.421652 -248.056908) (xy 121.417588 -248.048018) (xy 121.410476 -248.041414) (xy 121.406858 -248.03822)
			(xy 121.398678 -248.033101) (xy 121.39422 -248.031254) (xy 121.328942 -248.006108) (xy 121.322592 -248.004076)
			(xy 121.315431 -248.002665) (xy 121.300865 -248.003449) (xy 121.29389 -248.0056) (xy 121.29135 -248.006616)
			(xy 121.269047 -248.015319) (xy 121.22249 -248.02646) (xy 121.174764 -248.030204) (xy 121.127038 -248.02646)
			(xy 121.080481 -248.015319) (xy 121.058178 -248.006616) (xy 121.055638 -248.0056) (xy 121.048677 -248.003376)
			(xy 121.034091 -248.002595) (xy 121.026936 -248.004076) (xy 121.020586 -248.006108) (xy 120.955308 -248.031254)
			(xy 120.95084 -248.033084) (xy 120.942652 -248.038197) (xy 120.939052 -248.041414) (xy 120.932194 -248.047764)
			(xy 120.929908 -248.05259) (xy 120.927876 -248.056908) (xy 120.910457 -248.092112) (xy 120.869461 -248.159113)
			(xy 120.821843 -248.221583) (xy 120.768101 -248.278869) (xy 120.708795 -248.330373) (xy 120.644545 -248.375559)
			(xy 120.576019 -248.413954) (xy 120.503935 -248.445158) (xy 120.429043 -248.468846) (xy 120.352125 -248.48477)
			(xy 120.273984 -248.492764) (xy 120.23471 -248.49328) (xy 119.936768 -248.49328) (xy 119.896716 -248.492724)
			(xy 119.817051 -248.484325) (xy 119.777764 -248.476516) (xy 119.775224 -248.476008) (xy 119.764556 -248.474992)
			(xy 119.754142 -248.476008) (xy 119.751602 -248.476516) (xy 119.712316 -248.484335) (xy 119.632651 -248.492733)
			(xy 119.592598 -248.49328) (xy 119.294656 -248.49328) (xy 119.267732 -248.492772) (xy 119.235474 -248.49074)
			(xy 119.230722 -248.490465) (xy 119.221261 -248.491488) (xy 119.216678 -248.492772) (xy 119.207534 -248.495566)
			(xy 119.145558 -248.545096) (xy 119.141833 -248.548214) (xy 119.135574 -248.55564) (xy 119.133112 -248.559828)
			(xy 119.12854 -248.567956) (xy 119.127016 -248.577608) (xy 119.127016 -248.577862) (xy 119.123111 -248.601789)
			(xy 119.108724 -248.648085) (xy 119.0872 -248.691523) (xy 119.05908 -248.731013) (xy 119.02507 -248.765562)
			(xy 118.986027 -248.794299) (xy 118.942932 -248.816504) (xy 118.896869 -248.831616) (xy 118.848996 -248.839257)
			(xy 118.824756 -248.839736) (xy 118.800766 -248.839262) (xy 118.753378 -248.831751) (xy 118.707748 -248.81692)
			(xy 118.665 -248.795134) (xy 118.626185 -248.766931) (xy 118.592259 -248.733003) (xy 118.564057 -248.694187)
			(xy 118.542274 -248.651437) (xy 118.527446 -248.605806) (xy 118.519937 -248.558418) (xy 118.519448 -248.534428)
			(xy 118.519868 -248.511466) (xy 118.526758 -248.466061) (xy 118.540373 -248.4222) (xy 118.560404 -248.380874)
			(xy 118.5864 -248.343015) (xy 118.617774 -248.309478) (xy 118.635526 -248.294906) (xy 118.637304 -248.293382)
			(xy 118.651274 -248.269506) (xy 118.653552 -248.265406) (xy 118.656744 -248.256587) (xy 118.657624 -248.25198)
			(xy 118.667022 -248.193052) (xy 118.668071 -248.184313) (xy 118.664825 -248.167029) (xy 118.660672 -248.15927)
			(xy 118.65864 -248.156222) (xy 118.642736 -248.132359) (xy 118.614132 -248.082649) (xy 118.60149 -248.056908)
			(xy 118.599712 -248.053352) (xy 118.597758 -248.050134) (xy 118.593036 -248.044269) (xy 118.590314 -248.041668)
			(xy 118.582948 -248.03481) (xy 118.508018 -248.006108) (xy 118.504021 -248.004758) (xy 118.495724 -248.003228)
			(xy 118.491508 -248.00306) (xy 118.480332 -248.00306) (xy 118.473982 -248.0056) (xy 118.47068 -248.00687)
			(xy 118.442907 -248.017489) (xy 118.384581 -248.028997) (xy 118.354856 -248.02973) (xy 118.324928 -248.029)
			(xy 118.266216 -248.017353) (xy 118.23827 -248.006616) (xy 118.23573 -248.0056) (xy 118.228769 -248.003378)
			(xy 118.214184 -248.002599) (xy 118.207028 -248.004076) (xy 118.200678 -248.006108) (xy 118.1354 -248.031254)
			(xy 118.130932 -248.033084) (xy 118.122745 -248.038199) (xy 118.119144 -248.041414) (xy 118.112286 -248.047764)
			(xy 118.11 -248.05259) (xy 118.107968 -248.056908) (xy 118.090549 -248.092112) (xy 118.049553 -248.159112)
			(xy 118.001935 -248.221582) (xy 117.948193 -248.278867) (xy 117.888887 -248.330371) (xy 117.824636 -248.375556)
			(xy 117.756111 -248.41395) (xy 117.684026 -248.445154) (xy 117.609134 -248.468841) (xy 117.532217 -248.484764)
			(xy 117.454076 -248.492757) (xy 117.414802 -248.49328) (xy 117.11686 -248.49328) (xy 117.076808 -248.492724)
			(xy 116.997144 -248.484324) (xy 116.957856 -248.476516) (xy 116.955316 -248.476008) (xy 116.944648 -248.474992)
			(xy 116.934234 -248.476008) (xy 116.931694 -248.476516) (xy 116.892408 -248.484334) (xy 116.812743 -248.492731)
			(xy 116.77269 -248.49328) (xy 116.474748 -248.49328) (xy 116.447824 -248.492772) (xy 116.415566 -248.49074)
			(xy 116.410815 -248.490466) (xy 116.401354 -248.49149) (xy 116.39677 -248.492772) (xy 116.387626 -248.495566)
			(xy 116.32565 -248.545096) (xy 116.321931 -248.54822) (xy 116.315674 -248.555646) (xy 116.313204 -248.559828)
			(xy 116.308632 -248.567956) (xy 116.307108 -248.577608) (xy 116.307108 -248.577862) (xy 116.303203 -248.601789)
			(xy 116.288816 -248.648084) (xy 116.267292 -248.691522) (xy 116.239171 -248.731011) (xy 116.205162 -248.765559)
			(xy 116.166118 -248.794295) (xy 116.123023 -248.816499) (xy 116.07696 -248.83161) (xy 116.029088 -248.83925)
			(xy 116.004848 -248.839736) (xy 115.97492 -248.839005) (xy 115.916208 -248.827357) (xy 115.888262 -248.816622)
			(xy 115.885722 -248.815606) (xy 115.878761 -248.813385) (xy 115.864176 -248.812608) (xy 115.85702 -248.814082)
			(xy 115.85067 -248.816114) (xy 115.785392 -248.84126) (xy 115.780925 -248.843091) (xy 115.772739 -248.848207)
			(xy 115.769136 -248.85142) (xy 115.762532 -248.857516) (xy 115.758214 -248.86666) (xy 115.745768 -248.891044)
			(xy 115.745768 -248.891552) (xy 115.738148 -248.905268) (xy 115.73764 -248.905776) (xy 115.729044 -248.921253)
			(xy 115.710621 -248.951491) (xy 115.70081 -248.966228) (xy 115.698778 -248.969276) (xy 115.694669 -248.97705)
			(xy 115.691427 -248.994321) (xy 115.692428 -249.003058) (xy 115.701826 -249.061986) (xy 115.702675 -249.066602)
			(xy 115.705869 -249.075425) (xy 115.708176 -249.079512) (xy 115.722146 -249.103388) (xy 115.723924 -249.104912)
			(xy 115.741697 -249.119461) (xy 115.773084 -249.152993) (xy 115.799087 -249.190854) (xy 115.819116 -249.232186)
			(xy 115.83272 -249.276056) (xy 115.839589 -249.321469) (xy 115.840002 -249.344434) (xy 117.108998 -249.344434)
			(xy 117.112958 -249.29538) (xy 117.124735 -249.247596) (xy 117.144026 -249.20232) (xy 117.170329 -249.160724)
			(xy 117.202964 -249.123887) (xy 117.241085 -249.092762) (xy 117.283706 -249.068155) (xy 117.329722 -249.050703)
			(xy 117.377941 -249.040859) (xy 117.427116 -249.038878) (xy 117.475971 -249.04481) (xy 117.523242 -249.058502)
			(xy 117.567704 -249.0796) (xy 117.608207 -249.107556) (xy 117.6437 -249.141648) (xy 117.673265 -249.180992)
			(xy 117.696136 -249.224569) (xy 117.71172 -249.27125) (xy 117.719615 -249.319827) (xy 117.72011 -249.344434)
			(xy 118.988852 -249.344434) (xy 118.992812 -249.29538) (xy 119.004589 -249.247596) (xy 119.02388 -249.20232)
			(xy 119.050183 -249.160724) (xy 119.082818 -249.123887) (xy 119.120939 -249.092762) (xy 119.16356 -249.068155)
			(xy 119.209576 -249.050703) (xy 119.257795 -249.040859) (xy 119.30697 -249.038878) (xy 119.355825 -249.04481)
			(xy 119.403096 -249.058502) (xy 119.447558 -249.0796) (xy 119.488061 -249.107556) (xy 119.523554 -249.141648)
			(xy 119.553119 -249.180992) (xy 119.57599 -249.224569) (xy 119.591574 -249.27125) (xy 119.599469 -249.319827)
			(xy 119.599964 -249.344434) (xy 120.86896 -249.344434) (xy 120.87292 -249.29538) (xy 120.884697 -249.247596)
			(xy 120.903988 -249.20232) (xy 120.930291 -249.160724) (xy 120.962926 -249.123887) (xy 121.001047 -249.092762)
			(xy 121.043668 -249.068155) (xy 121.089684 -249.050703) (xy 121.137903 -249.040859) (xy 121.187078 -249.038878)
			(xy 121.235933 -249.04481) (xy 121.283204 -249.058502) (xy 121.327666 -249.0796) (xy 121.368169 -249.107556)
			(xy 121.403662 -249.141648) (xy 121.433227 -249.180992) (xy 121.456098 -249.224569) (xy 121.471682 -249.27125)
			(xy 121.479577 -249.319827) (xy 121.480072 -249.344434) (xy 122.748814 -249.344434) (xy 122.752774 -249.29538)
			(xy 122.764551 -249.247596) (xy 122.783842 -249.20232) (xy 122.810145 -249.160724) (xy 122.84278 -249.123887)
			(xy 122.880901 -249.092762) (xy 122.923522 -249.068155) (xy 122.969538 -249.050703) (xy 123.017757 -249.040859)
			(xy 123.066932 -249.038878) (xy 123.115787 -249.04481) (xy 123.163058 -249.058502) (xy 123.20752 -249.0796)
			(xy 123.248023 -249.107556) (xy 123.283516 -249.141648) (xy 123.313081 -249.180992) (xy 123.335952 -249.224569)
			(xy 123.351536 -249.27125) (xy 123.359431 -249.319827) (xy 123.359926 -249.344434) (xy 124.628922 -249.344434)
			(xy 124.632882 -249.29538) (xy 124.644659 -249.247596) (xy 124.66395 -249.20232) (xy 124.690253 -249.160724)
			(xy 124.722888 -249.123887) (xy 124.761009 -249.092762) (xy 124.80363 -249.068155) (xy 124.849646 -249.050703)
			(xy 124.897865 -249.040859) (xy 124.94704 -249.038878) (xy 124.995895 -249.04481) (xy 125.043166 -249.058502)
			(xy 125.087628 -249.0796) (xy 125.128131 -249.107556) (xy 125.163624 -249.141648) (xy 125.193189 -249.180992)
			(xy 125.21606 -249.224569) (xy 125.231644 -249.27125) (xy 125.239539 -249.319827) (xy 125.240034 -249.344434)
			(xy 125.239539 -249.369041) (xy 125.231644 -249.417618) (xy 125.21606 -249.464299) (xy 125.193189 -249.507876)
			(xy 125.163624 -249.54722) (xy 125.128131 -249.581312) (xy 125.087628 -249.609268) (xy 125.043166 -249.630366)
			(xy 124.995895 -249.644058) (xy 124.94704 -249.64999) (xy 124.897865 -249.648009) (xy 124.849646 -249.638165)
			(xy 124.80363 -249.620713) (xy 124.761009 -249.596106) (xy 124.722888 -249.564981) (xy 124.690253 -249.528144)
			(xy 124.66395 -249.486548) (xy 124.644659 -249.441272) (xy 124.632882 -249.393488) (xy 124.628922 -249.344434)
			(xy 123.359926 -249.344434) (xy 123.359431 -249.369041) (xy 123.351536 -249.417618) (xy 123.335952 -249.464299)
			(xy 123.313081 -249.507876) (xy 123.283516 -249.54722) (xy 123.248023 -249.581312) (xy 123.20752 -249.609268)
			(xy 123.163058 -249.630366) (xy 123.115787 -249.644058) (xy 123.066932 -249.64999) (xy 123.017757 -249.648009)
			(xy 122.969538 -249.638165) (xy 122.923522 -249.620713) (xy 122.880901 -249.596106) (xy 122.84278 -249.564981)
			(xy 122.810145 -249.528144) (xy 122.783842 -249.486548) (xy 122.764551 -249.441272) (xy 122.752774 -249.393488)
			(xy 122.748814 -249.344434) (xy 121.480072 -249.344434) (xy 121.479577 -249.369041) (xy 121.471682 -249.417618)
			(xy 121.456098 -249.464299) (xy 121.433227 -249.507876) (xy 121.403662 -249.54722) (xy 121.368169 -249.581312)
			(xy 121.327666 -249.609268) (xy 121.283204 -249.630366) (xy 121.235933 -249.644058) (xy 121.187078 -249.64999)
			(xy 121.137903 -249.648009) (xy 121.089684 -249.638165) (xy 121.043668 -249.620713) (xy 121.001047 -249.596106)
			(xy 120.962926 -249.564981) (xy 120.930291 -249.528144) (xy 120.903988 -249.486548) (xy 120.884697 -249.441272)
			(xy 120.87292 -249.393488) (xy 120.86896 -249.344434) (xy 119.599964 -249.344434) (xy 119.599469 -249.369041)
			(xy 119.591574 -249.417618) (xy 119.57599 -249.464299) (xy 119.553119 -249.507876) (xy 119.523554 -249.54722)
			(xy 119.488061 -249.581312) (xy 119.447558 -249.609268) (xy 119.403096 -249.630366) (xy 119.355825 -249.644058)
			(xy 119.30697 -249.64999) (xy 119.257795 -249.648009) (xy 119.209576 -249.638165) (xy 119.16356 -249.620713)
			(xy 119.120939 -249.596106) (xy 119.082818 -249.564981) (xy 119.050183 -249.528144) (xy 119.02388 -249.486548)
			(xy 119.004589 -249.441272) (xy 118.992812 -249.393488) (xy 118.988852 -249.344434) (xy 117.72011 -249.344434)
			(xy 117.719615 -249.369041) (xy 117.71172 -249.417618) (xy 117.696136 -249.464299) (xy 117.673265 -249.507876)
			(xy 117.6437 -249.54722) (xy 117.608207 -249.581312) (xy 117.567704 -249.609268) (xy 117.523242 -249.630366)
			(xy 117.475971 -249.644058) (xy 117.427116 -249.64999) (xy 117.377941 -249.648009) (xy 117.329722 -249.638165)
			(xy 117.283706 -249.620713) (xy 117.241085 -249.596106) (xy 117.202964 -249.564981) (xy 117.170329 -249.528144)
			(xy 117.144026 -249.486548) (xy 117.124735 -249.441272) (xy 117.112958 -249.393488) (xy 117.108998 -249.344434)
			(xy 115.840002 -249.344434) (xy 115.839529 -249.368423) (xy 115.832018 -249.415811) (xy 115.817188 -249.46144)
			(xy 115.795403 -249.504187) (xy 115.767198 -249.543001) (xy 115.73327 -249.576924) (xy 115.694453 -249.605123)
			(xy 115.651703 -249.626903) (xy 115.606072 -249.641728) (xy 115.558683 -249.649232) (xy 115.534694 -249.649742)
			(xy 115.510443 -249.649275) (xy 115.462552 -249.641607) (xy 115.416474 -249.626464) (xy 115.373371 -249.604227)
			(xy 115.334324 -249.575456) (xy 115.300317 -249.540874) (xy 115.272205 -249.50135) (xy 115.250694 -249.45788)
			(xy 115.236325 -249.411555) (xy 115.232434 -249.387614) (xy 115.23091 -249.377962) (xy 115.226338 -249.369834)
			(xy 115.223851 -249.365665) (xy 115.217587 -249.35825) (xy 115.213892 -249.355102) (xy 115.159536 -249.311668)
			(xy 115.15574 -249.308768) (xy 115.147301 -249.304297) (xy 115.142772 -249.302778) (xy 115.133882 -249.299984)
			(xy 115.12423 -249.300746) (xy 115.109521 -249.30181) (xy 115.080049 -249.302952) (xy 115.065302 -249.303032)
			(xy 114.765582 -249.303032) (xy 114.725854 -249.302492) (xy 114.646827 -249.294219) (xy 114.607848 -249.286522)
			(xy 114.605308 -249.286014) (xy 114.594894 -249.284998) (xy 114.584226 -249.286014) (xy 114.581686 -249.286522)
			(xy 114.542582 -249.294248) (xy 114.4633 -249.302522) (xy 114.423444 -249.303032) (xy 114.12474 -249.303032)
			(xy 114.109802 -249.30297) (xy 114.079949 -249.301826) (xy 114.06505 -249.300746) (xy 114.060299 -249.300473)
			(xy 114.050839 -249.301501) (xy 114.046254 -249.302778) (xy 114.037618 -249.305572) (xy 113.975642 -249.355102)
			(xy 113.971919 -249.358223) (xy 113.96565 -249.365642) (xy 113.963196 -249.369834) (xy 113.958624 -249.377962)
			(xy 113.9571 -249.387614) (xy 113.9571 -249.387868) (xy 113.953195 -249.411798) (xy 113.938809 -249.458098)
			(xy 113.917286 -249.501543) (xy 113.889167 -249.54104) (xy 113.855159 -249.575596) (xy 113.816117 -249.604342)
			(xy 113.773022 -249.626557) (xy 113.726958 -249.641681) (xy 113.679082 -249.649335) (xy 113.65484 -249.649742)
			(xy 113.630844 -249.649299) (xy 113.583442 -249.641797) (xy 113.537796 -249.626973) (xy 113.495032 -249.60519)
			(xy 113.456202 -249.576986) (xy 113.422262 -249.543054) (xy 113.394049 -249.504231) (xy 113.372256 -249.461472)
			(xy 113.35742 -249.415831) (xy 113.349907 -249.36843) (xy 113.349532 -249.344434) (xy 113.349952 -249.321471)
			(xy 113.356841 -249.276065) (xy 113.370454 -249.232204) (xy 113.390484 -249.190877) (xy 113.416479 -249.153016)
			(xy 113.447852 -249.119477) (xy 113.46561 -249.104912) (xy 113.467388 -249.103388) (xy 113.481358 -249.079512)
			(xy 113.483637 -249.075412) (xy 113.486831 -249.066594) (xy 113.487708 -249.061986) (xy 113.497106 -249.003058)
			(xy 113.498156 -248.994319) (xy 113.494912 -248.977034) (xy 113.490756 -248.969276) (xy 113.488724 -248.966228)
			(xy 113.478909 -248.951494) (xy 113.460485 -248.921256) (xy 113.451894 -248.905776) (xy 113.451386 -248.905268)
			(xy 113.443766 -248.891552) (xy 113.443766 -248.891044) (xy 113.43132 -248.86666) (xy 113.427002 -248.857516)
			(xy 113.420398 -248.85142) (xy 113.416781 -248.848224) (xy 113.408603 -248.843102) (xy 113.404142 -248.84126)
			(xy 113.338864 -248.816114) (xy 113.332514 -248.814082) (xy 113.325353 -248.812668) (xy 113.310784 -248.813446)
			(xy 113.303812 -248.815606) (xy 113.301272 -248.816622) (xy 113.27333 -248.827369) (xy 113.214615 -248.839009)
			(xy 113.184686 -248.839736) (xy 113.159429 -248.839213) (xy 113.109605 -248.830897) (xy 113.061828 -248.814493)
			(xy 113.017404 -248.79045) (xy 112.977542 -248.759423) (xy 112.943331 -248.722258) (xy 112.915703 -248.679969)
			(xy 112.895412 -248.633709) (xy 112.883012 -248.584741) (xy 112.878841 -248.5344) (xy 112.883012 -248.484059)
			(xy 112.895412 -248.435091) (xy 112.915703 -248.388831) (xy 112.943331 -248.346542) (xy 112.977542 -248.309377)
			(xy 113.017404 -248.27835) (xy 113.061828 -248.254307) (xy 113.109605 -248.237903) (xy 113.159429 -248.229587)
			(xy 113.184686 -248.22912) (xy 113.217452 -248.230898) (xy 113.218722 -248.231152) (xy 113.221262 -248.231152)
			(xy 113.229916 -248.231118) (xy 113.246415 -248.225931) (xy 113.25352 -248.220992) (xy 113.261648 -248.213118)
			(xy 113.316004 -248.148348) (xy 113.319343 -248.144155) (xy 113.324346 -248.134678) (xy 113.32591 -248.129552)
			(xy 113.32591 -248.101612) (xy 113.323878 -248.094754) (xy 113.308384 -248.035318) (xy 113.297462 -247.98401)
			(xy 113.297208 -247.982232) (xy 113.295684 -247.97512) (xy 113.278158 -247.945402) (xy 113.271554 -247.939814)
			(xy 113.232197 -247.906425) (xy 113.158187 -247.834476) (xy 113.089957 -247.757024) (xy 113.027915 -247.674532)
			(xy 112.972433 -247.587493) (xy 112.923841 -247.496427) (xy 112.882431 -247.401879) (xy 112.84845 -247.304414)
			(xy 112.8221 -247.204615) (xy 112.812322 -247.153938) (xy 112.811344 -247.149093) (xy 112.807764 -247.139882)
			(xy 112.80521 -247.13565) (xy 112.804448 -247.13438) (xy 112.795558 -247.124728) (xy 112.758941 -247.093315)
			(xy 112.68984 -247.025974) (xy 112.625783 -246.953817) (xy 112.567106 -246.877223) (xy 112.514114 -246.79659)
			(xy 112.467084 -246.712341) (xy 112.446308 -246.668798) (xy 112.44433 -246.664814) (xy 112.439227 -246.657529)
			(xy 112.436148 -246.65432) (xy 111.639858 -245.85803) (xy 111.629444 -245.849902) (xy 111.609909 -245.838296)
			(xy 111.573805 -245.810707) (xy 111.541669 -245.778582) (xy 111.52759 -245.760748) (xy 111.520913 -245.751832)
			(xy 111.508585 -245.733274) (xy 111.502952 -245.723664) (xy 111.502698 -245.723156) (xy 111.499142 -245.717314)
			(xy 111.168942 -245.387114) (xy 111.162104 -245.379713) (xy 111.154395 -245.361114) (xy 111.153956 -245.351046)
			(xy 111.153956 -212.560662) (xy 111.154388 -212.550596) (xy 111.162118 -212.532007) (xy 111.168942 -212.524594)
			(xy 117.587522 -206.106014) (xy 117.592713 -206.100261) (xy 117.599675 -206.086427) (xy 117.601238 -206.078836)
			(xy 117.602 -206.070454) (xy 117.602 -190.206122) (xy 117.601658 -190.197429) (xy 117.595823 -190.181052)
			(xy 117.59057 -190.174118) (xy 117.587268 -190.170308) (xy 117.292882 -189.875922) (xy 117.289153 -189.872399)
			(xy 117.28058 -189.866766) (xy 117.275864 -189.864746) (xy 117.267228 -189.86119) (xy 110.865412 -189.86119)
			(xy 110.855341 -189.860769) (xy 110.836734 -189.853056) (xy 110.829344 -189.846204) (xy 110.198408 -189.215268)
			(xy 110.194678 -189.211746) (xy 110.186105 -189.206115) (xy 110.18139 -189.204092) (xy 110.172754 -189.200536)
			(xy 106.06405 -189.200536) (xy 106.055362 -189.200891) (xy 106.039002 -189.206747) (xy 106.032046 -189.211966)
			(xy 106.028236 -189.215268) (xy 103.458264 -191.78524) (xy 103.450866 -191.792087) (xy 103.432268 -191.799818)
			(xy 103.422196 -191.800226) (xy 79.054198 -191.800226) (xy 79.044127 -191.799803) (xy 79.025521 -191.792091)
			(xy 79.01813 -191.78524) (xy 71.444612 -184.211722) (xy 71.438154 -184.205818) (xy 71.422323 -184.198391)
			(xy 71.404917 -184.196721) (xy 71.396352 -184.198514) (xy 71.394828 -184.198768) (xy 71.311262 -184.220104)
			(xy 71.304976 -184.221896) (xy 71.293526 -184.228191) (xy 71.288656 -184.23255) (xy 71.284084 -184.236868)
			(xy 71.27748 -184.248298) (xy 71.275448 -184.254902) (xy 71.267264 -184.280875) (xy 71.244562 -184.330372)
			(xy 71.21506 -184.376143) (xy 71.179355 -184.417259) (xy 71.138173 -184.452887) (xy 71.092347 -184.482304)
			(xy 71.042808 -184.504914) (xy 70.990559 -184.520258) (xy 70.936661 -184.528026) (xy 70.909434 -184.52846)
			(xy 70.882181 -184.527999) (xy 70.828229 -184.520246) (xy 70.77593 -184.504892) (xy 70.726348 -184.482251)
			(xy 70.680494 -184.452783) (xy 70.639301 -184.417089) (xy 70.603609 -184.375895) (xy 70.574142 -184.330039)
			(xy 70.551503 -184.280457) (xy 70.536151 -184.228158) (xy 70.5284 -184.174205) (xy 70.527926 -184.146952)
			(xy 70.528276 -184.123858) (xy 70.533876 -184.07801) (xy 70.539102 -184.055512) (xy 70.539102 -184.055258)
			(xy 70.541289 -184.04362) (xy 70.536001 -184.020568) (xy 70.528942 -184.011062) (xy 70.469506 -183.945276)
			(xy 70.46343 -183.939538) (xy 70.448522 -183.932013) (xy 70.440296 -183.930544) (xy 70.426072 -183.930544)
			(xy 70.42277 -183.931052) (xy 70.410129 -183.932617) (xy 70.384708 -183.934268) (xy 70.37197 -183.934354)
			(xy 70.369176 -183.934354) (xy 70.342058 -183.933676) (xy 70.288419 -183.925594) (xy 70.236465 -183.909996)
			(xy 70.187245 -183.887194) (xy 70.141752 -183.85765) (xy 70.100903 -183.82196) (xy 70.065521 -183.780842)
			(xy 70.036321 -183.735127) (xy 70.013892 -183.685737) (xy 69.998686 -183.633667) (xy 69.991009 -183.579968)
			(xy 69.990462 -183.552846) (xy 69.990989 -183.524438) (xy 69.999422 -183.468251) (xy 70.016095 -183.413935)
			(xy 70.040637 -183.362693) (xy 70.072508 -183.315657) (xy 70.111001 -183.273867) (xy 70.155266 -183.238248)
			(xy 70.204323 -183.209586) (xy 70.230492 -183.198516) (xy 70.235572 -183.196484) (xy 70.241922 -183.192166)
			(xy 70.248692 -183.186779) (xy 70.258439 -183.172498) (xy 70.260972 -183.164226) (xy 70.276212 -183.092598)
			(xy 70.276212 -183.09209) (xy 70.279006 -183.078374) (xy 70.280681 -183.06747) (xy 70.275688 -183.046004)
			(xy 70.269354 -183.036972) (xy 70.267322 -183.034432) (xy 67.459606 -180.226716) (xy 67.455877 -180.223192)
			(xy 67.447306 -180.217556) (xy 67.442588 -180.21554) (xy 67.433952 -180.211984) (xy 63.36792 -180.211984)
			(xy 63.359228 -180.212328) (xy 63.342857 -180.218171) (xy 63.335916 -180.223414) (xy 63.332106 -180.226716)
			(xy 62.392052 -181.16677) (xy 62.388529 -181.1705) (xy 62.382896 -181.179072) (xy 62.380876 -181.183788)
			(xy 62.37732 -181.192424) (xy 62.37732 -195.584572) (xy 62.377733 -195.594181) (xy 62.384782 -195.612063)
			(xy 62.391036 -195.61937) (xy 62.392306 -195.62064) (xy 62.399164 -195.626482) (xy 62.454282 -195.673472)
			(xy 62.463025 -195.680178) (xy 62.484224 -195.686107) (xy 62.495176 -195.684902) (xy 62.49543 -195.684902)
			(xy 62.515981 -195.6817) (xy 62.557436 -195.678268) (xy 62.578234 -195.678044) (xy 62.610197 -195.678548)
			(xy 62.673618 -195.686563) (xy 62.735534 -195.702465) (xy 62.794969 -195.726) (xy 62.850986 -195.756799)
			(xy 62.902701 -195.794375) (xy 62.949299 -195.838137) (xy 62.990045 -195.887394) (xy 63.024297 -195.941368)
			(xy 63.051514 -195.99921) (xy 63.071267 -196.060007) (xy 63.083245 -196.122801) (xy 63.087259 -196.1866)
			(xy 63.083245 -196.250399) (xy 63.071267 -196.313193) (xy 63.051514 -196.37399) (xy 63.024297 -196.431831)
			(xy 62.990045 -196.485806) (xy 62.949299 -196.535063) (xy 62.902701 -196.578825) (xy 62.850986 -196.616401)
			(xy 62.794969 -196.6472) (xy 62.735534 -196.670735) (xy 62.673618 -196.686637) (xy 62.610197 -196.694652)
			(xy 62.578234 -196.69506) (xy 62.557436 -196.694826) (xy 62.515983 -196.691394) (xy 62.49543 -196.688202)
			(xy 62.495176 -196.688202) (xy 62.484218 -196.686962) (xy 62.463002 -196.692883) (xy 62.454282 -196.699632)
			(xy 62.395354 -196.74967) (xy 62.3951 -196.749924) (xy 62.391085 -196.753529) (xy 62.384541 -196.762107)
			(xy 62.382146 -196.766942) (xy 62.37732 -196.777102) (xy 62.37732 -197.192072) (xy 64.17745 -197.192072)
			(xy 64.182661 -197.129198) (xy 64.195609 -197.06745) (xy 64.216096 -197.007779) (xy 64.243807 -196.9511)
			(xy 64.278315 -196.898284) (xy 64.319092 -196.850143) (xy 64.365511 -196.807415) (xy 64.416859 -196.770757)
			(xy 64.472346 -196.740732) (xy 64.531122 -196.717801) (xy 64.592283 -196.702317) (xy 64.654889 -196.694517)
			(xy 64.686434 -196.694044) (xy 64.704661 -196.694238) (xy 64.741018 -196.696907) (xy 64.759078 -196.699378)
			(xy 64.77381 -196.70141) (xy 64.80048 -196.689472) (xy 64.867536 -196.588126) (xy 64.868298 -196.558916)
			(xy 64.860678 -196.546216) (xy 64.843328 -196.516371) (xy 64.815962 -196.452995) (xy 64.797438 -196.386494)
			(xy 64.788098 -196.318096) (xy 64.787526 -196.28358) (xy 64.788028 -196.251619) (xy 64.796039 -196.188201)
			(xy 64.811936 -196.126287) (xy 64.835468 -196.066854) (xy 64.866262 -196.010839) (xy 64.903835 -195.959124)
			(xy 64.947592 -195.912527) (xy 64.996845 -195.871782) (xy 65.050816 -195.837531) (xy 65.108655 -195.810314)
			(xy 65.169448 -195.790561) (xy 65.232238 -195.778583) (xy 65.296034 -195.77457) (xy 65.35983 -195.778583)
			(xy 65.42262 -195.790561) (xy 65.483413 -195.810314) (xy 65.541252 -195.837531) (xy 65.595223 -195.871782)
			(xy 65.644476 -195.912527) (xy 65.688233 -195.959124) (xy 65.725806 -196.010839) (xy 65.7566 -196.066854)
			(xy 65.780132 -196.126287) (xy 65.796029 -196.188201) (xy 65.80404 -196.251619) (xy 65.804542 -196.28358)
			(xy 65.804001 -196.31701) (xy 65.795203 -196.383289) (xy 65.777795 -196.447844) (xy 65.765426 -196.478906)
			(xy 65.765426 -196.47916) (xy 65.762237 -196.488142) (xy 65.761962 -196.507184) (xy 65.764918 -196.516244)
			(xy 65.793366 -196.591428) (xy 65.806574 -196.605652) (xy 65.815464 -196.609716) (xy 65.83953 -196.621667)
			(xy 65.884317 -196.651355) (xy 65.924495 -196.687035) (xy 65.959269 -196.727999) (xy 65.98795 -196.773438)
			(xy 66.009972 -196.822452) (xy 66.024897 -196.874071) (xy 66.032432 -196.927273) (xy 66.032888 -196.95414)
			(xy 66.032777 -196.967073) (xy 66.030995 -196.992876) (xy 66.029332 -197.005702) (xy 66.028246 -197.018263)
			(xy 66.03707 -197.041853) (xy 66.046096 -197.05066) (xy 66.118994 -197.114922) (xy 66.143886 -197.120764)
			(xy 66.156078 -197.117462) (xy 66.188066 -197.109514) (xy 66.253424 -197.100982) (xy 66.28638 -197.100444)
			(xy 66.286634 -197.100444) (xy 66.318173 -197.101004) (xy 66.380766 -197.10881) (xy 66.441913 -197.124299)
			(xy 66.500675 -197.147233) (xy 66.556148 -197.177259) (xy 66.607482 -197.213915) (xy 66.653887 -197.25664)
			(xy 66.694651 -197.304777) (xy 66.729148 -197.357587) (xy 66.756847 -197.414258) (xy 66.777324 -197.47392)
			(xy 66.790264 -197.535656) (xy 66.795469 -197.59852) (xy 66.792857 -197.661544) (xy 66.78247 -197.723761)
			(xy 66.764467 -197.784215) (xy 66.739124 -197.841979) (xy 66.706831 -197.896164) (xy 66.668083 -197.945938)
			(xy 66.623477 -197.990538) (xy 66.573696 -198.029277) (xy 66.519506 -198.061562) (xy 66.461738 -198.086895)
			(xy 66.401281 -198.104888) (xy 66.339062 -198.115266) (xy 66.276038 -198.117867) (xy 66.213175 -198.112653)
			(xy 66.151441 -198.099703) (xy 66.091782 -198.079216) (xy 66.035115 -198.051507) (xy 65.982312 -198.017002)
			(xy 65.934181 -197.97623) (xy 65.891464 -197.929818) (xy 65.854815 -197.878479) (xy 65.824798 -197.823)
			(xy 65.801874 -197.764235) (xy 65.786395 -197.703086) (xy 65.778599 -197.640491) (xy 65.778126 -197.608952)
			(xy 65.77882 -197.572095) (xy 65.789525 -197.499162) (xy 65.799462 -197.463664) (xy 65.799462 -197.46341)
			(xy 65.8024 -197.451225) (xy 65.797325 -197.426707) (xy 65.78981 -197.416674) (xy 65.735708 -197.35165)
			(xy 65.727211 -197.342441) (xy 65.704029 -197.332996) (xy 65.691512 -197.333616) (xy 65.691258 -197.333616)
			(xy 65.681317 -197.334583) (xy 65.661368 -197.335597) (xy 65.65138 -197.335648) (xy 65.62413 -197.335141)
			(xy 65.570185 -197.327383) (xy 65.517893 -197.312027) (xy 65.468319 -197.289387) (xy 65.42247 -197.259922)
			(xy 65.381281 -197.224233) (xy 65.34559 -197.183046) (xy 65.316123 -197.137199) (xy 65.29348 -197.087625)
			(xy 65.278122 -197.035334) (xy 65.27036 -196.98139) (xy 65.269872 -196.95414) (xy 65.269872 -196.953886)
			(xy 65.270011 -196.939543) (xy 65.272175 -196.910938) (xy 65.27419 -196.896736) (xy 65.275184 -196.887117)
			(xy 65.270755 -196.868311) (xy 65.265554 -196.86016) (xy 65.219834 -196.794374) (xy 65.203832 -196.783706)
			(xy 65.19418 -196.781674) (xy 65.167415 -196.775836) (xy 65.11523 -196.759165) (xy 65.09004 -196.7484)
			(xy 65.080473 -196.744745) (xy 65.060021 -196.7444) (xy 65.041056 -196.752065) (xy 65.026587 -196.766523)
			(xy 65.018908 -196.785482) (xy 65.019236 -196.805934) (xy 65.02752 -196.824636) (xy 65.034668 -196.831966)
			(xy 65.055989 -196.852597) (xy 65.094199 -196.897985) (xy 65.12687 -196.947511) (xy 65.153556 -197.000501)
			(xy 65.173896 -197.056236) (xy 65.187613 -197.11396) (xy 65.194522 -197.172887) (xy 65.194942 -197.202552)
			(xy 65.194484 -197.234097) (xy 65.186685 -197.296704) (xy 65.171203 -197.357865) (xy 65.148274 -197.416641)
			(xy 65.118251 -197.472129) (xy 65.081594 -197.523478) (xy 65.038867 -197.569898) (xy 64.990727 -197.610676)
			(xy 64.937912 -197.645186) (xy 64.881234 -197.672899) (xy 64.821563 -197.693387) (xy 64.759816 -197.706337)
			(xy 64.696942 -197.71155) (xy 64.633905 -197.708945) (xy 64.571675 -197.698563) (xy 64.511207 -197.680563)
			(xy 64.45343 -197.655221) (xy 64.399231 -197.622928) (xy 64.349444 -197.584178) (xy 64.304832 -197.539567)
			(xy 64.26608 -197.48978) (xy 64.233785 -197.435582) (xy 64.208442 -197.377806) (xy 64.19044 -197.317339)
			(xy 64.180056 -197.255109) (xy 64.17745 -197.192072) (xy 62.37732 -197.192072) (xy 62.37732 -198.944992)
			(xy 67.815206 -198.944992) (xy 67.815694 -198.913616) (xy 67.823405 -198.851339) (xy 67.838722 -198.790484)
			(xy 67.86141 -198.731976) (xy 67.891126 -198.676706) (xy 67.927418 -198.625512) (xy 67.969733 -198.579173)
			(xy 68.01743 -198.538394) (xy 68.069782 -198.503795) (xy 68.125994 -198.4759) (xy 68.185212 -198.455135)
			(xy 68.246534 -198.441816) (xy 68.27774 -198.438516) (xy 68.2879 -198.437754) (xy 68.306188 -198.428102)
			(xy 68.364862 -198.355966) (xy 68.370704 -198.336154) (xy 68.369434 -198.325994) (xy 68.367984 -198.311879)
			(xy 68.366457 -198.283541) (xy 68.366386 -198.269352) (xy 68.366888 -198.237391) (xy 68.374899 -198.173973)
			(xy 68.390796 -198.112059) (xy 68.414328 -198.052626) (xy 68.445122 -197.996611) (xy 68.482695 -197.944896)
			(xy 68.526452 -197.898299) (xy 68.575705 -197.857554) (xy 68.629676 -197.823303) (xy 68.687515 -197.796086)
			(xy 68.748308 -197.776333) (xy 68.811098 -197.764355) (xy 68.874894 -197.760342) (xy 68.93869 -197.764355)
			(xy 69.00148 -197.776333) (xy 69.062273 -197.796086) (xy 69.120112 -197.823303) (xy 69.174083 -197.857554)
			(xy 69.223336 -197.898299) (xy 69.267093 -197.944896) (xy 69.304666 -197.996611) (xy 69.33546 -198.052626)
			(xy 69.358992 -198.112059) (xy 69.374889 -198.173973) (xy 69.3829 -198.237391) (xy 69.383402 -198.269352)
			(xy 69.382947 -198.300729) (xy 69.375231 -198.363007) (xy 69.35991 -198.423862) (xy 69.337218 -198.482369)
			(xy 69.307498 -198.53764) (xy 69.271203 -198.588833) (xy 69.228885 -198.635171) (xy 69.181186 -198.67595)
			(xy 69.128832 -198.710549) (xy 69.072618 -198.738443) (xy 69.013399 -198.759208) (xy 68.952074 -198.772528)
			(xy 68.920868 -198.775828) (xy 68.910708 -198.77659) (xy 68.89242 -198.786242) (xy 68.833746 -198.858378)
			(xy 68.827904 -198.87819) (xy 68.829174 -198.88835) (xy 68.830952 -198.90867) (xy 68.83146 -198.917814)
			(xy 68.839334 -198.934578) (xy 68.90004 -198.994776) (xy 68.917058 -199.002142) (xy 68.926202 -199.00265)
			(xy 68.95695 -199.00494) (xy 69.017608 -199.016005) (xy 69.076483 -199.034324) (xy 69.132711 -199.059626)
			(xy 69.185467 -199.091542) (xy 69.233977 -199.129603) (xy 69.277529 -199.173249) (xy 69.315484 -199.221842)
			(xy 69.347286 -199.274667) (xy 69.360288 -199.302624) (xy 69.360288 -199.302878) (xy 69.364626 -199.311345)
			(xy 69.378331 -199.324521) (xy 69.386958 -199.328532) (xy 69.460364 -199.359266) (xy 69.479668 -199.35952)
			(xy 69.488812 -199.356218) (xy 69.517481 -199.345901) (xy 69.576668 -199.331429) (xy 69.637162 -199.324149)
			(xy 69.667628 -199.323706) (xy 69.699589 -199.324182) (xy 69.763006 -199.332196) (xy 69.824919 -199.348096)
			(xy 69.88435 -199.371629) (xy 69.940364 -199.402426) (xy 69.992077 -199.44) (xy 70.038672 -199.483759)
			(xy 70.079416 -199.533012) (xy 70.113666 -199.586983) (xy 70.140881 -199.644822) (xy 70.160634 -199.705615)
			(xy 70.172611 -199.768405) (xy 70.176625 -199.8322) (xy 70.172611 -199.895995) (xy 70.160634 -199.958785)
			(xy 70.140881 -200.019578) (xy 70.113666 -200.077417) (xy 70.079416 -200.131388) (xy 70.038672 -200.180641)
			(xy 69.992077 -200.2244) (xy 69.940364 -200.261974) (xy 69.88435 -200.292771) (xy 69.824919 -200.316304)
			(xy 69.763006 -200.332204) (xy 69.699589 -200.340218) (xy 69.667628 -200.340722) (xy 69.635136 -200.340226)
			(xy 69.570683 -200.331927) (xy 69.507812 -200.315487) (xy 69.447548 -200.291173) (xy 69.390871 -200.259381)
			(xy 69.338704 -200.220629) (xy 69.291899 -200.175549) (xy 69.251216 -200.124874) (xy 69.217319 -200.069431)
			(xy 69.20357 -200.039986) (xy 69.20357 -200.039732) (xy 69.199245 -200.031257) (xy 69.185531 -200.018085)
			(xy 69.1769 -200.014078) (xy 69.103494 -199.983344) (xy 69.08419 -199.98309) (xy 69.075046 -199.986392)
			(xy 69.046372 -199.996694) (xy 68.987187 -200.011171) (xy 68.926695 -200.018458) (xy 68.89623 -200.018904)
			(xy 68.864451 -200.018418) (xy 68.801388 -200.010501) (xy 68.739803 -199.994786) (xy 68.680656 -199.97152)
			(xy 68.624871 -199.941063) (xy 68.573315 -199.903892) (xy 68.526794 -199.860585) (xy 68.486033 -199.811819)
			(xy 68.451667 -199.758353) (xy 68.424232 -199.701021) (xy 68.404156 -199.640717) (xy 68.391751 -199.578381)
			(xy 68.388992 -199.546718) (xy 68.388484 -199.537574) (xy 68.38061 -199.52081) (xy 68.319904 -199.460612)
			(xy 68.302886 -199.453246) (xy 68.293742 -199.452738) (xy 68.261772 -199.450425) (xy 68.198767 -199.438625)
			(xy 68.137744 -199.419003) (xy 68.07967 -199.391867) (xy 68.025466 -199.35765) (xy 67.975991 -199.316893)
			(xy 67.93203 -199.270242) (xy 67.894279 -199.218436) (xy 67.863338 -199.162298) (xy 67.839695 -199.102717)
			(xy 67.823727 -199.040637) (xy 67.815686 -198.977042) (xy 67.815206 -198.944992) (xy 62.37732 -198.944992)
			(xy 62.37732 -201.896218) (xy 71.201534 -201.896218) (xy 71.20195 -201.864264) (xy 71.209955 -201.800859)
			(xy 71.225842 -201.738956) (xy 71.249359 -201.679532) (xy 71.280137 -201.623523) (xy 71.31769 -201.571812)
			(xy 71.361427 -201.525213) (xy 71.410657 -201.484462) (xy 71.464605 -201.4502) (xy 71.522422 -201.422967)
			(xy 71.583194 -201.403194) (xy 71.645965 -201.391191) (xy 71.709746 -201.387147) (xy 71.77353 -201.391127)
			(xy 71.836313 -201.403068) (xy 71.897106 -201.42278) (xy 71.954949 -201.449955) (xy 72.008931 -201.484163)
			(xy 72.058202 -201.524865) (xy 72.101985 -201.57142) (xy 72.13959 -201.623094) (xy 72.170424 -201.679072)
			(xy 72.194001 -201.738473) (xy 72.209949 -201.800359) (xy 72.218018 -201.863756) (xy 72.21855 -201.89571)
			(xy 72.21855 -201.896726) (xy 72.251094 -201.901976) (xy 72.314539 -201.919883) (xy 72.375137 -201.945839)
			(xy 72.431875 -201.979406) (xy 72.483799 -202.020023) (xy 72.53004 -202.067008) (xy 72.569823 -202.119574)
			(xy 72.60248 -202.17684) (xy 72.627465 -202.237846) (xy 72.644358 -202.301568) (xy 72.652875 -202.366938)
			(xy 72.653398 -202.3999) (xy 72.653398 -202.400408) (xy 72.653047 -202.427478) (xy 72.647321 -202.481313)
			(xy 72.641968 -202.50785) (xy 72.640051 -202.519206) (xy 72.645405 -202.541583) (xy 72.659961 -202.559401)
			(xy 72.670162 -202.564746) (xy 72.69902 -202.578761) (xy 72.753312 -202.61294) (xy 72.802874 -202.653675)
			(xy 72.846919 -202.70032) (xy 72.884747 -202.752135) (xy 72.915758 -202.808296) (xy 72.93946 -202.867912)
			(xy 72.955475 -202.930035) (xy 72.963549 -202.993679) (xy 72.96404 -203.025756) (xy 72.963538 -203.057717)
			(xy 72.955527 -203.121135) (xy 72.93963 -203.183049) (xy 72.916098 -203.242482) (xy 72.885304 -203.298497)
			(xy 72.847731 -203.350212) (xy 72.803974 -203.396809) (xy 72.754721 -203.437554) (xy 72.70075 -203.471805)
			(xy 72.642911 -203.499022) (xy 72.582118 -203.518775) (xy 72.519328 -203.530753) (xy 72.455532 -203.534767)
			(xy 72.391736 -203.530753) (xy 72.328946 -203.518775) (xy 72.268153 -203.499022) (xy 72.210314 -203.471805)
			(xy 72.156343 -203.437554) (xy 72.10709 -203.396809) (xy 72.063333 -203.350212) (xy 72.02576 -203.298497)
			(xy 71.994966 -203.242482) (xy 71.971434 -203.183049) (xy 71.955537 -203.121135) (xy 71.947526 -203.057717)
			(xy 71.947024 -203.025756) (xy 71.947024 -203.025248) (xy 71.947368 -202.998178) (xy 71.953098 -202.944343)
			(xy 71.958454 -202.917806) (xy 71.960365 -202.906447) (xy 71.955025 -202.884066) (xy 71.940465 -202.866249)
			(xy 71.93026 -202.86091) (xy 71.899931 -202.84621) (xy 71.843142 -202.809908) (xy 71.791643 -202.766426)
			(xy 71.746335 -202.716525) (xy 71.708012 -202.66108) (xy 71.677345 -202.601061) (xy 71.65487 -202.537518)
			(xy 71.640981 -202.471564) (xy 71.637906 -202.438) (xy 71.636551 -202.427226) (xy 71.62608 -202.408224)
			(xy 71.60875 -202.395168) (xy 71.598282 -202.39228) (xy 71.567962 -202.384927) (xy 71.509233 -202.363877)
			(xy 71.45352 -202.335799) (xy 71.401661 -202.301115) (xy 71.354435 -202.260347) (xy 71.312553 -202.214107)
			(xy 71.276642 -202.16309) (xy 71.247244 -202.108062) (xy 71.224799 -202.049851) (xy 71.209645 -201.989331)
			(xy 71.202009 -201.927412) (xy 71.201534 -201.896218) (xy 62.37732 -201.896218) (xy 62.37732 -202.59167)
			(xy 68.287392 -202.59167) (xy 68.287894 -202.559709) (xy 68.295905 -202.496291) (xy 68.311802 -202.434377)
			(xy 68.335334 -202.374944) (xy 68.366128 -202.318929) (xy 68.403701 -202.267214) (xy 68.447458 -202.220617)
			(xy 68.496711 -202.179872) (xy 68.550682 -202.145621) (xy 68.608521 -202.118404) (xy 68.669314 -202.098651)
			(xy 68.732104 -202.086673) (xy 68.7959 -202.08266) (xy 68.859696 -202.086673) (xy 68.922486 -202.098651)
			(xy 68.983279 -202.118404) (xy 69.041118 -202.145621) (xy 69.095089 -202.179872) (xy 69.144342 -202.220617)
			(xy 69.188099 -202.267214) (xy 69.225672 -202.318929) (xy 69.256466 -202.374944) (xy 69.279998 -202.434377)
			(xy 69.295895 -202.496291) (xy 69.303906 -202.559709) (xy 69.304408 -202.59167) (xy 69.303841 -202.626702)
			(xy 69.294228 -202.696104) (xy 69.27518 -202.76353) (xy 69.247057 -202.827703) (xy 69.229224 -202.857862)
			(xy 69.223641 -202.867785) (xy 69.221125 -202.890391) (xy 69.224398 -202.901296) (xy 69.253608 -202.986132)
			(xy 69.269356 -203.002134) (xy 69.280024 -203.006198) (xy 69.308746 -203.01744) (xy 69.363465 -203.045903)
			(xy 69.414341 -203.080775) (xy 69.460627 -203.121543) (xy 69.501643 -203.167609) (xy 69.536787 -203.218298)
			(xy 69.565543 -203.272864) (xy 69.58749 -203.330507) (xy 69.602304 -203.390382) (xy 69.609769 -203.451608)
			(xy 69.610224 -203.482448) (xy 69.609722 -203.514409) (xy 69.601711 -203.577827) (xy 69.585814 -203.639741)
			(xy 69.562282 -203.699174) (xy 69.531488 -203.755189) (xy 69.493915 -203.806904) (xy 69.450158 -203.853501)
			(xy 69.400905 -203.894246) (xy 69.346934 -203.928497) (xy 69.289095 -203.955714) (xy 69.228302 -203.975467)
			(xy 69.165512 -203.987445) (xy 69.101716 -203.991459) (xy 69.03792 -203.987445) (xy 68.97513 -203.975467)
			(xy 68.914337 -203.955714) (xy 68.856498 -203.928497) (xy 68.802527 -203.894246) (xy 68.753274 -203.853501)
			(xy 68.709517 -203.806904) (xy 68.671944 -203.755189) (xy 68.64115 -203.699174) (xy 68.617618 -203.639741)
			(xy 68.601721 -203.577827) (xy 68.59371 -203.514409) (xy 68.593208 -203.482448) (xy 68.593796 -203.447417)
			(xy 68.603404 -203.378016) (xy 68.622447 -203.31059) (xy 68.650562 -203.246416) (xy 68.668392 -203.216256)
			(xy 68.673864 -203.206293) (xy 68.676381 -203.183738) (xy 68.673218 -203.172822) (xy 68.644008 -203.087986)
			(xy 68.62826 -203.071984) (xy 68.617592 -203.06792) (xy 68.58888 -203.056654) (xy 68.534161 -203.028194)
			(xy 68.483285 -202.993325) (xy 68.436999 -202.95256) (xy 68.395982 -202.906496) (xy 68.360837 -202.85581)
			(xy 68.33208 -202.801247) (xy 68.310132 -202.743606) (xy 68.295315 -202.683734) (xy 68.287848 -202.622509)
			(xy 68.287392 -202.59167) (xy 62.37732 -202.59167) (xy 62.37732 -204.143313) (xy 88.816428 -204.143313)
			(xy 88.816428 -204.079391) (xy 88.824439 -204.015973) (xy 88.840336 -203.954059) (xy 88.863868 -203.894626)
			(xy 88.894662 -203.838611) (xy 88.932235 -203.786896) (xy 88.975992 -203.740299) (xy 89.025245 -203.699554)
			(xy 89.079216 -203.665303) (xy 89.137055 -203.638086) (xy 89.197848 -203.618333) (xy 89.260638 -203.606355)
			(xy 89.324434 -203.602342) (xy 89.38823 -203.606355) (xy 89.45102 -203.618333) (xy 89.511813 -203.638086)
			(xy 89.569652 -203.665303) (xy 89.623623 -203.699554) (xy 89.672876 -203.740299) (xy 89.716633 -203.786896)
			(xy 89.754206 -203.838611) (xy 89.785 -203.894626) (xy 89.808532 -203.954059) (xy 89.824429 -204.015973)
			(xy 89.83244 -204.079391) (xy 89.832942 -204.111352) (xy 89.83244 -204.143313) (xy 90.086428 -204.143313)
			(xy 90.086428 -204.079391) (xy 90.094439 -204.015973) (xy 90.110336 -203.954059) (xy 90.133868 -203.894626)
			(xy 90.164662 -203.838611) (xy 90.202235 -203.786896) (xy 90.245992 -203.740299) (xy 90.295245 -203.699554)
			(xy 90.349216 -203.665303) (xy 90.407055 -203.638086) (xy 90.467848 -203.618333) (xy 90.530638 -203.606355)
			(xy 90.594434 -203.602342) (xy 90.65823 -203.606355) (xy 90.72102 -203.618333) (xy 90.781813 -203.638086)
			(xy 90.839652 -203.665303) (xy 90.893623 -203.699554) (xy 90.942876 -203.740299) (xy 90.986633 -203.786896)
			(xy 91.024206 -203.838611) (xy 91.055 -203.894626) (xy 91.078532 -203.954059) (xy 91.094429 -204.015973)
			(xy 91.10244 -204.079391) (xy 91.102942 -204.111352) (xy 91.10244 -204.143313) (xy 91.356428 -204.143313)
			(xy 91.356428 -204.079391) (xy 91.364439 -204.015973) (xy 91.380336 -203.954059) (xy 91.403868 -203.894626)
			(xy 91.434662 -203.838611) (xy 91.472235 -203.786896) (xy 91.515992 -203.740299) (xy 91.565245 -203.699554)
			(xy 91.619216 -203.665303) (xy 91.677055 -203.638086) (xy 91.737848 -203.618333) (xy 91.800638 -203.606355)
			(xy 91.864434 -203.602342) (xy 91.92823 -203.606355) (xy 91.99102 -203.618333) (xy 92.051813 -203.638086)
			(xy 92.109652 -203.665303) (xy 92.163623 -203.699554) (xy 92.212876 -203.740299) (xy 92.256633 -203.786896)
			(xy 92.294206 -203.838611) (xy 92.325 -203.894626) (xy 92.348532 -203.954059) (xy 92.364429 -204.015973)
			(xy 92.37244 -204.079391) (xy 92.372942 -204.111352) (xy 92.37244 -204.143313) (xy 92.626428 -204.143313)
			(xy 92.626428 -204.079391) (xy 92.634439 -204.015973) (xy 92.650336 -203.954059) (xy 92.673868 -203.894626)
			(xy 92.704662 -203.838611) (xy 92.742235 -203.786896) (xy 92.785992 -203.740299) (xy 92.835245 -203.699554)
			(xy 92.889216 -203.665303) (xy 92.947055 -203.638086) (xy 93.007848 -203.618333) (xy 93.070638 -203.606355)
			(xy 93.134434 -203.602342) (xy 93.19823 -203.606355) (xy 93.26102 -203.618333) (xy 93.321813 -203.638086)
			(xy 93.379652 -203.665303) (xy 93.433623 -203.699554) (xy 93.482876 -203.740299) (xy 93.526633 -203.786896)
			(xy 93.564206 -203.838611) (xy 93.595 -203.894626) (xy 93.618532 -203.954059) (xy 93.634429 -204.015973)
			(xy 93.64244 -204.079391) (xy 93.642942 -204.111352) (xy 93.64244 -204.143313) (xy 93.896428 -204.143313)
			(xy 93.896428 -204.079391) (xy 93.904439 -204.015973) (xy 93.920336 -203.954059) (xy 93.943868 -203.894626)
			(xy 93.974662 -203.838611) (xy 94.012235 -203.786896) (xy 94.055992 -203.740299) (xy 94.105245 -203.699554)
			(xy 94.159216 -203.665303) (xy 94.217055 -203.638086) (xy 94.277848 -203.618333) (xy 94.340638 -203.606355)
			(xy 94.404434 -203.602342) (xy 94.46823 -203.606355) (xy 94.53102 -203.618333) (xy 94.591813 -203.638086)
			(xy 94.649652 -203.665303) (xy 94.703623 -203.699554) (xy 94.752876 -203.740299) (xy 94.796633 -203.786896)
			(xy 94.834206 -203.838611) (xy 94.865 -203.894626) (xy 94.888532 -203.954059) (xy 94.904429 -204.015973)
			(xy 94.91244 -204.079391) (xy 94.912942 -204.111352) (xy 94.91244 -204.143313) (xy 95.166428 -204.143313)
			(xy 95.166428 -204.079391) (xy 95.174439 -204.015973) (xy 95.190336 -203.954059) (xy 95.213868 -203.894626)
			(xy 95.244662 -203.838611) (xy 95.282235 -203.786896) (xy 95.325992 -203.740299) (xy 95.375245 -203.699554)
			(xy 95.429216 -203.665303) (xy 95.487055 -203.638086) (xy 95.547848 -203.618333) (xy 95.610638 -203.606355)
			(xy 95.674434 -203.602342) (xy 95.73823 -203.606355) (xy 95.80102 -203.618333) (xy 95.861813 -203.638086)
			(xy 95.919652 -203.665303) (xy 95.973623 -203.699554) (xy 96.022876 -203.740299) (xy 96.066633 -203.786896)
			(xy 96.104206 -203.838611) (xy 96.135 -203.894626) (xy 96.158532 -203.954059) (xy 96.174429 -204.015973)
			(xy 96.18244 -204.079391) (xy 96.182942 -204.111352) (xy 96.18244 -204.143313) (xy 96.174429 -204.206731)
			(xy 96.158532 -204.268645) (xy 96.135 -204.328078) (xy 96.104206 -204.384093) (xy 96.066633 -204.435808)
			(xy 96.022876 -204.482405) (xy 95.973623 -204.52315) (xy 95.919652 -204.557401) (xy 95.861813 -204.584618)
			(xy 95.80102 -204.604371) (xy 95.73823 -204.616349) (xy 95.674434 -204.620363) (xy 95.610638 -204.616349)
			(xy 95.547848 -204.604371) (xy 95.487055 -204.584618) (xy 95.429216 -204.557401) (xy 95.375245 -204.52315)
			(xy 95.325992 -204.482405) (xy 95.282235 -204.435808) (xy 95.244662 -204.384093) (xy 95.213868 -204.328078)
			(xy 95.190336 -204.268645) (xy 95.174439 -204.206731) (xy 95.166428 -204.143313) (xy 94.91244 -204.143313)
			(xy 94.904429 -204.206731) (xy 94.888532 -204.268645) (xy 94.865 -204.328078) (xy 94.834206 -204.384093)
			(xy 94.796633 -204.435808) (xy 94.752876 -204.482405) (xy 94.703623 -204.52315) (xy 94.649652 -204.557401)
			(xy 94.591813 -204.584618) (xy 94.53102 -204.604371) (xy 94.46823 -204.616349) (xy 94.404434 -204.620363)
			(xy 94.340638 -204.616349) (xy 94.277848 -204.604371) (xy 94.217055 -204.584618) (xy 94.159216 -204.557401)
			(xy 94.105245 -204.52315) (xy 94.055992 -204.482405) (xy 94.012235 -204.435808) (xy 93.974662 -204.384093)
			(xy 93.943868 -204.328078) (xy 93.920336 -204.268645) (xy 93.904439 -204.206731) (xy 93.896428 -204.143313)
			(xy 93.64244 -204.143313) (xy 93.634429 -204.206731) (xy 93.618532 -204.268645) (xy 93.595 -204.328078)
			(xy 93.564206 -204.384093) (xy 93.526633 -204.435808) (xy 93.482876 -204.482405) (xy 93.433623 -204.52315)
			(xy 93.379652 -204.557401) (xy 93.321813 -204.584618) (xy 93.26102 -204.604371) (xy 93.19823 -204.616349)
			(xy 93.134434 -204.620363) (xy 93.070638 -204.616349) (xy 93.007848 -204.604371) (xy 92.947055 -204.584618)
			(xy 92.889216 -204.557401) (xy 92.835245 -204.52315) (xy 92.785992 -204.482405) (xy 92.742235 -204.435808)
			(xy 92.704662 -204.384093) (xy 92.673868 -204.328078) (xy 92.650336 -204.268645) (xy 92.634439 -204.206731)
			(xy 92.626428 -204.143313) (xy 92.37244 -204.143313) (xy 92.364429 -204.206731) (xy 92.348532 -204.268645)
			(xy 92.325 -204.328078) (xy 92.294206 -204.384093) (xy 92.256633 -204.435808) (xy 92.212876 -204.482405)
			(xy 92.163623 -204.52315) (xy 92.109652 -204.557401) (xy 92.051813 -204.584618) (xy 91.99102 -204.604371)
			(xy 91.92823 -204.616349) (xy 91.864434 -204.620363) (xy 91.800638 -204.616349) (xy 91.737848 -204.604371)
			(xy 91.677055 -204.584618) (xy 91.619216 -204.557401) (xy 91.565245 -204.52315) (xy 91.515992 -204.482405)
			(xy 91.472235 -204.435808) (xy 91.434662 -204.384093) (xy 91.403868 -204.328078) (xy 91.380336 -204.268645)
			(xy 91.364439 -204.206731) (xy 91.356428 -204.143313) (xy 91.10244 -204.143313) (xy 91.094429 -204.206731)
			(xy 91.078532 -204.268645) (xy 91.055 -204.328078) (xy 91.024206 -204.384093) (xy 90.986633 -204.435808)
			(xy 90.942876 -204.482405) (xy 90.893623 -204.52315) (xy 90.839652 -204.557401) (xy 90.781813 -204.584618)
			(xy 90.72102 -204.604371) (xy 90.65823 -204.616349) (xy 90.594434 -204.620363) (xy 90.530638 -204.616349)
			(xy 90.467848 -204.604371) (xy 90.407055 -204.584618) (xy 90.349216 -204.557401) (xy 90.295245 -204.52315)
			(xy 90.245992 -204.482405) (xy 90.202235 -204.435808) (xy 90.164662 -204.384093) (xy 90.133868 -204.328078)
			(xy 90.110336 -204.268645) (xy 90.094439 -204.206731) (xy 90.086428 -204.143313) (xy 89.83244 -204.143313)
			(xy 89.824429 -204.206731) (xy 89.808532 -204.268645) (xy 89.785 -204.328078) (xy 89.754206 -204.384093)
			(xy 89.716633 -204.435808) (xy 89.672876 -204.482405) (xy 89.623623 -204.52315) (xy 89.569652 -204.557401)
			(xy 89.511813 -204.584618) (xy 89.45102 -204.604371) (xy 89.38823 -204.616349) (xy 89.324434 -204.620363)
			(xy 89.260638 -204.616349) (xy 89.197848 -204.604371) (xy 89.137055 -204.584618) (xy 89.079216 -204.557401)
			(xy 89.025245 -204.52315) (xy 88.975992 -204.482405) (xy 88.932235 -204.435808) (xy 88.894662 -204.384093)
			(xy 88.863868 -204.328078) (xy 88.840336 -204.268645) (xy 88.824439 -204.206731) (xy 88.816428 -204.143313)
			(xy 62.37732 -204.143313) (xy 62.37732 -205.6407) (xy 70.978954 -205.6407) (xy 70.982969 -205.576896)
			(xy 70.994949 -205.514098) (xy 71.014706 -205.453298) (xy 71.041927 -205.395453) (xy 71.076184 -205.341476)
			(xy 71.116937 -205.292218) (xy 71.163542 -205.248457) (xy 71.215265 -205.210883) (xy 71.271289 -205.180088)
			(xy 71.330731 -205.156558) (xy 71.392654 -205.140664) (xy 71.456081 -205.132656) (xy 71.488046 -205.132178)
			(xy 71.518886 -205.132611) (xy 71.580113 -205.140077) (xy 71.639987 -205.154893) (xy 71.69763 -205.176842)
			(xy 71.752194 -205.205602) (xy 71.80288 -205.240751) (xy 71.848942 -205.281772) (xy 71.889705 -205.328063)
			(xy 71.924569 -205.378945) (xy 71.953024 -205.433669) (xy 71.97465 -205.491434) (xy 71.98233 -205.521306)
			(xy 71.984862 -205.530397) (xy 71.995567 -205.545925) (xy 72.003158 -205.551532) (xy 72.028558 -205.568804)
			(xy 72.036485 -205.573674) (xy 72.054603 -205.577837) (xy 72.063864 -205.576932) (xy 72.08099 -205.574771)
			(xy 72.115437 -205.57248) (xy 72.132698 -205.57236) (xy 72.164658 -205.572905) (xy 72.228075 -205.580916)
			(xy 72.289988 -205.596812) (xy 72.34942 -205.620343) (xy 72.405434 -205.651137) (xy 72.457148 -205.688708)
			(xy 72.503744 -205.732465) (xy 72.544489 -205.781717) (xy 72.578739 -205.835687) (xy 72.605956 -205.893524)
			(xy 72.625708 -205.954317) (xy 72.637686 -206.017105) (xy 72.6417 -206.0809) (xy 72.637686 -206.144695)
			(xy 72.625708 -206.207483) (xy 72.605956 -206.268276) (xy 72.593004 -206.2958) (xy 89.10542 -206.2958)
			(xy 89.109435 -206.231995) (xy 89.121414 -206.169197) (xy 89.14117 -206.108395) (xy 89.168391 -206.050549)
			(xy 89.202647 -205.99657) (xy 89.243398 -205.94731) (xy 89.290001 -205.903547) (xy 89.341723 -205.865969)
			(xy 89.397746 -205.83517) (xy 89.457187 -205.811636) (xy 89.51911 -205.795737) (xy 89.582537 -205.787725)
			(xy 89.614502 -205.787244) (xy 89.644167 -205.787692) (xy 89.703096 -205.794586) (xy 89.760822 -205.808293)
			(xy 89.81656 -205.828625) (xy 89.869553 -205.855307) (xy 89.91908 -205.887976) (xy 89.964467 -205.926187)
			(xy 89.985088 -205.947518) (xy 89.9922 -205.955138) (xy 90.011504 -205.96352) (xy 90.1065 -205.96352)
			(xy 90.125804 -205.955138) (xy 90.132916 -205.947518) (xy 90.15516 -205.924578) (xy 90.204406 -205.883862)
			(xy 90.258365 -205.849635) (xy 90.316188 -205.822439) (xy 90.376961 -205.802701) (xy 90.439729 -205.790732)
			(xy 90.503502 -205.786722) (xy 90.567275 -205.790732) (xy 90.630043 -205.802701) (xy 90.690816 -205.822439)
			(xy 90.748639 -205.849635) (xy 90.802598 -205.883862) (xy 90.851844 -205.924578) (xy 90.874088 -205.947518)
			(xy 90.8812 -205.955138) (xy 90.900504 -205.96352) (xy 90.9955 -205.96352) (xy 91.014804 -205.955138)
			(xy 91.021916 -205.947518) (xy 91.04252 -205.92617) (xy 91.087913 -205.887962) (xy 91.137444 -205.855295)
			(xy 91.190439 -205.828612) (xy 91.246178 -205.808277) (xy 91.303905 -205.794564) (xy 91.362835 -205.787661)
			(xy 91.392502 -205.787244) (xy 91.425903 -205.787747) (xy 91.492129 -205.796489) (xy 91.556639 -205.813834)
			(xy 91.61832 -205.839483) (xy 91.676108 -205.872994) (xy 91.729005 -205.913789) (xy 91.752928 -205.937104)
			(xy 91.760294 -205.944724) (xy 91.779852 -205.952598) (xy 91.875356 -205.94955) (xy 91.893898 -205.940914)
			(xy 91.90101 -205.93304) (xy 91.921747 -205.910372) (xy 91.967736 -205.869637) (xy 92.0183 -205.834742)
			(xy 92.0727 -205.806195) (xy 92.130145 -205.784412) (xy 92.189796 -205.769712) (xy 92.250784 -205.762307)
			(xy 92.281502 -205.761844) (xy 92.31346 -205.762442) (xy 92.376872 -205.770453) (xy 92.43878 -205.786348)
			(xy 92.498207 -205.809878) (xy 92.554217 -205.840669) (xy 92.605926 -205.878238) (xy 92.652518 -205.921992)
			(xy 92.69326 -205.97124) (xy 92.727508 -206.025206) (xy 92.754722 -206.083039) (xy 92.774473 -206.143826)
			(xy 92.786449 -206.20661) (xy 92.790463 -206.2704) (xy 92.786449 -206.33419) (xy 92.774473 -206.396974)
			(xy 92.754722 -206.457761) (xy 92.727508 -206.515594) (xy 92.69326 -206.56956) (xy 92.652518 -206.618808)
			(xy 92.605926 -206.662562) (xy 92.554217 -206.700131) (xy 92.498207 -206.730922) (xy 92.43878 -206.754452)
			(xy 92.376872 -206.770347) (xy 92.31346 -206.778358) (xy 92.281502 -206.77886) (xy 92.248101 -206.778353)
			(xy 92.181875 -206.769612) (xy 92.117365 -206.752268) (xy 92.055684 -206.726619) (xy 91.997897 -206.693109)
			(xy 91.944999 -206.652314) (xy 91.921076 -206.629) (xy 91.91371 -206.62138) (xy 91.894152 -206.613506)
			(xy 91.798648 -206.616554) (xy 91.780106 -206.62519) (xy 91.772994 -206.633064) (xy 91.752256 -206.65573)
			(xy 91.706267 -206.696465) (xy 91.655704 -206.731361) (xy 91.601303 -206.759908) (xy 91.543859 -206.781691)
			(xy 91.484208 -206.796392) (xy 91.42322 -206.803796) (xy 91.392502 -206.80426) (xy 91.362835 -206.80384)
			(xy 91.303904 -206.796944) (xy 91.246177 -206.783235) (xy 91.190438 -206.762899) (xy 91.137445 -206.736212)
			(xy 91.08792 -206.703538) (xy 91.042535 -206.66532) (xy 91.021916 -206.643986) (xy 91.014804 -206.636366)
			(xy 90.9955 -206.627984) (xy 90.900504 -206.627984) (xy 90.8812 -206.636366) (xy 90.874088 -206.643986)
			(xy 90.851844 -206.666926) (xy 90.802598 -206.707642) (xy 90.748639 -206.741869) (xy 90.690816 -206.769065)
			(xy 90.630043 -206.788803) (xy 90.567275 -206.800772) (xy 90.503502 -206.804782) (xy 90.439729 -206.800772)
			(xy 90.376961 -206.788803) (xy 90.316188 -206.769065) (xy 90.258365 -206.741869) (xy 90.204406 -206.707642)
			(xy 90.15516 -206.666926) (xy 90.132916 -206.643986) (xy 90.125804 -206.636366) (xy 90.1065 -206.627984)
			(xy 90.011504 -206.627984) (xy 89.9922 -206.636366) (xy 89.985088 -206.643986) (xy 89.964483 -206.665333)
			(xy 89.91909 -206.703541) (xy 89.869559 -206.736208) (xy 89.816564 -206.762891) (xy 89.760825 -206.783226)
			(xy 89.703099 -206.796939) (xy 89.644168 -206.803842) (xy 89.614502 -206.80426) (xy 89.582537 -206.803875)
			(xy 89.51911 -206.795863) (xy 89.457187 -206.779964) (xy 89.397746 -206.75643) (xy 89.341723 -206.725631)
			(xy 89.290001 -206.688053) (xy 89.243398 -206.64429) (xy 89.202647 -206.59503) (xy 89.168391 -206.541051)
			(xy 89.14117 -206.483205) (xy 89.121414 -206.422403) (xy 89.109435 -206.359605) (xy 89.10542 -206.2958)
			(xy 72.593004 -206.2958) (xy 72.578739 -206.326113) (xy 72.544489 -206.380083) (xy 72.503744 -206.429335)
			(xy 72.457148 -206.473092) (xy 72.405434 -206.510663) (xy 72.34942 -206.541457) (xy 72.289988 -206.564988)
			(xy 72.228075 -206.580884) (xy 72.164658 -206.588895) (xy 72.132698 -206.589376) (xy 72.101858 -206.588938)
			(xy 72.04063 -206.581477) (xy 71.980754 -206.566664) (xy 71.92311 -206.544717) (xy 71.868544 -206.515958)
			(xy 71.817857 -206.48081) (xy 71.771794 -206.439789) (xy 71.731032 -206.393496) (xy 71.696168 -206.342614)
			(xy 71.667716 -206.287887) (xy 71.646092 -206.230121) (xy 71.638414 -206.200248) (xy 71.635886 -206.191156)
			(xy 71.625177 -206.17563) (xy 71.617586 -206.170022) (xy 71.592186 -206.15275) (xy 71.584249 -206.147897)
			(xy 71.566139 -206.143725) (xy 71.55688 -206.144622) (xy 71.539754 -206.146788) (xy 71.505308 -206.149075)
			(xy 71.488046 -206.149194) (xy 71.456081 -206.148744) (xy 71.392654 -206.140736) (xy 71.330731 -206.124842)
			(xy 71.271289 -206.101312) (xy 71.215265 -206.070517) (xy 71.163542 -206.032943) (xy 71.116937 -205.989182)
			(xy 71.076184 -205.939924) (xy 71.041927 -205.885947) (xy 71.014706 -205.828102) (xy 70.994949 -205.767302)
			(xy 70.982969 -205.704504) (xy 70.978954 -205.6407) (xy 62.37732 -205.6407) (xy 62.37732 -209.023458)
			(xy 93.979238 -209.023458) (xy 93.97981 -208.988503) (xy 93.989376 -208.919249) (xy 94.008336 -208.851959)
			(xy 94.036333 -208.787899) (xy 94.072839 -208.728276) (xy 94.094554 -208.700878) (xy 94.099807 -208.693944)
			(xy 94.105643 -208.677568) (xy 94.105984 -208.668874) (xy 94.105984 -208.514442) (xy 94.105592 -208.50576)
			(xy 94.099754 -208.489401) (xy 94.094554 -208.482438) (xy 94.072852 -208.455031) (xy 94.036354 -208.395407)
			(xy 94.00836 -208.331348) (xy 93.989396 -208.264061) (xy 93.979821 -208.194812) (xy 93.979238 -208.159858)
			(xy 93.97975 -208.129142) (xy 93.987155 -208.068157) (xy 94.001851 -208.008509) (xy 94.023626 -207.951065)
			(xy 94.052161 -207.896662) (xy 94.087042 -207.846092) (xy 94.12776 -207.800092) (xy 94.150434 -207.779366)
			(xy 94.156916 -207.773119) (xy 94.165377 -207.757243) (xy 94.166944 -207.748378) (xy 94.171262 -207.718152)
			(xy 94.172138 -207.709332) (xy 94.16836 -207.692027) (xy 94.163896 -207.68437) (xy 94.150272 -207.661598)
			(xy 94.128786 -207.613075) (xy 94.114244 -207.562041) (xy 94.106927 -207.509481) (xy 94.106492 -207.482948)
			(xy 94.106978 -207.455697) (xy 94.114734 -207.401749) (xy 94.130089 -207.349454) (xy 94.152731 -207.299877)
			(xy 94.182197 -207.254027) (xy 94.217888 -207.212836) (xy 94.259079 -207.177145) (xy 94.304929 -207.147679)
			(xy 94.354506 -207.125037) (xy 94.406801 -207.109682) (xy 94.460749 -207.101926) (xy 94.515251 -207.101926)
			(xy 94.569199 -207.109682) (xy 94.621494 -207.125037) (xy 94.671071 -207.147679) (xy 94.716921 -207.177145)
			(xy 94.758112 -207.212836) (xy 94.793803 -207.254027) (xy 94.823269 -207.299877) (xy 94.845911 -207.349454)
			(xy 94.861266 -207.401749) (xy 94.869022 -207.455697) (xy 94.869508 -207.482948) (xy 94.869056 -207.509522)
			(xy 94.861698 -207.562157) (xy 94.847091 -207.613258) (xy 94.825517 -207.66183) (xy 94.81185 -207.684624)
			(xy 94.807465 -207.69231) (xy 94.803708 -207.70959) (xy 94.804484 -207.718406) (xy 94.808802 -207.748632)
			(xy 94.810378 -207.757493) (xy 94.818841 -207.773365) (xy 94.825312 -207.77962) (xy 94.847959 -207.80034)
			(xy 94.888629 -207.846318) (xy 94.923468 -207.896857) (xy 94.951968 -207.951224) (xy 94.973716 -208.008626)
			(xy 94.988394 -208.068229) (xy 94.99579 -208.129166) (xy 94.996254 -208.159858) (xy 94.995693 -208.194814)
			(xy 94.988767 -208.244948) (xy 97.281238 -208.244948) (xy 97.281647 -208.219369) (xy 97.288495 -208.168671)
			(xy 97.302049 -208.119341) (xy 97.322067 -208.072262) (xy 97.348189 -208.028275) (xy 97.379948 -207.988169)
			(xy 97.398078 -207.97012) (xy 97.404936 -207.963262) (xy 97.413064 -207.945736) (xy 97.417128 -207.856328)
			(xy 97.411032 -207.838548) (xy 97.404682 -207.830928) (xy 97.385401 -207.807813) (xy 97.351816 -207.757857)
			(xy 97.324364 -207.704285) (xy 97.30343 -207.647846) (xy 97.289307 -207.58933) (xy 97.282193 -207.529556)
			(xy 97.281746 -207.499458) (xy 97.282316 -207.464502) (xy 97.291882 -207.395249) (xy 97.310843 -207.327958)
			(xy 97.33884 -207.263898) (xy 97.375347 -207.204276) (xy 97.397062 -207.176878) (xy 97.402316 -207.169945)
			(xy 97.408151 -207.153568) (xy 97.408492 -207.144874) (xy 97.408492 -206.990442) (xy 97.408098 -206.98176)
			(xy 97.402261 -206.965402) (xy 97.397062 -206.958438) (xy 97.375361 -206.93103) (xy 97.338863 -206.871406)
			(xy 97.310868 -206.807348) (xy 97.291905 -206.740061) (xy 97.282329 -206.670812) (xy 97.281746 -206.635858)
			(xy 97.282315 -206.601743) (xy 97.291451 -206.534126) (xy 97.309553 -206.468341) (xy 97.336295 -206.405569)
			(xy 97.371197 -206.34694) (xy 97.391982 -206.319882) (xy 97.397395 -206.312399) (xy 97.403011 -206.294825)
			(xy 97.402904 -206.285592) (xy 97.401126 -206.254858) (xy 97.400258 -206.245891) (xy 97.393103 -206.229368)
			(xy 97.387156 -206.2226) (xy 97.367459 -206.201149) (xy 97.334103 -206.153415) (xy 97.308382 -206.101169)
			(xy 97.290894 -206.045622) (xy 97.282044 -205.988065) (xy 97.281492 -205.958948) (xy 97.281978 -205.931697)
			(xy 97.289734 -205.877749) (xy 97.305089 -205.825454) (xy 97.327731 -205.775877) (xy 97.357197 -205.730027)
			(xy 97.392888 -205.688836) (xy 97.434079 -205.653145) (xy 97.479929 -205.623679) (xy 97.529506 -205.601037)
			(xy 97.581801 -205.585682) (xy 97.635749 -205.577926) (xy 97.690251 -205.577926) (xy 97.744199 -205.585682)
			(xy 97.796494 -205.601037) (xy 97.846071 -205.623679) (xy 97.891921 -205.653145) (xy 97.933112 -205.688836)
			(xy 97.968803 -205.730027) (xy 97.998269 -205.775877) (xy 98.020911 -205.825454) (xy 98.036266 -205.877749)
			(xy 98.044022 -205.931697) (xy 98.044508 -205.958948) (xy 98.044088 -205.983848) (xy 98.037576 -206.03322)
			(xy 98.024695 -206.081326) (xy 98.015552 -206.10449) (xy 98.012405 -206.112988) (xy 98.011769 -206.131088)
			(xy 98.014282 -206.139796) (xy 98.024188 -206.169006) (xy 98.027438 -206.177531) (xy 98.038892 -206.191716)
			(xy 98.04654 -206.196692) (xy 98.074906 -206.213848) (xy 98.12734 -206.25441) (xy 98.174057 -206.301444)
			(xy 98.214264 -206.354151) (xy 98.247278 -206.411637) (xy 98.27254 -206.472927) (xy 98.289621 -206.536981)
			(xy 98.298231 -206.602712) (xy 98.298762 -206.635858) (xy 98.298199 -206.670814) (xy 98.288631 -206.740067)
			(xy 98.269669 -206.807358) (xy 98.24167 -206.871418) (xy 98.205162 -206.93104) (xy 98.183446 -206.958438)
			(xy 98.178227 -206.965395) (xy 98.172371 -206.981754) (xy 98.172016 -206.990442) (xy 98.172016 -207.144874)
			(xy 98.172401 -207.153557) (xy 98.178244 -207.169915) (xy 98.183446 -207.176878) (xy 98.205156 -207.20428)
			(xy 98.241652 -207.263905) (xy 98.269645 -207.327965) (xy 98.288607 -207.395253) (xy 98.29818 -207.464504)
			(xy 98.298762 -207.499458) (xy 98.298214 -207.532801) (xy 98.289498 -207.598915) (xy 98.272211 -207.663321)
			(xy 98.246649 -207.724913) (xy 98.213251 -207.782633) (xy 98.172591 -207.835489) (xy 98.125368 -207.882574)
			(xy 98.072393 -207.923078) (xy 98.043746 -207.940148) (xy 98.035667 -207.945299) (xy 98.023783 -207.960309)
			(xy 98.020632 -207.969358) (xy 97.997772 -208.046066) (xy 97.999296 -208.064862) (xy 98.003614 -208.073498)
			(xy 98.003614 -208.074006) (xy 98.016374 -208.100681) (xy 98.034453 -208.156977) (xy 98.043652 -208.215385)
			(xy 98.044254 -208.244948) (xy 98.043768 -208.272199) (xy 98.036012 -208.326147) (xy 98.020657 -208.378442)
			(xy 97.998015 -208.428019) (xy 97.968549 -208.473869) (xy 97.932858 -208.51506) (xy 97.891667 -208.550751)
			(xy 97.845817 -208.580217) (xy 97.79624 -208.602859) (xy 97.743945 -208.618214) (xy 97.689997 -208.62597)
			(xy 97.635495 -208.62597) (xy 97.581547 -208.618214) (xy 97.529252 -208.602859) (xy 97.479675 -208.580217)
			(xy 97.433825 -208.550751) (xy 97.392634 -208.51506) (xy 97.356943 -208.473869) (xy 97.327477 -208.428019)
			(xy 97.304835 -208.378442) (xy 97.28948 -208.326147) (xy 97.281724 -208.272199) (xy 97.281238 -208.244948)
			(xy 94.988767 -208.244948) (xy 94.986125 -208.264068) (xy 94.967162 -208.331358) (xy 94.939163 -208.395418)
			(xy 94.902654 -208.45504) (xy 94.880938 -208.482438) (xy 94.875719 -208.489394) (xy 94.869863 -208.505754)
			(xy 94.869508 -208.514442) (xy 94.869508 -208.668874) (xy 94.869895 -208.677557) (xy 94.875736 -208.693915)
			(xy 94.880938 -208.700878) (xy 94.902646 -208.72828) (xy 94.939144 -208.787906) (xy 94.967137 -208.851965)
			(xy 94.986098 -208.919254) (xy 94.995672 -208.988504) (xy 94.996254 -209.023458) (xy 94.995779 -209.05547)
			(xy 94.987735 -209.118988) (xy 94.971783 -209.180994) (xy 94.948175 -209.240507) (xy 94.917283 -209.296587)
			(xy 94.879597 -209.348345) (xy 94.835712 -209.394964) (xy 94.786323 -209.435706) (xy 94.759526 -209.453226)
			(xy 94.749875 -209.460025) (xy 94.737575 -209.480147) (xy 94.735904 -209.491834) (xy 94.729046 -209.572352)
			(xy 94.728625 -209.584068) (xy 94.737083 -209.605903) (xy 94.745302 -209.614262) (xy 94.764477 -209.632439)
			(xy 94.7982 -209.67311) (xy 94.825988 -209.718045) (xy 94.847311 -209.766385) (xy 94.861758 -209.817204)
			(xy 94.869056 -209.869531) (xy 94.869508 -209.895948) (xy 94.869009 -209.923317) (xy 94.861199 -209.977495)
			(xy 94.845718 -210.029997) (xy 94.822883 -210.079745) (xy 94.793166 -210.125713) (xy 94.775528 -210.146646)
			(xy 94.775274 -210.1469) (xy 94.769678 -210.15398) (xy 94.763438 -210.170902) (xy 94.763082 -210.17992)
			(xy 94.763082 -210.246976) (xy 94.763454 -210.255991) (xy 94.769692 -210.272908) (xy 94.775274 -210.279996)
			(xy 94.775528 -210.279996) (xy 94.775528 -210.28025) (xy 94.793161 -210.301187) (xy 94.822873 -210.347159)
			(xy 94.84571 -210.396905) (xy 94.861202 -210.449404) (xy 94.869033 -210.503579) (xy 94.869508 -210.530948)
			(xy 94.868932 -210.560386) (xy 94.859883 -210.618562) (xy 94.842009 -210.674659) (xy 94.815733 -210.727345)
			(xy 94.79915 -210.751674) (xy 94.798896 -210.751928) (xy 94.793901 -210.759886) (xy 94.789466 -210.778126)
			(xy 94.79026 -210.787488) (xy 94.799912 -210.865212) (xy 94.809056 -210.881976) (xy 94.816422 -210.888072)
			(xy 94.840181 -210.908866) (xy 94.88296 -210.955304) (xy 94.919665 -211.006678) (xy 94.949731 -211.062198)
			(xy 94.972696 -211.121012) (xy 94.988208 -211.182216) (xy 94.996028 -211.244869) (xy 94.996508 -211.276438)
			(xy 94.995895 -211.311403) (xy 94.986302 -211.380671) (xy 94.967301 -211.447969) (xy 94.939252 -211.512027)
			(xy 94.902685 -211.571633) (xy 94.880938 -211.599018) (xy 94.875653 -211.606007) (xy 94.869817 -211.622518)
			(xy 94.869508 -211.631276) (xy 94.869508 -211.7852) (xy 94.869871 -211.793947) (xy 94.875708 -211.810438)
			(xy 94.880938 -211.817458) (xy 94.902662 -211.84486) (xy 94.939216 -211.90447) (xy 94.967266 -211.968524)
			(xy 94.986281 -212.035815) (xy 94.995904 -212.105075) (xy 94.996508 -212.140038) (xy 94.996021 -212.170731)
			(xy 94.988644 -212.23167) (xy 94.973978 -212.291278) (xy 94.952238 -212.348684) (xy 94.923739 -212.403052)
			(xy 94.888897 -212.45359) (xy 94.848219 -212.499562) (xy 94.825566 -212.520276) (xy 94.819019 -212.526501)
			(xy 94.810425 -212.542377) (xy 94.808802 -212.551264) (xy 94.804738 -212.581236) (xy 94.803888 -212.590094)
			(xy 94.807515 -212.607501) (xy 94.81185 -212.615272) (xy 94.825512 -212.638068) (xy 94.847063 -212.686647)
			(xy 94.861668 -212.737745) (xy 94.869046 -212.790376) (xy 94.869508 -212.816948) (xy 94.869009 -212.844317)
			(xy 94.861199 -212.898495) (xy 94.845718 -212.950997) (xy 94.822883 -213.000745) (xy 94.793166 -213.046713)
			(xy 94.775528 -213.067646) (xy 94.775274 -213.0679) (xy 94.769678 -213.07498) (xy 94.763438 -213.091902)
			(xy 94.763082 -213.10092) (xy 94.763082 -213.167976) (xy 94.763454 -213.176991) (xy 94.769692 -213.193908)
			(xy 94.775274 -213.200996) (xy 94.775528 -213.200996) (xy 94.775528 -213.20125) (xy 94.793161 -213.222187)
			(xy 94.822873 -213.268159) (xy 94.84571 -213.317905) (xy 94.861202 -213.370404) (xy 94.869033 -213.424579)
			(xy 94.869508 -213.451948) (xy 94.869056 -213.478522) (xy 94.861698 -213.531157) (xy 94.847091 -213.582258)
			(xy 94.825517 -213.63083) (xy 94.81185 -213.653624) (xy 94.807433 -213.661366) (xy 94.803783 -213.678799)
			(xy 94.804738 -213.68766) (xy 94.808802 -213.717632) (xy 94.810453 -213.72651) (xy 94.819036 -213.742383)
			(xy 94.825566 -213.74862) (xy 94.848224 -213.769328) (xy 94.888891 -213.815309) (xy 94.923728 -213.865852)
			(xy 94.952226 -213.92022) (xy 94.973972 -213.977624) (xy 94.988649 -214.037228) (xy 94.996044 -214.098166)
			(xy 94.996508 -214.128858) (xy 94.995906 -214.163823) (xy 94.98631 -214.233092) (xy 94.967307 -214.30039)
			(xy 94.939256 -214.364448) (xy 94.902686 -214.424054) (xy 94.880938 -214.451438) (xy 94.875686 -214.458449)
			(xy 94.86983 -214.474943) (xy 94.869508 -214.483696) (xy 94.869508 -214.63762) (xy 94.869862 -214.646368)
			(xy 94.875705 -214.662859) (xy 94.880938 -214.669878) (xy 94.902671 -214.697273) (xy 94.939224 -214.756885)
			(xy 94.967271 -214.820941) (xy 94.986284 -214.888233) (xy 94.995905 -214.957495) (xy 94.996508 -214.992458)
			(xy 94.996038 -215.02403) (xy 94.988228 -215.086688) (xy 94.972724 -215.147898) (xy 94.949764 -215.206718)
			(xy 94.9197 -215.262245) (xy 94.882995 -215.313624) (xy 94.840214 -215.360065) (xy 94.816422 -215.380824)
			(xy 94.809056 -215.38692) (xy 94.799912 -215.403684) (xy 94.79026 -215.481408) (xy 94.789441 -215.490771)
			(xy 94.793884 -215.509016) (xy 94.798896 -215.516968) (xy 94.79915 -215.517222) (xy 94.81575 -215.541542)
			(xy 94.842041 -215.594226) (xy 94.859921 -215.650326) (xy 94.868965 -215.708508) (xy 94.869508 -215.737948)
			(xy 94.869022 -215.765199) (xy 94.861266 -215.819147) (xy 94.845911 -215.871442) (xy 94.823269 -215.921019)
			(xy 94.793803 -215.966869) (xy 94.758112 -216.00806) (xy 94.716921 -216.043751) (xy 94.671071 -216.073217)
			(xy 94.621494 -216.095859) (xy 94.569199 -216.111214) (xy 94.515251 -216.11897) (xy 94.460749 -216.11897)
			(xy 94.406801 -216.111214) (xy 94.354506 -216.095859) (xy 94.304929 -216.073217) (xy 94.259079 -216.043751)
			(xy 94.217888 -216.00806) (xy 94.182197 -215.966869) (xy 94.152731 -215.921019) (xy 94.130089 -215.871442)
			(xy 94.114734 -215.819147) (xy 94.106978 -215.765199) (xy 94.106492 -215.737948) (xy 94.107066 -215.70851)
			(xy 94.116115 -215.650334) (xy 94.13399 -215.594237) (xy 94.160267 -215.541551) (xy 94.17685 -215.517222)
			(xy 94.177104 -215.516968) (xy 94.182101 -215.509011) (xy 94.186534 -215.49077) (xy 94.18574 -215.481408)
			(xy 94.176088 -215.403684) (xy 94.166944 -215.38692) (xy 94.159578 -215.380824) (xy 94.135817 -215.360032)
			(xy 94.093038 -215.313594) (xy 94.056334 -215.26222) (xy 94.026268 -215.206699) (xy 94.003303 -215.147884)
			(xy 93.987791 -215.08668) (xy 93.979972 -215.024027) (xy 93.979492 -214.992458) (xy 93.980103 -214.957493)
			(xy 93.989697 -214.888225) (xy 94.008698 -214.820927) (xy 94.036747 -214.756869) (xy 94.073314 -214.697263)
			(xy 94.095062 -214.669878) (xy 94.100349 -214.66289) (xy 94.106184 -214.646379) (xy 94.106492 -214.63762)
			(xy 94.106492 -214.483696) (xy 94.106131 -214.474949) (xy 94.100293 -214.458458) (xy 94.095062 -214.451438)
			(xy 94.073336 -214.424038) (xy 94.036782 -214.364427) (xy 94.008733 -214.300373) (xy 93.989719 -214.233082)
			(xy 93.980096 -214.163821) (xy 93.979492 -214.128858) (xy 93.979977 -214.098165) (xy 93.987354 -214.037225)
			(xy 94.00202 -213.977618) (xy 94.023761 -213.920212) (xy 94.05226 -213.865844) (xy 94.087103 -213.815306)
			(xy 94.127781 -213.769334) (xy 94.150434 -213.74862) (xy 94.156982 -213.742396) (xy 94.165576 -213.726519)
			(xy 94.167198 -213.717632) (xy 94.171262 -213.68766) (xy 94.172114 -213.678802) (xy 94.168485 -213.661395)
			(xy 94.16415 -213.653624) (xy 94.150487 -213.630829) (xy 94.128936 -213.58225) (xy 94.114331 -213.531151)
			(xy 94.106954 -213.47852) (xy 94.106492 -213.451948) (xy 94.106988 -213.424579) (xy 94.114799 -213.370401)
			(xy 94.130281 -213.317898) (xy 94.153116 -213.268151) (xy 94.182834 -213.222183) (xy 94.200472 -213.20125)
			(xy 94.200726 -213.200996) (xy 94.206323 -213.193917) (xy 94.212563 -213.176994) (xy 94.212918 -213.167976)
			(xy 94.212918 -213.10092) (xy 94.212548 -213.091905) (xy 94.206309 -213.074988) (xy 94.200726 -213.0679)
			(xy 94.200472 -213.0679) (xy 94.200472 -213.067646) (xy 94.182837 -213.046711) (xy 94.153125 -213.000739)
			(xy 94.130289 -212.950992) (xy 94.114797 -212.898492) (xy 94.106967 -212.844317) (xy 94.106492 -212.816948)
			(xy 94.106943 -212.790374) (xy 94.114301 -212.737738) (xy 94.128909 -212.686638) (xy 94.150482 -212.638066)
			(xy 94.16415 -212.615272) (xy 94.168568 -212.607531) (xy 94.172218 -212.590097) (xy 94.171262 -212.581236)
			(xy 94.167198 -212.551264) (xy 94.165549 -212.542386) (xy 94.156965 -212.526512) (xy 94.150434 -212.520276)
			(xy 94.127774 -212.49957) (xy 94.087107 -212.453588) (xy 94.052271 -212.403046) (xy 94.023773 -212.348677)
			(xy 94.002027 -212.291273) (xy 93.98735 -212.231668) (xy 93.979956 -212.17073) (xy 93.979492 -212.140038)
			(xy 93.980091 -212.105073) (xy 93.989688 -212.035804) (xy 94.008692 -211.968506) (xy 94.036743 -211.904448)
			(xy 94.073313 -211.844842) (xy 94.095062 -211.817458) (xy 94.100315 -211.810448) (xy 94.106171 -211.793953)
			(xy 94.106492 -211.7852) (xy 94.106492 -211.631276) (xy 94.10614 -211.622528) (xy 94.100296 -211.606037)
			(xy 94.095062 -211.599018) (xy 94.073327 -211.571625) (xy 94.036774 -211.512012) (xy 94.008727 -211.447956)
			(xy 93.989715 -211.380663) (xy 93.980095 -211.311401) (xy 93.979492 -211.276438) (xy 93.979959 -211.244866)
			(xy 93.987769 -211.182208) (xy 94.003274 -211.120998) (xy 94.026235 -211.062178) (xy 94.056299 -211.006651)
			(xy 94.093004 -210.955272) (xy 94.135786 -210.908831) (xy 94.159578 -210.888072) (xy 94.166944 -210.881976)
			(xy 94.176088 -210.865212) (xy 94.18574 -210.787488) (xy 94.186562 -210.778126) (xy 94.182117 -210.75988)
			(xy 94.177104 -210.751928) (xy 94.17685 -210.751674) (xy 94.160248 -210.727355) (xy 94.133958 -210.67467)
			(xy 94.116078 -210.61857) (xy 94.107035 -210.560388) (xy 94.106492 -210.530948) (xy 94.106988 -210.503579)
			(xy 94.114799 -210.449401) (xy 94.130281 -210.396898) (xy 94.153116 -210.347151) (xy 94.182834 -210.301183)
			(xy 94.200472 -210.28025) (xy 94.200726 -210.279996) (xy 94.206323 -210.272917) (xy 94.212563 -210.255994)
			(xy 94.212918 -210.246976) (xy 94.212918 -210.17992) (xy 94.212548 -210.170905) (xy 94.206309 -210.153988)
			(xy 94.200726 -210.1469) (xy 94.200472 -210.1469) (xy 94.200472 -210.146646) (xy 94.182837 -210.125711)
			(xy 94.153125 -210.079739) (xy 94.130289 -210.029992) (xy 94.114797 -209.977492) (xy 94.106967 -209.923317)
			(xy 94.106492 -209.895948) (xy 94.106969 -209.869531) (xy 94.114253 -209.817201) (xy 94.12869 -209.766377)
			(xy 94.150002 -209.718032) (xy 94.177781 -209.67309) (xy 94.211497 -209.632411) (xy 94.230698 -209.614262)
			(xy 94.239334 -209.606388) (xy 94.24797 -209.58429) (xy 94.239842 -209.492088) (xy 94.238195 -209.480393)
			(xy 94.225884 -209.460269) (xy 94.21622 -209.45348) (xy 94.189395 -209.435959) (xy 94.139949 -209.39521)
			(xy 94.096014 -209.348572) (xy 94.058285 -209.296785) (xy 94.027359 -209.240669) (xy 94.003728 -209.181113)
			(xy 93.987764 -209.119061) (xy 93.979721 -209.055495) (xy 93.979238 -209.023458) (xy 62.37732 -209.023458)
			(xy 62.37732 -212.98027) (xy 78.81214 -212.98027) (xy 78.81617 -212.837935) (xy 78.828245 -212.696055)
			(xy 78.848328 -212.555087) (xy 78.876355 -212.41548) (xy 78.912235 -212.277682) (xy 78.955853 -212.142135)
			(xy 79.00707 -212.009273) (xy 79.065721 -211.879521) (xy 79.131619 -211.753295) (xy 79.204553 -211.630999)
			(xy 79.28429 -211.513026) (xy 79.370572 -211.399753) (xy 79.463125 -211.291542) (xy 79.561652 -211.188741)
			(xy 79.665837 -211.091679) (xy 79.775346 -211.000667) (xy 79.889829 -210.915995) (xy 80.008919 -210.837937)
			(xy 80.132234 -210.766741) (xy 80.25938 -210.702635) (xy 80.389949 -210.645826) (xy 80.523523 -210.596494)
			(xy 80.659674 -210.554798) (xy 80.797965 -210.520872) (xy 80.937955 -210.494824) (xy 81.079194 -210.476738)
			(xy 81.22123 -210.466671) (xy 81.363608 -210.464656) (xy 81.505872 -210.470699) (xy 81.647566 -210.484781)
			(xy 81.788236 -210.506857) (xy 81.927433 -210.536857) (xy 82.064709 -210.574683) (xy 82.199625 -210.620215)
			(xy 82.331749 -210.673306) (xy 82.460658 -210.733788) (xy 82.585939 -210.801466) (xy 82.70719 -210.876123)
			(xy 82.824023 -210.957521) (xy 82.936064 -211.045398) (xy 83.042954 -211.139473) (xy 83.144351 -211.239445)
			(xy 83.239929 -211.344993) (xy 83.329383 -211.455779) (xy 83.412425 -211.571448) (xy 83.488791 -211.691631)
			(xy 83.558235 -211.815941) (xy 83.620535 -211.943982) (xy 83.675491 -212.075341) (xy 83.722928 -212.2096)
			(xy 83.762692 -212.346327) (xy 83.794658 -212.485085) (xy 83.818723 -212.625429) (xy 83.834809 -212.76691)
			(xy 83.842864 -212.909074) (xy 83.843368 -212.98027) (xy 83.842864 -213.051466) (xy 83.834809 -213.19363)
			(xy 83.818723 -213.335111) (xy 83.794658 -213.475455) (xy 83.762692 -213.614213) (xy 83.722928 -213.75094)
			(xy 83.675491 -213.885199) (xy 83.620535 -214.016558) (xy 83.558235 -214.144599) (xy 83.488791 -214.268909)
			(xy 83.412425 -214.389092) (xy 83.329383 -214.504761) (xy 83.239929 -214.615547) (xy 83.144351 -214.721095)
			(xy 83.042954 -214.821067) (xy 82.936064 -214.915142) (xy 82.824023 -215.003019) (xy 82.70719 -215.084417)
			(xy 82.585939 -215.159074) (xy 82.460658 -215.226752) (xy 82.331749 -215.287234) (xy 82.199625 -215.340325)
			(xy 82.064709 -215.385857) (xy 81.927433 -215.423683) (xy 81.788236 -215.453683) (xy 81.647566 -215.475759)
			(xy 81.505872 -215.489841) (xy 81.363608 -215.495884) (xy 81.22123 -215.493869) (xy 81.079194 -215.483802)
			(xy 80.937955 -215.465716) (xy 80.797965 -215.439668) (xy 80.659674 -215.405742) (xy 80.523523 -215.364046)
			(xy 80.389949 -215.314714) (xy 80.25938 -215.257905) (xy 80.132234 -215.193799) (xy 80.008919 -215.122603)
			(xy 79.889829 -215.044545) (xy 79.775346 -214.959873) (xy 79.665837 -214.868861) (xy 79.561652 -214.771799)
			(xy 79.463125 -214.668998) (xy 79.370572 -214.560787) (xy 79.28429 -214.447514) (xy 79.204553 -214.329541)
			(xy 79.131619 -214.207245) (xy 79.065721 -214.081019) (xy 79.00707 -213.951267) (xy 78.955853 -213.818405)
			(xy 78.912235 -213.682858) (xy 78.876355 -213.54506) (xy 78.848328 -213.405453) (xy 78.828245 -213.264485)
			(xy 78.81617 -213.122605) (xy 78.81214 -212.98027) (xy 62.37732 -212.98027) (xy 62.37732 -215.857793)
			(xy 90.051884 -215.857793) (xy 90.051884 -215.793871) (xy 90.059895 -215.730453) (xy 90.075792 -215.668539)
			(xy 90.099324 -215.609106) (xy 90.130118 -215.553091) (xy 90.167691 -215.501376) (xy 90.211448 -215.454779)
			(xy 90.260701 -215.414034) (xy 90.314672 -215.379783) (xy 90.372511 -215.352566) (xy 90.433304 -215.332813)
			(xy 90.496094 -215.320835) (xy 90.55989 -215.316822) (xy 90.623686 -215.320835) (xy 90.686476 -215.332813)
			(xy 90.747269 -215.352566) (xy 90.805108 -215.379783) (xy 90.859079 -215.414034) (xy 90.908332 -215.454779)
			(xy 90.952089 -215.501376) (xy 90.989662 -215.553091) (xy 91.020456 -215.609106) (xy 91.043988 -215.668539)
			(xy 91.059885 -215.730453) (xy 91.067896 -215.793871) (xy 91.068398 -215.825832) (xy 91.067896 -215.857793)
			(xy 91.059885 -215.921211) (xy 91.043988 -215.983125) (xy 91.020456 -216.042558) (xy 90.989662 -216.098573)
			(xy 90.952089 -216.150288) (xy 90.908332 -216.196885) (xy 90.859079 -216.23763) (xy 90.805108 -216.271881)
			(xy 90.747269 -216.299098) (xy 90.686476 -216.318851) (xy 90.623686 -216.330829) (xy 90.55989 -216.334843)
			(xy 90.496094 -216.330829) (xy 90.433304 -216.318851) (xy 90.372511 -216.299098) (xy 90.314672 -216.271881)
			(xy 90.260701 -216.23763) (xy 90.211448 -216.196885) (xy 90.167691 -216.150288) (xy 90.130118 -216.098573)
			(xy 90.099324 -216.042558) (xy 90.075792 -215.983125) (xy 90.059895 -215.921211) (xy 90.051884 -215.857793)
			(xy 62.37732 -215.857793) (xy 62.37732 -216.583217) (xy 92.175832 -216.583217) (xy 92.175832 -216.519295)
			(xy 92.183843 -216.455877) (xy 92.19974 -216.393963) (xy 92.223272 -216.33453) (xy 92.254066 -216.278515)
			(xy 92.291639 -216.2268) (xy 92.335396 -216.180203) (xy 92.384649 -216.139458) (xy 92.43862 -216.105207)
			(xy 92.496459 -216.07799) (xy 92.557252 -216.058237) (xy 92.620042 -216.046259) (xy 92.683838 -216.042246)
			(xy 92.747634 -216.046259) (xy 92.810424 -216.058237) (xy 92.871217 -216.07799) (xy 92.929056 -216.105207)
			(xy 92.983027 -216.139458) (xy 93.03228 -216.180203) (xy 93.076037 -216.2268) (xy 93.11361 -216.278515)
			(xy 93.144404 -216.33453) (xy 93.167936 -216.393963) (xy 93.183833 -216.455877) (xy 93.191844 -216.519295)
			(xy 93.192346 -216.551256) (xy 93.191844 -216.583217) (xy 93.183833 -216.646635) (xy 93.167936 -216.708549)
			(xy 93.144404 -216.767982) (xy 93.11361 -216.823997) (xy 93.076037 -216.875712) (xy 93.03228 -216.922309)
			(xy 92.983027 -216.963054) (xy 92.929056 -216.997305) (xy 92.871217 -217.024522) (xy 92.810424 -217.044275)
			(xy 92.747634 -217.056253) (xy 92.683838 -217.060267) (xy 92.620042 -217.056253) (xy 92.557252 -217.044275)
			(xy 92.496459 -217.024522) (xy 92.43862 -216.997305) (xy 92.384649 -216.963054) (xy 92.335396 -216.922309)
			(xy 92.291639 -216.875712) (xy 92.254066 -216.823997) (xy 92.223272 -216.767982) (xy 92.19974 -216.708549)
			(xy 92.183843 -216.646635) (xy 92.175832 -216.583217) (xy 62.37732 -216.583217) (xy 62.37732 -218.3435)
			(xy 89.224369 -218.3435) (xy 89.228383 -218.279704) (xy 89.240361 -218.216913) (xy 89.260113 -218.156119)
			(xy 89.287329 -218.09828) (xy 89.32158 -218.044308) (xy 89.362324 -217.995054) (xy 89.408921 -217.951295)
			(xy 89.460634 -217.91372) (xy 89.516648 -217.882923) (xy 89.576081 -217.85939) (xy 89.637995 -217.84349)
			(xy 89.701413 -217.835476) (xy 89.733374 -217.834972) (xy 89.766077 -217.835474) (xy 89.830943 -217.843873)
			(xy 89.894195 -217.860522) (xy 89.95479 -217.885147) (xy 90.011725 -217.917341) (xy 90.064061 -217.956572)
			(xy 90.110933 -218.002191) (xy 90.131646 -218.027504) (xy 90.1319 -218.027758) (xy 90.139027 -218.035852)
			(xy 90.158243 -218.045592) (xy 90.168984 -218.046554) (xy 90.256614 -218.050872) (xy 90.27668 -218.042744)
			(xy 90.284554 -218.034616) (xy 90.310893 -218.008173) (xy 90.369936 -217.962521) (xy 90.402156 -217.943684)
			(xy 90.412156 -217.937337) (xy 90.425403 -217.917739) (xy 90.427556 -217.906092) (xy 90.440002 -217.813636)
			(xy 90.432128 -217.790776) (xy 90.423492 -217.782394) (xy 90.399788 -217.758434) (xy 90.358333 -217.70529)
			(xy 90.324264 -217.647135) (xy 90.298177 -217.584988) (xy 90.280531 -217.519939) (xy 90.271635 -217.453128)
			(xy 90.271092 -217.419428) (xy 90.271594 -217.387467) (xy 90.279605 -217.324049) (xy 90.295502 -217.262135)
			(xy 90.319034 -217.202702) (xy 90.349828 -217.146687) (xy 90.387401 -217.094972) (xy 90.431158 -217.048375)
			(xy 90.480411 -217.00763) (xy 90.534382 -216.973379) (xy 90.592221 -216.946162) (xy 90.653014 -216.926409)
			(xy 90.715804 -216.914431) (xy 90.7796 -216.910418) (xy 90.843396 -216.914431) (xy 90.906186 -216.926409)
			(xy 90.966979 -216.946162) (xy 91.024818 -216.973379) (xy 91.078789 -217.00763) (xy 91.128042 -217.048375)
			(xy 91.171799 -217.094972) (xy 91.209372 -217.146687) (xy 91.240166 -217.202702) (xy 91.263698 -217.262135)
			(xy 91.279595 -217.324049) (xy 91.287606 -217.387467) (xy 91.288108 -217.419428) (xy 91.287576 -217.453085)
			(xy 91.27868 -217.51981) (xy 91.26106 -217.584777) (xy 91.235024 -217.646853) (xy 91.201028 -217.704952)
			(xy 91.159664 -217.758059) (xy 91.137792 -217.779557) (xy 92.67545 -217.779557) (xy 92.67545 -217.715635)
			(xy 92.683461 -217.652217) (xy 92.699358 -217.590303) (xy 92.72289 -217.53087) (xy 92.753684 -217.474855)
			(xy 92.791257 -217.42314) (xy 92.835014 -217.376543) (xy 92.884267 -217.335798) (xy 92.938238 -217.301547)
			(xy 92.996077 -217.27433) (xy 93.05687 -217.254577) (xy 93.11966 -217.242599) (xy 93.183456 -217.238586)
			(xy 93.247252 -217.242599) (xy 93.310042 -217.254577) (xy 93.370835 -217.27433) (xy 93.428674 -217.301547)
			(xy 93.482645 -217.335798) (xy 93.531898 -217.376543) (xy 93.575655 -217.42314) (xy 93.613228 -217.474855)
			(xy 93.644022 -217.53087) (xy 93.667554 -217.590303) (xy 93.683451 -217.652217) (xy 93.691462 -217.715635)
			(xy 93.691964 -217.747596) (xy 93.691462 -217.779557) (xy 93.683451 -217.842975) (xy 93.667554 -217.904889)
			(xy 93.644022 -217.964322) (xy 93.613228 -218.020337) (xy 93.575655 -218.072052) (xy 93.531898 -218.118649)
			(xy 93.482645 -218.159394) (xy 93.428674 -218.193645) (xy 93.370835 -218.220862) (xy 93.310042 -218.240615)
			(xy 93.247252 -218.252593) (xy 93.183456 -218.256607) (xy 93.11966 -218.252593) (xy 93.05687 -218.240615)
			(xy 92.996077 -218.220862) (xy 92.938238 -218.193645) (xy 92.884267 -218.159394) (xy 92.835014 -218.118649)
			(xy 92.791257 -218.072052) (xy 92.753684 -218.020337) (xy 92.72289 -217.964322) (xy 92.699358 -217.904889)
			(xy 92.683461 -217.842975) (xy 92.67545 -217.779557) (xy 91.137792 -217.779557) (xy 91.111657 -217.805246)
			(xy 91.057845 -217.845688) (xy 91.028774 -217.862658) (xy 91.018782 -217.869014) (xy 91.005534 -217.888607)
			(xy 91.003374 -217.90025) (xy 90.990928 -217.992706) (xy 90.998802 -218.015566) (xy 91.007438 -218.023948)
			(xy 91.031101 -218.047947) (xy 91.072563 -218.101081) (xy 91.106639 -218.159227) (xy 91.132733 -218.221367)
			(xy 91.150387 -218.28641) (xy 91.159291 -218.353216) (xy 91.159838 -218.386914) (xy 91.159357 -218.417644)
			(xy 91.151948 -218.478656) (xy 91.137238 -218.53833) (xy 91.115444 -218.595797) (xy 91.086882 -218.650217)
			(xy 91.051969 -218.700798) (xy 91.011213 -218.746802) (xy 90.965211 -218.787559) (xy 90.914631 -218.822473)
			(xy 90.860211 -218.851037) (xy 90.802746 -218.872834) (xy 90.743072 -218.887545) (xy 90.68206 -218.894956)
			(xy 90.65133 -218.895422) (xy 90.618627 -218.894919) (xy 90.553761 -218.886521) (xy 90.490508 -218.869872)
			(xy 90.429914 -218.845247) (xy 90.372978 -218.813053) (xy 90.320643 -218.773822) (xy 90.273771 -218.728203)
			(xy 90.253058 -218.70289) (xy 90.252804 -218.702636) (xy 90.245677 -218.694543) (xy 90.226461 -218.684803)
			(xy 90.21572 -218.68384) (xy 90.12809 -218.679522) (xy 90.108024 -218.68765) (xy 90.10015 -218.695778)
			(xy 90.076081 -218.720011) (xy 90.022594 -218.762486) (xy 89.963904 -218.79742) (xy 89.901066 -218.824185)
			(xy 89.835211 -218.8423) (xy 89.767524 -218.851437) (xy 89.733374 -218.851988) (xy 89.701413 -218.851524)
			(xy 89.637995 -218.84351) (xy 89.576081 -218.82761) (xy 89.516648 -218.804077) (xy 89.460634 -218.77328)
			(xy 89.408921 -218.735705) (xy 89.362324 -218.691946) (xy 89.32158 -218.642692) (xy 89.287329 -218.58872)
			(xy 89.260113 -218.530881) (xy 89.240361 -218.470087) (xy 89.228383 -218.407296) (xy 89.224369 -218.3435)
			(xy 62.37732 -218.3435) (xy 62.37732 -218.942369) (xy 92.156528 -218.942369) (xy 92.156528 -218.878447)
			(xy 92.164539 -218.815029) (xy 92.180436 -218.753115) (xy 92.203968 -218.693682) (xy 92.234762 -218.637667)
			(xy 92.272335 -218.585952) (xy 92.316092 -218.539355) (xy 92.365345 -218.49861) (xy 92.419316 -218.464359)
			(xy 92.477155 -218.437142) (xy 92.537948 -218.417389) (xy 92.600738 -218.405411) (xy 92.664534 -218.401398)
			(xy 92.72833 -218.405411) (xy 92.79112 -218.417389) (xy 92.851913 -218.437142) (xy 92.909752 -218.464359)
			(xy 92.963723 -218.49861) (xy 93.012976 -218.539355) (xy 93.056733 -218.585952) (xy 93.094306 -218.637667)
			(xy 93.103328 -218.654079) (xy 93.376998 -218.654079) (xy 93.376998 -218.590157) (xy 93.385009 -218.526739)
			(xy 93.400906 -218.464825) (xy 93.424438 -218.405392) (xy 93.455232 -218.349377) (xy 93.492805 -218.297662)
			(xy 93.536562 -218.251065) (xy 93.585815 -218.21032) (xy 93.639786 -218.176069) (xy 93.697625 -218.148852)
			(xy 93.758418 -218.129099) (xy 93.821208 -218.117121) (xy 93.885004 -218.113108) (xy 93.9488 -218.117121)
			(xy 94.01159 -218.129099) (xy 94.072383 -218.148852) (xy 94.130222 -218.176069) (xy 94.184193 -218.21032)
			(xy 94.233446 -218.251065) (xy 94.277203 -218.297662) (xy 94.314776 -218.349377) (xy 94.34557 -218.405392)
			(xy 94.369102 -218.464825) (xy 94.384999 -218.526739) (xy 94.39301 -218.590157) (xy 94.393512 -218.622118)
			(xy 94.39301 -218.654079) (xy 94.384999 -218.717497) (xy 94.369102 -218.779411) (xy 94.34557 -218.838844)
			(xy 94.314776 -218.894859) (xy 94.277203 -218.946574) (xy 94.233446 -218.993171) (xy 94.184193 -219.033916)
			(xy 94.130222 -219.068167) (xy 94.072383 -219.095384) (xy 94.01159 -219.115137) (xy 93.9488 -219.127115)
			(xy 93.885004 -219.131129) (xy 93.821208 -219.127115) (xy 93.758418 -219.115137) (xy 93.697625 -219.095384)
			(xy 93.639786 -219.068167) (xy 93.585815 -219.033916) (xy 93.536562 -218.993171) (xy 93.492805 -218.946574)
			(xy 93.455232 -218.894859) (xy 93.424438 -218.838844) (xy 93.400906 -218.779411) (xy 93.385009 -218.717497)
			(xy 93.376998 -218.654079) (xy 93.103328 -218.654079) (xy 93.1251 -218.693682) (xy 93.148632 -218.753115)
			(xy 93.164529 -218.815029) (xy 93.17254 -218.878447) (xy 93.173042 -218.910408) (xy 93.17254 -218.942369)
			(xy 93.164529 -219.005787) (xy 93.148632 -219.067701) (xy 93.1251 -219.127134) (xy 93.094306 -219.183149)
			(xy 93.056733 -219.234864) (xy 93.012976 -219.281461) (xy 92.963723 -219.322206) (xy 92.909752 -219.356457)
			(xy 92.851913 -219.383674) (xy 92.79112 -219.403427) (xy 92.72833 -219.415405) (xy 92.664534 -219.419419)
			(xy 92.600738 -219.415405) (xy 92.537948 -219.403427) (xy 92.477155 -219.383674) (xy 92.419316 -219.356457)
			(xy 92.365345 -219.322206) (xy 92.316092 -219.281461) (xy 92.272335 -219.234864) (xy 92.234762 -219.183149)
			(xy 92.203968 -219.127134) (xy 92.180436 -219.067701) (xy 92.164539 -219.005787) (xy 92.156528 -218.942369)
			(xy 62.37732 -218.942369) (xy 62.37732 -221.804484) (xy 78.575166 -221.804484) (xy 78.579126 -221.75543)
			(xy 78.590903 -221.707646) (xy 78.610194 -221.66237) (xy 78.636497 -221.620774) (xy 78.669132 -221.583937)
			(xy 78.707253 -221.552812) (xy 78.749874 -221.528205) (xy 78.79589 -221.510753) (xy 78.844109 -221.500909)
			(xy 78.893284 -221.498928) (xy 78.942139 -221.50486) (xy 78.98941 -221.518552) (xy 79.033872 -221.53965)
			(xy 79.074375 -221.567606) (xy 79.109868 -221.601698) (xy 79.139433 -221.641042) (xy 79.162304 -221.684619)
			(xy 79.177888 -221.7313) (xy 79.185783 -221.779877) (xy 79.186278 -221.804484) (xy 79.51522 -221.804484)
			(xy 79.51918 -221.75543) (xy 79.530957 -221.707646) (xy 79.550248 -221.66237) (xy 79.576551 -221.620774)
			(xy 79.609186 -221.583937) (xy 79.647307 -221.552812) (xy 79.689928 -221.528205) (xy 79.735944 -221.510753)
			(xy 79.784163 -221.500909) (xy 79.833338 -221.498928) (xy 79.881402 -221.504764) (xy 84.682088 -221.504764)
			(xy 84.686048 -221.45571) (xy 84.697825 -221.407926) (xy 84.717116 -221.36265) (xy 84.743419 -221.321054)
			(xy 84.776054 -221.284217) (xy 84.814175 -221.253092) (xy 84.856796 -221.228485) (xy 84.902812 -221.211033)
			(xy 84.951031 -221.201189) (xy 85.000206 -221.199208) (xy 85.049061 -221.20514) (xy 85.096332 -221.218832)
			(xy 85.140794 -221.23993) (xy 85.181297 -221.267886) (xy 85.21679 -221.301978) (xy 85.246355 -221.341322)
			(xy 85.269226 -221.384899) (xy 85.28481 -221.43158) (xy 85.292705 -221.480157) (xy 85.2932 -221.504764)
			(xy 90.322158 -221.504764) (xy 90.326118 -221.45571) (xy 90.337895 -221.407926) (xy 90.357186 -221.36265)
			(xy 90.383489 -221.321054) (xy 90.416124 -221.284217) (xy 90.454245 -221.253092) (xy 90.496866 -221.228485)
			(xy 90.542882 -221.211033) (xy 90.591101 -221.201189) (xy 90.640276 -221.199208) (xy 90.689131 -221.20514)
			(xy 90.736402 -221.218832) (xy 90.780864 -221.23993) (xy 90.821367 -221.267886) (xy 90.85686 -221.301978)
			(xy 90.886425 -221.341322) (xy 90.909296 -221.384899) (xy 90.92488 -221.43158) (xy 90.932775 -221.480157)
			(xy 90.93327 -221.504764) (xy 90.932775 -221.529371) (xy 90.92488 -221.577948) (xy 90.909296 -221.624629)
			(xy 90.886425 -221.668206) (xy 90.85686 -221.70755) (xy 90.821367 -221.741642) (xy 90.780864 -221.769598)
			(xy 90.736402 -221.790696) (xy 90.689131 -221.804388) (xy 90.68834 -221.804484) (xy 93.615268 -221.804484)
			(xy 93.619228 -221.75543) (xy 93.631005 -221.707646) (xy 93.650296 -221.66237) (xy 93.676599 -221.620774)
			(xy 93.709234 -221.583937) (xy 93.747355 -221.552812) (xy 93.789976 -221.528205) (xy 93.835992 -221.510753)
			(xy 93.884211 -221.500909) (xy 93.933386 -221.498928) (xy 93.982241 -221.50486) (xy 94.029512 -221.518552)
			(xy 94.073974 -221.53965) (xy 94.114477 -221.567606) (xy 94.14997 -221.601698) (xy 94.179535 -221.641042)
			(xy 94.202406 -221.684619) (xy 94.21799 -221.7313) (xy 94.225885 -221.779877) (xy 94.22638 -221.804484)
			(xy 94.555322 -221.804484) (xy 94.559282 -221.75543) (xy 94.571059 -221.707646) (xy 94.59035 -221.66237)
			(xy 94.616653 -221.620774) (xy 94.649288 -221.583937) (xy 94.687409 -221.552812) (xy 94.73003 -221.528205)
			(xy 94.776046 -221.510753) (xy 94.824265 -221.500909) (xy 94.87344 -221.498928) (xy 94.922295 -221.50486)
			(xy 94.969566 -221.518552) (xy 95.014028 -221.53965) (xy 95.054531 -221.567606) (xy 95.090024 -221.601698)
			(xy 95.119589 -221.641042) (xy 95.14246 -221.684619) (xy 95.158044 -221.7313) (xy 95.165939 -221.779877)
			(xy 95.166434 -221.804484) (xy 95.495122 -221.804484) (xy 95.499082 -221.75543) (xy 95.510859 -221.707646)
			(xy 95.53015 -221.66237) (xy 95.556453 -221.620774) (xy 95.589088 -221.583937) (xy 95.627209 -221.552812)
			(xy 95.66983 -221.528205) (xy 95.715846 -221.510753) (xy 95.764065 -221.500909) (xy 95.81324 -221.498928)
			(xy 95.862095 -221.50486) (xy 95.909366 -221.518552) (xy 95.953828 -221.53965) (xy 95.994331 -221.567606)
			(xy 96.029824 -221.601698) (xy 96.059389 -221.641042) (xy 96.08226 -221.684619) (xy 96.097844 -221.7313)
			(xy 96.105739 -221.779877) (xy 96.106234 -221.804484) (xy 96.435176 -221.804484) (xy 96.439136 -221.75543)
			(xy 96.450913 -221.707646) (xy 96.470204 -221.66237) (xy 96.496507 -221.620774) (xy 96.529142 -221.583937)
			(xy 96.567263 -221.552812) (xy 96.609884 -221.528205) (xy 96.6559 -221.510753) (xy 96.704119 -221.500909)
			(xy 96.753294 -221.498928) (xy 96.802149 -221.50486) (xy 96.84942 -221.518552) (xy 96.893882 -221.53965)
			(xy 96.934385 -221.567606) (xy 96.969878 -221.601698) (xy 96.999443 -221.641042) (xy 97.022314 -221.684619)
			(xy 97.037898 -221.7313) (xy 97.045793 -221.779877) (xy 97.046288 -221.804484) (xy 97.37523 -221.804484)
			(xy 97.37919 -221.75543) (xy 97.390967 -221.707646) (xy 97.410258 -221.66237) (xy 97.436561 -221.620774)
			(xy 97.469196 -221.583937) (xy 97.507317 -221.552812) (xy 97.549938 -221.528205) (xy 97.595954 -221.510753)
			(xy 97.644173 -221.500909) (xy 97.693348 -221.498928) (xy 97.742203 -221.50486) (xy 97.789474 -221.518552)
			(xy 97.833936 -221.53965) (xy 97.874439 -221.567606) (xy 97.909932 -221.601698) (xy 97.939497 -221.641042)
			(xy 97.962368 -221.684619) (xy 97.977952 -221.7313) (xy 97.985847 -221.779877) (xy 97.986342 -221.804484)
			(xy 99.255338 -221.804484) (xy 99.259298 -221.75543) (xy 99.271075 -221.707646) (xy 99.290366 -221.66237)
			(xy 99.316669 -221.620774) (xy 99.349304 -221.583937) (xy 99.387425 -221.552812) (xy 99.430046 -221.528205)
			(xy 99.476062 -221.510753) (xy 99.524281 -221.500909) (xy 99.573456 -221.498928) (xy 99.622311 -221.50486)
			(xy 99.669582 -221.518552) (xy 99.714044 -221.53965) (xy 99.754547 -221.567606) (xy 99.79004 -221.601698)
			(xy 99.819605 -221.641042) (xy 99.842476 -221.684619) (xy 99.85806 -221.7313) (xy 99.865955 -221.779877)
			(xy 99.86645 -221.804484) (xy 100.195138 -221.804484) (xy 100.199098 -221.75543) (xy 100.210875 -221.707646)
			(xy 100.230166 -221.66237) (xy 100.256469 -221.620774) (xy 100.289104 -221.583937) (xy 100.327225 -221.552812)
			(xy 100.369846 -221.528205) (xy 100.415862 -221.510753) (xy 100.464081 -221.500909) (xy 100.513256 -221.498928)
			(xy 100.562111 -221.50486) (xy 100.609382 -221.518552) (xy 100.653844 -221.53965) (xy 100.694347 -221.567606)
			(xy 100.72984 -221.601698) (xy 100.759405 -221.641042) (xy 100.782276 -221.684619) (xy 100.79786 -221.7313)
			(xy 100.805755 -221.779877) (xy 100.80625 -221.804484) (xy 101.135192 -221.804484) (xy 101.139152 -221.75543)
			(xy 101.150929 -221.707646) (xy 101.17022 -221.66237) (xy 101.196523 -221.620774) (xy 101.229158 -221.583937)
			(xy 101.267279 -221.552812) (xy 101.3099 -221.528205) (xy 101.355916 -221.510753) (xy 101.404135 -221.500909)
			(xy 101.45331 -221.498928) (xy 101.502165 -221.50486) (xy 101.549436 -221.518552) (xy 101.593898 -221.53965)
			(xy 101.634401 -221.567606) (xy 101.669894 -221.601698) (xy 101.699459 -221.641042) (xy 101.72233 -221.684619)
			(xy 101.737914 -221.7313) (xy 101.745809 -221.779877) (xy 101.746304 -221.804484) (xy 102.075246 -221.804484)
			(xy 102.079206 -221.75543) (xy 102.090983 -221.707646) (xy 102.110274 -221.66237) (xy 102.136577 -221.620774)
			(xy 102.169212 -221.583937) (xy 102.207333 -221.552812) (xy 102.249954 -221.528205) (xy 102.29597 -221.510753)
			(xy 102.344189 -221.500909) (xy 102.393364 -221.498928) (xy 102.442219 -221.50486) (xy 102.48949 -221.518552)
			(xy 102.533952 -221.53965) (xy 102.574455 -221.567606) (xy 102.609948 -221.601698) (xy 102.639513 -221.641042)
			(xy 102.662384 -221.684619) (xy 102.677968 -221.7313) (xy 102.685863 -221.779877) (xy 102.686358 -221.804484)
			(xy 103.955354 -221.804484) (xy 103.959314 -221.75543) (xy 103.971091 -221.707646) (xy 103.990382 -221.66237)
			(xy 104.016685 -221.620774) (xy 104.04932 -221.583937) (xy 104.087441 -221.552812) (xy 104.130062 -221.528205)
			(xy 104.176078 -221.510753) (xy 104.224297 -221.500909) (xy 104.273472 -221.498928) (xy 104.322327 -221.50486)
			(xy 104.369598 -221.518552) (xy 104.41406 -221.53965) (xy 104.454563 -221.567606) (xy 104.490056 -221.601698)
			(xy 104.519621 -221.641042) (xy 104.542492 -221.684619) (xy 104.558076 -221.7313) (xy 104.565971 -221.779877)
			(xy 104.566466 -221.804484) (xy 104.895154 -221.804484) (xy 104.899114 -221.75543) (xy 104.910891 -221.707646)
			(xy 104.930182 -221.66237) (xy 104.956485 -221.620774) (xy 104.98912 -221.583937) (xy 105.027241 -221.552812)
			(xy 105.069862 -221.528205) (xy 105.115878 -221.510753) (xy 105.164097 -221.500909) (xy 105.213272 -221.498928)
			(xy 105.262127 -221.50486) (xy 105.309398 -221.518552) (xy 105.35386 -221.53965) (xy 105.394363 -221.567606)
			(xy 105.429856 -221.601698) (xy 105.459421 -221.641042) (xy 105.482292 -221.684619) (xy 105.497876 -221.7313)
			(xy 105.505771 -221.779877) (xy 105.506266 -221.804484) (xy 106.775262 -221.804484) (xy 106.779222 -221.75543)
			(xy 106.790999 -221.707646) (xy 106.81029 -221.66237) (xy 106.836593 -221.620774) (xy 106.869228 -221.583937)
			(xy 106.907349 -221.552812) (xy 106.94997 -221.528205) (xy 106.995986 -221.510753) (xy 107.044205 -221.500909)
			(xy 107.09338 -221.498928) (xy 107.142235 -221.50486) (xy 107.189506 -221.518552) (xy 107.233968 -221.53965)
			(xy 107.274471 -221.567606) (xy 107.309964 -221.601698) (xy 107.339529 -221.641042) (xy 107.3624 -221.684619)
			(xy 107.377984 -221.7313) (xy 107.385879 -221.779877) (xy 107.386374 -221.804484) (xy 107.385879 -221.829091)
			(xy 107.377984 -221.877668) (xy 107.3624 -221.924349) (xy 107.339529 -221.967926) (xy 107.309964 -222.00727)
			(xy 107.274471 -222.041362) (xy 107.233968 -222.069318) (xy 107.189506 -222.090416) (xy 107.142235 -222.104108)
			(xy 107.09338 -222.11004) (xy 107.044205 -222.108059) (xy 106.995986 -222.098215) (xy 106.94997 -222.080763)
			(xy 106.907349 -222.056156) (xy 106.869228 -222.025031) (xy 106.836593 -221.988194) (xy 106.81029 -221.946598)
			(xy 106.790999 -221.901322) (xy 106.779222 -221.853538) (xy 106.775262 -221.804484) (xy 105.506266 -221.804484)
			(xy 105.505771 -221.829091) (xy 105.497876 -221.877668) (xy 105.482292 -221.924349) (xy 105.459421 -221.967926)
			(xy 105.429856 -222.00727) (xy 105.394363 -222.041362) (xy 105.35386 -222.069318) (xy 105.309398 -222.090416)
			(xy 105.262127 -222.104108) (xy 105.213272 -222.11004) (xy 105.164097 -222.108059) (xy 105.115878 -222.098215)
			(xy 105.069862 -222.080763) (xy 105.027241 -222.056156) (xy 104.98912 -222.025031) (xy 104.956485 -221.988194)
			(xy 104.930182 -221.946598) (xy 104.910891 -221.901322) (xy 104.899114 -221.853538) (xy 104.895154 -221.804484)
			(xy 104.566466 -221.804484) (xy 104.565971 -221.829091) (xy 104.558076 -221.877668) (xy 104.542492 -221.924349)
			(xy 104.519621 -221.967926) (xy 104.490056 -222.00727) (xy 104.454563 -222.041362) (xy 104.41406 -222.069318)
			(xy 104.369598 -222.090416) (xy 104.322327 -222.104108) (xy 104.273472 -222.11004) (xy 104.224297 -222.108059)
			(xy 104.176078 -222.098215) (xy 104.130062 -222.080763) (xy 104.087441 -222.056156) (xy 104.04932 -222.025031)
			(xy 104.016685 -221.988194) (xy 103.990382 -221.946598) (xy 103.971091 -221.901322) (xy 103.959314 -221.853538)
			(xy 103.955354 -221.804484) (xy 102.686358 -221.804484) (xy 102.685863 -221.829091) (xy 102.677968 -221.877668)
			(xy 102.662384 -221.924349) (xy 102.639513 -221.967926) (xy 102.609948 -222.00727) (xy 102.574455 -222.041362)
			(xy 102.533952 -222.069318) (xy 102.48949 -222.090416) (xy 102.442219 -222.104108) (xy 102.393364 -222.11004)
			(xy 102.344189 -222.108059) (xy 102.29597 -222.098215) (xy 102.249954 -222.080763) (xy 102.207333 -222.056156)
			(xy 102.169212 -222.025031) (xy 102.136577 -221.988194) (xy 102.110274 -221.946598) (xy 102.090983 -221.901322)
			(xy 102.079206 -221.853538) (xy 102.075246 -221.804484) (xy 101.746304 -221.804484) (xy 101.745809 -221.829091)
			(xy 101.737914 -221.877668) (xy 101.72233 -221.924349) (xy 101.699459 -221.967926) (xy 101.669894 -222.00727)
			(xy 101.634401 -222.041362) (xy 101.593898 -222.069318) (xy 101.549436 -222.090416) (xy 101.502165 -222.104108)
			(xy 101.45331 -222.11004) (xy 101.404135 -222.108059) (xy 101.355916 -222.098215) (xy 101.3099 -222.080763)
			(xy 101.267279 -222.056156) (xy 101.229158 -222.025031) (xy 101.196523 -221.988194) (xy 101.17022 -221.946598)
			(xy 101.150929 -221.901322) (xy 101.139152 -221.853538) (xy 101.135192 -221.804484) (xy 100.80625 -221.804484)
			(xy 100.805755 -221.829091) (xy 100.79786 -221.877668) (xy 100.782276 -221.924349) (xy 100.759405 -221.967926)
			(xy 100.72984 -222.00727) (xy 100.694347 -222.041362) (xy 100.653844 -222.069318) (xy 100.609382 -222.090416)
			(xy 100.562111 -222.104108) (xy 100.513256 -222.11004) (xy 100.464081 -222.108059) (xy 100.415862 -222.098215)
			(xy 100.369846 -222.080763) (xy 100.327225 -222.056156) (xy 100.289104 -222.025031) (xy 100.256469 -221.988194)
			(xy 100.230166 -221.946598) (xy 100.210875 -221.901322) (xy 100.199098 -221.853538) (xy 100.195138 -221.804484)
			(xy 99.86645 -221.804484) (xy 99.865955 -221.829091) (xy 99.85806 -221.877668) (xy 99.842476 -221.924349)
			(xy 99.819605 -221.967926) (xy 99.79004 -222.00727) (xy 99.754547 -222.041362) (xy 99.714044 -222.069318)
			(xy 99.669582 -222.090416) (xy 99.622311 -222.104108) (xy 99.573456 -222.11004) (xy 99.524281 -222.108059)
			(xy 99.476062 -222.098215) (xy 99.430046 -222.080763) (xy 99.387425 -222.056156) (xy 99.349304 -222.025031)
			(xy 99.316669 -221.988194) (xy 99.290366 -221.946598) (xy 99.271075 -221.901322) (xy 99.259298 -221.853538)
			(xy 99.255338 -221.804484) (xy 97.986342 -221.804484) (xy 97.985847 -221.829091) (xy 97.977952 -221.877668)
			(xy 97.962368 -221.924349) (xy 97.939497 -221.967926) (xy 97.909932 -222.00727) (xy 97.874439 -222.041362)
			(xy 97.833936 -222.069318) (xy 97.789474 -222.090416) (xy 97.742203 -222.104108) (xy 97.693348 -222.11004)
			(xy 97.644173 -222.108059) (xy 97.595954 -222.098215) (xy 97.549938 -222.080763) (xy 97.507317 -222.056156)
			(xy 97.469196 -222.025031) (xy 97.436561 -221.988194) (xy 97.410258 -221.946598) (xy 97.390967 -221.901322)
			(xy 97.37919 -221.853538) (xy 97.37523 -221.804484) (xy 97.046288 -221.804484) (xy 97.045793 -221.829091)
			(xy 97.037898 -221.877668) (xy 97.022314 -221.924349) (xy 96.999443 -221.967926) (xy 96.969878 -222.00727)
			(xy 96.934385 -222.041362) (xy 96.893882 -222.069318) (xy 96.84942 -222.090416) (xy 96.802149 -222.104108)
			(xy 96.753294 -222.11004) (xy 96.704119 -222.108059) (xy 96.6559 -222.098215) (xy 96.609884 -222.080763)
			(xy 96.567263 -222.056156) (xy 96.529142 -222.025031) (xy 96.496507 -221.988194) (xy 96.470204 -221.946598)
			(xy 96.450913 -221.901322) (xy 96.439136 -221.853538) (xy 96.435176 -221.804484) (xy 96.106234 -221.804484)
			(xy 96.105739 -221.829091) (xy 96.097844 -221.877668) (xy 96.08226 -221.924349) (xy 96.059389 -221.967926)
			(xy 96.029824 -222.00727) (xy 95.994331 -222.041362) (xy 95.953828 -222.069318) (xy 95.909366 -222.090416)
			(xy 95.862095 -222.104108) (xy 95.81324 -222.11004) (xy 95.764065 -222.108059) (xy 95.715846 -222.098215)
			(xy 95.66983 -222.080763) (xy 95.627209 -222.056156) (xy 95.589088 -222.025031) (xy 95.556453 -221.988194)
			(xy 95.53015 -221.946598) (xy 95.510859 -221.901322) (xy 95.499082 -221.853538) (xy 95.495122 -221.804484)
			(xy 95.166434 -221.804484) (xy 95.165939 -221.829091) (xy 95.158044 -221.877668) (xy 95.14246 -221.924349)
			(xy 95.119589 -221.967926) (xy 95.090024 -222.00727) (xy 95.054531 -222.041362) (xy 95.014028 -222.069318)
			(xy 94.969566 -222.090416) (xy 94.922295 -222.104108) (xy 94.87344 -222.11004) (xy 94.824265 -222.108059)
			(xy 94.776046 -222.098215) (xy 94.73003 -222.080763) (xy 94.687409 -222.056156) (xy 94.649288 -222.025031)
			(xy 94.616653 -221.988194) (xy 94.59035 -221.946598) (xy 94.571059 -221.901322) (xy 94.559282 -221.853538)
			(xy 94.555322 -221.804484) (xy 94.22638 -221.804484) (xy 94.225885 -221.829091) (xy 94.21799 -221.877668)
			(xy 94.202406 -221.924349) (xy 94.179535 -221.967926) (xy 94.14997 -222.00727) (xy 94.114477 -222.041362)
			(xy 94.073974 -222.069318) (xy 94.029512 -222.090416) (xy 93.982241 -222.104108) (xy 93.933386 -222.11004)
			(xy 93.884211 -222.108059) (xy 93.835992 -222.098215) (xy 93.789976 -222.080763) (xy 93.747355 -222.056156)
			(xy 93.709234 -222.025031) (xy 93.676599 -221.988194) (xy 93.650296 -221.946598) (xy 93.631005 -221.901322)
			(xy 93.619228 -221.853538) (xy 93.615268 -221.804484) (xy 90.68834 -221.804484) (xy 90.640276 -221.81032)
			(xy 90.591101 -221.808339) (xy 90.542882 -221.798495) (xy 90.496866 -221.781043) (xy 90.454245 -221.756436)
			(xy 90.416124 -221.725311) (xy 90.383489 -221.688474) (xy 90.357186 -221.646878) (xy 90.337895 -221.601602)
			(xy 90.326118 -221.553818) (xy 90.322158 -221.504764) (xy 85.2932 -221.504764) (xy 85.292705 -221.529371)
			(xy 85.28481 -221.577948) (xy 85.269226 -221.624629) (xy 85.246355 -221.668206) (xy 85.21679 -221.70755)
			(xy 85.181297 -221.741642) (xy 85.140794 -221.769598) (xy 85.096332 -221.790696) (xy 85.049061 -221.804388)
			(xy 85.000206 -221.81032) (xy 84.951031 -221.808339) (xy 84.902812 -221.798495) (xy 84.856796 -221.781043)
			(xy 84.814175 -221.756436) (xy 84.776054 -221.725311) (xy 84.743419 -221.688474) (xy 84.717116 -221.646878)
			(xy 84.697825 -221.601602) (xy 84.686048 -221.553818) (xy 84.682088 -221.504764) (xy 79.881402 -221.504764)
			(xy 79.882193 -221.50486) (xy 79.929464 -221.518552) (xy 79.973926 -221.53965) (xy 80.014429 -221.567606)
			(xy 80.049922 -221.601698) (xy 80.079487 -221.641042) (xy 80.102358 -221.684619) (xy 80.117942 -221.7313)
			(xy 80.125837 -221.779877) (xy 80.126332 -221.804484) (xy 80.125837 -221.829091) (xy 80.117942 -221.877668)
			(xy 80.102358 -221.924349) (xy 80.079487 -221.967926) (xy 80.049922 -222.00727) (xy 80.014429 -222.041362)
			(xy 79.973926 -222.069318) (xy 79.929464 -222.090416) (xy 79.882193 -222.104108) (xy 79.833338 -222.11004)
			(xy 79.784163 -222.108059) (xy 79.735944 -222.098215) (xy 79.689928 -222.080763) (xy 79.647307 -222.056156)
			(xy 79.609186 -222.025031) (xy 79.576551 -221.988194) (xy 79.550248 -221.946598) (xy 79.530957 -221.901322)
			(xy 79.51918 -221.853538) (xy 79.51522 -221.804484) (xy 79.186278 -221.804484) (xy 79.185783 -221.829091)
			(xy 79.177888 -221.877668) (xy 79.162304 -221.924349) (xy 79.139433 -221.967926) (xy 79.109868 -222.00727)
			(xy 79.074375 -222.041362) (xy 79.033872 -222.069318) (xy 78.98941 -222.090416) (xy 78.942139 -222.104108)
			(xy 78.893284 -222.11004) (xy 78.844109 -222.108059) (xy 78.79589 -222.098215) (xy 78.749874 -222.080763)
			(xy 78.707253 -222.056156) (xy 78.669132 -222.025031) (xy 78.636497 -221.988194) (xy 78.610194 -221.946598)
			(xy 78.590903 -221.901322) (xy 78.579126 -221.853538) (xy 78.575166 -221.804484) (xy 62.37732 -221.804484)
			(xy 62.37732 -222.61449) (xy 80.925174 -222.61449) (xy 80.929134 -222.565436) (xy 80.940911 -222.517652)
			(xy 80.960202 -222.472376) (xy 80.986505 -222.43078) (xy 81.01914 -222.393943) (xy 81.057261 -222.362818)
			(xy 81.099882 -222.338211) (xy 81.145898 -222.320759) (xy 81.194117 -222.310915) (xy 81.243292 -222.308934)
			(xy 81.292147 -222.314866) (xy 81.339418 -222.328558) (xy 81.38388 -222.349656) (xy 81.424383 -222.377612)
			(xy 81.459876 -222.411704) (xy 81.489441 -222.451048) (xy 81.512312 -222.494625) (xy 81.527896 -222.541306)
			(xy 81.535791 -222.589883) (xy 81.536286 -222.61449) (xy 82.805282 -222.61449) (xy 82.809242 -222.565436)
			(xy 82.821019 -222.517652) (xy 82.84031 -222.472376) (xy 82.866613 -222.43078) (xy 82.899248 -222.393943)
			(xy 82.937369 -222.362818) (xy 82.97999 -222.338211) (xy 83.026006 -222.320759) (xy 83.074225 -222.310915)
			(xy 83.1234 -222.308934) (xy 83.172255 -222.314866) (xy 83.219526 -222.328558) (xy 83.263988 -222.349656)
			(xy 83.304491 -222.377612) (xy 83.339984 -222.411704) (xy 83.369549 -222.451048) (xy 83.39242 -222.494625)
			(xy 83.408004 -222.541306) (xy 83.415899 -222.589883) (xy 83.416394 -222.61449) (xy 91.26526 -222.61449)
			(xy 91.26922 -222.565436) (xy 91.280997 -222.517652) (xy 91.300288 -222.472376) (xy 91.326591 -222.43078)
			(xy 91.359226 -222.393943) (xy 91.397347 -222.362818) (xy 91.439968 -222.338211) (xy 91.485984 -222.320759)
			(xy 91.534203 -222.310915) (xy 91.583378 -222.308934) (xy 91.632233 -222.314866) (xy 91.679504 -222.328558)
			(xy 91.723966 -222.349656) (xy 91.764469 -222.377612) (xy 91.799962 -222.411704) (xy 91.829527 -222.451048)
			(xy 91.852398 -222.494625) (xy 91.867982 -222.541306) (xy 91.875877 -222.589883) (xy 91.876372 -222.61449)
			(xy 92.205314 -222.61449) (xy 92.209274 -222.565436) (xy 92.221051 -222.517652) (xy 92.240342 -222.472376)
			(xy 92.266645 -222.43078) (xy 92.29928 -222.393943) (xy 92.337401 -222.362818) (xy 92.380022 -222.338211)
			(xy 92.426038 -222.320759) (xy 92.474257 -222.310915) (xy 92.523432 -222.308934) (xy 92.572287 -222.314866)
			(xy 92.619558 -222.328558) (xy 92.66402 -222.349656) (xy 92.704523 -222.377612) (xy 92.740016 -222.411704)
			(xy 92.769581 -222.451048) (xy 92.792452 -222.494625) (xy 92.808036 -222.541306) (xy 92.815931 -222.589883)
			(xy 92.816426 -222.61449) (xy 95.025222 -222.61449) (xy 95.029182 -222.565436) (xy 95.040959 -222.517652)
			(xy 95.06025 -222.472376) (xy 95.086553 -222.43078) (xy 95.119188 -222.393943) (xy 95.157309 -222.362818)
			(xy 95.19993 -222.338211) (xy 95.245946 -222.320759) (xy 95.294165 -222.310915) (xy 95.34334 -222.308934)
			(xy 95.392195 -222.314866) (xy 95.439466 -222.328558) (xy 95.483928 -222.349656) (xy 95.524431 -222.377612)
			(xy 95.559924 -222.411704) (xy 95.589489 -222.451048) (xy 95.61236 -222.494625) (xy 95.627944 -222.541306)
			(xy 95.635839 -222.589883) (xy 95.636334 -222.61449) (xy 97.84513 -222.61449) (xy 97.84909 -222.565436)
			(xy 97.860867 -222.517652) (xy 97.880158 -222.472376) (xy 97.906461 -222.43078) (xy 97.939096 -222.393943)
			(xy 97.977217 -222.362818) (xy 98.019838 -222.338211) (xy 98.065854 -222.320759) (xy 98.114073 -222.310915)
			(xy 98.163248 -222.308934) (xy 98.212103 -222.314866) (xy 98.259374 -222.328558) (xy 98.303836 -222.349656)
			(xy 98.344339 -222.377612) (xy 98.379832 -222.411704) (xy 98.409397 -222.451048) (xy 98.432268 -222.494625)
			(xy 98.447852 -222.541306) (xy 98.455747 -222.589883) (xy 98.456242 -222.61449) (xy 100.665292 -222.61449)
			(xy 100.669252 -222.565436) (xy 100.681029 -222.517652) (xy 100.70032 -222.472376) (xy 100.726623 -222.43078)
			(xy 100.759258 -222.393943) (xy 100.797379 -222.362818) (xy 100.84 -222.338211) (xy 100.886016 -222.320759)
			(xy 100.934235 -222.310915) (xy 100.98341 -222.308934) (xy 101.032265 -222.314866) (xy 101.079536 -222.328558)
			(xy 101.123998 -222.349656) (xy 101.164501 -222.377612) (xy 101.199994 -222.411704) (xy 101.229559 -222.451048)
			(xy 101.25243 -222.494625) (xy 101.268014 -222.541306) (xy 101.275909 -222.589883) (xy 101.276404 -222.61449)
			(xy 110.065324 -222.61449) (xy 110.069284 -222.565436) (xy 110.081061 -222.517652) (xy 110.100352 -222.472376)
			(xy 110.126655 -222.43078) (xy 110.15929 -222.393943) (xy 110.197411 -222.362818) (xy 110.240032 -222.338211)
			(xy 110.286048 -222.320759) (xy 110.334267 -222.310915) (xy 110.383442 -222.308934) (xy 110.432297 -222.314866)
			(xy 110.479568 -222.328558) (xy 110.52403 -222.349656) (xy 110.564533 -222.377612) (xy 110.600026 -222.411704)
			(xy 110.629591 -222.451048) (xy 110.652462 -222.494625) (xy 110.668046 -222.541306) (xy 110.675941 -222.589883)
			(xy 110.676436 -222.61449) (xy 110.675941 -222.639097) (xy 110.668046 -222.687674) (xy 110.652462 -222.734355)
			(xy 110.629591 -222.777932) (xy 110.600026 -222.817276) (xy 110.564533 -222.851368) (xy 110.52403 -222.879324)
			(xy 110.479568 -222.900422) (xy 110.432297 -222.914114) (xy 110.383442 -222.920046) (xy 110.334267 -222.918065)
			(xy 110.286048 -222.908221) (xy 110.240032 -222.890769) (xy 110.197411 -222.866162) (xy 110.15929 -222.835037)
			(xy 110.126655 -222.7982) (xy 110.100352 -222.756604) (xy 110.081061 -222.711328) (xy 110.069284 -222.663544)
			(xy 110.065324 -222.61449) (xy 101.276404 -222.61449) (xy 101.275909 -222.639097) (xy 101.268014 -222.687674)
			(xy 101.25243 -222.734355) (xy 101.229559 -222.777932) (xy 101.199994 -222.817276) (xy 101.164501 -222.851368)
			(xy 101.123998 -222.879324) (xy 101.079536 -222.900422) (xy 101.032265 -222.914114) (xy 100.98341 -222.920046)
			(xy 100.934235 -222.918065) (xy 100.886016 -222.908221) (xy 100.84 -222.890769) (xy 100.797379 -222.866162)
			(xy 100.759258 -222.835037) (xy 100.726623 -222.7982) (xy 100.70032 -222.756604) (xy 100.681029 -222.711328)
			(xy 100.669252 -222.663544) (xy 100.665292 -222.61449) (xy 98.456242 -222.61449) (xy 98.455747 -222.639097)
			(xy 98.447852 -222.687674) (xy 98.432268 -222.734355) (xy 98.409397 -222.777932) (xy 98.379832 -222.817276)
			(xy 98.344339 -222.851368) (xy 98.303836 -222.879324) (xy 98.259374 -222.900422) (xy 98.212103 -222.914114)
			(xy 98.163248 -222.920046) (xy 98.114073 -222.918065) (xy 98.065854 -222.908221) (xy 98.019838 -222.890769)
			(xy 97.977217 -222.866162) (xy 97.939096 -222.835037) (xy 97.906461 -222.7982) (xy 97.880158 -222.756604)
			(xy 97.860867 -222.711328) (xy 97.84909 -222.663544) (xy 97.84513 -222.61449) (xy 95.636334 -222.61449)
			(xy 95.635839 -222.639097) (xy 95.627944 -222.687674) (xy 95.61236 -222.734355) (xy 95.589489 -222.777932)
			(xy 95.559924 -222.817276) (xy 95.524431 -222.851368) (xy 95.483928 -222.879324) (xy 95.439466 -222.900422)
			(xy 95.392195 -222.914114) (xy 95.34334 -222.920046) (xy 95.294165 -222.918065) (xy 95.245946 -222.908221)
			(xy 95.19993 -222.890769) (xy 95.157309 -222.866162) (xy 95.119188 -222.835037) (xy 95.086553 -222.7982)
			(xy 95.06025 -222.756604) (xy 95.040959 -222.711328) (xy 95.029182 -222.663544) (xy 95.025222 -222.61449)
			(xy 92.816426 -222.61449) (xy 92.815931 -222.639097) (xy 92.808036 -222.687674) (xy 92.792452 -222.734355)
			(xy 92.769581 -222.777932) (xy 92.740016 -222.817276) (xy 92.704523 -222.851368) (xy 92.66402 -222.879324)
			(xy 92.619558 -222.900422) (xy 92.572287 -222.914114) (xy 92.523432 -222.920046) (xy 92.474257 -222.918065)
			(xy 92.426038 -222.908221) (xy 92.380022 -222.890769) (xy 92.337401 -222.866162) (xy 92.29928 -222.835037)
			(xy 92.266645 -222.7982) (xy 92.240342 -222.756604) (xy 92.221051 -222.711328) (xy 92.209274 -222.663544)
			(xy 92.205314 -222.61449) (xy 91.876372 -222.61449) (xy 91.875877 -222.639097) (xy 91.867982 -222.687674)
			(xy 91.852398 -222.734355) (xy 91.829527 -222.777932) (xy 91.799962 -222.817276) (xy 91.764469 -222.851368)
			(xy 91.723966 -222.879324) (xy 91.679504 -222.900422) (xy 91.632233 -222.914114) (xy 91.583378 -222.920046)
			(xy 91.534203 -222.918065) (xy 91.485984 -222.908221) (xy 91.439968 -222.890769) (xy 91.397347 -222.866162)
			(xy 91.359226 -222.835037) (xy 91.326591 -222.7982) (xy 91.300288 -222.756604) (xy 91.280997 -222.711328)
			(xy 91.26922 -222.663544) (xy 91.26526 -222.61449) (xy 83.416394 -222.61449) (xy 83.415899 -222.639097)
			(xy 83.408004 -222.687674) (xy 83.39242 -222.734355) (xy 83.369549 -222.777932) (xy 83.339984 -222.817276)
			(xy 83.304491 -222.851368) (xy 83.263988 -222.879324) (xy 83.219526 -222.900422) (xy 83.172255 -222.914114)
			(xy 83.1234 -222.920046) (xy 83.074225 -222.918065) (xy 83.026006 -222.908221) (xy 82.97999 -222.890769)
			(xy 82.937369 -222.866162) (xy 82.899248 -222.835037) (xy 82.866613 -222.7982) (xy 82.84031 -222.756604)
			(xy 82.821019 -222.711328) (xy 82.809242 -222.663544) (xy 82.805282 -222.61449) (xy 81.536286 -222.61449)
			(xy 81.535791 -222.639097) (xy 81.527896 -222.687674) (xy 81.512312 -222.734355) (xy 81.489441 -222.777932)
			(xy 81.459876 -222.817276) (xy 81.424383 -222.851368) (xy 81.38388 -222.879324) (xy 81.339418 -222.900422)
			(xy 81.292147 -222.914114) (xy 81.243292 -222.920046) (xy 81.194117 -222.918065) (xy 81.145898 -222.908221)
			(xy 81.099882 -222.890769) (xy 81.057261 -222.866162) (xy 81.01914 -222.835037) (xy 80.986505 -222.7982)
			(xy 80.960202 -222.756604) (xy 80.940911 -222.711328) (xy 80.929134 -222.663544) (xy 80.925174 -222.61449)
			(xy 62.37732 -222.61449) (xy 62.37732 -223.424496) (xy 76.695312 -223.424496) (xy 76.699272 -223.375442)
			(xy 76.711049 -223.327658) (xy 76.73034 -223.282382) (xy 76.756643 -223.240786) (xy 76.789278 -223.203949)
			(xy 76.827399 -223.172824) (xy 76.87002 -223.148217) (xy 76.916036 -223.130765) (xy 76.964255 -223.120921)
			(xy 77.01343 -223.11894) (xy 77.062285 -223.124872) (xy 77.109556 -223.138564) (xy 77.154018 -223.159662)
			(xy 77.194521 -223.187618) (xy 77.230014 -223.22171) (xy 77.259579 -223.261054) (xy 77.28245 -223.304631)
			(xy 77.298034 -223.351312) (xy 77.305929 -223.399889) (xy 77.306424 -223.424496) (xy 78.575166 -223.424496)
			(xy 78.579126 -223.375442) (xy 78.590903 -223.327658) (xy 78.610194 -223.282382) (xy 78.636497 -223.240786)
			(xy 78.669132 -223.203949) (xy 78.707253 -223.172824) (xy 78.749874 -223.148217) (xy 78.79589 -223.130765)
			(xy 78.844109 -223.120921) (xy 78.893284 -223.11894) (xy 78.942139 -223.124872) (xy 78.98941 -223.138564)
			(xy 79.033872 -223.159662) (xy 79.074375 -223.187618) (xy 79.109868 -223.22171) (xy 79.139433 -223.261054)
			(xy 79.162304 -223.304631) (xy 79.177888 -223.351312) (xy 79.185783 -223.399889) (xy 79.186278 -223.424496)
			(xy 80.455274 -223.424496) (xy 80.459234 -223.375442) (xy 80.471011 -223.327658) (xy 80.490302 -223.282382)
			(xy 80.516605 -223.240786) (xy 80.54924 -223.203949) (xy 80.587361 -223.172824) (xy 80.629982 -223.148217)
			(xy 80.675998 -223.130765) (xy 80.724217 -223.120921) (xy 80.773392 -223.11894) (xy 80.822247 -223.124872)
			(xy 80.869518 -223.138564) (xy 80.91398 -223.159662) (xy 80.954483 -223.187618) (xy 80.989976 -223.22171)
			(xy 81.019541 -223.261054) (xy 81.042412 -223.304631) (xy 81.057996 -223.351312) (xy 81.065891 -223.399889)
			(xy 81.066386 -223.424496) (xy 82.335128 -223.424496) (xy 82.339088 -223.375442) (xy 82.350865 -223.327658)
			(xy 82.370156 -223.282382) (xy 82.396459 -223.240786) (xy 82.429094 -223.203949) (xy 82.467215 -223.172824)
			(xy 82.509836 -223.148217) (xy 82.555852 -223.130765) (xy 82.604071 -223.120921) (xy 82.653246 -223.11894)
			(xy 82.702101 -223.124872) (xy 82.749372 -223.138564) (xy 82.793834 -223.159662) (xy 82.834337 -223.187618)
			(xy 82.86983 -223.22171) (xy 82.899395 -223.261054) (xy 82.922266 -223.304631) (xy 82.93785 -223.351312)
			(xy 82.945745 -223.399889) (xy 82.94624 -223.424496) (xy 84.215236 -223.424496) (xy 84.219196 -223.375442)
			(xy 84.230973 -223.327658) (xy 84.250264 -223.282382) (xy 84.276567 -223.240786) (xy 84.309202 -223.203949)
			(xy 84.347323 -223.172824) (xy 84.389944 -223.148217) (xy 84.43596 -223.130765) (xy 84.484179 -223.120921)
			(xy 84.533354 -223.11894) (xy 84.582209 -223.124872) (xy 84.62948 -223.138564) (xy 84.673942 -223.159662)
			(xy 84.714445 -223.187618) (xy 84.749938 -223.22171) (xy 84.779503 -223.261054) (xy 84.802374 -223.304631)
			(xy 84.817958 -223.351312) (xy 84.825853 -223.399889) (xy 84.826062 -223.410272) (xy 86.095344 -223.410272)
			(xy 86.099304 -223.361218) (xy 86.111081 -223.313434) (xy 86.130372 -223.268158) (xy 86.156675 -223.226562)
			(xy 86.18931 -223.189725) (xy 86.227431 -223.1586) (xy 86.270052 -223.133993) (xy 86.316068 -223.116541)
			(xy 86.364287 -223.106697) (xy 86.413462 -223.104716) (xy 86.462317 -223.110648) (xy 86.509588 -223.12434)
			(xy 86.55405 -223.145438) (xy 86.594553 -223.173394) (xy 86.630046 -223.207486) (xy 86.659611 -223.24683)
			(xy 86.682482 -223.290407) (xy 86.698066 -223.337088) (xy 86.705961 -223.385665) (xy 86.706456 -223.410272)
			(xy 86.70617 -223.424496) (xy 87.035144 -223.424496) (xy 87.039104 -223.375442) (xy 87.050881 -223.327658)
			(xy 87.070172 -223.282382) (xy 87.096475 -223.240786) (xy 87.12911 -223.203949) (xy 87.167231 -223.172824)
			(xy 87.209852 -223.148217) (xy 87.255868 -223.130765) (xy 87.304087 -223.120921) (xy 87.353262 -223.11894)
			(xy 87.402117 -223.124872) (xy 87.449388 -223.138564) (xy 87.49385 -223.159662) (xy 87.534353 -223.187618)
			(xy 87.569846 -223.22171) (xy 87.599411 -223.261054) (xy 87.622282 -223.304631) (xy 87.637866 -223.351312)
			(xy 87.645761 -223.399889) (xy 87.64597 -223.410272) (xy 88.915506 -223.410272) (xy 88.919466 -223.361218)
			(xy 88.931243 -223.313434) (xy 88.950534 -223.268158) (xy 88.976837 -223.226562) (xy 89.009472 -223.189725)
			(xy 89.047593 -223.1586) (xy 89.090214 -223.133993) (xy 89.13623 -223.116541) (xy 89.184449 -223.106697)
			(xy 89.233624 -223.104716) (xy 89.282479 -223.110648) (xy 89.32975 -223.12434) (xy 89.374212 -223.145438)
			(xy 89.414715 -223.173394) (xy 89.450208 -223.207486) (xy 89.479773 -223.24683) (xy 89.502644 -223.290407)
			(xy 89.518228 -223.337088) (xy 89.526123 -223.385665) (xy 89.526618 -223.410272) (xy 89.526332 -223.424496)
			(xy 89.855306 -223.424496) (xy 89.859266 -223.375442) (xy 89.871043 -223.327658) (xy 89.890334 -223.282382)
			(xy 89.916637 -223.240786) (xy 89.949272 -223.203949) (xy 89.987393 -223.172824) (xy 90.030014 -223.148217)
			(xy 90.07603 -223.130765) (xy 90.124249 -223.120921) (xy 90.173424 -223.11894) (xy 90.222279 -223.124872)
			(xy 90.26955 -223.138564) (xy 90.314012 -223.159662) (xy 90.354515 -223.187618) (xy 90.390008 -223.22171)
			(xy 90.419573 -223.261054) (xy 90.442444 -223.304631) (xy 90.458028 -223.351312) (xy 90.465923 -223.399889)
			(xy 90.466418 -223.424496) (xy 90.795106 -223.424496) (xy 90.799066 -223.375442) (xy 90.810843 -223.327658)
			(xy 90.830134 -223.282382) (xy 90.856437 -223.240786) (xy 90.889072 -223.203949) (xy 90.927193 -223.172824)
			(xy 90.969814 -223.148217) (xy 91.01583 -223.130765) (xy 91.064049 -223.120921) (xy 91.113224 -223.11894)
			(xy 91.162079 -223.124872) (xy 91.20935 -223.138564) (xy 91.253812 -223.159662) (xy 91.294315 -223.187618)
			(xy 91.329808 -223.22171) (xy 91.359373 -223.261054) (xy 91.382244 -223.304631) (xy 91.397828 -223.351312)
			(xy 91.405723 -223.399889) (xy 91.406218 -223.424496) (xy 93.615268 -223.424496) (xy 93.619228 -223.375442)
			(xy 93.631005 -223.327658) (xy 93.650296 -223.282382) (xy 93.676599 -223.240786) (xy 93.709234 -223.203949)
			(xy 93.747355 -223.172824) (xy 93.789976 -223.148217) (xy 93.835992 -223.130765) (xy 93.884211 -223.120921)
			(xy 93.933386 -223.11894) (xy 93.982241 -223.124872) (xy 94.029512 -223.138564) (xy 94.073974 -223.159662)
			(xy 94.114477 -223.187618) (xy 94.14997 -223.22171) (xy 94.179535 -223.261054) (xy 94.202406 -223.304631)
			(xy 94.21799 -223.351312) (xy 94.225885 -223.399889) (xy 94.22638 -223.424496) (xy 94.555322 -223.424496)
			(xy 94.559282 -223.375442) (xy 94.571059 -223.327658) (xy 94.59035 -223.282382) (xy 94.616653 -223.240786)
			(xy 94.649288 -223.203949) (xy 94.687409 -223.172824) (xy 94.73003 -223.148217) (xy 94.776046 -223.130765)
			(xy 94.824265 -223.120921) (xy 94.87344 -223.11894) (xy 94.922295 -223.124872) (xy 94.969566 -223.138564)
			(xy 95.014028 -223.159662) (xy 95.054531 -223.187618) (xy 95.090024 -223.22171) (xy 95.119589 -223.261054)
			(xy 95.14246 -223.304631) (xy 95.158044 -223.351312) (xy 95.165939 -223.399889) (xy 95.166434 -223.424496)
			(xy 95.495122 -223.424496) (xy 95.499082 -223.375442) (xy 95.510859 -223.327658) (xy 95.53015 -223.282382)
			(xy 95.556453 -223.240786) (xy 95.589088 -223.203949) (xy 95.627209 -223.172824) (xy 95.66983 -223.148217)
			(xy 95.715846 -223.130765) (xy 95.764065 -223.120921) (xy 95.81324 -223.11894) (xy 95.862095 -223.124872)
			(xy 95.909366 -223.138564) (xy 95.953828 -223.159662) (xy 95.994331 -223.187618) (xy 96.029824 -223.22171)
			(xy 96.059389 -223.261054) (xy 96.08226 -223.304631) (xy 96.097844 -223.351312) (xy 96.105739 -223.399889)
			(xy 96.106234 -223.424496) (xy 96.435176 -223.424496) (xy 96.439136 -223.375442) (xy 96.450913 -223.327658)
			(xy 96.470204 -223.282382) (xy 96.496507 -223.240786) (xy 96.529142 -223.203949) (xy 96.567263 -223.172824)
			(xy 96.609884 -223.148217) (xy 96.6559 -223.130765) (xy 96.704119 -223.120921) (xy 96.753294 -223.11894)
			(xy 96.802149 -223.124872) (xy 96.84942 -223.138564) (xy 96.893882 -223.159662) (xy 96.934385 -223.187618)
			(xy 96.969878 -223.22171) (xy 96.999443 -223.261054) (xy 97.022314 -223.304631) (xy 97.037898 -223.351312)
			(xy 97.045793 -223.399889) (xy 97.046288 -223.424496) (xy 97.37523 -223.424496) (xy 97.37919 -223.375442)
			(xy 97.390967 -223.327658) (xy 97.410258 -223.282382) (xy 97.436561 -223.240786) (xy 97.469196 -223.203949)
			(xy 97.507317 -223.172824) (xy 97.549938 -223.148217) (xy 97.595954 -223.130765) (xy 97.644173 -223.120921)
			(xy 97.693348 -223.11894) (xy 97.742203 -223.124872) (xy 97.789474 -223.138564) (xy 97.833936 -223.159662)
			(xy 97.874439 -223.187618) (xy 97.909932 -223.22171) (xy 97.939497 -223.261054) (xy 97.962368 -223.304631)
			(xy 97.977952 -223.351312) (xy 97.985847 -223.399889) (xy 97.986342 -223.424496) (xy 98.315284 -223.424496)
			(xy 98.319244 -223.375442) (xy 98.331021 -223.327658) (xy 98.350312 -223.282382) (xy 98.376615 -223.240786)
			(xy 98.40925 -223.203949) (xy 98.447371 -223.172824) (xy 98.489992 -223.148217) (xy 98.536008 -223.130765)
			(xy 98.584227 -223.120921) (xy 98.633402 -223.11894) (xy 98.682257 -223.124872) (xy 98.729528 -223.138564)
			(xy 98.77399 -223.159662) (xy 98.814493 -223.187618) (xy 98.849986 -223.22171) (xy 98.879551 -223.261054)
			(xy 98.902422 -223.304631) (xy 98.918006 -223.351312) (xy 98.925901 -223.399889) (xy 98.926396 -223.424496)
			(xy 99.255338 -223.424496) (xy 99.259298 -223.375442) (xy 99.271075 -223.327658) (xy 99.290366 -223.282382)
			(xy 99.316669 -223.240786) (xy 99.349304 -223.203949) (xy 99.387425 -223.172824) (xy 99.430046 -223.148217)
			(xy 99.476062 -223.130765) (xy 99.524281 -223.120921) (xy 99.573456 -223.11894) (xy 99.622311 -223.124872)
			(xy 99.669582 -223.138564) (xy 99.714044 -223.159662) (xy 99.754547 -223.187618) (xy 99.79004 -223.22171)
			(xy 99.819605 -223.261054) (xy 99.842476 -223.304631) (xy 99.85806 -223.351312) (xy 99.865955 -223.399889)
			(xy 99.86645 -223.424496) (xy 100.195138 -223.424496) (xy 100.199098 -223.375442) (xy 100.210875 -223.327658)
			(xy 100.230166 -223.282382) (xy 100.256469 -223.240786) (xy 100.289104 -223.203949) (xy 100.327225 -223.172824)
			(xy 100.369846 -223.148217) (xy 100.415862 -223.130765) (xy 100.464081 -223.120921) (xy 100.513256 -223.11894)
			(xy 100.562111 -223.124872) (xy 100.609382 -223.138564) (xy 100.653844 -223.159662) (xy 100.694347 -223.187618)
			(xy 100.72984 -223.22171) (xy 100.759405 -223.261054) (xy 100.782276 -223.304631) (xy 100.79786 -223.351312)
			(xy 100.805755 -223.399889) (xy 100.80625 -223.424496) (xy 101.135192 -223.424496) (xy 101.139152 -223.375442)
			(xy 101.150929 -223.327658) (xy 101.17022 -223.282382) (xy 101.196523 -223.240786) (xy 101.229158 -223.203949)
			(xy 101.267279 -223.172824) (xy 101.3099 -223.148217) (xy 101.355916 -223.130765) (xy 101.404135 -223.120921)
			(xy 101.45331 -223.11894) (xy 101.502165 -223.124872) (xy 101.549436 -223.138564) (xy 101.593898 -223.159662)
			(xy 101.634401 -223.187618) (xy 101.669894 -223.22171) (xy 101.699459 -223.261054) (xy 101.72233 -223.304631)
			(xy 101.737914 -223.351312) (xy 101.745809 -223.399889) (xy 101.746304 -223.424496) (xy 102.075246 -223.424496)
			(xy 102.079206 -223.375442) (xy 102.090983 -223.327658) (xy 102.110274 -223.282382) (xy 102.136577 -223.240786)
			(xy 102.169212 -223.203949) (xy 102.207333 -223.172824) (xy 102.249954 -223.148217) (xy 102.29597 -223.130765)
			(xy 102.344189 -223.120921) (xy 102.393364 -223.11894) (xy 102.442219 -223.124872) (xy 102.48949 -223.138564)
			(xy 102.533952 -223.159662) (xy 102.574455 -223.187618) (xy 102.609948 -223.22171) (xy 102.639513 -223.261054)
			(xy 102.662384 -223.304631) (xy 102.677968 -223.351312) (xy 102.685863 -223.399889) (xy 102.686358 -223.424496)
			(xy 103.0153 -223.424496) (xy 103.01926 -223.375442) (xy 103.031037 -223.327658) (xy 103.050328 -223.282382)
			(xy 103.076631 -223.240786) (xy 103.109266 -223.203949) (xy 103.147387 -223.172824) (xy 103.190008 -223.148217)
			(xy 103.236024 -223.130765) (xy 103.284243 -223.120921) (xy 103.333418 -223.11894) (xy 103.382273 -223.124872)
			(xy 103.429544 -223.138564) (xy 103.474006 -223.159662) (xy 103.514509 -223.187618) (xy 103.550002 -223.22171)
			(xy 103.579567 -223.261054) (xy 103.602438 -223.304631) (xy 103.618022 -223.351312) (xy 103.625917 -223.399889)
			(xy 103.626412 -223.424496) (xy 109.59517 -223.424496) (xy 109.59913 -223.375442) (xy 109.610907 -223.327658)
			(xy 109.630198 -223.282382) (xy 109.656501 -223.240786) (xy 109.689136 -223.203949) (xy 109.727257 -223.172824)
			(xy 109.769878 -223.148217) (xy 109.815894 -223.130765) (xy 109.864113 -223.120921) (xy 109.913288 -223.11894)
			(xy 109.962143 -223.124872) (xy 110.009414 -223.138564) (xy 110.053876 -223.159662) (xy 110.094379 -223.187618)
			(xy 110.129872 -223.22171) (xy 110.159437 -223.261054) (xy 110.182308 -223.304631) (xy 110.197892 -223.351312)
			(xy 110.205787 -223.399889) (xy 110.206282 -223.424496) (xy 110.205787 -223.449103) (xy 110.197892 -223.49768)
			(xy 110.182308 -223.544361) (xy 110.159437 -223.587938) (xy 110.129872 -223.627282) (xy 110.094379 -223.661374)
			(xy 110.053876 -223.68933) (xy 110.009414 -223.710428) (xy 109.962143 -223.72412) (xy 109.913288 -223.730052)
			(xy 109.864113 -223.728071) (xy 109.815894 -223.718227) (xy 109.769878 -223.700775) (xy 109.727257 -223.676168)
			(xy 109.689136 -223.645043) (xy 109.656501 -223.608206) (xy 109.630198 -223.56661) (xy 109.610907 -223.521334)
			(xy 109.59913 -223.47355) (xy 109.59517 -223.424496) (xy 103.626412 -223.424496) (xy 103.625917 -223.449103)
			(xy 103.618022 -223.49768) (xy 103.602438 -223.544361) (xy 103.579567 -223.587938) (xy 103.550002 -223.627282)
			(xy 103.514509 -223.661374) (xy 103.474006 -223.68933) (xy 103.429544 -223.710428) (xy 103.382273 -223.72412)
			(xy 103.333418 -223.730052) (xy 103.284243 -223.728071) (xy 103.236024 -223.718227) (xy 103.190008 -223.700775)
			(xy 103.147387 -223.676168) (xy 103.109266 -223.645043) (xy 103.076631 -223.608206) (xy 103.050328 -223.56661)
			(xy 103.031037 -223.521334) (xy 103.01926 -223.47355) (xy 103.0153 -223.424496) (xy 102.686358 -223.424496)
			(xy 102.685863 -223.449103) (xy 102.677968 -223.49768) (xy 102.662384 -223.544361) (xy 102.639513 -223.587938)
			(xy 102.609948 -223.627282) (xy 102.574455 -223.661374) (xy 102.533952 -223.68933) (xy 102.48949 -223.710428)
			(xy 102.442219 -223.72412) (xy 102.393364 -223.730052) (xy 102.344189 -223.728071) (xy 102.29597 -223.718227)
			(xy 102.249954 -223.700775) (xy 102.207333 -223.676168) (xy 102.169212 -223.645043) (xy 102.136577 -223.608206)
			(xy 102.110274 -223.56661) (xy 102.090983 -223.521334) (xy 102.079206 -223.47355) (xy 102.075246 -223.424496)
			(xy 101.746304 -223.424496) (xy 101.745809 -223.449103) (xy 101.737914 -223.49768) (xy 101.72233 -223.544361)
			(xy 101.699459 -223.587938) (xy 101.669894 -223.627282) (xy 101.634401 -223.661374) (xy 101.593898 -223.68933)
			(xy 101.549436 -223.710428) (xy 101.502165 -223.72412) (xy 101.45331 -223.730052) (xy 101.404135 -223.728071)
			(xy 101.355916 -223.718227) (xy 101.3099 -223.700775) (xy 101.267279 -223.676168) (xy 101.229158 -223.645043)
			(xy 101.196523 -223.608206) (xy 101.17022 -223.56661) (xy 101.150929 -223.521334) (xy 101.139152 -223.47355)
			(xy 101.135192 -223.424496) (xy 100.80625 -223.424496) (xy 100.805755 -223.449103) (xy 100.79786 -223.49768)
			(xy 100.782276 -223.544361) (xy 100.759405 -223.587938) (xy 100.72984 -223.627282) (xy 100.694347 -223.661374)
			(xy 100.653844 -223.68933) (xy 100.609382 -223.710428) (xy 100.562111 -223.72412) (xy 100.513256 -223.730052)
			(xy 100.464081 -223.728071) (xy 100.415862 -223.718227) (xy 100.369846 -223.700775) (xy 100.327225 -223.676168)
			(xy 100.289104 -223.645043) (xy 100.256469 -223.608206) (xy 100.230166 -223.56661) (xy 100.210875 -223.521334)
			(xy 100.199098 -223.47355) (xy 100.195138 -223.424496) (xy 99.86645 -223.424496) (xy 99.865955 -223.449103)
			(xy 99.85806 -223.49768) (xy 99.842476 -223.544361) (xy 99.819605 -223.587938) (xy 99.79004 -223.627282)
			(xy 99.754547 -223.661374) (xy 99.714044 -223.68933) (xy 99.669582 -223.710428) (xy 99.622311 -223.72412)
			(xy 99.573456 -223.730052) (xy 99.524281 -223.728071) (xy 99.476062 -223.718227) (xy 99.430046 -223.700775)
			(xy 99.387425 -223.676168) (xy 99.349304 -223.645043) (xy 99.316669 -223.608206) (xy 99.290366 -223.56661)
			(xy 99.271075 -223.521334) (xy 99.259298 -223.47355) (xy 99.255338 -223.424496) (xy 98.926396 -223.424496)
			(xy 98.925901 -223.449103) (xy 98.918006 -223.49768) (xy 98.902422 -223.544361) (xy 98.879551 -223.587938)
			(xy 98.849986 -223.627282) (xy 98.814493 -223.661374) (xy 98.77399 -223.68933) (xy 98.729528 -223.710428)
			(xy 98.682257 -223.72412) (xy 98.633402 -223.730052) (xy 98.584227 -223.728071) (xy 98.536008 -223.718227)
			(xy 98.489992 -223.700775) (xy 98.447371 -223.676168) (xy 98.40925 -223.645043) (xy 98.376615 -223.608206)
			(xy 98.350312 -223.56661) (xy 98.331021 -223.521334) (xy 98.319244 -223.47355) (xy 98.315284 -223.424496)
			(xy 97.986342 -223.424496) (xy 97.985847 -223.449103) (xy 97.977952 -223.49768) (xy 97.962368 -223.544361)
			(xy 97.939497 -223.587938) (xy 97.909932 -223.627282) (xy 97.874439 -223.661374) (xy 97.833936 -223.68933)
			(xy 97.789474 -223.710428) (xy 97.742203 -223.72412) (xy 97.693348 -223.730052) (xy 97.644173 -223.728071)
			(xy 97.595954 -223.718227) (xy 97.549938 -223.700775) (xy 97.507317 -223.676168) (xy 97.469196 -223.645043)
			(xy 97.436561 -223.608206) (xy 97.410258 -223.56661) (xy 97.390967 -223.521334) (xy 97.37919 -223.47355)
			(xy 97.37523 -223.424496) (xy 97.046288 -223.424496) (xy 97.045793 -223.449103) (xy 97.037898 -223.49768)
			(xy 97.022314 -223.544361) (xy 96.999443 -223.587938) (xy 96.969878 -223.627282) (xy 96.934385 -223.661374)
			(xy 96.893882 -223.68933) (xy 96.84942 -223.710428) (xy 96.802149 -223.72412) (xy 96.753294 -223.730052)
			(xy 96.704119 -223.728071) (xy 96.6559 -223.718227) (xy 96.609884 -223.700775) (xy 96.567263 -223.676168)
			(xy 96.529142 -223.645043) (xy 96.496507 -223.608206) (xy 96.470204 -223.56661) (xy 96.450913 -223.521334)
			(xy 96.439136 -223.47355) (xy 96.435176 -223.424496) (xy 96.106234 -223.424496) (xy 96.105739 -223.449103)
			(xy 96.097844 -223.49768) (xy 96.08226 -223.544361) (xy 96.059389 -223.587938) (xy 96.029824 -223.627282)
			(xy 95.994331 -223.661374) (xy 95.953828 -223.68933) (xy 95.909366 -223.710428) (xy 95.862095 -223.72412)
			(xy 95.81324 -223.730052) (xy 95.764065 -223.728071) (xy 95.715846 -223.718227) (xy 95.66983 -223.700775)
			(xy 95.627209 -223.676168) (xy 95.589088 -223.645043) (xy 95.556453 -223.608206) (xy 95.53015 -223.56661)
			(xy 95.510859 -223.521334) (xy 95.499082 -223.47355) (xy 95.495122 -223.424496) (xy 95.166434 -223.424496)
			(xy 95.165939 -223.449103) (xy 95.158044 -223.49768) (xy 95.14246 -223.544361) (xy 95.119589 -223.587938)
			(xy 95.090024 -223.627282) (xy 95.054531 -223.661374) (xy 95.014028 -223.68933) (xy 94.969566 -223.710428)
			(xy 94.922295 -223.72412) (xy 94.87344 -223.730052) (xy 94.824265 -223.728071) (xy 94.776046 -223.718227)
			(xy 94.73003 -223.700775) (xy 94.687409 -223.676168) (xy 94.649288 -223.645043) (xy 94.616653 -223.608206)
			(xy 94.59035 -223.56661) (xy 94.571059 -223.521334) (xy 94.559282 -223.47355) (xy 94.555322 -223.424496)
			(xy 94.22638 -223.424496) (xy 94.225885 -223.449103) (xy 94.21799 -223.49768) (xy 94.202406 -223.544361)
			(xy 94.179535 -223.587938) (xy 94.14997 -223.627282) (xy 94.114477 -223.661374) (xy 94.073974 -223.68933)
			(xy 94.029512 -223.710428) (xy 93.982241 -223.72412) (xy 93.933386 -223.730052) (xy 93.884211 -223.728071)
			(xy 93.835992 -223.718227) (xy 93.789976 -223.700775) (xy 93.747355 -223.676168) (xy 93.709234 -223.645043)
			(xy 93.676599 -223.608206) (xy 93.650296 -223.56661) (xy 93.631005 -223.521334) (xy 93.619228 -223.47355)
			(xy 93.615268 -223.424496) (xy 91.406218 -223.424496) (xy 91.405723 -223.449103) (xy 91.397828 -223.49768)
			(xy 91.382244 -223.544361) (xy 91.359373 -223.587938) (xy 91.329808 -223.627282) (xy 91.294315 -223.661374)
			(xy 91.253812 -223.68933) (xy 91.20935 -223.710428) (xy 91.162079 -223.72412) (xy 91.113224 -223.730052)
			(xy 91.064049 -223.728071) (xy 91.01583 -223.718227) (xy 90.969814 -223.700775) (xy 90.927193 -223.676168)
			(xy 90.889072 -223.645043) (xy 90.856437 -223.608206) (xy 90.830134 -223.56661) (xy 90.810843 -223.521334)
			(xy 90.799066 -223.47355) (xy 90.795106 -223.424496) (xy 90.466418 -223.424496) (xy 90.465923 -223.449103)
			(xy 90.458028 -223.49768) (xy 90.442444 -223.544361) (xy 90.419573 -223.587938) (xy 90.390008 -223.627282)
			(xy 90.354515 -223.661374) (xy 90.314012 -223.68933) (xy 90.26955 -223.710428) (xy 90.222279 -223.72412)
			(xy 90.173424 -223.730052) (xy 90.124249 -223.728071) (xy 90.07603 -223.718227) (xy 90.030014 -223.700775)
			(xy 89.987393 -223.676168) (xy 89.949272 -223.645043) (xy 89.916637 -223.608206) (xy 89.890334 -223.56661)
			(xy 89.871043 -223.521334) (xy 89.859266 -223.47355) (xy 89.855306 -223.424496) (xy 89.526332 -223.424496)
			(xy 89.526123 -223.434879) (xy 89.518228 -223.483456) (xy 89.502644 -223.530137) (xy 89.479773 -223.573714)
			(xy 89.450208 -223.613058) (xy 89.414715 -223.64715) (xy 89.374212 -223.675106) (xy 89.32975 -223.696204)
			(xy 89.282479 -223.709896) (xy 89.233624 -223.715828) (xy 89.184449 -223.713847) (xy 89.13623 -223.704003)
			(xy 89.090214 -223.686551) (xy 89.047593 -223.661944) (xy 89.009472 -223.630819) (xy 88.976837 -223.593982)
			(xy 88.950534 -223.552386) (xy 88.931243 -223.50711) (xy 88.919466 -223.459326) (xy 88.915506 -223.410272)
			(xy 87.64597 -223.410272) (xy 87.646256 -223.424496) (xy 87.645761 -223.449103) (xy 87.637866 -223.49768)
			(xy 87.622282 -223.544361) (xy 87.599411 -223.587938) (xy 87.569846 -223.627282) (xy 87.534353 -223.661374)
			(xy 87.49385 -223.68933) (xy 87.449388 -223.710428) (xy 87.402117 -223.72412) (xy 87.353262 -223.730052)
			(xy 87.304087 -223.728071) (xy 87.255868 -223.718227) (xy 87.209852 -223.700775) (xy 87.167231 -223.676168)
			(xy 87.12911 -223.645043) (xy 87.096475 -223.608206) (xy 87.070172 -223.56661) (xy 87.050881 -223.521334)
			(xy 87.039104 -223.47355) (xy 87.035144 -223.424496) (xy 86.70617 -223.424496) (xy 86.705961 -223.434879)
			(xy 86.698066 -223.483456) (xy 86.682482 -223.530137) (xy 86.659611 -223.573714) (xy 86.630046 -223.613058)
			(xy 86.594553 -223.64715) (xy 86.55405 -223.675106) (xy 86.509588 -223.696204) (xy 86.462317 -223.709896)
			(xy 86.413462 -223.715828) (xy 86.364287 -223.713847) (xy 86.316068 -223.704003) (xy 86.270052 -223.686551)
			(xy 86.227431 -223.661944) (xy 86.18931 -223.630819) (xy 86.156675 -223.593982) (xy 86.130372 -223.552386)
			(xy 86.111081 -223.50711) (xy 86.099304 -223.459326) (xy 86.095344 -223.410272) (xy 84.826062 -223.410272)
			(xy 84.826348 -223.424496) (xy 84.825853 -223.449103) (xy 84.817958 -223.49768) (xy 84.802374 -223.544361)
			(xy 84.779503 -223.587938) (xy 84.749938 -223.627282) (xy 84.714445 -223.661374) (xy 84.673942 -223.68933)
			(xy 84.62948 -223.710428) (xy 84.582209 -223.72412) (xy 84.533354 -223.730052) (xy 84.484179 -223.728071)
			(xy 84.43596 -223.718227) (xy 84.389944 -223.700775) (xy 84.347323 -223.676168) (xy 84.309202 -223.645043)
			(xy 84.276567 -223.608206) (xy 84.250264 -223.56661) (xy 84.230973 -223.521334) (xy 84.219196 -223.47355)
			(xy 84.215236 -223.424496) (xy 82.94624 -223.424496) (xy 82.945745 -223.449103) (xy 82.93785 -223.49768)
			(xy 82.922266 -223.544361) (xy 82.899395 -223.587938) (xy 82.86983 -223.627282) (xy 82.834337 -223.661374)
			(xy 82.793834 -223.68933) (xy 82.749372 -223.710428) (xy 82.702101 -223.72412) (xy 82.653246 -223.730052)
			(xy 82.604071 -223.728071) (xy 82.555852 -223.718227) (xy 82.509836 -223.700775) (xy 82.467215 -223.676168)
			(xy 82.429094 -223.645043) (xy 82.396459 -223.608206) (xy 82.370156 -223.56661) (xy 82.350865 -223.521334)
			(xy 82.339088 -223.47355) (xy 82.335128 -223.424496) (xy 81.066386 -223.424496) (xy 81.065891 -223.449103)
			(xy 81.057996 -223.49768) (xy 81.042412 -223.544361) (xy 81.019541 -223.587938) (xy 80.989976 -223.627282)
			(xy 80.954483 -223.661374) (xy 80.91398 -223.68933) (xy 80.869518 -223.710428) (xy 80.822247 -223.72412)
			(xy 80.773392 -223.730052) (xy 80.724217 -223.728071) (xy 80.675998 -223.718227) (xy 80.629982 -223.700775)
			(xy 80.587361 -223.676168) (xy 80.54924 -223.645043) (xy 80.516605 -223.608206) (xy 80.490302 -223.56661)
			(xy 80.471011 -223.521334) (xy 80.459234 -223.47355) (xy 80.455274 -223.424496) (xy 79.186278 -223.424496)
			(xy 79.185783 -223.449103) (xy 79.177888 -223.49768) (xy 79.162304 -223.544361) (xy 79.139433 -223.587938)
			(xy 79.109868 -223.627282) (xy 79.074375 -223.661374) (xy 79.033872 -223.68933) (xy 78.98941 -223.710428)
			(xy 78.942139 -223.72412) (xy 78.893284 -223.730052) (xy 78.844109 -223.728071) (xy 78.79589 -223.718227)
			(xy 78.749874 -223.700775) (xy 78.707253 -223.676168) (xy 78.669132 -223.645043) (xy 78.636497 -223.608206)
			(xy 78.610194 -223.56661) (xy 78.590903 -223.521334) (xy 78.579126 -223.47355) (xy 78.575166 -223.424496)
			(xy 77.306424 -223.424496) (xy 77.305929 -223.449103) (xy 77.298034 -223.49768) (xy 77.28245 -223.544361)
			(xy 77.259579 -223.587938) (xy 77.230014 -223.627282) (xy 77.194521 -223.661374) (xy 77.154018 -223.68933)
			(xy 77.109556 -223.710428) (xy 77.062285 -223.72412) (xy 77.01343 -223.730052) (xy 76.964255 -223.728071)
			(xy 76.916036 -223.718227) (xy 76.87002 -223.700775) (xy 76.827399 -223.676168) (xy 76.789278 -223.645043)
			(xy 76.756643 -223.608206) (xy 76.73034 -223.56661) (xy 76.711049 -223.521334) (xy 76.699272 -223.47355)
			(xy 76.695312 -223.424496) (xy 62.37732 -223.424496) (xy 62.37732 -224.234502) (xy 77.165212 -224.234502)
			(xy 77.169172 -224.185448) (xy 77.180949 -224.137664) (xy 77.20024 -224.092388) (xy 77.226543 -224.050792)
			(xy 77.259178 -224.013955) (xy 77.297299 -223.98283) (xy 77.33992 -223.958223) (xy 77.385936 -223.940771)
			(xy 77.434155 -223.930927) (xy 77.48333 -223.928946) (xy 77.532185 -223.934878) (xy 77.579456 -223.94857)
			(xy 77.623918 -223.969668) (xy 77.664421 -223.997624) (xy 77.699914 -224.031716) (xy 77.729479 -224.07106)
			(xy 77.75235 -224.114637) (xy 77.767934 -224.161318) (xy 77.775829 -224.209895) (xy 77.776324 -224.234502)
			(xy 78.105266 -224.234502) (xy 78.109226 -224.185448) (xy 78.121003 -224.137664) (xy 78.140294 -224.092388)
			(xy 78.166597 -224.050792) (xy 78.199232 -224.013955) (xy 78.237353 -223.98283) (xy 78.279974 -223.958223)
			(xy 78.32599 -223.940771) (xy 78.374209 -223.930927) (xy 78.423384 -223.928946) (xy 78.472239 -223.934878)
			(xy 78.51951 -223.94857) (xy 78.563972 -223.969668) (xy 78.604475 -223.997624) (xy 78.639968 -224.031716)
			(xy 78.669533 -224.07106) (xy 78.692404 -224.114637) (xy 78.707988 -224.161318) (xy 78.715883 -224.209895)
			(xy 78.716378 -224.234502) (xy 79.985374 -224.234502) (xy 79.989334 -224.185448) (xy 80.001111 -224.137664)
			(xy 80.020402 -224.092388) (xy 80.046705 -224.050792) (xy 80.07934 -224.013955) (xy 80.117461 -223.98283)
			(xy 80.160082 -223.958223) (xy 80.206098 -223.940771) (xy 80.254317 -223.930927) (xy 80.303492 -223.928946)
			(xy 80.352347 -223.934878) (xy 80.399618 -223.94857) (xy 80.44408 -223.969668) (xy 80.484583 -223.997624)
			(xy 80.520076 -224.031716) (xy 80.549641 -224.07106) (xy 80.572512 -224.114637) (xy 80.588096 -224.161318)
			(xy 80.595991 -224.209895) (xy 80.596486 -224.234502) (xy 80.925174 -224.234502) (xy 80.929134 -224.185448)
			(xy 80.940911 -224.137664) (xy 80.960202 -224.092388) (xy 80.986505 -224.050792) (xy 81.01914 -224.013955)
			(xy 81.057261 -223.98283) (xy 81.099882 -223.958223) (xy 81.145898 -223.940771) (xy 81.194117 -223.930927)
			(xy 81.243292 -223.928946) (xy 81.292147 -223.934878) (xy 81.339418 -223.94857) (xy 81.38388 -223.969668)
			(xy 81.424383 -223.997624) (xy 81.459876 -224.031716) (xy 81.489441 -224.07106) (xy 81.512312 -224.114637)
			(xy 81.527896 -224.161318) (xy 81.535791 -224.209895) (xy 81.536286 -224.234502) (xy 81.865228 -224.234502)
			(xy 81.869188 -224.185448) (xy 81.880965 -224.137664) (xy 81.900256 -224.092388) (xy 81.926559 -224.050792)
			(xy 81.959194 -224.013955) (xy 81.997315 -223.98283) (xy 82.039936 -223.958223) (xy 82.085952 -223.940771)
			(xy 82.134171 -223.930927) (xy 82.183346 -223.928946) (xy 82.232201 -223.934878) (xy 82.279472 -223.94857)
			(xy 82.323934 -223.969668) (xy 82.364437 -223.997624) (xy 82.39993 -224.031716) (xy 82.429495 -224.07106)
			(xy 82.452366 -224.114637) (xy 82.46795 -224.161318) (xy 82.475845 -224.209895) (xy 82.47634 -224.234502)
			(xy 82.805282 -224.234502) (xy 82.809242 -224.185448) (xy 82.821019 -224.137664) (xy 82.84031 -224.092388)
			(xy 82.866613 -224.050792) (xy 82.899248 -224.013955) (xy 82.937369 -223.98283) (xy 82.97999 -223.958223)
			(xy 83.026006 -223.940771) (xy 83.074225 -223.930927) (xy 83.1234 -223.928946) (xy 83.172255 -223.934878)
			(xy 83.219526 -223.94857) (xy 83.263988 -223.969668) (xy 83.304491 -223.997624) (xy 83.339984 -224.031716)
			(xy 83.369549 -224.07106) (xy 83.39242 -224.114637) (xy 83.408004 -224.161318) (xy 83.415899 -224.209895)
			(xy 83.416394 -224.234502) (xy 83.745336 -224.234502) (xy 83.749296 -224.185448) (xy 83.761073 -224.137664)
			(xy 83.780364 -224.092388) (xy 83.806667 -224.050792) (xy 83.839302 -224.013955) (xy 83.877423 -223.98283)
			(xy 83.920044 -223.958223) (xy 83.96606 -223.940771) (xy 84.014279 -223.930927) (xy 84.063454 -223.928946)
			(xy 84.112309 -223.934878) (xy 84.15958 -223.94857) (xy 84.204042 -223.969668) (xy 84.244545 -223.997624)
			(xy 84.280038 -224.031716) (xy 84.309603 -224.07106) (xy 84.332474 -224.114637) (xy 84.348058 -224.161318)
			(xy 84.355953 -224.209895) (xy 84.356448 -224.234502) (xy 84.685136 -224.234502) (xy 84.689096 -224.185448)
			(xy 84.700873 -224.137664) (xy 84.720164 -224.092388) (xy 84.746467 -224.050792) (xy 84.779102 -224.013955)
			(xy 84.817223 -223.98283) (xy 84.859844 -223.958223) (xy 84.90586 -223.940771) (xy 84.954079 -223.930927)
			(xy 85.003254 -223.928946) (xy 85.052109 -223.934878) (xy 85.09938 -223.94857) (xy 85.143842 -223.969668)
			(xy 85.184345 -223.997624) (xy 85.219838 -224.031716) (xy 85.249403 -224.07106) (xy 85.272274 -224.114637)
			(xy 85.287858 -224.161318) (xy 85.295753 -224.209895) (xy 85.296248 -224.234502) (xy 86.565244 -224.234502)
			(xy 86.569204 -224.185448) (xy 86.580981 -224.137664) (xy 86.600272 -224.092388) (xy 86.626575 -224.050792)
			(xy 86.65921 -224.013955) (xy 86.697331 -223.98283) (xy 86.739952 -223.958223) (xy 86.785968 -223.940771)
			(xy 86.834187 -223.930927) (xy 86.883362 -223.928946) (xy 86.932217 -223.934878) (xy 86.979488 -223.94857)
			(xy 87.02395 -223.969668) (xy 87.064453 -223.997624) (xy 87.099946 -224.031716) (xy 87.129511 -224.07106)
			(xy 87.152382 -224.114637) (xy 87.167966 -224.161318) (xy 87.175861 -224.209895) (xy 87.176356 -224.234502)
			(xy 87.505298 -224.234502) (xy 87.509258 -224.185448) (xy 87.521035 -224.137664) (xy 87.540326 -224.092388)
			(xy 87.566629 -224.050792) (xy 87.599264 -224.013955) (xy 87.637385 -223.98283) (xy 87.680006 -223.958223)
			(xy 87.726022 -223.940771) (xy 87.774241 -223.930927) (xy 87.823416 -223.928946) (xy 87.872271 -223.934878)
			(xy 87.919542 -223.94857) (xy 87.964004 -223.969668) (xy 88.004507 -223.997624) (xy 88.04 -224.031716)
			(xy 88.069565 -224.07106) (xy 88.092436 -224.114637) (xy 88.10802 -224.161318) (xy 88.115915 -224.209895)
			(xy 88.11641 -224.234502) (xy 89.385152 -224.234502) (xy 89.389112 -224.185448) (xy 89.400889 -224.137664)
			(xy 89.42018 -224.092388) (xy 89.446483 -224.050792) (xy 89.479118 -224.013955) (xy 89.517239 -223.98283)
			(xy 89.55986 -223.958223) (xy 89.605876 -223.940771) (xy 89.654095 -223.930927) (xy 89.70327 -223.928946)
			(xy 89.752125 -223.934878) (xy 89.799396 -223.94857) (xy 89.843858 -223.969668) (xy 89.884361 -223.997624)
			(xy 89.919854 -224.031716) (xy 89.949419 -224.07106) (xy 89.97229 -224.114637) (xy 89.987874 -224.161318)
			(xy 89.995769 -224.209895) (xy 89.996264 -224.234502) (xy 90.325206 -224.234502) (xy 90.329166 -224.185448)
			(xy 90.340943 -224.137664) (xy 90.360234 -224.092388) (xy 90.386537 -224.050792) (xy 90.419172 -224.013955)
			(xy 90.457293 -223.98283) (xy 90.499914 -223.958223) (xy 90.54593 -223.940771) (xy 90.594149 -223.930927)
			(xy 90.643324 -223.928946) (xy 90.692179 -223.934878) (xy 90.73945 -223.94857) (xy 90.783912 -223.969668)
			(xy 90.824415 -223.997624) (xy 90.859908 -224.031716) (xy 90.889473 -224.07106) (xy 90.912344 -224.114637)
			(xy 90.927928 -224.161318) (xy 90.935823 -224.209895) (xy 90.936318 -224.234502) (xy 91.26526 -224.234502)
			(xy 91.26922 -224.185448) (xy 91.280997 -224.137664) (xy 91.300288 -224.092388) (xy 91.326591 -224.050792)
			(xy 91.359226 -224.013955) (xy 91.397347 -223.98283) (xy 91.439968 -223.958223) (xy 91.485984 -223.940771)
			(xy 91.534203 -223.930927) (xy 91.583378 -223.928946) (xy 91.632233 -223.934878) (xy 91.679504 -223.94857)
			(xy 91.723966 -223.969668) (xy 91.764469 -223.997624) (xy 91.799962 -224.031716) (xy 91.829527 -224.07106)
			(xy 91.852398 -224.114637) (xy 91.867982 -224.161318) (xy 91.875877 -224.209895) (xy 91.876372 -224.234502)
			(xy 93.145114 -224.234502) (xy 93.149074 -224.185448) (xy 93.160851 -224.137664) (xy 93.180142 -224.092388)
			(xy 93.206445 -224.050792) (xy 93.23908 -224.013955) (xy 93.277201 -223.98283) (xy 93.319822 -223.958223)
			(xy 93.365838 -223.940771) (xy 93.414057 -223.930927) (xy 93.463232 -223.928946) (xy 93.512087 -223.934878)
			(xy 93.559358 -223.94857) (xy 93.60382 -223.969668) (xy 93.644323 -223.997624) (xy 93.679816 -224.031716)
			(xy 93.709381 -224.07106) (xy 93.732252 -224.114637) (xy 93.747836 -224.161318) (xy 93.755731 -224.209895)
			(xy 93.756226 -224.234502) (xy 95.965276 -224.234502) (xy 95.969236 -224.185448) (xy 95.981013 -224.137664)
			(xy 96.000304 -224.092388) (xy 96.026607 -224.050792) (xy 96.059242 -224.013955) (xy 96.097363 -223.98283)
			(xy 96.139984 -223.958223) (xy 96.186 -223.940771) (xy 96.234219 -223.930927) (xy 96.283394 -223.928946)
			(xy 96.332249 -223.934878) (xy 96.37952 -223.94857) (xy 96.423982 -223.969668) (xy 96.464485 -223.997624)
			(xy 96.499978 -224.031716) (xy 96.529543 -224.07106) (xy 96.552414 -224.114637) (xy 96.567998 -224.161318)
			(xy 96.575893 -224.209895) (xy 96.576388 -224.234502) (xy 96.90533 -224.234502) (xy 96.90929 -224.185448)
			(xy 96.921067 -224.137664) (xy 96.940358 -224.092388) (xy 96.966661 -224.050792) (xy 96.999296 -224.013955)
			(xy 97.037417 -223.98283) (xy 97.080038 -223.958223) (xy 97.126054 -223.940771) (xy 97.174273 -223.930927)
			(xy 97.223448 -223.928946) (xy 97.272303 -223.934878) (xy 97.319574 -223.94857) (xy 97.364036 -223.969668)
			(xy 97.404539 -223.997624) (xy 97.440032 -224.031716) (xy 97.469597 -224.07106) (xy 97.492468 -224.114637)
			(xy 97.508052 -224.161318) (xy 97.515947 -224.209895) (xy 97.516442 -224.234502) (xy 97.84513 -224.234502)
			(xy 97.84909 -224.185448) (xy 97.860867 -224.137664) (xy 97.880158 -224.092388) (xy 97.906461 -224.050792)
			(xy 97.939096 -224.013955) (xy 97.977217 -223.98283) (xy 98.019838 -223.958223) (xy 98.065854 -223.940771)
			(xy 98.114073 -223.930927) (xy 98.163248 -223.928946) (xy 98.212103 -223.934878) (xy 98.259374 -223.94857)
			(xy 98.303836 -223.969668) (xy 98.344339 -223.997624) (xy 98.379832 -224.031716) (xy 98.409397 -224.07106)
			(xy 98.432268 -224.114637) (xy 98.447852 -224.161318) (xy 98.455747 -224.209895) (xy 98.456242 -224.234502)
			(xy 98.785184 -224.234502) (xy 98.789144 -224.185448) (xy 98.800921 -224.137664) (xy 98.820212 -224.092388)
			(xy 98.846515 -224.050792) (xy 98.87915 -224.013955) (xy 98.917271 -223.98283) (xy 98.959892 -223.958223)
			(xy 99.005908 -223.940771) (xy 99.054127 -223.930927) (xy 99.103302 -223.928946) (xy 99.152157 -223.934878)
			(xy 99.199428 -223.94857) (xy 99.24389 -223.969668) (xy 99.284393 -223.997624) (xy 99.319886 -224.031716)
			(xy 99.349451 -224.07106) (xy 99.372322 -224.114637) (xy 99.387906 -224.161318) (xy 99.395801 -224.209895)
			(xy 99.396296 -224.234502) (xy 99.725238 -224.234502) (xy 99.729198 -224.185448) (xy 99.740975 -224.137664)
			(xy 99.760266 -224.092388) (xy 99.786569 -224.050792) (xy 99.819204 -224.013955) (xy 99.857325 -223.98283)
			(xy 99.899946 -223.958223) (xy 99.945962 -223.940771) (xy 99.994181 -223.930927) (xy 100.043356 -223.928946)
			(xy 100.092211 -223.934878) (xy 100.139482 -223.94857) (xy 100.183944 -223.969668) (xy 100.224447 -223.997624)
			(xy 100.25994 -224.031716) (xy 100.289505 -224.07106) (xy 100.312376 -224.114637) (xy 100.32796 -224.161318)
			(xy 100.335855 -224.209895) (xy 100.33635 -224.234502) (xy 100.665292 -224.234502) (xy 100.669252 -224.185448)
			(xy 100.681029 -224.137664) (xy 100.70032 -224.092388) (xy 100.726623 -224.050792) (xy 100.759258 -224.013955)
			(xy 100.797379 -223.98283) (xy 100.84 -223.958223) (xy 100.886016 -223.940771) (xy 100.934235 -223.930927)
			(xy 100.98341 -223.928946) (xy 101.032265 -223.934878) (xy 101.079536 -223.94857) (xy 101.123998 -223.969668)
			(xy 101.164501 -223.997624) (xy 101.199994 -224.031716) (xy 101.229559 -224.07106) (xy 101.25243 -224.114637)
			(xy 101.268014 -224.161318) (xy 101.275909 -224.209895) (xy 101.276404 -224.234502) (xy 101.605346 -224.234502)
			(xy 101.609306 -224.185448) (xy 101.621083 -224.137664) (xy 101.640374 -224.092388) (xy 101.666677 -224.050792)
			(xy 101.699312 -224.013955) (xy 101.737433 -223.98283) (xy 101.780054 -223.958223) (xy 101.82607 -223.940771)
			(xy 101.874289 -223.930927) (xy 101.923464 -223.928946) (xy 101.972319 -223.934878) (xy 102.01959 -223.94857)
			(xy 102.064052 -223.969668) (xy 102.104555 -223.997624) (xy 102.140048 -224.031716) (xy 102.169613 -224.07106)
			(xy 102.192484 -224.114637) (xy 102.208068 -224.161318) (xy 102.215963 -224.209895) (xy 102.216458 -224.234502)
			(xy 102.545146 -224.234502) (xy 102.549106 -224.185448) (xy 102.560883 -224.137664) (xy 102.580174 -224.092388)
			(xy 102.606477 -224.050792) (xy 102.639112 -224.013955) (xy 102.677233 -223.98283) (xy 102.719854 -223.958223)
			(xy 102.76587 -223.940771) (xy 102.814089 -223.930927) (xy 102.863264 -223.928946) (xy 102.912119 -223.934878)
			(xy 102.95939 -223.94857) (xy 103.003852 -223.969668) (xy 103.044355 -223.997624) (xy 103.079848 -224.031716)
			(xy 103.109413 -224.07106) (xy 103.132284 -224.114637) (xy 103.147868 -224.161318) (xy 103.155763 -224.209895)
			(xy 103.156258 -224.234502) (xy 103.4852 -224.234502) (xy 103.48916 -224.185448) (xy 103.500937 -224.137664)
			(xy 103.520228 -224.092388) (xy 103.546531 -224.050792) (xy 103.579166 -224.013955) (xy 103.617287 -223.98283)
			(xy 103.659908 -223.958223) (xy 103.705924 -223.940771) (xy 103.754143 -223.930927) (xy 103.803318 -223.928946)
			(xy 103.852173 -223.934878) (xy 103.899444 -223.94857) (xy 103.943906 -223.969668) (xy 103.984409 -223.997624)
			(xy 104.019902 -224.031716) (xy 104.049467 -224.07106) (xy 104.072338 -224.114637) (xy 104.087922 -224.161318)
			(xy 104.095817 -224.209895) (xy 104.096312 -224.234502) (xy 104.425254 -224.234502) (xy 104.429214 -224.185448)
			(xy 104.440991 -224.137664) (xy 104.460282 -224.092388) (xy 104.486585 -224.050792) (xy 104.51922 -224.013955)
			(xy 104.557341 -223.98283) (xy 104.599962 -223.958223) (xy 104.645978 -223.940771) (xy 104.694197 -223.930927)
			(xy 104.743372 -223.928946) (xy 104.792227 -223.934878) (xy 104.839498 -223.94857) (xy 104.88396 -223.969668)
			(xy 104.924463 -223.997624) (xy 104.959956 -224.031716) (xy 104.989521 -224.07106) (xy 105.012392 -224.114637)
			(xy 105.027976 -224.161318) (xy 105.035871 -224.209895) (xy 105.036366 -224.234502) (xy 105.365308 -224.234502)
			(xy 105.369268 -224.185448) (xy 105.381045 -224.137664) (xy 105.400336 -224.092388) (xy 105.426639 -224.050792)
			(xy 105.459274 -224.013955) (xy 105.497395 -223.98283) (xy 105.540016 -223.958223) (xy 105.586032 -223.940771)
			(xy 105.634251 -223.930927) (xy 105.683426 -223.928946) (xy 105.732281 -223.934878) (xy 105.779552 -223.94857)
			(xy 105.824014 -223.969668) (xy 105.864517 -223.997624) (xy 105.90001 -224.031716) (xy 105.929575 -224.07106)
			(xy 105.952446 -224.114637) (xy 105.96803 -224.161318) (xy 105.975925 -224.209895) (xy 105.97642 -224.234502)
			(xy 106.305362 -224.234502) (xy 106.309322 -224.185448) (xy 106.321099 -224.137664) (xy 106.34039 -224.092388)
			(xy 106.366693 -224.050792) (xy 106.399328 -224.013955) (xy 106.437449 -223.98283) (xy 106.48007 -223.958223)
			(xy 106.526086 -223.940771) (xy 106.574305 -223.930927) (xy 106.62348 -223.928946) (xy 106.672335 -223.934878)
			(xy 106.719606 -223.94857) (xy 106.764068 -223.969668) (xy 106.804571 -223.997624) (xy 106.840064 -224.031716)
			(xy 106.869629 -224.07106) (xy 106.8925 -224.114637) (xy 106.908084 -224.161318) (xy 106.915979 -224.209895)
			(xy 106.916474 -224.234502) (xy 108.185216 -224.234502) (xy 108.189176 -224.185448) (xy 108.200953 -224.137664)
			(xy 108.220244 -224.092388) (xy 108.246547 -224.050792) (xy 108.279182 -224.013955) (xy 108.317303 -223.98283)
			(xy 108.359924 -223.958223) (xy 108.40594 -223.940771) (xy 108.454159 -223.930927) (xy 108.503334 -223.928946)
			(xy 108.552189 -223.934878) (xy 108.59946 -223.94857) (xy 108.643922 -223.969668) (xy 108.684425 -223.997624)
			(xy 108.719918 -224.031716) (xy 108.749483 -224.07106) (xy 108.772354 -224.114637) (xy 108.787938 -224.161318)
			(xy 108.795833 -224.209895) (xy 108.796328 -224.234502) (xy 109.12527 -224.234502) (xy 109.12923 -224.185448)
			(xy 109.141007 -224.137664) (xy 109.160298 -224.092388) (xy 109.186601 -224.050792) (xy 109.219236 -224.013955)
			(xy 109.257357 -223.98283) (xy 109.299978 -223.958223) (xy 109.345994 -223.940771) (xy 109.394213 -223.930927)
			(xy 109.443388 -223.928946) (xy 109.492243 -223.934878) (xy 109.539514 -223.94857) (xy 109.583976 -223.969668)
			(xy 109.624479 -223.997624) (xy 109.659972 -224.031716) (xy 109.689537 -224.07106) (xy 109.712408 -224.114637)
			(xy 109.727992 -224.161318) (xy 109.735887 -224.209895) (xy 109.736382 -224.234502) (xy 109.735887 -224.259109)
			(xy 109.727992 -224.307686) (xy 109.712408 -224.354367) (xy 109.689537 -224.397944) (xy 109.659972 -224.437288)
			(xy 109.624479 -224.47138) (xy 109.583976 -224.499336) (xy 109.539514 -224.520434) (xy 109.492243 -224.534126)
			(xy 109.443388 -224.540058) (xy 109.394213 -224.538077) (xy 109.345994 -224.528233) (xy 109.299978 -224.510781)
			(xy 109.257357 -224.486174) (xy 109.219236 -224.455049) (xy 109.186601 -224.418212) (xy 109.160298 -224.376616)
			(xy 109.141007 -224.33134) (xy 109.12923 -224.283556) (xy 109.12527 -224.234502) (xy 108.796328 -224.234502)
			(xy 108.795833 -224.259109) (xy 108.787938 -224.307686) (xy 108.772354 -224.354367) (xy 108.749483 -224.397944)
			(xy 108.719918 -224.437288) (xy 108.684425 -224.47138) (xy 108.643922 -224.499336) (xy 108.59946 -224.520434)
			(xy 108.552189 -224.534126) (xy 108.503334 -224.540058) (xy 108.454159 -224.538077) (xy 108.40594 -224.528233)
			(xy 108.359924 -224.510781) (xy 108.317303 -224.486174) (xy 108.279182 -224.455049) (xy 108.246547 -224.418212)
			(xy 108.220244 -224.376616) (xy 108.200953 -224.33134) (xy 108.189176 -224.283556) (xy 108.185216 -224.234502)
			(xy 106.916474 -224.234502) (xy 106.915979 -224.259109) (xy 106.908084 -224.307686) (xy 106.8925 -224.354367)
			(xy 106.869629 -224.397944) (xy 106.840064 -224.437288) (xy 106.804571 -224.47138) (xy 106.764068 -224.499336)
			(xy 106.719606 -224.520434) (xy 106.672335 -224.534126) (xy 106.62348 -224.540058) (xy 106.574305 -224.538077)
			(xy 106.526086 -224.528233) (xy 106.48007 -224.510781) (xy 106.437449 -224.486174) (xy 106.399328 -224.455049)
			(xy 106.366693 -224.418212) (xy 106.34039 -224.376616) (xy 106.321099 -224.33134) (xy 106.309322 -224.283556)
			(xy 106.305362 -224.234502) (xy 105.97642 -224.234502) (xy 105.975925 -224.259109) (xy 105.96803 -224.307686)
			(xy 105.952446 -224.354367) (xy 105.929575 -224.397944) (xy 105.90001 -224.437288) (xy 105.864517 -224.47138)
			(xy 105.824014 -224.499336) (xy 105.779552 -224.520434) (xy 105.732281 -224.534126) (xy 105.683426 -224.540058)
			(xy 105.634251 -224.538077) (xy 105.586032 -224.528233) (xy 105.540016 -224.510781) (xy 105.497395 -224.486174)
			(xy 105.459274 -224.455049) (xy 105.426639 -224.418212) (xy 105.400336 -224.376616) (xy 105.381045 -224.33134)
			(xy 105.369268 -224.283556) (xy 105.365308 -224.234502) (xy 105.036366 -224.234502) (xy 105.035871 -224.259109)
			(xy 105.027976 -224.307686) (xy 105.012392 -224.354367) (xy 104.989521 -224.397944) (xy 104.959956 -224.437288)
			(xy 104.924463 -224.47138) (xy 104.88396 -224.499336) (xy 104.839498 -224.520434) (xy 104.792227 -224.534126)
			(xy 104.743372 -224.540058) (xy 104.694197 -224.538077) (xy 104.645978 -224.528233) (xy 104.599962 -224.510781)
			(xy 104.557341 -224.486174) (xy 104.51922 -224.455049) (xy 104.486585 -224.418212) (xy 104.460282 -224.376616)
			(xy 104.440991 -224.33134) (xy 104.429214 -224.283556) (xy 104.425254 -224.234502) (xy 104.096312 -224.234502)
			(xy 104.095817 -224.259109) (xy 104.087922 -224.307686) (xy 104.072338 -224.354367) (xy 104.049467 -224.397944)
			(xy 104.019902 -224.437288) (xy 103.984409 -224.47138) (xy 103.943906 -224.499336) (xy 103.899444 -224.520434)
			(xy 103.852173 -224.534126) (xy 103.803318 -224.540058) (xy 103.754143 -224.538077) (xy 103.705924 -224.528233)
			(xy 103.659908 -224.510781) (xy 103.617287 -224.486174) (xy 103.579166 -224.455049) (xy 103.546531 -224.418212)
			(xy 103.520228 -224.376616) (xy 103.500937 -224.33134) (xy 103.48916 -224.283556) (xy 103.4852 -224.234502)
			(xy 103.156258 -224.234502) (xy 103.155763 -224.259109) (xy 103.147868 -224.307686) (xy 103.132284 -224.354367)
			(xy 103.109413 -224.397944) (xy 103.079848 -224.437288) (xy 103.044355 -224.47138) (xy 103.003852 -224.499336)
			(xy 102.95939 -224.520434) (xy 102.912119 -224.534126) (xy 102.863264 -224.540058) (xy 102.814089 -224.538077)
			(xy 102.76587 -224.528233) (xy 102.719854 -224.510781) (xy 102.677233 -224.486174) (xy 102.639112 -224.455049)
			(xy 102.606477 -224.418212) (xy 102.580174 -224.376616) (xy 102.560883 -224.33134) (xy 102.549106 -224.283556)
			(xy 102.545146 -224.234502) (xy 102.216458 -224.234502) (xy 102.215963 -224.259109) (xy 102.208068 -224.307686)
			(xy 102.192484 -224.354367) (xy 102.169613 -224.397944) (xy 102.140048 -224.437288) (xy 102.104555 -224.47138)
			(xy 102.064052 -224.499336) (xy 102.01959 -224.520434) (xy 101.972319 -224.534126) (xy 101.923464 -224.540058)
			(xy 101.874289 -224.538077) (xy 101.82607 -224.528233) (xy 101.780054 -224.510781) (xy 101.737433 -224.486174)
			(xy 101.699312 -224.455049) (xy 101.666677 -224.418212) (xy 101.640374 -224.376616) (xy 101.621083 -224.33134)
			(xy 101.609306 -224.283556) (xy 101.605346 -224.234502) (xy 101.276404 -224.234502) (xy 101.275909 -224.259109)
			(xy 101.268014 -224.307686) (xy 101.25243 -224.354367) (xy 101.229559 -224.397944) (xy 101.199994 -224.437288)
			(xy 101.164501 -224.47138) (xy 101.123998 -224.499336) (xy 101.079536 -224.520434) (xy 101.032265 -224.534126)
			(xy 100.98341 -224.540058) (xy 100.934235 -224.538077) (xy 100.886016 -224.528233) (xy 100.84 -224.510781)
			(xy 100.797379 -224.486174) (xy 100.759258 -224.455049) (xy 100.726623 -224.418212) (xy 100.70032 -224.376616)
			(xy 100.681029 -224.33134) (xy 100.669252 -224.283556) (xy 100.665292 -224.234502) (xy 100.33635 -224.234502)
			(xy 100.335855 -224.259109) (xy 100.32796 -224.307686) (xy 100.312376 -224.354367) (xy 100.289505 -224.397944)
			(xy 100.25994 -224.437288) (xy 100.224447 -224.47138) (xy 100.183944 -224.499336) (xy 100.139482 -224.520434)
			(xy 100.092211 -224.534126) (xy 100.043356 -224.540058) (xy 99.994181 -224.538077) (xy 99.945962 -224.528233)
			(xy 99.899946 -224.510781) (xy 99.857325 -224.486174) (xy 99.819204 -224.455049) (xy 99.786569 -224.418212)
			(xy 99.760266 -224.376616) (xy 99.740975 -224.33134) (xy 99.729198 -224.283556) (xy 99.725238 -224.234502)
			(xy 99.396296 -224.234502) (xy 99.395801 -224.259109) (xy 99.387906 -224.307686) (xy 99.372322 -224.354367)
			(xy 99.349451 -224.397944) (xy 99.319886 -224.437288) (xy 99.284393 -224.47138) (xy 99.24389 -224.499336)
			(xy 99.199428 -224.520434) (xy 99.152157 -224.534126) (xy 99.103302 -224.540058) (xy 99.054127 -224.538077)
			(xy 99.005908 -224.528233) (xy 98.959892 -224.510781) (xy 98.917271 -224.486174) (xy 98.87915 -224.455049)
			(xy 98.846515 -224.418212) (xy 98.820212 -224.376616) (xy 98.800921 -224.33134) (xy 98.789144 -224.283556)
			(xy 98.785184 -224.234502) (xy 98.456242 -224.234502) (xy 98.455747 -224.259109) (xy 98.447852 -224.307686)
			(xy 98.432268 -224.354367) (xy 98.409397 -224.397944) (xy 98.379832 -224.437288) (xy 98.344339 -224.47138)
			(xy 98.303836 -224.499336) (xy 98.259374 -224.520434) (xy 98.212103 -224.534126) (xy 98.163248 -224.540058)
			(xy 98.114073 -224.538077) (xy 98.065854 -224.528233) (xy 98.019838 -224.510781) (xy 97.977217 -224.486174)
			(xy 97.939096 -224.455049) (xy 97.906461 -224.418212) (xy 97.880158 -224.376616) (xy 97.860867 -224.33134)
			(xy 97.84909 -224.283556) (xy 97.84513 -224.234502) (xy 97.516442 -224.234502) (xy 97.515947 -224.259109)
			(xy 97.508052 -224.307686) (xy 97.492468 -224.354367) (xy 97.469597 -224.397944) (xy 97.440032 -224.437288)
			(xy 97.404539 -224.47138) (xy 97.364036 -224.499336) (xy 97.319574 -224.520434) (xy 97.272303 -224.534126)
			(xy 97.223448 -224.540058) (xy 97.174273 -224.538077) (xy 97.126054 -224.528233) (xy 97.080038 -224.510781)
			(xy 97.037417 -224.486174) (xy 96.999296 -224.455049) (xy 96.966661 -224.418212) (xy 96.940358 -224.376616)
			(xy 96.921067 -224.33134) (xy 96.90929 -224.283556) (xy 96.90533 -224.234502) (xy 96.576388 -224.234502)
			(xy 96.575893 -224.259109) (xy 96.567998 -224.307686) (xy 96.552414 -224.354367) (xy 96.529543 -224.397944)
			(xy 96.499978 -224.437288) (xy 96.464485 -224.47138) (xy 96.423982 -224.499336) (xy 96.37952 -224.520434)
			(xy 96.332249 -224.534126) (xy 96.283394 -224.540058) (xy 96.234219 -224.538077) (xy 96.186 -224.528233)
			(xy 96.139984 -224.510781) (xy 96.097363 -224.486174) (xy 96.059242 -224.455049) (xy 96.026607 -224.418212)
			(xy 96.000304 -224.376616) (xy 95.981013 -224.33134) (xy 95.969236 -224.283556) (xy 95.965276 -224.234502)
			(xy 93.756226 -224.234502) (xy 93.755731 -224.259109) (xy 93.747836 -224.307686) (xy 93.732252 -224.354367)
			(xy 93.709381 -224.397944) (xy 93.679816 -224.437288) (xy 93.644323 -224.47138) (xy 93.60382 -224.499336)
			(xy 93.559358 -224.520434) (xy 93.512087 -224.534126) (xy 93.463232 -224.540058) (xy 93.414057 -224.538077)
			(xy 93.365838 -224.528233) (xy 93.319822 -224.510781) (xy 93.277201 -224.486174) (xy 93.23908 -224.455049)
			(xy 93.206445 -224.418212) (xy 93.180142 -224.376616) (xy 93.160851 -224.33134) (xy 93.149074 -224.283556)
			(xy 93.145114 -224.234502) (xy 91.876372 -224.234502) (xy 91.875877 -224.259109) (xy 91.867982 -224.307686)
			(xy 91.852398 -224.354367) (xy 91.829527 -224.397944) (xy 91.799962 -224.437288) (xy 91.764469 -224.47138)
			(xy 91.723966 -224.499336) (xy 91.679504 -224.520434) (xy 91.632233 -224.534126) (xy 91.583378 -224.540058)
			(xy 91.534203 -224.538077) (xy 91.485984 -224.528233) (xy 91.439968 -224.510781) (xy 91.397347 -224.486174)
			(xy 91.359226 -224.455049) (xy 91.326591 -224.418212) (xy 91.300288 -224.376616) (xy 91.280997 -224.33134)
			(xy 91.26922 -224.283556) (xy 91.26526 -224.234502) (xy 90.936318 -224.234502) (xy 90.935823 -224.259109)
			(xy 90.927928 -224.307686) (xy 90.912344 -224.354367) (xy 90.889473 -224.397944) (xy 90.859908 -224.437288)
			(xy 90.824415 -224.47138) (xy 90.783912 -224.499336) (xy 90.73945 -224.520434) (xy 90.692179 -224.534126)
			(xy 90.643324 -224.540058) (xy 90.594149 -224.538077) (xy 90.54593 -224.528233) (xy 90.499914 -224.510781)
			(xy 90.457293 -224.486174) (xy 90.419172 -224.455049) (xy 90.386537 -224.418212) (xy 90.360234 -224.376616)
			(xy 90.340943 -224.33134) (xy 90.329166 -224.283556) (xy 90.325206 -224.234502) (xy 89.996264 -224.234502)
			(xy 89.995769 -224.259109) (xy 89.987874 -224.307686) (xy 89.97229 -224.354367) (xy 89.949419 -224.397944)
			(xy 89.919854 -224.437288) (xy 89.884361 -224.47138) (xy 89.843858 -224.499336) (xy 89.799396 -224.520434)
			(xy 89.752125 -224.534126) (xy 89.70327 -224.540058) (xy 89.654095 -224.538077) (xy 89.605876 -224.528233)
			(xy 89.55986 -224.510781) (xy 89.517239 -224.486174) (xy 89.479118 -224.455049) (xy 89.446483 -224.418212)
			(xy 89.42018 -224.376616) (xy 89.400889 -224.33134) (xy 89.389112 -224.283556) (xy 89.385152 -224.234502)
			(xy 88.11641 -224.234502) (xy 88.115915 -224.259109) (xy 88.10802 -224.307686) (xy 88.092436 -224.354367)
			(xy 88.069565 -224.397944) (xy 88.04 -224.437288) (xy 88.004507 -224.47138) (xy 87.964004 -224.499336)
			(xy 87.919542 -224.520434) (xy 87.872271 -224.534126) (xy 87.823416 -224.540058) (xy 87.774241 -224.538077)
			(xy 87.726022 -224.528233) (xy 87.680006 -224.510781) (xy 87.637385 -224.486174) (xy 87.599264 -224.455049)
			(xy 87.566629 -224.418212) (xy 87.540326 -224.376616) (xy 87.521035 -224.33134) (xy 87.509258 -224.283556)
			(xy 87.505298 -224.234502) (xy 87.176356 -224.234502) (xy 87.175861 -224.259109) (xy 87.167966 -224.307686)
			(xy 87.152382 -224.354367) (xy 87.129511 -224.397944) (xy 87.099946 -224.437288) (xy 87.064453 -224.47138)
			(xy 87.02395 -224.499336) (xy 86.979488 -224.520434) (xy 86.932217 -224.534126) (xy 86.883362 -224.540058)
			(xy 86.834187 -224.538077) (xy 86.785968 -224.528233) (xy 86.739952 -224.510781) (xy 86.697331 -224.486174)
			(xy 86.65921 -224.455049) (xy 86.626575 -224.418212) (xy 86.600272 -224.376616) (xy 86.580981 -224.33134)
			(xy 86.569204 -224.283556) (xy 86.565244 -224.234502) (xy 85.296248 -224.234502) (xy 85.295753 -224.259109)
			(xy 85.287858 -224.307686) (xy 85.272274 -224.354367) (xy 85.249403 -224.397944) (xy 85.219838 -224.437288)
			(xy 85.184345 -224.47138) (xy 85.143842 -224.499336) (xy 85.09938 -224.520434) (xy 85.052109 -224.534126)
			(xy 85.003254 -224.540058) (xy 84.954079 -224.538077) (xy 84.90586 -224.528233) (xy 84.859844 -224.510781)
			(xy 84.817223 -224.486174) (xy 84.779102 -224.455049) (xy 84.746467 -224.418212) (xy 84.720164 -224.376616)
			(xy 84.700873 -224.33134) (xy 84.689096 -224.283556) (xy 84.685136 -224.234502) (xy 84.356448 -224.234502)
			(xy 84.355953 -224.259109) (xy 84.348058 -224.307686) (xy 84.332474 -224.354367) (xy 84.309603 -224.397944)
			(xy 84.280038 -224.437288) (xy 84.244545 -224.47138) (xy 84.204042 -224.499336) (xy 84.15958 -224.520434)
			(xy 84.112309 -224.534126) (xy 84.063454 -224.540058) (xy 84.014279 -224.538077) (xy 83.96606 -224.528233)
			(xy 83.920044 -224.510781) (xy 83.877423 -224.486174) (xy 83.839302 -224.455049) (xy 83.806667 -224.418212)
			(xy 83.780364 -224.376616) (xy 83.761073 -224.33134) (xy 83.749296 -224.283556) (xy 83.745336 -224.234502)
			(xy 83.416394 -224.234502) (xy 83.415899 -224.259109) (xy 83.408004 -224.307686) (xy 83.39242 -224.354367)
			(xy 83.369549 -224.397944) (xy 83.339984 -224.437288) (xy 83.304491 -224.47138) (xy 83.263988 -224.499336)
			(xy 83.219526 -224.520434) (xy 83.172255 -224.534126) (xy 83.1234 -224.540058) (xy 83.074225 -224.538077)
			(xy 83.026006 -224.528233) (xy 82.97999 -224.510781) (xy 82.937369 -224.486174) (xy 82.899248 -224.455049)
			(xy 82.866613 -224.418212) (xy 82.84031 -224.376616) (xy 82.821019 -224.33134) (xy 82.809242 -224.283556)
			(xy 82.805282 -224.234502) (xy 82.47634 -224.234502) (xy 82.475845 -224.259109) (xy 82.46795 -224.307686)
			(xy 82.452366 -224.354367) (xy 82.429495 -224.397944) (xy 82.39993 -224.437288) (xy 82.364437 -224.47138)
			(xy 82.323934 -224.499336) (xy 82.279472 -224.520434) (xy 82.232201 -224.534126) (xy 82.183346 -224.540058)
			(xy 82.134171 -224.538077) (xy 82.085952 -224.528233) (xy 82.039936 -224.510781) (xy 81.997315 -224.486174)
			(xy 81.959194 -224.455049) (xy 81.926559 -224.418212) (xy 81.900256 -224.376616) (xy 81.880965 -224.33134)
			(xy 81.869188 -224.283556) (xy 81.865228 -224.234502) (xy 81.536286 -224.234502) (xy 81.535791 -224.259109)
			(xy 81.527896 -224.307686) (xy 81.512312 -224.354367) (xy 81.489441 -224.397944) (xy 81.459876 -224.437288)
			(xy 81.424383 -224.47138) (xy 81.38388 -224.499336) (xy 81.339418 -224.520434) (xy 81.292147 -224.534126)
			(xy 81.243292 -224.540058) (xy 81.194117 -224.538077) (xy 81.145898 -224.528233) (xy 81.099882 -224.510781)
			(xy 81.057261 -224.486174) (xy 81.01914 -224.455049) (xy 80.986505 -224.418212) (xy 80.960202 -224.376616)
			(xy 80.940911 -224.33134) (xy 80.929134 -224.283556) (xy 80.925174 -224.234502) (xy 80.596486 -224.234502)
			(xy 80.595991 -224.259109) (xy 80.588096 -224.307686) (xy 80.572512 -224.354367) (xy 80.549641 -224.397944)
			(xy 80.520076 -224.437288) (xy 80.484583 -224.47138) (xy 80.44408 -224.499336) (xy 80.399618 -224.520434)
			(xy 80.352347 -224.534126) (xy 80.303492 -224.540058) (xy 80.254317 -224.538077) (xy 80.206098 -224.528233)
			(xy 80.160082 -224.510781) (xy 80.117461 -224.486174) (xy 80.07934 -224.455049) (xy 80.046705 -224.418212)
			(xy 80.020402 -224.376616) (xy 80.001111 -224.33134) (xy 79.989334 -224.283556) (xy 79.985374 -224.234502)
			(xy 78.716378 -224.234502) (xy 78.715883 -224.259109) (xy 78.707988 -224.307686) (xy 78.692404 -224.354367)
			(xy 78.669533 -224.397944) (xy 78.639968 -224.437288) (xy 78.604475 -224.47138) (xy 78.563972 -224.499336)
			(xy 78.51951 -224.520434) (xy 78.472239 -224.534126) (xy 78.423384 -224.540058) (xy 78.374209 -224.538077)
			(xy 78.32599 -224.528233) (xy 78.279974 -224.510781) (xy 78.237353 -224.486174) (xy 78.199232 -224.455049)
			(xy 78.166597 -224.418212) (xy 78.140294 -224.376616) (xy 78.121003 -224.33134) (xy 78.109226 -224.283556)
			(xy 78.105266 -224.234502) (xy 77.776324 -224.234502) (xy 77.775829 -224.259109) (xy 77.767934 -224.307686)
			(xy 77.75235 -224.354367) (xy 77.729479 -224.397944) (xy 77.699914 -224.437288) (xy 77.664421 -224.47138)
			(xy 77.623918 -224.499336) (xy 77.579456 -224.520434) (xy 77.532185 -224.534126) (xy 77.48333 -224.540058)
			(xy 77.434155 -224.538077) (xy 77.385936 -224.528233) (xy 77.33992 -224.510781) (xy 77.297299 -224.486174)
			(xy 77.259178 -224.455049) (xy 77.226543 -224.418212) (xy 77.20024 -224.376616) (xy 77.180949 -224.33134)
			(xy 77.169172 -224.283556) (xy 77.165212 -224.234502) (xy 62.37732 -224.234502) (xy 62.37732 -225.044508)
			(xy 76.695312 -225.044508) (xy 76.699272 -224.995454) (xy 76.711049 -224.94767) (xy 76.73034 -224.902394)
			(xy 76.756643 -224.860798) (xy 76.789278 -224.823961) (xy 76.827399 -224.792836) (xy 76.87002 -224.768229)
			(xy 76.916036 -224.750777) (xy 76.964255 -224.740933) (xy 77.01343 -224.738952) (xy 77.062285 -224.744884)
			(xy 77.109556 -224.758576) (xy 77.154018 -224.779674) (xy 77.194521 -224.80763) (xy 77.230014 -224.841722)
			(xy 77.259579 -224.881066) (xy 77.28245 -224.924643) (xy 77.298034 -224.971324) (xy 77.305929 -225.019901)
			(xy 77.306424 -225.044508) (xy 78.575166 -225.044508) (xy 78.579126 -224.995454) (xy 78.590903 -224.94767)
			(xy 78.610194 -224.902394) (xy 78.636497 -224.860798) (xy 78.669132 -224.823961) (xy 78.707253 -224.792836)
			(xy 78.749874 -224.768229) (xy 78.79589 -224.750777) (xy 78.844109 -224.740933) (xy 78.893284 -224.738952)
			(xy 78.942139 -224.744884) (xy 78.98941 -224.758576) (xy 79.033872 -224.779674) (xy 79.074375 -224.80763)
			(xy 79.109868 -224.841722) (xy 79.139433 -224.881066) (xy 79.162304 -224.924643) (xy 79.177888 -224.971324)
			(xy 79.185783 -225.019901) (xy 79.186278 -225.044508) (xy 79.51522 -225.044508) (xy 79.51918 -224.995454)
			(xy 79.530957 -224.94767) (xy 79.550248 -224.902394) (xy 79.576551 -224.860798) (xy 79.609186 -224.823961)
			(xy 79.647307 -224.792836) (xy 79.689928 -224.768229) (xy 79.735944 -224.750777) (xy 79.784163 -224.740933)
			(xy 79.833338 -224.738952) (xy 79.882193 -224.744884) (xy 79.929464 -224.758576) (xy 79.973926 -224.779674)
			(xy 80.014429 -224.80763) (xy 80.049922 -224.841722) (xy 80.079487 -224.881066) (xy 80.102358 -224.924643)
			(xy 80.117942 -224.971324) (xy 80.125837 -225.019901) (xy 80.126332 -225.044508) (xy 80.444843 -225.044508)
			(xy 80.448938 -224.99378) (xy 80.461117 -224.944366) (xy 80.481065 -224.897546) (xy 80.508266 -224.854532)
			(xy 80.542014 -224.816438) (xy 80.581436 -224.784251) (xy 80.62551 -224.758805) (xy 80.673096 -224.740758)
			(xy 80.72296 -224.730578) (xy 80.773812 -224.728529) (xy 80.824333 -224.734663) (xy 80.873217 -224.748823)
			(xy 80.919196 -224.77064) (xy 80.96108 -224.79955) (xy 80.997784 -224.834805) (xy 81.028357 -224.875491)
			(xy 81.052008 -224.920554) (xy 81.068124 -224.968828) (xy 81.076288 -225.019062) (xy 81.0768 -225.044508)
			(xy 81.395328 -225.044508) (xy 81.399288 -224.995454) (xy 81.411065 -224.94767) (xy 81.430356 -224.902394)
			(xy 81.456659 -224.860798) (xy 81.489294 -224.823961) (xy 81.527415 -224.792836) (xy 81.570036 -224.768229)
			(xy 81.616052 -224.750777) (xy 81.664271 -224.740933) (xy 81.713446 -224.738952) (xy 81.762301 -224.744884)
			(xy 81.809572 -224.758576) (xy 81.854034 -224.779674) (xy 81.894537 -224.80763) (xy 81.93003 -224.841722)
			(xy 81.959595 -224.881066) (xy 81.982466 -224.924643) (xy 81.99805 -224.971324) (xy 82.005945 -225.019901)
			(xy 82.00644 -225.044508) (xy 82.335128 -225.044508) (xy 82.339088 -224.995454) (xy 82.350865 -224.94767)
			(xy 82.370156 -224.902394) (xy 82.396459 -224.860798) (xy 82.429094 -224.823961) (xy 82.467215 -224.792836)
			(xy 82.509836 -224.768229) (xy 82.555852 -224.750777) (xy 82.604071 -224.740933) (xy 82.653246 -224.738952)
			(xy 82.702101 -224.744884) (xy 82.749372 -224.758576) (xy 82.793834 -224.779674) (xy 82.834337 -224.80763)
			(xy 82.86983 -224.841722) (xy 82.899395 -224.881066) (xy 82.922266 -224.924643) (xy 82.93785 -224.971324)
			(xy 82.945745 -225.019901) (xy 82.94624 -225.044508) (xy 83.275182 -225.044508) (xy 83.279142 -224.995454)
			(xy 83.290919 -224.94767) (xy 83.31021 -224.902394) (xy 83.336513 -224.860798) (xy 83.369148 -224.823961)
			(xy 83.407269 -224.792836) (xy 83.44989 -224.768229) (xy 83.495906 -224.750777) (xy 83.544125 -224.740933)
			(xy 83.5933 -224.738952) (xy 83.642155 -224.744884) (xy 83.689426 -224.758576) (xy 83.733888 -224.779674)
			(xy 83.774391 -224.80763) (xy 83.809884 -224.841722) (xy 83.839449 -224.881066) (xy 83.86232 -224.924643)
			(xy 83.877904 -224.971324) (xy 83.885799 -225.019901) (xy 83.886294 -225.044508) (xy 84.204805 -225.044508)
			(xy 84.2089 -224.99378) (xy 84.221079 -224.944366) (xy 84.241027 -224.897546) (xy 84.268228 -224.854532)
			(xy 84.301976 -224.816438) (xy 84.341398 -224.784251) (xy 84.385472 -224.758805) (xy 84.433058 -224.740758)
			(xy 84.482922 -224.730578) (xy 84.533774 -224.728529) (xy 84.584295 -224.734663) (xy 84.633179 -224.748823)
			(xy 84.679158 -224.77064) (xy 84.721042 -224.79955) (xy 84.757746 -224.834805) (xy 84.788319 -224.875491)
			(xy 84.81197 -224.920554) (xy 84.828086 -224.968828) (xy 84.83625 -225.019062) (xy 84.836762 -225.044508)
			(xy 85.15529 -225.044508) (xy 85.15925 -224.995454) (xy 85.171027 -224.94767) (xy 85.190318 -224.902394)
			(xy 85.216621 -224.860798) (xy 85.249256 -224.823961) (xy 85.287377 -224.792836) (xy 85.329998 -224.768229)
			(xy 85.376014 -224.750777) (xy 85.424233 -224.740933) (xy 85.473408 -224.738952) (xy 85.522263 -224.744884)
			(xy 85.569534 -224.758576) (xy 85.613996 -224.779674) (xy 85.654499 -224.80763) (xy 85.689992 -224.841722)
			(xy 85.719557 -224.881066) (xy 85.742428 -224.924643) (xy 85.758012 -224.971324) (xy 85.765907 -225.019901)
			(xy 85.766402 -225.044508) (xy 86.095344 -225.044508) (xy 86.099304 -224.995454) (xy 86.111081 -224.94767)
			(xy 86.130372 -224.902394) (xy 86.156675 -224.860798) (xy 86.18931 -224.823961) (xy 86.227431 -224.792836)
			(xy 86.270052 -224.768229) (xy 86.316068 -224.750777) (xy 86.364287 -224.740933) (xy 86.413462 -224.738952)
			(xy 86.462317 -224.744884) (xy 86.509588 -224.758576) (xy 86.55405 -224.779674) (xy 86.594553 -224.80763)
			(xy 86.630046 -224.841722) (xy 86.659611 -224.881066) (xy 86.682482 -224.924643) (xy 86.698066 -224.971324)
			(xy 86.705961 -225.019901) (xy 86.706456 -225.044508) (xy 87.024713 -225.044508) (xy 87.028808 -224.99378)
			(xy 87.040987 -224.944366) (xy 87.060935 -224.897546) (xy 87.088136 -224.854532) (xy 87.121884 -224.816438)
			(xy 87.161306 -224.784251) (xy 87.20538 -224.758805) (xy 87.252966 -224.740758) (xy 87.30283 -224.730578)
			(xy 87.353682 -224.728529) (xy 87.404203 -224.734663) (xy 87.453087 -224.748823) (xy 87.499066 -224.77064)
			(xy 87.54095 -224.79955) (xy 87.577654 -224.834805) (xy 87.608227 -224.875491) (xy 87.631878 -224.920554)
			(xy 87.647994 -224.968828) (xy 87.656158 -225.019062) (xy 87.65667 -225.044508) (xy 87.975198 -225.044508)
			(xy 87.979158 -224.995454) (xy 87.990935 -224.94767) (xy 88.010226 -224.902394) (xy 88.036529 -224.860798)
			(xy 88.069164 -224.823961) (xy 88.107285 -224.792836) (xy 88.149906 -224.768229) (xy 88.195922 -224.750777)
			(xy 88.244141 -224.740933) (xy 88.293316 -224.738952) (xy 88.342171 -224.744884) (xy 88.389442 -224.758576)
			(xy 88.433904 -224.779674) (xy 88.474407 -224.80763) (xy 88.5099 -224.841722) (xy 88.539465 -224.881066)
			(xy 88.562336 -224.924643) (xy 88.57792 -224.971324) (xy 88.585815 -225.019901) (xy 88.58631 -225.044508)
			(xy 88.915252 -225.044508) (xy 88.919212 -224.995454) (xy 88.930989 -224.94767) (xy 88.95028 -224.902394)
			(xy 88.976583 -224.860798) (xy 89.009218 -224.823961) (xy 89.047339 -224.792836) (xy 89.08996 -224.768229)
			(xy 89.135976 -224.750777) (xy 89.184195 -224.740933) (xy 89.23337 -224.738952) (xy 89.282225 -224.744884)
			(xy 89.329496 -224.758576) (xy 89.373958 -224.779674) (xy 89.414461 -224.80763) (xy 89.449954 -224.841722)
			(xy 89.479519 -224.881066) (xy 89.50239 -224.924643) (xy 89.517974 -224.971324) (xy 89.525869 -225.019901)
			(xy 89.526364 -225.044508) (xy 89.855306 -225.044508) (xy 89.859266 -224.995454) (xy 89.871043 -224.94767)
			(xy 89.890334 -224.902394) (xy 89.916637 -224.860798) (xy 89.949272 -224.823961) (xy 89.987393 -224.792836)
			(xy 90.030014 -224.768229) (xy 90.07603 -224.750777) (xy 90.124249 -224.740933) (xy 90.173424 -224.738952)
			(xy 90.222279 -224.744884) (xy 90.26955 -224.758576) (xy 90.314012 -224.779674) (xy 90.354515 -224.80763)
			(xy 90.390008 -224.841722) (xy 90.419573 -224.881066) (xy 90.442444 -224.924643) (xy 90.458028 -224.971324)
			(xy 90.465923 -225.019901) (xy 90.466418 -225.044508) (xy 90.784675 -225.044508) (xy 90.78877 -224.99378)
			(xy 90.800949 -224.944366) (xy 90.820897 -224.897546) (xy 90.848098 -224.854532) (xy 90.881846 -224.816438)
			(xy 90.921268 -224.784251) (xy 90.965342 -224.758805) (xy 91.012928 -224.740758) (xy 91.062792 -224.730578)
			(xy 91.113644 -224.728529) (xy 91.164165 -224.734663) (xy 91.213049 -224.748823) (xy 91.259028 -224.77064)
			(xy 91.300912 -224.79955) (xy 91.337616 -224.834805) (xy 91.368189 -224.875491) (xy 91.39184 -224.920554)
			(xy 91.407956 -224.968828) (xy 91.41612 -225.019062) (xy 91.416632 -225.044508) (xy 91.73516 -225.044508)
			(xy 91.73912 -224.995454) (xy 91.750897 -224.94767) (xy 91.770188 -224.902394) (xy 91.796491 -224.860798)
			(xy 91.829126 -224.823961) (xy 91.867247 -224.792836) (xy 91.909868 -224.768229) (xy 91.955884 -224.750777)
			(xy 92.004103 -224.740933) (xy 92.053278 -224.738952) (xy 92.102133 -224.744884) (xy 92.149404 -224.758576)
			(xy 92.193866 -224.779674) (xy 92.234369 -224.80763) (xy 92.269862 -224.841722) (xy 92.299427 -224.881066)
			(xy 92.322298 -224.924643) (xy 92.337882 -224.971324) (xy 92.345777 -225.019901) (xy 92.346272 -225.044508)
			(xy 92.675214 -225.044508) (xy 92.679174 -224.995454) (xy 92.690951 -224.94767) (xy 92.710242 -224.902394)
			(xy 92.736545 -224.860798) (xy 92.76918 -224.823961) (xy 92.807301 -224.792836) (xy 92.849922 -224.768229)
			(xy 92.895938 -224.750777) (xy 92.944157 -224.740933) (xy 92.993332 -224.738952) (xy 93.042187 -224.744884)
			(xy 93.089458 -224.758576) (xy 93.13392 -224.779674) (xy 93.174423 -224.80763) (xy 93.209916 -224.841722)
			(xy 93.239481 -224.881066) (xy 93.262352 -224.924643) (xy 93.277936 -224.971324) (xy 93.285831 -225.019901)
			(xy 93.286326 -225.044508) (xy 93.604837 -225.044508) (xy 93.608932 -224.99378) (xy 93.621111 -224.944366)
			(xy 93.641059 -224.897546) (xy 93.66826 -224.854532) (xy 93.702008 -224.816438) (xy 93.74143 -224.784251)
			(xy 93.785504 -224.758805) (xy 93.83309 -224.740758) (xy 93.882954 -224.730578) (xy 93.933806 -224.728529)
			(xy 93.984327 -224.734663) (xy 94.033211 -224.748823) (xy 94.07919 -224.77064) (xy 94.121074 -224.79955)
			(xy 94.157778 -224.834805) (xy 94.188351 -224.875491) (xy 94.212002 -224.920554) (xy 94.228118 -224.968828)
			(xy 94.236282 -225.019062) (xy 94.236794 -225.044508) (xy 94.555322 -225.044508) (xy 94.559282 -224.995454)
			(xy 94.571059 -224.94767) (xy 94.59035 -224.902394) (xy 94.616653 -224.860798) (xy 94.649288 -224.823961)
			(xy 94.687409 -224.792836) (xy 94.73003 -224.768229) (xy 94.776046 -224.750777) (xy 94.824265 -224.740933)
			(xy 94.87344 -224.738952) (xy 94.922295 -224.744884) (xy 94.969566 -224.758576) (xy 95.014028 -224.779674)
			(xy 95.054531 -224.80763) (xy 95.090024 -224.841722) (xy 95.119589 -224.881066) (xy 95.14246 -224.924643)
			(xy 95.158044 -224.971324) (xy 95.165939 -225.019901) (xy 95.166434 -225.044508) (xy 95.495122 -225.044508)
			(xy 95.499082 -224.995454) (xy 95.510859 -224.94767) (xy 95.53015 -224.902394) (xy 95.556453 -224.860798)
			(xy 95.589088 -224.823961) (xy 95.627209 -224.792836) (xy 95.66983 -224.768229) (xy 95.715846 -224.750777)
			(xy 95.764065 -224.740933) (xy 95.81324 -224.738952) (xy 95.862095 -224.744884) (xy 95.909366 -224.758576)
			(xy 95.953828 -224.779674) (xy 95.994331 -224.80763) (xy 96.029824 -224.841722) (xy 96.059389 -224.881066)
			(xy 96.08226 -224.924643) (xy 96.097844 -224.971324) (xy 96.105739 -225.019901) (xy 96.106234 -225.044508)
			(xy 97.37523 -225.044508) (xy 97.37919 -224.995454) (xy 97.390967 -224.94767) (xy 97.410258 -224.902394)
			(xy 97.436561 -224.860798) (xy 97.469196 -224.823961) (xy 97.507317 -224.792836) (xy 97.549938 -224.768229)
			(xy 97.595954 -224.750777) (xy 97.644173 -224.740933) (xy 97.693348 -224.738952) (xy 97.742203 -224.744884)
			(xy 97.789474 -224.758576) (xy 97.833936 -224.779674) (xy 97.874439 -224.80763) (xy 97.909932 -224.841722)
			(xy 97.939497 -224.881066) (xy 97.962368 -224.924643) (xy 97.977952 -224.971324) (xy 97.985847 -225.019901)
			(xy 97.986342 -225.044508) (xy 98.315284 -225.044508) (xy 98.319244 -224.995454) (xy 98.331021 -224.94767)
			(xy 98.350312 -224.902394) (xy 98.376615 -224.860798) (xy 98.40925 -224.823961) (xy 98.447371 -224.792836)
			(xy 98.489992 -224.768229) (xy 98.536008 -224.750777) (xy 98.584227 -224.740933) (xy 98.633402 -224.738952)
			(xy 98.682257 -224.744884) (xy 98.729528 -224.758576) (xy 98.77399 -224.779674) (xy 98.814493 -224.80763)
			(xy 98.849986 -224.841722) (xy 98.879551 -224.881066) (xy 98.902422 -224.924643) (xy 98.918006 -224.971324)
			(xy 98.925901 -225.019901) (xy 98.926396 -225.044508) (xy 100.195138 -225.044508) (xy 100.199098 -224.995454)
			(xy 100.210875 -224.94767) (xy 100.230166 -224.902394) (xy 100.256469 -224.860798) (xy 100.289104 -224.823961)
			(xy 100.327225 -224.792836) (xy 100.369846 -224.768229) (xy 100.415862 -224.750777) (xy 100.464081 -224.740933)
			(xy 100.513256 -224.738952) (xy 100.562111 -224.744884) (xy 100.609382 -224.758576) (xy 100.653844 -224.779674)
			(xy 100.694347 -224.80763) (xy 100.72984 -224.841722) (xy 100.759405 -224.881066) (xy 100.782276 -224.924643)
			(xy 100.79786 -224.971324) (xy 100.805755 -225.019901) (xy 100.80625 -225.044508) (xy 101.135192 -225.044508)
			(xy 101.139152 -224.995454) (xy 101.150929 -224.94767) (xy 101.17022 -224.902394) (xy 101.196523 -224.860798)
			(xy 101.229158 -224.823961) (xy 101.267279 -224.792836) (xy 101.3099 -224.768229) (xy 101.355916 -224.750777)
			(xy 101.404135 -224.740933) (xy 101.45331 -224.738952) (xy 101.502165 -224.744884) (xy 101.549436 -224.758576)
			(xy 101.593898 -224.779674) (xy 101.634401 -224.80763) (xy 101.669894 -224.841722) (xy 101.699459 -224.881066)
			(xy 101.72233 -224.924643) (xy 101.737914 -224.971324) (xy 101.745809 -225.019901) (xy 101.746304 -225.044508)
			(xy 103.0153 -225.044508) (xy 103.01926 -224.995454) (xy 103.031037 -224.94767) (xy 103.050328 -224.902394)
			(xy 103.076631 -224.860798) (xy 103.109266 -224.823961) (xy 103.147387 -224.792836) (xy 103.190008 -224.768229)
			(xy 103.236024 -224.750777) (xy 103.284243 -224.740933) (xy 103.333418 -224.738952) (xy 103.382273 -224.744884)
			(xy 103.429544 -224.758576) (xy 103.474006 -224.779674) (xy 103.514509 -224.80763) (xy 103.550002 -224.841722)
			(xy 103.579567 -224.881066) (xy 103.602438 -224.924643) (xy 103.618022 -224.971324) (xy 103.625917 -225.019901)
			(xy 103.626412 -225.044508) (xy 103.955354 -225.044508) (xy 103.959314 -224.995454) (xy 103.971091 -224.94767)
			(xy 103.990382 -224.902394) (xy 104.016685 -224.860798) (xy 104.04932 -224.823961) (xy 104.087441 -224.792836)
			(xy 104.130062 -224.768229) (xy 104.176078 -224.750777) (xy 104.224297 -224.740933) (xy 104.273472 -224.738952)
			(xy 104.322327 -224.744884) (xy 104.369598 -224.758576) (xy 104.41406 -224.779674) (xy 104.454563 -224.80763)
			(xy 104.490056 -224.841722) (xy 104.519621 -224.881066) (xy 104.542492 -224.924643) (xy 104.558076 -224.971324)
			(xy 104.565971 -225.019901) (xy 104.566466 -225.044508) (xy 104.565971 -225.069115) (xy 104.558076 -225.117692)
			(xy 104.542492 -225.164373) (xy 104.519621 -225.20795) (xy 104.490056 -225.247294) (xy 104.454563 -225.281386)
			(xy 104.41406 -225.309342) (xy 104.369598 -225.33044) (xy 104.322327 -225.344132) (xy 104.273472 -225.350064)
			(xy 104.224297 -225.348083) (xy 104.176078 -225.338239) (xy 104.130062 -225.320787) (xy 104.087441 -225.29618)
			(xy 104.04932 -225.265055) (xy 104.016685 -225.228218) (xy 103.990382 -225.186622) (xy 103.971091 -225.141346)
			(xy 103.959314 -225.093562) (xy 103.955354 -225.044508) (xy 103.626412 -225.044508) (xy 103.625917 -225.069115)
			(xy 103.618022 -225.117692) (xy 103.602438 -225.164373) (xy 103.579567 -225.20795) (xy 103.550002 -225.247294)
			(xy 103.514509 -225.281386) (xy 103.474006 -225.309342) (xy 103.429544 -225.33044) (xy 103.382273 -225.344132)
			(xy 103.333418 -225.350064) (xy 103.284243 -225.348083) (xy 103.236024 -225.338239) (xy 103.190008 -225.320787)
			(xy 103.147387 -225.29618) (xy 103.109266 -225.265055) (xy 103.076631 -225.228218) (xy 103.050328 -225.186622)
			(xy 103.031037 -225.141346) (xy 103.01926 -225.093562) (xy 103.0153 -225.044508) (xy 101.746304 -225.044508)
			(xy 101.745809 -225.069115) (xy 101.737914 -225.117692) (xy 101.72233 -225.164373) (xy 101.699459 -225.20795)
			(xy 101.669894 -225.247294) (xy 101.634401 -225.281386) (xy 101.593898 -225.309342) (xy 101.549436 -225.33044)
			(xy 101.502165 -225.344132) (xy 101.45331 -225.350064) (xy 101.404135 -225.348083) (xy 101.355916 -225.338239)
			(xy 101.3099 -225.320787) (xy 101.267279 -225.29618) (xy 101.229158 -225.265055) (xy 101.196523 -225.228218)
			(xy 101.17022 -225.186622) (xy 101.150929 -225.141346) (xy 101.139152 -225.093562) (xy 101.135192 -225.044508)
			(xy 100.80625 -225.044508) (xy 100.805755 -225.069115) (xy 100.79786 -225.117692) (xy 100.782276 -225.164373)
			(xy 100.759405 -225.20795) (xy 100.72984 -225.247294) (xy 100.694347 -225.281386) (xy 100.653844 -225.309342)
			(xy 100.609382 -225.33044) (xy 100.562111 -225.344132) (xy 100.513256 -225.350064) (xy 100.464081 -225.348083)
			(xy 100.415862 -225.338239) (xy 100.369846 -225.320787) (xy 100.327225 -225.29618) (xy 100.289104 -225.265055)
			(xy 100.256469 -225.228218) (xy 100.230166 -225.186622) (xy 100.210875 -225.141346) (xy 100.199098 -225.093562)
			(xy 100.195138 -225.044508) (xy 98.926396 -225.044508) (xy 98.925901 -225.069115) (xy 98.918006 -225.117692)
			(xy 98.902422 -225.164373) (xy 98.879551 -225.20795) (xy 98.849986 -225.247294) (xy 98.814493 -225.281386)
			(xy 98.77399 -225.309342) (xy 98.729528 -225.33044) (xy 98.682257 -225.344132) (xy 98.633402 -225.350064)
			(xy 98.584227 -225.348083) (xy 98.536008 -225.338239) (xy 98.489992 -225.320787) (xy 98.447371 -225.29618)
			(xy 98.40925 -225.265055) (xy 98.376615 -225.228218) (xy 98.350312 -225.186622) (xy 98.331021 -225.141346)
			(xy 98.319244 -225.093562) (xy 98.315284 -225.044508) (xy 97.986342 -225.044508) (xy 97.985847 -225.069115)
			(xy 97.977952 -225.117692) (xy 97.962368 -225.164373) (xy 97.939497 -225.20795) (xy 97.909932 -225.247294)
			(xy 97.874439 -225.281386) (xy 97.833936 -225.309342) (xy 97.789474 -225.33044) (xy 97.742203 -225.344132)
			(xy 97.693348 -225.350064) (xy 97.644173 -225.348083) (xy 97.595954 -225.338239) (xy 97.549938 -225.320787)
			(xy 97.507317 -225.29618) (xy 97.469196 -225.265055) (xy 97.436561 -225.228218) (xy 97.410258 -225.186622)
			(xy 97.390967 -225.141346) (xy 97.37919 -225.093562) (xy 97.37523 -225.044508) (xy 96.106234 -225.044508)
			(xy 96.105739 -225.069115) (xy 96.097844 -225.117692) (xy 96.08226 -225.164373) (xy 96.059389 -225.20795)
			(xy 96.029824 -225.247294) (xy 95.994331 -225.281386) (xy 95.953828 -225.309342) (xy 95.909366 -225.33044)
			(xy 95.862095 -225.344132) (xy 95.81324 -225.350064) (xy 95.764065 -225.348083) (xy 95.715846 -225.338239)
			(xy 95.66983 -225.320787) (xy 95.627209 -225.29618) (xy 95.589088 -225.265055) (xy 95.556453 -225.228218)
			(xy 95.53015 -225.186622) (xy 95.510859 -225.141346) (xy 95.499082 -225.093562) (xy 95.495122 -225.044508)
			(xy 95.166434 -225.044508) (xy 95.165939 -225.069115) (xy 95.158044 -225.117692) (xy 95.14246 -225.164373)
			(xy 95.119589 -225.20795) (xy 95.090024 -225.247294) (xy 95.054531 -225.281386) (xy 95.014028 -225.309342)
			(xy 94.969566 -225.33044) (xy 94.922295 -225.344132) (xy 94.87344 -225.350064) (xy 94.824265 -225.348083)
			(xy 94.776046 -225.338239) (xy 94.73003 -225.320787) (xy 94.687409 -225.29618) (xy 94.649288 -225.265055)
			(xy 94.616653 -225.228218) (xy 94.59035 -225.186622) (xy 94.571059 -225.141346) (xy 94.559282 -225.093562)
			(xy 94.555322 -225.044508) (xy 94.236794 -225.044508) (xy 94.236282 -225.069954) (xy 94.228118 -225.120188)
			(xy 94.212002 -225.168462) (xy 94.188351 -225.213525) (xy 94.157778 -225.254211) (xy 94.121074 -225.289466)
			(xy 94.07919 -225.318376) (xy 94.033211 -225.340193) (xy 93.984327 -225.354353) (xy 93.933806 -225.360487)
			(xy 93.882954 -225.358438) (xy 93.83309 -225.348258) (xy 93.785504 -225.330211) (xy 93.74143 -225.304765)
			(xy 93.702008 -225.272578) (xy 93.66826 -225.234484) (xy 93.641059 -225.19147) (xy 93.621111 -225.14465)
			(xy 93.608932 -225.095236) (xy 93.604837 -225.044508) (xy 93.286326 -225.044508) (xy 93.285831 -225.069115)
			(xy 93.277936 -225.117692) (xy 93.262352 -225.164373) (xy 93.239481 -225.20795) (xy 93.209916 -225.247294)
			(xy 93.174423 -225.281386) (xy 93.13392 -225.309342) (xy 93.089458 -225.33044) (xy 93.042187 -225.344132)
			(xy 92.993332 -225.350064) (xy 92.944157 -225.348083) (xy 92.895938 -225.338239) (xy 92.849922 -225.320787)
			(xy 92.807301 -225.29618) (xy 92.76918 -225.265055) (xy 92.736545 -225.228218) (xy 92.710242 -225.186622)
			(xy 92.690951 -225.141346) (xy 92.679174 -225.093562) (xy 92.675214 -225.044508) (xy 92.346272 -225.044508)
			(xy 92.345777 -225.069115) (xy 92.337882 -225.117692) (xy 92.322298 -225.164373) (xy 92.299427 -225.20795)
			(xy 92.269862 -225.247294) (xy 92.234369 -225.281386) (xy 92.193866 -225.309342) (xy 92.149404 -225.33044)
			(xy 92.102133 -225.344132) (xy 92.053278 -225.350064) (xy 92.004103 -225.348083) (xy 91.955884 -225.338239)
			(xy 91.909868 -225.320787) (xy 91.867247 -225.29618) (xy 91.829126 -225.265055) (xy 91.796491 -225.228218)
			(xy 91.770188 -225.186622) (xy 91.750897 -225.141346) (xy 91.73912 -225.093562) (xy 91.73516 -225.044508)
			(xy 91.416632 -225.044508) (xy 91.41612 -225.069954) (xy 91.407956 -225.120188) (xy 91.39184 -225.168462)
			(xy 91.368189 -225.213525) (xy 91.337616 -225.254211) (xy 91.300912 -225.289466) (xy 91.259028 -225.318376)
			(xy 91.213049 -225.340193) (xy 91.164165 -225.354353) (xy 91.113644 -225.360487) (xy 91.062792 -225.358438)
			(xy 91.012928 -225.348258) (xy 90.965342 -225.330211) (xy 90.921268 -225.304765) (xy 90.881846 -225.272578)
			(xy 90.848098 -225.234484) (xy 90.820897 -225.19147) (xy 90.800949 -225.14465) (xy 90.78877 -225.095236)
			(xy 90.784675 -225.044508) (xy 90.466418 -225.044508) (xy 90.465923 -225.069115) (xy 90.458028 -225.117692)
			(xy 90.442444 -225.164373) (xy 90.419573 -225.20795) (xy 90.390008 -225.247294) (xy 90.354515 -225.281386)
			(xy 90.314012 -225.309342) (xy 90.26955 -225.33044) (xy 90.222279 -225.344132) (xy 90.173424 -225.350064)
			(xy 90.124249 -225.348083) (xy 90.07603 -225.338239) (xy 90.030014 -225.320787) (xy 89.987393 -225.29618)
			(xy 89.949272 -225.265055) (xy 89.916637 -225.228218) (xy 89.890334 -225.186622) (xy 89.871043 -225.141346)
			(xy 89.859266 -225.093562) (xy 89.855306 -225.044508) (xy 89.526364 -225.044508) (xy 89.525869 -225.069115)
			(xy 89.517974 -225.117692) (xy 89.50239 -225.164373) (xy 89.479519 -225.20795) (xy 89.449954 -225.247294)
			(xy 89.414461 -225.281386) (xy 89.373958 -225.309342) (xy 89.329496 -225.33044) (xy 89.282225 -225.344132)
			(xy 89.23337 -225.350064) (xy 89.184195 -225.348083) (xy 89.135976 -225.338239) (xy 89.08996 -225.320787)
			(xy 89.047339 -225.29618) (xy 89.009218 -225.265055) (xy 88.976583 -225.228218) (xy 88.95028 -225.186622)
			(xy 88.930989 -225.141346) (xy 88.919212 -225.093562) (xy 88.915252 -225.044508) (xy 88.58631 -225.044508)
			(xy 88.585815 -225.069115) (xy 88.57792 -225.117692) (xy 88.562336 -225.164373) (xy 88.539465 -225.20795)
			(xy 88.5099 -225.247294) (xy 88.474407 -225.281386) (xy 88.433904 -225.309342) (xy 88.389442 -225.33044)
			(xy 88.342171 -225.344132) (xy 88.293316 -225.350064) (xy 88.244141 -225.348083) (xy 88.195922 -225.338239)
			(xy 88.149906 -225.320787) (xy 88.107285 -225.29618) (xy 88.069164 -225.265055) (xy 88.036529 -225.228218)
			(xy 88.010226 -225.186622) (xy 87.990935 -225.141346) (xy 87.979158 -225.093562) (xy 87.975198 -225.044508)
			(xy 87.65667 -225.044508) (xy 87.656158 -225.069954) (xy 87.647994 -225.120188) (xy 87.631878 -225.168462)
			(xy 87.608227 -225.213525) (xy 87.577654 -225.254211) (xy 87.54095 -225.289466) (xy 87.499066 -225.318376)
			(xy 87.453087 -225.340193) (xy 87.404203 -225.354353) (xy 87.353682 -225.360487) (xy 87.30283 -225.358438)
			(xy 87.252966 -225.348258) (xy 87.20538 -225.330211) (xy 87.161306 -225.304765) (xy 87.121884 -225.272578)
			(xy 87.088136 -225.234484) (xy 87.060935 -225.19147) (xy 87.040987 -225.14465) (xy 87.028808 -225.095236)
			(xy 87.024713 -225.044508) (xy 86.706456 -225.044508) (xy 86.705961 -225.069115) (xy 86.698066 -225.117692)
			(xy 86.682482 -225.164373) (xy 86.659611 -225.20795) (xy 86.630046 -225.247294) (xy 86.594553 -225.281386)
			(xy 86.55405 -225.309342) (xy 86.509588 -225.33044) (xy 86.462317 -225.344132) (xy 86.413462 -225.350064)
			(xy 86.364287 -225.348083) (xy 86.316068 -225.338239) (xy 86.270052 -225.320787) (xy 86.227431 -225.29618)
			(xy 86.18931 -225.265055) (xy 86.156675 -225.228218) (xy 86.130372 -225.186622) (xy 86.111081 -225.141346)
			(xy 86.099304 -225.093562) (xy 86.095344 -225.044508) (xy 85.766402 -225.044508) (xy 85.765907 -225.069115)
			(xy 85.758012 -225.117692) (xy 85.742428 -225.164373) (xy 85.719557 -225.20795) (xy 85.689992 -225.247294)
			(xy 85.654499 -225.281386) (xy 85.613996 -225.309342) (xy 85.569534 -225.33044) (xy 85.522263 -225.344132)
			(xy 85.473408 -225.350064) (xy 85.424233 -225.348083) (xy 85.376014 -225.338239) (xy 85.329998 -225.320787)
			(xy 85.287377 -225.29618) (xy 85.249256 -225.265055) (xy 85.216621 -225.228218) (xy 85.190318 -225.186622)
			(xy 85.171027 -225.141346) (xy 85.15925 -225.093562) (xy 85.15529 -225.044508) (xy 84.836762 -225.044508)
			(xy 84.83625 -225.069954) (xy 84.828086 -225.120188) (xy 84.81197 -225.168462) (xy 84.788319 -225.213525)
			(xy 84.757746 -225.254211) (xy 84.721042 -225.289466) (xy 84.679158 -225.318376) (xy 84.633179 -225.340193)
			(xy 84.584295 -225.354353) (xy 84.533774 -225.360487) (xy 84.482922 -225.358438) (xy 84.433058 -225.348258)
			(xy 84.385472 -225.330211) (xy 84.341398 -225.304765) (xy 84.301976 -225.272578) (xy 84.268228 -225.234484)
			(xy 84.241027 -225.19147) (xy 84.221079 -225.14465) (xy 84.2089 -225.095236) (xy 84.204805 -225.044508)
			(xy 83.886294 -225.044508) (xy 83.885799 -225.069115) (xy 83.877904 -225.117692) (xy 83.86232 -225.164373)
			(xy 83.839449 -225.20795) (xy 83.809884 -225.247294) (xy 83.774391 -225.281386) (xy 83.733888 -225.309342)
			(xy 83.689426 -225.33044) (xy 83.642155 -225.344132) (xy 83.5933 -225.350064) (xy 83.544125 -225.348083)
			(xy 83.495906 -225.338239) (xy 83.44989 -225.320787) (xy 83.407269 -225.29618) (xy 83.369148 -225.265055)
			(xy 83.336513 -225.228218) (xy 83.31021 -225.186622) (xy 83.290919 -225.141346) (xy 83.279142 -225.093562)
			(xy 83.275182 -225.044508) (xy 82.94624 -225.044508) (xy 82.945745 -225.069115) (xy 82.93785 -225.117692)
			(xy 82.922266 -225.164373) (xy 82.899395 -225.20795) (xy 82.86983 -225.247294) (xy 82.834337 -225.281386)
			(xy 82.793834 -225.309342) (xy 82.749372 -225.33044) (xy 82.702101 -225.344132) (xy 82.653246 -225.350064)
			(xy 82.604071 -225.348083) (xy 82.555852 -225.338239) (xy 82.509836 -225.320787) (xy 82.467215 -225.29618)
			(xy 82.429094 -225.265055) (xy 82.396459 -225.228218) (xy 82.370156 -225.186622) (xy 82.350865 -225.141346)
			(xy 82.339088 -225.093562) (xy 82.335128 -225.044508) (xy 82.00644 -225.044508) (xy 82.005945 -225.069115)
			(xy 81.99805 -225.117692) (xy 81.982466 -225.164373) (xy 81.959595 -225.20795) (xy 81.93003 -225.247294)
			(xy 81.894537 -225.281386) (xy 81.854034 -225.309342) (xy 81.809572 -225.33044) (xy 81.762301 -225.344132)
			(xy 81.713446 -225.350064) (xy 81.664271 -225.348083) (xy 81.616052 -225.338239) (xy 81.570036 -225.320787)
			(xy 81.527415 -225.29618) (xy 81.489294 -225.265055) (xy 81.456659 -225.228218) (xy 81.430356 -225.186622)
			(xy 81.411065 -225.141346) (xy 81.399288 -225.093562) (xy 81.395328 -225.044508) (xy 81.0768 -225.044508)
			(xy 81.076288 -225.069954) (xy 81.068124 -225.120188) (xy 81.052008 -225.168462) (xy 81.028357 -225.213525)
			(xy 80.997784 -225.254211) (xy 80.96108 -225.289466) (xy 80.919196 -225.318376) (xy 80.873217 -225.340193)
			(xy 80.824333 -225.354353) (xy 80.773812 -225.360487) (xy 80.72296 -225.358438) (xy 80.673096 -225.348258)
			(xy 80.62551 -225.330211) (xy 80.581436 -225.304765) (xy 80.542014 -225.272578) (xy 80.508266 -225.234484)
			(xy 80.481065 -225.19147) (xy 80.461117 -225.14465) (xy 80.448938 -225.095236) (xy 80.444843 -225.044508)
			(xy 80.126332 -225.044508) (xy 80.125837 -225.069115) (xy 80.117942 -225.117692) (xy 80.102358 -225.164373)
			(xy 80.079487 -225.20795) (xy 80.049922 -225.247294) (xy 80.014429 -225.281386) (xy 79.973926 -225.309342)
			(xy 79.929464 -225.33044) (xy 79.882193 -225.344132) (xy 79.833338 -225.350064) (xy 79.784163 -225.348083)
			(xy 79.735944 -225.338239) (xy 79.689928 -225.320787) (xy 79.647307 -225.29618) (xy 79.609186 -225.265055)
			(xy 79.576551 -225.228218) (xy 79.550248 -225.186622) (xy 79.530957 -225.141346) (xy 79.51918 -225.093562)
			(xy 79.51522 -225.044508) (xy 79.186278 -225.044508) (xy 79.185783 -225.069115) (xy 79.177888 -225.117692)
			(xy 79.162304 -225.164373) (xy 79.139433 -225.20795) (xy 79.109868 -225.247294) (xy 79.074375 -225.281386)
			(xy 79.033872 -225.309342) (xy 78.98941 -225.33044) (xy 78.942139 -225.344132) (xy 78.893284 -225.350064)
			(xy 78.844109 -225.348083) (xy 78.79589 -225.338239) (xy 78.749874 -225.320787) (xy 78.707253 -225.29618)
			(xy 78.669132 -225.265055) (xy 78.636497 -225.228218) (xy 78.610194 -225.186622) (xy 78.590903 -225.141346)
			(xy 78.579126 -225.093562) (xy 78.575166 -225.044508) (xy 77.306424 -225.044508) (xy 77.305929 -225.069115)
			(xy 77.298034 -225.117692) (xy 77.28245 -225.164373) (xy 77.259579 -225.20795) (xy 77.230014 -225.247294)
			(xy 77.194521 -225.281386) (xy 77.154018 -225.309342) (xy 77.109556 -225.33044) (xy 77.062285 -225.344132)
			(xy 77.01343 -225.350064) (xy 76.964255 -225.348083) (xy 76.916036 -225.338239) (xy 76.87002 -225.320787)
			(xy 76.827399 -225.29618) (xy 76.789278 -225.265055) (xy 76.756643 -225.228218) (xy 76.73034 -225.186622)
			(xy 76.711049 -225.141346) (xy 76.699272 -225.093562) (xy 76.695312 -225.044508) (xy 62.37732 -225.044508)
			(xy 62.37732 -225.854514) (xy 78.105266 -225.854514) (xy 78.109226 -225.80546) (xy 78.121003 -225.757676)
			(xy 78.140294 -225.7124) (xy 78.166597 -225.670804) (xy 78.199232 -225.633967) (xy 78.237353 -225.602842)
			(xy 78.279974 -225.578235) (xy 78.32599 -225.560783) (xy 78.374209 -225.550939) (xy 78.423384 -225.548958)
			(xy 78.472239 -225.55489) (xy 78.51951 -225.568582) (xy 78.563972 -225.58968) (xy 78.604475 -225.617636)
			(xy 78.639968 -225.651728) (xy 78.669533 -225.691072) (xy 78.692404 -225.734649) (xy 78.707988 -225.78133)
			(xy 78.715883 -225.829907) (xy 78.716378 -225.854514) (xy 79.985374 -225.854514) (xy 79.989334 -225.80546)
			(xy 80.001111 -225.757676) (xy 80.020402 -225.7124) (xy 80.046705 -225.670804) (xy 80.07934 -225.633967)
			(xy 80.117461 -225.602842) (xy 80.160082 -225.578235) (xy 80.206098 -225.560783) (xy 80.254317 -225.550939)
			(xy 80.303492 -225.548958) (xy 80.352347 -225.55489) (xy 80.399618 -225.568582) (xy 80.44408 -225.58968)
			(xy 80.484583 -225.617636) (xy 80.520076 -225.651728) (xy 80.549641 -225.691072) (xy 80.572512 -225.734649)
			(xy 80.588096 -225.78133) (xy 80.595991 -225.829907) (xy 80.596486 -225.854514) (xy 80.914743 -225.854514)
			(xy 80.918838 -225.803786) (xy 80.931017 -225.754372) (xy 80.950965 -225.707552) (xy 80.978166 -225.664538)
			(xy 81.011914 -225.626444) (xy 81.051336 -225.594257) (xy 81.09541 -225.568811) (xy 81.142996 -225.550764)
			(xy 81.19286 -225.540584) (xy 81.243712 -225.538535) (xy 81.294233 -225.544669) (xy 81.343117 -225.558829)
			(xy 81.389096 -225.580646) (xy 81.43098 -225.609556) (xy 81.467684 -225.644811) (xy 81.498257 -225.685497)
			(xy 81.521908 -225.73056) (xy 81.538024 -225.778834) (xy 81.546188 -225.829068) (xy 81.5467 -225.854514)
			(xy 81.854797 -225.854514) (xy 81.858892 -225.803786) (xy 81.871071 -225.754372) (xy 81.891019 -225.707552)
			(xy 81.91822 -225.664538) (xy 81.951968 -225.626444) (xy 81.99139 -225.594257) (xy 82.035464 -225.568811)
			(xy 82.08305 -225.550764) (xy 82.132914 -225.540584) (xy 82.183766 -225.538535) (xy 82.234287 -225.544669)
			(xy 82.283171 -225.558829) (xy 82.32915 -225.580646) (xy 82.371034 -225.609556) (xy 82.407738 -225.644811)
			(xy 82.438311 -225.685497) (xy 82.461962 -225.73056) (xy 82.478078 -225.778834) (xy 82.486242 -225.829068)
			(xy 82.486754 -225.854514) (xy 82.805282 -225.854514) (xy 82.809242 -225.80546) (xy 82.821019 -225.757676)
			(xy 82.84031 -225.7124) (xy 82.866613 -225.670804) (xy 82.899248 -225.633967) (xy 82.937369 -225.602842)
			(xy 82.97999 -225.578235) (xy 83.026006 -225.560783) (xy 83.074225 -225.550939) (xy 83.1234 -225.548958)
			(xy 83.172255 -225.55489) (xy 83.219526 -225.568582) (xy 83.263988 -225.58968) (xy 83.304491 -225.617636)
			(xy 83.339984 -225.651728) (xy 83.369549 -225.691072) (xy 83.39242 -225.734649) (xy 83.408004 -225.78133)
			(xy 83.415899 -225.829907) (xy 83.416394 -225.854514) (xy 83.734905 -225.854514) (xy 83.739 -225.803786)
			(xy 83.751179 -225.754372) (xy 83.771127 -225.707552) (xy 83.798328 -225.664538) (xy 83.832076 -225.626444)
			(xy 83.871498 -225.594257) (xy 83.915572 -225.568811) (xy 83.963158 -225.550764) (xy 84.013022 -225.540584)
			(xy 84.063874 -225.538535) (xy 84.114395 -225.544669) (xy 84.163279 -225.558829) (xy 84.209258 -225.580646)
			(xy 84.251142 -225.609556) (xy 84.287846 -225.644811) (xy 84.318419 -225.685497) (xy 84.34207 -225.73056)
			(xy 84.358186 -225.778834) (xy 84.36635 -225.829068) (xy 84.366862 -225.854514) (xy 84.685136 -225.854514)
			(xy 84.689096 -225.80546) (xy 84.700873 -225.757676) (xy 84.720164 -225.7124) (xy 84.746467 -225.670804)
			(xy 84.779102 -225.633967) (xy 84.817223 -225.602842) (xy 84.859844 -225.578235) (xy 84.90586 -225.560783)
			(xy 84.954079 -225.550939) (xy 85.003254 -225.548958) (xy 85.052109 -225.55489) (xy 85.09938 -225.568582)
			(xy 85.143842 -225.58968) (xy 85.184345 -225.617636) (xy 85.219838 -225.651728) (xy 85.249403 -225.691072)
			(xy 85.272274 -225.734649) (xy 85.287858 -225.78133) (xy 85.295753 -225.829907) (xy 85.296248 -225.854514)
			(xy 85.614759 -225.854514) (xy 85.618854 -225.803786) (xy 85.631033 -225.754372) (xy 85.650981 -225.707552)
			(xy 85.678182 -225.664538) (xy 85.71193 -225.626444) (xy 85.751352 -225.594257) (xy 85.795426 -225.568811)
			(xy 85.843012 -225.550764) (xy 85.892876 -225.540584) (xy 85.943728 -225.538535) (xy 85.994249 -225.544669)
			(xy 86.043133 -225.558829) (xy 86.089112 -225.580646) (xy 86.130996 -225.609556) (xy 86.1677 -225.644811)
			(xy 86.198273 -225.685497) (xy 86.221924 -225.73056) (xy 86.23804 -225.778834) (xy 86.246204 -225.829068)
			(xy 86.246716 -225.854514) (xy 86.565244 -225.854514) (xy 86.569204 -225.80546) (xy 86.580981 -225.757676)
			(xy 86.600272 -225.7124) (xy 86.626575 -225.670804) (xy 86.65921 -225.633967) (xy 86.697331 -225.602842)
			(xy 86.739952 -225.578235) (xy 86.785968 -225.560783) (xy 86.834187 -225.550939) (xy 86.883362 -225.548958)
			(xy 86.932217 -225.55489) (xy 86.979488 -225.568582) (xy 87.02395 -225.58968) (xy 87.064453 -225.617636)
			(xy 87.099946 -225.651728) (xy 87.129511 -225.691072) (xy 87.152382 -225.734649) (xy 87.167966 -225.78133)
			(xy 87.175861 -225.829907) (xy 87.176356 -225.854514) (xy 87.494867 -225.854514) (xy 87.498962 -225.803786)
			(xy 87.511141 -225.754372) (xy 87.531089 -225.707552) (xy 87.55829 -225.664538) (xy 87.592038 -225.626444)
			(xy 87.63146 -225.594257) (xy 87.675534 -225.568811) (xy 87.72312 -225.550764) (xy 87.772984 -225.540584)
			(xy 87.823836 -225.538535) (xy 87.874357 -225.544669) (xy 87.923241 -225.558829) (xy 87.96922 -225.580646)
			(xy 88.011104 -225.609556) (xy 88.047808 -225.644811) (xy 88.078381 -225.685497) (xy 88.102032 -225.73056)
			(xy 88.118148 -225.778834) (xy 88.126312 -225.829068) (xy 88.126824 -225.854514) (xy 88.434921 -225.854514)
			(xy 88.439016 -225.803786) (xy 88.451195 -225.754372) (xy 88.471143 -225.707552) (xy 88.498344 -225.664538)
			(xy 88.532092 -225.626444) (xy 88.571514 -225.594257) (xy 88.615588 -225.568811) (xy 88.663174 -225.550764)
			(xy 88.713038 -225.540584) (xy 88.76389 -225.538535) (xy 88.814411 -225.544669) (xy 88.863295 -225.558829)
			(xy 88.909274 -225.580646) (xy 88.951158 -225.609556) (xy 88.987862 -225.644811) (xy 89.018435 -225.685497)
			(xy 89.042086 -225.73056) (xy 89.058202 -225.778834) (xy 89.066366 -225.829068) (xy 89.066878 -225.854514)
			(xy 89.385152 -225.854514) (xy 89.389112 -225.80546) (xy 89.400889 -225.757676) (xy 89.42018 -225.7124)
			(xy 89.446483 -225.670804) (xy 89.479118 -225.633967) (xy 89.517239 -225.602842) (xy 89.55986 -225.578235)
			(xy 89.605876 -225.560783) (xy 89.654095 -225.550939) (xy 89.70327 -225.548958) (xy 89.752125 -225.55489)
			(xy 89.799396 -225.568582) (xy 89.843858 -225.58968) (xy 89.884361 -225.617636) (xy 89.919854 -225.651728)
			(xy 89.949419 -225.691072) (xy 89.97229 -225.734649) (xy 89.987874 -225.78133) (xy 89.995769 -225.829907)
			(xy 89.996264 -225.854514) (xy 90.314775 -225.854514) (xy 90.31887 -225.803786) (xy 90.331049 -225.754372)
			(xy 90.350997 -225.707552) (xy 90.378198 -225.664538) (xy 90.411946 -225.626444) (xy 90.451368 -225.594257)
			(xy 90.495442 -225.568811) (xy 90.543028 -225.550764) (xy 90.592892 -225.540584) (xy 90.643744 -225.538535)
			(xy 90.694265 -225.544669) (xy 90.743149 -225.558829) (xy 90.789128 -225.580646) (xy 90.831012 -225.609556)
			(xy 90.867716 -225.644811) (xy 90.898289 -225.685497) (xy 90.92194 -225.73056) (xy 90.938056 -225.778834)
			(xy 90.94622 -225.829068) (xy 90.946732 -225.854514) (xy 91.26526 -225.854514) (xy 91.26922 -225.80546)
			(xy 91.280997 -225.757676) (xy 91.300288 -225.7124) (xy 91.326591 -225.670804) (xy 91.359226 -225.633967)
			(xy 91.397347 -225.602842) (xy 91.439968 -225.578235) (xy 91.485984 -225.560783) (xy 91.534203 -225.550939)
			(xy 91.583378 -225.548958) (xy 91.632233 -225.55489) (xy 91.679504 -225.568582) (xy 91.723966 -225.58968)
			(xy 91.764469 -225.617636) (xy 91.799962 -225.651728) (xy 91.829527 -225.691072) (xy 91.852398 -225.734649)
			(xy 91.867982 -225.78133) (xy 91.875877 -225.829907) (xy 91.876372 -225.854514) (xy 92.194883 -225.854514)
			(xy 92.198978 -225.803786) (xy 92.211157 -225.754372) (xy 92.231105 -225.707552) (xy 92.258306 -225.664538)
			(xy 92.292054 -225.626444) (xy 92.331476 -225.594257) (xy 92.37555 -225.568811) (xy 92.423136 -225.550764)
			(xy 92.473 -225.540584) (xy 92.523852 -225.538535) (xy 92.574373 -225.544669) (xy 92.623257 -225.558829)
			(xy 92.669236 -225.580646) (xy 92.71112 -225.609556) (xy 92.747824 -225.644811) (xy 92.778397 -225.685497)
			(xy 92.802048 -225.73056) (xy 92.818164 -225.778834) (xy 92.826328 -225.829068) (xy 92.82684 -225.854514)
			(xy 93.145114 -225.854514) (xy 93.149074 -225.80546) (xy 93.160851 -225.757676) (xy 93.180142 -225.7124)
			(xy 93.206445 -225.670804) (xy 93.23908 -225.633967) (xy 93.277201 -225.602842) (xy 93.319822 -225.578235)
			(xy 93.365838 -225.560783) (xy 93.414057 -225.550939) (xy 93.463232 -225.548958) (xy 93.512087 -225.55489)
			(xy 93.559358 -225.568582) (xy 93.60382 -225.58968) (xy 93.644323 -225.617636) (xy 93.679816 -225.651728)
			(xy 93.709381 -225.691072) (xy 93.732252 -225.734649) (xy 93.747836 -225.78133) (xy 93.755731 -225.829907)
			(xy 93.756226 -225.854514) (xy 94.074737 -225.854514) (xy 94.078832 -225.803786) (xy 94.091011 -225.754372)
			(xy 94.110959 -225.707552) (xy 94.13816 -225.664538) (xy 94.171908 -225.626444) (xy 94.21133 -225.594257)
			(xy 94.255404 -225.568811) (xy 94.30299 -225.550764) (xy 94.352854 -225.540584) (xy 94.403706 -225.538535)
			(xy 94.454227 -225.544669) (xy 94.503111 -225.558829) (xy 94.54909 -225.580646) (xy 94.590974 -225.609556)
			(xy 94.627678 -225.644811) (xy 94.658251 -225.685497) (xy 94.681902 -225.73056) (xy 94.698018 -225.778834)
			(xy 94.706182 -225.829068) (xy 94.706694 -225.854514) (xy 95.014791 -225.854514) (xy 95.018886 -225.803786)
			(xy 95.031065 -225.754372) (xy 95.051013 -225.707552) (xy 95.078214 -225.664538) (xy 95.111962 -225.626444)
			(xy 95.151384 -225.594257) (xy 95.195458 -225.568811) (xy 95.243044 -225.550764) (xy 95.292908 -225.540584)
			(xy 95.34376 -225.538535) (xy 95.394281 -225.544669) (xy 95.443165 -225.558829) (xy 95.489144 -225.580646)
			(xy 95.531028 -225.609556) (xy 95.567732 -225.644811) (xy 95.598305 -225.685497) (xy 95.621956 -225.73056)
			(xy 95.638072 -225.778834) (xy 95.646236 -225.829068) (xy 95.646748 -225.854514) (xy 96.90533 -225.854514)
			(xy 96.90929 -225.80546) (xy 96.921067 -225.757676) (xy 96.940358 -225.7124) (xy 96.966661 -225.670804)
			(xy 96.999296 -225.633967) (xy 97.037417 -225.602842) (xy 97.080038 -225.578235) (xy 97.126054 -225.560783)
			(xy 97.174273 -225.550939) (xy 97.223448 -225.548958) (xy 97.272303 -225.55489) (xy 97.319574 -225.568582)
			(xy 97.364036 -225.58968) (xy 97.404539 -225.617636) (xy 97.440032 -225.651728) (xy 97.469597 -225.691072)
			(xy 97.492468 -225.734649) (xy 97.508052 -225.78133) (xy 97.515947 -225.829907) (xy 97.516442 -225.854514)
			(xy 97.84513 -225.854514) (xy 97.84909 -225.80546) (xy 97.860867 -225.757676) (xy 97.880158 -225.7124)
			(xy 97.906461 -225.670804) (xy 97.939096 -225.633967) (xy 97.977217 -225.602842) (xy 98.019838 -225.578235)
			(xy 98.065854 -225.560783) (xy 98.114073 -225.550939) (xy 98.163248 -225.548958) (xy 98.212103 -225.55489)
			(xy 98.259374 -225.568582) (xy 98.303836 -225.58968) (xy 98.344339 -225.617636) (xy 98.379832 -225.651728)
			(xy 98.409397 -225.691072) (xy 98.432268 -225.734649) (xy 98.447852 -225.78133) (xy 98.455747 -225.829907)
			(xy 98.456242 -225.854514) (xy 99.725238 -225.854514) (xy 99.729198 -225.80546) (xy 99.740975 -225.757676)
			(xy 99.760266 -225.7124) (xy 99.786569 -225.670804) (xy 99.819204 -225.633967) (xy 99.857325 -225.602842)
			(xy 99.899946 -225.578235) (xy 99.945962 -225.560783) (xy 99.994181 -225.550939) (xy 100.043356 -225.548958)
			(xy 100.092211 -225.55489) (xy 100.139482 -225.568582) (xy 100.183944 -225.58968) (xy 100.224447 -225.617636)
			(xy 100.25994 -225.651728) (xy 100.289505 -225.691072) (xy 100.312376 -225.734649) (xy 100.32796 -225.78133)
			(xy 100.335855 -225.829907) (xy 100.33635 -225.854514) (xy 100.665292 -225.854514) (xy 100.669252 -225.80546)
			(xy 100.681029 -225.757676) (xy 100.70032 -225.7124) (xy 100.726623 -225.670804) (xy 100.759258 -225.633967)
			(xy 100.797379 -225.602842) (xy 100.84 -225.578235) (xy 100.886016 -225.560783) (xy 100.934235 -225.550939)
			(xy 100.98341 -225.548958) (xy 101.032265 -225.55489) (xy 101.079536 -225.568582) (xy 101.123998 -225.58968)
			(xy 101.164501 -225.617636) (xy 101.199994 -225.651728) (xy 101.229559 -225.691072) (xy 101.25243 -225.734649)
			(xy 101.268014 -225.78133) (xy 101.275909 -225.829907) (xy 101.276404 -225.854514) (xy 102.545146 -225.854514)
			(xy 102.549106 -225.80546) (xy 102.560883 -225.757676) (xy 102.580174 -225.7124) (xy 102.606477 -225.670804)
			(xy 102.639112 -225.633967) (xy 102.677233 -225.602842) (xy 102.719854 -225.578235) (xy 102.76587 -225.560783)
			(xy 102.814089 -225.550939) (xy 102.863264 -225.548958) (xy 102.912119 -225.55489) (xy 102.95939 -225.568582)
			(xy 103.003852 -225.58968) (xy 103.044355 -225.617636) (xy 103.079848 -225.651728) (xy 103.109413 -225.691072)
			(xy 103.132284 -225.734649) (xy 103.147868 -225.78133) (xy 103.155763 -225.829907) (xy 103.156258 -225.854514)
			(xy 103.4852 -225.854514) (xy 103.48916 -225.80546) (xy 103.500937 -225.757676) (xy 103.520228 -225.7124)
			(xy 103.546531 -225.670804) (xy 103.579166 -225.633967) (xy 103.617287 -225.602842) (xy 103.659908 -225.578235)
			(xy 103.705924 -225.560783) (xy 103.754143 -225.550939) (xy 103.803318 -225.548958) (xy 103.852173 -225.55489)
			(xy 103.899444 -225.568582) (xy 103.943906 -225.58968) (xy 103.984409 -225.617636) (xy 104.019902 -225.651728)
			(xy 104.049467 -225.691072) (xy 104.072338 -225.734649) (xy 104.087922 -225.78133) (xy 104.095817 -225.829907)
			(xy 104.096312 -225.854514) (xy 105.365308 -225.854514) (xy 105.369268 -225.80546) (xy 105.381045 -225.757676)
			(xy 105.400336 -225.7124) (xy 105.426639 -225.670804) (xy 105.459274 -225.633967) (xy 105.497395 -225.602842)
			(xy 105.540016 -225.578235) (xy 105.586032 -225.560783) (xy 105.634251 -225.550939) (xy 105.683426 -225.548958)
			(xy 105.732281 -225.55489) (xy 105.779552 -225.568582) (xy 105.824014 -225.58968) (xy 105.864517 -225.617636)
			(xy 105.90001 -225.651728) (xy 105.929575 -225.691072) (xy 105.952446 -225.734649) (xy 105.96803 -225.78133)
			(xy 105.975925 -225.829907) (xy 105.97642 -225.854514) (xy 106.305362 -225.854514) (xy 106.309322 -225.80546)
			(xy 106.321099 -225.757676) (xy 106.34039 -225.7124) (xy 106.366693 -225.670804) (xy 106.399328 -225.633967)
			(xy 106.437449 -225.602842) (xy 106.48007 -225.578235) (xy 106.526086 -225.560783) (xy 106.574305 -225.550939)
			(xy 106.62348 -225.548958) (xy 106.672335 -225.55489) (xy 106.719606 -225.568582) (xy 106.764068 -225.58968)
			(xy 106.804571 -225.617636) (xy 106.840064 -225.651728) (xy 106.869629 -225.691072) (xy 106.8925 -225.734649)
			(xy 106.908084 -225.78133) (xy 106.915979 -225.829907) (xy 106.916474 -225.854514) (xy 108.185216 -225.854514)
			(xy 108.189176 -225.80546) (xy 108.200953 -225.757676) (xy 108.220244 -225.7124) (xy 108.246547 -225.670804)
			(xy 108.279182 -225.633967) (xy 108.317303 -225.602842) (xy 108.359924 -225.578235) (xy 108.40594 -225.560783)
			(xy 108.454159 -225.550939) (xy 108.503334 -225.548958) (xy 108.552189 -225.55489) (xy 108.59946 -225.568582)
			(xy 108.643922 -225.58968) (xy 108.684425 -225.617636) (xy 108.719918 -225.651728) (xy 108.749483 -225.691072)
			(xy 108.772354 -225.734649) (xy 108.787938 -225.78133) (xy 108.795833 -225.829907) (xy 108.796328 -225.854514)
			(xy 109.12527 -225.854514) (xy 109.12923 -225.80546) (xy 109.141007 -225.757676) (xy 109.160298 -225.7124)
			(xy 109.186601 -225.670804) (xy 109.219236 -225.633967) (xy 109.257357 -225.602842) (xy 109.299978 -225.578235)
			(xy 109.345994 -225.560783) (xy 109.394213 -225.550939) (xy 109.443388 -225.548958) (xy 109.492243 -225.55489)
			(xy 109.539514 -225.568582) (xy 109.583976 -225.58968) (xy 109.624479 -225.617636) (xy 109.659972 -225.651728)
			(xy 109.689537 -225.691072) (xy 109.712408 -225.734649) (xy 109.727992 -225.78133) (xy 109.735887 -225.829907)
			(xy 109.736382 -225.854514) (xy 110.065324 -225.854514) (xy 110.069284 -225.80546) (xy 110.081061 -225.757676)
			(xy 110.100352 -225.7124) (xy 110.126655 -225.670804) (xy 110.15929 -225.633967) (xy 110.197411 -225.602842)
			(xy 110.240032 -225.578235) (xy 110.286048 -225.560783) (xy 110.334267 -225.550939) (xy 110.383442 -225.548958)
			(xy 110.432297 -225.55489) (xy 110.479568 -225.568582) (xy 110.52403 -225.58968) (xy 110.564533 -225.617636)
			(xy 110.600026 -225.651728) (xy 110.629591 -225.691072) (xy 110.652462 -225.734649) (xy 110.668046 -225.78133)
			(xy 110.675941 -225.829907) (xy 110.676436 -225.854514) (xy 110.675941 -225.879121) (xy 110.668046 -225.927698)
			(xy 110.652462 -225.974379) (xy 110.629591 -226.017956) (xy 110.600026 -226.0573) (xy 110.564533 -226.091392)
			(xy 110.52403 -226.119348) (xy 110.479568 -226.140446) (xy 110.432297 -226.154138) (xy 110.383442 -226.16007)
			(xy 110.334267 -226.158089) (xy 110.286048 -226.148245) (xy 110.240032 -226.130793) (xy 110.197411 -226.106186)
			(xy 110.15929 -226.075061) (xy 110.126655 -226.038224) (xy 110.100352 -225.996628) (xy 110.081061 -225.951352)
			(xy 110.069284 -225.903568) (xy 110.065324 -225.854514) (xy 109.736382 -225.854514) (xy 109.735887 -225.879121)
			(xy 109.727992 -225.927698) (xy 109.712408 -225.974379) (xy 109.689537 -226.017956) (xy 109.659972 -226.0573)
			(xy 109.624479 -226.091392) (xy 109.583976 -226.119348) (xy 109.539514 -226.140446) (xy 109.492243 -226.154138)
			(xy 109.443388 -226.16007) (xy 109.394213 -226.158089) (xy 109.345994 -226.148245) (xy 109.299978 -226.130793)
			(xy 109.257357 -226.106186) (xy 109.219236 -226.075061) (xy 109.186601 -226.038224) (xy 109.160298 -225.996628)
			(xy 109.141007 -225.951352) (xy 109.12923 -225.903568) (xy 109.12527 -225.854514) (xy 108.796328 -225.854514)
			(xy 108.795833 -225.879121) (xy 108.787938 -225.927698) (xy 108.772354 -225.974379) (xy 108.749483 -226.017956)
			(xy 108.719918 -226.0573) (xy 108.684425 -226.091392) (xy 108.643922 -226.119348) (xy 108.59946 -226.140446)
			(xy 108.552189 -226.154138) (xy 108.503334 -226.16007) (xy 108.454159 -226.158089) (xy 108.40594 -226.148245)
			(xy 108.359924 -226.130793) (xy 108.317303 -226.106186) (xy 108.279182 -226.075061) (xy 108.246547 -226.038224)
			(xy 108.220244 -225.996628) (xy 108.200953 -225.951352) (xy 108.189176 -225.903568) (xy 108.185216 -225.854514)
			(xy 106.916474 -225.854514) (xy 106.915979 -225.879121) (xy 106.908084 -225.927698) (xy 106.8925 -225.974379)
			(xy 106.869629 -226.017956) (xy 106.840064 -226.0573) (xy 106.804571 -226.091392) (xy 106.764068 -226.119348)
			(xy 106.719606 -226.140446) (xy 106.672335 -226.154138) (xy 106.62348 -226.16007) (xy 106.574305 -226.158089)
			(xy 106.526086 -226.148245) (xy 106.48007 -226.130793) (xy 106.437449 -226.106186) (xy 106.399328 -226.075061)
			(xy 106.366693 -226.038224) (xy 106.34039 -225.996628) (xy 106.321099 -225.951352) (xy 106.309322 -225.903568)
			(xy 106.305362 -225.854514) (xy 105.97642 -225.854514) (xy 105.975925 -225.879121) (xy 105.96803 -225.927698)
			(xy 105.952446 -225.974379) (xy 105.929575 -226.017956) (xy 105.90001 -226.0573) (xy 105.864517 -226.091392)
			(xy 105.824014 -226.119348) (xy 105.779552 -226.140446) (xy 105.732281 -226.154138) (xy 105.683426 -226.16007)
			(xy 105.634251 -226.158089) (xy 105.586032 -226.148245) (xy 105.540016 -226.130793) (xy 105.497395 -226.106186)
			(xy 105.459274 -226.075061) (xy 105.426639 -226.038224) (xy 105.400336 -225.996628) (xy 105.381045 -225.951352)
			(xy 105.369268 -225.903568) (xy 105.365308 -225.854514) (xy 104.096312 -225.854514) (xy 104.095817 -225.879121)
			(xy 104.087922 -225.927698) (xy 104.072338 -225.974379) (xy 104.049467 -226.017956) (xy 104.019902 -226.0573)
			(xy 103.984409 -226.091392) (xy 103.943906 -226.119348) (xy 103.899444 -226.140446) (xy 103.852173 -226.154138)
			(xy 103.803318 -226.16007) (xy 103.754143 -226.158089) (xy 103.705924 -226.148245) (xy 103.659908 -226.130793)
			(xy 103.617287 -226.106186) (xy 103.579166 -226.075061) (xy 103.546531 -226.038224) (xy 103.520228 -225.996628)
			(xy 103.500937 -225.951352) (xy 103.48916 -225.903568) (xy 103.4852 -225.854514) (xy 103.156258 -225.854514)
			(xy 103.155763 -225.879121) (xy 103.147868 -225.927698) (xy 103.132284 -225.974379) (xy 103.109413 -226.017956)
			(xy 103.079848 -226.0573) (xy 103.044355 -226.091392) (xy 103.003852 -226.119348) (xy 102.95939 -226.140446)
			(xy 102.912119 -226.154138) (xy 102.863264 -226.16007) (xy 102.814089 -226.158089) (xy 102.76587 -226.148245)
			(xy 102.719854 -226.130793) (xy 102.677233 -226.106186) (xy 102.639112 -226.075061) (xy 102.606477 -226.038224)
			(xy 102.580174 -225.996628) (xy 102.560883 -225.951352) (xy 102.549106 -225.903568) (xy 102.545146 -225.854514)
			(xy 101.276404 -225.854514) (xy 101.275909 -225.879121) (xy 101.268014 -225.927698) (xy 101.25243 -225.974379)
			(xy 101.229559 -226.017956) (xy 101.199994 -226.0573) (xy 101.164501 -226.091392) (xy 101.123998 -226.119348)
			(xy 101.079536 -226.140446) (xy 101.032265 -226.154138) (xy 100.98341 -226.16007) (xy 100.934235 -226.158089)
			(xy 100.886016 -226.148245) (xy 100.84 -226.130793) (xy 100.797379 -226.106186) (xy 100.759258 -226.075061)
			(xy 100.726623 -226.038224) (xy 100.70032 -225.996628) (xy 100.681029 -225.951352) (xy 100.669252 -225.903568)
			(xy 100.665292 -225.854514) (xy 100.33635 -225.854514) (xy 100.335855 -225.879121) (xy 100.32796 -225.927698)
			(xy 100.312376 -225.974379) (xy 100.289505 -226.017956) (xy 100.25994 -226.0573) (xy 100.224447 -226.091392)
			(xy 100.183944 -226.119348) (xy 100.139482 -226.140446) (xy 100.092211 -226.154138) (xy 100.043356 -226.16007)
			(xy 99.994181 -226.158089) (xy 99.945962 -226.148245) (xy 99.899946 -226.130793) (xy 99.857325 -226.106186)
			(xy 99.819204 -226.075061) (xy 99.786569 -226.038224) (xy 99.760266 -225.996628) (xy 99.740975 -225.951352)
			(xy 99.729198 -225.903568) (xy 99.725238 -225.854514) (xy 98.456242 -225.854514) (xy 98.455747 -225.879121)
			(xy 98.447852 -225.927698) (xy 98.432268 -225.974379) (xy 98.409397 -226.017956) (xy 98.379832 -226.0573)
			(xy 98.344339 -226.091392) (xy 98.303836 -226.119348) (xy 98.259374 -226.140446) (xy 98.212103 -226.154138)
			(xy 98.163248 -226.16007) (xy 98.114073 -226.158089) (xy 98.065854 -226.148245) (xy 98.019838 -226.130793)
			(xy 97.977217 -226.106186) (xy 97.939096 -226.075061) (xy 97.906461 -226.038224) (xy 97.880158 -225.996628)
			(xy 97.860867 -225.951352) (xy 97.84909 -225.903568) (xy 97.84513 -225.854514) (xy 97.516442 -225.854514)
			(xy 97.515947 -225.879121) (xy 97.508052 -225.927698) (xy 97.492468 -225.974379) (xy 97.469597 -226.017956)
			(xy 97.440032 -226.0573) (xy 97.404539 -226.091392) (xy 97.364036 -226.119348) (xy 97.319574 -226.140446)
			(xy 97.272303 -226.154138) (xy 97.223448 -226.16007) (xy 97.174273 -226.158089) (xy 97.126054 -226.148245)
			(xy 97.080038 -226.130793) (xy 97.037417 -226.106186) (xy 96.999296 -226.075061) (xy 96.966661 -226.038224)
			(xy 96.940358 -225.996628) (xy 96.921067 -225.951352) (xy 96.90929 -225.903568) (xy 96.90533 -225.854514)
			(xy 95.646748 -225.854514) (xy 95.646236 -225.87996) (xy 95.638072 -225.930194) (xy 95.621956 -225.978468)
			(xy 95.598305 -226.023531) (xy 95.567732 -226.064217) (xy 95.531028 -226.099472) (xy 95.489144 -226.128382)
			(xy 95.443165 -226.150199) (xy 95.394281 -226.164359) (xy 95.34376 -226.170493) (xy 95.292908 -226.168444)
			(xy 95.243044 -226.158264) (xy 95.195458 -226.140217) (xy 95.151384 -226.114771) (xy 95.111962 -226.082584)
			(xy 95.078214 -226.04449) (xy 95.051013 -226.001476) (xy 95.031065 -225.954656) (xy 95.018886 -225.905242)
			(xy 95.014791 -225.854514) (xy 94.706694 -225.854514) (xy 94.706182 -225.87996) (xy 94.698018 -225.930194)
			(xy 94.681902 -225.978468) (xy 94.658251 -226.023531) (xy 94.627678 -226.064217) (xy 94.590974 -226.099472)
			(xy 94.54909 -226.128382) (xy 94.503111 -226.150199) (xy 94.454227 -226.164359) (xy 94.403706 -226.170493)
			(xy 94.352854 -226.168444) (xy 94.30299 -226.158264) (xy 94.255404 -226.140217) (xy 94.21133 -226.114771)
			(xy 94.171908 -226.082584) (xy 94.13816 -226.04449) (xy 94.110959 -226.001476) (xy 94.091011 -225.954656)
			(xy 94.078832 -225.905242) (xy 94.074737 -225.854514) (xy 93.756226 -225.854514) (xy 93.755731 -225.879121)
			(xy 93.747836 -225.927698) (xy 93.732252 -225.974379) (xy 93.709381 -226.017956) (xy 93.679816 -226.0573)
			(xy 93.644323 -226.091392) (xy 93.60382 -226.119348) (xy 93.559358 -226.140446) (xy 93.512087 -226.154138)
			(xy 93.463232 -226.16007) (xy 93.414057 -226.158089) (xy 93.365838 -226.148245) (xy 93.319822 -226.130793)
			(xy 93.277201 -226.106186) (xy 93.23908 -226.075061) (xy 93.206445 -226.038224) (xy 93.180142 -225.996628)
			(xy 93.160851 -225.951352) (xy 93.149074 -225.903568) (xy 93.145114 -225.854514) (xy 92.82684 -225.854514)
			(xy 92.826328 -225.87996) (xy 92.818164 -225.930194) (xy 92.802048 -225.978468) (xy 92.778397 -226.023531)
			(xy 92.747824 -226.064217) (xy 92.71112 -226.099472) (xy 92.669236 -226.128382) (xy 92.623257 -226.150199)
			(xy 92.574373 -226.164359) (xy 92.523852 -226.170493) (xy 92.473 -226.168444) (xy 92.423136 -226.158264)
			(xy 92.37555 -226.140217) (xy 92.331476 -226.114771) (xy 92.292054 -226.082584) (xy 92.258306 -226.04449)
			(xy 92.231105 -226.001476) (xy 92.211157 -225.954656) (xy 92.198978 -225.905242) (xy 92.194883 -225.854514)
			(xy 91.876372 -225.854514) (xy 91.875877 -225.879121) (xy 91.867982 -225.927698) (xy 91.852398 -225.974379)
			(xy 91.829527 -226.017956) (xy 91.799962 -226.0573) (xy 91.764469 -226.091392) (xy 91.723966 -226.119348)
			(xy 91.679504 -226.140446) (xy 91.632233 -226.154138) (xy 91.583378 -226.16007) (xy 91.534203 -226.158089)
			(xy 91.485984 -226.148245) (xy 91.439968 -226.130793) (xy 91.397347 -226.106186) (xy 91.359226 -226.075061)
			(xy 91.326591 -226.038224) (xy 91.300288 -225.996628) (xy 91.280997 -225.951352) (xy 91.26922 -225.903568)
			(xy 91.26526 -225.854514) (xy 90.946732 -225.854514) (xy 90.94622 -225.87996) (xy 90.938056 -225.930194)
			(xy 90.92194 -225.978468) (xy 90.898289 -226.023531) (xy 90.867716 -226.064217) (xy 90.831012 -226.099472)
			(xy 90.789128 -226.128382) (xy 90.743149 -226.150199) (xy 90.694265 -226.164359) (xy 90.643744 -226.170493)
			(xy 90.592892 -226.168444) (xy 90.543028 -226.158264) (xy 90.495442 -226.140217) (xy 90.451368 -226.114771)
			(xy 90.411946 -226.082584) (xy 90.378198 -226.04449) (xy 90.350997 -226.001476) (xy 90.331049 -225.954656)
			(xy 90.31887 -225.905242) (xy 90.314775 -225.854514) (xy 89.996264 -225.854514) (xy 89.995769 -225.879121)
			(xy 89.987874 -225.927698) (xy 89.97229 -225.974379) (xy 89.949419 -226.017956) (xy 89.919854 -226.0573)
			(xy 89.884361 -226.091392) (xy 89.843858 -226.119348) (xy 89.799396 -226.140446) (xy 89.752125 -226.154138)
			(xy 89.70327 -226.16007) (xy 89.654095 -226.158089) (xy 89.605876 -226.148245) (xy 89.55986 -226.130793)
			(xy 89.517239 -226.106186) (xy 89.479118 -226.075061) (xy 89.446483 -226.038224) (xy 89.42018 -225.996628)
			(xy 89.400889 -225.951352) (xy 89.389112 -225.903568) (xy 89.385152 -225.854514) (xy 89.066878 -225.854514)
			(xy 89.066366 -225.87996) (xy 89.058202 -225.930194) (xy 89.042086 -225.978468) (xy 89.018435 -226.023531)
			(xy 88.987862 -226.064217) (xy 88.951158 -226.099472) (xy 88.909274 -226.128382) (xy 88.863295 -226.150199)
			(xy 88.814411 -226.164359) (xy 88.76389 -226.170493) (xy 88.713038 -226.168444) (xy 88.663174 -226.158264)
			(xy 88.615588 -226.140217) (xy 88.571514 -226.114771) (xy 88.532092 -226.082584) (xy 88.498344 -226.04449)
			(xy 88.471143 -226.001476) (xy 88.451195 -225.954656) (xy 88.439016 -225.905242) (xy 88.434921 -225.854514)
			(xy 88.126824 -225.854514) (xy 88.126312 -225.87996) (xy 88.118148 -225.930194) (xy 88.102032 -225.978468)
			(xy 88.078381 -226.023531) (xy 88.047808 -226.064217) (xy 88.011104 -226.099472) (xy 87.96922 -226.128382)
			(xy 87.923241 -226.150199) (xy 87.874357 -226.164359) (xy 87.823836 -226.170493) (xy 87.772984 -226.168444)
			(xy 87.72312 -226.158264) (xy 87.675534 -226.140217) (xy 87.63146 -226.114771) (xy 87.592038 -226.082584)
			(xy 87.55829 -226.04449) (xy 87.531089 -226.001476) (xy 87.511141 -225.954656) (xy 87.498962 -225.905242)
			(xy 87.494867 -225.854514) (xy 87.176356 -225.854514) (xy 87.175861 -225.879121) (xy 87.167966 -225.927698)
			(xy 87.152382 -225.974379) (xy 87.129511 -226.017956) (xy 87.099946 -226.0573) (xy 87.064453 -226.091392)
			(xy 87.02395 -226.119348) (xy 86.979488 -226.140446) (xy 86.932217 -226.154138) (xy 86.883362 -226.16007)
			(xy 86.834187 -226.158089) (xy 86.785968 -226.148245) (xy 86.739952 -226.130793) (xy 86.697331 -226.106186)
			(xy 86.65921 -226.075061) (xy 86.626575 -226.038224) (xy 86.600272 -225.996628) (xy 86.580981 -225.951352)
			(xy 86.569204 -225.903568) (xy 86.565244 -225.854514) (xy 86.246716 -225.854514) (xy 86.246204 -225.87996)
			(xy 86.23804 -225.930194) (xy 86.221924 -225.978468) (xy 86.198273 -226.023531) (xy 86.1677 -226.064217)
			(xy 86.130996 -226.099472) (xy 86.089112 -226.128382) (xy 86.043133 -226.150199) (xy 85.994249 -226.164359)
			(xy 85.943728 -226.170493) (xy 85.892876 -226.168444) (xy 85.843012 -226.158264) (xy 85.795426 -226.140217)
			(xy 85.751352 -226.114771) (xy 85.71193 -226.082584) (xy 85.678182 -226.04449) (xy 85.650981 -226.001476)
			(xy 85.631033 -225.954656) (xy 85.618854 -225.905242) (xy 85.614759 -225.854514) (xy 85.296248 -225.854514)
			(xy 85.295753 -225.879121) (xy 85.287858 -225.927698) (xy 85.272274 -225.974379) (xy 85.249403 -226.017956)
			(xy 85.219838 -226.0573) (xy 85.184345 -226.091392) (xy 85.143842 -226.119348) (xy 85.09938 -226.140446)
			(xy 85.052109 -226.154138) (xy 85.003254 -226.16007) (xy 84.954079 -226.158089) (xy 84.90586 -226.148245)
			(xy 84.859844 -226.130793) (xy 84.817223 -226.106186) (xy 84.779102 -226.075061) (xy 84.746467 -226.038224)
			(xy 84.720164 -225.996628) (xy 84.700873 -225.951352) (xy 84.689096 -225.903568) (xy 84.685136 -225.854514)
			(xy 84.366862 -225.854514) (xy 84.36635 -225.87996) (xy 84.358186 -225.930194) (xy 84.34207 -225.978468)
			(xy 84.318419 -226.023531) (xy 84.287846 -226.064217) (xy 84.251142 -226.099472) (xy 84.209258 -226.128382)
			(xy 84.163279 -226.150199) (xy 84.114395 -226.164359) (xy 84.063874 -226.170493) (xy 84.013022 -226.168444)
			(xy 83.963158 -226.158264) (xy 83.915572 -226.140217) (xy 83.871498 -226.114771) (xy 83.832076 -226.082584)
			(xy 83.798328 -226.04449) (xy 83.771127 -226.001476) (xy 83.751179 -225.954656) (xy 83.739 -225.905242)
			(xy 83.734905 -225.854514) (xy 83.416394 -225.854514) (xy 83.415899 -225.879121) (xy 83.408004 -225.927698)
			(xy 83.39242 -225.974379) (xy 83.369549 -226.017956) (xy 83.339984 -226.0573) (xy 83.304491 -226.091392)
			(xy 83.263988 -226.119348) (xy 83.219526 -226.140446) (xy 83.172255 -226.154138) (xy 83.1234 -226.16007)
			(xy 83.074225 -226.158089) (xy 83.026006 -226.148245) (xy 82.97999 -226.130793) (xy 82.937369 -226.106186)
			(xy 82.899248 -226.075061) (xy 82.866613 -226.038224) (xy 82.84031 -225.996628) (xy 82.821019 -225.951352)
			(xy 82.809242 -225.903568) (xy 82.805282 -225.854514) (xy 82.486754 -225.854514) (xy 82.486242 -225.87996)
			(xy 82.478078 -225.930194) (xy 82.461962 -225.978468) (xy 82.438311 -226.023531) (xy 82.407738 -226.064217)
			(xy 82.371034 -226.099472) (xy 82.32915 -226.128382) (xy 82.283171 -226.150199) (xy 82.234287 -226.164359)
			(xy 82.183766 -226.170493) (xy 82.132914 -226.168444) (xy 82.08305 -226.158264) (xy 82.035464 -226.140217)
			(xy 81.99139 -226.114771) (xy 81.951968 -226.082584) (xy 81.91822 -226.04449) (xy 81.891019 -226.001476)
			(xy 81.871071 -225.954656) (xy 81.858892 -225.905242) (xy 81.854797 -225.854514) (xy 81.5467 -225.854514)
			(xy 81.546188 -225.87996) (xy 81.538024 -225.930194) (xy 81.521908 -225.978468) (xy 81.498257 -226.023531)
			(xy 81.467684 -226.064217) (xy 81.43098 -226.099472) (xy 81.389096 -226.128382) (xy 81.343117 -226.150199)
			(xy 81.294233 -226.164359) (xy 81.243712 -226.170493) (xy 81.19286 -226.168444) (xy 81.142996 -226.158264)
			(xy 81.09541 -226.140217) (xy 81.051336 -226.114771) (xy 81.011914 -226.082584) (xy 80.978166 -226.04449)
			(xy 80.950965 -226.001476) (xy 80.931017 -225.954656) (xy 80.918838 -225.905242) (xy 80.914743 -225.854514)
			(xy 80.596486 -225.854514) (xy 80.595991 -225.879121) (xy 80.588096 -225.927698) (xy 80.572512 -225.974379)
			(xy 80.549641 -226.017956) (xy 80.520076 -226.0573) (xy 80.484583 -226.091392) (xy 80.44408 -226.119348)
			(xy 80.399618 -226.140446) (xy 80.352347 -226.154138) (xy 80.303492 -226.16007) (xy 80.254317 -226.158089)
			(xy 80.206098 -226.148245) (xy 80.160082 -226.130793) (xy 80.117461 -226.106186) (xy 80.07934 -226.075061)
			(xy 80.046705 -226.038224) (xy 80.020402 -225.996628) (xy 80.001111 -225.951352) (xy 79.989334 -225.903568)
			(xy 79.985374 -225.854514) (xy 78.716378 -225.854514) (xy 78.715883 -225.879121) (xy 78.707988 -225.927698)
			(xy 78.692404 -225.974379) (xy 78.669533 -226.017956) (xy 78.639968 -226.0573) (xy 78.604475 -226.091392)
			(xy 78.563972 -226.119348) (xy 78.51951 -226.140446) (xy 78.472239 -226.154138) (xy 78.423384 -226.16007)
			(xy 78.374209 -226.158089) (xy 78.32599 -226.148245) (xy 78.279974 -226.130793) (xy 78.237353 -226.106186)
			(xy 78.199232 -226.075061) (xy 78.166597 -226.038224) (xy 78.140294 -225.996628) (xy 78.121003 -225.951352)
			(xy 78.109226 -225.903568) (xy 78.105266 -225.854514) (xy 62.37732 -225.854514) (xy 62.37732 -226.66452)
			(xy 76.695312 -226.66452) (xy 76.699272 -226.615466) (xy 76.711049 -226.567682) (xy 76.73034 -226.522406)
			(xy 76.756643 -226.48081) (xy 76.789278 -226.443973) (xy 76.827399 -226.412848) (xy 76.87002 -226.388241)
			(xy 76.916036 -226.370789) (xy 76.964255 -226.360945) (xy 77.01343 -226.358964) (xy 77.062285 -226.364896)
			(xy 77.109556 -226.378588) (xy 77.154018 -226.399686) (xy 77.194521 -226.427642) (xy 77.230014 -226.461734)
			(xy 77.259579 -226.501078) (xy 77.28245 -226.544655) (xy 77.298034 -226.591336) (xy 77.305929 -226.639913)
			(xy 77.306424 -226.66452) (xy 79.51522 -226.66452) (xy 79.51918 -226.615466) (xy 79.530957 -226.567682)
			(xy 79.550248 -226.522406) (xy 79.576551 -226.48081) (xy 79.609186 -226.443973) (xy 79.647307 -226.412848)
			(xy 79.689928 -226.388241) (xy 79.735944 -226.370789) (xy 79.784163 -226.360945) (xy 79.833338 -226.358964)
			(xy 79.882193 -226.364896) (xy 79.929464 -226.378588) (xy 79.973926 -226.399686) (xy 80.014429 -226.427642)
			(xy 80.049922 -226.461734) (xy 80.079487 -226.501078) (xy 80.102358 -226.544655) (xy 80.117942 -226.591336)
			(xy 80.125837 -226.639913) (xy 80.126332 -226.66452) (xy 80.444843 -226.66452) (xy 80.448938 -226.613792)
			(xy 80.461117 -226.564378) (xy 80.481065 -226.517558) (xy 80.508266 -226.474544) (xy 80.542014 -226.43645)
			(xy 80.581436 -226.404263) (xy 80.62551 -226.378817) (xy 80.673096 -226.36077) (xy 80.72296 -226.35059)
			(xy 80.773812 -226.348541) (xy 80.824333 -226.354675) (xy 80.873217 -226.368835) (xy 80.919196 -226.390652)
			(xy 80.96108 -226.419562) (xy 80.997784 -226.454817) (xy 81.028357 -226.495503) (xy 81.052008 -226.540566)
			(xy 81.068124 -226.58884) (xy 81.076288 -226.639074) (xy 81.0768 -226.66452) (xy 81.395328 -226.66452)
			(xy 81.399288 -226.615466) (xy 81.411065 -226.567682) (xy 81.430356 -226.522406) (xy 81.456659 -226.48081)
			(xy 81.489294 -226.443973) (xy 81.527415 -226.412848) (xy 81.570036 -226.388241) (xy 81.616052 -226.370789)
			(xy 81.664271 -226.360945) (xy 81.713446 -226.358964) (xy 81.762301 -226.364896) (xy 81.809572 -226.378588)
			(xy 81.854034 -226.399686) (xy 81.894537 -226.427642) (xy 81.93003 -226.461734) (xy 81.959595 -226.501078)
			(xy 81.982466 -226.544655) (xy 81.99805 -226.591336) (xy 82.005945 -226.639913) (xy 82.00644 -226.66452)
			(xy 82.324697 -226.66452) (xy 82.328792 -226.613792) (xy 82.340971 -226.564378) (xy 82.360919 -226.517558)
			(xy 82.38812 -226.474544) (xy 82.421868 -226.43645) (xy 82.46129 -226.404263) (xy 82.505364 -226.378817)
			(xy 82.55295 -226.36077) (xy 82.602814 -226.35059) (xy 82.653666 -226.348541) (xy 82.704187 -226.354675)
			(xy 82.753071 -226.368835) (xy 82.79905 -226.390652) (xy 82.840934 -226.419562) (xy 82.877638 -226.454817)
			(xy 82.908211 -226.495503) (xy 82.931862 -226.540566) (xy 82.947978 -226.58884) (xy 82.956142 -226.639074)
			(xy 82.956654 -226.66452) (xy 83.275182 -226.66452) (xy 83.279142 -226.615466) (xy 83.290919 -226.567682)
			(xy 83.31021 -226.522406) (xy 83.336513 -226.48081) (xy 83.369148 -226.443973) (xy 83.407269 -226.412848)
			(xy 83.44989 -226.388241) (xy 83.495906 -226.370789) (xy 83.544125 -226.360945) (xy 83.5933 -226.358964)
			(xy 83.642155 -226.364896) (xy 83.689426 -226.378588) (xy 83.733888 -226.399686) (xy 83.774391 -226.427642)
			(xy 83.809884 -226.461734) (xy 83.839449 -226.501078) (xy 83.86232 -226.544655) (xy 83.877904 -226.591336)
			(xy 83.885799 -226.639913) (xy 83.886294 -226.66452) (xy 84.204805 -226.66452) (xy 84.2089 -226.613792)
			(xy 84.221079 -226.564378) (xy 84.241027 -226.517558) (xy 84.268228 -226.474544) (xy 84.301976 -226.43645)
			(xy 84.341398 -226.404263) (xy 84.385472 -226.378817) (xy 84.433058 -226.36077) (xy 84.482922 -226.35059)
			(xy 84.533774 -226.348541) (xy 84.584295 -226.354675) (xy 84.633179 -226.368835) (xy 84.679158 -226.390652)
			(xy 84.721042 -226.419562) (xy 84.757746 -226.454817) (xy 84.788319 -226.495503) (xy 84.81197 -226.540566)
			(xy 84.828086 -226.58884) (xy 84.83625 -226.639074) (xy 84.836762 -226.66452) (xy 85.144859 -226.66452)
			(xy 85.148954 -226.613792) (xy 85.161133 -226.564378) (xy 85.181081 -226.517558) (xy 85.208282 -226.474544)
			(xy 85.24203 -226.43645) (xy 85.281452 -226.404263) (xy 85.325526 -226.378817) (xy 85.373112 -226.36077)
			(xy 85.422976 -226.35059) (xy 85.473828 -226.348541) (xy 85.524349 -226.354675) (xy 85.573233 -226.368835)
			(xy 85.619212 -226.390652) (xy 85.661096 -226.419562) (xy 85.6978 -226.454817) (xy 85.728373 -226.495503)
			(xy 85.752024 -226.540566) (xy 85.76814 -226.58884) (xy 85.776304 -226.639074) (xy 85.776816 -226.66452)
			(xy 86.095344 -226.66452) (xy 86.099304 -226.615466) (xy 86.111081 -226.567682) (xy 86.130372 -226.522406)
			(xy 86.156675 -226.48081) (xy 86.18931 -226.443973) (xy 86.227431 -226.412848) (xy 86.270052 -226.388241)
			(xy 86.316068 -226.370789) (xy 86.364287 -226.360945) (xy 86.413462 -226.358964) (xy 86.462317 -226.364896)
			(xy 86.509588 -226.378588) (xy 86.55405 -226.399686) (xy 86.594553 -226.427642) (xy 86.630046 -226.461734)
			(xy 86.659611 -226.501078) (xy 86.682482 -226.544655) (xy 86.698066 -226.591336) (xy 86.705961 -226.639913)
			(xy 86.706456 -226.66452) (xy 87.024713 -226.66452) (xy 87.028808 -226.613792) (xy 87.040987 -226.564378)
			(xy 87.060935 -226.517558) (xy 87.088136 -226.474544) (xy 87.121884 -226.43645) (xy 87.161306 -226.404263)
			(xy 87.20538 -226.378817) (xy 87.252966 -226.36077) (xy 87.30283 -226.35059) (xy 87.353682 -226.348541)
			(xy 87.404203 -226.354675) (xy 87.453087 -226.368835) (xy 87.499066 -226.390652) (xy 87.54095 -226.419562)
			(xy 87.577654 -226.454817) (xy 87.608227 -226.495503) (xy 87.631878 -226.540566) (xy 87.647994 -226.58884)
			(xy 87.656158 -226.639074) (xy 87.65667 -226.66452) (xy 87.975198 -226.66452) (xy 87.979158 -226.615466)
			(xy 87.990935 -226.567682) (xy 88.010226 -226.522406) (xy 88.036529 -226.48081) (xy 88.069164 -226.443973)
			(xy 88.107285 -226.412848) (xy 88.149906 -226.388241) (xy 88.195922 -226.370789) (xy 88.244141 -226.360945)
			(xy 88.293316 -226.358964) (xy 88.342171 -226.364896) (xy 88.389442 -226.378588) (xy 88.433904 -226.399686)
			(xy 88.474407 -226.427642) (xy 88.5099 -226.461734) (xy 88.539465 -226.501078) (xy 88.562336 -226.544655)
			(xy 88.57792 -226.591336) (xy 88.585815 -226.639913) (xy 88.58631 -226.66452) (xy 88.904821 -226.66452)
			(xy 88.908916 -226.613792) (xy 88.921095 -226.564378) (xy 88.941043 -226.517558) (xy 88.968244 -226.474544)
			(xy 89.001992 -226.43645) (xy 89.041414 -226.404263) (xy 89.085488 -226.378817) (xy 89.133074 -226.36077)
			(xy 89.182938 -226.35059) (xy 89.23379 -226.348541) (xy 89.284311 -226.354675) (xy 89.333195 -226.368835)
			(xy 89.379174 -226.390652) (xy 89.421058 -226.419562) (xy 89.457762 -226.454817) (xy 89.488335 -226.495503)
			(xy 89.511986 -226.540566) (xy 89.528102 -226.58884) (xy 89.536266 -226.639074) (xy 89.536778 -226.66452)
			(xy 89.855306 -226.66452) (xy 89.859266 -226.615466) (xy 89.871043 -226.567682) (xy 89.890334 -226.522406)
			(xy 89.916637 -226.48081) (xy 89.949272 -226.443973) (xy 89.987393 -226.412848) (xy 90.030014 -226.388241)
			(xy 90.07603 -226.370789) (xy 90.124249 -226.360945) (xy 90.173424 -226.358964) (xy 90.222279 -226.364896)
			(xy 90.26955 -226.378588) (xy 90.314012 -226.399686) (xy 90.354515 -226.427642) (xy 90.390008 -226.461734)
			(xy 90.419573 -226.501078) (xy 90.442444 -226.544655) (xy 90.458028 -226.591336) (xy 90.465923 -226.639913)
			(xy 90.466418 -226.66452) (xy 90.784675 -226.66452) (xy 90.78877 -226.613792) (xy 90.800949 -226.564378)
			(xy 90.820897 -226.517558) (xy 90.848098 -226.474544) (xy 90.881846 -226.43645) (xy 90.921268 -226.404263)
			(xy 90.965342 -226.378817) (xy 91.012928 -226.36077) (xy 91.062792 -226.35059) (xy 91.113644 -226.348541)
			(xy 91.164165 -226.354675) (xy 91.213049 -226.368835) (xy 91.259028 -226.390652) (xy 91.300912 -226.419562)
			(xy 91.337616 -226.454817) (xy 91.368189 -226.495503) (xy 91.39184 -226.540566) (xy 91.407956 -226.58884)
			(xy 91.41612 -226.639074) (xy 91.416632 -226.66452) (xy 91.724729 -226.66452) (xy 91.728824 -226.613792)
			(xy 91.741003 -226.564378) (xy 91.760951 -226.517558) (xy 91.788152 -226.474544) (xy 91.8219 -226.43645)
			(xy 91.861322 -226.404263) (xy 91.905396 -226.378817) (xy 91.952982 -226.36077) (xy 92.002846 -226.35059)
			(xy 92.053698 -226.348541) (xy 92.104219 -226.354675) (xy 92.153103 -226.368835) (xy 92.199082 -226.390652)
			(xy 92.240966 -226.419562) (xy 92.27767 -226.454817) (xy 92.308243 -226.495503) (xy 92.331894 -226.540566)
			(xy 92.34801 -226.58884) (xy 92.356174 -226.639074) (xy 92.356686 -226.66452) (xy 92.675214 -226.66452)
			(xy 92.679174 -226.615466) (xy 92.690951 -226.567682) (xy 92.710242 -226.522406) (xy 92.736545 -226.48081)
			(xy 92.76918 -226.443973) (xy 92.807301 -226.412848) (xy 92.849922 -226.388241) (xy 92.895938 -226.370789)
			(xy 92.944157 -226.360945) (xy 92.993332 -226.358964) (xy 93.042187 -226.364896) (xy 93.089458 -226.378588)
			(xy 93.13392 -226.399686) (xy 93.174423 -226.427642) (xy 93.209916 -226.461734) (xy 93.239481 -226.501078)
			(xy 93.262352 -226.544655) (xy 93.277936 -226.591336) (xy 93.285831 -226.639913) (xy 93.286326 -226.66452)
			(xy 93.604837 -226.66452) (xy 93.608932 -226.613792) (xy 93.621111 -226.564378) (xy 93.641059 -226.517558)
			(xy 93.66826 -226.474544) (xy 93.702008 -226.43645) (xy 93.74143 -226.404263) (xy 93.785504 -226.378817)
			(xy 93.83309 -226.36077) (xy 93.882954 -226.35059) (xy 93.933806 -226.348541) (xy 93.984327 -226.354675)
			(xy 94.033211 -226.368835) (xy 94.07919 -226.390652) (xy 94.121074 -226.419562) (xy 94.157778 -226.454817)
			(xy 94.188351 -226.495503) (xy 94.212002 -226.540566) (xy 94.228118 -226.58884) (xy 94.236282 -226.639074)
			(xy 94.236794 -226.66452) (xy 94.555322 -226.66452) (xy 94.559282 -226.615466) (xy 94.571059 -226.567682)
			(xy 94.59035 -226.522406) (xy 94.616653 -226.48081) (xy 94.649288 -226.443973) (xy 94.687409 -226.412848)
			(xy 94.73003 -226.388241) (xy 94.776046 -226.370789) (xy 94.824265 -226.360945) (xy 94.87344 -226.358964)
			(xy 94.922295 -226.364896) (xy 94.969566 -226.378588) (xy 95.014028 -226.399686) (xy 95.054531 -226.427642)
			(xy 95.090024 -226.461734) (xy 95.119589 -226.501078) (xy 95.14246 -226.544655) (xy 95.158044 -226.591336)
			(xy 95.165939 -226.639913) (xy 95.166434 -226.66452) (xy 95.484691 -226.66452) (xy 95.488786 -226.613792)
			(xy 95.500965 -226.564378) (xy 95.520913 -226.517558) (xy 95.548114 -226.474544) (xy 95.581862 -226.43645)
			(xy 95.621284 -226.404263) (xy 95.665358 -226.378817) (xy 95.712944 -226.36077) (xy 95.762808 -226.35059)
			(xy 95.81366 -226.348541) (xy 95.864181 -226.354675) (xy 95.913065 -226.368835) (xy 95.959044 -226.390652)
			(xy 96.000928 -226.419562) (xy 96.037632 -226.454817) (xy 96.068205 -226.495503) (xy 96.091856 -226.540566)
			(xy 96.107972 -226.58884) (xy 96.116136 -226.639074) (xy 96.116648 -226.66452) (xy 96.435176 -226.66452)
			(xy 96.439136 -226.615466) (xy 96.450913 -226.567682) (xy 96.470204 -226.522406) (xy 96.496507 -226.48081)
			(xy 96.529142 -226.443973) (xy 96.567263 -226.412848) (xy 96.609884 -226.388241) (xy 96.6559 -226.370789)
			(xy 96.704119 -226.360945) (xy 96.753294 -226.358964) (xy 96.802149 -226.364896) (xy 96.84942 -226.378588)
			(xy 96.893882 -226.399686) (xy 96.934385 -226.427642) (xy 96.969878 -226.461734) (xy 96.999443 -226.501078)
			(xy 97.022314 -226.544655) (xy 97.037898 -226.591336) (xy 97.045793 -226.639913) (xy 97.046288 -226.66452)
			(xy 97.364799 -226.66452) (xy 97.368894 -226.613792) (xy 97.381073 -226.564378) (xy 97.401021 -226.517558)
			(xy 97.428222 -226.474544) (xy 97.46197 -226.43645) (xy 97.501392 -226.404263) (xy 97.545466 -226.378817)
			(xy 97.593052 -226.36077) (xy 97.642916 -226.35059) (xy 97.693768 -226.348541) (xy 97.744289 -226.354675)
			(xy 97.793173 -226.368835) (xy 97.839152 -226.390652) (xy 97.881036 -226.419562) (xy 97.91774 -226.454817)
			(xy 97.948313 -226.495503) (xy 97.971964 -226.540566) (xy 97.98808 -226.58884) (xy 97.996244 -226.639074)
			(xy 97.996756 -226.66452) (xy 98.304853 -226.66452) (xy 98.308948 -226.613792) (xy 98.321127 -226.564378)
			(xy 98.341075 -226.517558) (xy 98.368276 -226.474544) (xy 98.402024 -226.43645) (xy 98.441446 -226.404263)
			(xy 98.48552 -226.378817) (xy 98.533106 -226.36077) (xy 98.58297 -226.35059) (xy 98.633822 -226.348541)
			(xy 98.684343 -226.354675) (xy 98.733227 -226.368835) (xy 98.779206 -226.390652) (xy 98.82109 -226.419562)
			(xy 98.857794 -226.454817) (xy 98.888367 -226.495503) (xy 98.912018 -226.540566) (xy 98.928134 -226.58884)
			(xy 98.936298 -226.639074) (xy 98.93681 -226.66452) (xy 99.255338 -226.66452) (xy 99.259298 -226.615466)
			(xy 99.271075 -226.567682) (xy 99.290366 -226.522406) (xy 99.316669 -226.48081) (xy 99.349304 -226.443973)
			(xy 99.387425 -226.412848) (xy 99.430046 -226.388241) (xy 99.476062 -226.370789) (xy 99.524281 -226.360945)
			(xy 99.573456 -226.358964) (xy 99.622311 -226.364896) (xy 99.669582 -226.378588) (xy 99.714044 -226.399686)
			(xy 99.754547 -226.427642) (xy 99.79004 -226.461734) (xy 99.819605 -226.501078) (xy 99.842476 -226.544655)
			(xy 99.85806 -226.591336) (xy 99.865955 -226.639913) (xy 99.86645 -226.66452) (xy 100.184707 -226.66452)
			(xy 100.188802 -226.613792) (xy 100.200981 -226.564378) (xy 100.220929 -226.517558) (xy 100.24813 -226.474544)
			(xy 100.281878 -226.43645) (xy 100.3213 -226.404263) (xy 100.365374 -226.378817) (xy 100.41296 -226.36077)
			(xy 100.462824 -226.35059) (xy 100.513676 -226.348541) (xy 100.564197 -226.354675) (xy 100.613081 -226.368835)
			(xy 100.65906 -226.390652) (xy 100.700944 -226.419562) (xy 100.737648 -226.454817) (xy 100.768221 -226.495503)
			(xy 100.791872 -226.540566) (xy 100.807988 -226.58884) (xy 100.816152 -226.639074) (xy 100.816664 -226.66452)
			(xy 101.124761 -226.66452) (xy 101.128856 -226.613792) (xy 101.141035 -226.564378) (xy 101.160983 -226.517558)
			(xy 101.188184 -226.474544) (xy 101.221932 -226.43645) (xy 101.261354 -226.404263) (xy 101.305428 -226.378817)
			(xy 101.353014 -226.36077) (xy 101.402878 -226.35059) (xy 101.45373 -226.348541) (xy 101.504251 -226.354675)
			(xy 101.553135 -226.368835) (xy 101.599114 -226.390652) (xy 101.640998 -226.419562) (xy 101.677702 -226.454817)
			(xy 101.708275 -226.495503) (xy 101.731926 -226.540566) (xy 101.748042 -226.58884) (xy 101.756206 -226.639074)
			(xy 101.756718 -226.66452) (xy 102.075246 -226.66452) (xy 102.079206 -226.615466) (xy 102.090983 -226.567682)
			(xy 102.110274 -226.522406) (xy 102.136577 -226.48081) (xy 102.169212 -226.443973) (xy 102.207333 -226.412848)
			(xy 102.249954 -226.388241) (xy 102.29597 -226.370789) (xy 102.344189 -226.360945) (xy 102.393364 -226.358964)
			(xy 102.442219 -226.364896) (xy 102.48949 -226.378588) (xy 102.533952 -226.399686) (xy 102.574455 -226.427642)
			(xy 102.609948 -226.461734) (xy 102.639513 -226.501078) (xy 102.662384 -226.544655) (xy 102.677968 -226.591336)
			(xy 102.685863 -226.639913) (xy 102.686358 -226.66452) (xy 103.004869 -226.66452) (xy 103.008964 -226.613792)
			(xy 103.021143 -226.564378) (xy 103.041091 -226.517558) (xy 103.068292 -226.474544) (xy 103.10204 -226.43645)
			(xy 103.141462 -226.404263) (xy 103.185536 -226.378817) (xy 103.233122 -226.36077) (xy 103.282986 -226.35059)
			(xy 103.333838 -226.348541) (xy 103.384359 -226.354675) (xy 103.433243 -226.368835) (xy 103.479222 -226.390652)
			(xy 103.521106 -226.419562) (xy 103.55781 -226.454817) (xy 103.588383 -226.495503) (xy 103.612034 -226.540566)
			(xy 103.62815 -226.58884) (xy 103.636314 -226.639074) (xy 103.636826 -226.66452) (xy 103.944923 -226.66452)
			(xy 103.949018 -226.613792) (xy 103.961197 -226.564378) (xy 103.981145 -226.517558) (xy 104.008346 -226.474544)
			(xy 104.042094 -226.43645) (xy 104.081516 -226.404263) (xy 104.12559 -226.378817) (xy 104.173176 -226.36077)
			(xy 104.22304 -226.35059) (xy 104.273892 -226.348541) (xy 104.324413 -226.354675) (xy 104.373297 -226.368835)
			(xy 104.419276 -226.390652) (xy 104.46116 -226.419562) (xy 104.497864 -226.454817) (xy 104.528437 -226.495503)
			(xy 104.552088 -226.540566) (xy 104.568204 -226.58884) (xy 104.576368 -226.639074) (xy 104.57688 -226.66452)
			(xy 104.895154 -226.66452) (xy 104.899114 -226.615466) (xy 104.910891 -226.567682) (xy 104.930182 -226.522406)
			(xy 104.956485 -226.48081) (xy 104.98912 -226.443973) (xy 105.027241 -226.412848) (xy 105.069862 -226.388241)
			(xy 105.115878 -226.370789) (xy 105.164097 -226.360945) (xy 105.213272 -226.358964) (xy 105.262127 -226.364896)
			(xy 105.309398 -226.378588) (xy 105.35386 -226.399686) (xy 105.394363 -226.427642) (xy 105.429856 -226.461734)
			(xy 105.459421 -226.501078) (xy 105.482292 -226.544655) (xy 105.497876 -226.591336) (xy 105.505771 -226.639913)
			(xy 105.506266 -226.66452) (xy 105.824777 -226.66452) (xy 105.828872 -226.613792) (xy 105.841051 -226.564378)
			(xy 105.860999 -226.517558) (xy 105.8882 -226.474544) (xy 105.921948 -226.43645) (xy 105.96137 -226.404263)
			(xy 106.005444 -226.378817) (xy 106.05303 -226.36077) (xy 106.102894 -226.35059) (xy 106.153746 -226.348541)
			(xy 106.204267 -226.354675) (xy 106.253151 -226.368835) (xy 106.29913 -226.390652) (xy 106.341014 -226.419562)
			(xy 106.377718 -226.454817) (xy 106.408291 -226.495503) (xy 106.431942 -226.540566) (xy 106.448058 -226.58884)
			(xy 106.456222 -226.639074) (xy 106.456734 -226.66452) (xy 106.764831 -226.66452) (xy 106.768926 -226.613792)
			(xy 106.781105 -226.564378) (xy 106.801053 -226.517558) (xy 106.828254 -226.474544) (xy 106.862002 -226.43645)
			(xy 106.901424 -226.404263) (xy 106.945498 -226.378817) (xy 106.993084 -226.36077) (xy 107.042948 -226.35059)
			(xy 107.0938 -226.348541) (xy 107.144321 -226.354675) (xy 107.193205 -226.368835) (xy 107.239184 -226.390652)
			(xy 107.281068 -226.419562) (xy 107.317772 -226.454817) (xy 107.348345 -226.495503) (xy 107.371996 -226.540566)
			(xy 107.388112 -226.58884) (xy 107.396276 -226.639074) (xy 107.396788 -226.66452) (xy 107.715316 -226.66452)
			(xy 107.719276 -226.615466) (xy 107.731053 -226.567682) (xy 107.750344 -226.522406) (xy 107.776647 -226.48081)
			(xy 107.809282 -226.443973) (xy 107.847403 -226.412848) (xy 107.890024 -226.388241) (xy 107.93604 -226.370789)
			(xy 107.984259 -226.360945) (xy 108.033434 -226.358964) (xy 108.082289 -226.364896) (xy 108.12956 -226.378588)
			(xy 108.174022 -226.399686) (xy 108.214525 -226.427642) (xy 108.250018 -226.461734) (xy 108.279583 -226.501078)
			(xy 108.302454 -226.544655) (xy 108.318038 -226.591336) (xy 108.325933 -226.639913) (xy 108.326428 -226.66452)
			(xy 108.325933 -226.689127) (xy 108.318038 -226.737704) (xy 108.302454 -226.784385) (xy 108.279583 -226.827962)
			(xy 108.250018 -226.867306) (xy 108.214525 -226.901398) (xy 108.174022 -226.929354) (xy 108.12956 -226.950452)
			(xy 108.082289 -226.964144) (xy 108.033434 -226.970076) (xy 107.984259 -226.968095) (xy 107.93604 -226.958251)
			(xy 107.890024 -226.940799) (xy 107.847403 -226.916192) (xy 107.809282 -226.885067) (xy 107.776647 -226.84823)
			(xy 107.750344 -226.806634) (xy 107.731053 -226.761358) (xy 107.719276 -226.713574) (xy 107.715316 -226.66452)
			(xy 107.396788 -226.66452) (xy 107.396276 -226.689966) (xy 107.388112 -226.7402) (xy 107.371996 -226.788474)
			(xy 107.348345 -226.833537) (xy 107.317772 -226.874223) (xy 107.281068 -226.909478) (xy 107.239184 -226.938388)
			(xy 107.193205 -226.960205) (xy 107.144321 -226.974365) (xy 107.0938 -226.980499) (xy 107.042948 -226.97845)
			(xy 106.993084 -226.96827) (xy 106.945498 -226.950223) (xy 106.901424 -226.924777) (xy 106.862002 -226.89259)
			(xy 106.828254 -226.854496) (xy 106.801053 -226.811482) (xy 106.781105 -226.764662) (xy 106.768926 -226.715248)
			(xy 106.764831 -226.66452) (xy 106.456734 -226.66452) (xy 106.456222 -226.689966) (xy 106.448058 -226.7402)
			(xy 106.431942 -226.788474) (xy 106.408291 -226.833537) (xy 106.377718 -226.874223) (xy 106.341014 -226.909478)
			(xy 106.29913 -226.938388) (xy 106.253151 -226.960205) (xy 106.204267 -226.974365) (xy 106.153746 -226.980499)
			(xy 106.102894 -226.97845) (xy 106.05303 -226.96827) (xy 106.005444 -226.950223) (xy 105.96137 -226.924777)
			(xy 105.921948 -226.89259) (xy 105.8882 -226.854496) (xy 105.860999 -226.811482) (xy 105.841051 -226.764662)
			(xy 105.828872 -226.715248) (xy 105.824777 -226.66452) (xy 105.506266 -226.66452) (xy 105.505771 -226.689127)
			(xy 105.497876 -226.737704) (xy 105.482292 -226.784385) (xy 105.459421 -226.827962) (xy 105.429856 -226.867306)
			(xy 105.394363 -226.901398) (xy 105.35386 -226.929354) (xy 105.309398 -226.950452) (xy 105.262127 -226.964144)
			(xy 105.213272 -226.970076) (xy 105.164097 -226.968095) (xy 105.115878 -226.958251) (xy 105.069862 -226.940799)
			(xy 105.027241 -226.916192) (xy 104.98912 -226.885067) (xy 104.956485 -226.84823) (xy 104.930182 -226.806634)
			(xy 104.910891 -226.761358) (xy 104.899114 -226.713574) (xy 104.895154 -226.66452) (xy 104.57688 -226.66452)
			(xy 104.576368 -226.689966) (xy 104.568204 -226.7402) (xy 104.552088 -226.788474) (xy 104.528437 -226.833537)
			(xy 104.497864 -226.874223) (xy 104.46116 -226.909478) (xy 104.419276 -226.938388) (xy 104.373297 -226.960205)
			(xy 104.324413 -226.974365) (xy 104.273892 -226.980499) (xy 104.22304 -226.97845) (xy 104.173176 -226.96827)
			(xy 104.12559 -226.950223) (xy 104.081516 -226.924777) (xy 104.042094 -226.89259) (xy 104.008346 -226.854496)
			(xy 103.981145 -226.811482) (xy 103.961197 -226.764662) (xy 103.949018 -226.715248) (xy 103.944923 -226.66452)
			(xy 103.636826 -226.66452) (xy 103.636314 -226.689966) (xy 103.62815 -226.7402) (xy 103.612034 -226.788474)
			(xy 103.588383 -226.833537) (xy 103.55781 -226.874223) (xy 103.521106 -226.909478) (xy 103.479222 -226.938388)
			(xy 103.433243 -226.960205) (xy 103.384359 -226.974365) (xy 103.333838 -226.980499) (xy 103.282986 -226.97845)
			(xy 103.233122 -226.96827) (xy 103.185536 -226.950223) (xy 103.141462 -226.924777) (xy 103.10204 -226.89259)
			(xy 103.068292 -226.854496) (xy 103.041091 -226.811482) (xy 103.021143 -226.764662) (xy 103.008964 -226.715248)
			(xy 103.004869 -226.66452) (xy 102.686358 -226.66452) (xy 102.685863 -226.689127) (xy 102.677968 -226.737704)
			(xy 102.662384 -226.784385) (xy 102.639513 -226.827962) (xy 102.609948 -226.867306) (xy 102.574455 -226.901398)
			(xy 102.533952 -226.929354) (xy 102.48949 -226.950452) (xy 102.442219 -226.964144) (xy 102.393364 -226.970076)
			(xy 102.344189 -226.968095) (xy 102.29597 -226.958251) (xy 102.249954 -226.940799) (xy 102.207333 -226.916192)
			(xy 102.169212 -226.885067) (xy 102.136577 -226.84823) (xy 102.110274 -226.806634) (xy 102.090983 -226.761358)
			(xy 102.079206 -226.713574) (xy 102.075246 -226.66452) (xy 101.756718 -226.66452) (xy 101.756206 -226.689966)
			(xy 101.748042 -226.7402) (xy 101.731926 -226.788474) (xy 101.708275 -226.833537) (xy 101.677702 -226.874223)
			(xy 101.640998 -226.909478) (xy 101.599114 -226.938388) (xy 101.553135 -226.960205) (xy 101.504251 -226.974365)
			(xy 101.45373 -226.980499) (xy 101.402878 -226.97845) (xy 101.353014 -226.96827) (xy 101.305428 -226.950223)
			(xy 101.261354 -226.924777) (xy 101.221932 -226.89259) (xy 101.188184 -226.854496) (xy 101.160983 -226.811482)
			(xy 101.141035 -226.764662) (xy 101.128856 -226.715248) (xy 101.124761 -226.66452) (xy 100.816664 -226.66452)
			(xy 100.816152 -226.689966) (xy 100.807988 -226.7402) (xy 100.791872 -226.788474) (xy 100.768221 -226.833537)
			(xy 100.737648 -226.874223) (xy 100.700944 -226.909478) (xy 100.65906 -226.938388) (xy 100.613081 -226.960205)
			(xy 100.564197 -226.974365) (xy 100.513676 -226.980499) (xy 100.462824 -226.97845) (xy 100.41296 -226.96827)
			(xy 100.365374 -226.950223) (xy 100.3213 -226.924777) (xy 100.281878 -226.89259) (xy 100.24813 -226.854496)
			(xy 100.220929 -226.811482) (xy 100.200981 -226.764662) (xy 100.188802 -226.715248) (xy 100.184707 -226.66452)
			(xy 99.86645 -226.66452) (xy 99.865955 -226.689127) (xy 99.85806 -226.737704) (xy 99.842476 -226.784385)
			(xy 99.819605 -226.827962) (xy 99.79004 -226.867306) (xy 99.754547 -226.901398) (xy 99.714044 -226.929354)
			(xy 99.669582 -226.950452) (xy 99.622311 -226.964144) (xy 99.573456 -226.970076) (xy 99.524281 -226.968095)
			(xy 99.476062 -226.958251) (xy 99.430046 -226.940799) (xy 99.387425 -226.916192) (xy 99.349304 -226.885067)
			(xy 99.316669 -226.84823) (xy 99.290366 -226.806634) (xy 99.271075 -226.761358) (xy 99.259298 -226.713574)
			(xy 99.255338 -226.66452) (xy 98.93681 -226.66452) (xy 98.936298 -226.689966) (xy 98.928134 -226.7402)
			(xy 98.912018 -226.788474) (xy 98.888367 -226.833537) (xy 98.857794 -226.874223) (xy 98.82109 -226.909478)
			(xy 98.779206 -226.938388) (xy 98.733227 -226.960205) (xy 98.684343 -226.974365) (xy 98.633822 -226.980499)
			(xy 98.58297 -226.97845) (xy 98.533106 -226.96827) (xy 98.48552 -226.950223) (xy 98.441446 -226.924777)
			(xy 98.402024 -226.89259) (xy 98.368276 -226.854496) (xy 98.341075 -226.811482) (xy 98.321127 -226.764662)
			(xy 98.308948 -226.715248) (xy 98.304853 -226.66452) (xy 97.996756 -226.66452) (xy 97.996244 -226.689966)
			(xy 97.98808 -226.7402) (xy 97.971964 -226.788474) (xy 97.948313 -226.833537) (xy 97.91774 -226.874223)
			(xy 97.881036 -226.909478) (xy 97.839152 -226.938388) (xy 97.793173 -226.960205) (xy 97.744289 -226.974365)
			(xy 97.693768 -226.980499) (xy 97.642916 -226.97845) (xy 97.593052 -226.96827) (xy 97.545466 -226.950223)
			(xy 97.501392 -226.924777) (xy 97.46197 -226.89259) (xy 97.428222 -226.854496) (xy 97.401021 -226.811482)
			(xy 97.381073 -226.764662) (xy 97.368894 -226.715248) (xy 97.364799 -226.66452) (xy 97.046288 -226.66452)
			(xy 97.045793 -226.689127) (xy 97.037898 -226.737704) (xy 97.022314 -226.784385) (xy 96.999443 -226.827962)
			(xy 96.969878 -226.867306) (xy 96.934385 -226.901398) (xy 96.893882 -226.929354) (xy 96.84942 -226.950452)
			(xy 96.802149 -226.964144) (xy 96.753294 -226.970076) (xy 96.704119 -226.968095) (xy 96.6559 -226.958251)
			(xy 96.609884 -226.940799) (xy 96.567263 -226.916192) (xy 96.529142 -226.885067) (xy 96.496507 -226.84823)
			(xy 96.470204 -226.806634) (xy 96.450913 -226.761358) (xy 96.439136 -226.713574) (xy 96.435176 -226.66452)
			(xy 96.116648 -226.66452) (xy 96.116136 -226.689966) (xy 96.107972 -226.7402) (xy 96.091856 -226.788474)
			(xy 96.068205 -226.833537) (xy 96.037632 -226.874223) (xy 96.000928 -226.909478) (xy 95.959044 -226.938388)
			(xy 95.913065 -226.960205) (xy 95.864181 -226.974365) (xy 95.81366 -226.980499) (xy 95.762808 -226.97845)
			(xy 95.712944 -226.96827) (xy 95.665358 -226.950223) (xy 95.621284 -226.924777) (xy 95.581862 -226.89259)
			(xy 95.548114 -226.854496) (xy 95.520913 -226.811482) (xy 95.500965 -226.764662) (xy 95.488786 -226.715248)
			(xy 95.484691 -226.66452) (xy 95.166434 -226.66452) (xy 95.165939 -226.689127) (xy 95.158044 -226.737704)
			(xy 95.14246 -226.784385) (xy 95.119589 -226.827962) (xy 95.090024 -226.867306) (xy 95.054531 -226.901398)
			(xy 95.014028 -226.929354) (xy 94.969566 -226.950452) (xy 94.922295 -226.964144) (xy 94.87344 -226.970076)
			(xy 94.824265 -226.968095) (xy 94.776046 -226.958251) (xy 94.73003 -226.940799) (xy 94.687409 -226.916192)
			(xy 94.649288 -226.885067) (xy 94.616653 -226.84823) (xy 94.59035 -226.806634) (xy 94.571059 -226.761358)
			(xy 94.559282 -226.713574) (xy 94.555322 -226.66452) (xy 94.236794 -226.66452) (xy 94.236282 -226.689966)
			(xy 94.228118 -226.7402) (xy 94.212002 -226.788474) (xy 94.188351 -226.833537) (xy 94.157778 -226.874223)
			(xy 94.121074 -226.909478) (xy 94.07919 -226.938388) (xy 94.033211 -226.960205) (xy 93.984327 -226.974365)
			(xy 93.933806 -226.980499) (xy 93.882954 -226.97845) (xy 93.83309 -226.96827) (xy 93.785504 -226.950223)
			(xy 93.74143 -226.924777) (xy 93.702008 -226.89259) (xy 93.66826 -226.854496) (xy 93.641059 -226.811482)
			(xy 93.621111 -226.764662) (xy 93.608932 -226.715248) (xy 93.604837 -226.66452) (xy 93.286326 -226.66452)
			(xy 93.285831 -226.689127) (xy 93.277936 -226.737704) (xy 93.262352 -226.784385) (xy 93.239481 -226.827962)
			(xy 93.209916 -226.867306) (xy 93.174423 -226.901398) (xy 93.13392 -226.929354) (xy 93.089458 -226.950452)
			(xy 93.042187 -226.964144) (xy 92.993332 -226.970076) (xy 92.944157 -226.968095) (xy 92.895938 -226.958251)
			(xy 92.849922 -226.940799) (xy 92.807301 -226.916192) (xy 92.76918 -226.885067) (xy 92.736545 -226.84823)
			(xy 92.710242 -226.806634) (xy 92.690951 -226.761358) (xy 92.679174 -226.713574) (xy 92.675214 -226.66452)
			(xy 92.356686 -226.66452) (xy 92.356174 -226.689966) (xy 92.34801 -226.7402) (xy 92.331894 -226.788474)
			(xy 92.308243 -226.833537) (xy 92.27767 -226.874223) (xy 92.240966 -226.909478) (xy 92.199082 -226.938388)
			(xy 92.153103 -226.960205) (xy 92.104219 -226.974365) (xy 92.053698 -226.980499) (xy 92.002846 -226.97845)
			(xy 91.952982 -226.96827) (xy 91.905396 -226.950223) (xy 91.861322 -226.924777) (xy 91.8219 -226.89259)
			(xy 91.788152 -226.854496) (xy 91.760951 -226.811482) (xy 91.741003 -226.764662) (xy 91.728824 -226.715248)
			(xy 91.724729 -226.66452) (xy 91.416632 -226.66452) (xy 91.41612 -226.689966) (xy 91.407956 -226.7402)
			(xy 91.39184 -226.788474) (xy 91.368189 -226.833537) (xy 91.337616 -226.874223) (xy 91.300912 -226.909478)
			(xy 91.259028 -226.938388) (xy 91.213049 -226.960205) (xy 91.164165 -226.974365) (xy 91.113644 -226.980499)
			(xy 91.062792 -226.97845) (xy 91.012928 -226.96827) (xy 90.965342 -226.950223) (xy 90.921268 -226.924777)
			(xy 90.881846 -226.89259) (xy 90.848098 -226.854496) (xy 90.820897 -226.811482) (xy 90.800949 -226.764662)
			(xy 90.78877 -226.715248) (xy 90.784675 -226.66452) (xy 90.466418 -226.66452) (xy 90.465923 -226.689127)
			(xy 90.458028 -226.737704) (xy 90.442444 -226.784385) (xy 90.419573 -226.827962) (xy 90.390008 -226.867306)
			(xy 90.354515 -226.901398) (xy 90.314012 -226.929354) (xy 90.26955 -226.950452) (xy 90.222279 -226.964144)
			(xy 90.173424 -226.970076) (xy 90.124249 -226.968095) (xy 90.07603 -226.958251) (xy 90.030014 -226.940799)
			(xy 89.987393 -226.916192) (xy 89.949272 -226.885067) (xy 89.916637 -226.84823) (xy 89.890334 -226.806634)
			(xy 89.871043 -226.761358) (xy 89.859266 -226.713574) (xy 89.855306 -226.66452) (xy 89.536778 -226.66452)
			(xy 89.536266 -226.689966) (xy 89.528102 -226.7402) (xy 89.511986 -226.788474) (xy 89.488335 -226.833537)
			(xy 89.457762 -226.874223) (xy 89.421058 -226.909478) (xy 89.379174 -226.938388) (xy 89.333195 -226.960205)
			(xy 89.284311 -226.974365) (xy 89.23379 -226.980499) (xy 89.182938 -226.97845) (xy 89.133074 -226.96827)
			(xy 89.085488 -226.950223) (xy 89.041414 -226.924777) (xy 89.001992 -226.89259) (xy 88.968244 -226.854496)
			(xy 88.941043 -226.811482) (xy 88.921095 -226.764662) (xy 88.908916 -226.715248) (xy 88.904821 -226.66452)
			(xy 88.58631 -226.66452) (xy 88.585815 -226.689127) (xy 88.57792 -226.737704) (xy 88.562336 -226.784385)
			(xy 88.539465 -226.827962) (xy 88.5099 -226.867306) (xy 88.474407 -226.901398) (xy 88.433904 -226.929354)
			(xy 88.389442 -226.950452) (xy 88.342171 -226.964144) (xy 88.293316 -226.970076) (xy 88.244141 -226.968095)
			(xy 88.195922 -226.958251) (xy 88.149906 -226.940799) (xy 88.107285 -226.916192) (xy 88.069164 -226.885067)
			(xy 88.036529 -226.84823) (xy 88.010226 -226.806634) (xy 87.990935 -226.761358) (xy 87.979158 -226.713574)
			(xy 87.975198 -226.66452) (xy 87.65667 -226.66452) (xy 87.656158 -226.689966) (xy 87.647994 -226.7402)
			(xy 87.631878 -226.788474) (xy 87.608227 -226.833537) (xy 87.577654 -226.874223) (xy 87.54095 -226.909478)
			(xy 87.499066 -226.938388) (xy 87.453087 -226.960205) (xy 87.404203 -226.974365) (xy 87.353682 -226.980499)
			(xy 87.30283 -226.97845) (xy 87.252966 -226.96827) (xy 87.20538 -226.950223) (xy 87.161306 -226.924777)
			(xy 87.121884 -226.89259) (xy 87.088136 -226.854496) (xy 87.060935 -226.811482) (xy 87.040987 -226.764662)
			(xy 87.028808 -226.715248) (xy 87.024713 -226.66452) (xy 86.706456 -226.66452) (xy 86.705961 -226.689127)
			(xy 86.698066 -226.737704) (xy 86.682482 -226.784385) (xy 86.659611 -226.827962) (xy 86.630046 -226.867306)
			(xy 86.594553 -226.901398) (xy 86.55405 -226.929354) (xy 86.509588 -226.950452) (xy 86.462317 -226.964144)
			(xy 86.413462 -226.970076) (xy 86.364287 -226.968095) (xy 86.316068 -226.958251) (xy 86.270052 -226.940799)
			(xy 86.227431 -226.916192) (xy 86.18931 -226.885067) (xy 86.156675 -226.84823) (xy 86.130372 -226.806634)
			(xy 86.111081 -226.761358) (xy 86.099304 -226.713574) (xy 86.095344 -226.66452) (xy 85.776816 -226.66452)
			(xy 85.776304 -226.689966) (xy 85.76814 -226.7402) (xy 85.752024 -226.788474) (xy 85.728373 -226.833537)
			(xy 85.6978 -226.874223) (xy 85.661096 -226.909478) (xy 85.619212 -226.938388) (xy 85.573233 -226.960205)
			(xy 85.524349 -226.974365) (xy 85.473828 -226.980499) (xy 85.422976 -226.97845) (xy 85.373112 -226.96827)
			(xy 85.325526 -226.950223) (xy 85.281452 -226.924777) (xy 85.24203 -226.89259) (xy 85.208282 -226.854496)
			(xy 85.181081 -226.811482) (xy 85.161133 -226.764662) (xy 85.148954 -226.715248) (xy 85.144859 -226.66452)
			(xy 84.836762 -226.66452) (xy 84.83625 -226.689966) (xy 84.828086 -226.7402) (xy 84.81197 -226.788474)
			(xy 84.788319 -226.833537) (xy 84.757746 -226.874223) (xy 84.721042 -226.909478) (xy 84.679158 -226.938388)
			(xy 84.633179 -226.960205) (xy 84.584295 -226.974365) (xy 84.533774 -226.980499) (xy 84.482922 -226.97845)
			(xy 84.433058 -226.96827) (xy 84.385472 -226.950223) (xy 84.341398 -226.924777) (xy 84.301976 -226.89259)
			(xy 84.268228 -226.854496) (xy 84.241027 -226.811482) (xy 84.221079 -226.764662) (xy 84.2089 -226.715248)
			(xy 84.204805 -226.66452) (xy 83.886294 -226.66452) (xy 83.885799 -226.689127) (xy 83.877904 -226.737704)
			(xy 83.86232 -226.784385) (xy 83.839449 -226.827962) (xy 83.809884 -226.867306) (xy 83.774391 -226.901398)
			(xy 83.733888 -226.929354) (xy 83.689426 -226.950452) (xy 83.642155 -226.964144) (xy 83.5933 -226.970076)
			(xy 83.544125 -226.968095) (xy 83.495906 -226.958251) (xy 83.44989 -226.940799) (xy 83.407269 -226.916192)
			(xy 83.369148 -226.885067) (xy 83.336513 -226.84823) (xy 83.31021 -226.806634) (xy 83.290919 -226.761358)
			(xy 83.279142 -226.713574) (xy 83.275182 -226.66452) (xy 82.956654 -226.66452) (xy 82.956142 -226.689966)
			(xy 82.947978 -226.7402) (xy 82.931862 -226.788474) (xy 82.908211 -226.833537) (xy 82.877638 -226.874223)
			(xy 82.840934 -226.909478) (xy 82.79905 -226.938388) (xy 82.753071 -226.960205) (xy 82.704187 -226.974365)
			(xy 82.653666 -226.980499) (xy 82.602814 -226.97845) (xy 82.55295 -226.96827) (xy 82.505364 -226.950223)
			(xy 82.46129 -226.924777) (xy 82.421868 -226.89259) (xy 82.38812 -226.854496) (xy 82.360919 -226.811482)
			(xy 82.340971 -226.764662) (xy 82.328792 -226.715248) (xy 82.324697 -226.66452) (xy 82.00644 -226.66452)
			(xy 82.005945 -226.689127) (xy 81.99805 -226.737704) (xy 81.982466 -226.784385) (xy 81.959595 -226.827962)
			(xy 81.93003 -226.867306) (xy 81.894537 -226.901398) (xy 81.854034 -226.929354) (xy 81.809572 -226.950452)
			(xy 81.762301 -226.964144) (xy 81.713446 -226.970076) (xy 81.664271 -226.968095) (xy 81.616052 -226.958251)
			(xy 81.570036 -226.940799) (xy 81.527415 -226.916192) (xy 81.489294 -226.885067) (xy 81.456659 -226.84823)
			(xy 81.430356 -226.806634) (xy 81.411065 -226.761358) (xy 81.399288 -226.713574) (xy 81.395328 -226.66452)
			(xy 81.0768 -226.66452) (xy 81.076288 -226.689966) (xy 81.068124 -226.7402) (xy 81.052008 -226.788474)
			(xy 81.028357 -226.833537) (xy 80.997784 -226.874223) (xy 80.96108 -226.909478) (xy 80.919196 -226.938388)
			(xy 80.873217 -226.960205) (xy 80.824333 -226.974365) (xy 80.773812 -226.980499) (xy 80.72296 -226.97845)
			(xy 80.673096 -226.96827) (xy 80.62551 -226.950223) (xy 80.581436 -226.924777) (xy 80.542014 -226.89259)
			(xy 80.508266 -226.854496) (xy 80.481065 -226.811482) (xy 80.461117 -226.764662) (xy 80.448938 -226.715248)
			(xy 80.444843 -226.66452) (xy 80.126332 -226.66452) (xy 80.125837 -226.689127) (xy 80.117942 -226.737704)
			(xy 80.102358 -226.784385) (xy 80.079487 -226.827962) (xy 80.049922 -226.867306) (xy 80.014429 -226.901398)
			(xy 79.973926 -226.929354) (xy 79.929464 -226.950452) (xy 79.882193 -226.964144) (xy 79.833338 -226.970076)
			(xy 79.784163 -226.968095) (xy 79.735944 -226.958251) (xy 79.689928 -226.940799) (xy 79.647307 -226.916192)
			(xy 79.609186 -226.885067) (xy 79.576551 -226.84823) (xy 79.550248 -226.806634) (xy 79.530957 -226.761358)
			(xy 79.51918 -226.713574) (xy 79.51522 -226.66452) (xy 77.306424 -226.66452) (xy 77.305929 -226.689127)
			(xy 77.298034 -226.737704) (xy 77.28245 -226.784385) (xy 77.259579 -226.827962) (xy 77.230014 -226.867306)
			(xy 77.194521 -226.901398) (xy 77.154018 -226.929354) (xy 77.109556 -226.950452) (xy 77.062285 -226.964144)
			(xy 77.01343 -226.970076) (xy 76.964255 -226.968095) (xy 76.916036 -226.958251) (xy 76.87002 -226.940799)
			(xy 76.827399 -226.916192) (xy 76.789278 -226.885067) (xy 76.756643 -226.84823) (xy 76.73034 -226.806634)
			(xy 76.711049 -226.761358) (xy 76.699272 -226.713574) (xy 76.695312 -226.66452) (xy 62.37732 -226.66452)
			(xy 62.37732 -227.474526) (xy 78.105266 -227.474526) (xy 78.109226 -227.425472) (xy 78.121003 -227.377688)
			(xy 78.140294 -227.332412) (xy 78.166597 -227.290816) (xy 78.199232 -227.253979) (xy 78.237353 -227.222854)
			(xy 78.279974 -227.198247) (xy 78.32599 -227.180795) (xy 78.374209 -227.170951) (xy 78.423384 -227.16897)
			(xy 78.472239 -227.174902) (xy 78.51951 -227.188594) (xy 78.563972 -227.209692) (xy 78.604475 -227.237648)
			(xy 78.639968 -227.27174) (xy 78.669533 -227.311084) (xy 78.692404 -227.354661) (xy 78.707988 -227.401342)
			(xy 78.715883 -227.449919) (xy 78.716378 -227.474526) (xy 79.985374 -227.474526) (xy 79.989334 -227.425472)
			(xy 80.001111 -227.377688) (xy 80.020402 -227.332412) (xy 80.046705 -227.290816) (xy 80.07934 -227.253979)
			(xy 80.117461 -227.222854) (xy 80.160082 -227.198247) (xy 80.206098 -227.180795) (xy 80.254317 -227.170951)
			(xy 80.303492 -227.16897) (xy 80.352347 -227.174902) (xy 80.399618 -227.188594) (xy 80.44408 -227.209692)
			(xy 80.484583 -227.237648) (xy 80.520076 -227.27174) (xy 80.549641 -227.311084) (xy 80.572512 -227.354661)
			(xy 80.588096 -227.401342) (xy 80.595991 -227.449919) (xy 80.596486 -227.474526) (xy 80.914743 -227.474526)
			(xy 80.918838 -227.423798) (xy 80.931017 -227.374384) (xy 80.950965 -227.327564) (xy 80.978166 -227.28455)
			(xy 81.011914 -227.246456) (xy 81.051336 -227.214269) (xy 81.09541 -227.188823) (xy 81.142996 -227.170776)
			(xy 81.19286 -227.160596) (xy 81.243712 -227.158547) (xy 81.294233 -227.164681) (xy 81.343117 -227.178841)
			(xy 81.389096 -227.200658) (xy 81.43098 -227.229568) (xy 81.467684 -227.264823) (xy 81.498257 -227.305509)
			(xy 81.521908 -227.350572) (xy 81.538024 -227.398846) (xy 81.546188 -227.44908) (xy 81.5467 -227.474526)
			(xy 81.854797 -227.474526) (xy 81.858892 -227.423798) (xy 81.871071 -227.374384) (xy 81.891019 -227.327564)
			(xy 81.91822 -227.28455) (xy 81.951968 -227.246456) (xy 81.99139 -227.214269) (xy 82.035464 -227.188823)
			(xy 82.08305 -227.170776) (xy 82.132914 -227.160596) (xy 82.183766 -227.158547) (xy 82.234287 -227.164681)
			(xy 82.283171 -227.178841) (xy 82.32915 -227.200658) (xy 82.371034 -227.229568) (xy 82.407738 -227.264823)
			(xy 82.438311 -227.305509) (xy 82.461962 -227.350572) (xy 82.478078 -227.398846) (xy 82.486242 -227.44908)
			(xy 82.486754 -227.474526) (xy 82.805282 -227.474526) (xy 82.809242 -227.425472) (xy 82.821019 -227.377688)
			(xy 82.84031 -227.332412) (xy 82.866613 -227.290816) (xy 82.899248 -227.253979) (xy 82.937369 -227.222854)
			(xy 82.97999 -227.198247) (xy 83.026006 -227.180795) (xy 83.074225 -227.170951) (xy 83.1234 -227.16897)
			(xy 83.172255 -227.174902) (xy 83.219526 -227.188594) (xy 83.263988 -227.209692) (xy 83.304491 -227.237648)
			(xy 83.339984 -227.27174) (xy 83.369549 -227.311084) (xy 83.39242 -227.354661) (xy 83.408004 -227.401342)
			(xy 83.415899 -227.449919) (xy 83.416394 -227.474526) (xy 83.734905 -227.474526) (xy 83.739 -227.423798)
			(xy 83.751179 -227.374384) (xy 83.771127 -227.327564) (xy 83.798328 -227.28455) (xy 83.832076 -227.246456)
			(xy 83.871498 -227.214269) (xy 83.915572 -227.188823) (xy 83.963158 -227.170776) (xy 84.013022 -227.160596)
			(xy 84.063874 -227.158547) (xy 84.114395 -227.164681) (xy 84.163279 -227.178841) (xy 84.209258 -227.200658)
			(xy 84.251142 -227.229568) (xy 84.287846 -227.264823) (xy 84.318419 -227.305509) (xy 84.34207 -227.350572)
			(xy 84.358186 -227.398846) (xy 84.36635 -227.44908) (xy 84.366862 -227.474526) (xy 84.685136 -227.474526)
			(xy 84.689096 -227.425472) (xy 84.700873 -227.377688) (xy 84.720164 -227.332412) (xy 84.746467 -227.290816)
			(xy 84.779102 -227.253979) (xy 84.817223 -227.222854) (xy 84.859844 -227.198247) (xy 84.90586 -227.180795)
			(xy 84.954079 -227.170951) (xy 85.003254 -227.16897) (xy 85.052109 -227.174902) (xy 85.09938 -227.188594)
			(xy 85.143842 -227.209692) (xy 85.184345 -227.237648) (xy 85.219838 -227.27174) (xy 85.249403 -227.311084)
			(xy 85.272274 -227.354661) (xy 85.287858 -227.401342) (xy 85.295753 -227.449919) (xy 85.296248 -227.474526)
			(xy 85.614759 -227.474526) (xy 85.618854 -227.423798) (xy 85.631033 -227.374384) (xy 85.650981 -227.327564)
			(xy 85.678182 -227.28455) (xy 85.71193 -227.246456) (xy 85.751352 -227.214269) (xy 85.795426 -227.188823)
			(xy 85.843012 -227.170776) (xy 85.892876 -227.160596) (xy 85.943728 -227.158547) (xy 85.994249 -227.164681)
			(xy 86.043133 -227.178841) (xy 86.089112 -227.200658) (xy 86.130996 -227.229568) (xy 86.1677 -227.264823)
			(xy 86.198273 -227.305509) (xy 86.221924 -227.350572) (xy 86.23804 -227.398846) (xy 86.246204 -227.44908)
			(xy 86.246716 -227.474526) (xy 86.565244 -227.474526) (xy 86.569204 -227.425472) (xy 86.580981 -227.377688)
			(xy 86.600272 -227.332412) (xy 86.626575 -227.290816) (xy 86.65921 -227.253979) (xy 86.697331 -227.222854)
			(xy 86.739952 -227.198247) (xy 86.785968 -227.180795) (xy 86.834187 -227.170951) (xy 86.883362 -227.16897)
			(xy 86.932217 -227.174902) (xy 86.979488 -227.188594) (xy 87.02395 -227.209692) (xy 87.064453 -227.237648)
			(xy 87.099946 -227.27174) (xy 87.129511 -227.311084) (xy 87.152382 -227.354661) (xy 87.167966 -227.401342)
			(xy 87.175861 -227.449919) (xy 87.176356 -227.474526) (xy 87.494867 -227.474526) (xy 87.498962 -227.423798)
			(xy 87.511141 -227.374384) (xy 87.531089 -227.327564) (xy 87.55829 -227.28455) (xy 87.592038 -227.246456)
			(xy 87.63146 -227.214269) (xy 87.675534 -227.188823) (xy 87.72312 -227.170776) (xy 87.772984 -227.160596)
			(xy 87.823836 -227.158547) (xy 87.874357 -227.164681) (xy 87.923241 -227.178841) (xy 87.96922 -227.200658)
			(xy 88.011104 -227.229568) (xy 88.047808 -227.264823) (xy 88.078381 -227.305509) (xy 88.102032 -227.350572)
			(xy 88.118148 -227.398846) (xy 88.126312 -227.44908) (xy 88.126824 -227.474526) (xy 88.434921 -227.474526)
			(xy 88.439016 -227.423798) (xy 88.451195 -227.374384) (xy 88.471143 -227.327564) (xy 88.498344 -227.28455)
			(xy 88.532092 -227.246456) (xy 88.571514 -227.214269) (xy 88.615588 -227.188823) (xy 88.663174 -227.170776)
			(xy 88.713038 -227.160596) (xy 88.76389 -227.158547) (xy 88.814411 -227.164681) (xy 88.863295 -227.178841)
			(xy 88.909274 -227.200658) (xy 88.951158 -227.229568) (xy 88.987862 -227.264823) (xy 89.018435 -227.305509)
			(xy 89.042086 -227.350572) (xy 89.058202 -227.398846) (xy 89.066366 -227.44908) (xy 89.066878 -227.474526)
			(xy 89.385152 -227.474526) (xy 89.389112 -227.425472) (xy 89.400889 -227.377688) (xy 89.42018 -227.332412)
			(xy 89.446483 -227.290816) (xy 89.479118 -227.253979) (xy 89.517239 -227.222854) (xy 89.55986 -227.198247)
			(xy 89.605876 -227.180795) (xy 89.654095 -227.170951) (xy 89.70327 -227.16897) (xy 89.752125 -227.174902)
			(xy 89.799396 -227.188594) (xy 89.843858 -227.209692) (xy 89.884361 -227.237648) (xy 89.919854 -227.27174)
			(xy 89.949419 -227.311084) (xy 89.97229 -227.354661) (xy 89.987874 -227.401342) (xy 89.995769 -227.449919)
			(xy 89.996264 -227.474526) (xy 90.314775 -227.474526) (xy 90.31887 -227.423798) (xy 90.331049 -227.374384)
			(xy 90.350997 -227.327564) (xy 90.378198 -227.28455) (xy 90.411946 -227.246456) (xy 90.451368 -227.214269)
			(xy 90.495442 -227.188823) (xy 90.543028 -227.170776) (xy 90.592892 -227.160596) (xy 90.643744 -227.158547)
			(xy 90.694265 -227.164681) (xy 90.743149 -227.178841) (xy 90.789128 -227.200658) (xy 90.831012 -227.229568)
			(xy 90.867716 -227.264823) (xy 90.898289 -227.305509) (xy 90.92194 -227.350572) (xy 90.938056 -227.398846)
			(xy 90.94622 -227.44908) (xy 90.946732 -227.474526) (xy 91.26526 -227.474526) (xy 91.26922 -227.425472)
			(xy 91.280997 -227.377688) (xy 91.300288 -227.332412) (xy 91.326591 -227.290816) (xy 91.359226 -227.253979)
			(xy 91.397347 -227.222854) (xy 91.439968 -227.198247) (xy 91.485984 -227.180795) (xy 91.534203 -227.170951)
			(xy 91.583378 -227.16897) (xy 91.632233 -227.174902) (xy 91.679504 -227.188594) (xy 91.723966 -227.209692)
			(xy 91.764469 -227.237648) (xy 91.799962 -227.27174) (xy 91.829527 -227.311084) (xy 91.852398 -227.354661)
			(xy 91.867982 -227.401342) (xy 91.875877 -227.449919) (xy 91.876372 -227.474526) (xy 92.194883 -227.474526)
			(xy 92.198978 -227.423798) (xy 92.211157 -227.374384) (xy 92.231105 -227.327564) (xy 92.258306 -227.28455)
			(xy 92.292054 -227.246456) (xy 92.331476 -227.214269) (xy 92.37555 -227.188823) (xy 92.423136 -227.170776)
			(xy 92.473 -227.160596) (xy 92.523852 -227.158547) (xy 92.574373 -227.164681) (xy 92.623257 -227.178841)
			(xy 92.669236 -227.200658) (xy 92.71112 -227.229568) (xy 92.747824 -227.264823) (xy 92.778397 -227.305509)
			(xy 92.802048 -227.350572) (xy 92.818164 -227.398846) (xy 92.826328 -227.44908) (xy 92.82684 -227.474526)
			(xy 93.145114 -227.474526) (xy 93.149074 -227.425472) (xy 93.160851 -227.377688) (xy 93.180142 -227.332412)
			(xy 93.206445 -227.290816) (xy 93.23908 -227.253979) (xy 93.277201 -227.222854) (xy 93.319822 -227.198247)
			(xy 93.365838 -227.180795) (xy 93.414057 -227.170951) (xy 93.463232 -227.16897) (xy 93.512087 -227.174902)
			(xy 93.559358 -227.188594) (xy 93.60382 -227.209692) (xy 93.644323 -227.237648) (xy 93.679816 -227.27174)
			(xy 93.709381 -227.311084) (xy 93.732252 -227.354661) (xy 93.747836 -227.401342) (xy 93.755731 -227.449919)
			(xy 93.756226 -227.474526) (xy 94.074737 -227.474526) (xy 94.078832 -227.423798) (xy 94.091011 -227.374384)
			(xy 94.110959 -227.327564) (xy 94.13816 -227.28455) (xy 94.171908 -227.246456) (xy 94.21133 -227.214269)
			(xy 94.255404 -227.188823) (xy 94.30299 -227.170776) (xy 94.352854 -227.160596) (xy 94.403706 -227.158547)
			(xy 94.454227 -227.164681) (xy 94.503111 -227.178841) (xy 94.54909 -227.200658) (xy 94.590974 -227.229568)
			(xy 94.627678 -227.264823) (xy 94.658251 -227.305509) (xy 94.681902 -227.350572) (xy 94.698018 -227.398846)
			(xy 94.706182 -227.44908) (xy 94.706694 -227.474526) (xy 95.014791 -227.474526) (xy 95.018886 -227.423798)
			(xy 95.031065 -227.374384) (xy 95.051013 -227.327564) (xy 95.078214 -227.28455) (xy 95.111962 -227.246456)
			(xy 95.151384 -227.214269) (xy 95.195458 -227.188823) (xy 95.243044 -227.170776) (xy 95.292908 -227.160596)
			(xy 95.34376 -227.158547) (xy 95.394281 -227.164681) (xy 95.443165 -227.178841) (xy 95.489144 -227.200658)
			(xy 95.531028 -227.229568) (xy 95.567732 -227.264823) (xy 95.598305 -227.305509) (xy 95.621956 -227.350572)
			(xy 95.638072 -227.398846) (xy 95.646236 -227.44908) (xy 95.646748 -227.474526) (xy 95.965276 -227.474526)
			(xy 95.969236 -227.425472) (xy 95.981013 -227.377688) (xy 96.000304 -227.332412) (xy 96.026607 -227.290816)
			(xy 96.059242 -227.253979) (xy 96.097363 -227.222854) (xy 96.139984 -227.198247) (xy 96.186 -227.180795)
			(xy 96.234219 -227.170951) (xy 96.283394 -227.16897) (xy 96.332249 -227.174902) (xy 96.37952 -227.188594)
			(xy 96.423982 -227.209692) (xy 96.464485 -227.237648) (xy 96.499978 -227.27174) (xy 96.529543 -227.311084)
			(xy 96.552414 -227.354661) (xy 96.567998 -227.401342) (xy 96.575893 -227.449919) (xy 96.576388 -227.474526)
			(xy 98.785184 -227.474526) (xy 98.789144 -227.425472) (xy 98.800921 -227.377688) (xy 98.820212 -227.332412)
			(xy 98.846515 -227.290816) (xy 98.87915 -227.253979) (xy 98.917271 -227.222854) (xy 98.959892 -227.198247)
			(xy 99.005908 -227.180795) (xy 99.054127 -227.170951) (xy 99.103302 -227.16897) (xy 99.152157 -227.174902)
			(xy 99.199428 -227.188594) (xy 99.24389 -227.209692) (xy 99.284393 -227.237648) (xy 99.319886 -227.27174)
			(xy 99.349451 -227.311084) (xy 99.372322 -227.354661) (xy 99.387906 -227.401342) (xy 99.395801 -227.449919)
			(xy 99.396296 -227.474526) (xy 101.605346 -227.474526) (xy 101.609306 -227.425472) (xy 101.621083 -227.377688)
			(xy 101.640374 -227.332412) (xy 101.666677 -227.290816) (xy 101.699312 -227.253979) (xy 101.737433 -227.222854)
			(xy 101.780054 -227.198247) (xy 101.82607 -227.180795) (xy 101.874289 -227.170951) (xy 101.923464 -227.16897)
			(xy 101.972319 -227.174902) (xy 102.01959 -227.188594) (xy 102.064052 -227.209692) (xy 102.104555 -227.237648)
			(xy 102.140048 -227.27174) (xy 102.169613 -227.311084) (xy 102.192484 -227.354661) (xy 102.208068 -227.401342)
			(xy 102.215963 -227.449919) (xy 102.216458 -227.474526) (xy 104.425254 -227.474526) (xy 104.429214 -227.425472)
			(xy 104.440991 -227.377688) (xy 104.460282 -227.332412) (xy 104.486585 -227.290816) (xy 104.51922 -227.253979)
			(xy 104.557341 -227.222854) (xy 104.599962 -227.198247) (xy 104.645978 -227.180795) (xy 104.694197 -227.170951)
			(xy 104.743372 -227.16897) (xy 104.792227 -227.174902) (xy 104.839498 -227.188594) (xy 104.88396 -227.209692)
			(xy 104.924463 -227.237648) (xy 104.959956 -227.27174) (xy 104.989521 -227.311084) (xy 105.012392 -227.354661)
			(xy 105.027976 -227.401342) (xy 105.035871 -227.449919) (xy 105.036366 -227.474526) (xy 107.245162 -227.474526)
			(xy 107.249122 -227.425472) (xy 107.260899 -227.377688) (xy 107.28019 -227.332412) (xy 107.306493 -227.290816)
			(xy 107.339128 -227.253979) (xy 107.377249 -227.222854) (xy 107.41987 -227.198247) (xy 107.465886 -227.180795)
			(xy 107.514105 -227.170951) (xy 107.56328 -227.16897) (xy 107.612135 -227.174902) (xy 107.659406 -227.188594)
			(xy 107.703868 -227.209692) (xy 107.744371 -227.237648) (xy 107.779864 -227.27174) (xy 107.809429 -227.311084)
			(xy 107.8323 -227.354661) (xy 107.847884 -227.401342) (xy 107.855779 -227.449919) (xy 107.856274 -227.474526)
			(xy 108.174785 -227.474526) (xy 108.17888 -227.423798) (xy 108.191059 -227.374384) (xy 108.211007 -227.327564)
			(xy 108.238208 -227.28455) (xy 108.271956 -227.246456) (xy 108.311378 -227.214269) (xy 108.355452 -227.188823)
			(xy 108.403038 -227.170776) (xy 108.452902 -227.160596) (xy 108.503754 -227.158547) (xy 108.554275 -227.164681)
			(xy 108.603159 -227.178841) (xy 108.649138 -227.200658) (xy 108.691022 -227.229568) (xy 108.727726 -227.264823)
			(xy 108.758299 -227.305509) (xy 108.78195 -227.350572) (xy 108.798066 -227.398846) (xy 108.80623 -227.44908)
			(xy 108.806742 -227.474526) (xy 109.114839 -227.474526) (xy 109.118934 -227.423798) (xy 109.131113 -227.374384)
			(xy 109.151061 -227.327564) (xy 109.178262 -227.28455) (xy 109.21201 -227.246456) (xy 109.251432 -227.214269)
			(xy 109.295506 -227.188823) (xy 109.343092 -227.170776) (xy 109.392956 -227.160596) (xy 109.443808 -227.158547)
			(xy 109.494329 -227.164681) (xy 109.543213 -227.178841) (xy 109.589192 -227.200658) (xy 109.631076 -227.229568)
			(xy 109.66778 -227.264823) (xy 109.698353 -227.305509) (xy 109.722004 -227.350572) (xy 109.73812 -227.398846)
			(xy 109.746284 -227.44908) (xy 109.746796 -227.474526) (xy 110.065324 -227.474526) (xy 110.069284 -227.425472)
			(xy 110.081061 -227.377688) (xy 110.100352 -227.332412) (xy 110.126655 -227.290816) (xy 110.15929 -227.253979)
			(xy 110.197411 -227.222854) (xy 110.240032 -227.198247) (xy 110.286048 -227.180795) (xy 110.334267 -227.170951)
			(xy 110.383442 -227.16897) (xy 110.432297 -227.174902) (xy 110.479568 -227.188594) (xy 110.52403 -227.209692)
			(xy 110.564533 -227.237648) (xy 110.600026 -227.27174) (xy 110.629591 -227.311084) (xy 110.652462 -227.354661)
			(xy 110.668046 -227.401342) (xy 110.675941 -227.449919) (xy 110.676436 -227.474526) (xy 110.675941 -227.499133)
			(xy 110.668046 -227.54771) (xy 110.652462 -227.594391) (xy 110.629591 -227.637968) (xy 110.600026 -227.677312)
			(xy 110.564533 -227.711404) (xy 110.52403 -227.73936) (xy 110.479568 -227.760458) (xy 110.432297 -227.77415)
			(xy 110.383442 -227.780082) (xy 110.334267 -227.778101) (xy 110.286048 -227.768257) (xy 110.240032 -227.750805)
			(xy 110.197411 -227.726198) (xy 110.15929 -227.695073) (xy 110.126655 -227.658236) (xy 110.100352 -227.61664)
			(xy 110.081061 -227.571364) (xy 110.069284 -227.52358) (xy 110.065324 -227.474526) (xy 109.746796 -227.474526)
			(xy 109.746284 -227.499972) (xy 109.73812 -227.550206) (xy 109.722004 -227.59848) (xy 109.698353 -227.643543)
			(xy 109.66778 -227.684229) (xy 109.631076 -227.719484) (xy 109.589192 -227.748394) (xy 109.543213 -227.770211)
			(xy 109.494329 -227.784371) (xy 109.443808 -227.790505) (xy 109.392956 -227.788456) (xy 109.343092 -227.778276)
			(xy 109.295506 -227.760229) (xy 109.251432 -227.734783) (xy 109.21201 -227.702596) (xy 109.178262 -227.664502)
			(xy 109.151061 -227.621488) (xy 109.131113 -227.574668) (xy 109.118934 -227.525254) (xy 109.114839 -227.474526)
			(xy 108.806742 -227.474526) (xy 108.80623 -227.499972) (xy 108.798066 -227.550206) (xy 108.78195 -227.59848)
			(xy 108.758299 -227.643543) (xy 108.727726 -227.684229) (xy 108.691022 -227.719484) (xy 108.649138 -227.748394)
			(xy 108.603159 -227.770211) (xy 108.554275 -227.784371) (xy 108.503754 -227.790505) (xy 108.452902 -227.788456)
			(xy 108.403038 -227.778276) (xy 108.355452 -227.760229) (xy 108.311378 -227.734783) (xy 108.271956 -227.702596)
			(xy 108.238208 -227.664502) (xy 108.211007 -227.621488) (xy 108.191059 -227.574668) (xy 108.17888 -227.525254)
			(xy 108.174785 -227.474526) (xy 107.856274 -227.474526) (xy 107.855779 -227.499133) (xy 107.847884 -227.54771)
			(xy 107.8323 -227.594391) (xy 107.809429 -227.637968) (xy 107.779864 -227.677312) (xy 107.744371 -227.711404)
			(xy 107.703868 -227.73936) (xy 107.659406 -227.760458) (xy 107.612135 -227.77415) (xy 107.56328 -227.780082)
			(xy 107.514105 -227.778101) (xy 107.465886 -227.768257) (xy 107.41987 -227.750805) (xy 107.377249 -227.726198)
			(xy 107.339128 -227.695073) (xy 107.306493 -227.658236) (xy 107.28019 -227.61664) (xy 107.260899 -227.571364)
			(xy 107.249122 -227.52358) (xy 107.245162 -227.474526) (xy 105.036366 -227.474526) (xy 105.035871 -227.499133)
			(xy 105.027976 -227.54771) (xy 105.012392 -227.594391) (xy 104.989521 -227.637968) (xy 104.959956 -227.677312)
			(xy 104.924463 -227.711404) (xy 104.88396 -227.73936) (xy 104.839498 -227.760458) (xy 104.792227 -227.77415)
			(xy 104.743372 -227.780082) (xy 104.694197 -227.778101) (xy 104.645978 -227.768257) (xy 104.599962 -227.750805)
			(xy 104.557341 -227.726198) (xy 104.51922 -227.695073) (xy 104.486585 -227.658236) (xy 104.460282 -227.61664)
			(xy 104.440991 -227.571364) (xy 104.429214 -227.52358) (xy 104.425254 -227.474526) (xy 102.216458 -227.474526)
			(xy 102.215963 -227.499133) (xy 102.208068 -227.54771) (xy 102.192484 -227.594391) (xy 102.169613 -227.637968)
			(xy 102.140048 -227.677312) (xy 102.104555 -227.711404) (xy 102.064052 -227.73936) (xy 102.01959 -227.760458)
			(xy 101.972319 -227.77415) (xy 101.923464 -227.780082) (xy 101.874289 -227.778101) (xy 101.82607 -227.768257)
			(xy 101.780054 -227.750805) (xy 101.737433 -227.726198) (xy 101.699312 -227.695073) (xy 101.666677 -227.658236)
			(xy 101.640374 -227.61664) (xy 101.621083 -227.571364) (xy 101.609306 -227.52358) (xy 101.605346 -227.474526)
			(xy 99.396296 -227.474526) (xy 99.395801 -227.499133) (xy 99.387906 -227.54771) (xy 99.372322 -227.594391)
			(xy 99.349451 -227.637968) (xy 99.319886 -227.677312) (xy 99.284393 -227.711404) (xy 99.24389 -227.73936)
			(xy 99.199428 -227.760458) (xy 99.152157 -227.77415) (xy 99.103302 -227.780082) (xy 99.054127 -227.778101)
			(xy 99.005908 -227.768257) (xy 98.959892 -227.750805) (xy 98.917271 -227.726198) (xy 98.87915 -227.695073)
			(xy 98.846515 -227.658236) (xy 98.820212 -227.61664) (xy 98.800921 -227.571364) (xy 98.789144 -227.52358)
			(xy 98.785184 -227.474526) (xy 96.576388 -227.474526) (xy 96.575893 -227.499133) (xy 96.567998 -227.54771)
			(xy 96.552414 -227.594391) (xy 96.529543 -227.637968) (xy 96.499978 -227.677312) (xy 96.464485 -227.711404)
			(xy 96.423982 -227.73936) (xy 96.37952 -227.760458) (xy 96.332249 -227.77415) (xy 96.283394 -227.780082)
			(xy 96.234219 -227.778101) (xy 96.186 -227.768257) (xy 96.139984 -227.750805) (xy 96.097363 -227.726198)
			(xy 96.059242 -227.695073) (xy 96.026607 -227.658236) (xy 96.000304 -227.61664) (xy 95.981013 -227.571364)
			(xy 95.969236 -227.52358) (xy 95.965276 -227.474526) (xy 95.646748 -227.474526) (xy 95.646236 -227.499972)
			(xy 95.638072 -227.550206) (xy 95.621956 -227.59848) (xy 95.598305 -227.643543) (xy 95.567732 -227.684229)
			(xy 95.531028 -227.719484) (xy 95.489144 -227.748394) (xy 95.443165 -227.770211) (xy 95.394281 -227.784371)
			(xy 95.34376 -227.790505) (xy 95.292908 -227.788456) (xy 95.243044 -227.778276) (xy 95.195458 -227.760229)
			(xy 95.151384 -227.734783) (xy 95.111962 -227.702596) (xy 95.078214 -227.664502) (xy 95.051013 -227.621488)
			(xy 95.031065 -227.574668) (xy 95.018886 -227.525254) (xy 95.014791 -227.474526) (xy 94.706694 -227.474526)
			(xy 94.706182 -227.499972) (xy 94.698018 -227.550206) (xy 94.681902 -227.59848) (xy 94.658251 -227.643543)
			(xy 94.627678 -227.684229) (xy 94.590974 -227.719484) (xy 94.54909 -227.748394) (xy 94.503111 -227.770211)
			(xy 94.454227 -227.784371) (xy 94.403706 -227.790505) (xy 94.352854 -227.788456) (xy 94.30299 -227.778276)
			(xy 94.255404 -227.760229) (xy 94.21133 -227.734783) (xy 94.171908 -227.702596) (xy 94.13816 -227.664502)
			(xy 94.110959 -227.621488) (xy 94.091011 -227.574668) (xy 94.078832 -227.525254) (xy 94.074737 -227.474526)
			(xy 93.756226 -227.474526) (xy 93.755731 -227.499133) (xy 93.747836 -227.54771) (xy 93.732252 -227.594391)
			(xy 93.709381 -227.637968) (xy 93.679816 -227.677312) (xy 93.644323 -227.711404) (xy 93.60382 -227.73936)
			(xy 93.559358 -227.760458) (xy 93.512087 -227.77415) (xy 93.463232 -227.780082) (xy 93.414057 -227.778101)
			(xy 93.365838 -227.768257) (xy 93.319822 -227.750805) (xy 93.277201 -227.726198) (xy 93.23908 -227.695073)
			(xy 93.206445 -227.658236) (xy 93.180142 -227.61664) (xy 93.160851 -227.571364) (xy 93.149074 -227.52358)
			(xy 93.145114 -227.474526) (xy 92.82684 -227.474526) (xy 92.826328 -227.499972) (xy 92.818164 -227.550206)
			(xy 92.802048 -227.59848) (xy 92.778397 -227.643543) (xy 92.747824 -227.684229) (xy 92.71112 -227.719484)
			(xy 92.669236 -227.748394) (xy 92.623257 -227.770211) (xy 92.574373 -227.784371) (xy 92.523852 -227.790505)
			(xy 92.473 -227.788456) (xy 92.423136 -227.778276) (xy 92.37555 -227.760229) (xy 92.331476 -227.734783)
			(xy 92.292054 -227.702596) (xy 92.258306 -227.664502) (xy 92.231105 -227.621488) (xy 92.211157 -227.574668)
			(xy 92.198978 -227.525254) (xy 92.194883 -227.474526) (xy 91.876372 -227.474526) (xy 91.875877 -227.499133)
			(xy 91.867982 -227.54771) (xy 91.852398 -227.594391) (xy 91.829527 -227.637968) (xy 91.799962 -227.677312)
			(xy 91.764469 -227.711404) (xy 91.723966 -227.73936) (xy 91.679504 -227.760458) (xy 91.632233 -227.77415)
			(xy 91.583378 -227.780082) (xy 91.534203 -227.778101) (xy 91.485984 -227.768257) (xy 91.439968 -227.750805)
			(xy 91.397347 -227.726198) (xy 91.359226 -227.695073) (xy 91.326591 -227.658236) (xy 91.300288 -227.61664)
			(xy 91.280997 -227.571364) (xy 91.26922 -227.52358) (xy 91.26526 -227.474526) (xy 90.946732 -227.474526)
			(xy 90.94622 -227.499972) (xy 90.938056 -227.550206) (xy 90.92194 -227.59848) (xy 90.898289 -227.643543)
			(xy 90.867716 -227.684229) (xy 90.831012 -227.719484) (xy 90.789128 -227.748394) (xy 90.743149 -227.770211)
			(xy 90.694265 -227.784371) (xy 90.643744 -227.790505) (xy 90.592892 -227.788456) (xy 90.543028 -227.778276)
			(xy 90.495442 -227.760229) (xy 90.451368 -227.734783) (xy 90.411946 -227.702596) (xy 90.378198 -227.664502)
			(xy 90.350997 -227.621488) (xy 90.331049 -227.574668) (xy 90.31887 -227.525254) (xy 90.314775 -227.474526)
			(xy 89.996264 -227.474526) (xy 89.995769 -227.499133) (xy 89.987874 -227.54771) (xy 89.97229 -227.594391)
			(xy 89.949419 -227.637968) (xy 89.919854 -227.677312) (xy 89.884361 -227.711404) (xy 89.843858 -227.73936)
			(xy 89.799396 -227.760458) (xy 89.752125 -227.77415) (xy 89.70327 -227.780082) (xy 89.654095 -227.778101)
			(xy 89.605876 -227.768257) (xy 89.55986 -227.750805) (xy 89.517239 -227.726198) (xy 89.479118 -227.695073)
			(xy 89.446483 -227.658236) (xy 89.42018 -227.61664) (xy 89.400889 -227.571364) (xy 89.389112 -227.52358)
			(xy 89.385152 -227.474526) (xy 89.066878 -227.474526) (xy 89.066366 -227.499972) (xy 89.058202 -227.550206)
			(xy 89.042086 -227.59848) (xy 89.018435 -227.643543) (xy 88.987862 -227.684229) (xy 88.951158 -227.719484)
			(xy 88.909274 -227.748394) (xy 88.863295 -227.770211) (xy 88.814411 -227.784371) (xy 88.76389 -227.790505)
			(xy 88.713038 -227.788456) (xy 88.663174 -227.778276) (xy 88.615588 -227.760229) (xy 88.571514 -227.734783)
			(xy 88.532092 -227.702596) (xy 88.498344 -227.664502) (xy 88.471143 -227.621488) (xy 88.451195 -227.574668)
			(xy 88.439016 -227.525254) (xy 88.434921 -227.474526) (xy 88.126824 -227.474526) (xy 88.126312 -227.499972)
			(xy 88.118148 -227.550206) (xy 88.102032 -227.59848) (xy 88.078381 -227.643543) (xy 88.047808 -227.684229)
			(xy 88.011104 -227.719484) (xy 87.96922 -227.748394) (xy 87.923241 -227.770211) (xy 87.874357 -227.784371)
			(xy 87.823836 -227.790505) (xy 87.772984 -227.788456) (xy 87.72312 -227.778276) (xy 87.675534 -227.760229)
			(xy 87.63146 -227.734783) (xy 87.592038 -227.702596) (xy 87.55829 -227.664502) (xy 87.531089 -227.621488)
			(xy 87.511141 -227.574668) (xy 87.498962 -227.525254) (xy 87.494867 -227.474526) (xy 87.176356 -227.474526)
			(xy 87.175861 -227.499133) (xy 87.167966 -227.54771) (xy 87.152382 -227.594391) (xy 87.129511 -227.637968)
			(xy 87.099946 -227.677312) (xy 87.064453 -227.711404) (xy 87.02395 -227.73936) (xy 86.979488 -227.760458)
			(xy 86.932217 -227.77415) (xy 86.883362 -227.780082) (xy 86.834187 -227.778101) (xy 86.785968 -227.768257)
			(xy 86.739952 -227.750805) (xy 86.697331 -227.726198) (xy 86.65921 -227.695073) (xy 86.626575 -227.658236)
			(xy 86.600272 -227.61664) (xy 86.580981 -227.571364) (xy 86.569204 -227.52358) (xy 86.565244 -227.474526)
			(xy 86.246716 -227.474526) (xy 86.246204 -227.499972) (xy 86.23804 -227.550206) (xy 86.221924 -227.59848)
			(xy 86.198273 -227.643543) (xy 86.1677 -227.684229) (xy 86.130996 -227.719484) (xy 86.089112 -227.748394)
			(xy 86.043133 -227.770211) (xy 85.994249 -227.784371) (xy 85.943728 -227.790505) (xy 85.892876 -227.788456)
			(xy 85.843012 -227.778276) (xy 85.795426 -227.760229) (xy 85.751352 -227.734783) (xy 85.71193 -227.702596)
			(xy 85.678182 -227.664502) (xy 85.650981 -227.621488) (xy 85.631033 -227.574668) (xy 85.618854 -227.525254)
			(xy 85.614759 -227.474526) (xy 85.296248 -227.474526) (xy 85.295753 -227.499133) (xy 85.287858 -227.54771)
			(xy 85.272274 -227.594391) (xy 85.249403 -227.637968) (xy 85.219838 -227.677312) (xy 85.184345 -227.711404)
			(xy 85.143842 -227.73936) (xy 85.09938 -227.760458) (xy 85.052109 -227.77415) (xy 85.003254 -227.780082)
			(xy 84.954079 -227.778101) (xy 84.90586 -227.768257) (xy 84.859844 -227.750805) (xy 84.817223 -227.726198)
			(xy 84.779102 -227.695073) (xy 84.746467 -227.658236) (xy 84.720164 -227.61664) (xy 84.700873 -227.571364)
			(xy 84.689096 -227.52358) (xy 84.685136 -227.474526) (xy 84.366862 -227.474526) (xy 84.36635 -227.499972)
			(xy 84.358186 -227.550206) (xy 84.34207 -227.59848) (xy 84.318419 -227.643543) (xy 84.287846 -227.684229)
			(xy 84.251142 -227.719484) (xy 84.209258 -227.748394) (xy 84.163279 -227.770211) (xy 84.114395 -227.784371)
			(xy 84.063874 -227.790505) (xy 84.013022 -227.788456) (xy 83.963158 -227.778276) (xy 83.915572 -227.760229)
			(xy 83.871498 -227.734783) (xy 83.832076 -227.702596) (xy 83.798328 -227.664502) (xy 83.771127 -227.621488)
			(xy 83.751179 -227.574668) (xy 83.739 -227.525254) (xy 83.734905 -227.474526) (xy 83.416394 -227.474526)
			(xy 83.415899 -227.499133) (xy 83.408004 -227.54771) (xy 83.39242 -227.594391) (xy 83.369549 -227.637968)
			(xy 83.339984 -227.677312) (xy 83.304491 -227.711404) (xy 83.263988 -227.73936) (xy 83.219526 -227.760458)
			(xy 83.172255 -227.77415) (xy 83.1234 -227.780082) (xy 83.074225 -227.778101) (xy 83.026006 -227.768257)
			(xy 82.97999 -227.750805) (xy 82.937369 -227.726198) (xy 82.899248 -227.695073) (xy 82.866613 -227.658236)
			(xy 82.84031 -227.61664) (xy 82.821019 -227.571364) (xy 82.809242 -227.52358) (xy 82.805282 -227.474526)
			(xy 82.486754 -227.474526) (xy 82.486242 -227.499972) (xy 82.478078 -227.550206) (xy 82.461962 -227.59848)
			(xy 82.438311 -227.643543) (xy 82.407738 -227.684229) (xy 82.371034 -227.719484) (xy 82.32915 -227.748394)
			(xy 82.283171 -227.770211) (xy 82.234287 -227.784371) (xy 82.183766 -227.790505) (xy 82.132914 -227.788456)
			(xy 82.08305 -227.778276) (xy 82.035464 -227.760229) (xy 81.99139 -227.734783) (xy 81.951968 -227.702596)
			(xy 81.91822 -227.664502) (xy 81.891019 -227.621488) (xy 81.871071 -227.574668) (xy 81.858892 -227.525254)
			(xy 81.854797 -227.474526) (xy 81.5467 -227.474526) (xy 81.546188 -227.499972) (xy 81.538024 -227.550206)
			(xy 81.521908 -227.59848) (xy 81.498257 -227.643543) (xy 81.467684 -227.684229) (xy 81.43098 -227.719484)
			(xy 81.389096 -227.748394) (xy 81.343117 -227.770211) (xy 81.294233 -227.784371) (xy 81.243712 -227.790505)
			(xy 81.19286 -227.788456) (xy 81.142996 -227.778276) (xy 81.09541 -227.760229) (xy 81.051336 -227.734783)
			(xy 81.011914 -227.702596) (xy 80.978166 -227.664502) (xy 80.950965 -227.621488) (xy 80.931017 -227.574668)
			(xy 80.918838 -227.525254) (xy 80.914743 -227.474526) (xy 80.596486 -227.474526) (xy 80.595991 -227.499133)
			(xy 80.588096 -227.54771) (xy 80.572512 -227.594391) (xy 80.549641 -227.637968) (xy 80.520076 -227.677312)
			(xy 80.484583 -227.711404) (xy 80.44408 -227.73936) (xy 80.399618 -227.760458) (xy 80.352347 -227.77415)
			(xy 80.303492 -227.780082) (xy 80.254317 -227.778101) (xy 80.206098 -227.768257) (xy 80.160082 -227.750805)
			(xy 80.117461 -227.726198) (xy 80.07934 -227.695073) (xy 80.046705 -227.658236) (xy 80.020402 -227.61664)
			(xy 80.001111 -227.571364) (xy 79.989334 -227.52358) (xy 79.985374 -227.474526) (xy 78.716378 -227.474526)
			(xy 78.715883 -227.499133) (xy 78.707988 -227.54771) (xy 78.692404 -227.594391) (xy 78.669533 -227.637968)
			(xy 78.639968 -227.677312) (xy 78.604475 -227.711404) (xy 78.563972 -227.73936) (xy 78.51951 -227.760458)
			(xy 78.472239 -227.77415) (xy 78.423384 -227.780082) (xy 78.374209 -227.778101) (xy 78.32599 -227.768257)
			(xy 78.279974 -227.750805) (xy 78.237353 -227.726198) (xy 78.199232 -227.695073) (xy 78.166597 -227.658236)
			(xy 78.140294 -227.61664) (xy 78.121003 -227.571364) (xy 78.109226 -227.52358) (xy 78.105266 -227.474526)
			(xy 62.37732 -227.474526) (xy 62.37732 -228.284532) (xy 76.695312 -228.284532) (xy 76.699272 -228.235478)
			(xy 76.711049 -228.187694) (xy 76.73034 -228.142418) (xy 76.756643 -228.100822) (xy 76.789278 -228.063985)
			(xy 76.827399 -228.03286) (xy 76.87002 -228.008253) (xy 76.916036 -227.990801) (xy 76.964255 -227.980957)
			(xy 77.01343 -227.978976) (xy 77.062285 -227.984908) (xy 77.109556 -227.9986) (xy 77.154018 -228.019698)
			(xy 77.194521 -228.047654) (xy 77.230014 -228.081746) (xy 77.259579 -228.12109) (xy 77.28245 -228.164667)
			(xy 77.298034 -228.211348) (xy 77.305929 -228.259925) (xy 77.306424 -228.284532) (xy 79.51522 -228.284532)
			(xy 79.51918 -228.235478) (xy 79.530957 -228.187694) (xy 79.550248 -228.142418) (xy 79.576551 -228.100822)
			(xy 79.609186 -228.063985) (xy 79.647307 -228.03286) (xy 79.689928 -228.008253) (xy 79.735944 -227.990801)
			(xy 79.784163 -227.980957) (xy 79.833338 -227.978976) (xy 79.882193 -227.984908) (xy 79.929464 -227.9986)
			(xy 79.973926 -228.019698) (xy 80.014429 -228.047654) (xy 80.049922 -228.081746) (xy 80.079487 -228.12109)
			(xy 80.102358 -228.164667) (xy 80.117942 -228.211348) (xy 80.125837 -228.259925) (xy 80.126332 -228.284532)
			(xy 80.444843 -228.284532) (xy 80.448938 -228.233804) (xy 80.461117 -228.18439) (xy 80.481065 -228.13757)
			(xy 80.508266 -228.094556) (xy 80.542014 -228.056462) (xy 80.581436 -228.024275) (xy 80.62551 -227.998829)
			(xy 80.673096 -227.980782) (xy 80.72296 -227.970602) (xy 80.773812 -227.968553) (xy 80.824333 -227.974687)
			(xy 80.873217 -227.988847) (xy 80.919196 -228.010664) (xy 80.96108 -228.039574) (xy 80.997784 -228.074829)
			(xy 81.028357 -228.115515) (xy 81.052008 -228.160578) (xy 81.068124 -228.208852) (xy 81.076288 -228.259086)
			(xy 81.0768 -228.284532) (xy 81.395328 -228.284532) (xy 81.399288 -228.235478) (xy 81.411065 -228.187694)
			(xy 81.430356 -228.142418) (xy 81.456659 -228.100822) (xy 81.489294 -228.063985) (xy 81.527415 -228.03286)
			(xy 81.570036 -228.008253) (xy 81.616052 -227.990801) (xy 81.664271 -227.980957) (xy 81.713446 -227.978976)
			(xy 81.762301 -227.984908) (xy 81.809572 -227.9986) (xy 81.854034 -228.019698) (xy 81.894537 -228.047654)
			(xy 81.93003 -228.081746) (xy 81.959595 -228.12109) (xy 81.982466 -228.164667) (xy 81.99805 -228.211348)
			(xy 82.005945 -228.259925) (xy 82.00644 -228.284532) (xy 82.324697 -228.284532) (xy 82.328792 -228.233804)
			(xy 82.340971 -228.18439) (xy 82.360919 -228.13757) (xy 82.38812 -228.094556) (xy 82.421868 -228.056462)
			(xy 82.46129 -228.024275) (xy 82.505364 -227.998829) (xy 82.55295 -227.980782) (xy 82.602814 -227.970602)
			(xy 82.653666 -227.968553) (xy 82.704187 -227.974687) (xy 82.753071 -227.988847) (xy 82.79905 -228.010664)
			(xy 82.840934 -228.039574) (xy 82.877638 -228.074829) (xy 82.908211 -228.115515) (xy 82.931862 -228.160578)
			(xy 82.947978 -228.208852) (xy 82.956142 -228.259086) (xy 82.956654 -228.284532) (xy 83.275182 -228.284532)
			(xy 83.279142 -228.235478) (xy 83.290919 -228.187694) (xy 83.31021 -228.142418) (xy 83.336513 -228.100822)
			(xy 83.369148 -228.063985) (xy 83.407269 -228.03286) (xy 83.44989 -228.008253) (xy 83.495906 -227.990801)
			(xy 83.544125 -227.980957) (xy 83.5933 -227.978976) (xy 83.642155 -227.984908) (xy 83.689426 -227.9986)
			(xy 83.733888 -228.019698) (xy 83.774391 -228.047654) (xy 83.809884 -228.081746) (xy 83.839449 -228.12109)
			(xy 83.86232 -228.164667) (xy 83.877904 -228.211348) (xy 83.885799 -228.259925) (xy 83.886294 -228.284532)
			(xy 84.204805 -228.284532) (xy 84.2089 -228.233804) (xy 84.221079 -228.18439) (xy 84.241027 -228.13757)
			(xy 84.268228 -228.094556) (xy 84.301976 -228.056462) (xy 84.341398 -228.024275) (xy 84.385472 -227.998829)
			(xy 84.433058 -227.980782) (xy 84.482922 -227.970602) (xy 84.533774 -227.968553) (xy 84.584295 -227.974687)
			(xy 84.633179 -227.988847) (xy 84.679158 -228.010664) (xy 84.721042 -228.039574) (xy 84.757746 -228.074829)
			(xy 84.788319 -228.115515) (xy 84.81197 -228.160578) (xy 84.828086 -228.208852) (xy 84.83625 -228.259086)
			(xy 84.836762 -228.284532) (xy 85.144859 -228.284532) (xy 85.148954 -228.233804) (xy 85.161133 -228.18439)
			(xy 85.181081 -228.13757) (xy 85.208282 -228.094556) (xy 85.24203 -228.056462) (xy 85.281452 -228.024275)
			(xy 85.325526 -227.998829) (xy 85.373112 -227.980782) (xy 85.422976 -227.970602) (xy 85.473828 -227.968553)
			(xy 85.524349 -227.974687) (xy 85.573233 -227.988847) (xy 85.619212 -228.010664) (xy 85.661096 -228.039574)
			(xy 85.6978 -228.074829) (xy 85.728373 -228.115515) (xy 85.752024 -228.160578) (xy 85.76814 -228.208852)
			(xy 85.776304 -228.259086) (xy 85.776816 -228.284532) (xy 86.095344 -228.284532) (xy 86.099304 -228.235478)
			(xy 86.111081 -228.187694) (xy 86.130372 -228.142418) (xy 86.156675 -228.100822) (xy 86.18931 -228.063985)
			(xy 86.227431 -228.03286) (xy 86.270052 -228.008253) (xy 86.316068 -227.990801) (xy 86.364287 -227.980957)
			(xy 86.413462 -227.978976) (xy 86.462317 -227.984908) (xy 86.509588 -227.9986) (xy 86.55405 -228.019698)
			(xy 86.594553 -228.047654) (xy 86.630046 -228.081746) (xy 86.659611 -228.12109) (xy 86.682482 -228.164667)
			(xy 86.698066 -228.211348) (xy 86.705961 -228.259925) (xy 86.706456 -228.284532) (xy 87.024713 -228.284532)
			(xy 87.028808 -228.233804) (xy 87.040987 -228.18439) (xy 87.060935 -228.13757) (xy 87.088136 -228.094556)
			(xy 87.121884 -228.056462) (xy 87.161306 -228.024275) (xy 87.20538 -227.998829) (xy 87.252966 -227.980782)
			(xy 87.30283 -227.970602) (xy 87.353682 -227.968553) (xy 87.404203 -227.974687) (xy 87.453087 -227.988847)
			(xy 87.499066 -228.010664) (xy 87.54095 -228.039574) (xy 87.577654 -228.074829) (xy 87.608227 -228.115515)
			(xy 87.631878 -228.160578) (xy 87.647994 -228.208852) (xy 87.656158 -228.259086) (xy 87.65667 -228.284532)
			(xy 87.975198 -228.284532) (xy 87.979158 -228.235478) (xy 87.990935 -228.187694) (xy 88.010226 -228.142418)
			(xy 88.036529 -228.100822) (xy 88.069164 -228.063985) (xy 88.107285 -228.03286) (xy 88.149906 -228.008253)
			(xy 88.195922 -227.990801) (xy 88.244141 -227.980957) (xy 88.293316 -227.978976) (xy 88.342171 -227.984908)
			(xy 88.389442 -227.9986) (xy 88.433904 -228.019698) (xy 88.474407 -228.047654) (xy 88.5099 -228.081746)
			(xy 88.539465 -228.12109) (xy 88.562336 -228.164667) (xy 88.57792 -228.211348) (xy 88.585815 -228.259925)
			(xy 88.58631 -228.284532) (xy 88.904821 -228.284532) (xy 88.908916 -228.233804) (xy 88.921095 -228.18439)
			(xy 88.941043 -228.13757) (xy 88.968244 -228.094556) (xy 89.001992 -228.056462) (xy 89.041414 -228.024275)
			(xy 89.085488 -227.998829) (xy 89.133074 -227.980782) (xy 89.182938 -227.970602) (xy 89.23379 -227.968553)
			(xy 89.284311 -227.974687) (xy 89.333195 -227.988847) (xy 89.379174 -228.010664) (xy 89.421058 -228.039574)
			(xy 89.457762 -228.074829) (xy 89.488335 -228.115515) (xy 89.511986 -228.160578) (xy 89.528102 -228.208852)
			(xy 89.536266 -228.259086) (xy 89.536778 -228.284532) (xy 89.855306 -228.284532) (xy 89.859266 -228.235478)
			(xy 89.871043 -228.187694) (xy 89.890334 -228.142418) (xy 89.916637 -228.100822) (xy 89.949272 -228.063985)
			(xy 89.987393 -228.03286) (xy 90.030014 -228.008253) (xy 90.07603 -227.990801) (xy 90.124249 -227.980957)
			(xy 90.173424 -227.978976) (xy 90.222279 -227.984908) (xy 90.26955 -227.9986) (xy 90.314012 -228.019698)
			(xy 90.354515 -228.047654) (xy 90.390008 -228.081746) (xy 90.419573 -228.12109) (xy 90.442444 -228.164667)
			(xy 90.458028 -228.211348) (xy 90.465923 -228.259925) (xy 90.466418 -228.284532) (xy 90.784675 -228.284532)
			(xy 90.78877 -228.233804) (xy 90.800949 -228.18439) (xy 90.820897 -228.13757) (xy 90.848098 -228.094556)
			(xy 90.881846 -228.056462) (xy 90.921268 -228.024275) (xy 90.965342 -227.998829) (xy 91.012928 -227.980782)
			(xy 91.062792 -227.970602) (xy 91.113644 -227.968553) (xy 91.164165 -227.974687) (xy 91.213049 -227.988847)
			(xy 91.259028 -228.010664) (xy 91.300912 -228.039574) (xy 91.337616 -228.074829) (xy 91.368189 -228.115515)
			(xy 91.39184 -228.160578) (xy 91.407956 -228.208852) (xy 91.41612 -228.259086) (xy 91.416632 -228.284532)
			(xy 91.724729 -228.284532) (xy 91.728824 -228.233804) (xy 91.741003 -228.18439) (xy 91.760951 -228.13757)
			(xy 91.788152 -228.094556) (xy 91.8219 -228.056462) (xy 91.861322 -228.024275) (xy 91.905396 -227.998829)
			(xy 91.952982 -227.980782) (xy 92.002846 -227.970602) (xy 92.053698 -227.968553) (xy 92.104219 -227.974687)
			(xy 92.153103 -227.988847) (xy 92.199082 -228.010664) (xy 92.240966 -228.039574) (xy 92.27767 -228.074829)
			(xy 92.308243 -228.115515) (xy 92.331894 -228.160578) (xy 92.34801 -228.208852) (xy 92.356174 -228.259086)
			(xy 92.356686 -228.284532) (xy 92.675214 -228.284532) (xy 92.679174 -228.235478) (xy 92.690951 -228.187694)
			(xy 92.710242 -228.142418) (xy 92.736545 -228.100822) (xy 92.76918 -228.063985) (xy 92.807301 -228.03286)
			(xy 92.849922 -228.008253) (xy 92.895938 -227.990801) (xy 92.944157 -227.980957) (xy 92.993332 -227.978976)
			(xy 93.042187 -227.984908) (xy 93.089458 -227.9986) (xy 93.13392 -228.019698) (xy 93.174423 -228.047654)
			(xy 93.209916 -228.081746) (xy 93.239481 -228.12109) (xy 93.262352 -228.164667) (xy 93.277936 -228.211348)
			(xy 93.285831 -228.259925) (xy 93.286326 -228.284532) (xy 93.604837 -228.284532) (xy 93.608932 -228.233804)
			(xy 93.621111 -228.18439) (xy 93.641059 -228.13757) (xy 93.66826 -228.094556) (xy 93.702008 -228.056462)
			(xy 93.74143 -228.024275) (xy 93.785504 -227.998829) (xy 93.83309 -227.980782) (xy 93.882954 -227.970602)
			(xy 93.933806 -227.968553) (xy 93.984327 -227.974687) (xy 94.033211 -227.988847) (xy 94.07919 -228.010664)
			(xy 94.121074 -228.039574) (xy 94.157778 -228.074829) (xy 94.188351 -228.115515) (xy 94.212002 -228.160578)
			(xy 94.228118 -228.208852) (xy 94.236282 -228.259086) (xy 94.236794 -228.284532) (xy 94.555322 -228.284532)
			(xy 94.559282 -228.235478) (xy 94.571059 -228.187694) (xy 94.59035 -228.142418) (xy 94.616653 -228.100822)
			(xy 94.649288 -228.063985) (xy 94.687409 -228.03286) (xy 94.73003 -228.008253) (xy 94.776046 -227.990801)
			(xy 94.824265 -227.980957) (xy 94.87344 -227.978976) (xy 94.922295 -227.984908) (xy 94.969566 -227.9986)
			(xy 95.014028 -228.019698) (xy 95.054531 -228.047654) (xy 95.090024 -228.081746) (xy 95.119589 -228.12109)
			(xy 95.14246 -228.164667) (xy 95.158044 -228.211348) (xy 95.165939 -228.259925) (xy 95.166434 -228.284532)
			(xy 95.484691 -228.284532) (xy 95.488786 -228.233804) (xy 95.500965 -228.18439) (xy 95.520913 -228.13757)
			(xy 95.548114 -228.094556) (xy 95.581862 -228.056462) (xy 95.621284 -228.024275) (xy 95.665358 -227.998829)
			(xy 95.712944 -227.980782) (xy 95.762808 -227.970602) (xy 95.81366 -227.968553) (xy 95.864181 -227.974687)
			(xy 95.913065 -227.988847) (xy 95.959044 -228.010664) (xy 96.000928 -228.039574) (xy 96.037632 -228.074829)
			(xy 96.068205 -228.115515) (xy 96.091856 -228.160578) (xy 96.107972 -228.208852) (xy 96.116136 -228.259086)
			(xy 96.116648 -228.284532) (xy 96.435176 -228.284532) (xy 96.439136 -228.235478) (xy 96.450913 -228.187694)
			(xy 96.470204 -228.142418) (xy 96.496507 -228.100822) (xy 96.529142 -228.063985) (xy 96.567263 -228.03286)
			(xy 96.609884 -228.008253) (xy 96.6559 -227.990801) (xy 96.704119 -227.980957) (xy 96.753294 -227.978976)
			(xy 96.802149 -227.984908) (xy 96.84942 -227.9986) (xy 96.893882 -228.019698) (xy 96.934385 -228.047654)
			(xy 96.969878 -228.081746) (xy 96.999443 -228.12109) (xy 97.022314 -228.164667) (xy 97.037898 -228.211348)
			(xy 97.045793 -228.259925) (xy 97.046288 -228.284532) (xy 97.364799 -228.284532) (xy 97.368894 -228.233804)
			(xy 97.381073 -228.18439) (xy 97.401021 -228.13757) (xy 97.428222 -228.094556) (xy 97.46197 -228.056462)
			(xy 97.501392 -228.024275) (xy 97.545466 -227.998829) (xy 97.593052 -227.980782) (xy 97.642916 -227.970602)
			(xy 97.693768 -227.968553) (xy 97.744289 -227.974687) (xy 97.793173 -227.988847) (xy 97.839152 -228.010664)
			(xy 97.881036 -228.039574) (xy 97.91774 -228.074829) (xy 97.948313 -228.115515) (xy 97.971964 -228.160578)
			(xy 97.98808 -228.208852) (xy 97.996244 -228.259086) (xy 97.996756 -228.284532) (xy 98.304853 -228.284532)
			(xy 98.308948 -228.233804) (xy 98.321127 -228.18439) (xy 98.341075 -228.13757) (xy 98.368276 -228.094556)
			(xy 98.402024 -228.056462) (xy 98.441446 -228.024275) (xy 98.48552 -227.998829) (xy 98.533106 -227.980782)
			(xy 98.58297 -227.970602) (xy 98.633822 -227.968553) (xy 98.684343 -227.974687) (xy 98.733227 -227.988847)
			(xy 98.779206 -228.010664) (xy 98.82109 -228.039574) (xy 98.857794 -228.074829) (xy 98.888367 -228.115515)
			(xy 98.912018 -228.160578) (xy 98.928134 -228.208852) (xy 98.936298 -228.259086) (xy 98.93681 -228.284532)
			(xy 99.255338 -228.284532) (xy 99.259298 -228.235478) (xy 99.271075 -228.187694) (xy 99.290366 -228.142418)
			(xy 99.316669 -228.100822) (xy 99.349304 -228.063985) (xy 99.387425 -228.03286) (xy 99.430046 -228.008253)
			(xy 99.476062 -227.990801) (xy 99.524281 -227.980957) (xy 99.573456 -227.978976) (xy 99.622311 -227.984908)
			(xy 99.669582 -227.9986) (xy 99.714044 -228.019698) (xy 99.754547 -228.047654) (xy 99.79004 -228.081746)
			(xy 99.819605 -228.12109) (xy 99.842476 -228.164667) (xy 99.85806 -228.211348) (xy 99.865955 -228.259925)
			(xy 99.86645 -228.284532) (xy 100.184707 -228.284532) (xy 100.188802 -228.233804) (xy 100.200981 -228.18439)
			(xy 100.220929 -228.13757) (xy 100.24813 -228.094556) (xy 100.281878 -228.056462) (xy 100.3213 -228.024275)
			(xy 100.365374 -227.998829) (xy 100.41296 -227.980782) (xy 100.462824 -227.970602) (xy 100.513676 -227.968553)
			(xy 100.564197 -227.974687) (xy 100.613081 -227.988847) (xy 100.65906 -228.010664) (xy 100.700944 -228.039574)
			(xy 100.737648 -228.074829) (xy 100.768221 -228.115515) (xy 100.791872 -228.160578) (xy 100.807988 -228.208852)
			(xy 100.816152 -228.259086) (xy 100.816664 -228.284532) (xy 101.124761 -228.284532) (xy 101.128856 -228.233804)
			(xy 101.141035 -228.18439) (xy 101.160983 -228.13757) (xy 101.188184 -228.094556) (xy 101.221932 -228.056462)
			(xy 101.261354 -228.024275) (xy 101.305428 -227.998829) (xy 101.353014 -227.980782) (xy 101.402878 -227.970602)
			(xy 101.45373 -227.968553) (xy 101.504251 -227.974687) (xy 101.553135 -227.988847) (xy 101.599114 -228.010664)
			(xy 101.640998 -228.039574) (xy 101.677702 -228.074829) (xy 101.708275 -228.115515) (xy 101.731926 -228.160578)
			(xy 101.748042 -228.208852) (xy 101.756206 -228.259086) (xy 101.756718 -228.284532) (xy 102.075246 -228.284532)
			(xy 102.079206 -228.235478) (xy 102.090983 -228.187694) (xy 102.110274 -228.142418) (xy 102.136577 -228.100822)
			(xy 102.169212 -228.063985) (xy 102.207333 -228.03286) (xy 102.249954 -228.008253) (xy 102.29597 -227.990801)
			(xy 102.344189 -227.980957) (xy 102.393364 -227.978976) (xy 102.442219 -227.984908) (xy 102.48949 -227.9986)
			(xy 102.533952 -228.019698) (xy 102.574455 -228.047654) (xy 102.609948 -228.081746) (xy 102.639513 -228.12109)
			(xy 102.662384 -228.164667) (xy 102.677968 -228.211348) (xy 102.685863 -228.259925) (xy 102.686358 -228.284532)
			(xy 103.004869 -228.284532) (xy 103.008964 -228.233804) (xy 103.021143 -228.18439) (xy 103.041091 -228.13757)
			(xy 103.068292 -228.094556) (xy 103.10204 -228.056462) (xy 103.141462 -228.024275) (xy 103.185536 -227.998829)
			(xy 103.233122 -227.980782) (xy 103.282986 -227.970602) (xy 103.333838 -227.968553) (xy 103.384359 -227.974687)
			(xy 103.433243 -227.988847) (xy 103.479222 -228.010664) (xy 103.521106 -228.039574) (xy 103.55781 -228.074829)
			(xy 103.588383 -228.115515) (xy 103.612034 -228.160578) (xy 103.62815 -228.208852) (xy 103.636314 -228.259086)
			(xy 103.636826 -228.284532) (xy 103.944923 -228.284532) (xy 103.949018 -228.233804) (xy 103.961197 -228.18439)
			(xy 103.981145 -228.13757) (xy 104.008346 -228.094556) (xy 104.042094 -228.056462) (xy 104.081516 -228.024275)
			(xy 104.12559 -227.998829) (xy 104.173176 -227.980782) (xy 104.22304 -227.970602) (xy 104.273892 -227.968553)
			(xy 104.324413 -227.974687) (xy 104.373297 -227.988847) (xy 104.419276 -228.010664) (xy 104.46116 -228.039574)
			(xy 104.497864 -228.074829) (xy 104.528437 -228.115515) (xy 104.552088 -228.160578) (xy 104.568204 -228.208852)
			(xy 104.576368 -228.259086) (xy 104.57688 -228.284532) (xy 104.895154 -228.284532) (xy 104.899114 -228.235478)
			(xy 104.910891 -228.187694) (xy 104.930182 -228.142418) (xy 104.956485 -228.100822) (xy 104.98912 -228.063985)
			(xy 105.027241 -228.03286) (xy 105.069862 -228.008253) (xy 105.115878 -227.990801) (xy 105.164097 -227.980957)
			(xy 105.213272 -227.978976) (xy 105.262127 -227.984908) (xy 105.309398 -227.9986) (xy 105.35386 -228.019698)
			(xy 105.394363 -228.047654) (xy 105.429856 -228.081746) (xy 105.459421 -228.12109) (xy 105.482292 -228.164667)
			(xy 105.497876 -228.211348) (xy 105.505771 -228.259925) (xy 105.506266 -228.284532) (xy 105.824777 -228.284532)
			(xy 105.828872 -228.233804) (xy 105.841051 -228.18439) (xy 105.860999 -228.13757) (xy 105.8882 -228.094556)
			(xy 105.921948 -228.056462) (xy 105.96137 -228.024275) (xy 106.005444 -227.998829) (xy 106.05303 -227.980782)
			(xy 106.102894 -227.970602) (xy 106.153746 -227.968553) (xy 106.204267 -227.974687) (xy 106.253151 -227.988847)
			(xy 106.29913 -228.010664) (xy 106.341014 -228.039574) (xy 106.377718 -228.074829) (xy 106.408291 -228.115515)
			(xy 106.431942 -228.160578) (xy 106.448058 -228.208852) (xy 106.456222 -228.259086) (xy 106.456734 -228.284532)
			(xy 106.764831 -228.284532) (xy 106.768926 -228.233804) (xy 106.781105 -228.18439) (xy 106.801053 -228.13757)
			(xy 106.828254 -228.094556) (xy 106.862002 -228.056462) (xy 106.901424 -228.024275) (xy 106.945498 -227.998829)
			(xy 106.993084 -227.980782) (xy 107.042948 -227.970602) (xy 107.0938 -227.968553) (xy 107.144321 -227.974687)
			(xy 107.193205 -227.988847) (xy 107.239184 -228.010664) (xy 107.281068 -228.039574) (xy 107.317772 -228.074829)
			(xy 107.348345 -228.115515) (xy 107.371996 -228.160578) (xy 107.388112 -228.208852) (xy 107.396276 -228.259086)
			(xy 107.396788 -228.284532) (xy 107.715316 -228.284532) (xy 107.719276 -228.235478) (xy 107.731053 -228.187694)
			(xy 107.750344 -228.142418) (xy 107.776647 -228.100822) (xy 107.809282 -228.063985) (xy 107.847403 -228.03286)
			(xy 107.890024 -228.008253) (xy 107.93604 -227.990801) (xy 107.984259 -227.980957) (xy 108.033434 -227.978976)
			(xy 108.082289 -227.984908) (xy 108.12956 -227.9986) (xy 108.174022 -228.019698) (xy 108.214525 -228.047654)
			(xy 108.250018 -228.081746) (xy 108.279583 -228.12109) (xy 108.302454 -228.164667) (xy 108.318038 -228.211348)
			(xy 108.325933 -228.259925) (xy 108.326428 -228.284532) (xy 108.325933 -228.309139) (xy 108.318038 -228.357716)
			(xy 108.302454 -228.404397) (xy 108.279583 -228.447974) (xy 108.250018 -228.487318) (xy 108.214525 -228.52141)
			(xy 108.174022 -228.549366) (xy 108.12956 -228.570464) (xy 108.082289 -228.584156) (xy 108.033434 -228.590088)
			(xy 107.984259 -228.588107) (xy 107.93604 -228.578263) (xy 107.890024 -228.560811) (xy 107.847403 -228.536204)
			(xy 107.809282 -228.505079) (xy 107.776647 -228.468242) (xy 107.750344 -228.426646) (xy 107.731053 -228.38137)
			(xy 107.719276 -228.333586) (xy 107.715316 -228.284532) (xy 107.396788 -228.284532) (xy 107.396276 -228.309978)
			(xy 107.388112 -228.360212) (xy 107.371996 -228.408486) (xy 107.348345 -228.453549) (xy 107.317772 -228.494235)
			(xy 107.281068 -228.52949) (xy 107.239184 -228.5584) (xy 107.193205 -228.580217) (xy 107.144321 -228.594377)
			(xy 107.0938 -228.600511) (xy 107.042948 -228.598462) (xy 106.993084 -228.588282) (xy 106.945498 -228.570235)
			(xy 106.901424 -228.544789) (xy 106.862002 -228.512602) (xy 106.828254 -228.474508) (xy 106.801053 -228.431494)
			(xy 106.781105 -228.384674) (xy 106.768926 -228.33526) (xy 106.764831 -228.284532) (xy 106.456734 -228.284532)
			(xy 106.456222 -228.309978) (xy 106.448058 -228.360212) (xy 106.431942 -228.408486) (xy 106.408291 -228.453549)
			(xy 106.377718 -228.494235) (xy 106.341014 -228.52949) (xy 106.29913 -228.5584) (xy 106.253151 -228.580217)
			(xy 106.204267 -228.594377) (xy 106.153746 -228.600511) (xy 106.102894 -228.598462) (xy 106.05303 -228.588282)
			(xy 106.005444 -228.570235) (xy 105.96137 -228.544789) (xy 105.921948 -228.512602) (xy 105.8882 -228.474508)
			(xy 105.860999 -228.431494) (xy 105.841051 -228.384674) (xy 105.828872 -228.33526) (xy 105.824777 -228.284532)
			(xy 105.506266 -228.284532) (xy 105.505771 -228.309139) (xy 105.497876 -228.357716) (xy 105.482292 -228.404397)
			(xy 105.459421 -228.447974) (xy 105.429856 -228.487318) (xy 105.394363 -228.52141) (xy 105.35386 -228.549366)
			(xy 105.309398 -228.570464) (xy 105.262127 -228.584156) (xy 105.213272 -228.590088) (xy 105.164097 -228.588107)
			(xy 105.115878 -228.578263) (xy 105.069862 -228.560811) (xy 105.027241 -228.536204) (xy 104.98912 -228.505079)
			(xy 104.956485 -228.468242) (xy 104.930182 -228.426646) (xy 104.910891 -228.38137) (xy 104.899114 -228.333586)
			(xy 104.895154 -228.284532) (xy 104.57688 -228.284532) (xy 104.576368 -228.309978) (xy 104.568204 -228.360212)
			(xy 104.552088 -228.408486) (xy 104.528437 -228.453549) (xy 104.497864 -228.494235) (xy 104.46116 -228.52949)
			(xy 104.419276 -228.5584) (xy 104.373297 -228.580217) (xy 104.324413 -228.594377) (xy 104.273892 -228.600511)
			(xy 104.22304 -228.598462) (xy 104.173176 -228.588282) (xy 104.12559 -228.570235) (xy 104.081516 -228.544789)
			(xy 104.042094 -228.512602) (xy 104.008346 -228.474508) (xy 103.981145 -228.431494) (xy 103.961197 -228.384674)
			(xy 103.949018 -228.33526) (xy 103.944923 -228.284532) (xy 103.636826 -228.284532) (xy 103.636314 -228.309978)
			(xy 103.62815 -228.360212) (xy 103.612034 -228.408486) (xy 103.588383 -228.453549) (xy 103.55781 -228.494235)
			(xy 103.521106 -228.52949) (xy 103.479222 -228.5584) (xy 103.433243 -228.580217) (xy 103.384359 -228.594377)
			(xy 103.333838 -228.600511) (xy 103.282986 -228.598462) (xy 103.233122 -228.588282) (xy 103.185536 -228.570235)
			(xy 103.141462 -228.544789) (xy 103.10204 -228.512602) (xy 103.068292 -228.474508) (xy 103.041091 -228.431494)
			(xy 103.021143 -228.384674) (xy 103.008964 -228.33526) (xy 103.004869 -228.284532) (xy 102.686358 -228.284532)
			(xy 102.685863 -228.309139) (xy 102.677968 -228.357716) (xy 102.662384 -228.404397) (xy 102.639513 -228.447974)
			(xy 102.609948 -228.487318) (xy 102.574455 -228.52141) (xy 102.533952 -228.549366) (xy 102.48949 -228.570464)
			(xy 102.442219 -228.584156) (xy 102.393364 -228.590088) (xy 102.344189 -228.588107) (xy 102.29597 -228.578263)
			(xy 102.249954 -228.560811) (xy 102.207333 -228.536204) (xy 102.169212 -228.505079) (xy 102.136577 -228.468242)
			(xy 102.110274 -228.426646) (xy 102.090983 -228.38137) (xy 102.079206 -228.333586) (xy 102.075246 -228.284532)
			(xy 101.756718 -228.284532) (xy 101.756206 -228.309978) (xy 101.748042 -228.360212) (xy 101.731926 -228.408486)
			(xy 101.708275 -228.453549) (xy 101.677702 -228.494235) (xy 101.640998 -228.52949) (xy 101.599114 -228.5584)
			(xy 101.553135 -228.580217) (xy 101.504251 -228.594377) (xy 101.45373 -228.600511) (xy 101.402878 -228.598462)
			(xy 101.353014 -228.588282) (xy 101.305428 -228.570235) (xy 101.261354 -228.544789) (xy 101.221932 -228.512602)
			(xy 101.188184 -228.474508) (xy 101.160983 -228.431494) (xy 101.141035 -228.384674) (xy 101.128856 -228.33526)
			(xy 101.124761 -228.284532) (xy 100.816664 -228.284532) (xy 100.816152 -228.309978) (xy 100.807988 -228.360212)
			(xy 100.791872 -228.408486) (xy 100.768221 -228.453549) (xy 100.737648 -228.494235) (xy 100.700944 -228.52949)
			(xy 100.65906 -228.5584) (xy 100.613081 -228.580217) (xy 100.564197 -228.594377) (xy 100.513676 -228.600511)
			(xy 100.462824 -228.598462) (xy 100.41296 -228.588282) (xy 100.365374 -228.570235) (xy 100.3213 -228.544789)
			(xy 100.281878 -228.512602) (xy 100.24813 -228.474508) (xy 100.220929 -228.431494) (xy 100.200981 -228.384674)
			(xy 100.188802 -228.33526) (xy 100.184707 -228.284532) (xy 99.86645 -228.284532) (xy 99.865955 -228.309139)
			(xy 99.85806 -228.357716) (xy 99.842476 -228.404397) (xy 99.819605 -228.447974) (xy 99.79004 -228.487318)
			(xy 99.754547 -228.52141) (xy 99.714044 -228.549366) (xy 99.669582 -228.570464) (xy 99.622311 -228.584156)
			(xy 99.573456 -228.590088) (xy 99.524281 -228.588107) (xy 99.476062 -228.578263) (xy 99.430046 -228.560811)
			(xy 99.387425 -228.536204) (xy 99.349304 -228.505079) (xy 99.316669 -228.468242) (xy 99.290366 -228.426646)
			(xy 99.271075 -228.38137) (xy 99.259298 -228.333586) (xy 99.255338 -228.284532) (xy 98.93681 -228.284532)
			(xy 98.936298 -228.309978) (xy 98.928134 -228.360212) (xy 98.912018 -228.408486) (xy 98.888367 -228.453549)
			(xy 98.857794 -228.494235) (xy 98.82109 -228.52949) (xy 98.779206 -228.5584) (xy 98.733227 -228.580217)
			(xy 98.684343 -228.594377) (xy 98.633822 -228.600511) (xy 98.58297 -228.598462) (xy 98.533106 -228.588282)
			(xy 98.48552 -228.570235) (xy 98.441446 -228.544789) (xy 98.402024 -228.512602) (xy 98.368276 -228.474508)
			(xy 98.341075 -228.431494) (xy 98.321127 -228.384674) (xy 98.308948 -228.33526) (xy 98.304853 -228.284532)
			(xy 97.996756 -228.284532) (xy 97.996244 -228.309978) (xy 97.98808 -228.360212) (xy 97.971964 -228.408486)
			(xy 97.948313 -228.453549) (xy 97.91774 -228.494235) (xy 97.881036 -228.52949) (xy 97.839152 -228.5584)
			(xy 97.793173 -228.580217) (xy 97.744289 -228.594377) (xy 97.693768 -228.600511) (xy 97.642916 -228.598462)
			(xy 97.593052 -228.588282) (xy 97.545466 -228.570235) (xy 97.501392 -228.544789) (xy 97.46197 -228.512602)
			(xy 97.428222 -228.474508) (xy 97.401021 -228.431494) (xy 97.381073 -228.384674) (xy 97.368894 -228.33526)
			(xy 97.364799 -228.284532) (xy 97.046288 -228.284532) (xy 97.045793 -228.309139) (xy 97.037898 -228.357716)
			(xy 97.022314 -228.404397) (xy 96.999443 -228.447974) (xy 96.969878 -228.487318) (xy 96.934385 -228.52141)
			(xy 96.893882 -228.549366) (xy 96.84942 -228.570464) (xy 96.802149 -228.584156) (xy 96.753294 -228.590088)
			(xy 96.704119 -228.588107) (xy 96.6559 -228.578263) (xy 96.609884 -228.560811) (xy 96.567263 -228.536204)
			(xy 96.529142 -228.505079) (xy 96.496507 -228.468242) (xy 96.470204 -228.426646) (xy 96.450913 -228.38137)
			(xy 96.439136 -228.333586) (xy 96.435176 -228.284532) (xy 96.116648 -228.284532) (xy 96.116136 -228.309978)
			(xy 96.107972 -228.360212) (xy 96.091856 -228.408486) (xy 96.068205 -228.453549) (xy 96.037632 -228.494235)
			(xy 96.000928 -228.52949) (xy 95.959044 -228.5584) (xy 95.913065 -228.580217) (xy 95.864181 -228.594377)
			(xy 95.81366 -228.600511) (xy 95.762808 -228.598462) (xy 95.712944 -228.588282) (xy 95.665358 -228.570235)
			(xy 95.621284 -228.544789) (xy 95.581862 -228.512602) (xy 95.548114 -228.474508) (xy 95.520913 -228.431494)
			(xy 95.500965 -228.384674) (xy 95.488786 -228.33526) (xy 95.484691 -228.284532) (xy 95.166434 -228.284532)
			(xy 95.165939 -228.309139) (xy 95.158044 -228.357716) (xy 95.14246 -228.404397) (xy 95.119589 -228.447974)
			(xy 95.090024 -228.487318) (xy 95.054531 -228.52141) (xy 95.014028 -228.549366) (xy 94.969566 -228.570464)
			(xy 94.922295 -228.584156) (xy 94.87344 -228.590088) (xy 94.824265 -228.588107) (xy 94.776046 -228.578263)
			(xy 94.73003 -228.560811) (xy 94.687409 -228.536204) (xy 94.649288 -228.505079) (xy 94.616653 -228.468242)
			(xy 94.59035 -228.426646) (xy 94.571059 -228.38137) (xy 94.559282 -228.333586) (xy 94.555322 -228.284532)
			(xy 94.236794 -228.284532) (xy 94.236282 -228.309978) (xy 94.228118 -228.360212) (xy 94.212002 -228.408486)
			(xy 94.188351 -228.453549) (xy 94.157778 -228.494235) (xy 94.121074 -228.52949) (xy 94.07919 -228.5584)
			(xy 94.033211 -228.580217) (xy 93.984327 -228.594377) (xy 93.933806 -228.600511) (xy 93.882954 -228.598462)
			(xy 93.83309 -228.588282) (xy 93.785504 -228.570235) (xy 93.74143 -228.544789) (xy 93.702008 -228.512602)
			(xy 93.66826 -228.474508) (xy 93.641059 -228.431494) (xy 93.621111 -228.384674) (xy 93.608932 -228.33526)
			(xy 93.604837 -228.284532) (xy 93.286326 -228.284532) (xy 93.285831 -228.309139) (xy 93.277936 -228.357716)
			(xy 93.262352 -228.404397) (xy 93.239481 -228.447974) (xy 93.209916 -228.487318) (xy 93.174423 -228.52141)
			(xy 93.13392 -228.549366) (xy 93.089458 -228.570464) (xy 93.042187 -228.584156) (xy 92.993332 -228.590088)
			(xy 92.944157 -228.588107) (xy 92.895938 -228.578263) (xy 92.849922 -228.560811) (xy 92.807301 -228.536204)
			(xy 92.76918 -228.505079) (xy 92.736545 -228.468242) (xy 92.710242 -228.426646) (xy 92.690951 -228.38137)
			(xy 92.679174 -228.333586) (xy 92.675214 -228.284532) (xy 92.356686 -228.284532) (xy 92.356174 -228.309978)
			(xy 92.34801 -228.360212) (xy 92.331894 -228.408486) (xy 92.308243 -228.453549) (xy 92.27767 -228.494235)
			(xy 92.240966 -228.52949) (xy 92.199082 -228.5584) (xy 92.153103 -228.580217) (xy 92.104219 -228.594377)
			(xy 92.053698 -228.600511) (xy 92.002846 -228.598462) (xy 91.952982 -228.588282) (xy 91.905396 -228.570235)
			(xy 91.861322 -228.544789) (xy 91.8219 -228.512602) (xy 91.788152 -228.474508) (xy 91.760951 -228.431494)
			(xy 91.741003 -228.384674) (xy 91.728824 -228.33526) (xy 91.724729 -228.284532) (xy 91.416632 -228.284532)
			(xy 91.41612 -228.309978) (xy 91.407956 -228.360212) (xy 91.39184 -228.408486) (xy 91.368189 -228.453549)
			(xy 91.337616 -228.494235) (xy 91.300912 -228.52949) (xy 91.259028 -228.5584) (xy 91.213049 -228.580217)
			(xy 91.164165 -228.594377) (xy 91.113644 -228.600511) (xy 91.062792 -228.598462) (xy 91.012928 -228.588282)
			(xy 90.965342 -228.570235) (xy 90.921268 -228.544789) (xy 90.881846 -228.512602) (xy 90.848098 -228.474508)
			(xy 90.820897 -228.431494) (xy 90.800949 -228.384674) (xy 90.78877 -228.33526) (xy 90.784675 -228.284532)
			(xy 90.466418 -228.284532) (xy 90.465923 -228.309139) (xy 90.458028 -228.357716) (xy 90.442444 -228.404397)
			(xy 90.419573 -228.447974) (xy 90.390008 -228.487318) (xy 90.354515 -228.52141) (xy 90.314012 -228.549366)
			(xy 90.26955 -228.570464) (xy 90.222279 -228.584156) (xy 90.173424 -228.590088) (xy 90.124249 -228.588107)
			(xy 90.07603 -228.578263) (xy 90.030014 -228.560811) (xy 89.987393 -228.536204) (xy 89.949272 -228.505079)
			(xy 89.916637 -228.468242) (xy 89.890334 -228.426646) (xy 89.871043 -228.38137) (xy 89.859266 -228.333586)
			(xy 89.855306 -228.284532) (xy 89.536778 -228.284532) (xy 89.536266 -228.309978) (xy 89.528102 -228.360212)
			(xy 89.511986 -228.408486) (xy 89.488335 -228.453549) (xy 89.457762 -228.494235) (xy 89.421058 -228.52949)
			(xy 89.379174 -228.5584) (xy 89.333195 -228.580217) (xy 89.284311 -228.594377) (xy 89.23379 -228.600511)
			(xy 89.182938 -228.598462) (xy 89.133074 -228.588282) (xy 89.085488 -228.570235) (xy 89.041414 -228.544789)
			(xy 89.001992 -228.512602) (xy 88.968244 -228.474508) (xy 88.941043 -228.431494) (xy 88.921095 -228.384674)
			(xy 88.908916 -228.33526) (xy 88.904821 -228.284532) (xy 88.58631 -228.284532) (xy 88.585815 -228.309139)
			(xy 88.57792 -228.357716) (xy 88.562336 -228.404397) (xy 88.539465 -228.447974) (xy 88.5099 -228.487318)
			(xy 88.474407 -228.52141) (xy 88.433904 -228.549366) (xy 88.389442 -228.570464) (xy 88.342171 -228.584156)
			(xy 88.293316 -228.590088) (xy 88.244141 -228.588107) (xy 88.195922 -228.578263) (xy 88.149906 -228.560811)
			(xy 88.107285 -228.536204) (xy 88.069164 -228.505079) (xy 88.036529 -228.468242) (xy 88.010226 -228.426646)
			(xy 87.990935 -228.38137) (xy 87.979158 -228.333586) (xy 87.975198 -228.284532) (xy 87.65667 -228.284532)
			(xy 87.656158 -228.309978) (xy 87.647994 -228.360212) (xy 87.631878 -228.408486) (xy 87.608227 -228.453549)
			(xy 87.577654 -228.494235) (xy 87.54095 -228.52949) (xy 87.499066 -228.5584) (xy 87.453087 -228.580217)
			(xy 87.404203 -228.594377) (xy 87.353682 -228.600511) (xy 87.30283 -228.598462) (xy 87.252966 -228.588282)
			(xy 87.20538 -228.570235) (xy 87.161306 -228.544789) (xy 87.121884 -228.512602) (xy 87.088136 -228.474508)
			(xy 87.060935 -228.431494) (xy 87.040987 -228.384674) (xy 87.028808 -228.33526) (xy 87.024713 -228.284532)
			(xy 86.706456 -228.284532) (xy 86.705961 -228.309139) (xy 86.698066 -228.357716) (xy 86.682482 -228.404397)
			(xy 86.659611 -228.447974) (xy 86.630046 -228.487318) (xy 86.594553 -228.52141) (xy 86.55405 -228.549366)
			(xy 86.509588 -228.570464) (xy 86.462317 -228.584156) (xy 86.413462 -228.590088) (xy 86.364287 -228.588107)
			(xy 86.316068 -228.578263) (xy 86.270052 -228.560811) (xy 86.227431 -228.536204) (xy 86.18931 -228.505079)
			(xy 86.156675 -228.468242) (xy 86.130372 -228.426646) (xy 86.111081 -228.38137) (xy 86.099304 -228.333586)
			(xy 86.095344 -228.284532) (xy 85.776816 -228.284532) (xy 85.776304 -228.309978) (xy 85.76814 -228.360212)
			(xy 85.752024 -228.408486) (xy 85.728373 -228.453549) (xy 85.6978 -228.494235) (xy 85.661096 -228.52949)
			(xy 85.619212 -228.5584) (xy 85.573233 -228.580217) (xy 85.524349 -228.594377) (xy 85.473828 -228.600511)
			(xy 85.422976 -228.598462) (xy 85.373112 -228.588282) (xy 85.325526 -228.570235) (xy 85.281452 -228.544789)
			(xy 85.24203 -228.512602) (xy 85.208282 -228.474508) (xy 85.181081 -228.431494) (xy 85.161133 -228.384674)
			(xy 85.148954 -228.33526) (xy 85.144859 -228.284532) (xy 84.836762 -228.284532) (xy 84.83625 -228.309978)
			(xy 84.828086 -228.360212) (xy 84.81197 -228.408486) (xy 84.788319 -228.453549) (xy 84.757746 -228.494235)
			(xy 84.721042 -228.52949) (xy 84.679158 -228.5584) (xy 84.633179 -228.580217) (xy 84.584295 -228.594377)
			(xy 84.533774 -228.600511) (xy 84.482922 -228.598462) (xy 84.433058 -228.588282) (xy 84.385472 -228.570235)
			(xy 84.341398 -228.544789) (xy 84.301976 -228.512602) (xy 84.268228 -228.474508) (xy 84.241027 -228.431494)
			(xy 84.221079 -228.384674) (xy 84.2089 -228.33526) (xy 84.204805 -228.284532) (xy 83.886294 -228.284532)
			(xy 83.885799 -228.309139) (xy 83.877904 -228.357716) (xy 83.86232 -228.404397) (xy 83.839449 -228.447974)
			(xy 83.809884 -228.487318) (xy 83.774391 -228.52141) (xy 83.733888 -228.549366) (xy 83.689426 -228.570464)
			(xy 83.642155 -228.584156) (xy 83.5933 -228.590088) (xy 83.544125 -228.588107) (xy 83.495906 -228.578263)
			(xy 83.44989 -228.560811) (xy 83.407269 -228.536204) (xy 83.369148 -228.505079) (xy 83.336513 -228.468242)
			(xy 83.31021 -228.426646) (xy 83.290919 -228.38137) (xy 83.279142 -228.333586) (xy 83.275182 -228.284532)
			(xy 82.956654 -228.284532) (xy 82.956142 -228.309978) (xy 82.947978 -228.360212) (xy 82.931862 -228.408486)
			(xy 82.908211 -228.453549) (xy 82.877638 -228.494235) (xy 82.840934 -228.52949) (xy 82.79905 -228.5584)
			(xy 82.753071 -228.580217) (xy 82.704187 -228.594377) (xy 82.653666 -228.600511) (xy 82.602814 -228.598462)
			(xy 82.55295 -228.588282) (xy 82.505364 -228.570235) (xy 82.46129 -228.544789) (xy 82.421868 -228.512602)
			(xy 82.38812 -228.474508) (xy 82.360919 -228.431494) (xy 82.340971 -228.384674) (xy 82.328792 -228.33526)
			(xy 82.324697 -228.284532) (xy 82.00644 -228.284532) (xy 82.005945 -228.309139) (xy 81.99805 -228.357716)
			(xy 81.982466 -228.404397) (xy 81.959595 -228.447974) (xy 81.93003 -228.487318) (xy 81.894537 -228.52141)
			(xy 81.854034 -228.549366) (xy 81.809572 -228.570464) (xy 81.762301 -228.584156) (xy 81.713446 -228.590088)
			(xy 81.664271 -228.588107) (xy 81.616052 -228.578263) (xy 81.570036 -228.560811) (xy 81.527415 -228.536204)
			(xy 81.489294 -228.505079) (xy 81.456659 -228.468242) (xy 81.430356 -228.426646) (xy 81.411065 -228.38137)
			(xy 81.399288 -228.333586) (xy 81.395328 -228.284532) (xy 81.0768 -228.284532) (xy 81.076288 -228.309978)
			(xy 81.068124 -228.360212) (xy 81.052008 -228.408486) (xy 81.028357 -228.453549) (xy 80.997784 -228.494235)
			(xy 80.96108 -228.52949) (xy 80.919196 -228.5584) (xy 80.873217 -228.580217) (xy 80.824333 -228.594377)
			(xy 80.773812 -228.600511) (xy 80.72296 -228.598462) (xy 80.673096 -228.588282) (xy 80.62551 -228.570235)
			(xy 80.581436 -228.544789) (xy 80.542014 -228.512602) (xy 80.508266 -228.474508) (xy 80.481065 -228.431494)
			(xy 80.461117 -228.384674) (xy 80.448938 -228.33526) (xy 80.444843 -228.284532) (xy 80.126332 -228.284532)
			(xy 80.125837 -228.309139) (xy 80.117942 -228.357716) (xy 80.102358 -228.404397) (xy 80.079487 -228.447974)
			(xy 80.049922 -228.487318) (xy 80.014429 -228.52141) (xy 79.973926 -228.549366) (xy 79.929464 -228.570464)
			(xy 79.882193 -228.584156) (xy 79.833338 -228.590088) (xy 79.784163 -228.588107) (xy 79.735944 -228.578263)
			(xy 79.689928 -228.560811) (xy 79.647307 -228.536204) (xy 79.609186 -228.505079) (xy 79.576551 -228.468242)
			(xy 79.550248 -228.426646) (xy 79.530957 -228.38137) (xy 79.51918 -228.333586) (xy 79.51522 -228.284532)
			(xy 77.306424 -228.284532) (xy 77.305929 -228.309139) (xy 77.298034 -228.357716) (xy 77.28245 -228.404397)
			(xy 77.259579 -228.447974) (xy 77.230014 -228.487318) (xy 77.194521 -228.52141) (xy 77.154018 -228.549366)
			(xy 77.109556 -228.570464) (xy 77.062285 -228.584156) (xy 77.01343 -228.590088) (xy 76.964255 -228.588107)
			(xy 76.916036 -228.578263) (xy 76.87002 -228.560811) (xy 76.827399 -228.536204) (xy 76.789278 -228.505079)
			(xy 76.756643 -228.468242) (xy 76.73034 -228.426646) (xy 76.711049 -228.38137) (xy 76.699272 -228.333586)
			(xy 76.695312 -228.284532) (xy 62.37732 -228.284532) (xy 62.37732 -229.094538) (xy 78.105266 -229.094538)
			(xy 78.109226 -229.045484) (xy 78.121003 -228.9977) (xy 78.140294 -228.952424) (xy 78.166597 -228.910828)
			(xy 78.199232 -228.873991) (xy 78.237353 -228.842866) (xy 78.279974 -228.818259) (xy 78.32599 -228.800807)
			(xy 78.374209 -228.790963) (xy 78.423384 -228.788982) (xy 78.472239 -228.794914) (xy 78.51951 -228.808606)
			(xy 78.563972 -228.829704) (xy 78.604475 -228.85766) (xy 78.639968 -228.891752) (xy 78.669533 -228.931096)
			(xy 78.692404 -228.974673) (xy 78.707988 -229.021354) (xy 78.715883 -229.069931) (xy 78.716378 -229.094538)
			(xy 79.985374 -229.094538) (xy 79.989334 -229.045484) (xy 80.001111 -228.9977) (xy 80.020402 -228.952424)
			(xy 80.046705 -228.910828) (xy 80.07934 -228.873991) (xy 80.117461 -228.842866) (xy 80.160082 -228.818259)
			(xy 80.206098 -228.800807) (xy 80.254317 -228.790963) (xy 80.303492 -228.788982) (xy 80.352347 -228.794914)
			(xy 80.399618 -228.808606) (xy 80.44408 -228.829704) (xy 80.484583 -228.85766) (xy 80.520076 -228.891752)
			(xy 80.549641 -228.931096) (xy 80.572512 -228.974673) (xy 80.588096 -229.021354) (xy 80.595991 -229.069931)
			(xy 80.596486 -229.094538) (xy 80.914743 -229.094538) (xy 80.918838 -229.04381) (xy 80.931017 -228.994396)
			(xy 80.950965 -228.947576) (xy 80.978166 -228.904562) (xy 81.011914 -228.866468) (xy 81.051336 -228.834281)
			(xy 81.09541 -228.808835) (xy 81.142996 -228.790788) (xy 81.19286 -228.780608) (xy 81.243712 -228.778559)
			(xy 81.294233 -228.784693) (xy 81.343117 -228.798853) (xy 81.389096 -228.82067) (xy 81.43098 -228.84958)
			(xy 81.467684 -228.884835) (xy 81.498257 -228.925521) (xy 81.521908 -228.970584) (xy 81.538024 -229.018858)
			(xy 81.546188 -229.069092) (xy 81.5467 -229.094538) (xy 81.854797 -229.094538) (xy 81.858892 -229.04381)
			(xy 81.871071 -228.994396) (xy 81.891019 -228.947576) (xy 81.91822 -228.904562) (xy 81.951968 -228.866468)
			(xy 81.99139 -228.834281) (xy 82.035464 -228.808835) (xy 82.08305 -228.790788) (xy 82.132914 -228.780608)
			(xy 82.183766 -228.778559) (xy 82.234287 -228.784693) (xy 82.283171 -228.798853) (xy 82.32915 -228.82067)
			(xy 82.371034 -228.84958) (xy 82.407738 -228.884835) (xy 82.438311 -228.925521) (xy 82.461962 -228.970584)
			(xy 82.478078 -229.018858) (xy 82.486242 -229.069092) (xy 82.486754 -229.094538) (xy 82.805282 -229.094538)
			(xy 82.809242 -229.045484) (xy 82.821019 -228.9977) (xy 82.84031 -228.952424) (xy 82.866613 -228.910828)
			(xy 82.899248 -228.873991) (xy 82.937369 -228.842866) (xy 82.97999 -228.818259) (xy 83.026006 -228.800807)
			(xy 83.074225 -228.790963) (xy 83.1234 -228.788982) (xy 83.172255 -228.794914) (xy 83.219526 -228.808606)
			(xy 83.263988 -228.829704) (xy 83.304491 -228.85766) (xy 83.339984 -228.891752) (xy 83.369549 -228.931096)
			(xy 83.39242 -228.974673) (xy 83.408004 -229.021354) (xy 83.415899 -229.069931) (xy 83.416394 -229.094538)
			(xy 83.734905 -229.094538) (xy 83.739 -229.04381) (xy 83.751179 -228.994396) (xy 83.771127 -228.947576)
			(xy 83.798328 -228.904562) (xy 83.832076 -228.866468) (xy 83.871498 -228.834281) (xy 83.915572 -228.808835)
			(xy 83.963158 -228.790788) (xy 84.013022 -228.780608) (xy 84.063874 -228.778559) (xy 84.114395 -228.784693)
			(xy 84.163279 -228.798853) (xy 84.209258 -228.82067) (xy 84.251142 -228.84958) (xy 84.287846 -228.884835)
			(xy 84.318419 -228.925521) (xy 84.34207 -228.970584) (xy 84.358186 -229.018858) (xy 84.36635 -229.069092)
			(xy 84.366862 -229.094538) (xy 84.685136 -229.094538) (xy 84.689096 -229.045484) (xy 84.700873 -228.9977)
			(xy 84.720164 -228.952424) (xy 84.746467 -228.910828) (xy 84.779102 -228.873991) (xy 84.817223 -228.842866)
			(xy 84.859844 -228.818259) (xy 84.90586 -228.800807) (xy 84.954079 -228.790963) (xy 85.003254 -228.788982)
			(xy 85.052109 -228.794914) (xy 85.09938 -228.808606) (xy 85.143842 -228.829704) (xy 85.184345 -228.85766)
			(xy 85.219838 -228.891752) (xy 85.249403 -228.931096) (xy 85.272274 -228.974673) (xy 85.287858 -229.021354)
			(xy 85.295753 -229.069931) (xy 85.296248 -229.094538) (xy 85.614759 -229.094538) (xy 85.618854 -229.04381)
			(xy 85.631033 -228.994396) (xy 85.650981 -228.947576) (xy 85.678182 -228.904562) (xy 85.71193 -228.866468)
			(xy 85.751352 -228.834281) (xy 85.795426 -228.808835) (xy 85.843012 -228.790788) (xy 85.892876 -228.780608)
			(xy 85.943728 -228.778559) (xy 85.994249 -228.784693) (xy 86.043133 -228.798853) (xy 86.089112 -228.82067)
			(xy 86.130996 -228.84958) (xy 86.1677 -228.884835) (xy 86.198273 -228.925521) (xy 86.221924 -228.970584)
			(xy 86.23804 -229.018858) (xy 86.246204 -229.069092) (xy 86.246716 -229.094538) (xy 86.565244 -229.094538)
			(xy 86.569204 -229.045484) (xy 86.580981 -228.9977) (xy 86.600272 -228.952424) (xy 86.626575 -228.910828)
			(xy 86.65921 -228.873991) (xy 86.697331 -228.842866) (xy 86.739952 -228.818259) (xy 86.785968 -228.800807)
			(xy 86.834187 -228.790963) (xy 86.883362 -228.788982) (xy 86.932217 -228.794914) (xy 86.979488 -228.808606)
			(xy 87.02395 -228.829704) (xy 87.064453 -228.85766) (xy 87.099946 -228.891752) (xy 87.129511 -228.931096)
			(xy 87.152382 -228.974673) (xy 87.167966 -229.021354) (xy 87.175861 -229.069931) (xy 87.176356 -229.094538)
			(xy 87.494867 -229.094538) (xy 87.498962 -229.04381) (xy 87.511141 -228.994396) (xy 87.531089 -228.947576)
			(xy 87.55829 -228.904562) (xy 87.592038 -228.866468) (xy 87.63146 -228.834281) (xy 87.675534 -228.808835)
			(xy 87.72312 -228.790788) (xy 87.772984 -228.780608) (xy 87.823836 -228.778559) (xy 87.874357 -228.784693)
			(xy 87.923241 -228.798853) (xy 87.96922 -228.82067) (xy 88.011104 -228.84958) (xy 88.047808 -228.884835)
			(xy 88.078381 -228.925521) (xy 88.102032 -228.970584) (xy 88.118148 -229.018858) (xy 88.126312 -229.069092)
			(xy 88.126824 -229.094538) (xy 88.434921 -229.094538) (xy 88.439016 -229.04381) (xy 88.451195 -228.994396)
			(xy 88.471143 -228.947576) (xy 88.498344 -228.904562) (xy 88.532092 -228.866468) (xy 88.571514 -228.834281)
			(xy 88.615588 -228.808835) (xy 88.663174 -228.790788) (xy 88.713038 -228.780608) (xy 88.76389 -228.778559)
			(xy 88.814411 -228.784693) (xy 88.863295 -228.798853) (xy 88.909274 -228.82067) (xy 88.951158 -228.84958)
			(xy 88.987862 -228.884835) (xy 89.018435 -228.925521) (xy 89.042086 -228.970584) (xy 89.058202 -229.018858)
			(xy 89.066366 -229.069092) (xy 89.066878 -229.094538) (xy 89.385152 -229.094538) (xy 89.389112 -229.045484)
			(xy 89.400889 -228.9977) (xy 89.42018 -228.952424) (xy 89.446483 -228.910828) (xy 89.479118 -228.873991)
			(xy 89.517239 -228.842866) (xy 89.55986 -228.818259) (xy 89.605876 -228.800807) (xy 89.654095 -228.790963)
			(xy 89.70327 -228.788982) (xy 89.752125 -228.794914) (xy 89.799396 -228.808606) (xy 89.843858 -228.829704)
			(xy 89.884361 -228.85766) (xy 89.919854 -228.891752) (xy 89.949419 -228.931096) (xy 89.97229 -228.974673)
			(xy 89.987874 -229.021354) (xy 89.995769 -229.069931) (xy 89.996264 -229.094538) (xy 90.314775 -229.094538)
			(xy 90.31887 -229.04381) (xy 90.331049 -228.994396) (xy 90.350997 -228.947576) (xy 90.378198 -228.904562)
			(xy 90.411946 -228.866468) (xy 90.451368 -228.834281) (xy 90.495442 -228.808835) (xy 90.543028 -228.790788)
			(xy 90.592892 -228.780608) (xy 90.643744 -228.778559) (xy 90.694265 -228.784693) (xy 90.743149 -228.798853)
			(xy 90.789128 -228.82067) (xy 90.831012 -228.84958) (xy 90.867716 -228.884835) (xy 90.898289 -228.925521)
			(xy 90.92194 -228.970584) (xy 90.938056 -229.018858) (xy 90.94622 -229.069092) (xy 90.946732 -229.094538)
			(xy 91.26526 -229.094538) (xy 91.26922 -229.045484) (xy 91.280997 -228.9977) (xy 91.300288 -228.952424)
			(xy 91.326591 -228.910828) (xy 91.359226 -228.873991) (xy 91.397347 -228.842866) (xy 91.439968 -228.818259)
			(xy 91.485984 -228.800807) (xy 91.534203 -228.790963) (xy 91.583378 -228.788982) (xy 91.632233 -228.794914)
			(xy 91.679504 -228.808606) (xy 91.723966 -228.829704) (xy 91.764469 -228.85766) (xy 91.799962 -228.891752)
			(xy 91.829527 -228.931096) (xy 91.852398 -228.974673) (xy 91.867982 -229.021354) (xy 91.875877 -229.069931)
			(xy 91.876372 -229.094538) (xy 92.194883 -229.094538) (xy 92.198978 -229.04381) (xy 92.211157 -228.994396)
			(xy 92.231105 -228.947576) (xy 92.258306 -228.904562) (xy 92.292054 -228.866468) (xy 92.331476 -228.834281)
			(xy 92.37555 -228.808835) (xy 92.423136 -228.790788) (xy 92.473 -228.780608) (xy 92.523852 -228.778559)
			(xy 92.574373 -228.784693) (xy 92.623257 -228.798853) (xy 92.669236 -228.82067) (xy 92.71112 -228.84958)
			(xy 92.747824 -228.884835) (xy 92.778397 -228.925521) (xy 92.802048 -228.970584) (xy 92.818164 -229.018858)
			(xy 92.826328 -229.069092) (xy 92.82684 -229.094538) (xy 93.145114 -229.094538) (xy 93.149074 -229.045484)
			(xy 93.160851 -228.9977) (xy 93.180142 -228.952424) (xy 93.206445 -228.910828) (xy 93.23908 -228.873991)
			(xy 93.277201 -228.842866) (xy 93.319822 -228.818259) (xy 93.365838 -228.800807) (xy 93.414057 -228.790963)
			(xy 93.463232 -228.788982) (xy 93.512087 -228.794914) (xy 93.559358 -228.808606) (xy 93.60382 -228.829704)
			(xy 93.644323 -228.85766) (xy 93.679816 -228.891752) (xy 93.709381 -228.931096) (xy 93.732252 -228.974673)
			(xy 93.747836 -229.021354) (xy 93.755731 -229.069931) (xy 93.756226 -229.094538) (xy 94.074737 -229.094538)
			(xy 94.078832 -229.04381) (xy 94.091011 -228.994396) (xy 94.110959 -228.947576) (xy 94.13816 -228.904562)
			(xy 94.171908 -228.866468) (xy 94.21133 -228.834281) (xy 94.255404 -228.808835) (xy 94.30299 -228.790788)
			(xy 94.352854 -228.780608) (xy 94.403706 -228.778559) (xy 94.454227 -228.784693) (xy 94.503111 -228.798853)
			(xy 94.54909 -228.82067) (xy 94.590974 -228.84958) (xy 94.627678 -228.884835) (xy 94.658251 -228.925521)
			(xy 94.681902 -228.970584) (xy 94.698018 -229.018858) (xy 94.706182 -229.069092) (xy 94.706694 -229.094538)
			(xy 95.014791 -229.094538) (xy 95.018886 -229.04381) (xy 95.031065 -228.994396) (xy 95.051013 -228.947576)
			(xy 95.078214 -228.904562) (xy 95.111962 -228.866468) (xy 95.151384 -228.834281) (xy 95.195458 -228.808835)
			(xy 95.243044 -228.790788) (xy 95.292908 -228.780608) (xy 95.34376 -228.778559) (xy 95.394281 -228.784693)
			(xy 95.443165 -228.798853) (xy 95.489144 -228.82067) (xy 95.531028 -228.84958) (xy 95.567732 -228.884835)
			(xy 95.598305 -228.925521) (xy 95.621956 -228.970584) (xy 95.638072 -229.018858) (xy 95.646236 -229.069092)
			(xy 95.646748 -229.094538) (xy 95.965276 -229.094538) (xy 95.969236 -229.045484) (xy 95.981013 -228.9977)
			(xy 96.000304 -228.952424) (xy 96.026607 -228.910828) (xy 96.059242 -228.873991) (xy 96.097363 -228.842866)
			(xy 96.139984 -228.818259) (xy 96.186 -228.800807) (xy 96.234219 -228.790963) (xy 96.283394 -228.788982)
			(xy 96.332249 -228.794914) (xy 96.37952 -228.808606) (xy 96.423982 -228.829704) (xy 96.464485 -228.85766)
			(xy 96.499978 -228.891752) (xy 96.529543 -228.931096) (xy 96.552414 -228.974673) (xy 96.567998 -229.021354)
			(xy 96.575893 -229.069931) (xy 96.576388 -229.094538) (xy 96.90533 -229.094538) (xy 96.90929 -229.045484)
			(xy 96.921067 -228.9977) (xy 96.940358 -228.952424) (xy 96.966661 -228.910828) (xy 96.999296 -228.873991)
			(xy 97.037417 -228.842866) (xy 97.080038 -228.818259) (xy 97.126054 -228.800807) (xy 97.174273 -228.790963)
			(xy 97.223448 -228.788982) (xy 97.272303 -228.794914) (xy 97.319574 -228.808606) (xy 97.364036 -228.829704)
			(xy 97.404539 -228.85766) (xy 97.440032 -228.891752) (xy 97.469597 -228.931096) (xy 97.492468 -228.974673)
			(xy 97.508052 -229.021354) (xy 97.515947 -229.069931) (xy 97.516442 -229.094538) (xy 97.84513 -229.094538)
			(xy 97.84909 -229.045484) (xy 97.860867 -228.9977) (xy 97.880158 -228.952424) (xy 97.906461 -228.910828)
			(xy 97.939096 -228.873991) (xy 97.977217 -228.842866) (xy 98.019838 -228.818259) (xy 98.065854 -228.800807)
			(xy 98.114073 -228.790963) (xy 98.163248 -228.788982) (xy 98.212103 -228.794914) (xy 98.259374 -228.808606)
			(xy 98.303836 -228.829704) (xy 98.344339 -228.85766) (xy 98.379832 -228.891752) (xy 98.409397 -228.931096)
			(xy 98.432268 -228.974673) (xy 98.447852 -229.021354) (xy 98.455747 -229.069931) (xy 98.456242 -229.094538)
			(xy 98.785184 -229.094538) (xy 98.789144 -229.045484) (xy 98.800921 -228.9977) (xy 98.820212 -228.952424)
			(xy 98.846515 -228.910828) (xy 98.87915 -228.873991) (xy 98.917271 -228.842866) (xy 98.959892 -228.818259)
			(xy 99.005908 -228.800807) (xy 99.054127 -228.790963) (xy 99.103302 -228.788982) (xy 99.152157 -228.794914)
			(xy 99.199428 -228.808606) (xy 99.24389 -228.829704) (xy 99.284393 -228.85766) (xy 99.319886 -228.891752)
			(xy 99.349451 -228.931096) (xy 99.372322 -228.974673) (xy 99.387906 -229.021354) (xy 99.395801 -229.069931)
			(xy 99.396296 -229.094538) (xy 99.725238 -229.094538) (xy 99.729198 -229.045484) (xy 99.740975 -228.9977)
			(xy 99.760266 -228.952424) (xy 99.786569 -228.910828) (xy 99.819204 -228.873991) (xy 99.857325 -228.842866)
			(xy 99.899946 -228.818259) (xy 99.945962 -228.800807) (xy 99.994181 -228.790963) (xy 100.043356 -228.788982)
			(xy 100.092211 -228.794914) (xy 100.139482 -228.808606) (xy 100.183944 -228.829704) (xy 100.224447 -228.85766)
			(xy 100.25994 -228.891752) (xy 100.289505 -228.931096) (xy 100.312376 -228.974673) (xy 100.32796 -229.021354)
			(xy 100.335855 -229.069931) (xy 100.33635 -229.094538) (xy 100.665292 -229.094538) (xy 100.669252 -229.045484)
			(xy 100.681029 -228.9977) (xy 100.70032 -228.952424) (xy 100.726623 -228.910828) (xy 100.759258 -228.873991)
			(xy 100.797379 -228.842866) (xy 100.84 -228.818259) (xy 100.886016 -228.800807) (xy 100.934235 -228.790963)
			(xy 100.98341 -228.788982) (xy 101.032265 -228.794914) (xy 101.079536 -228.808606) (xy 101.123998 -228.829704)
			(xy 101.164501 -228.85766) (xy 101.199994 -228.891752) (xy 101.229559 -228.931096) (xy 101.25243 -228.974673)
			(xy 101.268014 -229.021354) (xy 101.275909 -229.069931) (xy 101.276404 -229.094538) (xy 101.605346 -229.094538)
			(xy 101.609306 -229.045484) (xy 101.621083 -228.9977) (xy 101.640374 -228.952424) (xy 101.666677 -228.910828)
			(xy 101.699312 -228.873991) (xy 101.737433 -228.842866) (xy 101.780054 -228.818259) (xy 101.82607 -228.800807)
			(xy 101.874289 -228.790963) (xy 101.923464 -228.788982) (xy 101.972319 -228.794914) (xy 102.01959 -228.808606)
			(xy 102.064052 -228.829704) (xy 102.104555 -228.85766) (xy 102.140048 -228.891752) (xy 102.169613 -228.931096)
			(xy 102.192484 -228.974673) (xy 102.208068 -229.021354) (xy 102.215963 -229.069931) (xy 102.216458 -229.094538)
			(xy 102.545146 -229.094538) (xy 102.549106 -229.045484) (xy 102.560883 -228.9977) (xy 102.580174 -228.952424)
			(xy 102.606477 -228.910828) (xy 102.639112 -228.873991) (xy 102.677233 -228.842866) (xy 102.719854 -228.818259)
			(xy 102.76587 -228.800807) (xy 102.814089 -228.790963) (xy 102.863264 -228.788982) (xy 102.912119 -228.794914)
			(xy 102.95939 -228.808606) (xy 103.003852 -228.829704) (xy 103.044355 -228.85766) (xy 103.079848 -228.891752)
			(xy 103.109413 -228.931096) (xy 103.132284 -228.974673) (xy 103.147868 -229.021354) (xy 103.155763 -229.069931)
			(xy 103.156258 -229.094538) (xy 103.4852 -229.094538) (xy 103.48916 -229.045484) (xy 103.500937 -228.9977)
			(xy 103.520228 -228.952424) (xy 103.546531 -228.910828) (xy 103.579166 -228.873991) (xy 103.617287 -228.842866)
			(xy 103.659908 -228.818259) (xy 103.705924 -228.800807) (xy 103.754143 -228.790963) (xy 103.803318 -228.788982)
			(xy 103.852173 -228.794914) (xy 103.899444 -228.808606) (xy 103.943906 -228.829704) (xy 103.984409 -228.85766)
			(xy 104.019902 -228.891752) (xy 104.049467 -228.931096) (xy 104.072338 -228.974673) (xy 104.087922 -229.021354)
			(xy 104.095817 -229.069931) (xy 104.096312 -229.094538) (xy 104.425254 -229.094538) (xy 104.429214 -229.045484)
			(xy 104.440991 -228.9977) (xy 104.460282 -228.952424) (xy 104.486585 -228.910828) (xy 104.51922 -228.873991)
			(xy 104.557341 -228.842866) (xy 104.599962 -228.818259) (xy 104.645978 -228.800807) (xy 104.694197 -228.790963)
			(xy 104.743372 -228.788982) (xy 104.792227 -228.794914) (xy 104.839498 -228.808606) (xy 104.88396 -228.829704)
			(xy 104.924463 -228.85766) (xy 104.959956 -228.891752) (xy 104.989521 -228.931096) (xy 105.012392 -228.974673)
			(xy 105.027976 -229.021354) (xy 105.035871 -229.069931) (xy 105.036366 -229.094538) (xy 105.365308 -229.094538)
			(xy 105.369268 -229.045484) (xy 105.381045 -228.9977) (xy 105.400336 -228.952424) (xy 105.426639 -228.910828)
			(xy 105.459274 -228.873991) (xy 105.497395 -228.842866) (xy 105.540016 -228.818259) (xy 105.586032 -228.800807)
			(xy 105.634251 -228.790963) (xy 105.683426 -228.788982) (xy 105.732281 -228.794914) (xy 105.779552 -228.808606)
			(xy 105.824014 -228.829704) (xy 105.864517 -228.85766) (xy 105.90001 -228.891752) (xy 105.929575 -228.931096)
			(xy 105.952446 -228.974673) (xy 105.96803 -229.021354) (xy 105.975925 -229.069931) (xy 105.97642 -229.094538)
			(xy 106.305362 -229.094538) (xy 106.309322 -229.045484) (xy 106.321099 -228.9977) (xy 106.34039 -228.952424)
			(xy 106.366693 -228.910828) (xy 106.399328 -228.873991) (xy 106.437449 -228.842866) (xy 106.48007 -228.818259)
			(xy 106.526086 -228.800807) (xy 106.574305 -228.790963) (xy 106.62348 -228.788982) (xy 106.672335 -228.794914)
			(xy 106.719606 -228.808606) (xy 106.764068 -228.829704) (xy 106.804571 -228.85766) (xy 106.840064 -228.891752)
			(xy 106.869629 -228.931096) (xy 106.8925 -228.974673) (xy 106.908084 -229.021354) (xy 106.915979 -229.069931)
			(xy 106.916474 -229.094538) (xy 107.245162 -229.094538) (xy 107.249122 -229.045484) (xy 107.260899 -228.9977)
			(xy 107.28019 -228.952424) (xy 107.306493 -228.910828) (xy 107.339128 -228.873991) (xy 107.377249 -228.842866)
			(xy 107.41987 -228.818259) (xy 107.465886 -228.800807) (xy 107.514105 -228.790963) (xy 107.56328 -228.788982)
			(xy 107.612135 -228.794914) (xy 107.659406 -228.808606) (xy 107.703868 -228.829704) (xy 107.744371 -228.85766)
			(xy 107.779864 -228.891752) (xy 107.809429 -228.931096) (xy 107.8323 -228.974673) (xy 107.847884 -229.021354)
			(xy 107.855779 -229.069931) (xy 107.856274 -229.094538) (xy 108.174785 -229.094538) (xy 108.17888 -229.04381)
			(xy 108.191059 -228.994396) (xy 108.211007 -228.947576) (xy 108.238208 -228.904562) (xy 108.271956 -228.866468)
			(xy 108.311378 -228.834281) (xy 108.355452 -228.808835) (xy 108.403038 -228.790788) (xy 108.452902 -228.780608)
			(xy 108.503754 -228.778559) (xy 108.554275 -228.784693) (xy 108.603159 -228.798853) (xy 108.649138 -228.82067)
			(xy 108.691022 -228.84958) (xy 108.727726 -228.884835) (xy 108.758299 -228.925521) (xy 108.78195 -228.970584)
			(xy 108.798066 -229.018858) (xy 108.80623 -229.069092) (xy 108.806742 -229.094538) (xy 109.114839 -229.094538)
			(xy 109.118934 -229.04381) (xy 109.131113 -228.994396) (xy 109.151061 -228.947576) (xy 109.178262 -228.904562)
			(xy 109.21201 -228.866468) (xy 109.251432 -228.834281) (xy 109.295506 -228.808835) (xy 109.343092 -228.790788)
			(xy 109.392956 -228.780608) (xy 109.443808 -228.778559) (xy 109.494329 -228.784693) (xy 109.543213 -228.798853)
			(xy 109.589192 -228.82067) (xy 109.631076 -228.84958) (xy 109.66778 -228.884835) (xy 109.698353 -228.925521)
			(xy 109.722004 -228.970584) (xy 109.73812 -229.018858) (xy 109.746284 -229.069092) (xy 109.746796 -229.094538)
			(xy 110.065324 -229.094538) (xy 110.069284 -229.045484) (xy 110.081061 -228.9977) (xy 110.100352 -228.952424)
			(xy 110.126655 -228.910828) (xy 110.15929 -228.873991) (xy 110.197411 -228.842866) (xy 110.240032 -228.818259)
			(xy 110.286048 -228.800807) (xy 110.334267 -228.790963) (xy 110.383442 -228.788982) (xy 110.432297 -228.794914)
			(xy 110.479568 -228.808606) (xy 110.52403 -228.829704) (xy 110.564533 -228.85766) (xy 110.600026 -228.891752)
			(xy 110.629591 -228.931096) (xy 110.652462 -228.974673) (xy 110.668046 -229.021354) (xy 110.675941 -229.069931)
			(xy 110.676436 -229.094538) (xy 110.675941 -229.119145) (xy 110.668046 -229.167722) (xy 110.652462 -229.214403)
			(xy 110.629591 -229.25798) (xy 110.600026 -229.297324) (xy 110.564533 -229.331416) (xy 110.52403 -229.359372)
			(xy 110.479568 -229.38047) (xy 110.432297 -229.394162) (xy 110.383442 -229.400094) (xy 110.334267 -229.398113)
			(xy 110.286048 -229.388269) (xy 110.240032 -229.370817) (xy 110.197411 -229.34621) (xy 110.15929 -229.315085)
			(xy 110.126655 -229.278248) (xy 110.100352 -229.236652) (xy 110.081061 -229.191376) (xy 110.069284 -229.143592)
			(xy 110.065324 -229.094538) (xy 109.746796 -229.094538) (xy 109.746284 -229.119984) (xy 109.73812 -229.170218)
			(xy 109.722004 -229.218492) (xy 109.698353 -229.263555) (xy 109.66778 -229.304241) (xy 109.631076 -229.339496)
			(xy 109.589192 -229.368406) (xy 109.543213 -229.390223) (xy 109.494329 -229.404383) (xy 109.443808 -229.410517)
			(xy 109.392956 -229.408468) (xy 109.343092 -229.398288) (xy 109.295506 -229.380241) (xy 109.251432 -229.354795)
			(xy 109.21201 -229.322608) (xy 109.178262 -229.284514) (xy 109.151061 -229.2415) (xy 109.131113 -229.19468)
			(xy 109.118934 -229.145266) (xy 109.114839 -229.094538) (xy 108.806742 -229.094538) (xy 108.80623 -229.119984)
			(xy 108.798066 -229.170218) (xy 108.78195 -229.218492) (xy 108.758299 -229.263555) (xy 108.727726 -229.304241)
			(xy 108.691022 -229.339496) (xy 108.649138 -229.368406) (xy 108.603159 -229.390223) (xy 108.554275 -229.404383)
			(xy 108.503754 -229.410517) (xy 108.452902 -229.408468) (xy 108.403038 -229.398288) (xy 108.355452 -229.380241)
			(xy 108.311378 -229.354795) (xy 108.271956 -229.322608) (xy 108.238208 -229.284514) (xy 108.211007 -229.2415)
			(xy 108.191059 -229.19468) (xy 108.17888 -229.145266) (xy 108.174785 -229.094538) (xy 107.856274 -229.094538)
			(xy 107.855779 -229.119145) (xy 107.847884 -229.167722) (xy 107.8323 -229.214403) (xy 107.809429 -229.25798)
			(xy 107.779864 -229.297324) (xy 107.744371 -229.331416) (xy 107.703868 -229.359372) (xy 107.659406 -229.38047)
			(xy 107.612135 -229.394162) (xy 107.56328 -229.400094) (xy 107.514105 -229.398113) (xy 107.465886 -229.388269)
			(xy 107.41987 -229.370817) (xy 107.377249 -229.34621) (xy 107.339128 -229.315085) (xy 107.306493 -229.278248)
			(xy 107.28019 -229.236652) (xy 107.260899 -229.191376) (xy 107.249122 -229.143592) (xy 107.245162 -229.094538)
			(xy 106.916474 -229.094538) (xy 106.915979 -229.119145) (xy 106.908084 -229.167722) (xy 106.8925 -229.214403)
			(xy 106.869629 -229.25798) (xy 106.840064 -229.297324) (xy 106.804571 -229.331416) (xy 106.764068 -229.359372)
			(xy 106.719606 -229.38047) (xy 106.672335 -229.394162) (xy 106.62348 -229.400094) (xy 106.574305 -229.398113)
			(xy 106.526086 -229.388269) (xy 106.48007 -229.370817) (xy 106.437449 -229.34621) (xy 106.399328 -229.315085)
			(xy 106.366693 -229.278248) (xy 106.34039 -229.236652) (xy 106.321099 -229.191376) (xy 106.309322 -229.143592)
			(xy 106.305362 -229.094538) (xy 105.97642 -229.094538) (xy 105.975925 -229.119145) (xy 105.96803 -229.167722)
			(xy 105.952446 -229.214403) (xy 105.929575 -229.25798) (xy 105.90001 -229.297324) (xy 105.864517 -229.331416)
			(xy 105.824014 -229.359372) (xy 105.779552 -229.38047) (xy 105.732281 -229.394162) (xy 105.683426 -229.400094)
			(xy 105.634251 -229.398113) (xy 105.586032 -229.388269) (xy 105.540016 -229.370817) (xy 105.497395 -229.34621)
			(xy 105.459274 -229.315085) (xy 105.426639 -229.278248) (xy 105.400336 -229.236652) (xy 105.381045 -229.191376)
			(xy 105.369268 -229.143592) (xy 105.365308 -229.094538) (xy 105.036366 -229.094538) (xy 105.035871 -229.119145)
			(xy 105.027976 -229.167722) (xy 105.012392 -229.214403) (xy 104.989521 -229.25798) (xy 104.959956 -229.297324)
			(xy 104.924463 -229.331416) (xy 104.88396 -229.359372) (xy 104.839498 -229.38047) (xy 104.792227 -229.394162)
			(xy 104.743372 -229.400094) (xy 104.694197 -229.398113) (xy 104.645978 -229.388269) (xy 104.599962 -229.370817)
			(xy 104.557341 -229.34621) (xy 104.51922 -229.315085) (xy 104.486585 -229.278248) (xy 104.460282 -229.236652)
			(xy 104.440991 -229.191376) (xy 104.429214 -229.143592) (xy 104.425254 -229.094538) (xy 104.096312 -229.094538)
			(xy 104.095817 -229.119145) (xy 104.087922 -229.167722) (xy 104.072338 -229.214403) (xy 104.049467 -229.25798)
			(xy 104.019902 -229.297324) (xy 103.984409 -229.331416) (xy 103.943906 -229.359372) (xy 103.899444 -229.38047)
			(xy 103.852173 -229.394162) (xy 103.803318 -229.400094) (xy 103.754143 -229.398113) (xy 103.705924 -229.388269)
			(xy 103.659908 -229.370817) (xy 103.617287 -229.34621) (xy 103.579166 -229.315085) (xy 103.546531 -229.278248)
			(xy 103.520228 -229.236652) (xy 103.500937 -229.191376) (xy 103.48916 -229.143592) (xy 103.4852 -229.094538)
			(xy 103.156258 -229.094538) (xy 103.155763 -229.119145) (xy 103.147868 -229.167722) (xy 103.132284 -229.214403)
			(xy 103.109413 -229.25798) (xy 103.079848 -229.297324) (xy 103.044355 -229.331416) (xy 103.003852 -229.359372)
			(xy 102.95939 -229.38047) (xy 102.912119 -229.394162) (xy 102.863264 -229.400094) (xy 102.814089 -229.398113)
			(xy 102.76587 -229.388269) (xy 102.719854 -229.370817) (xy 102.677233 -229.34621) (xy 102.639112 -229.315085)
			(xy 102.606477 -229.278248) (xy 102.580174 -229.236652) (xy 102.560883 -229.191376) (xy 102.549106 -229.143592)
			(xy 102.545146 -229.094538) (xy 102.216458 -229.094538) (xy 102.215963 -229.119145) (xy 102.208068 -229.167722)
			(xy 102.192484 -229.214403) (xy 102.169613 -229.25798) (xy 102.140048 -229.297324) (xy 102.104555 -229.331416)
			(xy 102.064052 -229.359372) (xy 102.01959 -229.38047) (xy 101.972319 -229.394162) (xy 101.923464 -229.400094)
			(xy 101.874289 -229.398113) (xy 101.82607 -229.388269) (xy 101.780054 -229.370817) (xy 101.737433 -229.34621)
			(xy 101.699312 -229.315085) (xy 101.666677 -229.278248) (xy 101.640374 -229.236652) (xy 101.621083 -229.191376)
			(xy 101.609306 -229.143592) (xy 101.605346 -229.094538) (xy 101.276404 -229.094538) (xy 101.275909 -229.119145)
			(xy 101.268014 -229.167722) (xy 101.25243 -229.214403) (xy 101.229559 -229.25798) (xy 101.199994 -229.297324)
			(xy 101.164501 -229.331416) (xy 101.123998 -229.359372) (xy 101.079536 -229.38047) (xy 101.032265 -229.394162)
			(xy 100.98341 -229.400094) (xy 100.934235 -229.398113) (xy 100.886016 -229.388269) (xy 100.84 -229.370817)
			(xy 100.797379 -229.34621) (xy 100.759258 -229.315085) (xy 100.726623 -229.278248) (xy 100.70032 -229.236652)
			(xy 100.681029 -229.191376) (xy 100.669252 -229.143592) (xy 100.665292 -229.094538) (xy 100.33635 -229.094538)
			(xy 100.335855 -229.119145) (xy 100.32796 -229.167722) (xy 100.312376 -229.214403) (xy 100.289505 -229.25798)
			(xy 100.25994 -229.297324) (xy 100.224447 -229.331416) (xy 100.183944 -229.359372) (xy 100.139482 -229.38047)
			(xy 100.092211 -229.394162) (xy 100.043356 -229.400094) (xy 99.994181 -229.398113) (xy 99.945962 -229.388269)
			(xy 99.899946 -229.370817) (xy 99.857325 -229.34621) (xy 99.819204 -229.315085) (xy 99.786569 -229.278248)
			(xy 99.760266 -229.236652) (xy 99.740975 -229.191376) (xy 99.729198 -229.143592) (xy 99.725238 -229.094538)
			(xy 99.396296 -229.094538) (xy 99.395801 -229.119145) (xy 99.387906 -229.167722) (xy 99.372322 -229.214403)
			(xy 99.349451 -229.25798) (xy 99.319886 -229.297324) (xy 99.284393 -229.331416) (xy 99.24389 -229.359372)
			(xy 99.199428 -229.38047) (xy 99.152157 -229.394162) (xy 99.103302 -229.400094) (xy 99.054127 -229.398113)
			(xy 99.005908 -229.388269) (xy 98.959892 -229.370817) (xy 98.917271 -229.34621) (xy 98.87915 -229.315085)
			(xy 98.846515 -229.278248) (xy 98.820212 -229.236652) (xy 98.800921 -229.191376) (xy 98.789144 -229.143592)
			(xy 98.785184 -229.094538) (xy 98.456242 -229.094538) (xy 98.455747 -229.119145) (xy 98.447852 -229.167722)
			(xy 98.432268 -229.214403) (xy 98.409397 -229.25798) (xy 98.379832 -229.297324) (xy 98.344339 -229.331416)
			(xy 98.303836 -229.359372) (xy 98.259374 -229.38047) (xy 98.212103 -229.394162) (xy 98.163248 -229.400094)
			(xy 98.114073 -229.398113) (xy 98.065854 -229.388269) (xy 98.019838 -229.370817) (xy 97.977217 -229.34621)
			(xy 97.939096 -229.315085) (xy 97.906461 -229.278248) (xy 97.880158 -229.236652) (xy 97.860867 -229.191376)
			(xy 97.84909 -229.143592) (xy 97.84513 -229.094538) (xy 97.516442 -229.094538) (xy 97.515947 -229.119145)
			(xy 97.508052 -229.167722) (xy 97.492468 -229.214403) (xy 97.469597 -229.25798) (xy 97.440032 -229.297324)
			(xy 97.404539 -229.331416) (xy 97.364036 -229.359372) (xy 97.319574 -229.38047) (xy 97.272303 -229.394162)
			(xy 97.223448 -229.400094) (xy 97.174273 -229.398113) (xy 97.126054 -229.388269) (xy 97.080038 -229.370817)
			(xy 97.037417 -229.34621) (xy 96.999296 -229.315085) (xy 96.966661 -229.278248) (xy 96.940358 -229.236652)
			(xy 96.921067 -229.191376) (xy 96.90929 -229.143592) (xy 96.90533 -229.094538) (xy 96.576388 -229.094538)
			(xy 96.575893 -229.119145) (xy 96.567998 -229.167722) (xy 96.552414 -229.214403) (xy 96.529543 -229.25798)
			(xy 96.499978 -229.297324) (xy 96.464485 -229.331416) (xy 96.423982 -229.359372) (xy 96.37952 -229.38047)
			(xy 96.332249 -229.394162) (xy 96.283394 -229.400094) (xy 96.234219 -229.398113) (xy 96.186 -229.388269)
			(xy 96.139984 -229.370817) (xy 96.097363 -229.34621) (xy 96.059242 -229.315085) (xy 96.026607 -229.278248)
			(xy 96.000304 -229.236652) (xy 95.981013 -229.191376) (xy 95.969236 -229.143592) (xy 95.965276 -229.094538)
			(xy 95.646748 -229.094538) (xy 95.646236 -229.119984) (xy 95.638072 -229.170218) (xy 95.621956 -229.218492)
			(xy 95.598305 -229.263555) (xy 95.567732 -229.304241) (xy 95.531028 -229.339496) (xy 95.489144 -229.368406)
			(xy 95.443165 -229.390223) (xy 95.394281 -229.404383) (xy 95.34376 -229.410517) (xy 95.292908 -229.408468)
			(xy 95.243044 -229.398288) (xy 95.195458 -229.380241) (xy 95.151384 -229.354795) (xy 95.111962 -229.322608)
			(xy 95.078214 -229.284514) (xy 95.051013 -229.2415) (xy 95.031065 -229.19468) (xy 95.018886 -229.145266)
			(xy 95.014791 -229.094538) (xy 94.706694 -229.094538) (xy 94.706182 -229.119984) (xy 94.698018 -229.170218)
			(xy 94.681902 -229.218492) (xy 94.658251 -229.263555) (xy 94.627678 -229.304241) (xy 94.590974 -229.339496)
			(xy 94.54909 -229.368406) (xy 94.503111 -229.390223) (xy 94.454227 -229.404383) (xy 94.403706 -229.410517)
			(xy 94.352854 -229.408468) (xy 94.30299 -229.398288) (xy 94.255404 -229.380241) (xy 94.21133 -229.354795)
			(xy 94.171908 -229.322608) (xy 94.13816 -229.284514) (xy 94.110959 -229.2415) (xy 94.091011 -229.19468)
			(xy 94.078832 -229.145266) (xy 94.074737 -229.094538) (xy 93.756226 -229.094538) (xy 93.755731 -229.119145)
			(xy 93.747836 -229.167722) (xy 93.732252 -229.214403) (xy 93.709381 -229.25798) (xy 93.679816 -229.297324)
			(xy 93.644323 -229.331416) (xy 93.60382 -229.359372) (xy 93.559358 -229.38047) (xy 93.512087 -229.394162)
			(xy 93.463232 -229.400094) (xy 93.414057 -229.398113) (xy 93.365838 -229.388269) (xy 93.319822 -229.370817)
			(xy 93.277201 -229.34621) (xy 93.23908 -229.315085) (xy 93.206445 -229.278248) (xy 93.180142 -229.236652)
			(xy 93.160851 -229.191376) (xy 93.149074 -229.143592) (xy 93.145114 -229.094538) (xy 92.82684 -229.094538)
			(xy 92.826328 -229.119984) (xy 92.818164 -229.170218) (xy 92.802048 -229.218492) (xy 92.778397 -229.263555)
			(xy 92.747824 -229.304241) (xy 92.71112 -229.339496) (xy 92.669236 -229.368406) (xy 92.623257 -229.390223)
			(xy 92.574373 -229.404383) (xy 92.523852 -229.410517) (xy 92.473 -229.408468) (xy 92.423136 -229.398288)
			(xy 92.37555 -229.380241) (xy 92.331476 -229.354795) (xy 92.292054 -229.322608) (xy 92.258306 -229.284514)
			(xy 92.231105 -229.2415) (xy 92.211157 -229.19468) (xy 92.198978 -229.145266) (xy 92.194883 -229.094538)
			(xy 91.876372 -229.094538) (xy 91.875877 -229.119145) (xy 91.867982 -229.167722) (xy 91.852398 -229.214403)
			(xy 91.829527 -229.25798) (xy 91.799962 -229.297324) (xy 91.764469 -229.331416) (xy 91.723966 -229.359372)
			(xy 91.679504 -229.38047) (xy 91.632233 -229.394162) (xy 91.583378 -229.400094) (xy 91.534203 -229.398113)
			(xy 91.485984 -229.388269) (xy 91.439968 -229.370817) (xy 91.397347 -229.34621) (xy 91.359226 -229.315085)
			(xy 91.326591 -229.278248) (xy 91.300288 -229.236652) (xy 91.280997 -229.191376) (xy 91.26922 -229.143592)
			(xy 91.26526 -229.094538) (xy 90.946732 -229.094538) (xy 90.94622 -229.119984) (xy 90.938056 -229.170218)
			(xy 90.92194 -229.218492) (xy 90.898289 -229.263555) (xy 90.867716 -229.304241) (xy 90.831012 -229.339496)
			(xy 90.789128 -229.368406) (xy 90.743149 -229.390223) (xy 90.694265 -229.404383) (xy 90.643744 -229.410517)
			(xy 90.592892 -229.408468) (xy 90.543028 -229.398288) (xy 90.495442 -229.380241) (xy 90.451368 -229.354795)
			(xy 90.411946 -229.322608) (xy 90.378198 -229.284514) (xy 90.350997 -229.2415) (xy 90.331049 -229.19468)
			(xy 90.31887 -229.145266) (xy 90.314775 -229.094538) (xy 89.996264 -229.094538) (xy 89.995769 -229.119145)
			(xy 89.987874 -229.167722) (xy 89.97229 -229.214403) (xy 89.949419 -229.25798) (xy 89.919854 -229.297324)
			(xy 89.884361 -229.331416) (xy 89.843858 -229.359372) (xy 89.799396 -229.38047) (xy 89.752125 -229.394162)
			(xy 89.70327 -229.400094) (xy 89.654095 -229.398113) (xy 89.605876 -229.388269) (xy 89.55986 -229.370817)
			(xy 89.517239 -229.34621) (xy 89.479118 -229.315085) (xy 89.446483 -229.278248) (xy 89.42018 -229.236652)
			(xy 89.400889 -229.191376) (xy 89.389112 -229.143592) (xy 89.385152 -229.094538) (xy 89.066878 -229.094538)
			(xy 89.066366 -229.119984) (xy 89.058202 -229.170218) (xy 89.042086 -229.218492) (xy 89.018435 -229.263555)
			(xy 88.987862 -229.304241) (xy 88.951158 -229.339496) (xy 88.909274 -229.368406) (xy 88.863295 -229.390223)
			(xy 88.814411 -229.404383) (xy 88.76389 -229.410517) (xy 88.713038 -229.408468) (xy 88.663174 -229.398288)
			(xy 88.615588 -229.380241) (xy 88.571514 -229.354795) (xy 88.532092 -229.322608) (xy 88.498344 -229.284514)
			(xy 88.471143 -229.2415) (xy 88.451195 -229.19468) (xy 88.439016 -229.145266) (xy 88.434921 -229.094538)
			(xy 88.126824 -229.094538) (xy 88.126312 -229.119984) (xy 88.118148 -229.170218) (xy 88.102032 -229.218492)
			(xy 88.078381 -229.263555) (xy 88.047808 -229.304241) (xy 88.011104 -229.339496) (xy 87.96922 -229.368406)
			(xy 87.923241 -229.390223) (xy 87.874357 -229.404383) (xy 87.823836 -229.410517) (xy 87.772984 -229.408468)
			(xy 87.72312 -229.398288) (xy 87.675534 -229.380241) (xy 87.63146 -229.354795) (xy 87.592038 -229.322608)
			(xy 87.55829 -229.284514) (xy 87.531089 -229.2415) (xy 87.511141 -229.19468) (xy 87.498962 -229.145266)
			(xy 87.494867 -229.094538) (xy 87.176356 -229.094538) (xy 87.175861 -229.119145) (xy 87.167966 -229.167722)
			(xy 87.152382 -229.214403) (xy 87.129511 -229.25798) (xy 87.099946 -229.297324) (xy 87.064453 -229.331416)
			(xy 87.02395 -229.359372) (xy 86.979488 -229.38047) (xy 86.932217 -229.394162) (xy 86.883362 -229.400094)
			(xy 86.834187 -229.398113) (xy 86.785968 -229.388269) (xy 86.739952 -229.370817) (xy 86.697331 -229.34621)
			(xy 86.65921 -229.315085) (xy 86.626575 -229.278248) (xy 86.600272 -229.236652) (xy 86.580981 -229.191376)
			(xy 86.569204 -229.143592) (xy 86.565244 -229.094538) (xy 86.246716 -229.094538) (xy 86.246204 -229.119984)
			(xy 86.23804 -229.170218) (xy 86.221924 -229.218492) (xy 86.198273 -229.263555) (xy 86.1677 -229.304241)
			(xy 86.130996 -229.339496) (xy 86.089112 -229.368406) (xy 86.043133 -229.390223) (xy 85.994249 -229.404383)
			(xy 85.943728 -229.410517) (xy 85.892876 -229.408468) (xy 85.843012 -229.398288) (xy 85.795426 -229.380241)
			(xy 85.751352 -229.354795) (xy 85.71193 -229.322608) (xy 85.678182 -229.284514) (xy 85.650981 -229.2415)
			(xy 85.631033 -229.19468) (xy 85.618854 -229.145266) (xy 85.614759 -229.094538) (xy 85.296248 -229.094538)
			(xy 85.295753 -229.119145) (xy 85.287858 -229.167722) (xy 85.272274 -229.214403) (xy 85.249403 -229.25798)
			(xy 85.219838 -229.297324) (xy 85.184345 -229.331416) (xy 85.143842 -229.359372) (xy 85.09938 -229.38047)
			(xy 85.052109 -229.394162) (xy 85.003254 -229.400094) (xy 84.954079 -229.398113) (xy 84.90586 -229.388269)
			(xy 84.859844 -229.370817) (xy 84.817223 -229.34621) (xy 84.779102 -229.315085) (xy 84.746467 -229.278248)
			(xy 84.720164 -229.236652) (xy 84.700873 -229.191376) (xy 84.689096 -229.143592) (xy 84.685136 -229.094538)
			(xy 84.366862 -229.094538) (xy 84.36635 -229.119984) (xy 84.358186 -229.170218) (xy 84.34207 -229.218492)
			(xy 84.318419 -229.263555) (xy 84.287846 -229.304241) (xy 84.251142 -229.339496) (xy 84.209258 -229.368406)
			(xy 84.163279 -229.390223) (xy 84.114395 -229.404383) (xy 84.063874 -229.410517) (xy 84.013022 -229.408468)
			(xy 83.963158 -229.398288) (xy 83.915572 -229.380241) (xy 83.871498 -229.354795) (xy 83.832076 -229.322608)
			(xy 83.798328 -229.284514) (xy 83.771127 -229.2415) (xy 83.751179 -229.19468) (xy 83.739 -229.145266)
			(xy 83.734905 -229.094538) (xy 83.416394 -229.094538) (xy 83.415899 -229.119145) (xy 83.408004 -229.167722)
			(xy 83.39242 -229.214403) (xy 83.369549 -229.25798) (xy 83.339984 -229.297324) (xy 83.304491 -229.331416)
			(xy 83.263988 -229.359372) (xy 83.219526 -229.38047) (xy 83.172255 -229.394162) (xy 83.1234 -229.400094)
			(xy 83.074225 -229.398113) (xy 83.026006 -229.388269) (xy 82.97999 -229.370817) (xy 82.937369 -229.34621)
			(xy 82.899248 -229.315085) (xy 82.866613 -229.278248) (xy 82.84031 -229.236652) (xy 82.821019 -229.191376)
			(xy 82.809242 -229.143592) (xy 82.805282 -229.094538) (xy 82.486754 -229.094538) (xy 82.486242 -229.119984)
			(xy 82.478078 -229.170218) (xy 82.461962 -229.218492) (xy 82.438311 -229.263555) (xy 82.407738 -229.304241)
			(xy 82.371034 -229.339496) (xy 82.32915 -229.368406) (xy 82.283171 -229.390223) (xy 82.234287 -229.404383)
			(xy 82.183766 -229.410517) (xy 82.132914 -229.408468) (xy 82.08305 -229.398288) (xy 82.035464 -229.380241)
			(xy 81.99139 -229.354795) (xy 81.951968 -229.322608) (xy 81.91822 -229.284514) (xy 81.891019 -229.2415)
			(xy 81.871071 -229.19468) (xy 81.858892 -229.145266) (xy 81.854797 -229.094538) (xy 81.5467 -229.094538)
			(xy 81.546188 -229.119984) (xy 81.538024 -229.170218) (xy 81.521908 -229.218492) (xy 81.498257 -229.263555)
			(xy 81.467684 -229.304241) (xy 81.43098 -229.339496) (xy 81.389096 -229.368406) (xy 81.343117 -229.390223)
			(xy 81.294233 -229.404383) (xy 81.243712 -229.410517) (xy 81.19286 -229.408468) (xy 81.142996 -229.398288)
			(xy 81.09541 -229.380241) (xy 81.051336 -229.354795) (xy 81.011914 -229.322608) (xy 80.978166 -229.284514)
			(xy 80.950965 -229.2415) (xy 80.931017 -229.19468) (xy 80.918838 -229.145266) (xy 80.914743 -229.094538)
			(xy 80.596486 -229.094538) (xy 80.595991 -229.119145) (xy 80.588096 -229.167722) (xy 80.572512 -229.214403)
			(xy 80.549641 -229.25798) (xy 80.520076 -229.297324) (xy 80.484583 -229.331416) (xy 80.44408 -229.359372)
			(xy 80.399618 -229.38047) (xy 80.352347 -229.394162) (xy 80.303492 -229.400094) (xy 80.254317 -229.398113)
			(xy 80.206098 -229.388269) (xy 80.160082 -229.370817) (xy 80.117461 -229.34621) (xy 80.07934 -229.315085)
			(xy 80.046705 -229.278248) (xy 80.020402 -229.236652) (xy 80.001111 -229.191376) (xy 79.989334 -229.143592)
			(xy 79.985374 -229.094538) (xy 78.716378 -229.094538) (xy 78.715883 -229.119145) (xy 78.707988 -229.167722)
			(xy 78.692404 -229.214403) (xy 78.669533 -229.25798) (xy 78.639968 -229.297324) (xy 78.604475 -229.331416)
			(xy 78.563972 -229.359372) (xy 78.51951 -229.38047) (xy 78.472239 -229.394162) (xy 78.423384 -229.400094)
			(xy 78.374209 -229.398113) (xy 78.32599 -229.388269) (xy 78.279974 -229.370817) (xy 78.237353 -229.34621)
			(xy 78.199232 -229.315085) (xy 78.166597 -229.278248) (xy 78.140294 -229.236652) (xy 78.121003 -229.191376)
			(xy 78.109226 -229.143592) (xy 78.105266 -229.094538) (xy 62.37732 -229.094538) (xy 62.37732 -230.170228)
			(xy 76.507098 -230.170228) (xy 76.511058 -230.121174) (xy 76.522835 -230.07339) (xy 76.542126 -230.028114)
			(xy 76.568429 -229.986518) (xy 76.601064 -229.949681) (xy 76.639185 -229.918556) (xy 76.681806 -229.893949)
			(xy 76.727822 -229.876497) (xy 76.776041 -229.866653) (xy 76.825216 -229.864672) (xy 76.874071 -229.870604)
			(xy 76.921342 -229.884296) (xy 76.963477 -229.90429) (xy 79.51522 -229.90429) (xy 79.51918 -229.855236)
			(xy 79.530957 -229.807452) (xy 79.550248 -229.762176) (xy 79.576551 -229.72058) (xy 79.609186 -229.683743)
			(xy 79.647307 -229.652618) (xy 79.689928 -229.628011) (xy 79.735944 -229.610559) (xy 79.784163 -229.600715)
			(xy 79.833338 -229.598734) (xy 79.882193 -229.604666) (xy 79.929464 -229.618358) (xy 79.973926 -229.639456)
			(xy 80.014429 -229.667412) (xy 80.049922 -229.701504) (xy 80.079487 -229.740848) (xy 80.102358 -229.784425)
			(xy 80.117942 -229.831106) (xy 80.125837 -229.879683) (xy 80.126332 -229.90429) (xy 80.444843 -229.90429)
			(xy 80.448938 -229.853562) (xy 80.461117 -229.804148) (xy 80.481065 -229.757328) (xy 80.508266 -229.714314)
			(xy 80.542014 -229.67622) (xy 80.581436 -229.644033) (xy 80.62551 -229.618587) (xy 80.673096 -229.60054)
			(xy 80.72296 -229.59036) (xy 80.773812 -229.588311) (xy 80.824333 -229.594445) (xy 80.873217 -229.608605)
			(xy 80.919196 -229.630422) (xy 80.96108 -229.659332) (xy 80.997784 -229.694587) (xy 81.028357 -229.735273)
			(xy 81.052008 -229.780336) (xy 81.068124 -229.82861) (xy 81.076288 -229.878844) (xy 81.0768 -229.90429)
			(xy 81.395328 -229.90429) (xy 81.399288 -229.855236) (xy 81.411065 -229.807452) (xy 81.430356 -229.762176)
			(xy 81.456659 -229.72058) (xy 81.489294 -229.683743) (xy 81.527415 -229.652618) (xy 81.570036 -229.628011)
			(xy 81.616052 -229.610559) (xy 81.664271 -229.600715) (xy 81.713446 -229.598734) (xy 81.762301 -229.604666)
			(xy 81.809572 -229.618358) (xy 81.854034 -229.639456) (xy 81.894537 -229.667412) (xy 81.93003 -229.701504)
			(xy 81.959595 -229.740848) (xy 81.982466 -229.784425) (xy 81.99805 -229.831106) (xy 82.005945 -229.879683)
			(xy 82.00644 -229.90429) (xy 82.324697 -229.90429) (xy 82.328792 -229.853562) (xy 82.340971 -229.804148)
			(xy 82.360919 -229.757328) (xy 82.38812 -229.714314) (xy 82.421868 -229.67622) (xy 82.46129 -229.644033)
			(xy 82.505364 -229.618587) (xy 82.55295 -229.60054) (xy 82.602814 -229.59036) (xy 82.653666 -229.588311)
			(xy 82.704187 -229.594445) (xy 82.753071 -229.608605) (xy 82.79905 -229.630422) (xy 82.840934 -229.659332)
			(xy 82.877638 -229.694587) (xy 82.908211 -229.735273) (xy 82.931862 -229.780336) (xy 82.947978 -229.82861)
			(xy 82.956142 -229.878844) (xy 82.956654 -229.90429) (xy 83.275182 -229.90429) (xy 83.279142 -229.855236)
			(xy 83.290919 -229.807452) (xy 83.31021 -229.762176) (xy 83.336513 -229.72058) (xy 83.369148 -229.683743)
			(xy 83.407269 -229.652618) (xy 83.44989 -229.628011) (xy 83.495906 -229.610559) (xy 83.544125 -229.600715)
			(xy 83.5933 -229.598734) (xy 83.642155 -229.604666) (xy 83.689426 -229.618358) (xy 83.733888 -229.639456)
			(xy 83.774391 -229.667412) (xy 83.809884 -229.701504) (xy 83.839449 -229.740848) (xy 83.86232 -229.784425)
			(xy 83.877904 -229.831106) (xy 83.885799 -229.879683) (xy 83.886294 -229.90429) (xy 84.204805 -229.90429)
			(xy 84.2089 -229.853562) (xy 84.221079 -229.804148) (xy 84.241027 -229.757328) (xy 84.268228 -229.714314)
			(xy 84.301976 -229.67622) (xy 84.341398 -229.644033) (xy 84.385472 -229.618587) (xy 84.433058 -229.60054)
			(xy 84.482922 -229.59036) (xy 84.533774 -229.588311) (xy 84.584295 -229.594445) (xy 84.633179 -229.608605)
			(xy 84.679158 -229.630422) (xy 84.721042 -229.659332) (xy 84.757746 -229.694587) (xy 84.788319 -229.735273)
			(xy 84.81197 -229.780336) (xy 84.828086 -229.82861) (xy 84.83625 -229.878844) (xy 84.836762 -229.90429)
			(xy 85.144859 -229.90429) (xy 85.148954 -229.853562) (xy 85.161133 -229.804148) (xy 85.181081 -229.757328)
			(xy 85.208282 -229.714314) (xy 85.24203 -229.67622) (xy 85.281452 -229.644033) (xy 85.325526 -229.618587)
			(xy 85.373112 -229.60054) (xy 85.422976 -229.59036) (xy 85.473828 -229.588311) (xy 85.524349 -229.594445)
			(xy 85.573233 -229.608605) (xy 85.619212 -229.630422) (xy 85.661096 -229.659332) (xy 85.6978 -229.694587)
			(xy 85.728373 -229.735273) (xy 85.752024 -229.780336) (xy 85.76814 -229.82861) (xy 85.776304 -229.878844)
			(xy 85.776816 -229.90429) (xy 86.095344 -229.90429) (xy 86.099304 -229.855236) (xy 86.111081 -229.807452)
			(xy 86.130372 -229.762176) (xy 86.156675 -229.72058) (xy 86.18931 -229.683743) (xy 86.227431 -229.652618)
			(xy 86.270052 -229.628011) (xy 86.316068 -229.610559) (xy 86.364287 -229.600715) (xy 86.413462 -229.598734)
			(xy 86.462317 -229.604666) (xy 86.509588 -229.618358) (xy 86.55405 -229.639456) (xy 86.594553 -229.667412)
			(xy 86.630046 -229.701504) (xy 86.659611 -229.740848) (xy 86.682482 -229.784425) (xy 86.698066 -229.831106)
			(xy 86.705961 -229.879683) (xy 86.706456 -229.90429) (xy 87.024713 -229.90429) (xy 87.028808 -229.853562)
			(xy 87.040987 -229.804148) (xy 87.060935 -229.757328) (xy 87.088136 -229.714314) (xy 87.121884 -229.67622)
			(xy 87.161306 -229.644033) (xy 87.20538 -229.618587) (xy 87.252966 -229.60054) (xy 87.30283 -229.59036)
			(xy 87.353682 -229.588311) (xy 87.404203 -229.594445) (xy 87.453087 -229.608605) (xy 87.499066 -229.630422)
			(xy 87.54095 -229.659332) (xy 87.577654 -229.694587) (xy 87.608227 -229.735273) (xy 87.631878 -229.780336)
			(xy 87.647994 -229.82861) (xy 87.656158 -229.878844) (xy 87.65667 -229.90429) (xy 87.975198 -229.90429)
			(xy 87.979158 -229.855236) (xy 87.990935 -229.807452) (xy 88.010226 -229.762176) (xy 88.036529 -229.72058)
			(xy 88.069164 -229.683743) (xy 88.107285 -229.652618) (xy 88.149906 -229.628011) (xy 88.195922 -229.610559)
			(xy 88.244141 -229.600715) (xy 88.293316 -229.598734) (xy 88.342171 -229.604666) (xy 88.389442 -229.618358)
			(xy 88.433904 -229.639456) (xy 88.474407 -229.667412) (xy 88.5099 -229.701504) (xy 88.539465 -229.740848)
			(xy 88.562336 -229.784425) (xy 88.57792 -229.831106) (xy 88.585815 -229.879683) (xy 88.58631 -229.90429)
			(xy 88.904821 -229.90429) (xy 88.908916 -229.853562) (xy 88.921095 -229.804148) (xy 88.941043 -229.757328)
			(xy 88.968244 -229.714314) (xy 89.001992 -229.67622) (xy 89.041414 -229.644033) (xy 89.085488 -229.618587)
			(xy 89.133074 -229.60054) (xy 89.182938 -229.59036) (xy 89.23379 -229.588311) (xy 89.284311 -229.594445)
			(xy 89.333195 -229.608605) (xy 89.379174 -229.630422) (xy 89.421058 -229.659332) (xy 89.457762 -229.694587)
			(xy 89.488335 -229.735273) (xy 89.511986 -229.780336) (xy 89.528102 -229.82861) (xy 89.536266 -229.878844)
			(xy 89.536778 -229.90429) (xy 89.855306 -229.90429) (xy 89.859266 -229.855236) (xy 89.871043 -229.807452)
			(xy 89.890334 -229.762176) (xy 89.916637 -229.72058) (xy 89.949272 -229.683743) (xy 89.987393 -229.652618)
			(xy 90.030014 -229.628011) (xy 90.07603 -229.610559) (xy 90.124249 -229.600715) (xy 90.173424 -229.598734)
			(xy 90.222279 -229.604666) (xy 90.26955 -229.618358) (xy 90.314012 -229.639456) (xy 90.354515 -229.667412)
			(xy 90.390008 -229.701504) (xy 90.419573 -229.740848) (xy 90.442444 -229.784425) (xy 90.458028 -229.831106)
			(xy 90.465923 -229.879683) (xy 90.466418 -229.90429) (xy 90.784675 -229.90429) (xy 90.78877 -229.853562)
			(xy 90.800949 -229.804148) (xy 90.820897 -229.757328) (xy 90.848098 -229.714314) (xy 90.881846 -229.67622)
			(xy 90.921268 -229.644033) (xy 90.965342 -229.618587) (xy 91.012928 -229.60054) (xy 91.062792 -229.59036)
			(xy 91.113644 -229.588311) (xy 91.164165 -229.594445) (xy 91.213049 -229.608605) (xy 91.259028 -229.630422)
			(xy 91.300912 -229.659332) (xy 91.337616 -229.694587) (xy 91.368189 -229.735273) (xy 91.39184 -229.780336)
			(xy 91.407956 -229.82861) (xy 91.41612 -229.878844) (xy 91.416632 -229.90429) (xy 91.724729 -229.90429)
			(xy 91.728824 -229.853562) (xy 91.741003 -229.804148) (xy 91.760951 -229.757328) (xy 91.788152 -229.714314)
			(xy 91.8219 -229.67622) (xy 91.861322 -229.644033) (xy 91.905396 -229.618587) (xy 91.952982 -229.60054)
			(xy 92.002846 -229.59036) (xy 92.053698 -229.588311) (xy 92.104219 -229.594445) (xy 92.153103 -229.608605)
			(xy 92.199082 -229.630422) (xy 92.240966 -229.659332) (xy 92.27767 -229.694587) (xy 92.308243 -229.735273)
			(xy 92.331894 -229.780336) (xy 92.34801 -229.82861) (xy 92.356174 -229.878844) (xy 92.356686 -229.90429)
			(xy 92.675214 -229.90429) (xy 92.679174 -229.855236) (xy 92.690951 -229.807452) (xy 92.710242 -229.762176)
			(xy 92.736545 -229.72058) (xy 92.76918 -229.683743) (xy 92.807301 -229.652618) (xy 92.849922 -229.628011)
			(xy 92.895938 -229.610559) (xy 92.944157 -229.600715) (xy 92.993332 -229.598734) (xy 93.042187 -229.604666)
			(xy 93.089458 -229.618358) (xy 93.13392 -229.639456) (xy 93.174423 -229.667412) (xy 93.209916 -229.701504)
			(xy 93.239481 -229.740848) (xy 93.262352 -229.784425) (xy 93.277936 -229.831106) (xy 93.285831 -229.879683)
			(xy 93.286326 -229.90429) (xy 93.604837 -229.90429) (xy 93.608932 -229.853562) (xy 93.621111 -229.804148)
			(xy 93.641059 -229.757328) (xy 93.66826 -229.714314) (xy 93.702008 -229.67622) (xy 93.74143 -229.644033)
			(xy 93.785504 -229.618587) (xy 93.83309 -229.60054) (xy 93.882954 -229.59036) (xy 93.933806 -229.588311)
			(xy 93.984327 -229.594445) (xy 94.033211 -229.608605) (xy 94.07919 -229.630422) (xy 94.121074 -229.659332)
			(xy 94.157778 -229.694587) (xy 94.188351 -229.735273) (xy 94.212002 -229.780336) (xy 94.228118 -229.82861)
			(xy 94.236282 -229.878844) (xy 94.236794 -229.90429) (xy 94.555322 -229.90429) (xy 94.559282 -229.855236)
			(xy 94.571059 -229.807452) (xy 94.59035 -229.762176) (xy 94.616653 -229.72058) (xy 94.649288 -229.683743)
			(xy 94.687409 -229.652618) (xy 94.73003 -229.628011) (xy 94.776046 -229.610559) (xy 94.824265 -229.600715)
			(xy 94.87344 -229.598734) (xy 94.922295 -229.604666) (xy 94.969566 -229.618358) (xy 95.014028 -229.639456)
			(xy 95.054531 -229.667412) (xy 95.090024 -229.701504) (xy 95.119589 -229.740848) (xy 95.14246 -229.784425)
			(xy 95.158044 -229.831106) (xy 95.165939 -229.879683) (xy 95.166434 -229.90429) (xy 95.484691 -229.90429)
			(xy 95.488786 -229.853562) (xy 95.500965 -229.804148) (xy 95.520913 -229.757328) (xy 95.548114 -229.714314)
			(xy 95.581862 -229.67622) (xy 95.621284 -229.644033) (xy 95.665358 -229.618587) (xy 95.712944 -229.60054)
			(xy 95.762808 -229.59036) (xy 95.81366 -229.588311) (xy 95.864181 -229.594445) (xy 95.913065 -229.608605)
			(xy 95.959044 -229.630422) (xy 96.000928 -229.659332) (xy 96.037632 -229.694587) (xy 96.068205 -229.735273)
			(xy 96.091856 -229.780336) (xy 96.107972 -229.82861) (xy 96.116136 -229.878844) (xy 96.116648 -229.90429)
			(xy 96.435176 -229.90429) (xy 96.439136 -229.855236) (xy 96.450913 -229.807452) (xy 96.470204 -229.762176)
			(xy 96.496507 -229.72058) (xy 96.529142 -229.683743) (xy 96.567263 -229.652618) (xy 96.609884 -229.628011)
			(xy 96.6559 -229.610559) (xy 96.704119 -229.600715) (xy 96.753294 -229.598734) (xy 96.802149 -229.604666)
			(xy 96.84942 -229.618358) (xy 96.893882 -229.639456) (xy 96.934385 -229.667412) (xy 96.969878 -229.701504)
			(xy 96.999443 -229.740848) (xy 97.022314 -229.784425) (xy 97.037898 -229.831106) (xy 97.045793 -229.879683)
			(xy 97.046288 -229.90429) (xy 97.364799 -229.90429) (xy 97.368894 -229.853562) (xy 97.381073 -229.804148)
			(xy 97.401021 -229.757328) (xy 97.428222 -229.714314) (xy 97.46197 -229.67622) (xy 97.501392 -229.644033)
			(xy 97.545466 -229.618587) (xy 97.593052 -229.60054) (xy 97.642916 -229.59036) (xy 97.693768 -229.588311)
			(xy 97.744289 -229.594445) (xy 97.793173 -229.608605) (xy 97.839152 -229.630422) (xy 97.881036 -229.659332)
			(xy 97.91774 -229.694587) (xy 97.948313 -229.735273) (xy 97.971964 -229.780336) (xy 97.98808 -229.82861)
			(xy 97.996244 -229.878844) (xy 97.996756 -229.90429) (xy 98.304853 -229.90429) (xy 98.308948 -229.853562)
			(xy 98.321127 -229.804148) (xy 98.341075 -229.757328) (xy 98.368276 -229.714314) (xy 98.402024 -229.67622)
			(xy 98.441446 -229.644033) (xy 98.48552 -229.618587) (xy 98.533106 -229.60054) (xy 98.58297 -229.59036)
			(xy 98.633822 -229.588311) (xy 98.684343 -229.594445) (xy 98.733227 -229.608605) (xy 98.779206 -229.630422)
			(xy 98.82109 -229.659332) (xy 98.857794 -229.694587) (xy 98.888367 -229.735273) (xy 98.912018 -229.780336)
			(xy 98.928134 -229.82861) (xy 98.936298 -229.878844) (xy 98.93681 -229.90429) (xy 99.255338 -229.90429)
			(xy 99.259298 -229.855236) (xy 99.271075 -229.807452) (xy 99.290366 -229.762176) (xy 99.316669 -229.72058)
			(xy 99.349304 -229.683743) (xy 99.387425 -229.652618) (xy 99.430046 -229.628011) (xy 99.476062 -229.610559)
			(xy 99.524281 -229.600715) (xy 99.573456 -229.598734) (xy 99.622311 -229.604666) (xy 99.669582 -229.618358)
			(xy 99.714044 -229.639456) (xy 99.754547 -229.667412) (xy 99.79004 -229.701504) (xy 99.819605 -229.740848)
			(xy 99.842476 -229.784425) (xy 99.85806 -229.831106) (xy 99.865955 -229.879683) (xy 99.86645 -229.90429)
			(xy 100.184707 -229.90429) (xy 100.188802 -229.853562) (xy 100.200981 -229.804148) (xy 100.220929 -229.757328)
			(xy 100.24813 -229.714314) (xy 100.281878 -229.67622) (xy 100.3213 -229.644033) (xy 100.365374 -229.618587)
			(xy 100.41296 -229.60054) (xy 100.462824 -229.59036) (xy 100.513676 -229.588311) (xy 100.564197 -229.594445)
			(xy 100.613081 -229.608605) (xy 100.65906 -229.630422) (xy 100.700944 -229.659332) (xy 100.737648 -229.694587)
			(xy 100.768221 -229.735273) (xy 100.791872 -229.780336) (xy 100.807988 -229.82861) (xy 100.816152 -229.878844)
			(xy 100.816664 -229.90429) (xy 101.124761 -229.90429) (xy 101.128856 -229.853562) (xy 101.141035 -229.804148)
			(xy 101.160983 -229.757328) (xy 101.188184 -229.714314) (xy 101.221932 -229.67622) (xy 101.261354 -229.644033)
			(xy 101.305428 -229.618587) (xy 101.353014 -229.60054) (xy 101.402878 -229.59036) (xy 101.45373 -229.588311)
			(xy 101.504251 -229.594445) (xy 101.553135 -229.608605) (xy 101.599114 -229.630422) (xy 101.640998 -229.659332)
			(xy 101.677702 -229.694587) (xy 101.708275 -229.735273) (xy 101.731926 -229.780336) (xy 101.748042 -229.82861)
			(xy 101.756206 -229.878844) (xy 101.756718 -229.90429) (xy 102.075246 -229.90429) (xy 102.079206 -229.855236)
			(xy 102.090983 -229.807452) (xy 102.110274 -229.762176) (xy 102.136577 -229.72058) (xy 102.169212 -229.683743)
			(xy 102.207333 -229.652618) (xy 102.249954 -229.628011) (xy 102.29597 -229.610559) (xy 102.344189 -229.600715)
			(xy 102.393364 -229.598734) (xy 102.442219 -229.604666) (xy 102.48949 -229.618358) (xy 102.533952 -229.639456)
			(xy 102.574455 -229.667412) (xy 102.609948 -229.701504) (xy 102.639513 -229.740848) (xy 102.662384 -229.784425)
			(xy 102.677968 -229.831106) (xy 102.685863 -229.879683) (xy 102.686358 -229.90429) (xy 103.004869 -229.90429)
			(xy 103.008964 -229.853562) (xy 103.021143 -229.804148) (xy 103.041091 -229.757328) (xy 103.068292 -229.714314)
			(xy 103.10204 -229.67622) (xy 103.141462 -229.644033) (xy 103.185536 -229.618587) (xy 103.233122 -229.60054)
			(xy 103.282986 -229.59036) (xy 103.333838 -229.588311) (xy 103.384359 -229.594445) (xy 103.433243 -229.608605)
			(xy 103.479222 -229.630422) (xy 103.521106 -229.659332) (xy 103.55781 -229.694587) (xy 103.588383 -229.735273)
			(xy 103.612034 -229.780336) (xy 103.62815 -229.82861) (xy 103.636314 -229.878844) (xy 103.636826 -229.90429)
			(xy 103.944923 -229.90429) (xy 103.949018 -229.853562) (xy 103.961197 -229.804148) (xy 103.981145 -229.757328)
			(xy 104.008346 -229.714314) (xy 104.042094 -229.67622) (xy 104.081516 -229.644033) (xy 104.12559 -229.618587)
			(xy 104.173176 -229.60054) (xy 104.22304 -229.59036) (xy 104.273892 -229.588311) (xy 104.324413 -229.594445)
			(xy 104.373297 -229.608605) (xy 104.419276 -229.630422) (xy 104.46116 -229.659332) (xy 104.497864 -229.694587)
			(xy 104.528437 -229.735273) (xy 104.552088 -229.780336) (xy 104.568204 -229.82861) (xy 104.576368 -229.878844)
			(xy 104.57688 -229.90429) (xy 104.895154 -229.90429) (xy 104.899114 -229.855236) (xy 104.910891 -229.807452)
			(xy 104.930182 -229.762176) (xy 104.956485 -229.72058) (xy 104.98912 -229.683743) (xy 105.027241 -229.652618)
			(xy 105.069862 -229.628011) (xy 105.115878 -229.610559) (xy 105.164097 -229.600715) (xy 105.213272 -229.598734)
			(xy 105.262127 -229.604666) (xy 105.309398 -229.618358) (xy 105.35386 -229.639456) (xy 105.394363 -229.667412)
			(xy 105.429856 -229.701504) (xy 105.459421 -229.740848) (xy 105.482292 -229.784425) (xy 105.497876 -229.831106)
			(xy 105.505771 -229.879683) (xy 105.506266 -229.90429) (xy 105.824777 -229.90429) (xy 105.828872 -229.853562)
			(xy 105.841051 -229.804148) (xy 105.860999 -229.757328) (xy 105.8882 -229.714314) (xy 105.921948 -229.67622)
			(xy 105.96137 -229.644033) (xy 106.005444 -229.618587) (xy 106.05303 -229.60054) (xy 106.102894 -229.59036)
			(xy 106.153746 -229.588311) (xy 106.204267 -229.594445) (xy 106.253151 -229.608605) (xy 106.29913 -229.630422)
			(xy 106.341014 -229.659332) (xy 106.377718 -229.694587) (xy 106.408291 -229.735273) (xy 106.431942 -229.780336)
			(xy 106.448058 -229.82861) (xy 106.456222 -229.878844) (xy 106.456734 -229.90429) (xy 106.764831 -229.90429)
			(xy 106.768926 -229.853562) (xy 106.781105 -229.804148) (xy 106.801053 -229.757328) (xy 106.828254 -229.714314)
			(xy 106.862002 -229.67622) (xy 106.901424 -229.644033) (xy 106.945498 -229.618587) (xy 106.993084 -229.60054)
			(xy 107.042948 -229.59036) (xy 107.0938 -229.588311) (xy 107.144321 -229.594445) (xy 107.193205 -229.608605)
			(xy 107.239184 -229.630422) (xy 107.281068 -229.659332) (xy 107.317772 -229.694587) (xy 107.348345 -229.735273)
			(xy 107.371996 -229.780336) (xy 107.388112 -229.82861) (xy 107.396276 -229.878844) (xy 107.396788 -229.90429)
			(xy 107.715316 -229.90429) (xy 107.719276 -229.855236) (xy 107.731053 -229.807452) (xy 107.750344 -229.762176)
			(xy 107.776647 -229.72058) (xy 107.809282 -229.683743) (xy 107.847403 -229.652618) (xy 107.890024 -229.628011)
			(xy 107.93604 -229.610559) (xy 107.984259 -229.600715) (xy 108.033434 -229.598734) (xy 108.082289 -229.604666)
			(xy 108.12956 -229.618358) (xy 108.174022 -229.639456) (xy 108.214525 -229.667412) (xy 108.250018 -229.701504)
			(xy 108.279583 -229.740848) (xy 108.302454 -229.784425) (xy 108.318038 -229.831106) (xy 108.325933 -229.879683)
			(xy 108.326428 -229.90429) (xy 108.65537 -229.90429) (xy 108.65933 -229.855236) (xy 108.671107 -229.807452)
			(xy 108.690398 -229.762176) (xy 108.716701 -229.72058) (xy 108.749336 -229.683743) (xy 108.787457 -229.652618)
			(xy 108.830078 -229.628011) (xy 108.876094 -229.610559) (xy 108.924313 -229.600715) (xy 108.973488 -229.598734)
			(xy 109.022343 -229.604666) (xy 109.069614 -229.618358) (xy 109.114076 -229.639456) (xy 109.154579 -229.667412)
			(xy 109.190072 -229.701504) (xy 109.219637 -229.740848) (xy 109.242508 -229.784425) (xy 109.258092 -229.831106)
			(xy 109.265987 -229.879683) (xy 109.266482 -229.90429) (xy 109.59517 -229.90429) (xy 109.59913 -229.855236)
			(xy 109.610907 -229.807452) (xy 109.630198 -229.762176) (xy 109.656501 -229.72058) (xy 109.689136 -229.683743)
			(xy 109.727257 -229.652618) (xy 109.769878 -229.628011) (xy 109.815894 -229.610559) (xy 109.864113 -229.600715)
			(xy 109.913288 -229.598734) (xy 109.962143 -229.604666) (xy 110.009414 -229.618358) (xy 110.053876 -229.639456)
			(xy 110.094379 -229.667412) (xy 110.129872 -229.701504) (xy 110.159437 -229.740848) (xy 110.182308 -229.784425)
			(xy 110.197892 -229.831106) (xy 110.205787 -229.879683) (xy 110.206282 -229.90429) (xy 110.205787 -229.928897)
			(xy 110.197892 -229.977474) (xy 110.182308 -230.024155) (xy 110.159437 -230.067732) (xy 110.129872 -230.107076)
			(xy 110.094379 -230.141168) (xy 110.053876 -230.169124) (xy 110.009414 -230.190222) (xy 109.962143 -230.203914)
			(xy 109.913288 -230.209846) (xy 109.864113 -230.207865) (xy 109.815894 -230.198021) (xy 109.769878 -230.180569)
			(xy 109.727257 -230.155962) (xy 109.689136 -230.124837) (xy 109.656501 -230.088) (xy 109.630198 -230.046404)
			(xy 109.610907 -230.001128) (xy 109.59913 -229.953344) (xy 109.59517 -229.90429) (xy 109.266482 -229.90429)
			(xy 109.265987 -229.928897) (xy 109.258092 -229.977474) (xy 109.242508 -230.024155) (xy 109.219637 -230.067732)
			(xy 109.190072 -230.107076) (xy 109.154579 -230.141168) (xy 109.114076 -230.169124) (xy 109.069614 -230.190222)
			(xy 109.022343 -230.203914) (xy 108.973488 -230.209846) (xy 108.924313 -230.207865) (xy 108.876094 -230.198021)
			(xy 108.830078 -230.180569) (xy 108.787457 -230.155962) (xy 108.749336 -230.124837) (xy 108.716701 -230.088)
			(xy 108.690398 -230.046404) (xy 108.671107 -230.001128) (xy 108.65933 -229.953344) (xy 108.65537 -229.90429)
			(xy 108.326428 -229.90429) (xy 108.325933 -229.928897) (xy 108.318038 -229.977474) (xy 108.302454 -230.024155)
			(xy 108.279583 -230.067732) (xy 108.250018 -230.107076) (xy 108.214525 -230.141168) (xy 108.174022 -230.169124)
			(xy 108.12956 -230.190222) (xy 108.082289 -230.203914) (xy 108.033434 -230.209846) (xy 107.984259 -230.207865)
			(xy 107.93604 -230.198021) (xy 107.890024 -230.180569) (xy 107.847403 -230.155962) (xy 107.809282 -230.124837)
			(xy 107.776647 -230.088) (xy 107.750344 -230.046404) (xy 107.731053 -230.001128) (xy 107.719276 -229.953344)
			(xy 107.715316 -229.90429) (xy 107.396788 -229.90429) (xy 107.396276 -229.929736) (xy 107.388112 -229.97997)
			(xy 107.371996 -230.028244) (xy 107.348345 -230.073307) (xy 107.317772 -230.113993) (xy 107.281068 -230.149248)
			(xy 107.239184 -230.178158) (xy 107.193205 -230.199975) (xy 107.144321 -230.214135) (xy 107.0938 -230.220269)
			(xy 107.042948 -230.21822) (xy 106.993084 -230.20804) (xy 106.945498 -230.189993) (xy 106.901424 -230.164547)
			(xy 106.862002 -230.13236) (xy 106.828254 -230.094266) (xy 106.801053 -230.051252) (xy 106.781105 -230.004432)
			(xy 106.768926 -229.955018) (xy 106.764831 -229.90429) (xy 106.456734 -229.90429) (xy 106.456222 -229.929736)
			(xy 106.448058 -229.97997) (xy 106.431942 -230.028244) (xy 106.408291 -230.073307) (xy 106.377718 -230.113993)
			(xy 106.341014 -230.149248) (xy 106.29913 -230.178158) (xy 106.253151 -230.199975) (xy 106.204267 -230.214135)
			(xy 106.153746 -230.220269) (xy 106.102894 -230.21822) (xy 106.05303 -230.20804) (xy 106.005444 -230.189993)
			(xy 105.96137 -230.164547) (xy 105.921948 -230.13236) (xy 105.8882 -230.094266) (xy 105.860999 -230.051252)
			(xy 105.841051 -230.004432) (xy 105.828872 -229.955018) (xy 105.824777 -229.90429) (xy 105.506266 -229.90429)
			(xy 105.505771 -229.928897) (xy 105.497876 -229.977474) (xy 105.482292 -230.024155) (xy 105.459421 -230.067732)
			(xy 105.429856 -230.107076) (xy 105.394363 -230.141168) (xy 105.35386 -230.169124) (xy 105.309398 -230.190222)
			(xy 105.262127 -230.203914) (xy 105.213272 -230.209846) (xy 105.164097 -230.207865) (xy 105.115878 -230.198021)
			(xy 105.069862 -230.180569) (xy 105.027241 -230.155962) (xy 104.98912 -230.124837) (xy 104.956485 -230.088)
			(xy 104.930182 -230.046404) (xy 104.910891 -230.001128) (xy 104.899114 -229.953344) (xy 104.895154 -229.90429)
			(xy 104.57688 -229.90429) (xy 104.576368 -229.929736) (xy 104.568204 -229.97997) (xy 104.552088 -230.028244)
			(xy 104.528437 -230.073307) (xy 104.497864 -230.113993) (xy 104.46116 -230.149248) (xy 104.419276 -230.178158)
			(xy 104.373297 -230.199975) (xy 104.324413 -230.214135) (xy 104.273892 -230.220269) (xy 104.22304 -230.21822)
			(xy 104.173176 -230.20804) (xy 104.12559 -230.189993) (xy 104.081516 -230.164547) (xy 104.042094 -230.13236)
			(xy 104.008346 -230.094266) (xy 103.981145 -230.051252) (xy 103.961197 -230.004432) (xy 103.949018 -229.955018)
			(xy 103.944923 -229.90429) (xy 103.636826 -229.90429) (xy 103.636314 -229.929736) (xy 103.62815 -229.97997)
			(xy 103.612034 -230.028244) (xy 103.588383 -230.073307) (xy 103.55781 -230.113993) (xy 103.521106 -230.149248)
			(xy 103.479222 -230.178158) (xy 103.433243 -230.199975) (xy 103.384359 -230.214135) (xy 103.333838 -230.220269)
			(xy 103.282986 -230.21822) (xy 103.233122 -230.20804) (xy 103.185536 -230.189993) (xy 103.141462 -230.164547)
			(xy 103.10204 -230.13236) (xy 103.068292 -230.094266) (xy 103.041091 -230.051252) (xy 103.021143 -230.004432)
			(xy 103.008964 -229.955018) (xy 103.004869 -229.90429) (xy 102.686358 -229.90429) (xy 102.685863 -229.928897)
			(xy 102.677968 -229.977474) (xy 102.662384 -230.024155) (xy 102.639513 -230.067732) (xy 102.609948 -230.107076)
			(xy 102.574455 -230.141168) (xy 102.533952 -230.169124) (xy 102.48949 -230.190222) (xy 102.442219 -230.203914)
			(xy 102.393364 -230.209846) (xy 102.344189 -230.207865) (xy 102.29597 -230.198021) (xy 102.249954 -230.180569)
			(xy 102.207333 -230.155962) (xy 102.169212 -230.124837) (xy 102.136577 -230.088) (xy 102.110274 -230.046404)
			(xy 102.090983 -230.001128) (xy 102.079206 -229.953344) (xy 102.075246 -229.90429) (xy 101.756718 -229.90429)
			(xy 101.756206 -229.929736) (xy 101.748042 -229.97997) (xy 101.731926 -230.028244) (xy 101.708275 -230.073307)
			(xy 101.677702 -230.113993) (xy 101.640998 -230.149248) (xy 101.599114 -230.178158) (xy 101.553135 -230.199975)
			(xy 101.504251 -230.214135) (xy 101.45373 -230.220269) (xy 101.402878 -230.21822) (xy 101.353014 -230.20804)
			(xy 101.305428 -230.189993) (xy 101.261354 -230.164547) (xy 101.221932 -230.13236) (xy 101.188184 -230.094266)
			(xy 101.160983 -230.051252) (xy 101.141035 -230.004432) (xy 101.128856 -229.955018) (xy 101.124761 -229.90429)
			(xy 100.816664 -229.90429) (xy 100.816152 -229.929736) (xy 100.807988 -229.97997) (xy 100.791872 -230.028244)
			(xy 100.768221 -230.073307) (xy 100.737648 -230.113993) (xy 100.700944 -230.149248) (xy 100.65906 -230.178158)
			(xy 100.613081 -230.199975) (xy 100.564197 -230.214135) (xy 100.513676 -230.220269) (xy 100.462824 -230.21822)
			(xy 100.41296 -230.20804) (xy 100.365374 -230.189993) (xy 100.3213 -230.164547) (xy 100.281878 -230.13236)
			(xy 100.24813 -230.094266) (xy 100.220929 -230.051252) (xy 100.200981 -230.004432) (xy 100.188802 -229.955018)
			(xy 100.184707 -229.90429) (xy 99.86645 -229.90429) (xy 99.865955 -229.928897) (xy 99.85806 -229.977474)
			(xy 99.842476 -230.024155) (xy 99.819605 -230.067732) (xy 99.79004 -230.107076) (xy 99.754547 -230.141168)
			(xy 99.714044 -230.169124) (xy 99.669582 -230.190222) (xy 99.622311 -230.203914) (xy 99.573456 -230.209846)
			(xy 99.524281 -230.207865) (xy 99.476062 -230.198021) (xy 99.430046 -230.180569) (xy 99.387425 -230.155962)
			(xy 99.349304 -230.124837) (xy 99.316669 -230.088) (xy 99.290366 -230.046404) (xy 99.271075 -230.001128)
			(xy 99.259298 -229.953344) (xy 99.255338 -229.90429) (xy 98.93681 -229.90429) (xy 98.936298 -229.929736)
			(xy 98.928134 -229.97997) (xy 98.912018 -230.028244) (xy 98.888367 -230.073307) (xy 98.857794 -230.113993)
			(xy 98.82109 -230.149248) (xy 98.779206 -230.178158) (xy 98.733227 -230.199975) (xy 98.684343 -230.214135)
			(xy 98.633822 -230.220269) (xy 98.58297 -230.21822) (xy 98.533106 -230.20804) (xy 98.48552 -230.189993)
			(xy 98.441446 -230.164547) (xy 98.402024 -230.13236) (xy 98.368276 -230.094266) (xy 98.341075 -230.051252)
			(xy 98.321127 -230.004432) (xy 98.308948 -229.955018) (xy 98.304853 -229.90429) (xy 97.996756 -229.90429)
			(xy 97.996244 -229.929736) (xy 97.98808 -229.97997) (xy 97.971964 -230.028244) (xy 97.948313 -230.073307)
			(xy 97.91774 -230.113993) (xy 97.881036 -230.149248) (xy 97.839152 -230.178158) (xy 97.793173 -230.199975)
			(xy 97.744289 -230.214135) (xy 97.693768 -230.220269) (xy 97.642916 -230.21822) (xy 97.593052 -230.20804)
			(xy 97.545466 -230.189993) (xy 97.501392 -230.164547) (xy 97.46197 -230.13236) (xy 97.428222 -230.094266)
			(xy 97.401021 -230.051252) (xy 97.381073 -230.004432) (xy 97.368894 -229.955018) (xy 97.364799 -229.90429)
			(xy 97.046288 -229.90429) (xy 97.045793 -229.928897) (xy 97.037898 -229.977474) (xy 97.022314 -230.024155)
			(xy 96.999443 -230.067732) (xy 96.969878 -230.107076) (xy 96.934385 -230.141168) (xy 96.893882 -230.169124)
			(xy 96.84942 -230.190222) (xy 96.802149 -230.203914) (xy 96.753294 -230.209846) (xy 96.704119 -230.207865)
			(xy 96.6559 -230.198021) (xy 96.609884 -230.180569) (xy 96.567263 -230.155962) (xy 96.529142 -230.124837)
			(xy 96.496507 -230.088) (xy 96.470204 -230.046404) (xy 96.450913 -230.001128) (xy 96.439136 -229.953344)
			(xy 96.435176 -229.90429) (xy 96.116648 -229.90429) (xy 96.116136 -229.929736) (xy 96.107972 -229.97997)
			(xy 96.091856 -230.028244) (xy 96.068205 -230.073307) (xy 96.037632 -230.113993) (xy 96.000928 -230.149248)
			(xy 95.959044 -230.178158) (xy 95.913065 -230.199975) (xy 95.864181 -230.214135) (xy 95.81366 -230.220269)
			(xy 95.762808 -230.21822) (xy 95.712944 -230.20804) (xy 95.665358 -230.189993) (xy 95.621284 -230.164547)
			(xy 95.581862 -230.13236) (xy 95.548114 -230.094266) (xy 95.520913 -230.051252) (xy 95.500965 -230.004432)
			(xy 95.488786 -229.955018) (xy 95.484691 -229.90429) (xy 95.166434 -229.90429) (xy 95.165939 -229.928897)
			(xy 95.158044 -229.977474) (xy 95.14246 -230.024155) (xy 95.119589 -230.067732) (xy 95.090024 -230.107076)
			(xy 95.054531 -230.141168) (xy 95.014028 -230.169124) (xy 94.969566 -230.190222) (xy 94.922295 -230.203914)
			(xy 94.87344 -230.209846) (xy 94.824265 -230.207865) (xy 94.776046 -230.198021) (xy 94.73003 -230.180569)
			(xy 94.687409 -230.155962) (xy 94.649288 -230.124837) (xy 94.616653 -230.088) (xy 94.59035 -230.046404)
			(xy 94.571059 -230.001128) (xy 94.559282 -229.953344) (xy 94.555322 -229.90429) (xy 94.236794 -229.90429)
			(xy 94.236282 -229.929736) (xy 94.228118 -229.97997) (xy 94.212002 -230.028244) (xy 94.188351 -230.073307)
			(xy 94.157778 -230.113993) (xy 94.121074 -230.149248) (xy 94.07919 -230.178158) (xy 94.033211 -230.199975)
			(xy 93.984327 -230.214135) (xy 93.933806 -230.220269) (xy 93.882954 -230.21822) (xy 93.83309 -230.20804)
			(xy 93.785504 -230.189993) (xy 93.74143 -230.164547) (xy 93.702008 -230.13236) (xy 93.66826 -230.094266)
			(xy 93.641059 -230.051252) (xy 93.621111 -230.004432) (xy 93.608932 -229.955018) (xy 93.604837 -229.90429)
			(xy 93.286326 -229.90429) (xy 93.285831 -229.928897) (xy 93.277936 -229.977474) (xy 93.262352 -230.024155)
			(xy 93.239481 -230.067732) (xy 93.209916 -230.107076) (xy 93.174423 -230.141168) (xy 93.13392 -230.169124)
			(xy 93.089458 -230.190222) (xy 93.042187 -230.203914) (xy 92.993332 -230.209846) (xy 92.944157 -230.207865)
			(xy 92.895938 -230.198021) (xy 92.849922 -230.180569) (xy 92.807301 -230.155962) (xy 92.76918 -230.124837)
			(xy 92.736545 -230.088) (xy 92.710242 -230.046404) (xy 92.690951 -230.001128) (xy 92.679174 -229.953344)
			(xy 92.675214 -229.90429) (xy 92.356686 -229.90429) (xy 92.356174 -229.929736) (xy 92.34801 -229.97997)
			(xy 92.331894 -230.028244) (xy 92.308243 -230.073307) (xy 92.27767 -230.113993) (xy 92.240966 -230.149248)
			(xy 92.199082 -230.178158) (xy 92.153103 -230.199975) (xy 92.104219 -230.214135) (xy 92.053698 -230.220269)
			(xy 92.002846 -230.21822) (xy 91.952982 -230.20804) (xy 91.905396 -230.189993) (xy 91.861322 -230.164547)
			(xy 91.8219 -230.13236) (xy 91.788152 -230.094266) (xy 91.760951 -230.051252) (xy 91.741003 -230.004432)
			(xy 91.728824 -229.955018) (xy 91.724729 -229.90429) (xy 91.416632 -229.90429) (xy 91.41612 -229.929736)
			(xy 91.407956 -229.97997) (xy 91.39184 -230.028244) (xy 91.368189 -230.073307) (xy 91.337616 -230.113993)
			(xy 91.300912 -230.149248) (xy 91.259028 -230.178158) (xy 91.213049 -230.199975) (xy 91.164165 -230.214135)
			(xy 91.113644 -230.220269) (xy 91.062792 -230.21822) (xy 91.012928 -230.20804) (xy 90.965342 -230.189993)
			(xy 90.921268 -230.164547) (xy 90.881846 -230.13236) (xy 90.848098 -230.094266) (xy 90.820897 -230.051252)
			(xy 90.800949 -230.004432) (xy 90.78877 -229.955018) (xy 90.784675 -229.90429) (xy 90.466418 -229.90429)
			(xy 90.465923 -229.928897) (xy 90.458028 -229.977474) (xy 90.442444 -230.024155) (xy 90.419573 -230.067732)
			(xy 90.390008 -230.107076) (xy 90.354515 -230.141168) (xy 90.314012 -230.169124) (xy 90.26955 -230.190222)
			(xy 90.222279 -230.203914) (xy 90.173424 -230.209846) (xy 90.124249 -230.207865) (xy 90.07603 -230.198021)
			(xy 90.030014 -230.180569) (xy 89.987393 -230.155962) (xy 89.949272 -230.124837) (xy 89.916637 -230.088)
			(xy 89.890334 -230.046404) (xy 89.871043 -230.001128) (xy 89.859266 -229.953344) (xy 89.855306 -229.90429)
			(xy 89.536778 -229.90429) (xy 89.536266 -229.929736) (xy 89.528102 -229.97997) (xy 89.511986 -230.028244)
			(xy 89.488335 -230.073307) (xy 89.457762 -230.113993) (xy 89.421058 -230.149248) (xy 89.379174 -230.178158)
			(xy 89.333195 -230.199975) (xy 89.284311 -230.214135) (xy 89.23379 -230.220269) (xy 89.182938 -230.21822)
			(xy 89.133074 -230.20804) (xy 89.085488 -230.189993) (xy 89.041414 -230.164547) (xy 89.001992 -230.13236)
			(xy 88.968244 -230.094266) (xy 88.941043 -230.051252) (xy 88.921095 -230.004432) (xy 88.908916 -229.955018)
			(xy 88.904821 -229.90429) (xy 88.58631 -229.90429) (xy 88.585815 -229.928897) (xy 88.57792 -229.977474)
			(xy 88.562336 -230.024155) (xy 88.539465 -230.067732) (xy 88.5099 -230.107076) (xy 88.474407 -230.141168)
			(xy 88.433904 -230.169124) (xy 88.389442 -230.190222) (xy 88.342171 -230.203914) (xy 88.293316 -230.209846)
			(xy 88.244141 -230.207865) (xy 88.195922 -230.198021) (xy 88.149906 -230.180569) (xy 88.107285 -230.155962)
			(xy 88.069164 -230.124837) (xy 88.036529 -230.088) (xy 88.010226 -230.046404) (xy 87.990935 -230.001128)
			(xy 87.979158 -229.953344) (xy 87.975198 -229.90429) (xy 87.65667 -229.90429) (xy 87.656158 -229.929736)
			(xy 87.647994 -229.97997) (xy 87.631878 -230.028244) (xy 87.608227 -230.073307) (xy 87.577654 -230.113993)
			(xy 87.54095 -230.149248) (xy 87.499066 -230.178158) (xy 87.453087 -230.199975) (xy 87.404203 -230.214135)
			(xy 87.353682 -230.220269) (xy 87.30283 -230.21822) (xy 87.252966 -230.20804) (xy 87.20538 -230.189993)
			(xy 87.161306 -230.164547) (xy 87.121884 -230.13236) (xy 87.088136 -230.094266) (xy 87.060935 -230.051252)
			(xy 87.040987 -230.004432) (xy 87.028808 -229.955018) (xy 87.024713 -229.90429) (xy 86.706456 -229.90429)
			(xy 86.705961 -229.928897) (xy 86.698066 -229.977474) (xy 86.682482 -230.024155) (xy 86.659611 -230.067732)
			(xy 86.630046 -230.107076) (xy 86.594553 -230.141168) (xy 86.55405 -230.169124) (xy 86.509588 -230.190222)
			(xy 86.462317 -230.203914) (xy 86.413462 -230.209846) (xy 86.364287 -230.207865) (xy 86.316068 -230.198021)
			(xy 86.270052 -230.180569) (xy 86.227431 -230.155962) (xy 86.18931 -230.124837) (xy 86.156675 -230.088)
			(xy 86.130372 -230.046404) (xy 86.111081 -230.001128) (xy 86.099304 -229.953344) (xy 86.095344 -229.90429)
			(xy 85.776816 -229.90429) (xy 85.776304 -229.929736) (xy 85.76814 -229.97997) (xy 85.752024 -230.028244)
			(xy 85.728373 -230.073307) (xy 85.6978 -230.113993) (xy 85.661096 -230.149248) (xy 85.619212 -230.178158)
			(xy 85.573233 -230.199975) (xy 85.524349 -230.214135) (xy 85.473828 -230.220269) (xy 85.422976 -230.21822)
			(xy 85.373112 -230.20804) (xy 85.325526 -230.189993) (xy 85.281452 -230.164547) (xy 85.24203 -230.13236)
			(xy 85.208282 -230.094266) (xy 85.181081 -230.051252) (xy 85.161133 -230.004432) (xy 85.148954 -229.955018)
			(xy 85.144859 -229.90429) (xy 84.836762 -229.90429) (xy 84.83625 -229.929736) (xy 84.828086 -229.97997)
			(xy 84.81197 -230.028244) (xy 84.788319 -230.073307) (xy 84.757746 -230.113993) (xy 84.721042 -230.149248)
			(xy 84.679158 -230.178158) (xy 84.633179 -230.199975) (xy 84.584295 -230.214135) (xy 84.533774 -230.220269)
			(xy 84.482922 -230.21822) (xy 84.433058 -230.20804) (xy 84.385472 -230.189993) (xy 84.341398 -230.164547)
			(xy 84.301976 -230.13236) (xy 84.268228 -230.094266) (xy 84.241027 -230.051252) (xy 84.221079 -230.004432)
			(xy 84.2089 -229.955018) (xy 84.204805 -229.90429) (xy 83.886294 -229.90429) (xy 83.885799 -229.928897)
			(xy 83.877904 -229.977474) (xy 83.86232 -230.024155) (xy 83.839449 -230.067732) (xy 83.809884 -230.107076)
			(xy 83.774391 -230.141168) (xy 83.733888 -230.169124) (xy 83.689426 -230.190222) (xy 83.642155 -230.203914)
			(xy 83.5933 -230.209846) (xy 83.544125 -230.207865) (xy 83.495906 -230.198021) (xy 83.44989 -230.180569)
			(xy 83.407269 -230.155962) (xy 83.369148 -230.124837) (xy 83.336513 -230.088) (xy 83.31021 -230.046404)
			(xy 83.290919 -230.001128) (xy 83.279142 -229.953344) (xy 83.275182 -229.90429) (xy 82.956654 -229.90429)
			(xy 82.956142 -229.929736) (xy 82.947978 -229.97997) (xy 82.931862 -230.028244) (xy 82.908211 -230.073307)
			(xy 82.877638 -230.113993) (xy 82.840934 -230.149248) (xy 82.79905 -230.178158) (xy 82.753071 -230.199975)
			(xy 82.704187 -230.214135) (xy 82.653666 -230.220269) (xy 82.602814 -230.21822) (xy 82.55295 -230.20804)
			(xy 82.505364 -230.189993) (xy 82.46129 -230.164547) (xy 82.421868 -230.13236) (xy 82.38812 -230.094266)
			(xy 82.360919 -230.051252) (xy 82.340971 -230.004432) (xy 82.328792 -229.955018) (xy 82.324697 -229.90429)
			(xy 82.00644 -229.90429) (xy 82.005945 -229.928897) (xy 81.99805 -229.977474) (xy 81.982466 -230.024155)
			(xy 81.959595 -230.067732) (xy 81.93003 -230.107076) (xy 81.894537 -230.141168) (xy 81.854034 -230.169124)
			(xy 81.809572 -230.190222) (xy 81.762301 -230.203914) (xy 81.713446 -230.209846) (xy 81.664271 -230.207865)
			(xy 81.616052 -230.198021) (xy 81.570036 -230.180569) (xy 81.527415 -230.155962) (xy 81.489294 -230.124837)
			(xy 81.456659 -230.088) (xy 81.430356 -230.046404) (xy 81.411065 -230.001128) (xy 81.399288 -229.953344)
			(xy 81.395328 -229.90429) (xy 81.0768 -229.90429) (xy 81.076288 -229.929736) (xy 81.068124 -229.97997)
			(xy 81.052008 -230.028244) (xy 81.028357 -230.073307) (xy 80.997784 -230.113993) (xy 80.96108 -230.149248)
			(xy 80.919196 -230.178158) (xy 80.873217 -230.199975) (xy 80.824333 -230.214135) (xy 80.773812 -230.220269)
			(xy 80.72296 -230.21822) (xy 80.673096 -230.20804) (xy 80.62551 -230.189993) (xy 80.581436 -230.164547)
			(xy 80.542014 -230.13236) (xy 80.508266 -230.094266) (xy 80.481065 -230.051252) (xy 80.461117 -230.004432)
			(xy 80.448938 -229.955018) (xy 80.444843 -229.90429) (xy 80.126332 -229.90429) (xy 80.125837 -229.928897)
			(xy 80.117942 -229.977474) (xy 80.102358 -230.024155) (xy 80.079487 -230.067732) (xy 80.049922 -230.107076)
			(xy 80.014429 -230.141168) (xy 79.973926 -230.169124) (xy 79.929464 -230.190222) (xy 79.882193 -230.203914)
			(xy 79.833338 -230.209846) (xy 79.784163 -230.207865) (xy 79.735944 -230.198021) (xy 79.689928 -230.180569)
			(xy 79.647307 -230.155962) (xy 79.609186 -230.124837) (xy 79.576551 -230.088) (xy 79.550248 -230.046404)
			(xy 79.530957 -230.001128) (xy 79.51918 -229.953344) (xy 79.51522 -229.90429) (xy 76.963477 -229.90429)
			(xy 76.965804 -229.905394) (xy 77.006307 -229.93335) (xy 77.0418 -229.967442) (xy 77.071365 -230.006786)
			(xy 77.094236 -230.050363) (xy 77.10982 -230.097044) (xy 77.117715 -230.145621) (xy 77.11821 -230.170228)
			(xy 77.117715 -230.194835) (xy 77.10982 -230.243412) (xy 77.094236 -230.290093) (xy 77.071365 -230.33367)
			(xy 77.0418 -230.373014) (xy 77.006307 -230.407106) (xy 76.965804 -230.435062) (xy 76.921342 -230.45616)
			(xy 76.874071 -230.469852) (xy 76.825216 -230.475784) (xy 76.776041 -230.473803) (xy 76.727822 -230.463959)
			(xy 76.681806 -230.446507) (xy 76.639185 -230.4219) (xy 76.601064 -230.390775) (xy 76.568429 -230.353938)
			(xy 76.542126 -230.312342) (xy 76.522835 -230.267066) (xy 76.511058 -230.219282) (xy 76.507098 -230.170228)
			(xy 62.37732 -230.170228) (xy 62.37732 -230.71455) (xy 78.105266 -230.71455) (xy 78.109226 -230.665496)
			(xy 78.121003 -230.617712) (xy 78.140294 -230.572436) (xy 78.166597 -230.53084) (xy 78.199232 -230.494003)
			(xy 78.237353 -230.462878) (xy 78.279974 -230.438271) (xy 78.32599 -230.420819) (xy 78.374209 -230.410975)
			(xy 78.423384 -230.408994) (xy 78.472239 -230.414926) (xy 78.51951 -230.428618) (xy 78.563972 -230.449716)
			(xy 78.604475 -230.477672) (xy 78.639968 -230.511764) (xy 78.669533 -230.551108) (xy 78.692404 -230.594685)
			(xy 78.707988 -230.641366) (xy 78.715883 -230.689943) (xy 78.716378 -230.71455) (xy 79.985374 -230.71455)
			(xy 79.989334 -230.665496) (xy 80.001111 -230.617712) (xy 80.020402 -230.572436) (xy 80.046705 -230.53084)
			(xy 80.07934 -230.494003) (xy 80.117461 -230.462878) (xy 80.160082 -230.438271) (xy 80.206098 -230.420819)
			(xy 80.254317 -230.410975) (xy 80.303492 -230.408994) (xy 80.352347 -230.414926) (xy 80.399618 -230.428618)
			(xy 80.44408 -230.449716) (xy 80.484583 -230.477672) (xy 80.520076 -230.511764) (xy 80.549641 -230.551108)
			(xy 80.572512 -230.594685) (xy 80.588096 -230.641366) (xy 80.595991 -230.689943) (xy 80.596486 -230.71455)
			(xy 80.914743 -230.71455) (xy 80.918838 -230.663822) (xy 80.931017 -230.614408) (xy 80.950965 -230.567588)
			(xy 80.978166 -230.524574) (xy 81.011914 -230.48648) (xy 81.051336 -230.454293) (xy 81.09541 -230.428847)
			(xy 81.142996 -230.4108) (xy 81.19286 -230.40062) (xy 81.243712 -230.398571) (xy 81.294233 -230.404705)
			(xy 81.343117 -230.418865) (xy 81.389096 -230.440682) (xy 81.43098 -230.469592) (xy 81.467684 -230.504847)
			(xy 81.498257 -230.545533) (xy 81.521908 -230.590596) (xy 81.538024 -230.63887) (xy 81.546188 -230.689104)
			(xy 81.5467 -230.71455) (xy 81.854797 -230.71455) (xy 81.858892 -230.663822) (xy 81.871071 -230.614408)
			(xy 81.891019 -230.567588) (xy 81.91822 -230.524574) (xy 81.951968 -230.48648) (xy 81.99139 -230.454293)
			(xy 82.035464 -230.428847) (xy 82.08305 -230.4108) (xy 82.132914 -230.40062) (xy 82.183766 -230.398571)
			(xy 82.234287 -230.404705) (xy 82.283171 -230.418865) (xy 82.32915 -230.440682) (xy 82.371034 -230.469592)
			(xy 82.407738 -230.504847) (xy 82.438311 -230.545533) (xy 82.461962 -230.590596) (xy 82.478078 -230.63887)
			(xy 82.486242 -230.689104) (xy 82.486754 -230.71455) (xy 82.805282 -230.71455) (xy 82.809242 -230.665496)
			(xy 82.821019 -230.617712) (xy 82.84031 -230.572436) (xy 82.866613 -230.53084) (xy 82.899248 -230.494003)
			(xy 82.937369 -230.462878) (xy 82.97999 -230.438271) (xy 83.026006 -230.420819) (xy 83.074225 -230.410975)
			(xy 83.1234 -230.408994) (xy 83.172255 -230.414926) (xy 83.219526 -230.428618) (xy 83.263988 -230.449716)
			(xy 83.304491 -230.477672) (xy 83.339984 -230.511764) (xy 83.369549 -230.551108) (xy 83.39242 -230.594685)
			(xy 83.408004 -230.641366) (xy 83.415899 -230.689943) (xy 83.416394 -230.71455) (xy 83.734905 -230.71455)
			(xy 83.739 -230.663822) (xy 83.751179 -230.614408) (xy 83.771127 -230.567588) (xy 83.798328 -230.524574)
			(xy 83.832076 -230.48648) (xy 83.871498 -230.454293) (xy 83.915572 -230.428847) (xy 83.963158 -230.4108)
			(xy 84.013022 -230.40062) (xy 84.063874 -230.398571) (xy 84.114395 -230.404705) (xy 84.163279 -230.418865)
			(xy 84.209258 -230.440682) (xy 84.251142 -230.469592) (xy 84.287846 -230.504847) (xy 84.318419 -230.545533)
			(xy 84.34207 -230.590596) (xy 84.358186 -230.63887) (xy 84.36635 -230.689104) (xy 84.366857 -230.714296)
			(xy 84.685136 -230.714296) (xy 84.689096 -230.665242) (xy 84.700873 -230.617458) (xy 84.720164 -230.572182)
			(xy 84.746467 -230.530586) (xy 84.779102 -230.493749) (xy 84.817223 -230.462624) (xy 84.859844 -230.438017)
			(xy 84.90586 -230.420565) (xy 84.954079 -230.410721) (xy 85.003254 -230.40874) (xy 85.052109 -230.414672)
			(xy 85.09938 -230.428364) (xy 85.143842 -230.449462) (xy 85.184345 -230.477418) (xy 85.219838 -230.51151)
			(xy 85.249403 -230.550854) (xy 85.272274 -230.594431) (xy 85.287858 -230.641112) (xy 85.295753 -230.689689)
			(xy 85.296248 -230.714296) (xy 85.296243 -230.71455) (xy 85.614759 -230.71455) (xy 85.618854 -230.663822)
			(xy 85.631033 -230.614408) (xy 85.650981 -230.567588) (xy 85.678182 -230.524574) (xy 85.71193 -230.48648)
			(xy 85.751352 -230.454293) (xy 85.795426 -230.428847) (xy 85.843012 -230.4108) (xy 85.892876 -230.40062)
			(xy 85.943728 -230.398571) (xy 85.994249 -230.404705) (xy 86.043133 -230.418865) (xy 86.089112 -230.440682)
			(xy 86.130996 -230.469592) (xy 86.1677 -230.504847) (xy 86.198273 -230.545533) (xy 86.221924 -230.590596)
			(xy 86.23804 -230.63887) (xy 86.246204 -230.689104) (xy 86.246716 -230.71455) (xy 86.565244 -230.71455)
			(xy 86.569204 -230.665496) (xy 86.580981 -230.617712) (xy 86.600272 -230.572436) (xy 86.626575 -230.53084)
			(xy 86.65921 -230.494003) (xy 86.697331 -230.462878) (xy 86.739952 -230.438271) (xy 86.785968 -230.420819)
			(xy 86.834187 -230.410975) (xy 86.883362 -230.408994) (xy 86.932217 -230.414926) (xy 86.979488 -230.428618)
			(xy 87.02395 -230.449716) (xy 87.064453 -230.477672) (xy 87.099946 -230.511764) (xy 87.129511 -230.551108)
			(xy 87.152382 -230.594685) (xy 87.167966 -230.641366) (xy 87.175861 -230.689943) (xy 87.176356 -230.71455)
			(xy 87.494867 -230.71455) (xy 87.498962 -230.663822) (xy 87.511141 -230.614408) (xy 87.531089 -230.567588)
			(xy 87.55829 -230.524574) (xy 87.592038 -230.48648) (xy 87.63146 -230.454293) (xy 87.675534 -230.428847)
			(xy 87.72312 -230.4108) (xy 87.772984 -230.40062) (xy 87.823836 -230.398571) (xy 87.874357 -230.404705)
			(xy 87.923241 -230.418865) (xy 87.96922 -230.440682) (xy 88.011104 -230.469592) (xy 88.047808 -230.504847)
			(xy 88.078381 -230.545533) (xy 88.102032 -230.590596) (xy 88.118148 -230.63887) (xy 88.126312 -230.689104)
			(xy 88.126824 -230.71455) (xy 88.434921 -230.71455) (xy 88.439016 -230.663822) (xy 88.451195 -230.614408)
			(xy 88.471143 -230.567588) (xy 88.498344 -230.524574) (xy 88.532092 -230.48648) (xy 88.571514 -230.454293)
			(xy 88.615588 -230.428847) (xy 88.663174 -230.4108) (xy 88.713038 -230.40062) (xy 88.76389 -230.398571)
			(xy 88.814411 -230.404705) (xy 88.863295 -230.418865) (xy 88.909274 -230.440682) (xy 88.951158 -230.469592)
			(xy 88.987862 -230.504847) (xy 89.018435 -230.545533) (xy 89.042086 -230.590596) (xy 89.058202 -230.63887)
			(xy 89.066366 -230.689104) (xy 89.066873 -230.714296) (xy 89.385152 -230.714296) (xy 89.389112 -230.665242)
			(xy 89.400889 -230.617458) (xy 89.42018 -230.572182) (xy 89.446483 -230.530586) (xy 89.479118 -230.493749)
			(xy 89.517239 -230.462624) (xy 89.55986 -230.438017) (xy 89.605876 -230.420565) (xy 89.654095 -230.410721)
			(xy 89.70327 -230.40874) (xy 89.752125 -230.414672) (xy 89.799396 -230.428364) (xy 89.843858 -230.449462)
			(xy 89.884361 -230.477418) (xy 89.919854 -230.51151) (xy 89.949419 -230.550854) (xy 89.97229 -230.594431)
			(xy 89.987874 -230.641112) (xy 89.995769 -230.689689) (xy 89.996264 -230.714296) (xy 89.996259 -230.71455)
			(xy 90.314775 -230.71455) (xy 90.31887 -230.663822) (xy 90.331049 -230.614408) (xy 90.350997 -230.567588)
			(xy 90.378198 -230.524574) (xy 90.411946 -230.48648) (xy 90.451368 -230.454293) (xy 90.495442 -230.428847)
			(xy 90.543028 -230.4108) (xy 90.592892 -230.40062) (xy 90.643744 -230.398571) (xy 90.694265 -230.404705)
			(xy 90.743149 -230.418865) (xy 90.789128 -230.440682) (xy 90.831012 -230.469592) (xy 90.867716 -230.504847)
			(xy 90.898289 -230.545533) (xy 90.92194 -230.590596) (xy 90.938056 -230.63887) (xy 90.94622 -230.689104)
			(xy 90.946732 -230.71455) (xy 91.26526 -230.71455) (xy 91.26922 -230.665496) (xy 91.280997 -230.617712)
			(xy 91.300288 -230.572436) (xy 91.326591 -230.53084) (xy 91.359226 -230.494003) (xy 91.397347 -230.462878)
			(xy 91.439968 -230.438271) (xy 91.485984 -230.420819) (xy 91.534203 -230.410975) (xy 91.583378 -230.408994)
			(xy 91.632233 -230.414926) (xy 91.679504 -230.428618) (xy 91.723966 -230.449716) (xy 91.764469 -230.477672)
			(xy 91.799962 -230.511764) (xy 91.829527 -230.551108) (xy 91.852398 -230.594685) (xy 91.867982 -230.641366)
			(xy 91.875877 -230.689943) (xy 91.876372 -230.71455) (xy 92.194883 -230.71455) (xy 92.198978 -230.663822)
			(xy 92.211157 -230.614408) (xy 92.231105 -230.567588) (xy 92.258306 -230.524574) (xy 92.292054 -230.48648)
			(xy 92.331476 -230.454293) (xy 92.37555 -230.428847) (xy 92.423136 -230.4108) (xy 92.473 -230.40062)
			(xy 92.523852 -230.398571) (xy 92.574373 -230.404705) (xy 92.623257 -230.418865) (xy 92.669236 -230.440682)
			(xy 92.71112 -230.469592) (xy 92.747824 -230.504847) (xy 92.778397 -230.545533) (xy 92.802048 -230.590596)
			(xy 92.818164 -230.63887) (xy 92.826328 -230.689104) (xy 92.826835 -230.714296) (xy 93.145114 -230.714296)
			(xy 93.149074 -230.665242) (xy 93.160851 -230.617458) (xy 93.180142 -230.572182) (xy 93.206445 -230.530586)
			(xy 93.23908 -230.493749) (xy 93.277201 -230.462624) (xy 93.319822 -230.438017) (xy 93.365838 -230.420565)
			(xy 93.414057 -230.410721) (xy 93.463232 -230.40874) (xy 93.512087 -230.414672) (xy 93.559358 -230.428364)
			(xy 93.60382 -230.449462) (xy 93.644323 -230.477418) (xy 93.679816 -230.51151) (xy 93.709381 -230.550854)
			(xy 93.732252 -230.594431) (xy 93.747836 -230.641112) (xy 93.755731 -230.689689) (xy 93.756226 -230.714296)
			(xy 93.756221 -230.71455) (xy 94.074737 -230.71455) (xy 94.078832 -230.663822) (xy 94.091011 -230.614408)
			(xy 94.110959 -230.567588) (xy 94.13816 -230.524574) (xy 94.171908 -230.48648) (xy 94.21133 -230.454293)
			(xy 94.255404 -230.428847) (xy 94.30299 -230.4108) (xy 94.352854 -230.40062) (xy 94.403706 -230.398571)
			(xy 94.454227 -230.404705) (xy 94.503111 -230.418865) (xy 94.54909 -230.440682) (xy 94.590974 -230.469592)
			(xy 94.627678 -230.504847) (xy 94.658251 -230.545533) (xy 94.681902 -230.590596) (xy 94.698018 -230.63887)
			(xy 94.706182 -230.689104) (xy 94.706694 -230.71455) (xy 95.014791 -230.71455) (xy 95.018886 -230.663822)
			(xy 95.031065 -230.614408) (xy 95.051013 -230.567588) (xy 95.078214 -230.524574) (xy 95.111962 -230.48648)
			(xy 95.151384 -230.454293) (xy 95.195458 -230.428847) (xy 95.243044 -230.4108) (xy 95.292908 -230.40062)
			(xy 95.34376 -230.398571) (xy 95.394281 -230.404705) (xy 95.443165 -230.418865) (xy 95.489144 -230.440682)
			(xy 95.531028 -230.469592) (xy 95.567732 -230.504847) (xy 95.598305 -230.545533) (xy 95.621956 -230.590596)
			(xy 95.638072 -230.63887) (xy 95.646236 -230.689104) (xy 95.646748 -230.71455) (xy 95.965276 -230.71455)
			(xy 95.969236 -230.665496) (xy 95.981013 -230.617712) (xy 96.000304 -230.572436) (xy 96.026607 -230.53084)
			(xy 96.059242 -230.494003) (xy 96.097363 -230.462878) (xy 96.139984 -230.438271) (xy 96.186 -230.420819)
			(xy 96.234219 -230.410975) (xy 96.283394 -230.408994) (xy 96.332249 -230.414926) (xy 96.37952 -230.428618)
			(xy 96.423982 -230.449716) (xy 96.464485 -230.477672) (xy 96.499978 -230.511764) (xy 96.529543 -230.551108)
			(xy 96.552414 -230.594685) (xy 96.567998 -230.641366) (xy 96.575893 -230.689943) (xy 96.576388 -230.71455)
			(xy 98.785184 -230.71455) (xy 98.789144 -230.665496) (xy 98.800921 -230.617712) (xy 98.820212 -230.572436)
			(xy 98.846515 -230.53084) (xy 98.87915 -230.494003) (xy 98.917271 -230.462878) (xy 98.959892 -230.438271)
			(xy 99.005908 -230.420819) (xy 99.054127 -230.410975) (xy 99.103302 -230.408994) (xy 99.152157 -230.414926)
			(xy 99.199428 -230.428618) (xy 99.24389 -230.449716) (xy 99.284393 -230.477672) (xy 99.319886 -230.511764)
			(xy 99.349451 -230.551108) (xy 99.372322 -230.594685) (xy 99.387906 -230.641366) (xy 99.395801 -230.689943)
			(xy 99.396291 -230.714296) (xy 101.605346 -230.714296) (xy 101.609306 -230.665242) (xy 101.621083 -230.617458)
			(xy 101.640374 -230.572182) (xy 101.666677 -230.530586) (xy 101.699312 -230.493749) (xy 101.737433 -230.462624)
			(xy 101.780054 -230.438017) (xy 101.82607 -230.420565) (xy 101.874289 -230.410721) (xy 101.923464 -230.40874)
			(xy 101.972319 -230.414672) (xy 102.01959 -230.428364) (xy 102.064052 -230.449462) (xy 102.104555 -230.477418)
			(xy 102.140048 -230.51151) (xy 102.169613 -230.550854) (xy 102.192484 -230.594431) (xy 102.208068 -230.641112)
			(xy 102.215963 -230.689689) (xy 102.216458 -230.714296) (xy 102.216453 -230.71455) (xy 104.425254 -230.71455)
			(xy 104.429214 -230.665496) (xy 104.440991 -230.617712) (xy 104.460282 -230.572436) (xy 104.486585 -230.53084)
			(xy 104.51922 -230.494003) (xy 104.557341 -230.462878) (xy 104.599962 -230.438271) (xy 104.645978 -230.420819)
			(xy 104.694197 -230.410975) (xy 104.743372 -230.408994) (xy 104.792227 -230.414926) (xy 104.839498 -230.428618)
			(xy 104.88396 -230.449716) (xy 104.924463 -230.477672) (xy 104.959956 -230.511764) (xy 104.989521 -230.551108)
			(xy 105.012392 -230.594685) (xy 105.027976 -230.641366) (xy 105.035871 -230.689943) (xy 105.036361 -230.714296)
			(xy 107.245162 -230.714296) (xy 107.249122 -230.665242) (xy 107.260899 -230.617458) (xy 107.28019 -230.572182)
			(xy 107.306493 -230.530586) (xy 107.339128 -230.493749) (xy 107.377249 -230.462624) (xy 107.41987 -230.438017)
			(xy 107.465886 -230.420565) (xy 107.514105 -230.410721) (xy 107.56328 -230.40874) (xy 107.612135 -230.414672)
			(xy 107.659406 -230.428364) (xy 107.703868 -230.449462) (xy 107.744371 -230.477418) (xy 107.779864 -230.51151)
			(xy 107.809429 -230.550854) (xy 107.8323 -230.594431) (xy 107.847884 -230.641112) (xy 107.855779 -230.689689)
			(xy 107.856274 -230.714296) (xy 107.856269 -230.71455) (xy 108.174785 -230.71455) (xy 108.17888 -230.663822)
			(xy 108.191059 -230.614408) (xy 108.211007 -230.567588) (xy 108.238208 -230.524574) (xy 108.271956 -230.48648)
			(xy 108.311378 -230.454293) (xy 108.355452 -230.428847) (xy 108.403038 -230.4108) (xy 108.452902 -230.40062)
			(xy 108.503754 -230.398571) (xy 108.554275 -230.404705) (xy 108.603159 -230.418865) (xy 108.649138 -230.440682)
			(xy 108.691022 -230.469592) (xy 108.727726 -230.504847) (xy 108.758299 -230.545533) (xy 108.78195 -230.590596)
			(xy 108.798066 -230.63887) (xy 108.80623 -230.689104) (xy 108.806742 -230.71455) (xy 109.114839 -230.71455)
			(xy 109.118934 -230.663822) (xy 109.131113 -230.614408) (xy 109.151061 -230.567588) (xy 109.178262 -230.524574)
			(xy 109.21201 -230.48648) (xy 109.251432 -230.454293) (xy 109.295506 -230.428847) (xy 109.343092 -230.4108)
			(xy 109.392956 -230.40062) (xy 109.443808 -230.398571) (xy 109.494329 -230.404705) (xy 109.543213 -230.418865)
			(xy 109.589192 -230.440682) (xy 109.631076 -230.469592) (xy 109.66778 -230.504847) (xy 109.698353 -230.545533)
			(xy 109.722004 -230.590596) (xy 109.73812 -230.63887) (xy 109.746284 -230.689104) (xy 109.746796 -230.71455)
			(xy 110.065324 -230.71455) (xy 110.069284 -230.665496) (xy 110.081061 -230.617712) (xy 110.100352 -230.572436)
			(xy 110.126655 -230.53084) (xy 110.15929 -230.494003) (xy 110.197411 -230.462878) (xy 110.240032 -230.438271)
			(xy 110.286048 -230.420819) (xy 110.334267 -230.410975) (xy 110.383442 -230.408994) (xy 110.432297 -230.414926)
			(xy 110.479568 -230.428618) (xy 110.52403 -230.449716) (xy 110.564533 -230.477672) (xy 110.600026 -230.511764)
			(xy 110.629591 -230.551108) (xy 110.652462 -230.594685) (xy 110.668046 -230.641366) (xy 110.675941 -230.689943)
			(xy 110.676436 -230.71455) (xy 110.675941 -230.739157) (xy 110.668046 -230.787734) (xy 110.652462 -230.834415)
			(xy 110.629591 -230.877992) (xy 110.600026 -230.917336) (xy 110.564533 -230.951428) (xy 110.52403 -230.979384)
			(xy 110.479568 -231.000482) (xy 110.432297 -231.014174) (xy 110.383442 -231.020106) (xy 110.334267 -231.018125)
			(xy 110.286048 -231.008281) (xy 110.240032 -230.990829) (xy 110.197411 -230.966222) (xy 110.15929 -230.935097)
			(xy 110.126655 -230.89826) (xy 110.100352 -230.856664) (xy 110.081061 -230.811388) (xy 110.069284 -230.763604)
			(xy 110.065324 -230.71455) (xy 109.746796 -230.71455) (xy 109.746284 -230.739996) (xy 109.73812 -230.79023)
			(xy 109.722004 -230.838504) (xy 109.698353 -230.883567) (xy 109.66778 -230.924253) (xy 109.631076 -230.959508)
			(xy 109.589192 -230.988418) (xy 109.543213 -231.010235) (xy 109.494329 -231.024395) (xy 109.443808 -231.030529)
			(xy 109.392956 -231.02848) (xy 109.343092 -231.0183) (xy 109.295506 -231.000253) (xy 109.251432 -230.974807)
			(xy 109.21201 -230.94262) (xy 109.178262 -230.904526) (xy 109.151061 -230.861512) (xy 109.131113 -230.814692)
			(xy 109.118934 -230.765278) (xy 109.114839 -230.71455) (xy 108.806742 -230.71455) (xy 108.80623 -230.739996)
			(xy 108.798066 -230.79023) (xy 108.78195 -230.838504) (xy 108.758299 -230.883567) (xy 108.727726 -230.924253)
			(xy 108.691022 -230.959508) (xy 108.649138 -230.988418) (xy 108.603159 -231.010235) (xy 108.554275 -231.024395)
			(xy 108.503754 -231.030529) (xy 108.452902 -231.02848) (xy 108.403038 -231.0183) (xy 108.355452 -231.000253)
			(xy 108.311378 -230.974807) (xy 108.271956 -230.94262) (xy 108.238208 -230.904526) (xy 108.211007 -230.861512)
			(xy 108.191059 -230.814692) (xy 108.17888 -230.765278) (xy 108.174785 -230.71455) (xy 107.856269 -230.71455)
			(xy 107.855779 -230.738903) (xy 107.847884 -230.78748) (xy 107.8323 -230.834161) (xy 107.809429 -230.877738)
			(xy 107.779864 -230.917082) (xy 107.744371 -230.951174) (xy 107.703868 -230.97913) (xy 107.659406 -231.000228)
			(xy 107.612135 -231.01392) (xy 107.56328 -231.019852) (xy 107.514105 -231.017871) (xy 107.465886 -231.008027)
			(xy 107.41987 -230.990575) (xy 107.377249 -230.965968) (xy 107.339128 -230.934843) (xy 107.306493 -230.898006)
			(xy 107.28019 -230.85641) (xy 107.260899 -230.811134) (xy 107.249122 -230.76335) (xy 107.245162 -230.714296)
			(xy 105.036361 -230.714296) (xy 105.036366 -230.71455) (xy 105.035871 -230.739157) (xy 105.027976 -230.787734)
			(xy 105.012392 -230.834415) (xy 104.989521 -230.877992) (xy 104.959956 -230.917336) (xy 104.924463 -230.951428)
			(xy 104.88396 -230.979384) (xy 104.839498 -231.000482) (xy 104.792227 -231.014174) (xy 104.743372 -231.020106)
			(xy 104.694197 -231.018125) (xy 104.645978 -231.008281) (xy 104.599962 -230.990829) (xy 104.557341 -230.966222)
			(xy 104.51922 -230.935097) (xy 104.486585 -230.89826) (xy 104.460282 -230.856664) (xy 104.440991 -230.811388)
			(xy 104.429214 -230.763604) (xy 104.425254 -230.71455) (xy 102.216453 -230.71455) (xy 102.215963 -230.738903)
			(xy 102.208068 -230.78748) (xy 102.192484 -230.834161) (xy 102.169613 -230.877738) (xy 102.140048 -230.917082)
			(xy 102.104555 -230.951174) (xy 102.064052 -230.97913) (xy 102.01959 -231.000228) (xy 101.972319 -231.01392)
			(xy 101.923464 -231.019852) (xy 101.874289 -231.017871) (xy 101.82607 -231.008027) (xy 101.780054 -230.990575)
			(xy 101.737433 -230.965968) (xy 101.699312 -230.934843) (xy 101.666677 -230.898006) (xy 101.640374 -230.85641)
			(xy 101.621083 -230.811134) (xy 101.609306 -230.76335) (xy 101.605346 -230.714296) (xy 99.396291 -230.714296)
			(xy 99.396296 -230.71455) (xy 99.395801 -230.739157) (xy 99.387906 -230.787734) (xy 99.372322 -230.834415)
			(xy 99.349451 -230.877992) (xy 99.319886 -230.917336) (xy 99.284393 -230.951428) (xy 99.24389 -230.979384)
			(xy 99.199428 -231.000482) (xy 99.152157 -231.014174) (xy 99.103302 -231.020106) (xy 99.054127 -231.018125)
			(xy 99.005908 -231.008281) (xy 98.959892 -230.990829) (xy 98.917271 -230.966222) (xy 98.87915 -230.935097)
			(xy 98.846515 -230.89826) (xy 98.820212 -230.856664) (xy 98.800921 -230.811388) (xy 98.789144 -230.763604)
			(xy 98.785184 -230.71455) (xy 96.576388 -230.71455) (xy 96.575893 -230.739157) (xy 96.567998 -230.787734)
			(xy 96.552414 -230.834415) (xy 96.529543 -230.877992) (xy 96.499978 -230.917336) (xy 96.464485 -230.951428)
			(xy 96.423982 -230.979384) (xy 96.37952 -231.000482) (xy 96.332249 -231.014174) (xy 96.283394 -231.020106)
			(xy 96.234219 -231.018125) (xy 96.186 -231.008281) (xy 96.139984 -230.990829) (xy 96.097363 -230.966222)
			(xy 96.059242 -230.935097) (xy 96.026607 -230.89826) (xy 96.000304 -230.856664) (xy 95.981013 -230.811388)
			(xy 95.969236 -230.763604) (xy 95.965276 -230.71455) (xy 95.646748 -230.71455) (xy 95.646236 -230.739996)
			(xy 95.638072 -230.79023) (xy 95.621956 -230.838504) (xy 95.598305 -230.883567) (xy 95.567732 -230.924253)
			(xy 95.531028 -230.959508) (xy 95.489144 -230.988418) (xy 95.443165 -231.010235) (xy 95.394281 -231.024395)
			(xy 95.34376 -231.030529) (xy 95.292908 -231.02848) (xy 95.243044 -231.0183) (xy 95.195458 -231.000253)
			(xy 95.151384 -230.974807) (xy 95.111962 -230.94262) (xy 95.078214 -230.904526) (xy 95.051013 -230.861512)
			(xy 95.031065 -230.814692) (xy 95.018886 -230.765278) (xy 95.014791 -230.71455) (xy 94.706694 -230.71455)
			(xy 94.706182 -230.739996) (xy 94.698018 -230.79023) (xy 94.681902 -230.838504) (xy 94.658251 -230.883567)
			(xy 94.627678 -230.924253) (xy 94.590974 -230.959508) (xy 94.54909 -230.988418) (xy 94.503111 -231.010235)
			(xy 94.454227 -231.024395) (xy 94.403706 -231.030529) (xy 94.352854 -231.02848) (xy 94.30299 -231.0183)
			(xy 94.255404 -231.000253) (xy 94.21133 -230.974807) (xy 94.171908 -230.94262) (xy 94.13816 -230.904526)
			(xy 94.110959 -230.861512) (xy 94.091011 -230.814692) (xy 94.078832 -230.765278) (xy 94.074737 -230.71455)
			(xy 93.756221 -230.71455) (xy 93.755731 -230.738903) (xy 93.747836 -230.78748) (xy 93.732252 -230.834161)
			(xy 93.709381 -230.877738) (xy 93.679816 -230.917082) (xy 93.644323 -230.951174) (xy 93.60382 -230.97913)
			(xy 93.559358 -231.000228) (xy 93.512087 -231.01392) (xy 93.463232 -231.019852) (xy 93.414057 -231.017871)
			(xy 93.365838 -231.008027) (xy 93.319822 -230.990575) (xy 93.277201 -230.965968) (xy 93.23908 -230.934843)
			(xy 93.206445 -230.898006) (xy 93.180142 -230.85641) (xy 93.160851 -230.811134) (xy 93.149074 -230.76335)
			(xy 93.145114 -230.714296) (xy 92.826835 -230.714296) (xy 92.82684 -230.71455) (xy 92.826328 -230.739996)
			(xy 92.818164 -230.79023) (xy 92.802048 -230.838504) (xy 92.778397 -230.883567) (xy 92.747824 -230.924253)
			(xy 92.71112 -230.959508) (xy 92.669236 -230.988418) (xy 92.623257 -231.010235) (xy 92.574373 -231.024395)
			(xy 92.523852 -231.030529) (xy 92.473 -231.02848) (xy 92.423136 -231.0183) (xy 92.37555 -231.000253)
			(xy 92.331476 -230.974807) (xy 92.292054 -230.94262) (xy 92.258306 -230.904526) (xy 92.231105 -230.861512)
			(xy 92.211157 -230.814692) (xy 92.198978 -230.765278) (xy 92.194883 -230.71455) (xy 91.876372 -230.71455)
			(xy 91.875877 -230.739157) (xy 91.867982 -230.787734) (xy 91.852398 -230.834415) (xy 91.829527 -230.877992)
			(xy 91.799962 -230.917336) (xy 91.764469 -230.951428) (xy 91.723966 -230.979384) (xy 91.679504 -231.000482)
			(xy 91.632233 -231.014174) (xy 91.583378 -231.020106) (xy 91.534203 -231.018125) (xy 91.485984 -231.008281)
			(xy 91.439968 -230.990829) (xy 91.397347 -230.966222) (xy 91.359226 -230.935097) (xy 91.326591 -230.89826)
			(xy 91.300288 -230.856664) (xy 91.280997 -230.811388) (xy 91.26922 -230.763604) (xy 91.26526 -230.71455)
			(xy 90.946732 -230.71455) (xy 90.94622 -230.739996) (xy 90.938056 -230.79023) (xy 90.92194 -230.838504)
			(xy 90.898289 -230.883567) (xy 90.867716 -230.924253) (xy 90.831012 -230.959508) (xy 90.789128 -230.988418)
			(xy 90.743149 -231.010235) (xy 90.694265 -231.024395) (xy 90.643744 -231.030529) (xy 90.592892 -231.02848)
			(xy 90.543028 -231.0183) (xy 90.495442 -231.000253) (xy 90.451368 -230.974807) (xy 90.411946 -230.94262)
			(xy 90.378198 -230.904526) (xy 90.350997 -230.861512) (xy 90.331049 -230.814692) (xy 90.31887 -230.765278)
			(xy 90.314775 -230.71455) (xy 89.996259 -230.71455) (xy 89.995769 -230.738903) (xy 89.987874 -230.78748)
			(xy 89.97229 -230.834161) (xy 89.949419 -230.877738) (xy 89.919854 -230.917082) (xy 89.884361 -230.951174)
			(xy 89.843858 -230.97913) (xy 89.799396 -231.000228) (xy 89.752125 -231.01392) (xy 89.70327 -231.019852)
			(xy 89.654095 -231.017871) (xy 89.605876 -231.008027) (xy 89.55986 -230.990575) (xy 89.517239 -230.965968)
			(xy 89.479118 -230.934843) (xy 89.446483 -230.898006) (xy 89.42018 -230.85641) (xy 89.400889 -230.811134)
			(xy 89.389112 -230.76335) (xy 89.385152 -230.714296) (xy 89.066873 -230.714296) (xy 89.066878 -230.71455)
			(xy 89.066366 -230.739996) (xy 89.058202 -230.79023) (xy 89.042086 -230.838504) (xy 89.018435 -230.883567)
			(xy 88.987862 -230.924253) (xy 88.951158 -230.959508) (xy 88.909274 -230.988418) (xy 88.863295 -231.010235)
			(xy 88.814411 -231.024395) (xy 88.76389 -231.030529) (xy 88.713038 -231.02848) (xy 88.663174 -231.0183)
			(xy 88.615588 -231.000253) (xy 88.571514 -230.974807) (xy 88.532092 -230.94262) (xy 88.498344 -230.904526)
			(xy 88.471143 -230.861512) (xy 88.451195 -230.814692) (xy 88.439016 -230.765278) (xy 88.434921 -230.71455)
			(xy 88.126824 -230.71455) (xy 88.126312 -230.739996) (xy 88.118148 -230.79023) (xy 88.102032 -230.838504)
			(xy 88.078381 -230.883567) (xy 88.047808 -230.924253) (xy 88.011104 -230.959508) (xy 87.96922 -230.988418)
			(xy 87.923241 -231.010235) (xy 87.874357 -231.024395) (xy 87.823836 -231.030529) (xy 87.772984 -231.02848)
			(xy 87.72312 -231.0183) (xy 87.675534 -231.000253) (xy 87.63146 -230.974807) (xy 87.592038 -230.94262)
			(xy 87.55829 -230.904526) (xy 87.531089 -230.861512) (xy 87.511141 -230.814692) (xy 87.498962 -230.765278)
			(xy 87.494867 -230.71455) (xy 87.176356 -230.71455) (xy 87.175861 -230.739157) (xy 87.167966 -230.787734)
			(xy 87.152382 -230.834415) (xy 87.129511 -230.877992) (xy 87.099946 -230.917336) (xy 87.064453 -230.951428)
			(xy 87.02395 -230.979384) (xy 86.979488 -231.000482) (xy 86.932217 -231.014174) (xy 86.883362 -231.020106)
			(xy 86.834187 -231.018125) (xy 86.785968 -231.008281) (xy 86.739952 -230.990829) (xy 86.697331 -230.966222)
			(xy 86.65921 -230.935097) (xy 86.626575 -230.89826) (xy 86.600272 -230.856664) (xy 86.580981 -230.811388)
			(xy 86.569204 -230.763604) (xy 86.565244 -230.71455) (xy 86.246716 -230.71455) (xy 86.246204 -230.739996)
			(xy 86.23804 -230.79023) (xy 86.221924 -230.838504) (xy 86.198273 -230.883567) (xy 86.1677 -230.924253)
			(xy 86.130996 -230.959508) (xy 86.089112 -230.988418) (xy 86.043133 -231.010235) (xy 85.994249 -231.024395)
			(xy 85.943728 -231.030529) (xy 85.892876 -231.02848) (xy 85.843012 -231.0183) (xy 85.795426 -231.000253)
			(xy 85.751352 -230.974807) (xy 85.71193 -230.94262) (xy 85.678182 -230.904526) (xy 85.650981 -230.861512)
			(xy 85.631033 -230.814692) (xy 85.618854 -230.765278) (xy 85.614759 -230.71455) (xy 85.296243 -230.71455)
			(xy 85.295753 -230.738903) (xy 85.287858 -230.78748) (xy 85.272274 -230.834161) (xy 85.249403 -230.877738)
			(xy 85.219838 -230.917082) (xy 85.184345 -230.951174) (xy 85.143842 -230.97913) (xy 85.09938 -231.000228)
			(xy 85.052109 -231.01392) (xy 85.003254 -231.019852) (xy 84.954079 -231.017871) (xy 84.90586 -231.008027)
			(xy 84.859844 -230.990575) (xy 84.817223 -230.965968) (xy 84.779102 -230.934843) (xy 84.746467 -230.898006)
			(xy 84.720164 -230.85641) (xy 84.700873 -230.811134) (xy 84.689096 -230.76335) (xy 84.685136 -230.714296)
			(xy 84.366857 -230.714296) (xy 84.366862 -230.71455) (xy 84.36635 -230.739996) (xy 84.358186 -230.79023)
			(xy 84.34207 -230.838504) (xy 84.318419 -230.883567) (xy 84.287846 -230.924253) (xy 84.251142 -230.959508)
			(xy 84.209258 -230.988418) (xy 84.163279 -231.010235) (xy 84.114395 -231.024395) (xy 84.063874 -231.030529)
			(xy 84.013022 -231.02848) (xy 83.963158 -231.0183) (xy 83.915572 -231.000253) (xy 83.871498 -230.974807)
			(xy 83.832076 -230.94262) (xy 83.798328 -230.904526) (xy 83.771127 -230.861512) (xy 83.751179 -230.814692)
			(xy 83.739 -230.765278) (xy 83.734905 -230.71455) (xy 83.416394 -230.71455) (xy 83.415899 -230.739157)
			(xy 83.408004 -230.787734) (xy 83.39242 -230.834415) (xy 83.369549 -230.877992) (xy 83.339984 -230.917336)
			(xy 83.304491 -230.951428) (xy 83.263988 -230.979384) (xy 83.219526 -231.000482) (xy 83.172255 -231.014174)
			(xy 83.1234 -231.020106) (xy 83.074225 -231.018125) (xy 83.026006 -231.008281) (xy 82.97999 -230.990829)
			(xy 82.937369 -230.966222) (xy 82.899248 -230.935097) (xy 82.866613 -230.89826) (xy 82.84031 -230.856664)
			(xy 82.821019 -230.811388) (xy 82.809242 -230.763604) (xy 82.805282 -230.71455) (xy 82.486754 -230.71455)
			(xy 82.486242 -230.739996) (xy 82.478078 -230.79023) (xy 82.461962 -230.838504) (xy 82.438311 -230.883567)
			(xy 82.407738 -230.924253) (xy 82.371034 -230.959508) (xy 82.32915 -230.988418) (xy 82.283171 -231.010235)
			(xy 82.234287 -231.024395) (xy 82.183766 -231.030529) (xy 82.132914 -231.02848) (xy 82.08305 -231.0183)
			(xy 82.035464 -231.000253) (xy 81.99139 -230.974807) (xy 81.951968 -230.94262) (xy 81.91822 -230.904526)
			(xy 81.891019 -230.861512) (xy 81.871071 -230.814692) (xy 81.858892 -230.765278) (xy 81.854797 -230.71455)
			(xy 81.5467 -230.71455) (xy 81.546188 -230.739996) (xy 81.538024 -230.79023) (xy 81.521908 -230.838504)
			(xy 81.498257 -230.883567) (xy 81.467684 -230.924253) (xy 81.43098 -230.959508) (xy 81.389096 -230.988418)
			(xy 81.343117 -231.010235) (xy 81.294233 -231.024395) (xy 81.243712 -231.030529) (xy 81.19286 -231.02848)
			(xy 81.142996 -231.0183) (xy 81.09541 -231.000253) (xy 81.051336 -230.974807) (xy 81.011914 -230.94262)
			(xy 80.978166 -230.904526) (xy 80.950965 -230.861512) (xy 80.931017 -230.814692) (xy 80.918838 -230.765278)
			(xy 80.914743 -230.71455) (xy 80.596486 -230.71455) (xy 80.595991 -230.739157) (xy 80.588096 -230.787734)
			(xy 80.572512 -230.834415) (xy 80.549641 -230.877992) (xy 80.520076 -230.917336) (xy 80.484583 -230.951428)
			(xy 80.44408 -230.979384) (xy 80.399618 -231.000482) (xy 80.352347 -231.014174) (xy 80.303492 -231.020106)
			(xy 80.254317 -231.018125) (xy 80.206098 -231.008281) (xy 80.160082 -230.990829) (xy 80.117461 -230.966222)
			(xy 80.07934 -230.935097) (xy 80.046705 -230.89826) (xy 80.020402 -230.856664) (xy 80.001111 -230.811388)
			(xy 79.989334 -230.763604) (xy 79.985374 -230.71455) (xy 78.716378 -230.71455) (xy 78.715883 -230.739157)
			(xy 78.707988 -230.787734) (xy 78.692404 -230.834415) (xy 78.669533 -230.877992) (xy 78.639968 -230.917336)
			(xy 78.604475 -230.951428) (xy 78.563972 -230.979384) (xy 78.51951 -231.000482) (xy 78.472239 -231.014174)
			(xy 78.423384 -231.020106) (xy 78.374209 -231.018125) (xy 78.32599 -231.008281) (xy 78.279974 -230.990829)
			(xy 78.237353 -230.966222) (xy 78.199232 -230.935097) (xy 78.166597 -230.89826) (xy 78.140294 -230.856664)
			(xy 78.121003 -230.811388) (xy 78.109226 -230.763604) (xy 78.105266 -230.71455) (xy 62.37732 -230.71455)
			(xy 62.37732 -231.79024) (xy 76.507098 -231.79024) (xy 76.511058 -231.741186) (xy 76.522835 -231.693402)
			(xy 76.542126 -231.648126) (xy 76.568429 -231.60653) (xy 76.601064 -231.569693) (xy 76.639185 -231.538568)
			(xy 76.681806 -231.513961) (xy 76.727822 -231.496509) (xy 76.776041 -231.486665) (xy 76.825216 -231.484684)
			(xy 76.874071 -231.490616) (xy 76.921342 -231.504308) (xy 76.963477 -231.524302) (xy 79.51522 -231.524302)
			(xy 79.51918 -231.475248) (xy 79.530957 -231.427464) (xy 79.550248 -231.382188) (xy 79.576551 -231.340592)
			(xy 79.609186 -231.303755) (xy 79.647307 -231.27263) (xy 79.689928 -231.248023) (xy 79.735944 -231.230571)
			(xy 79.784163 -231.220727) (xy 79.833338 -231.218746) (xy 79.882193 -231.224678) (xy 79.929464 -231.23837)
			(xy 79.973926 -231.259468) (xy 80.014429 -231.287424) (xy 80.049922 -231.321516) (xy 80.079487 -231.36086)
			(xy 80.102358 -231.404437) (xy 80.117942 -231.451118) (xy 80.125837 -231.499695) (xy 80.126332 -231.524302)
			(xy 80.444843 -231.524302) (xy 80.448938 -231.473574) (xy 80.461117 -231.42416) (xy 80.481065 -231.37734)
			(xy 80.508266 -231.334326) (xy 80.542014 -231.296232) (xy 80.581436 -231.264045) (xy 80.62551 -231.238599)
			(xy 80.673096 -231.220552) (xy 80.72296 -231.210372) (xy 80.773812 -231.208323) (xy 80.824333 -231.214457)
			(xy 80.873217 -231.228617) (xy 80.919196 -231.250434) (xy 80.96108 -231.279344) (xy 80.997784 -231.314599)
			(xy 81.028357 -231.355285) (xy 81.052008 -231.400348) (xy 81.068124 -231.448622) (xy 81.076288 -231.498856)
			(xy 81.0768 -231.524302) (xy 81.395328 -231.524302) (xy 81.399288 -231.475248) (xy 81.411065 -231.427464)
			(xy 81.430356 -231.382188) (xy 81.456659 -231.340592) (xy 81.489294 -231.303755) (xy 81.527415 -231.27263)
			(xy 81.570036 -231.248023) (xy 81.616052 -231.230571) (xy 81.664271 -231.220727) (xy 81.713446 -231.218746)
			(xy 81.762301 -231.224678) (xy 81.809572 -231.23837) (xy 81.854034 -231.259468) (xy 81.894537 -231.287424)
			(xy 81.93003 -231.321516) (xy 81.959595 -231.36086) (xy 81.982466 -231.404437) (xy 81.99805 -231.451118)
			(xy 82.005945 -231.499695) (xy 82.00644 -231.524302) (xy 82.324697 -231.524302) (xy 82.328792 -231.473574)
			(xy 82.340971 -231.42416) (xy 82.360919 -231.37734) (xy 82.38812 -231.334326) (xy 82.421868 -231.296232)
			(xy 82.46129 -231.264045) (xy 82.505364 -231.238599) (xy 82.55295 -231.220552) (xy 82.602814 -231.210372)
			(xy 82.653666 -231.208323) (xy 82.704187 -231.214457) (xy 82.753071 -231.228617) (xy 82.79905 -231.250434)
			(xy 82.840934 -231.279344) (xy 82.877638 -231.314599) (xy 82.908211 -231.355285) (xy 82.931862 -231.400348)
			(xy 82.947978 -231.448622) (xy 82.956142 -231.498856) (xy 82.956654 -231.524302) (xy 83.275182 -231.524302)
			(xy 83.279142 -231.475248) (xy 83.290919 -231.427464) (xy 83.31021 -231.382188) (xy 83.336513 -231.340592)
			(xy 83.369148 -231.303755) (xy 83.407269 -231.27263) (xy 83.44989 -231.248023) (xy 83.495906 -231.230571)
			(xy 83.544125 -231.220727) (xy 83.5933 -231.218746) (xy 83.642155 -231.224678) (xy 83.689426 -231.23837)
			(xy 83.733888 -231.259468) (xy 83.774391 -231.287424) (xy 83.809884 -231.321516) (xy 83.839449 -231.36086)
			(xy 83.86232 -231.404437) (xy 83.877904 -231.451118) (xy 83.885799 -231.499695) (xy 83.886294 -231.524302)
			(xy 84.204805 -231.524302) (xy 84.2089 -231.473574) (xy 84.221079 -231.42416) (xy 84.241027 -231.37734)
			(xy 84.268228 -231.334326) (xy 84.301976 -231.296232) (xy 84.341398 -231.264045) (xy 84.385472 -231.238599)
			(xy 84.433058 -231.220552) (xy 84.482922 -231.210372) (xy 84.533774 -231.208323) (xy 84.584295 -231.214457)
			(xy 84.633179 -231.228617) (xy 84.679158 -231.250434) (xy 84.721042 -231.279344) (xy 84.757746 -231.314599)
			(xy 84.788319 -231.355285) (xy 84.81197 -231.400348) (xy 84.828086 -231.448622) (xy 84.83625 -231.498856)
			(xy 84.836762 -231.524302) (xy 85.144859 -231.524302) (xy 85.148954 -231.473574) (xy 85.161133 -231.42416)
			(xy 85.181081 -231.37734) (xy 85.208282 -231.334326) (xy 85.24203 -231.296232) (xy 85.281452 -231.264045)
			(xy 85.325526 -231.238599) (xy 85.373112 -231.220552) (xy 85.422976 -231.210372) (xy 85.473828 -231.208323)
			(xy 85.524349 -231.214457) (xy 85.573233 -231.228617) (xy 85.619212 -231.250434) (xy 85.661096 -231.279344)
			(xy 85.6978 -231.314599) (xy 85.728373 -231.355285) (xy 85.752024 -231.400348) (xy 85.76814 -231.448622)
			(xy 85.776304 -231.498856) (xy 85.776816 -231.524302) (xy 86.095344 -231.524302) (xy 86.099304 -231.475248)
			(xy 86.111081 -231.427464) (xy 86.130372 -231.382188) (xy 86.156675 -231.340592) (xy 86.18931 -231.303755)
			(xy 86.227431 -231.27263) (xy 86.270052 -231.248023) (xy 86.316068 -231.230571) (xy 86.364287 -231.220727)
			(xy 86.413462 -231.218746) (xy 86.462317 -231.224678) (xy 86.509588 -231.23837) (xy 86.55405 -231.259468)
			(xy 86.594553 -231.287424) (xy 86.630046 -231.321516) (xy 86.659611 -231.36086) (xy 86.682482 -231.404437)
			(xy 86.698066 -231.451118) (xy 86.705961 -231.499695) (xy 86.706456 -231.524302) (xy 87.024713 -231.524302)
			(xy 87.028808 -231.473574) (xy 87.040987 -231.42416) (xy 87.060935 -231.37734) (xy 87.088136 -231.334326)
			(xy 87.121884 -231.296232) (xy 87.161306 -231.264045) (xy 87.20538 -231.238599) (xy 87.252966 -231.220552)
			(xy 87.30283 -231.210372) (xy 87.353682 -231.208323) (xy 87.404203 -231.214457) (xy 87.453087 -231.228617)
			(xy 87.499066 -231.250434) (xy 87.54095 -231.279344) (xy 87.577654 -231.314599) (xy 87.608227 -231.355285)
			(xy 87.631878 -231.400348) (xy 87.647994 -231.448622) (xy 87.656158 -231.498856) (xy 87.65667 -231.524302)
			(xy 87.975198 -231.524302) (xy 87.979158 -231.475248) (xy 87.990935 -231.427464) (xy 88.010226 -231.382188)
			(xy 88.036529 -231.340592) (xy 88.069164 -231.303755) (xy 88.107285 -231.27263) (xy 88.149906 -231.248023)
			(xy 88.195922 -231.230571) (xy 88.244141 -231.220727) (xy 88.293316 -231.218746) (xy 88.342171 -231.224678)
			(xy 88.389442 -231.23837) (xy 88.433904 -231.259468) (xy 88.474407 -231.287424) (xy 88.5099 -231.321516)
			(xy 88.539465 -231.36086) (xy 88.562336 -231.404437) (xy 88.57792 -231.451118) (xy 88.585815 -231.499695)
			(xy 88.58631 -231.524302) (xy 88.904821 -231.524302) (xy 88.908916 -231.473574) (xy 88.921095 -231.42416)
			(xy 88.941043 -231.37734) (xy 88.968244 -231.334326) (xy 89.001992 -231.296232) (xy 89.041414 -231.264045)
			(xy 89.085488 -231.238599) (xy 89.133074 -231.220552) (xy 89.182938 -231.210372) (xy 89.23379 -231.208323)
			(xy 89.284311 -231.214457) (xy 89.333195 -231.228617) (xy 89.379174 -231.250434) (xy 89.421058 -231.279344)
			(xy 89.457762 -231.314599) (xy 89.488335 -231.355285) (xy 89.511986 -231.400348) (xy 89.528102 -231.448622)
			(xy 89.536266 -231.498856) (xy 89.536778 -231.524302) (xy 89.855306 -231.524302) (xy 89.859266 -231.475248)
			(xy 89.871043 -231.427464) (xy 89.890334 -231.382188) (xy 89.916637 -231.340592) (xy 89.949272 -231.303755)
			(xy 89.987393 -231.27263) (xy 90.030014 -231.248023) (xy 90.07603 -231.230571) (xy 90.124249 -231.220727)
			(xy 90.173424 -231.218746) (xy 90.222279 -231.224678) (xy 90.26955 -231.23837) (xy 90.314012 -231.259468)
			(xy 90.354515 -231.287424) (xy 90.390008 -231.321516) (xy 90.419573 -231.36086) (xy 90.442444 -231.404437)
			(xy 90.458028 -231.451118) (xy 90.465923 -231.499695) (xy 90.466418 -231.524302) (xy 90.784675 -231.524302)
			(xy 90.78877 -231.473574) (xy 90.800949 -231.42416) (xy 90.820897 -231.37734) (xy 90.848098 -231.334326)
			(xy 90.881846 -231.296232) (xy 90.921268 -231.264045) (xy 90.965342 -231.238599) (xy 91.012928 -231.220552)
			(xy 91.062792 -231.210372) (xy 91.113644 -231.208323) (xy 91.164165 -231.214457) (xy 91.213049 -231.228617)
			(xy 91.259028 -231.250434) (xy 91.300912 -231.279344) (xy 91.337616 -231.314599) (xy 91.368189 -231.355285)
			(xy 91.39184 -231.400348) (xy 91.407956 -231.448622) (xy 91.41612 -231.498856) (xy 91.416632 -231.524302)
			(xy 91.724729 -231.524302) (xy 91.728824 -231.473574) (xy 91.741003 -231.42416) (xy 91.760951 -231.37734)
			(xy 91.788152 -231.334326) (xy 91.8219 -231.296232) (xy 91.861322 -231.264045) (xy 91.905396 -231.238599)
			(xy 91.952982 -231.220552) (xy 92.002846 -231.210372) (xy 92.053698 -231.208323) (xy 92.104219 -231.214457)
			(xy 92.153103 -231.228617) (xy 92.199082 -231.250434) (xy 92.240966 -231.279344) (xy 92.27767 -231.314599)
			(xy 92.308243 -231.355285) (xy 92.331894 -231.400348) (xy 92.34801 -231.448622) (xy 92.356174 -231.498856)
			(xy 92.356686 -231.524302) (xy 92.675214 -231.524302) (xy 92.679174 -231.475248) (xy 92.690951 -231.427464)
			(xy 92.710242 -231.382188) (xy 92.736545 -231.340592) (xy 92.76918 -231.303755) (xy 92.807301 -231.27263)
			(xy 92.849922 -231.248023) (xy 92.895938 -231.230571) (xy 92.944157 -231.220727) (xy 92.993332 -231.218746)
			(xy 93.042187 -231.224678) (xy 93.089458 -231.23837) (xy 93.13392 -231.259468) (xy 93.174423 -231.287424)
			(xy 93.209916 -231.321516) (xy 93.239481 -231.36086) (xy 93.262352 -231.404437) (xy 93.277936 -231.451118)
			(xy 93.285831 -231.499695) (xy 93.286326 -231.524302) (xy 93.604837 -231.524302) (xy 93.608932 -231.473574)
			(xy 93.621111 -231.42416) (xy 93.641059 -231.37734) (xy 93.66826 -231.334326) (xy 93.702008 -231.296232)
			(xy 93.74143 -231.264045) (xy 93.785504 -231.238599) (xy 93.83309 -231.220552) (xy 93.882954 -231.210372)
			(xy 93.933806 -231.208323) (xy 93.984327 -231.214457) (xy 94.033211 -231.228617) (xy 94.07919 -231.250434)
			(xy 94.121074 -231.279344) (xy 94.157778 -231.314599) (xy 94.188351 -231.355285) (xy 94.212002 -231.400348)
			(xy 94.228118 -231.448622) (xy 94.236282 -231.498856) (xy 94.236794 -231.524302) (xy 94.555322 -231.524302)
			(xy 94.559282 -231.475248) (xy 94.571059 -231.427464) (xy 94.59035 -231.382188) (xy 94.616653 -231.340592)
			(xy 94.649288 -231.303755) (xy 94.687409 -231.27263) (xy 94.73003 -231.248023) (xy 94.776046 -231.230571)
			(xy 94.824265 -231.220727) (xy 94.87344 -231.218746) (xy 94.922295 -231.224678) (xy 94.969566 -231.23837)
			(xy 95.014028 -231.259468) (xy 95.054531 -231.287424) (xy 95.090024 -231.321516) (xy 95.119589 -231.36086)
			(xy 95.14246 -231.404437) (xy 95.158044 -231.451118) (xy 95.165939 -231.499695) (xy 95.166434 -231.524302)
			(xy 95.484691 -231.524302) (xy 95.488786 -231.473574) (xy 95.500965 -231.42416) (xy 95.520913 -231.37734)
			(xy 95.548114 -231.334326) (xy 95.581862 -231.296232) (xy 95.621284 -231.264045) (xy 95.665358 -231.238599)
			(xy 95.712944 -231.220552) (xy 95.762808 -231.210372) (xy 95.81366 -231.208323) (xy 95.864181 -231.214457)
			(xy 95.913065 -231.228617) (xy 95.959044 -231.250434) (xy 96.000928 -231.279344) (xy 96.037632 -231.314599)
			(xy 96.068205 -231.355285) (xy 96.091856 -231.400348) (xy 96.107972 -231.448622) (xy 96.116136 -231.498856)
			(xy 96.116648 -231.524302) (xy 96.435176 -231.524302) (xy 96.439136 -231.475248) (xy 96.450913 -231.427464)
			(xy 96.470204 -231.382188) (xy 96.496507 -231.340592) (xy 96.529142 -231.303755) (xy 96.567263 -231.27263)
			(xy 96.609884 -231.248023) (xy 96.6559 -231.230571) (xy 96.704119 -231.220727) (xy 96.753294 -231.218746)
			(xy 96.802149 -231.224678) (xy 96.84942 -231.23837) (xy 96.893882 -231.259468) (xy 96.934385 -231.287424)
			(xy 96.969878 -231.321516) (xy 96.999443 -231.36086) (xy 97.022314 -231.404437) (xy 97.037898 -231.451118)
			(xy 97.045793 -231.499695) (xy 97.046288 -231.524302) (xy 97.364799 -231.524302) (xy 97.368894 -231.473574)
			(xy 97.381073 -231.42416) (xy 97.401021 -231.37734) (xy 97.428222 -231.334326) (xy 97.46197 -231.296232)
			(xy 97.501392 -231.264045) (xy 97.545466 -231.238599) (xy 97.593052 -231.220552) (xy 97.642916 -231.210372)
			(xy 97.693768 -231.208323) (xy 97.744289 -231.214457) (xy 97.793173 -231.228617) (xy 97.839152 -231.250434)
			(xy 97.881036 -231.279344) (xy 97.91774 -231.314599) (xy 97.948313 -231.355285) (xy 97.971964 -231.400348)
			(xy 97.98808 -231.448622) (xy 97.996244 -231.498856) (xy 97.996756 -231.524302) (xy 98.304853 -231.524302)
			(xy 98.308948 -231.473574) (xy 98.321127 -231.42416) (xy 98.341075 -231.37734) (xy 98.368276 -231.334326)
			(xy 98.402024 -231.296232) (xy 98.441446 -231.264045) (xy 98.48552 -231.238599) (xy 98.533106 -231.220552)
			(xy 98.58297 -231.210372) (xy 98.633822 -231.208323) (xy 98.684343 -231.214457) (xy 98.733227 -231.228617)
			(xy 98.779206 -231.250434) (xy 98.82109 -231.279344) (xy 98.857794 -231.314599) (xy 98.888367 -231.355285)
			(xy 98.912018 -231.400348) (xy 98.928134 -231.448622) (xy 98.936298 -231.498856) (xy 98.93681 -231.524302)
			(xy 99.255338 -231.524302) (xy 99.259298 -231.475248) (xy 99.271075 -231.427464) (xy 99.290366 -231.382188)
			(xy 99.316669 -231.340592) (xy 99.349304 -231.303755) (xy 99.387425 -231.27263) (xy 99.430046 -231.248023)
			(xy 99.476062 -231.230571) (xy 99.524281 -231.220727) (xy 99.573456 -231.218746) (xy 99.622311 -231.224678)
			(xy 99.669582 -231.23837) (xy 99.714044 -231.259468) (xy 99.754547 -231.287424) (xy 99.79004 -231.321516)
			(xy 99.819605 -231.36086) (xy 99.842476 -231.404437) (xy 99.85806 -231.451118) (xy 99.865955 -231.499695)
			(xy 99.86645 -231.524302) (xy 100.184707 -231.524302) (xy 100.188802 -231.473574) (xy 100.200981 -231.42416)
			(xy 100.220929 -231.37734) (xy 100.24813 -231.334326) (xy 100.281878 -231.296232) (xy 100.3213 -231.264045)
			(xy 100.365374 -231.238599) (xy 100.41296 -231.220552) (xy 100.462824 -231.210372) (xy 100.513676 -231.208323)
			(xy 100.564197 -231.214457) (xy 100.613081 -231.228617) (xy 100.65906 -231.250434) (xy 100.700944 -231.279344)
			(xy 100.737648 -231.314599) (xy 100.768221 -231.355285) (xy 100.791872 -231.400348) (xy 100.807988 -231.448622)
			(xy 100.816152 -231.498856) (xy 100.816664 -231.524302) (xy 101.124761 -231.524302) (xy 101.128856 -231.473574)
			(xy 101.141035 -231.42416) (xy 101.160983 -231.37734) (xy 101.188184 -231.334326) (xy 101.221932 -231.296232)
			(xy 101.261354 -231.264045) (xy 101.305428 -231.238599) (xy 101.353014 -231.220552) (xy 101.402878 -231.210372)
			(xy 101.45373 -231.208323) (xy 101.504251 -231.214457) (xy 101.553135 -231.228617) (xy 101.599114 -231.250434)
			(xy 101.640998 -231.279344) (xy 101.677702 -231.314599) (xy 101.708275 -231.355285) (xy 101.731926 -231.400348)
			(xy 101.748042 -231.448622) (xy 101.756206 -231.498856) (xy 101.756718 -231.524302) (xy 102.075246 -231.524302)
			(xy 102.079206 -231.475248) (xy 102.090983 -231.427464) (xy 102.110274 -231.382188) (xy 102.136577 -231.340592)
			(xy 102.169212 -231.303755) (xy 102.207333 -231.27263) (xy 102.249954 -231.248023) (xy 102.29597 -231.230571)
			(xy 102.344189 -231.220727) (xy 102.393364 -231.218746) (xy 102.442219 -231.224678) (xy 102.48949 -231.23837)
			(xy 102.533952 -231.259468) (xy 102.574455 -231.287424) (xy 102.609948 -231.321516) (xy 102.639513 -231.36086)
			(xy 102.662384 -231.404437) (xy 102.677968 -231.451118) (xy 102.685863 -231.499695) (xy 102.686358 -231.524302)
			(xy 103.004869 -231.524302) (xy 103.008964 -231.473574) (xy 103.021143 -231.42416) (xy 103.041091 -231.37734)
			(xy 103.068292 -231.334326) (xy 103.10204 -231.296232) (xy 103.141462 -231.264045) (xy 103.185536 -231.238599)
			(xy 103.233122 -231.220552) (xy 103.282986 -231.210372) (xy 103.333838 -231.208323) (xy 103.384359 -231.214457)
			(xy 103.433243 -231.228617) (xy 103.479222 -231.250434) (xy 103.521106 -231.279344) (xy 103.55781 -231.314599)
			(xy 103.588383 -231.355285) (xy 103.612034 -231.400348) (xy 103.62815 -231.448622) (xy 103.636314 -231.498856)
			(xy 103.636826 -231.524302) (xy 103.944923 -231.524302) (xy 103.949018 -231.473574) (xy 103.961197 -231.42416)
			(xy 103.981145 -231.37734) (xy 104.008346 -231.334326) (xy 104.042094 -231.296232) (xy 104.081516 -231.264045)
			(xy 104.12559 -231.238599) (xy 104.173176 -231.220552) (xy 104.22304 -231.210372) (xy 104.273892 -231.208323)
			(xy 104.324413 -231.214457) (xy 104.373297 -231.228617) (xy 104.419276 -231.250434) (xy 104.46116 -231.279344)
			(xy 104.497864 -231.314599) (xy 104.528437 -231.355285) (xy 104.552088 -231.400348) (xy 104.568204 -231.448622)
			(xy 104.576368 -231.498856) (xy 104.57688 -231.524302) (xy 104.895154 -231.524302) (xy 104.899114 -231.475248)
			(xy 104.910891 -231.427464) (xy 104.930182 -231.382188) (xy 104.956485 -231.340592) (xy 104.98912 -231.303755)
			(xy 105.027241 -231.27263) (xy 105.069862 -231.248023) (xy 105.115878 -231.230571) (xy 105.164097 -231.220727)
			(xy 105.213272 -231.218746) (xy 105.262127 -231.224678) (xy 105.309398 -231.23837) (xy 105.35386 -231.259468)
			(xy 105.394363 -231.287424) (xy 105.429856 -231.321516) (xy 105.459421 -231.36086) (xy 105.482292 -231.404437)
			(xy 105.497876 -231.451118) (xy 105.505771 -231.499695) (xy 105.506266 -231.524302) (xy 105.824777 -231.524302)
			(xy 105.828872 -231.473574) (xy 105.841051 -231.42416) (xy 105.860999 -231.37734) (xy 105.8882 -231.334326)
			(xy 105.921948 -231.296232) (xy 105.96137 -231.264045) (xy 106.005444 -231.238599) (xy 106.05303 -231.220552)
			(xy 106.102894 -231.210372) (xy 106.153746 -231.208323) (xy 106.204267 -231.214457) (xy 106.253151 -231.228617)
			(xy 106.29913 -231.250434) (xy 106.341014 -231.279344) (xy 106.377718 -231.314599) (xy 106.408291 -231.355285)
			(xy 106.431942 -231.400348) (xy 106.448058 -231.448622) (xy 106.456222 -231.498856) (xy 106.456734 -231.524302)
			(xy 106.764831 -231.524302) (xy 106.768926 -231.473574) (xy 106.781105 -231.42416) (xy 106.801053 -231.37734)
			(xy 106.828254 -231.334326) (xy 106.862002 -231.296232) (xy 106.901424 -231.264045) (xy 106.945498 -231.238599)
			(xy 106.993084 -231.220552) (xy 107.042948 -231.210372) (xy 107.0938 -231.208323) (xy 107.144321 -231.214457)
			(xy 107.193205 -231.228617) (xy 107.239184 -231.250434) (xy 107.281068 -231.279344) (xy 107.317772 -231.314599)
			(xy 107.348345 -231.355285) (xy 107.371996 -231.400348) (xy 107.388112 -231.448622) (xy 107.396276 -231.498856)
			(xy 107.396788 -231.524302) (xy 107.715316 -231.524302) (xy 107.719276 -231.475248) (xy 107.731053 -231.427464)
			(xy 107.750344 -231.382188) (xy 107.776647 -231.340592) (xy 107.809282 -231.303755) (xy 107.847403 -231.27263)
			(xy 107.890024 -231.248023) (xy 107.93604 -231.230571) (xy 107.984259 -231.220727) (xy 108.033434 -231.218746)
			(xy 108.082289 -231.224678) (xy 108.12956 -231.23837) (xy 108.174022 -231.259468) (xy 108.214525 -231.287424)
			(xy 108.250018 -231.321516) (xy 108.279583 -231.36086) (xy 108.302454 -231.404437) (xy 108.318038 -231.451118)
			(xy 108.325933 -231.499695) (xy 108.326428 -231.524302) (xy 108.325933 -231.548909) (xy 108.318038 -231.597486)
			(xy 108.302454 -231.644167) (xy 108.279583 -231.687744) (xy 108.250018 -231.727088) (xy 108.214525 -231.76118)
			(xy 108.174022 -231.789136) (xy 108.12956 -231.810234) (xy 108.082289 -231.823926) (xy 108.033434 -231.829858)
			(xy 107.984259 -231.827877) (xy 107.93604 -231.818033) (xy 107.890024 -231.800581) (xy 107.847403 -231.775974)
			(xy 107.809282 -231.744849) (xy 107.776647 -231.708012) (xy 107.750344 -231.666416) (xy 107.731053 -231.62114)
			(xy 107.719276 -231.573356) (xy 107.715316 -231.524302) (xy 107.396788 -231.524302) (xy 107.396276 -231.549748)
			(xy 107.388112 -231.599982) (xy 107.371996 -231.648256) (xy 107.348345 -231.693319) (xy 107.317772 -231.734005)
			(xy 107.281068 -231.76926) (xy 107.239184 -231.79817) (xy 107.193205 -231.819987) (xy 107.144321 -231.834147)
			(xy 107.0938 -231.840281) (xy 107.042948 -231.838232) (xy 106.993084 -231.828052) (xy 106.945498 -231.810005)
			(xy 106.901424 -231.784559) (xy 106.862002 -231.752372) (xy 106.828254 -231.714278) (xy 106.801053 -231.671264)
			(xy 106.781105 -231.624444) (xy 106.768926 -231.57503) (xy 106.764831 -231.524302) (xy 106.456734 -231.524302)
			(xy 106.456222 -231.549748) (xy 106.448058 -231.599982) (xy 106.431942 -231.648256) (xy 106.408291 -231.693319)
			(xy 106.377718 -231.734005) (xy 106.341014 -231.76926) (xy 106.29913 -231.79817) (xy 106.253151 -231.819987)
			(xy 106.204267 -231.834147) (xy 106.153746 -231.840281) (xy 106.102894 -231.838232) (xy 106.05303 -231.828052)
			(xy 106.005444 -231.810005) (xy 105.96137 -231.784559) (xy 105.921948 -231.752372) (xy 105.8882 -231.714278)
			(xy 105.860999 -231.671264) (xy 105.841051 -231.624444) (xy 105.828872 -231.57503) (xy 105.824777 -231.524302)
			(xy 105.506266 -231.524302) (xy 105.505771 -231.548909) (xy 105.497876 -231.597486) (xy 105.482292 -231.644167)
			(xy 105.459421 -231.687744) (xy 105.429856 -231.727088) (xy 105.394363 -231.76118) (xy 105.35386 -231.789136)
			(xy 105.309398 -231.810234) (xy 105.262127 -231.823926) (xy 105.213272 -231.829858) (xy 105.164097 -231.827877)
			(xy 105.115878 -231.818033) (xy 105.069862 -231.800581) (xy 105.027241 -231.775974) (xy 104.98912 -231.744849)
			(xy 104.956485 -231.708012) (xy 104.930182 -231.666416) (xy 104.910891 -231.62114) (xy 104.899114 -231.573356)
			(xy 104.895154 -231.524302) (xy 104.57688 -231.524302) (xy 104.576368 -231.549748) (xy 104.568204 -231.599982)
			(xy 104.552088 -231.648256) (xy 104.528437 -231.693319) (xy 104.497864 -231.734005) (xy 104.46116 -231.76926)
			(xy 104.419276 -231.79817) (xy 104.373297 -231.819987) (xy 104.324413 -231.834147) (xy 104.273892 -231.840281)
			(xy 104.22304 -231.838232) (xy 104.173176 -231.828052) (xy 104.12559 -231.810005) (xy 104.081516 -231.784559)
			(xy 104.042094 -231.752372) (xy 104.008346 -231.714278) (xy 103.981145 -231.671264) (xy 103.961197 -231.624444)
			(xy 103.949018 -231.57503) (xy 103.944923 -231.524302) (xy 103.636826 -231.524302) (xy 103.636314 -231.549748)
			(xy 103.62815 -231.599982) (xy 103.612034 -231.648256) (xy 103.588383 -231.693319) (xy 103.55781 -231.734005)
			(xy 103.521106 -231.76926) (xy 103.479222 -231.79817) (xy 103.433243 -231.819987) (xy 103.384359 -231.834147)
			(xy 103.333838 -231.840281) (xy 103.282986 -231.838232) (xy 103.233122 -231.828052) (xy 103.185536 -231.810005)
			(xy 103.141462 -231.784559) (xy 103.10204 -231.752372) (xy 103.068292 -231.714278) (xy 103.041091 -231.671264)
			(xy 103.021143 -231.624444) (xy 103.008964 -231.57503) (xy 103.004869 -231.524302) (xy 102.686358 -231.524302)
			(xy 102.685863 -231.548909) (xy 102.677968 -231.597486) (xy 102.662384 -231.644167) (xy 102.639513 -231.687744)
			(xy 102.609948 -231.727088) (xy 102.574455 -231.76118) (xy 102.533952 -231.789136) (xy 102.48949 -231.810234)
			(xy 102.442219 -231.823926) (xy 102.393364 -231.829858) (xy 102.344189 -231.827877) (xy 102.29597 -231.818033)
			(xy 102.249954 -231.800581) (xy 102.207333 -231.775974) (xy 102.169212 -231.744849) (xy 102.136577 -231.708012)
			(xy 102.110274 -231.666416) (xy 102.090983 -231.62114) (xy 102.079206 -231.573356) (xy 102.075246 -231.524302)
			(xy 101.756718 -231.524302) (xy 101.756206 -231.549748) (xy 101.748042 -231.599982) (xy 101.731926 -231.648256)
			(xy 101.708275 -231.693319) (xy 101.677702 -231.734005) (xy 101.640998 -231.76926) (xy 101.599114 -231.79817)
			(xy 101.553135 -231.819987) (xy 101.504251 -231.834147) (xy 101.45373 -231.840281) (xy 101.402878 -231.838232)
			(xy 101.353014 -231.828052) (xy 101.305428 -231.810005) (xy 101.261354 -231.784559) (xy 101.221932 -231.752372)
			(xy 101.188184 -231.714278) (xy 101.160983 -231.671264) (xy 101.141035 -231.624444) (xy 101.128856 -231.57503)
			(xy 101.124761 -231.524302) (xy 100.816664 -231.524302) (xy 100.816152 -231.549748) (xy 100.807988 -231.599982)
			(xy 100.791872 -231.648256) (xy 100.768221 -231.693319) (xy 100.737648 -231.734005) (xy 100.700944 -231.76926)
			(xy 100.65906 -231.79817) (xy 100.613081 -231.819987) (xy 100.564197 -231.834147) (xy 100.513676 -231.840281)
			(xy 100.462824 -231.838232) (xy 100.41296 -231.828052) (xy 100.365374 -231.810005) (xy 100.3213 -231.784559)
			(xy 100.281878 -231.752372) (xy 100.24813 -231.714278) (xy 100.220929 -231.671264) (xy 100.200981 -231.624444)
			(xy 100.188802 -231.57503) (xy 100.184707 -231.524302) (xy 99.86645 -231.524302) (xy 99.865955 -231.548909)
			(xy 99.85806 -231.597486) (xy 99.842476 -231.644167) (xy 99.819605 -231.687744) (xy 99.79004 -231.727088)
			(xy 99.754547 -231.76118) (xy 99.714044 -231.789136) (xy 99.669582 -231.810234) (xy 99.622311 -231.823926)
			(xy 99.573456 -231.829858) (xy 99.524281 -231.827877) (xy 99.476062 -231.818033) (xy 99.430046 -231.800581)
			(xy 99.387425 -231.775974) (xy 99.349304 -231.744849) (xy 99.316669 -231.708012) (xy 99.290366 -231.666416)
			(xy 99.271075 -231.62114) (xy 99.259298 -231.573356) (xy 99.255338 -231.524302) (xy 98.93681 -231.524302)
			(xy 98.936298 -231.549748) (xy 98.928134 -231.599982) (xy 98.912018 -231.648256) (xy 98.888367 -231.693319)
			(xy 98.857794 -231.734005) (xy 98.82109 -231.76926) (xy 98.779206 -231.79817) (xy 98.733227 -231.819987)
			(xy 98.684343 -231.834147) (xy 98.633822 -231.840281) (xy 98.58297 -231.838232) (xy 98.533106 -231.828052)
			(xy 98.48552 -231.810005) (xy 98.441446 -231.784559) (xy 98.402024 -231.752372) (xy 98.368276 -231.714278)
			(xy 98.341075 -231.671264) (xy 98.321127 -231.624444) (xy 98.308948 -231.57503) (xy 98.304853 -231.524302)
			(xy 97.996756 -231.524302) (xy 97.996244 -231.549748) (xy 97.98808 -231.599982) (xy 97.971964 -231.648256)
			(xy 97.948313 -231.693319) (xy 97.91774 -231.734005) (xy 97.881036 -231.76926) (xy 97.839152 -231.79817)
			(xy 97.793173 -231.819987) (xy 97.744289 -231.834147) (xy 97.693768 -231.840281) (xy 97.642916 -231.838232)
			(xy 97.593052 -231.828052) (xy 97.545466 -231.810005) (xy 97.501392 -231.784559) (xy 97.46197 -231.752372)
			(xy 97.428222 -231.714278) (xy 97.401021 -231.671264) (xy 97.381073 -231.624444) (xy 97.368894 -231.57503)
			(xy 97.364799 -231.524302) (xy 97.046288 -231.524302) (xy 97.045793 -231.548909) (xy 97.037898 -231.597486)
			(xy 97.022314 -231.644167) (xy 96.999443 -231.687744) (xy 96.969878 -231.727088) (xy 96.934385 -231.76118)
			(xy 96.893882 -231.789136) (xy 96.84942 -231.810234) (xy 96.802149 -231.823926) (xy 96.753294 -231.829858)
			(xy 96.704119 -231.827877) (xy 96.6559 -231.818033) (xy 96.609884 -231.800581) (xy 96.567263 -231.775974)
			(xy 96.529142 -231.744849) (xy 96.496507 -231.708012) (xy 96.470204 -231.666416) (xy 96.450913 -231.62114)
			(xy 96.439136 -231.573356) (xy 96.435176 -231.524302) (xy 96.116648 -231.524302) (xy 96.116136 -231.549748)
			(xy 96.107972 -231.599982) (xy 96.091856 -231.648256) (xy 96.068205 -231.693319) (xy 96.037632 -231.734005)
			(xy 96.000928 -231.76926) (xy 95.959044 -231.79817) (xy 95.913065 -231.819987) (xy 95.864181 -231.834147)
			(xy 95.81366 -231.840281) (xy 95.762808 -231.838232) (xy 95.712944 -231.828052) (xy 95.665358 -231.810005)
			(xy 95.621284 -231.784559) (xy 95.581862 -231.752372) (xy 95.548114 -231.714278) (xy 95.520913 -231.671264)
			(xy 95.500965 -231.624444) (xy 95.488786 -231.57503) (xy 95.484691 -231.524302) (xy 95.166434 -231.524302)
			(xy 95.165939 -231.548909) (xy 95.158044 -231.597486) (xy 95.14246 -231.644167) (xy 95.119589 -231.687744)
			(xy 95.090024 -231.727088) (xy 95.054531 -231.76118) (xy 95.014028 -231.789136) (xy 94.969566 -231.810234)
			(xy 94.922295 -231.823926) (xy 94.87344 -231.829858) (xy 94.824265 -231.827877) (xy 94.776046 -231.818033)
			(xy 94.73003 -231.800581) (xy 94.687409 -231.775974) (xy 94.649288 -231.744849) (xy 94.616653 -231.708012)
			(xy 94.59035 -231.666416) (xy 94.571059 -231.62114) (xy 94.559282 -231.573356) (xy 94.555322 -231.524302)
			(xy 94.236794 -231.524302) (xy 94.236282 -231.549748) (xy 94.228118 -231.599982) (xy 94.212002 -231.648256)
			(xy 94.188351 -231.693319) (xy 94.157778 -231.734005) (xy 94.121074 -231.76926) (xy 94.07919 -231.79817)
			(xy 94.033211 -231.819987) (xy 93.984327 -231.834147) (xy 93.933806 -231.840281) (xy 93.882954 -231.838232)
			(xy 93.83309 -231.828052) (xy 93.785504 -231.810005) (xy 93.74143 -231.784559) (xy 93.702008 -231.752372)
			(xy 93.66826 -231.714278) (xy 93.641059 -231.671264) (xy 93.621111 -231.624444) (xy 93.608932 -231.57503)
			(xy 93.604837 -231.524302) (xy 93.286326 -231.524302) (xy 93.285831 -231.548909) (xy 93.277936 -231.597486)
			(xy 93.262352 -231.644167) (xy 93.239481 -231.687744) (xy 93.209916 -231.727088) (xy 93.174423 -231.76118)
			(xy 93.13392 -231.789136) (xy 93.089458 -231.810234) (xy 93.042187 -231.823926) (xy 92.993332 -231.829858)
			(xy 92.944157 -231.827877) (xy 92.895938 -231.818033) (xy 92.849922 -231.800581) (xy 92.807301 -231.775974)
			(xy 92.76918 -231.744849) (xy 92.736545 -231.708012) (xy 92.710242 -231.666416) (xy 92.690951 -231.62114)
			(xy 92.679174 -231.573356) (xy 92.675214 -231.524302) (xy 92.356686 -231.524302) (xy 92.356174 -231.549748)
			(xy 92.34801 -231.599982) (xy 92.331894 -231.648256) (xy 92.308243 -231.693319) (xy 92.27767 -231.734005)
			(xy 92.240966 -231.76926) (xy 92.199082 -231.79817) (xy 92.153103 -231.819987) (xy 92.104219 -231.834147)
			(xy 92.053698 -231.840281) (xy 92.002846 -231.838232) (xy 91.952982 -231.828052) (xy 91.905396 -231.810005)
			(xy 91.861322 -231.784559) (xy 91.8219 -231.752372) (xy 91.788152 -231.714278) (xy 91.760951 -231.671264)
			(xy 91.741003 -231.624444) (xy 91.728824 -231.57503) (xy 91.724729 -231.524302) (xy 91.416632 -231.524302)
			(xy 91.41612 -231.549748) (xy 91.407956 -231.599982) (xy 91.39184 -231.648256) (xy 91.368189 -231.693319)
			(xy 91.337616 -231.734005) (xy 91.300912 -231.76926) (xy 91.259028 -231.79817) (xy 91.213049 -231.819987)
			(xy 91.164165 -231.834147) (xy 91.113644 -231.840281) (xy 91.062792 -231.838232) (xy 91.012928 -231.828052)
			(xy 90.965342 -231.810005) (xy 90.921268 -231.784559) (xy 90.881846 -231.752372) (xy 90.848098 -231.714278)
			(xy 90.820897 -231.671264) (xy 90.800949 -231.624444) (xy 90.78877 -231.57503) (xy 90.784675 -231.524302)
			(xy 90.466418 -231.524302) (xy 90.465923 -231.548909) (xy 90.458028 -231.597486) (xy 90.442444 -231.644167)
			(xy 90.419573 -231.687744) (xy 90.390008 -231.727088) (xy 90.354515 -231.76118) (xy 90.314012 -231.789136)
			(xy 90.26955 -231.810234) (xy 90.222279 -231.823926) (xy 90.173424 -231.829858) (xy 90.124249 -231.827877)
			(xy 90.07603 -231.818033) (xy 90.030014 -231.800581) (xy 89.987393 -231.775974) (xy 89.949272 -231.744849)
			(xy 89.916637 -231.708012) (xy 89.890334 -231.666416) (xy 89.871043 -231.62114) (xy 89.859266 -231.573356)
			(xy 89.855306 -231.524302) (xy 89.536778 -231.524302) (xy 89.536266 -231.549748) (xy 89.528102 -231.599982)
			(xy 89.511986 -231.648256) (xy 89.488335 -231.693319) (xy 89.457762 -231.734005) (xy 89.421058 -231.76926)
			(xy 89.379174 -231.79817) (xy 89.333195 -231.819987) (xy 89.284311 -231.834147) (xy 89.23379 -231.840281)
			(xy 89.182938 -231.838232) (xy 89.133074 -231.828052) (xy 89.085488 -231.810005) (xy 89.041414 -231.784559)
			(xy 89.001992 -231.752372) (xy 88.968244 -231.714278) (xy 88.941043 -231.671264) (xy 88.921095 -231.624444)
			(xy 88.908916 -231.57503) (xy 88.904821 -231.524302) (xy 88.58631 -231.524302) (xy 88.585815 -231.548909)
			(xy 88.57792 -231.597486) (xy 88.562336 -231.644167) (xy 88.539465 -231.687744) (xy 88.5099 -231.727088)
			(xy 88.474407 -231.76118) (xy 88.433904 -231.789136) (xy 88.389442 -231.810234) (xy 88.342171 -231.823926)
			(xy 88.293316 -231.829858) (xy 88.244141 -231.827877) (xy 88.195922 -231.818033) (xy 88.149906 -231.800581)
			(xy 88.107285 -231.775974) (xy 88.069164 -231.744849) (xy 88.036529 -231.708012) (xy 88.010226 -231.666416)
			(xy 87.990935 -231.62114) (xy 87.979158 -231.573356) (xy 87.975198 -231.524302) (xy 87.65667 -231.524302)
			(xy 87.656158 -231.549748) (xy 87.647994 -231.599982) (xy 87.631878 -231.648256) (xy 87.608227 -231.693319)
			(xy 87.577654 -231.734005) (xy 87.54095 -231.76926) (xy 87.499066 -231.79817) (xy 87.453087 -231.819987)
			(xy 87.404203 -231.834147) (xy 87.353682 -231.840281) (xy 87.30283 -231.838232) (xy 87.252966 -231.828052)
			(xy 87.20538 -231.810005) (xy 87.161306 -231.784559) (xy 87.121884 -231.752372) (xy 87.088136 -231.714278)
			(xy 87.060935 -231.671264) (xy 87.040987 -231.624444) (xy 87.028808 -231.57503) (xy 87.024713 -231.524302)
			(xy 86.706456 -231.524302) (xy 86.705961 -231.548909) (xy 86.698066 -231.597486) (xy 86.682482 -231.644167)
			(xy 86.659611 -231.687744) (xy 86.630046 -231.727088) (xy 86.594553 -231.76118) (xy 86.55405 -231.789136)
			(xy 86.509588 -231.810234) (xy 86.462317 -231.823926) (xy 86.413462 -231.829858) (xy 86.364287 -231.827877)
			(xy 86.316068 -231.818033) (xy 86.270052 -231.800581) (xy 86.227431 -231.775974) (xy 86.18931 -231.744849)
			(xy 86.156675 -231.708012) (xy 86.130372 -231.666416) (xy 86.111081 -231.62114) (xy 86.099304 -231.573356)
			(xy 86.095344 -231.524302) (xy 85.776816 -231.524302) (xy 85.776304 -231.549748) (xy 85.76814 -231.599982)
			(xy 85.752024 -231.648256) (xy 85.728373 -231.693319) (xy 85.6978 -231.734005) (xy 85.661096 -231.76926)
			(xy 85.619212 -231.79817) (xy 85.573233 -231.819987) (xy 85.524349 -231.834147) (xy 85.473828 -231.840281)
			(xy 85.422976 -231.838232) (xy 85.373112 -231.828052) (xy 85.325526 -231.810005) (xy 85.281452 -231.784559)
			(xy 85.24203 -231.752372) (xy 85.208282 -231.714278) (xy 85.181081 -231.671264) (xy 85.161133 -231.624444)
			(xy 85.148954 -231.57503) (xy 85.144859 -231.524302) (xy 84.836762 -231.524302) (xy 84.83625 -231.549748)
			(xy 84.828086 -231.599982) (xy 84.81197 -231.648256) (xy 84.788319 -231.693319) (xy 84.757746 -231.734005)
			(xy 84.721042 -231.76926) (xy 84.679158 -231.79817) (xy 84.633179 -231.819987) (xy 84.584295 -231.834147)
			(xy 84.533774 -231.840281) (xy 84.482922 -231.838232) (xy 84.433058 -231.828052) (xy 84.385472 -231.810005)
			(xy 84.341398 -231.784559) (xy 84.301976 -231.752372) (xy 84.268228 -231.714278) (xy 84.241027 -231.671264)
			(xy 84.221079 -231.624444) (xy 84.2089 -231.57503) (xy 84.204805 -231.524302) (xy 83.886294 -231.524302)
			(xy 83.885799 -231.548909) (xy 83.877904 -231.597486) (xy 83.86232 -231.644167) (xy 83.839449 -231.687744)
			(xy 83.809884 -231.727088) (xy 83.774391 -231.76118) (xy 83.733888 -231.789136) (xy 83.689426 -231.810234)
			(xy 83.642155 -231.823926) (xy 83.5933 -231.829858) (xy 83.544125 -231.827877) (xy 83.495906 -231.818033)
			(xy 83.44989 -231.800581) (xy 83.407269 -231.775974) (xy 83.369148 -231.744849) (xy 83.336513 -231.708012)
			(xy 83.31021 -231.666416) (xy 83.290919 -231.62114) (xy 83.279142 -231.573356) (xy 83.275182 -231.524302)
			(xy 82.956654 -231.524302) (xy 82.956142 -231.549748) (xy 82.947978 -231.599982) (xy 82.931862 -231.648256)
			(xy 82.908211 -231.693319) (xy 82.877638 -231.734005) (xy 82.840934 -231.76926) (xy 82.79905 -231.79817)
			(xy 82.753071 -231.819987) (xy 82.704187 -231.834147) (xy 82.653666 -231.840281) (xy 82.602814 -231.838232)
			(xy 82.55295 -231.828052) (xy 82.505364 -231.810005) (xy 82.46129 -231.784559) (xy 82.421868 -231.752372)
			(xy 82.38812 -231.714278) (xy 82.360919 -231.671264) (xy 82.340971 -231.624444) (xy 82.328792 -231.57503)
			(xy 82.324697 -231.524302) (xy 82.00644 -231.524302) (xy 82.005945 -231.548909) (xy 81.99805 -231.597486)
			(xy 81.982466 -231.644167) (xy 81.959595 -231.687744) (xy 81.93003 -231.727088) (xy 81.894537 -231.76118)
			(xy 81.854034 -231.789136) (xy 81.809572 -231.810234) (xy 81.762301 -231.823926) (xy 81.713446 -231.829858)
			(xy 81.664271 -231.827877) (xy 81.616052 -231.818033) (xy 81.570036 -231.800581) (xy 81.527415 -231.775974)
			(xy 81.489294 -231.744849) (xy 81.456659 -231.708012) (xy 81.430356 -231.666416) (xy 81.411065 -231.62114)
			(xy 81.399288 -231.573356) (xy 81.395328 -231.524302) (xy 81.0768 -231.524302) (xy 81.076288 -231.549748)
			(xy 81.068124 -231.599982) (xy 81.052008 -231.648256) (xy 81.028357 -231.693319) (xy 80.997784 -231.734005)
			(xy 80.96108 -231.76926) (xy 80.919196 -231.79817) (xy 80.873217 -231.819987) (xy 80.824333 -231.834147)
			(xy 80.773812 -231.840281) (xy 80.72296 -231.838232) (xy 80.673096 -231.828052) (xy 80.62551 -231.810005)
			(xy 80.581436 -231.784559) (xy 80.542014 -231.752372) (xy 80.508266 -231.714278) (xy 80.481065 -231.671264)
			(xy 80.461117 -231.624444) (xy 80.448938 -231.57503) (xy 80.444843 -231.524302) (xy 80.126332 -231.524302)
			(xy 80.125837 -231.548909) (xy 80.117942 -231.597486) (xy 80.102358 -231.644167) (xy 80.079487 -231.687744)
			(xy 80.049922 -231.727088) (xy 80.014429 -231.76118) (xy 79.973926 -231.789136) (xy 79.929464 -231.810234)
			(xy 79.882193 -231.823926) (xy 79.833338 -231.829858) (xy 79.784163 -231.827877) (xy 79.735944 -231.818033)
			(xy 79.689928 -231.800581) (xy 79.647307 -231.775974) (xy 79.609186 -231.744849) (xy 79.576551 -231.708012)
			(xy 79.550248 -231.666416) (xy 79.530957 -231.62114) (xy 79.51918 -231.573356) (xy 79.51522 -231.524302)
			(xy 76.963477 -231.524302) (xy 76.965804 -231.525406) (xy 77.006307 -231.553362) (xy 77.0418 -231.587454)
			(xy 77.071365 -231.626798) (xy 77.094236 -231.670375) (xy 77.10982 -231.717056) (xy 77.117715 -231.765633)
			(xy 77.11821 -231.79024) (xy 77.117715 -231.814847) (xy 77.10982 -231.863424) (xy 77.094236 -231.910105)
			(xy 77.071365 -231.953682) (xy 77.0418 -231.993026) (xy 77.006307 -232.027118) (xy 76.965804 -232.055074)
			(xy 76.921342 -232.076172) (xy 76.874071 -232.089864) (xy 76.825216 -232.095796) (xy 76.776041 -232.093815)
			(xy 76.727822 -232.083971) (xy 76.681806 -232.066519) (xy 76.639185 -232.041912) (xy 76.601064 -232.010787)
			(xy 76.568429 -231.97395) (xy 76.542126 -231.932354) (xy 76.522835 -231.887078) (xy 76.511058 -231.839294)
			(xy 76.507098 -231.79024) (xy 62.37732 -231.79024) (xy 62.37732 -232.334308) (xy 78.105266 -232.334308)
			(xy 78.109226 -232.285254) (xy 78.121003 -232.23747) (xy 78.140294 -232.192194) (xy 78.166597 -232.150598)
			(xy 78.199232 -232.113761) (xy 78.237353 -232.082636) (xy 78.279974 -232.058029) (xy 78.32599 -232.040577)
			(xy 78.374209 -232.030733) (xy 78.423384 -232.028752) (xy 78.472239 -232.034684) (xy 78.51951 -232.048376)
			(xy 78.563972 -232.069474) (xy 78.604475 -232.09743) (xy 78.639968 -232.131522) (xy 78.669533 -232.170866)
			(xy 78.692404 -232.214443) (xy 78.707988 -232.261124) (xy 78.715883 -232.309701) (xy 78.716378 -232.334308)
			(xy 79.985374 -232.334308) (xy 79.989334 -232.285254) (xy 80.001111 -232.23747) (xy 80.020402 -232.192194)
			(xy 80.046705 -232.150598) (xy 80.07934 -232.113761) (xy 80.117461 -232.082636) (xy 80.160082 -232.058029)
			(xy 80.206098 -232.040577) (xy 80.254317 -232.030733) (xy 80.303492 -232.028752) (xy 80.352347 -232.034684)
			(xy 80.399618 -232.048376) (xy 80.44408 -232.069474) (xy 80.484583 -232.09743) (xy 80.520076 -232.131522)
			(xy 80.549641 -232.170866) (xy 80.572512 -232.214443) (xy 80.588096 -232.261124) (xy 80.595991 -232.309701)
			(xy 80.596486 -232.334308) (xy 80.914743 -232.334308) (xy 80.918838 -232.28358) (xy 80.931017 -232.234166)
			(xy 80.950965 -232.187346) (xy 80.978166 -232.144332) (xy 81.011914 -232.106238) (xy 81.051336 -232.074051)
			(xy 81.09541 -232.048605) (xy 81.142996 -232.030558) (xy 81.19286 -232.020378) (xy 81.243712 -232.018329)
			(xy 81.294233 -232.024463) (xy 81.343117 -232.038623) (xy 81.389096 -232.06044) (xy 81.43098 -232.08935)
			(xy 81.467684 -232.124605) (xy 81.498257 -232.165291) (xy 81.521908 -232.210354) (xy 81.538024 -232.258628)
			(xy 81.546188 -232.308862) (xy 81.5467 -232.334308) (xy 81.854797 -232.334308) (xy 81.858892 -232.28358)
			(xy 81.871071 -232.234166) (xy 81.891019 -232.187346) (xy 81.91822 -232.144332) (xy 81.951968 -232.106238)
			(xy 81.99139 -232.074051) (xy 82.035464 -232.048605) (xy 82.08305 -232.030558) (xy 82.132914 -232.020378)
			(xy 82.183766 -232.018329) (xy 82.234287 -232.024463) (xy 82.283171 -232.038623) (xy 82.32915 -232.06044)
			(xy 82.371034 -232.08935) (xy 82.407738 -232.124605) (xy 82.438311 -232.165291) (xy 82.461962 -232.210354)
			(xy 82.478078 -232.258628) (xy 82.486242 -232.308862) (xy 82.486754 -232.334308) (xy 82.805282 -232.334308)
			(xy 82.809242 -232.285254) (xy 82.821019 -232.23747) (xy 82.84031 -232.192194) (xy 82.866613 -232.150598)
			(xy 82.899248 -232.113761) (xy 82.937369 -232.082636) (xy 82.97999 -232.058029) (xy 83.026006 -232.040577)
			(xy 83.074225 -232.030733) (xy 83.1234 -232.028752) (xy 83.172255 -232.034684) (xy 83.219526 -232.048376)
			(xy 83.263988 -232.069474) (xy 83.304491 -232.09743) (xy 83.339984 -232.131522) (xy 83.369549 -232.170866)
			(xy 83.39242 -232.214443) (xy 83.408004 -232.261124) (xy 83.415899 -232.309701) (xy 83.416394 -232.334308)
			(xy 83.734905 -232.334308) (xy 83.739 -232.28358) (xy 83.751179 -232.234166) (xy 83.771127 -232.187346)
			(xy 83.798328 -232.144332) (xy 83.832076 -232.106238) (xy 83.871498 -232.074051) (xy 83.915572 -232.048605)
			(xy 83.963158 -232.030558) (xy 84.013022 -232.020378) (xy 84.063874 -232.018329) (xy 84.114395 -232.024463)
			(xy 84.163279 -232.038623) (xy 84.209258 -232.06044) (xy 84.251142 -232.08935) (xy 84.287846 -232.124605)
			(xy 84.318419 -232.165291) (xy 84.34207 -232.210354) (xy 84.358186 -232.258628) (xy 84.36635 -232.308862)
			(xy 84.366862 -232.334308) (xy 84.685136 -232.334308) (xy 84.689096 -232.285254) (xy 84.700873 -232.23747)
			(xy 84.720164 -232.192194) (xy 84.746467 -232.150598) (xy 84.779102 -232.113761) (xy 84.817223 -232.082636)
			(xy 84.859844 -232.058029) (xy 84.90586 -232.040577) (xy 84.954079 -232.030733) (xy 85.003254 -232.028752)
			(xy 85.052109 -232.034684) (xy 85.09938 -232.048376) (xy 85.143842 -232.069474) (xy 85.184345 -232.09743)
			(xy 85.219838 -232.131522) (xy 85.249403 -232.170866) (xy 85.272274 -232.214443) (xy 85.287858 -232.261124)
			(xy 85.295753 -232.309701) (xy 85.296248 -232.334308) (xy 85.614759 -232.334308) (xy 85.618854 -232.28358)
			(xy 85.631033 -232.234166) (xy 85.650981 -232.187346) (xy 85.678182 -232.144332) (xy 85.71193 -232.106238)
			(xy 85.751352 -232.074051) (xy 85.795426 -232.048605) (xy 85.843012 -232.030558) (xy 85.892876 -232.020378)
			(xy 85.943728 -232.018329) (xy 85.994249 -232.024463) (xy 86.043133 -232.038623) (xy 86.089112 -232.06044)
			(xy 86.130996 -232.08935) (xy 86.1677 -232.124605) (xy 86.198273 -232.165291) (xy 86.221924 -232.210354)
			(xy 86.23804 -232.258628) (xy 86.246204 -232.308862) (xy 86.246716 -232.334308) (xy 86.565244 -232.334308)
			(xy 86.569204 -232.285254) (xy 86.580981 -232.23747) (xy 86.600272 -232.192194) (xy 86.626575 -232.150598)
			(xy 86.65921 -232.113761) (xy 86.697331 -232.082636) (xy 86.739952 -232.058029) (xy 86.785968 -232.040577)
			(xy 86.834187 -232.030733) (xy 86.883362 -232.028752) (xy 86.932217 -232.034684) (xy 86.979488 -232.048376)
			(xy 87.02395 -232.069474) (xy 87.064453 -232.09743) (xy 87.099946 -232.131522) (xy 87.129511 -232.170866)
			(xy 87.152382 -232.214443) (xy 87.167966 -232.261124) (xy 87.175861 -232.309701) (xy 87.176356 -232.334308)
			(xy 87.494867 -232.334308) (xy 87.498962 -232.28358) (xy 87.511141 -232.234166) (xy 87.531089 -232.187346)
			(xy 87.55829 -232.144332) (xy 87.592038 -232.106238) (xy 87.63146 -232.074051) (xy 87.675534 -232.048605)
			(xy 87.72312 -232.030558) (xy 87.772984 -232.020378) (xy 87.823836 -232.018329) (xy 87.874357 -232.024463)
			(xy 87.923241 -232.038623) (xy 87.96922 -232.06044) (xy 88.011104 -232.08935) (xy 88.047808 -232.124605)
			(xy 88.078381 -232.165291) (xy 88.102032 -232.210354) (xy 88.118148 -232.258628) (xy 88.126312 -232.308862)
			(xy 88.126824 -232.334308) (xy 88.434921 -232.334308) (xy 88.439016 -232.28358) (xy 88.451195 -232.234166)
			(xy 88.471143 -232.187346) (xy 88.498344 -232.144332) (xy 88.532092 -232.106238) (xy 88.571514 -232.074051)
			(xy 88.615588 -232.048605) (xy 88.663174 -232.030558) (xy 88.713038 -232.020378) (xy 88.76389 -232.018329)
			(xy 88.814411 -232.024463) (xy 88.863295 -232.038623) (xy 88.909274 -232.06044) (xy 88.951158 -232.08935)
			(xy 88.987862 -232.124605) (xy 89.018435 -232.165291) (xy 89.042086 -232.210354) (xy 89.058202 -232.258628)
			(xy 89.066366 -232.308862) (xy 89.066878 -232.334308) (xy 89.385152 -232.334308) (xy 89.389112 -232.285254)
			(xy 89.400889 -232.23747) (xy 89.42018 -232.192194) (xy 89.446483 -232.150598) (xy 89.479118 -232.113761)
			(xy 89.517239 -232.082636) (xy 89.55986 -232.058029) (xy 89.605876 -232.040577) (xy 89.654095 -232.030733)
			(xy 89.70327 -232.028752) (xy 89.752125 -232.034684) (xy 89.799396 -232.048376) (xy 89.843858 -232.069474)
			(xy 89.884361 -232.09743) (xy 89.919854 -232.131522) (xy 89.949419 -232.170866) (xy 89.97229 -232.214443)
			(xy 89.987874 -232.261124) (xy 89.995769 -232.309701) (xy 89.996264 -232.334308) (xy 90.314775 -232.334308)
			(xy 90.31887 -232.28358) (xy 90.331049 -232.234166) (xy 90.350997 -232.187346) (xy 90.378198 -232.144332)
			(xy 90.411946 -232.106238) (xy 90.451368 -232.074051) (xy 90.495442 -232.048605) (xy 90.543028 -232.030558)
			(xy 90.592892 -232.020378) (xy 90.643744 -232.018329) (xy 90.694265 -232.024463) (xy 90.743149 -232.038623)
			(xy 90.789128 -232.06044) (xy 90.831012 -232.08935) (xy 90.867716 -232.124605) (xy 90.898289 -232.165291)
			(xy 90.92194 -232.210354) (xy 90.938056 -232.258628) (xy 90.94622 -232.308862) (xy 90.946732 -232.334308)
			(xy 91.26526 -232.334308) (xy 91.26922 -232.285254) (xy 91.280997 -232.23747) (xy 91.300288 -232.192194)
			(xy 91.326591 -232.150598) (xy 91.359226 -232.113761) (xy 91.397347 -232.082636) (xy 91.439968 -232.058029)
			(xy 91.485984 -232.040577) (xy 91.534203 -232.030733) (xy 91.583378 -232.028752) (xy 91.632233 -232.034684)
			(xy 91.679504 -232.048376) (xy 91.723966 -232.069474) (xy 91.764469 -232.09743) (xy 91.799962 -232.131522)
			(xy 91.829527 -232.170866) (xy 91.852398 -232.214443) (xy 91.867982 -232.261124) (xy 91.875877 -232.309701)
			(xy 91.876372 -232.334308) (xy 92.194883 -232.334308) (xy 92.198978 -232.28358) (xy 92.211157 -232.234166)
			(xy 92.231105 -232.187346) (xy 92.258306 -232.144332) (xy 92.292054 -232.106238) (xy 92.331476 -232.074051)
			(xy 92.37555 -232.048605) (xy 92.423136 -232.030558) (xy 92.473 -232.020378) (xy 92.523852 -232.018329)
			(xy 92.574373 -232.024463) (xy 92.623257 -232.038623) (xy 92.669236 -232.06044) (xy 92.71112 -232.08935)
			(xy 92.747824 -232.124605) (xy 92.778397 -232.165291) (xy 92.802048 -232.210354) (xy 92.818164 -232.258628)
			(xy 92.826328 -232.308862) (xy 92.82684 -232.334308) (xy 93.145114 -232.334308) (xy 93.149074 -232.285254)
			(xy 93.160851 -232.23747) (xy 93.180142 -232.192194) (xy 93.206445 -232.150598) (xy 93.23908 -232.113761)
			(xy 93.277201 -232.082636) (xy 93.319822 -232.058029) (xy 93.365838 -232.040577) (xy 93.414057 -232.030733)
			(xy 93.463232 -232.028752) (xy 93.512087 -232.034684) (xy 93.559358 -232.048376) (xy 93.60382 -232.069474)
			(xy 93.644323 -232.09743) (xy 93.679816 -232.131522) (xy 93.709381 -232.170866) (xy 93.732252 -232.214443)
			(xy 93.747836 -232.261124) (xy 93.755731 -232.309701) (xy 93.756226 -232.334308) (xy 94.074737 -232.334308)
			(xy 94.078832 -232.28358) (xy 94.091011 -232.234166) (xy 94.110959 -232.187346) (xy 94.13816 -232.144332)
			(xy 94.171908 -232.106238) (xy 94.21133 -232.074051) (xy 94.255404 -232.048605) (xy 94.30299 -232.030558)
			(xy 94.352854 -232.020378) (xy 94.403706 -232.018329) (xy 94.454227 -232.024463) (xy 94.503111 -232.038623)
			(xy 94.54909 -232.06044) (xy 94.590974 -232.08935) (xy 94.627678 -232.124605) (xy 94.658251 -232.165291)
			(xy 94.681902 -232.210354) (xy 94.698018 -232.258628) (xy 94.706182 -232.308862) (xy 94.706694 -232.334308)
			(xy 95.014791 -232.334308) (xy 95.018886 -232.28358) (xy 95.031065 -232.234166) (xy 95.051013 -232.187346)
			(xy 95.078214 -232.144332) (xy 95.111962 -232.106238) (xy 95.151384 -232.074051) (xy 95.195458 -232.048605)
			(xy 95.243044 -232.030558) (xy 95.292908 -232.020378) (xy 95.34376 -232.018329) (xy 95.394281 -232.024463)
			(xy 95.443165 -232.038623) (xy 95.489144 -232.06044) (xy 95.531028 -232.08935) (xy 95.567732 -232.124605)
			(xy 95.598305 -232.165291) (xy 95.621956 -232.210354) (xy 95.638072 -232.258628) (xy 95.646236 -232.308862)
			(xy 95.646748 -232.334308) (xy 95.965276 -232.334308) (xy 95.969236 -232.285254) (xy 95.981013 -232.23747)
			(xy 96.000304 -232.192194) (xy 96.026607 -232.150598) (xy 96.059242 -232.113761) (xy 96.097363 -232.082636)
			(xy 96.139984 -232.058029) (xy 96.186 -232.040577) (xy 96.234219 -232.030733) (xy 96.283394 -232.028752)
			(xy 96.332249 -232.034684) (xy 96.37952 -232.048376) (xy 96.423982 -232.069474) (xy 96.464485 -232.09743)
			(xy 96.499978 -232.131522) (xy 96.529543 -232.170866) (xy 96.552414 -232.214443) (xy 96.567998 -232.261124)
			(xy 96.575893 -232.309701) (xy 96.576388 -232.334308) (xy 96.90533 -232.334308) (xy 96.90929 -232.285254)
			(xy 96.921067 -232.23747) (xy 96.940358 -232.192194) (xy 96.966661 -232.150598) (xy 96.999296 -232.113761)
			(xy 97.037417 -232.082636) (xy 97.080038 -232.058029) (xy 97.126054 -232.040577) (xy 97.174273 -232.030733)
			(xy 97.223448 -232.028752) (xy 97.272303 -232.034684) (xy 97.319574 -232.048376) (xy 97.364036 -232.069474)
			(xy 97.404539 -232.09743) (xy 97.440032 -232.131522) (xy 97.469597 -232.170866) (xy 97.492468 -232.214443)
			(xy 97.508052 -232.261124) (xy 97.515947 -232.309701) (xy 97.516442 -232.334308) (xy 97.84513 -232.334308)
			(xy 97.84909 -232.285254) (xy 97.860867 -232.23747) (xy 97.880158 -232.192194) (xy 97.906461 -232.150598)
			(xy 97.939096 -232.113761) (xy 97.977217 -232.082636) (xy 98.019838 -232.058029) (xy 98.065854 -232.040577)
			(xy 98.114073 -232.030733) (xy 98.163248 -232.028752) (xy 98.212103 -232.034684) (xy 98.259374 -232.048376)
			(xy 98.303836 -232.069474) (xy 98.344339 -232.09743) (xy 98.379832 -232.131522) (xy 98.409397 -232.170866)
			(xy 98.432268 -232.214443) (xy 98.447852 -232.261124) (xy 98.455747 -232.309701) (xy 98.456242 -232.334308)
			(xy 98.785184 -232.334308) (xy 98.789144 -232.285254) (xy 98.800921 -232.23747) (xy 98.820212 -232.192194)
			(xy 98.846515 -232.150598) (xy 98.87915 -232.113761) (xy 98.917271 -232.082636) (xy 98.959892 -232.058029)
			(xy 99.005908 -232.040577) (xy 99.054127 -232.030733) (xy 99.103302 -232.028752) (xy 99.152157 -232.034684)
			(xy 99.199428 -232.048376) (xy 99.24389 -232.069474) (xy 99.284393 -232.09743) (xy 99.319886 -232.131522)
			(xy 99.349451 -232.170866) (xy 99.372322 -232.214443) (xy 99.387906 -232.261124) (xy 99.395801 -232.309701)
			(xy 99.396296 -232.334308) (xy 99.725238 -232.334308) (xy 99.729198 -232.285254) (xy 99.740975 -232.23747)
			(xy 99.760266 -232.192194) (xy 99.786569 -232.150598) (xy 99.819204 -232.113761) (xy 99.857325 -232.082636)
			(xy 99.899946 -232.058029) (xy 99.945962 -232.040577) (xy 99.994181 -232.030733) (xy 100.043356 -232.028752)
			(xy 100.092211 -232.034684) (xy 100.139482 -232.048376) (xy 100.183944 -232.069474) (xy 100.224447 -232.09743)
			(xy 100.25994 -232.131522) (xy 100.289505 -232.170866) (xy 100.312376 -232.214443) (xy 100.32796 -232.261124)
			(xy 100.335855 -232.309701) (xy 100.33635 -232.334308) (xy 100.665292 -232.334308) (xy 100.669252 -232.285254)
			(xy 100.681029 -232.23747) (xy 100.70032 -232.192194) (xy 100.726623 -232.150598) (xy 100.759258 -232.113761)
			(xy 100.797379 -232.082636) (xy 100.84 -232.058029) (xy 100.886016 -232.040577) (xy 100.934235 -232.030733)
			(xy 100.98341 -232.028752) (xy 101.032265 -232.034684) (xy 101.079536 -232.048376) (xy 101.123998 -232.069474)
			(xy 101.164501 -232.09743) (xy 101.199994 -232.131522) (xy 101.229559 -232.170866) (xy 101.25243 -232.214443)
			(xy 101.268014 -232.261124) (xy 101.275909 -232.309701) (xy 101.276404 -232.334308) (xy 101.605346 -232.334308)
			(xy 101.609306 -232.285254) (xy 101.621083 -232.23747) (xy 101.640374 -232.192194) (xy 101.666677 -232.150598)
			(xy 101.699312 -232.113761) (xy 101.737433 -232.082636) (xy 101.780054 -232.058029) (xy 101.82607 -232.040577)
			(xy 101.874289 -232.030733) (xy 101.923464 -232.028752) (xy 101.972319 -232.034684) (xy 102.01959 -232.048376)
			(xy 102.064052 -232.069474) (xy 102.104555 -232.09743) (xy 102.140048 -232.131522) (xy 102.169613 -232.170866)
			(xy 102.192484 -232.214443) (xy 102.208068 -232.261124) (xy 102.215963 -232.309701) (xy 102.216458 -232.334308)
			(xy 102.545146 -232.334308) (xy 102.549106 -232.285254) (xy 102.560883 -232.23747) (xy 102.580174 -232.192194)
			(xy 102.606477 -232.150598) (xy 102.639112 -232.113761) (xy 102.677233 -232.082636) (xy 102.719854 -232.058029)
			(xy 102.76587 -232.040577) (xy 102.814089 -232.030733) (xy 102.863264 -232.028752) (xy 102.912119 -232.034684)
			(xy 102.95939 -232.048376) (xy 103.003852 -232.069474) (xy 103.044355 -232.09743) (xy 103.079848 -232.131522)
			(xy 103.109413 -232.170866) (xy 103.132284 -232.214443) (xy 103.147868 -232.261124) (xy 103.155763 -232.309701)
			(xy 103.156258 -232.334308) (xy 103.4852 -232.334308) (xy 103.48916 -232.285254) (xy 103.500937 -232.23747)
			(xy 103.520228 -232.192194) (xy 103.546531 -232.150598) (xy 103.579166 -232.113761) (xy 103.617287 -232.082636)
			(xy 103.659908 -232.058029) (xy 103.705924 -232.040577) (xy 103.754143 -232.030733) (xy 103.803318 -232.028752)
			(xy 103.852173 -232.034684) (xy 103.899444 -232.048376) (xy 103.943906 -232.069474) (xy 103.984409 -232.09743)
			(xy 104.019902 -232.131522) (xy 104.049467 -232.170866) (xy 104.072338 -232.214443) (xy 104.087922 -232.261124)
			(xy 104.095817 -232.309701) (xy 104.096312 -232.334308) (xy 104.425254 -232.334308) (xy 104.429214 -232.285254)
			(xy 104.440991 -232.23747) (xy 104.460282 -232.192194) (xy 104.486585 -232.150598) (xy 104.51922 -232.113761)
			(xy 104.557341 -232.082636) (xy 104.599962 -232.058029) (xy 104.645978 -232.040577) (xy 104.694197 -232.030733)
			(xy 104.743372 -232.028752) (xy 104.792227 -232.034684) (xy 104.839498 -232.048376) (xy 104.88396 -232.069474)
			(xy 104.924463 -232.09743) (xy 104.959956 -232.131522) (xy 104.989521 -232.170866) (xy 105.012392 -232.214443)
			(xy 105.027976 -232.261124) (xy 105.035871 -232.309701) (xy 105.036366 -232.334308) (xy 105.365308 -232.334308)
			(xy 105.369268 -232.285254) (xy 105.381045 -232.23747) (xy 105.400336 -232.192194) (xy 105.426639 -232.150598)
			(xy 105.459274 -232.113761) (xy 105.497395 -232.082636) (xy 105.540016 -232.058029) (xy 105.586032 -232.040577)
			(xy 105.634251 -232.030733) (xy 105.683426 -232.028752) (xy 105.732281 -232.034684) (xy 105.779552 -232.048376)
			(xy 105.824014 -232.069474) (xy 105.864517 -232.09743) (xy 105.90001 -232.131522) (xy 105.929575 -232.170866)
			(xy 105.952446 -232.214443) (xy 105.96803 -232.261124) (xy 105.975925 -232.309701) (xy 105.97642 -232.334308)
			(xy 106.305362 -232.334308) (xy 106.309322 -232.285254) (xy 106.321099 -232.23747) (xy 106.34039 -232.192194)
			(xy 106.366693 -232.150598) (xy 106.399328 -232.113761) (xy 106.437449 -232.082636) (xy 106.48007 -232.058029)
			(xy 106.526086 -232.040577) (xy 106.574305 -232.030733) (xy 106.62348 -232.028752) (xy 106.672335 -232.034684)
			(xy 106.719606 -232.048376) (xy 106.764068 -232.069474) (xy 106.804571 -232.09743) (xy 106.840064 -232.131522)
			(xy 106.869629 -232.170866) (xy 106.8925 -232.214443) (xy 106.908084 -232.261124) (xy 106.915979 -232.309701)
			(xy 106.916474 -232.334308) (xy 107.245162 -232.334308) (xy 107.249122 -232.285254) (xy 107.260899 -232.23747)
			(xy 107.28019 -232.192194) (xy 107.306493 -232.150598) (xy 107.339128 -232.113761) (xy 107.377249 -232.082636)
			(xy 107.41987 -232.058029) (xy 107.465886 -232.040577) (xy 107.514105 -232.030733) (xy 107.56328 -232.028752)
			(xy 107.612135 -232.034684) (xy 107.659406 -232.048376) (xy 107.703868 -232.069474) (xy 107.744371 -232.09743)
			(xy 107.779864 -232.131522) (xy 107.809429 -232.170866) (xy 107.8323 -232.214443) (xy 107.847884 -232.261124)
			(xy 107.855779 -232.309701) (xy 107.856274 -232.334308) (xy 108.174785 -232.334308) (xy 108.17888 -232.28358)
			(xy 108.191059 -232.234166) (xy 108.211007 -232.187346) (xy 108.238208 -232.144332) (xy 108.271956 -232.106238)
			(xy 108.311378 -232.074051) (xy 108.355452 -232.048605) (xy 108.403038 -232.030558) (xy 108.452902 -232.020378)
			(xy 108.503754 -232.018329) (xy 108.554275 -232.024463) (xy 108.603159 -232.038623) (xy 108.649138 -232.06044)
			(xy 108.691022 -232.08935) (xy 108.727726 -232.124605) (xy 108.758299 -232.165291) (xy 108.78195 -232.210354)
			(xy 108.798066 -232.258628) (xy 108.80623 -232.308862) (xy 108.806742 -232.334308) (xy 109.114839 -232.334308)
			(xy 109.118934 -232.28358) (xy 109.131113 -232.234166) (xy 109.151061 -232.187346) (xy 109.178262 -232.144332)
			(xy 109.21201 -232.106238) (xy 109.251432 -232.074051) (xy 109.295506 -232.048605) (xy 109.343092 -232.030558)
			(xy 109.392956 -232.020378) (xy 109.443808 -232.018329) (xy 109.494329 -232.024463) (xy 109.543213 -232.038623)
			(xy 109.589192 -232.06044) (xy 109.631076 -232.08935) (xy 109.66778 -232.124605) (xy 109.698353 -232.165291)
			(xy 109.722004 -232.210354) (xy 109.73812 -232.258628) (xy 109.746284 -232.308862) (xy 109.746796 -232.334308)
			(xy 110.065324 -232.334308) (xy 110.069284 -232.285254) (xy 110.081061 -232.23747) (xy 110.100352 -232.192194)
			(xy 110.126655 -232.150598) (xy 110.15929 -232.113761) (xy 110.197411 -232.082636) (xy 110.240032 -232.058029)
			(xy 110.286048 -232.040577) (xy 110.334267 -232.030733) (xy 110.383442 -232.028752) (xy 110.432297 -232.034684)
			(xy 110.479568 -232.048376) (xy 110.52403 -232.069474) (xy 110.564533 -232.09743) (xy 110.600026 -232.131522)
			(xy 110.629591 -232.170866) (xy 110.652462 -232.214443) (xy 110.668046 -232.261124) (xy 110.675941 -232.309701)
			(xy 110.676436 -232.334308) (xy 110.675941 -232.358915) (xy 110.668046 -232.407492) (xy 110.652462 -232.454173)
			(xy 110.629591 -232.49775) (xy 110.600026 -232.537094) (xy 110.564533 -232.571186) (xy 110.52403 -232.599142)
			(xy 110.479568 -232.62024) (xy 110.432297 -232.633932) (xy 110.383442 -232.639864) (xy 110.334267 -232.637883)
			(xy 110.286048 -232.628039) (xy 110.240032 -232.610587) (xy 110.197411 -232.58598) (xy 110.15929 -232.554855)
			(xy 110.126655 -232.518018) (xy 110.100352 -232.476422) (xy 110.081061 -232.431146) (xy 110.069284 -232.383362)
			(xy 110.065324 -232.334308) (xy 109.746796 -232.334308) (xy 109.746284 -232.359754) (xy 109.73812 -232.409988)
			(xy 109.722004 -232.458262) (xy 109.698353 -232.503325) (xy 109.66778 -232.544011) (xy 109.631076 -232.579266)
			(xy 109.589192 -232.608176) (xy 109.543213 -232.629993) (xy 109.494329 -232.644153) (xy 109.443808 -232.650287)
			(xy 109.392956 -232.648238) (xy 109.343092 -232.638058) (xy 109.295506 -232.620011) (xy 109.251432 -232.594565)
			(xy 109.21201 -232.562378) (xy 109.178262 -232.524284) (xy 109.151061 -232.48127) (xy 109.131113 -232.43445)
			(xy 109.118934 -232.385036) (xy 109.114839 -232.334308) (xy 108.806742 -232.334308) (xy 108.80623 -232.359754)
			(xy 108.798066 -232.409988) (xy 108.78195 -232.458262) (xy 108.758299 -232.503325) (xy 108.727726 -232.544011)
			(xy 108.691022 -232.579266) (xy 108.649138 -232.608176) (xy 108.603159 -232.629993) (xy 108.554275 -232.644153)
			(xy 108.503754 -232.650287) (xy 108.452902 -232.648238) (xy 108.403038 -232.638058) (xy 108.355452 -232.620011)
			(xy 108.311378 -232.594565) (xy 108.271956 -232.562378) (xy 108.238208 -232.524284) (xy 108.211007 -232.48127)
			(xy 108.191059 -232.43445) (xy 108.17888 -232.385036) (xy 108.174785 -232.334308) (xy 107.856274 -232.334308)
			(xy 107.855779 -232.358915) (xy 107.847884 -232.407492) (xy 107.8323 -232.454173) (xy 107.809429 -232.49775)
			(xy 107.779864 -232.537094) (xy 107.744371 -232.571186) (xy 107.703868 -232.599142) (xy 107.659406 -232.62024)
			(xy 107.612135 -232.633932) (xy 107.56328 -232.639864) (xy 107.514105 -232.637883) (xy 107.465886 -232.628039)
			(xy 107.41987 -232.610587) (xy 107.377249 -232.58598) (xy 107.339128 -232.554855) (xy 107.306493 -232.518018)
			(xy 107.28019 -232.476422) (xy 107.260899 -232.431146) (xy 107.249122 -232.383362) (xy 107.245162 -232.334308)
			(xy 106.916474 -232.334308) (xy 106.915979 -232.358915) (xy 106.908084 -232.407492) (xy 106.8925 -232.454173)
			(xy 106.869629 -232.49775) (xy 106.840064 -232.537094) (xy 106.804571 -232.571186) (xy 106.764068 -232.599142)
			(xy 106.719606 -232.62024) (xy 106.672335 -232.633932) (xy 106.62348 -232.639864) (xy 106.574305 -232.637883)
			(xy 106.526086 -232.628039) (xy 106.48007 -232.610587) (xy 106.437449 -232.58598) (xy 106.399328 -232.554855)
			(xy 106.366693 -232.518018) (xy 106.34039 -232.476422) (xy 106.321099 -232.431146) (xy 106.309322 -232.383362)
			(xy 106.305362 -232.334308) (xy 105.97642 -232.334308) (xy 105.975925 -232.358915) (xy 105.96803 -232.407492)
			(xy 105.952446 -232.454173) (xy 105.929575 -232.49775) (xy 105.90001 -232.537094) (xy 105.864517 -232.571186)
			(xy 105.824014 -232.599142) (xy 105.779552 -232.62024) (xy 105.732281 -232.633932) (xy 105.683426 -232.639864)
			(xy 105.634251 -232.637883) (xy 105.586032 -232.628039) (xy 105.540016 -232.610587) (xy 105.497395 -232.58598)
			(xy 105.459274 -232.554855) (xy 105.426639 -232.518018) (xy 105.400336 -232.476422) (xy 105.381045 -232.431146)
			(xy 105.369268 -232.383362) (xy 105.365308 -232.334308) (xy 105.036366 -232.334308) (xy 105.035871 -232.358915)
			(xy 105.027976 -232.407492) (xy 105.012392 -232.454173) (xy 104.989521 -232.49775) (xy 104.959956 -232.537094)
			(xy 104.924463 -232.571186) (xy 104.88396 -232.599142) (xy 104.839498 -232.62024) (xy 104.792227 -232.633932)
			(xy 104.743372 -232.639864) (xy 104.694197 -232.637883) (xy 104.645978 -232.628039) (xy 104.599962 -232.610587)
			(xy 104.557341 -232.58598) (xy 104.51922 -232.554855) (xy 104.486585 -232.518018) (xy 104.460282 -232.476422)
			(xy 104.440991 -232.431146) (xy 104.429214 -232.383362) (xy 104.425254 -232.334308) (xy 104.096312 -232.334308)
			(xy 104.095817 -232.358915) (xy 104.087922 -232.407492) (xy 104.072338 -232.454173) (xy 104.049467 -232.49775)
			(xy 104.019902 -232.537094) (xy 103.984409 -232.571186) (xy 103.943906 -232.599142) (xy 103.899444 -232.62024)
			(xy 103.852173 -232.633932) (xy 103.803318 -232.639864) (xy 103.754143 -232.637883) (xy 103.705924 -232.628039)
			(xy 103.659908 -232.610587) (xy 103.617287 -232.58598) (xy 103.579166 -232.554855) (xy 103.546531 -232.518018)
			(xy 103.520228 -232.476422) (xy 103.500937 -232.431146) (xy 103.48916 -232.383362) (xy 103.4852 -232.334308)
			(xy 103.156258 -232.334308) (xy 103.155763 -232.358915) (xy 103.147868 -232.407492) (xy 103.132284 -232.454173)
			(xy 103.109413 -232.49775) (xy 103.079848 -232.537094) (xy 103.044355 -232.571186) (xy 103.003852 -232.599142)
			(xy 102.95939 -232.62024) (xy 102.912119 -232.633932) (xy 102.863264 -232.639864) (xy 102.814089 -232.637883)
			(xy 102.76587 -232.628039) (xy 102.719854 -232.610587) (xy 102.677233 -232.58598) (xy 102.639112 -232.554855)
			(xy 102.606477 -232.518018) (xy 102.580174 -232.476422) (xy 102.560883 -232.431146) (xy 102.549106 -232.383362)
			(xy 102.545146 -232.334308) (xy 102.216458 -232.334308) (xy 102.215963 -232.358915) (xy 102.208068 -232.407492)
			(xy 102.192484 -232.454173) (xy 102.169613 -232.49775) (xy 102.140048 -232.537094) (xy 102.104555 -232.571186)
			(xy 102.064052 -232.599142) (xy 102.01959 -232.62024) (xy 101.972319 -232.633932) (xy 101.923464 -232.639864)
			(xy 101.874289 -232.637883) (xy 101.82607 -232.628039) (xy 101.780054 -232.610587) (xy 101.737433 -232.58598)
			(xy 101.699312 -232.554855) (xy 101.666677 -232.518018) (xy 101.640374 -232.476422) (xy 101.621083 -232.431146)
			(xy 101.609306 -232.383362) (xy 101.605346 -232.334308) (xy 101.276404 -232.334308) (xy 101.275909 -232.358915)
			(xy 101.268014 -232.407492) (xy 101.25243 -232.454173) (xy 101.229559 -232.49775) (xy 101.199994 -232.537094)
			(xy 101.164501 -232.571186) (xy 101.123998 -232.599142) (xy 101.079536 -232.62024) (xy 101.032265 -232.633932)
			(xy 100.98341 -232.639864) (xy 100.934235 -232.637883) (xy 100.886016 -232.628039) (xy 100.84 -232.610587)
			(xy 100.797379 -232.58598) (xy 100.759258 -232.554855) (xy 100.726623 -232.518018) (xy 100.70032 -232.476422)
			(xy 100.681029 -232.431146) (xy 100.669252 -232.383362) (xy 100.665292 -232.334308) (xy 100.33635 -232.334308)
			(xy 100.335855 -232.358915) (xy 100.32796 -232.407492) (xy 100.312376 -232.454173) (xy 100.289505 -232.49775)
			(xy 100.25994 -232.537094) (xy 100.224447 -232.571186) (xy 100.183944 -232.599142) (xy 100.139482 -232.62024)
			(xy 100.092211 -232.633932) (xy 100.043356 -232.639864) (xy 99.994181 -232.637883) (xy 99.945962 -232.628039)
			(xy 99.899946 -232.610587) (xy 99.857325 -232.58598) (xy 99.819204 -232.554855) (xy 99.786569 -232.518018)
			(xy 99.760266 -232.476422) (xy 99.740975 -232.431146) (xy 99.729198 -232.383362) (xy 99.725238 -232.334308)
			(xy 99.396296 -232.334308) (xy 99.395801 -232.358915) (xy 99.387906 -232.407492) (xy 99.372322 -232.454173)
			(xy 99.349451 -232.49775) (xy 99.319886 -232.537094) (xy 99.284393 -232.571186) (xy 99.24389 -232.599142)
			(xy 99.199428 -232.62024) (xy 99.152157 -232.633932) (xy 99.103302 -232.639864) (xy 99.054127 -232.637883)
			(xy 99.005908 -232.628039) (xy 98.959892 -232.610587) (xy 98.917271 -232.58598) (xy 98.87915 -232.554855)
			(xy 98.846515 -232.518018) (xy 98.820212 -232.476422) (xy 98.800921 -232.431146) (xy 98.789144 -232.383362)
			(xy 98.785184 -232.334308) (xy 98.456242 -232.334308) (xy 98.455747 -232.358915) (xy 98.447852 -232.407492)
			(xy 98.432268 -232.454173) (xy 98.409397 -232.49775) (xy 98.379832 -232.537094) (xy 98.344339 -232.571186)
			(xy 98.303836 -232.599142) (xy 98.259374 -232.62024) (xy 98.212103 -232.633932) (xy 98.163248 -232.639864)
			(xy 98.114073 -232.637883) (xy 98.065854 -232.628039) (xy 98.019838 -232.610587) (xy 97.977217 -232.58598)
			(xy 97.939096 -232.554855) (xy 97.906461 -232.518018) (xy 97.880158 -232.476422) (xy 97.860867 -232.431146)
			(xy 97.84909 -232.383362) (xy 97.84513 -232.334308) (xy 97.516442 -232.334308) (xy 97.515947 -232.358915)
			(xy 97.508052 -232.407492) (xy 97.492468 -232.454173) (xy 97.469597 -232.49775) (xy 97.440032 -232.537094)
			(xy 97.404539 -232.571186) (xy 97.364036 -232.599142) (xy 97.319574 -232.62024) (xy 97.272303 -232.633932)
			(xy 97.223448 -232.639864) (xy 97.174273 -232.637883) (xy 97.126054 -232.628039) (xy 97.080038 -232.610587)
			(xy 97.037417 -232.58598) (xy 96.999296 -232.554855) (xy 96.966661 -232.518018) (xy 96.940358 -232.476422)
			(xy 96.921067 -232.431146) (xy 96.90929 -232.383362) (xy 96.90533 -232.334308) (xy 96.576388 -232.334308)
			(xy 96.575893 -232.358915) (xy 96.567998 -232.407492) (xy 96.552414 -232.454173) (xy 96.529543 -232.49775)
			(xy 96.499978 -232.537094) (xy 96.464485 -232.571186) (xy 96.423982 -232.599142) (xy 96.37952 -232.62024)
			(xy 96.332249 -232.633932) (xy 96.283394 -232.639864) (xy 96.234219 -232.637883) (xy 96.186 -232.628039)
			(xy 96.139984 -232.610587) (xy 96.097363 -232.58598) (xy 96.059242 -232.554855) (xy 96.026607 -232.518018)
			(xy 96.000304 -232.476422) (xy 95.981013 -232.431146) (xy 95.969236 -232.383362) (xy 95.965276 -232.334308)
			(xy 95.646748 -232.334308) (xy 95.646236 -232.359754) (xy 95.638072 -232.409988) (xy 95.621956 -232.458262)
			(xy 95.598305 -232.503325) (xy 95.567732 -232.544011) (xy 95.531028 -232.579266) (xy 95.489144 -232.608176)
			(xy 95.443165 -232.629993) (xy 95.394281 -232.644153) (xy 95.34376 -232.650287) (xy 95.292908 -232.648238)
			(xy 95.243044 -232.638058) (xy 95.195458 -232.620011) (xy 95.151384 -232.594565) (xy 95.111962 -232.562378)
			(xy 95.078214 -232.524284) (xy 95.051013 -232.48127) (xy 95.031065 -232.43445) (xy 95.018886 -232.385036)
			(xy 95.014791 -232.334308) (xy 94.706694 -232.334308) (xy 94.706182 -232.359754) (xy 94.698018 -232.409988)
			(xy 94.681902 -232.458262) (xy 94.658251 -232.503325) (xy 94.627678 -232.544011) (xy 94.590974 -232.579266)
			(xy 94.54909 -232.608176) (xy 94.503111 -232.629993) (xy 94.454227 -232.644153) (xy 94.403706 -232.650287)
			(xy 94.352854 -232.648238) (xy 94.30299 -232.638058) (xy 94.255404 -232.620011) (xy 94.21133 -232.594565)
			(xy 94.171908 -232.562378) (xy 94.13816 -232.524284) (xy 94.110959 -232.48127) (xy 94.091011 -232.43445)
			(xy 94.078832 -232.385036) (xy 94.074737 -232.334308) (xy 93.756226 -232.334308) (xy 93.755731 -232.358915)
			(xy 93.747836 -232.407492) (xy 93.732252 -232.454173) (xy 93.709381 -232.49775) (xy 93.679816 -232.537094)
			(xy 93.644323 -232.571186) (xy 93.60382 -232.599142) (xy 93.559358 -232.62024) (xy 93.512087 -232.633932)
			(xy 93.463232 -232.639864) (xy 93.414057 -232.637883) (xy 93.365838 -232.628039) (xy 93.319822 -232.610587)
			(xy 93.277201 -232.58598) (xy 93.23908 -232.554855) (xy 93.206445 -232.518018) (xy 93.180142 -232.476422)
			(xy 93.160851 -232.431146) (xy 93.149074 -232.383362) (xy 93.145114 -232.334308) (xy 92.82684 -232.334308)
			(xy 92.826328 -232.359754) (xy 92.818164 -232.409988) (xy 92.802048 -232.458262) (xy 92.778397 -232.503325)
			(xy 92.747824 -232.544011) (xy 92.71112 -232.579266) (xy 92.669236 -232.608176) (xy 92.623257 -232.629993)
			(xy 92.574373 -232.644153) (xy 92.523852 -232.650287) (xy 92.473 -232.648238) (xy 92.423136 -232.638058)
			(xy 92.37555 -232.620011) (xy 92.331476 -232.594565) (xy 92.292054 -232.562378) (xy 92.258306 -232.524284)
			(xy 92.231105 -232.48127) (xy 92.211157 -232.43445) (xy 92.198978 -232.385036) (xy 92.194883 -232.334308)
			(xy 91.876372 -232.334308) (xy 91.875877 -232.358915) (xy 91.867982 -232.407492) (xy 91.852398 -232.454173)
			(xy 91.829527 -232.49775) (xy 91.799962 -232.537094) (xy 91.764469 -232.571186) (xy 91.723966 -232.599142)
			(xy 91.679504 -232.62024) (xy 91.632233 -232.633932) (xy 91.583378 -232.639864) (xy 91.534203 -232.637883)
			(xy 91.485984 -232.628039) (xy 91.439968 -232.610587) (xy 91.397347 -232.58598) (xy 91.359226 -232.554855)
			(xy 91.326591 -232.518018) (xy 91.300288 -232.476422) (xy 91.280997 -232.431146) (xy 91.26922 -232.383362)
			(xy 91.26526 -232.334308) (xy 90.946732 -232.334308) (xy 90.94622 -232.359754) (xy 90.938056 -232.409988)
			(xy 90.92194 -232.458262) (xy 90.898289 -232.503325) (xy 90.867716 -232.544011) (xy 90.831012 -232.579266)
			(xy 90.789128 -232.608176) (xy 90.743149 -232.629993) (xy 90.694265 -232.644153) (xy 90.643744 -232.650287)
			(xy 90.592892 -232.648238) (xy 90.543028 -232.638058) (xy 90.495442 -232.620011) (xy 90.451368 -232.594565)
			(xy 90.411946 -232.562378) (xy 90.378198 -232.524284) (xy 90.350997 -232.48127) (xy 90.331049 -232.43445)
			(xy 90.31887 -232.385036) (xy 90.314775 -232.334308) (xy 89.996264 -232.334308) (xy 89.995769 -232.358915)
			(xy 89.987874 -232.407492) (xy 89.97229 -232.454173) (xy 89.949419 -232.49775) (xy 89.919854 -232.537094)
			(xy 89.884361 -232.571186) (xy 89.843858 -232.599142) (xy 89.799396 -232.62024) (xy 89.752125 -232.633932)
			(xy 89.70327 -232.639864) (xy 89.654095 -232.637883) (xy 89.605876 -232.628039) (xy 89.55986 -232.610587)
			(xy 89.517239 -232.58598) (xy 89.479118 -232.554855) (xy 89.446483 -232.518018) (xy 89.42018 -232.476422)
			(xy 89.400889 -232.431146) (xy 89.389112 -232.383362) (xy 89.385152 -232.334308) (xy 89.066878 -232.334308)
			(xy 89.066366 -232.359754) (xy 89.058202 -232.409988) (xy 89.042086 -232.458262) (xy 89.018435 -232.503325)
			(xy 88.987862 -232.544011) (xy 88.951158 -232.579266) (xy 88.909274 -232.608176) (xy 88.863295 -232.629993)
			(xy 88.814411 -232.644153) (xy 88.76389 -232.650287) (xy 88.713038 -232.648238) (xy 88.663174 -232.638058)
			(xy 88.615588 -232.620011) (xy 88.571514 -232.594565) (xy 88.532092 -232.562378) (xy 88.498344 -232.524284)
			(xy 88.471143 -232.48127) (xy 88.451195 -232.43445) (xy 88.439016 -232.385036) (xy 88.434921 -232.334308)
			(xy 88.126824 -232.334308) (xy 88.126312 -232.359754) (xy 88.118148 -232.409988) (xy 88.102032 -232.458262)
			(xy 88.078381 -232.503325) (xy 88.047808 -232.544011) (xy 88.011104 -232.579266) (xy 87.96922 -232.608176)
			(xy 87.923241 -232.629993) (xy 87.874357 -232.644153) (xy 87.823836 -232.650287) (xy 87.772984 -232.648238)
			(xy 87.72312 -232.638058) (xy 87.675534 -232.620011) (xy 87.63146 -232.594565) (xy 87.592038 -232.562378)
			(xy 87.55829 -232.524284) (xy 87.531089 -232.48127) (xy 87.511141 -232.43445) (xy 87.498962 -232.385036)
			(xy 87.494867 -232.334308) (xy 87.176356 -232.334308) (xy 87.175861 -232.358915) (xy 87.167966 -232.407492)
			(xy 87.152382 -232.454173) (xy 87.129511 -232.49775) (xy 87.099946 -232.537094) (xy 87.064453 -232.571186)
			(xy 87.02395 -232.599142) (xy 86.979488 -232.62024) (xy 86.932217 -232.633932) (xy 86.883362 -232.639864)
			(xy 86.834187 -232.637883) (xy 86.785968 -232.628039) (xy 86.739952 -232.610587) (xy 86.697331 -232.58598)
			(xy 86.65921 -232.554855) (xy 86.626575 -232.518018) (xy 86.600272 -232.476422) (xy 86.580981 -232.431146)
			(xy 86.569204 -232.383362) (xy 86.565244 -232.334308) (xy 86.246716 -232.334308) (xy 86.246204 -232.359754)
			(xy 86.23804 -232.409988) (xy 86.221924 -232.458262) (xy 86.198273 -232.503325) (xy 86.1677 -232.544011)
			(xy 86.130996 -232.579266) (xy 86.089112 -232.608176) (xy 86.043133 -232.629993) (xy 85.994249 -232.644153)
			(xy 85.943728 -232.650287) (xy 85.892876 -232.648238) (xy 85.843012 -232.638058) (xy 85.795426 -232.620011)
			(xy 85.751352 -232.594565) (xy 85.71193 -232.562378) (xy 85.678182 -232.524284) (xy 85.650981 -232.48127)
			(xy 85.631033 -232.43445) (xy 85.618854 -232.385036) (xy 85.614759 -232.334308) (xy 85.296248 -232.334308)
			(xy 85.295753 -232.358915) (xy 85.287858 -232.407492) (xy 85.272274 -232.454173) (xy 85.249403 -232.49775)
			(xy 85.219838 -232.537094) (xy 85.184345 -232.571186) (xy 85.143842 -232.599142) (xy 85.09938 -232.62024)
			(xy 85.052109 -232.633932) (xy 85.003254 -232.639864) (xy 84.954079 -232.637883) (xy 84.90586 -232.628039)
			(xy 84.859844 -232.610587) (xy 84.817223 -232.58598) (xy 84.779102 -232.554855) (xy 84.746467 -232.518018)
			(xy 84.720164 -232.476422) (xy 84.700873 -232.431146) (xy 84.689096 -232.383362) (xy 84.685136 -232.334308)
			(xy 84.366862 -232.334308) (xy 84.36635 -232.359754) (xy 84.358186 -232.409988) (xy 84.34207 -232.458262)
			(xy 84.318419 -232.503325) (xy 84.287846 -232.544011) (xy 84.251142 -232.579266) (xy 84.209258 -232.608176)
			(xy 84.163279 -232.629993) (xy 84.114395 -232.644153) (xy 84.063874 -232.650287) (xy 84.013022 -232.648238)
			(xy 83.963158 -232.638058) (xy 83.915572 -232.620011) (xy 83.871498 -232.594565) (xy 83.832076 -232.562378)
			(xy 83.798328 -232.524284) (xy 83.771127 -232.48127) (xy 83.751179 -232.43445) (xy 83.739 -232.385036)
			(xy 83.734905 -232.334308) (xy 83.416394 -232.334308) (xy 83.415899 -232.358915) (xy 83.408004 -232.407492)
			(xy 83.39242 -232.454173) (xy 83.369549 -232.49775) (xy 83.339984 -232.537094) (xy 83.304491 -232.571186)
			(xy 83.263988 -232.599142) (xy 83.219526 -232.62024) (xy 83.172255 -232.633932) (xy 83.1234 -232.639864)
			(xy 83.074225 -232.637883) (xy 83.026006 -232.628039) (xy 82.97999 -232.610587) (xy 82.937369 -232.58598)
			(xy 82.899248 -232.554855) (xy 82.866613 -232.518018) (xy 82.84031 -232.476422) (xy 82.821019 -232.431146)
			(xy 82.809242 -232.383362) (xy 82.805282 -232.334308) (xy 82.486754 -232.334308) (xy 82.486242 -232.359754)
			(xy 82.478078 -232.409988) (xy 82.461962 -232.458262) (xy 82.438311 -232.503325) (xy 82.407738 -232.544011)
			(xy 82.371034 -232.579266) (xy 82.32915 -232.608176) (xy 82.283171 -232.629993) (xy 82.234287 -232.644153)
			(xy 82.183766 -232.650287) (xy 82.132914 -232.648238) (xy 82.08305 -232.638058) (xy 82.035464 -232.620011)
			(xy 81.99139 -232.594565) (xy 81.951968 -232.562378) (xy 81.91822 -232.524284) (xy 81.891019 -232.48127)
			(xy 81.871071 -232.43445) (xy 81.858892 -232.385036) (xy 81.854797 -232.334308) (xy 81.5467 -232.334308)
			(xy 81.546188 -232.359754) (xy 81.538024 -232.409988) (xy 81.521908 -232.458262) (xy 81.498257 -232.503325)
			(xy 81.467684 -232.544011) (xy 81.43098 -232.579266) (xy 81.389096 -232.608176) (xy 81.343117 -232.629993)
			(xy 81.294233 -232.644153) (xy 81.243712 -232.650287) (xy 81.19286 -232.648238) (xy 81.142996 -232.638058)
			(xy 81.09541 -232.620011) (xy 81.051336 -232.594565) (xy 81.011914 -232.562378) (xy 80.978166 -232.524284)
			(xy 80.950965 -232.48127) (xy 80.931017 -232.43445) (xy 80.918838 -232.385036) (xy 80.914743 -232.334308)
			(xy 80.596486 -232.334308) (xy 80.595991 -232.358915) (xy 80.588096 -232.407492) (xy 80.572512 -232.454173)
			(xy 80.549641 -232.49775) (xy 80.520076 -232.537094) (xy 80.484583 -232.571186) (xy 80.44408 -232.599142)
			(xy 80.399618 -232.62024) (xy 80.352347 -232.633932) (xy 80.303492 -232.639864) (xy 80.254317 -232.637883)
			(xy 80.206098 -232.628039) (xy 80.160082 -232.610587) (xy 80.117461 -232.58598) (xy 80.07934 -232.554855)
			(xy 80.046705 -232.518018) (xy 80.020402 -232.476422) (xy 80.001111 -232.431146) (xy 79.989334 -232.383362)
			(xy 79.985374 -232.334308) (xy 78.716378 -232.334308) (xy 78.715883 -232.358915) (xy 78.707988 -232.407492)
			(xy 78.692404 -232.454173) (xy 78.669533 -232.49775) (xy 78.639968 -232.537094) (xy 78.604475 -232.571186)
			(xy 78.563972 -232.599142) (xy 78.51951 -232.62024) (xy 78.472239 -232.633932) (xy 78.423384 -232.639864)
			(xy 78.374209 -232.637883) (xy 78.32599 -232.628039) (xy 78.279974 -232.610587) (xy 78.237353 -232.58598)
			(xy 78.199232 -232.554855) (xy 78.166597 -232.518018) (xy 78.140294 -232.476422) (xy 78.121003 -232.431146)
			(xy 78.109226 -232.383362) (xy 78.105266 -232.334308) (xy 62.37732 -232.334308) (xy 62.37732 -233.410252)
			(xy 76.507098 -233.410252) (xy 76.511058 -233.361198) (xy 76.522835 -233.313414) (xy 76.542126 -233.268138)
			(xy 76.568429 -233.226542) (xy 76.601064 -233.189705) (xy 76.639185 -233.15858) (xy 76.681806 -233.133973)
			(xy 76.727822 -233.116521) (xy 76.776041 -233.106677) (xy 76.825216 -233.104696) (xy 76.874071 -233.110628)
			(xy 76.921342 -233.12432) (xy 76.963477 -233.144314) (xy 79.51522 -233.144314) (xy 79.51918 -233.09526)
			(xy 79.530957 -233.047476) (xy 79.550248 -233.0022) (xy 79.576551 -232.960604) (xy 79.609186 -232.923767)
			(xy 79.647307 -232.892642) (xy 79.689928 -232.868035) (xy 79.735944 -232.850583) (xy 79.784163 -232.840739)
			(xy 79.833338 -232.838758) (xy 79.882193 -232.84469) (xy 79.929464 -232.858382) (xy 79.973926 -232.87948)
			(xy 80.014429 -232.907436) (xy 80.049922 -232.941528) (xy 80.079487 -232.980872) (xy 80.102358 -233.024449)
			(xy 80.117942 -233.07113) (xy 80.125837 -233.119707) (xy 80.126332 -233.144314) (xy 80.444843 -233.144314)
			(xy 80.448938 -233.093586) (xy 80.461117 -233.044172) (xy 80.481065 -232.997352) (xy 80.508266 -232.954338)
			(xy 80.542014 -232.916244) (xy 80.581436 -232.884057) (xy 80.62551 -232.858611) (xy 80.673096 -232.840564)
			(xy 80.72296 -232.830384) (xy 80.773812 -232.828335) (xy 80.824333 -232.834469) (xy 80.873217 -232.848629)
			(xy 80.919196 -232.870446) (xy 80.96108 -232.899356) (xy 80.997784 -232.934611) (xy 81.028357 -232.975297)
			(xy 81.052008 -233.02036) (xy 81.068124 -233.068634) (xy 81.076288 -233.118868) (xy 81.0768 -233.144314)
			(xy 81.395328 -233.144314) (xy 81.399288 -233.09526) (xy 81.411065 -233.047476) (xy 81.430356 -233.0022)
			(xy 81.456659 -232.960604) (xy 81.489294 -232.923767) (xy 81.527415 -232.892642) (xy 81.570036 -232.868035)
			(xy 81.616052 -232.850583) (xy 81.664271 -232.840739) (xy 81.713446 -232.838758) (xy 81.762301 -232.84469)
			(xy 81.809572 -232.858382) (xy 81.854034 -232.87948) (xy 81.894537 -232.907436) (xy 81.93003 -232.941528)
			(xy 81.959595 -232.980872) (xy 81.982466 -233.024449) (xy 81.99805 -233.07113) (xy 82.005945 -233.119707)
			(xy 82.00644 -233.144314) (xy 82.324697 -233.144314) (xy 82.328792 -233.093586) (xy 82.340971 -233.044172)
			(xy 82.360919 -232.997352) (xy 82.38812 -232.954338) (xy 82.421868 -232.916244) (xy 82.46129 -232.884057)
			(xy 82.505364 -232.858611) (xy 82.55295 -232.840564) (xy 82.602814 -232.830384) (xy 82.653666 -232.828335)
			(xy 82.704187 -232.834469) (xy 82.753071 -232.848629) (xy 82.79905 -232.870446) (xy 82.840934 -232.899356)
			(xy 82.877638 -232.934611) (xy 82.908211 -232.975297) (xy 82.931862 -233.02036) (xy 82.947978 -233.068634)
			(xy 82.956142 -233.118868) (xy 82.956654 -233.144314) (xy 83.275182 -233.144314) (xy 83.279142 -233.09526)
			(xy 83.290919 -233.047476) (xy 83.31021 -233.0022) (xy 83.336513 -232.960604) (xy 83.369148 -232.923767)
			(xy 83.407269 -232.892642) (xy 83.44989 -232.868035) (xy 83.495906 -232.850583) (xy 83.544125 -232.840739)
			(xy 83.5933 -232.838758) (xy 83.642155 -232.84469) (xy 83.689426 -232.858382) (xy 83.733888 -232.87948)
			(xy 83.774391 -232.907436) (xy 83.809884 -232.941528) (xy 83.839449 -232.980872) (xy 83.86232 -233.024449)
			(xy 83.877904 -233.07113) (xy 83.885799 -233.119707) (xy 83.886294 -233.144314) (xy 84.204805 -233.144314)
			(xy 84.2089 -233.093586) (xy 84.221079 -233.044172) (xy 84.241027 -232.997352) (xy 84.268228 -232.954338)
			(xy 84.301976 -232.916244) (xy 84.341398 -232.884057) (xy 84.385472 -232.858611) (xy 84.433058 -232.840564)
			(xy 84.482922 -232.830384) (xy 84.533774 -232.828335) (xy 84.584295 -232.834469) (xy 84.633179 -232.848629)
			(xy 84.679158 -232.870446) (xy 84.721042 -232.899356) (xy 84.757746 -232.934611) (xy 84.788319 -232.975297)
			(xy 84.81197 -233.02036) (xy 84.828086 -233.068634) (xy 84.83625 -233.118868) (xy 84.836762 -233.144314)
			(xy 85.144859 -233.144314) (xy 85.148954 -233.093586) (xy 85.161133 -233.044172) (xy 85.181081 -232.997352)
			(xy 85.208282 -232.954338) (xy 85.24203 -232.916244) (xy 85.281452 -232.884057) (xy 85.325526 -232.858611)
			(xy 85.373112 -232.840564) (xy 85.422976 -232.830384) (xy 85.473828 -232.828335) (xy 85.524349 -232.834469)
			(xy 85.573233 -232.848629) (xy 85.619212 -232.870446) (xy 85.661096 -232.899356) (xy 85.6978 -232.934611)
			(xy 85.728373 -232.975297) (xy 85.752024 -233.02036) (xy 85.76814 -233.068634) (xy 85.776304 -233.118868)
			(xy 85.776816 -233.144314) (xy 86.095344 -233.144314) (xy 86.099304 -233.09526) (xy 86.111081 -233.047476)
			(xy 86.130372 -233.0022) (xy 86.156675 -232.960604) (xy 86.18931 -232.923767) (xy 86.227431 -232.892642)
			(xy 86.270052 -232.868035) (xy 86.316068 -232.850583) (xy 86.364287 -232.840739) (xy 86.413462 -232.838758)
			(xy 86.462317 -232.84469) (xy 86.509588 -232.858382) (xy 86.55405 -232.87948) (xy 86.594553 -232.907436)
			(xy 86.630046 -232.941528) (xy 86.659611 -232.980872) (xy 86.682482 -233.024449) (xy 86.698066 -233.07113)
			(xy 86.705961 -233.119707) (xy 86.706456 -233.144314) (xy 87.024713 -233.144314) (xy 87.028808 -233.093586)
			(xy 87.040987 -233.044172) (xy 87.060935 -232.997352) (xy 87.088136 -232.954338) (xy 87.121884 -232.916244)
			(xy 87.161306 -232.884057) (xy 87.20538 -232.858611) (xy 87.252966 -232.840564) (xy 87.30283 -232.830384)
			(xy 87.353682 -232.828335) (xy 87.404203 -232.834469) (xy 87.453087 -232.848629) (xy 87.499066 -232.870446)
			(xy 87.54095 -232.899356) (xy 87.577654 -232.934611) (xy 87.608227 -232.975297) (xy 87.631878 -233.02036)
			(xy 87.647994 -233.068634) (xy 87.656158 -233.118868) (xy 87.65667 -233.144314) (xy 87.975198 -233.144314)
			(xy 87.979158 -233.09526) (xy 87.990935 -233.047476) (xy 88.010226 -233.0022) (xy 88.036529 -232.960604)
			(xy 88.069164 -232.923767) (xy 88.107285 -232.892642) (xy 88.149906 -232.868035) (xy 88.195922 -232.850583)
			(xy 88.244141 -232.840739) (xy 88.293316 -232.838758) (xy 88.342171 -232.84469) (xy 88.389442 -232.858382)
			(xy 88.433904 -232.87948) (xy 88.474407 -232.907436) (xy 88.5099 -232.941528) (xy 88.539465 -232.980872)
			(xy 88.562336 -233.024449) (xy 88.57792 -233.07113) (xy 88.585815 -233.119707) (xy 88.58631 -233.144314)
			(xy 88.904821 -233.144314) (xy 88.908916 -233.093586) (xy 88.921095 -233.044172) (xy 88.941043 -232.997352)
			(xy 88.968244 -232.954338) (xy 89.001992 -232.916244) (xy 89.041414 -232.884057) (xy 89.085488 -232.858611)
			(xy 89.133074 -232.840564) (xy 89.182938 -232.830384) (xy 89.23379 -232.828335) (xy 89.284311 -232.834469)
			(xy 89.333195 -232.848629) (xy 89.379174 -232.870446) (xy 89.421058 -232.899356) (xy 89.457762 -232.934611)
			(xy 89.488335 -232.975297) (xy 89.511986 -233.02036) (xy 89.528102 -233.068634) (xy 89.536266 -233.118868)
			(xy 89.536778 -233.144314) (xy 89.855306 -233.144314) (xy 89.859266 -233.09526) (xy 89.871043 -233.047476)
			(xy 89.890334 -233.0022) (xy 89.916637 -232.960604) (xy 89.949272 -232.923767) (xy 89.987393 -232.892642)
			(xy 90.030014 -232.868035) (xy 90.07603 -232.850583) (xy 90.124249 -232.840739) (xy 90.173424 -232.838758)
			(xy 90.222279 -232.84469) (xy 90.26955 -232.858382) (xy 90.314012 -232.87948) (xy 90.354515 -232.907436)
			(xy 90.390008 -232.941528) (xy 90.419573 -232.980872) (xy 90.442444 -233.024449) (xy 90.458028 -233.07113)
			(xy 90.465923 -233.119707) (xy 90.466418 -233.144314) (xy 90.784675 -233.144314) (xy 90.78877 -233.093586)
			(xy 90.800949 -233.044172) (xy 90.820897 -232.997352) (xy 90.848098 -232.954338) (xy 90.881846 -232.916244)
			(xy 90.921268 -232.884057) (xy 90.965342 -232.858611) (xy 91.012928 -232.840564) (xy 91.062792 -232.830384)
			(xy 91.113644 -232.828335) (xy 91.164165 -232.834469) (xy 91.213049 -232.848629) (xy 91.259028 -232.870446)
			(xy 91.300912 -232.899356) (xy 91.337616 -232.934611) (xy 91.368189 -232.975297) (xy 91.39184 -233.02036)
			(xy 91.407956 -233.068634) (xy 91.41612 -233.118868) (xy 91.416632 -233.144314) (xy 91.724729 -233.144314)
			(xy 91.728824 -233.093586) (xy 91.741003 -233.044172) (xy 91.760951 -232.997352) (xy 91.788152 -232.954338)
			(xy 91.8219 -232.916244) (xy 91.861322 -232.884057) (xy 91.905396 -232.858611) (xy 91.952982 -232.840564)
			(xy 92.002846 -232.830384) (xy 92.053698 -232.828335) (xy 92.104219 -232.834469) (xy 92.153103 -232.848629)
			(xy 92.199082 -232.870446) (xy 92.240966 -232.899356) (xy 92.27767 -232.934611) (xy 92.308243 -232.975297)
			(xy 92.331894 -233.02036) (xy 92.34801 -233.068634) (xy 92.356174 -233.118868) (xy 92.356686 -233.144314)
			(xy 92.675214 -233.144314) (xy 92.679174 -233.09526) (xy 92.690951 -233.047476) (xy 92.710242 -233.0022)
			(xy 92.736545 -232.960604) (xy 92.76918 -232.923767) (xy 92.807301 -232.892642) (xy 92.849922 -232.868035)
			(xy 92.895938 -232.850583) (xy 92.944157 -232.840739) (xy 92.993332 -232.838758) (xy 93.042187 -232.84469)
			(xy 93.089458 -232.858382) (xy 93.13392 -232.87948) (xy 93.174423 -232.907436) (xy 93.209916 -232.941528)
			(xy 93.239481 -232.980872) (xy 93.262352 -233.024449) (xy 93.277936 -233.07113) (xy 93.285831 -233.119707)
			(xy 93.286326 -233.144314) (xy 93.604837 -233.144314) (xy 93.608932 -233.093586) (xy 93.621111 -233.044172)
			(xy 93.641059 -232.997352) (xy 93.66826 -232.954338) (xy 93.702008 -232.916244) (xy 93.74143 -232.884057)
			(xy 93.785504 -232.858611) (xy 93.83309 -232.840564) (xy 93.882954 -232.830384) (xy 93.933806 -232.828335)
			(xy 93.984327 -232.834469) (xy 94.033211 -232.848629) (xy 94.07919 -232.870446) (xy 94.121074 -232.899356)
			(xy 94.157778 -232.934611) (xy 94.188351 -232.975297) (xy 94.212002 -233.02036) (xy 94.228118 -233.068634)
			(xy 94.236282 -233.118868) (xy 94.236794 -233.144314) (xy 94.555322 -233.144314) (xy 94.559282 -233.09526)
			(xy 94.571059 -233.047476) (xy 94.59035 -233.0022) (xy 94.616653 -232.960604) (xy 94.649288 -232.923767)
			(xy 94.687409 -232.892642) (xy 94.73003 -232.868035) (xy 94.776046 -232.850583) (xy 94.824265 -232.840739)
			(xy 94.87344 -232.838758) (xy 94.922295 -232.84469) (xy 94.969566 -232.858382) (xy 95.014028 -232.87948)
			(xy 95.054531 -232.907436) (xy 95.090024 -232.941528) (xy 95.119589 -232.980872) (xy 95.14246 -233.024449)
			(xy 95.158044 -233.07113) (xy 95.165939 -233.119707) (xy 95.166434 -233.144314) (xy 95.484691 -233.144314)
			(xy 95.488786 -233.093586) (xy 95.500965 -233.044172) (xy 95.520913 -232.997352) (xy 95.548114 -232.954338)
			(xy 95.581862 -232.916244) (xy 95.621284 -232.884057) (xy 95.665358 -232.858611) (xy 95.712944 -232.840564)
			(xy 95.762808 -232.830384) (xy 95.81366 -232.828335) (xy 95.864181 -232.834469) (xy 95.913065 -232.848629)
			(xy 95.959044 -232.870446) (xy 96.000928 -232.899356) (xy 96.037632 -232.934611) (xy 96.068205 -232.975297)
			(xy 96.091856 -233.02036) (xy 96.107972 -233.068634) (xy 96.116136 -233.118868) (xy 96.116648 -233.144314)
			(xy 96.435176 -233.144314) (xy 96.439136 -233.09526) (xy 96.450913 -233.047476) (xy 96.470204 -233.0022)
			(xy 96.496507 -232.960604) (xy 96.529142 -232.923767) (xy 96.567263 -232.892642) (xy 96.609884 -232.868035)
			(xy 96.6559 -232.850583) (xy 96.704119 -232.840739) (xy 96.753294 -232.838758) (xy 96.802149 -232.84469)
			(xy 96.84942 -232.858382) (xy 96.893882 -232.87948) (xy 96.934385 -232.907436) (xy 96.969878 -232.941528)
			(xy 96.999443 -232.980872) (xy 97.022314 -233.024449) (xy 97.037898 -233.07113) (xy 97.045793 -233.119707)
			(xy 97.046288 -233.144314) (xy 97.364799 -233.144314) (xy 97.368894 -233.093586) (xy 97.381073 -233.044172)
			(xy 97.401021 -232.997352) (xy 97.428222 -232.954338) (xy 97.46197 -232.916244) (xy 97.501392 -232.884057)
			(xy 97.545466 -232.858611) (xy 97.593052 -232.840564) (xy 97.642916 -232.830384) (xy 97.693768 -232.828335)
			(xy 97.744289 -232.834469) (xy 97.793173 -232.848629) (xy 97.839152 -232.870446) (xy 97.881036 -232.899356)
			(xy 97.91774 -232.934611) (xy 97.948313 -232.975297) (xy 97.971964 -233.02036) (xy 97.98808 -233.068634)
			(xy 97.996244 -233.118868) (xy 97.996756 -233.144314) (xy 98.304853 -233.144314) (xy 98.308948 -233.093586)
			(xy 98.321127 -233.044172) (xy 98.341075 -232.997352) (xy 98.368276 -232.954338) (xy 98.402024 -232.916244)
			(xy 98.441446 -232.884057) (xy 98.48552 -232.858611) (xy 98.533106 -232.840564) (xy 98.58297 -232.830384)
			(xy 98.633822 -232.828335) (xy 98.684343 -232.834469) (xy 98.733227 -232.848629) (xy 98.779206 -232.870446)
			(xy 98.82109 -232.899356) (xy 98.857794 -232.934611) (xy 98.888367 -232.975297) (xy 98.912018 -233.02036)
			(xy 98.928134 -233.068634) (xy 98.936298 -233.118868) (xy 98.93681 -233.144314) (xy 99.255338 -233.144314)
			(xy 99.259298 -233.09526) (xy 99.271075 -233.047476) (xy 99.290366 -233.0022) (xy 99.316669 -232.960604)
			(xy 99.349304 -232.923767) (xy 99.387425 -232.892642) (xy 99.430046 -232.868035) (xy 99.476062 -232.850583)
			(xy 99.524281 -232.840739) (xy 99.573456 -232.838758) (xy 99.622311 -232.84469) (xy 99.669582 -232.858382)
			(xy 99.714044 -232.87948) (xy 99.754547 -232.907436) (xy 99.79004 -232.941528) (xy 99.819605 -232.980872)
			(xy 99.842476 -233.024449) (xy 99.85806 -233.07113) (xy 99.865955 -233.119707) (xy 99.86645 -233.144314)
			(xy 100.184707 -233.144314) (xy 100.188802 -233.093586) (xy 100.200981 -233.044172) (xy 100.220929 -232.997352)
			(xy 100.24813 -232.954338) (xy 100.281878 -232.916244) (xy 100.3213 -232.884057) (xy 100.365374 -232.858611)
			(xy 100.41296 -232.840564) (xy 100.462824 -232.830384) (xy 100.513676 -232.828335) (xy 100.564197 -232.834469)
			(xy 100.613081 -232.848629) (xy 100.65906 -232.870446) (xy 100.700944 -232.899356) (xy 100.737648 -232.934611)
			(xy 100.768221 -232.975297) (xy 100.791872 -233.02036) (xy 100.807988 -233.068634) (xy 100.816152 -233.118868)
			(xy 100.816664 -233.144314) (xy 101.124761 -233.144314) (xy 101.128856 -233.093586) (xy 101.141035 -233.044172)
			(xy 101.160983 -232.997352) (xy 101.188184 -232.954338) (xy 101.221932 -232.916244) (xy 101.261354 -232.884057)
			(xy 101.305428 -232.858611) (xy 101.353014 -232.840564) (xy 101.402878 -232.830384) (xy 101.45373 -232.828335)
			(xy 101.504251 -232.834469) (xy 101.553135 -232.848629) (xy 101.599114 -232.870446) (xy 101.640998 -232.899356)
			(xy 101.677702 -232.934611) (xy 101.708275 -232.975297) (xy 101.731926 -233.02036) (xy 101.748042 -233.068634)
			(xy 101.756206 -233.118868) (xy 101.756718 -233.144314) (xy 102.075246 -233.144314) (xy 102.079206 -233.09526)
			(xy 102.090983 -233.047476) (xy 102.110274 -233.0022) (xy 102.136577 -232.960604) (xy 102.169212 -232.923767)
			(xy 102.207333 -232.892642) (xy 102.249954 -232.868035) (xy 102.29597 -232.850583) (xy 102.344189 -232.840739)
			(xy 102.393364 -232.838758) (xy 102.442219 -232.84469) (xy 102.48949 -232.858382) (xy 102.533952 -232.87948)
			(xy 102.574455 -232.907436) (xy 102.609948 -232.941528) (xy 102.639513 -232.980872) (xy 102.662384 -233.024449)
			(xy 102.677968 -233.07113) (xy 102.685863 -233.119707) (xy 102.686358 -233.144314) (xy 103.004869 -233.144314)
			(xy 103.008964 -233.093586) (xy 103.021143 -233.044172) (xy 103.041091 -232.997352) (xy 103.068292 -232.954338)
			(xy 103.10204 -232.916244) (xy 103.141462 -232.884057) (xy 103.185536 -232.858611) (xy 103.233122 -232.840564)
			(xy 103.282986 -232.830384) (xy 103.333838 -232.828335) (xy 103.384359 -232.834469) (xy 103.433243 -232.848629)
			(xy 103.479222 -232.870446) (xy 103.521106 -232.899356) (xy 103.55781 -232.934611) (xy 103.588383 -232.975297)
			(xy 103.612034 -233.02036) (xy 103.62815 -233.068634) (xy 103.636314 -233.118868) (xy 103.636826 -233.144314)
			(xy 103.944923 -233.144314) (xy 103.949018 -233.093586) (xy 103.961197 -233.044172) (xy 103.981145 -232.997352)
			(xy 104.008346 -232.954338) (xy 104.042094 -232.916244) (xy 104.081516 -232.884057) (xy 104.12559 -232.858611)
			(xy 104.173176 -232.840564) (xy 104.22304 -232.830384) (xy 104.273892 -232.828335) (xy 104.324413 -232.834469)
			(xy 104.373297 -232.848629) (xy 104.419276 -232.870446) (xy 104.46116 -232.899356) (xy 104.497864 -232.934611)
			(xy 104.528437 -232.975297) (xy 104.552088 -233.02036) (xy 104.568204 -233.068634) (xy 104.576368 -233.118868)
			(xy 104.57688 -233.144314) (xy 104.895154 -233.144314) (xy 104.899114 -233.09526) (xy 104.910891 -233.047476)
			(xy 104.930182 -233.0022) (xy 104.956485 -232.960604) (xy 104.98912 -232.923767) (xy 105.027241 -232.892642)
			(xy 105.069862 -232.868035) (xy 105.115878 -232.850583) (xy 105.164097 -232.840739) (xy 105.213272 -232.838758)
			(xy 105.262127 -232.84469) (xy 105.309398 -232.858382) (xy 105.35386 -232.87948) (xy 105.394363 -232.907436)
			(xy 105.429856 -232.941528) (xy 105.459421 -232.980872) (xy 105.482292 -233.024449) (xy 105.497876 -233.07113)
			(xy 105.505771 -233.119707) (xy 105.506266 -233.144314) (xy 105.824777 -233.144314) (xy 105.828872 -233.093586)
			(xy 105.841051 -233.044172) (xy 105.860999 -232.997352) (xy 105.8882 -232.954338) (xy 105.921948 -232.916244)
			(xy 105.96137 -232.884057) (xy 106.005444 -232.858611) (xy 106.05303 -232.840564) (xy 106.102894 -232.830384)
			(xy 106.153746 -232.828335) (xy 106.204267 -232.834469) (xy 106.253151 -232.848629) (xy 106.29913 -232.870446)
			(xy 106.341014 -232.899356) (xy 106.377718 -232.934611) (xy 106.408291 -232.975297) (xy 106.431942 -233.02036)
			(xy 106.448058 -233.068634) (xy 106.456222 -233.118868) (xy 106.456734 -233.144314) (xy 106.764831 -233.144314)
			(xy 106.768926 -233.093586) (xy 106.781105 -233.044172) (xy 106.801053 -232.997352) (xy 106.828254 -232.954338)
			(xy 106.862002 -232.916244) (xy 106.901424 -232.884057) (xy 106.945498 -232.858611) (xy 106.993084 -232.840564)
			(xy 107.042948 -232.830384) (xy 107.0938 -232.828335) (xy 107.144321 -232.834469) (xy 107.193205 -232.848629)
			(xy 107.239184 -232.870446) (xy 107.281068 -232.899356) (xy 107.317772 -232.934611) (xy 107.348345 -232.975297)
			(xy 107.371996 -233.02036) (xy 107.388112 -233.068634) (xy 107.396276 -233.118868) (xy 107.396788 -233.144314)
			(xy 107.715316 -233.144314) (xy 107.719276 -233.09526) (xy 107.731053 -233.047476) (xy 107.750344 -233.0022)
			(xy 107.776647 -232.960604) (xy 107.809282 -232.923767) (xy 107.847403 -232.892642) (xy 107.890024 -232.868035)
			(xy 107.93604 -232.850583) (xy 107.984259 -232.840739) (xy 108.033434 -232.838758) (xy 108.082289 -232.84469)
			(xy 108.12956 -232.858382) (xy 108.174022 -232.87948) (xy 108.214525 -232.907436) (xy 108.250018 -232.941528)
			(xy 108.279583 -232.980872) (xy 108.302454 -233.024449) (xy 108.318038 -233.07113) (xy 108.325933 -233.119707)
			(xy 108.326428 -233.144314) (xy 108.65537 -233.144314) (xy 108.65933 -233.09526) (xy 108.671107 -233.047476)
			(xy 108.690398 -233.0022) (xy 108.716701 -232.960604) (xy 108.749336 -232.923767) (xy 108.787457 -232.892642)
			(xy 108.830078 -232.868035) (xy 108.876094 -232.850583) (xy 108.924313 -232.840739) (xy 108.973488 -232.838758)
			(xy 109.022343 -232.84469) (xy 109.069614 -232.858382) (xy 109.114076 -232.87948) (xy 109.154579 -232.907436)
			(xy 109.190072 -232.941528) (xy 109.219637 -232.980872) (xy 109.242508 -233.024449) (xy 109.258092 -233.07113)
			(xy 109.265987 -233.119707) (xy 109.266482 -233.144314) (xy 109.59517 -233.144314) (xy 109.59913 -233.09526)
			(xy 109.610907 -233.047476) (xy 109.630198 -233.0022) (xy 109.656501 -232.960604) (xy 109.689136 -232.923767)
			(xy 109.727257 -232.892642) (xy 109.769878 -232.868035) (xy 109.815894 -232.850583) (xy 109.864113 -232.840739)
			(xy 109.913288 -232.838758) (xy 109.962143 -232.84469) (xy 110.009414 -232.858382) (xy 110.053876 -232.87948)
			(xy 110.094379 -232.907436) (xy 110.129872 -232.941528) (xy 110.159437 -232.980872) (xy 110.182308 -233.024449)
			(xy 110.197892 -233.07113) (xy 110.205787 -233.119707) (xy 110.206282 -233.144314) (xy 110.205787 -233.168921)
			(xy 110.197892 -233.217498) (xy 110.182308 -233.264179) (xy 110.159437 -233.307756) (xy 110.129872 -233.3471)
			(xy 110.094379 -233.381192) (xy 110.053876 -233.409148) (xy 110.009414 -233.430246) (xy 109.962143 -233.443938)
			(xy 109.913288 -233.44987) (xy 109.864113 -233.447889) (xy 109.815894 -233.438045) (xy 109.769878 -233.420593)
			(xy 109.727257 -233.395986) (xy 109.689136 -233.364861) (xy 109.656501 -233.328024) (xy 109.630198 -233.286428)
			(xy 109.610907 -233.241152) (xy 109.59913 -233.193368) (xy 109.59517 -233.144314) (xy 109.266482 -233.144314)
			(xy 109.265987 -233.168921) (xy 109.258092 -233.217498) (xy 109.242508 -233.264179) (xy 109.219637 -233.307756)
			(xy 109.190072 -233.3471) (xy 109.154579 -233.381192) (xy 109.114076 -233.409148) (xy 109.069614 -233.430246)
			(xy 109.022343 -233.443938) (xy 108.973488 -233.44987) (xy 108.924313 -233.447889) (xy 108.876094 -233.438045)
			(xy 108.830078 -233.420593) (xy 108.787457 -233.395986) (xy 108.749336 -233.364861) (xy 108.716701 -233.328024)
			(xy 108.690398 -233.286428) (xy 108.671107 -233.241152) (xy 108.65933 -233.193368) (xy 108.65537 -233.144314)
			(xy 108.326428 -233.144314) (xy 108.325933 -233.168921) (xy 108.318038 -233.217498) (xy 108.302454 -233.264179)
			(xy 108.279583 -233.307756) (xy 108.250018 -233.3471) (xy 108.214525 -233.381192) (xy 108.174022 -233.409148)
			(xy 108.12956 -233.430246) (xy 108.082289 -233.443938) (xy 108.033434 -233.44987) (xy 107.984259 -233.447889)
			(xy 107.93604 -233.438045) (xy 107.890024 -233.420593) (xy 107.847403 -233.395986) (xy 107.809282 -233.364861)
			(xy 107.776647 -233.328024) (xy 107.750344 -233.286428) (xy 107.731053 -233.241152) (xy 107.719276 -233.193368)
			(xy 107.715316 -233.144314) (xy 107.396788 -233.144314) (xy 107.396276 -233.16976) (xy 107.388112 -233.219994)
			(xy 107.371996 -233.268268) (xy 107.348345 -233.313331) (xy 107.317772 -233.354017) (xy 107.281068 -233.389272)
			(xy 107.239184 -233.418182) (xy 107.193205 -233.439999) (xy 107.144321 -233.454159) (xy 107.0938 -233.460293)
			(xy 107.042948 -233.458244) (xy 106.993084 -233.448064) (xy 106.945498 -233.430017) (xy 106.901424 -233.404571)
			(xy 106.862002 -233.372384) (xy 106.828254 -233.33429) (xy 106.801053 -233.291276) (xy 106.781105 -233.244456)
			(xy 106.768926 -233.195042) (xy 106.764831 -233.144314) (xy 106.456734 -233.144314) (xy 106.456222 -233.16976)
			(xy 106.448058 -233.219994) (xy 106.431942 -233.268268) (xy 106.408291 -233.313331) (xy 106.377718 -233.354017)
			(xy 106.341014 -233.389272) (xy 106.29913 -233.418182) (xy 106.253151 -233.439999) (xy 106.204267 -233.454159)
			(xy 106.153746 -233.460293) (xy 106.102894 -233.458244) (xy 106.05303 -233.448064) (xy 106.005444 -233.430017)
			(xy 105.96137 -233.404571) (xy 105.921948 -233.372384) (xy 105.8882 -233.33429) (xy 105.860999 -233.291276)
			(xy 105.841051 -233.244456) (xy 105.828872 -233.195042) (xy 105.824777 -233.144314) (xy 105.506266 -233.144314)
			(xy 105.505771 -233.168921) (xy 105.497876 -233.217498) (xy 105.482292 -233.264179) (xy 105.459421 -233.307756)
			(xy 105.429856 -233.3471) (xy 105.394363 -233.381192) (xy 105.35386 -233.409148) (xy 105.309398 -233.430246)
			(xy 105.262127 -233.443938) (xy 105.213272 -233.44987) (xy 105.164097 -233.447889) (xy 105.115878 -233.438045)
			(xy 105.069862 -233.420593) (xy 105.027241 -233.395986) (xy 104.98912 -233.364861) (xy 104.956485 -233.328024)
			(xy 104.930182 -233.286428) (xy 104.910891 -233.241152) (xy 104.899114 -233.193368) (xy 104.895154 -233.144314)
			(xy 104.57688 -233.144314) (xy 104.576368 -233.16976) (xy 104.568204 -233.219994) (xy 104.552088 -233.268268)
			(xy 104.528437 -233.313331) (xy 104.497864 -233.354017) (xy 104.46116 -233.389272) (xy 104.419276 -233.418182)
			(xy 104.373297 -233.439999) (xy 104.324413 -233.454159) (xy 104.273892 -233.460293) (xy 104.22304 -233.458244)
			(xy 104.173176 -233.448064) (xy 104.12559 -233.430017) (xy 104.081516 -233.404571) (xy 104.042094 -233.372384)
			(xy 104.008346 -233.33429) (xy 103.981145 -233.291276) (xy 103.961197 -233.244456) (xy 103.949018 -233.195042)
			(xy 103.944923 -233.144314) (xy 103.636826 -233.144314) (xy 103.636314 -233.16976) (xy 103.62815 -233.219994)
			(xy 103.612034 -233.268268) (xy 103.588383 -233.313331) (xy 103.55781 -233.354017) (xy 103.521106 -233.389272)
			(xy 103.479222 -233.418182) (xy 103.433243 -233.439999) (xy 103.384359 -233.454159) (xy 103.333838 -233.460293)
			(xy 103.282986 -233.458244) (xy 103.233122 -233.448064) (xy 103.185536 -233.430017) (xy 103.141462 -233.404571)
			(xy 103.10204 -233.372384) (xy 103.068292 -233.33429) (xy 103.041091 -233.291276) (xy 103.021143 -233.244456)
			(xy 103.008964 -233.195042) (xy 103.004869 -233.144314) (xy 102.686358 -233.144314) (xy 102.685863 -233.168921)
			(xy 102.677968 -233.217498) (xy 102.662384 -233.264179) (xy 102.639513 -233.307756) (xy 102.609948 -233.3471)
			(xy 102.574455 -233.381192) (xy 102.533952 -233.409148) (xy 102.48949 -233.430246) (xy 102.442219 -233.443938)
			(xy 102.393364 -233.44987) (xy 102.344189 -233.447889) (xy 102.29597 -233.438045) (xy 102.249954 -233.420593)
			(xy 102.207333 -233.395986) (xy 102.169212 -233.364861) (xy 102.136577 -233.328024) (xy 102.110274 -233.286428)
			(xy 102.090983 -233.241152) (xy 102.079206 -233.193368) (xy 102.075246 -233.144314) (xy 101.756718 -233.144314)
			(xy 101.756206 -233.16976) (xy 101.748042 -233.219994) (xy 101.731926 -233.268268) (xy 101.708275 -233.313331)
			(xy 101.677702 -233.354017) (xy 101.640998 -233.389272) (xy 101.599114 -233.418182) (xy 101.553135 -233.439999)
			(xy 101.504251 -233.454159) (xy 101.45373 -233.460293) (xy 101.402878 -233.458244) (xy 101.353014 -233.448064)
			(xy 101.305428 -233.430017) (xy 101.261354 -233.404571) (xy 101.221932 -233.372384) (xy 101.188184 -233.33429)
			(xy 101.160983 -233.291276) (xy 101.141035 -233.244456) (xy 101.128856 -233.195042) (xy 101.124761 -233.144314)
			(xy 100.816664 -233.144314) (xy 100.816152 -233.16976) (xy 100.807988 -233.219994) (xy 100.791872 -233.268268)
			(xy 100.768221 -233.313331) (xy 100.737648 -233.354017) (xy 100.700944 -233.389272) (xy 100.65906 -233.418182)
			(xy 100.613081 -233.439999) (xy 100.564197 -233.454159) (xy 100.513676 -233.460293) (xy 100.462824 -233.458244)
			(xy 100.41296 -233.448064) (xy 100.365374 -233.430017) (xy 100.3213 -233.404571) (xy 100.281878 -233.372384)
			(xy 100.24813 -233.33429) (xy 100.220929 -233.291276) (xy 100.200981 -233.244456) (xy 100.188802 -233.195042)
			(xy 100.184707 -233.144314) (xy 99.86645 -233.144314) (xy 99.865955 -233.168921) (xy 99.85806 -233.217498)
			(xy 99.842476 -233.264179) (xy 99.819605 -233.307756) (xy 99.79004 -233.3471) (xy 99.754547 -233.381192)
			(xy 99.714044 -233.409148) (xy 99.669582 -233.430246) (xy 99.622311 -233.443938) (xy 99.573456 -233.44987)
			(xy 99.524281 -233.447889) (xy 99.476062 -233.438045) (xy 99.430046 -233.420593) (xy 99.387425 -233.395986)
			(xy 99.349304 -233.364861) (xy 99.316669 -233.328024) (xy 99.290366 -233.286428) (xy 99.271075 -233.241152)
			(xy 99.259298 -233.193368) (xy 99.255338 -233.144314) (xy 98.93681 -233.144314) (xy 98.936298 -233.16976)
			(xy 98.928134 -233.219994) (xy 98.912018 -233.268268) (xy 98.888367 -233.313331) (xy 98.857794 -233.354017)
			(xy 98.82109 -233.389272) (xy 98.779206 -233.418182) (xy 98.733227 -233.439999) (xy 98.684343 -233.454159)
			(xy 98.633822 -233.460293) (xy 98.58297 -233.458244) (xy 98.533106 -233.448064) (xy 98.48552 -233.430017)
			(xy 98.441446 -233.404571) (xy 98.402024 -233.372384) (xy 98.368276 -233.33429) (xy 98.341075 -233.291276)
			(xy 98.321127 -233.244456) (xy 98.308948 -233.195042) (xy 98.304853 -233.144314) (xy 97.996756 -233.144314)
			(xy 97.996244 -233.16976) (xy 97.98808 -233.219994) (xy 97.971964 -233.268268) (xy 97.948313 -233.313331)
			(xy 97.91774 -233.354017) (xy 97.881036 -233.389272) (xy 97.839152 -233.418182) (xy 97.793173 -233.439999)
			(xy 97.744289 -233.454159) (xy 97.693768 -233.460293) (xy 97.642916 -233.458244) (xy 97.593052 -233.448064)
			(xy 97.545466 -233.430017) (xy 97.501392 -233.404571) (xy 97.46197 -233.372384) (xy 97.428222 -233.33429)
			(xy 97.401021 -233.291276) (xy 97.381073 -233.244456) (xy 97.368894 -233.195042) (xy 97.364799 -233.144314)
			(xy 97.046288 -233.144314) (xy 97.045793 -233.168921) (xy 97.037898 -233.217498) (xy 97.022314 -233.264179)
			(xy 96.999443 -233.307756) (xy 96.969878 -233.3471) (xy 96.934385 -233.381192) (xy 96.893882 -233.409148)
			(xy 96.84942 -233.430246) (xy 96.802149 -233.443938) (xy 96.753294 -233.44987) (xy 96.704119 -233.447889)
			(xy 96.6559 -233.438045) (xy 96.609884 -233.420593) (xy 96.567263 -233.395986) (xy 96.529142 -233.364861)
			(xy 96.496507 -233.328024) (xy 96.470204 -233.286428) (xy 96.450913 -233.241152) (xy 96.439136 -233.193368)
			(xy 96.435176 -233.144314) (xy 96.116648 -233.144314) (xy 96.116136 -233.16976) (xy 96.107972 -233.219994)
			(xy 96.091856 -233.268268) (xy 96.068205 -233.313331) (xy 96.037632 -233.354017) (xy 96.000928 -233.389272)
			(xy 95.959044 -233.418182) (xy 95.913065 -233.439999) (xy 95.864181 -233.454159) (xy 95.81366 -233.460293)
			(xy 95.762808 -233.458244) (xy 95.712944 -233.448064) (xy 95.665358 -233.430017) (xy 95.621284 -233.404571)
			(xy 95.581862 -233.372384) (xy 95.548114 -233.33429) (xy 95.520913 -233.291276) (xy 95.500965 -233.244456)
			(xy 95.488786 -233.195042) (xy 95.484691 -233.144314) (xy 95.166434 -233.144314) (xy 95.165939 -233.168921)
			(xy 95.158044 -233.217498) (xy 95.14246 -233.264179) (xy 95.119589 -233.307756) (xy 95.090024 -233.3471)
			(xy 95.054531 -233.381192) (xy 95.014028 -233.409148) (xy 94.969566 -233.430246) (xy 94.922295 -233.443938)
			(xy 94.87344 -233.44987) (xy 94.824265 -233.447889) (xy 94.776046 -233.438045) (xy 94.73003 -233.420593)
			(xy 94.687409 -233.395986) (xy 94.649288 -233.364861) (xy 94.616653 -233.328024) (xy 94.59035 -233.286428)
			(xy 94.571059 -233.241152) (xy 94.559282 -233.193368) (xy 94.555322 -233.144314) (xy 94.236794 -233.144314)
			(xy 94.236282 -233.16976) (xy 94.228118 -233.219994) (xy 94.212002 -233.268268) (xy 94.188351 -233.313331)
			(xy 94.157778 -233.354017) (xy 94.121074 -233.389272) (xy 94.07919 -233.418182) (xy 94.033211 -233.439999)
			(xy 93.984327 -233.454159) (xy 93.933806 -233.460293) (xy 93.882954 -233.458244) (xy 93.83309 -233.448064)
			(xy 93.785504 -233.430017) (xy 93.74143 -233.404571) (xy 93.702008 -233.372384) (xy 93.66826 -233.33429)
			(xy 93.641059 -233.291276) (xy 93.621111 -233.244456) (xy 93.608932 -233.195042) (xy 93.604837 -233.144314)
			(xy 93.286326 -233.144314) (xy 93.285831 -233.168921) (xy 93.277936 -233.217498) (xy 93.262352 -233.264179)
			(xy 93.239481 -233.307756) (xy 93.209916 -233.3471) (xy 93.174423 -233.381192) (xy 93.13392 -233.409148)
			(xy 93.089458 -233.430246) (xy 93.042187 -233.443938) (xy 92.993332 -233.44987) (xy 92.944157 -233.447889)
			(xy 92.895938 -233.438045) (xy 92.849922 -233.420593) (xy 92.807301 -233.395986) (xy 92.76918 -233.364861)
			(xy 92.736545 -233.328024) (xy 92.710242 -233.286428) (xy 92.690951 -233.241152) (xy 92.679174 -233.193368)
			(xy 92.675214 -233.144314) (xy 92.356686 -233.144314) (xy 92.356174 -233.16976) (xy 92.34801 -233.219994)
			(xy 92.331894 -233.268268) (xy 92.308243 -233.313331) (xy 92.27767 -233.354017) (xy 92.240966 -233.389272)
			(xy 92.199082 -233.418182) (xy 92.153103 -233.439999) (xy 92.104219 -233.454159) (xy 92.053698 -233.460293)
			(xy 92.002846 -233.458244) (xy 91.952982 -233.448064) (xy 91.905396 -233.430017) (xy 91.861322 -233.404571)
			(xy 91.8219 -233.372384) (xy 91.788152 -233.33429) (xy 91.760951 -233.291276) (xy 91.741003 -233.244456)
			(xy 91.728824 -233.195042) (xy 91.724729 -233.144314) (xy 91.416632 -233.144314) (xy 91.41612 -233.16976)
			(xy 91.407956 -233.219994) (xy 91.39184 -233.268268) (xy 91.368189 -233.313331) (xy 91.337616 -233.354017)
			(xy 91.300912 -233.389272) (xy 91.259028 -233.418182) (xy 91.213049 -233.439999) (xy 91.164165 -233.454159)
			(xy 91.113644 -233.460293) (xy 91.062792 -233.458244) (xy 91.012928 -233.448064) (xy 90.965342 -233.430017)
			(xy 90.921268 -233.404571) (xy 90.881846 -233.372384) (xy 90.848098 -233.33429) (xy 90.820897 -233.291276)
			(xy 90.800949 -233.244456) (xy 90.78877 -233.195042) (xy 90.784675 -233.144314) (xy 90.466418 -233.144314)
			(xy 90.465923 -233.168921) (xy 90.458028 -233.217498) (xy 90.442444 -233.264179) (xy 90.419573 -233.307756)
			(xy 90.390008 -233.3471) (xy 90.354515 -233.381192) (xy 90.314012 -233.409148) (xy 90.26955 -233.430246)
			(xy 90.222279 -233.443938) (xy 90.173424 -233.44987) (xy 90.124249 -233.447889) (xy 90.07603 -233.438045)
			(xy 90.030014 -233.420593) (xy 89.987393 -233.395986) (xy 89.949272 -233.364861) (xy 89.916637 -233.328024)
			(xy 89.890334 -233.286428) (xy 89.871043 -233.241152) (xy 89.859266 -233.193368) (xy 89.855306 -233.144314)
			(xy 89.536778 -233.144314) (xy 89.536266 -233.16976) (xy 89.528102 -233.219994) (xy 89.511986 -233.268268)
			(xy 89.488335 -233.313331) (xy 89.457762 -233.354017) (xy 89.421058 -233.389272) (xy 89.379174 -233.418182)
			(xy 89.333195 -233.439999) (xy 89.284311 -233.454159) (xy 89.23379 -233.460293) (xy 89.182938 -233.458244)
			(xy 89.133074 -233.448064) (xy 89.085488 -233.430017) (xy 89.041414 -233.404571) (xy 89.001992 -233.372384)
			(xy 88.968244 -233.33429) (xy 88.941043 -233.291276) (xy 88.921095 -233.244456) (xy 88.908916 -233.195042)
			(xy 88.904821 -233.144314) (xy 88.58631 -233.144314) (xy 88.585815 -233.168921) (xy 88.57792 -233.217498)
			(xy 88.562336 -233.264179) (xy 88.539465 -233.307756) (xy 88.5099 -233.3471) (xy 88.474407 -233.381192)
			(xy 88.433904 -233.409148) (xy 88.389442 -233.430246) (xy 88.342171 -233.443938) (xy 88.293316 -233.44987)
			(xy 88.244141 -233.447889) (xy 88.195922 -233.438045) (xy 88.149906 -233.420593) (xy 88.107285 -233.395986)
			(xy 88.069164 -233.364861) (xy 88.036529 -233.328024) (xy 88.010226 -233.286428) (xy 87.990935 -233.241152)
			(xy 87.979158 -233.193368) (xy 87.975198 -233.144314) (xy 87.65667 -233.144314) (xy 87.656158 -233.16976)
			(xy 87.647994 -233.219994) (xy 87.631878 -233.268268) (xy 87.608227 -233.313331) (xy 87.577654 -233.354017)
			(xy 87.54095 -233.389272) (xy 87.499066 -233.418182) (xy 87.453087 -233.439999) (xy 87.404203 -233.454159)
			(xy 87.353682 -233.460293) (xy 87.30283 -233.458244) (xy 87.252966 -233.448064) (xy 87.20538 -233.430017)
			(xy 87.161306 -233.404571) (xy 87.121884 -233.372384) (xy 87.088136 -233.33429) (xy 87.060935 -233.291276)
			(xy 87.040987 -233.244456) (xy 87.028808 -233.195042) (xy 87.024713 -233.144314) (xy 86.706456 -233.144314)
			(xy 86.705961 -233.168921) (xy 86.698066 -233.217498) (xy 86.682482 -233.264179) (xy 86.659611 -233.307756)
			(xy 86.630046 -233.3471) (xy 86.594553 -233.381192) (xy 86.55405 -233.409148) (xy 86.509588 -233.430246)
			(xy 86.462317 -233.443938) (xy 86.413462 -233.44987) (xy 86.364287 -233.447889) (xy 86.316068 -233.438045)
			(xy 86.270052 -233.420593) (xy 86.227431 -233.395986) (xy 86.18931 -233.364861) (xy 86.156675 -233.328024)
			(xy 86.130372 -233.286428) (xy 86.111081 -233.241152) (xy 86.099304 -233.193368) (xy 86.095344 -233.144314)
			(xy 85.776816 -233.144314) (xy 85.776304 -233.16976) (xy 85.76814 -233.219994) (xy 85.752024 -233.268268)
			(xy 85.728373 -233.313331) (xy 85.6978 -233.354017) (xy 85.661096 -233.389272) (xy 85.619212 -233.418182)
			(xy 85.573233 -233.439999) (xy 85.524349 -233.454159) (xy 85.473828 -233.460293) (xy 85.422976 -233.458244)
			(xy 85.373112 -233.448064) (xy 85.325526 -233.430017) (xy 85.281452 -233.404571) (xy 85.24203 -233.372384)
			(xy 85.208282 -233.33429) (xy 85.181081 -233.291276) (xy 85.161133 -233.244456) (xy 85.148954 -233.195042)
			(xy 85.144859 -233.144314) (xy 84.836762 -233.144314) (xy 84.83625 -233.16976) (xy 84.828086 -233.219994)
			(xy 84.81197 -233.268268) (xy 84.788319 -233.313331) (xy 84.757746 -233.354017) (xy 84.721042 -233.389272)
			(xy 84.679158 -233.418182) (xy 84.633179 -233.439999) (xy 84.584295 -233.454159) (xy 84.533774 -233.460293)
			(xy 84.482922 -233.458244) (xy 84.433058 -233.448064) (xy 84.385472 -233.430017) (xy 84.341398 -233.404571)
			(xy 84.301976 -233.372384) (xy 84.268228 -233.33429) (xy 84.241027 -233.291276) (xy 84.221079 -233.244456)
			(xy 84.2089 -233.195042) (xy 84.204805 -233.144314) (xy 83.886294 -233.144314) (xy 83.885799 -233.168921)
			(xy 83.877904 -233.217498) (xy 83.86232 -233.264179) (xy 83.839449 -233.307756) (xy 83.809884 -233.3471)
			(xy 83.774391 -233.381192) (xy 83.733888 -233.409148) (xy 83.689426 -233.430246) (xy 83.642155 -233.443938)
			(xy 83.5933 -233.44987) (xy 83.544125 -233.447889) (xy 83.495906 -233.438045) (xy 83.44989 -233.420593)
			(xy 83.407269 -233.395986) (xy 83.369148 -233.364861) (xy 83.336513 -233.328024) (xy 83.31021 -233.286428)
			(xy 83.290919 -233.241152) (xy 83.279142 -233.193368) (xy 83.275182 -233.144314) (xy 82.956654 -233.144314)
			(xy 82.956142 -233.16976) (xy 82.947978 -233.219994) (xy 82.931862 -233.268268) (xy 82.908211 -233.313331)
			(xy 82.877638 -233.354017) (xy 82.840934 -233.389272) (xy 82.79905 -233.418182) (xy 82.753071 -233.439999)
			(xy 82.704187 -233.454159) (xy 82.653666 -233.460293) (xy 82.602814 -233.458244) (xy 82.55295 -233.448064)
			(xy 82.505364 -233.430017) (xy 82.46129 -233.404571) (xy 82.421868 -233.372384) (xy 82.38812 -233.33429)
			(xy 82.360919 -233.291276) (xy 82.340971 -233.244456) (xy 82.328792 -233.195042) (xy 82.324697 -233.144314)
			(xy 82.00644 -233.144314) (xy 82.005945 -233.168921) (xy 81.99805 -233.217498) (xy 81.982466 -233.264179)
			(xy 81.959595 -233.307756) (xy 81.93003 -233.3471) (xy 81.894537 -233.381192) (xy 81.854034 -233.409148)
			(xy 81.809572 -233.430246) (xy 81.762301 -233.443938) (xy 81.713446 -233.44987) (xy 81.664271 -233.447889)
			(xy 81.616052 -233.438045) (xy 81.570036 -233.420593) (xy 81.527415 -233.395986) (xy 81.489294 -233.364861)
			(xy 81.456659 -233.328024) (xy 81.430356 -233.286428) (xy 81.411065 -233.241152) (xy 81.399288 -233.193368)
			(xy 81.395328 -233.144314) (xy 81.0768 -233.144314) (xy 81.076288 -233.16976) (xy 81.068124 -233.219994)
			(xy 81.052008 -233.268268) (xy 81.028357 -233.313331) (xy 80.997784 -233.354017) (xy 80.96108 -233.389272)
			(xy 80.919196 -233.418182) (xy 80.873217 -233.439999) (xy 80.824333 -233.454159) (xy 80.773812 -233.460293)
			(xy 80.72296 -233.458244) (xy 80.673096 -233.448064) (xy 80.62551 -233.430017) (xy 80.581436 -233.404571)
			(xy 80.542014 -233.372384) (xy 80.508266 -233.33429) (xy 80.481065 -233.291276) (xy 80.461117 -233.244456)
			(xy 80.448938 -233.195042) (xy 80.444843 -233.144314) (xy 80.126332 -233.144314) (xy 80.125837 -233.168921)
			(xy 80.117942 -233.217498) (xy 80.102358 -233.264179) (xy 80.079487 -233.307756) (xy 80.049922 -233.3471)
			(xy 80.014429 -233.381192) (xy 79.973926 -233.409148) (xy 79.929464 -233.430246) (xy 79.882193 -233.443938)
			(xy 79.833338 -233.44987) (xy 79.784163 -233.447889) (xy 79.735944 -233.438045) (xy 79.689928 -233.420593)
			(xy 79.647307 -233.395986) (xy 79.609186 -233.364861) (xy 79.576551 -233.328024) (xy 79.550248 -233.286428)
			(xy 79.530957 -233.241152) (xy 79.51918 -233.193368) (xy 79.51522 -233.144314) (xy 76.963477 -233.144314)
			(xy 76.965804 -233.145418) (xy 77.006307 -233.173374) (xy 77.0418 -233.207466) (xy 77.071365 -233.24681)
			(xy 77.094236 -233.290387) (xy 77.10982 -233.337068) (xy 77.117715 -233.385645) (xy 77.11821 -233.410252)
			(xy 77.117715 -233.434859) (xy 77.10982 -233.483436) (xy 77.094236 -233.530117) (xy 77.071365 -233.573694)
			(xy 77.0418 -233.613038) (xy 77.006307 -233.64713) (xy 76.965804 -233.675086) (xy 76.921342 -233.696184)
			(xy 76.874071 -233.709876) (xy 76.825216 -233.715808) (xy 76.776041 -233.713827) (xy 76.727822 -233.703983)
			(xy 76.681806 -233.686531) (xy 76.639185 -233.661924) (xy 76.601064 -233.630799) (xy 76.568429 -233.593962)
			(xy 76.542126 -233.552366) (xy 76.522835 -233.50709) (xy 76.511058 -233.459306) (xy 76.507098 -233.410252)
			(xy 62.37732 -233.410252) (xy 62.37732 -233.95432) (xy 78.105266 -233.95432) (xy 78.109226 -233.905266)
			(xy 78.121003 -233.857482) (xy 78.140294 -233.812206) (xy 78.166597 -233.77061) (xy 78.199232 -233.733773)
			(xy 78.237353 -233.702648) (xy 78.279974 -233.678041) (xy 78.32599 -233.660589) (xy 78.374209 -233.650745)
			(xy 78.423384 -233.648764) (xy 78.472239 -233.654696) (xy 78.51951 -233.668388) (xy 78.563972 -233.689486)
			(xy 78.604475 -233.717442) (xy 78.639968 -233.751534) (xy 78.669533 -233.790878) (xy 78.692404 -233.834455)
			(xy 78.707988 -233.881136) (xy 78.715883 -233.929713) (xy 78.716378 -233.95432) (xy 79.985374 -233.95432)
			(xy 79.989334 -233.905266) (xy 80.001111 -233.857482) (xy 80.020402 -233.812206) (xy 80.046705 -233.77061)
			(xy 80.07934 -233.733773) (xy 80.117461 -233.702648) (xy 80.160082 -233.678041) (xy 80.206098 -233.660589)
			(xy 80.254317 -233.650745) (xy 80.303492 -233.648764) (xy 80.352347 -233.654696) (xy 80.399618 -233.668388)
			(xy 80.44408 -233.689486) (xy 80.484583 -233.717442) (xy 80.520076 -233.751534) (xy 80.549641 -233.790878)
			(xy 80.572512 -233.834455) (xy 80.588096 -233.881136) (xy 80.595991 -233.929713) (xy 80.596486 -233.95432)
			(xy 80.914743 -233.95432) (xy 80.918838 -233.903592) (xy 80.931017 -233.854178) (xy 80.950965 -233.807358)
			(xy 80.978166 -233.764344) (xy 81.011914 -233.72625) (xy 81.051336 -233.694063) (xy 81.09541 -233.668617)
			(xy 81.142996 -233.65057) (xy 81.19286 -233.64039) (xy 81.243712 -233.638341) (xy 81.294233 -233.644475)
			(xy 81.343117 -233.658635) (xy 81.389096 -233.680452) (xy 81.43098 -233.709362) (xy 81.467684 -233.744617)
			(xy 81.498257 -233.785303) (xy 81.521908 -233.830366) (xy 81.538024 -233.87864) (xy 81.546188 -233.928874)
			(xy 81.5467 -233.95432) (xy 81.854797 -233.95432) (xy 81.858892 -233.903592) (xy 81.871071 -233.854178)
			(xy 81.891019 -233.807358) (xy 81.91822 -233.764344) (xy 81.951968 -233.72625) (xy 81.99139 -233.694063)
			(xy 82.035464 -233.668617) (xy 82.08305 -233.65057) (xy 82.132914 -233.64039) (xy 82.183766 -233.638341)
			(xy 82.234287 -233.644475) (xy 82.283171 -233.658635) (xy 82.32915 -233.680452) (xy 82.371034 -233.709362)
			(xy 82.407738 -233.744617) (xy 82.438311 -233.785303) (xy 82.461962 -233.830366) (xy 82.478078 -233.87864)
			(xy 82.486242 -233.928874) (xy 82.486754 -233.95432) (xy 82.805282 -233.95432) (xy 82.809242 -233.905266)
			(xy 82.821019 -233.857482) (xy 82.84031 -233.812206) (xy 82.866613 -233.77061) (xy 82.899248 -233.733773)
			(xy 82.937369 -233.702648) (xy 82.97999 -233.678041) (xy 83.026006 -233.660589) (xy 83.074225 -233.650745)
			(xy 83.1234 -233.648764) (xy 83.172255 -233.654696) (xy 83.219526 -233.668388) (xy 83.263988 -233.689486)
			(xy 83.304491 -233.717442) (xy 83.339984 -233.751534) (xy 83.369549 -233.790878) (xy 83.39242 -233.834455)
			(xy 83.408004 -233.881136) (xy 83.415899 -233.929713) (xy 83.416394 -233.95432) (xy 83.734905 -233.95432)
			(xy 83.739 -233.903592) (xy 83.751179 -233.854178) (xy 83.771127 -233.807358) (xy 83.798328 -233.764344)
			(xy 83.832076 -233.72625) (xy 83.871498 -233.694063) (xy 83.915572 -233.668617) (xy 83.963158 -233.65057)
			(xy 84.013022 -233.64039) (xy 84.063874 -233.638341) (xy 84.114395 -233.644475) (xy 84.163279 -233.658635)
			(xy 84.209258 -233.680452) (xy 84.251142 -233.709362) (xy 84.287846 -233.744617) (xy 84.318419 -233.785303)
			(xy 84.34207 -233.830366) (xy 84.358186 -233.87864) (xy 84.36635 -233.928874) (xy 84.366862 -233.95432)
			(xy 84.685136 -233.95432) (xy 84.689096 -233.905266) (xy 84.700873 -233.857482) (xy 84.720164 -233.812206)
			(xy 84.746467 -233.77061) (xy 84.779102 -233.733773) (xy 84.817223 -233.702648) (xy 84.859844 -233.678041)
			(xy 84.90586 -233.660589) (xy 84.954079 -233.650745) (xy 85.003254 -233.648764) (xy 85.052109 -233.654696)
			(xy 85.09938 -233.668388) (xy 85.143842 -233.689486) (xy 85.184345 -233.717442) (xy 85.219838 -233.751534)
			(xy 85.249403 -233.790878) (xy 85.272274 -233.834455) (xy 85.287858 -233.881136) (xy 85.295753 -233.929713)
			(xy 85.296248 -233.95432) (xy 85.614759 -233.95432) (xy 85.618854 -233.903592) (xy 85.631033 -233.854178)
			(xy 85.650981 -233.807358) (xy 85.678182 -233.764344) (xy 85.71193 -233.72625) (xy 85.751352 -233.694063)
			(xy 85.795426 -233.668617) (xy 85.843012 -233.65057) (xy 85.892876 -233.64039) (xy 85.943728 -233.638341)
			(xy 85.994249 -233.644475) (xy 86.043133 -233.658635) (xy 86.089112 -233.680452) (xy 86.130996 -233.709362)
			(xy 86.1677 -233.744617) (xy 86.198273 -233.785303) (xy 86.221924 -233.830366) (xy 86.23804 -233.87864)
			(xy 86.246204 -233.928874) (xy 86.246716 -233.95432) (xy 86.565244 -233.95432) (xy 86.569204 -233.905266)
			(xy 86.580981 -233.857482) (xy 86.600272 -233.812206) (xy 86.626575 -233.77061) (xy 86.65921 -233.733773)
			(xy 86.697331 -233.702648) (xy 86.739952 -233.678041) (xy 86.785968 -233.660589) (xy 86.834187 -233.650745)
			(xy 86.883362 -233.648764) (xy 86.932217 -233.654696) (xy 86.979488 -233.668388) (xy 87.02395 -233.689486)
			(xy 87.064453 -233.717442) (xy 87.099946 -233.751534) (xy 87.129511 -233.790878) (xy 87.152382 -233.834455)
			(xy 87.167966 -233.881136) (xy 87.175861 -233.929713) (xy 87.176356 -233.95432) (xy 87.494867 -233.95432)
			(xy 87.498962 -233.903592) (xy 87.511141 -233.854178) (xy 87.531089 -233.807358) (xy 87.55829 -233.764344)
			(xy 87.592038 -233.72625) (xy 87.63146 -233.694063) (xy 87.675534 -233.668617) (xy 87.72312 -233.65057)
			(xy 87.772984 -233.64039) (xy 87.823836 -233.638341) (xy 87.874357 -233.644475) (xy 87.923241 -233.658635)
			(xy 87.96922 -233.680452) (xy 88.011104 -233.709362) (xy 88.047808 -233.744617) (xy 88.078381 -233.785303)
			(xy 88.102032 -233.830366) (xy 88.118148 -233.87864) (xy 88.126312 -233.928874) (xy 88.126824 -233.95432)
			(xy 88.434921 -233.95432) (xy 88.439016 -233.903592) (xy 88.451195 -233.854178) (xy 88.471143 -233.807358)
			(xy 88.498344 -233.764344) (xy 88.532092 -233.72625) (xy 88.571514 -233.694063) (xy 88.615588 -233.668617)
			(xy 88.663174 -233.65057) (xy 88.713038 -233.64039) (xy 88.76389 -233.638341) (xy 88.814411 -233.644475)
			(xy 88.863295 -233.658635) (xy 88.909274 -233.680452) (xy 88.951158 -233.709362) (xy 88.987862 -233.744617)
			(xy 89.018435 -233.785303) (xy 89.042086 -233.830366) (xy 89.058202 -233.87864) (xy 89.066366 -233.928874)
			(xy 89.066878 -233.95432) (xy 89.385152 -233.95432) (xy 89.389112 -233.905266) (xy 89.400889 -233.857482)
			(xy 89.42018 -233.812206) (xy 89.446483 -233.77061) (xy 89.479118 -233.733773) (xy 89.517239 -233.702648)
			(xy 89.55986 -233.678041) (xy 89.605876 -233.660589) (xy 89.654095 -233.650745) (xy 89.70327 -233.648764)
			(xy 89.752125 -233.654696) (xy 89.799396 -233.668388) (xy 89.843858 -233.689486) (xy 89.884361 -233.717442)
			(xy 89.919854 -233.751534) (xy 89.949419 -233.790878) (xy 89.97229 -233.834455) (xy 89.987874 -233.881136)
			(xy 89.995769 -233.929713) (xy 89.996264 -233.95432) (xy 90.314775 -233.95432) (xy 90.31887 -233.903592)
			(xy 90.331049 -233.854178) (xy 90.350997 -233.807358) (xy 90.378198 -233.764344) (xy 90.411946 -233.72625)
			(xy 90.451368 -233.694063) (xy 90.495442 -233.668617) (xy 90.543028 -233.65057) (xy 90.592892 -233.64039)
			(xy 90.643744 -233.638341) (xy 90.694265 -233.644475) (xy 90.743149 -233.658635) (xy 90.789128 -233.680452)
			(xy 90.831012 -233.709362) (xy 90.867716 -233.744617) (xy 90.898289 -233.785303) (xy 90.92194 -233.830366)
			(xy 90.938056 -233.87864) (xy 90.94622 -233.928874) (xy 90.946732 -233.95432) (xy 91.26526 -233.95432)
			(xy 91.26922 -233.905266) (xy 91.280997 -233.857482) (xy 91.300288 -233.812206) (xy 91.326591 -233.77061)
			(xy 91.359226 -233.733773) (xy 91.397347 -233.702648) (xy 91.439968 -233.678041) (xy 91.485984 -233.660589)
			(xy 91.534203 -233.650745) (xy 91.583378 -233.648764) (xy 91.632233 -233.654696) (xy 91.679504 -233.668388)
			(xy 91.723966 -233.689486) (xy 91.764469 -233.717442) (xy 91.799962 -233.751534) (xy 91.829527 -233.790878)
			(xy 91.852398 -233.834455) (xy 91.867982 -233.881136) (xy 91.875877 -233.929713) (xy 91.876372 -233.95432)
			(xy 92.194883 -233.95432) (xy 92.198978 -233.903592) (xy 92.211157 -233.854178) (xy 92.231105 -233.807358)
			(xy 92.258306 -233.764344) (xy 92.292054 -233.72625) (xy 92.331476 -233.694063) (xy 92.37555 -233.668617)
			(xy 92.423136 -233.65057) (xy 92.473 -233.64039) (xy 92.523852 -233.638341) (xy 92.574373 -233.644475)
			(xy 92.623257 -233.658635) (xy 92.669236 -233.680452) (xy 92.71112 -233.709362) (xy 92.747824 -233.744617)
			(xy 92.778397 -233.785303) (xy 92.802048 -233.830366) (xy 92.818164 -233.87864) (xy 92.826328 -233.928874)
			(xy 92.82684 -233.95432) (xy 93.145114 -233.95432) (xy 93.149074 -233.905266) (xy 93.160851 -233.857482)
			(xy 93.180142 -233.812206) (xy 93.206445 -233.77061) (xy 93.23908 -233.733773) (xy 93.277201 -233.702648)
			(xy 93.319822 -233.678041) (xy 93.365838 -233.660589) (xy 93.414057 -233.650745) (xy 93.463232 -233.648764)
			(xy 93.512087 -233.654696) (xy 93.559358 -233.668388) (xy 93.60382 -233.689486) (xy 93.644323 -233.717442)
			(xy 93.679816 -233.751534) (xy 93.709381 -233.790878) (xy 93.732252 -233.834455) (xy 93.747836 -233.881136)
			(xy 93.755731 -233.929713) (xy 93.756226 -233.95432) (xy 94.074737 -233.95432) (xy 94.078832 -233.903592)
			(xy 94.091011 -233.854178) (xy 94.110959 -233.807358) (xy 94.13816 -233.764344) (xy 94.171908 -233.72625)
			(xy 94.21133 -233.694063) (xy 94.255404 -233.668617) (xy 94.30299 -233.65057) (xy 94.352854 -233.64039)
			(xy 94.403706 -233.638341) (xy 94.454227 -233.644475) (xy 94.503111 -233.658635) (xy 94.54909 -233.680452)
			(xy 94.590974 -233.709362) (xy 94.627678 -233.744617) (xy 94.658251 -233.785303) (xy 94.681902 -233.830366)
			(xy 94.698018 -233.87864) (xy 94.706182 -233.928874) (xy 94.706694 -233.95432) (xy 95.014791 -233.95432)
			(xy 95.018886 -233.903592) (xy 95.031065 -233.854178) (xy 95.051013 -233.807358) (xy 95.078214 -233.764344)
			(xy 95.111962 -233.72625) (xy 95.151384 -233.694063) (xy 95.195458 -233.668617) (xy 95.243044 -233.65057)
			(xy 95.292908 -233.64039) (xy 95.34376 -233.638341) (xy 95.394281 -233.644475) (xy 95.443165 -233.658635)
			(xy 95.489144 -233.680452) (xy 95.531028 -233.709362) (xy 95.567732 -233.744617) (xy 95.598305 -233.785303)
			(xy 95.621956 -233.830366) (xy 95.638072 -233.87864) (xy 95.646236 -233.928874) (xy 95.646748 -233.95432)
			(xy 95.965276 -233.95432) (xy 95.969236 -233.905266) (xy 95.981013 -233.857482) (xy 96.000304 -233.812206)
			(xy 96.026607 -233.77061) (xy 96.059242 -233.733773) (xy 96.097363 -233.702648) (xy 96.139984 -233.678041)
			(xy 96.186 -233.660589) (xy 96.234219 -233.650745) (xy 96.283394 -233.648764) (xy 96.332249 -233.654696)
			(xy 96.37952 -233.668388) (xy 96.423982 -233.689486) (xy 96.464485 -233.717442) (xy 96.499978 -233.751534)
			(xy 96.529543 -233.790878) (xy 96.552414 -233.834455) (xy 96.567998 -233.881136) (xy 96.575893 -233.929713)
			(xy 96.576388 -233.95432) (xy 98.785184 -233.95432) (xy 98.789144 -233.905266) (xy 98.800921 -233.857482)
			(xy 98.820212 -233.812206) (xy 98.846515 -233.77061) (xy 98.87915 -233.733773) (xy 98.917271 -233.702648)
			(xy 98.959892 -233.678041) (xy 99.005908 -233.660589) (xy 99.054127 -233.650745) (xy 99.103302 -233.648764)
			(xy 99.152157 -233.654696) (xy 99.199428 -233.668388) (xy 99.24389 -233.689486) (xy 99.284393 -233.717442)
			(xy 99.319886 -233.751534) (xy 99.349451 -233.790878) (xy 99.372322 -233.834455) (xy 99.387906 -233.881136)
			(xy 99.395801 -233.929713) (xy 99.396296 -233.95432) (xy 101.605346 -233.95432) (xy 101.609306 -233.905266)
			(xy 101.621083 -233.857482) (xy 101.640374 -233.812206) (xy 101.666677 -233.77061) (xy 101.699312 -233.733773)
			(xy 101.737433 -233.702648) (xy 101.780054 -233.678041) (xy 101.82607 -233.660589) (xy 101.874289 -233.650745)
			(xy 101.923464 -233.648764) (xy 101.972319 -233.654696) (xy 102.01959 -233.668388) (xy 102.064052 -233.689486)
			(xy 102.104555 -233.717442) (xy 102.140048 -233.751534) (xy 102.169613 -233.790878) (xy 102.192484 -233.834455)
			(xy 102.208068 -233.881136) (xy 102.215963 -233.929713) (xy 102.216458 -233.95432) (xy 104.425254 -233.95432)
			(xy 104.429214 -233.905266) (xy 104.440991 -233.857482) (xy 104.460282 -233.812206) (xy 104.486585 -233.77061)
			(xy 104.51922 -233.733773) (xy 104.557341 -233.702648) (xy 104.599962 -233.678041) (xy 104.645978 -233.660589)
			(xy 104.694197 -233.650745) (xy 104.743372 -233.648764) (xy 104.792227 -233.654696) (xy 104.839498 -233.668388)
			(xy 104.88396 -233.689486) (xy 104.924463 -233.717442) (xy 104.959956 -233.751534) (xy 104.989521 -233.790878)
			(xy 105.012392 -233.834455) (xy 105.027976 -233.881136) (xy 105.035871 -233.929713) (xy 105.036366 -233.95432)
			(xy 107.245162 -233.95432) (xy 107.249122 -233.905266) (xy 107.260899 -233.857482) (xy 107.28019 -233.812206)
			(xy 107.306493 -233.77061) (xy 107.339128 -233.733773) (xy 107.377249 -233.702648) (xy 107.41987 -233.678041)
			(xy 107.465886 -233.660589) (xy 107.514105 -233.650745) (xy 107.56328 -233.648764) (xy 107.612135 -233.654696)
			(xy 107.659406 -233.668388) (xy 107.703868 -233.689486) (xy 107.744371 -233.717442) (xy 107.779864 -233.751534)
			(xy 107.809429 -233.790878) (xy 107.8323 -233.834455) (xy 107.847884 -233.881136) (xy 107.855779 -233.929713)
			(xy 107.856274 -233.95432) (xy 108.174785 -233.95432) (xy 108.17888 -233.903592) (xy 108.191059 -233.854178)
			(xy 108.211007 -233.807358) (xy 108.238208 -233.764344) (xy 108.271956 -233.72625) (xy 108.311378 -233.694063)
			(xy 108.355452 -233.668617) (xy 108.403038 -233.65057) (xy 108.452902 -233.64039) (xy 108.503754 -233.638341)
			(xy 108.554275 -233.644475) (xy 108.603159 -233.658635) (xy 108.649138 -233.680452) (xy 108.691022 -233.709362)
			(xy 108.727726 -233.744617) (xy 108.758299 -233.785303) (xy 108.78195 -233.830366) (xy 108.798066 -233.87864)
			(xy 108.80623 -233.928874) (xy 108.806742 -233.95432) (xy 109.114839 -233.95432) (xy 109.118934 -233.903592)
			(xy 109.131113 -233.854178) (xy 109.151061 -233.807358) (xy 109.178262 -233.764344) (xy 109.21201 -233.72625)
			(xy 109.251432 -233.694063) (xy 109.295506 -233.668617) (xy 109.343092 -233.65057) (xy 109.392956 -233.64039)
			(xy 109.443808 -233.638341) (xy 109.494329 -233.644475) (xy 109.543213 -233.658635) (xy 109.589192 -233.680452)
			(xy 109.631076 -233.709362) (xy 109.66778 -233.744617) (xy 109.698353 -233.785303) (xy 109.722004 -233.830366)
			(xy 109.73812 -233.87864) (xy 109.746284 -233.928874) (xy 109.746796 -233.95432) (xy 110.065324 -233.95432)
			(xy 110.069284 -233.905266) (xy 110.081061 -233.857482) (xy 110.100352 -233.812206) (xy 110.126655 -233.77061)
			(xy 110.15929 -233.733773) (xy 110.197411 -233.702648) (xy 110.240032 -233.678041) (xy 110.286048 -233.660589)
			(xy 110.334267 -233.650745) (xy 110.383442 -233.648764) (xy 110.432297 -233.654696) (xy 110.479568 -233.668388)
			(xy 110.52403 -233.689486) (xy 110.564533 -233.717442) (xy 110.600026 -233.751534) (xy 110.629591 -233.790878)
			(xy 110.652462 -233.834455) (xy 110.668046 -233.881136) (xy 110.675941 -233.929713) (xy 110.676436 -233.95432)
			(xy 110.675941 -233.978927) (xy 110.668046 -234.027504) (xy 110.652462 -234.074185) (xy 110.629591 -234.117762)
			(xy 110.600026 -234.157106) (xy 110.564533 -234.191198) (xy 110.52403 -234.219154) (xy 110.479568 -234.240252)
			(xy 110.432297 -234.253944) (xy 110.383442 -234.259876) (xy 110.334267 -234.257895) (xy 110.286048 -234.248051)
			(xy 110.240032 -234.230599) (xy 110.197411 -234.205992) (xy 110.15929 -234.174867) (xy 110.126655 -234.13803)
			(xy 110.100352 -234.096434) (xy 110.081061 -234.051158) (xy 110.069284 -234.003374) (xy 110.065324 -233.95432)
			(xy 109.746796 -233.95432) (xy 109.746284 -233.979766) (xy 109.73812 -234.03) (xy 109.722004 -234.078274)
			(xy 109.698353 -234.123337) (xy 109.66778 -234.164023) (xy 109.631076 -234.199278) (xy 109.589192 -234.228188)
			(xy 109.543213 -234.250005) (xy 109.494329 -234.264165) (xy 109.443808 -234.270299) (xy 109.392956 -234.26825)
			(xy 109.343092 -234.25807) (xy 109.295506 -234.240023) (xy 109.251432 -234.214577) (xy 109.21201 -234.18239)
			(xy 109.178262 -234.144296) (xy 109.151061 -234.101282) (xy 109.131113 -234.054462) (xy 109.118934 -234.005048)
			(xy 109.114839 -233.95432) (xy 108.806742 -233.95432) (xy 108.80623 -233.979766) (xy 108.798066 -234.03)
			(xy 108.78195 -234.078274) (xy 108.758299 -234.123337) (xy 108.727726 -234.164023) (xy 108.691022 -234.199278)
			(xy 108.649138 -234.228188) (xy 108.603159 -234.250005) (xy 108.554275 -234.264165) (xy 108.503754 -234.270299)
			(xy 108.452902 -234.26825) (xy 108.403038 -234.25807) (xy 108.355452 -234.240023) (xy 108.311378 -234.214577)
			(xy 108.271956 -234.18239) (xy 108.238208 -234.144296) (xy 108.211007 -234.101282) (xy 108.191059 -234.054462)
			(xy 108.17888 -234.005048) (xy 108.174785 -233.95432) (xy 107.856274 -233.95432) (xy 107.855779 -233.978927)
			(xy 107.847884 -234.027504) (xy 107.8323 -234.074185) (xy 107.809429 -234.117762) (xy 107.779864 -234.157106)
			(xy 107.744371 -234.191198) (xy 107.703868 -234.219154) (xy 107.659406 -234.240252) (xy 107.612135 -234.253944)
			(xy 107.56328 -234.259876) (xy 107.514105 -234.257895) (xy 107.465886 -234.248051) (xy 107.41987 -234.230599)
			(xy 107.377249 -234.205992) (xy 107.339128 -234.174867) (xy 107.306493 -234.13803) (xy 107.28019 -234.096434)
			(xy 107.260899 -234.051158) (xy 107.249122 -234.003374) (xy 107.245162 -233.95432) (xy 105.036366 -233.95432)
			(xy 105.035871 -233.978927) (xy 105.027976 -234.027504) (xy 105.012392 -234.074185) (xy 104.989521 -234.117762)
			(xy 104.959956 -234.157106) (xy 104.924463 -234.191198) (xy 104.88396 -234.219154) (xy 104.839498 -234.240252)
			(xy 104.792227 -234.253944) (xy 104.743372 -234.259876) (xy 104.694197 -234.257895) (xy 104.645978 -234.248051)
			(xy 104.599962 -234.230599) (xy 104.557341 -234.205992) (xy 104.51922 -234.174867) (xy 104.486585 -234.13803)
			(xy 104.460282 -234.096434) (xy 104.440991 -234.051158) (xy 104.429214 -234.003374) (xy 104.425254 -233.95432)
			(xy 102.216458 -233.95432) (xy 102.215963 -233.978927) (xy 102.208068 -234.027504) (xy 102.192484 -234.074185)
			(xy 102.169613 -234.117762) (xy 102.140048 -234.157106) (xy 102.104555 -234.191198) (xy 102.064052 -234.219154)
			(xy 102.01959 -234.240252) (xy 101.972319 -234.253944) (xy 101.923464 -234.259876) (xy 101.874289 -234.257895)
			(xy 101.82607 -234.248051) (xy 101.780054 -234.230599) (xy 101.737433 -234.205992) (xy 101.699312 -234.174867)
			(xy 101.666677 -234.13803) (xy 101.640374 -234.096434) (xy 101.621083 -234.051158) (xy 101.609306 -234.003374)
			(xy 101.605346 -233.95432) (xy 99.396296 -233.95432) (xy 99.395801 -233.978927) (xy 99.387906 -234.027504)
			(xy 99.372322 -234.074185) (xy 99.349451 -234.117762) (xy 99.319886 -234.157106) (xy 99.284393 -234.191198)
			(xy 99.24389 -234.219154) (xy 99.199428 -234.240252) (xy 99.152157 -234.253944) (xy 99.103302 -234.259876)
			(xy 99.054127 -234.257895) (xy 99.005908 -234.248051) (xy 98.959892 -234.230599) (xy 98.917271 -234.205992)
			(xy 98.87915 -234.174867) (xy 98.846515 -234.13803) (xy 98.820212 -234.096434) (xy 98.800921 -234.051158)
			(xy 98.789144 -234.003374) (xy 98.785184 -233.95432) (xy 96.576388 -233.95432) (xy 96.575893 -233.978927)
			(xy 96.567998 -234.027504) (xy 96.552414 -234.074185) (xy 96.529543 -234.117762) (xy 96.499978 -234.157106)
			(xy 96.464485 -234.191198) (xy 96.423982 -234.219154) (xy 96.37952 -234.240252) (xy 96.332249 -234.253944)
			(xy 96.283394 -234.259876) (xy 96.234219 -234.257895) (xy 96.186 -234.248051) (xy 96.139984 -234.230599)
			(xy 96.097363 -234.205992) (xy 96.059242 -234.174867) (xy 96.026607 -234.13803) (xy 96.000304 -234.096434)
			(xy 95.981013 -234.051158) (xy 95.969236 -234.003374) (xy 95.965276 -233.95432) (xy 95.646748 -233.95432)
			(xy 95.646236 -233.979766) (xy 95.638072 -234.03) (xy 95.621956 -234.078274) (xy 95.598305 -234.123337)
			(xy 95.567732 -234.164023) (xy 95.531028 -234.199278) (xy 95.489144 -234.228188) (xy 95.443165 -234.250005)
			(xy 95.394281 -234.264165) (xy 95.34376 -234.270299) (xy 95.292908 -234.26825) (xy 95.243044 -234.25807)
			(xy 95.195458 -234.240023) (xy 95.151384 -234.214577) (xy 95.111962 -234.18239) (xy 95.078214 -234.144296)
			(xy 95.051013 -234.101282) (xy 95.031065 -234.054462) (xy 95.018886 -234.005048) (xy 95.014791 -233.95432)
			(xy 94.706694 -233.95432) (xy 94.706182 -233.979766) (xy 94.698018 -234.03) (xy 94.681902 -234.078274)
			(xy 94.658251 -234.123337) (xy 94.627678 -234.164023) (xy 94.590974 -234.199278) (xy 94.54909 -234.228188)
			(xy 94.503111 -234.250005) (xy 94.454227 -234.264165) (xy 94.403706 -234.270299) (xy 94.352854 -234.26825)
			(xy 94.30299 -234.25807) (xy 94.255404 -234.240023) (xy 94.21133 -234.214577) (xy 94.171908 -234.18239)
			(xy 94.13816 -234.144296) (xy 94.110959 -234.101282) (xy 94.091011 -234.054462) (xy 94.078832 -234.005048)
			(xy 94.074737 -233.95432) (xy 93.756226 -233.95432) (xy 93.755731 -233.978927) (xy 93.747836 -234.027504)
			(xy 93.732252 -234.074185) (xy 93.709381 -234.117762) (xy 93.679816 -234.157106) (xy 93.644323 -234.191198)
			(xy 93.60382 -234.219154) (xy 93.559358 -234.240252) (xy 93.512087 -234.253944) (xy 93.463232 -234.259876)
			(xy 93.414057 -234.257895) (xy 93.365838 -234.248051) (xy 93.319822 -234.230599) (xy 93.277201 -234.205992)
			(xy 93.23908 -234.174867) (xy 93.206445 -234.13803) (xy 93.180142 -234.096434) (xy 93.160851 -234.051158)
			(xy 93.149074 -234.003374) (xy 93.145114 -233.95432) (xy 92.82684 -233.95432) (xy 92.826328 -233.979766)
			(xy 92.818164 -234.03) (xy 92.802048 -234.078274) (xy 92.778397 -234.123337) (xy 92.747824 -234.164023)
			(xy 92.71112 -234.199278) (xy 92.669236 -234.228188) (xy 92.623257 -234.250005) (xy 92.574373 -234.264165)
			(xy 92.523852 -234.270299) (xy 92.473 -234.26825) (xy 92.423136 -234.25807) (xy 92.37555 -234.240023)
			(xy 92.331476 -234.214577) (xy 92.292054 -234.18239) (xy 92.258306 -234.144296) (xy 92.231105 -234.101282)
			(xy 92.211157 -234.054462) (xy 92.198978 -234.005048) (xy 92.194883 -233.95432) (xy 91.876372 -233.95432)
			(xy 91.875877 -233.978927) (xy 91.867982 -234.027504) (xy 91.852398 -234.074185) (xy 91.829527 -234.117762)
			(xy 91.799962 -234.157106) (xy 91.764469 -234.191198) (xy 91.723966 -234.219154) (xy 91.679504 -234.240252)
			(xy 91.632233 -234.253944) (xy 91.583378 -234.259876) (xy 91.534203 -234.257895) (xy 91.485984 -234.248051)
			(xy 91.439968 -234.230599) (xy 91.397347 -234.205992) (xy 91.359226 -234.174867) (xy 91.326591 -234.13803)
			(xy 91.300288 -234.096434) (xy 91.280997 -234.051158) (xy 91.26922 -234.003374) (xy 91.26526 -233.95432)
			(xy 90.946732 -233.95432) (xy 90.94622 -233.979766) (xy 90.938056 -234.03) (xy 90.92194 -234.078274)
			(xy 90.898289 -234.123337) (xy 90.867716 -234.164023) (xy 90.831012 -234.199278) (xy 90.789128 -234.228188)
			(xy 90.743149 -234.250005) (xy 90.694265 -234.264165) (xy 90.643744 -234.270299) (xy 90.592892 -234.26825)
			(xy 90.543028 -234.25807) (xy 90.495442 -234.240023) (xy 90.451368 -234.214577) (xy 90.411946 -234.18239)
			(xy 90.378198 -234.144296) (xy 90.350997 -234.101282) (xy 90.331049 -234.054462) (xy 90.31887 -234.005048)
			(xy 90.314775 -233.95432) (xy 89.996264 -233.95432) (xy 89.995769 -233.978927) (xy 89.987874 -234.027504)
			(xy 89.97229 -234.074185) (xy 89.949419 -234.117762) (xy 89.919854 -234.157106) (xy 89.884361 -234.191198)
			(xy 89.843858 -234.219154) (xy 89.799396 -234.240252) (xy 89.752125 -234.253944) (xy 89.70327 -234.259876)
			(xy 89.654095 -234.257895) (xy 89.605876 -234.248051) (xy 89.55986 -234.230599) (xy 89.517239 -234.205992)
			(xy 89.479118 -234.174867) (xy 89.446483 -234.13803) (xy 89.42018 -234.096434) (xy 89.400889 -234.051158)
			(xy 89.389112 -234.003374) (xy 89.385152 -233.95432) (xy 89.066878 -233.95432) (xy 89.066366 -233.979766)
			(xy 89.058202 -234.03) (xy 89.042086 -234.078274) (xy 89.018435 -234.123337) (xy 88.987862 -234.164023)
			(xy 88.951158 -234.199278) (xy 88.909274 -234.228188) (xy 88.863295 -234.250005) (xy 88.814411 -234.264165)
			(xy 88.76389 -234.270299) (xy 88.713038 -234.26825) (xy 88.663174 -234.25807) (xy 88.615588 -234.240023)
			(xy 88.571514 -234.214577) (xy 88.532092 -234.18239) (xy 88.498344 -234.144296) (xy 88.471143 -234.101282)
			(xy 88.451195 -234.054462) (xy 88.439016 -234.005048) (xy 88.434921 -233.95432) (xy 88.126824 -233.95432)
			(xy 88.126312 -233.979766) (xy 88.118148 -234.03) (xy 88.102032 -234.078274) (xy 88.078381 -234.123337)
			(xy 88.047808 -234.164023) (xy 88.011104 -234.199278) (xy 87.96922 -234.228188) (xy 87.923241 -234.250005)
			(xy 87.874357 -234.264165) (xy 87.823836 -234.270299) (xy 87.772984 -234.26825) (xy 87.72312 -234.25807)
			(xy 87.675534 -234.240023) (xy 87.63146 -234.214577) (xy 87.592038 -234.18239) (xy 87.55829 -234.144296)
			(xy 87.531089 -234.101282) (xy 87.511141 -234.054462) (xy 87.498962 -234.005048) (xy 87.494867 -233.95432)
			(xy 87.176356 -233.95432) (xy 87.175861 -233.978927) (xy 87.167966 -234.027504) (xy 87.152382 -234.074185)
			(xy 87.129511 -234.117762) (xy 87.099946 -234.157106) (xy 87.064453 -234.191198) (xy 87.02395 -234.219154)
			(xy 86.979488 -234.240252) (xy 86.932217 -234.253944) (xy 86.883362 -234.259876) (xy 86.834187 -234.257895)
			(xy 86.785968 -234.248051) (xy 86.739952 -234.230599) (xy 86.697331 -234.205992) (xy 86.65921 -234.174867)
			(xy 86.626575 -234.13803) (xy 86.600272 -234.096434) (xy 86.580981 -234.051158) (xy 86.569204 -234.003374)
			(xy 86.565244 -233.95432) (xy 86.246716 -233.95432) (xy 86.246204 -233.979766) (xy 86.23804 -234.03)
			(xy 86.221924 -234.078274) (xy 86.198273 -234.123337) (xy 86.1677 -234.164023) (xy 86.130996 -234.199278)
			(xy 86.089112 -234.228188) (xy 86.043133 -234.250005) (xy 85.994249 -234.264165) (xy 85.943728 -234.270299)
			(xy 85.892876 -234.26825) (xy 85.843012 -234.25807) (xy 85.795426 -234.240023) (xy 85.751352 -234.214577)
			(xy 85.71193 -234.18239) (xy 85.678182 -234.144296) (xy 85.650981 -234.101282) (xy 85.631033 -234.054462)
			(xy 85.618854 -234.005048) (xy 85.614759 -233.95432) (xy 85.296248 -233.95432) (xy 85.295753 -233.978927)
			(xy 85.287858 -234.027504) (xy 85.272274 -234.074185) (xy 85.249403 -234.117762) (xy 85.219838 -234.157106)
			(xy 85.184345 -234.191198) (xy 85.143842 -234.219154) (xy 85.09938 -234.240252) (xy 85.052109 -234.253944)
			(xy 85.003254 -234.259876) (xy 84.954079 -234.257895) (xy 84.90586 -234.248051) (xy 84.859844 -234.230599)
			(xy 84.817223 -234.205992) (xy 84.779102 -234.174867) (xy 84.746467 -234.13803) (xy 84.720164 -234.096434)
			(xy 84.700873 -234.051158) (xy 84.689096 -234.003374) (xy 84.685136 -233.95432) (xy 84.366862 -233.95432)
			(xy 84.36635 -233.979766) (xy 84.358186 -234.03) (xy 84.34207 -234.078274) (xy 84.318419 -234.123337)
			(xy 84.287846 -234.164023) (xy 84.251142 -234.199278) (xy 84.209258 -234.228188) (xy 84.163279 -234.250005)
			(xy 84.114395 -234.264165) (xy 84.063874 -234.270299) (xy 84.013022 -234.26825) (xy 83.963158 -234.25807)
			(xy 83.915572 -234.240023) (xy 83.871498 -234.214577) (xy 83.832076 -234.18239) (xy 83.798328 -234.144296)
			(xy 83.771127 -234.101282) (xy 83.751179 -234.054462) (xy 83.739 -234.005048) (xy 83.734905 -233.95432)
			(xy 83.416394 -233.95432) (xy 83.415899 -233.978927) (xy 83.408004 -234.027504) (xy 83.39242 -234.074185)
			(xy 83.369549 -234.117762) (xy 83.339984 -234.157106) (xy 83.304491 -234.191198) (xy 83.263988 -234.219154)
			(xy 83.219526 -234.240252) (xy 83.172255 -234.253944) (xy 83.1234 -234.259876) (xy 83.074225 -234.257895)
			(xy 83.026006 -234.248051) (xy 82.97999 -234.230599) (xy 82.937369 -234.205992) (xy 82.899248 -234.174867)
			(xy 82.866613 -234.13803) (xy 82.84031 -234.096434) (xy 82.821019 -234.051158) (xy 82.809242 -234.003374)
			(xy 82.805282 -233.95432) (xy 82.486754 -233.95432) (xy 82.486242 -233.979766) (xy 82.478078 -234.03)
			(xy 82.461962 -234.078274) (xy 82.438311 -234.123337) (xy 82.407738 -234.164023) (xy 82.371034 -234.199278)
			(xy 82.32915 -234.228188) (xy 82.283171 -234.250005) (xy 82.234287 -234.264165) (xy 82.183766 -234.270299)
			(xy 82.132914 -234.26825) (xy 82.08305 -234.25807) (xy 82.035464 -234.240023) (xy 81.99139 -234.214577)
			(xy 81.951968 -234.18239) (xy 81.91822 -234.144296) (xy 81.891019 -234.101282) (xy 81.871071 -234.054462)
			(xy 81.858892 -234.005048) (xy 81.854797 -233.95432) (xy 81.5467 -233.95432) (xy 81.546188 -233.979766)
			(xy 81.538024 -234.03) (xy 81.521908 -234.078274) (xy 81.498257 -234.123337) (xy 81.467684 -234.164023)
			(xy 81.43098 -234.199278) (xy 81.389096 -234.228188) (xy 81.343117 -234.250005) (xy 81.294233 -234.264165)
			(xy 81.243712 -234.270299) (xy 81.19286 -234.26825) (xy 81.142996 -234.25807) (xy 81.09541 -234.240023)
			(xy 81.051336 -234.214577) (xy 81.011914 -234.18239) (xy 80.978166 -234.144296) (xy 80.950965 -234.101282)
			(xy 80.931017 -234.054462) (xy 80.918838 -234.005048) (xy 80.914743 -233.95432) (xy 80.596486 -233.95432)
			(xy 80.595991 -233.978927) (xy 80.588096 -234.027504) (xy 80.572512 -234.074185) (xy 80.549641 -234.117762)
			(xy 80.520076 -234.157106) (xy 80.484583 -234.191198) (xy 80.44408 -234.219154) (xy 80.399618 -234.240252)
			(xy 80.352347 -234.253944) (xy 80.303492 -234.259876) (xy 80.254317 -234.257895) (xy 80.206098 -234.248051)
			(xy 80.160082 -234.230599) (xy 80.117461 -234.205992) (xy 80.07934 -234.174867) (xy 80.046705 -234.13803)
			(xy 80.020402 -234.096434) (xy 80.001111 -234.051158) (xy 79.989334 -234.003374) (xy 79.985374 -233.95432)
			(xy 78.716378 -233.95432) (xy 78.715883 -233.978927) (xy 78.707988 -234.027504) (xy 78.692404 -234.074185)
			(xy 78.669533 -234.117762) (xy 78.639968 -234.157106) (xy 78.604475 -234.191198) (xy 78.563972 -234.219154)
			(xy 78.51951 -234.240252) (xy 78.472239 -234.253944) (xy 78.423384 -234.259876) (xy 78.374209 -234.257895)
			(xy 78.32599 -234.248051) (xy 78.279974 -234.230599) (xy 78.237353 -234.205992) (xy 78.199232 -234.174867)
			(xy 78.166597 -234.13803) (xy 78.140294 -234.096434) (xy 78.121003 -234.051158) (xy 78.109226 -234.003374)
			(xy 78.105266 -233.95432) (xy 62.37732 -233.95432) (xy 62.37732 -235.030264) (xy 76.507098 -235.030264)
			(xy 76.511058 -234.98121) (xy 76.522835 -234.933426) (xy 76.542126 -234.88815) (xy 76.568429 -234.846554)
			(xy 76.601064 -234.809717) (xy 76.639185 -234.778592) (xy 76.681806 -234.753985) (xy 76.727822 -234.736533)
			(xy 76.776041 -234.726689) (xy 76.825216 -234.724708) (xy 76.874071 -234.73064) (xy 76.921342 -234.744332)
			(xy 76.963477 -234.764326) (xy 79.51522 -234.764326) (xy 79.51918 -234.715272) (xy 79.530957 -234.667488)
			(xy 79.550248 -234.622212) (xy 79.576551 -234.580616) (xy 79.609186 -234.543779) (xy 79.647307 -234.512654)
			(xy 79.689928 -234.488047) (xy 79.735944 -234.470595) (xy 79.784163 -234.460751) (xy 79.833338 -234.45877)
			(xy 79.882193 -234.464702) (xy 79.929464 -234.478394) (xy 79.973926 -234.499492) (xy 80.014429 -234.527448)
			(xy 80.049922 -234.56154) (xy 80.079487 -234.600884) (xy 80.102358 -234.644461) (xy 80.117942 -234.691142)
			(xy 80.125837 -234.739719) (xy 80.126332 -234.764326) (xy 80.444843 -234.764326) (xy 80.448938 -234.713598)
			(xy 80.461117 -234.664184) (xy 80.481065 -234.617364) (xy 80.508266 -234.57435) (xy 80.542014 -234.536256)
			(xy 80.581436 -234.504069) (xy 80.62551 -234.478623) (xy 80.673096 -234.460576) (xy 80.72296 -234.450396)
			(xy 80.773812 -234.448347) (xy 80.824333 -234.454481) (xy 80.873217 -234.468641) (xy 80.919196 -234.490458)
			(xy 80.96108 -234.519368) (xy 80.997784 -234.554623) (xy 81.028357 -234.595309) (xy 81.052008 -234.640372)
			(xy 81.068124 -234.688646) (xy 81.076288 -234.73888) (xy 81.0768 -234.764326) (xy 81.395328 -234.764326)
			(xy 81.399288 -234.715272) (xy 81.411065 -234.667488) (xy 81.430356 -234.622212) (xy 81.456659 -234.580616)
			(xy 81.489294 -234.543779) (xy 81.527415 -234.512654) (xy 81.570036 -234.488047) (xy 81.616052 -234.470595)
			(xy 81.664271 -234.460751) (xy 81.713446 -234.45877) (xy 81.762301 -234.464702) (xy 81.809572 -234.478394)
			(xy 81.854034 -234.499492) (xy 81.894537 -234.527448) (xy 81.93003 -234.56154) (xy 81.959595 -234.600884)
			(xy 81.982466 -234.644461) (xy 81.99805 -234.691142) (xy 82.005945 -234.739719) (xy 82.00644 -234.764326)
			(xy 82.324697 -234.764326) (xy 82.328792 -234.713598) (xy 82.340971 -234.664184) (xy 82.360919 -234.617364)
			(xy 82.38812 -234.57435) (xy 82.421868 -234.536256) (xy 82.46129 -234.504069) (xy 82.505364 -234.478623)
			(xy 82.55295 -234.460576) (xy 82.602814 -234.450396) (xy 82.653666 -234.448347) (xy 82.704187 -234.454481)
			(xy 82.753071 -234.468641) (xy 82.79905 -234.490458) (xy 82.840934 -234.519368) (xy 82.877638 -234.554623)
			(xy 82.908211 -234.595309) (xy 82.931862 -234.640372) (xy 82.947978 -234.688646) (xy 82.956142 -234.73888)
			(xy 82.956654 -234.764326) (xy 83.275182 -234.764326) (xy 83.279142 -234.715272) (xy 83.290919 -234.667488)
			(xy 83.31021 -234.622212) (xy 83.336513 -234.580616) (xy 83.369148 -234.543779) (xy 83.407269 -234.512654)
			(xy 83.44989 -234.488047) (xy 83.495906 -234.470595) (xy 83.544125 -234.460751) (xy 83.5933 -234.45877)
			(xy 83.642155 -234.464702) (xy 83.689426 -234.478394) (xy 83.733888 -234.499492) (xy 83.774391 -234.527448)
			(xy 83.809884 -234.56154) (xy 83.839449 -234.600884) (xy 83.86232 -234.644461) (xy 83.877904 -234.691142)
			(xy 83.885799 -234.739719) (xy 83.886294 -234.764326) (xy 84.204805 -234.764326) (xy 84.2089 -234.713598)
			(xy 84.221079 -234.664184) (xy 84.241027 -234.617364) (xy 84.268228 -234.57435) (xy 84.301976 -234.536256)
			(xy 84.341398 -234.504069) (xy 84.385472 -234.478623) (xy 84.433058 -234.460576) (xy 84.482922 -234.450396)
			(xy 84.533774 -234.448347) (xy 84.584295 -234.454481) (xy 84.633179 -234.468641) (xy 84.679158 -234.490458)
			(xy 84.721042 -234.519368) (xy 84.757746 -234.554623) (xy 84.788319 -234.595309) (xy 84.81197 -234.640372)
			(xy 84.828086 -234.688646) (xy 84.83625 -234.73888) (xy 84.836762 -234.764326) (xy 85.144859 -234.764326)
			(xy 85.148954 -234.713598) (xy 85.161133 -234.664184) (xy 85.181081 -234.617364) (xy 85.208282 -234.57435)
			(xy 85.24203 -234.536256) (xy 85.281452 -234.504069) (xy 85.325526 -234.478623) (xy 85.373112 -234.460576)
			(xy 85.422976 -234.450396) (xy 85.473828 -234.448347) (xy 85.524349 -234.454481) (xy 85.573233 -234.468641)
			(xy 85.619212 -234.490458) (xy 85.661096 -234.519368) (xy 85.6978 -234.554623) (xy 85.728373 -234.595309)
			(xy 85.752024 -234.640372) (xy 85.76814 -234.688646) (xy 85.776304 -234.73888) (xy 85.776816 -234.764326)
			(xy 86.095344 -234.764326) (xy 86.099304 -234.715272) (xy 86.111081 -234.667488) (xy 86.130372 -234.622212)
			(xy 86.156675 -234.580616) (xy 86.18931 -234.543779) (xy 86.227431 -234.512654) (xy 86.270052 -234.488047)
			(xy 86.316068 -234.470595) (xy 86.364287 -234.460751) (xy 86.413462 -234.45877) (xy 86.462317 -234.464702)
			(xy 86.509588 -234.478394) (xy 86.55405 -234.499492) (xy 86.594553 -234.527448) (xy 86.630046 -234.56154)
			(xy 86.659611 -234.600884) (xy 86.682482 -234.644461) (xy 86.698066 -234.691142) (xy 86.705961 -234.739719)
			(xy 86.706456 -234.764326) (xy 87.024713 -234.764326) (xy 87.028808 -234.713598) (xy 87.040987 -234.664184)
			(xy 87.060935 -234.617364) (xy 87.088136 -234.57435) (xy 87.121884 -234.536256) (xy 87.161306 -234.504069)
			(xy 87.20538 -234.478623) (xy 87.252966 -234.460576) (xy 87.30283 -234.450396) (xy 87.353682 -234.448347)
			(xy 87.404203 -234.454481) (xy 87.453087 -234.468641) (xy 87.499066 -234.490458) (xy 87.54095 -234.519368)
			(xy 87.577654 -234.554623) (xy 87.608227 -234.595309) (xy 87.631878 -234.640372) (xy 87.647994 -234.688646)
			(xy 87.656158 -234.73888) (xy 87.65667 -234.764326) (xy 87.975198 -234.764326) (xy 87.979158 -234.715272)
			(xy 87.990935 -234.667488) (xy 88.010226 -234.622212) (xy 88.036529 -234.580616) (xy 88.069164 -234.543779)
			(xy 88.107285 -234.512654) (xy 88.149906 -234.488047) (xy 88.195922 -234.470595) (xy 88.244141 -234.460751)
			(xy 88.293316 -234.45877) (xy 88.342171 -234.464702) (xy 88.389442 -234.478394) (xy 88.433904 -234.499492)
			(xy 88.474407 -234.527448) (xy 88.5099 -234.56154) (xy 88.539465 -234.600884) (xy 88.562336 -234.644461)
			(xy 88.57792 -234.691142) (xy 88.585815 -234.739719) (xy 88.58631 -234.764326) (xy 88.904821 -234.764326)
			(xy 88.908916 -234.713598) (xy 88.921095 -234.664184) (xy 88.941043 -234.617364) (xy 88.968244 -234.57435)
			(xy 89.001992 -234.536256) (xy 89.041414 -234.504069) (xy 89.085488 -234.478623) (xy 89.133074 -234.460576)
			(xy 89.182938 -234.450396) (xy 89.23379 -234.448347) (xy 89.284311 -234.454481) (xy 89.333195 -234.468641)
			(xy 89.379174 -234.490458) (xy 89.421058 -234.519368) (xy 89.457762 -234.554623) (xy 89.488335 -234.595309)
			(xy 89.511986 -234.640372) (xy 89.528102 -234.688646) (xy 89.536266 -234.73888) (xy 89.536778 -234.764326)
			(xy 89.855306 -234.764326) (xy 89.859266 -234.715272) (xy 89.871043 -234.667488) (xy 89.890334 -234.622212)
			(xy 89.916637 -234.580616) (xy 89.949272 -234.543779) (xy 89.987393 -234.512654) (xy 90.030014 -234.488047)
			(xy 90.07603 -234.470595) (xy 90.124249 -234.460751) (xy 90.173424 -234.45877) (xy 90.222279 -234.464702)
			(xy 90.26955 -234.478394) (xy 90.314012 -234.499492) (xy 90.354515 -234.527448) (xy 90.390008 -234.56154)
			(xy 90.419573 -234.600884) (xy 90.442444 -234.644461) (xy 90.458028 -234.691142) (xy 90.465923 -234.739719)
			(xy 90.466418 -234.764326) (xy 90.784675 -234.764326) (xy 90.78877 -234.713598) (xy 90.800949 -234.664184)
			(xy 90.820897 -234.617364) (xy 90.848098 -234.57435) (xy 90.881846 -234.536256) (xy 90.921268 -234.504069)
			(xy 90.965342 -234.478623) (xy 91.012928 -234.460576) (xy 91.062792 -234.450396) (xy 91.113644 -234.448347)
			(xy 91.164165 -234.454481) (xy 91.213049 -234.468641) (xy 91.259028 -234.490458) (xy 91.300912 -234.519368)
			(xy 91.337616 -234.554623) (xy 91.368189 -234.595309) (xy 91.39184 -234.640372) (xy 91.407956 -234.688646)
			(xy 91.41612 -234.73888) (xy 91.416632 -234.764326) (xy 91.724729 -234.764326) (xy 91.728824 -234.713598)
			(xy 91.741003 -234.664184) (xy 91.760951 -234.617364) (xy 91.788152 -234.57435) (xy 91.8219 -234.536256)
			(xy 91.861322 -234.504069) (xy 91.905396 -234.478623) (xy 91.952982 -234.460576) (xy 92.002846 -234.450396)
			(xy 92.053698 -234.448347) (xy 92.104219 -234.454481) (xy 92.153103 -234.468641) (xy 92.199082 -234.490458)
			(xy 92.240966 -234.519368) (xy 92.27767 -234.554623) (xy 92.308243 -234.595309) (xy 92.331894 -234.640372)
			(xy 92.34801 -234.688646) (xy 92.356174 -234.73888) (xy 92.356686 -234.764326) (xy 92.675214 -234.764326)
			(xy 92.679174 -234.715272) (xy 92.690951 -234.667488) (xy 92.710242 -234.622212) (xy 92.736545 -234.580616)
			(xy 92.76918 -234.543779) (xy 92.807301 -234.512654) (xy 92.849922 -234.488047) (xy 92.895938 -234.470595)
			(xy 92.944157 -234.460751) (xy 92.993332 -234.45877) (xy 93.042187 -234.464702) (xy 93.089458 -234.478394)
			(xy 93.13392 -234.499492) (xy 93.174423 -234.527448) (xy 93.209916 -234.56154) (xy 93.239481 -234.600884)
			(xy 93.262352 -234.644461) (xy 93.277936 -234.691142) (xy 93.285831 -234.739719) (xy 93.286326 -234.764326)
			(xy 93.604837 -234.764326) (xy 93.608932 -234.713598) (xy 93.621111 -234.664184) (xy 93.641059 -234.617364)
			(xy 93.66826 -234.57435) (xy 93.702008 -234.536256) (xy 93.74143 -234.504069) (xy 93.785504 -234.478623)
			(xy 93.83309 -234.460576) (xy 93.882954 -234.450396) (xy 93.933806 -234.448347) (xy 93.984327 -234.454481)
			(xy 94.033211 -234.468641) (xy 94.07919 -234.490458) (xy 94.121074 -234.519368) (xy 94.157778 -234.554623)
			(xy 94.188351 -234.595309) (xy 94.212002 -234.640372) (xy 94.228118 -234.688646) (xy 94.236282 -234.73888)
			(xy 94.236794 -234.764326) (xy 94.555322 -234.764326) (xy 94.559282 -234.715272) (xy 94.571059 -234.667488)
			(xy 94.59035 -234.622212) (xy 94.616653 -234.580616) (xy 94.649288 -234.543779) (xy 94.687409 -234.512654)
			(xy 94.73003 -234.488047) (xy 94.776046 -234.470595) (xy 94.824265 -234.460751) (xy 94.87344 -234.45877)
			(xy 94.922295 -234.464702) (xy 94.969566 -234.478394) (xy 95.014028 -234.499492) (xy 95.054531 -234.527448)
			(xy 95.090024 -234.56154) (xy 95.119589 -234.600884) (xy 95.14246 -234.644461) (xy 95.158044 -234.691142)
			(xy 95.165939 -234.739719) (xy 95.166434 -234.764326) (xy 95.484691 -234.764326) (xy 95.488786 -234.713598)
			(xy 95.500965 -234.664184) (xy 95.520913 -234.617364) (xy 95.548114 -234.57435) (xy 95.581862 -234.536256)
			(xy 95.621284 -234.504069) (xy 95.665358 -234.478623) (xy 95.712944 -234.460576) (xy 95.762808 -234.450396)
			(xy 95.81366 -234.448347) (xy 95.864181 -234.454481) (xy 95.913065 -234.468641) (xy 95.959044 -234.490458)
			(xy 96.000928 -234.519368) (xy 96.037632 -234.554623) (xy 96.068205 -234.595309) (xy 96.091856 -234.640372)
			(xy 96.107972 -234.688646) (xy 96.116136 -234.73888) (xy 96.116648 -234.764326) (xy 96.435176 -234.764326)
			(xy 96.439136 -234.715272) (xy 96.450913 -234.667488) (xy 96.470204 -234.622212) (xy 96.496507 -234.580616)
			(xy 96.529142 -234.543779) (xy 96.567263 -234.512654) (xy 96.609884 -234.488047) (xy 96.6559 -234.470595)
			(xy 96.704119 -234.460751) (xy 96.753294 -234.45877) (xy 96.802149 -234.464702) (xy 96.84942 -234.478394)
			(xy 96.893882 -234.499492) (xy 96.934385 -234.527448) (xy 96.969878 -234.56154) (xy 96.999443 -234.600884)
			(xy 97.022314 -234.644461) (xy 97.037898 -234.691142) (xy 97.045793 -234.739719) (xy 97.046288 -234.764326)
			(xy 97.364799 -234.764326) (xy 97.368894 -234.713598) (xy 97.381073 -234.664184) (xy 97.401021 -234.617364)
			(xy 97.428222 -234.57435) (xy 97.46197 -234.536256) (xy 97.501392 -234.504069) (xy 97.545466 -234.478623)
			(xy 97.593052 -234.460576) (xy 97.642916 -234.450396) (xy 97.693768 -234.448347) (xy 97.744289 -234.454481)
			(xy 97.793173 -234.468641) (xy 97.839152 -234.490458) (xy 97.881036 -234.519368) (xy 97.91774 -234.554623)
			(xy 97.948313 -234.595309) (xy 97.971964 -234.640372) (xy 97.98808 -234.688646) (xy 97.996244 -234.73888)
			(xy 97.996756 -234.764326) (xy 98.304853 -234.764326) (xy 98.308948 -234.713598) (xy 98.321127 -234.664184)
			(xy 98.341075 -234.617364) (xy 98.368276 -234.57435) (xy 98.402024 -234.536256) (xy 98.441446 -234.504069)
			(xy 98.48552 -234.478623) (xy 98.533106 -234.460576) (xy 98.58297 -234.450396) (xy 98.633822 -234.448347)
			(xy 98.684343 -234.454481) (xy 98.733227 -234.468641) (xy 98.779206 -234.490458) (xy 98.82109 -234.519368)
			(xy 98.857794 -234.554623) (xy 98.888367 -234.595309) (xy 98.912018 -234.640372) (xy 98.928134 -234.688646)
			(xy 98.936298 -234.73888) (xy 98.93681 -234.764326) (xy 99.255338 -234.764326) (xy 99.259298 -234.715272)
			(xy 99.271075 -234.667488) (xy 99.290366 -234.622212) (xy 99.316669 -234.580616) (xy 99.349304 -234.543779)
			(xy 99.387425 -234.512654) (xy 99.430046 -234.488047) (xy 99.476062 -234.470595) (xy 99.524281 -234.460751)
			(xy 99.573456 -234.45877) (xy 99.622311 -234.464702) (xy 99.669582 -234.478394) (xy 99.714044 -234.499492)
			(xy 99.754547 -234.527448) (xy 99.79004 -234.56154) (xy 99.819605 -234.600884) (xy 99.842476 -234.644461)
			(xy 99.85806 -234.691142) (xy 99.865955 -234.739719) (xy 99.86645 -234.764326) (xy 100.184707 -234.764326)
			(xy 100.188802 -234.713598) (xy 100.200981 -234.664184) (xy 100.220929 -234.617364) (xy 100.24813 -234.57435)
			(xy 100.281878 -234.536256) (xy 100.3213 -234.504069) (xy 100.365374 -234.478623) (xy 100.41296 -234.460576)
			(xy 100.462824 -234.450396) (xy 100.513676 -234.448347) (xy 100.564197 -234.454481) (xy 100.613081 -234.468641)
			(xy 100.65906 -234.490458) (xy 100.700944 -234.519368) (xy 100.737648 -234.554623) (xy 100.768221 -234.595309)
			(xy 100.791872 -234.640372) (xy 100.807988 -234.688646) (xy 100.816152 -234.73888) (xy 100.816664 -234.764326)
			(xy 101.124761 -234.764326) (xy 101.128856 -234.713598) (xy 101.141035 -234.664184) (xy 101.160983 -234.617364)
			(xy 101.188184 -234.57435) (xy 101.221932 -234.536256) (xy 101.261354 -234.504069) (xy 101.305428 -234.478623)
			(xy 101.353014 -234.460576) (xy 101.402878 -234.450396) (xy 101.45373 -234.448347) (xy 101.504251 -234.454481)
			(xy 101.553135 -234.468641) (xy 101.599114 -234.490458) (xy 101.640998 -234.519368) (xy 101.677702 -234.554623)
			(xy 101.708275 -234.595309) (xy 101.731926 -234.640372) (xy 101.748042 -234.688646) (xy 101.756206 -234.73888)
			(xy 101.756718 -234.764326) (xy 102.075246 -234.764326) (xy 102.079206 -234.715272) (xy 102.090983 -234.667488)
			(xy 102.110274 -234.622212) (xy 102.136577 -234.580616) (xy 102.169212 -234.543779) (xy 102.207333 -234.512654)
			(xy 102.249954 -234.488047) (xy 102.29597 -234.470595) (xy 102.344189 -234.460751) (xy 102.393364 -234.45877)
			(xy 102.442219 -234.464702) (xy 102.48949 -234.478394) (xy 102.533952 -234.499492) (xy 102.574455 -234.527448)
			(xy 102.609948 -234.56154) (xy 102.639513 -234.600884) (xy 102.662384 -234.644461) (xy 102.677968 -234.691142)
			(xy 102.685863 -234.739719) (xy 102.686358 -234.764326) (xy 103.004869 -234.764326) (xy 103.008964 -234.713598)
			(xy 103.021143 -234.664184) (xy 103.041091 -234.617364) (xy 103.068292 -234.57435) (xy 103.10204 -234.536256)
			(xy 103.141462 -234.504069) (xy 103.185536 -234.478623) (xy 103.233122 -234.460576) (xy 103.282986 -234.450396)
			(xy 103.333838 -234.448347) (xy 103.384359 -234.454481) (xy 103.433243 -234.468641) (xy 103.479222 -234.490458)
			(xy 103.521106 -234.519368) (xy 103.55781 -234.554623) (xy 103.588383 -234.595309) (xy 103.612034 -234.640372)
			(xy 103.62815 -234.688646) (xy 103.636314 -234.73888) (xy 103.636826 -234.764326) (xy 103.944923 -234.764326)
			(xy 103.949018 -234.713598) (xy 103.961197 -234.664184) (xy 103.981145 -234.617364) (xy 104.008346 -234.57435)
			(xy 104.042094 -234.536256) (xy 104.081516 -234.504069) (xy 104.12559 -234.478623) (xy 104.173176 -234.460576)
			(xy 104.22304 -234.450396) (xy 104.273892 -234.448347) (xy 104.324413 -234.454481) (xy 104.373297 -234.468641)
			(xy 104.419276 -234.490458) (xy 104.46116 -234.519368) (xy 104.497864 -234.554623) (xy 104.528437 -234.595309)
			(xy 104.552088 -234.640372) (xy 104.568204 -234.688646) (xy 104.576368 -234.73888) (xy 104.57688 -234.764326)
			(xy 104.895154 -234.764326) (xy 104.899114 -234.715272) (xy 104.910891 -234.667488) (xy 104.930182 -234.622212)
			(xy 104.956485 -234.580616) (xy 104.98912 -234.543779) (xy 105.027241 -234.512654) (xy 105.069862 -234.488047)
			(xy 105.115878 -234.470595) (xy 105.164097 -234.460751) (xy 105.213272 -234.45877) (xy 105.262127 -234.464702)
			(xy 105.309398 -234.478394) (xy 105.35386 -234.499492) (xy 105.394363 -234.527448) (xy 105.429856 -234.56154)
			(xy 105.459421 -234.600884) (xy 105.482292 -234.644461) (xy 105.497876 -234.691142) (xy 105.505771 -234.739719)
			(xy 105.506266 -234.764326) (xy 105.824777 -234.764326) (xy 105.828872 -234.713598) (xy 105.841051 -234.664184)
			(xy 105.860999 -234.617364) (xy 105.8882 -234.57435) (xy 105.921948 -234.536256) (xy 105.96137 -234.504069)
			(xy 106.005444 -234.478623) (xy 106.05303 -234.460576) (xy 106.102894 -234.450396) (xy 106.153746 -234.448347)
			(xy 106.204267 -234.454481) (xy 106.253151 -234.468641) (xy 106.29913 -234.490458) (xy 106.341014 -234.519368)
			(xy 106.377718 -234.554623) (xy 106.408291 -234.595309) (xy 106.431942 -234.640372) (xy 106.448058 -234.688646)
			(xy 106.456222 -234.73888) (xy 106.456734 -234.764326) (xy 106.764831 -234.764326) (xy 106.768926 -234.713598)
			(xy 106.781105 -234.664184) (xy 106.801053 -234.617364) (xy 106.828254 -234.57435) (xy 106.862002 -234.536256)
			(xy 106.901424 -234.504069) (xy 106.945498 -234.478623) (xy 106.993084 -234.460576) (xy 107.042948 -234.450396)
			(xy 107.0938 -234.448347) (xy 107.144321 -234.454481) (xy 107.193205 -234.468641) (xy 107.239184 -234.490458)
			(xy 107.281068 -234.519368) (xy 107.317772 -234.554623) (xy 107.348345 -234.595309) (xy 107.371996 -234.640372)
			(xy 107.388112 -234.688646) (xy 107.396276 -234.73888) (xy 107.396788 -234.764326) (xy 107.715316 -234.764326)
			(xy 107.719276 -234.715272) (xy 107.731053 -234.667488) (xy 107.750344 -234.622212) (xy 107.776647 -234.580616)
			(xy 107.809282 -234.543779) (xy 107.847403 -234.512654) (xy 107.890024 -234.488047) (xy 107.93604 -234.470595)
			(xy 107.984259 -234.460751) (xy 108.033434 -234.45877) (xy 108.082289 -234.464702) (xy 108.12956 -234.478394)
			(xy 108.174022 -234.499492) (xy 108.214525 -234.527448) (xy 108.250018 -234.56154) (xy 108.279583 -234.600884)
			(xy 108.302454 -234.644461) (xy 108.318038 -234.691142) (xy 108.325933 -234.739719) (xy 108.326428 -234.764326)
			(xy 108.325933 -234.788933) (xy 108.318038 -234.83751) (xy 108.302454 -234.884191) (xy 108.279583 -234.927768)
			(xy 108.250018 -234.967112) (xy 108.214525 -235.001204) (xy 108.174022 -235.02916) (xy 108.12956 -235.050258)
			(xy 108.082289 -235.06395) (xy 108.033434 -235.069882) (xy 107.984259 -235.067901) (xy 107.93604 -235.058057)
			(xy 107.890024 -235.040605) (xy 107.847403 -235.015998) (xy 107.809282 -234.984873) (xy 107.776647 -234.948036)
			(xy 107.750344 -234.90644) (xy 107.731053 -234.861164) (xy 107.719276 -234.81338) (xy 107.715316 -234.764326)
			(xy 107.396788 -234.764326) (xy 107.396276 -234.789772) (xy 107.388112 -234.840006) (xy 107.371996 -234.88828)
			(xy 107.348345 -234.933343) (xy 107.317772 -234.974029) (xy 107.281068 -235.009284) (xy 107.239184 -235.038194)
			(xy 107.193205 -235.060011) (xy 107.144321 -235.074171) (xy 107.0938 -235.080305) (xy 107.042948 -235.078256)
			(xy 106.993084 -235.068076) (xy 106.945498 -235.050029) (xy 106.901424 -235.024583) (xy 106.862002 -234.992396)
			(xy 106.828254 -234.954302) (xy 106.801053 -234.911288) (xy 106.781105 -234.864468) (xy 106.768926 -234.815054)
			(xy 106.764831 -234.764326) (xy 106.456734 -234.764326) (xy 106.456222 -234.789772) (xy 106.448058 -234.840006)
			(xy 106.431942 -234.88828) (xy 106.408291 -234.933343) (xy 106.377718 -234.974029) (xy 106.341014 -235.009284)
			(xy 106.29913 -235.038194) (xy 106.253151 -235.060011) (xy 106.204267 -235.074171) (xy 106.153746 -235.080305)
			(xy 106.102894 -235.078256) (xy 106.05303 -235.068076) (xy 106.005444 -235.050029) (xy 105.96137 -235.024583)
			(xy 105.921948 -234.992396) (xy 105.8882 -234.954302) (xy 105.860999 -234.911288) (xy 105.841051 -234.864468)
			(xy 105.828872 -234.815054) (xy 105.824777 -234.764326) (xy 105.506266 -234.764326) (xy 105.505771 -234.788933)
			(xy 105.497876 -234.83751) (xy 105.482292 -234.884191) (xy 105.459421 -234.927768) (xy 105.429856 -234.967112)
			(xy 105.394363 -235.001204) (xy 105.35386 -235.02916) (xy 105.309398 -235.050258) (xy 105.262127 -235.06395)
			(xy 105.213272 -235.069882) (xy 105.164097 -235.067901) (xy 105.115878 -235.058057) (xy 105.069862 -235.040605)
			(xy 105.027241 -235.015998) (xy 104.98912 -234.984873) (xy 104.956485 -234.948036) (xy 104.930182 -234.90644)
			(xy 104.910891 -234.861164) (xy 104.899114 -234.81338) (xy 104.895154 -234.764326) (xy 104.57688 -234.764326)
			(xy 104.576368 -234.789772) (xy 104.568204 -234.840006) (xy 104.552088 -234.88828) (xy 104.528437 -234.933343)
			(xy 104.497864 -234.974029) (xy 104.46116 -235.009284) (xy 104.419276 -235.038194) (xy 104.373297 -235.060011)
			(xy 104.324413 -235.074171) (xy 104.273892 -235.080305) (xy 104.22304 -235.078256) (xy 104.173176 -235.068076)
			(xy 104.12559 -235.050029) (xy 104.081516 -235.024583) (xy 104.042094 -234.992396) (xy 104.008346 -234.954302)
			(xy 103.981145 -234.911288) (xy 103.961197 -234.864468) (xy 103.949018 -234.815054) (xy 103.944923 -234.764326)
			(xy 103.636826 -234.764326) (xy 103.636314 -234.789772) (xy 103.62815 -234.840006) (xy 103.612034 -234.88828)
			(xy 103.588383 -234.933343) (xy 103.55781 -234.974029) (xy 103.521106 -235.009284) (xy 103.479222 -235.038194)
			(xy 103.433243 -235.060011) (xy 103.384359 -235.074171) (xy 103.333838 -235.080305) (xy 103.282986 -235.078256)
			(xy 103.233122 -235.068076) (xy 103.185536 -235.050029) (xy 103.141462 -235.024583) (xy 103.10204 -234.992396)
			(xy 103.068292 -234.954302) (xy 103.041091 -234.911288) (xy 103.021143 -234.864468) (xy 103.008964 -234.815054)
			(xy 103.004869 -234.764326) (xy 102.686358 -234.764326) (xy 102.685863 -234.788933) (xy 102.677968 -234.83751)
			(xy 102.662384 -234.884191) (xy 102.639513 -234.927768) (xy 102.609948 -234.967112) (xy 102.574455 -235.001204)
			(xy 102.533952 -235.02916) (xy 102.48949 -235.050258) (xy 102.442219 -235.06395) (xy 102.393364 -235.069882)
			(xy 102.344189 -235.067901) (xy 102.29597 -235.058057) (xy 102.249954 -235.040605) (xy 102.207333 -235.015998)
			(xy 102.169212 -234.984873) (xy 102.136577 -234.948036) (xy 102.110274 -234.90644) (xy 102.090983 -234.861164)
			(xy 102.079206 -234.81338) (xy 102.075246 -234.764326) (xy 101.756718 -234.764326) (xy 101.756206 -234.789772)
			(xy 101.748042 -234.840006) (xy 101.731926 -234.88828) (xy 101.708275 -234.933343) (xy 101.677702 -234.974029)
			(xy 101.640998 -235.009284) (xy 101.599114 -235.038194) (xy 101.553135 -235.060011) (xy 101.504251 -235.074171)
			(xy 101.45373 -235.080305) (xy 101.402878 -235.078256) (xy 101.353014 -235.068076) (xy 101.305428 -235.050029)
			(xy 101.261354 -235.024583) (xy 101.221932 -234.992396) (xy 101.188184 -234.954302) (xy 101.160983 -234.911288)
			(xy 101.141035 -234.864468) (xy 101.128856 -234.815054) (xy 101.124761 -234.764326) (xy 100.816664 -234.764326)
			(xy 100.816152 -234.789772) (xy 100.807988 -234.840006) (xy 100.791872 -234.88828) (xy 100.768221 -234.933343)
			(xy 100.737648 -234.974029) (xy 100.700944 -235.009284) (xy 100.65906 -235.038194) (xy 100.613081 -235.060011)
			(xy 100.564197 -235.074171) (xy 100.513676 -235.080305) (xy 100.462824 -235.078256) (xy 100.41296 -235.068076)
			(xy 100.365374 -235.050029) (xy 100.3213 -235.024583) (xy 100.281878 -234.992396) (xy 100.24813 -234.954302)
			(xy 100.220929 -234.911288) (xy 100.200981 -234.864468) (xy 100.188802 -234.815054) (xy 100.184707 -234.764326)
			(xy 99.86645 -234.764326) (xy 99.865955 -234.788933) (xy 99.85806 -234.83751) (xy 99.842476 -234.884191)
			(xy 99.819605 -234.927768) (xy 99.79004 -234.967112) (xy 99.754547 -235.001204) (xy 99.714044 -235.02916)
			(xy 99.669582 -235.050258) (xy 99.622311 -235.06395) (xy 99.573456 -235.069882) (xy 99.524281 -235.067901)
			(xy 99.476062 -235.058057) (xy 99.430046 -235.040605) (xy 99.387425 -235.015998) (xy 99.349304 -234.984873)
			(xy 99.316669 -234.948036) (xy 99.290366 -234.90644) (xy 99.271075 -234.861164) (xy 99.259298 -234.81338)
			(xy 99.255338 -234.764326) (xy 98.93681 -234.764326) (xy 98.936298 -234.789772) (xy 98.928134 -234.840006)
			(xy 98.912018 -234.88828) (xy 98.888367 -234.933343) (xy 98.857794 -234.974029) (xy 98.82109 -235.009284)
			(xy 98.779206 -235.038194) (xy 98.733227 -235.060011) (xy 98.684343 -235.074171) (xy 98.633822 -235.080305)
			(xy 98.58297 -235.078256) (xy 98.533106 -235.068076) (xy 98.48552 -235.050029) (xy 98.441446 -235.024583)
			(xy 98.402024 -234.992396) (xy 98.368276 -234.954302) (xy 98.341075 -234.911288) (xy 98.321127 -234.864468)
			(xy 98.308948 -234.815054) (xy 98.304853 -234.764326) (xy 97.996756 -234.764326) (xy 97.996244 -234.789772)
			(xy 97.98808 -234.840006) (xy 97.971964 -234.88828) (xy 97.948313 -234.933343) (xy 97.91774 -234.974029)
			(xy 97.881036 -235.009284) (xy 97.839152 -235.038194) (xy 97.793173 -235.060011) (xy 97.744289 -235.074171)
			(xy 97.693768 -235.080305) (xy 97.642916 -235.078256) (xy 97.593052 -235.068076) (xy 97.545466 -235.050029)
			(xy 97.501392 -235.024583) (xy 97.46197 -234.992396) (xy 97.428222 -234.954302) (xy 97.401021 -234.911288)
			(xy 97.381073 -234.864468) (xy 97.368894 -234.815054) (xy 97.364799 -234.764326) (xy 97.046288 -234.764326)
			(xy 97.045793 -234.788933) (xy 97.037898 -234.83751) (xy 97.022314 -234.884191) (xy 96.999443 -234.927768)
			(xy 96.969878 -234.967112) (xy 96.934385 -235.001204) (xy 96.893882 -235.02916) (xy 96.84942 -235.050258)
			(xy 96.802149 -235.06395) (xy 96.753294 -235.069882) (xy 96.704119 -235.067901) (xy 96.6559 -235.058057)
			(xy 96.609884 -235.040605) (xy 96.567263 -235.015998) (xy 96.529142 -234.984873) (xy 96.496507 -234.948036)
			(xy 96.470204 -234.90644) (xy 96.450913 -234.861164) (xy 96.439136 -234.81338) (xy 96.435176 -234.764326)
			(xy 96.116648 -234.764326) (xy 96.116136 -234.789772) (xy 96.107972 -234.840006) (xy 96.091856 -234.88828)
			(xy 96.068205 -234.933343) (xy 96.037632 -234.974029) (xy 96.000928 -235.009284) (xy 95.959044 -235.038194)
			(xy 95.913065 -235.060011) (xy 95.864181 -235.074171) (xy 95.81366 -235.080305) (xy 95.762808 -235.078256)
			(xy 95.712944 -235.068076) (xy 95.665358 -235.050029) (xy 95.621284 -235.024583) (xy 95.581862 -234.992396)
			(xy 95.548114 -234.954302) (xy 95.520913 -234.911288) (xy 95.500965 -234.864468) (xy 95.488786 -234.815054)
			(xy 95.484691 -234.764326) (xy 95.166434 -234.764326) (xy 95.165939 -234.788933) (xy 95.158044 -234.83751)
			(xy 95.14246 -234.884191) (xy 95.119589 -234.927768) (xy 95.090024 -234.967112) (xy 95.054531 -235.001204)
			(xy 95.014028 -235.02916) (xy 94.969566 -235.050258) (xy 94.922295 -235.06395) (xy 94.87344 -235.069882)
			(xy 94.824265 -235.067901) (xy 94.776046 -235.058057) (xy 94.73003 -235.040605) (xy 94.687409 -235.015998)
			(xy 94.649288 -234.984873) (xy 94.616653 -234.948036) (xy 94.59035 -234.90644) (xy 94.571059 -234.861164)
			(xy 94.559282 -234.81338) (xy 94.555322 -234.764326) (xy 94.236794 -234.764326) (xy 94.236282 -234.789772)
			(xy 94.228118 -234.840006) (xy 94.212002 -234.88828) (xy 94.188351 -234.933343) (xy 94.157778 -234.974029)
			(xy 94.121074 -235.009284) (xy 94.07919 -235.038194) (xy 94.033211 -235.060011) (xy 93.984327 -235.074171)
			(xy 93.933806 -235.080305) (xy 93.882954 -235.078256) (xy 93.83309 -235.068076) (xy 93.785504 -235.050029)
			(xy 93.74143 -235.024583) (xy 93.702008 -234.992396) (xy 93.66826 -234.954302) (xy 93.641059 -234.911288)
			(xy 93.621111 -234.864468) (xy 93.608932 -234.815054) (xy 93.604837 -234.764326) (xy 93.286326 -234.764326)
			(xy 93.285831 -234.788933) (xy 93.277936 -234.83751) (xy 93.262352 -234.884191) (xy 93.239481 -234.927768)
			(xy 93.209916 -234.967112) (xy 93.174423 -235.001204) (xy 93.13392 -235.02916) (xy 93.089458 -235.050258)
			(xy 93.042187 -235.06395) (xy 92.993332 -235.069882) (xy 92.944157 -235.067901) (xy 92.895938 -235.058057)
			(xy 92.849922 -235.040605) (xy 92.807301 -235.015998) (xy 92.76918 -234.984873) (xy 92.736545 -234.948036)
			(xy 92.710242 -234.90644) (xy 92.690951 -234.861164) (xy 92.679174 -234.81338) (xy 92.675214 -234.764326)
			(xy 92.356686 -234.764326) (xy 92.356174 -234.789772) (xy 92.34801 -234.840006) (xy 92.331894 -234.88828)
			(xy 92.308243 -234.933343) (xy 92.27767 -234.974029) (xy 92.240966 -235.009284) (xy 92.199082 -235.038194)
			(xy 92.153103 -235.060011) (xy 92.104219 -235.074171) (xy 92.053698 -235.080305) (xy 92.002846 -235.078256)
			(xy 91.952982 -235.068076) (xy 91.905396 -235.050029) (xy 91.861322 -235.024583) (xy 91.8219 -234.992396)
			(xy 91.788152 -234.954302) (xy 91.760951 -234.911288) (xy 91.741003 -234.864468) (xy 91.728824 -234.815054)
			(xy 91.724729 -234.764326) (xy 91.416632 -234.764326) (xy 91.41612 -234.789772) (xy 91.407956 -234.840006)
			(xy 91.39184 -234.88828) (xy 91.368189 -234.933343) (xy 91.337616 -234.974029) (xy 91.300912 -235.009284)
			(xy 91.259028 -235.038194) (xy 91.213049 -235.060011) (xy 91.164165 -235.074171) (xy 91.113644 -235.080305)
			(xy 91.062792 -235.078256) (xy 91.012928 -235.068076) (xy 90.965342 -235.050029) (xy 90.921268 -235.024583)
			(xy 90.881846 -234.992396) (xy 90.848098 -234.954302) (xy 90.820897 -234.911288) (xy 90.800949 -234.864468)
			(xy 90.78877 -234.815054) (xy 90.784675 -234.764326) (xy 90.466418 -234.764326) (xy 90.465923 -234.788933)
			(xy 90.458028 -234.83751) (xy 90.442444 -234.884191) (xy 90.419573 -234.927768) (xy 90.390008 -234.967112)
			(xy 90.354515 -235.001204) (xy 90.314012 -235.02916) (xy 90.26955 -235.050258) (xy 90.222279 -235.06395)
			(xy 90.173424 -235.069882) (xy 90.124249 -235.067901) (xy 90.07603 -235.058057) (xy 90.030014 -235.040605)
			(xy 89.987393 -235.015998) (xy 89.949272 -234.984873) (xy 89.916637 -234.948036) (xy 89.890334 -234.90644)
			(xy 89.871043 -234.861164) (xy 89.859266 -234.81338) (xy 89.855306 -234.764326) (xy 89.536778 -234.764326)
			(xy 89.536266 -234.789772) (xy 89.528102 -234.840006) (xy 89.511986 -234.88828) (xy 89.488335 -234.933343)
			(xy 89.457762 -234.974029) (xy 89.421058 -235.009284) (xy 89.379174 -235.038194) (xy 89.333195 -235.060011)
			(xy 89.284311 -235.074171) (xy 89.23379 -235.080305) (xy 89.182938 -235.078256) (xy 89.133074 -235.068076)
			(xy 89.085488 -235.050029) (xy 89.041414 -235.024583) (xy 89.001992 -234.992396) (xy 88.968244 -234.954302)
			(xy 88.941043 -234.911288) (xy 88.921095 -234.864468) (xy 88.908916 -234.815054) (xy 88.904821 -234.764326)
			(xy 88.58631 -234.764326) (xy 88.585815 -234.788933) (xy 88.57792 -234.83751) (xy 88.562336 -234.884191)
			(xy 88.539465 -234.927768) (xy 88.5099 -234.967112) (xy 88.474407 -235.001204) (xy 88.433904 -235.02916)
			(xy 88.389442 -235.050258) (xy 88.342171 -235.06395) (xy 88.293316 -235.069882) (xy 88.244141 -235.067901)
			(xy 88.195922 -235.058057) (xy 88.149906 -235.040605) (xy 88.107285 -235.015998) (xy 88.069164 -234.984873)
			(xy 88.036529 -234.948036) (xy 88.010226 -234.90644) (xy 87.990935 -234.861164) (xy 87.979158 -234.81338)
			(xy 87.975198 -234.764326) (xy 87.65667 -234.764326) (xy 87.656158 -234.789772) (xy 87.647994 -234.840006)
			(xy 87.631878 -234.88828) (xy 87.608227 -234.933343) (xy 87.577654 -234.974029) (xy 87.54095 -235.009284)
			(xy 87.499066 -235.038194) (xy 87.453087 -235.060011) (xy 87.404203 -235.074171) (xy 87.353682 -235.080305)
			(xy 87.30283 -235.078256) (xy 87.252966 -235.068076) (xy 87.20538 -235.050029) (xy 87.161306 -235.024583)
			(xy 87.121884 -234.992396) (xy 87.088136 -234.954302) (xy 87.060935 -234.911288) (xy 87.040987 -234.864468)
			(xy 87.028808 -234.815054) (xy 87.024713 -234.764326) (xy 86.706456 -234.764326) (xy 86.705961 -234.788933)
			(xy 86.698066 -234.83751) (xy 86.682482 -234.884191) (xy 86.659611 -234.927768) (xy 86.630046 -234.967112)
			(xy 86.594553 -235.001204) (xy 86.55405 -235.02916) (xy 86.509588 -235.050258) (xy 86.462317 -235.06395)
			(xy 86.413462 -235.069882) (xy 86.364287 -235.067901) (xy 86.316068 -235.058057) (xy 86.270052 -235.040605)
			(xy 86.227431 -235.015998) (xy 86.18931 -234.984873) (xy 86.156675 -234.948036) (xy 86.130372 -234.90644)
			(xy 86.111081 -234.861164) (xy 86.099304 -234.81338) (xy 86.095344 -234.764326) (xy 85.776816 -234.764326)
			(xy 85.776304 -234.789772) (xy 85.76814 -234.840006) (xy 85.752024 -234.88828) (xy 85.728373 -234.933343)
			(xy 85.6978 -234.974029) (xy 85.661096 -235.009284) (xy 85.619212 -235.038194) (xy 85.573233 -235.060011)
			(xy 85.524349 -235.074171) (xy 85.473828 -235.080305) (xy 85.422976 -235.078256) (xy 85.373112 -235.068076)
			(xy 85.325526 -235.050029) (xy 85.281452 -235.024583) (xy 85.24203 -234.992396) (xy 85.208282 -234.954302)
			(xy 85.181081 -234.911288) (xy 85.161133 -234.864468) (xy 85.148954 -234.815054) (xy 85.144859 -234.764326)
			(xy 84.836762 -234.764326) (xy 84.83625 -234.789772) (xy 84.828086 -234.840006) (xy 84.81197 -234.88828)
			(xy 84.788319 -234.933343) (xy 84.757746 -234.974029) (xy 84.721042 -235.009284) (xy 84.679158 -235.038194)
			(xy 84.633179 -235.060011) (xy 84.584295 -235.074171) (xy 84.533774 -235.080305) (xy 84.482922 -235.078256)
			(xy 84.433058 -235.068076) (xy 84.385472 -235.050029) (xy 84.341398 -235.024583) (xy 84.301976 -234.992396)
			(xy 84.268228 -234.954302) (xy 84.241027 -234.911288) (xy 84.221079 -234.864468) (xy 84.2089 -234.815054)
			(xy 84.204805 -234.764326) (xy 83.886294 -234.764326) (xy 83.885799 -234.788933) (xy 83.877904 -234.83751)
			(xy 83.86232 -234.884191) (xy 83.839449 -234.927768) (xy 83.809884 -234.967112) (xy 83.774391 -235.001204)
			(xy 83.733888 -235.02916) (xy 83.689426 -235.050258) (xy 83.642155 -235.06395) (xy 83.5933 -235.069882)
			(xy 83.544125 -235.067901) (xy 83.495906 -235.058057) (xy 83.44989 -235.040605) (xy 83.407269 -235.015998)
			(xy 83.369148 -234.984873) (xy 83.336513 -234.948036) (xy 83.31021 -234.90644) (xy 83.290919 -234.861164)
			(xy 83.279142 -234.81338) (xy 83.275182 -234.764326) (xy 82.956654 -234.764326) (xy 82.956142 -234.789772)
			(xy 82.947978 -234.840006) (xy 82.931862 -234.88828) (xy 82.908211 -234.933343) (xy 82.877638 -234.974029)
			(xy 82.840934 -235.009284) (xy 82.79905 -235.038194) (xy 82.753071 -235.060011) (xy 82.704187 -235.074171)
			(xy 82.653666 -235.080305) (xy 82.602814 -235.078256) (xy 82.55295 -235.068076) (xy 82.505364 -235.050029)
			(xy 82.46129 -235.024583) (xy 82.421868 -234.992396) (xy 82.38812 -234.954302) (xy 82.360919 -234.911288)
			(xy 82.340971 -234.864468) (xy 82.328792 -234.815054) (xy 82.324697 -234.764326) (xy 82.00644 -234.764326)
			(xy 82.005945 -234.788933) (xy 81.99805 -234.83751) (xy 81.982466 -234.884191) (xy 81.959595 -234.927768)
			(xy 81.93003 -234.967112) (xy 81.894537 -235.001204) (xy 81.854034 -235.02916) (xy 81.809572 -235.050258)
			(xy 81.762301 -235.06395) (xy 81.713446 -235.069882) (xy 81.664271 -235.067901) (xy 81.616052 -235.058057)
			(xy 81.570036 -235.040605) (xy 81.527415 -235.015998) (xy 81.489294 -234.984873) (xy 81.456659 -234.948036)
			(xy 81.430356 -234.90644) (xy 81.411065 -234.861164) (xy 81.399288 -234.81338) (xy 81.395328 -234.764326)
			(xy 81.0768 -234.764326) (xy 81.076288 -234.789772) (xy 81.068124 -234.840006) (xy 81.052008 -234.88828)
			(xy 81.028357 -234.933343) (xy 80.997784 -234.974029) (xy 80.96108 -235.009284) (xy 80.919196 -235.038194)
			(xy 80.873217 -235.060011) (xy 80.824333 -235.074171) (xy 80.773812 -235.080305) (xy 80.72296 -235.078256)
			(xy 80.673096 -235.068076) (xy 80.62551 -235.050029) (xy 80.581436 -235.024583) (xy 80.542014 -234.992396)
			(xy 80.508266 -234.954302) (xy 80.481065 -234.911288) (xy 80.461117 -234.864468) (xy 80.448938 -234.815054)
			(xy 80.444843 -234.764326) (xy 80.126332 -234.764326) (xy 80.125837 -234.788933) (xy 80.117942 -234.83751)
			(xy 80.102358 -234.884191) (xy 80.079487 -234.927768) (xy 80.049922 -234.967112) (xy 80.014429 -235.001204)
			(xy 79.973926 -235.02916) (xy 79.929464 -235.050258) (xy 79.882193 -235.06395) (xy 79.833338 -235.069882)
			(xy 79.784163 -235.067901) (xy 79.735944 -235.058057) (xy 79.689928 -235.040605) (xy 79.647307 -235.015998)
			(xy 79.609186 -234.984873) (xy 79.576551 -234.948036) (xy 79.550248 -234.90644) (xy 79.530957 -234.861164)
			(xy 79.51918 -234.81338) (xy 79.51522 -234.764326) (xy 76.963477 -234.764326) (xy 76.965804 -234.76543)
			(xy 77.006307 -234.793386) (xy 77.0418 -234.827478) (xy 77.071365 -234.866822) (xy 77.094236 -234.910399)
			(xy 77.10982 -234.95708) (xy 77.117715 -235.005657) (xy 77.11821 -235.030264) (xy 77.117715 -235.054871)
			(xy 77.10982 -235.103448) (xy 77.094236 -235.150129) (xy 77.071365 -235.193706) (xy 77.0418 -235.23305)
			(xy 77.006307 -235.267142) (xy 76.965804 -235.295098) (xy 76.921342 -235.316196) (xy 76.874071 -235.329888)
			(xy 76.825216 -235.33582) (xy 76.776041 -235.333839) (xy 76.727822 -235.323995) (xy 76.681806 -235.306543)
			(xy 76.639185 -235.281936) (xy 76.601064 -235.250811) (xy 76.568429 -235.213974) (xy 76.542126 -235.172378)
			(xy 76.522835 -235.127102) (xy 76.511058 -235.079318) (xy 76.507098 -235.030264) (xy 62.37732 -235.030264)
			(xy 62.37732 -235.574332) (xy 78.105266 -235.574332) (xy 78.109226 -235.525278) (xy 78.121003 -235.477494)
			(xy 78.140294 -235.432218) (xy 78.166597 -235.390622) (xy 78.199232 -235.353785) (xy 78.237353 -235.32266)
			(xy 78.279974 -235.298053) (xy 78.32599 -235.280601) (xy 78.374209 -235.270757) (xy 78.423384 -235.268776)
			(xy 78.472239 -235.274708) (xy 78.51951 -235.2884) (xy 78.563972 -235.309498) (xy 78.604475 -235.337454)
			(xy 78.639968 -235.371546) (xy 78.669533 -235.41089) (xy 78.692404 -235.454467) (xy 78.707988 -235.501148)
			(xy 78.715883 -235.549725) (xy 78.716378 -235.574332) (xy 79.985374 -235.574332) (xy 79.989334 -235.525278)
			(xy 80.001111 -235.477494) (xy 80.020402 -235.432218) (xy 80.046705 -235.390622) (xy 80.07934 -235.353785)
			(xy 80.117461 -235.32266) (xy 80.160082 -235.298053) (xy 80.206098 -235.280601) (xy 80.254317 -235.270757)
			(xy 80.303492 -235.268776) (xy 80.352347 -235.274708) (xy 80.399618 -235.2884) (xy 80.44408 -235.309498)
			(xy 80.484583 -235.337454) (xy 80.520076 -235.371546) (xy 80.549641 -235.41089) (xy 80.572512 -235.454467)
			(xy 80.588096 -235.501148) (xy 80.595991 -235.549725) (xy 80.596486 -235.574332) (xy 80.914743 -235.574332)
			(xy 80.918838 -235.523604) (xy 80.931017 -235.47419) (xy 80.950965 -235.42737) (xy 80.978166 -235.384356)
			(xy 81.011914 -235.346262) (xy 81.051336 -235.314075) (xy 81.09541 -235.288629) (xy 81.142996 -235.270582)
			(xy 81.19286 -235.260402) (xy 81.243712 -235.258353) (xy 81.294233 -235.264487) (xy 81.343117 -235.278647)
			(xy 81.389096 -235.300464) (xy 81.43098 -235.329374) (xy 81.467684 -235.364629) (xy 81.498257 -235.405315)
			(xy 81.521908 -235.450378) (xy 81.538024 -235.498652) (xy 81.546188 -235.548886) (xy 81.5467 -235.574332)
			(xy 81.854797 -235.574332) (xy 81.858892 -235.523604) (xy 81.871071 -235.47419) (xy 81.891019 -235.42737)
			(xy 81.91822 -235.384356) (xy 81.951968 -235.346262) (xy 81.99139 -235.314075) (xy 82.035464 -235.288629)
			(xy 82.08305 -235.270582) (xy 82.132914 -235.260402) (xy 82.183766 -235.258353) (xy 82.234287 -235.264487)
			(xy 82.283171 -235.278647) (xy 82.32915 -235.300464) (xy 82.371034 -235.329374) (xy 82.407738 -235.364629)
			(xy 82.438311 -235.405315) (xy 82.461962 -235.450378) (xy 82.478078 -235.498652) (xy 82.486242 -235.548886)
			(xy 82.486754 -235.574332) (xy 82.805282 -235.574332) (xy 82.809242 -235.525278) (xy 82.821019 -235.477494)
			(xy 82.84031 -235.432218) (xy 82.866613 -235.390622) (xy 82.899248 -235.353785) (xy 82.937369 -235.32266)
			(xy 82.97999 -235.298053) (xy 83.026006 -235.280601) (xy 83.074225 -235.270757) (xy 83.1234 -235.268776)
			(xy 83.172255 -235.274708) (xy 83.219526 -235.2884) (xy 83.263988 -235.309498) (xy 83.304491 -235.337454)
			(xy 83.339984 -235.371546) (xy 83.369549 -235.41089) (xy 83.39242 -235.454467) (xy 83.408004 -235.501148)
			(xy 83.415899 -235.549725) (xy 83.416394 -235.574332) (xy 83.734905 -235.574332) (xy 83.739 -235.523604)
			(xy 83.751179 -235.47419) (xy 83.771127 -235.42737) (xy 83.798328 -235.384356) (xy 83.832076 -235.346262)
			(xy 83.871498 -235.314075) (xy 83.915572 -235.288629) (xy 83.963158 -235.270582) (xy 84.013022 -235.260402)
			(xy 84.063874 -235.258353) (xy 84.114395 -235.264487) (xy 84.163279 -235.278647) (xy 84.209258 -235.300464)
			(xy 84.251142 -235.329374) (xy 84.287846 -235.364629) (xy 84.318419 -235.405315) (xy 84.34207 -235.450378)
			(xy 84.358186 -235.498652) (xy 84.36635 -235.548886) (xy 84.366862 -235.574332) (xy 84.685136 -235.574332)
			(xy 84.689096 -235.525278) (xy 84.700873 -235.477494) (xy 84.720164 -235.432218) (xy 84.746467 -235.390622)
			(xy 84.779102 -235.353785) (xy 84.817223 -235.32266) (xy 84.859844 -235.298053) (xy 84.90586 -235.280601)
			(xy 84.954079 -235.270757) (xy 85.003254 -235.268776) (xy 85.052109 -235.274708) (xy 85.09938 -235.2884)
			(xy 85.143842 -235.309498) (xy 85.184345 -235.337454) (xy 85.219838 -235.371546) (xy 85.249403 -235.41089)
			(xy 85.272274 -235.454467) (xy 85.287858 -235.501148) (xy 85.295753 -235.549725) (xy 85.296248 -235.574332)
			(xy 85.614759 -235.574332) (xy 85.618854 -235.523604) (xy 85.631033 -235.47419) (xy 85.650981 -235.42737)
			(xy 85.678182 -235.384356) (xy 85.71193 -235.346262) (xy 85.751352 -235.314075) (xy 85.795426 -235.288629)
			(xy 85.843012 -235.270582) (xy 85.892876 -235.260402) (xy 85.943728 -235.258353) (xy 85.994249 -235.264487)
			(xy 86.043133 -235.278647) (xy 86.089112 -235.300464) (xy 86.130996 -235.329374) (xy 86.1677 -235.364629)
			(xy 86.198273 -235.405315) (xy 86.221924 -235.450378) (xy 86.23804 -235.498652) (xy 86.246204 -235.548886)
			(xy 86.246716 -235.574332) (xy 86.565244 -235.574332) (xy 86.569204 -235.525278) (xy 86.580981 -235.477494)
			(xy 86.600272 -235.432218) (xy 86.626575 -235.390622) (xy 86.65921 -235.353785) (xy 86.697331 -235.32266)
			(xy 86.739952 -235.298053) (xy 86.785968 -235.280601) (xy 86.834187 -235.270757) (xy 86.883362 -235.268776)
			(xy 86.932217 -235.274708) (xy 86.979488 -235.2884) (xy 87.02395 -235.309498) (xy 87.064453 -235.337454)
			(xy 87.099946 -235.371546) (xy 87.129511 -235.41089) (xy 87.152382 -235.454467) (xy 87.167966 -235.501148)
			(xy 87.175861 -235.549725) (xy 87.176356 -235.574332) (xy 87.494867 -235.574332) (xy 87.498962 -235.523604)
			(xy 87.511141 -235.47419) (xy 87.531089 -235.42737) (xy 87.55829 -235.384356) (xy 87.592038 -235.346262)
			(xy 87.63146 -235.314075) (xy 87.675534 -235.288629) (xy 87.72312 -235.270582) (xy 87.772984 -235.260402)
			(xy 87.823836 -235.258353) (xy 87.874357 -235.264487) (xy 87.923241 -235.278647) (xy 87.96922 -235.300464)
			(xy 88.011104 -235.329374) (xy 88.047808 -235.364629) (xy 88.078381 -235.405315) (xy 88.102032 -235.450378)
			(xy 88.118148 -235.498652) (xy 88.126312 -235.548886) (xy 88.126824 -235.574332) (xy 88.434921 -235.574332)
			(xy 88.439016 -235.523604) (xy 88.451195 -235.47419) (xy 88.471143 -235.42737) (xy 88.498344 -235.384356)
			(xy 88.532092 -235.346262) (xy 88.571514 -235.314075) (xy 88.615588 -235.288629) (xy 88.663174 -235.270582)
			(xy 88.713038 -235.260402) (xy 88.76389 -235.258353) (xy 88.814411 -235.264487) (xy 88.863295 -235.278647)
			(xy 88.909274 -235.300464) (xy 88.951158 -235.329374) (xy 88.987862 -235.364629) (xy 89.018435 -235.405315)
			(xy 89.042086 -235.450378) (xy 89.058202 -235.498652) (xy 89.066366 -235.548886) (xy 89.066878 -235.574332)
			(xy 89.385152 -235.574332) (xy 89.389112 -235.525278) (xy 89.400889 -235.477494) (xy 89.42018 -235.432218)
			(xy 89.446483 -235.390622) (xy 89.479118 -235.353785) (xy 89.517239 -235.32266) (xy 89.55986 -235.298053)
			(xy 89.605876 -235.280601) (xy 89.654095 -235.270757) (xy 89.70327 -235.268776) (xy 89.752125 -235.274708)
			(xy 89.799396 -235.2884) (xy 89.843858 -235.309498) (xy 89.884361 -235.337454) (xy 89.919854 -235.371546)
			(xy 89.949419 -235.41089) (xy 89.97229 -235.454467) (xy 89.987874 -235.501148) (xy 89.995769 -235.549725)
			(xy 89.996264 -235.574332) (xy 90.314775 -235.574332) (xy 90.31887 -235.523604) (xy 90.331049 -235.47419)
			(xy 90.350997 -235.42737) (xy 90.378198 -235.384356) (xy 90.411946 -235.346262) (xy 90.451368 -235.314075)
			(xy 90.495442 -235.288629) (xy 90.543028 -235.270582) (xy 90.592892 -235.260402) (xy 90.643744 -235.258353)
			(xy 90.694265 -235.264487) (xy 90.743149 -235.278647) (xy 90.789128 -235.300464) (xy 90.831012 -235.329374)
			(xy 90.867716 -235.364629) (xy 90.898289 -235.405315) (xy 90.92194 -235.450378) (xy 90.938056 -235.498652)
			(xy 90.94622 -235.548886) (xy 90.946732 -235.574332) (xy 91.26526 -235.574332) (xy 91.26922 -235.525278)
			(xy 91.280997 -235.477494) (xy 91.300288 -235.432218) (xy 91.326591 -235.390622) (xy 91.359226 -235.353785)
			(xy 91.397347 -235.32266) (xy 91.439968 -235.298053) (xy 91.485984 -235.280601) (xy 91.534203 -235.270757)
			(xy 91.583378 -235.268776) (xy 91.632233 -235.274708) (xy 91.679504 -235.2884) (xy 91.723966 -235.309498)
			(xy 91.764469 -235.337454) (xy 91.799962 -235.371546) (xy 91.829527 -235.41089) (xy 91.852398 -235.454467)
			(xy 91.867982 -235.501148) (xy 91.875877 -235.549725) (xy 91.876372 -235.574332) (xy 92.194883 -235.574332)
			(xy 92.198978 -235.523604) (xy 92.211157 -235.47419) (xy 92.231105 -235.42737) (xy 92.258306 -235.384356)
			(xy 92.292054 -235.346262) (xy 92.331476 -235.314075) (xy 92.37555 -235.288629) (xy 92.423136 -235.270582)
			(xy 92.473 -235.260402) (xy 92.523852 -235.258353) (xy 92.574373 -235.264487) (xy 92.623257 -235.278647)
			(xy 92.669236 -235.300464) (xy 92.71112 -235.329374) (xy 92.747824 -235.364629) (xy 92.778397 -235.405315)
			(xy 92.802048 -235.450378) (xy 92.818164 -235.498652) (xy 92.826328 -235.548886) (xy 92.82684 -235.574332)
			(xy 93.145114 -235.574332) (xy 93.149074 -235.525278) (xy 93.160851 -235.477494) (xy 93.180142 -235.432218)
			(xy 93.206445 -235.390622) (xy 93.23908 -235.353785) (xy 93.277201 -235.32266) (xy 93.319822 -235.298053)
			(xy 93.365838 -235.280601) (xy 93.414057 -235.270757) (xy 93.463232 -235.268776) (xy 93.512087 -235.274708)
			(xy 93.559358 -235.2884) (xy 93.60382 -235.309498) (xy 93.644323 -235.337454) (xy 93.679816 -235.371546)
			(xy 93.709381 -235.41089) (xy 93.732252 -235.454467) (xy 93.747836 -235.501148) (xy 93.755731 -235.549725)
			(xy 93.756226 -235.574332) (xy 94.074737 -235.574332) (xy 94.078832 -235.523604) (xy 94.091011 -235.47419)
			(xy 94.110959 -235.42737) (xy 94.13816 -235.384356) (xy 94.171908 -235.346262) (xy 94.21133 -235.314075)
			(xy 94.255404 -235.288629) (xy 94.30299 -235.270582) (xy 94.352854 -235.260402) (xy 94.403706 -235.258353)
			(xy 94.454227 -235.264487) (xy 94.503111 -235.278647) (xy 94.54909 -235.300464) (xy 94.590974 -235.329374)
			(xy 94.627678 -235.364629) (xy 94.658251 -235.405315) (xy 94.681902 -235.450378) (xy 94.698018 -235.498652)
			(xy 94.706182 -235.548886) (xy 94.706694 -235.574332) (xy 95.014791 -235.574332) (xy 95.018886 -235.523604)
			(xy 95.031065 -235.47419) (xy 95.051013 -235.42737) (xy 95.078214 -235.384356) (xy 95.111962 -235.346262)
			(xy 95.151384 -235.314075) (xy 95.195458 -235.288629) (xy 95.243044 -235.270582) (xy 95.292908 -235.260402)
			(xy 95.34376 -235.258353) (xy 95.394281 -235.264487) (xy 95.443165 -235.278647) (xy 95.489144 -235.300464)
			(xy 95.531028 -235.329374) (xy 95.567732 -235.364629) (xy 95.598305 -235.405315) (xy 95.621956 -235.450378)
			(xy 95.638072 -235.498652) (xy 95.646236 -235.548886) (xy 95.646748 -235.574332) (xy 95.965276 -235.574332)
			(xy 95.969236 -235.525278) (xy 95.981013 -235.477494) (xy 96.000304 -235.432218) (xy 96.026607 -235.390622)
			(xy 96.059242 -235.353785) (xy 96.097363 -235.32266) (xy 96.139984 -235.298053) (xy 96.186 -235.280601)
			(xy 96.234219 -235.270757) (xy 96.283394 -235.268776) (xy 96.332249 -235.274708) (xy 96.37952 -235.2884)
			(xy 96.423982 -235.309498) (xy 96.464485 -235.337454) (xy 96.499978 -235.371546) (xy 96.529543 -235.41089)
			(xy 96.552414 -235.454467) (xy 96.567998 -235.501148) (xy 96.575893 -235.549725) (xy 96.576388 -235.574332)
			(xy 96.90533 -235.574332) (xy 96.90929 -235.525278) (xy 96.921067 -235.477494) (xy 96.940358 -235.432218)
			(xy 96.966661 -235.390622) (xy 96.999296 -235.353785) (xy 97.037417 -235.32266) (xy 97.080038 -235.298053)
			(xy 97.126054 -235.280601) (xy 97.174273 -235.270757) (xy 97.223448 -235.268776) (xy 97.272303 -235.274708)
			(xy 97.319574 -235.2884) (xy 97.364036 -235.309498) (xy 97.404539 -235.337454) (xy 97.440032 -235.371546)
			(xy 97.469597 -235.41089) (xy 97.492468 -235.454467) (xy 97.508052 -235.501148) (xy 97.515947 -235.549725)
			(xy 97.516442 -235.574332) (xy 97.84513 -235.574332) (xy 97.84909 -235.525278) (xy 97.860867 -235.477494)
			(xy 97.880158 -235.432218) (xy 97.906461 -235.390622) (xy 97.939096 -235.353785) (xy 97.977217 -235.32266)
			(xy 98.019838 -235.298053) (xy 98.065854 -235.280601) (xy 98.114073 -235.270757) (xy 98.163248 -235.268776)
			(xy 98.212103 -235.274708) (xy 98.259374 -235.2884) (xy 98.303836 -235.309498) (xy 98.344339 -235.337454)
			(xy 98.379832 -235.371546) (xy 98.409397 -235.41089) (xy 98.432268 -235.454467) (xy 98.447852 -235.501148)
			(xy 98.455747 -235.549725) (xy 98.456242 -235.574332) (xy 98.785184 -235.574332) (xy 98.789144 -235.525278)
			(xy 98.800921 -235.477494) (xy 98.820212 -235.432218) (xy 98.846515 -235.390622) (xy 98.87915 -235.353785)
			(xy 98.917271 -235.32266) (xy 98.959892 -235.298053) (xy 99.005908 -235.280601) (xy 99.054127 -235.270757)
			(xy 99.103302 -235.268776) (xy 99.152157 -235.274708) (xy 99.199428 -235.2884) (xy 99.24389 -235.309498)
			(xy 99.284393 -235.337454) (xy 99.319886 -235.371546) (xy 99.349451 -235.41089) (xy 99.372322 -235.454467)
			(xy 99.387906 -235.501148) (xy 99.395801 -235.549725) (xy 99.396296 -235.574332) (xy 99.725238 -235.574332)
			(xy 99.729198 -235.525278) (xy 99.740975 -235.477494) (xy 99.760266 -235.432218) (xy 99.786569 -235.390622)
			(xy 99.819204 -235.353785) (xy 99.857325 -235.32266) (xy 99.899946 -235.298053) (xy 99.945962 -235.280601)
			(xy 99.994181 -235.270757) (xy 100.043356 -235.268776) (xy 100.092211 -235.274708) (xy 100.139482 -235.2884)
			(xy 100.183944 -235.309498) (xy 100.224447 -235.337454) (xy 100.25994 -235.371546) (xy 100.289505 -235.41089)
			(xy 100.312376 -235.454467) (xy 100.32796 -235.501148) (xy 100.335855 -235.549725) (xy 100.33635 -235.574332)
			(xy 100.665292 -235.574332) (xy 100.669252 -235.525278) (xy 100.681029 -235.477494) (xy 100.70032 -235.432218)
			(xy 100.726623 -235.390622) (xy 100.759258 -235.353785) (xy 100.797379 -235.32266) (xy 100.84 -235.298053)
			(xy 100.886016 -235.280601) (xy 100.934235 -235.270757) (xy 100.98341 -235.268776) (xy 101.032265 -235.274708)
			(xy 101.079536 -235.2884) (xy 101.123998 -235.309498) (xy 101.164501 -235.337454) (xy 101.199994 -235.371546)
			(xy 101.229559 -235.41089) (xy 101.25243 -235.454467) (xy 101.268014 -235.501148) (xy 101.275909 -235.549725)
			(xy 101.276404 -235.574332) (xy 101.605346 -235.574332) (xy 101.609306 -235.525278) (xy 101.621083 -235.477494)
			(xy 101.640374 -235.432218) (xy 101.666677 -235.390622) (xy 101.699312 -235.353785) (xy 101.737433 -235.32266)
			(xy 101.780054 -235.298053) (xy 101.82607 -235.280601) (xy 101.874289 -235.270757) (xy 101.923464 -235.268776)
			(xy 101.972319 -235.274708) (xy 102.01959 -235.2884) (xy 102.064052 -235.309498) (xy 102.104555 -235.337454)
			(xy 102.140048 -235.371546) (xy 102.169613 -235.41089) (xy 102.192484 -235.454467) (xy 102.208068 -235.501148)
			(xy 102.215963 -235.549725) (xy 102.216458 -235.574332) (xy 102.545146 -235.574332) (xy 102.549106 -235.525278)
			(xy 102.560883 -235.477494) (xy 102.580174 -235.432218) (xy 102.606477 -235.390622) (xy 102.639112 -235.353785)
			(xy 102.677233 -235.32266) (xy 102.719854 -235.298053) (xy 102.76587 -235.280601) (xy 102.814089 -235.270757)
			(xy 102.863264 -235.268776) (xy 102.912119 -235.274708) (xy 102.95939 -235.2884) (xy 103.003852 -235.309498)
			(xy 103.044355 -235.337454) (xy 103.079848 -235.371546) (xy 103.109413 -235.41089) (xy 103.132284 -235.454467)
			(xy 103.147868 -235.501148) (xy 103.155763 -235.549725) (xy 103.156258 -235.574332) (xy 103.4852 -235.574332)
			(xy 103.48916 -235.525278) (xy 103.500937 -235.477494) (xy 103.520228 -235.432218) (xy 103.546531 -235.390622)
			(xy 103.579166 -235.353785) (xy 103.617287 -235.32266) (xy 103.659908 -235.298053) (xy 103.705924 -235.280601)
			(xy 103.754143 -235.270757) (xy 103.803318 -235.268776) (xy 103.852173 -235.274708) (xy 103.899444 -235.2884)
			(xy 103.943906 -235.309498) (xy 103.984409 -235.337454) (xy 104.019902 -235.371546) (xy 104.049467 -235.41089)
			(xy 104.072338 -235.454467) (xy 104.087922 -235.501148) (xy 104.095817 -235.549725) (xy 104.096312 -235.574332)
			(xy 104.425254 -235.574332) (xy 104.429214 -235.525278) (xy 104.440991 -235.477494) (xy 104.460282 -235.432218)
			(xy 104.486585 -235.390622) (xy 104.51922 -235.353785) (xy 104.557341 -235.32266) (xy 104.599962 -235.298053)
			(xy 104.645978 -235.280601) (xy 104.694197 -235.270757) (xy 104.743372 -235.268776) (xy 104.792227 -235.274708)
			(xy 104.839498 -235.2884) (xy 104.88396 -235.309498) (xy 104.924463 -235.337454) (xy 104.959956 -235.371546)
			(xy 104.989521 -235.41089) (xy 105.012392 -235.454467) (xy 105.027976 -235.501148) (xy 105.035871 -235.549725)
			(xy 105.036366 -235.574332) (xy 105.365308 -235.574332) (xy 105.369268 -235.525278) (xy 105.381045 -235.477494)
			(xy 105.400336 -235.432218) (xy 105.426639 -235.390622) (xy 105.459274 -235.353785) (xy 105.497395 -235.32266)
			(xy 105.540016 -235.298053) (xy 105.586032 -235.280601) (xy 105.634251 -235.270757) (xy 105.683426 -235.268776)
			(xy 105.732281 -235.274708) (xy 105.779552 -235.2884) (xy 105.824014 -235.309498) (xy 105.864517 -235.337454)
			(xy 105.90001 -235.371546) (xy 105.929575 -235.41089) (xy 105.952446 -235.454467) (xy 105.96803 -235.501148)
			(xy 105.975925 -235.549725) (xy 105.97642 -235.574332) (xy 106.305362 -235.574332) (xy 106.309322 -235.525278)
			(xy 106.321099 -235.477494) (xy 106.34039 -235.432218) (xy 106.366693 -235.390622) (xy 106.399328 -235.353785)
			(xy 106.437449 -235.32266) (xy 106.48007 -235.298053) (xy 106.526086 -235.280601) (xy 106.574305 -235.270757)
			(xy 106.62348 -235.268776) (xy 106.672335 -235.274708) (xy 106.719606 -235.2884) (xy 106.764068 -235.309498)
			(xy 106.804571 -235.337454) (xy 106.840064 -235.371546) (xy 106.869629 -235.41089) (xy 106.8925 -235.454467)
			(xy 106.908084 -235.501148) (xy 106.915979 -235.549725) (xy 106.916474 -235.574332) (xy 107.245162 -235.574332)
			(xy 107.249122 -235.525278) (xy 107.260899 -235.477494) (xy 107.28019 -235.432218) (xy 107.306493 -235.390622)
			(xy 107.339128 -235.353785) (xy 107.377249 -235.32266) (xy 107.41987 -235.298053) (xy 107.465886 -235.280601)
			(xy 107.514105 -235.270757) (xy 107.56328 -235.268776) (xy 107.612135 -235.274708) (xy 107.659406 -235.2884)
			(xy 107.703868 -235.309498) (xy 107.744371 -235.337454) (xy 107.779864 -235.371546) (xy 107.809429 -235.41089)
			(xy 107.8323 -235.454467) (xy 107.847884 -235.501148) (xy 107.855779 -235.549725) (xy 107.856274 -235.574332)
			(xy 108.174785 -235.574332) (xy 108.17888 -235.523604) (xy 108.191059 -235.47419) (xy 108.211007 -235.42737)
			(xy 108.238208 -235.384356) (xy 108.271956 -235.346262) (xy 108.311378 -235.314075) (xy 108.355452 -235.288629)
			(xy 108.403038 -235.270582) (xy 108.452902 -235.260402) (xy 108.503754 -235.258353) (xy 108.554275 -235.264487)
			(xy 108.603159 -235.278647) (xy 108.649138 -235.300464) (xy 108.691022 -235.329374) (xy 108.727726 -235.364629)
			(xy 108.758299 -235.405315) (xy 108.78195 -235.450378) (xy 108.798066 -235.498652) (xy 108.80623 -235.548886)
			(xy 108.806742 -235.574332) (xy 109.114839 -235.574332) (xy 109.118934 -235.523604) (xy 109.131113 -235.47419)
			(xy 109.151061 -235.42737) (xy 109.178262 -235.384356) (xy 109.21201 -235.346262) (xy 109.251432 -235.314075)
			(xy 109.295506 -235.288629) (xy 109.343092 -235.270582) (xy 109.392956 -235.260402) (xy 109.443808 -235.258353)
			(xy 109.494329 -235.264487) (xy 109.543213 -235.278647) (xy 109.589192 -235.300464) (xy 109.631076 -235.329374)
			(xy 109.66778 -235.364629) (xy 109.698353 -235.405315) (xy 109.722004 -235.450378) (xy 109.73812 -235.498652)
			(xy 109.746284 -235.548886) (xy 109.746796 -235.574332) (xy 110.065324 -235.574332) (xy 110.069284 -235.525278)
			(xy 110.081061 -235.477494) (xy 110.100352 -235.432218) (xy 110.126655 -235.390622) (xy 110.15929 -235.353785)
			(xy 110.197411 -235.32266) (xy 110.240032 -235.298053) (xy 110.286048 -235.280601) (xy 110.334267 -235.270757)
			(xy 110.383442 -235.268776) (xy 110.432297 -235.274708) (xy 110.479568 -235.2884) (xy 110.52403 -235.309498)
			(xy 110.564533 -235.337454) (xy 110.600026 -235.371546) (xy 110.629591 -235.41089) (xy 110.652462 -235.454467)
			(xy 110.668046 -235.501148) (xy 110.675941 -235.549725) (xy 110.676436 -235.574332) (xy 110.675941 -235.598939)
			(xy 110.668046 -235.647516) (xy 110.652462 -235.694197) (xy 110.629591 -235.737774) (xy 110.600026 -235.777118)
			(xy 110.564533 -235.81121) (xy 110.52403 -235.839166) (xy 110.479568 -235.860264) (xy 110.432297 -235.873956)
			(xy 110.383442 -235.879888) (xy 110.334267 -235.877907) (xy 110.286048 -235.868063) (xy 110.240032 -235.850611)
			(xy 110.197411 -235.826004) (xy 110.15929 -235.794879) (xy 110.126655 -235.758042) (xy 110.100352 -235.716446)
			(xy 110.081061 -235.67117) (xy 110.069284 -235.623386) (xy 110.065324 -235.574332) (xy 109.746796 -235.574332)
			(xy 109.746284 -235.599778) (xy 109.73812 -235.650012) (xy 109.722004 -235.698286) (xy 109.698353 -235.743349)
			(xy 109.66778 -235.784035) (xy 109.631076 -235.81929) (xy 109.589192 -235.8482) (xy 109.543213 -235.870017)
			(xy 109.494329 -235.884177) (xy 109.443808 -235.890311) (xy 109.392956 -235.888262) (xy 109.343092 -235.878082)
			(xy 109.295506 -235.860035) (xy 109.251432 -235.834589) (xy 109.21201 -235.802402) (xy 109.178262 -235.764308)
			(xy 109.151061 -235.721294) (xy 109.131113 -235.674474) (xy 109.118934 -235.62506) (xy 109.114839 -235.574332)
			(xy 108.806742 -235.574332) (xy 108.80623 -235.599778) (xy 108.798066 -235.650012) (xy 108.78195 -235.698286)
			(xy 108.758299 -235.743349) (xy 108.727726 -235.784035) (xy 108.691022 -235.81929) (xy 108.649138 -235.8482)
			(xy 108.603159 -235.870017) (xy 108.554275 -235.884177) (xy 108.503754 -235.890311) (xy 108.452902 -235.888262)
			(xy 108.403038 -235.878082) (xy 108.355452 -235.860035) (xy 108.311378 -235.834589) (xy 108.271956 -235.802402)
			(xy 108.238208 -235.764308) (xy 108.211007 -235.721294) (xy 108.191059 -235.674474) (xy 108.17888 -235.62506)
			(xy 108.174785 -235.574332) (xy 107.856274 -235.574332) (xy 107.855779 -235.598939) (xy 107.847884 -235.647516)
			(xy 107.8323 -235.694197) (xy 107.809429 -235.737774) (xy 107.779864 -235.777118) (xy 107.744371 -235.81121)
			(xy 107.703868 -235.839166) (xy 107.659406 -235.860264) (xy 107.612135 -235.873956) (xy 107.56328 -235.879888)
			(xy 107.514105 -235.877907) (xy 107.465886 -235.868063) (xy 107.41987 -235.850611) (xy 107.377249 -235.826004)
			(xy 107.339128 -235.794879) (xy 107.306493 -235.758042) (xy 107.28019 -235.716446) (xy 107.260899 -235.67117)
			(xy 107.249122 -235.623386) (xy 107.245162 -235.574332) (xy 106.916474 -235.574332) (xy 106.915979 -235.598939)
			(xy 106.908084 -235.647516) (xy 106.8925 -235.694197) (xy 106.869629 -235.737774) (xy 106.840064 -235.777118)
			(xy 106.804571 -235.81121) (xy 106.764068 -235.839166) (xy 106.719606 -235.860264) (xy 106.672335 -235.873956)
			(xy 106.62348 -235.879888) (xy 106.574305 -235.877907) (xy 106.526086 -235.868063) (xy 106.48007 -235.850611)
			(xy 106.437449 -235.826004) (xy 106.399328 -235.794879) (xy 106.366693 -235.758042) (xy 106.34039 -235.716446)
			(xy 106.321099 -235.67117) (xy 106.309322 -235.623386) (xy 106.305362 -235.574332) (xy 105.97642 -235.574332)
			(xy 105.975925 -235.598939) (xy 105.96803 -235.647516) (xy 105.952446 -235.694197) (xy 105.929575 -235.737774)
			(xy 105.90001 -235.777118) (xy 105.864517 -235.81121) (xy 105.824014 -235.839166) (xy 105.779552 -235.860264)
			(xy 105.732281 -235.873956) (xy 105.683426 -235.879888) (xy 105.634251 -235.877907) (xy 105.586032 -235.868063)
			(xy 105.540016 -235.850611) (xy 105.497395 -235.826004) (xy 105.459274 -235.794879) (xy 105.426639 -235.758042)
			(xy 105.400336 -235.716446) (xy 105.381045 -235.67117) (xy 105.369268 -235.623386) (xy 105.365308 -235.574332)
			(xy 105.036366 -235.574332) (xy 105.035871 -235.598939) (xy 105.027976 -235.647516) (xy 105.012392 -235.694197)
			(xy 104.989521 -235.737774) (xy 104.959956 -235.777118) (xy 104.924463 -235.81121) (xy 104.88396 -235.839166)
			(xy 104.839498 -235.860264) (xy 104.792227 -235.873956) (xy 104.743372 -235.879888) (xy 104.694197 -235.877907)
			(xy 104.645978 -235.868063) (xy 104.599962 -235.850611) (xy 104.557341 -235.826004) (xy 104.51922 -235.794879)
			(xy 104.486585 -235.758042) (xy 104.460282 -235.716446) (xy 104.440991 -235.67117) (xy 104.429214 -235.623386)
			(xy 104.425254 -235.574332) (xy 104.096312 -235.574332) (xy 104.095817 -235.598939) (xy 104.087922 -235.647516)
			(xy 104.072338 -235.694197) (xy 104.049467 -235.737774) (xy 104.019902 -235.777118) (xy 103.984409 -235.81121)
			(xy 103.943906 -235.839166) (xy 103.899444 -235.860264) (xy 103.852173 -235.873956) (xy 103.803318 -235.879888)
			(xy 103.754143 -235.877907) (xy 103.705924 -235.868063) (xy 103.659908 -235.850611) (xy 103.617287 -235.826004)
			(xy 103.579166 -235.794879) (xy 103.546531 -235.758042) (xy 103.520228 -235.716446) (xy 103.500937 -235.67117)
			(xy 103.48916 -235.623386) (xy 103.4852 -235.574332) (xy 103.156258 -235.574332) (xy 103.155763 -235.598939)
			(xy 103.147868 -235.647516) (xy 103.132284 -235.694197) (xy 103.109413 -235.737774) (xy 103.079848 -235.777118)
			(xy 103.044355 -235.81121) (xy 103.003852 -235.839166) (xy 102.95939 -235.860264) (xy 102.912119 -235.873956)
			(xy 102.863264 -235.879888) (xy 102.814089 -235.877907) (xy 102.76587 -235.868063) (xy 102.719854 -235.850611)
			(xy 102.677233 -235.826004) (xy 102.639112 -235.794879) (xy 102.606477 -235.758042) (xy 102.580174 -235.716446)
			(xy 102.560883 -235.67117) (xy 102.549106 -235.623386) (xy 102.545146 -235.574332) (xy 102.216458 -235.574332)
			(xy 102.215963 -235.598939) (xy 102.208068 -235.647516) (xy 102.192484 -235.694197) (xy 102.169613 -235.737774)
			(xy 102.140048 -235.777118) (xy 102.104555 -235.81121) (xy 102.064052 -235.839166) (xy 102.01959 -235.860264)
			(xy 101.972319 -235.873956) (xy 101.923464 -235.879888) (xy 101.874289 -235.877907) (xy 101.82607 -235.868063)
			(xy 101.780054 -235.850611) (xy 101.737433 -235.826004) (xy 101.699312 -235.794879) (xy 101.666677 -235.758042)
			(xy 101.640374 -235.716446) (xy 101.621083 -235.67117) (xy 101.609306 -235.623386) (xy 101.605346 -235.574332)
			(xy 101.276404 -235.574332) (xy 101.275909 -235.598939) (xy 101.268014 -235.647516) (xy 101.25243 -235.694197)
			(xy 101.229559 -235.737774) (xy 101.199994 -235.777118) (xy 101.164501 -235.81121) (xy 101.123998 -235.839166)
			(xy 101.079536 -235.860264) (xy 101.032265 -235.873956) (xy 100.98341 -235.879888) (xy 100.934235 -235.877907)
			(xy 100.886016 -235.868063) (xy 100.84 -235.850611) (xy 100.797379 -235.826004) (xy 100.759258 -235.794879)
			(xy 100.726623 -235.758042) (xy 100.70032 -235.716446) (xy 100.681029 -235.67117) (xy 100.669252 -235.623386)
			(xy 100.665292 -235.574332) (xy 100.33635 -235.574332) (xy 100.335855 -235.598939) (xy 100.32796 -235.647516)
			(xy 100.312376 -235.694197) (xy 100.289505 -235.737774) (xy 100.25994 -235.777118) (xy 100.224447 -235.81121)
			(xy 100.183944 -235.839166) (xy 100.139482 -235.860264) (xy 100.092211 -235.873956) (xy 100.043356 -235.879888)
			(xy 99.994181 -235.877907) (xy 99.945962 -235.868063) (xy 99.899946 -235.850611) (xy 99.857325 -235.826004)
			(xy 99.819204 -235.794879) (xy 99.786569 -235.758042) (xy 99.760266 -235.716446) (xy 99.740975 -235.67117)
			(xy 99.729198 -235.623386) (xy 99.725238 -235.574332) (xy 99.396296 -235.574332) (xy 99.395801 -235.598939)
			(xy 99.387906 -235.647516) (xy 99.372322 -235.694197) (xy 99.349451 -235.737774) (xy 99.319886 -235.777118)
			(xy 99.284393 -235.81121) (xy 99.24389 -235.839166) (xy 99.199428 -235.860264) (xy 99.152157 -235.873956)
			(xy 99.103302 -235.879888) (xy 99.054127 -235.877907) (xy 99.005908 -235.868063) (xy 98.959892 -235.850611)
			(xy 98.917271 -235.826004) (xy 98.87915 -235.794879) (xy 98.846515 -235.758042) (xy 98.820212 -235.716446)
			(xy 98.800921 -235.67117) (xy 98.789144 -235.623386) (xy 98.785184 -235.574332) (xy 98.456242 -235.574332)
			(xy 98.455747 -235.598939) (xy 98.447852 -235.647516) (xy 98.432268 -235.694197) (xy 98.409397 -235.737774)
			(xy 98.379832 -235.777118) (xy 98.344339 -235.81121) (xy 98.303836 -235.839166) (xy 98.259374 -235.860264)
			(xy 98.212103 -235.873956) (xy 98.163248 -235.879888) (xy 98.114073 -235.877907) (xy 98.065854 -235.868063)
			(xy 98.019838 -235.850611) (xy 97.977217 -235.826004) (xy 97.939096 -235.794879) (xy 97.906461 -235.758042)
			(xy 97.880158 -235.716446) (xy 97.860867 -235.67117) (xy 97.84909 -235.623386) (xy 97.84513 -235.574332)
			(xy 97.516442 -235.574332) (xy 97.515947 -235.598939) (xy 97.508052 -235.647516) (xy 97.492468 -235.694197)
			(xy 97.469597 -235.737774) (xy 97.440032 -235.777118) (xy 97.404539 -235.81121) (xy 97.364036 -235.839166)
			(xy 97.319574 -235.860264) (xy 97.272303 -235.873956) (xy 97.223448 -235.879888) (xy 97.174273 -235.877907)
			(xy 97.126054 -235.868063) (xy 97.080038 -235.850611) (xy 97.037417 -235.826004) (xy 96.999296 -235.794879)
			(xy 96.966661 -235.758042) (xy 96.940358 -235.716446) (xy 96.921067 -235.67117) (xy 96.90929 -235.623386)
			(xy 96.90533 -235.574332) (xy 96.576388 -235.574332) (xy 96.575893 -235.598939) (xy 96.567998 -235.647516)
			(xy 96.552414 -235.694197) (xy 96.529543 -235.737774) (xy 96.499978 -235.777118) (xy 96.464485 -235.81121)
			(xy 96.423982 -235.839166) (xy 96.37952 -235.860264) (xy 96.332249 -235.873956) (xy 96.283394 -235.879888)
			(xy 96.234219 -235.877907) (xy 96.186 -235.868063) (xy 96.139984 -235.850611) (xy 96.097363 -235.826004)
			(xy 96.059242 -235.794879) (xy 96.026607 -235.758042) (xy 96.000304 -235.716446) (xy 95.981013 -235.67117)
			(xy 95.969236 -235.623386) (xy 95.965276 -235.574332) (xy 95.646748 -235.574332) (xy 95.646236 -235.599778)
			(xy 95.638072 -235.650012) (xy 95.621956 -235.698286) (xy 95.598305 -235.743349) (xy 95.567732 -235.784035)
			(xy 95.531028 -235.81929) (xy 95.489144 -235.8482) (xy 95.443165 -235.870017) (xy 95.394281 -235.884177)
			(xy 95.34376 -235.890311) (xy 95.292908 -235.888262) (xy 95.243044 -235.878082) (xy 95.195458 -235.860035)
			(xy 95.151384 -235.834589) (xy 95.111962 -235.802402) (xy 95.078214 -235.764308) (xy 95.051013 -235.721294)
			(xy 95.031065 -235.674474) (xy 95.018886 -235.62506) (xy 95.014791 -235.574332) (xy 94.706694 -235.574332)
			(xy 94.706182 -235.599778) (xy 94.698018 -235.650012) (xy 94.681902 -235.698286) (xy 94.658251 -235.743349)
			(xy 94.627678 -235.784035) (xy 94.590974 -235.81929) (xy 94.54909 -235.8482) (xy 94.503111 -235.870017)
			(xy 94.454227 -235.884177) (xy 94.403706 -235.890311) (xy 94.352854 -235.888262) (xy 94.30299 -235.878082)
			(xy 94.255404 -235.860035) (xy 94.21133 -235.834589) (xy 94.171908 -235.802402) (xy 94.13816 -235.764308)
			(xy 94.110959 -235.721294) (xy 94.091011 -235.674474) (xy 94.078832 -235.62506) (xy 94.074737 -235.574332)
			(xy 93.756226 -235.574332) (xy 93.755731 -235.598939) (xy 93.747836 -235.647516) (xy 93.732252 -235.694197)
			(xy 93.709381 -235.737774) (xy 93.679816 -235.777118) (xy 93.644323 -235.81121) (xy 93.60382 -235.839166)
			(xy 93.559358 -235.860264) (xy 93.512087 -235.873956) (xy 93.463232 -235.879888) (xy 93.414057 -235.877907)
			(xy 93.365838 -235.868063) (xy 93.319822 -235.850611) (xy 93.277201 -235.826004) (xy 93.23908 -235.794879)
			(xy 93.206445 -235.758042) (xy 93.180142 -235.716446) (xy 93.160851 -235.67117) (xy 93.149074 -235.623386)
			(xy 93.145114 -235.574332) (xy 92.82684 -235.574332) (xy 92.826328 -235.599778) (xy 92.818164 -235.650012)
			(xy 92.802048 -235.698286) (xy 92.778397 -235.743349) (xy 92.747824 -235.784035) (xy 92.71112 -235.81929)
			(xy 92.669236 -235.8482) (xy 92.623257 -235.870017) (xy 92.574373 -235.884177) (xy 92.523852 -235.890311)
			(xy 92.473 -235.888262) (xy 92.423136 -235.878082) (xy 92.37555 -235.860035) (xy 92.331476 -235.834589)
			(xy 92.292054 -235.802402) (xy 92.258306 -235.764308) (xy 92.231105 -235.721294) (xy 92.211157 -235.674474)
			(xy 92.198978 -235.62506) (xy 92.194883 -235.574332) (xy 91.876372 -235.574332) (xy 91.875877 -235.598939)
			(xy 91.867982 -235.647516) (xy 91.852398 -235.694197) (xy 91.829527 -235.737774) (xy 91.799962 -235.777118)
			(xy 91.764469 -235.81121) (xy 91.723966 -235.839166) (xy 91.679504 -235.860264) (xy 91.632233 -235.873956)
			(xy 91.583378 -235.879888) (xy 91.534203 -235.877907) (xy 91.485984 -235.868063) (xy 91.439968 -235.850611)
			(xy 91.397347 -235.826004) (xy 91.359226 -235.794879) (xy 91.326591 -235.758042) (xy 91.300288 -235.716446)
			(xy 91.280997 -235.67117) (xy 91.26922 -235.623386) (xy 91.26526 -235.574332) (xy 90.946732 -235.574332)
			(xy 90.94622 -235.599778) (xy 90.938056 -235.650012) (xy 90.92194 -235.698286) (xy 90.898289 -235.743349)
			(xy 90.867716 -235.784035) (xy 90.831012 -235.81929) (xy 90.789128 -235.8482) (xy 90.743149 -235.870017)
			(xy 90.694265 -235.884177) (xy 90.643744 -235.890311) (xy 90.592892 -235.888262) (xy 90.543028 -235.878082)
			(xy 90.495442 -235.860035) (xy 90.451368 -235.834589) (xy 90.411946 -235.802402) (xy 90.378198 -235.764308)
			(xy 90.350997 -235.721294) (xy 90.331049 -235.674474) (xy 90.31887 -235.62506) (xy 90.314775 -235.574332)
			(xy 89.996264 -235.574332) (xy 89.995769 -235.598939) (xy 89.987874 -235.647516) (xy 89.97229 -235.694197)
			(xy 89.949419 -235.737774) (xy 89.919854 -235.777118) (xy 89.884361 -235.81121) (xy 89.843858 -235.839166)
			(xy 89.799396 -235.860264) (xy 89.752125 -235.873956) (xy 89.70327 -235.879888) (xy 89.654095 -235.877907)
			(xy 89.605876 -235.868063) (xy 89.55986 -235.850611) (xy 89.517239 -235.826004) (xy 89.479118 -235.794879)
			(xy 89.446483 -235.758042) (xy 89.42018 -235.716446) (xy 89.400889 -235.67117) (xy 89.389112 -235.623386)
			(xy 89.385152 -235.574332) (xy 89.066878 -235.574332) (xy 89.066366 -235.599778) (xy 89.058202 -235.650012)
			(xy 89.042086 -235.698286) (xy 89.018435 -235.743349) (xy 88.987862 -235.784035) (xy 88.951158 -235.81929)
			(xy 88.909274 -235.8482) (xy 88.863295 -235.870017) (xy 88.814411 -235.884177) (xy 88.76389 -235.890311)
			(xy 88.713038 -235.888262) (xy 88.663174 -235.878082) (xy 88.615588 -235.860035) (xy 88.571514 -235.834589)
			(xy 88.532092 -235.802402) (xy 88.498344 -235.764308) (xy 88.471143 -235.721294) (xy 88.451195 -235.674474)
			(xy 88.439016 -235.62506) (xy 88.434921 -235.574332) (xy 88.126824 -235.574332) (xy 88.126312 -235.599778)
			(xy 88.118148 -235.650012) (xy 88.102032 -235.698286) (xy 88.078381 -235.743349) (xy 88.047808 -235.784035)
			(xy 88.011104 -235.81929) (xy 87.96922 -235.8482) (xy 87.923241 -235.870017) (xy 87.874357 -235.884177)
			(xy 87.823836 -235.890311) (xy 87.772984 -235.888262) (xy 87.72312 -235.878082) (xy 87.675534 -235.860035)
			(xy 87.63146 -235.834589) (xy 87.592038 -235.802402) (xy 87.55829 -235.764308) (xy 87.531089 -235.721294)
			(xy 87.511141 -235.674474) (xy 87.498962 -235.62506) (xy 87.494867 -235.574332) (xy 87.176356 -235.574332)
			(xy 87.175861 -235.598939) (xy 87.167966 -235.647516) (xy 87.152382 -235.694197) (xy 87.129511 -235.737774)
			(xy 87.099946 -235.777118) (xy 87.064453 -235.81121) (xy 87.02395 -235.839166) (xy 86.979488 -235.860264)
			(xy 86.932217 -235.873956) (xy 86.883362 -235.879888) (xy 86.834187 -235.877907) (xy 86.785968 -235.868063)
			(xy 86.739952 -235.850611) (xy 86.697331 -235.826004) (xy 86.65921 -235.794879) (xy 86.626575 -235.758042)
			(xy 86.600272 -235.716446) (xy 86.580981 -235.67117) (xy 86.569204 -235.623386) (xy 86.565244 -235.574332)
			(xy 86.246716 -235.574332) (xy 86.246204 -235.599778) (xy 86.23804 -235.650012) (xy 86.221924 -235.698286)
			(xy 86.198273 -235.743349) (xy 86.1677 -235.784035) (xy 86.130996 -235.81929) (xy 86.089112 -235.8482)
			(xy 86.043133 -235.870017) (xy 85.994249 -235.884177) (xy 85.943728 -235.890311) (xy 85.892876 -235.888262)
			(xy 85.843012 -235.878082) (xy 85.795426 -235.860035) (xy 85.751352 -235.834589) (xy 85.71193 -235.802402)
			(xy 85.678182 -235.764308) (xy 85.650981 -235.721294) (xy 85.631033 -235.674474) (xy 85.618854 -235.62506)
			(xy 85.614759 -235.574332) (xy 85.296248 -235.574332) (xy 85.295753 -235.598939) (xy 85.287858 -235.647516)
			(xy 85.272274 -235.694197) (xy 85.249403 -235.737774) (xy 85.219838 -235.777118) (xy 85.184345 -235.81121)
			(xy 85.143842 -235.839166) (xy 85.09938 -235.860264) (xy 85.052109 -235.873956) (xy 85.003254 -235.879888)
			(xy 84.954079 -235.877907) (xy 84.90586 -235.868063) (xy 84.859844 -235.850611) (xy 84.817223 -235.826004)
			(xy 84.779102 -235.794879) (xy 84.746467 -235.758042) (xy 84.720164 -235.716446) (xy 84.700873 -235.67117)
			(xy 84.689096 -235.623386) (xy 84.685136 -235.574332) (xy 84.366862 -235.574332) (xy 84.36635 -235.599778)
			(xy 84.358186 -235.650012) (xy 84.34207 -235.698286) (xy 84.318419 -235.743349) (xy 84.287846 -235.784035)
			(xy 84.251142 -235.81929) (xy 84.209258 -235.8482) (xy 84.163279 -235.870017) (xy 84.114395 -235.884177)
			(xy 84.063874 -235.890311) (xy 84.013022 -235.888262) (xy 83.963158 -235.878082) (xy 83.915572 -235.860035)
			(xy 83.871498 -235.834589) (xy 83.832076 -235.802402) (xy 83.798328 -235.764308) (xy 83.771127 -235.721294)
			(xy 83.751179 -235.674474) (xy 83.739 -235.62506) (xy 83.734905 -235.574332) (xy 83.416394 -235.574332)
			(xy 83.415899 -235.598939) (xy 83.408004 -235.647516) (xy 83.39242 -235.694197) (xy 83.369549 -235.737774)
			(xy 83.339984 -235.777118) (xy 83.304491 -235.81121) (xy 83.263988 -235.839166) (xy 83.219526 -235.860264)
			(xy 83.172255 -235.873956) (xy 83.1234 -235.879888) (xy 83.074225 -235.877907) (xy 83.026006 -235.868063)
			(xy 82.97999 -235.850611) (xy 82.937369 -235.826004) (xy 82.899248 -235.794879) (xy 82.866613 -235.758042)
			(xy 82.84031 -235.716446) (xy 82.821019 -235.67117) (xy 82.809242 -235.623386) (xy 82.805282 -235.574332)
			(xy 82.486754 -235.574332) (xy 82.486242 -235.599778) (xy 82.478078 -235.650012) (xy 82.461962 -235.698286)
			(xy 82.438311 -235.743349) (xy 82.407738 -235.784035) (xy 82.371034 -235.81929) (xy 82.32915 -235.8482)
			(xy 82.283171 -235.870017) (xy 82.234287 -235.884177) (xy 82.183766 -235.890311) (xy 82.132914 -235.888262)
			(xy 82.08305 -235.878082) (xy 82.035464 -235.860035) (xy 81.99139 -235.834589) (xy 81.951968 -235.802402)
			(xy 81.91822 -235.764308) (xy 81.891019 -235.721294) (xy 81.871071 -235.674474) (xy 81.858892 -235.62506)
			(xy 81.854797 -235.574332) (xy 81.5467 -235.574332) (xy 81.546188 -235.599778) (xy 81.538024 -235.650012)
			(xy 81.521908 -235.698286) (xy 81.498257 -235.743349) (xy 81.467684 -235.784035) (xy 81.43098 -235.81929)
			(xy 81.389096 -235.8482) (xy 81.343117 -235.870017) (xy 81.294233 -235.884177) (xy 81.243712 -235.890311)
			(xy 81.19286 -235.888262) (xy 81.142996 -235.878082) (xy 81.09541 -235.860035) (xy 81.051336 -235.834589)
			(xy 81.011914 -235.802402) (xy 80.978166 -235.764308) (xy 80.950965 -235.721294) (xy 80.931017 -235.674474)
			(xy 80.918838 -235.62506) (xy 80.914743 -235.574332) (xy 80.596486 -235.574332) (xy 80.595991 -235.598939)
			(xy 80.588096 -235.647516) (xy 80.572512 -235.694197) (xy 80.549641 -235.737774) (xy 80.520076 -235.777118)
			(xy 80.484583 -235.81121) (xy 80.44408 -235.839166) (xy 80.399618 -235.860264) (xy 80.352347 -235.873956)
			(xy 80.303492 -235.879888) (xy 80.254317 -235.877907) (xy 80.206098 -235.868063) (xy 80.160082 -235.850611)
			(xy 80.117461 -235.826004) (xy 80.07934 -235.794879) (xy 80.046705 -235.758042) (xy 80.020402 -235.716446)
			(xy 80.001111 -235.67117) (xy 79.989334 -235.623386) (xy 79.985374 -235.574332) (xy 78.716378 -235.574332)
			(xy 78.715883 -235.598939) (xy 78.707988 -235.647516) (xy 78.692404 -235.694197) (xy 78.669533 -235.737774)
			(xy 78.639968 -235.777118) (xy 78.604475 -235.81121) (xy 78.563972 -235.839166) (xy 78.51951 -235.860264)
			(xy 78.472239 -235.873956) (xy 78.423384 -235.879888) (xy 78.374209 -235.877907) (xy 78.32599 -235.868063)
			(xy 78.279974 -235.850611) (xy 78.237353 -235.826004) (xy 78.199232 -235.794879) (xy 78.166597 -235.758042)
			(xy 78.140294 -235.716446) (xy 78.121003 -235.67117) (xy 78.109226 -235.623386) (xy 78.105266 -235.574332)
			(xy 62.37732 -235.574332) (xy 62.37732 -236.650276) (xy 76.507098 -236.650276) (xy 76.511058 -236.601222)
			(xy 76.522835 -236.553438) (xy 76.542126 -236.508162) (xy 76.568429 -236.466566) (xy 76.601064 -236.429729)
			(xy 76.639185 -236.398604) (xy 76.681806 -236.373997) (xy 76.727822 -236.356545) (xy 76.776041 -236.346701)
			(xy 76.825216 -236.34472) (xy 76.874071 -236.350652) (xy 76.921342 -236.364344) (xy 76.963477 -236.384338)
			(xy 79.51522 -236.384338) (xy 79.51918 -236.335284) (xy 79.530957 -236.2875) (xy 79.550248 -236.242224)
			(xy 79.576551 -236.200628) (xy 79.609186 -236.163791) (xy 79.647307 -236.132666) (xy 79.689928 -236.108059)
			(xy 79.735944 -236.090607) (xy 79.784163 -236.080763) (xy 79.833338 -236.078782) (xy 79.882193 -236.084714)
			(xy 79.929464 -236.098406) (xy 79.973926 -236.119504) (xy 80.014429 -236.14746) (xy 80.049922 -236.181552)
			(xy 80.079487 -236.220896) (xy 80.102358 -236.264473) (xy 80.117942 -236.311154) (xy 80.125837 -236.359731)
			(xy 80.126332 -236.384338) (xy 80.444843 -236.384338) (xy 80.448938 -236.33361) (xy 80.461117 -236.284196)
			(xy 80.481065 -236.237376) (xy 80.508266 -236.194362) (xy 80.542014 -236.156268) (xy 80.581436 -236.124081)
			(xy 80.62551 -236.098635) (xy 80.673096 -236.080588) (xy 80.72296 -236.070408) (xy 80.773812 -236.068359)
			(xy 80.824333 -236.074493) (xy 80.873217 -236.088653) (xy 80.919196 -236.11047) (xy 80.96108 -236.13938)
			(xy 80.997784 -236.174635) (xy 81.028357 -236.215321) (xy 81.052008 -236.260384) (xy 81.068124 -236.308658)
			(xy 81.076288 -236.358892) (xy 81.0768 -236.384338) (xy 81.395328 -236.384338) (xy 81.399288 -236.335284)
			(xy 81.411065 -236.2875) (xy 81.430356 -236.242224) (xy 81.456659 -236.200628) (xy 81.489294 -236.163791)
			(xy 81.527415 -236.132666) (xy 81.570036 -236.108059) (xy 81.616052 -236.090607) (xy 81.664271 -236.080763)
			(xy 81.713446 -236.078782) (xy 81.762301 -236.084714) (xy 81.809572 -236.098406) (xy 81.854034 -236.119504)
			(xy 81.894537 -236.14746) (xy 81.93003 -236.181552) (xy 81.959595 -236.220896) (xy 81.982466 -236.264473)
			(xy 81.99805 -236.311154) (xy 82.005945 -236.359731) (xy 82.00644 -236.384338) (xy 82.324697 -236.384338)
			(xy 82.328792 -236.33361) (xy 82.340971 -236.284196) (xy 82.360919 -236.237376) (xy 82.38812 -236.194362)
			(xy 82.421868 -236.156268) (xy 82.46129 -236.124081) (xy 82.505364 -236.098635) (xy 82.55295 -236.080588)
			(xy 82.602814 -236.070408) (xy 82.653666 -236.068359) (xy 82.704187 -236.074493) (xy 82.753071 -236.088653)
			(xy 82.79905 -236.11047) (xy 82.840934 -236.13938) (xy 82.877638 -236.174635) (xy 82.908211 -236.215321)
			(xy 82.931862 -236.260384) (xy 82.947978 -236.308658) (xy 82.956142 -236.358892) (xy 82.956654 -236.384338)
			(xy 83.275182 -236.384338) (xy 83.279142 -236.335284) (xy 83.290919 -236.2875) (xy 83.31021 -236.242224)
			(xy 83.336513 -236.200628) (xy 83.369148 -236.163791) (xy 83.407269 -236.132666) (xy 83.44989 -236.108059)
			(xy 83.495906 -236.090607) (xy 83.544125 -236.080763) (xy 83.5933 -236.078782) (xy 83.642155 -236.084714)
			(xy 83.689426 -236.098406) (xy 83.733888 -236.119504) (xy 83.774391 -236.14746) (xy 83.809884 -236.181552)
			(xy 83.839449 -236.220896) (xy 83.86232 -236.264473) (xy 83.877904 -236.311154) (xy 83.885799 -236.359731)
			(xy 83.886294 -236.384338) (xy 84.204805 -236.384338) (xy 84.2089 -236.33361) (xy 84.221079 -236.284196)
			(xy 84.241027 -236.237376) (xy 84.268228 -236.194362) (xy 84.301976 -236.156268) (xy 84.341398 -236.124081)
			(xy 84.385472 -236.098635) (xy 84.433058 -236.080588) (xy 84.482922 -236.070408) (xy 84.533774 -236.068359)
			(xy 84.584295 -236.074493) (xy 84.633179 -236.088653) (xy 84.679158 -236.11047) (xy 84.721042 -236.13938)
			(xy 84.757746 -236.174635) (xy 84.788319 -236.215321) (xy 84.81197 -236.260384) (xy 84.828086 -236.308658)
			(xy 84.83625 -236.358892) (xy 84.836762 -236.384338) (xy 85.144859 -236.384338) (xy 85.148954 -236.33361)
			(xy 85.161133 -236.284196) (xy 85.181081 -236.237376) (xy 85.208282 -236.194362) (xy 85.24203 -236.156268)
			(xy 85.281452 -236.124081) (xy 85.325526 -236.098635) (xy 85.373112 -236.080588) (xy 85.422976 -236.070408)
			(xy 85.473828 -236.068359) (xy 85.524349 -236.074493) (xy 85.573233 -236.088653) (xy 85.619212 -236.11047)
			(xy 85.661096 -236.13938) (xy 85.6978 -236.174635) (xy 85.728373 -236.215321) (xy 85.752024 -236.260384)
			(xy 85.76814 -236.308658) (xy 85.776304 -236.358892) (xy 85.776816 -236.384338) (xy 86.095344 -236.384338)
			(xy 86.099304 -236.335284) (xy 86.111081 -236.2875) (xy 86.130372 -236.242224) (xy 86.156675 -236.200628)
			(xy 86.18931 -236.163791) (xy 86.227431 -236.132666) (xy 86.270052 -236.108059) (xy 86.316068 -236.090607)
			(xy 86.364287 -236.080763) (xy 86.413462 -236.078782) (xy 86.462317 -236.084714) (xy 86.509588 -236.098406)
			(xy 86.55405 -236.119504) (xy 86.594553 -236.14746) (xy 86.630046 -236.181552) (xy 86.659611 -236.220896)
			(xy 86.682482 -236.264473) (xy 86.698066 -236.311154) (xy 86.705961 -236.359731) (xy 86.706456 -236.384338)
			(xy 87.024713 -236.384338) (xy 87.028808 -236.33361) (xy 87.040987 -236.284196) (xy 87.060935 -236.237376)
			(xy 87.088136 -236.194362) (xy 87.121884 -236.156268) (xy 87.161306 -236.124081) (xy 87.20538 -236.098635)
			(xy 87.252966 -236.080588) (xy 87.30283 -236.070408) (xy 87.353682 -236.068359) (xy 87.404203 -236.074493)
			(xy 87.453087 -236.088653) (xy 87.499066 -236.11047) (xy 87.54095 -236.13938) (xy 87.577654 -236.174635)
			(xy 87.608227 -236.215321) (xy 87.631878 -236.260384) (xy 87.647994 -236.308658) (xy 87.656158 -236.358892)
			(xy 87.65667 -236.384338) (xy 87.975198 -236.384338) (xy 87.979158 -236.335284) (xy 87.990935 -236.2875)
			(xy 88.010226 -236.242224) (xy 88.036529 -236.200628) (xy 88.069164 -236.163791) (xy 88.107285 -236.132666)
			(xy 88.149906 -236.108059) (xy 88.195922 -236.090607) (xy 88.244141 -236.080763) (xy 88.293316 -236.078782)
			(xy 88.342171 -236.084714) (xy 88.389442 -236.098406) (xy 88.433904 -236.119504) (xy 88.474407 -236.14746)
			(xy 88.5099 -236.181552) (xy 88.539465 -236.220896) (xy 88.562336 -236.264473) (xy 88.57792 -236.311154)
			(xy 88.585815 -236.359731) (xy 88.58631 -236.384338) (xy 88.904821 -236.384338) (xy 88.908916 -236.33361)
			(xy 88.921095 -236.284196) (xy 88.941043 -236.237376) (xy 88.968244 -236.194362) (xy 89.001992 -236.156268)
			(xy 89.041414 -236.124081) (xy 89.085488 -236.098635) (xy 89.133074 -236.080588) (xy 89.182938 -236.070408)
			(xy 89.23379 -236.068359) (xy 89.284311 -236.074493) (xy 89.333195 -236.088653) (xy 89.379174 -236.11047)
			(xy 89.421058 -236.13938) (xy 89.457762 -236.174635) (xy 89.488335 -236.215321) (xy 89.511986 -236.260384)
			(xy 89.528102 -236.308658) (xy 89.536266 -236.358892) (xy 89.536778 -236.384338) (xy 89.855306 -236.384338)
			(xy 89.859266 -236.335284) (xy 89.871043 -236.2875) (xy 89.890334 -236.242224) (xy 89.916637 -236.200628)
			(xy 89.949272 -236.163791) (xy 89.987393 -236.132666) (xy 90.030014 -236.108059) (xy 90.07603 -236.090607)
			(xy 90.124249 -236.080763) (xy 90.173424 -236.078782) (xy 90.222279 -236.084714) (xy 90.26955 -236.098406)
			(xy 90.314012 -236.119504) (xy 90.354515 -236.14746) (xy 90.390008 -236.181552) (xy 90.419573 -236.220896)
			(xy 90.442444 -236.264473) (xy 90.458028 -236.311154) (xy 90.465923 -236.359731) (xy 90.466418 -236.384338)
			(xy 90.784675 -236.384338) (xy 90.78877 -236.33361) (xy 90.800949 -236.284196) (xy 90.820897 -236.237376)
			(xy 90.848098 -236.194362) (xy 90.881846 -236.156268) (xy 90.921268 -236.124081) (xy 90.965342 -236.098635)
			(xy 91.012928 -236.080588) (xy 91.062792 -236.070408) (xy 91.113644 -236.068359) (xy 91.164165 -236.074493)
			(xy 91.213049 -236.088653) (xy 91.259028 -236.11047) (xy 91.300912 -236.13938) (xy 91.337616 -236.174635)
			(xy 91.368189 -236.215321) (xy 91.39184 -236.260384) (xy 91.407956 -236.308658) (xy 91.41612 -236.358892)
			(xy 91.416632 -236.384338) (xy 91.724729 -236.384338) (xy 91.728824 -236.33361) (xy 91.741003 -236.284196)
			(xy 91.760951 -236.237376) (xy 91.788152 -236.194362) (xy 91.8219 -236.156268) (xy 91.861322 -236.124081)
			(xy 91.905396 -236.098635) (xy 91.952982 -236.080588) (xy 92.002846 -236.070408) (xy 92.053698 -236.068359)
			(xy 92.104219 -236.074493) (xy 92.153103 -236.088653) (xy 92.199082 -236.11047) (xy 92.240966 -236.13938)
			(xy 92.27767 -236.174635) (xy 92.308243 -236.215321) (xy 92.331894 -236.260384) (xy 92.34801 -236.308658)
			(xy 92.356174 -236.358892) (xy 92.356686 -236.384338) (xy 92.675214 -236.384338) (xy 92.679174 -236.335284)
			(xy 92.690951 -236.2875) (xy 92.710242 -236.242224) (xy 92.736545 -236.200628) (xy 92.76918 -236.163791)
			(xy 92.807301 -236.132666) (xy 92.849922 -236.108059) (xy 92.895938 -236.090607) (xy 92.944157 -236.080763)
			(xy 92.993332 -236.078782) (xy 93.042187 -236.084714) (xy 93.089458 -236.098406) (xy 93.13392 -236.119504)
			(xy 93.174423 -236.14746) (xy 93.209916 -236.181552) (xy 93.239481 -236.220896) (xy 93.262352 -236.264473)
			(xy 93.277936 -236.311154) (xy 93.285831 -236.359731) (xy 93.286326 -236.384338) (xy 93.604837 -236.384338)
			(xy 93.608932 -236.33361) (xy 93.621111 -236.284196) (xy 93.641059 -236.237376) (xy 93.66826 -236.194362)
			(xy 93.702008 -236.156268) (xy 93.74143 -236.124081) (xy 93.785504 -236.098635) (xy 93.83309 -236.080588)
			(xy 93.882954 -236.070408) (xy 93.933806 -236.068359) (xy 93.984327 -236.074493) (xy 94.033211 -236.088653)
			(xy 94.07919 -236.11047) (xy 94.121074 -236.13938) (xy 94.157778 -236.174635) (xy 94.188351 -236.215321)
			(xy 94.212002 -236.260384) (xy 94.228118 -236.308658) (xy 94.236282 -236.358892) (xy 94.236794 -236.384338)
			(xy 94.555322 -236.384338) (xy 94.559282 -236.335284) (xy 94.571059 -236.2875) (xy 94.59035 -236.242224)
			(xy 94.616653 -236.200628) (xy 94.649288 -236.163791) (xy 94.687409 -236.132666) (xy 94.73003 -236.108059)
			(xy 94.776046 -236.090607) (xy 94.824265 -236.080763) (xy 94.87344 -236.078782) (xy 94.922295 -236.084714)
			(xy 94.969566 -236.098406) (xy 95.014028 -236.119504) (xy 95.054531 -236.14746) (xy 95.090024 -236.181552)
			(xy 95.119589 -236.220896) (xy 95.14246 -236.264473) (xy 95.158044 -236.311154) (xy 95.165939 -236.359731)
			(xy 95.166434 -236.384338) (xy 95.484691 -236.384338) (xy 95.488786 -236.33361) (xy 95.500965 -236.284196)
			(xy 95.520913 -236.237376) (xy 95.548114 -236.194362) (xy 95.581862 -236.156268) (xy 95.621284 -236.124081)
			(xy 95.665358 -236.098635) (xy 95.712944 -236.080588) (xy 95.762808 -236.070408) (xy 95.81366 -236.068359)
			(xy 95.864181 -236.074493) (xy 95.913065 -236.088653) (xy 95.959044 -236.11047) (xy 96.000928 -236.13938)
			(xy 96.037632 -236.174635) (xy 96.068205 -236.215321) (xy 96.091856 -236.260384) (xy 96.107972 -236.308658)
			(xy 96.116136 -236.358892) (xy 96.116648 -236.384338) (xy 96.435176 -236.384338) (xy 96.439136 -236.335284)
			(xy 96.450913 -236.2875) (xy 96.470204 -236.242224) (xy 96.496507 -236.200628) (xy 96.529142 -236.163791)
			(xy 96.567263 -236.132666) (xy 96.609884 -236.108059) (xy 96.6559 -236.090607) (xy 96.704119 -236.080763)
			(xy 96.753294 -236.078782) (xy 96.802149 -236.084714) (xy 96.84942 -236.098406) (xy 96.893882 -236.119504)
			(xy 96.934385 -236.14746) (xy 96.969878 -236.181552) (xy 96.999443 -236.220896) (xy 97.022314 -236.264473)
			(xy 97.037898 -236.311154) (xy 97.045793 -236.359731) (xy 97.046288 -236.384338) (xy 97.364799 -236.384338)
			(xy 97.368894 -236.33361) (xy 97.381073 -236.284196) (xy 97.401021 -236.237376) (xy 97.428222 -236.194362)
			(xy 97.46197 -236.156268) (xy 97.501392 -236.124081) (xy 97.545466 -236.098635) (xy 97.593052 -236.080588)
			(xy 97.642916 -236.070408) (xy 97.693768 -236.068359) (xy 97.744289 -236.074493) (xy 97.793173 -236.088653)
			(xy 97.839152 -236.11047) (xy 97.881036 -236.13938) (xy 97.91774 -236.174635) (xy 97.948313 -236.215321)
			(xy 97.971964 -236.260384) (xy 97.98808 -236.308658) (xy 97.996244 -236.358892) (xy 97.996756 -236.384338)
			(xy 98.304853 -236.384338) (xy 98.308948 -236.33361) (xy 98.321127 -236.284196) (xy 98.341075 -236.237376)
			(xy 98.368276 -236.194362) (xy 98.402024 -236.156268) (xy 98.441446 -236.124081) (xy 98.48552 -236.098635)
			(xy 98.533106 -236.080588) (xy 98.58297 -236.070408) (xy 98.633822 -236.068359) (xy 98.684343 -236.074493)
			(xy 98.733227 -236.088653) (xy 98.779206 -236.11047) (xy 98.82109 -236.13938) (xy 98.857794 -236.174635)
			(xy 98.888367 -236.215321) (xy 98.912018 -236.260384) (xy 98.928134 -236.308658) (xy 98.936298 -236.358892)
			(xy 98.93681 -236.384338) (xy 99.255338 -236.384338) (xy 99.259298 -236.335284) (xy 99.271075 -236.2875)
			(xy 99.290366 -236.242224) (xy 99.316669 -236.200628) (xy 99.349304 -236.163791) (xy 99.387425 -236.132666)
			(xy 99.430046 -236.108059) (xy 99.476062 -236.090607) (xy 99.524281 -236.080763) (xy 99.573456 -236.078782)
			(xy 99.622311 -236.084714) (xy 99.669582 -236.098406) (xy 99.714044 -236.119504) (xy 99.754547 -236.14746)
			(xy 99.79004 -236.181552) (xy 99.819605 -236.220896) (xy 99.842476 -236.264473) (xy 99.85806 -236.311154)
			(xy 99.865955 -236.359731) (xy 99.86645 -236.384338) (xy 100.184707 -236.384338) (xy 100.188802 -236.33361)
			(xy 100.200981 -236.284196) (xy 100.220929 -236.237376) (xy 100.24813 -236.194362) (xy 100.281878 -236.156268)
			(xy 100.3213 -236.124081) (xy 100.365374 -236.098635) (xy 100.41296 -236.080588) (xy 100.462824 -236.070408)
			(xy 100.513676 -236.068359) (xy 100.564197 -236.074493) (xy 100.613081 -236.088653) (xy 100.65906 -236.11047)
			(xy 100.700944 -236.13938) (xy 100.737648 -236.174635) (xy 100.768221 -236.215321) (xy 100.791872 -236.260384)
			(xy 100.807988 -236.308658) (xy 100.816152 -236.358892) (xy 100.816664 -236.384338) (xy 101.124761 -236.384338)
			(xy 101.128856 -236.33361) (xy 101.141035 -236.284196) (xy 101.160983 -236.237376) (xy 101.188184 -236.194362)
			(xy 101.221932 -236.156268) (xy 101.261354 -236.124081) (xy 101.305428 -236.098635) (xy 101.353014 -236.080588)
			(xy 101.402878 -236.070408) (xy 101.45373 -236.068359) (xy 101.504251 -236.074493) (xy 101.553135 -236.088653)
			(xy 101.599114 -236.11047) (xy 101.640998 -236.13938) (xy 101.677702 -236.174635) (xy 101.708275 -236.215321)
			(xy 101.731926 -236.260384) (xy 101.748042 -236.308658) (xy 101.756206 -236.358892) (xy 101.756718 -236.384338)
			(xy 102.075246 -236.384338) (xy 102.079206 -236.335284) (xy 102.090983 -236.2875) (xy 102.110274 -236.242224)
			(xy 102.136577 -236.200628) (xy 102.169212 -236.163791) (xy 102.207333 -236.132666) (xy 102.249954 -236.108059)
			(xy 102.29597 -236.090607) (xy 102.344189 -236.080763) (xy 102.393364 -236.078782) (xy 102.442219 -236.084714)
			(xy 102.48949 -236.098406) (xy 102.533952 -236.119504) (xy 102.574455 -236.14746) (xy 102.609948 -236.181552)
			(xy 102.639513 -236.220896) (xy 102.662384 -236.264473) (xy 102.677968 -236.311154) (xy 102.685863 -236.359731)
			(xy 102.686358 -236.384338) (xy 104.895154 -236.384338) (xy 104.899114 -236.335284) (xy 104.910891 -236.2875)
			(xy 104.930182 -236.242224) (xy 104.956485 -236.200628) (xy 104.98912 -236.163791) (xy 105.027241 -236.132666)
			(xy 105.069862 -236.108059) (xy 105.115878 -236.090607) (xy 105.164097 -236.080763) (xy 105.213272 -236.078782)
			(xy 105.262127 -236.084714) (xy 105.309398 -236.098406) (xy 105.35386 -236.119504) (xy 105.394363 -236.14746)
			(xy 105.429856 -236.181552) (xy 105.459421 -236.220896) (xy 105.482292 -236.264473) (xy 105.497876 -236.311154)
			(xy 105.505771 -236.359731) (xy 105.506266 -236.384338) (xy 107.715316 -236.384338) (xy 107.719276 -236.335284)
			(xy 107.731053 -236.2875) (xy 107.750344 -236.242224) (xy 107.776647 -236.200628) (xy 107.809282 -236.163791)
			(xy 107.847403 -236.132666) (xy 107.890024 -236.108059) (xy 107.93604 -236.090607) (xy 107.984259 -236.080763)
			(xy 108.033434 -236.078782) (xy 108.082289 -236.084714) (xy 108.12956 -236.098406) (xy 108.174022 -236.119504)
			(xy 108.214525 -236.14746) (xy 108.250018 -236.181552) (xy 108.279583 -236.220896) (xy 108.302454 -236.264473)
			(xy 108.318038 -236.311154) (xy 108.325933 -236.359731) (xy 108.326428 -236.384338) (xy 108.65537 -236.384338)
			(xy 108.65933 -236.335284) (xy 108.671107 -236.2875) (xy 108.690398 -236.242224) (xy 108.716701 -236.200628)
			(xy 108.749336 -236.163791) (xy 108.787457 -236.132666) (xy 108.830078 -236.108059) (xy 108.876094 -236.090607)
			(xy 108.924313 -236.080763) (xy 108.973488 -236.078782) (xy 109.022343 -236.084714) (xy 109.069614 -236.098406)
			(xy 109.114076 -236.119504) (xy 109.154579 -236.14746) (xy 109.190072 -236.181552) (xy 109.219637 -236.220896)
			(xy 109.242508 -236.264473) (xy 109.258092 -236.311154) (xy 109.265987 -236.359731) (xy 109.266482 -236.384338)
			(xy 109.59517 -236.384338) (xy 109.59913 -236.335284) (xy 109.610907 -236.2875) (xy 109.630198 -236.242224)
			(xy 109.656501 -236.200628) (xy 109.689136 -236.163791) (xy 109.727257 -236.132666) (xy 109.769878 -236.108059)
			(xy 109.815894 -236.090607) (xy 109.864113 -236.080763) (xy 109.913288 -236.078782) (xy 109.962143 -236.084714)
			(xy 110.009414 -236.098406) (xy 110.053876 -236.119504) (xy 110.094379 -236.14746) (xy 110.129872 -236.181552)
			(xy 110.159437 -236.220896) (xy 110.182308 -236.264473) (xy 110.197892 -236.311154) (xy 110.205787 -236.359731)
			(xy 110.206282 -236.384338) (xy 110.205787 -236.408945) (xy 110.197892 -236.457522) (xy 110.182308 -236.504203)
			(xy 110.159437 -236.54778) (xy 110.129872 -236.587124) (xy 110.094379 -236.621216) (xy 110.053876 -236.649172)
			(xy 110.009414 -236.67027) (xy 109.962143 -236.683962) (xy 109.913288 -236.689894) (xy 109.864113 -236.687913)
			(xy 109.815894 -236.678069) (xy 109.769878 -236.660617) (xy 109.727257 -236.63601) (xy 109.689136 -236.604885)
			(xy 109.656501 -236.568048) (xy 109.630198 -236.526452) (xy 109.610907 -236.481176) (xy 109.59913 -236.433392)
			(xy 109.59517 -236.384338) (xy 109.266482 -236.384338) (xy 109.265987 -236.408945) (xy 109.258092 -236.457522)
			(xy 109.242508 -236.504203) (xy 109.219637 -236.54778) (xy 109.190072 -236.587124) (xy 109.154579 -236.621216)
			(xy 109.114076 -236.649172) (xy 109.069614 -236.67027) (xy 109.022343 -236.683962) (xy 108.973488 -236.689894)
			(xy 108.924313 -236.687913) (xy 108.876094 -236.678069) (xy 108.830078 -236.660617) (xy 108.787457 -236.63601)
			(xy 108.749336 -236.604885) (xy 108.716701 -236.568048) (xy 108.690398 -236.526452) (xy 108.671107 -236.481176)
			(xy 108.65933 -236.433392) (xy 108.65537 -236.384338) (xy 108.326428 -236.384338) (xy 108.325933 -236.408945)
			(xy 108.318038 -236.457522) (xy 108.302454 -236.504203) (xy 108.279583 -236.54778) (xy 108.250018 -236.587124)
			(xy 108.214525 -236.621216) (xy 108.174022 -236.649172) (xy 108.12956 -236.67027) (xy 108.082289 -236.683962)
			(xy 108.033434 -236.689894) (xy 107.984259 -236.687913) (xy 107.93604 -236.678069) (xy 107.890024 -236.660617)
			(xy 107.847403 -236.63601) (xy 107.809282 -236.604885) (xy 107.776647 -236.568048) (xy 107.750344 -236.526452)
			(xy 107.731053 -236.481176) (xy 107.719276 -236.433392) (xy 107.715316 -236.384338) (xy 105.506266 -236.384338)
			(xy 105.505771 -236.408945) (xy 105.497876 -236.457522) (xy 105.482292 -236.504203) (xy 105.459421 -236.54778)
			(xy 105.429856 -236.587124) (xy 105.394363 -236.621216) (xy 105.35386 -236.649172) (xy 105.309398 -236.67027)
			(xy 105.262127 -236.683962) (xy 105.213272 -236.689894) (xy 105.164097 -236.687913) (xy 105.115878 -236.678069)
			(xy 105.069862 -236.660617) (xy 105.027241 -236.63601) (xy 104.98912 -236.604885) (xy 104.956485 -236.568048)
			(xy 104.930182 -236.526452) (xy 104.910891 -236.481176) (xy 104.899114 -236.433392) (xy 104.895154 -236.384338)
			(xy 102.686358 -236.384338) (xy 102.685863 -236.408945) (xy 102.677968 -236.457522) (xy 102.662384 -236.504203)
			(xy 102.639513 -236.54778) (xy 102.609948 -236.587124) (xy 102.574455 -236.621216) (xy 102.533952 -236.649172)
			(xy 102.48949 -236.67027) (xy 102.442219 -236.683962) (xy 102.393364 -236.689894) (xy 102.344189 -236.687913)
			(xy 102.29597 -236.678069) (xy 102.249954 -236.660617) (xy 102.207333 -236.63601) (xy 102.169212 -236.604885)
			(xy 102.136577 -236.568048) (xy 102.110274 -236.526452) (xy 102.090983 -236.481176) (xy 102.079206 -236.433392)
			(xy 102.075246 -236.384338) (xy 101.756718 -236.384338) (xy 101.756206 -236.409784) (xy 101.748042 -236.460018)
			(xy 101.731926 -236.508292) (xy 101.708275 -236.553355) (xy 101.677702 -236.594041) (xy 101.640998 -236.629296)
			(xy 101.599114 -236.658206) (xy 101.553135 -236.680023) (xy 101.504251 -236.694183) (xy 101.45373 -236.700317)
			(xy 101.402878 -236.698268) (xy 101.353014 -236.688088) (xy 101.305428 -236.670041) (xy 101.261354 -236.644595)
			(xy 101.221932 -236.612408) (xy 101.188184 -236.574314) (xy 101.160983 -236.5313) (xy 101.141035 -236.48448)
			(xy 101.128856 -236.435066) (xy 101.124761 -236.384338) (xy 100.816664 -236.384338) (xy 100.816152 -236.409784)
			(xy 100.807988 -236.460018) (xy 100.791872 -236.508292) (xy 100.768221 -236.553355) (xy 100.737648 -236.594041)
			(xy 100.700944 -236.629296) (xy 100.65906 -236.658206) (xy 100.613081 -236.680023) (xy 100.564197 -236.694183)
			(xy 100.513676 -236.700317) (xy 100.462824 -236.698268) (xy 100.41296 -236.688088) (xy 100.365374 -236.670041)
			(xy 100.3213 -236.644595) (xy 100.281878 -236.612408) (xy 100.24813 -236.574314) (xy 100.220929 -236.5313)
			(xy 100.200981 -236.48448) (xy 100.188802 -236.435066) (xy 100.184707 -236.384338) (xy 99.86645 -236.384338)
			(xy 99.865955 -236.408945) (xy 99.85806 -236.457522) (xy 99.842476 -236.504203) (xy 99.819605 -236.54778)
			(xy 99.79004 -236.587124) (xy 99.754547 -236.621216) (xy 99.714044 -236.649172) (xy 99.669582 -236.67027)
			(xy 99.622311 -236.683962) (xy 99.573456 -236.689894) (xy 99.524281 -236.687913) (xy 99.476062 -236.678069)
			(xy 99.430046 -236.660617) (xy 99.387425 -236.63601) (xy 99.349304 -236.604885) (xy 99.316669 -236.568048)
			(xy 99.290366 -236.526452) (xy 99.271075 -236.481176) (xy 99.259298 -236.433392) (xy 99.255338 -236.384338)
			(xy 98.93681 -236.384338) (xy 98.936298 -236.409784) (xy 98.928134 -236.460018) (xy 98.912018 -236.508292)
			(xy 98.888367 -236.553355) (xy 98.857794 -236.594041) (xy 98.82109 -236.629296) (xy 98.779206 -236.658206)
			(xy 98.733227 -236.680023) (xy 98.684343 -236.694183) (xy 98.633822 -236.700317) (xy 98.58297 -236.698268)
			(xy 98.533106 -236.688088) (xy 98.48552 -236.670041) (xy 98.441446 -236.644595) (xy 98.402024 -236.612408)
			(xy 98.368276 -236.574314) (xy 98.341075 -236.5313) (xy 98.321127 -236.48448) (xy 98.308948 -236.435066)
			(xy 98.304853 -236.384338) (xy 97.996756 -236.384338) (xy 97.996244 -236.409784) (xy 97.98808 -236.460018)
			(xy 97.971964 -236.508292) (xy 97.948313 -236.553355) (xy 97.91774 -236.594041) (xy 97.881036 -236.629296)
			(xy 97.839152 -236.658206) (xy 97.793173 -236.680023) (xy 97.744289 -236.694183) (xy 97.693768 -236.700317)
			(xy 97.642916 -236.698268) (xy 97.593052 -236.688088) (xy 97.545466 -236.670041) (xy 97.501392 -236.644595)
			(xy 97.46197 -236.612408) (xy 97.428222 -236.574314) (xy 97.401021 -236.5313) (xy 97.381073 -236.48448)
			(xy 97.368894 -236.435066) (xy 97.364799 -236.384338) (xy 97.046288 -236.384338) (xy 97.045793 -236.408945)
			(xy 97.037898 -236.457522) (xy 97.022314 -236.504203) (xy 96.999443 -236.54778) (xy 96.969878 -236.587124)
			(xy 96.934385 -236.621216) (xy 96.893882 -236.649172) (xy 96.84942 -236.67027) (xy 96.802149 -236.683962)
			(xy 96.753294 -236.689894) (xy 96.704119 -236.687913) (xy 96.6559 -236.678069) (xy 96.609884 -236.660617)
			(xy 96.567263 -236.63601) (xy 96.529142 -236.604885) (xy 96.496507 -236.568048) (xy 96.470204 -236.526452)
			(xy 96.450913 -236.481176) (xy 96.439136 -236.433392) (xy 96.435176 -236.384338) (xy 96.116648 -236.384338)
			(xy 96.116136 -236.409784) (xy 96.107972 -236.460018) (xy 96.091856 -236.508292) (xy 96.068205 -236.553355)
			(xy 96.037632 -236.594041) (xy 96.000928 -236.629296) (xy 95.959044 -236.658206) (xy 95.913065 -236.680023)
			(xy 95.864181 -236.694183) (xy 95.81366 -236.700317) (xy 95.762808 -236.698268) (xy 95.712944 -236.688088)
			(xy 95.665358 -236.670041) (xy 95.621284 -236.644595) (xy 95.581862 -236.612408) (xy 95.548114 -236.574314)
			(xy 95.520913 -236.5313) (xy 95.500965 -236.48448) (xy 95.488786 -236.435066) (xy 95.484691 -236.384338)
			(xy 95.166434 -236.384338) (xy 95.165939 -236.408945) (xy 95.158044 -236.457522) (xy 95.14246 -236.504203)
			(xy 95.119589 -236.54778) (xy 95.090024 -236.587124) (xy 95.054531 -236.621216) (xy 95.014028 -236.649172)
			(xy 94.969566 -236.67027) (xy 94.922295 -236.683962) (xy 94.87344 -236.689894) (xy 94.824265 -236.687913)
			(xy 94.776046 -236.678069) (xy 94.73003 -236.660617) (xy 94.687409 -236.63601) (xy 94.649288 -236.604885)
			(xy 94.616653 -236.568048) (xy 94.59035 -236.526452) (xy 94.571059 -236.481176) (xy 94.559282 -236.433392)
			(xy 94.555322 -236.384338) (xy 94.236794 -236.384338) (xy 94.236282 -236.409784) (xy 94.228118 -236.460018)
			(xy 94.212002 -236.508292) (xy 94.188351 -236.553355) (xy 94.157778 -236.594041) (xy 94.121074 -236.629296)
			(xy 94.07919 -236.658206) (xy 94.033211 -236.680023) (xy 93.984327 -236.694183) (xy 93.933806 -236.700317)
			(xy 93.882954 -236.698268) (xy 93.83309 -236.688088) (xy 93.785504 -236.670041) (xy 93.74143 -236.644595)
			(xy 93.702008 -236.612408) (xy 93.66826 -236.574314) (xy 93.641059 -236.5313) (xy 93.621111 -236.48448)
			(xy 93.608932 -236.435066) (xy 93.604837 -236.384338) (xy 93.286326 -236.384338) (xy 93.285831 -236.408945)
			(xy 93.277936 -236.457522) (xy 93.262352 -236.504203) (xy 93.239481 -236.54778) (xy 93.209916 -236.587124)
			(xy 93.174423 -236.621216) (xy 93.13392 -236.649172) (xy 93.089458 -236.67027) (xy 93.042187 -236.683962)
			(xy 92.993332 -236.689894) (xy 92.944157 -236.687913) (xy 92.895938 -236.678069) (xy 92.849922 -236.660617)
			(xy 92.807301 -236.63601) (xy 92.76918 -236.604885) (xy 92.736545 -236.568048) (xy 92.710242 -236.526452)
			(xy 92.690951 -236.481176) (xy 92.679174 -236.433392) (xy 92.675214 -236.384338) (xy 92.356686 -236.384338)
			(xy 92.356174 -236.409784) (xy 92.34801 -236.460018) (xy 92.331894 -236.508292) (xy 92.308243 -236.553355)
			(xy 92.27767 -236.594041) (xy 92.240966 -236.629296) (xy 92.199082 -236.658206) (xy 92.153103 -236.680023)
			(xy 92.104219 -236.694183) (xy 92.053698 -236.700317) (xy 92.002846 -236.698268) (xy 91.952982 -236.688088)
			(xy 91.905396 -236.670041) (xy 91.861322 -236.644595) (xy 91.8219 -236.612408) (xy 91.788152 -236.574314)
			(xy 91.760951 -236.5313) (xy 91.741003 -236.48448) (xy 91.728824 -236.435066) (xy 91.724729 -236.384338)
			(xy 91.416632 -236.384338) (xy 91.41612 -236.409784) (xy 91.407956 -236.460018) (xy 91.39184 -236.508292)
			(xy 91.368189 -236.553355) (xy 91.337616 -236.594041) (xy 91.300912 -236.629296) (xy 91.259028 -236.658206)
			(xy 91.213049 -236.680023) (xy 91.164165 -236.694183) (xy 91.113644 -236.700317) (xy 91.062792 -236.698268)
			(xy 91.012928 -236.688088) (xy 90.965342 -236.670041) (xy 90.921268 -236.644595) (xy 90.881846 -236.612408)
			(xy 90.848098 -236.574314) (xy 90.820897 -236.5313) (xy 90.800949 -236.48448) (xy 90.78877 -236.435066)
			(xy 90.784675 -236.384338) (xy 90.466418 -236.384338) (xy 90.465923 -236.408945) (xy 90.458028 -236.457522)
			(xy 90.442444 -236.504203) (xy 90.419573 -236.54778) (xy 90.390008 -236.587124) (xy 90.354515 -236.621216)
			(xy 90.314012 -236.649172) (xy 90.26955 -236.67027) (xy 90.222279 -236.683962) (xy 90.173424 -236.689894)
			(xy 90.124249 -236.687913) (xy 90.07603 -236.678069) (xy 90.030014 -236.660617) (xy 89.987393 -236.63601)
			(xy 89.949272 -236.604885) (xy 89.916637 -236.568048) (xy 89.890334 -236.526452) (xy 89.871043 -236.481176)
			(xy 89.859266 -236.433392) (xy 89.855306 -236.384338) (xy 89.536778 -236.384338) (xy 89.536266 -236.409784)
			(xy 89.528102 -236.460018) (xy 89.511986 -236.508292) (xy 89.488335 -236.553355) (xy 89.457762 -236.594041)
			(xy 89.421058 -236.629296) (xy 89.379174 -236.658206) (xy 89.333195 -236.680023) (xy 89.284311 -236.694183)
			(xy 89.23379 -236.700317) (xy 89.182938 -236.698268) (xy 89.133074 -236.688088) (xy 89.085488 -236.670041)
			(xy 89.041414 -236.644595) (xy 89.001992 -236.612408) (xy 88.968244 -236.574314) (xy 88.941043 -236.5313)
			(xy 88.921095 -236.48448) (xy 88.908916 -236.435066) (xy 88.904821 -236.384338) (xy 88.58631 -236.384338)
			(xy 88.585815 -236.408945) (xy 88.57792 -236.457522) (xy 88.562336 -236.504203) (xy 88.539465 -236.54778)
			(xy 88.5099 -236.587124) (xy 88.474407 -236.621216) (xy 88.433904 -236.649172) (xy 88.389442 -236.67027)
			(xy 88.342171 -236.683962) (xy 88.293316 -236.689894) (xy 88.244141 -236.687913) (xy 88.195922 -236.678069)
			(xy 88.149906 -236.660617) (xy 88.107285 -236.63601) (xy 88.069164 -236.604885) (xy 88.036529 -236.568048)
			(xy 88.010226 -236.526452) (xy 87.990935 -236.481176) (xy 87.979158 -236.433392) (xy 87.975198 -236.384338)
			(xy 87.65667 -236.384338) (xy 87.656158 -236.409784) (xy 87.647994 -236.460018) (xy 87.631878 -236.508292)
			(xy 87.608227 -236.553355) (xy 87.577654 -236.594041) (xy 87.54095 -236.629296) (xy 87.499066 -236.658206)
			(xy 87.453087 -236.680023) (xy 87.404203 -236.694183) (xy 87.353682 -236.700317) (xy 87.30283 -236.698268)
			(xy 87.252966 -236.688088) (xy 87.20538 -236.670041) (xy 87.161306 -236.644595) (xy 87.121884 -236.612408)
			(xy 87.088136 -236.574314) (xy 87.060935 -236.5313) (xy 87.040987 -236.48448) (xy 87.028808 -236.435066)
			(xy 87.024713 -236.384338) (xy 86.706456 -236.384338) (xy 86.705961 -236.408945) (xy 86.698066 -236.457522)
			(xy 86.682482 -236.504203) (xy 86.659611 -236.54778) (xy 86.630046 -236.587124) (xy 86.594553 -236.621216)
			(xy 86.55405 -236.649172) (xy 86.509588 -236.67027) (xy 86.462317 -236.683962) (xy 86.413462 -236.689894)
			(xy 86.364287 -236.687913) (xy 86.316068 -236.678069) (xy 86.270052 -236.660617) (xy 86.227431 -236.63601)
			(xy 86.18931 -236.604885) (xy 86.156675 -236.568048) (xy 86.130372 -236.526452) (xy 86.111081 -236.481176)
			(xy 86.099304 -236.433392) (xy 86.095344 -236.384338) (xy 85.776816 -236.384338) (xy 85.776304 -236.409784)
			(xy 85.76814 -236.460018) (xy 85.752024 -236.508292) (xy 85.728373 -236.553355) (xy 85.6978 -236.594041)
			(xy 85.661096 -236.629296) (xy 85.619212 -236.658206) (xy 85.573233 -236.680023) (xy 85.524349 -236.694183)
			(xy 85.473828 -236.700317) (xy 85.422976 -236.698268) (xy 85.373112 -236.688088) (xy 85.325526 -236.670041)
			(xy 85.281452 -236.644595) (xy 85.24203 -236.612408) (xy 85.208282 -236.574314) (xy 85.181081 -236.5313)
			(xy 85.161133 -236.48448) (xy 85.148954 -236.435066) (xy 85.144859 -236.384338) (xy 84.836762 -236.384338)
			(xy 84.83625 -236.409784) (xy 84.828086 -236.460018) (xy 84.81197 -236.508292) (xy 84.788319 -236.553355)
			(xy 84.757746 -236.594041) (xy 84.721042 -236.629296) (xy 84.679158 -236.658206) (xy 84.633179 -236.680023)
			(xy 84.584295 -236.694183) (xy 84.533774 -236.700317) (xy 84.482922 -236.698268) (xy 84.433058 -236.688088)
			(xy 84.385472 -236.670041) (xy 84.341398 -236.644595) (xy 84.301976 -236.612408) (xy 84.268228 -236.574314)
			(xy 84.241027 -236.5313) (xy 84.221079 -236.48448) (xy 84.2089 -236.435066) (xy 84.204805 -236.384338)
			(xy 83.886294 -236.384338) (xy 83.885799 -236.408945) (xy 83.877904 -236.457522) (xy 83.86232 -236.504203)
			(xy 83.839449 -236.54778) (xy 83.809884 -236.587124) (xy 83.774391 -236.621216) (xy 83.733888 -236.649172)
			(xy 83.689426 -236.67027) (xy 83.642155 -236.683962) (xy 83.5933 -236.689894) (xy 83.544125 -236.687913)
			(xy 83.495906 -236.678069) (xy 83.44989 -236.660617) (xy 83.407269 -236.63601) (xy 83.369148 -236.604885)
			(xy 83.336513 -236.568048) (xy 83.31021 -236.526452) (xy 83.290919 -236.481176) (xy 83.279142 -236.433392)
			(xy 83.275182 -236.384338) (xy 82.956654 -236.384338) (xy 82.956142 -236.409784) (xy 82.947978 -236.460018)
			(xy 82.931862 -236.508292) (xy 82.908211 -236.553355) (xy 82.877638 -236.594041) (xy 82.840934 -236.629296)
			(xy 82.79905 -236.658206) (xy 82.753071 -236.680023) (xy 82.704187 -236.694183) (xy 82.653666 -236.700317)
			(xy 82.602814 -236.698268) (xy 82.55295 -236.688088) (xy 82.505364 -236.670041) (xy 82.46129 -236.644595)
			(xy 82.421868 -236.612408) (xy 82.38812 -236.574314) (xy 82.360919 -236.5313) (xy 82.340971 -236.48448)
			(xy 82.328792 -236.435066) (xy 82.324697 -236.384338) (xy 82.00644 -236.384338) (xy 82.005945 -236.408945)
			(xy 81.99805 -236.457522) (xy 81.982466 -236.504203) (xy 81.959595 -236.54778) (xy 81.93003 -236.587124)
			(xy 81.894537 -236.621216) (xy 81.854034 -236.649172) (xy 81.809572 -236.67027) (xy 81.762301 -236.683962)
			(xy 81.713446 -236.689894) (xy 81.664271 -236.687913) (xy 81.616052 -236.678069) (xy 81.570036 -236.660617)
			(xy 81.527415 -236.63601) (xy 81.489294 -236.604885) (xy 81.456659 -236.568048) (xy 81.430356 -236.526452)
			(xy 81.411065 -236.481176) (xy 81.399288 -236.433392) (xy 81.395328 -236.384338) (xy 81.0768 -236.384338)
			(xy 81.076288 -236.409784) (xy 81.068124 -236.460018) (xy 81.052008 -236.508292) (xy 81.028357 -236.553355)
			(xy 80.997784 -236.594041) (xy 80.96108 -236.629296) (xy 80.919196 -236.658206) (xy 80.873217 -236.680023)
			(xy 80.824333 -236.694183) (xy 80.773812 -236.700317) (xy 80.72296 -236.698268) (xy 80.673096 -236.688088)
			(xy 80.62551 -236.670041) (xy 80.581436 -236.644595) (xy 80.542014 -236.612408) (xy 80.508266 -236.574314)
			(xy 80.481065 -236.5313) (xy 80.461117 -236.48448) (xy 80.448938 -236.435066) (xy 80.444843 -236.384338)
			(xy 80.126332 -236.384338) (xy 80.125837 -236.408945) (xy 80.117942 -236.457522) (xy 80.102358 -236.504203)
			(xy 80.079487 -236.54778) (xy 80.049922 -236.587124) (xy 80.014429 -236.621216) (xy 79.973926 -236.649172)
			(xy 79.929464 -236.67027) (xy 79.882193 -236.683962) (xy 79.833338 -236.689894) (xy 79.784163 -236.687913)
			(xy 79.735944 -236.678069) (xy 79.689928 -236.660617) (xy 79.647307 -236.63601) (xy 79.609186 -236.604885)
			(xy 79.576551 -236.568048) (xy 79.550248 -236.526452) (xy 79.530957 -236.481176) (xy 79.51918 -236.433392)
			(xy 79.51522 -236.384338) (xy 76.963477 -236.384338) (xy 76.965804 -236.385442) (xy 77.006307 -236.413398)
			(xy 77.0418 -236.44749) (xy 77.071365 -236.486834) (xy 77.094236 -236.530411) (xy 77.10982 -236.577092)
			(xy 77.117715 -236.625669) (xy 77.11821 -236.650276) (xy 77.117715 -236.674883) (xy 77.10982 -236.72346)
			(xy 77.094236 -236.770141) (xy 77.071365 -236.813718) (xy 77.0418 -236.853062) (xy 77.006307 -236.887154)
			(xy 76.965804 -236.91511) (xy 76.921342 -236.936208) (xy 76.874071 -236.9499) (xy 76.825216 -236.955832)
			(xy 76.776041 -236.953851) (xy 76.727822 -236.944007) (xy 76.681806 -236.926555) (xy 76.639185 -236.901948)
			(xy 76.601064 -236.870823) (xy 76.568429 -236.833986) (xy 76.542126 -236.79239) (xy 76.522835 -236.747114)
			(xy 76.511058 -236.69933) (xy 76.507098 -236.650276) (xy 62.37732 -236.650276) (xy 62.37732 -237.194344)
			(xy 78.105266 -237.194344) (xy 78.109226 -237.14529) (xy 78.121003 -237.097506) (xy 78.140294 -237.05223)
			(xy 78.166597 -237.010634) (xy 78.199232 -236.973797) (xy 78.237353 -236.942672) (xy 78.279974 -236.918065)
			(xy 78.32599 -236.900613) (xy 78.374209 -236.890769) (xy 78.423384 -236.888788) (xy 78.472239 -236.89472)
			(xy 78.51951 -236.908412) (xy 78.563972 -236.92951) (xy 78.604475 -236.957466) (xy 78.639968 -236.991558)
			(xy 78.669533 -237.030902) (xy 78.692404 -237.074479) (xy 78.707988 -237.12116) (xy 78.715883 -237.169737)
			(xy 78.716378 -237.194344) (xy 79.985374 -237.194344) (xy 79.989334 -237.14529) (xy 80.001111 -237.097506)
			(xy 80.020402 -237.05223) (xy 80.046705 -237.010634) (xy 80.07934 -236.973797) (xy 80.117461 -236.942672)
			(xy 80.160082 -236.918065) (xy 80.206098 -236.900613) (xy 80.254317 -236.890769) (xy 80.303492 -236.888788)
			(xy 80.352347 -236.89472) (xy 80.399618 -236.908412) (xy 80.44408 -236.92951) (xy 80.484583 -236.957466)
			(xy 80.520076 -236.991558) (xy 80.549641 -237.030902) (xy 80.572512 -237.074479) (xy 80.588096 -237.12116)
			(xy 80.595991 -237.169737) (xy 80.596486 -237.194344) (xy 80.914743 -237.194344) (xy 80.918838 -237.143616)
			(xy 80.931017 -237.094202) (xy 80.950965 -237.047382) (xy 80.978166 -237.004368) (xy 81.011914 -236.966274)
			(xy 81.051336 -236.934087) (xy 81.09541 -236.908641) (xy 81.142996 -236.890594) (xy 81.19286 -236.880414)
			(xy 81.243712 -236.878365) (xy 81.294233 -236.884499) (xy 81.343117 -236.898659) (xy 81.389096 -236.920476)
			(xy 81.43098 -236.949386) (xy 81.467684 -236.984641) (xy 81.498257 -237.025327) (xy 81.521908 -237.07039)
			(xy 81.538024 -237.118664) (xy 81.546188 -237.168898) (xy 81.5467 -237.194344) (xy 81.854797 -237.194344)
			(xy 81.858892 -237.143616) (xy 81.871071 -237.094202) (xy 81.891019 -237.047382) (xy 81.91822 -237.004368)
			(xy 81.951968 -236.966274) (xy 81.99139 -236.934087) (xy 82.035464 -236.908641) (xy 82.08305 -236.890594)
			(xy 82.132914 -236.880414) (xy 82.183766 -236.878365) (xy 82.234287 -236.884499) (xy 82.283171 -236.898659)
			(xy 82.32915 -236.920476) (xy 82.371034 -236.949386) (xy 82.407738 -236.984641) (xy 82.438311 -237.025327)
			(xy 82.461962 -237.07039) (xy 82.478078 -237.118664) (xy 82.486242 -237.168898) (xy 82.486754 -237.194344)
			(xy 82.805282 -237.194344) (xy 82.809242 -237.14529) (xy 82.821019 -237.097506) (xy 82.84031 -237.05223)
			(xy 82.866613 -237.010634) (xy 82.899248 -236.973797) (xy 82.937369 -236.942672) (xy 82.97999 -236.918065)
			(xy 83.026006 -236.900613) (xy 83.074225 -236.890769) (xy 83.1234 -236.888788) (xy 83.172255 -236.89472)
			(xy 83.219526 -236.908412) (xy 83.263988 -236.92951) (xy 83.304491 -236.957466) (xy 83.339984 -236.991558)
			(xy 83.369549 -237.030902) (xy 83.39242 -237.074479) (xy 83.408004 -237.12116) (xy 83.415899 -237.169737)
			(xy 83.416394 -237.194344) (xy 83.734905 -237.194344) (xy 83.739 -237.143616) (xy 83.751179 -237.094202)
			(xy 83.771127 -237.047382) (xy 83.798328 -237.004368) (xy 83.832076 -236.966274) (xy 83.871498 -236.934087)
			(xy 83.915572 -236.908641) (xy 83.963158 -236.890594) (xy 84.013022 -236.880414) (xy 84.063874 -236.878365)
			(xy 84.114395 -236.884499) (xy 84.163279 -236.898659) (xy 84.209258 -236.920476) (xy 84.251142 -236.949386)
			(xy 84.287846 -236.984641) (xy 84.318419 -237.025327) (xy 84.34207 -237.07039) (xy 84.358186 -237.118664)
			(xy 84.36635 -237.168898) (xy 84.366862 -237.194344) (xy 84.685136 -237.194344) (xy 84.689096 -237.14529)
			(xy 84.700873 -237.097506) (xy 84.720164 -237.05223) (xy 84.746467 -237.010634) (xy 84.779102 -236.973797)
			(xy 84.817223 -236.942672) (xy 84.859844 -236.918065) (xy 84.90586 -236.900613) (xy 84.954079 -236.890769)
			(xy 85.003254 -236.888788) (xy 85.052109 -236.89472) (xy 85.09938 -236.908412) (xy 85.143842 -236.92951)
			(xy 85.184345 -236.957466) (xy 85.219838 -236.991558) (xy 85.249403 -237.030902) (xy 85.272274 -237.074479)
			(xy 85.287858 -237.12116) (xy 85.295753 -237.169737) (xy 85.296248 -237.194344) (xy 85.614759 -237.194344)
			(xy 85.618854 -237.143616) (xy 85.631033 -237.094202) (xy 85.650981 -237.047382) (xy 85.678182 -237.004368)
			(xy 85.71193 -236.966274) (xy 85.751352 -236.934087) (xy 85.795426 -236.908641) (xy 85.843012 -236.890594)
			(xy 85.892876 -236.880414) (xy 85.943728 -236.878365) (xy 85.994249 -236.884499) (xy 86.043133 -236.898659)
			(xy 86.089112 -236.920476) (xy 86.130996 -236.949386) (xy 86.1677 -236.984641) (xy 86.198273 -237.025327)
			(xy 86.221924 -237.07039) (xy 86.23804 -237.118664) (xy 86.246204 -237.168898) (xy 86.246716 -237.194344)
			(xy 86.565244 -237.194344) (xy 86.569204 -237.14529) (xy 86.580981 -237.097506) (xy 86.600272 -237.05223)
			(xy 86.626575 -237.010634) (xy 86.65921 -236.973797) (xy 86.697331 -236.942672) (xy 86.739952 -236.918065)
			(xy 86.785968 -236.900613) (xy 86.834187 -236.890769) (xy 86.883362 -236.888788) (xy 86.932217 -236.89472)
			(xy 86.979488 -236.908412) (xy 87.02395 -236.92951) (xy 87.064453 -236.957466) (xy 87.099946 -236.991558)
			(xy 87.129511 -237.030902) (xy 87.152382 -237.074479) (xy 87.167966 -237.12116) (xy 87.175861 -237.169737)
			(xy 87.176356 -237.194344) (xy 87.494867 -237.194344) (xy 87.498962 -237.143616) (xy 87.511141 -237.094202)
			(xy 87.531089 -237.047382) (xy 87.55829 -237.004368) (xy 87.592038 -236.966274) (xy 87.63146 -236.934087)
			(xy 87.675534 -236.908641) (xy 87.72312 -236.890594) (xy 87.772984 -236.880414) (xy 87.823836 -236.878365)
			(xy 87.874357 -236.884499) (xy 87.923241 -236.898659) (xy 87.96922 -236.920476) (xy 88.011104 -236.949386)
			(xy 88.047808 -236.984641) (xy 88.078381 -237.025327) (xy 88.102032 -237.07039) (xy 88.118148 -237.118664)
			(xy 88.126312 -237.168898) (xy 88.126824 -237.194344) (xy 88.434921 -237.194344) (xy 88.439016 -237.143616)
			(xy 88.451195 -237.094202) (xy 88.471143 -237.047382) (xy 88.498344 -237.004368) (xy 88.532092 -236.966274)
			(xy 88.571514 -236.934087) (xy 88.615588 -236.908641) (xy 88.663174 -236.890594) (xy 88.713038 -236.880414)
			(xy 88.76389 -236.878365) (xy 88.814411 -236.884499) (xy 88.863295 -236.898659) (xy 88.909274 -236.920476)
			(xy 88.951158 -236.949386) (xy 88.987862 -236.984641) (xy 89.018435 -237.025327) (xy 89.042086 -237.07039)
			(xy 89.058202 -237.118664) (xy 89.066366 -237.168898) (xy 89.066878 -237.194344) (xy 89.385152 -237.194344)
			(xy 89.389112 -237.14529) (xy 89.400889 -237.097506) (xy 89.42018 -237.05223) (xy 89.446483 -237.010634)
			(xy 89.479118 -236.973797) (xy 89.517239 -236.942672) (xy 89.55986 -236.918065) (xy 89.605876 -236.900613)
			(xy 89.654095 -236.890769) (xy 89.70327 -236.888788) (xy 89.752125 -236.89472) (xy 89.799396 -236.908412)
			(xy 89.843858 -236.92951) (xy 89.884361 -236.957466) (xy 89.919854 -236.991558) (xy 89.949419 -237.030902)
			(xy 89.97229 -237.074479) (xy 89.987874 -237.12116) (xy 89.995769 -237.169737) (xy 89.996264 -237.194344)
			(xy 90.314775 -237.194344) (xy 90.31887 -237.143616) (xy 90.331049 -237.094202) (xy 90.350997 -237.047382)
			(xy 90.378198 -237.004368) (xy 90.411946 -236.966274) (xy 90.451368 -236.934087) (xy 90.495442 -236.908641)
			(xy 90.543028 -236.890594) (xy 90.592892 -236.880414) (xy 90.643744 -236.878365) (xy 90.694265 -236.884499)
			(xy 90.743149 -236.898659) (xy 90.789128 -236.920476) (xy 90.831012 -236.949386) (xy 90.867716 -236.984641)
			(xy 90.898289 -237.025327) (xy 90.92194 -237.07039) (xy 90.938056 -237.118664) (xy 90.94622 -237.168898)
			(xy 90.946732 -237.194344) (xy 91.26526 -237.194344) (xy 91.26922 -237.14529) (xy 91.280997 -237.097506)
			(xy 91.300288 -237.05223) (xy 91.326591 -237.010634) (xy 91.359226 -236.973797) (xy 91.397347 -236.942672)
			(xy 91.439968 -236.918065) (xy 91.485984 -236.900613) (xy 91.534203 -236.890769) (xy 91.583378 -236.888788)
			(xy 91.632233 -236.89472) (xy 91.679504 -236.908412) (xy 91.723966 -236.92951) (xy 91.764469 -236.957466)
			(xy 91.799962 -236.991558) (xy 91.829527 -237.030902) (xy 91.852398 -237.074479) (xy 91.867982 -237.12116)
			(xy 91.875877 -237.169737) (xy 91.876372 -237.194344) (xy 92.194883 -237.194344) (xy 92.198978 -237.143616)
			(xy 92.211157 -237.094202) (xy 92.231105 -237.047382) (xy 92.258306 -237.004368) (xy 92.292054 -236.966274)
			(xy 92.331476 -236.934087) (xy 92.37555 -236.908641) (xy 92.423136 -236.890594) (xy 92.473 -236.880414)
			(xy 92.523852 -236.878365) (xy 92.574373 -236.884499) (xy 92.623257 -236.898659) (xy 92.669236 -236.920476)
			(xy 92.71112 -236.949386) (xy 92.747824 -236.984641) (xy 92.778397 -237.025327) (xy 92.802048 -237.07039)
			(xy 92.818164 -237.118664) (xy 92.826328 -237.168898) (xy 92.82684 -237.194344) (xy 93.145114 -237.194344)
			(xy 93.149074 -237.14529) (xy 93.160851 -237.097506) (xy 93.180142 -237.05223) (xy 93.206445 -237.010634)
			(xy 93.23908 -236.973797) (xy 93.277201 -236.942672) (xy 93.319822 -236.918065) (xy 93.365838 -236.900613)
			(xy 93.414057 -236.890769) (xy 93.463232 -236.888788) (xy 93.512087 -236.89472) (xy 93.559358 -236.908412)
			(xy 93.60382 -236.92951) (xy 93.644323 -236.957466) (xy 93.679816 -236.991558) (xy 93.709381 -237.030902)
			(xy 93.732252 -237.074479) (xy 93.747836 -237.12116) (xy 93.755731 -237.169737) (xy 93.756226 -237.194344)
			(xy 94.074737 -237.194344) (xy 94.078832 -237.143616) (xy 94.091011 -237.094202) (xy 94.110959 -237.047382)
			(xy 94.13816 -237.004368) (xy 94.171908 -236.966274) (xy 94.21133 -236.934087) (xy 94.255404 -236.908641)
			(xy 94.30299 -236.890594) (xy 94.352854 -236.880414) (xy 94.403706 -236.878365) (xy 94.454227 -236.884499)
			(xy 94.503111 -236.898659) (xy 94.54909 -236.920476) (xy 94.590974 -236.949386) (xy 94.627678 -236.984641)
			(xy 94.658251 -237.025327) (xy 94.681902 -237.07039) (xy 94.698018 -237.118664) (xy 94.706182 -237.168898)
			(xy 94.706694 -237.194344) (xy 95.014791 -237.194344) (xy 95.018886 -237.143616) (xy 95.031065 -237.094202)
			(xy 95.051013 -237.047382) (xy 95.078214 -237.004368) (xy 95.111962 -236.966274) (xy 95.151384 -236.934087)
			(xy 95.195458 -236.908641) (xy 95.243044 -236.890594) (xy 95.292908 -236.880414) (xy 95.34376 -236.878365)
			(xy 95.394281 -236.884499) (xy 95.443165 -236.898659) (xy 95.489144 -236.920476) (xy 95.531028 -236.949386)
			(xy 95.567732 -236.984641) (xy 95.598305 -237.025327) (xy 95.621956 -237.07039) (xy 95.638072 -237.118664)
			(xy 95.646236 -237.168898) (xy 95.646748 -237.194344) (xy 95.965276 -237.194344) (xy 95.969236 -237.14529)
			(xy 95.981013 -237.097506) (xy 96.000304 -237.05223) (xy 96.026607 -237.010634) (xy 96.059242 -236.973797)
			(xy 96.097363 -236.942672) (xy 96.139984 -236.918065) (xy 96.186 -236.900613) (xy 96.234219 -236.890769)
			(xy 96.283394 -236.888788) (xy 96.332249 -236.89472) (xy 96.37952 -236.908412) (xy 96.423982 -236.92951)
			(xy 96.464485 -236.957466) (xy 96.499978 -236.991558) (xy 96.529543 -237.030902) (xy 96.552414 -237.074479)
			(xy 96.567998 -237.12116) (xy 96.575893 -237.169737) (xy 96.576388 -237.194344) (xy 96.90533 -237.194344)
			(xy 96.90929 -237.14529) (xy 96.921067 -237.097506) (xy 96.940358 -237.05223) (xy 96.966661 -237.010634)
			(xy 96.999296 -236.973797) (xy 97.037417 -236.942672) (xy 97.080038 -236.918065) (xy 97.126054 -236.900613)
			(xy 97.174273 -236.890769) (xy 97.223448 -236.888788) (xy 97.272303 -236.89472) (xy 97.319574 -236.908412)
			(xy 97.364036 -236.92951) (xy 97.404539 -236.957466) (xy 97.440032 -236.991558) (xy 97.469597 -237.030902)
			(xy 97.492468 -237.074479) (xy 97.508052 -237.12116) (xy 97.515947 -237.169737) (xy 97.516442 -237.194344)
			(xy 97.84513 -237.194344) (xy 97.84909 -237.14529) (xy 97.860867 -237.097506) (xy 97.880158 -237.05223)
			(xy 97.906461 -237.010634) (xy 97.939096 -236.973797) (xy 97.977217 -236.942672) (xy 98.019838 -236.918065)
			(xy 98.065854 -236.900613) (xy 98.114073 -236.890769) (xy 98.163248 -236.888788) (xy 98.212103 -236.89472)
			(xy 98.259374 -236.908412) (xy 98.303836 -236.92951) (xy 98.344339 -236.957466) (xy 98.379832 -236.991558)
			(xy 98.409397 -237.030902) (xy 98.432268 -237.074479) (xy 98.447852 -237.12116) (xy 98.455747 -237.169737)
			(xy 98.456242 -237.194344) (xy 98.785184 -237.194344) (xy 98.789144 -237.14529) (xy 98.800921 -237.097506)
			(xy 98.820212 -237.05223) (xy 98.846515 -237.010634) (xy 98.87915 -236.973797) (xy 98.917271 -236.942672)
			(xy 98.959892 -236.918065) (xy 99.005908 -236.900613) (xy 99.054127 -236.890769) (xy 99.103302 -236.888788)
			(xy 99.152157 -236.89472) (xy 99.199428 -236.908412) (xy 99.24389 -236.92951) (xy 99.284393 -236.957466)
			(xy 99.319886 -236.991558) (xy 99.349451 -237.030902) (xy 99.372322 -237.074479) (xy 99.387906 -237.12116)
			(xy 99.395801 -237.169737) (xy 99.396296 -237.194344) (xy 99.725238 -237.194344) (xy 99.729198 -237.14529)
			(xy 99.740975 -237.097506) (xy 99.760266 -237.05223) (xy 99.786569 -237.010634) (xy 99.819204 -236.973797)
			(xy 99.857325 -236.942672) (xy 99.899946 -236.918065) (xy 99.945962 -236.900613) (xy 99.994181 -236.890769)
			(xy 100.043356 -236.888788) (xy 100.092211 -236.89472) (xy 100.139482 -236.908412) (xy 100.183944 -236.92951)
			(xy 100.224447 -236.957466) (xy 100.25994 -236.991558) (xy 100.289505 -237.030902) (xy 100.312376 -237.074479)
			(xy 100.32796 -237.12116) (xy 100.335855 -237.169737) (xy 100.33635 -237.194344) (xy 100.665292 -237.194344)
			(xy 100.669252 -237.14529) (xy 100.681029 -237.097506) (xy 100.70032 -237.05223) (xy 100.726623 -237.010634)
			(xy 100.759258 -236.973797) (xy 100.797379 -236.942672) (xy 100.84 -236.918065) (xy 100.886016 -236.900613)
			(xy 100.934235 -236.890769) (xy 100.98341 -236.888788) (xy 101.032265 -236.89472) (xy 101.079536 -236.908412)
			(xy 101.123998 -236.92951) (xy 101.164501 -236.957466) (xy 101.199994 -236.991558) (xy 101.229559 -237.030902)
			(xy 101.25243 -237.074479) (xy 101.268014 -237.12116) (xy 101.275909 -237.169737) (xy 101.276404 -237.194344)
			(xy 101.605346 -237.194344) (xy 101.609306 -237.14529) (xy 101.621083 -237.097506) (xy 101.640374 -237.05223)
			(xy 101.666677 -237.010634) (xy 101.699312 -236.973797) (xy 101.737433 -236.942672) (xy 101.780054 -236.918065)
			(xy 101.82607 -236.900613) (xy 101.874289 -236.890769) (xy 101.923464 -236.888788) (xy 101.972319 -236.89472)
			(xy 102.01959 -236.908412) (xy 102.064052 -236.92951) (xy 102.104555 -236.957466) (xy 102.140048 -236.991558)
			(xy 102.169613 -237.030902) (xy 102.192484 -237.074479) (xy 102.208068 -237.12116) (xy 102.215963 -237.169737)
			(xy 102.216458 -237.194344) (xy 102.545146 -237.194344) (xy 102.549106 -237.14529) (xy 102.560883 -237.097506)
			(xy 102.580174 -237.05223) (xy 102.606477 -237.010634) (xy 102.639112 -236.973797) (xy 102.677233 -236.942672)
			(xy 102.719854 -236.918065) (xy 102.76587 -236.900613) (xy 102.814089 -236.890769) (xy 102.863264 -236.888788)
			(xy 102.912119 -236.89472) (xy 102.95939 -236.908412) (xy 103.003852 -236.92951) (xy 103.044355 -236.957466)
			(xy 103.079848 -236.991558) (xy 103.109413 -237.030902) (xy 103.132284 -237.074479) (xy 103.147868 -237.12116)
			(xy 103.155763 -237.169737) (xy 103.156258 -237.194344) (xy 103.4852 -237.194344) (xy 103.48916 -237.14529)
			(xy 103.500937 -237.097506) (xy 103.520228 -237.05223) (xy 103.546531 -237.010634) (xy 103.579166 -236.973797)
			(xy 103.617287 -236.942672) (xy 103.659908 -236.918065) (xy 103.705924 -236.900613) (xy 103.754143 -236.890769)
			(xy 103.803318 -236.888788) (xy 103.852173 -236.89472) (xy 103.899444 -236.908412) (xy 103.943906 -236.92951)
			(xy 103.984409 -236.957466) (xy 104.019902 -236.991558) (xy 104.049467 -237.030902) (xy 104.072338 -237.074479)
			(xy 104.087922 -237.12116) (xy 104.095817 -237.169737) (xy 104.096312 -237.194344) (xy 104.425254 -237.194344)
			(xy 104.429214 -237.14529) (xy 104.440991 -237.097506) (xy 104.460282 -237.05223) (xy 104.486585 -237.010634)
			(xy 104.51922 -236.973797) (xy 104.557341 -236.942672) (xy 104.599962 -236.918065) (xy 104.645978 -236.900613)
			(xy 104.694197 -236.890769) (xy 104.743372 -236.888788) (xy 104.792227 -236.89472) (xy 104.839498 -236.908412)
			(xy 104.88396 -236.92951) (xy 104.924463 -236.957466) (xy 104.959956 -236.991558) (xy 104.989521 -237.030902)
			(xy 105.012392 -237.074479) (xy 105.027976 -237.12116) (xy 105.035871 -237.169737) (xy 105.036366 -237.194344)
			(xy 105.365308 -237.194344) (xy 105.369268 -237.14529) (xy 105.381045 -237.097506) (xy 105.400336 -237.05223)
			(xy 105.426639 -237.010634) (xy 105.459274 -236.973797) (xy 105.497395 -236.942672) (xy 105.540016 -236.918065)
			(xy 105.586032 -236.900613) (xy 105.634251 -236.890769) (xy 105.683426 -236.888788) (xy 105.732281 -236.89472)
			(xy 105.779552 -236.908412) (xy 105.824014 -236.92951) (xy 105.864517 -236.957466) (xy 105.90001 -236.991558)
			(xy 105.929575 -237.030902) (xy 105.952446 -237.074479) (xy 105.96803 -237.12116) (xy 105.975925 -237.169737)
			(xy 105.97642 -237.194344) (xy 106.305362 -237.194344) (xy 106.309322 -237.14529) (xy 106.321099 -237.097506)
			(xy 106.34039 -237.05223) (xy 106.366693 -237.010634) (xy 106.399328 -236.973797) (xy 106.437449 -236.942672)
			(xy 106.48007 -236.918065) (xy 106.526086 -236.900613) (xy 106.574305 -236.890769) (xy 106.62348 -236.888788)
			(xy 106.672335 -236.89472) (xy 106.719606 -236.908412) (xy 106.764068 -236.92951) (xy 106.804571 -236.957466)
			(xy 106.840064 -236.991558) (xy 106.869629 -237.030902) (xy 106.8925 -237.074479) (xy 106.908084 -237.12116)
			(xy 106.915979 -237.169737) (xy 106.916474 -237.194344) (xy 107.245162 -237.194344) (xy 107.249122 -237.14529)
			(xy 107.260899 -237.097506) (xy 107.28019 -237.05223) (xy 107.306493 -237.010634) (xy 107.339128 -236.973797)
			(xy 107.377249 -236.942672) (xy 107.41987 -236.918065) (xy 107.465886 -236.900613) (xy 107.514105 -236.890769)
			(xy 107.56328 -236.888788) (xy 107.612135 -236.89472) (xy 107.659406 -236.908412) (xy 107.703868 -236.92951)
			(xy 107.744371 -236.957466) (xy 107.779864 -236.991558) (xy 107.809429 -237.030902) (xy 107.8323 -237.074479)
			(xy 107.847884 -237.12116) (xy 107.855779 -237.169737) (xy 107.856274 -237.194344) (xy 110.065324 -237.194344)
			(xy 110.069284 -237.14529) (xy 110.081061 -237.097506) (xy 110.100352 -237.05223) (xy 110.126655 -237.010634)
			(xy 110.15929 -236.973797) (xy 110.197411 -236.942672) (xy 110.240032 -236.918065) (xy 110.286048 -236.900613)
			(xy 110.334267 -236.890769) (xy 110.383442 -236.888788) (xy 110.432297 -236.89472) (xy 110.479568 -236.908412)
			(xy 110.52403 -236.92951) (xy 110.564533 -236.957466) (xy 110.600026 -236.991558) (xy 110.629591 -237.030902)
			(xy 110.652462 -237.074479) (xy 110.668046 -237.12116) (xy 110.675941 -237.169737) (xy 110.676436 -237.194344)
			(xy 110.675941 -237.218951) (xy 110.668046 -237.267528) (xy 110.652462 -237.314209) (xy 110.629591 -237.357786)
			(xy 110.600026 -237.39713) (xy 110.564533 -237.431222) (xy 110.52403 -237.459178) (xy 110.479568 -237.480276)
			(xy 110.432297 -237.493968) (xy 110.383442 -237.4999) (xy 110.334267 -237.497919) (xy 110.286048 -237.488075)
			(xy 110.240032 -237.470623) (xy 110.197411 -237.446016) (xy 110.15929 -237.414891) (xy 110.126655 -237.378054)
			(xy 110.100352 -237.336458) (xy 110.081061 -237.291182) (xy 110.069284 -237.243398) (xy 110.065324 -237.194344)
			(xy 107.856274 -237.194344) (xy 107.855779 -237.218951) (xy 107.847884 -237.267528) (xy 107.8323 -237.314209)
			(xy 107.809429 -237.357786) (xy 107.779864 -237.39713) (xy 107.744371 -237.431222) (xy 107.703868 -237.459178)
			(xy 107.659406 -237.480276) (xy 107.612135 -237.493968) (xy 107.56328 -237.4999) (xy 107.514105 -237.497919)
			(xy 107.465886 -237.488075) (xy 107.41987 -237.470623) (xy 107.377249 -237.446016) (xy 107.339128 -237.414891)
			(xy 107.306493 -237.378054) (xy 107.28019 -237.336458) (xy 107.260899 -237.291182) (xy 107.249122 -237.243398)
			(xy 107.245162 -237.194344) (xy 106.916474 -237.194344) (xy 106.915979 -237.218951) (xy 106.908084 -237.267528)
			(xy 106.8925 -237.314209) (xy 106.869629 -237.357786) (xy 106.840064 -237.39713) (xy 106.804571 -237.431222)
			(xy 106.764068 -237.459178) (xy 106.719606 -237.480276) (xy 106.672335 -237.493968) (xy 106.62348 -237.4999)
			(xy 106.574305 -237.497919) (xy 106.526086 -237.488075) (xy 106.48007 -237.470623) (xy 106.437449 -237.446016)
			(xy 106.399328 -237.414891) (xy 106.366693 -237.378054) (xy 106.34039 -237.336458) (xy 106.321099 -237.291182)
			(xy 106.309322 -237.243398) (xy 106.305362 -237.194344) (xy 105.97642 -237.194344) (xy 105.975925 -237.218951)
			(xy 105.96803 -237.267528) (xy 105.952446 -237.314209) (xy 105.929575 -237.357786) (xy 105.90001 -237.39713)
			(xy 105.864517 -237.431222) (xy 105.824014 -237.459178) (xy 105.779552 -237.480276) (xy 105.732281 -237.493968)
			(xy 105.683426 -237.4999) (xy 105.634251 -237.497919) (xy 105.586032 -237.488075) (xy 105.540016 -237.470623)
			(xy 105.497395 -237.446016) (xy 105.459274 -237.414891) (xy 105.426639 -237.378054) (xy 105.400336 -237.336458)
			(xy 105.381045 -237.291182) (xy 105.369268 -237.243398) (xy 105.365308 -237.194344) (xy 105.036366 -237.194344)
			(xy 105.035871 -237.218951) (xy 105.027976 -237.267528) (xy 105.012392 -237.314209) (xy 104.989521 -237.357786)
			(xy 104.959956 -237.39713) (xy 104.924463 -237.431222) (xy 104.88396 -237.459178) (xy 104.839498 -237.480276)
			(xy 104.792227 -237.493968) (xy 104.743372 -237.4999) (xy 104.694197 -237.497919) (xy 104.645978 -237.488075)
			(xy 104.599962 -237.470623) (xy 104.557341 -237.446016) (xy 104.51922 -237.414891) (xy 104.486585 -237.378054)
			(xy 104.460282 -237.336458) (xy 104.440991 -237.291182) (xy 104.429214 -237.243398) (xy 104.425254 -237.194344)
			(xy 104.096312 -237.194344) (xy 104.095817 -237.218951) (xy 104.087922 -237.267528) (xy 104.072338 -237.314209)
			(xy 104.049467 -237.357786) (xy 104.019902 -237.39713) (xy 103.984409 -237.431222) (xy 103.943906 -237.459178)
			(xy 103.899444 -237.480276) (xy 103.852173 -237.493968) (xy 103.803318 -237.4999) (xy 103.754143 -237.497919)
			(xy 103.705924 -237.488075) (xy 103.659908 -237.470623) (xy 103.617287 -237.446016) (xy 103.579166 -237.414891)
			(xy 103.546531 -237.378054) (xy 103.520228 -237.336458) (xy 103.500937 -237.291182) (xy 103.48916 -237.243398)
			(xy 103.4852 -237.194344) (xy 103.156258 -237.194344) (xy 103.155763 -237.218951) (xy 103.147868 -237.267528)
			(xy 103.132284 -237.314209) (xy 103.109413 -237.357786) (xy 103.079848 -237.39713) (xy 103.044355 -237.431222)
			(xy 103.003852 -237.459178) (xy 102.95939 -237.480276) (xy 102.912119 -237.493968) (xy 102.863264 -237.4999)
			(xy 102.814089 -237.497919) (xy 102.76587 -237.488075) (xy 102.719854 -237.470623) (xy 102.677233 -237.446016)
			(xy 102.639112 -237.414891) (xy 102.606477 -237.378054) (xy 102.580174 -237.336458) (xy 102.560883 -237.291182)
			(xy 102.549106 -237.243398) (xy 102.545146 -237.194344) (xy 102.216458 -237.194344) (xy 102.215963 -237.218951)
			(xy 102.208068 -237.267528) (xy 102.192484 -237.314209) (xy 102.169613 -237.357786) (xy 102.140048 -237.39713)
			(xy 102.104555 -237.431222) (xy 102.064052 -237.459178) (xy 102.01959 -237.480276) (xy 101.972319 -237.493968)
			(xy 101.923464 -237.4999) (xy 101.874289 -237.497919) (xy 101.82607 -237.488075) (xy 101.780054 -237.470623)
			(xy 101.737433 -237.446016) (xy 101.699312 -237.414891) (xy 101.666677 -237.378054) (xy 101.640374 -237.336458)
			(xy 101.621083 -237.291182) (xy 101.609306 -237.243398) (xy 101.605346 -237.194344) (xy 101.276404 -237.194344)
			(xy 101.275909 -237.218951) (xy 101.268014 -237.267528) (xy 101.25243 -237.314209) (xy 101.229559 -237.357786)
			(xy 101.199994 -237.39713) (xy 101.164501 -237.431222) (xy 101.123998 -237.459178) (xy 101.079536 -237.480276)
			(xy 101.032265 -237.493968) (xy 100.98341 -237.4999) (xy 100.934235 -237.497919) (xy 100.886016 -237.488075)
			(xy 100.84 -237.470623) (xy 100.797379 -237.446016) (xy 100.759258 -237.414891) (xy 100.726623 -237.378054)
			(xy 100.70032 -237.336458) (xy 100.681029 -237.291182) (xy 100.669252 -237.243398) (xy 100.665292 -237.194344)
			(xy 100.33635 -237.194344) (xy 100.335855 -237.218951) (xy 100.32796 -237.267528) (xy 100.312376 -237.314209)
			(xy 100.289505 -237.357786) (xy 100.25994 -237.39713) (xy 100.224447 -237.431222) (xy 100.183944 -237.459178)
			(xy 100.139482 -237.480276) (xy 100.092211 -237.493968) (xy 100.043356 -237.4999) (xy 99.994181 -237.497919)
			(xy 99.945962 -237.488075) (xy 99.899946 -237.470623) (xy 99.857325 -237.446016) (xy 99.819204 -237.414891)
			(xy 99.786569 -237.378054) (xy 99.760266 -237.336458) (xy 99.740975 -237.291182) (xy 99.729198 -237.243398)
			(xy 99.725238 -237.194344) (xy 99.396296 -237.194344) (xy 99.395801 -237.218951) (xy 99.387906 -237.267528)
			(xy 99.372322 -237.314209) (xy 99.349451 -237.357786) (xy 99.319886 -237.39713) (xy 99.284393 -237.431222)
			(xy 99.24389 -237.459178) (xy 99.199428 -237.480276) (xy 99.152157 -237.493968) (xy 99.103302 -237.4999)
			(xy 99.054127 -237.497919) (xy 99.005908 -237.488075) (xy 98.959892 -237.470623) (xy 98.917271 -237.446016)
			(xy 98.87915 -237.414891) (xy 98.846515 -237.378054) (xy 98.820212 -237.336458) (xy 98.800921 -237.291182)
			(xy 98.789144 -237.243398) (xy 98.785184 -237.194344) (xy 98.456242 -237.194344) (xy 98.455747 -237.218951)
			(xy 98.447852 -237.267528) (xy 98.432268 -237.314209) (xy 98.409397 -237.357786) (xy 98.379832 -237.39713)
			(xy 98.344339 -237.431222) (xy 98.303836 -237.459178) (xy 98.259374 -237.480276) (xy 98.212103 -237.493968)
			(xy 98.163248 -237.4999) (xy 98.114073 -237.497919) (xy 98.065854 -237.488075) (xy 98.019838 -237.470623)
			(xy 97.977217 -237.446016) (xy 97.939096 -237.414891) (xy 97.906461 -237.378054) (xy 97.880158 -237.336458)
			(xy 97.860867 -237.291182) (xy 97.84909 -237.243398) (xy 97.84513 -237.194344) (xy 97.516442 -237.194344)
			(xy 97.515947 -237.218951) (xy 97.508052 -237.267528) (xy 97.492468 -237.314209) (xy 97.469597 -237.357786)
			(xy 97.440032 -237.39713) (xy 97.404539 -237.431222) (xy 97.364036 -237.459178) (xy 97.319574 -237.480276)
			(xy 97.272303 -237.493968) (xy 97.223448 -237.4999) (xy 97.174273 -237.497919) (xy 97.126054 -237.488075)
			(xy 97.080038 -237.470623) (xy 97.037417 -237.446016) (xy 96.999296 -237.414891) (xy 96.966661 -237.378054)
			(xy 96.940358 -237.336458) (xy 96.921067 -237.291182) (xy 96.90929 -237.243398) (xy 96.90533 -237.194344)
			(xy 96.576388 -237.194344) (xy 96.575893 -237.218951) (xy 96.567998 -237.267528) (xy 96.552414 -237.314209)
			(xy 96.529543 -237.357786) (xy 96.499978 -237.39713) (xy 96.464485 -237.431222) (xy 96.423982 -237.459178)
			(xy 96.37952 -237.480276) (xy 96.332249 -237.493968) (xy 96.283394 -237.4999) (xy 96.234219 -237.497919)
			(xy 96.186 -237.488075) (xy 96.139984 -237.470623) (xy 96.097363 -237.446016) (xy 96.059242 -237.414891)
			(xy 96.026607 -237.378054) (xy 96.000304 -237.336458) (xy 95.981013 -237.291182) (xy 95.969236 -237.243398)
			(xy 95.965276 -237.194344) (xy 95.646748 -237.194344) (xy 95.646236 -237.21979) (xy 95.638072 -237.270024)
			(xy 95.621956 -237.318298) (xy 95.598305 -237.363361) (xy 95.567732 -237.404047) (xy 95.531028 -237.439302)
			(xy 95.489144 -237.468212) (xy 95.443165 -237.490029) (xy 95.394281 -237.504189) (xy 95.34376 -237.510323)
			(xy 95.292908 -237.508274) (xy 95.243044 -237.498094) (xy 95.195458 -237.480047) (xy 95.151384 -237.454601)
			(xy 95.111962 -237.422414) (xy 95.078214 -237.38432) (xy 95.051013 -237.341306) (xy 95.031065 -237.294486)
			(xy 95.018886 -237.245072) (xy 95.014791 -237.194344) (xy 94.706694 -237.194344) (xy 94.706182 -237.21979)
			(xy 94.698018 -237.270024) (xy 94.681902 -237.318298) (xy 94.658251 -237.363361) (xy 94.627678 -237.404047)
			(xy 94.590974 -237.439302) (xy 94.54909 -237.468212) (xy 94.503111 -237.490029) (xy 94.454227 -237.504189)
			(xy 94.403706 -237.510323) (xy 94.352854 -237.508274) (xy 94.30299 -237.498094) (xy 94.255404 -237.480047)
			(xy 94.21133 -237.454601) (xy 94.171908 -237.422414) (xy 94.13816 -237.38432) (xy 94.110959 -237.341306)
			(xy 94.091011 -237.294486) (xy 94.078832 -237.245072) (xy 94.074737 -237.194344) (xy 93.756226 -237.194344)
			(xy 93.755731 -237.218951) (xy 93.747836 -237.267528) (xy 93.732252 -237.314209) (xy 93.709381 -237.357786)
			(xy 93.679816 -237.39713) (xy 93.644323 -237.431222) (xy 93.60382 -237.459178) (xy 93.559358 -237.480276)
			(xy 93.512087 -237.493968) (xy 93.463232 -237.4999) (xy 93.414057 -237.497919) (xy 93.365838 -237.488075)
			(xy 93.319822 -237.470623) (xy 93.277201 -237.446016) (xy 93.23908 -237.414891) (xy 93.206445 -237.378054)
			(xy 93.180142 -237.336458) (xy 93.160851 -237.291182) (xy 93.149074 -237.243398) (xy 93.145114 -237.194344)
			(xy 92.82684 -237.194344) (xy 92.826328 -237.21979) (xy 92.818164 -237.270024) (xy 92.802048 -237.318298)
			(xy 92.778397 -237.363361) (xy 92.747824 -237.404047) (xy 92.71112 -237.439302) (xy 92.669236 -237.468212)
			(xy 92.623257 -237.490029) (xy 92.574373 -237.504189) (xy 92.523852 -237.510323) (xy 92.473 -237.508274)
			(xy 92.423136 -237.498094) (xy 92.37555 -237.480047) (xy 92.331476 -237.454601) (xy 92.292054 -237.422414)
			(xy 92.258306 -237.38432) (xy 92.231105 -237.341306) (xy 92.211157 -237.294486) (xy 92.198978 -237.245072)
			(xy 92.194883 -237.194344) (xy 91.876372 -237.194344) (xy 91.875877 -237.218951) (xy 91.867982 -237.267528)
			(xy 91.852398 -237.314209) (xy 91.829527 -237.357786) (xy 91.799962 -237.39713) (xy 91.764469 -237.431222)
			(xy 91.723966 -237.459178) (xy 91.679504 -237.480276) (xy 91.632233 -237.493968) (xy 91.583378 -237.4999)
			(xy 91.534203 -237.497919) (xy 91.485984 -237.488075) (xy 91.439968 -237.470623) (xy 91.397347 -237.446016)
			(xy 91.359226 -237.414891) (xy 91.326591 -237.378054) (xy 91.300288 -237.336458) (xy 91.280997 -237.291182)
			(xy 91.26922 -237.243398) (xy 91.26526 -237.194344) (xy 90.946732 -237.194344) (xy 90.94622 -237.21979)
			(xy 90.938056 -237.270024) (xy 90.92194 -237.318298) (xy 90.898289 -237.363361) (xy 90.867716 -237.404047)
			(xy 90.831012 -237.439302) (xy 90.789128 -237.468212) (xy 90.743149 -237.490029) (xy 90.694265 -237.504189)
			(xy 90.643744 -237.510323) (xy 90.592892 -237.508274) (xy 90.543028 -237.498094) (xy 90.495442 -237.480047)
			(xy 90.451368 -237.454601) (xy 90.411946 -237.422414) (xy 90.378198 -237.38432) (xy 90.350997 -237.341306)
			(xy 90.331049 -237.294486) (xy 90.31887 -237.245072) (xy 90.314775 -237.194344) (xy 89.996264 -237.194344)
			(xy 89.995769 -237.218951) (xy 89.987874 -237.267528) (xy 89.97229 -237.314209) (xy 89.949419 -237.357786)
			(xy 89.919854 -237.39713) (xy 89.884361 -237.431222) (xy 89.843858 -237.459178) (xy 89.799396 -237.480276)
			(xy 89.752125 -237.493968) (xy 89.70327 -237.4999) (xy 89.654095 -237.497919) (xy 89.605876 -237.488075)
			(xy 89.55986 -237.470623) (xy 89.517239 -237.446016) (xy 89.479118 -237.414891) (xy 89.446483 -237.378054)
			(xy 89.42018 -237.336458) (xy 89.400889 -237.291182) (xy 89.389112 -237.243398) (xy 89.385152 -237.194344)
			(xy 89.066878 -237.194344) (xy 89.066366 -237.21979) (xy 89.058202 -237.270024) (xy 89.042086 -237.318298)
			(xy 89.018435 -237.363361) (xy 88.987862 -237.404047) (xy 88.951158 -237.439302) (xy 88.909274 -237.468212)
			(xy 88.863295 -237.490029) (xy 88.814411 -237.504189) (xy 88.76389 -237.510323) (xy 88.713038 -237.508274)
			(xy 88.663174 -237.498094) (xy 88.615588 -237.480047) (xy 88.571514 -237.454601) (xy 88.532092 -237.422414)
			(xy 88.498344 -237.38432) (xy 88.471143 -237.341306) (xy 88.451195 -237.294486) (xy 88.439016 -237.245072)
			(xy 88.434921 -237.194344) (xy 88.126824 -237.194344) (xy 88.126312 -237.21979) (xy 88.118148 -237.270024)
			(xy 88.102032 -237.318298) (xy 88.078381 -237.363361) (xy 88.047808 -237.404047) (xy 88.011104 -237.439302)
			(xy 87.96922 -237.468212) (xy 87.923241 -237.490029) (xy 87.874357 -237.504189) (xy 87.823836 -237.510323)
			(xy 87.772984 -237.508274) (xy 87.72312 -237.498094) (xy 87.675534 -237.480047) (xy 87.63146 -237.454601)
			(xy 87.592038 -237.422414) (xy 87.55829 -237.38432) (xy 87.531089 -237.341306) (xy 87.511141 -237.294486)
			(xy 87.498962 -237.245072) (xy 87.494867 -237.194344) (xy 87.176356 -237.194344) (xy 87.175861 -237.218951)
			(xy 87.167966 -237.267528) (xy 87.152382 -237.314209) (xy 87.129511 -237.357786) (xy 87.099946 -237.39713)
			(xy 87.064453 -237.431222) (xy 87.02395 -237.459178) (xy 86.979488 -237.480276) (xy 86.932217 -237.493968)
			(xy 86.883362 -237.4999) (xy 86.834187 -237.497919) (xy 86.785968 -237.488075) (xy 86.739952 -237.470623)
			(xy 86.697331 -237.446016) (xy 86.65921 -237.414891) (xy 86.626575 -237.378054) (xy 86.600272 -237.336458)
			(xy 86.580981 -237.291182) (xy 86.569204 -237.243398) (xy 86.565244 -237.194344) (xy 86.246716 -237.194344)
			(xy 86.246204 -237.21979) (xy 86.23804 -237.270024) (xy 86.221924 -237.318298) (xy 86.198273 -237.363361)
			(xy 86.1677 -237.404047) (xy 86.130996 -237.439302) (xy 86.089112 -237.468212) (xy 86.043133 -237.490029)
			(xy 85.994249 -237.504189) (xy 85.943728 -237.510323) (xy 85.892876 -237.508274) (xy 85.843012 -237.498094)
			(xy 85.795426 -237.480047) (xy 85.751352 -237.454601) (xy 85.71193 -237.422414) (xy 85.678182 -237.38432)
			(xy 85.650981 -237.341306) (xy 85.631033 -237.294486) (xy 85.618854 -237.245072) (xy 85.614759 -237.194344)
			(xy 85.296248 -237.194344) (xy 85.295753 -237.218951) (xy 85.287858 -237.267528) (xy 85.272274 -237.314209)
			(xy 85.249403 -237.357786) (xy 85.219838 -237.39713) (xy 85.184345 -237.431222) (xy 85.143842 -237.459178)
			(xy 85.09938 -237.480276) (xy 85.052109 -237.493968) (xy 85.003254 -237.4999) (xy 84.954079 -237.497919)
			(xy 84.90586 -237.488075) (xy 84.859844 -237.470623) (xy 84.817223 -237.446016) (xy 84.779102 -237.414891)
			(xy 84.746467 -237.378054) (xy 84.720164 -237.336458) (xy 84.700873 -237.291182) (xy 84.689096 -237.243398)
			(xy 84.685136 -237.194344) (xy 84.366862 -237.194344) (xy 84.36635 -237.21979) (xy 84.358186 -237.270024)
			(xy 84.34207 -237.318298) (xy 84.318419 -237.363361) (xy 84.287846 -237.404047) (xy 84.251142 -237.439302)
			(xy 84.209258 -237.468212) (xy 84.163279 -237.490029) (xy 84.114395 -237.504189) (xy 84.063874 -237.510323)
			(xy 84.013022 -237.508274) (xy 83.963158 -237.498094) (xy 83.915572 -237.480047) (xy 83.871498 -237.454601)
			(xy 83.832076 -237.422414) (xy 83.798328 -237.38432) (xy 83.771127 -237.341306) (xy 83.751179 -237.294486)
			(xy 83.739 -237.245072) (xy 83.734905 -237.194344) (xy 83.416394 -237.194344) (xy 83.415899 -237.218951)
			(xy 83.408004 -237.267528) (xy 83.39242 -237.314209) (xy 83.369549 -237.357786) (xy 83.339984 -237.39713)
			(xy 83.304491 -237.431222) (xy 83.263988 -237.459178) (xy 83.219526 -237.480276) (xy 83.172255 -237.493968)
			(xy 83.1234 -237.4999) (xy 83.074225 -237.497919) (xy 83.026006 -237.488075) (xy 82.97999 -237.470623)
			(xy 82.937369 -237.446016) (xy 82.899248 -237.414891) (xy 82.866613 -237.378054) (xy 82.84031 -237.336458)
			(xy 82.821019 -237.291182) (xy 82.809242 -237.243398) (xy 82.805282 -237.194344) (xy 82.486754 -237.194344)
			(xy 82.486242 -237.21979) (xy 82.478078 -237.270024) (xy 82.461962 -237.318298) (xy 82.438311 -237.363361)
			(xy 82.407738 -237.404047) (xy 82.371034 -237.439302) (xy 82.32915 -237.468212) (xy 82.283171 -237.490029)
			(xy 82.234287 -237.504189) (xy 82.183766 -237.510323) (xy 82.132914 -237.508274) (xy 82.08305 -237.498094)
			(xy 82.035464 -237.480047) (xy 81.99139 -237.454601) (xy 81.951968 -237.422414) (xy 81.91822 -237.38432)
			(xy 81.891019 -237.341306) (xy 81.871071 -237.294486) (xy 81.858892 -237.245072) (xy 81.854797 -237.194344)
			(xy 81.5467 -237.194344) (xy 81.546188 -237.21979) (xy 81.538024 -237.270024) (xy 81.521908 -237.318298)
			(xy 81.498257 -237.363361) (xy 81.467684 -237.404047) (xy 81.43098 -237.439302) (xy 81.389096 -237.468212)
			(xy 81.343117 -237.490029) (xy 81.294233 -237.504189) (xy 81.243712 -237.510323) (xy 81.19286 -237.508274)
			(xy 81.142996 -237.498094) (xy 81.09541 -237.480047) (xy 81.051336 -237.454601) (xy 81.011914 -237.422414)
			(xy 80.978166 -237.38432) (xy 80.950965 -237.341306) (xy 80.931017 -237.294486) (xy 80.918838 -237.245072)
			(xy 80.914743 -237.194344) (xy 80.596486 -237.194344) (xy 80.595991 -237.218951) (xy 80.588096 -237.267528)
			(xy 80.572512 -237.314209) (xy 80.549641 -237.357786) (xy 80.520076 -237.39713) (xy 80.484583 -237.431222)
			(xy 80.44408 -237.459178) (xy 80.399618 -237.480276) (xy 80.352347 -237.493968) (xy 80.303492 -237.4999)
			(xy 80.254317 -237.497919) (xy 80.206098 -237.488075) (xy 80.160082 -237.470623) (xy 80.117461 -237.446016)
			(xy 80.07934 -237.414891) (xy 80.046705 -237.378054) (xy 80.020402 -237.336458) (xy 80.001111 -237.291182)
			(xy 79.989334 -237.243398) (xy 79.985374 -237.194344) (xy 78.716378 -237.194344) (xy 78.715883 -237.218951)
			(xy 78.707988 -237.267528) (xy 78.692404 -237.314209) (xy 78.669533 -237.357786) (xy 78.639968 -237.39713)
			(xy 78.604475 -237.431222) (xy 78.563972 -237.459178) (xy 78.51951 -237.480276) (xy 78.472239 -237.493968)
			(xy 78.423384 -237.4999) (xy 78.374209 -237.497919) (xy 78.32599 -237.488075) (xy 78.279974 -237.470623)
			(xy 78.237353 -237.446016) (xy 78.199232 -237.414891) (xy 78.166597 -237.378054) (xy 78.140294 -237.336458)
			(xy 78.121003 -237.291182) (xy 78.109226 -237.243398) (xy 78.105266 -237.194344) (xy 62.37732 -237.194344)
			(xy 62.37732 -238.270288) (xy 76.507098 -238.270288) (xy 76.511058 -238.221234) (xy 76.522835 -238.17345)
			(xy 76.542126 -238.128174) (xy 76.568429 -238.086578) (xy 76.601064 -238.049741) (xy 76.639185 -238.018616)
			(xy 76.681806 -237.994009) (xy 76.727822 -237.976557) (xy 76.776041 -237.966713) (xy 76.825216 -237.964732)
			(xy 76.874071 -237.970664) (xy 76.921342 -237.984356) (xy 76.963477 -238.00435) (xy 79.51522 -238.00435)
			(xy 79.51918 -237.955296) (xy 79.530957 -237.907512) (xy 79.550248 -237.862236) (xy 79.576551 -237.82064)
			(xy 79.609186 -237.783803) (xy 79.647307 -237.752678) (xy 79.689928 -237.728071) (xy 79.735944 -237.710619)
			(xy 79.784163 -237.700775) (xy 79.833338 -237.698794) (xy 79.882193 -237.704726) (xy 79.929464 -237.718418)
			(xy 79.973926 -237.739516) (xy 80.014429 -237.767472) (xy 80.049922 -237.801564) (xy 80.079487 -237.840908)
			(xy 80.102358 -237.884485) (xy 80.117942 -237.931166) (xy 80.125837 -237.979743) (xy 80.126332 -238.00435)
			(xy 80.444843 -238.00435) (xy 80.448938 -237.953622) (xy 80.461117 -237.904208) (xy 80.481065 -237.857388)
			(xy 80.508266 -237.814374) (xy 80.542014 -237.77628) (xy 80.581436 -237.744093) (xy 80.62551 -237.718647)
			(xy 80.673096 -237.7006) (xy 80.72296 -237.69042) (xy 80.773812 -237.688371) (xy 80.824333 -237.694505)
			(xy 80.873217 -237.708665) (xy 80.919196 -237.730482) (xy 80.96108 -237.759392) (xy 80.997784 -237.794647)
			(xy 81.028357 -237.835333) (xy 81.052008 -237.880396) (xy 81.068124 -237.92867) (xy 81.076288 -237.978904)
			(xy 81.0768 -238.00435) (xy 81.395328 -238.00435) (xy 81.399288 -237.955296) (xy 81.411065 -237.907512)
			(xy 81.430356 -237.862236) (xy 81.456659 -237.82064) (xy 81.489294 -237.783803) (xy 81.527415 -237.752678)
			(xy 81.570036 -237.728071) (xy 81.616052 -237.710619) (xy 81.664271 -237.700775) (xy 81.713446 -237.698794)
			(xy 81.762301 -237.704726) (xy 81.809572 -237.718418) (xy 81.854034 -237.739516) (xy 81.894537 -237.767472)
			(xy 81.93003 -237.801564) (xy 81.959595 -237.840908) (xy 81.982466 -237.884485) (xy 81.99805 -237.931166)
			(xy 82.005945 -237.979743) (xy 82.00644 -238.00435) (xy 82.324697 -238.00435) (xy 82.328792 -237.953622)
			(xy 82.340971 -237.904208) (xy 82.360919 -237.857388) (xy 82.38812 -237.814374) (xy 82.421868 -237.77628)
			(xy 82.46129 -237.744093) (xy 82.505364 -237.718647) (xy 82.55295 -237.7006) (xy 82.602814 -237.69042)
			(xy 82.653666 -237.688371) (xy 82.704187 -237.694505) (xy 82.753071 -237.708665) (xy 82.79905 -237.730482)
			(xy 82.840934 -237.759392) (xy 82.877638 -237.794647) (xy 82.908211 -237.835333) (xy 82.931862 -237.880396)
			(xy 82.947978 -237.92867) (xy 82.956142 -237.978904) (xy 82.956654 -238.00435) (xy 83.275182 -238.00435)
			(xy 83.279142 -237.955296) (xy 83.290919 -237.907512) (xy 83.31021 -237.862236) (xy 83.336513 -237.82064)
			(xy 83.369148 -237.783803) (xy 83.407269 -237.752678) (xy 83.44989 -237.728071) (xy 83.495906 -237.710619)
			(xy 83.544125 -237.700775) (xy 83.5933 -237.698794) (xy 83.642155 -237.704726) (xy 83.689426 -237.718418)
			(xy 83.733888 -237.739516) (xy 83.774391 -237.767472) (xy 83.809884 -237.801564) (xy 83.839449 -237.840908)
			(xy 83.86232 -237.884485) (xy 83.877904 -237.931166) (xy 83.885799 -237.979743) (xy 83.886294 -238.00435)
			(xy 84.204805 -238.00435) (xy 84.2089 -237.953622) (xy 84.221079 -237.904208) (xy 84.241027 -237.857388)
			(xy 84.268228 -237.814374) (xy 84.301976 -237.77628) (xy 84.341398 -237.744093) (xy 84.385472 -237.718647)
			(xy 84.433058 -237.7006) (xy 84.482922 -237.69042) (xy 84.533774 -237.688371) (xy 84.584295 -237.694505)
			(xy 84.633179 -237.708665) (xy 84.679158 -237.730482) (xy 84.721042 -237.759392) (xy 84.757746 -237.794647)
			(xy 84.788319 -237.835333) (xy 84.81197 -237.880396) (xy 84.828086 -237.92867) (xy 84.83625 -237.978904)
			(xy 84.836762 -238.00435) (xy 85.144859 -238.00435) (xy 85.148954 -237.953622) (xy 85.161133 -237.904208)
			(xy 85.181081 -237.857388) (xy 85.208282 -237.814374) (xy 85.24203 -237.77628) (xy 85.281452 -237.744093)
			(xy 85.325526 -237.718647) (xy 85.373112 -237.7006) (xy 85.422976 -237.69042) (xy 85.473828 -237.688371)
			(xy 85.524349 -237.694505) (xy 85.573233 -237.708665) (xy 85.619212 -237.730482) (xy 85.661096 -237.759392)
			(xy 85.6978 -237.794647) (xy 85.728373 -237.835333) (xy 85.752024 -237.880396) (xy 85.76814 -237.92867)
			(xy 85.776304 -237.978904) (xy 85.776816 -238.00435) (xy 86.095344 -238.00435) (xy 86.099304 -237.955296)
			(xy 86.111081 -237.907512) (xy 86.130372 -237.862236) (xy 86.156675 -237.82064) (xy 86.18931 -237.783803)
			(xy 86.227431 -237.752678) (xy 86.270052 -237.728071) (xy 86.316068 -237.710619) (xy 86.364287 -237.700775)
			(xy 86.413462 -237.698794) (xy 86.462317 -237.704726) (xy 86.509588 -237.718418) (xy 86.55405 -237.739516)
			(xy 86.594553 -237.767472) (xy 86.630046 -237.801564) (xy 86.659611 -237.840908) (xy 86.682482 -237.884485)
			(xy 86.698066 -237.931166) (xy 86.705961 -237.979743) (xy 86.706456 -238.00435) (xy 87.024713 -238.00435)
			(xy 87.028808 -237.953622) (xy 87.040987 -237.904208) (xy 87.060935 -237.857388) (xy 87.088136 -237.814374)
			(xy 87.121884 -237.77628) (xy 87.161306 -237.744093) (xy 87.20538 -237.718647) (xy 87.252966 -237.7006)
			(xy 87.30283 -237.69042) (xy 87.353682 -237.688371) (xy 87.404203 -237.694505) (xy 87.453087 -237.708665)
			(xy 87.499066 -237.730482) (xy 87.54095 -237.759392) (xy 87.577654 -237.794647) (xy 87.608227 -237.835333)
			(xy 87.631878 -237.880396) (xy 87.647994 -237.92867) (xy 87.656158 -237.978904) (xy 87.65667 -238.00435)
			(xy 87.975198 -238.00435) (xy 87.979158 -237.955296) (xy 87.990935 -237.907512) (xy 88.010226 -237.862236)
			(xy 88.036529 -237.82064) (xy 88.069164 -237.783803) (xy 88.107285 -237.752678) (xy 88.149906 -237.728071)
			(xy 88.195922 -237.710619) (xy 88.244141 -237.700775) (xy 88.293316 -237.698794) (xy 88.342171 -237.704726)
			(xy 88.389442 -237.718418) (xy 88.433904 -237.739516) (xy 88.474407 -237.767472) (xy 88.5099 -237.801564)
			(xy 88.539465 -237.840908) (xy 88.562336 -237.884485) (xy 88.57792 -237.931166) (xy 88.585815 -237.979743)
			(xy 88.58631 -238.00435) (xy 88.904821 -238.00435) (xy 88.908916 -237.953622) (xy 88.921095 -237.904208)
			(xy 88.941043 -237.857388) (xy 88.968244 -237.814374) (xy 89.001992 -237.77628) (xy 89.041414 -237.744093)
			(xy 89.085488 -237.718647) (xy 89.133074 -237.7006) (xy 89.182938 -237.69042) (xy 89.23379 -237.688371)
			(xy 89.284311 -237.694505) (xy 89.333195 -237.708665) (xy 89.379174 -237.730482) (xy 89.421058 -237.759392)
			(xy 89.457762 -237.794647) (xy 89.488335 -237.835333) (xy 89.511986 -237.880396) (xy 89.528102 -237.92867)
			(xy 89.536266 -237.978904) (xy 89.536778 -238.00435) (xy 89.855306 -238.00435) (xy 89.859266 -237.955296)
			(xy 89.871043 -237.907512) (xy 89.890334 -237.862236) (xy 89.916637 -237.82064) (xy 89.949272 -237.783803)
			(xy 89.987393 -237.752678) (xy 90.030014 -237.728071) (xy 90.07603 -237.710619) (xy 90.124249 -237.700775)
			(xy 90.173424 -237.698794) (xy 90.222279 -237.704726) (xy 90.26955 -237.718418) (xy 90.314012 -237.739516)
			(xy 90.354515 -237.767472) (xy 90.390008 -237.801564) (xy 90.419573 -237.840908) (xy 90.442444 -237.884485)
			(xy 90.458028 -237.931166) (xy 90.465923 -237.979743) (xy 90.466418 -238.00435) (xy 90.784675 -238.00435)
			(xy 90.78877 -237.953622) (xy 90.800949 -237.904208) (xy 90.820897 -237.857388) (xy 90.848098 -237.814374)
			(xy 90.881846 -237.77628) (xy 90.921268 -237.744093) (xy 90.965342 -237.718647) (xy 91.012928 -237.7006)
			(xy 91.062792 -237.69042) (xy 91.113644 -237.688371) (xy 91.164165 -237.694505) (xy 91.213049 -237.708665)
			(xy 91.259028 -237.730482) (xy 91.300912 -237.759392) (xy 91.337616 -237.794647) (xy 91.368189 -237.835333)
			(xy 91.39184 -237.880396) (xy 91.407956 -237.92867) (xy 91.41612 -237.978904) (xy 91.416632 -238.00435)
			(xy 91.724729 -238.00435) (xy 91.728824 -237.953622) (xy 91.741003 -237.904208) (xy 91.760951 -237.857388)
			(xy 91.788152 -237.814374) (xy 91.8219 -237.77628) (xy 91.861322 -237.744093) (xy 91.905396 -237.718647)
			(xy 91.952982 -237.7006) (xy 92.002846 -237.69042) (xy 92.053698 -237.688371) (xy 92.104219 -237.694505)
			(xy 92.153103 -237.708665) (xy 92.199082 -237.730482) (xy 92.240966 -237.759392) (xy 92.27767 -237.794647)
			(xy 92.308243 -237.835333) (xy 92.331894 -237.880396) (xy 92.34801 -237.92867) (xy 92.356174 -237.978904)
			(xy 92.356686 -238.00435) (xy 92.675214 -238.00435) (xy 92.679174 -237.955296) (xy 92.690951 -237.907512)
			(xy 92.710242 -237.862236) (xy 92.736545 -237.82064) (xy 92.76918 -237.783803) (xy 92.807301 -237.752678)
			(xy 92.849922 -237.728071) (xy 92.895938 -237.710619) (xy 92.944157 -237.700775) (xy 92.993332 -237.698794)
			(xy 93.042187 -237.704726) (xy 93.089458 -237.718418) (xy 93.13392 -237.739516) (xy 93.174423 -237.767472)
			(xy 93.209916 -237.801564) (xy 93.239481 -237.840908) (xy 93.262352 -237.884485) (xy 93.277936 -237.931166)
			(xy 93.285831 -237.979743) (xy 93.286326 -238.00435) (xy 93.604837 -238.00435) (xy 93.608932 -237.953622)
			(xy 93.621111 -237.904208) (xy 93.641059 -237.857388) (xy 93.66826 -237.814374) (xy 93.702008 -237.77628)
			(xy 93.74143 -237.744093) (xy 93.785504 -237.718647) (xy 93.83309 -237.7006) (xy 93.882954 -237.69042)
			(xy 93.933806 -237.688371) (xy 93.984327 -237.694505) (xy 94.033211 -237.708665) (xy 94.07919 -237.730482)
			(xy 94.121074 -237.759392) (xy 94.157778 -237.794647) (xy 94.188351 -237.835333) (xy 94.212002 -237.880396)
			(xy 94.228118 -237.92867) (xy 94.236282 -237.978904) (xy 94.236794 -238.00435) (xy 94.555322 -238.00435)
			(xy 94.559282 -237.955296) (xy 94.571059 -237.907512) (xy 94.59035 -237.862236) (xy 94.616653 -237.82064)
			(xy 94.649288 -237.783803) (xy 94.687409 -237.752678) (xy 94.73003 -237.728071) (xy 94.776046 -237.710619)
			(xy 94.824265 -237.700775) (xy 94.87344 -237.698794) (xy 94.922295 -237.704726) (xy 94.969566 -237.718418)
			(xy 95.014028 -237.739516) (xy 95.054531 -237.767472) (xy 95.090024 -237.801564) (xy 95.119589 -237.840908)
			(xy 95.14246 -237.884485) (xy 95.158044 -237.931166) (xy 95.165939 -237.979743) (xy 95.166434 -238.00435)
			(xy 95.484691 -238.00435) (xy 95.488786 -237.953622) (xy 95.500965 -237.904208) (xy 95.520913 -237.857388)
			(xy 95.548114 -237.814374) (xy 95.581862 -237.77628) (xy 95.621284 -237.744093) (xy 95.665358 -237.718647)
			(xy 95.712944 -237.7006) (xy 95.762808 -237.69042) (xy 95.81366 -237.688371) (xy 95.864181 -237.694505)
			(xy 95.913065 -237.708665) (xy 95.959044 -237.730482) (xy 96.000928 -237.759392) (xy 96.037632 -237.794647)
			(xy 96.068205 -237.835333) (xy 96.091856 -237.880396) (xy 96.107972 -237.92867) (xy 96.116136 -237.978904)
			(xy 96.116648 -238.00435) (xy 96.435176 -238.00435) (xy 96.439136 -237.955296) (xy 96.450913 -237.907512)
			(xy 96.470204 -237.862236) (xy 96.496507 -237.82064) (xy 96.529142 -237.783803) (xy 96.567263 -237.752678)
			(xy 96.609884 -237.728071) (xy 96.6559 -237.710619) (xy 96.704119 -237.700775) (xy 96.753294 -237.698794)
			(xy 96.802149 -237.704726) (xy 96.84942 -237.718418) (xy 96.893882 -237.739516) (xy 96.934385 -237.767472)
			(xy 96.969878 -237.801564) (xy 96.999443 -237.840908) (xy 97.022314 -237.884485) (xy 97.037898 -237.931166)
			(xy 97.045793 -237.979743) (xy 97.046288 -238.00435) (xy 97.37523 -238.00435) (xy 97.37919 -237.955296)
			(xy 97.390967 -237.907512) (xy 97.410258 -237.862236) (xy 97.436561 -237.82064) (xy 97.469196 -237.783803)
			(xy 97.507317 -237.752678) (xy 97.549938 -237.728071) (xy 97.595954 -237.710619) (xy 97.644173 -237.700775)
			(xy 97.693348 -237.698794) (xy 97.742203 -237.704726) (xy 97.789474 -237.718418) (xy 97.833936 -237.739516)
			(xy 97.874439 -237.767472) (xy 97.909932 -237.801564) (xy 97.939497 -237.840908) (xy 97.962368 -237.884485)
			(xy 97.977952 -237.931166) (xy 97.985847 -237.979743) (xy 97.986342 -238.00435) (xy 98.315284 -238.00435)
			(xy 98.319244 -237.955296) (xy 98.331021 -237.907512) (xy 98.350312 -237.862236) (xy 98.376615 -237.82064)
			(xy 98.40925 -237.783803) (xy 98.447371 -237.752678) (xy 98.489992 -237.728071) (xy 98.536008 -237.710619)
			(xy 98.584227 -237.700775) (xy 98.633402 -237.698794) (xy 98.682257 -237.704726) (xy 98.729528 -237.718418)
			(xy 98.77399 -237.739516) (xy 98.814493 -237.767472) (xy 98.849986 -237.801564) (xy 98.879551 -237.840908)
			(xy 98.902422 -237.884485) (xy 98.918006 -237.931166) (xy 98.925901 -237.979743) (xy 98.926396 -238.00435)
			(xy 99.255338 -238.00435) (xy 99.259298 -237.955296) (xy 99.271075 -237.907512) (xy 99.290366 -237.862236)
			(xy 99.316669 -237.82064) (xy 99.349304 -237.783803) (xy 99.387425 -237.752678) (xy 99.430046 -237.728071)
			(xy 99.476062 -237.710619) (xy 99.524281 -237.700775) (xy 99.573456 -237.698794) (xy 99.622311 -237.704726)
			(xy 99.669582 -237.718418) (xy 99.714044 -237.739516) (xy 99.754547 -237.767472) (xy 99.79004 -237.801564)
			(xy 99.819605 -237.840908) (xy 99.842476 -237.884485) (xy 99.85806 -237.931166) (xy 99.865955 -237.979743)
			(xy 99.86645 -238.00435) (xy 100.195138 -238.00435) (xy 100.199098 -237.955296) (xy 100.210875 -237.907512)
			(xy 100.230166 -237.862236) (xy 100.256469 -237.82064) (xy 100.289104 -237.783803) (xy 100.327225 -237.752678)
			(xy 100.369846 -237.728071) (xy 100.415862 -237.710619) (xy 100.464081 -237.700775) (xy 100.513256 -237.698794)
			(xy 100.562111 -237.704726) (xy 100.609382 -237.718418) (xy 100.653844 -237.739516) (xy 100.694347 -237.767472)
			(xy 100.72984 -237.801564) (xy 100.759405 -237.840908) (xy 100.782276 -237.884485) (xy 100.79786 -237.931166)
			(xy 100.805755 -237.979743) (xy 100.80625 -238.00435) (xy 101.135192 -238.00435) (xy 101.139152 -237.955296)
			(xy 101.150929 -237.907512) (xy 101.17022 -237.862236) (xy 101.196523 -237.82064) (xy 101.229158 -237.783803)
			(xy 101.267279 -237.752678) (xy 101.3099 -237.728071) (xy 101.355916 -237.710619) (xy 101.404135 -237.700775)
			(xy 101.45331 -237.698794) (xy 101.502165 -237.704726) (xy 101.549436 -237.718418) (xy 101.593898 -237.739516)
			(xy 101.634401 -237.767472) (xy 101.669894 -237.801564) (xy 101.699459 -237.840908) (xy 101.72233 -237.884485)
			(xy 101.737914 -237.931166) (xy 101.745809 -237.979743) (xy 101.746304 -238.00435) (xy 102.075246 -238.00435)
			(xy 102.079206 -237.955296) (xy 102.090983 -237.907512) (xy 102.110274 -237.862236) (xy 102.136577 -237.82064)
			(xy 102.169212 -237.783803) (xy 102.207333 -237.752678) (xy 102.249954 -237.728071) (xy 102.29597 -237.710619)
			(xy 102.344189 -237.700775) (xy 102.393364 -237.698794) (xy 102.442219 -237.704726) (xy 102.48949 -237.718418)
			(xy 102.533952 -237.739516) (xy 102.574455 -237.767472) (xy 102.609948 -237.801564) (xy 102.639513 -237.840908)
			(xy 102.662384 -237.884485) (xy 102.677968 -237.931166) (xy 102.685863 -237.979743) (xy 102.686358 -238.00435)
			(xy 103.0153 -238.00435) (xy 103.01926 -237.955296) (xy 103.031037 -237.907512) (xy 103.050328 -237.862236)
			(xy 103.076631 -237.82064) (xy 103.109266 -237.783803) (xy 103.147387 -237.752678) (xy 103.190008 -237.728071)
			(xy 103.236024 -237.710619) (xy 103.284243 -237.700775) (xy 103.333418 -237.698794) (xy 103.382273 -237.704726)
			(xy 103.429544 -237.718418) (xy 103.474006 -237.739516) (xy 103.514509 -237.767472) (xy 103.550002 -237.801564)
			(xy 103.579567 -237.840908) (xy 103.602438 -237.884485) (xy 103.618022 -237.931166) (xy 103.625917 -237.979743)
			(xy 103.626412 -238.00435) (xy 103.955354 -238.00435) (xy 103.959314 -237.955296) (xy 103.971091 -237.907512)
			(xy 103.990382 -237.862236) (xy 104.016685 -237.82064) (xy 104.04932 -237.783803) (xy 104.087441 -237.752678)
			(xy 104.130062 -237.728071) (xy 104.176078 -237.710619) (xy 104.224297 -237.700775) (xy 104.273472 -237.698794)
			(xy 104.322327 -237.704726) (xy 104.369598 -237.718418) (xy 104.41406 -237.739516) (xy 104.454563 -237.767472)
			(xy 104.490056 -237.801564) (xy 104.519621 -237.840908) (xy 104.542492 -237.884485) (xy 104.558076 -237.931166)
			(xy 104.565971 -237.979743) (xy 104.566466 -238.00435) (xy 104.895154 -238.00435) (xy 104.899114 -237.955296)
			(xy 104.910891 -237.907512) (xy 104.930182 -237.862236) (xy 104.956485 -237.82064) (xy 104.98912 -237.783803)
			(xy 105.027241 -237.752678) (xy 105.069862 -237.728071) (xy 105.115878 -237.710619) (xy 105.164097 -237.700775)
			(xy 105.213272 -237.698794) (xy 105.262127 -237.704726) (xy 105.309398 -237.718418) (xy 105.35386 -237.739516)
			(xy 105.394363 -237.767472) (xy 105.429856 -237.801564) (xy 105.459421 -237.840908) (xy 105.482292 -237.884485)
			(xy 105.497876 -237.931166) (xy 105.505771 -237.979743) (xy 105.506266 -238.00435) (xy 105.824777 -238.00435)
			(xy 105.828872 -237.953622) (xy 105.841051 -237.904208) (xy 105.860999 -237.857388) (xy 105.8882 -237.814374)
			(xy 105.921948 -237.77628) (xy 105.96137 -237.744093) (xy 106.005444 -237.718647) (xy 106.05303 -237.7006)
			(xy 106.102894 -237.69042) (xy 106.153746 -237.688371) (xy 106.204267 -237.694505) (xy 106.253151 -237.708665)
			(xy 106.29913 -237.730482) (xy 106.341014 -237.759392) (xy 106.377718 -237.794647) (xy 106.408291 -237.835333)
			(xy 106.431942 -237.880396) (xy 106.448058 -237.92867) (xy 106.456222 -237.978904) (xy 106.456734 -238.00435)
			(xy 106.764831 -238.00435) (xy 106.768926 -237.953622) (xy 106.781105 -237.904208) (xy 106.801053 -237.857388)
			(xy 106.828254 -237.814374) (xy 106.862002 -237.77628) (xy 106.901424 -237.744093) (xy 106.945498 -237.718647)
			(xy 106.993084 -237.7006) (xy 107.042948 -237.69042) (xy 107.0938 -237.688371) (xy 107.144321 -237.694505)
			(xy 107.193205 -237.708665) (xy 107.239184 -237.730482) (xy 107.281068 -237.759392) (xy 107.317772 -237.794647)
			(xy 107.348345 -237.835333) (xy 107.371996 -237.880396) (xy 107.388112 -237.92867) (xy 107.396276 -237.978904)
			(xy 107.396788 -238.00435) (xy 107.715316 -238.00435) (xy 107.719276 -237.955296) (xy 107.731053 -237.907512)
			(xy 107.750344 -237.862236) (xy 107.776647 -237.82064) (xy 107.809282 -237.783803) (xy 107.847403 -237.752678)
			(xy 107.890024 -237.728071) (xy 107.93604 -237.710619) (xy 107.984259 -237.700775) (xy 108.033434 -237.698794)
			(xy 108.082289 -237.704726) (xy 108.12956 -237.718418) (xy 108.174022 -237.739516) (xy 108.214525 -237.767472)
			(xy 108.250018 -237.801564) (xy 108.279583 -237.840908) (xy 108.302454 -237.884485) (xy 108.318038 -237.931166)
			(xy 108.325933 -237.979743) (xy 108.326428 -238.00435) (xy 108.65537 -238.00435) (xy 108.65933 -237.955296)
			(xy 108.671107 -237.907512) (xy 108.690398 -237.862236) (xy 108.716701 -237.82064) (xy 108.749336 -237.783803)
			(xy 108.787457 -237.752678) (xy 108.830078 -237.728071) (xy 108.876094 -237.710619) (xy 108.924313 -237.700775)
			(xy 108.973488 -237.698794) (xy 109.022343 -237.704726) (xy 109.069614 -237.718418) (xy 109.114076 -237.739516)
			(xy 109.154579 -237.767472) (xy 109.190072 -237.801564) (xy 109.219637 -237.840908) (xy 109.242508 -237.884485)
			(xy 109.258092 -237.931166) (xy 109.265987 -237.979743) (xy 109.266482 -238.00435) (xy 109.59517 -238.00435)
			(xy 109.59913 -237.955296) (xy 109.610907 -237.907512) (xy 109.630198 -237.862236) (xy 109.656501 -237.82064)
			(xy 109.689136 -237.783803) (xy 109.727257 -237.752678) (xy 109.769878 -237.728071) (xy 109.815894 -237.710619)
			(xy 109.864113 -237.700775) (xy 109.913288 -237.698794) (xy 109.962143 -237.704726) (xy 110.009414 -237.718418)
			(xy 110.053876 -237.739516) (xy 110.094379 -237.767472) (xy 110.129872 -237.801564) (xy 110.159437 -237.840908)
			(xy 110.182308 -237.884485) (xy 110.197892 -237.931166) (xy 110.205787 -237.979743) (xy 110.206282 -238.00435)
			(xy 110.205787 -238.028957) (xy 110.197892 -238.077534) (xy 110.182308 -238.124215) (xy 110.159437 -238.167792)
			(xy 110.129872 -238.207136) (xy 110.094379 -238.241228) (xy 110.053876 -238.269184) (xy 110.009414 -238.290282)
			(xy 109.962143 -238.303974) (xy 109.913288 -238.309906) (xy 109.864113 -238.307925) (xy 109.815894 -238.298081)
			(xy 109.769878 -238.280629) (xy 109.727257 -238.256022) (xy 109.689136 -238.224897) (xy 109.656501 -238.18806)
			(xy 109.630198 -238.146464) (xy 109.610907 -238.101188) (xy 109.59913 -238.053404) (xy 109.59517 -238.00435)
			(xy 109.266482 -238.00435) (xy 109.265987 -238.028957) (xy 109.258092 -238.077534) (xy 109.242508 -238.124215)
			(xy 109.219637 -238.167792) (xy 109.190072 -238.207136) (xy 109.154579 -238.241228) (xy 109.114076 -238.269184)
			(xy 109.069614 -238.290282) (xy 109.022343 -238.303974) (xy 108.973488 -238.309906) (xy 108.924313 -238.307925)
			(xy 108.876094 -238.298081) (xy 108.830078 -238.280629) (xy 108.787457 -238.256022) (xy 108.749336 -238.224897)
			(xy 108.716701 -238.18806) (xy 108.690398 -238.146464) (xy 108.671107 -238.101188) (xy 108.65933 -238.053404)
			(xy 108.65537 -238.00435) (xy 108.326428 -238.00435) (xy 108.325933 -238.028957) (xy 108.318038 -238.077534)
			(xy 108.302454 -238.124215) (xy 108.279583 -238.167792) (xy 108.250018 -238.207136) (xy 108.214525 -238.241228)
			(xy 108.174022 -238.269184) (xy 108.12956 -238.290282) (xy 108.082289 -238.303974) (xy 108.033434 -238.309906)
			(xy 107.984259 -238.307925) (xy 107.93604 -238.298081) (xy 107.890024 -238.280629) (xy 107.847403 -238.256022)
			(xy 107.809282 -238.224897) (xy 107.776647 -238.18806) (xy 107.750344 -238.146464) (xy 107.731053 -238.101188)
			(xy 107.719276 -238.053404) (xy 107.715316 -238.00435) (xy 107.396788 -238.00435) (xy 107.396276 -238.029796)
			(xy 107.388112 -238.08003) (xy 107.371996 -238.128304) (xy 107.348345 -238.173367) (xy 107.317772 -238.214053)
			(xy 107.281068 -238.249308) (xy 107.239184 -238.278218) (xy 107.193205 -238.300035) (xy 107.144321 -238.314195)
			(xy 107.0938 -238.320329) (xy 107.042948 -238.31828) (xy 106.993084 -238.3081) (xy 106.945498 -238.290053)
			(xy 106.901424 -238.264607) (xy 106.862002 -238.23242) (xy 106.828254 -238.194326) (xy 106.801053 -238.151312)
			(xy 106.781105 -238.104492) (xy 106.768926 -238.055078) (xy 106.764831 -238.00435) (xy 106.456734 -238.00435)
			(xy 106.456222 -238.029796) (xy 106.448058 -238.08003) (xy 106.431942 -238.128304) (xy 106.408291 -238.173367)
			(xy 106.377718 -238.214053) (xy 106.341014 -238.249308) (xy 106.29913 -238.278218) (xy 106.253151 -238.300035)
			(xy 106.204267 -238.314195) (xy 106.153746 -238.320329) (xy 106.102894 -238.31828) (xy 106.05303 -238.3081)
			(xy 106.005444 -238.290053) (xy 105.96137 -238.264607) (xy 105.921948 -238.23242) (xy 105.8882 -238.194326)
			(xy 105.860999 -238.151312) (xy 105.841051 -238.104492) (xy 105.828872 -238.055078) (xy 105.824777 -238.00435)
			(xy 105.506266 -238.00435) (xy 105.505771 -238.028957) (xy 105.497876 -238.077534) (xy 105.482292 -238.124215)
			(xy 105.459421 -238.167792) (xy 105.429856 -238.207136) (xy 105.394363 -238.241228) (xy 105.35386 -238.269184)
			(xy 105.309398 -238.290282) (xy 105.262127 -238.303974) (xy 105.213272 -238.309906) (xy 105.164097 -238.307925)
			(xy 105.115878 -238.298081) (xy 105.069862 -238.280629) (xy 105.027241 -238.256022) (xy 104.98912 -238.224897)
			(xy 104.956485 -238.18806) (xy 104.930182 -238.146464) (xy 104.910891 -238.101188) (xy 104.899114 -238.053404)
			(xy 104.895154 -238.00435) (xy 104.566466 -238.00435) (xy 104.565971 -238.028957) (xy 104.558076 -238.077534)
			(xy 104.542492 -238.124215) (xy 104.519621 -238.167792) (xy 104.490056 -238.207136) (xy 104.454563 -238.241228)
			(xy 104.41406 -238.269184) (xy 104.369598 -238.290282) (xy 104.322327 -238.303974) (xy 104.273472 -238.309906)
			(xy 104.224297 -238.307925) (xy 104.176078 -238.298081) (xy 104.130062 -238.280629) (xy 104.087441 -238.256022)
			(xy 104.04932 -238.224897) (xy 104.016685 -238.18806) (xy 103.990382 -238.146464) (xy 103.971091 -238.101188)
			(xy 103.959314 -238.053404) (xy 103.955354 -238.00435) (xy 103.626412 -238.00435) (xy 103.625917 -238.028957)
			(xy 103.618022 -238.077534) (xy 103.602438 -238.124215) (xy 103.579567 -238.167792) (xy 103.550002 -238.207136)
			(xy 103.514509 -238.241228) (xy 103.474006 -238.269184) (xy 103.429544 -238.290282) (xy 103.382273 -238.303974)
			(xy 103.333418 -238.309906) (xy 103.284243 -238.307925) (xy 103.236024 -238.298081) (xy 103.190008 -238.280629)
			(xy 103.147387 -238.256022) (xy 103.109266 -238.224897) (xy 103.076631 -238.18806) (xy 103.050328 -238.146464)
			(xy 103.031037 -238.101188) (xy 103.01926 -238.053404) (xy 103.0153 -238.00435) (xy 102.686358 -238.00435)
			(xy 102.685863 -238.028957) (xy 102.677968 -238.077534) (xy 102.662384 -238.124215) (xy 102.639513 -238.167792)
			(xy 102.609948 -238.207136) (xy 102.574455 -238.241228) (xy 102.533952 -238.269184) (xy 102.48949 -238.290282)
			(xy 102.442219 -238.303974) (xy 102.393364 -238.309906) (xy 102.344189 -238.307925) (xy 102.29597 -238.298081)
			(xy 102.249954 -238.280629) (xy 102.207333 -238.256022) (xy 102.169212 -238.224897) (xy 102.136577 -238.18806)
			(xy 102.110274 -238.146464) (xy 102.090983 -238.101188) (xy 102.079206 -238.053404) (xy 102.075246 -238.00435)
			(xy 101.746304 -238.00435) (xy 101.745809 -238.028957) (xy 101.737914 -238.077534) (xy 101.72233 -238.124215)
			(xy 101.699459 -238.167792) (xy 101.669894 -238.207136) (xy 101.634401 -238.241228) (xy 101.593898 -238.269184)
			(xy 101.549436 -238.290282) (xy 101.502165 -238.303974) (xy 101.45331 -238.309906) (xy 101.404135 -238.307925)
			(xy 101.355916 -238.298081) (xy 101.3099 -238.280629) (xy 101.267279 -238.256022) (xy 101.229158 -238.224897)
			(xy 101.196523 -238.18806) (xy 101.17022 -238.146464) (xy 101.150929 -238.101188) (xy 101.139152 -238.053404)
			(xy 101.135192 -238.00435) (xy 100.80625 -238.00435) (xy 100.805755 -238.028957) (xy 100.79786 -238.077534)
			(xy 100.782276 -238.124215) (xy 100.759405 -238.167792) (xy 100.72984 -238.207136) (xy 100.694347 -238.241228)
			(xy 100.653844 -238.269184) (xy 100.609382 -238.290282) (xy 100.562111 -238.303974) (xy 100.513256 -238.309906)
			(xy 100.464081 -238.307925) (xy 100.415862 -238.298081) (xy 100.369846 -238.280629) (xy 100.327225 -238.256022)
			(xy 100.289104 -238.224897) (xy 100.256469 -238.18806) (xy 100.230166 -238.146464) (xy 100.210875 -238.101188)
			(xy 100.199098 -238.053404) (xy 100.195138 -238.00435) (xy 99.86645 -238.00435) (xy 99.865955 -238.028957)
			(xy 99.85806 -238.077534) (xy 99.842476 -238.124215) (xy 99.819605 -238.167792) (xy 99.79004 -238.207136)
			(xy 99.754547 -238.241228) (xy 99.714044 -238.269184) (xy 99.669582 -238.290282) (xy 99.622311 -238.303974)
			(xy 99.573456 -238.309906) (xy 99.524281 -238.307925) (xy 99.476062 -238.298081) (xy 99.430046 -238.280629)
			(xy 99.387425 -238.256022) (xy 99.349304 -238.224897) (xy 99.316669 -238.18806) (xy 99.290366 -238.146464)
			(xy 99.271075 -238.101188) (xy 99.259298 -238.053404) (xy 99.255338 -238.00435) (xy 98.926396 -238.00435)
			(xy 98.925901 -238.028957) (xy 98.918006 -238.077534) (xy 98.902422 -238.124215) (xy 98.879551 -238.167792)
			(xy 98.849986 -238.207136) (xy 98.814493 -238.241228) (xy 98.77399 -238.269184) (xy 98.729528 -238.290282)
			(xy 98.682257 -238.303974) (xy 98.633402 -238.309906) (xy 98.584227 -238.307925) (xy 98.536008 -238.298081)
			(xy 98.489992 -238.280629) (xy 98.447371 -238.256022) (xy 98.40925 -238.224897) (xy 98.376615 -238.18806)
			(xy 98.350312 -238.146464) (xy 98.331021 -238.101188) (xy 98.319244 -238.053404) (xy 98.315284 -238.00435)
			(xy 97.986342 -238.00435) (xy 97.985847 -238.028957) (xy 97.977952 -238.077534) (xy 97.962368 -238.124215)
			(xy 97.939497 -238.167792) (xy 97.909932 -238.207136) (xy 97.874439 -238.241228) (xy 97.833936 -238.269184)
			(xy 97.789474 -238.290282) (xy 97.742203 -238.303974) (xy 97.693348 -238.309906) (xy 97.644173 -238.307925)
			(xy 97.595954 -238.298081) (xy 97.549938 -238.280629) (xy 97.507317 -238.256022) (xy 97.469196 -238.224897)
			(xy 97.436561 -238.18806) (xy 97.410258 -238.146464) (xy 97.390967 -238.101188) (xy 97.37919 -238.053404)
			(xy 97.37523 -238.00435) (xy 97.046288 -238.00435) (xy 97.045793 -238.028957) (xy 97.037898 -238.077534)
			(xy 97.022314 -238.124215) (xy 96.999443 -238.167792) (xy 96.969878 -238.207136) (xy 96.934385 -238.241228)
			(xy 96.893882 -238.269184) (xy 96.84942 -238.290282) (xy 96.802149 -238.303974) (xy 96.753294 -238.309906)
			(xy 96.704119 -238.307925) (xy 96.6559 -238.298081) (xy 96.609884 -238.280629) (xy 96.567263 -238.256022)
			(xy 96.529142 -238.224897) (xy 96.496507 -238.18806) (xy 96.470204 -238.146464) (xy 96.450913 -238.101188)
			(xy 96.439136 -238.053404) (xy 96.435176 -238.00435) (xy 96.116648 -238.00435) (xy 96.116136 -238.029796)
			(xy 96.107972 -238.08003) (xy 96.091856 -238.128304) (xy 96.068205 -238.173367) (xy 96.037632 -238.214053)
			(xy 96.000928 -238.249308) (xy 95.959044 -238.278218) (xy 95.913065 -238.300035) (xy 95.864181 -238.314195)
			(xy 95.81366 -238.320329) (xy 95.762808 -238.31828) (xy 95.712944 -238.3081) (xy 95.665358 -238.290053)
			(xy 95.621284 -238.264607) (xy 95.581862 -238.23242) (xy 95.548114 -238.194326) (xy 95.520913 -238.151312)
			(xy 95.500965 -238.104492) (xy 95.488786 -238.055078) (xy 95.484691 -238.00435) (xy 95.166434 -238.00435)
			(xy 95.165939 -238.028957) (xy 95.158044 -238.077534) (xy 95.14246 -238.124215) (xy 95.119589 -238.167792)
			(xy 95.090024 -238.207136) (xy 95.054531 -238.241228) (xy 95.014028 -238.269184) (xy 94.969566 -238.290282)
			(xy 94.922295 -238.303974) (xy 94.87344 -238.309906) (xy 94.824265 -238.307925) (xy 94.776046 -238.298081)
			(xy 94.73003 -238.280629) (xy 94.687409 -238.256022) (xy 94.649288 -238.224897) (xy 94.616653 -238.18806)
			(xy 94.59035 -238.146464) (xy 94.571059 -238.101188) (xy 94.559282 -238.053404) (xy 94.555322 -238.00435)
			(xy 94.236794 -238.00435) (xy 94.236282 -238.029796) (xy 94.228118 -238.08003) (xy 94.212002 -238.128304)
			(xy 94.188351 -238.173367) (xy 94.157778 -238.214053) (xy 94.121074 -238.249308) (xy 94.07919 -238.278218)
			(xy 94.033211 -238.300035) (xy 93.984327 -238.314195) (xy 93.933806 -238.320329) (xy 93.882954 -238.31828)
			(xy 93.83309 -238.3081) (xy 93.785504 -238.290053) (xy 93.74143 -238.264607) (xy 93.702008 -238.23242)
			(xy 93.66826 -238.194326) (xy 93.641059 -238.151312) (xy 93.621111 -238.104492) (xy 93.608932 -238.055078)
			(xy 93.604837 -238.00435) (xy 93.286326 -238.00435) (xy 93.285831 -238.028957) (xy 93.277936 -238.077534)
			(xy 93.262352 -238.124215) (xy 93.239481 -238.167792) (xy 93.209916 -238.207136) (xy 93.174423 -238.241228)
			(xy 93.13392 -238.269184) (xy 93.089458 -238.290282) (xy 93.042187 -238.303974) (xy 92.993332 -238.309906)
			(xy 92.944157 -238.307925) (xy 92.895938 -238.298081) (xy 92.849922 -238.280629) (xy 92.807301 -238.256022)
			(xy 92.76918 -238.224897) (xy 92.736545 -238.18806) (xy 92.710242 -238.146464) (xy 92.690951 -238.101188)
			(xy 92.679174 -238.053404) (xy 92.675214 -238.00435) (xy 92.356686 -238.00435) (xy 92.356174 -238.029796)
			(xy 92.34801 -238.08003) (xy 92.331894 -238.128304) (xy 92.308243 -238.173367) (xy 92.27767 -238.214053)
			(xy 92.240966 -238.249308) (xy 92.199082 -238.278218) (xy 92.153103 -238.300035) (xy 92.104219 -238.314195)
			(xy 92.053698 -238.320329) (xy 92.002846 -238.31828) (xy 91.952982 -238.3081) (xy 91.905396 -238.290053)
			(xy 91.861322 -238.264607) (xy 91.8219 -238.23242) (xy 91.788152 -238.194326) (xy 91.760951 -238.151312)
			(xy 91.741003 -238.104492) (xy 91.728824 -238.055078) (xy 91.724729 -238.00435) (xy 91.416632 -238.00435)
			(xy 91.41612 -238.029796) (xy 91.407956 -238.08003) (xy 91.39184 -238.128304) (xy 91.368189 -238.173367)
			(xy 91.337616 -238.214053) (xy 91.300912 -238.249308) (xy 91.259028 -238.278218) (xy 91.213049 -238.300035)
			(xy 91.164165 -238.314195) (xy 91.113644 -238.320329) (xy 91.062792 -238.31828) (xy 91.012928 -238.3081)
			(xy 90.965342 -238.290053) (xy 90.921268 -238.264607) (xy 90.881846 -238.23242) (xy 90.848098 -238.194326)
			(xy 90.820897 -238.151312) (xy 90.800949 -238.104492) (xy 90.78877 -238.055078) (xy 90.784675 -238.00435)
			(xy 90.466418 -238.00435) (xy 90.465923 -238.028957) (xy 90.458028 -238.077534) (xy 90.442444 -238.124215)
			(xy 90.419573 -238.167792) (xy 90.390008 -238.207136) (xy 90.354515 -238.241228) (xy 90.314012 -238.269184)
			(xy 90.26955 -238.290282) (xy 90.222279 -238.303974) (xy 90.173424 -238.309906) (xy 90.124249 -238.307925)
			(xy 90.07603 -238.298081) (xy 90.030014 -238.280629) (xy 89.987393 -238.256022) (xy 89.949272 -238.224897)
			(xy 89.916637 -238.18806) (xy 89.890334 -238.146464) (xy 89.871043 -238.101188) (xy 89.859266 -238.053404)
			(xy 89.855306 -238.00435) (xy 89.536778 -238.00435) (xy 89.536266 -238.029796) (xy 89.528102 -238.08003)
			(xy 89.511986 -238.128304) (xy 89.488335 -238.173367) (xy 89.457762 -238.214053) (xy 89.421058 -238.249308)
			(xy 89.379174 -238.278218) (xy 89.333195 -238.300035) (xy 89.284311 -238.314195) (xy 89.23379 -238.320329)
			(xy 89.182938 -238.31828) (xy 89.133074 -238.3081) (xy 89.085488 -238.290053) (xy 89.041414 -238.264607)
			(xy 89.001992 -238.23242) (xy 88.968244 -238.194326) (xy 88.941043 -238.151312) (xy 88.921095 -238.104492)
			(xy 88.908916 -238.055078) (xy 88.904821 -238.00435) (xy 88.58631 -238.00435) (xy 88.585815 -238.028957)
			(xy 88.57792 -238.077534) (xy 88.562336 -238.124215) (xy 88.539465 -238.167792) (xy 88.5099 -238.207136)
			(xy 88.474407 -238.241228) (xy 88.433904 -238.269184) (xy 88.389442 -238.290282) (xy 88.342171 -238.303974)
			(xy 88.293316 -238.309906) (xy 88.244141 -238.307925) (xy 88.195922 -238.298081) (xy 88.149906 -238.280629)
			(xy 88.107285 -238.256022) (xy 88.069164 -238.224897) (xy 88.036529 -238.18806) (xy 88.010226 -238.146464)
			(xy 87.990935 -238.101188) (xy 87.979158 -238.053404) (xy 87.975198 -238.00435) (xy 87.65667 -238.00435)
			(xy 87.656158 -238.029796) (xy 87.647994 -238.08003) (xy 87.631878 -238.128304) (xy 87.608227 -238.173367)
			(xy 87.577654 -238.214053) (xy 87.54095 -238.249308) (xy 87.499066 -238.278218) (xy 87.453087 -238.300035)
			(xy 87.404203 -238.314195) (xy 87.353682 -238.320329) (xy 87.30283 -238.31828) (xy 87.252966 -238.3081)
			(xy 87.20538 -238.290053) (xy 87.161306 -238.264607) (xy 87.121884 -238.23242) (xy 87.088136 -238.194326)
			(xy 87.060935 -238.151312) (xy 87.040987 -238.104492) (xy 87.028808 -238.055078) (xy 87.024713 -238.00435)
			(xy 86.706456 -238.00435) (xy 86.705961 -238.028957) (xy 86.698066 -238.077534) (xy 86.682482 -238.124215)
			(xy 86.659611 -238.167792) (xy 86.630046 -238.207136) (xy 86.594553 -238.241228) (xy 86.55405 -238.269184)
			(xy 86.509588 -238.290282) (xy 86.462317 -238.303974) (xy 86.413462 -238.309906) (xy 86.364287 -238.307925)
			(xy 86.316068 -238.298081) (xy 86.270052 -238.280629) (xy 86.227431 -238.256022) (xy 86.18931 -238.224897)
			(xy 86.156675 -238.18806) (xy 86.130372 -238.146464) (xy 86.111081 -238.101188) (xy 86.099304 -238.053404)
			(xy 86.095344 -238.00435) (xy 85.776816 -238.00435) (xy 85.776304 -238.029796) (xy 85.76814 -238.08003)
			(xy 85.752024 -238.128304) (xy 85.728373 -238.173367) (xy 85.6978 -238.214053) (xy 85.661096 -238.249308)
			(xy 85.619212 -238.278218) (xy 85.573233 -238.300035) (xy 85.524349 -238.314195) (xy 85.473828 -238.320329)
			(xy 85.422976 -238.31828) (xy 85.373112 -238.3081) (xy 85.325526 -238.290053) (xy 85.281452 -238.264607)
			(xy 85.24203 -238.23242) (xy 85.208282 -238.194326) (xy 85.181081 -238.151312) (xy 85.161133 -238.104492)
			(xy 85.148954 -238.055078) (xy 85.144859 -238.00435) (xy 84.836762 -238.00435) (xy 84.83625 -238.029796)
			(xy 84.828086 -238.08003) (xy 84.81197 -238.128304) (xy 84.788319 -238.173367) (xy 84.757746 -238.214053)
			(xy 84.721042 -238.249308) (xy 84.679158 -238.278218) (xy 84.633179 -238.300035) (xy 84.584295 -238.314195)
			(xy 84.533774 -238.320329) (xy 84.482922 -238.31828) (xy 84.433058 -238.3081) (xy 84.385472 -238.290053)
			(xy 84.341398 -238.264607) (xy 84.301976 -238.23242) (xy 84.268228 -238.194326) (xy 84.241027 -238.151312)
			(xy 84.221079 -238.104492) (xy 84.2089 -238.055078) (xy 84.204805 -238.00435) (xy 83.886294 -238.00435)
			(xy 83.885799 -238.028957) (xy 83.877904 -238.077534) (xy 83.86232 -238.124215) (xy 83.839449 -238.167792)
			(xy 83.809884 -238.207136) (xy 83.774391 -238.241228) (xy 83.733888 -238.269184) (xy 83.689426 -238.290282)
			(xy 83.642155 -238.303974) (xy 83.5933 -238.309906) (xy 83.544125 -238.307925) (xy 83.495906 -238.298081)
			(xy 83.44989 -238.280629) (xy 83.407269 -238.256022) (xy 83.369148 -238.224897) (xy 83.336513 -238.18806)
			(xy 83.31021 -238.146464) (xy 83.290919 -238.101188) (xy 83.279142 -238.053404) (xy 83.275182 -238.00435)
			(xy 82.956654 -238.00435) (xy 82.956142 -238.029796) (xy 82.947978 -238.08003) (xy 82.931862 -238.128304)
			(xy 82.908211 -238.173367) (xy 82.877638 -238.214053) (xy 82.840934 -238.249308) (xy 82.79905 -238.278218)
			(xy 82.753071 -238.300035) (xy 82.704187 -238.314195) (xy 82.653666 -238.320329) (xy 82.602814 -238.31828)
			(xy 82.55295 -238.3081) (xy 82.505364 -238.290053) (xy 82.46129 -238.264607) (xy 82.421868 -238.23242)
			(xy 82.38812 -238.194326) (xy 82.360919 -238.151312) (xy 82.340971 -238.104492) (xy 82.328792 -238.055078)
			(xy 82.324697 -238.00435) (xy 82.00644 -238.00435) (xy 82.005945 -238.028957) (xy 81.99805 -238.077534)
			(xy 81.982466 -238.124215) (xy 81.959595 -238.167792) (xy 81.93003 -238.207136) (xy 81.894537 -238.241228)
			(xy 81.854034 -238.269184) (xy 81.809572 -238.290282) (xy 81.762301 -238.303974) (xy 81.713446 -238.309906)
			(xy 81.664271 -238.307925) (xy 81.616052 -238.298081) (xy 81.570036 -238.280629) (xy 81.527415 -238.256022)
			(xy 81.489294 -238.224897) (xy 81.456659 -238.18806) (xy 81.430356 -238.146464) (xy 81.411065 -238.101188)
			(xy 81.399288 -238.053404) (xy 81.395328 -238.00435) (xy 81.0768 -238.00435) (xy 81.076288 -238.029796)
			(xy 81.068124 -238.08003) (xy 81.052008 -238.128304) (xy 81.028357 -238.173367) (xy 80.997784 -238.214053)
			(xy 80.96108 -238.249308) (xy 80.919196 -238.278218) (xy 80.873217 -238.300035) (xy 80.824333 -238.314195)
			(xy 80.773812 -238.320329) (xy 80.72296 -238.31828) (xy 80.673096 -238.3081) (xy 80.62551 -238.290053)
			(xy 80.581436 -238.264607) (xy 80.542014 -238.23242) (xy 80.508266 -238.194326) (xy 80.481065 -238.151312)
			(xy 80.461117 -238.104492) (xy 80.448938 -238.055078) (xy 80.444843 -238.00435) (xy 80.126332 -238.00435)
			(xy 80.125837 -238.028957) (xy 80.117942 -238.077534) (xy 80.102358 -238.124215) (xy 80.079487 -238.167792)
			(xy 80.049922 -238.207136) (xy 80.014429 -238.241228) (xy 79.973926 -238.269184) (xy 79.929464 -238.290282)
			(xy 79.882193 -238.303974) (xy 79.833338 -238.309906) (xy 79.784163 -238.307925) (xy 79.735944 -238.298081)
			(xy 79.689928 -238.280629) (xy 79.647307 -238.256022) (xy 79.609186 -238.224897) (xy 79.576551 -238.18806)
			(xy 79.550248 -238.146464) (xy 79.530957 -238.101188) (xy 79.51918 -238.053404) (xy 79.51522 -238.00435)
			(xy 76.963477 -238.00435) (xy 76.965804 -238.005454) (xy 77.006307 -238.03341) (xy 77.0418 -238.067502)
			(xy 77.071365 -238.106846) (xy 77.094236 -238.150423) (xy 77.10982 -238.197104) (xy 77.117715 -238.245681)
			(xy 77.11821 -238.270288) (xy 77.117715 -238.294895) (xy 77.10982 -238.343472) (xy 77.094236 -238.390153)
			(xy 77.071365 -238.43373) (xy 77.0418 -238.473074) (xy 77.006307 -238.507166) (xy 76.965804 -238.535122)
			(xy 76.921342 -238.55622) (xy 76.874071 -238.569912) (xy 76.825216 -238.575844) (xy 76.776041 -238.573863)
			(xy 76.727822 -238.564019) (xy 76.681806 -238.546567) (xy 76.639185 -238.52196) (xy 76.601064 -238.490835)
			(xy 76.568429 -238.453998) (xy 76.542126 -238.412402) (xy 76.522835 -238.367126) (xy 76.511058 -238.319342)
			(xy 76.507098 -238.270288) (xy 62.37732 -238.270288) (xy 62.37732 -238.814356) (xy 78.105266 -238.814356)
			(xy 78.109226 -238.765302) (xy 78.121003 -238.717518) (xy 78.140294 -238.672242) (xy 78.166597 -238.630646)
			(xy 78.199232 -238.593809) (xy 78.237353 -238.562684) (xy 78.279974 -238.538077) (xy 78.32599 -238.520625)
			(xy 78.374209 -238.510781) (xy 78.423384 -238.5088) (xy 78.472239 -238.514732) (xy 78.51951 -238.528424)
			(xy 78.563972 -238.549522) (xy 78.604475 -238.577478) (xy 78.639968 -238.61157) (xy 78.669533 -238.650914)
			(xy 78.692404 -238.694491) (xy 78.707988 -238.741172) (xy 78.715883 -238.789749) (xy 78.716378 -238.814356)
			(xy 79.985374 -238.814356) (xy 79.989334 -238.765302) (xy 80.001111 -238.717518) (xy 80.020402 -238.672242)
			(xy 80.046705 -238.630646) (xy 80.07934 -238.593809) (xy 80.117461 -238.562684) (xy 80.160082 -238.538077)
			(xy 80.206098 -238.520625) (xy 80.254317 -238.510781) (xy 80.303492 -238.5088) (xy 80.352347 -238.514732)
			(xy 80.399618 -238.528424) (xy 80.44408 -238.549522) (xy 80.484583 -238.577478) (xy 80.520076 -238.61157)
			(xy 80.549641 -238.650914) (xy 80.572512 -238.694491) (xy 80.588096 -238.741172) (xy 80.595991 -238.789749)
			(xy 80.596486 -238.814356) (xy 80.914743 -238.814356) (xy 80.918838 -238.763628) (xy 80.931017 -238.714214)
			(xy 80.950965 -238.667394) (xy 80.978166 -238.62438) (xy 81.011914 -238.586286) (xy 81.051336 -238.554099)
			(xy 81.09541 -238.528653) (xy 81.142996 -238.510606) (xy 81.19286 -238.500426) (xy 81.243712 -238.498377)
			(xy 81.294233 -238.504511) (xy 81.343117 -238.518671) (xy 81.389096 -238.540488) (xy 81.43098 -238.569398)
			(xy 81.467684 -238.604653) (xy 81.498257 -238.645339) (xy 81.521908 -238.690402) (xy 81.538024 -238.738676)
			(xy 81.546188 -238.78891) (xy 81.5467 -238.814356) (xy 81.854797 -238.814356) (xy 81.858892 -238.763628)
			(xy 81.871071 -238.714214) (xy 81.891019 -238.667394) (xy 81.91822 -238.62438) (xy 81.951968 -238.586286)
			(xy 81.99139 -238.554099) (xy 82.035464 -238.528653) (xy 82.08305 -238.510606) (xy 82.132914 -238.500426)
			(xy 82.183766 -238.498377) (xy 82.234287 -238.504511) (xy 82.283171 -238.518671) (xy 82.32915 -238.540488)
			(xy 82.371034 -238.569398) (xy 82.407738 -238.604653) (xy 82.438311 -238.645339) (xy 82.461962 -238.690402)
			(xy 82.478078 -238.738676) (xy 82.486242 -238.78891) (xy 82.486754 -238.814356) (xy 82.805282 -238.814356)
			(xy 82.809242 -238.765302) (xy 82.821019 -238.717518) (xy 82.84031 -238.672242) (xy 82.866613 -238.630646)
			(xy 82.899248 -238.593809) (xy 82.937369 -238.562684) (xy 82.97999 -238.538077) (xy 83.026006 -238.520625)
			(xy 83.074225 -238.510781) (xy 83.1234 -238.5088) (xy 83.172255 -238.514732) (xy 83.219526 -238.528424)
			(xy 83.263988 -238.549522) (xy 83.304491 -238.577478) (xy 83.339984 -238.61157) (xy 83.369549 -238.650914)
			(xy 83.39242 -238.694491) (xy 83.408004 -238.741172) (xy 83.415899 -238.789749) (xy 83.416394 -238.814356)
			(xy 83.734905 -238.814356) (xy 83.739 -238.763628) (xy 83.751179 -238.714214) (xy 83.771127 -238.667394)
			(xy 83.798328 -238.62438) (xy 83.832076 -238.586286) (xy 83.871498 -238.554099) (xy 83.915572 -238.528653)
			(xy 83.963158 -238.510606) (xy 84.013022 -238.500426) (xy 84.063874 -238.498377) (xy 84.114395 -238.504511)
			(xy 84.163279 -238.518671) (xy 84.209258 -238.540488) (xy 84.251142 -238.569398) (xy 84.287846 -238.604653)
			(xy 84.318419 -238.645339) (xy 84.34207 -238.690402) (xy 84.358186 -238.738676) (xy 84.36635 -238.78891)
			(xy 84.366862 -238.814356) (xy 84.685136 -238.814356) (xy 84.689096 -238.765302) (xy 84.700873 -238.717518)
			(xy 84.720164 -238.672242) (xy 84.746467 -238.630646) (xy 84.779102 -238.593809) (xy 84.817223 -238.562684)
			(xy 84.859844 -238.538077) (xy 84.90586 -238.520625) (xy 84.954079 -238.510781) (xy 85.003254 -238.5088)
			(xy 85.052109 -238.514732) (xy 85.09938 -238.528424) (xy 85.143842 -238.549522) (xy 85.184345 -238.577478)
			(xy 85.219838 -238.61157) (xy 85.249403 -238.650914) (xy 85.272274 -238.694491) (xy 85.287858 -238.741172)
			(xy 85.295753 -238.789749) (xy 85.296248 -238.814356) (xy 85.614759 -238.814356) (xy 85.618854 -238.763628)
			(xy 85.631033 -238.714214) (xy 85.650981 -238.667394) (xy 85.678182 -238.62438) (xy 85.71193 -238.586286)
			(xy 85.751352 -238.554099) (xy 85.795426 -238.528653) (xy 85.843012 -238.510606) (xy 85.892876 -238.500426)
			(xy 85.943728 -238.498377) (xy 85.994249 -238.504511) (xy 86.043133 -238.518671) (xy 86.089112 -238.540488)
			(xy 86.130996 -238.569398) (xy 86.1677 -238.604653) (xy 86.198273 -238.645339) (xy 86.221924 -238.690402)
			(xy 86.23804 -238.738676) (xy 86.246204 -238.78891) (xy 86.246716 -238.814356) (xy 86.565244 -238.814356)
			(xy 86.569204 -238.765302) (xy 86.580981 -238.717518) (xy 86.600272 -238.672242) (xy 86.626575 -238.630646)
			(xy 86.65921 -238.593809) (xy 86.697331 -238.562684) (xy 86.739952 -238.538077) (xy 86.785968 -238.520625)
			(xy 86.834187 -238.510781) (xy 86.883362 -238.5088) (xy 86.932217 -238.514732) (xy 86.979488 -238.528424)
			(xy 87.02395 -238.549522) (xy 87.064453 -238.577478) (xy 87.099946 -238.61157) (xy 87.129511 -238.650914)
			(xy 87.152382 -238.694491) (xy 87.167966 -238.741172) (xy 87.175861 -238.789749) (xy 87.176356 -238.814356)
			(xy 87.494867 -238.814356) (xy 87.498962 -238.763628) (xy 87.511141 -238.714214) (xy 87.531089 -238.667394)
			(xy 87.55829 -238.62438) (xy 87.592038 -238.586286) (xy 87.63146 -238.554099) (xy 87.675534 -238.528653)
			(xy 87.72312 -238.510606) (xy 87.772984 -238.500426) (xy 87.823836 -238.498377) (xy 87.874357 -238.504511)
			(xy 87.923241 -238.518671) (xy 87.96922 -238.540488) (xy 88.011104 -238.569398) (xy 88.047808 -238.604653)
			(xy 88.078381 -238.645339) (xy 88.102032 -238.690402) (xy 88.118148 -238.738676) (xy 88.126312 -238.78891)
			(xy 88.126824 -238.814356) (xy 88.434921 -238.814356) (xy 88.439016 -238.763628) (xy 88.451195 -238.714214)
			(xy 88.471143 -238.667394) (xy 88.498344 -238.62438) (xy 88.532092 -238.586286) (xy 88.571514 -238.554099)
			(xy 88.615588 -238.528653) (xy 88.663174 -238.510606) (xy 88.713038 -238.500426) (xy 88.76389 -238.498377)
			(xy 88.814411 -238.504511) (xy 88.863295 -238.518671) (xy 88.909274 -238.540488) (xy 88.951158 -238.569398)
			(xy 88.987862 -238.604653) (xy 89.018435 -238.645339) (xy 89.042086 -238.690402) (xy 89.058202 -238.738676)
			(xy 89.066366 -238.78891) (xy 89.066878 -238.814356) (xy 89.385152 -238.814356) (xy 89.389112 -238.765302)
			(xy 89.400889 -238.717518) (xy 89.42018 -238.672242) (xy 89.446483 -238.630646) (xy 89.479118 -238.593809)
			(xy 89.517239 -238.562684) (xy 89.55986 -238.538077) (xy 89.605876 -238.520625) (xy 89.654095 -238.510781)
			(xy 89.70327 -238.5088) (xy 89.752125 -238.514732) (xy 89.799396 -238.528424) (xy 89.843858 -238.549522)
			(xy 89.884361 -238.577478) (xy 89.919854 -238.61157) (xy 89.949419 -238.650914) (xy 89.97229 -238.694491)
			(xy 89.987874 -238.741172) (xy 89.995769 -238.789749) (xy 89.996264 -238.814356) (xy 90.314775 -238.814356)
			(xy 90.31887 -238.763628) (xy 90.331049 -238.714214) (xy 90.350997 -238.667394) (xy 90.378198 -238.62438)
			(xy 90.411946 -238.586286) (xy 90.451368 -238.554099) (xy 90.495442 -238.528653) (xy 90.543028 -238.510606)
			(xy 90.592892 -238.500426) (xy 90.643744 -238.498377) (xy 90.694265 -238.504511) (xy 90.743149 -238.518671)
			(xy 90.789128 -238.540488) (xy 90.831012 -238.569398) (xy 90.867716 -238.604653) (xy 90.898289 -238.645339)
			(xy 90.92194 -238.690402) (xy 90.938056 -238.738676) (xy 90.94622 -238.78891) (xy 90.946732 -238.814356)
			(xy 91.26526 -238.814356) (xy 91.26922 -238.765302) (xy 91.280997 -238.717518) (xy 91.300288 -238.672242)
			(xy 91.326591 -238.630646) (xy 91.359226 -238.593809) (xy 91.397347 -238.562684) (xy 91.439968 -238.538077)
			(xy 91.485984 -238.520625) (xy 91.534203 -238.510781) (xy 91.583378 -238.5088) (xy 91.632233 -238.514732)
			(xy 91.679504 -238.528424) (xy 91.723966 -238.549522) (xy 91.764469 -238.577478) (xy 91.799962 -238.61157)
			(xy 91.829527 -238.650914) (xy 91.852398 -238.694491) (xy 91.867982 -238.741172) (xy 91.875877 -238.789749)
			(xy 91.876372 -238.814356) (xy 92.194883 -238.814356) (xy 92.198978 -238.763628) (xy 92.211157 -238.714214)
			(xy 92.231105 -238.667394) (xy 92.258306 -238.62438) (xy 92.292054 -238.586286) (xy 92.331476 -238.554099)
			(xy 92.37555 -238.528653) (xy 92.423136 -238.510606) (xy 92.473 -238.500426) (xy 92.523852 -238.498377)
			(xy 92.574373 -238.504511) (xy 92.623257 -238.518671) (xy 92.669236 -238.540488) (xy 92.71112 -238.569398)
			(xy 92.747824 -238.604653) (xy 92.778397 -238.645339) (xy 92.802048 -238.690402) (xy 92.818164 -238.738676)
			(xy 92.826328 -238.78891) (xy 92.82684 -238.814356) (xy 93.145114 -238.814356) (xy 93.149074 -238.765302)
			(xy 93.160851 -238.717518) (xy 93.180142 -238.672242) (xy 93.206445 -238.630646) (xy 93.23908 -238.593809)
			(xy 93.277201 -238.562684) (xy 93.319822 -238.538077) (xy 93.365838 -238.520625) (xy 93.414057 -238.510781)
			(xy 93.463232 -238.5088) (xy 93.512087 -238.514732) (xy 93.559358 -238.528424) (xy 93.60382 -238.549522)
			(xy 93.644323 -238.577478) (xy 93.679816 -238.61157) (xy 93.709381 -238.650914) (xy 93.732252 -238.694491)
			(xy 93.747836 -238.741172) (xy 93.755731 -238.789749) (xy 93.756226 -238.814356) (xy 94.074737 -238.814356)
			(xy 94.078832 -238.763628) (xy 94.091011 -238.714214) (xy 94.110959 -238.667394) (xy 94.13816 -238.62438)
			(xy 94.171908 -238.586286) (xy 94.21133 -238.554099) (xy 94.255404 -238.528653) (xy 94.30299 -238.510606)
			(xy 94.352854 -238.500426) (xy 94.403706 -238.498377) (xy 94.454227 -238.504511) (xy 94.503111 -238.518671)
			(xy 94.54909 -238.540488) (xy 94.590974 -238.569398) (xy 94.627678 -238.604653) (xy 94.658251 -238.645339)
			(xy 94.681902 -238.690402) (xy 94.698018 -238.738676) (xy 94.706182 -238.78891) (xy 94.706694 -238.814356)
			(xy 95.014791 -238.814356) (xy 95.018886 -238.763628) (xy 95.031065 -238.714214) (xy 95.051013 -238.667394)
			(xy 95.078214 -238.62438) (xy 95.111962 -238.586286) (xy 95.151384 -238.554099) (xy 95.195458 -238.528653)
			(xy 95.243044 -238.510606) (xy 95.292908 -238.500426) (xy 95.34376 -238.498377) (xy 95.394281 -238.504511)
			(xy 95.443165 -238.518671) (xy 95.489144 -238.540488) (xy 95.531028 -238.569398) (xy 95.567732 -238.604653)
			(xy 95.598305 -238.645339) (xy 95.621956 -238.690402) (xy 95.638072 -238.738676) (xy 95.646236 -238.78891)
			(xy 95.646748 -238.814356) (xy 95.965276 -238.814356) (xy 95.969236 -238.765302) (xy 95.981013 -238.717518)
			(xy 96.000304 -238.672242) (xy 96.026607 -238.630646) (xy 96.059242 -238.593809) (xy 96.097363 -238.562684)
			(xy 96.139984 -238.538077) (xy 96.186 -238.520625) (xy 96.234219 -238.510781) (xy 96.283394 -238.5088)
			(xy 96.332249 -238.514732) (xy 96.37952 -238.528424) (xy 96.423982 -238.549522) (xy 96.464485 -238.577478)
			(xy 96.499978 -238.61157) (xy 96.529543 -238.650914) (xy 96.552414 -238.694491) (xy 96.567998 -238.741172)
			(xy 96.575893 -238.789749) (xy 96.576388 -238.814356) (xy 98.785184 -238.814356) (xy 98.789144 -238.765302)
			(xy 98.800921 -238.717518) (xy 98.820212 -238.672242) (xy 98.846515 -238.630646) (xy 98.87915 -238.593809)
			(xy 98.917271 -238.562684) (xy 98.959892 -238.538077) (xy 99.005908 -238.520625) (xy 99.054127 -238.510781)
			(xy 99.103302 -238.5088) (xy 99.152157 -238.514732) (xy 99.199428 -238.528424) (xy 99.24389 -238.549522)
			(xy 99.284393 -238.577478) (xy 99.319886 -238.61157) (xy 99.349451 -238.650914) (xy 99.372322 -238.694491)
			(xy 99.387906 -238.741172) (xy 99.395801 -238.789749) (xy 99.396296 -238.814356) (xy 101.605346 -238.814356)
			(xy 101.609306 -238.765302) (xy 101.621083 -238.717518) (xy 101.640374 -238.672242) (xy 101.666677 -238.630646)
			(xy 101.699312 -238.593809) (xy 101.737433 -238.562684) (xy 101.780054 -238.538077) (xy 101.82607 -238.520625)
			(xy 101.874289 -238.510781) (xy 101.923464 -238.5088) (xy 101.972319 -238.514732) (xy 102.01959 -238.528424)
			(xy 102.064052 -238.549522) (xy 102.104555 -238.577478) (xy 102.140048 -238.61157) (xy 102.169613 -238.650914)
			(xy 102.192484 -238.694491) (xy 102.208068 -238.741172) (xy 102.215963 -238.789749) (xy 102.216458 -238.814356)
			(xy 104.425254 -238.814356) (xy 104.429214 -238.765302) (xy 104.440991 -238.717518) (xy 104.460282 -238.672242)
			(xy 104.486585 -238.630646) (xy 104.51922 -238.593809) (xy 104.557341 -238.562684) (xy 104.599962 -238.538077)
			(xy 104.645978 -238.520625) (xy 104.694197 -238.510781) (xy 104.743372 -238.5088) (xy 104.792227 -238.514732)
			(xy 104.839498 -238.528424) (xy 104.88396 -238.549522) (xy 104.924463 -238.577478) (xy 104.959956 -238.61157)
			(xy 104.989521 -238.650914) (xy 105.012392 -238.694491) (xy 105.027976 -238.741172) (xy 105.035871 -238.789749)
			(xy 105.036366 -238.814356) (xy 107.245162 -238.814356) (xy 107.249122 -238.765302) (xy 107.260899 -238.717518)
			(xy 107.28019 -238.672242) (xy 107.306493 -238.630646) (xy 107.339128 -238.593809) (xy 107.377249 -238.562684)
			(xy 107.41987 -238.538077) (xy 107.465886 -238.520625) (xy 107.514105 -238.510781) (xy 107.56328 -238.5088)
			(xy 107.612135 -238.514732) (xy 107.659406 -238.528424) (xy 107.703868 -238.549522) (xy 107.744371 -238.577478)
			(xy 107.779864 -238.61157) (xy 107.809429 -238.650914) (xy 107.8323 -238.694491) (xy 107.847884 -238.741172)
			(xy 107.855779 -238.789749) (xy 107.856274 -238.814356) (xy 108.174785 -238.814356) (xy 108.17888 -238.763628)
			(xy 108.191059 -238.714214) (xy 108.211007 -238.667394) (xy 108.238208 -238.62438) (xy 108.271956 -238.586286)
			(xy 108.311378 -238.554099) (xy 108.355452 -238.528653) (xy 108.403038 -238.510606) (xy 108.452902 -238.500426)
			(xy 108.503754 -238.498377) (xy 108.554275 -238.504511) (xy 108.603159 -238.518671) (xy 108.649138 -238.540488)
			(xy 108.691022 -238.569398) (xy 108.727726 -238.604653) (xy 108.758299 -238.645339) (xy 108.78195 -238.690402)
			(xy 108.798066 -238.738676) (xy 108.80623 -238.78891) (xy 108.806742 -238.814356) (xy 109.114839 -238.814356)
			(xy 109.118934 -238.763628) (xy 109.131113 -238.714214) (xy 109.151061 -238.667394) (xy 109.178262 -238.62438)
			(xy 109.21201 -238.586286) (xy 109.251432 -238.554099) (xy 109.295506 -238.528653) (xy 109.343092 -238.510606)
			(xy 109.392956 -238.500426) (xy 109.443808 -238.498377) (xy 109.494329 -238.504511) (xy 109.543213 -238.518671)
			(xy 109.589192 -238.540488) (xy 109.631076 -238.569398) (xy 109.66778 -238.604653) (xy 109.698353 -238.645339)
			(xy 109.722004 -238.690402) (xy 109.73812 -238.738676) (xy 109.746284 -238.78891) (xy 109.746796 -238.814356)
			(xy 110.065324 -238.814356) (xy 110.069284 -238.765302) (xy 110.081061 -238.717518) (xy 110.100352 -238.672242)
			(xy 110.126655 -238.630646) (xy 110.15929 -238.593809) (xy 110.197411 -238.562684) (xy 110.240032 -238.538077)
			(xy 110.286048 -238.520625) (xy 110.334267 -238.510781) (xy 110.383442 -238.5088) (xy 110.432297 -238.514732)
			(xy 110.479568 -238.528424) (xy 110.52403 -238.549522) (xy 110.564533 -238.577478) (xy 110.600026 -238.61157)
			(xy 110.629591 -238.650914) (xy 110.652462 -238.694491) (xy 110.668046 -238.741172) (xy 110.675941 -238.789749)
			(xy 110.676436 -238.814356) (xy 110.675941 -238.838963) (xy 110.668046 -238.88754) (xy 110.652462 -238.934221)
			(xy 110.629591 -238.977798) (xy 110.600026 -239.017142) (xy 110.564533 -239.051234) (xy 110.52403 -239.07919)
			(xy 110.479568 -239.100288) (xy 110.432297 -239.11398) (xy 110.383442 -239.119912) (xy 110.334267 -239.117931)
			(xy 110.286048 -239.108087) (xy 110.240032 -239.090635) (xy 110.197411 -239.066028) (xy 110.15929 -239.034903)
			(xy 110.126655 -238.998066) (xy 110.100352 -238.95647) (xy 110.081061 -238.911194) (xy 110.069284 -238.86341)
			(xy 110.065324 -238.814356) (xy 109.746796 -238.814356) (xy 109.746284 -238.839802) (xy 109.73812 -238.890036)
			(xy 109.722004 -238.93831) (xy 109.698353 -238.983373) (xy 109.66778 -239.024059) (xy 109.631076 -239.059314)
			(xy 109.589192 -239.088224) (xy 109.543213 -239.110041) (xy 109.494329 -239.124201) (xy 109.443808 -239.130335)
			(xy 109.392956 -239.128286) (xy 109.343092 -239.118106) (xy 109.295506 -239.100059) (xy 109.251432 -239.074613)
			(xy 109.21201 -239.042426) (xy 109.178262 -239.004332) (xy 109.151061 -238.961318) (xy 109.131113 -238.914498)
			(xy 109.118934 -238.865084) (xy 109.114839 -238.814356) (xy 108.806742 -238.814356) (xy 108.80623 -238.839802)
			(xy 108.798066 -238.890036) (xy 108.78195 -238.93831) (xy 108.758299 -238.983373) (xy 108.727726 -239.024059)
			(xy 108.691022 -239.059314) (xy 108.649138 -239.088224) (xy 108.603159 -239.110041) (xy 108.554275 -239.124201)
			(xy 108.503754 -239.130335) (xy 108.452902 -239.128286) (xy 108.403038 -239.118106) (xy 108.355452 -239.100059)
			(xy 108.311378 -239.074613) (xy 108.271956 -239.042426) (xy 108.238208 -239.004332) (xy 108.211007 -238.961318)
			(xy 108.191059 -238.914498) (xy 108.17888 -238.865084) (xy 108.174785 -238.814356) (xy 107.856274 -238.814356)
			(xy 107.855779 -238.838963) (xy 107.847884 -238.88754) (xy 107.8323 -238.934221) (xy 107.809429 -238.977798)
			(xy 107.779864 -239.017142) (xy 107.744371 -239.051234) (xy 107.703868 -239.07919) (xy 107.659406 -239.100288)
			(xy 107.612135 -239.11398) (xy 107.56328 -239.119912) (xy 107.514105 -239.117931) (xy 107.465886 -239.108087)
			(xy 107.41987 -239.090635) (xy 107.377249 -239.066028) (xy 107.339128 -239.034903) (xy 107.306493 -238.998066)
			(xy 107.28019 -238.95647) (xy 107.260899 -238.911194) (xy 107.249122 -238.86341) (xy 107.245162 -238.814356)
			(xy 105.036366 -238.814356) (xy 105.035871 -238.838963) (xy 105.027976 -238.88754) (xy 105.012392 -238.934221)
			(xy 104.989521 -238.977798) (xy 104.959956 -239.017142) (xy 104.924463 -239.051234) (xy 104.88396 -239.07919)
			(xy 104.839498 -239.100288) (xy 104.792227 -239.11398) (xy 104.743372 -239.119912) (xy 104.694197 -239.117931)
			(xy 104.645978 -239.108087) (xy 104.599962 -239.090635) (xy 104.557341 -239.066028) (xy 104.51922 -239.034903)
			(xy 104.486585 -238.998066) (xy 104.460282 -238.95647) (xy 104.440991 -238.911194) (xy 104.429214 -238.86341)
			(xy 104.425254 -238.814356) (xy 102.216458 -238.814356) (xy 102.215963 -238.838963) (xy 102.208068 -238.88754)
			(xy 102.192484 -238.934221) (xy 102.169613 -238.977798) (xy 102.140048 -239.017142) (xy 102.104555 -239.051234)
			(xy 102.064052 -239.07919) (xy 102.01959 -239.100288) (xy 101.972319 -239.11398) (xy 101.923464 -239.119912)
			(xy 101.874289 -239.117931) (xy 101.82607 -239.108087) (xy 101.780054 -239.090635) (xy 101.737433 -239.066028)
			(xy 101.699312 -239.034903) (xy 101.666677 -238.998066) (xy 101.640374 -238.95647) (xy 101.621083 -238.911194)
			(xy 101.609306 -238.86341) (xy 101.605346 -238.814356) (xy 99.396296 -238.814356) (xy 99.395801 -238.838963)
			(xy 99.387906 -238.88754) (xy 99.372322 -238.934221) (xy 99.349451 -238.977798) (xy 99.319886 -239.017142)
			(xy 99.284393 -239.051234) (xy 99.24389 -239.07919) (xy 99.199428 -239.100288) (xy 99.152157 -239.11398)
			(xy 99.103302 -239.119912) (xy 99.054127 -239.117931) (xy 99.005908 -239.108087) (xy 98.959892 -239.090635)
			(xy 98.917271 -239.066028) (xy 98.87915 -239.034903) (xy 98.846515 -238.998066) (xy 98.820212 -238.95647)
			(xy 98.800921 -238.911194) (xy 98.789144 -238.86341) (xy 98.785184 -238.814356) (xy 96.576388 -238.814356)
			(xy 96.575893 -238.838963) (xy 96.567998 -238.88754) (xy 96.552414 -238.934221) (xy 96.529543 -238.977798)
			(xy 96.499978 -239.017142) (xy 96.464485 -239.051234) (xy 96.423982 -239.07919) (xy 96.37952 -239.100288)
			(xy 96.332249 -239.11398) (xy 96.283394 -239.119912) (xy 96.234219 -239.117931) (xy 96.186 -239.108087)
			(xy 96.139984 -239.090635) (xy 96.097363 -239.066028) (xy 96.059242 -239.034903) (xy 96.026607 -238.998066)
			(xy 96.000304 -238.95647) (xy 95.981013 -238.911194) (xy 95.969236 -238.86341) (xy 95.965276 -238.814356)
			(xy 95.646748 -238.814356) (xy 95.646236 -238.839802) (xy 95.638072 -238.890036) (xy 95.621956 -238.93831)
			(xy 95.598305 -238.983373) (xy 95.567732 -239.024059) (xy 95.531028 -239.059314) (xy 95.489144 -239.088224)
			(xy 95.443165 -239.110041) (xy 95.394281 -239.124201) (xy 95.34376 -239.130335) (xy 95.292908 -239.128286)
			(xy 95.243044 -239.118106) (xy 95.195458 -239.100059) (xy 95.151384 -239.074613) (xy 95.111962 -239.042426)
			(xy 95.078214 -239.004332) (xy 95.051013 -238.961318) (xy 95.031065 -238.914498) (xy 95.018886 -238.865084)
			(xy 95.014791 -238.814356) (xy 94.706694 -238.814356) (xy 94.706182 -238.839802) (xy 94.698018 -238.890036)
			(xy 94.681902 -238.93831) (xy 94.658251 -238.983373) (xy 94.627678 -239.024059) (xy 94.590974 -239.059314)
			(xy 94.54909 -239.088224) (xy 94.503111 -239.110041) (xy 94.454227 -239.124201) (xy 94.403706 -239.130335)
			(xy 94.352854 -239.128286) (xy 94.30299 -239.118106) (xy 94.255404 -239.100059) (xy 94.21133 -239.074613)
			(xy 94.171908 -239.042426) (xy 94.13816 -239.004332) (xy 94.110959 -238.961318) (xy 94.091011 -238.914498)
			(xy 94.078832 -238.865084) (xy 94.074737 -238.814356) (xy 93.756226 -238.814356) (xy 93.755731 -238.838963)
			(xy 93.747836 -238.88754) (xy 93.732252 -238.934221) (xy 93.709381 -238.977798) (xy 93.679816 -239.017142)
			(xy 93.644323 -239.051234) (xy 93.60382 -239.07919) (xy 93.559358 -239.100288) (xy 93.512087 -239.11398)
			(xy 93.463232 -239.119912) (xy 93.414057 -239.117931) (xy 93.365838 -239.108087) (xy 93.319822 -239.090635)
			(xy 93.277201 -239.066028) (xy 93.23908 -239.034903) (xy 93.206445 -238.998066) (xy 93.180142 -238.95647)
			(xy 93.160851 -238.911194) (xy 93.149074 -238.86341) (xy 93.145114 -238.814356) (xy 92.82684 -238.814356)
			(xy 92.826328 -238.839802) (xy 92.818164 -238.890036) (xy 92.802048 -238.93831) (xy 92.778397 -238.983373)
			(xy 92.747824 -239.024059) (xy 92.71112 -239.059314) (xy 92.669236 -239.088224) (xy 92.623257 -239.110041)
			(xy 92.574373 -239.124201) (xy 92.523852 -239.130335) (xy 92.473 -239.128286) (xy 92.423136 -239.118106)
			(xy 92.37555 -239.100059) (xy 92.331476 -239.074613) (xy 92.292054 -239.042426) (xy 92.258306 -239.004332)
			(xy 92.231105 -238.961318) (xy 92.211157 -238.914498) (xy 92.198978 -238.865084) (xy 92.194883 -238.814356)
			(xy 91.876372 -238.814356) (xy 91.875877 -238.838963) (xy 91.867982 -238.88754) (xy 91.852398 -238.934221)
			(xy 91.829527 -238.977798) (xy 91.799962 -239.017142) (xy 91.764469 -239.051234) (xy 91.723966 -239.07919)
			(xy 91.679504 -239.100288) (xy 91.632233 -239.11398) (xy 91.583378 -239.119912) (xy 91.534203 -239.117931)
			(xy 91.485984 -239.108087) (xy 91.439968 -239.090635) (xy 91.397347 -239.066028) (xy 91.359226 -239.034903)
			(xy 91.326591 -238.998066) (xy 91.300288 -238.95647) (xy 91.280997 -238.911194) (xy 91.26922 -238.86341)
			(xy 91.26526 -238.814356) (xy 90.946732 -238.814356) (xy 90.94622 -238.839802) (xy 90.938056 -238.890036)
			(xy 90.92194 -238.93831) (xy 90.898289 -238.983373) (xy 90.867716 -239.024059) (xy 90.831012 -239.059314)
			(xy 90.789128 -239.088224) (xy 90.743149 -239.110041) (xy 90.694265 -239.124201) (xy 90.643744 -239.130335)
			(xy 90.592892 -239.128286) (xy 90.543028 -239.118106) (xy 90.495442 -239.100059) (xy 90.451368 -239.074613)
			(xy 90.411946 -239.042426) (xy 90.378198 -239.004332) (xy 90.350997 -238.961318) (xy 90.331049 -238.914498)
			(xy 90.31887 -238.865084) (xy 90.314775 -238.814356) (xy 89.996264 -238.814356) (xy 89.995769 -238.838963)
			(xy 89.987874 -238.88754) (xy 89.97229 -238.934221) (xy 89.949419 -238.977798) (xy 89.919854 -239.017142)
			(xy 89.884361 -239.051234) (xy 89.843858 -239.07919) (xy 89.799396 -239.100288) (xy 89.752125 -239.11398)
			(xy 89.70327 -239.119912) (xy 89.654095 -239.117931) (xy 89.605876 -239.108087) (xy 89.55986 -239.090635)
			(xy 89.517239 -239.066028) (xy 89.479118 -239.034903) (xy 89.446483 -238.998066) (xy 89.42018 -238.95647)
			(xy 89.400889 -238.911194) (xy 89.389112 -238.86341) (xy 89.385152 -238.814356) (xy 89.066878 -238.814356)
			(xy 89.066366 -238.839802) (xy 89.058202 -238.890036) (xy 89.042086 -238.93831) (xy 89.018435 -238.983373)
			(xy 88.987862 -239.024059) (xy 88.951158 -239.059314) (xy 88.909274 -239.088224) (xy 88.863295 -239.110041)
			(xy 88.814411 -239.124201) (xy 88.76389 -239.130335) (xy 88.713038 -239.128286) (xy 88.663174 -239.118106)
			(xy 88.615588 -239.100059) (xy 88.571514 -239.074613) (xy 88.532092 -239.042426) (xy 88.498344 -239.004332)
			(xy 88.471143 -238.961318) (xy 88.451195 -238.914498) (xy 88.439016 -238.865084) (xy 88.434921 -238.814356)
			(xy 88.126824 -238.814356) (xy 88.126312 -238.839802) (xy 88.118148 -238.890036) (xy 88.102032 -238.93831)
			(xy 88.078381 -238.983373) (xy 88.047808 -239.024059) (xy 88.011104 -239.059314) (xy 87.96922 -239.088224)
			(xy 87.923241 -239.110041) (xy 87.874357 -239.124201) (xy 87.823836 -239.130335) (xy 87.772984 -239.128286)
			(xy 87.72312 -239.118106) (xy 87.675534 -239.100059) (xy 87.63146 -239.074613) (xy 87.592038 -239.042426)
			(xy 87.55829 -239.004332) (xy 87.531089 -238.961318) (xy 87.511141 -238.914498) (xy 87.498962 -238.865084)
			(xy 87.494867 -238.814356) (xy 87.176356 -238.814356) (xy 87.175861 -238.838963) (xy 87.167966 -238.88754)
			(xy 87.152382 -238.934221) (xy 87.129511 -238.977798) (xy 87.099946 -239.017142) (xy 87.064453 -239.051234)
			(xy 87.02395 -239.07919) (xy 86.979488 -239.100288) (xy 86.932217 -239.11398) (xy 86.883362 -239.119912)
			(xy 86.834187 -239.117931) (xy 86.785968 -239.108087) (xy 86.739952 -239.090635) (xy 86.697331 -239.066028)
			(xy 86.65921 -239.034903) (xy 86.626575 -238.998066) (xy 86.600272 -238.95647) (xy 86.580981 -238.911194)
			(xy 86.569204 -238.86341) (xy 86.565244 -238.814356) (xy 86.246716 -238.814356) (xy 86.246204 -238.839802)
			(xy 86.23804 -238.890036) (xy 86.221924 -238.93831) (xy 86.198273 -238.983373) (xy 86.1677 -239.024059)
			(xy 86.130996 -239.059314) (xy 86.089112 -239.088224) (xy 86.043133 -239.110041) (xy 85.994249 -239.124201)
			(xy 85.943728 -239.130335) (xy 85.892876 -239.128286) (xy 85.843012 -239.118106) (xy 85.795426 -239.100059)
			(xy 85.751352 -239.074613) (xy 85.71193 -239.042426) (xy 85.678182 -239.004332) (xy 85.650981 -238.961318)
			(xy 85.631033 -238.914498) (xy 85.618854 -238.865084) (xy 85.614759 -238.814356) (xy 85.296248 -238.814356)
			(xy 85.295753 -238.838963) (xy 85.287858 -238.88754) (xy 85.272274 -238.934221) (xy 85.249403 -238.977798)
			(xy 85.219838 -239.017142) (xy 85.184345 -239.051234) (xy 85.143842 -239.07919) (xy 85.09938 -239.100288)
			(xy 85.052109 -239.11398) (xy 85.003254 -239.119912) (xy 84.954079 -239.117931) (xy 84.90586 -239.108087)
			(xy 84.859844 -239.090635) (xy 84.817223 -239.066028) (xy 84.779102 -239.034903) (xy 84.746467 -238.998066)
			(xy 84.720164 -238.95647) (xy 84.700873 -238.911194) (xy 84.689096 -238.86341) (xy 84.685136 -238.814356)
			(xy 84.366862 -238.814356) (xy 84.36635 -238.839802) (xy 84.358186 -238.890036) (xy 84.34207 -238.93831)
			(xy 84.318419 -238.983373) (xy 84.287846 -239.024059) (xy 84.251142 -239.059314) (xy 84.209258 -239.088224)
			(xy 84.163279 -239.110041) (xy 84.114395 -239.124201) (xy 84.063874 -239.130335) (xy 84.013022 -239.128286)
			(xy 83.963158 -239.118106) (xy 83.915572 -239.100059) (xy 83.871498 -239.074613) (xy 83.832076 -239.042426)
			(xy 83.798328 -239.004332) (xy 83.771127 -238.961318) (xy 83.751179 -238.914498) (xy 83.739 -238.865084)
			(xy 83.734905 -238.814356) (xy 83.416394 -238.814356) (xy 83.415899 -238.838963) (xy 83.408004 -238.88754)
			(xy 83.39242 -238.934221) (xy 83.369549 -238.977798) (xy 83.339984 -239.017142) (xy 83.304491 -239.051234)
			(xy 83.263988 -239.07919) (xy 83.219526 -239.100288) (xy 83.172255 -239.11398) (xy 83.1234 -239.119912)
			(xy 83.074225 -239.117931) (xy 83.026006 -239.108087) (xy 82.97999 -239.090635) (xy 82.937369 -239.066028)
			(xy 82.899248 -239.034903) (xy 82.866613 -238.998066) (xy 82.84031 -238.95647) (xy 82.821019 -238.911194)
			(xy 82.809242 -238.86341) (xy 82.805282 -238.814356) (xy 82.486754 -238.814356) (xy 82.486242 -238.839802)
			(xy 82.478078 -238.890036) (xy 82.461962 -238.93831) (xy 82.438311 -238.983373) (xy 82.407738 -239.024059)
			(xy 82.371034 -239.059314) (xy 82.32915 -239.088224) (xy 82.283171 -239.110041) (xy 82.234287 -239.124201)
			(xy 82.183766 -239.130335) (xy 82.132914 -239.128286) (xy 82.08305 -239.118106) (xy 82.035464 -239.100059)
			(xy 81.99139 -239.074613) (xy 81.951968 -239.042426) (xy 81.91822 -239.004332) (xy 81.891019 -238.961318)
			(xy 81.871071 -238.914498) (xy 81.858892 -238.865084) (xy 81.854797 -238.814356) (xy 81.5467 -238.814356)
			(xy 81.546188 -238.839802) (xy 81.538024 -238.890036) (xy 81.521908 -238.93831) (xy 81.498257 -238.983373)
			(xy 81.467684 -239.024059) (xy 81.43098 -239.059314) (xy 81.389096 -239.088224) (xy 81.343117 -239.110041)
			(xy 81.294233 -239.124201) (xy 81.243712 -239.130335) (xy 81.19286 -239.128286) (xy 81.142996 -239.118106)
			(xy 81.09541 -239.100059) (xy 81.051336 -239.074613) (xy 81.011914 -239.042426) (xy 80.978166 -239.004332)
			(xy 80.950965 -238.961318) (xy 80.931017 -238.914498) (xy 80.918838 -238.865084) (xy 80.914743 -238.814356)
			(xy 80.596486 -238.814356) (xy 80.595991 -238.838963) (xy 80.588096 -238.88754) (xy 80.572512 -238.934221)
			(xy 80.549641 -238.977798) (xy 80.520076 -239.017142) (xy 80.484583 -239.051234) (xy 80.44408 -239.07919)
			(xy 80.399618 -239.100288) (xy 80.352347 -239.11398) (xy 80.303492 -239.119912) (xy 80.254317 -239.117931)
			(xy 80.206098 -239.108087) (xy 80.160082 -239.090635) (xy 80.117461 -239.066028) (xy 80.07934 -239.034903)
			(xy 80.046705 -238.998066) (xy 80.020402 -238.95647) (xy 80.001111 -238.911194) (xy 79.989334 -238.86341)
			(xy 79.985374 -238.814356) (xy 78.716378 -238.814356) (xy 78.715883 -238.838963) (xy 78.707988 -238.88754)
			(xy 78.692404 -238.934221) (xy 78.669533 -238.977798) (xy 78.639968 -239.017142) (xy 78.604475 -239.051234)
			(xy 78.563972 -239.07919) (xy 78.51951 -239.100288) (xy 78.472239 -239.11398) (xy 78.423384 -239.119912)
			(xy 78.374209 -239.117931) (xy 78.32599 -239.108087) (xy 78.279974 -239.090635) (xy 78.237353 -239.066028)
			(xy 78.199232 -239.034903) (xy 78.166597 -238.998066) (xy 78.140294 -238.95647) (xy 78.121003 -238.911194)
			(xy 78.109226 -238.86341) (xy 78.105266 -238.814356) (xy 62.37732 -238.814356) (xy 62.37732 -239.8903)
			(xy 76.507098 -239.8903) (xy 76.511058 -239.841246) (xy 76.522835 -239.793462) (xy 76.542126 -239.748186)
			(xy 76.568429 -239.70659) (xy 76.601064 -239.669753) (xy 76.639185 -239.638628) (xy 76.681806 -239.614021)
			(xy 76.727822 -239.596569) (xy 76.776041 -239.586725) (xy 76.825216 -239.584744) (xy 76.874071 -239.590676)
			(xy 76.921342 -239.604368) (xy 76.963477 -239.624362) (xy 79.51522 -239.624362) (xy 79.51918 -239.575308)
			(xy 79.530957 -239.527524) (xy 79.550248 -239.482248) (xy 79.576551 -239.440652) (xy 79.609186 -239.403815)
			(xy 79.647307 -239.37269) (xy 79.689928 -239.348083) (xy 79.735944 -239.330631) (xy 79.784163 -239.320787)
			(xy 79.833338 -239.318806) (xy 79.882193 -239.324738) (xy 79.929464 -239.33843) (xy 79.973926 -239.359528)
			(xy 80.014429 -239.387484) (xy 80.049922 -239.421576) (xy 80.079487 -239.46092) (xy 80.102358 -239.504497)
			(xy 80.117942 -239.551178) (xy 80.125837 -239.599755) (xy 80.126332 -239.624362) (xy 80.444843 -239.624362)
			(xy 80.448938 -239.573634) (xy 80.461117 -239.52422) (xy 80.481065 -239.4774) (xy 80.508266 -239.434386)
			(xy 80.542014 -239.396292) (xy 80.581436 -239.364105) (xy 80.62551 -239.338659) (xy 80.673096 -239.320612)
			(xy 80.72296 -239.310432) (xy 80.773812 -239.308383) (xy 80.824333 -239.314517) (xy 80.873217 -239.328677)
			(xy 80.919196 -239.350494) (xy 80.96108 -239.379404) (xy 80.997784 -239.414659) (xy 81.028357 -239.455345)
			(xy 81.052008 -239.500408) (xy 81.068124 -239.548682) (xy 81.076288 -239.598916) (xy 81.0768 -239.624362)
			(xy 81.395328 -239.624362) (xy 81.399288 -239.575308) (xy 81.411065 -239.527524) (xy 81.430356 -239.482248)
			(xy 81.456659 -239.440652) (xy 81.489294 -239.403815) (xy 81.527415 -239.37269) (xy 81.570036 -239.348083)
			(xy 81.616052 -239.330631) (xy 81.664271 -239.320787) (xy 81.713446 -239.318806) (xy 81.762301 -239.324738)
			(xy 81.809572 -239.33843) (xy 81.854034 -239.359528) (xy 81.894537 -239.387484) (xy 81.93003 -239.421576)
			(xy 81.959595 -239.46092) (xy 81.982466 -239.504497) (xy 81.99805 -239.551178) (xy 82.005945 -239.599755)
			(xy 82.00644 -239.624362) (xy 82.324697 -239.624362) (xy 82.328792 -239.573634) (xy 82.340971 -239.52422)
			(xy 82.360919 -239.4774) (xy 82.38812 -239.434386) (xy 82.421868 -239.396292) (xy 82.46129 -239.364105)
			(xy 82.505364 -239.338659) (xy 82.55295 -239.320612) (xy 82.602814 -239.310432) (xy 82.653666 -239.308383)
			(xy 82.704187 -239.314517) (xy 82.753071 -239.328677) (xy 82.79905 -239.350494) (xy 82.840934 -239.379404)
			(xy 82.877638 -239.414659) (xy 82.908211 -239.455345) (xy 82.931862 -239.500408) (xy 82.947978 -239.548682)
			(xy 82.956142 -239.598916) (xy 82.956654 -239.624362) (xy 83.275182 -239.624362) (xy 83.279142 -239.575308)
			(xy 83.290919 -239.527524) (xy 83.31021 -239.482248) (xy 83.336513 -239.440652) (xy 83.369148 -239.403815)
			(xy 83.407269 -239.37269) (xy 83.44989 -239.348083) (xy 83.495906 -239.330631) (xy 83.544125 -239.320787)
			(xy 83.5933 -239.318806) (xy 83.642155 -239.324738) (xy 83.689426 -239.33843) (xy 83.733888 -239.359528)
			(xy 83.774391 -239.387484) (xy 83.809884 -239.421576) (xy 83.839449 -239.46092) (xy 83.86232 -239.504497)
			(xy 83.877904 -239.551178) (xy 83.885799 -239.599755) (xy 83.886294 -239.624362) (xy 84.204805 -239.624362)
			(xy 84.2089 -239.573634) (xy 84.221079 -239.52422) (xy 84.241027 -239.4774) (xy 84.268228 -239.434386)
			(xy 84.301976 -239.396292) (xy 84.341398 -239.364105) (xy 84.385472 -239.338659) (xy 84.433058 -239.320612)
			(xy 84.482922 -239.310432) (xy 84.533774 -239.308383) (xy 84.584295 -239.314517) (xy 84.633179 -239.328677)
			(xy 84.679158 -239.350494) (xy 84.721042 -239.379404) (xy 84.757746 -239.414659) (xy 84.788319 -239.455345)
			(xy 84.81197 -239.500408) (xy 84.828086 -239.548682) (xy 84.83625 -239.598916) (xy 84.836762 -239.624362)
			(xy 85.144859 -239.624362) (xy 85.148954 -239.573634) (xy 85.161133 -239.52422) (xy 85.181081 -239.4774)
			(xy 85.208282 -239.434386) (xy 85.24203 -239.396292) (xy 85.281452 -239.364105) (xy 85.325526 -239.338659)
			(xy 85.373112 -239.320612) (xy 85.422976 -239.310432) (xy 85.473828 -239.308383) (xy 85.524349 -239.314517)
			(xy 85.573233 -239.328677) (xy 85.619212 -239.350494) (xy 85.661096 -239.379404) (xy 85.6978 -239.414659)
			(xy 85.728373 -239.455345) (xy 85.752024 -239.500408) (xy 85.76814 -239.548682) (xy 85.776304 -239.598916)
			(xy 85.776816 -239.624362) (xy 86.095344 -239.624362) (xy 86.099304 -239.575308) (xy 86.111081 -239.527524)
			(xy 86.130372 -239.482248) (xy 86.156675 -239.440652) (xy 86.18931 -239.403815) (xy 86.227431 -239.37269)
			(xy 86.270052 -239.348083) (xy 86.316068 -239.330631) (xy 86.364287 -239.320787) (xy 86.413462 -239.318806)
			(xy 86.462317 -239.324738) (xy 86.509588 -239.33843) (xy 86.55405 -239.359528) (xy 86.594553 -239.387484)
			(xy 86.630046 -239.421576) (xy 86.659611 -239.46092) (xy 86.682482 -239.504497) (xy 86.698066 -239.551178)
			(xy 86.705961 -239.599755) (xy 86.706456 -239.624362) (xy 87.024713 -239.624362) (xy 87.028808 -239.573634)
			(xy 87.040987 -239.52422) (xy 87.060935 -239.4774) (xy 87.088136 -239.434386) (xy 87.121884 -239.396292)
			(xy 87.161306 -239.364105) (xy 87.20538 -239.338659) (xy 87.252966 -239.320612) (xy 87.30283 -239.310432)
			(xy 87.353682 -239.308383) (xy 87.404203 -239.314517) (xy 87.453087 -239.328677) (xy 87.499066 -239.350494)
			(xy 87.54095 -239.379404) (xy 87.577654 -239.414659) (xy 87.608227 -239.455345) (xy 87.631878 -239.500408)
			(xy 87.647994 -239.548682) (xy 87.656158 -239.598916) (xy 87.65667 -239.624362) (xy 87.975198 -239.624362)
			(xy 87.979158 -239.575308) (xy 87.990935 -239.527524) (xy 88.010226 -239.482248) (xy 88.036529 -239.440652)
			(xy 88.069164 -239.403815) (xy 88.107285 -239.37269) (xy 88.149906 -239.348083) (xy 88.195922 -239.330631)
			(xy 88.244141 -239.320787) (xy 88.293316 -239.318806) (xy 88.342171 -239.324738) (xy 88.389442 -239.33843)
			(xy 88.433904 -239.359528) (xy 88.474407 -239.387484) (xy 88.5099 -239.421576) (xy 88.539465 -239.46092)
			(xy 88.562336 -239.504497) (xy 88.57792 -239.551178) (xy 88.585815 -239.599755) (xy 88.58631 -239.624362)
			(xy 88.904821 -239.624362) (xy 88.908916 -239.573634) (xy 88.921095 -239.52422) (xy 88.941043 -239.4774)
			(xy 88.968244 -239.434386) (xy 89.001992 -239.396292) (xy 89.041414 -239.364105) (xy 89.085488 -239.338659)
			(xy 89.133074 -239.320612) (xy 89.182938 -239.310432) (xy 89.23379 -239.308383) (xy 89.284311 -239.314517)
			(xy 89.333195 -239.328677) (xy 89.379174 -239.350494) (xy 89.421058 -239.379404) (xy 89.457762 -239.414659)
			(xy 89.488335 -239.455345) (xy 89.511986 -239.500408) (xy 89.528102 -239.548682) (xy 89.536266 -239.598916)
			(xy 89.536778 -239.624362) (xy 89.855306 -239.624362) (xy 89.859266 -239.575308) (xy 89.871043 -239.527524)
			(xy 89.890334 -239.482248) (xy 89.916637 -239.440652) (xy 89.949272 -239.403815) (xy 89.987393 -239.37269)
			(xy 90.030014 -239.348083) (xy 90.07603 -239.330631) (xy 90.124249 -239.320787) (xy 90.173424 -239.318806)
			(xy 90.222279 -239.324738) (xy 90.26955 -239.33843) (xy 90.314012 -239.359528) (xy 90.354515 -239.387484)
			(xy 90.390008 -239.421576) (xy 90.419573 -239.46092) (xy 90.442444 -239.504497) (xy 90.458028 -239.551178)
			(xy 90.465923 -239.599755) (xy 90.466418 -239.624362) (xy 90.784675 -239.624362) (xy 90.78877 -239.573634)
			(xy 90.800949 -239.52422) (xy 90.820897 -239.4774) (xy 90.848098 -239.434386) (xy 90.881846 -239.396292)
			(xy 90.921268 -239.364105) (xy 90.965342 -239.338659) (xy 91.012928 -239.320612) (xy 91.062792 -239.310432)
			(xy 91.113644 -239.308383) (xy 91.164165 -239.314517) (xy 91.213049 -239.328677) (xy 91.259028 -239.350494)
			(xy 91.300912 -239.379404) (xy 91.337616 -239.414659) (xy 91.368189 -239.455345) (xy 91.39184 -239.500408)
			(xy 91.407956 -239.548682) (xy 91.41612 -239.598916) (xy 91.416632 -239.624362) (xy 91.724729 -239.624362)
			(xy 91.728824 -239.573634) (xy 91.741003 -239.52422) (xy 91.760951 -239.4774) (xy 91.788152 -239.434386)
			(xy 91.8219 -239.396292) (xy 91.861322 -239.364105) (xy 91.905396 -239.338659) (xy 91.952982 -239.320612)
			(xy 92.002846 -239.310432) (xy 92.053698 -239.308383) (xy 92.104219 -239.314517) (xy 92.153103 -239.328677)
			(xy 92.199082 -239.350494) (xy 92.240966 -239.379404) (xy 92.27767 -239.414659) (xy 92.308243 -239.455345)
			(xy 92.331894 -239.500408) (xy 92.34801 -239.548682) (xy 92.356174 -239.598916) (xy 92.356686 -239.624362)
			(xy 92.675214 -239.624362) (xy 92.679174 -239.575308) (xy 92.690951 -239.527524) (xy 92.710242 -239.482248)
			(xy 92.736545 -239.440652) (xy 92.76918 -239.403815) (xy 92.807301 -239.37269) (xy 92.849922 -239.348083)
			(xy 92.895938 -239.330631) (xy 92.944157 -239.320787) (xy 92.993332 -239.318806) (xy 93.042187 -239.324738)
			(xy 93.089458 -239.33843) (xy 93.13392 -239.359528) (xy 93.174423 -239.387484) (xy 93.209916 -239.421576)
			(xy 93.239481 -239.46092) (xy 93.262352 -239.504497) (xy 93.277936 -239.551178) (xy 93.285831 -239.599755)
			(xy 93.286326 -239.624362) (xy 93.604837 -239.624362) (xy 93.608932 -239.573634) (xy 93.621111 -239.52422)
			(xy 93.641059 -239.4774) (xy 93.66826 -239.434386) (xy 93.702008 -239.396292) (xy 93.74143 -239.364105)
			(xy 93.785504 -239.338659) (xy 93.83309 -239.320612) (xy 93.882954 -239.310432) (xy 93.933806 -239.308383)
			(xy 93.984327 -239.314517) (xy 94.033211 -239.328677) (xy 94.07919 -239.350494) (xy 94.121074 -239.379404)
			(xy 94.157778 -239.414659) (xy 94.188351 -239.455345) (xy 94.212002 -239.500408) (xy 94.228118 -239.548682)
			(xy 94.236282 -239.598916) (xy 94.236794 -239.624362) (xy 94.555322 -239.624362) (xy 94.559282 -239.575308)
			(xy 94.571059 -239.527524) (xy 94.59035 -239.482248) (xy 94.616653 -239.440652) (xy 94.649288 -239.403815)
			(xy 94.687409 -239.37269) (xy 94.73003 -239.348083) (xy 94.776046 -239.330631) (xy 94.824265 -239.320787)
			(xy 94.87344 -239.318806) (xy 94.922295 -239.324738) (xy 94.969566 -239.33843) (xy 95.014028 -239.359528)
			(xy 95.054531 -239.387484) (xy 95.090024 -239.421576) (xy 95.119589 -239.46092) (xy 95.14246 -239.504497)
			(xy 95.158044 -239.551178) (xy 95.165939 -239.599755) (xy 95.166434 -239.624362) (xy 95.484691 -239.624362)
			(xy 95.488786 -239.573634) (xy 95.500965 -239.52422) (xy 95.520913 -239.4774) (xy 95.548114 -239.434386)
			(xy 95.581862 -239.396292) (xy 95.621284 -239.364105) (xy 95.665358 -239.338659) (xy 95.712944 -239.320612)
			(xy 95.762808 -239.310432) (xy 95.81366 -239.308383) (xy 95.864181 -239.314517) (xy 95.913065 -239.328677)
			(xy 95.959044 -239.350494) (xy 96.000928 -239.379404) (xy 96.037632 -239.414659) (xy 96.068205 -239.455345)
			(xy 96.091856 -239.500408) (xy 96.107972 -239.548682) (xy 96.116136 -239.598916) (xy 96.116648 -239.624362)
			(xy 96.435176 -239.624362) (xy 96.439136 -239.575308) (xy 96.450913 -239.527524) (xy 96.470204 -239.482248)
			(xy 96.496507 -239.440652) (xy 96.529142 -239.403815) (xy 96.567263 -239.37269) (xy 96.609884 -239.348083)
			(xy 96.6559 -239.330631) (xy 96.704119 -239.320787) (xy 96.753294 -239.318806) (xy 96.802149 -239.324738)
			(xy 96.84942 -239.33843) (xy 96.893882 -239.359528) (xy 96.934385 -239.387484) (xy 96.969878 -239.421576)
			(xy 96.999443 -239.46092) (xy 97.022314 -239.504497) (xy 97.037898 -239.551178) (xy 97.045793 -239.599755)
			(xy 97.046288 -239.624362) (xy 97.364799 -239.624362) (xy 97.368894 -239.573634) (xy 97.381073 -239.52422)
			(xy 97.401021 -239.4774) (xy 97.428222 -239.434386) (xy 97.46197 -239.396292) (xy 97.501392 -239.364105)
			(xy 97.545466 -239.338659) (xy 97.593052 -239.320612) (xy 97.642916 -239.310432) (xy 97.693768 -239.308383)
			(xy 97.744289 -239.314517) (xy 97.793173 -239.328677) (xy 97.839152 -239.350494) (xy 97.881036 -239.379404)
			(xy 97.91774 -239.414659) (xy 97.948313 -239.455345) (xy 97.971964 -239.500408) (xy 97.98808 -239.548682)
			(xy 97.996244 -239.598916) (xy 97.996756 -239.624362) (xy 98.304853 -239.624362) (xy 98.308948 -239.573634)
			(xy 98.321127 -239.52422) (xy 98.341075 -239.4774) (xy 98.368276 -239.434386) (xy 98.402024 -239.396292)
			(xy 98.441446 -239.364105) (xy 98.48552 -239.338659) (xy 98.533106 -239.320612) (xy 98.58297 -239.310432)
			(xy 98.633822 -239.308383) (xy 98.684343 -239.314517) (xy 98.733227 -239.328677) (xy 98.779206 -239.350494)
			(xy 98.82109 -239.379404) (xy 98.857794 -239.414659) (xy 98.888367 -239.455345) (xy 98.912018 -239.500408)
			(xy 98.928134 -239.548682) (xy 98.936298 -239.598916) (xy 98.93681 -239.624362) (xy 99.255338 -239.624362)
			(xy 99.259298 -239.575308) (xy 99.271075 -239.527524) (xy 99.290366 -239.482248) (xy 99.316669 -239.440652)
			(xy 99.349304 -239.403815) (xy 99.387425 -239.37269) (xy 99.430046 -239.348083) (xy 99.476062 -239.330631)
			(xy 99.524281 -239.320787) (xy 99.573456 -239.318806) (xy 99.622311 -239.324738) (xy 99.669582 -239.33843)
			(xy 99.714044 -239.359528) (xy 99.754547 -239.387484) (xy 99.79004 -239.421576) (xy 99.819605 -239.46092)
			(xy 99.842476 -239.504497) (xy 99.85806 -239.551178) (xy 99.865955 -239.599755) (xy 99.86645 -239.624362)
			(xy 100.184707 -239.624362) (xy 100.188802 -239.573634) (xy 100.200981 -239.52422) (xy 100.220929 -239.4774)
			(xy 100.24813 -239.434386) (xy 100.281878 -239.396292) (xy 100.3213 -239.364105) (xy 100.365374 -239.338659)
			(xy 100.41296 -239.320612) (xy 100.462824 -239.310432) (xy 100.513676 -239.308383) (xy 100.564197 -239.314517)
			(xy 100.613081 -239.328677) (xy 100.65906 -239.350494) (xy 100.700944 -239.379404) (xy 100.737648 -239.414659)
			(xy 100.768221 -239.455345) (xy 100.791872 -239.500408) (xy 100.807988 -239.548682) (xy 100.816152 -239.598916)
			(xy 100.816664 -239.624362) (xy 101.124761 -239.624362) (xy 101.128856 -239.573634) (xy 101.141035 -239.52422)
			(xy 101.160983 -239.4774) (xy 101.188184 -239.434386) (xy 101.221932 -239.396292) (xy 101.261354 -239.364105)
			(xy 101.305428 -239.338659) (xy 101.353014 -239.320612) (xy 101.402878 -239.310432) (xy 101.45373 -239.308383)
			(xy 101.504251 -239.314517) (xy 101.553135 -239.328677) (xy 101.599114 -239.350494) (xy 101.640998 -239.379404)
			(xy 101.677702 -239.414659) (xy 101.708275 -239.455345) (xy 101.731926 -239.500408) (xy 101.748042 -239.548682)
			(xy 101.756206 -239.598916) (xy 101.756718 -239.624362) (xy 102.075246 -239.624362) (xy 102.079206 -239.575308)
			(xy 102.090983 -239.527524) (xy 102.110274 -239.482248) (xy 102.136577 -239.440652) (xy 102.169212 -239.403815)
			(xy 102.207333 -239.37269) (xy 102.249954 -239.348083) (xy 102.29597 -239.330631) (xy 102.344189 -239.320787)
			(xy 102.393364 -239.318806) (xy 102.442219 -239.324738) (xy 102.48949 -239.33843) (xy 102.533952 -239.359528)
			(xy 102.574455 -239.387484) (xy 102.609948 -239.421576) (xy 102.639513 -239.46092) (xy 102.662384 -239.504497)
			(xy 102.677968 -239.551178) (xy 102.685863 -239.599755) (xy 102.686358 -239.624362) (xy 103.004869 -239.624362)
			(xy 103.008964 -239.573634) (xy 103.021143 -239.52422) (xy 103.041091 -239.4774) (xy 103.068292 -239.434386)
			(xy 103.10204 -239.396292) (xy 103.141462 -239.364105) (xy 103.185536 -239.338659) (xy 103.233122 -239.320612)
			(xy 103.282986 -239.310432) (xy 103.333838 -239.308383) (xy 103.384359 -239.314517) (xy 103.433243 -239.328677)
			(xy 103.479222 -239.350494) (xy 103.521106 -239.379404) (xy 103.55781 -239.414659) (xy 103.588383 -239.455345)
			(xy 103.612034 -239.500408) (xy 103.62815 -239.548682) (xy 103.636314 -239.598916) (xy 103.636826 -239.624362)
			(xy 103.944923 -239.624362) (xy 103.949018 -239.573634) (xy 103.961197 -239.52422) (xy 103.981145 -239.4774)
			(xy 104.008346 -239.434386) (xy 104.042094 -239.396292) (xy 104.081516 -239.364105) (xy 104.12559 -239.338659)
			(xy 104.173176 -239.320612) (xy 104.22304 -239.310432) (xy 104.273892 -239.308383) (xy 104.324413 -239.314517)
			(xy 104.373297 -239.328677) (xy 104.419276 -239.350494) (xy 104.46116 -239.379404) (xy 104.497864 -239.414659)
			(xy 104.528437 -239.455345) (xy 104.552088 -239.500408) (xy 104.568204 -239.548682) (xy 104.576368 -239.598916)
			(xy 104.57688 -239.624362) (xy 104.895154 -239.624362) (xy 104.899114 -239.575308) (xy 104.910891 -239.527524)
			(xy 104.930182 -239.482248) (xy 104.956485 -239.440652) (xy 104.98912 -239.403815) (xy 105.027241 -239.37269)
			(xy 105.069862 -239.348083) (xy 105.115878 -239.330631) (xy 105.164097 -239.320787) (xy 105.213272 -239.318806)
			(xy 105.262127 -239.324738) (xy 105.309398 -239.33843) (xy 105.35386 -239.359528) (xy 105.394363 -239.387484)
			(xy 105.429856 -239.421576) (xy 105.459421 -239.46092) (xy 105.482292 -239.504497) (xy 105.497876 -239.551178)
			(xy 105.505771 -239.599755) (xy 105.506266 -239.624362) (xy 105.824777 -239.624362) (xy 105.828872 -239.573634)
			(xy 105.841051 -239.52422) (xy 105.860999 -239.4774) (xy 105.8882 -239.434386) (xy 105.921948 -239.396292)
			(xy 105.96137 -239.364105) (xy 106.005444 -239.338659) (xy 106.05303 -239.320612) (xy 106.102894 -239.310432)
			(xy 106.153746 -239.308383) (xy 106.204267 -239.314517) (xy 106.253151 -239.328677) (xy 106.29913 -239.350494)
			(xy 106.341014 -239.379404) (xy 106.377718 -239.414659) (xy 106.408291 -239.455345) (xy 106.431942 -239.500408)
			(xy 106.448058 -239.548682) (xy 106.456222 -239.598916) (xy 106.456734 -239.624362) (xy 106.764831 -239.624362)
			(xy 106.768926 -239.573634) (xy 106.781105 -239.52422) (xy 106.801053 -239.4774) (xy 106.828254 -239.434386)
			(xy 106.862002 -239.396292) (xy 106.901424 -239.364105) (xy 106.945498 -239.338659) (xy 106.993084 -239.320612)
			(xy 107.042948 -239.310432) (xy 107.0938 -239.308383) (xy 107.144321 -239.314517) (xy 107.193205 -239.328677)
			(xy 107.239184 -239.350494) (xy 107.281068 -239.379404) (xy 107.317772 -239.414659) (xy 107.348345 -239.455345)
			(xy 107.371996 -239.500408) (xy 107.388112 -239.548682) (xy 107.396276 -239.598916) (xy 107.396788 -239.624362)
			(xy 107.715316 -239.624362) (xy 107.719276 -239.575308) (xy 107.731053 -239.527524) (xy 107.750344 -239.482248)
			(xy 107.776647 -239.440652) (xy 107.809282 -239.403815) (xy 107.847403 -239.37269) (xy 107.890024 -239.348083)
			(xy 107.93604 -239.330631) (xy 107.984259 -239.320787) (xy 108.033434 -239.318806) (xy 108.082289 -239.324738)
			(xy 108.12956 -239.33843) (xy 108.174022 -239.359528) (xy 108.214525 -239.387484) (xy 108.250018 -239.421576)
			(xy 108.279583 -239.46092) (xy 108.302454 -239.504497) (xy 108.318038 -239.551178) (xy 108.325933 -239.599755)
			(xy 108.326428 -239.624362) (xy 108.325933 -239.648969) (xy 108.318038 -239.697546) (xy 108.302454 -239.744227)
			(xy 108.279583 -239.787804) (xy 108.250018 -239.827148) (xy 108.214525 -239.86124) (xy 108.174022 -239.889196)
			(xy 108.12956 -239.910294) (xy 108.082289 -239.923986) (xy 108.033434 -239.929918) (xy 107.984259 -239.927937)
			(xy 107.93604 -239.918093) (xy 107.890024 -239.900641) (xy 107.847403 -239.876034) (xy 107.809282 -239.844909)
			(xy 107.776647 -239.808072) (xy 107.750344 -239.766476) (xy 107.731053 -239.7212) (xy 107.719276 -239.673416)
			(xy 107.715316 -239.624362) (xy 107.396788 -239.624362) (xy 107.396276 -239.649808) (xy 107.388112 -239.700042)
			(xy 107.371996 -239.748316) (xy 107.348345 -239.793379) (xy 107.317772 -239.834065) (xy 107.281068 -239.86932)
			(xy 107.239184 -239.89823) (xy 107.193205 -239.920047) (xy 107.144321 -239.934207) (xy 107.0938 -239.940341)
			(xy 107.042948 -239.938292) (xy 106.993084 -239.928112) (xy 106.945498 -239.910065) (xy 106.901424 -239.884619)
			(xy 106.862002 -239.852432) (xy 106.828254 -239.814338) (xy 106.801053 -239.771324) (xy 106.781105 -239.724504)
			(xy 106.768926 -239.67509) (xy 106.764831 -239.624362) (xy 106.456734 -239.624362) (xy 106.456222 -239.649808)
			(xy 106.448058 -239.700042) (xy 106.431942 -239.748316) (xy 106.408291 -239.793379) (xy 106.377718 -239.834065)
			(xy 106.341014 -239.86932) (xy 106.29913 -239.89823) (xy 106.253151 -239.920047) (xy 106.204267 -239.934207)
			(xy 106.153746 -239.940341) (xy 106.102894 -239.938292) (xy 106.05303 -239.928112) (xy 106.005444 -239.910065)
			(xy 105.96137 -239.884619) (xy 105.921948 -239.852432) (xy 105.8882 -239.814338) (xy 105.860999 -239.771324)
			(xy 105.841051 -239.724504) (xy 105.828872 -239.67509) (xy 105.824777 -239.624362) (xy 105.506266 -239.624362)
			(xy 105.505771 -239.648969) (xy 105.497876 -239.697546) (xy 105.482292 -239.744227) (xy 105.459421 -239.787804)
			(xy 105.429856 -239.827148) (xy 105.394363 -239.86124) (xy 105.35386 -239.889196) (xy 105.309398 -239.910294)
			(xy 105.262127 -239.923986) (xy 105.213272 -239.929918) (xy 105.164097 -239.927937) (xy 105.115878 -239.918093)
			(xy 105.069862 -239.900641) (xy 105.027241 -239.876034) (xy 104.98912 -239.844909) (xy 104.956485 -239.808072)
			(xy 104.930182 -239.766476) (xy 104.910891 -239.7212) (xy 104.899114 -239.673416) (xy 104.895154 -239.624362)
			(xy 104.57688 -239.624362) (xy 104.576368 -239.649808) (xy 104.568204 -239.700042) (xy 104.552088 -239.748316)
			(xy 104.528437 -239.793379) (xy 104.497864 -239.834065) (xy 104.46116 -239.86932) (xy 104.419276 -239.89823)
			(xy 104.373297 -239.920047) (xy 104.324413 -239.934207) (xy 104.273892 -239.940341) (xy 104.22304 -239.938292)
			(xy 104.173176 -239.928112) (xy 104.12559 -239.910065) (xy 104.081516 -239.884619) (xy 104.042094 -239.852432)
			(xy 104.008346 -239.814338) (xy 103.981145 -239.771324) (xy 103.961197 -239.724504) (xy 103.949018 -239.67509)
			(xy 103.944923 -239.624362) (xy 103.636826 -239.624362) (xy 103.636314 -239.649808) (xy 103.62815 -239.700042)
			(xy 103.612034 -239.748316) (xy 103.588383 -239.793379) (xy 103.55781 -239.834065) (xy 103.521106 -239.86932)
			(xy 103.479222 -239.89823) (xy 103.433243 -239.920047) (xy 103.384359 -239.934207) (xy 103.333838 -239.940341)
			(xy 103.282986 -239.938292) (xy 103.233122 -239.928112) (xy 103.185536 -239.910065) (xy 103.141462 -239.884619)
			(xy 103.10204 -239.852432) (xy 103.068292 -239.814338) (xy 103.041091 -239.771324) (xy 103.021143 -239.724504)
			(xy 103.008964 -239.67509) (xy 103.004869 -239.624362) (xy 102.686358 -239.624362) (xy 102.685863 -239.648969)
			(xy 102.677968 -239.697546) (xy 102.662384 -239.744227) (xy 102.639513 -239.787804) (xy 102.609948 -239.827148)
			(xy 102.574455 -239.86124) (xy 102.533952 -239.889196) (xy 102.48949 -239.910294) (xy 102.442219 -239.923986)
			(xy 102.393364 -239.929918) (xy 102.344189 -239.927937) (xy 102.29597 -239.918093) (xy 102.249954 -239.900641)
			(xy 102.207333 -239.876034) (xy 102.169212 -239.844909) (xy 102.136577 -239.808072) (xy 102.110274 -239.766476)
			(xy 102.090983 -239.7212) (xy 102.079206 -239.673416) (xy 102.075246 -239.624362) (xy 101.756718 -239.624362)
			(xy 101.756206 -239.649808) (xy 101.748042 -239.700042) (xy 101.731926 -239.748316) (xy 101.708275 -239.793379)
			(xy 101.677702 -239.834065) (xy 101.640998 -239.86932) (xy 101.599114 -239.89823) (xy 101.553135 -239.920047)
			(xy 101.504251 -239.934207) (xy 101.45373 -239.940341) (xy 101.402878 -239.938292) (xy 101.353014 -239.928112)
			(xy 101.305428 -239.910065) (xy 101.261354 -239.884619) (xy 101.221932 -239.852432) (xy 101.188184 -239.814338)
			(xy 101.160983 -239.771324) (xy 101.141035 -239.724504) (xy 101.128856 -239.67509) (xy 101.124761 -239.624362)
			(xy 100.816664 -239.624362) (xy 100.816152 -239.649808) (xy 100.807988 -239.700042) (xy 100.791872 -239.748316)
			(xy 100.768221 -239.793379) (xy 100.737648 -239.834065) (xy 100.700944 -239.86932) (xy 100.65906 -239.89823)
			(xy 100.613081 -239.920047) (xy 100.564197 -239.934207) (xy 100.513676 -239.940341) (xy 100.462824 -239.938292)
			(xy 100.41296 -239.928112) (xy 100.365374 -239.910065) (xy 100.3213 -239.884619) (xy 100.281878 -239.852432)
			(xy 100.24813 -239.814338) (xy 100.220929 -239.771324) (xy 100.200981 -239.724504) (xy 100.188802 -239.67509)
			(xy 100.184707 -239.624362) (xy 99.86645 -239.624362) (xy 99.865955 -239.648969) (xy 99.85806 -239.697546)
			(xy 99.842476 -239.744227) (xy 99.819605 -239.787804) (xy 99.79004 -239.827148) (xy 99.754547 -239.86124)
			(xy 99.714044 -239.889196) (xy 99.669582 -239.910294) (xy 99.622311 -239.923986) (xy 99.573456 -239.929918)
			(xy 99.524281 -239.927937) (xy 99.476062 -239.918093) (xy 99.430046 -239.900641) (xy 99.387425 -239.876034)
			(xy 99.349304 -239.844909) (xy 99.316669 -239.808072) (xy 99.290366 -239.766476) (xy 99.271075 -239.7212)
			(xy 99.259298 -239.673416) (xy 99.255338 -239.624362) (xy 98.93681 -239.624362) (xy 98.936298 -239.649808)
			(xy 98.928134 -239.700042) (xy 98.912018 -239.748316) (xy 98.888367 -239.793379) (xy 98.857794 -239.834065)
			(xy 98.82109 -239.86932) (xy 98.779206 -239.89823) (xy 98.733227 -239.920047) (xy 98.684343 -239.934207)
			(xy 98.633822 -239.940341) (xy 98.58297 -239.938292) (xy 98.533106 -239.928112) (xy 98.48552 -239.910065)
			(xy 98.441446 -239.884619) (xy 98.402024 -239.852432) (xy 98.368276 -239.814338) (xy 98.341075 -239.771324)
			(xy 98.321127 -239.724504) (xy 98.308948 -239.67509) (xy 98.304853 -239.624362) (xy 97.996756 -239.624362)
			(xy 97.996244 -239.649808) (xy 97.98808 -239.700042) (xy 97.971964 -239.748316) (xy 97.948313 -239.793379)
			(xy 97.91774 -239.834065) (xy 97.881036 -239.86932) (xy 97.839152 -239.89823) (xy 97.793173 -239.920047)
			(xy 97.744289 -239.934207) (xy 97.693768 -239.940341) (xy 97.642916 -239.938292) (xy 97.593052 -239.928112)
			(xy 97.545466 -239.910065) (xy 97.501392 -239.884619) (xy 97.46197 -239.852432) (xy 97.428222 -239.814338)
			(xy 97.401021 -239.771324) (xy 97.381073 -239.724504) (xy 97.368894 -239.67509) (xy 97.364799 -239.624362)
			(xy 97.046288 -239.624362) (xy 97.045793 -239.648969) (xy 97.037898 -239.697546) (xy 97.022314 -239.744227)
			(xy 96.999443 -239.787804) (xy 96.969878 -239.827148) (xy 96.934385 -239.86124) (xy 96.893882 -239.889196)
			(xy 96.84942 -239.910294) (xy 96.802149 -239.923986) (xy 96.753294 -239.929918) (xy 96.704119 -239.927937)
			(xy 96.6559 -239.918093) (xy 96.609884 -239.900641) (xy 96.567263 -239.876034) (xy 96.529142 -239.844909)
			(xy 96.496507 -239.808072) (xy 96.470204 -239.766476) (xy 96.450913 -239.7212) (xy 96.439136 -239.673416)
			(xy 96.435176 -239.624362) (xy 96.116648 -239.624362) (xy 96.116136 -239.649808) (xy 96.107972 -239.700042)
			(xy 96.091856 -239.748316) (xy 96.068205 -239.793379) (xy 96.037632 -239.834065) (xy 96.000928 -239.86932)
			(xy 95.959044 -239.89823) (xy 95.913065 -239.920047) (xy 95.864181 -239.934207) (xy 95.81366 -239.940341)
			(xy 95.762808 -239.938292) (xy 95.712944 -239.928112) (xy 95.665358 -239.910065) (xy 95.621284 -239.884619)
			(xy 95.581862 -239.852432) (xy 95.548114 -239.814338) (xy 95.520913 -239.771324) (xy 95.500965 -239.724504)
			(xy 95.488786 -239.67509) (xy 95.484691 -239.624362) (xy 95.166434 -239.624362) (xy 95.165939 -239.648969)
			(xy 95.158044 -239.697546) (xy 95.14246 -239.744227) (xy 95.119589 -239.787804) (xy 95.090024 -239.827148)
			(xy 95.054531 -239.86124) (xy 95.014028 -239.889196) (xy 94.969566 -239.910294) (xy 94.922295 -239.923986)
			(xy 94.87344 -239.929918) (xy 94.824265 -239.927937) (xy 94.776046 -239.918093) (xy 94.73003 -239.900641)
			(xy 94.687409 -239.876034) (xy 94.649288 -239.844909) (xy 94.616653 -239.808072) (xy 94.59035 -239.766476)
			(xy 94.571059 -239.7212) (xy 94.559282 -239.673416) (xy 94.555322 -239.624362) (xy 94.236794 -239.624362)
			(xy 94.236282 -239.649808) (xy 94.228118 -239.700042) (xy 94.212002 -239.748316) (xy 94.188351 -239.793379)
			(xy 94.157778 -239.834065) (xy 94.121074 -239.86932) (xy 94.07919 -239.89823) (xy 94.033211 -239.920047)
			(xy 93.984327 -239.934207) (xy 93.933806 -239.940341) (xy 93.882954 -239.938292) (xy 93.83309 -239.928112)
			(xy 93.785504 -239.910065) (xy 93.74143 -239.884619) (xy 93.702008 -239.852432) (xy 93.66826 -239.814338)
			(xy 93.641059 -239.771324) (xy 93.621111 -239.724504) (xy 93.608932 -239.67509) (xy 93.604837 -239.624362)
			(xy 93.286326 -239.624362) (xy 93.285831 -239.648969) (xy 93.277936 -239.697546) (xy 93.262352 -239.744227)
			(xy 93.239481 -239.787804) (xy 93.209916 -239.827148) (xy 93.174423 -239.86124) (xy 93.13392 -239.889196)
			(xy 93.089458 -239.910294) (xy 93.042187 -239.923986) (xy 92.993332 -239.929918) (xy 92.944157 -239.927937)
			(xy 92.895938 -239.918093) (xy 92.849922 -239.900641) (xy 92.807301 -239.876034) (xy 92.76918 -239.844909)
			(xy 92.736545 -239.808072) (xy 92.710242 -239.766476) (xy 92.690951 -239.7212) (xy 92.679174 -239.673416)
			(xy 92.675214 -239.624362) (xy 92.356686 -239.624362) (xy 92.356174 -239.649808) (xy 92.34801 -239.700042)
			(xy 92.331894 -239.748316) (xy 92.308243 -239.793379) (xy 92.27767 -239.834065) (xy 92.240966 -239.86932)
			(xy 92.199082 -239.89823) (xy 92.153103 -239.920047) (xy 92.104219 -239.934207) (xy 92.053698 -239.940341)
			(xy 92.002846 -239.938292) (xy 91.952982 -239.928112) (xy 91.905396 -239.910065) (xy 91.861322 -239.884619)
			(xy 91.8219 -239.852432) (xy 91.788152 -239.814338) (xy 91.760951 -239.771324) (xy 91.741003 -239.724504)
			(xy 91.728824 -239.67509) (xy 91.724729 -239.624362) (xy 91.416632 -239.624362) (xy 91.41612 -239.649808)
			(xy 91.407956 -239.700042) (xy 91.39184 -239.748316) (xy 91.368189 -239.793379) (xy 91.337616 -239.834065)
			(xy 91.300912 -239.86932) (xy 91.259028 -239.89823) (xy 91.213049 -239.920047) (xy 91.164165 -239.934207)
			(xy 91.113644 -239.940341) (xy 91.062792 -239.938292) (xy 91.012928 -239.928112) (xy 90.965342 -239.910065)
			(xy 90.921268 -239.884619) (xy 90.881846 -239.852432) (xy 90.848098 -239.814338) (xy 90.820897 -239.771324)
			(xy 90.800949 -239.724504) (xy 90.78877 -239.67509) (xy 90.784675 -239.624362) (xy 90.466418 -239.624362)
			(xy 90.465923 -239.648969) (xy 90.458028 -239.697546) (xy 90.442444 -239.744227) (xy 90.419573 -239.787804)
			(xy 90.390008 -239.827148) (xy 90.354515 -239.86124) (xy 90.314012 -239.889196) (xy 90.26955 -239.910294)
			(xy 90.222279 -239.923986) (xy 90.173424 -239.929918) (xy 90.124249 -239.927937) (xy 90.07603 -239.918093)
			(xy 90.030014 -239.900641) (xy 89.987393 -239.876034) (xy 89.949272 -239.844909) (xy 89.916637 -239.808072)
			(xy 89.890334 -239.766476) (xy 89.871043 -239.7212) (xy 89.859266 -239.673416) (xy 89.855306 -239.624362)
			(xy 89.536778 -239.624362) (xy 89.536266 -239.649808) (xy 89.528102 -239.700042) (xy 89.511986 -239.748316)
			(xy 89.488335 -239.793379) (xy 89.457762 -239.834065) (xy 89.421058 -239.86932) (xy 89.379174 -239.89823)
			(xy 89.333195 -239.920047) (xy 89.284311 -239.934207) (xy 89.23379 -239.940341) (xy 89.182938 -239.938292)
			(xy 89.133074 -239.928112) (xy 89.085488 -239.910065) (xy 89.041414 -239.884619) (xy 89.001992 -239.852432)
			(xy 88.968244 -239.814338) (xy 88.941043 -239.771324) (xy 88.921095 -239.724504) (xy 88.908916 -239.67509)
			(xy 88.904821 -239.624362) (xy 88.58631 -239.624362) (xy 88.585815 -239.648969) (xy 88.57792 -239.697546)
			(xy 88.562336 -239.744227) (xy 88.539465 -239.787804) (xy 88.5099 -239.827148) (xy 88.474407 -239.86124)
			(xy 88.433904 -239.889196) (xy 88.389442 -239.910294) (xy 88.342171 -239.923986) (xy 88.293316 -239.929918)
			(xy 88.244141 -239.927937) (xy 88.195922 -239.918093) (xy 88.149906 -239.900641) (xy 88.107285 -239.876034)
			(xy 88.069164 -239.844909) (xy 88.036529 -239.808072) (xy 88.010226 -239.766476) (xy 87.990935 -239.7212)
			(xy 87.979158 -239.673416) (xy 87.975198 -239.624362) (xy 87.65667 -239.624362) (xy 87.656158 -239.649808)
			(xy 87.647994 -239.700042) (xy 87.631878 -239.748316) (xy 87.608227 -239.793379) (xy 87.577654 -239.834065)
			(xy 87.54095 -239.86932) (xy 87.499066 -239.89823) (xy 87.453087 -239.920047) (xy 87.404203 -239.934207)
			(xy 87.353682 -239.940341) (xy 87.30283 -239.938292) (xy 87.252966 -239.928112) (xy 87.20538 -239.910065)
			(xy 87.161306 -239.884619) (xy 87.121884 -239.852432) (xy 87.088136 -239.814338) (xy 87.060935 -239.771324)
			(xy 87.040987 -239.724504) (xy 87.028808 -239.67509) (xy 87.024713 -239.624362) (xy 86.706456 -239.624362)
			(xy 86.705961 -239.648969) (xy 86.698066 -239.697546) (xy 86.682482 -239.744227) (xy 86.659611 -239.787804)
			(xy 86.630046 -239.827148) (xy 86.594553 -239.86124) (xy 86.55405 -239.889196) (xy 86.509588 -239.910294)
			(xy 86.462317 -239.923986) (xy 86.413462 -239.929918) (xy 86.364287 -239.927937) (xy 86.316068 -239.918093)
			(xy 86.270052 -239.900641) (xy 86.227431 -239.876034) (xy 86.18931 -239.844909) (xy 86.156675 -239.808072)
			(xy 86.130372 -239.766476) (xy 86.111081 -239.7212) (xy 86.099304 -239.673416) (xy 86.095344 -239.624362)
			(xy 85.776816 -239.624362) (xy 85.776304 -239.649808) (xy 85.76814 -239.700042) (xy 85.752024 -239.748316)
			(xy 85.728373 -239.793379) (xy 85.6978 -239.834065) (xy 85.661096 -239.86932) (xy 85.619212 -239.89823)
			(xy 85.573233 -239.920047) (xy 85.524349 -239.934207) (xy 85.473828 -239.940341) (xy 85.422976 -239.938292)
			(xy 85.373112 -239.928112) (xy 85.325526 -239.910065) (xy 85.281452 -239.884619) (xy 85.24203 -239.852432)
			(xy 85.208282 -239.814338) (xy 85.181081 -239.771324) (xy 85.161133 -239.724504) (xy 85.148954 -239.67509)
			(xy 85.144859 -239.624362) (xy 84.836762 -239.624362) (xy 84.83625 -239.649808) (xy 84.828086 -239.700042)
			(xy 84.81197 -239.748316) (xy 84.788319 -239.793379) (xy 84.757746 -239.834065) (xy 84.721042 -239.86932)
			(xy 84.679158 -239.89823) (xy 84.633179 -239.920047) (xy 84.584295 -239.934207) (xy 84.533774 -239.940341)
			(xy 84.482922 -239.938292) (xy 84.433058 -239.928112) (xy 84.385472 -239.910065) (xy 84.341398 -239.884619)
			(xy 84.301976 -239.852432) (xy 84.268228 -239.814338) (xy 84.241027 -239.771324) (xy 84.221079 -239.724504)
			(xy 84.2089 -239.67509) (xy 84.204805 -239.624362) (xy 83.886294 -239.624362) (xy 83.885799 -239.648969)
			(xy 83.877904 -239.697546) (xy 83.86232 -239.744227) (xy 83.839449 -239.787804) (xy 83.809884 -239.827148)
			(xy 83.774391 -239.86124) (xy 83.733888 -239.889196) (xy 83.689426 -239.910294) (xy 83.642155 -239.923986)
			(xy 83.5933 -239.929918) (xy 83.544125 -239.927937) (xy 83.495906 -239.918093) (xy 83.44989 -239.900641)
			(xy 83.407269 -239.876034) (xy 83.369148 -239.844909) (xy 83.336513 -239.808072) (xy 83.31021 -239.766476)
			(xy 83.290919 -239.7212) (xy 83.279142 -239.673416) (xy 83.275182 -239.624362) (xy 82.956654 -239.624362)
			(xy 82.956142 -239.649808) (xy 82.947978 -239.700042) (xy 82.931862 -239.748316) (xy 82.908211 -239.793379)
			(xy 82.877638 -239.834065) (xy 82.840934 -239.86932) (xy 82.79905 -239.89823) (xy 82.753071 -239.920047)
			(xy 82.704187 -239.934207) (xy 82.653666 -239.940341) (xy 82.602814 -239.938292) (xy 82.55295 -239.928112)
			(xy 82.505364 -239.910065) (xy 82.46129 -239.884619) (xy 82.421868 -239.852432) (xy 82.38812 -239.814338)
			(xy 82.360919 -239.771324) (xy 82.340971 -239.724504) (xy 82.328792 -239.67509) (xy 82.324697 -239.624362)
			(xy 82.00644 -239.624362) (xy 82.005945 -239.648969) (xy 81.99805 -239.697546) (xy 81.982466 -239.744227)
			(xy 81.959595 -239.787804) (xy 81.93003 -239.827148) (xy 81.894537 -239.86124) (xy 81.854034 -239.889196)
			(xy 81.809572 -239.910294) (xy 81.762301 -239.923986) (xy 81.713446 -239.929918) (xy 81.664271 -239.927937)
			(xy 81.616052 -239.918093) (xy 81.570036 -239.900641) (xy 81.527415 -239.876034) (xy 81.489294 -239.844909)
			(xy 81.456659 -239.808072) (xy 81.430356 -239.766476) (xy 81.411065 -239.7212) (xy 81.399288 -239.673416)
			(xy 81.395328 -239.624362) (xy 81.0768 -239.624362) (xy 81.076288 -239.649808) (xy 81.068124 -239.700042)
			(xy 81.052008 -239.748316) (xy 81.028357 -239.793379) (xy 80.997784 -239.834065) (xy 80.96108 -239.86932)
			(xy 80.919196 -239.89823) (xy 80.873217 -239.920047) (xy 80.824333 -239.934207) (xy 80.773812 -239.940341)
			(xy 80.72296 -239.938292) (xy 80.673096 -239.928112) (xy 80.62551 -239.910065) (xy 80.581436 -239.884619)
			(xy 80.542014 -239.852432) (xy 80.508266 -239.814338) (xy 80.481065 -239.771324) (xy 80.461117 -239.724504)
			(xy 80.448938 -239.67509) (xy 80.444843 -239.624362) (xy 80.126332 -239.624362) (xy 80.125837 -239.648969)
			(xy 80.117942 -239.697546) (xy 80.102358 -239.744227) (xy 80.079487 -239.787804) (xy 80.049922 -239.827148)
			(xy 80.014429 -239.86124) (xy 79.973926 -239.889196) (xy 79.929464 -239.910294) (xy 79.882193 -239.923986)
			(xy 79.833338 -239.929918) (xy 79.784163 -239.927937) (xy 79.735944 -239.918093) (xy 79.689928 -239.900641)
			(xy 79.647307 -239.876034) (xy 79.609186 -239.844909) (xy 79.576551 -239.808072) (xy 79.550248 -239.766476)
			(xy 79.530957 -239.7212) (xy 79.51918 -239.673416) (xy 79.51522 -239.624362) (xy 76.963477 -239.624362)
			(xy 76.965804 -239.625466) (xy 77.006307 -239.653422) (xy 77.0418 -239.687514) (xy 77.071365 -239.726858)
			(xy 77.094236 -239.770435) (xy 77.10982 -239.817116) (xy 77.117715 -239.865693) (xy 77.11821 -239.8903)
			(xy 77.117715 -239.914907) (xy 77.10982 -239.963484) (xy 77.094236 -240.010165) (xy 77.071365 -240.053742)
			(xy 77.0418 -240.093086) (xy 77.006307 -240.127178) (xy 76.965804 -240.155134) (xy 76.921342 -240.176232)
			(xy 76.874071 -240.189924) (xy 76.825216 -240.195856) (xy 76.776041 -240.193875) (xy 76.727822 -240.184031)
			(xy 76.681806 -240.166579) (xy 76.639185 -240.141972) (xy 76.601064 -240.110847) (xy 76.568429 -240.07401)
			(xy 76.542126 -240.032414) (xy 76.522835 -239.987138) (xy 76.511058 -239.939354) (xy 76.507098 -239.8903)
			(xy 62.37732 -239.8903) (xy 62.37732 -240.434368) (xy 78.105266 -240.434368) (xy 78.109226 -240.385314)
			(xy 78.121003 -240.33753) (xy 78.140294 -240.292254) (xy 78.166597 -240.250658) (xy 78.199232 -240.213821)
			(xy 78.237353 -240.182696) (xy 78.279974 -240.158089) (xy 78.32599 -240.140637) (xy 78.374209 -240.130793)
			(xy 78.423384 -240.128812) (xy 78.472239 -240.134744) (xy 78.51951 -240.148436) (xy 78.563972 -240.169534)
			(xy 78.604475 -240.19749) (xy 78.639968 -240.231582) (xy 78.669533 -240.270926) (xy 78.692404 -240.314503)
			(xy 78.707988 -240.361184) (xy 78.715883 -240.409761) (xy 78.716378 -240.434368) (xy 79.985374 -240.434368)
			(xy 79.989334 -240.385314) (xy 80.001111 -240.33753) (xy 80.020402 -240.292254) (xy 80.046705 -240.250658)
			(xy 80.07934 -240.213821) (xy 80.117461 -240.182696) (xy 80.160082 -240.158089) (xy 80.206098 -240.140637)
			(xy 80.254317 -240.130793) (xy 80.303492 -240.128812) (xy 80.352347 -240.134744) (xy 80.399618 -240.148436)
			(xy 80.44408 -240.169534) (xy 80.484583 -240.19749) (xy 80.520076 -240.231582) (xy 80.549641 -240.270926)
			(xy 80.572512 -240.314503) (xy 80.588096 -240.361184) (xy 80.595991 -240.409761) (xy 80.596486 -240.434368)
			(xy 80.914743 -240.434368) (xy 80.918838 -240.38364) (xy 80.931017 -240.334226) (xy 80.950965 -240.287406)
			(xy 80.978166 -240.244392) (xy 81.011914 -240.206298) (xy 81.051336 -240.174111) (xy 81.09541 -240.148665)
			(xy 81.142996 -240.130618) (xy 81.19286 -240.120438) (xy 81.243712 -240.118389) (xy 81.294233 -240.124523)
			(xy 81.343117 -240.138683) (xy 81.389096 -240.1605) (xy 81.43098 -240.18941) (xy 81.467684 -240.224665)
			(xy 81.498257 -240.265351) (xy 81.521908 -240.310414) (xy 81.538024 -240.358688) (xy 81.546188 -240.408922)
			(xy 81.5467 -240.434368) (xy 81.854797 -240.434368) (xy 81.858892 -240.38364) (xy 81.871071 -240.334226)
			(xy 81.891019 -240.287406) (xy 81.91822 -240.244392) (xy 81.951968 -240.206298) (xy 81.99139 -240.174111)
			(xy 82.035464 -240.148665) (xy 82.08305 -240.130618) (xy 82.132914 -240.120438) (xy 82.183766 -240.118389)
			(xy 82.234287 -240.124523) (xy 82.283171 -240.138683) (xy 82.32915 -240.1605) (xy 82.371034 -240.18941)
			(xy 82.407738 -240.224665) (xy 82.438311 -240.265351) (xy 82.461962 -240.310414) (xy 82.478078 -240.358688)
			(xy 82.486242 -240.408922) (xy 82.486754 -240.434368) (xy 82.805282 -240.434368) (xy 82.809242 -240.385314)
			(xy 82.821019 -240.33753) (xy 82.84031 -240.292254) (xy 82.866613 -240.250658) (xy 82.899248 -240.213821)
			(xy 82.937369 -240.182696) (xy 82.97999 -240.158089) (xy 83.026006 -240.140637) (xy 83.074225 -240.130793)
			(xy 83.1234 -240.128812) (xy 83.172255 -240.134744) (xy 83.219526 -240.148436) (xy 83.263988 -240.169534)
			(xy 83.304491 -240.19749) (xy 83.339984 -240.231582) (xy 83.369549 -240.270926) (xy 83.39242 -240.314503)
			(xy 83.408004 -240.361184) (xy 83.415899 -240.409761) (xy 83.416394 -240.434368) (xy 83.734905 -240.434368)
			(xy 83.739 -240.38364) (xy 83.751179 -240.334226) (xy 83.771127 -240.287406) (xy 83.798328 -240.244392)
			(xy 83.832076 -240.206298) (xy 83.871498 -240.174111) (xy 83.915572 -240.148665) (xy 83.963158 -240.130618)
			(xy 84.013022 -240.120438) (xy 84.063874 -240.118389) (xy 84.114395 -240.124523) (xy 84.163279 -240.138683)
			(xy 84.209258 -240.1605) (xy 84.251142 -240.18941) (xy 84.287846 -240.224665) (xy 84.318419 -240.265351)
			(xy 84.34207 -240.310414) (xy 84.358186 -240.358688) (xy 84.36635 -240.408922) (xy 84.366862 -240.434368)
			(xy 84.685136 -240.434368) (xy 84.689096 -240.385314) (xy 84.700873 -240.33753) (xy 84.720164 -240.292254)
			(xy 84.746467 -240.250658) (xy 84.779102 -240.213821) (xy 84.817223 -240.182696) (xy 84.859844 -240.158089)
			(xy 84.90586 -240.140637) (xy 84.954079 -240.130793) (xy 85.003254 -240.128812) (xy 85.052109 -240.134744)
			(xy 85.09938 -240.148436) (xy 85.143842 -240.169534) (xy 85.184345 -240.19749) (xy 85.219838 -240.231582)
			(xy 85.249403 -240.270926) (xy 85.272274 -240.314503) (xy 85.287858 -240.361184) (xy 85.295753 -240.409761)
			(xy 85.296248 -240.434368) (xy 85.614759 -240.434368) (xy 85.618854 -240.38364) (xy 85.631033 -240.334226)
			(xy 85.650981 -240.287406) (xy 85.678182 -240.244392) (xy 85.71193 -240.206298) (xy 85.751352 -240.174111)
			(xy 85.795426 -240.148665) (xy 85.843012 -240.130618) (xy 85.892876 -240.120438) (xy 85.943728 -240.118389)
			(xy 85.994249 -240.124523) (xy 86.043133 -240.138683) (xy 86.089112 -240.1605) (xy 86.130996 -240.18941)
			(xy 86.1677 -240.224665) (xy 86.198273 -240.265351) (xy 86.221924 -240.310414) (xy 86.23804 -240.358688)
			(xy 86.246204 -240.408922) (xy 86.246716 -240.434368) (xy 86.565244 -240.434368) (xy 86.569204 -240.385314)
			(xy 86.580981 -240.33753) (xy 86.600272 -240.292254) (xy 86.626575 -240.250658) (xy 86.65921 -240.213821)
			(xy 86.697331 -240.182696) (xy 86.739952 -240.158089) (xy 86.785968 -240.140637) (xy 86.834187 -240.130793)
			(xy 86.883362 -240.128812) (xy 86.932217 -240.134744) (xy 86.979488 -240.148436) (xy 87.02395 -240.169534)
			(xy 87.064453 -240.19749) (xy 87.099946 -240.231582) (xy 87.129511 -240.270926) (xy 87.152382 -240.314503)
			(xy 87.167966 -240.361184) (xy 87.175861 -240.409761) (xy 87.176356 -240.434368) (xy 87.494867 -240.434368)
			(xy 87.498962 -240.38364) (xy 87.511141 -240.334226) (xy 87.531089 -240.287406) (xy 87.55829 -240.244392)
			(xy 87.592038 -240.206298) (xy 87.63146 -240.174111) (xy 87.675534 -240.148665) (xy 87.72312 -240.130618)
			(xy 87.772984 -240.120438) (xy 87.823836 -240.118389) (xy 87.874357 -240.124523) (xy 87.923241 -240.138683)
			(xy 87.96922 -240.1605) (xy 88.011104 -240.18941) (xy 88.047808 -240.224665) (xy 88.078381 -240.265351)
			(xy 88.102032 -240.310414) (xy 88.118148 -240.358688) (xy 88.126312 -240.408922) (xy 88.126824 -240.434368)
			(xy 88.434921 -240.434368) (xy 88.439016 -240.38364) (xy 88.451195 -240.334226) (xy 88.471143 -240.287406)
			(xy 88.498344 -240.244392) (xy 88.532092 -240.206298) (xy 88.571514 -240.174111) (xy 88.615588 -240.148665)
			(xy 88.663174 -240.130618) (xy 88.713038 -240.120438) (xy 88.76389 -240.118389) (xy 88.814411 -240.124523)
			(xy 88.863295 -240.138683) (xy 88.909274 -240.1605) (xy 88.951158 -240.18941) (xy 88.987862 -240.224665)
			(xy 89.018435 -240.265351) (xy 89.042086 -240.310414) (xy 89.058202 -240.358688) (xy 89.066366 -240.408922)
			(xy 89.066878 -240.434368) (xy 89.385152 -240.434368) (xy 89.389112 -240.385314) (xy 89.400889 -240.33753)
			(xy 89.42018 -240.292254) (xy 89.446483 -240.250658) (xy 89.479118 -240.213821) (xy 89.517239 -240.182696)
			(xy 89.55986 -240.158089) (xy 89.605876 -240.140637) (xy 89.654095 -240.130793) (xy 89.70327 -240.128812)
			(xy 89.752125 -240.134744) (xy 89.799396 -240.148436) (xy 89.843858 -240.169534) (xy 89.884361 -240.19749)
			(xy 89.919854 -240.231582) (xy 89.949419 -240.270926) (xy 89.97229 -240.314503) (xy 89.987874 -240.361184)
			(xy 89.995769 -240.409761) (xy 89.996264 -240.434368) (xy 90.314775 -240.434368) (xy 90.31887 -240.38364)
			(xy 90.331049 -240.334226) (xy 90.350997 -240.287406) (xy 90.378198 -240.244392) (xy 90.411946 -240.206298)
			(xy 90.451368 -240.174111) (xy 90.495442 -240.148665) (xy 90.543028 -240.130618) (xy 90.592892 -240.120438)
			(xy 90.643744 -240.118389) (xy 90.694265 -240.124523) (xy 90.743149 -240.138683) (xy 90.789128 -240.1605)
			(xy 90.831012 -240.18941) (xy 90.867716 -240.224665) (xy 90.898289 -240.265351) (xy 90.92194 -240.310414)
			(xy 90.938056 -240.358688) (xy 90.94622 -240.408922) (xy 90.946732 -240.434368) (xy 91.26526 -240.434368)
			(xy 91.26922 -240.385314) (xy 91.280997 -240.33753) (xy 91.300288 -240.292254) (xy 91.326591 -240.250658)
			(xy 91.359226 -240.213821) (xy 91.397347 -240.182696) (xy 91.439968 -240.158089) (xy 91.485984 -240.140637)
			(xy 91.534203 -240.130793) (xy 91.583378 -240.128812) (xy 91.632233 -240.134744) (xy 91.679504 -240.148436)
			(xy 91.723966 -240.169534) (xy 91.764469 -240.19749) (xy 91.799962 -240.231582) (xy 91.829527 -240.270926)
			(xy 91.852398 -240.314503) (xy 91.867982 -240.361184) (xy 91.875877 -240.409761) (xy 91.876372 -240.434368)
			(xy 92.194883 -240.434368) (xy 92.198978 -240.38364) (xy 92.211157 -240.334226) (xy 92.231105 -240.287406)
			(xy 92.258306 -240.244392) (xy 92.292054 -240.206298) (xy 92.331476 -240.174111) (xy 92.37555 -240.148665)
			(xy 92.423136 -240.130618) (xy 92.473 -240.120438) (xy 92.523852 -240.118389) (xy 92.574373 -240.124523)
			(xy 92.623257 -240.138683) (xy 92.669236 -240.1605) (xy 92.71112 -240.18941) (xy 92.747824 -240.224665)
			(xy 92.778397 -240.265351) (xy 92.802048 -240.310414) (xy 92.818164 -240.358688) (xy 92.826328 -240.408922)
			(xy 92.82684 -240.434368) (xy 93.145114 -240.434368) (xy 93.149074 -240.385314) (xy 93.160851 -240.33753)
			(xy 93.180142 -240.292254) (xy 93.206445 -240.250658) (xy 93.23908 -240.213821) (xy 93.277201 -240.182696)
			(xy 93.319822 -240.158089) (xy 93.365838 -240.140637) (xy 93.414057 -240.130793) (xy 93.463232 -240.128812)
			(xy 93.512087 -240.134744) (xy 93.559358 -240.148436) (xy 93.60382 -240.169534) (xy 93.644323 -240.19749)
			(xy 93.679816 -240.231582) (xy 93.709381 -240.270926) (xy 93.732252 -240.314503) (xy 93.747836 -240.361184)
			(xy 93.755731 -240.409761) (xy 93.756226 -240.434368) (xy 94.074737 -240.434368) (xy 94.078832 -240.38364)
			(xy 94.091011 -240.334226) (xy 94.110959 -240.287406) (xy 94.13816 -240.244392) (xy 94.171908 -240.206298)
			(xy 94.21133 -240.174111) (xy 94.255404 -240.148665) (xy 94.30299 -240.130618) (xy 94.352854 -240.120438)
			(xy 94.403706 -240.118389) (xy 94.454227 -240.124523) (xy 94.503111 -240.138683) (xy 94.54909 -240.1605)
			(xy 94.590974 -240.18941) (xy 94.627678 -240.224665) (xy 94.658251 -240.265351) (xy 94.681902 -240.310414)
			(xy 94.698018 -240.358688) (xy 94.706182 -240.408922) (xy 94.706694 -240.434368) (xy 95.014791 -240.434368)
			(xy 95.018886 -240.38364) (xy 95.031065 -240.334226) (xy 95.051013 -240.287406) (xy 95.078214 -240.244392)
			(xy 95.111962 -240.206298) (xy 95.151384 -240.174111) (xy 95.195458 -240.148665) (xy 95.243044 -240.130618)
			(xy 95.292908 -240.120438) (xy 95.34376 -240.118389) (xy 95.394281 -240.124523) (xy 95.443165 -240.138683)
			(xy 95.489144 -240.1605) (xy 95.531028 -240.18941) (xy 95.567732 -240.224665) (xy 95.598305 -240.265351)
			(xy 95.621956 -240.310414) (xy 95.638072 -240.358688) (xy 95.646236 -240.408922) (xy 95.646748 -240.434368)
			(xy 95.965276 -240.434368) (xy 95.969236 -240.385314) (xy 95.981013 -240.33753) (xy 96.000304 -240.292254)
			(xy 96.026607 -240.250658) (xy 96.059242 -240.213821) (xy 96.097363 -240.182696) (xy 96.139984 -240.158089)
			(xy 96.186 -240.140637) (xy 96.234219 -240.130793) (xy 96.283394 -240.128812) (xy 96.332249 -240.134744)
			(xy 96.37952 -240.148436) (xy 96.423982 -240.169534) (xy 96.464485 -240.19749) (xy 96.499978 -240.231582)
			(xy 96.529543 -240.270926) (xy 96.552414 -240.314503) (xy 96.567998 -240.361184) (xy 96.575893 -240.409761)
			(xy 96.576388 -240.434368) (xy 96.90533 -240.434368) (xy 96.90929 -240.385314) (xy 96.921067 -240.33753)
			(xy 96.940358 -240.292254) (xy 96.966661 -240.250658) (xy 96.999296 -240.213821) (xy 97.037417 -240.182696)
			(xy 97.080038 -240.158089) (xy 97.126054 -240.140637) (xy 97.174273 -240.130793) (xy 97.223448 -240.128812)
			(xy 97.272303 -240.134744) (xy 97.319574 -240.148436) (xy 97.364036 -240.169534) (xy 97.404539 -240.19749)
			(xy 97.440032 -240.231582) (xy 97.469597 -240.270926) (xy 97.492468 -240.314503) (xy 97.508052 -240.361184)
			(xy 97.515947 -240.409761) (xy 97.516442 -240.434368) (xy 97.84513 -240.434368) (xy 97.84909 -240.385314)
			(xy 97.860867 -240.33753) (xy 97.880158 -240.292254) (xy 97.906461 -240.250658) (xy 97.939096 -240.213821)
			(xy 97.977217 -240.182696) (xy 98.019838 -240.158089) (xy 98.065854 -240.140637) (xy 98.114073 -240.130793)
			(xy 98.163248 -240.128812) (xy 98.212103 -240.134744) (xy 98.259374 -240.148436) (xy 98.303836 -240.169534)
			(xy 98.344339 -240.19749) (xy 98.379832 -240.231582) (xy 98.409397 -240.270926) (xy 98.432268 -240.314503)
			(xy 98.447852 -240.361184) (xy 98.455747 -240.409761) (xy 98.456242 -240.434368) (xy 98.785184 -240.434368)
			(xy 98.789144 -240.385314) (xy 98.800921 -240.33753) (xy 98.820212 -240.292254) (xy 98.846515 -240.250658)
			(xy 98.87915 -240.213821) (xy 98.917271 -240.182696) (xy 98.959892 -240.158089) (xy 99.005908 -240.140637)
			(xy 99.054127 -240.130793) (xy 99.103302 -240.128812) (xy 99.152157 -240.134744) (xy 99.199428 -240.148436)
			(xy 99.24389 -240.169534) (xy 99.284393 -240.19749) (xy 99.319886 -240.231582) (xy 99.349451 -240.270926)
			(xy 99.372322 -240.314503) (xy 99.387906 -240.361184) (xy 99.395801 -240.409761) (xy 99.396296 -240.434368)
			(xy 99.725238 -240.434368) (xy 99.729198 -240.385314) (xy 99.740975 -240.33753) (xy 99.760266 -240.292254)
			(xy 99.786569 -240.250658) (xy 99.819204 -240.213821) (xy 99.857325 -240.182696) (xy 99.899946 -240.158089)
			(xy 99.945962 -240.140637) (xy 99.994181 -240.130793) (xy 100.043356 -240.128812) (xy 100.092211 -240.134744)
			(xy 100.139482 -240.148436) (xy 100.183944 -240.169534) (xy 100.224447 -240.19749) (xy 100.25994 -240.231582)
			(xy 100.289505 -240.270926) (xy 100.312376 -240.314503) (xy 100.32796 -240.361184) (xy 100.335855 -240.409761)
			(xy 100.33635 -240.434368) (xy 100.665292 -240.434368) (xy 100.669252 -240.385314) (xy 100.681029 -240.33753)
			(xy 100.70032 -240.292254) (xy 100.726623 -240.250658) (xy 100.759258 -240.213821) (xy 100.797379 -240.182696)
			(xy 100.84 -240.158089) (xy 100.886016 -240.140637) (xy 100.934235 -240.130793) (xy 100.98341 -240.128812)
			(xy 101.032265 -240.134744) (xy 101.079536 -240.148436) (xy 101.123998 -240.169534) (xy 101.164501 -240.19749)
			(xy 101.199994 -240.231582) (xy 101.229559 -240.270926) (xy 101.25243 -240.314503) (xy 101.268014 -240.361184)
			(xy 101.275909 -240.409761) (xy 101.276404 -240.434368) (xy 101.605346 -240.434368) (xy 101.609306 -240.385314)
			(xy 101.621083 -240.33753) (xy 101.640374 -240.292254) (xy 101.666677 -240.250658) (xy 101.699312 -240.213821)
			(xy 101.737433 -240.182696) (xy 101.780054 -240.158089) (xy 101.82607 -240.140637) (xy 101.874289 -240.130793)
			(xy 101.923464 -240.128812) (xy 101.972319 -240.134744) (xy 102.01959 -240.148436) (xy 102.064052 -240.169534)
			(xy 102.104555 -240.19749) (xy 102.140048 -240.231582) (xy 102.169613 -240.270926) (xy 102.192484 -240.314503)
			(xy 102.208068 -240.361184) (xy 102.215963 -240.409761) (xy 102.216458 -240.434368) (xy 102.545146 -240.434368)
			(xy 102.549106 -240.385314) (xy 102.560883 -240.33753) (xy 102.580174 -240.292254) (xy 102.606477 -240.250658)
			(xy 102.639112 -240.213821) (xy 102.677233 -240.182696) (xy 102.719854 -240.158089) (xy 102.76587 -240.140637)
			(xy 102.814089 -240.130793) (xy 102.863264 -240.128812) (xy 102.912119 -240.134744) (xy 102.95939 -240.148436)
			(xy 103.003852 -240.169534) (xy 103.044355 -240.19749) (xy 103.079848 -240.231582) (xy 103.109413 -240.270926)
			(xy 103.132284 -240.314503) (xy 103.147868 -240.361184) (xy 103.155763 -240.409761) (xy 103.156258 -240.434368)
			(xy 103.4852 -240.434368) (xy 103.48916 -240.385314) (xy 103.500937 -240.33753) (xy 103.520228 -240.292254)
			(xy 103.546531 -240.250658) (xy 103.579166 -240.213821) (xy 103.617287 -240.182696) (xy 103.659908 -240.158089)
			(xy 103.705924 -240.140637) (xy 103.754143 -240.130793) (xy 103.803318 -240.128812) (xy 103.852173 -240.134744)
			(xy 103.899444 -240.148436) (xy 103.943906 -240.169534) (xy 103.984409 -240.19749) (xy 104.019902 -240.231582)
			(xy 104.049467 -240.270926) (xy 104.072338 -240.314503) (xy 104.087922 -240.361184) (xy 104.095817 -240.409761)
			(xy 104.096312 -240.434368) (xy 104.425254 -240.434368) (xy 104.429214 -240.385314) (xy 104.440991 -240.33753)
			(xy 104.460282 -240.292254) (xy 104.486585 -240.250658) (xy 104.51922 -240.213821) (xy 104.557341 -240.182696)
			(xy 104.599962 -240.158089) (xy 104.645978 -240.140637) (xy 104.694197 -240.130793) (xy 104.743372 -240.128812)
			(xy 104.792227 -240.134744) (xy 104.839498 -240.148436) (xy 104.88396 -240.169534) (xy 104.924463 -240.19749)
			(xy 104.959956 -240.231582) (xy 104.989521 -240.270926) (xy 105.012392 -240.314503) (xy 105.027976 -240.361184)
			(xy 105.035871 -240.409761) (xy 105.036366 -240.434368) (xy 105.365308 -240.434368) (xy 105.369268 -240.385314)
			(xy 105.381045 -240.33753) (xy 105.400336 -240.292254) (xy 105.426639 -240.250658) (xy 105.459274 -240.213821)
			(xy 105.497395 -240.182696) (xy 105.540016 -240.158089) (xy 105.586032 -240.140637) (xy 105.634251 -240.130793)
			(xy 105.683426 -240.128812) (xy 105.732281 -240.134744) (xy 105.779552 -240.148436) (xy 105.824014 -240.169534)
			(xy 105.864517 -240.19749) (xy 105.90001 -240.231582) (xy 105.929575 -240.270926) (xy 105.952446 -240.314503)
			(xy 105.96803 -240.361184) (xy 105.975925 -240.409761) (xy 105.97642 -240.434368) (xy 106.305362 -240.434368)
			(xy 106.309322 -240.385314) (xy 106.321099 -240.33753) (xy 106.34039 -240.292254) (xy 106.366693 -240.250658)
			(xy 106.399328 -240.213821) (xy 106.437449 -240.182696) (xy 106.48007 -240.158089) (xy 106.526086 -240.140637)
			(xy 106.574305 -240.130793) (xy 106.62348 -240.128812) (xy 106.672335 -240.134744) (xy 106.719606 -240.148436)
			(xy 106.764068 -240.169534) (xy 106.804571 -240.19749) (xy 106.840064 -240.231582) (xy 106.869629 -240.270926)
			(xy 106.8925 -240.314503) (xy 106.908084 -240.361184) (xy 106.915979 -240.409761) (xy 106.916474 -240.434368)
			(xy 107.245162 -240.434368) (xy 107.249122 -240.385314) (xy 107.260899 -240.33753) (xy 107.28019 -240.292254)
			(xy 107.306493 -240.250658) (xy 107.339128 -240.213821) (xy 107.377249 -240.182696) (xy 107.41987 -240.158089)
			(xy 107.465886 -240.140637) (xy 107.514105 -240.130793) (xy 107.56328 -240.128812) (xy 107.612135 -240.134744)
			(xy 107.659406 -240.148436) (xy 107.703868 -240.169534) (xy 107.744371 -240.19749) (xy 107.779864 -240.231582)
			(xy 107.809429 -240.270926) (xy 107.8323 -240.314503) (xy 107.847884 -240.361184) (xy 107.855779 -240.409761)
			(xy 107.856274 -240.434368) (xy 108.174785 -240.434368) (xy 108.17888 -240.38364) (xy 108.191059 -240.334226)
			(xy 108.211007 -240.287406) (xy 108.238208 -240.244392) (xy 108.271956 -240.206298) (xy 108.311378 -240.174111)
			(xy 108.355452 -240.148665) (xy 108.403038 -240.130618) (xy 108.452902 -240.120438) (xy 108.503754 -240.118389)
			(xy 108.554275 -240.124523) (xy 108.603159 -240.138683) (xy 108.649138 -240.1605) (xy 108.691022 -240.18941)
			(xy 108.727726 -240.224665) (xy 108.758299 -240.265351) (xy 108.78195 -240.310414) (xy 108.798066 -240.358688)
			(xy 108.80623 -240.408922) (xy 108.806742 -240.434368) (xy 109.114839 -240.434368) (xy 109.118934 -240.38364)
			(xy 109.131113 -240.334226) (xy 109.151061 -240.287406) (xy 109.178262 -240.244392) (xy 109.21201 -240.206298)
			(xy 109.251432 -240.174111) (xy 109.295506 -240.148665) (xy 109.343092 -240.130618) (xy 109.392956 -240.120438)
			(xy 109.443808 -240.118389) (xy 109.494329 -240.124523) (xy 109.543213 -240.138683) (xy 109.589192 -240.1605)
			(xy 109.631076 -240.18941) (xy 109.66778 -240.224665) (xy 109.698353 -240.265351) (xy 109.722004 -240.310414)
			(xy 109.73812 -240.358688) (xy 109.746284 -240.408922) (xy 109.746796 -240.434368) (xy 110.065324 -240.434368)
			(xy 110.069284 -240.385314) (xy 110.081061 -240.33753) (xy 110.100352 -240.292254) (xy 110.126655 -240.250658)
			(xy 110.15929 -240.213821) (xy 110.197411 -240.182696) (xy 110.240032 -240.158089) (xy 110.286048 -240.140637)
			(xy 110.334267 -240.130793) (xy 110.383442 -240.128812) (xy 110.432297 -240.134744) (xy 110.479568 -240.148436)
			(xy 110.52403 -240.169534) (xy 110.564533 -240.19749) (xy 110.600026 -240.231582) (xy 110.629591 -240.270926)
			(xy 110.652462 -240.314503) (xy 110.668046 -240.361184) (xy 110.675941 -240.409761) (xy 110.676436 -240.434368)
			(xy 110.675941 -240.458975) (xy 110.668046 -240.507552) (xy 110.652462 -240.554233) (xy 110.629591 -240.59781)
			(xy 110.600026 -240.637154) (xy 110.564533 -240.671246) (xy 110.52403 -240.699202) (xy 110.479568 -240.7203)
			(xy 110.432297 -240.733992) (xy 110.383442 -240.739924) (xy 110.334267 -240.737943) (xy 110.286048 -240.728099)
			(xy 110.240032 -240.710647) (xy 110.197411 -240.68604) (xy 110.15929 -240.654915) (xy 110.126655 -240.618078)
			(xy 110.100352 -240.576482) (xy 110.081061 -240.531206) (xy 110.069284 -240.483422) (xy 110.065324 -240.434368)
			(xy 109.746796 -240.434368) (xy 109.746284 -240.459814) (xy 109.73812 -240.510048) (xy 109.722004 -240.558322)
			(xy 109.698353 -240.603385) (xy 109.66778 -240.644071) (xy 109.631076 -240.679326) (xy 109.589192 -240.708236)
			(xy 109.543213 -240.730053) (xy 109.494329 -240.744213) (xy 109.443808 -240.750347) (xy 109.392956 -240.748298)
			(xy 109.343092 -240.738118) (xy 109.295506 -240.720071) (xy 109.251432 -240.694625) (xy 109.21201 -240.662438)
			(xy 109.178262 -240.624344) (xy 109.151061 -240.58133) (xy 109.131113 -240.53451) (xy 109.118934 -240.485096)
			(xy 109.114839 -240.434368) (xy 108.806742 -240.434368) (xy 108.80623 -240.459814) (xy 108.798066 -240.510048)
			(xy 108.78195 -240.558322) (xy 108.758299 -240.603385) (xy 108.727726 -240.644071) (xy 108.691022 -240.679326)
			(xy 108.649138 -240.708236) (xy 108.603159 -240.730053) (xy 108.554275 -240.744213) (xy 108.503754 -240.750347)
			(xy 108.452902 -240.748298) (xy 108.403038 -240.738118) (xy 108.355452 -240.720071) (xy 108.311378 -240.694625)
			(xy 108.271956 -240.662438) (xy 108.238208 -240.624344) (xy 108.211007 -240.58133) (xy 108.191059 -240.53451)
			(xy 108.17888 -240.485096) (xy 108.174785 -240.434368) (xy 107.856274 -240.434368) (xy 107.855779 -240.458975)
			(xy 107.847884 -240.507552) (xy 107.8323 -240.554233) (xy 107.809429 -240.59781) (xy 107.779864 -240.637154)
			(xy 107.744371 -240.671246) (xy 107.703868 -240.699202) (xy 107.659406 -240.7203) (xy 107.612135 -240.733992)
			(xy 107.56328 -240.739924) (xy 107.514105 -240.737943) (xy 107.465886 -240.728099) (xy 107.41987 -240.710647)
			(xy 107.377249 -240.68604) (xy 107.339128 -240.654915) (xy 107.306493 -240.618078) (xy 107.28019 -240.576482)
			(xy 107.260899 -240.531206) (xy 107.249122 -240.483422) (xy 107.245162 -240.434368) (xy 106.916474 -240.434368)
			(xy 106.915979 -240.458975) (xy 106.908084 -240.507552) (xy 106.8925 -240.554233) (xy 106.869629 -240.59781)
			(xy 106.840064 -240.637154) (xy 106.804571 -240.671246) (xy 106.764068 -240.699202) (xy 106.719606 -240.7203)
			(xy 106.672335 -240.733992) (xy 106.62348 -240.739924) (xy 106.574305 -240.737943) (xy 106.526086 -240.728099)
			(xy 106.48007 -240.710647) (xy 106.437449 -240.68604) (xy 106.399328 -240.654915) (xy 106.366693 -240.618078)
			(xy 106.34039 -240.576482) (xy 106.321099 -240.531206) (xy 106.309322 -240.483422) (xy 106.305362 -240.434368)
			(xy 105.97642 -240.434368) (xy 105.975925 -240.458975) (xy 105.96803 -240.507552) (xy 105.952446 -240.554233)
			(xy 105.929575 -240.59781) (xy 105.90001 -240.637154) (xy 105.864517 -240.671246) (xy 105.824014 -240.699202)
			(xy 105.779552 -240.7203) (xy 105.732281 -240.733992) (xy 105.683426 -240.739924) (xy 105.634251 -240.737943)
			(xy 105.586032 -240.728099) (xy 105.540016 -240.710647) (xy 105.497395 -240.68604) (xy 105.459274 -240.654915)
			(xy 105.426639 -240.618078) (xy 105.400336 -240.576482) (xy 105.381045 -240.531206) (xy 105.369268 -240.483422)
			(xy 105.365308 -240.434368) (xy 105.036366 -240.434368) (xy 105.035871 -240.458975) (xy 105.027976 -240.507552)
			(xy 105.012392 -240.554233) (xy 104.989521 -240.59781) (xy 104.959956 -240.637154) (xy 104.924463 -240.671246)
			(xy 104.88396 -240.699202) (xy 104.839498 -240.7203) (xy 104.792227 -240.733992) (xy 104.743372 -240.739924)
			(xy 104.694197 -240.737943) (xy 104.645978 -240.728099) (xy 104.599962 -240.710647) (xy 104.557341 -240.68604)
			(xy 104.51922 -240.654915) (xy 104.486585 -240.618078) (xy 104.460282 -240.576482) (xy 104.440991 -240.531206)
			(xy 104.429214 -240.483422) (xy 104.425254 -240.434368) (xy 104.096312 -240.434368) (xy 104.095817 -240.458975)
			(xy 104.087922 -240.507552) (xy 104.072338 -240.554233) (xy 104.049467 -240.59781) (xy 104.019902 -240.637154)
			(xy 103.984409 -240.671246) (xy 103.943906 -240.699202) (xy 103.899444 -240.7203) (xy 103.852173 -240.733992)
			(xy 103.803318 -240.739924) (xy 103.754143 -240.737943) (xy 103.705924 -240.728099) (xy 103.659908 -240.710647)
			(xy 103.617287 -240.68604) (xy 103.579166 -240.654915) (xy 103.546531 -240.618078) (xy 103.520228 -240.576482)
			(xy 103.500937 -240.531206) (xy 103.48916 -240.483422) (xy 103.4852 -240.434368) (xy 103.156258 -240.434368)
			(xy 103.155763 -240.458975) (xy 103.147868 -240.507552) (xy 103.132284 -240.554233) (xy 103.109413 -240.59781)
			(xy 103.079848 -240.637154) (xy 103.044355 -240.671246) (xy 103.003852 -240.699202) (xy 102.95939 -240.7203)
			(xy 102.912119 -240.733992) (xy 102.863264 -240.739924) (xy 102.814089 -240.737943) (xy 102.76587 -240.728099)
			(xy 102.719854 -240.710647) (xy 102.677233 -240.68604) (xy 102.639112 -240.654915) (xy 102.606477 -240.618078)
			(xy 102.580174 -240.576482) (xy 102.560883 -240.531206) (xy 102.549106 -240.483422) (xy 102.545146 -240.434368)
			(xy 102.216458 -240.434368) (xy 102.215963 -240.458975) (xy 102.208068 -240.507552) (xy 102.192484 -240.554233)
			(xy 102.169613 -240.59781) (xy 102.140048 -240.637154) (xy 102.104555 -240.671246) (xy 102.064052 -240.699202)
			(xy 102.01959 -240.7203) (xy 101.972319 -240.733992) (xy 101.923464 -240.739924) (xy 101.874289 -240.737943)
			(xy 101.82607 -240.728099) (xy 101.780054 -240.710647) (xy 101.737433 -240.68604) (xy 101.699312 -240.654915)
			(xy 101.666677 -240.618078) (xy 101.640374 -240.576482) (xy 101.621083 -240.531206) (xy 101.609306 -240.483422)
			(xy 101.605346 -240.434368) (xy 101.276404 -240.434368) (xy 101.275909 -240.458975) (xy 101.268014 -240.507552)
			(xy 101.25243 -240.554233) (xy 101.229559 -240.59781) (xy 101.199994 -240.637154) (xy 101.164501 -240.671246)
			(xy 101.123998 -240.699202) (xy 101.079536 -240.7203) (xy 101.032265 -240.733992) (xy 100.98341 -240.739924)
			(xy 100.934235 -240.737943) (xy 100.886016 -240.728099) (xy 100.84 -240.710647) (xy 100.797379 -240.68604)
			(xy 100.759258 -240.654915) (xy 100.726623 -240.618078) (xy 100.70032 -240.576482) (xy 100.681029 -240.531206)
			(xy 100.669252 -240.483422) (xy 100.665292 -240.434368) (xy 100.33635 -240.434368) (xy 100.335855 -240.458975)
			(xy 100.32796 -240.507552) (xy 100.312376 -240.554233) (xy 100.289505 -240.59781) (xy 100.25994 -240.637154)
			(xy 100.224447 -240.671246) (xy 100.183944 -240.699202) (xy 100.139482 -240.7203) (xy 100.092211 -240.733992)
			(xy 100.043356 -240.739924) (xy 99.994181 -240.737943) (xy 99.945962 -240.728099) (xy 99.899946 -240.710647)
			(xy 99.857325 -240.68604) (xy 99.819204 -240.654915) (xy 99.786569 -240.618078) (xy 99.760266 -240.576482)
			(xy 99.740975 -240.531206) (xy 99.729198 -240.483422) (xy 99.725238 -240.434368) (xy 99.396296 -240.434368)
			(xy 99.395801 -240.458975) (xy 99.387906 -240.507552) (xy 99.372322 -240.554233) (xy 99.349451 -240.59781)
			(xy 99.319886 -240.637154) (xy 99.284393 -240.671246) (xy 99.24389 -240.699202) (xy 99.199428 -240.7203)
			(xy 99.152157 -240.733992) (xy 99.103302 -240.739924) (xy 99.054127 -240.737943) (xy 99.005908 -240.728099)
			(xy 98.959892 -240.710647) (xy 98.917271 -240.68604) (xy 98.87915 -240.654915) (xy 98.846515 -240.618078)
			(xy 98.820212 -240.576482) (xy 98.800921 -240.531206) (xy 98.789144 -240.483422) (xy 98.785184 -240.434368)
			(xy 98.456242 -240.434368) (xy 98.455747 -240.458975) (xy 98.447852 -240.507552) (xy 98.432268 -240.554233)
			(xy 98.409397 -240.59781) (xy 98.379832 -240.637154) (xy 98.344339 -240.671246) (xy 98.303836 -240.699202)
			(xy 98.259374 -240.7203) (xy 98.212103 -240.733992) (xy 98.163248 -240.739924) (xy 98.114073 -240.737943)
			(xy 98.065854 -240.728099) (xy 98.019838 -240.710647) (xy 97.977217 -240.68604) (xy 97.939096 -240.654915)
			(xy 97.906461 -240.618078) (xy 97.880158 -240.576482) (xy 97.860867 -240.531206) (xy 97.84909 -240.483422)
			(xy 97.84513 -240.434368) (xy 97.516442 -240.434368) (xy 97.515947 -240.458975) (xy 97.508052 -240.507552)
			(xy 97.492468 -240.554233) (xy 97.469597 -240.59781) (xy 97.440032 -240.637154) (xy 97.404539 -240.671246)
			(xy 97.364036 -240.699202) (xy 97.319574 -240.7203) (xy 97.272303 -240.733992) (xy 97.223448 -240.739924)
			(xy 97.174273 -240.737943) (xy 97.126054 -240.728099) (xy 97.080038 -240.710647) (xy 97.037417 -240.68604)
			(xy 96.999296 -240.654915) (xy 96.966661 -240.618078) (xy 96.940358 -240.576482) (xy 96.921067 -240.531206)
			(xy 96.90929 -240.483422) (xy 96.90533 -240.434368) (xy 96.576388 -240.434368) (xy 96.575893 -240.458975)
			(xy 96.567998 -240.507552) (xy 96.552414 -240.554233) (xy 96.529543 -240.59781) (xy 96.499978 -240.637154)
			(xy 96.464485 -240.671246) (xy 96.423982 -240.699202) (xy 96.37952 -240.7203) (xy 96.332249 -240.733992)
			(xy 96.283394 -240.739924) (xy 96.234219 -240.737943) (xy 96.186 -240.728099) (xy 96.139984 -240.710647)
			(xy 96.097363 -240.68604) (xy 96.059242 -240.654915) (xy 96.026607 -240.618078) (xy 96.000304 -240.576482)
			(xy 95.981013 -240.531206) (xy 95.969236 -240.483422) (xy 95.965276 -240.434368) (xy 95.646748 -240.434368)
			(xy 95.646236 -240.459814) (xy 95.638072 -240.510048) (xy 95.621956 -240.558322) (xy 95.598305 -240.603385)
			(xy 95.567732 -240.644071) (xy 95.531028 -240.679326) (xy 95.489144 -240.708236) (xy 95.443165 -240.730053)
			(xy 95.394281 -240.744213) (xy 95.34376 -240.750347) (xy 95.292908 -240.748298) (xy 95.243044 -240.738118)
			(xy 95.195458 -240.720071) (xy 95.151384 -240.694625) (xy 95.111962 -240.662438) (xy 95.078214 -240.624344)
			(xy 95.051013 -240.58133) (xy 95.031065 -240.53451) (xy 95.018886 -240.485096) (xy 95.014791 -240.434368)
			(xy 94.706694 -240.434368) (xy 94.706182 -240.459814) (xy 94.698018 -240.510048) (xy 94.681902 -240.558322)
			(xy 94.658251 -240.603385) (xy 94.627678 -240.644071) (xy 94.590974 -240.679326) (xy 94.54909 -240.708236)
			(xy 94.503111 -240.730053) (xy 94.454227 -240.744213) (xy 94.403706 -240.750347) (xy 94.352854 -240.748298)
			(xy 94.30299 -240.738118) (xy 94.255404 -240.720071) (xy 94.21133 -240.694625) (xy 94.171908 -240.662438)
			(xy 94.13816 -240.624344) (xy 94.110959 -240.58133) (xy 94.091011 -240.53451) (xy 94.078832 -240.485096)
			(xy 94.074737 -240.434368) (xy 93.756226 -240.434368) (xy 93.755731 -240.458975) (xy 93.747836 -240.507552)
			(xy 93.732252 -240.554233) (xy 93.709381 -240.59781) (xy 93.679816 -240.637154) (xy 93.644323 -240.671246)
			(xy 93.60382 -240.699202) (xy 93.559358 -240.7203) (xy 93.512087 -240.733992) (xy 93.463232 -240.739924)
			(xy 93.414057 -240.737943) (xy 93.365838 -240.728099) (xy 93.319822 -240.710647) (xy 93.277201 -240.68604)
			(xy 93.23908 -240.654915) (xy 93.206445 -240.618078) (xy 93.180142 -240.576482) (xy 93.160851 -240.531206)
			(xy 93.149074 -240.483422) (xy 93.145114 -240.434368) (xy 92.82684 -240.434368) (xy 92.826328 -240.459814)
			(xy 92.818164 -240.510048) (xy 92.802048 -240.558322) (xy 92.778397 -240.603385) (xy 92.747824 -240.644071)
			(xy 92.71112 -240.679326) (xy 92.669236 -240.708236) (xy 92.623257 -240.730053) (xy 92.574373 -240.744213)
			(xy 92.523852 -240.750347) (xy 92.473 -240.748298) (xy 92.423136 -240.738118) (xy 92.37555 -240.720071)
			(xy 92.331476 -240.694625) (xy 92.292054 -240.662438) (xy 92.258306 -240.624344) (xy 92.231105 -240.58133)
			(xy 92.211157 -240.53451) (xy 92.198978 -240.485096) (xy 92.194883 -240.434368) (xy 91.876372 -240.434368)
			(xy 91.875877 -240.458975) (xy 91.867982 -240.507552) (xy 91.852398 -240.554233) (xy 91.829527 -240.59781)
			(xy 91.799962 -240.637154) (xy 91.764469 -240.671246) (xy 91.723966 -240.699202) (xy 91.679504 -240.7203)
			(xy 91.632233 -240.733992) (xy 91.583378 -240.739924) (xy 91.534203 -240.737943) (xy 91.485984 -240.728099)
			(xy 91.439968 -240.710647) (xy 91.397347 -240.68604) (xy 91.359226 -240.654915) (xy 91.326591 -240.618078)
			(xy 91.300288 -240.576482) (xy 91.280997 -240.531206) (xy 91.26922 -240.483422) (xy 91.26526 -240.434368)
			(xy 90.946732 -240.434368) (xy 90.94622 -240.459814) (xy 90.938056 -240.510048) (xy 90.92194 -240.558322)
			(xy 90.898289 -240.603385) (xy 90.867716 -240.644071) (xy 90.831012 -240.679326) (xy 90.789128 -240.708236)
			(xy 90.743149 -240.730053) (xy 90.694265 -240.744213) (xy 90.643744 -240.750347) (xy 90.592892 -240.748298)
			(xy 90.543028 -240.738118) (xy 90.495442 -240.720071) (xy 90.451368 -240.694625) (xy 90.411946 -240.662438)
			(xy 90.378198 -240.624344) (xy 90.350997 -240.58133) (xy 90.331049 -240.53451) (xy 90.31887 -240.485096)
			(xy 90.314775 -240.434368) (xy 89.996264 -240.434368) (xy 89.995769 -240.458975) (xy 89.987874 -240.507552)
			(xy 89.97229 -240.554233) (xy 89.949419 -240.59781) (xy 89.919854 -240.637154) (xy 89.884361 -240.671246)
			(xy 89.843858 -240.699202) (xy 89.799396 -240.7203) (xy 89.752125 -240.733992) (xy 89.70327 -240.739924)
			(xy 89.654095 -240.737943) (xy 89.605876 -240.728099) (xy 89.55986 -240.710647) (xy 89.517239 -240.68604)
			(xy 89.479118 -240.654915) (xy 89.446483 -240.618078) (xy 89.42018 -240.576482) (xy 89.400889 -240.531206)
			(xy 89.389112 -240.483422) (xy 89.385152 -240.434368) (xy 89.066878 -240.434368) (xy 89.066366 -240.459814)
			(xy 89.058202 -240.510048) (xy 89.042086 -240.558322) (xy 89.018435 -240.603385) (xy 88.987862 -240.644071)
			(xy 88.951158 -240.679326) (xy 88.909274 -240.708236) (xy 88.863295 -240.730053) (xy 88.814411 -240.744213)
			(xy 88.76389 -240.750347) (xy 88.713038 -240.748298) (xy 88.663174 -240.738118) (xy 88.615588 -240.720071)
			(xy 88.571514 -240.694625) (xy 88.532092 -240.662438) (xy 88.498344 -240.624344) (xy 88.471143 -240.58133)
			(xy 88.451195 -240.53451) (xy 88.439016 -240.485096) (xy 88.434921 -240.434368) (xy 88.126824 -240.434368)
			(xy 88.126312 -240.459814) (xy 88.118148 -240.510048) (xy 88.102032 -240.558322) (xy 88.078381 -240.603385)
			(xy 88.047808 -240.644071) (xy 88.011104 -240.679326) (xy 87.96922 -240.708236) (xy 87.923241 -240.730053)
			(xy 87.874357 -240.744213) (xy 87.823836 -240.750347) (xy 87.772984 -240.748298) (xy 87.72312 -240.738118)
			(xy 87.675534 -240.720071) (xy 87.63146 -240.694625) (xy 87.592038 -240.662438) (xy 87.55829 -240.624344)
			(xy 87.531089 -240.58133) (xy 87.511141 -240.53451) (xy 87.498962 -240.485096) (xy 87.494867 -240.434368)
			(xy 87.176356 -240.434368) (xy 87.175861 -240.458975) (xy 87.167966 -240.507552) (xy 87.152382 -240.554233)
			(xy 87.129511 -240.59781) (xy 87.099946 -240.637154) (xy 87.064453 -240.671246) (xy 87.02395 -240.699202)
			(xy 86.979488 -240.7203) (xy 86.932217 -240.733992) (xy 86.883362 -240.739924) (xy 86.834187 -240.737943)
			(xy 86.785968 -240.728099) (xy 86.739952 -240.710647) (xy 86.697331 -240.68604) (xy 86.65921 -240.654915)
			(xy 86.626575 -240.618078) (xy 86.600272 -240.576482) (xy 86.580981 -240.531206) (xy 86.569204 -240.483422)
			(xy 86.565244 -240.434368) (xy 86.246716 -240.434368) (xy 86.246204 -240.459814) (xy 86.23804 -240.510048)
			(xy 86.221924 -240.558322) (xy 86.198273 -240.603385) (xy 86.1677 -240.644071) (xy 86.130996 -240.679326)
			(xy 86.089112 -240.708236) (xy 86.043133 -240.730053) (xy 85.994249 -240.744213) (xy 85.943728 -240.750347)
			(xy 85.892876 -240.748298) (xy 85.843012 -240.738118) (xy 85.795426 -240.720071) (xy 85.751352 -240.694625)
			(xy 85.71193 -240.662438) (xy 85.678182 -240.624344) (xy 85.650981 -240.58133) (xy 85.631033 -240.53451)
			(xy 85.618854 -240.485096) (xy 85.614759 -240.434368) (xy 85.296248 -240.434368) (xy 85.295753 -240.458975)
			(xy 85.287858 -240.507552) (xy 85.272274 -240.554233) (xy 85.249403 -240.59781) (xy 85.219838 -240.637154)
			(xy 85.184345 -240.671246) (xy 85.143842 -240.699202) (xy 85.09938 -240.7203) (xy 85.052109 -240.733992)
			(xy 85.003254 -240.739924) (xy 84.954079 -240.737943) (xy 84.90586 -240.728099) (xy 84.859844 -240.710647)
			(xy 84.817223 -240.68604) (xy 84.779102 -240.654915) (xy 84.746467 -240.618078) (xy 84.720164 -240.576482)
			(xy 84.700873 -240.531206) (xy 84.689096 -240.483422) (xy 84.685136 -240.434368) (xy 84.366862 -240.434368)
			(xy 84.36635 -240.459814) (xy 84.358186 -240.510048) (xy 84.34207 -240.558322) (xy 84.318419 -240.603385)
			(xy 84.287846 -240.644071) (xy 84.251142 -240.679326) (xy 84.209258 -240.708236) (xy 84.163279 -240.730053)
			(xy 84.114395 -240.744213) (xy 84.063874 -240.750347) (xy 84.013022 -240.748298) (xy 83.963158 -240.738118)
			(xy 83.915572 -240.720071) (xy 83.871498 -240.694625) (xy 83.832076 -240.662438) (xy 83.798328 -240.624344)
			(xy 83.771127 -240.58133) (xy 83.751179 -240.53451) (xy 83.739 -240.485096) (xy 83.734905 -240.434368)
			(xy 83.416394 -240.434368) (xy 83.415899 -240.458975) (xy 83.408004 -240.507552) (xy 83.39242 -240.554233)
			(xy 83.369549 -240.59781) (xy 83.339984 -240.637154) (xy 83.304491 -240.671246) (xy 83.263988 -240.699202)
			(xy 83.219526 -240.7203) (xy 83.172255 -240.733992) (xy 83.1234 -240.739924) (xy 83.074225 -240.737943)
			(xy 83.026006 -240.728099) (xy 82.97999 -240.710647) (xy 82.937369 -240.68604) (xy 82.899248 -240.654915)
			(xy 82.866613 -240.618078) (xy 82.84031 -240.576482) (xy 82.821019 -240.531206) (xy 82.809242 -240.483422)
			(xy 82.805282 -240.434368) (xy 82.486754 -240.434368) (xy 82.486242 -240.459814) (xy 82.478078 -240.510048)
			(xy 82.461962 -240.558322) (xy 82.438311 -240.603385) (xy 82.407738 -240.644071) (xy 82.371034 -240.679326)
			(xy 82.32915 -240.708236) (xy 82.283171 -240.730053) (xy 82.234287 -240.744213) (xy 82.183766 -240.750347)
			(xy 82.132914 -240.748298) (xy 82.08305 -240.738118) (xy 82.035464 -240.720071) (xy 81.99139 -240.694625)
			(xy 81.951968 -240.662438) (xy 81.91822 -240.624344) (xy 81.891019 -240.58133) (xy 81.871071 -240.53451)
			(xy 81.858892 -240.485096) (xy 81.854797 -240.434368) (xy 81.5467 -240.434368) (xy 81.546188 -240.459814)
			(xy 81.538024 -240.510048) (xy 81.521908 -240.558322) (xy 81.498257 -240.603385) (xy 81.467684 -240.644071)
			(xy 81.43098 -240.679326) (xy 81.389096 -240.708236) (xy 81.343117 -240.730053) (xy 81.294233 -240.744213)
			(xy 81.243712 -240.750347) (xy 81.19286 -240.748298) (xy 81.142996 -240.738118) (xy 81.09541 -240.720071)
			(xy 81.051336 -240.694625) (xy 81.011914 -240.662438) (xy 80.978166 -240.624344) (xy 80.950965 -240.58133)
			(xy 80.931017 -240.53451) (xy 80.918838 -240.485096) (xy 80.914743 -240.434368) (xy 80.596486 -240.434368)
			(xy 80.595991 -240.458975) (xy 80.588096 -240.507552) (xy 80.572512 -240.554233) (xy 80.549641 -240.59781)
			(xy 80.520076 -240.637154) (xy 80.484583 -240.671246) (xy 80.44408 -240.699202) (xy 80.399618 -240.7203)
			(xy 80.352347 -240.733992) (xy 80.303492 -240.739924) (xy 80.254317 -240.737943) (xy 80.206098 -240.728099)
			(xy 80.160082 -240.710647) (xy 80.117461 -240.68604) (xy 80.07934 -240.654915) (xy 80.046705 -240.618078)
			(xy 80.020402 -240.576482) (xy 80.001111 -240.531206) (xy 79.989334 -240.483422) (xy 79.985374 -240.434368)
			(xy 78.716378 -240.434368) (xy 78.715883 -240.458975) (xy 78.707988 -240.507552) (xy 78.692404 -240.554233)
			(xy 78.669533 -240.59781) (xy 78.639968 -240.637154) (xy 78.604475 -240.671246) (xy 78.563972 -240.699202)
			(xy 78.51951 -240.7203) (xy 78.472239 -240.733992) (xy 78.423384 -240.739924) (xy 78.374209 -240.737943)
			(xy 78.32599 -240.728099) (xy 78.279974 -240.710647) (xy 78.237353 -240.68604) (xy 78.199232 -240.654915)
			(xy 78.166597 -240.618078) (xy 78.140294 -240.576482) (xy 78.121003 -240.531206) (xy 78.109226 -240.483422)
			(xy 78.105266 -240.434368) (xy 62.37732 -240.434368) (xy 62.37732 -241.510312) (xy 76.507098 -241.510312)
			(xy 76.511058 -241.461258) (xy 76.522835 -241.413474) (xy 76.542126 -241.368198) (xy 76.568429 -241.326602)
			(xy 76.601064 -241.289765) (xy 76.639185 -241.25864) (xy 76.681806 -241.234033) (xy 76.727822 -241.216581)
			(xy 76.776041 -241.206737) (xy 76.825216 -241.204756) (xy 76.874071 -241.210688) (xy 76.921342 -241.22438)
			(xy 76.963477 -241.244374) (xy 79.51522 -241.244374) (xy 79.51918 -241.19532) (xy 79.530957 -241.147536)
			(xy 79.550248 -241.10226) (xy 79.576551 -241.060664) (xy 79.609186 -241.023827) (xy 79.647307 -240.992702)
			(xy 79.689928 -240.968095) (xy 79.735944 -240.950643) (xy 79.784163 -240.940799) (xy 79.833338 -240.938818)
			(xy 79.882193 -240.94475) (xy 79.929464 -240.958442) (xy 79.973926 -240.97954) (xy 80.014429 -241.007496)
			(xy 80.049922 -241.041588) (xy 80.079487 -241.080932) (xy 80.102358 -241.124509) (xy 80.117942 -241.17119)
			(xy 80.125837 -241.219767) (xy 80.126332 -241.244374) (xy 80.444843 -241.244374) (xy 80.448938 -241.193646)
			(xy 80.461117 -241.144232) (xy 80.481065 -241.097412) (xy 80.508266 -241.054398) (xy 80.542014 -241.016304)
			(xy 80.581436 -240.984117) (xy 80.62551 -240.958671) (xy 80.673096 -240.940624) (xy 80.72296 -240.930444)
			(xy 80.773812 -240.928395) (xy 80.824333 -240.934529) (xy 80.873217 -240.948689) (xy 80.919196 -240.970506)
			(xy 80.96108 -240.999416) (xy 80.997784 -241.034671) (xy 81.028357 -241.075357) (xy 81.052008 -241.12042)
			(xy 81.068124 -241.168694) (xy 81.076288 -241.218928) (xy 81.0768 -241.244374) (xy 81.395328 -241.244374)
			(xy 81.399288 -241.19532) (xy 81.411065 -241.147536) (xy 81.430356 -241.10226) (xy 81.456659 -241.060664)
			(xy 81.489294 -241.023827) (xy 81.527415 -240.992702) (xy 81.570036 -240.968095) (xy 81.616052 -240.950643)
			(xy 81.664271 -240.940799) (xy 81.713446 -240.938818) (xy 81.762301 -240.94475) (xy 81.809572 -240.958442)
			(xy 81.854034 -240.97954) (xy 81.894537 -241.007496) (xy 81.93003 -241.041588) (xy 81.959595 -241.080932)
			(xy 81.982466 -241.124509) (xy 81.99805 -241.17119) (xy 82.005945 -241.219767) (xy 82.00644 -241.244374)
			(xy 82.324697 -241.244374) (xy 82.328792 -241.193646) (xy 82.340971 -241.144232) (xy 82.360919 -241.097412)
			(xy 82.38812 -241.054398) (xy 82.421868 -241.016304) (xy 82.46129 -240.984117) (xy 82.505364 -240.958671)
			(xy 82.55295 -240.940624) (xy 82.602814 -240.930444) (xy 82.653666 -240.928395) (xy 82.704187 -240.934529)
			(xy 82.753071 -240.948689) (xy 82.79905 -240.970506) (xy 82.840934 -240.999416) (xy 82.877638 -241.034671)
			(xy 82.908211 -241.075357) (xy 82.931862 -241.12042) (xy 82.947978 -241.168694) (xy 82.956142 -241.218928)
			(xy 82.956654 -241.244374) (xy 83.275182 -241.244374) (xy 83.279142 -241.19532) (xy 83.290919 -241.147536)
			(xy 83.31021 -241.10226) (xy 83.336513 -241.060664) (xy 83.369148 -241.023827) (xy 83.407269 -240.992702)
			(xy 83.44989 -240.968095) (xy 83.495906 -240.950643) (xy 83.544125 -240.940799) (xy 83.5933 -240.938818)
			(xy 83.642155 -240.94475) (xy 83.689426 -240.958442) (xy 83.733888 -240.97954) (xy 83.774391 -241.007496)
			(xy 83.809884 -241.041588) (xy 83.839449 -241.080932) (xy 83.86232 -241.124509) (xy 83.877904 -241.17119)
			(xy 83.885799 -241.219767) (xy 83.886294 -241.244374) (xy 84.204805 -241.244374) (xy 84.2089 -241.193646)
			(xy 84.221079 -241.144232) (xy 84.241027 -241.097412) (xy 84.268228 -241.054398) (xy 84.301976 -241.016304)
			(xy 84.341398 -240.984117) (xy 84.385472 -240.958671) (xy 84.433058 -240.940624) (xy 84.482922 -240.930444)
			(xy 84.533774 -240.928395) (xy 84.584295 -240.934529) (xy 84.633179 -240.948689) (xy 84.679158 -240.970506)
			(xy 84.721042 -240.999416) (xy 84.757746 -241.034671) (xy 84.788319 -241.075357) (xy 84.81197 -241.12042)
			(xy 84.828086 -241.168694) (xy 84.83625 -241.218928) (xy 84.836762 -241.244374) (xy 85.144859 -241.244374)
			(xy 85.148954 -241.193646) (xy 85.161133 -241.144232) (xy 85.181081 -241.097412) (xy 85.208282 -241.054398)
			(xy 85.24203 -241.016304) (xy 85.281452 -240.984117) (xy 85.325526 -240.958671) (xy 85.373112 -240.940624)
			(xy 85.422976 -240.930444) (xy 85.473828 -240.928395) (xy 85.524349 -240.934529) (xy 85.573233 -240.948689)
			(xy 85.619212 -240.970506) (xy 85.661096 -240.999416) (xy 85.6978 -241.034671) (xy 85.728373 -241.075357)
			(xy 85.752024 -241.12042) (xy 85.76814 -241.168694) (xy 85.776304 -241.218928) (xy 85.776816 -241.244374)
			(xy 86.095344 -241.244374) (xy 86.099304 -241.19532) (xy 86.111081 -241.147536) (xy 86.130372 -241.10226)
			(xy 86.156675 -241.060664) (xy 86.18931 -241.023827) (xy 86.227431 -240.992702) (xy 86.270052 -240.968095)
			(xy 86.316068 -240.950643) (xy 86.364287 -240.940799) (xy 86.413462 -240.938818) (xy 86.462317 -240.94475)
			(xy 86.509588 -240.958442) (xy 86.55405 -240.97954) (xy 86.594553 -241.007496) (xy 86.630046 -241.041588)
			(xy 86.659611 -241.080932) (xy 86.682482 -241.124509) (xy 86.698066 -241.17119) (xy 86.705961 -241.219767)
			(xy 86.706456 -241.244374) (xy 87.024713 -241.244374) (xy 87.028808 -241.193646) (xy 87.040987 -241.144232)
			(xy 87.060935 -241.097412) (xy 87.088136 -241.054398) (xy 87.121884 -241.016304) (xy 87.161306 -240.984117)
			(xy 87.20538 -240.958671) (xy 87.252966 -240.940624) (xy 87.30283 -240.930444) (xy 87.353682 -240.928395)
			(xy 87.404203 -240.934529) (xy 87.453087 -240.948689) (xy 87.499066 -240.970506) (xy 87.54095 -240.999416)
			(xy 87.577654 -241.034671) (xy 87.608227 -241.075357) (xy 87.631878 -241.12042) (xy 87.647994 -241.168694)
			(xy 87.656158 -241.218928) (xy 87.65667 -241.244374) (xy 87.975198 -241.244374) (xy 87.979158 -241.19532)
			(xy 87.990935 -241.147536) (xy 88.010226 -241.10226) (xy 88.036529 -241.060664) (xy 88.069164 -241.023827)
			(xy 88.107285 -240.992702) (xy 88.149906 -240.968095) (xy 88.195922 -240.950643) (xy 88.244141 -240.940799)
			(xy 88.293316 -240.938818) (xy 88.342171 -240.94475) (xy 88.389442 -240.958442) (xy 88.433904 -240.97954)
			(xy 88.474407 -241.007496) (xy 88.5099 -241.041588) (xy 88.539465 -241.080932) (xy 88.562336 -241.124509)
			(xy 88.57792 -241.17119) (xy 88.585815 -241.219767) (xy 88.58631 -241.244374) (xy 88.904821 -241.244374)
			(xy 88.908916 -241.193646) (xy 88.921095 -241.144232) (xy 88.941043 -241.097412) (xy 88.968244 -241.054398)
			(xy 89.001992 -241.016304) (xy 89.041414 -240.984117) (xy 89.085488 -240.958671) (xy 89.133074 -240.940624)
			(xy 89.182938 -240.930444) (xy 89.23379 -240.928395) (xy 89.284311 -240.934529) (xy 89.333195 -240.948689)
			(xy 89.379174 -240.970506) (xy 89.421058 -240.999416) (xy 89.457762 -241.034671) (xy 89.488335 -241.075357)
			(xy 89.511986 -241.12042) (xy 89.528102 -241.168694) (xy 89.536266 -241.218928) (xy 89.536778 -241.244374)
			(xy 89.855306 -241.244374) (xy 89.859266 -241.19532) (xy 89.871043 -241.147536) (xy 89.890334 -241.10226)
			(xy 89.916637 -241.060664) (xy 89.949272 -241.023827) (xy 89.987393 -240.992702) (xy 90.030014 -240.968095)
			(xy 90.07603 -240.950643) (xy 90.124249 -240.940799) (xy 90.173424 -240.938818) (xy 90.222279 -240.94475)
			(xy 90.26955 -240.958442) (xy 90.314012 -240.97954) (xy 90.354515 -241.007496) (xy 90.390008 -241.041588)
			(xy 90.419573 -241.080932) (xy 90.442444 -241.124509) (xy 90.458028 -241.17119) (xy 90.465923 -241.219767)
			(xy 90.466418 -241.244374) (xy 90.784675 -241.244374) (xy 90.78877 -241.193646) (xy 90.800949 -241.144232)
			(xy 90.820897 -241.097412) (xy 90.848098 -241.054398) (xy 90.881846 -241.016304) (xy 90.921268 -240.984117)
			(xy 90.965342 -240.958671) (xy 91.012928 -240.940624) (xy 91.062792 -240.930444) (xy 91.113644 -240.928395)
			(xy 91.164165 -240.934529) (xy 91.213049 -240.948689) (xy 91.259028 -240.970506) (xy 91.300912 -240.999416)
			(xy 91.337616 -241.034671) (xy 91.368189 -241.075357) (xy 91.39184 -241.12042) (xy 91.407956 -241.168694)
			(xy 91.41612 -241.218928) (xy 91.416632 -241.244374) (xy 91.724729 -241.244374) (xy 91.728824 -241.193646)
			(xy 91.741003 -241.144232) (xy 91.760951 -241.097412) (xy 91.788152 -241.054398) (xy 91.8219 -241.016304)
			(xy 91.861322 -240.984117) (xy 91.905396 -240.958671) (xy 91.952982 -240.940624) (xy 92.002846 -240.930444)
			(xy 92.053698 -240.928395) (xy 92.104219 -240.934529) (xy 92.153103 -240.948689) (xy 92.199082 -240.970506)
			(xy 92.240966 -240.999416) (xy 92.27767 -241.034671) (xy 92.308243 -241.075357) (xy 92.331894 -241.12042)
			(xy 92.34801 -241.168694) (xy 92.356174 -241.218928) (xy 92.356686 -241.244374) (xy 92.675214 -241.244374)
			(xy 92.679174 -241.19532) (xy 92.690951 -241.147536) (xy 92.710242 -241.10226) (xy 92.736545 -241.060664)
			(xy 92.76918 -241.023827) (xy 92.807301 -240.992702) (xy 92.849922 -240.968095) (xy 92.895938 -240.950643)
			(xy 92.944157 -240.940799) (xy 92.993332 -240.938818) (xy 93.042187 -240.94475) (xy 93.089458 -240.958442)
			(xy 93.13392 -240.97954) (xy 93.174423 -241.007496) (xy 93.209916 -241.041588) (xy 93.239481 -241.080932)
			(xy 93.262352 -241.124509) (xy 93.277936 -241.17119) (xy 93.285831 -241.219767) (xy 93.286326 -241.244374)
			(xy 93.604837 -241.244374) (xy 93.608932 -241.193646) (xy 93.621111 -241.144232) (xy 93.641059 -241.097412)
			(xy 93.66826 -241.054398) (xy 93.702008 -241.016304) (xy 93.74143 -240.984117) (xy 93.785504 -240.958671)
			(xy 93.83309 -240.940624) (xy 93.882954 -240.930444) (xy 93.933806 -240.928395) (xy 93.984327 -240.934529)
			(xy 94.033211 -240.948689) (xy 94.07919 -240.970506) (xy 94.121074 -240.999416) (xy 94.157778 -241.034671)
			(xy 94.188351 -241.075357) (xy 94.212002 -241.12042) (xy 94.228118 -241.168694) (xy 94.236282 -241.218928)
			(xy 94.236794 -241.244374) (xy 94.555322 -241.244374) (xy 94.559282 -241.19532) (xy 94.571059 -241.147536)
			(xy 94.59035 -241.10226) (xy 94.616653 -241.060664) (xy 94.649288 -241.023827) (xy 94.687409 -240.992702)
			(xy 94.73003 -240.968095) (xy 94.776046 -240.950643) (xy 94.824265 -240.940799) (xy 94.87344 -240.938818)
			(xy 94.922295 -240.94475) (xy 94.969566 -240.958442) (xy 95.014028 -240.97954) (xy 95.054531 -241.007496)
			(xy 95.090024 -241.041588) (xy 95.119589 -241.080932) (xy 95.14246 -241.124509) (xy 95.158044 -241.17119)
			(xy 95.165939 -241.219767) (xy 95.166434 -241.244374) (xy 95.484691 -241.244374) (xy 95.488786 -241.193646)
			(xy 95.500965 -241.144232) (xy 95.520913 -241.097412) (xy 95.548114 -241.054398) (xy 95.581862 -241.016304)
			(xy 95.621284 -240.984117) (xy 95.665358 -240.958671) (xy 95.712944 -240.940624) (xy 95.762808 -240.930444)
			(xy 95.81366 -240.928395) (xy 95.864181 -240.934529) (xy 95.913065 -240.948689) (xy 95.959044 -240.970506)
			(xy 96.000928 -240.999416) (xy 96.037632 -241.034671) (xy 96.068205 -241.075357) (xy 96.091856 -241.12042)
			(xy 96.107972 -241.168694) (xy 96.116136 -241.218928) (xy 96.116648 -241.244374) (xy 96.435176 -241.244374)
			(xy 96.439136 -241.19532) (xy 96.450913 -241.147536) (xy 96.470204 -241.10226) (xy 96.496507 -241.060664)
			(xy 96.529142 -241.023827) (xy 96.567263 -240.992702) (xy 96.609884 -240.968095) (xy 96.6559 -240.950643)
			(xy 96.704119 -240.940799) (xy 96.753294 -240.938818) (xy 96.802149 -240.94475) (xy 96.84942 -240.958442)
			(xy 96.893882 -240.97954) (xy 96.934385 -241.007496) (xy 96.969878 -241.041588) (xy 96.999443 -241.080932)
			(xy 97.022314 -241.124509) (xy 97.037898 -241.17119) (xy 97.045793 -241.219767) (xy 97.046288 -241.244374)
			(xy 97.364799 -241.244374) (xy 97.368894 -241.193646) (xy 97.381073 -241.144232) (xy 97.401021 -241.097412)
			(xy 97.428222 -241.054398) (xy 97.46197 -241.016304) (xy 97.501392 -240.984117) (xy 97.545466 -240.958671)
			(xy 97.593052 -240.940624) (xy 97.642916 -240.930444) (xy 97.693768 -240.928395) (xy 97.744289 -240.934529)
			(xy 97.793173 -240.948689) (xy 97.839152 -240.970506) (xy 97.881036 -240.999416) (xy 97.91774 -241.034671)
			(xy 97.948313 -241.075357) (xy 97.971964 -241.12042) (xy 97.98808 -241.168694) (xy 97.996244 -241.218928)
			(xy 97.996756 -241.244374) (xy 98.304853 -241.244374) (xy 98.308948 -241.193646) (xy 98.321127 -241.144232)
			(xy 98.341075 -241.097412) (xy 98.368276 -241.054398) (xy 98.402024 -241.016304) (xy 98.441446 -240.984117)
			(xy 98.48552 -240.958671) (xy 98.533106 -240.940624) (xy 98.58297 -240.930444) (xy 98.633822 -240.928395)
			(xy 98.684343 -240.934529) (xy 98.733227 -240.948689) (xy 98.779206 -240.970506) (xy 98.82109 -240.999416)
			(xy 98.857794 -241.034671) (xy 98.888367 -241.075357) (xy 98.912018 -241.12042) (xy 98.928134 -241.168694)
			(xy 98.936298 -241.218928) (xy 98.93681 -241.244374) (xy 99.255338 -241.244374) (xy 99.259298 -241.19532)
			(xy 99.271075 -241.147536) (xy 99.290366 -241.10226) (xy 99.316669 -241.060664) (xy 99.349304 -241.023827)
			(xy 99.387425 -240.992702) (xy 99.430046 -240.968095) (xy 99.476062 -240.950643) (xy 99.524281 -240.940799)
			(xy 99.573456 -240.938818) (xy 99.622311 -240.94475) (xy 99.669582 -240.958442) (xy 99.714044 -240.97954)
			(xy 99.754547 -241.007496) (xy 99.79004 -241.041588) (xy 99.819605 -241.080932) (xy 99.842476 -241.124509)
			(xy 99.85806 -241.17119) (xy 99.865955 -241.219767) (xy 99.86645 -241.244374) (xy 100.184707 -241.244374)
			(xy 100.188802 -241.193646) (xy 100.200981 -241.144232) (xy 100.220929 -241.097412) (xy 100.24813 -241.054398)
			(xy 100.281878 -241.016304) (xy 100.3213 -240.984117) (xy 100.365374 -240.958671) (xy 100.41296 -240.940624)
			(xy 100.462824 -240.930444) (xy 100.513676 -240.928395) (xy 100.564197 -240.934529) (xy 100.613081 -240.948689)
			(xy 100.65906 -240.970506) (xy 100.700944 -240.999416) (xy 100.737648 -241.034671) (xy 100.768221 -241.075357)
			(xy 100.791872 -241.12042) (xy 100.807988 -241.168694) (xy 100.816152 -241.218928) (xy 100.816664 -241.244374)
			(xy 101.124761 -241.244374) (xy 101.128856 -241.193646) (xy 101.141035 -241.144232) (xy 101.160983 -241.097412)
			(xy 101.188184 -241.054398) (xy 101.221932 -241.016304) (xy 101.261354 -240.984117) (xy 101.305428 -240.958671)
			(xy 101.353014 -240.940624) (xy 101.402878 -240.930444) (xy 101.45373 -240.928395) (xy 101.504251 -240.934529)
			(xy 101.553135 -240.948689) (xy 101.599114 -240.970506) (xy 101.640998 -240.999416) (xy 101.677702 -241.034671)
			(xy 101.708275 -241.075357) (xy 101.731926 -241.12042) (xy 101.748042 -241.168694) (xy 101.756206 -241.218928)
			(xy 101.756718 -241.244374) (xy 102.075246 -241.244374) (xy 102.079206 -241.19532) (xy 102.090983 -241.147536)
			(xy 102.110274 -241.10226) (xy 102.136577 -241.060664) (xy 102.169212 -241.023827) (xy 102.207333 -240.992702)
			(xy 102.249954 -240.968095) (xy 102.29597 -240.950643) (xy 102.344189 -240.940799) (xy 102.393364 -240.938818)
			(xy 102.442219 -240.94475) (xy 102.48949 -240.958442) (xy 102.533952 -240.97954) (xy 102.574455 -241.007496)
			(xy 102.609948 -241.041588) (xy 102.639513 -241.080932) (xy 102.662384 -241.124509) (xy 102.677968 -241.17119)
			(xy 102.685863 -241.219767) (xy 102.686358 -241.244374) (xy 103.004869 -241.244374) (xy 103.008964 -241.193646)
			(xy 103.021143 -241.144232) (xy 103.041091 -241.097412) (xy 103.068292 -241.054398) (xy 103.10204 -241.016304)
			(xy 103.141462 -240.984117) (xy 103.185536 -240.958671) (xy 103.233122 -240.940624) (xy 103.282986 -240.930444)
			(xy 103.333838 -240.928395) (xy 103.384359 -240.934529) (xy 103.433243 -240.948689) (xy 103.479222 -240.970506)
			(xy 103.521106 -240.999416) (xy 103.55781 -241.034671) (xy 103.588383 -241.075357) (xy 103.612034 -241.12042)
			(xy 103.62815 -241.168694) (xy 103.636314 -241.218928) (xy 103.636826 -241.244374) (xy 103.944923 -241.244374)
			(xy 103.949018 -241.193646) (xy 103.961197 -241.144232) (xy 103.981145 -241.097412) (xy 104.008346 -241.054398)
			(xy 104.042094 -241.016304) (xy 104.081516 -240.984117) (xy 104.12559 -240.958671) (xy 104.173176 -240.940624)
			(xy 104.22304 -240.930444) (xy 104.273892 -240.928395) (xy 104.324413 -240.934529) (xy 104.373297 -240.948689)
			(xy 104.419276 -240.970506) (xy 104.46116 -240.999416) (xy 104.497864 -241.034671) (xy 104.528437 -241.075357)
			(xy 104.552088 -241.12042) (xy 104.568204 -241.168694) (xy 104.576368 -241.218928) (xy 104.57688 -241.244374)
			(xy 104.895154 -241.244374) (xy 104.899114 -241.19532) (xy 104.910891 -241.147536) (xy 104.930182 -241.10226)
			(xy 104.956485 -241.060664) (xy 104.98912 -241.023827) (xy 105.027241 -240.992702) (xy 105.069862 -240.968095)
			(xy 105.115878 -240.950643) (xy 105.164097 -240.940799) (xy 105.213272 -240.938818) (xy 105.262127 -240.94475)
			(xy 105.309398 -240.958442) (xy 105.35386 -240.97954) (xy 105.394363 -241.007496) (xy 105.429856 -241.041588)
			(xy 105.459421 -241.080932) (xy 105.482292 -241.124509) (xy 105.497876 -241.17119) (xy 105.505771 -241.219767)
			(xy 105.506266 -241.244374) (xy 105.824777 -241.244374) (xy 105.828872 -241.193646) (xy 105.841051 -241.144232)
			(xy 105.860999 -241.097412) (xy 105.8882 -241.054398) (xy 105.921948 -241.016304) (xy 105.96137 -240.984117)
			(xy 106.005444 -240.958671) (xy 106.05303 -240.940624) (xy 106.102894 -240.930444) (xy 106.153746 -240.928395)
			(xy 106.204267 -240.934529) (xy 106.253151 -240.948689) (xy 106.29913 -240.970506) (xy 106.341014 -240.999416)
			(xy 106.377718 -241.034671) (xy 106.408291 -241.075357) (xy 106.431942 -241.12042) (xy 106.448058 -241.168694)
			(xy 106.456222 -241.218928) (xy 106.456734 -241.244374) (xy 106.764831 -241.244374) (xy 106.768926 -241.193646)
			(xy 106.781105 -241.144232) (xy 106.801053 -241.097412) (xy 106.828254 -241.054398) (xy 106.862002 -241.016304)
			(xy 106.901424 -240.984117) (xy 106.945498 -240.958671) (xy 106.993084 -240.940624) (xy 107.042948 -240.930444)
			(xy 107.0938 -240.928395) (xy 107.144321 -240.934529) (xy 107.193205 -240.948689) (xy 107.239184 -240.970506)
			(xy 107.281068 -240.999416) (xy 107.317772 -241.034671) (xy 107.348345 -241.075357) (xy 107.371996 -241.12042)
			(xy 107.388112 -241.168694) (xy 107.396276 -241.218928) (xy 107.396788 -241.244374) (xy 107.715316 -241.244374)
			(xy 107.719276 -241.19532) (xy 107.731053 -241.147536) (xy 107.750344 -241.10226) (xy 107.776647 -241.060664)
			(xy 107.809282 -241.023827) (xy 107.847403 -240.992702) (xy 107.890024 -240.968095) (xy 107.93604 -240.950643)
			(xy 107.984259 -240.940799) (xy 108.033434 -240.938818) (xy 108.082289 -240.94475) (xy 108.12956 -240.958442)
			(xy 108.174022 -240.97954) (xy 108.214525 -241.007496) (xy 108.250018 -241.041588) (xy 108.279583 -241.080932)
			(xy 108.302454 -241.124509) (xy 108.318038 -241.17119) (xy 108.325933 -241.219767) (xy 108.326428 -241.244374)
			(xy 108.65537 -241.244374) (xy 108.65933 -241.19532) (xy 108.671107 -241.147536) (xy 108.690398 -241.10226)
			(xy 108.716701 -241.060664) (xy 108.749336 -241.023827) (xy 108.787457 -240.992702) (xy 108.830078 -240.968095)
			(xy 108.876094 -240.950643) (xy 108.924313 -240.940799) (xy 108.973488 -240.938818) (xy 109.022343 -240.94475)
			(xy 109.069614 -240.958442) (xy 109.114076 -240.97954) (xy 109.154579 -241.007496) (xy 109.190072 -241.041588)
			(xy 109.219637 -241.080932) (xy 109.242508 -241.124509) (xy 109.258092 -241.17119) (xy 109.265987 -241.219767)
			(xy 109.266482 -241.244374) (xy 109.59517 -241.244374) (xy 109.59913 -241.19532) (xy 109.610907 -241.147536)
			(xy 109.630198 -241.10226) (xy 109.656501 -241.060664) (xy 109.689136 -241.023827) (xy 109.727257 -240.992702)
			(xy 109.769878 -240.968095) (xy 109.815894 -240.950643) (xy 109.864113 -240.940799) (xy 109.913288 -240.938818)
			(xy 109.962143 -240.94475) (xy 110.009414 -240.958442) (xy 110.053876 -240.97954) (xy 110.094379 -241.007496)
			(xy 110.129872 -241.041588) (xy 110.159437 -241.080932) (xy 110.182308 -241.124509) (xy 110.197892 -241.17119)
			(xy 110.205787 -241.219767) (xy 110.206282 -241.244374) (xy 110.205787 -241.268981) (xy 110.197892 -241.317558)
			(xy 110.182308 -241.364239) (xy 110.159437 -241.407816) (xy 110.129872 -241.44716) (xy 110.094379 -241.481252)
			(xy 110.053876 -241.509208) (xy 110.009414 -241.530306) (xy 109.962143 -241.543998) (xy 109.913288 -241.54993)
			(xy 109.864113 -241.547949) (xy 109.815894 -241.538105) (xy 109.769878 -241.520653) (xy 109.727257 -241.496046)
			(xy 109.689136 -241.464921) (xy 109.656501 -241.428084) (xy 109.630198 -241.386488) (xy 109.610907 -241.341212)
			(xy 109.59913 -241.293428) (xy 109.59517 -241.244374) (xy 109.266482 -241.244374) (xy 109.265987 -241.268981)
			(xy 109.258092 -241.317558) (xy 109.242508 -241.364239) (xy 109.219637 -241.407816) (xy 109.190072 -241.44716)
			(xy 109.154579 -241.481252) (xy 109.114076 -241.509208) (xy 109.069614 -241.530306) (xy 109.022343 -241.543998)
			(xy 108.973488 -241.54993) (xy 108.924313 -241.547949) (xy 108.876094 -241.538105) (xy 108.830078 -241.520653)
			(xy 108.787457 -241.496046) (xy 108.749336 -241.464921) (xy 108.716701 -241.428084) (xy 108.690398 -241.386488)
			(xy 108.671107 -241.341212) (xy 108.65933 -241.293428) (xy 108.65537 -241.244374) (xy 108.326428 -241.244374)
			(xy 108.325933 -241.268981) (xy 108.318038 -241.317558) (xy 108.302454 -241.364239) (xy 108.279583 -241.407816)
			(xy 108.250018 -241.44716) (xy 108.214525 -241.481252) (xy 108.174022 -241.509208) (xy 108.12956 -241.530306)
			(xy 108.082289 -241.543998) (xy 108.033434 -241.54993) (xy 107.984259 -241.547949) (xy 107.93604 -241.538105)
			(xy 107.890024 -241.520653) (xy 107.847403 -241.496046) (xy 107.809282 -241.464921) (xy 107.776647 -241.428084)
			(xy 107.750344 -241.386488) (xy 107.731053 -241.341212) (xy 107.719276 -241.293428) (xy 107.715316 -241.244374)
			(xy 107.396788 -241.244374) (xy 107.396276 -241.26982) (xy 107.388112 -241.320054) (xy 107.371996 -241.368328)
			(xy 107.348345 -241.413391) (xy 107.317772 -241.454077) (xy 107.281068 -241.489332) (xy 107.239184 -241.518242)
			(xy 107.193205 -241.540059) (xy 107.144321 -241.554219) (xy 107.0938 -241.560353) (xy 107.042948 -241.558304)
			(xy 106.993084 -241.548124) (xy 106.945498 -241.530077) (xy 106.901424 -241.504631) (xy 106.862002 -241.472444)
			(xy 106.828254 -241.43435) (xy 106.801053 -241.391336) (xy 106.781105 -241.344516) (xy 106.768926 -241.295102)
			(xy 106.764831 -241.244374) (xy 106.456734 -241.244374) (xy 106.456222 -241.26982) (xy 106.448058 -241.320054)
			(xy 106.431942 -241.368328) (xy 106.408291 -241.413391) (xy 106.377718 -241.454077) (xy 106.341014 -241.489332)
			(xy 106.29913 -241.518242) (xy 106.253151 -241.540059) (xy 106.204267 -241.554219) (xy 106.153746 -241.560353)
			(xy 106.102894 -241.558304) (xy 106.05303 -241.548124) (xy 106.005444 -241.530077) (xy 105.96137 -241.504631)
			(xy 105.921948 -241.472444) (xy 105.8882 -241.43435) (xy 105.860999 -241.391336) (xy 105.841051 -241.344516)
			(xy 105.828872 -241.295102) (xy 105.824777 -241.244374) (xy 105.506266 -241.244374) (xy 105.505771 -241.268981)
			(xy 105.497876 -241.317558) (xy 105.482292 -241.364239) (xy 105.459421 -241.407816) (xy 105.429856 -241.44716)
			(xy 105.394363 -241.481252) (xy 105.35386 -241.509208) (xy 105.309398 -241.530306) (xy 105.262127 -241.543998)
			(xy 105.213272 -241.54993) (xy 105.164097 -241.547949) (xy 105.115878 -241.538105) (xy 105.069862 -241.520653)
			(xy 105.027241 -241.496046) (xy 104.98912 -241.464921) (xy 104.956485 -241.428084) (xy 104.930182 -241.386488)
			(xy 104.910891 -241.341212) (xy 104.899114 -241.293428) (xy 104.895154 -241.244374) (xy 104.57688 -241.244374)
			(xy 104.576368 -241.26982) (xy 104.568204 -241.320054) (xy 104.552088 -241.368328) (xy 104.528437 -241.413391)
			(xy 104.497864 -241.454077) (xy 104.46116 -241.489332) (xy 104.419276 -241.518242) (xy 104.373297 -241.540059)
			(xy 104.324413 -241.554219) (xy 104.273892 -241.560353) (xy 104.22304 -241.558304) (xy 104.173176 -241.548124)
			(xy 104.12559 -241.530077) (xy 104.081516 -241.504631) (xy 104.042094 -241.472444) (xy 104.008346 -241.43435)
			(xy 103.981145 -241.391336) (xy 103.961197 -241.344516) (xy 103.949018 -241.295102) (xy 103.944923 -241.244374)
			(xy 103.636826 -241.244374) (xy 103.636314 -241.26982) (xy 103.62815 -241.320054) (xy 103.612034 -241.368328)
			(xy 103.588383 -241.413391) (xy 103.55781 -241.454077) (xy 103.521106 -241.489332) (xy 103.479222 -241.518242)
			(xy 103.433243 -241.540059) (xy 103.384359 -241.554219) (xy 103.333838 -241.560353) (xy 103.282986 -241.558304)
			(xy 103.233122 -241.548124) (xy 103.185536 -241.530077) (xy 103.141462 -241.504631) (xy 103.10204 -241.472444)
			(xy 103.068292 -241.43435) (xy 103.041091 -241.391336) (xy 103.021143 -241.344516) (xy 103.008964 -241.295102)
			(xy 103.004869 -241.244374) (xy 102.686358 -241.244374) (xy 102.685863 -241.268981) (xy 102.677968 -241.317558)
			(xy 102.662384 -241.364239) (xy 102.639513 -241.407816) (xy 102.609948 -241.44716) (xy 102.574455 -241.481252)
			(xy 102.533952 -241.509208) (xy 102.48949 -241.530306) (xy 102.442219 -241.543998) (xy 102.393364 -241.54993)
			(xy 102.344189 -241.547949) (xy 102.29597 -241.538105) (xy 102.249954 -241.520653) (xy 102.207333 -241.496046)
			(xy 102.169212 -241.464921) (xy 102.136577 -241.428084) (xy 102.110274 -241.386488) (xy 102.090983 -241.341212)
			(xy 102.079206 -241.293428) (xy 102.075246 -241.244374) (xy 101.756718 -241.244374) (xy 101.756206 -241.26982)
			(xy 101.748042 -241.320054) (xy 101.731926 -241.368328) (xy 101.708275 -241.413391) (xy 101.677702 -241.454077)
			(xy 101.640998 -241.489332) (xy 101.599114 -241.518242) (xy 101.553135 -241.540059) (xy 101.504251 -241.554219)
			(xy 101.45373 -241.560353) (xy 101.402878 -241.558304) (xy 101.353014 -241.548124) (xy 101.305428 -241.530077)
			(xy 101.261354 -241.504631) (xy 101.221932 -241.472444) (xy 101.188184 -241.43435) (xy 101.160983 -241.391336)
			(xy 101.141035 -241.344516) (xy 101.128856 -241.295102) (xy 101.124761 -241.244374) (xy 100.816664 -241.244374)
			(xy 100.816152 -241.26982) (xy 100.807988 -241.320054) (xy 100.791872 -241.368328) (xy 100.768221 -241.413391)
			(xy 100.737648 -241.454077) (xy 100.700944 -241.489332) (xy 100.65906 -241.518242) (xy 100.613081 -241.540059)
			(xy 100.564197 -241.554219) (xy 100.513676 -241.560353) (xy 100.462824 -241.558304) (xy 100.41296 -241.548124)
			(xy 100.365374 -241.530077) (xy 100.3213 -241.504631) (xy 100.281878 -241.472444) (xy 100.24813 -241.43435)
			(xy 100.220929 -241.391336) (xy 100.200981 -241.344516) (xy 100.188802 -241.295102) (xy 100.184707 -241.244374)
			(xy 99.86645 -241.244374) (xy 99.865955 -241.268981) (xy 99.85806 -241.317558) (xy 99.842476 -241.364239)
			(xy 99.819605 -241.407816) (xy 99.79004 -241.44716) (xy 99.754547 -241.481252) (xy 99.714044 -241.509208)
			(xy 99.669582 -241.530306) (xy 99.622311 -241.543998) (xy 99.573456 -241.54993) (xy 99.524281 -241.547949)
			(xy 99.476062 -241.538105) (xy 99.430046 -241.520653) (xy 99.387425 -241.496046) (xy 99.349304 -241.464921)
			(xy 99.316669 -241.428084) (xy 99.290366 -241.386488) (xy 99.271075 -241.341212) (xy 99.259298 -241.293428)
			(xy 99.255338 -241.244374) (xy 98.93681 -241.244374) (xy 98.936298 -241.26982) (xy 98.928134 -241.320054)
			(xy 98.912018 -241.368328) (xy 98.888367 -241.413391) (xy 98.857794 -241.454077) (xy 98.82109 -241.489332)
			(xy 98.779206 -241.518242) (xy 98.733227 -241.540059) (xy 98.684343 -241.554219) (xy 98.633822 -241.560353)
			(xy 98.58297 -241.558304) (xy 98.533106 -241.548124) (xy 98.48552 -241.530077) (xy 98.441446 -241.504631)
			(xy 98.402024 -241.472444) (xy 98.368276 -241.43435) (xy 98.341075 -241.391336) (xy 98.321127 -241.344516)
			(xy 98.308948 -241.295102) (xy 98.304853 -241.244374) (xy 97.996756 -241.244374) (xy 97.996244 -241.26982)
			(xy 97.98808 -241.320054) (xy 97.971964 -241.368328) (xy 97.948313 -241.413391) (xy 97.91774 -241.454077)
			(xy 97.881036 -241.489332) (xy 97.839152 -241.518242) (xy 97.793173 -241.540059) (xy 97.744289 -241.554219)
			(xy 97.693768 -241.560353) (xy 97.642916 -241.558304) (xy 97.593052 -241.548124) (xy 97.545466 -241.530077)
			(xy 97.501392 -241.504631) (xy 97.46197 -241.472444) (xy 97.428222 -241.43435) (xy 97.401021 -241.391336)
			(xy 97.381073 -241.344516) (xy 97.368894 -241.295102) (xy 97.364799 -241.244374) (xy 97.046288 -241.244374)
			(xy 97.045793 -241.268981) (xy 97.037898 -241.317558) (xy 97.022314 -241.364239) (xy 96.999443 -241.407816)
			(xy 96.969878 -241.44716) (xy 96.934385 -241.481252) (xy 96.893882 -241.509208) (xy 96.84942 -241.530306)
			(xy 96.802149 -241.543998) (xy 96.753294 -241.54993) (xy 96.704119 -241.547949) (xy 96.6559 -241.538105)
			(xy 96.609884 -241.520653) (xy 96.567263 -241.496046) (xy 96.529142 -241.464921) (xy 96.496507 -241.428084)
			(xy 96.470204 -241.386488) (xy 96.450913 -241.341212) (xy 96.439136 -241.293428) (xy 96.435176 -241.244374)
			(xy 96.116648 -241.244374) (xy 96.116136 -241.26982) (xy 96.107972 -241.320054) (xy 96.091856 -241.368328)
			(xy 96.068205 -241.413391) (xy 96.037632 -241.454077) (xy 96.000928 -241.489332) (xy 95.959044 -241.518242)
			(xy 95.913065 -241.540059) (xy 95.864181 -241.554219) (xy 95.81366 -241.560353) (xy 95.762808 -241.558304)
			(xy 95.712944 -241.548124) (xy 95.665358 -241.530077) (xy 95.621284 -241.504631) (xy 95.581862 -241.472444)
			(xy 95.548114 -241.43435) (xy 95.520913 -241.391336) (xy 95.500965 -241.344516) (xy 95.488786 -241.295102)
			(xy 95.484691 -241.244374) (xy 95.166434 -241.244374) (xy 95.165939 -241.268981) (xy 95.158044 -241.317558)
			(xy 95.14246 -241.364239) (xy 95.119589 -241.407816) (xy 95.090024 -241.44716) (xy 95.054531 -241.481252)
			(xy 95.014028 -241.509208) (xy 94.969566 -241.530306) (xy 94.922295 -241.543998) (xy 94.87344 -241.54993)
			(xy 94.824265 -241.547949) (xy 94.776046 -241.538105) (xy 94.73003 -241.520653) (xy 94.687409 -241.496046)
			(xy 94.649288 -241.464921) (xy 94.616653 -241.428084) (xy 94.59035 -241.386488) (xy 94.571059 -241.341212)
			(xy 94.559282 -241.293428) (xy 94.555322 -241.244374) (xy 94.236794 -241.244374) (xy 94.236282 -241.26982)
			(xy 94.228118 -241.320054) (xy 94.212002 -241.368328) (xy 94.188351 -241.413391) (xy 94.157778 -241.454077)
			(xy 94.121074 -241.489332) (xy 94.07919 -241.518242) (xy 94.033211 -241.540059) (xy 93.984327 -241.554219)
			(xy 93.933806 -241.560353) (xy 93.882954 -241.558304) (xy 93.83309 -241.548124) (xy 93.785504 -241.530077)
			(xy 93.74143 -241.504631) (xy 93.702008 -241.472444) (xy 93.66826 -241.43435) (xy 93.641059 -241.391336)
			(xy 93.621111 -241.344516) (xy 93.608932 -241.295102) (xy 93.604837 -241.244374) (xy 93.286326 -241.244374)
			(xy 93.285831 -241.268981) (xy 93.277936 -241.317558) (xy 93.262352 -241.364239) (xy 93.239481 -241.407816)
			(xy 93.209916 -241.44716) (xy 93.174423 -241.481252) (xy 93.13392 -241.509208) (xy 93.089458 -241.530306)
			(xy 93.042187 -241.543998) (xy 92.993332 -241.54993) (xy 92.944157 -241.547949) (xy 92.895938 -241.538105)
			(xy 92.849922 -241.520653) (xy 92.807301 -241.496046) (xy 92.76918 -241.464921) (xy 92.736545 -241.428084)
			(xy 92.710242 -241.386488) (xy 92.690951 -241.341212) (xy 92.679174 -241.293428) (xy 92.675214 -241.244374)
			(xy 92.356686 -241.244374) (xy 92.356174 -241.26982) (xy 92.34801 -241.320054) (xy 92.331894 -241.368328)
			(xy 92.308243 -241.413391) (xy 92.27767 -241.454077) (xy 92.240966 -241.489332) (xy 92.199082 -241.518242)
			(xy 92.153103 -241.540059) (xy 92.104219 -241.554219) (xy 92.053698 -241.560353) (xy 92.002846 -241.558304)
			(xy 91.952982 -241.548124) (xy 91.905396 -241.530077) (xy 91.861322 -241.504631) (xy 91.8219 -241.472444)
			(xy 91.788152 -241.43435) (xy 91.760951 -241.391336) (xy 91.741003 -241.344516) (xy 91.728824 -241.295102)
			(xy 91.724729 -241.244374) (xy 91.416632 -241.244374) (xy 91.41612 -241.26982) (xy 91.407956 -241.320054)
			(xy 91.39184 -241.368328) (xy 91.368189 -241.413391) (xy 91.337616 -241.454077) (xy 91.300912 -241.489332)
			(xy 91.259028 -241.518242) (xy 91.213049 -241.540059) (xy 91.164165 -241.554219) (xy 91.113644 -241.560353)
			(xy 91.062792 -241.558304) (xy 91.012928 -241.548124) (xy 90.965342 -241.530077) (xy 90.921268 -241.504631)
			(xy 90.881846 -241.472444) (xy 90.848098 -241.43435) (xy 90.820897 -241.391336) (xy 90.800949 -241.344516)
			(xy 90.78877 -241.295102) (xy 90.784675 -241.244374) (xy 90.466418 -241.244374) (xy 90.465923 -241.268981)
			(xy 90.458028 -241.317558) (xy 90.442444 -241.364239) (xy 90.419573 -241.407816) (xy 90.390008 -241.44716)
			(xy 90.354515 -241.481252) (xy 90.314012 -241.509208) (xy 90.26955 -241.530306) (xy 90.222279 -241.543998)
			(xy 90.173424 -241.54993) (xy 90.124249 -241.547949) (xy 90.07603 -241.538105) (xy 90.030014 -241.520653)
			(xy 89.987393 -241.496046) (xy 89.949272 -241.464921) (xy 89.916637 -241.428084) (xy 89.890334 -241.386488)
			(xy 89.871043 -241.341212) (xy 89.859266 -241.293428) (xy 89.855306 -241.244374) (xy 89.536778 -241.244374)
			(xy 89.536266 -241.26982) (xy 89.528102 -241.320054) (xy 89.511986 -241.368328) (xy 89.488335 -241.413391)
			(xy 89.457762 -241.454077) (xy 89.421058 -241.489332) (xy 89.379174 -241.518242) (xy 89.333195 -241.540059)
			(xy 89.284311 -241.554219) (xy 89.23379 -241.560353) (xy 89.182938 -241.558304) (xy 89.133074 -241.548124)
			(xy 89.085488 -241.530077) (xy 89.041414 -241.504631) (xy 89.001992 -241.472444) (xy 88.968244 -241.43435)
			(xy 88.941043 -241.391336) (xy 88.921095 -241.344516) (xy 88.908916 -241.295102) (xy 88.904821 -241.244374)
			(xy 88.58631 -241.244374) (xy 88.585815 -241.268981) (xy 88.57792 -241.317558) (xy 88.562336 -241.364239)
			(xy 88.539465 -241.407816) (xy 88.5099 -241.44716) (xy 88.474407 -241.481252) (xy 88.433904 -241.509208)
			(xy 88.389442 -241.530306) (xy 88.342171 -241.543998) (xy 88.293316 -241.54993) (xy 88.244141 -241.547949)
			(xy 88.195922 -241.538105) (xy 88.149906 -241.520653) (xy 88.107285 -241.496046) (xy 88.069164 -241.464921)
			(xy 88.036529 -241.428084) (xy 88.010226 -241.386488) (xy 87.990935 -241.341212) (xy 87.979158 -241.293428)
			(xy 87.975198 -241.244374) (xy 87.65667 -241.244374) (xy 87.656158 -241.26982) (xy 87.647994 -241.320054)
			(xy 87.631878 -241.368328) (xy 87.608227 -241.413391) (xy 87.577654 -241.454077) (xy 87.54095 -241.489332)
			(xy 87.499066 -241.518242) (xy 87.453087 -241.540059) (xy 87.404203 -241.554219) (xy 87.353682 -241.560353)
			(xy 87.30283 -241.558304) (xy 87.252966 -241.548124) (xy 87.20538 -241.530077) (xy 87.161306 -241.504631)
			(xy 87.121884 -241.472444) (xy 87.088136 -241.43435) (xy 87.060935 -241.391336) (xy 87.040987 -241.344516)
			(xy 87.028808 -241.295102) (xy 87.024713 -241.244374) (xy 86.706456 -241.244374) (xy 86.705961 -241.268981)
			(xy 86.698066 -241.317558) (xy 86.682482 -241.364239) (xy 86.659611 -241.407816) (xy 86.630046 -241.44716)
			(xy 86.594553 -241.481252) (xy 86.55405 -241.509208) (xy 86.509588 -241.530306) (xy 86.462317 -241.543998)
			(xy 86.413462 -241.54993) (xy 86.364287 -241.547949) (xy 86.316068 -241.538105) (xy 86.270052 -241.520653)
			(xy 86.227431 -241.496046) (xy 86.18931 -241.464921) (xy 86.156675 -241.428084) (xy 86.130372 -241.386488)
			(xy 86.111081 -241.341212) (xy 86.099304 -241.293428) (xy 86.095344 -241.244374) (xy 85.776816 -241.244374)
			(xy 85.776304 -241.26982) (xy 85.76814 -241.320054) (xy 85.752024 -241.368328) (xy 85.728373 -241.413391)
			(xy 85.6978 -241.454077) (xy 85.661096 -241.489332) (xy 85.619212 -241.518242) (xy 85.573233 -241.540059)
			(xy 85.524349 -241.554219) (xy 85.473828 -241.560353) (xy 85.422976 -241.558304) (xy 85.373112 -241.548124)
			(xy 85.325526 -241.530077) (xy 85.281452 -241.504631) (xy 85.24203 -241.472444) (xy 85.208282 -241.43435)
			(xy 85.181081 -241.391336) (xy 85.161133 -241.344516) (xy 85.148954 -241.295102) (xy 85.144859 -241.244374)
			(xy 84.836762 -241.244374) (xy 84.83625 -241.26982) (xy 84.828086 -241.320054) (xy 84.81197 -241.368328)
			(xy 84.788319 -241.413391) (xy 84.757746 -241.454077) (xy 84.721042 -241.489332) (xy 84.679158 -241.518242)
			(xy 84.633179 -241.540059) (xy 84.584295 -241.554219) (xy 84.533774 -241.560353) (xy 84.482922 -241.558304)
			(xy 84.433058 -241.548124) (xy 84.385472 -241.530077) (xy 84.341398 -241.504631) (xy 84.301976 -241.472444)
			(xy 84.268228 -241.43435) (xy 84.241027 -241.391336) (xy 84.221079 -241.344516) (xy 84.2089 -241.295102)
			(xy 84.204805 -241.244374) (xy 83.886294 -241.244374) (xy 83.885799 -241.268981) (xy 83.877904 -241.317558)
			(xy 83.86232 -241.364239) (xy 83.839449 -241.407816) (xy 83.809884 -241.44716) (xy 83.774391 -241.481252)
			(xy 83.733888 -241.509208) (xy 83.689426 -241.530306) (xy 83.642155 -241.543998) (xy 83.5933 -241.54993)
			(xy 83.544125 -241.547949) (xy 83.495906 -241.538105) (xy 83.44989 -241.520653) (xy 83.407269 -241.496046)
			(xy 83.369148 -241.464921) (xy 83.336513 -241.428084) (xy 83.31021 -241.386488) (xy 83.290919 -241.341212)
			(xy 83.279142 -241.293428) (xy 83.275182 -241.244374) (xy 82.956654 -241.244374) (xy 82.956142 -241.26982)
			(xy 82.947978 -241.320054) (xy 82.931862 -241.368328) (xy 82.908211 -241.413391) (xy 82.877638 -241.454077)
			(xy 82.840934 -241.489332) (xy 82.79905 -241.518242) (xy 82.753071 -241.540059) (xy 82.704187 -241.554219)
			(xy 82.653666 -241.560353) (xy 82.602814 -241.558304) (xy 82.55295 -241.548124) (xy 82.505364 -241.530077)
			(xy 82.46129 -241.504631) (xy 82.421868 -241.472444) (xy 82.38812 -241.43435) (xy 82.360919 -241.391336)
			(xy 82.340971 -241.344516) (xy 82.328792 -241.295102) (xy 82.324697 -241.244374) (xy 82.00644 -241.244374)
			(xy 82.005945 -241.268981) (xy 81.99805 -241.317558) (xy 81.982466 -241.364239) (xy 81.959595 -241.407816)
			(xy 81.93003 -241.44716) (xy 81.894537 -241.481252) (xy 81.854034 -241.509208) (xy 81.809572 -241.530306)
			(xy 81.762301 -241.543998) (xy 81.713446 -241.54993) (xy 81.664271 -241.547949) (xy 81.616052 -241.538105)
			(xy 81.570036 -241.520653) (xy 81.527415 -241.496046) (xy 81.489294 -241.464921) (xy 81.456659 -241.428084)
			(xy 81.430356 -241.386488) (xy 81.411065 -241.341212) (xy 81.399288 -241.293428) (xy 81.395328 -241.244374)
			(xy 81.0768 -241.244374) (xy 81.076288 -241.26982) (xy 81.068124 -241.320054) (xy 81.052008 -241.368328)
			(xy 81.028357 -241.413391) (xy 80.997784 -241.454077) (xy 80.96108 -241.489332) (xy 80.919196 -241.518242)
			(xy 80.873217 -241.540059) (xy 80.824333 -241.554219) (xy 80.773812 -241.560353) (xy 80.72296 -241.558304)
			(xy 80.673096 -241.548124) (xy 80.62551 -241.530077) (xy 80.581436 -241.504631) (xy 80.542014 -241.472444)
			(xy 80.508266 -241.43435) (xy 80.481065 -241.391336) (xy 80.461117 -241.344516) (xy 80.448938 -241.295102)
			(xy 80.444843 -241.244374) (xy 80.126332 -241.244374) (xy 80.125837 -241.268981) (xy 80.117942 -241.317558)
			(xy 80.102358 -241.364239) (xy 80.079487 -241.407816) (xy 80.049922 -241.44716) (xy 80.014429 -241.481252)
			(xy 79.973926 -241.509208) (xy 79.929464 -241.530306) (xy 79.882193 -241.543998) (xy 79.833338 -241.54993)
			(xy 79.784163 -241.547949) (xy 79.735944 -241.538105) (xy 79.689928 -241.520653) (xy 79.647307 -241.496046)
			(xy 79.609186 -241.464921) (xy 79.576551 -241.428084) (xy 79.550248 -241.386488) (xy 79.530957 -241.341212)
			(xy 79.51918 -241.293428) (xy 79.51522 -241.244374) (xy 76.963477 -241.244374) (xy 76.965804 -241.245478)
			(xy 77.006307 -241.273434) (xy 77.0418 -241.307526) (xy 77.071365 -241.34687) (xy 77.094236 -241.390447)
			(xy 77.10982 -241.437128) (xy 77.117715 -241.485705) (xy 77.11821 -241.510312) (xy 77.117715 -241.534919)
			(xy 77.10982 -241.583496) (xy 77.094236 -241.630177) (xy 77.071365 -241.673754) (xy 77.0418 -241.713098)
			(xy 77.006307 -241.74719) (xy 76.965804 -241.775146) (xy 76.921342 -241.796244) (xy 76.874071 -241.809936)
			(xy 76.825216 -241.815868) (xy 76.776041 -241.813887) (xy 76.727822 -241.804043) (xy 76.681806 -241.786591)
			(xy 76.639185 -241.761984) (xy 76.601064 -241.730859) (xy 76.568429 -241.694022) (xy 76.542126 -241.652426)
			(xy 76.522835 -241.60715) (xy 76.511058 -241.559366) (xy 76.507098 -241.510312) (xy 62.37732 -241.510312)
			(xy 62.37732 -242.05438) (xy 78.105266 -242.05438) (xy 78.109226 -242.005326) (xy 78.121003 -241.957542)
			(xy 78.140294 -241.912266) (xy 78.166597 -241.87067) (xy 78.199232 -241.833833) (xy 78.237353 -241.802708)
			(xy 78.279974 -241.778101) (xy 78.32599 -241.760649) (xy 78.374209 -241.750805) (xy 78.423384 -241.748824)
			(xy 78.472239 -241.754756) (xy 78.51951 -241.768448) (xy 78.563972 -241.789546) (xy 78.604475 -241.817502)
			(xy 78.639968 -241.851594) (xy 78.669533 -241.890938) (xy 78.692404 -241.934515) (xy 78.707988 -241.981196)
			(xy 78.715883 -242.029773) (xy 78.716378 -242.05438) (xy 79.985374 -242.05438) (xy 79.989334 -242.005326)
			(xy 80.001111 -241.957542) (xy 80.020402 -241.912266) (xy 80.046705 -241.87067) (xy 80.07934 -241.833833)
			(xy 80.117461 -241.802708) (xy 80.160082 -241.778101) (xy 80.206098 -241.760649) (xy 80.254317 -241.750805)
			(xy 80.303492 -241.748824) (xy 80.352347 -241.754756) (xy 80.399618 -241.768448) (xy 80.44408 -241.789546)
			(xy 80.484583 -241.817502) (xy 80.520076 -241.851594) (xy 80.549641 -241.890938) (xy 80.572512 -241.934515)
			(xy 80.588096 -241.981196) (xy 80.595991 -242.029773) (xy 80.596486 -242.05438) (xy 80.914743 -242.05438)
			(xy 80.918838 -242.003652) (xy 80.931017 -241.954238) (xy 80.950965 -241.907418) (xy 80.978166 -241.864404)
			(xy 81.011914 -241.82631) (xy 81.051336 -241.794123) (xy 81.09541 -241.768677) (xy 81.142996 -241.75063)
			(xy 81.19286 -241.74045) (xy 81.243712 -241.738401) (xy 81.294233 -241.744535) (xy 81.343117 -241.758695)
			(xy 81.389096 -241.780512) (xy 81.43098 -241.809422) (xy 81.467684 -241.844677) (xy 81.498257 -241.885363)
			(xy 81.521908 -241.930426) (xy 81.538024 -241.9787) (xy 81.546188 -242.028934) (xy 81.5467 -242.05438)
			(xy 81.854797 -242.05438) (xy 81.858892 -242.003652) (xy 81.871071 -241.954238) (xy 81.891019 -241.907418)
			(xy 81.91822 -241.864404) (xy 81.951968 -241.82631) (xy 81.99139 -241.794123) (xy 82.035464 -241.768677)
			(xy 82.08305 -241.75063) (xy 82.132914 -241.74045) (xy 82.183766 -241.738401) (xy 82.234287 -241.744535)
			(xy 82.283171 -241.758695) (xy 82.32915 -241.780512) (xy 82.371034 -241.809422) (xy 82.407738 -241.844677)
			(xy 82.438311 -241.885363) (xy 82.461962 -241.930426) (xy 82.478078 -241.9787) (xy 82.486242 -242.028934)
			(xy 82.486754 -242.05438) (xy 82.805282 -242.05438) (xy 82.809242 -242.005326) (xy 82.821019 -241.957542)
			(xy 82.84031 -241.912266) (xy 82.866613 -241.87067) (xy 82.899248 -241.833833) (xy 82.937369 -241.802708)
			(xy 82.97999 -241.778101) (xy 83.026006 -241.760649) (xy 83.074225 -241.750805) (xy 83.1234 -241.748824)
			(xy 83.172255 -241.754756) (xy 83.219526 -241.768448) (xy 83.263988 -241.789546) (xy 83.304491 -241.817502)
			(xy 83.339984 -241.851594) (xy 83.369549 -241.890938) (xy 83.39242 -241.934515) (xy 83.408004 -241.981196)
			(xy 83.415899 -242.029773) (xy 83.416394 -242.05438) (xy 83.734905 -242.05438) (xy 83.739 -242.003652)
			(xy 83.751179 -241.954238) (xy 83.771127 -241.907418) (xy 83.798328 -241.864404) (xy 83.832076 -241.82631)
			(xy 83.871498 -241.794123) (xy 83.915572 -241.768677) (xy 83.963158 -241.75063) (xy 84.013022 -241.74045)
			(xy 84.063874 -241.738401) (xy 84.114395 -241.744535) (xy 84.163279 -241.758695) (xy 84.209258 -241.780512)
			(xy 84.251142 -241.809422) (xy 84.287846 -241.844677) (xy 84.318419 -241.885363) (xy 84.34207 -241.930426)
			(xy 84.358186 -241.9787) (xy 84.36635 -242.028934) (xy 84.366862 -242.05438) (xy 84.685136 -242.05438)
			(xy 84.689096 -242.005326) (xy 84.700873 -241.957542) (xy 84.720164 -241.912266) (xy 84.746467 -241.87067)
			(xy 84.779102 -241.833833) (xy 84.817223 -241.802708) (xy 84.859844 -241.778101) (xy 84.90586 -241.760649)
			(xy 84.954079 -241.750805) (xy 85.003254 -241.748824) (xy 85.052109 -241.754756) (xy 85.09938 -241.768448)
			(xy 85.143842 -241.789546) (xy 85.184345 -241.817502) (xy 85.219838 -241.851594) (xy 85.249403 -241.890938)
			(xy 85.272274 -241.934515) (xy 85.287858 -241.981196) (xy 85.295753 -242.029773) (xy 85.296248 -242.05438)
			(xy 85.614759 -242.05438) (xy 85.618854 -242.003652) (xy 85.631033 -241.954238) (xy 85.650981 -241.907418)
			(xy 85.678182 -241.864404) (xy 85.71193 -241.82631) (xy 85.751352 -241.794123) (xy 85.795426 -241.768677)
			(xy 85.843012 -241.75063) (xy 85.892876 -241.74045) (xy 85.943728 -241.738401) (xy 85.994249 -241.744535)
			(xy 86.043133 -241.758695) (xy 86.089112 -241.780512) (xy 86.130996 -241.809422) (xy 86.1677 -241.844677)
			(xy 86.198273 -241.885363) (xy 86.221924 -241.930426) (xy 86.23804 -241.9787) (xy 86.246204 -242.028934)
			(xy 86.246716 -242.05438) (xy 86.565244 -242.05438) (xy 86.569204 -242.005326) (xy 86.580981 -241.957542)
			(xy 86.600272 -241.912266) (xy 86.626575 -241.87067) (xy 86.65921 -241.833833) (xy 86.697331 -241.802708)
			(xy 86.739952 -241.778101) (xy 86.785968 -241.760649) (xy 86.834187 -241.750805) (xy 86.883362 -241.748824)
			(xy 86.932217 -241.754756) (xy 86.979488 -241.768448) (xy 87.02395 -241.789546) (xy 87.064453 -241.817502)
			(xy 87.099946 -241.851594) (xy 87.129511 -241.890938) (xy 87.152382 -241.934515) (xy 87.167966 -241.981196)
			(xy 87.175861 -242.029773) (xy 87.176356 -242.05438) (xy 87.494867 -242.05438) (xy 87.498962 -242.003652)
			(xy 87.511141 -241.954238) (xy 87.531089 -241.907418) (xy 87.55829 -241.864404) (xy 87.592038 -241.82631)
			(xy 87.63146 -241.794123) (xy 87.675534 -241.768677) (xy 87.72312 -241.75063) (xy 87.772984 -241.74045)
			(xy 87.823836 -241.738401) (xy 87.874357 -241.744535) (xy 87.923241 -241.758695) (xy 87.96922 -241.780512)
			(xy 88.011104 -241.809422) (xy 88.047808 -241.844677) (xy 88.078381 -241.885363) (xy 88.102032 -241.930426)
			(xy 88.118148 -241.9787) (xy 88.126312 -242.028934) (xy 88.126824 -242.05438) (xy 88.434921 -242.05438)
			(xy 88.439016 -242.003652) (xy 88.451195 -241.954238) (xy 88.471143 -241.907418) (xy 88.498344 -241.864404)
			(xy 88.532092 -241.82631) (xy 88.571514 -241.794123) (xy 88.615588 -241.768677) (xy 88.663174 -241.75063)
			(xy 88.713038 -241.74045) (xy 88.76389 -241.738401) (xy 88.814411 -241.744535) (xy 88.863295 -241.758695)
			(xy 88.909274 -241.780512) (xy 88.951158 -241.809422) (xy 88.987862 -241.844677) (xy 89.018435 -241.885363)
			(xy 89.042086 -241.930426) (xy 89.058202 -241.9787) (xy 89.066366 -242.028934) (xy 89.066878 -242.05438)
			(xy 89.385152 -242.05438) (xy 89.389112 -242.005326) (xy 89.400889 -241.957542) (xy 89.42018 -241.912266)
			(xy 89.446483 -241.87067) (xy 89.479118 -241.833833) (xy 89.517239 -241.802708) (xy 89.55986 -241.778101)
			(xy 89.605876 -241.760649) (xy 89.654095 -241.750805) (xy 89.70327 -241.748824) (xy 89.752125 -241.754756)
			(xy 89.799396 -241.768448) (xy 89.843858 -241.789546) (xy 89.884361 -241.817502) (xy 89.919854 -241.851594)
			(xy 89.949419 -241.890938) (xy 89.97229 -241.934515) (xy 89.987874 -241.981196) (xy 89.995769 -242.029773)
			(xy 89.996264 -242.05438) (xy 90.314775 -242.05438) (xy 90.31887 -242.003652) (xy 90.331049 -241.954238)
			(xy 90.350997 -241.907418) (xy 90.378198 -241.864404) (xy 90.411946 -241.82631) (xy 90.451368 -241.794123)
			(xy 90.495442 -241.768677) (xy 90.543028 -241.75063) (xy 90.592892 -241.74045) (xy 90.643744 -241.738401)
			(xy 90.694265 -241.744535) (xy 90.743149 -241.758695) (xy 90.789128 -241.780512) (xy 90.831012 -241.809422)
			(xy 90.867716 -241.844677) (xy 90.898289 -241.885363) (xy 90.92194 -241.930426) (xy 90.938056 -241.9787)
			(xy 90.94622 -242.028934) (xy 90.946732 -242.05438) (xy 91.26526 -242.05438) (xy 91.26922 -242.005326)
			(xy 91.280997 -241.957542) (xy 91.300288 -241.912266) (xy 91.326591 -241.87067) (xy 91.359226 -241.833833)
			(xy 91.397347 -241.802708) (xy 91.439968 -241.778101) (xy 91.485984 -241.760649) (xy 91.534203 -241.750805)
			(xy 91.583378 -241.748824) (xy 91.632233 -241.754756) (xy 91.679504 -241.768448) (xy 91.723966 -241.789546)
			(xy 91.764469 -241.817502) (xy 91.799962 -241.851594) (xy 91.829527 -241.890938) (xy 91.852398 -241.934515)
			(xy 91.867982 -241.981196) (xy 91.875877 -242.029773) (xy 91.876372 -242.05438) (xy 92.194883 -242.05438)
			(xy 92.198978 -242.003652) (xy 92.211157 -241.954238) (xy 92.231105 -241.907418) (xy 92.258306 -241.864404)
			(xy 92.292054 -241.82631) (xy 92.331476 -241.794123) (xy 92.37555 -241.768677) (xy 92.423136 -241.75063)
			(xy 92.473 -241.74045) (xy 92.523852 -241.738401) (xy 92.574373 -241.744535) (xy 92.623257 -241.758695)
			(xy 92.669236 -241.780512) (xy 92.71112 -241.809422) (xy 92.747824 -241.844677) (xy 92.778397 -241.885363)
			(xy 92.802048 -241.930426) (xy 92.818164 -241.9787) (xy 92.826328 -242.028934) (xy 92.82684 -242.05438)
			(xy 93.145114 -242.05438) (xy 93.149074 -242.005326) (xy 93.160851 -241.957542) (xy 93.180142 -241.912266)
			(xy 93.206445 -241.87067) (xy 93.23908 -241.833833) (xy 93.277201 -241.802708) (xy 93.319822 -241.778101)
			(xy 93.365838 -241.760649) (xy 93.414057 -241.750805) (xy 93.463232 -241.748824) (xy 93.512087 -241.754756)
			(xy 93.559358 -241.768448) (xy 93.60382 -241.789546) (xy 93.644323 -241.817502) (xy 93.679816 -241.851594)
			(xy 93.709381 -241.890938) (xy 93.732252 -241.934515) (xy 93.747836 -241.981196) (xy 93.755731 -242.029773)
			(xy 93.756226 -242.05438) (xy 94.074737 -242.05438) (xy 94.078832 -242.003652) (xy 94.091011 -241.954238)
			(xy 94.110959 -241.907418) (xy 94.13816 -241.864404) (xy 94.171908 -241.82631) (xy 94.21133 -241.794123)
			(xy 94.255404 -241.768677) (xy 94.30299 -241.75063) (xy 94.352854 -241.74045) (xy 94.403706 -241.738401)
			(xy 94.454227 -241.744535) (xy 94.503111 -241.758695) (xy 94.54909 -241.780512) (xy 94.590974 -241.809422)
			(xy 94.627678 -241.844677) (xy 94.658251 -241.885363) (xy 94.681902 -241.930426) (xy 94.698018 -241.9787)
			(xy 94.706182 -242.028934) (xy 94.706694 -242.05438) (xy 95.014791 -242.05438) (xy 95.018886 -242.003652)
			(xy 95.031065 -241.954238) (xy 95.051013 -241.907418) (xy 95.078214 -241.864404) (xy 95.111962 -241.82631)
			(xy 95.151384 -241.794123) (xy 95.195458 -241.768677) (xy 95.243044 -241.75063) (xy 95.292908 -241.74045)
			(xy 95.34376 -241.738401) (xy 95.394281 -241.744535) (xy 95.443165 -241.758695) (xy 95.489144 -241.780512)
			(xy 95.531028 -241.809422) (xy 95.567732 -241.844677) (xy 95.598305 -241.885363) (xy 95.621956 -241.930426)
			(xy 95.638072 -241.9787) (xy 95.646236 -242.028934) (xy 95.646748 -242.05438) (xy 95.965276 -242.05438)
			(xy 95.969236 -242.005326) (xy 95.981013 -241.957542) (xy 96.000304 -241.912266) (xy 96.026607 -241.87067)
			(xy 96.059242 -241.833833) (xy 96.097363 -241.802708) (xy 96.139984 -241.778101) (xy 96.186 -241.760649)
			(xy 96.234219 -241.750805) (xy 96.283394 -241.748824) (xy 96.332249 -241.754756) (xy 96.37952 -241.768448)
			(xy 96.423982 -241.789546) (xy 96.464485 -241.817502) (xy 96.499978 -241.851594) (xy 96.529543 -241.890938)
			(xy 96.552414 -241.934515) (xy 96.567998 -241.981196) (xy 96.575893 -242.029773) (xy 96.576388 -242.05438)
			(xy 98.785184 -242.05438) (xy 98.789144 -242.005326) (xy 98.800921 -241.957542) (xy 98.820212 -241.912266)
			(xy 98.846515 -241.87067) (xy 98.87915 -241.833833) (xy 98.917271 -241.802708) (xy 98.959892 -241.778101)
			(xy 99.005908 -241.760649) (xy 99.054127 -241.750805) (xy 99.103302 -241.748824) (xy 99.152157 -241.754756)
			(xy 99.199428 -241.768448) (xy 99.24389 -241.789546) (xy 99.284393 -241.817502) (xy 99.319886 -241.851594)
			(xy 99.349451 -241.890938) (xy 99.372322 -241.934515) (xy 99.387906 -241.981196) (xy 99.395801 -242.029773)
			(xy 99.396296 -242.05438) (xy 101.605346 -242.05438) (xy 101.609306 -242.005326) (xy 101.621083 -241.957542)
			(xy 101.640374 -241.912266) (xy 101.666677 -241.87067) (xy 101.699312 -241.833833) (xy 101.737433 -241.802708)
			(xy 101.780054 -241.778101) (xy 101.82607 -241.760649) (xy 101.874289 -241.750805) (xy 101.923464 -241.748824)
			(xy 101.972319 -241.754756) (xy 102.01959 -241.768448) (xy 102.064052 -241.789546) (xy 102.104555 -241.817502)
			(xy 102.140048 -241.851594) (xy 102.169613 -241.890938) (xy 102.192484 -241.934515) (xy 102.208068 -241.981196)
			(xy 102.215963 -242.029773) (xy 102.216458 -242.05438) (xy 104.425254 -242.05438) (xy 104.429214 -242.005326)
			(xy 104.440991 -241.957542) (xy 104.460282 -241.912266) (xy 104.486585 -241.87067) (xy 104.51922 -241.833833)
			(xy 104.557341 -241.802708) (xy 104.599962 -241.778101) (xy 104.645978 -241.760649) (xy 104.694197 -241.750805)
			(xy 104.743372 -241.748824) (xy 104.792227 -241.754756) (xy 104.839498 -241.768448) (xy 104.88396 -241.789546)
			(xy 104.924463 -241.817502) (xy 104.959956 -241.851594) (xy 104.989521 -241.890938) (xy 105.012392 -241.934515)
			(xy 105.027976 -241.981196) (xy 105.035871 -242.029773) (xy 105.036366 -242.05438) (xy 107.245162 -242.05438)
			(xy 107.249122 -242.005326) (xy 107.260899 -241.957542) (xy 107.28019 -241.912266) (xy 107.306493 -241.87067)
			(xy 107.339128 -241.833833) (xy 107.377249 -241.802708) (xy 107.41987 -241.778101) (xy 107.465886 -241.760649)
			(xy 107.514105 -241.750805) (xy 107.56328 -241.748824) (xy 107.612135 -241.754756) (xy 107.659406 -241.768448)
			(xy 107.703868 -241.789546) (xy 107.744371 -241.817502) (xy 107.779864 -241.851594) (xy 107.809429 -241.890938)
			(xy 107.8323 -241.934515) (xy 107.847884 -241.981196) (xy 107.855779 -242.029773) (xy 107.856274 -242.05438)
			(xy 108.174785 -242.05438) (xy 108.17888 -242.003652) (xy 108.191059 -241.954238) (xy 108.211007 -241.907418)
			(xy 108.238208 -241.864404) (xy 108.271956 -241.82631) (xy 108.311378 -241.794123) (xy 108.355452 -241.768677)
			(xy 108.403038 -241.75063) (xy 108.452902 -241.74045) (xy 108.503754 -241.738401) (xy 108.554275 -241.744535)
			(xy 108.603159 -241.758695) (xy 108.649138 -241.780512) (xy 108.691022 -241.809422) (xy 108.727726 -241.844677)
			(xy 108.758299 -241.885363) (xy 108.78195 -241.930426) (xy 108.798066 -241.9787) (xy 108.80623 -242.028934)
			(xy 108.806742 -242.05438) (xy 109.114839 -242.05438) (xy 109.118934 -242.003652) (xy 109.131113 -241.954238)
			(xy 109.151061 -241.907418) (xy 109.178262 -241.864404) (xy 109.21201 -241.82631) (xy 109.251432 -241.794123)
			(xy 109.295506 -241.768677) (xy 109.343092 -241.75063) (xy 109.392956 -241.74045) (xy 109.443808 -241.738401)
			(xy 109.494329 -241.744535) (xy 109.543213 -241.758695) (xy 109.589192 -241.780512) (xy 109.631076 -241.809422)
			(xy 109.66778 -241.844677) (xy 109.698353 -241.885363) (xy 109.722004 -241.930426) (xy 109.73812 -241.9787)
			(xy 109.746284 -242.028934) (xy 109.746796 -242.05438) (xy 110.065324 -242.05438) (xy 110.069284 -242.005326)
			(xy 110.081061 -241.957542) (xy 110.100352 -241.912266) (xy 110.126655 -241.87067) (xy 110.15929 -241.833833)
			(xy 110.197411 -241.802708) (xy 110.240032 -241.778101) (xy 110.286048 -241.760649) (xy 110.334267 -241.750805)
			(xy 110.383442 -241.748824) (xy 110.432297 -241.754756) (xy 110.479568 -241.768448) (xy 110.52403 -241.789546)
			(xy 110.564533 -241.817502) (xy 110.600026 -241.851594) (xy 110.629591 -241.890938) (xy 110.652462 -241.934515)
			(xy 110.668046 -241.981196) (xy 110.675941 -242.029773) (xy 110.676436 -242.05438) (xy 110.675941 -242.078987)
			(xy 110.668046 -242.127564) (xy 110.652462 -242.174245) (xy 110.629591 -242.217822) (xy 110.600026 -242.257166)
			(xy 110.564533 -242.291258) (xy 110.52403 -242.319214) (xy 110.479568 -242.340312) (xy 110.432297 -242.354004)
			(xy 110.383442 -242.359936) (xy 110.334267 -242.357955) (xy 110.286048 -242.348111) (xy 110.240032 -242.330659)
			(xy 110.197411 -242.306052) (xy 110.15929 -242.274927) (xy 110.126655 -242.23809) (xy 110.100352 -242.196494)
			(xy 110.081061 -242.151218) (xy 110.069284 -242.103434) (xy 110.065324 -242.05438) (xy 109.746796 -242.05438)
			(xy 109.746284 -242.079826) (xy 109.73812 -242.13006) (xy 109.722004 -242.178334) (xy 109.698353 -242.223397)
			(xy 109.66778 -242.264083) (xy 109.631076 -242.299338) (xy 109.589192 -242.328248) (xy 109.543213 -242.350065)
			(xy 109.494329 -242.364225) (xy 109.443808 -242.370359) (xy 109.392956 -242.36831) (xy 109.343092 -242.35813)
			(xy 109.295506 -242.340083) (xy 109.251432 -242.314637) (xy 109.21201 -242.28245) (xy 109.178262 -242.244356)
			(xy 109.151061 -242.201342) (xy 109.131113 -242.154522) (xy 109.118934 -242.105108) (xy 109.114839 -242.05438)
			(xy 108.806742 -242.05438) (xy 108.80623 -242.079826) (xy 108.798066 -242.13006) (xy 108.78195 -242.178334)
			(xy 108.758299 -242.223397) (xy 108.727726 -242.264083) (xy 108.691022 -242.299338) (xy 108.649138 -242.328248)
			(xy 108.603159 -242.350065) (xy 108.554275 -242.364225) (xy 108.503754 -242.370359) (xy 108.452902 -242.36831)
			(xy 108.403038 -242.35813) (xy 108.355452 -242.340083) (xy 108.311378 -242.314637) (xy 108.271956 -242.28245)
			(xy 108.238208 -242.244356) (xy 108.211007 -242.201342) (xy 108.191059 -242.154522) (xy 108.17888 -242.105108)
			(xy 108.174785 -242.05438) (xy 107.856274 -242.05438) (xy 107.855779 -242.078987) (xy 107.847884 -242.127564)
			(xy 107.8323 -242.174245) (xy 107.809429 -242.217822) (xy 107.779864 -242.257166) (xy 107.744371 -242.291258)
			(xy 107.703868 -242.319214) (xy 107.659406 -242.340312) (xy 107.612135 -242.354004) (xy 107.56328 -242.359936)
			(xy 107.514105 -242.357955) (xy 107.465886 -242.348111) (xy 107.41987 -242.330659) (xy 107.377249 -242.306052)
			(xy 107.339128 -242.274927) (xy 107.306493 -242.23809) (xy 107.28019 -242.196494) (xy 107.260899 -242.151218)
			(xy 107.249122 -242.103434) (xy 107.245162 -242.05438) (xy 105.036366 -242.05438) (xy 105.035871 -242.078987)
			(xy 105.027976 -242.127564) (xy 105.012392 -242.174245) (xy 104.989521 -242.217822) (xy 104.959956 -242.257166)
			(xy 104.924463 -242.291258) (xy 104.88396 -242.319214) (xy 104.839498 -242.340312) (xy 104.792227 -242.354004)
			(xy 104.743372 -242.359936) (xy 104.694197 -242.357955) (xy 104.645978 -242.348111) (xy 104.599962 -242.330659)
			(xy 104.557341 -242.306052) (xy 104.51922 -242.274927) (xy 104.486585 -242.23809) (xy 104.460282 -242.196494)
			(xy 104.440991 -242.151218) (xy 104.429214 -242.103434) (xy 104.425254 -242.05438) (xy 102.216458 -242.05438)
			(xy 102.215963 -242.078987) (xy 102.208068 -242.127564) (xy 102.192484 -242.174245) (xy 102.169613 -242.217822)
			(xy 102.140048 -242.257166) (xy 102.104555 -242.291258) (xy 102.064052 -242.319214) (xy 102.01959 -242.340312)
			(xy 101.972319 -242.354004) (xy 101.923464 -242.359936) (xy 101.874289 -242.357955) (xy 101.82607 -242.348111)
			(xy 101.780054 -242.330659) (xy 101.737433 -242.306052) (xy 101.699312 -242.274927) (xy 101.666677 -242.23809)
			(xy 101.640374 -242.196494) (xy 101.621083 -242.151218) (xy 101.609306 -242.103434) (xy 101.605346 -242.05438)
			(xy 99.396296 -242.05438) (xy 99.395801 -242.078987) (xy 99.387906 -242.127564) (xy 99.372322 -242.174245)
			(xy 99.349451 -242.217822) (xy 99.319886 -242.257166) (xy 99.284393 -242.291258) (xy 99.24389 -242.319214)
			(xy 99.199428 -242.340312) (xy 99.152157 -242.354004) (xy 99.103302 -242.359936) (xy 99.054127 -242.357955)
			(xy 99.005908 -242.348111) (xy 98.959892 -242.330659) (xy 98.917271 -242.306052) (xy 98.87915 -242.274927)
			(xy 98.846515 -242.23809) (xy 98.820212 -242.196494) (xy 98.800921 -242.151218) (xy 98.789144 -242.103434)
			(xy 98.785184 -242.05438) (xy 96.576388 -242.05438) (xy 96.575893 -242.078987) (xy 96.567998 -242.127564)
			(xy 96.552414 -242.174245) (xy 96.529543 -242.217822) (xy 96.499978 -242.257166) (xy 96.464485 -242.291258)
			(xy 96.423982 -242.319214) (xy 96.37952 -242.340312) (xy 96.332249 -242.354004) (xy 96.283394 -242.359936)
			(xy 96.234219 -242.357955) (xy 96.186 -242.348111) (xy 96.139984 -242.330659) (xy 96.097363 -242.306052)
			(xy 96.059242 -242.274927) (xy 96.026607 -242.23809) (xy 96.000304 -242.196494) (xy 95.981013 -242.151218)
			(xy 95.969236 -242.103434) (xy 95.965276 -242.05438) (xy 95.646748 -242.05438) (xy 95.646236 -242.079826)
			(xy 95.638072 -242.13006) (xy 95.621956 -242.178334) (xy 95.598305 -242.223397) (xy 95.567732 -242.264083)
			(xy 95.531028 -242.299338) (xy 95.489144 -242.328248) (xy 95.443165 -242.350065) (xy 95.394281 -242.364225)
			(xy 95.34376 -242.370359) (xy 95.292908 -242.36831) (xy 95.243044 -242.35813) (xy 95.195458 -242.340083)
			(xy 95.151384 -242.314637) (xy 95.111962 -242.28245) (xy 95.078214 -242.244356) (xy 95.051013 -242.201342)
			(xy 95.031065 -242.154522) (xy 95.018886 -242.105108) (xy 95.014791 -242.05438) (xy 94.706694 -242.05438)
			(xy 94.706182 -242.079826) (xy 94.698018 -242.13006) (xy 94.681902 -242.178334) (xy 94.658251 -242.223397)
			(xy 94.627678 -242.264083) (xy 94.590974 -242.299338) (xy 94.54909 -242.328248) (xy 94.503111 -242.350065)
			(xy 94.454227 -242.364225) (xy 94.403706 -242.370359) (xy 94.352854 -242.36831) (xy 94.30299 -242.35813)
			(xy 94.255404 -242.340083) (xy 94.21133 -242.314637) (xy 94.171908 -242.28245) (xy 94.13816 -242.244356)
			(xy 94.110959 -242.201342) (xy 94.091011 -242.154522) (xy 94.078832 -242.105108) (xy 94.074737 -242.05438)
			(xy 93.756226 -242.05438) (xy 93.755731 -242.078987) (xy 93.747836 -242.127564) (xy 93.732252 -242.174245)
			(xy 93.709381 -242.217822) (xy 93.679816 -242.257166) (xy 93.644323 -242.291258) (xy 93.60382 -242.319214)
			(xy 93.559358 -242.340312) (xy 93.512087 -242.354004) (xy 93.463232 -242.359936) (xy 93.414057 -242.357955)
			(xy 93.365838 -242.348111) (xy 93.319822 -242.330659) (xy 93.277201 -242.306052) (xy 93.23908 -242.274927)
			(xy 93.206445 -242.23809) (xy 93.180142 -242.196494) (xy 93.160851 -242.151218) (xy 93.149074 -242.103434)
			(xy 93.145114 -242.05438) (xy 92.82684 -242.05438) (xy 92.826328 -242.079826) (xy 92.818164 -242.13006)
			(xy 92.802048 -242.178334) (xy 92.778397 -242.223397) (xy 92.747824 -242.264083) (xy 92.71112 -242.299338)
			(xy 92.669236 -242.328248) (xy 92.623257 -242.350065) (xy 92.574373 -242.364225) (xy 92.523852 -242.370359)
			(xy 92.473 -242.36831) (xy 92.423136 -242.35813) (xy 92.37555 -242.340083) (xy 92.331476 -242.314637)
			(xy 92.292054 -242.28245) (xy 92.258306 -242.244356) (xy 92.231105 -242.201342) (xy 92.211157 -242.154522)
			(xy 92.198978 -242.105108) (xy 92.194883 -242.05438) (xy 91.876372 -242.05438) (xy 91.875877 -242.078987)
			(xy 91.867982 -242.127564) (xy 91.852398 -242.174245) (xy 91.829527 -242.217822) (xy 91.799962 -242.257166)
			(xy 91.764469 -242.291258) (xy 91.723966 -242.319214) (xy 91.679504 -242.340312) (xy 91.632233 -242.354004)
			(xy 91.583378 -242.359936) (xy 91.534203 -242.357955) (xy 91.485984 -242.348111) (xy 91.439968 -242.330659)
			(xy 91.397347 -242.306052) (xy 91.359226 -242.274927) (xy 91.326591 -242.23809) (xy 91.300288 -242.196494)
			(xy 91.280997 -242.151218) (xy 91.26922 -242.103434) (xy 91.26526 -242.05438) (xy 90.946732 -242.05438)
			(xy 90.94622 -242.079826) (xy 90.938056 -242.13006) (xy 90.92194 -242.178334) (xy 90.898289 -242.223397)
			(xy 90.867716 -242.264083) (xy 90.831012 -242.299338) (xy 90.789128 -242.328248) (xy 90.743149 -242.350065)
			(xy 90.694265 -242.364225) (xy 90.643744 -242.370359) (xy 90.592892 -242.36831) (xy 90.543028 -242.35813)
			(xy 90.495442 -242.340083) (xy 90.451368 -242.314637) (xy 90.411946 -242.28245) (xy 90.378198 -242.244356)
			(xy 90.350997 -242.201342) (xy 90.331049 -242.154522) (xy 90.31887 -242.105108) (xy 90.314775 -242.05438)
			(xy 89.996264 -242.05438) (xy 89.995769 -242.078987) (xy 89.987874 -242.127564) (xy 89.97229 -242.174245)
			(xy 89.949419 -242.217822) (xy 89.919854 -242.257166) (xy 89.884361 -242.291258) (xy 89.843858 -242.319214)
			(xy 89.799396 -242.340312) (xy 89.752125 -242.354004) (xy 89.70327 -242.359936) (xy 89.654095 -242.357955)
			(xy 89.605876 -242.348111) (xy 89.55986 -242.330659) (xy 89.517239 -242.306052) (xy 89.479118 -242.274927)
			(xy 89.446483 -242.23809) (xy 89.42018 -242.196494) (xy 89.400889 -242.151218) (xy 89.389112 -242.103434)
			(xy 89.385152 -242.05438) (xy 89.066878 -242.05438) (xy 89.066366 -242.079826) (xy 89.058202 -242.13006)
			(xy 89.042086 -242.178334) (xy 89.018435 -242.223397) (xy 88.987862 -242.264083) (xy 88.951158 -242.299338)
			(xy 88.909274 -242.328248) (xy 88.863295 -242.350065) (xy 88.814411 -242.364225) (xy 88.76389 -242.370359)
			(xy 88.713038 -242.36831) (xy 88.663174 -242.35813) (xy 88.615588 -242.340083) (xy 88.571514 -242.314637)
			(xy 88.532092 -242.28245) (xy 88.498344 -242.244356) (xy 88.471143 -242.201342) (xy 88.451195 -242.154522)
			(xy 88.439016 -242.105108) (xy 88.434921 -242.05438) (xy 88.126824 -242.05438) (xy 88.126312 -242.079826)
			(xy 88.118148 -242.13006) (xy 88.102032 -242.178334) (xy 88.078381 -242.223397) (xy 88.047808 -242.264083)
			(xy 88.011104 -242.299338) (xy 87.96922 -242.328248) (xy 87.923241 -242.350065) (xy 87.874357 -242.364225)
			(xy 87.823836 -242.370359) (xy 87.772984 -242.36831) (xy 87.72312 -242.35813) (xy 87.675534 -242.340083)
			(xy 87.63146 -242.314637) (xy 87.592038 -242.28245) (xy 87.55829 -242.244356) (xy 87.531089 -242.201342)
			(xy 87.511141 -242.154522) (xy 87.498962 -242.105108) (xy 87.494867 -242.05438) (xy 87.176356 -242.05438)
			(xy 87.175861 -242.078987) (xy 87.167966 -242.127564) (xy 87.152382 -242.174245) (xy 87.129511 -242.217822)
			(xy 87.099946 -242.257166) (xy 87.064453 -242.291258) (xy 87.02395 -242.319214) (xy 86.979488 -242.340312)
			(xy 86.932217 -242.354004) (xy 86.883362 -242.359936) (xy 86.834187 -242.357955) (xy 86.785968 -242.348111)
			(xy 86.739952 -242.330659) (xy 86.697331 -242.306052) (xy 86.65921 -242.274927) (xy 86.626575 -242.23809)
			(xy 86.600272 -242.196494) (xy 86.580981 -242.151218) (xy 86.569204 -242.103434) (xy 86.565244 -242.05438)
			(xy 86.246716 -242.05438) (xy 86.246204 -242.079826) (xy 86.23804 -242.13006) (xy 86.221924 -242.178334)
			(xy 86.198273 -242.223397) (xy 86.1677 -242.264083) (xy 86.130996 -242.299338) (xy 86.089112 -242.328248)
			(xy 86.043133 -242.350065) (xy 85.994249 -242.364225) (xy 85.943728 -242.370359) (xy 85.892876 -242.36831)
			(xy 85.843012 -242.35813) (xy 85.795426 -242.340083) (xy 85.751352 -242.314637) (xy 85.71193 -242.28245)
			(xy 85.678182 -242.244356) (xy 85.650981 -242.201342) (xy 85.631033 -242.154522) (xy 85.618854 -242.105108)
			(xy 85.614759 -242.05438) (xy 85.296248 -242.05438) (xy 85.295753 -242.078987) (xy 85.287858 -242.127564)
			(xy 85.272274 -242.174245) (xy 85.249403 -242.217822) (xy 85.219838 -242.257166) (xy 85.184345 -242.291258)
			(xy 85.143842 -242.319214) (xy 85.09938 -242.340312) (xy 85.052109 -242.354004) (xy 85.003254 -242.359936)
			(xy 84.954079 -242.357955) (xy 84.90586 -242.348111) (xy 84.859844 -242.330659) (xy 84.817223 -242.306052)
			(xy 84.779102 -242.274927) (xy 84.746467 -242.23809) (xy 84.720164 -242.196494) (xy 84.700873 -242.151218)
			(xy 84.689096 -242.103434) (xy 84.685136 -242.05438) (xy 84.366862 -242.05438) (xy 84.36635 -242.079826)
			(xy 84.358186 -242.13006) (xy 84.34207 -242.178334) (xy 84.318419 -242.223397) (xy 84.287846 -242.264083)
			(xy 84.251142 -242.299338) (xy 84.209258 -242.328248) (xy 84.163279 -242.350065) (xy 84.114395 -242.364225)
			(xy 84.063874 -242.370359) (xy 84.013022 -242.36831) (xy 83.963158 -242.35813) (xy 83.915572 -242.340083)
			(xy 83.871498 -242.314637) (xy 83.832076 -242.28245) (xy 83.798328 -242.244356) (xy 83.771127 -242.201342)
			(xy 83.751179 -242.154522) (xy 83.739 -242.105108) (xy 83.734905 -242.05438) (xy 83.416394 -242.05438)
			(xy 83.415899 -242.078987) (xy 83.408004 -242.127564) (xy 83.39242 -242.174245) (xy 83.369549 -242.217822)
			(xy 83.339984 -242.257166) (xy 83.304491 -242.291258) (xy 83.263988 -242.319214) (xy 83.219526 -242.340312)
			(xy 83.172255 -242.354004) (xy 83.1234 -242.359936) (xy 83.074225 -242.357955) (xy 83.026006 -242.348111)
			(xy 82.97999 -242.330659) (xy 82.937369 -242.306052) (xy 82.899248 -242.274927) (xy 82.866613 -242.23809)
			(xy 82.84031 -242.196494) (xy 82.821019 -242.151218) (xy 82.809242 -242.103434) (xy 82.805282 -242.05438)
			(xy 82.486754 -242.05438) (xy 82.486242 -242.079826) (xy 82.478078 -242.13006) (xy 82.461962 -242.178334)
			(xy 82.438311 -242.223397) (xy 82.407738 -242.264083) (xy 82.371034 -242.299338) (xy 82.32915 -242.328248)
			(xy 82.283171 -242.350065) (xy 82.234287 -242.364225) (xy 82.183766 -242.370359) (xy 82.132914 -242.36831)
			(xy 82.08305 -242.35813) (xy 82.035464 -242.340083) (xy 81.99139 -242.314637) (xy 81.951968 -242.28245)
			(xy 81.91822 -242.244356) (xy 81.891019 -242.201342) (xy 81.871071 -242.154522) (xy 81.858892 -242.105108)
			(xy 81.854797 -242.05438) (xy 81.5467 -242.05438) (xy 81.546188 -242.079826) (xy 81.538024 -242.13006)
			(xy 81.521908 -242.178334) (xy 81.498257 -242.223397) (xy 81.467684 -242.264083) (xy 81.43098 -242.299338)
			(xy 81.389096 -242.328248) (xy 81.343117 -242.350065) (xy 81.294233 -242.364225) (xy 81.243712 -242.370359)
			(xy 81.19286 -242.36831) (xy 81.142996 -242.35813) (xy 81.09541 -242.340083) (xy 81.051336 -242.314637)
			(xy 81.011914 -242.28245) (xy 80.978166 -242.244356) (xy 80.950965 -242.201342) (xy 80.931017 -242.154522)
			(xy 80.918838 -242.105108) (xy 80.914743 -242.05438) (xy 80.596486 -242.05438) (xy 80.595991 -242.078987)
			(xy 80.588096 -242.127564) (xy 80.572512 -242.174245) (xy 80.549641 -242.217822) (xy 80.520076 -242.257166)
			(xy 80.484583 -242.291258) (xy 80.44408 -242.319214) (xy 80.399618 -242.340312) (xy 80.352347 -242.354004)
			(xy 80.303492 -242.359936) (xy 80.254317 -242.357955) (xy 80.206098 -242.348111) (xy 80.160082 -242.330659)
			(xy 80.117461 -242.306052) (xy 80.07934 -242.274927) (xy 80.046705 -242.23809) (xy 80.020402 -242.196494)
			(xy 80.001111 -242.151218) (xy 79.989334 -242.103434) (xy 79.985374 -242.05438) (xy 78.716378 -242.05438)
			(xy 78.715883 -242.078987) (xy 78.707988 -242.127564) (xy 78.692404 -242.174245) (xy 78.669533 -242.217822)
			(xy 78.639968 -242.257166) (xy 78.604475 -242.291258) (xy 78.563972 -242.319214) (xy 78.51951 -242.340312)
			(xy 78.472239 -242.354004) (xy 78.423384 -242.359936) (xy 78.374209 -242.357955) (xy 78.32599 -242.348111)
			(xy 78.279974 -242.330659) (xy 78.237353 -242.306052) (xy 78.199232 -242.274927) (xy 78.166597 -242.23809)
			(xy 78.140294 -242.196494) (xy 78.121003 -242.151218) (xy 78.109226 -242.103434) (xy 78.105266 -242.05438)
			(xy 62.37732 -242.05438) (xy 62.37732 -243.130324) (xy 76.507098 -243.130324) (xy 76.511058 -243.08127)
			(xy 76.522835 -243.033486) (xy 76.542126 -242.98821) (xy 76.568429 -242.946614) (xy 76.601064 -242.909777)
			(xy 76.639185 -242.878652) (xy 76.681806 -242.854045) (xy 76.727822 -242.836593) (xy 76.776041 -242.826749)
			(xy 76.825216 -242.824768) (xy 76.874071 -242.8307) (xy 76.921342 -242.844392) (xy 76.963477 -242.864386)
			(xy 79.51522 -242.864386) (xy 79.51918 -242.815332) (xy 79.530957 -242.767548) (xy 79.550248 -242.722272)
			(xy 79.576551 -242.680676) (xy 79.609186 -242.643839) (xy 79.647307 -242.612714) (xy 79.689928 -242.588107)
			(xy 79.735944 -242.570655) (xy 79.784163 -242.560811) (xy 79.833338 -242.55883) (xy 79.882193 -242.564762)
			(xy 79.929464 -242.578454) (xy 79.973926 -242.599552) (xy 80.014429 -242.627508) (xy 80.049922 -242.6616)
			(xy 80.079487 -242.700944) (xy 80.102358 -242.744521) (xy 80.117942 -242.791202) (xy 80.125837 -242.839779)
			(xy 80.126332 -242.864386) (xy 80.444843 -242.864386) (xy 80.448938 -242.813658) (xy 80.461117 -242.764244)
			(xy 80.481065 -242.717424) (xy 80.508266 -242.67441) (xy 80.542014 -242.636316) (xy 80.581436 -242.604129)
			(xy 80.62551 -242.578683) (xy 80.673096 -242.560636) (xy 80.72296 -242.550456) (xy 80.773812 -242.548407)
			(xy 80.824333 -242.554541) (xy 80.873217 -242.568701) (xy 80.919196 -242.590518) (xy 80.96108 -242.619428)
			(xy 80.997784 -242.654683) (xy 81.028357 -242.695369) (xy 81.052008 -242.740432) (xy 81.068124 -242.788706)
			(xy 81.076288 -242.83894) (xy 81.0768 -242.864386) (xy 81.395328 -242.864386) (xy 81.399288 -242.815332)
			(xy 81.411065 -242.767548) (xy 81.430356 -242.722272) (xy 81.456659 -242.680676) (xy 81.489294 -242.643839)
			(xy 81.527415 -242.612714) (xy 81.570036 -242.588107) (xy 81.616052 -242.570655) (xy 81.664271 -242.560811)
			(xy 81.713446 -242.55883) (xy 81.762301 -242.564762) (xy 81.809572 -242.578454) (xy 81.854034 -242.599552)
			(xy 81.894537 -242.627508) (xy 81.93003 -242.6616) (xy 81.959595 -242.700944) (xy 81.982466 -242.744521)
			(xy 81.99805 -242.791202) (xy 82.005945 -242.839779) (xy 82.00644 -242.864386) (xy 82.324697 -242.864386)
			(xy 82.328792 -242.813658) (xy 82.340971 -242.764244) (xy 82.360919 -242.717424) (xy 82.38812 -242.67441)
			(xy 82.421868 -242.636316) (xy 82.46129 -242.604129) (xy 82.505364 -242.578683) (xy 82.55295 -242.560636)
			(xy 82.602814 -242.550456) (xy 82.653666 -242.548407) (xy 82.704187 -242.554541) (xy 82.753071 -242.568701)
			(xy 82.79905 -242.590518) (xy 82.840934 -242.619428) (xy 82.877638 -242.654683) (xy 82.908211 -242.695369)
			(xy 82.931862 -242.740432) (xy 82.947978 -242.788706) (xy 82.956142 -242.83894) (xy 82.956654 -242.864386)
			(xy 83.275182 -242.864386) (xy 83.279142 -242.815332) (xy 83.290919 -242.767548) (xy 83.31021 -242.722272)
			(xy 83.336513 -242.680676) (xy 83.369148 -242.643839) (xy 83.407269 -242.612714) (xy 83.44989 -242.588107)
			(xy 83.495906 -242.570655) (xy 83.544125 -242.560811) (xy 83.5933 -242.55883) (xy 83.642155 -242.564762)
			(xy 83.689426 -242.578454) (xy 83.733888 -242.599552) (xy 83.774391 -242.627508) (xy 83.809884 -242.6616)
			(xy 83.839449 -242.700944) (xy 83.86232 -242.744521) (xy 83.877904 -242.791202) (xy 83.885799 -242.839779)
			(xy 83.886294 -242.864386) (xy 84.204805 -242.864386) (xy 84.2089 -242.813658) (xy 84.221079 -242.764244)
			(xy 84.241027 -242.717424) (xy 84.268228 -242.67441) (xy 84.301976 -242.636316) (xy 84.341398 -242.604129)
			(xy 84.385472 -242.578683) (xy 84.433058 -242.560636) (xy 84.482922 -242.550456) (xy 84.533774 -242.548407)
			(xy 84.584295 -242.554541) (xy 84.633179 -242.568701) (xy 84.679158 -242.590518) (xy 84.721042 -242.619428)
			(xy 84.757746 -242.654683) (xy 84.788319 -242.695369) (xy 84.81197 -242.740432) (xy 84.828086 -242.788706)
			(xy 84.83625 -242.83894) (xy 84.836762 -242.864386) (xy 85.144859 -242.864386) (xy 85.148954 -242.813658)
			(xy 85.161133 -242.764244) (xy 85.181081 -242.717424) (xy 85.208282 -242.67441) (xy 85.24203 -242.636316)
			(xy 85.281452 -242.604129) (xy 85.325526 -242.578683) (xy 85.373112 -242.560636) (xy 85.422976 -242.550456)
			(xy 85.473828 -242.548407) (xy 85.524349 -242.554541) (xy 85.573233 -242.568701) (xy 85.619212 -242.590518)
			(xy 85.661096 -242.619428) (xy 85.6978 -242.654683) (xy 85.728373 -242.695369) (xy 85.752024 -242.740432)
			(xy 85.76814 -242.788706) (xy 85.776304 -242.83894) (xy 85.776816 -242.864386) (xy 86.095344 -242.864386)
			(xy 86.099304 -242.815332) (xy 86.111081 -242.767548) (xy 86.130372 -242.722272) (xy 86.156675 -242.680676)
			(xy 86.18931 -242.643839) (xy 86.227431 -242.612714) (xy 86.270052 -242.588107) (xy 86.316068 -242.570655)
			(xy 86.364287 -242.560811) (xy 86.413462 -242.55883) (xy 86.462317 -242.564762) (xy 86.509588 -242.578454)
			(xy 86.55405 -242.599552) (xy 86.594553 -242.627508) (xy 86.630046 -242.6616) (xy 86.659611 -242.700944)
			(xy 86.682482 -242.744521) (xy 86.698066 -242.791202) (xy 86.705961 -242.839779) (xy 86.706456 -242.864386)
			(xy 87.024713 -242.864386) (xy 87.028808 -242.813658) (xy 87.040987 -242.764244) (xy 87.060935 -242.717424)
			(xy 87.088136 -242.67441) (xy 87.121884 -242.636316) (xy 87.161306 -242.604129) (xy 87.20538 -242.578683)
			(xy 87.252966 -242.560636) (xy 87.30283 -242.550456) (xy 87.353682 -242.548407) (xy 87.404203 -242.554541)
			(xy 87.453087 -242.568701) (xy 87.499066 -242.590518) (xy 87.54095 -242.619428) (xy 87.577654 -242.654683)
			(xy 87.608227 -242.695369) (xy 87.631878 -242.740432) (xy 87.647994 -242.788706) (xy 87.656158 -242.83894)
			(xy 87.65667 -242.864386) (xy 87.975198 -242.864386) (xy 87.979158 -242.815332) (xy 87.990935 -242.767548)
			(xy 88.010226 -242.722272) (xy 88.036529 -242.680676) (xy 88.069164 -242.643839) (xy 88.107285 -242.612714)
			(xy 88.149906 -242.588107) (xy 88.195922 -242.570655) (xy 88.244141 -242.560811) (xy 88.293316 -242.55883)
			(xy 88.342171 -242.564762) (xy 88.389442 -242.578454) (xy 88.433904 -242.599552) (xy 88.474407 -242.627508)
			(xy 88.5099 -242.6616) (xy 88.539465 -242.700944) (xy 88.562336 -242.744521) (xy 88.57792 -242.791202)
			(xy 88.585815 -242.839779) (xy 88.58631 -242.864386) (xy 88.904821 -242.864386) (xy 88.908916 -242.813658)
			(xy 88.921095 -242.764244) (xy 88.941043 -242.717424) (xy 88.968244 -242.67441) (xy 89.001992 -242.636316)
			(xy 89.041414 -242.604129) (xy 89.085488 -242.578683) (xy 89.133074 -242.560636) (xy 89.182938 -242.550456)
			(xy 89.23379 -242.548407) (xy 89.284311 -242.554541) (xy 89.333195 -242.568701) (xy 89.379174 -242.590518)
			(xy 89.421058 -242.619428) (xy 89.457762 -242.654683) (xy 89.488335 -242.695369) (xy 89.511986 -242.740432)
			(xy 89.528102 -242.788706) (xy 89.536266 -242.83894) (xy 89.536778 -242.864386) (xy 89.855306 -242.864386)
			(xy 89.859266 -242.815332) (xy 89.871043 -242.767548) (xy 89.890334 -242.722272) (xy 89.916637 -242.680676)
			(xy 89.949272 -242.643839) (xy 89.987393 -242.612714) (xy 90.030014 -242.588107) (xy 90.07603 -242.570655)
			(xy 90.124249 -242.560811) (xy 90.173424 -242.55883) (xy 90.222279 -242.564762) (xy 90.26955 -242.578454)
			(xy 90.314012 -242.599552) (xy 90.354515 -242.627508) (xy 90.390008 -242.6616) (xy 90.419573 -242.700944)
			(xy 90.442444 -242.744521) (xy 90.458028 -242.791202) (xy 90.465923 -242.839779) (xy 90.466418 -242.864386)
			(xy 90.784675 -242.864386) (xy 90.78877 -242.813658) (xy 90.800949 -242.764244) (xy 90.820897 -242.717424)
			(xy 90.848098 -242.67441) (xy 90.881846 -242.636316) (xy 90.921268 -242.604129) (xy 90.965342 -242.578683)
			(xy 91.012928 -242.560636) (xy 91.062792 -242.550456) (xy 91.113644 -242.548407) (xy 91.164165 -242.554541)
			(xy 91.213049 -242.568701) (xy 91.259028 -242.590518) (xy 91.300912 -242.619428) (xy 91.337616 -242.654683)
			(xy 91.368189 -242.695369) (xy 91.39184 -242.740432) (xy 91.407956 -242.788706) (xy 91.41612 -242.83894)
			(xy 91.416632 -242.864386) (xy 91.724729 -242.864386) (xy 91.728824 -242.813658) (xy 91.741003 -242.764244)
			(xy 91.760951 -242.717424) (xy 91.788152 -242.67441) (xy 91.8219 -242.636316) (xy 91.861322 -242.604129)
			(xy 91.905396 -242.578683) (xy 91.952982 -242.560636) (xy 92.002846 -242.550456) (xy 92.053698 -242.548407)
			(xy 92.104219 -242.554541) (xy 92.153103 -242.568701) (xy 92.199082 -242.590518) (xy 92.240966 -242.619428)
			(xy 92.27767 -242.654683) (xy 92.308243 -242.695369) (xy 92.331894 -242.740432) (xy 92.34801 -242.788706)
			(xy 92.356174 -242.83894) (xy 92.356686 -242.864386) (xy 92.675214 -242.864386) (xy 92.679174 -242.815332)
			(xy 92.690951 -242.767548) (xy 92.710242 -242.722272) (xy 92.736545 -242.680676) (xy 92.76918 -242.643839)
			(xy 92.807301 -242.612714) (xy 92.849922 -242.588107) (xy 92.895938 -242.570655) (xy 92.944157 -242.560811)
			(xy 92.993332 -242.55883) (xy 93.042187 -242.564762) (xy 93.089458 -242.578454) (xy 93.13392 -242.599552)
			(xy 93.174423 -242.627508) (xy 93.209916 -242.6616) (xy 93.239481 -242.700944) (xy 93.262352 -242.744521)
			(xy 93.277936 -242.791202) (xy 93.285831 -242.839779) (xy 93.286326 -242.864386) (xy 93.604837 -242.864386)
			(xy 93.608932 -242.813658) (xy 93.621111 -242.764244) (xy 93.641059 -242.717424) (xy 93.66826 -242.67441)
			(xy 93.702008 -242.636316) (xy 93.74143 -242.604129) (xy 93.785504 -242.578683) (xy 93.83309 -242.560636)
			(xy 93.882954 -242.550456) (xy 93.933806 -242.548407) (xy 93.984327 -242.554541) (xy 94.033211 -242.568701)
			(xy 94.07919 -242.590518) (xy 94.121074 -242.619428) (xy 94.157778 -242.654683) (xy 94.188351 -242.695369)
			(xy 94.212002 -242.740432) (xy 94.228118 -242.788706) (xy 94.236282 -242.83894) (xy 94.236794 -242.864386)
			(xy 94.555322 -242.864386) (xy 94.559282 -242.815332) (xy 94.571059 -242.767548) (xy 94.59035 -242.722272)
			(xy 94.616653 -242.680676) (xy 94.649288 -242.643839) (xy 94.687409 -242.612714) (xy 94.73003 -242.588107)
			(xy 94.776046 -242.570655) (xy 94.824265 -242.560811) (xy 94.87344 -242.55883) (xy 94.922295 -242.564762)
			(xy 94.969566 -242.578454) (xy 95.014028 -242.599552) (xy 95.054531 -242.627508) (xy 95.090024 -242.6616)
			(xy 95.119589 -242.700944) (xy 95.14246 -242.744521) (xy 95.158044 -242.791202) (xy 95.165939 -242.839779)
			(xy 95.166434 -242.864386) (xy 95.484691 -242.864386) (xy 95.488786 -242.813658) (xy 95.500965 -242.764244)
			(xy 95.520913 -242.717424) (xy 95.548114 -242.67441) (xy 95.581862 -242.636316) (xy 95.621284 -242.604129)
			(xy 95.665358 -242.578683) (xy 95.712944 -242.560636) (xy 95.762808 -242.550456) (xy 95.81366 -242.548407)
			(xy 95.864181 -242.554541) (xy 95.913065 -242.568701) (xy 95.959044 -242.590518) (xy 96.000928 -242.619428)
			(xy 96.037632 -242.654683) (xy 96.068205 -242.695369) (xy 96.091856 -242.740432) (xy 96.107972 -242.788706)
			(xy 96.116136 -242.83894) (xy 96.116648 -242.864386) (xy 96.435176 -242.864386) (xy 96.439136 -242.815332)
			(xy 96.450913 -242.767548) (xy 96.470204 -242.722272) (xy 96.496507 -242.680676) (xy 96.529142 -242.643839)
			(xy 96.567263 -242.612714) (xy 96.609884 -242.588107) (xy 96.6559 -242.570655) (xy 96.704119 -242.560811)
			(xy 96.753294 -242.55883) (xy 96.802149 -242.564762) (xy 96.84942 -242.578454) (xy 96.893882 -242.599552)
			(xy 96.934385 -242.627508) (xy 96.969878 -242.6616) (xy 96.999443 -242.700944) (xy 97.022314 -242.744521)
			(xy 97.037898 -242.791202) (xy 97.045793 -242.839779) (xy 97.046288 -242.864386) (xy 97.364799 -242.864386)
			(xy 97.368894 -242.813658) (xy 97.381073 -242.764244) (xy 97.401021 -242.717424) (xy 97.428222 -242.67441)
			(xy 97.46197 -242.636316) (xy 97.501392 -242.604129) (xy 97.545466 -242.578683) (xy 97.593052 -242.560636)
			(xy 97.642916 -242.550456) (xy 97.693768 -242.548407) (xy 97.744289 -242.554541) (xy 97.793173 -242.568701)
			(xy 97.839152 -242.590518) (xy 97.881036 -242.619428) (xy 97.91774 -242.654683) (xy 97.948313 -242.695369)
			(xy 97.971964 -242.740432) (xy 97.98808 -242.788706) (xy 97.996244 -242.83894) (xy 97.996756 -242.864386)
			(xy 98.304853 -242.864386) (xy 98.308948 -242.813658) (xy 98.321127 -242.764244) (xy 98.341075 -242.717424)
			(xy 98.368276 -242.67441) (xy 98.402024 -242.636316) (xy 98.441446 -242.604129) (xy 98.48552 -242.578683)
			(xy 98.533106 -242.560636) (xy 98.58297 -242.550456) (xy 98.633822 -242.548407) (xy 98.684343 -242.554541)
			(xy 98.733227 -242.568701) (xy 98.779206 -242.590518) (xy 98.82109 -242.619428) (xy 98.857794 -242.654683)
			(xy 98.888367 -242.695369) (xy 98.912018 -242.740432) (xy 98.928134 -242.788706) (xy 98.936298 -242.83894)
			(xy 98.93681 -242.864386) (xy 99.255338 -242.864386) (xy 99.259298 -242.815332) (xy 99.271075 -242.767548)
			(xy 99.290366 -242.722272) (xy 99.316669 -242.680676) (xy 99.349304 -242.643839) (xy 99.387425 -242.612714)
			(xy 99.430046 -242.588107) (xy 99.476062 -242.570655) (xy 99.524281 -242.560811) (xy 99.573456 -242.55883)
			(xy 99.622311 -242.564762) (xy 99.669582 -242.578454) (xy 99.714044 -242.599552) (xy 99.754547 -242.627508)
			(xy 99.79004 -242.6616) (xy 99.819605 -242.700944) (xy 99.842476 -242.744521) (xy 99.85806 -242.791202)
			(xy 99.865955 -242.839779) (xy 99.86645 -242.864386) (xy 100.184707 -242.864386) (xy 100.188802 -242.813658)
			(xy 100.200981 -242.764244) (xy 100.220929 -242.717424) (xy 100.24813 -242.67441) (xy 100.281878 -242.636316)
			(xy 100.3213 -242.604129) (xy 100.365374 -242.578683) (xy 100.41296 -242.560636) (xy 100.462824 -242.550456)
			(xy 100.513676 -242.548407) (xy 100.564197 -242.554541) (xy 100.613081 -242.568701) (xy 100.65906 -242.590518)
			(xy 100.700944 -242.619428) (xy 100.737648 -242.654683) (xy 100.768221 -242.695369) (xy 100.791872 -242.740432)
			(xy 100.807988 -242.788706) (xy 100.816152 -242.83894) (xy 100.816664 -242.864386) (xy 101.124761 -242.864386)
			(xy 101.128856 -242.813658) (xy 101.141035 -242.764244) (xy 101.160983 -242.717424) (xy 101.188184 -242.67441)
			(xy 101.221932 -242.636316) (xy 101.261354 -242.604129) (xy 101.305428 -242.578683) (xy 101.353014 -242.560636)
			(xy 101.402878 -242.550456) (xy 101.45373 -242.548407) (xy 101.504251 -242.554541) (xy 101.553135 -242.568701)
			(xy 101.599114 -242.590518) (xy 101.640998 -242.619428) (xy 101.677702 -242.654683) (xy 101.708275 -242.695369)
			(xy 101.731926 -242.740432) (xy 101.748042 -242.788706) (xy 101.756206 -242.83894) (xy 101.756718 -242.864386)
			(xy 102.075246 -242.864386) (xy 102.079206 -242.815332) (xy 102.090983 -242.767548) (xy 102.110274 -242.722272)
			(xy 102.136577 -242.680676) (xy 102.169212 -242.643839) (xy 102.207333 -242.612714) (xy 102.249954 -242.588107)
			(xy 102.29597 -242.570655) (xy 102.344189 -242.560811) (xy 102.393364 -242.55883) (xy 102.442219 -242.564762)
			(xy 102.48949 -242.578454) (xy 102.533952 -242.599552) (xy 102.574455 -242.627508) (xy 102.609948 -242.6616)
			(xy 102.639513 -242.700944) (xy 102.662384 -242.744521) (xy 102.677968 -242.791202) (xy 102.685863 -242.839779)
			(xy 102.686358 -242.864386) (xy 103.004869 -242.864386) (xy 103.008964 -242.813658) (xy 103.021143 -242.764244)
			(xy 103.041091 -242.717424) (xy 103.068292 -242.67441) (xy 103.10204 -242.636316) (xy 103.141462 -242.604129)
			(xy 103.185536 -242.578683) (xy 103.233122 -242.560636) (xy 103.282986 -242.550456) (xy 103.333838 -242.548407)
			(xy 103.384359 -242.554541) (xy 103.433243 -242.568701) (xy 103.479222 -242.590518) (xy 103.521106 -242.619428)
			(xy 103.55781 -242.654683) (xy 103.588383 -242.695369) (xy 103.612034 -242.740432) (xy 103.62815 -242.788706)
			(xy 103.636314 -242.83894) (xy 103.636826 -242.864386) (xy 103.944923 -242.864386) (xy 103.949018 -242.813658)
			(xy 103.961197 -242.764244) (xy 103.981145 -242.717424) (xy 104.008346 -242.67441) (xy 104.042094 -242.636316)
			(xy 104.081516 -242.604129) (xy 104.12559 -242.578683) (xy 104.173176 -242.560636) (xy 104.22304 -242.550456)
			(xy 104.273892 -242.548407) (xy 104.324413 -242.554541) (xy 104.373297 -242.568701) (xy 104.419276 -242.590518)
			(xy 104.46116 -242.619428) (xy 104.497864 -242.654683) (xy 104.528437 -242.695369) (xy 104.552088 -242.740432)
			(xy 104.568204 -242.788706) (xy 104.576368 -242.83894) (xy 104.57688 -242.864386) (xy 104.895154 -242.864386)
			(xy 104.899114 -242.815332) (xy 104.910891 -242.767548) (xy 104.930182 -242.722272) (xy 104.956485 -242.680676)
			(xy 104.98912 -242.643839) (xy 105.027241 -242.612714) (xy 105.069862 -242.588107) (xy 105.115878 -242.570655)
			(xy 105.164097 -242.560811) (xy 105.213272 -242.55883) (xy 105.262127 -242.564762) (xy 105.309398 -242.578454)
			(xy 105.35386 -242.599552) (xy 105.394363 -242.627508) (xy 105.429856 -242.6616) (xy 105.459421 -242.700944)
			(xy 105.482292 -242.744521) (xy 105.497876 -242.791202) (xy 105.505771 -242.839779) (xy 105.506266 -242.864386)
			(xy 105.824777 -242.864386) (xy 105.828872 -242.813658) (xy 105.841051 -242.764244) (xy 105.860999 -242.717424)
			(xy 105.8882 -242.67441) (xy 105.921948 -242.636316) (xy 105.96137 -242.604129) (xy 106.005444 -242.578683)
			(xy 106.05303 -242.560636) (xy 106.102894 -242.550456) (xy 106.153746 -242.548407) (xy 106.204267 -242.554541)
			(xy 106.253151 -242.568701) (xy 106.29913 -242.590518) (xy 106.341014 -242.619428) (xy 106.377718 -242.654683)
			(xy 106.408291 -242.695369) (xy 106.431942 -242.740432) (xy 106.448058 -242.788706) (xy 106.456222 -242.83894)
			(xy 106.456734 -242.864386) (xy 106.764831 -242.864386) (xy 106.768926 -242.813658) (xy 106.781105 -242.764244)
			(xy 106.801053 -242.717424) (xy 106.828254 -242.67441) (xy 106.862002 -242.636316) (xy 106.901424 -242.604129)
			(xy 106.945498 -242.578683) (xy 106.993084 -242.560636) (xy 107.042948 -242.550456) (xy 107.0938 -242.548407)
			(xy 107.144321 -242.554541) (xy 107.193205 -242.568701) (xy 107.239184 -242.590518) (xy 107.281068 -242.619428)
			(xy 107.317772 -242.654683) (xy 107.348345 -242.695369) (xy 107.371996 -242.740432) (xy 107.388112 -242.788706)
			(xy 107.396276 -242.83894) (xy 107.396788 -242.864386) (xy 107.715316 -242.864386) (xy 107.719276 -242.815332)
			(xy 107.731053 -242.767548) (xy 107.750344 -242.722272) (xy 107.776647 -242.680676) (xy 107.809282 -242.643839)
			(xy 107.847403 -242.612714) (xy 107.890024 -242.588107) (xy 107.93604 -242.570655) (xy 107.984259 -242.560811)
			(xy 108.033434 -242.55883) (xy 108.082289 -242.564762) (xy 108.12956 -242.578454) (xy 108.174022 -242.599552)
			(xy 108.214525 -242.627508) (xy 108.250018 -242.6616) (xy 108.279583 -242.700944) (xy 108.302454 -242.744521)
			(xy 108.318038 -242.791202) (xy 108.325933 -242.839779) (xy 108.326428 -242.864386) (xy 108.325933 -242.888993)
			(xy 108.318038 -242.93757) (xy 108.302454 -242.984251) (xy 108.279583 -243.027828) (xy 108.250018 -243.067172)
			(xy 108.214525 -243.101264) (xy 108.174022 -243.12922) (xy 108.12956 -243.150318) (xy 108.082289 -243.16401)
			(xy 108.033434 -243.169942) (xy 107.984259 -243.167961) (xy 107.93604 -243.158117) (xy 107.890024 -243.140665)
			(xy 107.847403 -243.116058) (xy 107.809282 -243.084933) (xy 107.776647 -243.048096) (xy 107.750344 -243.0065)
			(xy 107.731053 -242.961224) (xy 107.719276 -242.91344) (xy 107.715316 -242.864386) (xy 107.396788 -242.864386)
			(xy 107.396276 -242.889832) (xy 107.388112 -242.940066) (xy 107.371996 -242.98834) (xy 107.348345 -243.033403)
			(xy 107.317772 -243.074089) (xy 107.281068 -243.109344) (xy 107.239184 -243.138254) (xy 107.193205 -243.160071)
			(xy 107.144321 -243.174231) (xy 107.0938 -243.180365) (xy 107.042948 -243.178316) (xy 106.993084 -243.168136)
			(xy 106.945498 -243.150089) (xy 106.901424 -243.124643) (xy 106.862002 -243.092456) (xy 106.828254 -243.054362)
			(xy 106.801053 -243.011348) (xy 106.781105 -242.964528) (xy 106.768926 -242.915114) (xy 106.764831 -242.864386)
			(xy 106.456734 -242.864386) (xy 106.456222 -242.889832) (xy 106.448058 -242.940066) (xy 106.431942 -242.98834)
			(xy 106.408291 -243.033403) (xy 106.377718 -243.074089) (xy 106.341014 -243.109344) (xy 106.29913 -243.138254)
			(xy 106.253151 -243.160071) (xy 106.204267 -243.174231) (xy 106.153746 -243.180365) (xy 106.102894 -243.178316)
			(xy 106.05303 -243.168136) (xy 106.005444 -243.150089) (xy 105.96137 -243.124643) (xy 105.921948 -243.092456)
			(xy 105.8882 -243.054362) (xy 105.860999 -243.011348) (xy 105.841051 -242.964528) (xy 105.828872 -242.915114)
			(xy 105.824777 -242.864386) (xy 105.506266 -242.864386) (xy 105.505771 -242.888993) (xy 105.497876 -242.93757)
			(xy 105.482292 -242.984251) (xy 105.459421 -243.027828) (xy 105.429856 -243.067172) (xy 105.394363 -243.101264)
			(xy 105.35386 -243.12922) (xy 105.309398 -243.150318) (xy 105.262127 -243.16401) (xy 105.213272 -243.169942)
			(xy 105.164097 -243.167961) (xy 105.115878 -243.158117) (xy 105.069862 -243.140665) (xy 105.027241 -243.116058)
			(xy 104.98912 -243.084933) (xy 104.956485 -243.048096) (xy 104.930182 -243.0065) (xy 104.910891 -242.961224)
			(xy 104.899114 -242.91344) (xy 104.895154 -242.864386) (xy 104.57688 -242.864386) (xy 104.576368 -242.889832)
			(xy 104.568204 -242.940066) (xy 104.552088 -242.98834) (xy 104.528437 -243.033403) (xy 104.497864 -243.074089)
			(xy 104.46116 -243.109344) (xy 104.419276 -243.138254) (xy 104.373297 -243.160071) (xy 104.324413 -243.174231)
			(xy 104.273892 -243.180365) (xy 104.22304 -243.178316) (xy 104.173176 -243.168136) (xy 104.12559 -243.150089)
			(xy 104.081516 -243.124643) (xy 104.042094 -243.092456) (xy 104.008346 -243.054362) (xy 103.981145 -243.011348)
			(xy 103.961197 -242.964528) (xy 103.949018 -242.915114) (xy 103.944923 -242.864386) (xy 103.636826 -242.864386)
			(xy 103.636314 -242.889832) (xy 103.62815 -242.940066) (xy 103.612034 -242.98834) (xy 103.588383 -243.033403)
			(xy 103.55781 -243.074089) (xy 103.521106 -243.109344) (xy 103.479222 -243.138254) (xy 103.433243 -243.160071)
			(xy 103.384359 -243.174231) (xy 103.333838 -243.180365) (xy 103.282986 -243.178316) (xy 103.233122 -243.168136)
			(xy 103.185536 -243.150089) (xy 103.141462 -243.124643) (xy 103.10204 -243.092456) (xy 103.068292 -243.054362)
			(xy 103.041091 -243.011348) (xy 103.021143 -242.964528) (xy 103.008964 -242.915114) (xy 103.004869 -242.864386)
			(xy 102.686358 -242.864386) (xy 102.685863 -242.888993) (xy 102.677968 -242.93757) (xy 102.662384 -242.984251)
			(xy 102.639513 -243.027828) (xy 102.609948 -243.067172) (xy 102.574455 -243.101264) (xy 102.533952 -243.12922)
			(xy 102.48949 -243.150318) (xy 102.442219 -243.16401) (xy 102.393364 -243.169942) (xy 102.344189 -243.167961)
			(xy 102.29597 -243.158117) (xy 102.249954 -243.140665) (xy 102.207333 -243.116058) (xy 102.169212 -243.084933)
			(xy 102.136577 -243.048096) (xy 102.110274 -243.0065) (xy 102.090983 -242.961224) (xy 102.079206 -242.91344)
			(xy 102.075246 -242.864386) (xy 101.756718 -242.864386) (xy 101.756206 -242.889832) (xy 101.748042 -242.940066)
			(xy 101.731926 -242.98834) (xy 101.708275 -243.033403) (xy 101.677702 -243.074089) (xy 101.640998 -243.109344)
			(xy 101.599114 -243.138254) (xy 101.553135 -243.160071) (xy 101.504251 -243.174231) (xy 101.45373 -243.180365)
			(xy 101.402878 -243.178316) (xy 101.353014 -243.168136) (xy 101.305428 -243.150089) (xy 101.261354 -243.124643)
			(xy 101.221932 -243.092456) (xy 101.188184 -243.054362) (xy 101.160983 -243.011348) (xy 101.141035 -242.964528)
			(xy 101.128856 -242.915114) (xy 101.124761 -242.864386) (xy 100.816664 -242.864386) (xy 100.816152 -242.889832)
			(xy 100.807988 -242.940066) (xy 100.791872 -242.98834) (xy 100.768221 -243.033403) (xy 100.737648 -243.074089)
			(xy 100.700944 -243.109344) (xy 100.65906 -243.138254) (xy 100.613081 -243.160071) (xy 100.564197 -243.174231)
			(xy 100.513676 -243.180365) (xy 100.462824 -243.178316) (xy 100.41296 -243.168136) (xy 100.365374 -243.150089)
			(xy 100.3213 -243.124643) (xy 100.281878 -243.092456) (xy 100.24813 -243.054362) (xy 100.220929 -243.011348)
			(xy 100.200981 -242.964528) (xy 100.188802 -242.915114) (xy 100.184707 -242.864386) (xy 99.86645 -242.864386)
			(xy 99.865955 -242.888993) (xy 99.85806 -242.93757) (xy 99.842476 -242.984251) (xy 99.819605 -243.027828)
			(xy 99.79004 -243.067172) (xy 99.754547 -243.101264) (xy 99.714044 -243.12922) (xy 99.669582 -243.150318)
			(xy 99.622311 -243.16401) (xy 99.573456 -243.169942) (xy 99.524281 -243.167961) (xy 99.476062 -243.158117)
			(xy 99.430046 -243.140665) (xy 99.387425 -243.116058) (xy 99.349304 -243.084933) (xy 99.316669 -243.048096)
			(xy 99.290366 -243.0065) (xy 99.271075 -242.961224) (xy 99.259298 -242.91344) (xy 99.255338 -242.864386)
			(xy 98.93681 -242.864386) (xy 98.936298 -242.889832) (xy 98.928134 -242.940066) (xy 98.912018 -242.98834)
			(xy 98.888367 -243.033403) (xy 98.857794 -243.074089) (xy 98.82109 -243.109344) (xy 98.779206 -243.138254)
			(xy 98.733227 -243.160071) (xy 98.684343 -243.174231) (xy 98.633822 -243.180365) (xy 98.58297 -243.178316)
			(xy 98.533106 -243.168136) (xy 98.48552 -243.150089) (xy 98.441446 -243.124643) (xy 98.402024 -243.092456)
			(xy 98.368276 -243.054362) (xy 98.341075 -243.011348) (xy 98.321127 -242.964528) (xy 98.308948 -242.915114)
			(xy 98.304853 -242.864386) (xy 97.996756 -242.864386) (xy 97.996244 -242.889832) (xy 97.98808 -242.940066)
			(xy 97.971964 -242.98834) (xy 97.948313 -243.033403) (xy 97.91774 -243.074089) (xy 97.881036 -243.109344)
			(xy 97.839152 -243.138254) (xy 97.793173 -243.160071) (xy 97.744289 -243.174231) (xy 97.693768 -243.180365)
			(xy 97.642916 -243.178316) (xy 97.593052 -243.168136) (xy 97.545466 -243.150089) (xy 97.501392 -243.124643)
			(xy 97.46197 -243.092456) (xy 97.428222 -243.054362) (xy 97.401021 -243.011348) (xy 97.381073 -242.964528)
			(xy 97.368894 -242.915114) (xy 97.364799 -242.864386) (xy 97.046288 -242.864386) (xy 97.045793 -242.888993)
			(xy 97.037898 -242.93757) (xy 97.022314 -242.984251) (xy 96.999443 -243.027828) (xy 96.969878 -243.067172)
			(xy 96.934385 -243.101264) (xy 96.893882 -243.12922) (xy 96.84942 -243.150318) (xy 96.802149 -243.16401)
			(xy 96.753294 -243.169942) (xy 96.704119 -243.167961) (xy 96.6559 -243.158117) (xy 96.609884 -243.140665)
			(xy 96.567263 -243.116058) (xy 96.529142 -243.084933) (xy 96.496507 -243.048096) (xy 96.470204 -243.0065)
			(xy 96.450913 -242.961224) (xy 96.439136 -242.91344) (xy 96.435176 -242.864386) (xy 96.116648 -242.864386)
			(xy 96.116136 -242.889832) (xy 96.107972 -242.940066) (xy 96.091856 -242.98834) (xy 96.068205 -243.033403)
			(xy 96.037632 -243.074089) (xy 96.000928 -243.109344) (xy 95.959044 -243.138254) (xy 95.913065 -243.160071)
			(xy 95.864181 -243.174231) (xy 95.81366 -243.180365) (xy 95.762808 -243.178316) (xy 95.712944 -243.168136)
			(xy 95.665358 -243.150089) (xy 95.621284 -243.124643) (xy 95.581862 -243.092456) (xy 95.548114 -243.054362)
			(xy 95.520913 -243.011348) (xy 95.500965 -242.964528) (xy 95.488786 -242.915114) (xy 95.484691 -242.864386)
			(xy 95.166434 -242.864386) (xy 95.165939 -242.888993) (xy 95.158044 -242.93757) (xy 95.14246 -242.984251)
			(xy 95.119589 -243.027828) (xy 95.090024 -243.067172) (xy 95.054531 -243.101264) (xy 95.014028 -243.12922)
			(xy 94.969566 -243.150318) (xy 94.922295 -243.16401) (xy 94.87344 -243.169942) (xy 94.824265 -243.167961)
			(xy 94.776046 -243.158117) (xy 94.73003 -243.140665) (xy 94.687409 -243.116058) (xy 94.649288 -243.084933)
			(xy 94.616653 -243.048096) (xy 94.59035 -243.0065) (xy 94.571059 -242.961224) (xy 94.559282 -242.91344)
			(xy 94.555322 -242.864386) (xy 94.236794 -242.864386) (xy 94.236282 -242.889832) (xy 94.228118 -242.940066)
			(xy 94.212002 -242.98834) (xy 94.188351 -243.033403) (xy 94.157778 -243.074089) (xy 94.121074 -243.109344)
			(xy 94.07919 -243.138254) (xy 94.033211 -243.160071) (xy 93.984327 -243.174231) (xy 93.933806 -243.180365)
			(xy 93.882954 -243.178316) (xy 93.83309 -243.168136) (xy 93.785504 -243.150089) (xy 93.74143 -243.124643)
			(xy 93.702008 -243.092456) (xy 93.66826 -243.054362) (xy 93.641059 -243.011348) (xy 93.621111 -242.964528)
			(xy 93.608932 -242.915114) (xy 93.604837 -242.864386) (xy 93.286326 -242.864386) (xy 93.285831 -242.888993)
			(xy 93.277936 -242.93757) (xy 93.262352 -242.984251) (xy 93.239481 -243.027828) (xy 93.209916 -243.067172)
			(xy 93.174423 -243.101264) (xy 93.13392 -243.12922) (xy 93.089458 -243.150318) (xy 93.042187 -243.16401)
			(xy 92.993332 -243.169942) (xy 92.944157 -243.167961) (xy 92.895938 -243.158117) (xy 92.849922 -243.140665)
			(xy 92.807301 -243.116058) (xy 92.76918 -243.084933) (xy 92.736545 -243.048096) (xy 92.710242 -243.0065)
			(xy 92.690951 -242.961224) (xy 92.679174 -242.91344) (xy 92.675214 -242.864386) (xy 92.356686 -242.864386)
			(xy 92.356174 -242.889832) (xy 92.34801 -242.940066) (xy 92.331894 -242.98834) (xy 92.308243 -243.033403)
			(xy 92.27767 -243.074089) (xy 92.240966 -243.109344) (xy 92.199082 -243.138254) (xy 92.153103 -243.160071)
			(xy 92.104219 -243.174231) (xy 92.053698 -243.180365) (xy 92.002846 -243.178316) (xy 91.952982 -243.168136)
			(xy 91.905396 -243.150089) (xy 91.861322 -243.124643) (xy 91.8219 -243.092456) (xy 91.788152 -243.054362)
			(xy 91.760951 -243.011348) (xy 91.741003 -242.964528) (xy 91.728824 -242.915114) (xy 91.724729 -242.864386)
			(xy 91.416632 -242.864386) (xy 91.41612 -242.889832) (xy 91.407956 -242.940066) (xy 91.39184 -242.98834)
			(xy 91.368189 -243.033403) (xy 91.337616 -243.074089) (xy 91.300912 -243.109344) (xy 91.259028 -243.138254)
			(xy 91.213049 -243.160071) (xy 91.164165 -243.174231) (xy 91.113644 -243.180365) (xy 91.062792 -243.178316)
			(xy 91.012928 -243.168136) (xy 90.965342 -243.150089) (xy 90.921268 -243.124643) (xy 90.881846 -243.092456)
			(xy 90.848098 -243.054362) (xy 90.820897 -243.011348) (xy 90.800949 -242.964528) (xy 90.78877 -242.915114)
			(xy 90.784675 -242.864386) (xy 90.466418 -242.864386) (xy 90.465923 -242.888993) (xy 90.458028 -242.93757)
			(xy 90.442444 -242.984251) (xy 90.419573 -243.027828) (xy 90.390008 -243.067172) (xy 90.354515 -243.101264)
			(xy 90.314012 -243.12922) (xy 90.26955 -243.150318) (xy 90.222279 -243.16401) (xy 90.173424 -243.169942)
			(xy 90.124249 -243.167961) (xy 90.07603 -243.158117) (xy 90.030014 -243.140665) (xy 89.987393 -243.116058)
			(xy 89.949272 -243.084933) (xy 89.916637 -243.048096) (xy 89.890334 -243.0065) (xy 89.871043 -242.961224)
			(xy 89.859266 -242.91344) (xy 89.855306 -242.864386) (xy 89.536778 -242.864386) (xy 89.536266 -242.889832)
			(xy 89.528102 -242.940066) (xy 89.511986 -242.98834) (xy 89.488335 -243.033403) (xy 89.457762 -243.074089)
			(xy 89.421058 -243.109344) (xy 89.379174 -243.138254) (xy 89.333195 -243.160071) (xy 89.284311 -243.174231)
			(xy 89.23379 -243.180365) (xy 89.182938 -243.178316) (xy 89.133074 -243.168136) (xy 89.085488 -243.150089)
			(xy 89.041414 -243.124643) (xy 89.001992 -243.092456) (xy 88.968244 -243.054362) (xy 88.941043 -243.011348)
			(xy 88.921095 -242.964528) (xy 88.908916 -242.915114) (xy 88.904821 -242.864386) (xy 88.58631 -242.864386)
			(xy 88.585815 -242.888993) (xy 88.57792 -242.93757) (xy 88.562336 -242.984251) (xy 88.539465 -243.027828)
			(xy 88.5099 -243.067172) (xy 88.474407 -243.101264) (xy 88.433904 -243.12922) (xy 88.389442 -243.150318)
			(xy 88.342171 -243.16401) (xy 88.293316 -243.169942) (xy 88.244141 -243.167961) (xy 88.195922 -243.158117)
			(xy 88.149906 -243.140665) (xy 88.107285 -243.116058) (xy 88.069164 -243.084933) (xy 88.036529 -243.048096)
			(xy 88.010226 -243.0065) (xy 87.990935 -242.961224) (xy 87.979158 -242.91344) (xy 87.975198 -242.864386)
			(xy 87.65667 -242.864386) (xy 87.656158 -242.889832) (xy 87.647994 -242.940066) (xy 87.631878 -242.98834)
			(xy 87.608227 -243.033403) (xy 87.577654 -243.074089) (xy 87.54095 -243.109344) (xy 87.499066 -243.138254)
			(xy 87.453087 -243.160071) (xy 87.404203 -243.174231) (xy 87.353682 -243.180365) (xy 87.30283 -243.178316)
			(xy 87.252966 -243.168136) (xy 87.20538 -243.150089) (xy 87.161306 -243.124643) (xy 87.121884 -243.092456)
			(xy 87.088136 -243.054362) (xy 87.060935 -243.011348) (xy 87.040987 -242.964528) (xy 87.028808 -242.915114)
			(xy 87.024713 -242.864386) (xy 86.706456 -242.864386) (xy 86.705961 -242.888993) (xy 86.698066 -242.93757)
			(xy 86.682482 -242.984251) (xy 86.659611 -243.027828) (xy 86.630046 -243.067172) (xy 86.594553 -243.101264)
			(xy 86.55405 -243.12922) (xy 86.509588 -243.150318) (xy 86.462317 -243.16401) (xy 86.413462 -243.169942)
			(xy 86.364287 -243.167961) (xy 86.316068 -243.158117) (xy 86.270052 -243.140665) (xy 86.227431 -243.116058)
			(xy 86.18931 -243.084933) (xy 86.156675 -243.048096) (xy 86.130372 -243.0065) (xy 86.111081 -242.961224)
			(xy 86.099304 -242.91344) (xy 86.095344 -242.864386) (xy 85.776816 -242.864386) (xy 85.776304 -242.889832)
			(xy 85.76814 -242.940066) (xy 85.752024 -242.98834) (xy 85.728373 -243.033403) (xy 85.6978 -243.074089)
			(xy 85.661096 -243.109344) (xy 85.619212 -243.138254) (xy 85.573233 -243.160071) (xy 85.524349 -243.174231)
			(xy 85.473828 -243.180365) (xy 85.422976 -243.178316) (xy 85.373112 -243.168136) (xy 85.325526 -243.150089)
			(xy 85.281452 -243.124643) (xy 85.24203 -243.092456) (xy 85.208282 -243.054362) (xy 85.181081 -243.011348)
			(xy 85.161133 -242.964528) (xy 85.148954 -242.915114) (xy 85.144859 -242.864386) (xy 84.836762 -242.864386)
			(xy 84.83625 -242.889832) (xy 84.828086 -242.940066) (xy 84.81197 -242.98834) (xy 84.788319 -243.033403)
			(xy 84.757746 -243.074089) (xy 84.721042 -243.109344) (xy 84.679158 -243.138254) (xy 84.633179 -243.160071)
			(xy 84.584295 -243.174231) (xy 84.533774 -243.180365) (xy 84.482922 -243.178316) (xy 84.433058 -243.168136)
			(xy 84.385472 -243.150089) (xy 84.341398 -243.124643) (xy 84.301976 -243.092456) (xy 84.268228 -243.054362)
			(xy 84.241027 -243.011348) (xy 84.221079 -242.964528) (xy 84.2089 -242.915114) (xy 84.204805 -242.864386)
			(xy 83.886294 -242.864386) (xy 83.885799 -242.888993) (xy 83.877904 -242.93757) (xy 83.86232 -242.984251)
			(xy 83.839449 -243.027828) (xy 83.809884 -243.067172) (xy 83.774391 -243.101264) (xy 83.733888 -243.12922)
			(xy 83.689426 -243.150318) (xy 83.642155 -243.16401) (xy 83.5933 -243.169942) (xy 83.544125 -243.167961)
			(xy 83.495906 -243.158117) (xy 83.44989 -243.140665) (xy 83.407269 -243.116058) (xy 83.369148 -243.084933)
			(xy 83.336513 -243.048096) (xy 83.31021 -243.0065) (xy 83.290919 -242.961224) (xy 83.279142 -242.91344)
			(xy 83.275182 -242.864386) (xy 82.956654 -242.864386) (xy 82.956142 -242.889832) (xy 82.947978 -242.940066)
			(xy 82.931862 -242.98834) (xy 82.908211 -243.033403) (xy 82.877638 -243.074089) (xy 82.840934 -243.109344)
			(xy 82.79905 -243.138254) (xy 82.753071 -243.160071) (xy 82.704187 -243.174231) (xy 82.653666 -243.180365)
			(xy 82.602814 -243.178316) (xy 82.55295 -243.168136) (xy 82.505364 -243.150089) (xy 82.46129 -243.124643)
			(xy 82.421868 -243.092456) (xy 82.38812 -243.054362) (xy 82.360919 -243.011348) (xy 82.340971 -242.964528)
			(xy 82.328792 -242.915114) (xy 82.324697 -242.864386) (xy 82.00644 -242.864386) (xy 82.005945 -242.888993)
			(xy 81.99805 -242.93757) (xy 81.982466 -242.984251) (xy 81.959595 -243.027828) (xy 81.93003 -243.067172)
			(xy 81.894537 -243.101264) (xy 81.854034 -243.12922) (xy 81.809572 -243.150318) (xy 81.762301 -243.16401)
			(xy 81.713446 -243.169942) (xy 81.664271 -243.167961) (xy 81.616052 -243.158117) (xy 81.570036 -243.140665)
			(xy 81.527415 -243.116058) (xy 81.489294 -243.084933) (xy 81.456659 -243.048096) (xy 81.430356 -243.0065)
			(xy 81.411065 -242.961224) (xy 81.399288 -242.91344) (xy 81.395328 -242.864386) (xy 81.0768 -242.864386)
			(xy 81.076288 -242.889832) (xy 81.068124 -242.940066) (xy 81.052008 -242.98834) (xy 81.028357 -243.033403)
			(xy 80.997784 -243.074089) (xy 80.96108 -243.109344) (xy 80.919196 -243.138254) (xy 80.873217 -243.160071)
			(xy 80.824333 -243.174231) (xy 80.773812 -243.180365) (xy 80.72296 -243.178316) (xy 80.673096 -243.168136)
			(xy 80.62551 -243.150089) (xy 80.581436 -243.124643) (xy 80.542014 -243.092456) (xy 80.508266 -243.054362)
			(xy 80.481065 -243.011348) (xy 80.461117 -242.964528) (xy 80.448938 -242.915114) (xy 80.444843 -242.864386)
			(xy 80.126332 -242.864386) (xy 80.125837 -242.888993) (xy 80.117942 -242.93757) (xy 80.102358 -242.984251)
			(xy 80.079487 -243.027828) (xy 80.049922 -243.067172) (xy 80.014429 -243.101264) (xy 79.973926 -243.12922)
			(xy 79.929464 -243.150318) (xy 79.882193 -243.16401) (xy 79.833338 -243.169942) (xy 79.784163 -243.167961)
			(xy 79.735944 -243.158117) (xy 79.689928 -243.140665) (xy 79.647307 -243.116058) (xy 79.609186 -243.084933)
			(xy 79.576551 -243.048096) (xy 79.550248 -243.0065) (xy 79.530957 -242.961224) (xy 79.51918 -242.91344)
			(xy 79.51522 -242.864386) (xy 76.963477 -242.864386) (xy 76.965804 -242.86549) (xy 77.006307 -242.893446)
			(xy 77.0418 -242.927538) (xy 77.071365 -242.966882) (xy 77.094236 -243.010459) (xy 77.10982 -243.05714)
			(xy 77.117715 -243.105717) (xy 77.11821 -243.130324) (xy 77.117715 -243.154931) (xy 77.10982 -243.203508)
			(xy 77.094236 -243.250189) (xy 77.071365 -243.293766) (xy 77.0418 -243.33311) (xy 77.006307 -243.367202)
			(xy 76.965804 -243.395158) (xy 76.921342 -243.416256) (xy 76.874071 -243.429948) (xy 76.825216 -243.43588)
			(xy 76.776041 -243.433899) (xy 76.727822 -243.424055) (xy 76.681806 -243.406603) (xy 76.639185 -243.381996)
			(xy 76.601064 -243.350871) (xy 76.568429 -243.314034) (xy 76.542126 -243.272438) (xy 76.522835 -243.227162)
			(xy 76.511058 -243.179378) (xy 76.507098 -243.130324) (xy 62.37732 -243.130324) (xy 62.37732 -243.674392)
			(xy 78.105266 -243.674392) (xy 78.109226 -243.625338) (xy 78.121003 -243.577554) (xy 78.140294 -243.532278)
			(xy 78.166597 -243.490682) (xy 78.199232 -243.453845) (xy 78.237353 -243.42272) (xy 78.279974 -243.398113)
			(xy 78.32599 -243.380661) (xy 78.374209 -243.370817) (xy 78.423384 -243.368836) (xy 78.472239 -243.374768)
			(xy 78.51951 -243.38846) (xy 78.563972 -243.409558) (xy 78.604475 -243.437514) (xy 78.639968 -243.471606)
			(xy 78.669533 -243.51095) (xy 78.692404 -243.554527) (xy 78.707988 -243.601208) (xy 78.715883 -243.649785)
			(xy 78.716378 -243.674392) (xy 79.985374 -243.674392) (xy 79.989334 -243.625338) (xy 80.001111 -243.577554)
			(xy 80.020402 -243.532278) (xy 80.046705 -243.490682) (xy 80.07934 -243.453845) (xy 80.117461 -243.42272)
			(xy 80.160082 -243.398113) (xy 80.206098 -243.380661) (xy 80.254317 -243.370817) (xy 80.303492 -243.368836)
			(xy 80.352347 -243.374768) (xy 80.399618 -243.38846) (xy 80.44408 -243.409558) (xy 80.484583 -243.437514)
			(xy 80.520076 -243.471606) (xy 80.549641 -243.51095) (xy 80.572512 -243.554527) (xy 80.588096 -243.601208)
			(xy 80.595991 -243.649785) (xy 80.596486 -243.674392) (xy 80.914743 -243.674392) (xy 80.918838 -243.623664)
			(xy 80.931017 -243.57425) (xy 80.950965 -243.52743) (xy 80.978166 -243.484416) (xy 81.011914 -243.446322)
			(xy 81.051336 -243.414135) (xy 81.09541 -243.388689) (xy 81.142996 -243.370642) (xy 81.19286 -243.360462)
			(xy 81.243712 -243.358413) (xy 81.294233 -243.364547) (xy 81.343117 -243.378707) (xy 81.389096 -243.400524)
			(xy 81.43098 -243.429434) (xy 81.467684 -243.464689) (xy 81.498257 -243.505375) (xy 81.521908 -243.550438)
			(xy 81.538024 -243.598712) (xy 81.546188 -243.648946) (xy 81.5467 -243.674392) (xy 81.854797 -243.674392)
			(xy 81.858892 -243.623664) (xy 81.871071 -243.57425) (xy 81.891019 -243.52743) (xy 81.91822 -243.484416)
			(xy 81.951968 -243.446322) (xy 81.99139 -243.414135) (xy 82.035464 -243.388689) (xy 82.08305 -243.370642)
			(xy 82.132914 -243.360462) (xy 82.183766 -243.358413) (xy 82.234287 -243.364547) (xy 82.283171 -243.378707)
			(xy 82.32915 -243.400524) (xy 82.371034 -243.429434) (xy 82.407738 -243.464689) (xy 82.438311 -243.505375)
			(xy 82.461962 -243.550438) (xy 82.478078 -243.598712) (xy 82.486242 -243.648946) (xy 82.486754 -243.674392)
			(xy 82.805282 -243.674392) (xy 82.809242 -243.625338) (xy 82.821019 -243.577554) (xy 82.84031 -243.532278)
			(xy 82.866613 -243.490682) (xy 82.899248 -243.453845) (xy 82.937369 -243.42272) (xy 82.97999 -243.398113)
			(xy 83.026006 -243.380661) (xy 83.074225 -243.370817) (xy 83.1234 -243.368836) (xy 83.172255 -243.374768)
			(xy 83.219526 -243.38846) (xy 83.263988 -243.409558) (xy 83.304491 -243.437514) (xy 83.339984 -243.471606)
			(xy 83.369549 -243.51095) (xy 83.39242 -243.554527) (xy 83.408004 -243.601208) (xy 83.415899 -243.649785)
			(xy 83.416394 -243.674392) (xy 83.734905 -243.674392) (xy 83.739 -243.623664) (xy 83.751179 -243.57425)
			(xy 83.771127 -243.52743) (xy 83.798328 -243.484416) (xy 83.832076 -243.446322) (xy 83.871498 -243.414135)
			(xy 83.915572 -243.388689) (xy 83.963158 -243.370642) (xy 84.013022 -243.360462) (xy 84.063874 -243.358413)
			(xy 84.114395 -243.364547) (xy 84.163279 -243.378707) (xy 84.209258 -243.400524) (xy 84.251142 -243.429434)
			(xy 84.287846 -243.464689) (xy 84.318419 -243.505375) (xy 84.34207 -243.550438) (xy 84.358186 -243.598712)
			(xy 84.36635 -243.648946) (xy 84.366862 -243.674392) (xy 84.685136 -243.674392) (xy 84.689096 -243.625338)
			(xy 84.700873 -243.577554) (xy 84.720164 -243.532278) (xy 84.746467 -243.490682) (xy 84.779102 -243.453845)
			(xy 84.817223 -243.42272) (xy 84.859844 -243.398113) (xy 84.90586 -243.380661) (xy 84.954079 -243.370817)
			(xy 85.003254 -243.368836) (xy 85.052109 -243.374768) (xy 85.09938 -243.38846) (xy 85.143842 -243.409558)
			(xy 85.184345 -243.437514) (xy 85.219838 -243.471606) (xy 85.249403 -243.51095) (xy 85.272274 -243.554527)
			(xy 85.287858 -243.601208) (xy 85.295753 -243.649785) (xy 85.296248 -243.674392) (xy 85.614759 -243.674392)
			(xy 85.618854 -243.623664) (xy 85.631033 -243.57425) (xy 85.650981 -243.52743) (xy 85.678182 -243.484416)
			(xy 85.71193 -243.446322) (xy 85.751352 -243.414135) (xy 85.795426 -243.388689) (xy 85.843012 -243.370642)
			(xy 85.892876 -243.360462) (xy 85.943728 -243.358413) (xy 85.994249 -243.364547) (xy 86.043133 -243.378707)
			(xy 86.089112 -243.400524) (xy 86.130996 -243.429434) (xy 86.1677 -243.464689) (xy 86.198273 -243.505375)
			(xy 86.221924 -243.550438) (xy 86.23804 -243.598712) (xy 86.246204 -243.648946) (xy 86.246716 -243.674392)
			(xy 86.565244 -243.674392) (xy 86.569204 -243.625338) (xy 86.580981 -243.577554) (xy 86.600272 -243.532278)
			(xy 86.626575 -243.490682) (xy 86.65921 -243.453845) (xy 86.697331 -243.42272) (xy 86.739952 -243.398113)
			(xy 86.785968 -243.380661) (xy 86.834187 -243.370817) (xy 86.883362 -243.368836) (xy 86.932217 -243.374768)
			(xy 86.979488 -243.38846) (xy 87.02395 -243.409558) (xy 87.064453 -243.437514) (xy 87.099946 -243.471606)
			(xy 87.129511 -243.51095) (xy 87.152382 -243.554527) (xy 87.167966 -243.601208) (xy 87.175861 -243.649785)
			(xy 87.176356 -243.674392) (xy 87.494867 -243.674392) (xy 87.498962 -243.623664) (xy 87.511141 -243.57425)
			(xy 87.531089 -243.52743) (xy 87.55829 -243.484416) (xy 87.592038 -243.446322) (xy 87.63146 -243.414135)
			(xy 87.675534 -243.388689) (xy 87.72312 -243.370642) (xy 87.772984 -243.360462) (xy 87.823836 -243.358413)
			(xy 87.874357 -243.364547) (xy 87.923241 -243.378707) (xy 87.96922 -243.400524) (xy 88.011104 -243.429434)
			(xy 88.047808 -243.464689) (xy 88.078381 -243.505375) (xy 88.102032 -243.550438) (xy 88.118148 -243.598712)
			(xy 88.126312 -243.648946) (xy 88.126824 -243.674392) (xy 88.434921 -243.674392) (xy 88.439016 -243.623664)
			(xy 88.451195 -243.57425) (xy 88.471143 -243.52743) (xy 88.498344 -243.484416) (xy 88.532092 -243.446322)
			(xy 88.571514 -243.414135) (xy 88.615588 -243.388689) (xy 88.663174 -243.370642) (xy 88.713038 -243.360462)
			(xy 88.76389 -243.358413) (xy 88.814411 -243.364547) (xy 88.863295 -243.378707) (xy 88.909274 -243.400524)
			(xy 88.951158 -243.429434) (xy 88.987862 -243.464689) (xy 89.018435 -243.505375) (xy 89.042086 -243.550438)
			(xy 89.058202 -243.598712) (xy 89.066366 -243.648946) (xy 89.066878 -243.674392) (xy 89.385152 -243.674392)
			(xy 89.389112 -243.625338) (xy 89.400889 -243.577554) (xy 89.42018 -243.532278) (xy 89.446483 -243.490682)
			(xy 89.479118 -243.453845) (xy 89.517239 -243.42272) (xy 89.55986 -243.398113) (xy 89.605876 -243.380661)
			(xy 89.654095 -243.370817) (xy 89.70327 -243.368836) (xy 89.752125 -243.374768) (xy 89.799396 -243.38846)
			(xy 89.843858 -243.409558) (xy 89.884361 -243.437514) (xy 89.919854 -243.471606) (xy 89.949419 -243.51095)
			(xy 89.97229 -243.554527) (xy 89.987874 -243.601208) (xy 89.995769 -243.649785) (xy 89.996264 -243.674392)
			(xy 90.314775 -243.674392) (xy 90.31887 -243.623664) (xy 90.331049 -243.57425) (xy 90.350997 -243.52743)
			(xy 90.378198 -243.484416) (xy 90.411946 -243.446322) (xy 90.451368 -243.414135) (xy 90.495442 -243.388689)
			(xy 90.543028 -243.370642) (xy 90.592892 -243.360462) (xy 90.643744 -243.358413) (xy 90.694265 -243.364547)
			(xy 90.743149 -243.378707) (xy 90.789128 -243.400524) (xy 90.831012 -243.429434) (xy 90.867716 -243.464689)
			(xy 90.898289 -243.505375) (xy 90.92194 -243.550438) (xy 90.938056 -243.598712) (xy 90.94622 -243.648946)
			(xy 90.946732 -243.674392) (xy 91.26526 -243.674392) (xy 91.26922 -243.625338) (xy 91.280997 -243.577554)
			(xy 91.300288 -243.532278) (xy 91.326591 -243.490682) (xy 91.359226 -243.453845) (xy 91.397347 -243.42272)
			(xy 91.439968 -243.398113) (xy 91.485984 -243.380661) (xy 91.534203 -243.370817) (xy 91.583378 -243.368836)
			(xy 91.632233 -243.374768) (xy 91.679504 -243.38846) (xy 91.723966 -243.409558) (xy 91.764469 -243.437514)
			(xy 91.799962 -243.471606) (xy 91.829527 -243.51095) (xy 91.852398 -243.554527) (xy 91.867982 -243.601208)
			(xy 91.875877 -243.649785) (xy 91.876372 -243.674392) (xy 92.194883 -243.674392) (xy 92.198978 -243.623664)
			(xy 92.211157 -243.57425) (xy 92.231105 -243.52743) (xy 92.258306 -243.484416) (xy 92.292054 -243.446322)
			(xy 92.331476 -243.414135) (xy 92.37555 -243.388689) (xy 92.423136 -243.370642) (xy 92.473 -243.360462)
			(xy 92.523852 -243.358413) (xy 92.574373 -243.364547) (xy 92.623257 -243.378707) (xy 92.669236 -243.400524)
			(xy 92.71112 -243.429434) (xy 92.747824 -243.464689) (xy 92.778397 -243.505375) (xy 92.802048 -243.550438)
			(xy 92.818164 -243.598712) (xy 92.826328 -243.648946) (xy 92.82684 -243.674392) (xy 93.145114 -243.674392)
			(xy 93.149074 -243.625338) (xy 93.160851 -243.577554) (xy 93.180142 -243.532278) (xy 93.206445 -243.490682)
			(xy 93.23908 -243.453845) (xy 93.277201 -243.42272) (xy 93.319822 -243.398113) (xy 93.365838 -243.380661)
			(xy 93.414057 -243.370817) (xy 93.463232 -243.368836) (xy 93.512087 -243.374768) (xy 93.559358 -243.38846)
			(xy 93.60382 -243.409558) (xy 93.644323 -243.437514) (xy 93.679816 -243.471606) (xy 93.709381 -243.51095)
			(xy 93.732252 -243.554527) (xy 93.747836 -243.601208) (xy 93.755731 -243.649785) (xy 93.756226 -243.674392)
			(xy 94.074737 -243.674392) (xy 94.078832 -243.623664) (xy 94.091011 -243.57425) (xy 94.110959 -243.52743)
			(xy 94.13816 -243.484416) (xy 94.171908 -243.446322) (xy 94.21133 -243.414135) (xy 94.255404 -243.388689)
			(xy 94.30299 -243.370642) (xy 94.352854 -243.360462) (xy 94.403706 -243.358413) (xy 94.454227 -243.364547)
			(xy 94.503111 -243.378707) (xy 94.54909 -243.400524) (xy 94.590974 -243.429434) (xy 94.627678 -243.464689)
			(xy 94.658251 -243.505375) (xy 94.681902 -243.550438) (xy 94.698018 -243.598712) (xy 94.706182 -243.648946)
			(xy 94.706694 -243.674392) (xy 95.014791 -243.674392) (xy 95.018886 -243.623664) (xy 95.031065 -243.57425)
			(xy 95.051013 -243.52743) (xy 95.078214 -243.484416) (xy 95.111962 -243.446322) (xy 95.151384 -243.414135)
			(xy 95.195458 -243.388689) (xy 95.243044 -243.370642) (xy 95.292908 -243.360462) (xy 95.34376 -243.358413)
			(xy 95.394281 -243.364547) (xy 95.443165 -243.378707) (xy 95.489144 -243.400524) (xy 95.531028 -243.429434)
			(xy 95.567732 -243.464689) (xy 95.598305 -243.505375) (xy 95.621956 -243.550438) (xy 95.638072 -243.598712)
			(xy 95.646236 -243.648946) (xy 95.646748 -243.674392) (xy 95.965276 -243.674392) (xy 95.969236 -243.625338)
			(xy 95.981013 -243.577554) (xy 96.000304 -243.532278) (xy 96.026607 -243.490682) (xy 96.059242 -243.453845)
			(xy 96.097363 -243.42272) (xy 96.139984 -243.398113) (xy 96.186 -243.380661) (xy 96.234219 -243.370817)
			(xy 96.283394 -243.368836) (xy 96.332249 -243.374768) (xy 96.37952 -243.38846) (xy 96.423982 -243.409558)
			(xy 96.464485 -243.437514) (xy 96.499978 -243.471606) (xy 96.529543 -243.51095) (xy 96.552414 -243.554527)
			(xy 96.567998 -243.601208) (xy 96.575893 -243.649785) (xy 96.576388 -243.674392) (xy 96.90533 -243.674392)
			(xy 96.90929 -243.625338) (xy 96.921067 -243.577554) (xy 96.940358 -243.532278) (xy 96.966661 -243.490682)
			(xy 96.999296 -243.453845) (xy 97.037417 -243.42272) (xy 97.080038 -243.398113) (xy 97.126054 -243.380661)
			(xy 97.174273 -243.370817) (xy 97.223448 -243.368836) (xy 97.272303 -243.374768) (xy 97.319574 -243.38846)
			(xy 97.364036 -243.409558) (xy 97.404539 -243.437514) (xy 97.440032 -243.471606) (xy 97.469597 -243.51095)
			(xy 97.492468 -243.554527) (xy 97.508052 -243.601208) (xy 97.515947 -243.649785) (xy 97.516442 -243.674392)
			(xy 97.84513 -243.674392) (xy 97.84909 -243.625338) (xy 97.860867 -243.577554) (xy 97.880158 -243.532278)
			(xy 97.906461 -243.490682) (xy 97.939096 -243.453845) (xy 97.977217 -243.42272) (xy 98.019838 -243.398113)
			(xy 98.065854 -243.380661) (xy 98.114073 -243.370817) (xy 98.163248 -243.368836) (xy 98.212103 -243.374768)
			(xy 98.259374 -243.38846) (xy 98.303836 -243.409558) (xy 98.344339 -243.437514) (xy 98.379832 -243.471606)
			(xy 98.409397 -243.51095) (xy 98.432268 -243.554527) (xy 98.447852 -243.601208) (xy 98.455747 -243.649785)
			(xy 98.456242 -243.674392) (xy 98.785184 -243.674392) (xy 98.789144 -243.625338) (xy 98.800921 -243.577554)
			(xy 98.820212 -243.532278) (xy 98.846515 -243.490682) (xy 98.87915 -243.453845) (xy 98.917271 -243.42272)
			(xy 98.959892 -243.398113) (xy 99.005908 -243.380661) (xy 99.054127 -243.370817) (xy 99.103302 -243.368836)
			(xy 99.152157 -243.374768) (xy 99.199428 -243.38846) (xy 99.24389 -243.409558) (xy 99.284393 -243.437514)
			(xy 99.319886 -243.471606) (xy 99.349451 -243.51095) (xy 99.372322 -243.554527) (xy 99.387906 -243.601208)
			(xy 99.395801 -243.649785) (xy 99.396296 -243.674392) (xy 99.725238 -243.674392) (xy 99.729198 -243.625338)
			(xy 99.740975 -243.577554) (xy 99.760266 -243.532278) (xy 99.786569 -243.490682) (xy 99.819204 -243.453845)
			(xy 99.857325 -243.42272) (xy 99.899946 -243.398113) (xy 99.945962 -243.380661) (xy 99.994181 -243.370817)
			(xy 100.043356 -243.368836) (xy 100.092211 -243.374768) (xy 100.139482 -243.38846) (xy 100.183944 -243.409558)
			(xy 100.224447 -243.437514) (xy 100.25994 -243.471606) (xy 100.289505 -243.51095) (xy 100.312376 -243.554527)
			(xy 100.32796 -243.601208) (xy 100.335855 -243.649785) (xy 100.33635 -243.674392) (xy 100.665292 -243.674392)
			(xy 100.669252 -243.625338) (xy 100.681029 -243.577554) (xy 100.70032 -243.532278) (xy 100.726623 -243.490682)
			(xy 100.759258 -243.453845) (xy 100.797379 -243.42272) (xy 100.84 -243.398113) (xy 100.886016 -243.380661)
			(xy 100.934235 -243.370817) (xy 100.98341 -243.368836) (xy 101.032265 -243.374768) (xy 101.079536 -243.38846)
			(xy 101.123998 -243.409558) (xy 101.164501 -243.437514) (xy 101.199994 -243.471606) (xy 101.229559 -243.51095)
			(xy 101.25243 -243.554527) (xy 101.268014 -243.601208) (xy 101.275909 -243.649785) (xy 101.276404 -243.674392)
			(xy 101.605346 -243.674392) (xy 101.609306 -243.625338) (xy 101.621083 -243.577554) (xy 101.640374 -243.532278)
			(xy 101.666677 -243.490682) (xy 101.699312 -243.453845) (xy 101.737433 -243.42272) (xy 101.780054 -243.398113)
			(xy 101.82607 -243.380661) (xy 101.874289 -243.370817) (xy 101.923464 -243.368836) (xy 101.972319 -243.374768)
			(xy 102.01959 -243.38846) (xy 102.064052 -243.409558) (xy 102.104555 -243.437514) (xy 102.140048 -243.471606)
			(xy 102.169613 -243.51095) (xy 102.192484 -243.554527) (xy 102.208068 -243.601208) (xy 102.215963 -243.649785)
			(xy 102.216458 -243.674392) (xy 102.545146 -243.674392) (xy 102.549106 -243.625338) (xy 102.560883 -243.577554)
			(xy 102.580174 -243.532278) (xy 102.606477 -243.490682) (xy 102.639112 -243.453845) (xy 102.677233 -243.42272)
			(xy 102.719854 -243.398113) (xy 102.76587 -243.380661) (xy 102.814089 -243.370817) (xy 102.863264 -243.368836)
			(xy 102.912119 -243.374768) (xy 102.95939 -243.38846) (xy 103.003852 -243.409558) (xy 103.044355 -243.437514)
			(xy 103.079848 -243.471606) (xy 103.109413 -243.51095) (xy 103.132284 -243.554527) (xy 103.147868 -243.601208)
			(xy 103.155763 -243.649785) (xy 103.156258 -243.674392) (xy 103.4852 -243.674392) (xy 103.48916 -243.625338)
			(xy 103.500937 -243.577554) (xy 103.520228 -243.532278) (xy 103.546531 -243.490682) (xy 103.579166 -243.453845)
			(xy 103.617287 -243.42272) (xy 103.659908 -243.398113) (xy 103.705924 -243.380661) (xy 103.754143 -243.370817)
			(xy 103.803318 -243.368836) (xy 103.852173 -243.374768) (xy 103.899444 -243.38846) (xy 103.943906 -243.409558)
			(xy 103.984409 -243.437514) (xy 104.019902 -243.471606) (xy 104.049467 -243.51095) (xy 104.072338 -243.554527)
			(xy 104.087922 -243.601208) (xy 104.095817 -243.649785) (xy 104.096312 -243.674392) (xy 104.425254 -243.674392)
			(xy 104.429214 -243.625338) (xy 104.440991 -243.577554) (xy 104.460282 -243.532278) (xy 104.486585 -243.490682)
			(xy 104.51922 -243.453845) (xy 104.557341 -243.42272) (xy 104.599962 -243.398113) (xy 104.645978 -243.380661)
			(xy 104.694197 -243.370817) (xy 104.743372 -243.368836) (xy 104.792227 -243.374768) (xy 104.839498 -243.38846)
			(xy 104.88396 -243.409558) (xy 104.924463 -243.437514) (xy 104.959956 -243.471606) (xy 104.989521 -243.51095)
			(xy 105.012392 -243.554527) (xy 105.027976 -243.601208) (xy 105.035871 -243.649785) (xy 105.036366 -243.674392)
			(xy 105.365308 -243.674392) (xy 105.369268 -243.625338) (xy 105.381045 -243.577554) (xy 105.400336 -243.532278)
			(xy 105.426639 -243.490682) (xy 105.459274 -243.453845) (xy 105.497395 -243.42272) (xy 105.540016 -243.398113)
			(xy 105.586032 -243.380661) (xy 105.634251 -243.370817) (xy 105.683426 -243.368836) (xy 105.732281 -243.374768)
			(xy 105.779552 -243.38846) (xy 105.824014 -243.409558) (xy 105.864517 -243.437514) (xy 105.90001 -243.471606)
			(xy 105.929575 -243.51095) (xy 105.952446 -243.554527) (xy 105.96803 -243.601208) (xy 105.975925 -243.649785)
			(xy 105.97642 -243.674392) (xy 106.305362 -243.674392) (xy 106.309322 -243.625338) (xy 106.321099 -243.577554)
			(xy 106.34039 -243.532278) (xy 106.366693 -243.490682) (xy 106.399328 -243.453845) (xy 106.437449 -243.42272)
			(xy 106.48007 -243.398113) (xy 106.526086 -243.380661) (xy 106.574305 -243.370817) (xy 106.62348 -243.368836)
			(xy 106.672335 -243.374768) (xy 106.719606 -243.38846) (xy 106.764068 -243.409558) (xy 106.804571 -243.437514)
			(xy 106.840064 -243.471606) (xy 106.869629 -243.51095) (xy 106.8925 -243.554527) (xy 106.908084 -243.601208)
			(xy 106.915979 -243.649785) (xy 106.916474 -243.674392) (xy 107.245162 -243.674392) (xy 107.249122 -243.625338)
			(xy 107.260899 -243.577554) (xy 107.28019 -243.532278) (xy 107.306493 -243.490682) (xy 107.339128 -243.453845)
			(xy 107.377249 -243.42272) (xy 107.41987 -243.398113) (xy 107.465886 -243.380661) (xy 107.514105 -243.370817)
			(xy 107.56328 -243.368836) (xy 107.612135 -243.374768) (xy 107.659406 -243.38846) (xy 107.703868 -243.409558)
			(xy 107.744371 -243.437514) (xy 107.779864 -243.471606) (xy 107.809429 -243.51095) (xy 107.8323 -243.554527)
			(xy 107.847884 -243.601208) (xy 107.855779 -243.649785) (xy 107.856274 -243.674392) (xy 108.174785 -243.674392)
			(xy 108.17888 -243.623664) (xy 108.191059 -243.57425) (xy 108.211007 -243.52743) (xy 108.238208 -243.484416)
			(xy 108.271956 -243.446322) (xy 108.311378 -243.414135) (xy 108.355452 -243.388689) (xy 108.403038 -243.370642)
			(xy 108.452902 -243.360462) (xy 108.503754 -243.358413) (xy 108.554275 -243.364547) (xy 108.603159 -243.378707)
			(xy 108.649138 -243.400524) (xy 108.691022 -243.429434) (xy 108.727726 -243.464689) (xy 108.758299 -243.505375)
			(xy 108.78195 -243.550438) (xy 108.798066 -243.598712) (xy 108.80623 -243.648946) (xy 108.806742 -243.674392)
			(xy 109.114839 -243.674392) (xy 109.118934 -243.623664) (xy 109.131113 -243.57425) (xy 109.151061 -243.52743)
			(xy 109.178262 -243.484416) (xy 109.21201 -243.446322) (xy 109.251432 -243.414135) (xy 109.295506 -243.388689)
			(xy 109.343092 -243.370642) (xy 109.392956 -243.360462) (xy 109.443808 -243.358413) (xy 109.494329 -243.364547)
			(xy 109.543213 -243.378707) (xy 109.589192 -243.400524) (xy 109.631076 -243.429434) (xy 109.66778 -243.464689)
			(xy 109.698353 -243.505375) (xy 109.722004 -243.550438) (xy 109.73812 -243.598712) (xy 109.746284 -243.648946)
			(xy 109.746796 -243.674392) (xy 110.065324 -243.674392) (xy 110.069284 -243.625338) (xy 110.081061 -243.577554)
			(xy 110.100352 -243.532278) (xy 110.126655 -243.490682) (xy 110.15929 -243.453845) (xy 110.197411 -243.42272)
			(xy 110.240032 -243.398113) (xy 110.286048 -243.380661) (xy 110.334267 -243.370817) (xy 110.383442 -243.368836)
			(xy 110.432297 -243.374768) (xy 110.479568 -243.38846) (xy 110.52403 -243.409558) (xy 110.564533 -243.437514)
			(xy 110.600026 -243.471606) (xy 110.629591 -243.51095) (xy 110.652462 -243.554527) (xy 110.668046 -243.601208)
			(xy 110.675941 -243.649785) (xy 110.676436 -243.674392) (xy 110.675941 -243.698999) (xy 110.668046 -243.747576)
			(xy 110.652462 -243.794257) (xy 110.629591 -243.837834) (xy 110.600026 -243.877178) (xy 110.564533 -243.91127)
			(xy 110.52403 -243.939226) (xy 110.479568 -243.960324) (xy 110.432297 -243.974016) (xy 110.383442 -243.979948)
			(xy 110.334267 -243.977967) (xy 110.286048 -243.968123) (xy 110.240032 -243.950671) (xy 110.197411 -243.926064)
			(xy 110.15929 -243.894939) (xy 110.126655 -243.858102) (xy 110.100352 -243.816506) (xy 110.081061 -243.77123)
			(xy 110.069284 -243.723446) (xy 110.065324 -243.674392) (xy 109.746796 -243.674392) (xy 109.746284 -243.699838)
			(xy 109.73812 -243.750072) (xy 109.722004 -243.798346) (xy 109.698353 -243.843409) (xy 109.66778 -243.884095)
			(xy 109.631076 -243.91935) (xy 109.589192 -243.94826) (xy 109.543213 -243.970077) (xy 109.494329 -243.984237)
			(xy 109.443808 -243.990371) (xy 109.392956 -243.988322) (xy 109.343092 -243.978142) (xy 109.295506 -243.960095)
			(xy 109.251432 -243.934649) (xy 109.21201 -243.902462) (xy 109.178262 -243.864368) (xy 109.151061 -243.821354)
			(xy 109.131113 -243.774534) (xy 109.118934 -243.72512) (xy 109.114839 -243.674392) (xy 108.806742 -243.674392)
			(xy 108.80623 -243.699838) (xy 108.798066 -243.750072) (xy 108.78195 -243.798346) (xy 108.758299 -243.843409)
			(xy 108.727726 -243.884095) (xy 108.691022 -243.91935) (xy 108.649138 -243.94826) (xy 108.603159 -243.970077)
			(xy 108.554275 -243.984237) (xy 108.503754 -243.990371) (xy 108.452902 -243.988322) (xy 108.403038 -243.978142)
			(xy 108.355452 -243.960095) (xy 108.311378 -243.934649) (xy 108.271956 -243.902462) (xy 108.238208 -243.864368)
			(xy 108.211007 -243.821354) (xy 108.191059 -243.774534) (xy 108.17888 -243.72512) (xy 108.174785 -243.674392)
			(xy 107.856274 -243.674392) (xy 107.855779 -243.698999) (xy 107.847884 -243.747576) (xy 107.8323 -243.794257)
			(xy 107.809429 -243.837834) (xy 107.779864 -243.877178) (xy 107.744371 -243.91127) (xy 107.703868 -243.939226)
			(xy 107.659406 -243.960324) (xy 107.612135 -243.974016) (xy 107.56328 -243.979948) (xy 107.514105 -243.977967)
			(xy 107.465886 -243.968123) (xy 107.41987 -243.950671) (xy 107.377249 -243.926064) (xy 107.339128 -243.894939)
			(xy 107.306493 -243.858102) (xy 107.28019 -243.816506) (xy 107.260899 -243.77123) (xy 107.249122 -243.723446)
			(xy 107.245162 -243.674392) (xy 106.916474 -243.674392) (xy 106.915979 -243.698999) (xy 106.908084 -243.747576)
			(xy 106.8925 -243.794257) (xy 106.869629 -243.837834) (xy 106.840064 -243.877178) (xy 106.804571 -243.91127)
			(xy 106.764068 -243.939226) (xy 106.719606 -243.960324) (xy 106.672335 -243.974016) (xy 106.62348 -243.979948)
			(xy 106.574305 -243.977967) (xy 106.526086 -243.968123) (xy 106.48007 -243.950671) (xy 106.437449 -243.926064)
			(xy 106.399328 -243.894939) (xy 106.366693 -243.858102) (xy 106.34039 -243.816506) (xy 106.321099 -243.77123)
			(xy 106.309322 -243.723446) (xy 106.305362 -243.674392) (xy 105.97642 -243.674392) (xy 105.975925 -243.698999)
			(xy 105.96803 -243.747576) (xy 105.952446 -243.794257) (xy 105.929575 -243.837834) (xy 105.90001 -243.877178)
			(xy 105.864517 -243.91127) (xy 105.824014 -243.939226) (xy 105.779552 -243.960324) (xy 105.732281 -243.974016)
			(xy 105.683426 -243.979948) (xy 105.634251 -243.977967) (xy 105.586032 -243.968123) (xy 105.540016 -243.950671)
			(xy 105.497395 -243.926064) (xy 105.459274 -243.894939) (xy 105.426639 -243.858102) (xy 105.400336 -243.816506)
			(xy 105.381045 -243.77123) (xy 105.369268 -243.723446) (xy 105.365308 -243.674392) (xy 105.036366 -243.674392)
			(xy 105.035871 -243.698999) (xy 105.027976 -243.747576) (xy 105.012392 -243.794257) (xy 104.989521 -243.837834)
			(xy 104.959956 -243.877178) (xy 104.924463 -243.91127) (xy 104.88396 -243.939226) (xy 104.839498 -243.960324)
			(xy 104.792227 -243.974016) (xy 104.743372 -243.979948) (xy 104.694197 -243.977967) (xy 104.645978 -243.968123)
			(xy 104.599962 -243.950671) (xy 104.557341 -243.926064) (xy 104.51922 -243.894939) (xy 104.486585 -243.858102)
			(xy 104.460282 -243.816506) (xy 104.440991 -243.77123) (xy 104.429214 -243.723446) (xy 104.425254 -243.674392)
			(xy 104.096312 -243.674392) (xy 104.095817 -243.698999) (xy 104.087922 -243.747576) (xy 104.072338 -243.794257)
			(xy 104.049467 -243.837834) (xy 104.019902 -243.877178) (xy 103.984409 -243.91127) (xy 103.943906 -243.939226)
			(xy 103.899444 -243.960324) (xy 103.852173 -243.974016) (xy 103.803318 -243.979948) (xy 103.754143 -243.977967)
			(xy 103.705924 -243.968123) (xy 103.659908 -243.950671) (xy 103.617287 -243.926064) (xy 103.579166 -243.894939)
			(xy 103.546531 -243.858102) (xy 103.520228 -243.816506) (xy 103.500937 -243.77123) (xy 103.48916 -243.723446)
			(xy 103.4852 -243.674392) (xy 103.156258 -243.674392) (xy 103.155763 -243.698999) (xy 103.147868 -243.747576)
			(xy 103.132284 -243.794257) (xy 103.109413 -243.837834) (xy 103.079848 -243.877178) (xy 103.044355 -243.91127)
			(xy 103.003852 -243.939226) (xy 102.95939 -243.960324) (xy 102.912119 -243.974016) (xy 102.863264 -243.979948)
			(xy 102.814089 -243.977967) (xy 102.76587 -243.968123) (xy 102.719854 -243.950671) (xy 102.677233 -243.926064)
			(xy 102.639112 -243.894939) (xy 102.606477 -243.858102) (xy 102.580174 -243.816506) (xy 102.560883 -243.77123)
			(xy 102.549106 -243.723446) (xy 102.545146 -243.674392) (xy 102.216458 -243.674392) (xy 102.215963 -243.698999)
			(xy 102.208068 -243.747576) (xy 102.192484 -243.794257) (xy 102.169613 -243.837834) (xy 102.140048 -243.877178)
			(xy 102.104555 -243.91127) (xy 102.064052 -243.939226) (xy 102.01959 -243.960324) (xy 101.972319 -243.974016)
			(xy 101.923464 -243.979948) (xy 101.874289 -243.977967) (xy 101.82607 -243.968123) (xy 101.780054 -243.950671)
			(xy 101.737433 -243.926064) (xy 101.699312 -243.894939) (xy 101.666677 -243.858102) (xy 101.640374 -243.816506)
			(xy 101.621083 -243.77123) (xy 101.609306 -243.723446) (xy 101.605346 -243.674392) (xy 101.276404 -243.674392)
			(xy 101.275909 -243.698999) (xy 101.268014 -243.747576) (xy 101.25243 -243.794257) (xy 101.229559 -243.837834)
			(xy 101.199994 -243.877178) (xy 101.164501 -243.91127) (xy 101.123998 -243.939226) (xy 101.079536 -243.960324)
			(xy 101.032265 -243.974016) (xy 100.98341 -243.979948) (xy 100.934235 -243.977967) (xy 100.886016 -243.968123)
			(xy 100.84 -243.950671) (xy 100.797379 -243.926064) (xy 100.759258 -243.894939) (xy 100.726623 -243.858102)
			(xy 100.70032 -243.816506) (xy 100.681029 -243.77123) (xy 100.669252 -243.723446) (xy 100.665292 -243.674392)
			(xy 100.33635 -243.674392) (xy 100.335855 -243.698999) (xy 100.32796 -243.747576) (xy 100.312376 -243.794257)
			(xy 100.289505 -243.837834) (xy 100.25994 -243.877178) (xy 100.224447 -243.91127) (xy 100.183944 -243.939226)
			(xy 100.139482 -243.960324) (xy 100.092211 -243.974016) (xy 100.043356 -243.979948) (xy 99.994181 -243.977967)
			(xy 99.945962 -243.968123) (xy 99.899946 -243.950671) (xy 99.857325 -243.926064) (xy 99.819204 -243.894939)
			(xy 99.786569 -243.858102) (xy 99.760266 -243.816506) (xy 99.740975 -243.77123) (xy 99.729198 -243.723446)
			(xy 99.725238 -243.674392) (xy 99.396296 -243.674392) (xy 99.395801 -243.698999) (xy 99.387906 -243.747576)
			(xy 99.372322 -243.794257) (xy 99.349451 -243.837834) (xy 99.319886 -243.877178) (xy 99.284393 -243.91127)
			(xy 99.24389 -243.939226) (xy 99.199428 -243.960324) (xy 99.152157 -243.974016) (xy 99.103302 -243.979948)
			(xy 99.054127 -243.977967) (xy 99.005908 -243.968123) (xy 98.959892 -243.950671) (xy 98.917271 -243.926064)
			(xy 98.87915 -243.894939) (xy 98.846515 -243.858102) (xy 98.820212 -243.816506) (xy 98.800921 -243.77123)
			(xy 98.789144 -243.723446) (xy 98.785184 -243.674392) (xy 98.456242 -243.674392) (xy 98.455747 -243.698999)
			(xy 98.447852 -243.747576) (xy 98.432268 -243.794257) (xy 98.409397 -243.837834) (xy 98.379832 -243.877178)
			(xy 98.344339 -243.91127) (xy 98.303836 -243.939226) (xy 98.259374 -243.960324) (xy 98.212103 -243.974016)
			(xy 98.163248 -243.979948) (xy 98.114073 -243.977967) (xy 98.065854 -243.968123) (xy 98.019838 -243.950671)
			(xy 97.977217 -243.926064) (xy 97.939096 -243.894939) (xy 97.906461 -243.858102) (xy 97.880158 -243.816506)
			(xy 97.860867 -243.77123) (xy 97.84909 -243.723446) (xy 97.84513 -243.674392) (xy 97.516442 -243.674392)
			(xy 97.515947 -243.698999) (xy 97.508052 -243.747576) (xy 97.492468 -243.794257) (xy 97.469597 -243.837834)
			(xy 97.440032 -243.877178) (xy 97.404539 -243.91127) (xy 97.364036 -243.939226) (xy 97.319574 -243.960324)
			(xy 97.272303 -243.974016) (xy 97.223448 -243.979948) (xy 97.174273 -243.977967) (xy 97.126054 -243.968123)
			(xy 97.080038 -243.950671) (xy 97.037417 -243.926064) (xy 96.999296 -243.894939) (xy 96.966661 -243.858102)
			(xy 96.940358 -243.816506) (xy 96.921067 -243.77123) (xy 96.90929 -243.723446) (xy 96.90533 -243.674392)
			(xy 96.576388 -243.674392) (xy 96.575893 -243.698999) (xy 96.567998 -243.747576) (xy 96.552414 -243.794257)
			(xy 96.529543 -243.837834) (xy 96.499978 -243.877178) (xy 96.464485 -243.91127) (xy 96.423982 -243.939226)
			(xy 96.37952 -243.960324) (xy 96.332249 -243.974016) (xy 96.283394 -243.979948) (xy 96.234219 -243.977967)
			(xy 96.186 -243.968123) (xy 96.139984 -243.950671) (xy 96.097363 -243.926064) (xy 96.059242 -243.894939)
			(xy 96.026607 -243.858102) (xy 96.000304 -243.816506) (xy 95.981013 -243.77123) (xy 95.969236 -243.723446)
			(xy 95.965276 -243.674392) (xy 95.646748 -243.674392) (xy 95.646236 -243.699838) (xy 95.638072 -243.750072)
			(xy 95.621956 -243.798346) (xy 95.598305 -243.843409) (xy 95.567732 -243.884095) (xy 95.531028 -243.91935)
			(xy 95.489144 -243.94826) (xy 95.443165 -243.970077) (xy 95.394281 -243.984237) (xy 95.34376 -243.990371)
			(xy 95.292908 -243.988322) (xy 95.243044 -243.978142) (xy 95.195458 -243.960095) (xy 95.151384 -243.934649)
			(xy 95.111962 -243.902462) (xy 95.078214 -243.864368) (xy 95.051013 -243.821354) (xy 95.031065 -243.774534)
			(xy 95.018886 -243.72512) (xy 95.014791 -243.674392) (xy 94.706694 -243.674392) (xy 94.706182 -243.699838)
			(xy 94.698018 -243.750072) (xy 94.681902 -243.798346) (xy 94.658251 -243.843409) (xy 94.627678 -243.884095)
			(xy 94.590974 -243.91935) (xy 94.54909 -243.94826) (xy 94.503111 -243.970077) (xy 94.454227 -243.984237)
			(xy 94.403706 -243.990371) (xy 94.352854 -243.988322) (xy 94.30299 -243.978142) (xy 94.255404 -243.960095)
			(xy 94.21133 -243.934649) (xy 94.171908 -243.902462) (xy 94.13816 -243.864368) (xy 94.110959 -243.821354)
			(xy 94.091011 -243.774534) (xy 94.078832 -243.72512) (xy 94.074737 -243.674392) (xy 93.756226 -243.674392)
			(xy 93.755731 -243.698999) (xy 93.747836 -243.747576) (xy 93.732252 -243.794257) (xy 93.709381 -243.837834)
			(xy 93.679816 -243.877178) (xy 93.644323 -243.91127) (xy 93.60382 -243.939226) (xy 93.559358 -243.960324)
			(xy 93.512087 -243.974016) (xy 93.463232 -243.979948) (xy 93.414057 -243.977967) (xy 93.365838 -243.968123)
			(xy 93.319822 -243.950671) (xy 93.277201 -243.926064) (xy 93.23908 -243.894939) (xy 93.206445 -243.858102)
			(xy 93.180142 -243.816506) (xy 93.160851 -243.77123) (xy 93.149074 -243.723446) (xy 93.145114 -243.674392)
			(xy 92.82684 -243.674392) (xy 92.826328 -243.699838) (xy 92.818164 -243.750072) (xy 92.802048 -243.798346)
			(xy 92.778397 -243.843409) (xy 92.747824 -243.884095) (xy 92.71112 -243.91935) (xy 92.669236 -243.94826)
			(xy 92.623257 -243.970077) (xy 92.574373 -243.984237) (xy 92.523852 -243.990371) (xy 92.473 -243.988322)
			(xy 92.423136 -243.978142) (xy 92.37555 -243.960095) (xy 92.331476 -243.934649) (xy 92.292054 -243.902462)
			(xy 92.258306 -243.864368) (xy 92.231105 -243.821354) (xy 92.211157 -243.774534) (xy 92.198978 -243.72512)
			(xy 92.194883 -243.674392) (xy 91.876372 -243.674392) (xy 91.875877 -243.698999) (xy 91.867982 -243.747576)
			(xy 91.852398 -243.794257) (xy 91.829527 -243.837834) (xy 91.799962 -243.877178) (xy 91.764469 -243.91127)
			(xy 91.723966 -243.939226) (xy 91.679504 -243.960324) (xy 91.632233 -243.974016) (xy 91.583378 -243.979948)
			(xy 91.534203 -243.977967) (xy 91.485984 -243.968123) (xy 91.439968 -243.950671) (xy 91.397347 -243.926064)
			(xy 91.359226 -243.894939) (xy 91.326591 -243.858102) (xy 91.300288 -243.816506) (xy 91.280997 -243.77123)
			(xy 91.26922 -243.723446) (xy 91.26526 -243.674392) (xy 90.946732 -243.674392) (xy 90.94622 -243.699838)
			(xy 90.938056 -243.750072) (xy 90.92194 -243.798346) (xy 90.898289 -243.843409) (xy 90.867716 -243.884095)
			(xy 90.831012 -243.91935) (xy 90.789128 -243.94826) (xy 90.743149 -243.970077) (xy 90.694265 -243.984237)
			(xy 90.643744 -243.990371) (xy 90.592892 -243.988322) (xy 90.543028 -243.978142) (xy 90.495442 -243.960095)
			(xy 90.451368 -243.934649) (xy 90.411946 -243.902462) (xy 90.378198 -243.864368) (xy 90.350997 -243.821354)
			(xy 90.331049 -243.774534) (xy 90.31887 -243.72512) (xy 90.314775 -243.674392) (xy 89.996264 -243.674392)
			(xy 89.995769 -243.698999) (xy 89.987874 -243.747576) (xy 89.97229 -243.794257) (xy 89.949419 -243.837834)
			(xy 89.919854 -243.877178) (xy 89.884361 -243.91127) (xy 89.843858 -243.939226) (xy 89.799396 -243.960324)
			(xy 89.752125 -243.974016) (xy 89.70327 -243.979948) (xy 89.654095 -243.977967) (xy 89.605876 -243.968123)
			(xy 89.55986 -243.950671) (xy 89.517239 -243.926064) (xy 89.479118 -243.894939) (xy 89.446483 -243.858102)
			(xy 89.42018 -243.816506) (xy 89.400889 -243.77123) (xy 89.389112 -243.723446) (xy 89.385152 -243.674392)
			(xy 89.066878 -243.674392) (xy 89.066366 -243.699838) (xy 89.058202 -243.750072) (xy 89.042086 -243.798346)
			(xy 89.018435 -243.843409) (xy 88.987862 -243.884095) (xy 88.951158 -243.91935) (xy 88.909274 -243.94826)
			(xy 88.863295 -243.970077) (xy 88.814411 -243.984237) (xy 88.76389 -243.990371) (xy 88.713038 -243.988322)
			(xy 88.663174 -243.978142) (xy 88.615588 -243.960095) (xy 88.571514 -243.934649) (xy 88.532092 -243.902462)
			(xy 88.498344 -243.864368) (xy 88.471143 -243.821354) (xy 88.451195 -243.774534) (xy 88.439016 -243.72512)
			(xy 88.434921 -243.674392) (xy 88.126824 -243.674392) (xy 88.126312 -243.699838) (xy 88.118148 -243.750072)
			(xy 88.102032 -243.798346) (xy 88.078381 -243.843409) (xy 88.047808 -243.884095) (xy 88.011104 -243.91935)
			(xy 87.96922 -243.94826) (xy 87.923241 -243.970077) (xy 87.874357 -243.984237) (xy 87.823836 -243.990371)
			(xy 87.772984 -243.988322) (xy 87.72312 -243.978142) (xy 87.675534 -243.960095) (xy 87.63146 -243.934649)
			(xy 87.592038 -243.902462) (xy 87.55829 -243.864368) (xy 87.531089 -243.821354) (xy 87.511141 -243.774534)
			(xy 87.498962 -243.72512) (xy 87.494867 -243.674392) (xy 87.176356 -243.674392) (xy 87.175861 -243.698999)
			(xy 87.167966 -243.747576) (xy 87.152382 -243.794257) (xy 87.129511 -243.837834) (xy 87.099946 -243.877178)
			(xy 87.064453 -243.91127) (xy 87.02395 -243.939226) (xy 86.979488 -243.960324) (xy 86.932217 -243.974016)
			(xy 86.883362 -243.979948) (xy 86.834187 -243.977967) (xy 86.785968 -243.968123) (xy 86.739952 -243.950671)
			(xy 86.697331 -243.926064) (xy 86.65921 -243.894939) (xy 86.626575 -243.858102) (xy 86.600272 -243.816506)
			(xy 86.580981 -243.77123) (xy 86.569204 -243.723446) (xy 86.565244 -243.674392) (xy 86.246716 -243.674392)
			(xy 86.246204 -243.699838) (xy 86.23804 -243.750072) (xy 86.221924 -243.798346) (xy 86.198273 -243.843409)
			(xy 86.1677 -243.884095) (xy 86.130996 -243.91935) (xy 86.089112 -243.94826) (xy 86.043133 -243.970077)
			(xy 85.994249 -243.984237) (xy 85.943728 -243.990371) (xy 85.892876 -243.988322) (xy 85.843012 -243.978142)
			(xy 85.795426 -243.960095) (xy 85.751352 -243.934649) (xy 85.71193 -243.902462) (xy 85.678182 -243.864368)
			(xy 85.650981 -243.821354) (xy 85.631033 -243.774534) (xy 85.618854 -243.72512) (xy 85.614759 -243.674392)
			(xy 85.296248 -243.674392) (xy 85.295753 -243.698999) (xy 85.287858 -243.747576) (xy 85.272274 -243.794257)
			(xy 85.249403 -243.837834) (xy 85.219838 -243.877178) (xy 85.184345 -243.91127) (xy 85.143842 -243.939226)
			(xy 85.09938 -243.960324) (xy 85.052109 -243.974016) (xy 85.003254 -243.979948) (xy 84.954079 -243.977967)
			(xy 84.90586 -243.968123) (xy 84.859844 -243.950671) (xy 84.817223 -243.926064) (xy 84.779102 -243.894939)
			(xy 84.746467 -243.858102) (xy 84.720164 -243.816506) (xy 84.700873 -243.77123) (xy 84.689096 -243.723446)
			(xy 84.685136 -243.674392) (xy 84.366862 -243.674392) (xy 84.36635 -243.699838) (xy 84.358186 -243.750072)
			(xy 84.34207 -243.798346) (xy 84.318419 -243.843409) (xy 84.287846 -243.884095) (xy 84.251142 -243.91935)
			(xy 84.209258 -243.94826) (xy 84.163279 -243.970077) (xy 84.114395 -243.984237) (xy 84.063874 -243.990371)
			(xy 84.013022 -243.988322) (xy 83.963158 -243.978142) (xy 83.915572 -243.960095) (xy 83.871498 -243.934649)
			(xy 83.832076 -243.902462) (xy 83.798328 -243.864368) (xy 83.771127 -243.821354) (xy 83.751179 -243.774534)
			(xy 83.739 -243.72512) (xy 83.734905 -243.674392) (xy 83.416394 -243.674392) (xy 83.415899 -243.698999)
			(xy 83.408004 -243.747576) (xy 83.39242 -243.794257) (xy 83.369549 -243.837834) (xy 83.339984 -243.877178)
			(xy 83.304491 -243.91127) (xy 83.263988 -243.939226) (xy 83.219526 -243.960324) (xy 83.172255 -243.974016)
			(xy 83.1234 -243.979948) (xy 83.074225 -243.977967) (xy 83.026006 -243.968123) (xy 82.97999 -243.950671)
			(xy 82.937369 -243.926064) (xy 82.899248 -243.894939) (xy 82.866613 -243.858102) (xy 82.84031 -243.816506)
			(xy 82.821019 -243.77123) (xy 82.809242 -243.723446) (xy 82.805282 -243.674392) (xy 82.486754 -243.674392)
			(xy 82.486242 -243.699838) (xy 82.478078 -243.750072) (xy 82.461962 -243.798346) (xy 82.438311 -243.843409)
			(xy 82.407738 -243.884095) (xy 82.371034 -243.91935) (xy 82.32915 -243.94826) (xy 82.283171 -243.970077)
			(xy 82.234287 -243.984237) (xy 82.183766 -243.990371) (xy 82.132914 -243.988322) (xy 82.08305 -243.978142)
			(xy 82.035464 -243.960095) (xy 81.99139 -243.934649) (xy 81.951968 -243.902462) (xy 81.91822 -243.864368)
			(xy 81.891019 -243.821354) (xy 81.871071 -243.774534) (xy 81.858892 -243.72512) (xy 81.854797 -243.674392)
			(xy 81.5467 -243.674392) (xy 81.546188 -243.699838) (xy 81.538024 -243.750072) (xy 81.521908 -243.798346)
			(xy 81.498257 -243.843409) (xy 81.467684 -243.884095) (xy 81.43098 -243.91935) (xy 81.389096 -243.94826)
			(xy 81.343117 -243.970077) (xy 81.294233 -243.984237) (xy 81.243712 -243.990371) (xy 81.19286 -243.988322)
			(xy 81.142996 -243.978142) (xy 81.09541 -243.960095) (xy 81.051336 -243.934649) (xy 81.011914 -243.902462)
			(xy 80.978166 -243.864368) (xy 80.950965 -243.821354) (xy 80.931017 -243.774534) (xy 80.918838 -243.72512)
			(xy 80.914743 -243.674392) (xy 80.596486 -243.674392) (xy 80.595991 -243.698999) (xy 80.588096 -243.747576)
			(xy 80.572512 -243.794257) (xy 80.549641 -243.837834) (xy 80.520076 -243.877178) (xy 80.484583 -243.91127)
			(xy 80.44408 -243.939226) (xy 80.399618 -243.960324) (xy 80.352347 -243.974016) (xy 80.303492 -243.979948)
			(xy 80.254317 -243.977967) (xy 80.206098 -243.968123) (xy 80.160082 -243.950671) (xy 80.117461 -243.926064)
			(xy 80.07934 -243.894939) (xy 80.046705 -243.858102) (xy 80.020402 -243.816506) (xy 80.001111 -243.77123)
			(xy 79.989334 -243.723446) (xy 79.985374 -243.674392) (xy 78.716378 -243.674392) (xy 78.715883 -243.698999)
			(xy 78.707988 -243.747576) (xy 78.692404 -243.794257) (xy 78.669533 -243.837834) (xy 78.639968 -243.877178)
			(xy 78.604475 -243.91127) (xy 78.563972 -243.939226) (xy 78.51951 -243.960324) (xy 78.472239 -243.974016)
			(xy 78.423384 -243.979948) (xy 78.374209 -243.977967) (xy 78.32599 -243.968123) (xy 78.279974 -243.950671)
			(xy 78.237353 -243.926064) (xy 78.199232 -243.894939) (xy 78.166597 -243.858102) (xy 78.140294 -243.816506)
			(xy 78.121003 -243.77123) (xy 78.109226 -243.723446) (xy 78.105266 -243.674392) (xy 62.37732 -243.674392)
			(xy 62.37732 -244.750336) (xy 76.507098 -244.750336) (xy 76.511058 -244.701282) (xy 76.522835 -244.653498)
			(xy 76.542126 -244.608222) (xy 76.568429 -244.566626) (xy 76.601064 -244.529789) (xy 76.639185 -244.498664)
			(xy 76.681806 -244.474057) (xy 76.727822 -244.456605) (xy 76.776041 -244.446761) (xy 76.825216 -244.44478)
			(xy 76.874071 -244.450712) (xy 76.921342 -244.464404) (xy 76.963477 -244.484398) (xy 79.51522 -244.484398)
			(xy 79.51918 -244.435344) (xy 79.530957 -244.38756) (xy 79.550248 -244.342284) (xy 79.576551 -244.300688)
			(xy 79.609186 -244.263851) (xy 79.647307 -244.232726) (xy 79.689928 -244.208119) (xy 79.735944 -244.190667)
			(xy 79.784163 -244.180823) (xy 79.833338 -244.178842) (xy 79.882193 -244.184774) (xy 79.929464 -244.198466)
			(xy 79.973926 -244.219564) (xy 80.014429 -244.24752) (xy 80.049922 -244.281612) (xy 80.079487 -244.320956)
			(xy 80.102358 -244.364533) (xy 80.117942 -244.411214) (xy 80.125837 -244.459791) (xy 80.126332 -244.484398)
			(xy 80.444843 -244.484398) (xy 80.448938 -244.43367) (xy 80.461117 -244.384256) (xy 80.481065 -244.337436)
			(xy 80.508266 -244.294422) (xy 80.542014 -244.256328) (xy 80.581436 -244.224141) (xy 80.62551 -244.198695)
			(xy 80.673096 -244.180648) (xy 80.72296 -244.170468) (xy 80.773812 -244.168419) (xy 80.824333 -244.174553)
			(xy 80.873217 -244.188713) (xy 80.919196 -244.21053) (xy 80.96108 -244.23944) (xy 80.997784 -244.274695)
			(xy 81.028357 -244.315381) (xy 81.052008 -244.360444) (xy 81.068124 -244.408718) (xy 81.076288 -244.458952)
			(xy 81.0768 -244.484398) (xy 81.395328 -244.484398) (xy 81.399288 -244.435344) (xy 81.411065 -244.38756)
			(xy 81.430356 -244.342284) (xy 81.456659 -244.300688) (xy 81.489294 -244.263851) (xy 81.527415 -244.232726)
			(xy 81.570036 -244.208119) (xy 81.616052 -244.190667) (xy 81.664271 -244.180823) (xy 81.713446 -244.178842)
			(xy 81.762301 -244.184774) (xy 81.809572 -244.198466) (xy 81.854034 -244.219564) (xy 81.894537 -244.24752)
			(xy 81.93003 -244.281612) (xy 81.959595 -244.320956) (xy 81.982466 -244.364533) (xy 81.99805 -244.411214)
			(xy 82.005945 -244.459791) (xy 82.00644 -244.484398) (xy 82.324697 -244.484398) (xy 82.328792 -244.43367)
			(xy 82.340971 -244.384256) (xy 82.360919 -244.337436) (xy 82.38812 -244.294422) (xy 82.421868 -244.256328)
			(xy 82.46129 -244.224141) (xy 82.505364 -244.198695) (xy 82.55295 -244.180648) (xy 82.602814 -244.170468)
			(xy 82.653666 -244.168419) (xy 82.704187 -244.174553) (xy 82.753071 -244.188713) (xy 82.79905 -244.21053)
			(xy 82.840934 -244.23944) (xy 82.877638 -244.274695) (xy 82.908211 -244.315381) (xy 82.931862 -244.360444)
			(xy 82.947978 -244.408718) (xy 82.956142 -244.458952) (xy 82.956654 -244.484398) (xy 83.275182 -244.484398)
			(xy 83.279142 -244.435344) (xy 83.290919 -244.38756) (xy 83.31021 -244.342284) (xy 83.336513 -244.300688)
			(xy 83.369148 -244.263851) (xy 83.407269 -244.232726) (xy 83.44989 -244.208119) (xy 83.495906 -244.190667)
			(xy 83.544125 -244.180823) (xy 83.5933 -244.178842) (xy 83.642155 -244.184774) (xy 83.689426 -244.198466)
			(xy 83.733888 -244.219564) (xy 83.774391 -244.24752) (xy 83.809884 -244.281612) (xy 83.839449 -244.320956)
			(xy 83.86232 -244.364533) (xy 83.877904 -244.411214) (xy 83.885799 -244.459791) (xy 83.886294 -244.484398)
			(xy 84.204805 -244.484398) (xy 84.2089 -244.43367) (xy 84.221079 -244.384256) (xy 84.241027 -244.337436)
			(xy 84.268228 -244.294422) (xy 84.301976 -244.256328) (xy 84.341398 -244.224141) (xy 84.385472 -244.198695)
			(xy 84.433058 -244.180648) (xy 84.482922 -244.170468) (xy 84.533774 -244.168419) (xy 84.584295 -244.174553)
			(xy 84.633179 -244.188713) (xy 84.679158 -244.21053) (xy 84.721042 -244.23944) (xy 84.757746 -244.274695)
			(xy 84.788319 -244.315381) (xy 84.81197 -244.360444) (xy 84.828086 -244.408718) (xy 84.83625 -244.458952)
			(xy 84.836762 -244.484398) (xy 85.144859 -244.484398) (xy 85.148954 -244.43367) (xy 85.161133 -244.384256)
			(xy 85.181081 -244.337436) (xy 85.208282 -244.294422) (xy 85.24203 -244.256328) (xy 85.281452 -244.224141)
			(xy 85.325526 -244.198695) (xy 85.373112 -244.180648) (xy 85.422976 -244.170468) (xy 85.473828 -244.168419)
			(xy 85.524349 -244.174553) (xy 85.573233 -244.188713) (xy 85.619212 -244.21053) (xy 85.661096 -244.23944)
			(xy 85.6978 -244.274695) (xy 85.728373 -244.315381) (xy 85.752024 -244.360444) (xy 85.76814 -244.408718)
			(xy 85.776304 -244.458952) (xy 85.776816 -244.484398) (xy 86.095344 -244.484398) (xy 86.099304 -244.435344)
			(xy 86.111081 -244.38756) (xy 86.130372 -244.342284) (xy 86.156675 -244.300688) (xy 86.18931 -244.263851)
			(xy 86.227431 -244.232726) (xy 86.270052 -244.208119) (xy 86.316068 -244.190667) (xy 86.364287 -244.180823)
			(xy 86.413462 -244.178842) (xy 86.462317 -244.184774) (xy 86.509588 -244.198466) (xy 86.55405 -244.219564)
			(xy 86.594553 -244.24752) (xy 86.630046 -244.281612) (xy 86.659611 -244.320956) (xy 86.682482 -244.364533)
			(xy 86.698066 -244.411214) (xy 86.705961 -244.459791) (xy 86.706456 -244.484398) (xy 87.024713 -244.484398)
			(xy 87.028808 -244.43367) (xy 87.040987 -244.384256) (xy 87.060935 -244.337436) (xy 87.088136 -244.294422)
			(xy 87.121884 -244.256328) (xy 87.161306 -244.224141) (xy 87.20538 -244.198695) (xy 87.252966 -244.180648)
			(xy 87.30283 -244.170468) (xy 87.353682 -244.168419) (xy 87.404203 -244.174553) (xy 87.453087 -244.188713)
			(xy 87.499066 -244.21053) (xy 87.54095 -244.23944) (xy 87.577654 -244.274695) (xy 87.608227 -244.315381)
			(xy 87.631878 -244.360444) (xy 87.647994 -244.408718) (xy 87.656158 -244.458952) (xy 87.65667 -244.484398)
			(xy 87.975198 -244.484398) (xy 87.979158 -244.435344) (xy 87.990935 -244.38756) (xy 88.010226 -244.342284)
			(xy 88.036529 -244.300688) (xy 88.069164 -244.263851) (xy 88.107285 -244.232726) (xy 88.149906 -244.208119)
			(xy 88.195922 -244.190667) (xy 88.244141 -244.180823) (xy 88.293316 -244.178842) (xy 88.342171 -244.184774)
			(xy 88.389442 -244.198466) (xy 88.433904 -244.219564) (xy 88.474407 -244.24752) (xy 88.5099 -244.281612)
			(xy 88.539465 -244.320956) (xy 88.562336 -244.364533) (xy 88.57792 -244.411214) (xy 88.585815 -244.459791)
			(xy 88.58631 -244.484398) (xy 88.904821 -244.484398) (xy 88.908916 -244.43367) (xy 88.921095 -244.384256)
			(xy 88.941043 -244.337436) (xy 88.968244 -244.294422) (xy 89.001992 -244.256328) (xy 89.041414 -244.224141)
			(xy 89.085488 -244.198695) (xy 89.133074 -244.180648) (xy 89.182938 -244.170468) (xy 89.23379 -244.168419)
			(xy 89.284311 -244.174553) (xy 89.333195 -244.188713) (xy 89.379174 -244.21053) (xy 89.421058 -244.23944)
			(xy 89.457762 -244.274695) (xy 89.488335 -244.315381) (xy 89.511986 -244.360444) (xy 89.528102 -244.408718)
			(xy 89.536266 -244.458952) (xy 89.536778 -244.484398) (xy 89.855306 -244.484398) (xy 89.859266 -244.435344)
			(xy 89.871043 -244.38756) (xy 89.890334 -244.342284) (xy 89.916637 -244.300688) (xy 89.949272 -244.263851)
			(xy 89.987393 -244.232726) (xy 90.030014 -244.208119) (xy 90.07603 -244.190667) (xy 90.124249 -244.180823)
			(xy 90.173424 -244.178842) (xy 90.222279 -244.184774) (xy 90.26955 -244.198466) (xy 90.314012 -244.219564)
			(xy 90.354515 -244.24752) (xy 90.390008 -244.281612) (xy 90.419573 -244.320956) (xy 90.442444 -244.364533)
			(xy 90.458028 -244.411214) (xy 90.465923 -244.459791) (xy 90.466418 -244.484398) (xy 90.784675 -244.484398)
			(xy 90.78877 -244.43367) (xy 90.800949 -244.384256) (xy 90.820897 -244.337436) (xy 90.848098 -244.294422)
			(xy 90.881846 -244.256328) (xy 90.921268 -244.224141) (xy 90.965342 -244.198695) (xy 91.012928 -244.180648)
			(xy 91.062792 -244.170468) (xy 91.113644 -244.168419) (xy 91.164165 -244.174553) (xy 91.213049 -244.188713)
			(xy 91.259028 -244.21053) (xy 91.300912 -244.23944) (xy 91.337616 -244.274695) (xy 91.368189 -244.315381)
			(xy 91.39184 -244.360444) (xy 91.407956 -244.408718) (xy 91.41612 -244.458952) (xy 91.416632 -244.484398)
			(xy 91.724729 -244.484398) (xy 91.728824 -244.43367) (xy 91.741003 -244.384256) (xy 91.760951 -244.337436)
			(xy 91.788152 -244.294422) (xy 91.8219 -244.256328) (xy 91.861322 -244.224141) (xy 91.905396 -244.198695)
			(xy 91.952982 -244.180648) (xy 92.002846 -244.170468) (xy 92.053698 -244.168419) (xy 92.104219 -244.174553)
			(xy 92.153103 -244.188713) (xy 92.199082 -244.21053) (xy 92.240966 -244.23944) (xy 92.27767 -244.274695)
			(xy 92.308243 -244.315381) (xy 92.331894 -244.360444) (xy 92.34801 -244.408718) (xy 92.356174 -244.458952)
			(xy 92.356686 -244.484398) (xy 92.675214 -244.484398) (xy 92.679174 -244.435344) (xy 92.690951 -244.38756)
			(xy 92.710242 -244.342284) (xy 92.736545 -244.300688) (xy 92.76918 -244.263851) (xy 92.807301 -244.232726)
			(xy 92.849922 -244.208119) (xy 92.895938 -244.190667) (xy 92.944157 -244.180823) (xy 92.993332 -244.178842)
			(xy 93.042187 -244.184774) (xy 93.089458 -244.198466) (xy 93.13392 -244.219564) (xy 93.174423 -244.24752)
			(xy 93.209916 -244.281612) (xy 93.239481 -244.320956) (xy 93.262352 -244.364533) (xy 93.277936 -244.411214)
			(xy 93.285831 -244.459791) (xy 93.286326 -244.484398) (xy 93.604837 -244.484398) (xy 93.608932 -244.43367)
			(xy 93.621111 -244.384256) (xy 93.641059 -244.337436) (xy 93.66826 -244.294422) (xy 93.702008 -244.256328)
			(xy 93.74143 -244.224141) (xy 93.785504 -244.198695) (xy 93.83309 -244.180648) (xy 93.882954 -244.170468)
			(xy 93.933806 -244.168419) (xy 93.984327 -244.174553) (xy 94.033211 -244.188713) (xy 94.07919 -244.21053)
			(xy 94.121074 -244.23944) (xy 94.157778 -244.274695) (xy 94.188351 -244.315381) (xy 94.212002 -244.360444)
			(xy 94.228118 -244.408718) (xy 94.236282 -244.458952) (xy 94.236794 -244.484398) (xy 94.555322 -244.484398)
			(xy 94.559282 -244.435344) (xy 94.571059 -244.38756) (xy 94.59035 -244.342284) (xy 94.616653 -244.300688)
			(xy 94.649288 -244.263851) (xy 94.687409 -244.232726) (xy 94.73003 -244.208119) (xy 94.776046 -244.190667)
			(xy 94.824265 -244.180823) (xy 94.87344 -244.178842) (xy 94.922295 -244.184774) (xy 94.969566 -244.198466)
			(xy 95.014028 -244.219564) (xy 95.054531 -244.24752) (xy 95.090024 -244.281612) (xy 95.119589 -244.320956)
			(xy 95.14246 -244.364533) (xy 95.158044 -244.411214) (xy 95.165939 -244.459791) (xy 95.166434 -244.484398)
			(xy 95.484691 -244.484398) (xy 95.488786 -244.43367) (xy 95.500965 -244.384256) (xy 95.520913 -244.337436)
			(xy 95.548114 -244.294422) (xy 95.581862 -244.256328) (xy 95.621284 -244.224141) (xy 95.665358 -244.198695)
			(xy 95.712944 -244.180648) (xy 95.762808 -244.170468) (xy 95.81366 -244.168419) (xy 95.864181 -244.174553)
			(xy 95.913065 -244.188713) (xy 95.959044 -244.21053) (xy 96.000928 -244.23944) (xy 96.037632 -244.274695)
			(xy 96.068205 -244.315381) (xy 96.091856 -244.360444) (xy 96.107972 -244.408718) (xy 96.116136 -244.458952)
			(xy 96.116648 -244.484398) (xy 96.435176 -244.484398) (xy 96.439136 -244.435344) (xy 96.450913 -244.38756)
			(xy 96.470204 -244.342284) (xy 96.496507 -244.300688) (xy 96.529142 -244.263851) (xy 96.567263 -244.232726)
			(xy 96.609884 -244.208119) (xy 96.6559 -244.190667) (xy 96.704119 -244.180823) (xy 96.753294 -244.178842)
			(xy 96.802149 -244.184774) (xy 96.84942 -244.198466) (xy 96.893882 -244.219564) (xy 96.934385 -244.24752)
			(xy 96.969878 -244.281612) (xy 96.999443 -244.320956) (xy 97.022314 -244.364533) (xy 97.037898 -244.411214)
			(xy 97.045793 -244.459791) (xy 97.046288 -244.484398) (xy 97.364799 -244.484398) (xy 97.368894 -244.43367)
			(xy 97.381073 -244.384256) (xy 97.401021 -244.337436) (xy 97.428222 -244.294422) (xy 97.46197 -244.256328)
			(xy 97.501392 -244.224141) (xy 97.545466 -244.198695) (xy 97.593052 -244.180648) (xy 97.642916 -244.170468)
			(xy 97.693768 -244.168419) (xy 97.744289 -244.174553) (xy 97.793173 -244.188713) (xy 97.839152 -244.21053)
			(xy 97.881036 -244.23944) (xy 97.91774 -244.274695) (xy 97.948313 -244.315381) (xy 97.971964 -244.360444)
			(xy 97.98808 -244.408718) (xy 97.996244 -244.458952) (xy 97.996756 -244.484398) (xy 98.304853 -244.484398)
			(xy 98.308948 -244.43367) (xy 98.321127 -244.384256) (xy 98.341075 -244.337436) (xy 98.368276 -244.294422)
			(xy 98.402024 -244.256328) (xy 98.441446 -244.224141) (xy 98.48552 -244.198695) (xy 98.533106 -244.180648)
			(xy 98.58297 -244.170468) (xy 98.633822 -244.168419) (xy 98.684343 -244.174553) (xy 98.733227 -244.188713)
			(xy 98.779206 -244.21053) (xy 98.82109 -244.23944) (xy 98.857794 -244.274695) (xy 98.888367 -244.315381)
			(xy 98.912018 -244.360444) (xy 98.928134 -244.408718) (xy 98.936298 -244.458952) (xy 98.93681 -244.484398)
			(xy 99.255338 -244.484398) (xy 99.259298 -244.435344) (xy 99.271075 -244.38756) (xy 99.290366 -244.342284)
			(xy 99.316669 -244.300688) (xy 99.349304 -244.263851) (xy 99.387425 -244.232726) (xy 99.430046 -244.208119)
			(xy 99.476062 -244.190667) (xy 99.524281 -244.180823) (xy 99.573456 -244.178842) (xy 99.622311 -244.184774)
			(xy 99.669582 -244.198466) (xy 99.714044 -244.219564) (xy 99.754547 -244.24752) (xy 99.79004 -244.281612)
			(xy 99.819605 -244.320956) (xy 99.842476 -244.364533) (xy 99.85806 -244.411214) (xy 99.865955 -244.459791)
			(xy 99.86645 -244.484398) (xy 100.184707 -244.484398) (xy 100.188802 -244.43367) (xy 100.200981 -244.384256)
			(xy 100.220929 -244.337436) (xy 100.24813 -244.294422) (xy 100.281878 -244.256328) (xy 100.3213 -244.224141)
			(xy 100.365374 -244.198695) (xy 100.41296 -244.180648) (xy 100.462824 -244.170468) (xy 100.513676 -244.168419)
			(xy 100.564197 -244.174553) (xy 100.613081 -244.188713) (xy 100.65906 -244.21053) (xy 100.700944 -244.23944)
			(xy 100.737648 -244.274695) (xy 100.768221 -244.315381) (xy 100.791872 -244.360444) (xy 100.807988 -244.408718)
			(xy 100.816152 -244.458952) (xy 100.816664 -244.484398) (xy 101.124761 -244.484398) (xy 101.128856 -244.43367)
			(xy 101.141035 -244.384256) (xy 101.160983 -244.337436) (xy 101.188184 -244.294422) (xy 101.221932 -244.256328)
			(xy 101.261354 -244.224141) (xy 101.305428 -244.198695) (xy 101.353014 -244.180648) (xy 101.402878 -244.170468)
			(xy 101.45373 -244.168419) (xy 101.504251 -244.174553) (xy 101.553135 -244.188713) (xy 101.599114 -244.21053)
			(xy 101.640998 -244.23944) (xy 101.677702 -244.274695) (xy 101.708275 -244.315381) (xy 101.731926 -244.360444)
			(xy 101.748042 -244.408718) (xy 101.756206 -244.458952) (xy 101.756718 -244.484398) (xy 102.075246 -244.484398)
			(xy 102.079206 -244.435344) (xy 102.090983 -244.38756) (xy 102.110274 -244.342284) (xy 102.136577 -244.300688)
			(xy 102.169212 -244.263851) (xy 102.207333 -244.232726) (xy 102.249954 -244.208119) (xy 102.29597 -244.190667)
			(xy 102.344189 -244.180823) (xy 102.393364 -244.178842) (xy 102.442219 -244.184774) (xy 102.48949 -244.198466)
			(xy 102.533952 -244.219564) (xy 102.574455 -244.24752) (xy 102.609948 -244.281612) (xy 102.639513 -244.320956)
			(xy 102.662384 -244.364533) (xy 102.677968 -244.411214) (xy 102.685863 -244.459791) (xy 102.686358 -244.484398)
			(xy 103.004869 -244.484398) (xy 103.008964 -244.43367) (xy 103.021143 -244.384256) (xy 103.041091 -244.337436)
			(xy 103.068292 -244.294422) (xy 103.10204 -244.256328) (xy 103.141462 -244.224141) (xy 103.185536 -244.198695)
			(xy 103.233122 -244.180648) (xy 103.282986 -244.170468) (xy 103.333838 -244.168419) (xy 103.384359 -244.174553)
			(xy 103.433243 -244.188713) (xy 103.479222 -244.21053) (xy 103.521106 -244.23944) (xy 103.55781 -244.274695)
			(xy 103.588383 -244.315381) (xy 103.612034 -244.360444) (xy 103.62815 -244.408718) (xy 103.636314 -244.458952)
			(xy 103.636826 -244.484398) (xy 103.944923 -244.484398) (xy 103.949018 -244.43367) (xy 103.961197 -244.384256)
			(xy 103.981145 -244.337436) (xy 104.008346 -244.294422) (xy 104.042094 -244.256328) (xy 104.081516 -244.224141)
			(xy 104.12559 -244.198695) (xy 104.173176 -244.180648) (xy 104.22304 -244.170468) (xy 104.273892 -244.168419)
			(xy 104.324413 -244.174553) (xy 104.373297 -244.188713) (xy 104.419276 -244.21053) (xy 104.46116 -244.23944)
			(xy 104.497864 -244.274695) (xy 104.528437 -244.315381) (xy 104.552088 -244.360444) (xy 104.568204 -244.408718)
			(xy 104.576368 -244.458952) (xy 104.57688 -244.484398) (xy 104.895154 -244.484398) (xy 104.899114 -244.435344)
			(xy 104.910891 -244.38756) (xy 104.930182 -244.342284) (xy 104.956485 -244.300688) (xy 104.98912 -244.263851)
			(xy 105.027241 -244.232726) (xy 105.069862 -244.208119) (xy 105.115878 -244.190667) (xy 105.164097 -244.180823)
			(xy 105.213272 -244.178842) (xy 105.262127 -244.184774) (xy 105.309398 -244.198466) (xy 105.35386 -244.219564)
			(xy 105.394363 -244.24752) (xy 105.429856 -244.281612) (xy 105.459421 -244.320956) (xy 105.482292 -244.364533)
			(xy 105.497876 -244.411214) (xy 105.505771 -244.459791) (xy 105.506266 -244.484398) (xy 105.824777 -244.484398)
			(xy 105.828872 -244.43367) (xy 105.841051 -244.384256) (xy 105.860999 -244.337436) (xy 105.8882 -244.294422)
			(xy 105.921948 -244.256328) (xy 105.96137 -244.224141) (xy 106.005444 -244.198695) (xy 106.05303 -244.180648)
			(xy 106.102894 -244.170468) (xy 106.153746 -244.168419) (xy 106.204267 -244.174553) (xy 106.253151 -244.188713)
			(xy 106.29913 -244.21053) (xy 106.341014 -244.23944) (xy 106.377718 -244.274695) (xy 106.408291 -244.315381)
			(xy 106.431942 -244.360444) (xy 106.448058 -244.408718) (xy 106.456222 -244.458952) (xy 106.456734 -244.484398)
			(xy 106.764831 -244.484398) (xy 106.768926 -244.43367) (xy 106.781105 -244.384256) (xy 106.801053 -244.337436)
			(xy 106.828254 -244.294422) (xy 106.862002 -244.256328) (xy 106.901424 -244.224141) (xy 106.945498 -244.198695)
			(xy 106.993084 -244.180648) (xy 107.042948 -244.170468) (xy 107.0938 -244.168419) (xy 107.144321 -244.174553)
			(xy 107.193205 -244.188713) (xy 107.239184 -244.21053) (xy 107.281068 -244.23944) (xy 107.317772 -244.274695)
			(xy 107.348345 -244.315381) (xy 107.371996 -244.360444) (xy 107.388112 -244.408718) (xy 107.396276 -244.458952)
			(xy 107.396788 -244.484398) (xy 107.715316 -244.484398) (xy 107.719276 -244.435344) (xy 107.731053 -244.38756)
			(xy 107.750344 -244.342284) (xy 107.776647 -244.300688) (xy 107.809282 -244.263851) (xy 107.847403 -244.232726)
			(xy 107.890024 -244.208119) (xy 107.93604 -244.190667) (xy 107.984259 -244.180823) (xy 108.033434 -244.178842)
			(xy 108.082289 -244.184774) (xy 108.12956 -244.198466) (xy 108.174022 -244.219564) (xy 108.214525 -244.24752)
			(xy 108.250018 -244.281612) (xy 108.279583 -244.320956) (xy 108.302454 -244.364533) (xy 108.318038 -244.411214)
			(xy 108.325933 -244.459791) (xy 108.326428 -244.484398) (xy 108.65537 -244.484398) (xy 108.65933 -244.435344)
			(xy 108.671107 -244.38756) (xy 108.690398 -244.342284) (xy 108.716701 -244.300688) (xy 108.749336 -244.263851)
			(xy 108.787457 -244.232726) (xy 108.830078 -244.208119) (xy 108.876094 -244.190667) (xy 108.924313 -244.180823)
			(xy 108.973488 -244.178842) (xy 109.022343 -244.184774) (xy 109.069614 -244.198466) (xy 109.114076 -244.219564)
			(xy 109.154579 -244.24752) (xy 109.190072 -244.281612) (xy 109.219637 -244.320956) (xy 109.242508 -244.364533)
			(xy 109.258092 -244.411214) (xy 109.265987 -244.459791) (xy 109.266482 -244.484398) (xy 109.59517 -244.484398)
			(xy 109.59913 -244.435344) (xy 109.610907 -244.38756) (xy 109.630198 -244.342284) (xy 109.656501 -244.300688)
			(xy 109.689136 -244.263851) (xy 109.727257 -244.232726) (xy 109.769878 -244.208119) (xy 109.815894 -244.190667)
			(xy 109.864113 -244.180823) (xy 109.913288 -244.178842) (xy 109.962143 -244.184774) (xy 110.009414 -244.198466)
			(xy 110.053876 -244.219564) (xy 110.094379 -244.24752) (xy 110.129872 -244.281612) (xy 110.159437 -244.320956)
			(xy 110.182308 -244.364533) (xy 110.197892 -244.411214) (xy 110.205787 -244.459791) (xy 110.206282 -244.484398)
			(xy 110.205787 -244.509005) (xy 110.197892 -244.557582) (xy 110.182308 -244.604263) (xy 110.159437 -244.64784)
			(xy 110.129872 -244.687184) (xy 110.094379 -244.721276) (xy 110.053876 -244.749232) (xy 110.009414 -244.77033)
			(xy 109.962143 -244.784022) (xy 109.913288 -244.789954) (xy 109.864113 -244.787973) (xy 109.815894 -244.778129)
			(xy 109.769878 -244.760677) (xy 109.727257 -244.73607) (xy 109.689136 -244.704945) (xy 109.656501 -244.668108)
			(xy 109.630198 -244.626512) (xy 109.610907 -244.581236) (xy 109.59913 -244.533452) (xy 109.59517 -244.484398)
			(xy 109.266482 -244.484398) (xy 109.265987 -244.509005) (xy 109.258092 -244.557582) (xy 109.242508 -244.604263)
			(xy 109.219637 -244.64784) (xy 109.190072 -244.687184) (xy 109.154579 -244.721276) (xy 109.114076 -244.749232)
			(xy 109.069614 -244.77033) (xy 109.022343 -244.784022) (xy 108.973488 -244.789954) (xy 108.924313 -244.787973)
			(xy 108.876094 -244.778129) (xy 108.830078 -244.760677) (xy 108.787457 -244.73607) (xy 108.749336 -244.704945)
			(xy 108.716701 -244.668108) (xy 108.690398 -244.626512) (xy 108.671107 -244.581236) (xy 108.65933 -244.533452)
			(xy 108.65537 -244.484398) (xy 108.326428 -244.484398) (xy 108.325933 -244.509005) (xy 108.318038 -244.557582)
			(xy 108.302454 -244.604263) (xy 108.279583 -244.64784) (xy 108.250018 -244.687184) (xy 108.214525 -244.721276)
			(xy 108.174022 -244.749232) (xy 108.12956 -244.77033) (xy 108.082289 -244.784022) (xy 108.033434 -244.789954)
			(xy 107.984259 -244.787973) (xy 107.93604 -244.778129) (xy 107.890024 -244.760677) (xy 107.847403 -244.73607)
			(xy 107.809282 -244.704945) (xy 107.776647 -244.668108) (xy 107.750344 -244.626512) (xy 107.731053 -244.581236)
			(xy 107.719276 -244.533452) (xy 107.715316 -244.484398) (xy 107.396788 -244.484398) (xy 107.396276 -244.509844)
			(xy 107.388112 -244.560078) (xy 107.371996 -244.608352) (xy 107.348345 -244.653415) (xy 107.317772 -244.694101)
			(xy 107.281068 -244.729356) (xy 107.239184 -244.758266) (xy 107.193205 -244.780083) (xy 107.144321 -244.794243)
			(xy 107.0938 -244.800377) (xy 107.042948 -244.798328) (xy 106.993084 -244.788148) (xy 106.945498 -244.770101)
			(xy 106.901424 -244.744655) (xy 106.862002 -244.712468) (xy 106.828254 -244.674374) (xy 106.801053 -244.63136)
			(xy 106.781105 -244.58454) (xy 106.768926 -244.535126) (xy 106.764831 -244.484398) (xy 106.456734 -244.484398)
			(xy 106.456222 -244.509844) (xy 106.448058 -244.560078) (xy 106.431942 -244.608352) (xy 106.408291 -244.653415)
			(xy 106.377718 -244.694101) (xy 106.341014 -244.729356) (xy 106.29913 -244.758266) (xy 106.253151 -244.780083)
			(xy 106.204267 -244.794243) (xy 106.153746 -244.800377) (xy 106.102894 -244.798328) (xy 106.05303 -244.788148)
			(xy 106.005444 -244.770101) (xy 105.96137 -244.744655) (xy 105.921948 -244.712468) (xy 105.8882 -244.674374)
			(xy 105.860999 -244.63136) (xy 105.841051 -244.58454) (xy 105.828872 -244.535126) (xy 105.824777 -244.484398)
			(xy 105.506266 -244.484398) (xy 105.505771 -244.509005) (xy 105.497876 -244.557582) (xy 105.482292 -244.604263)
			(xy 105.459421 -244.64784) (xy 105.429856 -244.687184) (xy 105.394363 -244.721276) (xy 105.35386 -244.749232)
			(xy 105.309398 -244.77033) (xy 105.262127 -244.784022) (xy 105.213272 -244.789954) (xy 105.164097 -244.787973)
			(xy 105.115878 -244.778129) (xy 105.069862 -244.760677) (xy 105.027241 -244.73607) (xy 104.98912 -244.704945)
			(xy 104.956485 -244.668108) (xy 104.930182 -244.626512) (xy 104.910891 -244.581236) (xy 104.899114 -244.533452)
			(xy 104.895154 -244.484398) (xy 104.57688 -244.484398) (xy 104.576368 -244.509844) (xy 104.568204 -244.560078)
			(xy 104.552088 -244.608352) (xy 104.528437 -244.653415) (xy 104.497864 -244.694101) (xy 104.46116 -244.729356)
			(xy 104.419276 -244.758266) (xy 104.373297 -244.780083) (xy 104.324413 -244.794243) (xy 104.273892 -244.800377)
			(xy 104.22304 -244.798328) (xy 104.173176 -244.788148) (xy 104.12559 -244.770101) (xy 104.081516 -244.744655)
			(xy 104.042094 -244.712468) (xy 104.008346 -244.674374) (xy 103.981145 -244.63136) (xy 103.961197 -244.58454)
			(xy 103.949018 -244.535126) (xy 103.944923 -244.484398) (xy 103.636826 -244.484398) (xy 103.636314 -244.509844)
			(xy 103.62815 -244.560078) (xy 103.612034 -244.608352) (xy 103.588383 -244.653415) (xy 103.55781 -244.694101)
			(xy 103.521106 -244.729356) (xy 103.479222 -244.758266) (xy 103.433243 -244.780083) (xy 103.384359 -244.794243)
			(xy 103.333838 -244.800377) (xy 103.282986 -244.798328) (xy 103.233122 -244.788148) (xy 103.185536 -244.770101)
			(xy 103.141462 -244.744655) (xy 103.10204 -244.712468) (xy 103.068292 -244.674374) (xy 103.041091 -244.63136)
			(xy 103.021143 -244.58454) (xy 103.008964 -244.535126) (xy 103.004869 -244.484398) (xy 102.686358 -244.484398)
			(xy 102.685863 -244.509005) (xy 102.677968 -244.557582) (xy 102.662384 -244.604263) (xy 102.639513 -244.64784)
			(xy 102.609948 -244.687184) (xy 102.574455 -244.721276) (xy 102.533952 -244.749232) (xy 102.48949 -244.77033)
			(xy 102.442219 -244.784022) (xy 102.393364 -244.789954) (xy 102.344189 -244.787973) (xy 102.29597 -244.778129)
			(xy 102.249954 -244.760677) (xy 102.207333 -244.73607) (xy 102.169212 -244.704945) (xy 102.136577 -244.668108)
			(xy 102.110274 -244.626512) (xy 102.090983 -244.581236) (xy 102.079206 -244.533452) (xy 102.075246 -244.484398)
			(xy 101.756718 -244.484398) (xy 101.756206 -244.509844) (xy 101.748042 -244.560078) (xy 101.731926 -244.608352)
			(xy 101.708275 -244.653415) (xy 101.677702 -244.694101) (xy 101.640998 -244.729356) (xy 101.599114 -244.758266)
			(xy 101.553135 -244.780083) (xy 101.504251 -244.794243) (xy 101.45373 -244.800377) (xy 101.402878 -244.798328)
			(xy 101.353014 -244.788148) (xy 101.305428 -244.770101) (xy 101.261354 -244.744655) (xy 101.221932 -244.712468)
			(xy 101.188184 -244.674374) (xy 101.160983 -244.63136) (xy 101.141035 -244.58454) (xy 101.128856 -244.535126)
			(xy 101.124761 -244.484398) (xy 100.816664 -244.484398) (xy 100.816152 -244.509844) (xy 100.807988 -244.560078)
			(xy 100.791872 -244.608352) (xy 100.768221 -244.653415) (xy 100.737648 -244.694101) (xy 100.700944 -244.729356)
			(xy 100.65906 -244.758266) (xy 100.613081 -244.780083) (xy 100.564197 -244.794243) (xy 100.513676 -244.800377)
			(xy 100.462824 -244.798328) (xy 100.41296 -244.788148) (xy 100.365374 -244.770101) (xy 100.3213 -244.744655)
			(xy 100.281878 -244.712468) (xy 100.24813 -244.674374) (xy 100.220929 -244.63136) (xy 100.200981 -244.58454)
			(xy 100.188802 -244.535126) (xy 100.184707 -244.484398) (xy 99.86645 -244.484398) (xy 99.865955 -244.509005)
			(xy 99.85806 -244.557582) (xy 99.842476 -244.604263) (xy 99.819605 -244.64784) (xy 99.79004 -244.687184)
			(xy 99.754547 -244.721276) (xy 99.714044 -244.749232) (xy 99.669582 -244.77033) (xy 99.622311 -244.784022)
			(xy 99.573456 -244.789954) (xy 99.524281 -244.787973) (xy 99.476062 -244.778129) (xy 99.430046 -244.760677)
			(xy 99.387425 -244.73607) (xy 99.349304 -244.704945) (xy 99.316669 -244.668108) (xy 99.290366 -244.626512)
			(xy 99.271075 -244.581236) (xy 99.259298 -244.533452) (xy 99.255338 -244.484398) (xy 98.93681 -244.484398)
			(xy 98.936298 -244.509844) (xy 98.928134 -244.560078) (xy 98.912018 -244.608352) (xy 98.888367 -244.653415)
			(xy 98.857794 -244.694101) (xy 98.82109 -244.729356) (xy 98.779206 -244.758266) (xy 98.733227 -244.780083)
			(xy 98.684343 -244.794243) (xy 98.633822 -244.800377) (xy 98.58297 -244.798328) (xy 98.533106 -244.788148)
			(xy 98.48552 -244.770101) (xy 98.441446 -244.744655) (xy 98.402024 -244.712468) (xy 98.368276 -244.674374)
			(xy 98.341075 -244.63136) (xy 98.321127 -244.58454) (xy 98.308948 -244.535126) (xy 98.304853 -244.484398)
			(xy 97.996756 -244.484398) (xy 97.996244 -244.509844) (xy 97.98808 -244.560078) (xy 97.971964 -244.608352)
			(xy 97.948313 -244.653415) (xy 97.91774 -244.694101) (xy 97.881036 -244.729356) (xy 97.839152 -244.758266)
			(xy 97.793173 -244.780083) (xy 97.744289 -244.794243) (xy 97.693768 -244.800377) (xy 97.642916 -244.798328)
			(xy 97.593052 -244.788148) (xy 97.545466 -244.770101) (xy 97.501392 -244.744655) (xy 97.46197 -244.712468)
			(xy 97.428222 -244.674374) (xy 97.401021 -244.63136) (xy 97.381073 -244.58454) (xy 97.368894 -244.535126)
			(xy 97.364799 -244.484398) (xy 97.046288 -244.484398) (xy 97.045793 -244.509005) (xy 97.037898 -244.557582)
			(xy 97.022314 -244.604263) (xy 96.999443 -244.64784) (xy 96.969878 -244.687184) (xy 96.934385 -244.721276)
			(xy 96.893882 -244.749232) (xy 96.84942 -244.77033) (xy 96.802149 -244.784022) (xy 96.753294 -244.789954)
			(xy 96.704119 -244.787973) (xy 96.6559 -244.778129) (xy 96.609884 -244.760677) (xy 96.567263 -244.73607)
			(xy 96.529142 -244.704945) (xy 96.496507 -244.668108) (xy 96.470204 -244.626512) (xy 96.450913 -244.581236)
			(xy 96.439136 -244.533452) (xy 96.435176 -244.484398) (xy 96.116648 -244.484398) (xy 96.116136 -244.509844)
			(xy 96.107972 -244.560078) (xy 96.091856 -244.608352) (xy 96.068205 -244.653415) (xy 96.037632 -244.694101)
			(xy 96.000928 -244.729356) (xy 95.959044 -244.758266) (xy 95.913065 -244.780083) (xy 95.864181 -244.794243)
			(xy 95.81366 -244.800377) (xy 95.762808 -244.798328) (xy 95.712944 -244.788148) (xy 95.665358 -244.770101)
			(xy 95.621284 -244.744655) (xy 95.581862 -244.712468) (xy 95.548114 -244.674374) (xy 95.520913 -244.63136)
			(xy 95.500965 -244.58454) (xy 95.488786 -244.535126) (xy 95.484691 -244.484398) (xy 95.166434 -244.484398)
			(xy 95.165939 -244.509005) (xy 95.158044 -244.557582) (xy 95.14246 -244.604263) (xy 95.119589 -244.64784)
			(xy 95.090024 -244.687184) (xy 95.054531 -244.721276) (xy 95.014028 -244.749232) (xy 94.969566 -244.77033)
			(xy 94.922295 -244.784022) (xy 94.87344 -244.789954) (xy 94.824265 -244.787973) (xy 94.776046 -244.778129)
			(xy 94.73003 -244.760677) (xy 94.687409 -244.73607) (xy 94.649288 -244.704945) (xy 94.616653 -244.668108)
			(xy 94.59035 -244.626512) (xy 94.571059 -244.581236) (xy 94.559282 -244.533452) (xy 94.555322 -244.484398)
			(xy 94.236794 -244.484398) (xy 94.236282 -244.509844) (xy 94.228118 -244.560078) (xy 94.212002 -244.608352)
			(xy 94.188351 -244.653415) (xy 94.157778 -244.694101) (xy 94.121074 -244.729356) (xy 94.07919 -244.758266)
			(xy 94.033211 -244.780083) (xy 93.984327 -244.794243) (xy 93.933806 -244.800377) (xy 93.882954 -244.798328)
			(xy 93.83309 -244.788148) (xy 93.785504 -244.770101) (xy 93.74143 -244.744655) (xy 93.702008 -244.712468)
			(xy 93.66826 -244.674374) (xy 93.641059 -244.63136) (xy 93.621111 -244.58454) (xy 93.608932 -244.535126)
			(xy 93.604837 -244.484398) (xy 93.286326 -244.484398) (xy 93.285831 -244.509005) (xy 93.277936 -244.557582)
			(xy 93.262352 -244.604263) (xy 93.239481 -244.64784) (xy 93.209916 -244.687184) (xy 93.174423 -244.721276)
			(xy 93.13392 -244.749232) (xy 93.089458 -244.77033) (xy 93.042187 -244.784022) (xy 92.993332 -244.789954)
			(xy 92.944157 -244.787973) (xy 92.895938 -244.778129) (xy 92.849922 -244.760677) (xy 92.807301 -244.73607)
			(xy 92.76918 -244.704945) (xy 92.736545 -244.668108) (xy 92.710242 -244.626512) (xy 92.690951 -244.581236)
			(xy 92.679174 -244.533452) (xy 92.675214 -244.484398) (xy 92.356686 -244.484398) (xy 92.356174 -244.509844)
			(xy 92.34801 -244.560078) (xy 92.331894 -244.608352) (xy 92.308243 -244.653415) (xy 92.27767 -244.694101)
			(xy 92.240966 -244.729356) (xy 92.199082 -244.758266) (xy 92.153103 -244.780083) (xy 92.104219 -244.794243)
			(xy 92.053698 -244.800377) (xy 92.002846 -244.798328) (xy 91.952982 -244.788148) (xy 91.905396 -244.770101)
			(xy 91.861322 -244.744655) (xy 91.8219 -244.712468) (xy 91.788152 -244.674374) (xy 91.760951 -244.63136)
			(xy 91.741003 -244.58454) (xy 91.728824 -244.535126) (xy 91.724729 -244.484398) (xy 91.416632 -244.484398)
			(xy 91.41612 -244.509844) (xy 91.407956 -244.560078) (xy 91.39184 -244.608352) (xy 91.368189 -244.653415)
			(xy 91.337616 -244.694101) (xy 91.300912 -244.729356) (xy 91.259028 -244.758266) (xy 91.213049 -244.780083)
			(xy 91.164165 -244.794243) (xy 91.113644 -244.800377) (xy 91.062792 -244.798328) (xy 91.012928 -244.788148)
			(xy 90.965342 -244.770101) (xy 90.921268 -244.744655) (xy 90.881846 -244.712468) (xy 90.848098 -244.674374)
			(xy 90.820897 -244.63136) (xy 90.800949 -244.58454) (xy 90.78877 -244.535126) (xy 90.784675 -244.484398)
			(xy 90.466418 -244.484398) (xy 90.465923 -244.509005) (xy 90.458028 -244.557582) (xy 90.442444 -244.604263)
			(xy 90.419573 -244.64784) (xy 90.390008 -244.687184) (xy 90.354515 -244.721276) (xy 90.314012 -244.749232)
			(xy 90.26955 -244.77033) (xy 90.222279 -244.784022) (xy 90.173424 -244.789954) (xy 90.124249 -244.787973)
			(xy 90.07603 -244.778129) (xy 90.030014 -244.760677) (xy 89.987393 -244.73607) (xy 89.949272 -244.704945)
			(xy 89.916637 -244.668108) (xy 89.890334 -244.626512) (xy 89.871043 -244.581236) (xy 89.859266 -244.533452)
			(xy 89.855306 -244.484398) (xy 89.536778 -244.484398) (xy 89.536266 -244.509844) (xy 89.528102 -244.560078)
			(xy 89.511986 -244.608352) (xy 89.488335 -244.653415) (xy 89.457762 -244.694101) (xy 89.421058 -244.729356)
			(xy 89.379174 -244.758266) (xy 89.333195 -244.780083) (xy 89.284311 -244.794243) (xy 89.23379 -244.800377)
			(xy 89.182938 -244.798328) (xy 89.133074 -244.788148) (xy 89.085488 -244.770101) (xy 89.041414 -244.744655)
			(xy 89.001992 -244.712468) (xy 88.968244 -244.674374) (xy 88.941043 -244.63136) (xy 88.921095 -244.58454)
			(xy 88.908916 -244.535126) (xy 88.904821 -244.484398) (xy 88.58631 -244.484398) (xy 88.585815 -244.509005)
			(xy 88.57792 -244.557582) (xy 88.562336 -244.604263) (xy 88.539465 -244.64784) (xy 88.5099 -244.687184)
			(xy 88.474407 -244.721276) (xy 88.433904 -244.749232) (xy 88.389442 -244.77033) (xy 88.342171 -244.784022)
			(xy 88.293316 -244.789954) (xy 88.244141 -244.787973) (xy 88.195922 -244.778129) (xy 88.149906 -244.760677)
			(xy 88.107285 -244.73607) (xy 88.069164 -244.704945) (xy 88.036529 -244.668108) (xy 88.010226 -244.626512)
			(xy 87.990935 -244.581236) (xy 87.979158 -244.533452) (xy 87.975198 -244.484398) (xy 87.65667 -244.484398)
			(xy 87.656158 -244.509844) (xy 87.647994 -244.560078) (xy 87.631878 -244.608352) (xy 87.608227 -244.653415)
			(xy 87.577654 -244.694101) (xy 87.54095 -244.729356) (xy 87.499066 -244.758266) (xy 87.453087 -244.780083)
			(xy 87.404203 -244.794243) (xy 87.353682 -244.800377) (xy 87.30283 -244.798328) (xy 87.252966 -244.788148)
			(xy 87.20538 -244.770101) (xy 87.161306 -244.744655) (xy 87.121884 -244.712468) (xy 87.088136 -244.674374)
			(xy 87.060935 -244.63136) (xy 87.040987 -244.58454) (xy 87.028808 -244.535126) (xy 87.024713 -244.484398)
			(xy 86.706456 -244.484398) (xy 86.705961 -244.509005) (xy 86.698066 -244.557582) (xy 86.682482 -244.604263)
			(xy 86.659611 -244.64784) (xy 86.630046 -244.687184) (xy 86.594553 -244.721276) (xy 86.55405 -244.749232)
			(xy 86.509588 -244.77033) (xy 86.462317 -244.784022) (xy 86.413462 -244.789954) (xy 86.364287 -244.787973)
			(xy 86.316068 -244.778129) (xy 86.270052 -244.760677) (xy 86.227431 -244.73607) (xy 86.18931 -244.704945)
			(xy 86.156675 -244.668108) (xy 86.130372 -244.626512) (xy 86.111081 -244.581236) (xy 86.099304 -244.533452)
			(xy 86.095344 -244.484398) (xy 85.776816 -244.484398) (xy 85.776304 -244.509844) (xy 85.76814 -244.560078)
			(xy 85.752024 -244.608352) (xy 85.728373 -244.653415) (xy 85.6978 -244.694101) (xy 85.661096 -244.729356)
			(xy 85.619212 -244.758266) (xy 85.573233 -244.780083) (xy 85.524349 -244.794243) (xy 85.473828 -244.800377)
			(xy 85.422976 -244.798328) (xy 85.373112 -244.788148) (xy 85.325526 -244.770101) (xy 85.281452 -244.744655)
			(xy 85.24203 -244.712468) (xy 85.208282 -244.674374) (xy 85.181081 -244.63136) (xy 85.161133 -244.58454)
			(xy 85.148954 -244.535126) (xy 85.144859 -244.484398) (xy 84.836762 -244.484398) (xy 84.83625 -244.509844)
			(xy 84.828086 -244.560078) (xy 84.81197 -244.608352) (xy 84.788319 -244.653415) (xy 84.757746 -244.694101)
			(xy 84.721042 -244.729356) (xy 84.679158 -244.758266) (xy 84.633179 -244.780083) (xy 84.584295 -244.794243)
			(xy 84.533774 -244.800377) (xy 84.482922 -244.798328) (xy 84.433058 -244.788148) (xy 84.385472 -244.770101)
			(xy 84.341398 -244.744655) (xy 84.301976 -244.712468) (xy 84.268228 -244.674374) (xy 84.241027 -244.63136)
			(xy 84.221079 -244.58454) (xy 84.2089 -244.535126) (xy 84.204805 -244.484398) (xy 83.886294 -244.484398)
			(xy 83.885799 -244.509005) (xy 83.877904 -244.557582) (xy 83.86232 -244.604263) (xy 83.839449 -244.64784)
			(xy 83.809884 -244.687184) (xy 83.774391 -244.721276) (xy 83.733888 -244.749232) (xy 83.689426 -244.77033)
			(xy 83.642155 -244.784022) (xy 83.5933 -244.789954) (xy 83.544125 -244.787973) (xy 83.495906 -244.778129)
			(xy 83.44989 -244.760677) (xy 83.407269 -244.73607) (xy 83.369148 -244.704945) (xy 83.336513 -244.668108)
			(xy 83.31021 -244.626512) (xy 83.290919 -244.581236) (xy 83.279142 -244.533452) (xy 83.275182 -244.484398)
			(xy 82.956654 -244.484398) (xy 82.956142 -244.509844) (xy 82.947978 -244.560078) (xy 82.931862 -244.608352)
			(xy 82.908211 -244.653415) (xy 82.877638 -244.694101) (xy 82.840934 -244.729356) (xy 82.79905 -244.758266)
			(xy 82.753071 -244.780083) (xy 82.704187 -244.794243) (xy 82.653666 -244.800377) (xy 82.602814 -244.798328)
			(xy 82.55295 -244.788148) (xy 82.505364 -244.770101) (xy 82.46129 -244.744655) (xy 82.421868 -244.712468)
			(xy 82.38812 -244.674374) (xy 82.360919 -244.63136) (xy 82.340971 -244.58454) (xy 82.328792 -244.535126)
			(xy 82.324697 -244.484398) (xy 82.00644 -244.484398) (xy 82.005945 -244.509005) (xy 81.99805 -244.557582)
			(xy 81.982466 -244.604263) (xy 81.959595 -244.64784) (xy 81.93003 -244.687184) (xy 81.894537 -244.721276)
			(xy 81.854034 -244.749232) (xy 81.809572 -244.77033) (xy 81.762301 -244.784022) (xy 81.713446 -244.789954)
			(xy 81.664271 -244.787973) (xy 81.616052 -244.778129) (xy 81.570036 -244.760677) (xy 81.527415 -244.73607)
			(xy 81.489294 -244.704945) (xy 81.456659 -244.668108) (xy 81.430356 -244.626512) (xy 81.411065 -244.581236)
			(xy 81.399288 -244.533452) (xy 81.395328 -244.484398) (xy 81.0768 -244.484398) (xy 81.076288 -244.509844)
			(xy 81.068124 -244.560078) (xy 81.052008 -244.608352) (xy 81.028357 -244.653415) (xy 80.997784 -244.694101)
			(xy 80.96108 -244.729356) (xy 80.919196 -244.758266) (xy 80.873217 -244.780083) (xy 80.824333 -244.794243)
			(xy 80.773812 -244.800377) (xy 80.72296 -244.798328) (xy 80.673096 -244.788148) (xy 80.62551 -244.770101)
			(xy 80.581436 -244.744655) (xy 80.542014 -244.712468) (xy 80.508266 -244.674374) (xy 80.481065 -244.63136)
			(xy 80.461117 -244.58454) (xy 80.448938 -244.535126) (xy 80.444843 -244.484398) (xy 80.126332 -244.484398)
			(xy 80.125837 -244.509005) (xy 80.117942 -244.557582) (xy 80.102358 -244.604263) (xy 80.079487 -244.64784)
			(xy 80.049922 -244.687184) (xy 80.014429 -244.721276) (xy 79.973926 -244.749232) (xy 79.929464 -244.77033)
			(xy 79.882193 -244.784022) (xy 79.833338 -244.789954) (xy 79.784163 -244.787973) (xy 79.735944 -244.778129)
			(xy 79.689928 -244.760677) (xy 79.647307 -244.73607) (xy 79.609186 -244.704945) (xy 79.576551 -244.668108)
			(xy 79.550248 -244.626512) (xy 79.530957 -244.581236) (xy 79.51918 -244.533452) (xy 79.51522 -244.484398)
			(xy 76.963477 -244.484398) (xy 76.965804 -244.485502) (xy 77.006307 -244.513458) (xy 77.0418 -244.54755)
			(xy 77.071365 -244.586894) (xy 77.094236 -244.630471) (xy 77.10982 -244.677152) (xy 77.117715 -244.725729)
			(xy 77.11821 -244.750336) (xy 77.117715 -244.774943) (xy 77.10982 -244.82352) (xy 77.094236 -244.870201)
			(xy 77.071365 -244.913778) (xy 77.0418 -244.953122) (xy 77.006307 -244.987214) (xy 76.965804 -245.01517)
			(xy 76.921342 -245.036268) (xy 76.874071 -245.04996) (xy 76.825216 -245.055892) (xy 76.776041 -245.053911)
			(xy 76.727822 -245.044067) (xy 76.681806 -245.026615) (xy 76.639185 -245.002008) (xy 76.601064 -244.970883)
			(xy 76.568429 -244.934046) (xy 76.542126 -244.89245) (xy 76.522835 -244.847174) (xy 76.511058 -244.79939)
			(xy 76.507098 -244.750336) (xy 62.37732 -244.750336) (xy 62.37732 -245.294404) (xy 78.105266 -245.294404)
			(xy 78.109226 -245.24535) (xy 78.121003 -245.197566) (xy 78.140294 -245.15229) (xy 78.166597 -245.110694)
			(xy 78.199232 -245.073857) (xy 78.237353 -245.042732) (xy 78.279974 -245.018125) (xy 78.32599 -245.000673)
			(xy 78.374209 -244.990829) (xy 78.423384 -244.988848) (xy 78.472239 -244.99478) (xy 78.51951 -245.008472)
			(xy 78.563972 -245.02957) (xy 78.604475 -245.057526) (xy 78.639968 -245.091618) (xy 78.669533 -245.130962)
			(xy 78.692404 -245.174539) (xy 78.707988 -245.22122) (xy 78.715883 -245.269797) (xy 78.716378 -245.294404)
			(xy 79.985374 -245.294404) (xy 79.989334 -245.24535) (xy 80.001111 -245.197566) (xy 80.020402 -245.15229)
			(xy 80.046705 -245.110694) (xy 80.07934 -245.073857) (xy 80.117461 -245.042732) (xy 80.160082 -245.018125)
			(xy 80.206098 -245.000673) (xy 80.254317 -244.990829) (xy 80.303492 -244.988848) (xy 80.352347 -244.99478)
			(xy 80.399618 -245.008472) (xy 80.44408 -245.02957) (xy 80.484583 -245.057526) (xy 80.520076 -245.091618)
			(xy 80.549641 -245.130962) (xy 80.572512 -245.174539) (xy 80.588096 -245.22122) (xy 80.595991 -245.269797)
			(xy 80.596486 -245.294404) (xy 80.914743 -245.294404) (xy 80.918838 -245.243676) (xy 80.931017 -245.194262)
			(xy 80.950965 -245.147442) (xy 80.978166 -245.104428) (xy 81.011914 -245.066334) (xy 81.051336 -245.034147)
			(xy 81.09541 -245.008701) (xy 81.142996 -244.990654) (xy 81.19286 -244.980474) (xy 81.243712 -244.978425)
			(xy 81.294233 -244.984559) (xy 81.343117 -244.998719) (xy 81.389096 -245.020536) (xy 81.43098 -245.049446)
			(xy 81.467684 -245.084701) (xy 81.498257 -245.125387) (xy 81.521908 -245.17045) (xy 81.538024 -245.218724)
			(xy 81.546188 -245.268958) (xy 81.5467 -245.294404) (xy 81.854797 -245.294404) (xy 81.858892 -245.243676)
			(xy 81.871071 -245.194262) (xy 81.891019 -245.147442) (xy 81.91822 -245.104428) (xy 81.951968 -245.066334)
			(xy 81.99139 -245.034147) (xy 82.035464 -245.008701) (xy 82.08305 -244.990654) (xy 82.132914 -244.980474)
			(xy 82.183766 -244.978425) (xy 82.234287 -244.984559) (xy 82.283171 -244.998719) (xy 82.32915 -245.020536)
			(xy 82.371034 -245.049446) (xy 82.407738 -245.084701) (xy 82.438311 -245.125387) (xy 82.461962 -245.17045)
			(xy 82.478078 -245.218724) (xy 82.486242 -245.268958) (xy 82.486754 -245.294404) (xy 82.805282 -245.294404)
			(xy 82.809242 -245.24535) (xy 82.821019 -245.197566) (xy 82.84031 -245.15229) (xy 82.866613 -245.110694)
			(xy 82.899248 -245.073857) (xy 82.937369 -245.042732) (xy 82.97999 -245.018125) (xy 83.026006 -245.000673)
			(xy 83.074225 -244.990829) (xy 83.1234 -244.988848) (xy 83.172255 -244.99478) (xy 83.219526 -245.008472)
			(xy 83.263988 -245.02957) (xy 83.304491 -245.057526) (xy 83.339984 -245.091618) (xy 83.369549 -245.130962)
			(xy 83.39242 -245.174539) (xy 83.408004 -245.22122) (xy 83.415899 -245.269797) (xy 83.416394 -245.294404)
			(xy 83.734905 -245.294404) (xy 83.739 -245.243676) (xy 83.751179 -245.194262) (xy 83.771127 -245.147442)
			(xy 83.798328 -245.104428) (xy 83.832076 -245.066334) (xy 83.871498 -245.034147) (xy 83.915572 -245.008701)
			(xy 83.963158 -244.990654) (xy 84.013022 -244.980474) (xy 84.063874 -244.978425) (xy 84.114395 -244.984559)
			(xy 84.163279 -244.998719) (xy 84.209258 -245.020536) (xy 84.251142 -245.049446) (xy 84.287846 -245.084701)
			(xy 84.318419 -245.125387) (xy 84.34207 -245.17045) (xy 84.358186 -245.218724) (xy 84.36635 -245.268958)
			(xy 84.366862 -245.294404) (xy 84.685136 -245.294404) (xy 84.689096 -245.24535) (xy 84.700873 -245.197566)
			(xy 84.720164 -245.15229) (xy 84.746467 -245.110694) (xy 84.779102 -245.073857) (xy 84.817223 -245.042732)
			(xy 84.859844 -245.018125) (xy 84.90586 -245.000673) (xy 84.954079 -244.990829) (xy 85.003254 -244.988848)
			(xy 85.052109 -244.99478) (xy 85.09938 -245.008472) (xy 85.143842 -245.02957) (xy 85.184345 -245.057526)
			(xy 85.219838 -245.091618) (xy 85.249403 -245.130962) (xy 85.272274 -245.174539) (xy 85.287858 -245.22122)
			(xy 85.295753 -245.269797) (xy 85.296248 -245.294404) (xy 85.614759 -245.294404) (xy 85.618854 -245.243676)
			(xy 85.631033 -245.194262) (xy 85.650981 -245.147442) (xy 85.678182 -245.104428) (xy 85.71193 -245.066334)
			(xy 85.751352 -245.034147) (xy 85.795426 -245.008701) (xy 85.843012 -244.990654) (xy 85.892876 -244.980474)
			(xy 85.943728 -244.978425) (xy 85.994249 -244.984559) (xy 86.043133 -244.998719) (xy 86.089112 -245.020536)
			(xy 86.130996 -245.049446) (xy 86.1677 -245.084701) (xy 86.198273 -245.125387) (xy 86.221924 -245.17045)
			(xy 86.23804 -245.218724) (xy 86.246204 -245.268958) (xy 86.246716 -245.294404) (xy 86.565244 -245.294404)
			(xy 86.569204 -245.24535) (xy 86.580981 -245.197566) (xy 86.600272 -245.15229) (xy 86.626575 -245.110694)
			(xy 86.65921 -245.073857) (xy 86.697331 -245.042732) (xy 86.739952 -245.018125) (xy 86.785968 -245.000673)
			(xy 86.834187 -244.990829) (xy 86.883362 -244.988848) (xy 86.932217 -244.99478) (xy 86.979488 -245.008472)
			(xy 87.02395 -245.02957) (xy 87.064453 -245.057526) (xy 87.099946 -245.091618) (xy 87.129511 -245.130962)
			(xy 87.152382 -245.174539) (xy 87.167966 -245.22122) (xy 87.175861 -245.269797) (xy 87.176356 -245.294404)
			(xy 87.494867 -245.294404) (xy 87.498962 -245.243676) (xy 87.511141 -245.194262) (xy 87.531089 -245.147442)
			(xy 87.55829 -245.104428) (xy 87.592038 -245.066334) (xy 87.63146 -245.034147) (xy 87.675534 -245.008701)
			(xy 87.72312 -244.990654) (xy 87.772984 -244.980474) (xy 87.823836 -244.978425) (xy 87.874357 -244.984559)
			(xy 87.923241 -244.998719) (xy 87.96922 -245.020536) (xy 88.011104 -245.049446) (xy 88.047808 -245.084701)
			(xy 88.078381 -245.125387) (xy 88.102032 -245.17045) (xy 88.118148 -245.218724) (xy 88.126312 -245.268958)
			(xy 88.126824 -245.294404) (xy 88.434921 -245.294404) (xy 88.439016 -245.243676) (xy 88.451195 -245.194262)
			(xy 88.471143 -245.147442) (xy 88.498344 -245.104428) (xy 88.532092 -245.066334) (xy 88.571514 -245.034147)
			(xy 88.615588 -245.008701) (xy 88.663174 -244.990654) (xy 88.713038 -244.980474) (xy 88.76389 -244.978425)
			(xy 88.814411 -244.984559) (xy 88.863295 -244.998719) (xy 88.909274 -245.020536) (xy 88.951158 -245.049446)
			(xy 88.987862 -245.084701) (xy 89.018435 -245.125387) (xy 89.042086 -245.17045) (xy 89.058202 -245.218724)
			(xy 89.066366 -245.268958) (xy 89.066878 -245.294404) (xy 89.385152 -245.294404) (xy 89.389112 -245.24535)
			(xy 89.400889 -245.197566) (xy 89.42018 -245.15229) (xy 89.446483 -245.110694) (xy 89.479118 -245.073857)
			(xy 89.517239 -245.042732) (xy 89.55986 -245.018125) (xy 89.605876 -245.000673) (xy 89.654095 -244.990829)
			(xy 89.70327 -244.988848) (xy 89.752125 -244.99478) (xy 89.799396 -245.008472) (xy 89.843858 -245.02957)
			(xy 89.884361 -245.057526) (xy 89.919854 -245.091618) (xy 89.949419 -245.130962) (xy 89.97229 -245.174539)
			(xy 89.987874 -245.22122) (xy 89.995769 -245.269797) (xy 89.996264 -245.294404) (xy 90.314775 -245.294404)
			(xy 90.31887 -245.243676) (xy 90.331049 -245.194262) (xy 90.350997 -245.147442) (xy 90.378198 -245.104428)
			(xy 90.411946 -245.066334) (xy 90.451368 -245.034147) (xy 90.495442 -245.008701) (xy 90.543028 -244.990654)
			(xy 90.592892 -244.980474) (xy 90.643744 -244.978425) (xy 90.694265 -244.984559) (xy 90.743149 -244.998719)
			(xy 90.789128 -245.020536) (xy 90.831012 -245.049446) (xy 90.867716 -245.084701) (xy 90.898289 -245.125387)
			(xy 90.92194 -245.17045) (xy 90.938056 -245.218724) (xy 90.94622 -245.268958) (xy 90.946732 -245.294404)
			(xy 91.26526 -245.294404) (xy 91.26922 -245.24535) (xy 91.280997 -245.197566) (xy 91.300288 -245.15229)
			(xy 91.326591 -245.110694) (xy 91.359226 -245.073857) (xy 91.397347 -245.042732) (xy 91.439968 -245.018125)
			(xy 91.485984 -245.000673) (xy 91.534203 -244.990829) (xy 91.583378 -244.988848) (xy 91.632233 -244.99478)
			(xy 91.679504 -245.008472) (xy 91.723966 -245.02957) (xy 91.764469 -245.057526) (xy 91.799962 -245.091618)
			(xy 91.829527 -245.130962) (xy 91.852398 -245.174539) (xy 91.867982 -245.22122) (xy 91.875877 -245.269797)
			(xy 91.876372 -245.294404) (xy 92.194883 -245.294404) (xy 92.198978 -245.243676) (xy 92.211157 -245.194262)
			(xy 92.231105 -245.147442) (xy 92.258306 -245.104428) (xy 92.292054 -245.066334) (xy 92.331476 -245.034147)
			(xy 92.37555 -245.008701) (xy 92.423136 -244.990654) (xy 92.473 -244.980474) (xy 92.523852 -244.978425)
			(xy 92.574373 -244.984559) (xy 92.623257 -244.998719) (xy 92.669236 -245.020536) (xy 92.71112 -245.049446)
			(xy 92.747824 -245.084701) (xy 92.778397 -245.125387) (xy 92.802048 -245.17045) (xy 92.818164 -245.218724)
			(xy 92.826328 -245.268958) (xy 92.82684 -245.294404) (xy 93.145114 -245.294404) (xy 93.149074 -245.24535)
			(xy 93.160851 -245.197566) (xy 93.180142 -245.15229) (xy 93.206445 -245.110694) (xy 93.23908 -245.073857)
			(xy 93.277201 -245.042732) (xy 93.319822 -245.018125) (xy 93.365838 -245.000673) (xy 93.414057 -244.990829)
			(xy 93.463232 -244.988848) (xy 93.512087 -244.99478) (xy 93.559358 -245.008472) (xy 93.60382 -245.02957)
			(xy 93.644323 -245.057526) (xy 93.679816 -245.091618) (xy 93.709381 -245.130962) (xy 93.732252 -245.174539)
			(xy 93.747836 -245.22122) (xy 93.755731 -245.269797) (xy 93.756226 -245.294404) (xy 94.074737 -245.294404)
			(xy 94.078832 -245.243676) (xy 94.091011 -245.194262) (xy 94.110959 -245.147442) (xy 94.13816 -245.104428)
			(xy 94.171908 -245.066334) (xy 94.21133 -245.034147) (xy 94.255404 -245.008701) (xy 94.30299 -244.990654)
			(xy 94.352854 -244.980474) (xy 94.403706 -244.978425) (xy 94.454227 -244.984559) (xy 94.503111 -244.998719)
			(xy 94.54909 -245.020536) (xy 94.590974 -245.049446) (xy 94.627678 -245.084701) (xy 94.658251 -245.125387)
			(xy 94.681902 -245.17045) (xy 94.698018 -245.218724) (xy 94.706182 -245.268958) (xy 94.706694 -245.294404)
			(xy 95.014791 -245.294404) (xy 95.018886 -245.243676) (xy 95.031065 -245.194262) (xy 95.051013 -245.147442)
			(xy 95.078214 -245.104428) (xy 95.111962 -245.066334) (xy 95.151384 -245.034147) (xy 95.195458 -245.008701)
			(xy 95.243044 -244.990654) (xy 95.292908 -244.980474) (xy 95.34376 -244.978425) (xy 95.394281 -244.984559)
			(xy 95.443165 -244.998719) (xy 95.489144 -245.020536) (xy 95.531028 -245.049446) (xy 95.567732 -245.084701)
			(xy 95.598305 -245.125387) (xy 95.621956 -245.17045) (xy 95.638072 -245.218724) (xy 95.646236 -245.268958)
			(xy 95.646748 -245.294404) (xy 95.965276 -245.294404) (xy 95.969236 -245.24535) (xy 95.981013 -245.197566)
			(xy 96.000304 -245.15229) (xy 96.026607 -245.110694) (xy 96.059242 -245.073857) (xy 96.097363 -245.042732)
			(xy 96.139984 -245.018125) (xy 96.186 -245.000673) (xy 96.234219 -244.990829) (xy 96.283394 -244.988848)
			(xy 96.332249 -244.99478) (xy 96.37952 -245.008472) (xy 96.423982 -245.02957) (xy 96.464485 -245.057526)
			(xy 96.499978 -245.091618) (xy 96.529543 -245.130962) (xy 96.552414 -245.174539) (xy 96.567998 -245.22122)
			(xy 96.575893 -245.269797) (xy 96.576388 -245.294404) (xy 98.785184 -245.294404) (xy 98.789144 -245.24535)
			(xy 98.800921 -245.197566) (xy 98.820212 -245.15229) (xy 98.846515 -245.110694) (xy 98.87915 -245.073857)
			(xy 98.917271 -245.042732) (xy 98.959892 -245.018125) (xy 99.005908 -245.000673) (xy 99.054127 -244.990829)
			(xy 99.103302 -244.988848) (xy 99.152157 -244.99478) (xy 99.199428 -245.008472) (xy 99.24389 -245.02957)
			(xy 99.284393 -245.057526) (xy 99.319886 -245.091618) (xy 99.349451 -245.130962) (xy 99.372322 -245.174539)
			(xy 99.387906 -245.22122) (xy 99.395801 -245.269797) (xy 99.396296 -245.294404) (xy 101.605346 -245.294404)
			(xy 101.609306 -245.24535) (xy 101.621083 -245.197566) (xy 101.640374 -245.15229) (xy 101.666677 -245.110694)
			(xy 101.699312 -245.073857) (xy 101.737433 -245.042732) (xy 101.780054 -245.018125) (xy 101.82607 -245.000673)
			(xy 101.874289 -244.990829) (xy 101.923464 -244.988848) (xy 101.972319 -244.99478) (xy 102.01959 -245.008472)
			(xy 102.064052 -245.02957) (xy 102.104555 -245.057526) (xy 102.140048 -245.091618) (xy 102.169613 -245.130962)
			(xy 102.192484 -245.174539) (xy 102.208068 -245.22122) (xy 102.215963 -245.269797) (xy 102.216458 -245.294404)
			(xy 104.425254 -245.294404) (xy 104.429214 -245.24535) (xy 104.440991 -245.197566) (xy 104.460282 -245.15229)
			(xy 104.486585 -245.110694) (xy 104.51922 -245.073857) (xy 104.557341 -245.042732) (xy 104.599962 -245.018125)
			(xy 104.645978 -245.000673) (xy 104.694197 -244.990829) (xy 104.743372 -244.988848) (xy 104.792227 -244.99478)
			(xy 104.839498 -245.008472) (xy 104.88396 -245.02957) (xy 104.924463 -245.057526) (xy 104.959956 -245.091618)
			(xy 104.989521 -245.130962) (xy 105.012392 -245.174539) (xy 105.027976 -245.22122) (xy 105.035871 -245.269797)
			(xy 105.036366 -245.294404) (xy 107.245162 -245.294404) (xy 107.249122 -245.24535) (xy 107.260899 -245.197566)
			(xy 107.28019 -245.15229) (xy 107.306493 -245.110694) (xy 107.339128 -245.073857) (xy 107.377249 -245.042732)
			(xy 107.41987 -245.018125) (xy 107.465886 -245.000673) (xy 107.514105 -244.990829) (xy 107.56328 -244.988848)
			(xy 107.612135 -244.99478) (xy 107.659406 -245.008472) (xy 107.703868 -245.02957) (xy 107.744371 -245.057526)
			(xy 107.779864 -245.091618) (xy 107.809429 -245.130962) (xy 107.8323 -245.174539) (xy 107.847884 -245.22122)
			(xy 107.855779 -245.269797) (xy 107.856274 -245.294404) (xy 108.174785 -245.294404) (xy 108.17888 -245.243676)
			(xy 108.191059 -245.194262) (xy 108.211007 -245.147442) (xy 108.238208 -245.104428) (xy 108.271956 -245.066334)
			(xy 108.311378 -245.034147) (xy 108.355452 -245.008701) (xy 108.403038 -244.990654) (xy 108.452902 -244.980474)
			(xy 108.503754 -244.978425) (xy 108.554275 -244.984559) (xy 108.603159 -244.998719) (xy 108.649138 -245.020536)
			(xy 108.691022 -245.049446) (xy 108.727726 -245.084701) (xy 108.758299 -245.125387) (xy 108.78195 -245.17045)
			(xy 108.798066 -245.218724) (xy 108.80623 -245.268958) (xy 108.806742 -245.294404) (xy 109.114839 -245.294404)
			(xy 109.118934 -245.243676) (xy 109.131113 -245.194262) (xy 109.151061 -245.147442) (xy 109.178262 -245.104428)
			(xy 109.21201 -245.066334) (xy 109.251432 -245.034147) (xy 109.295506 -245.008701) (xy 109.343092 -244.990654)
			(xy 109.392956 -244.980474) (xy 109.443808 -244.978425) (xy 109.494329 -244.984559) (xy 109.543213 -244.998719)
			(xy 109.589192 -245.020536) (xy 109.631076 -245.049446) (xy 109.66778 -245.084701) (xy 109.698353 -245.125387)
			(xy 109.722004 -245.17045) (xy 109.73812 -245.218724) (xy 109.746284 -245.268958) (xy 109.746796 -245.294404)
			(xy 110.065324 -245.294404) (xy 110.069284 -245.24535) (xy 110.081061 -245.197566) (xy 110.100352 -245.15229)
			(xy 110.126655 -245.110694) (xy 110.15929 -245.073857) (xy 110.197411 -245.042732) (xy 110.240032 -245.018125)
			(xy 110.286048 -245.000673) (xy 110.334267 -244.990829) (xy 110.383442 -244.988848) (xy 110.432297 -244.99478)
			(xy 110.479568 -245.008472) (xy 110.52403 -245.02957) (xy 110.564533 -245.057526) (xy 110.600026 -245.091618)
			(xy 110.629591 -245.130962) (xy 110.652462 -245.174539) (xy 110.668046 -245.22122) (xy 110.675941 -245.269797)
			(xy 110.676436 -245.294404) (xy 110.675941 -245.319011) (xy 110.668046 -245.367588) (xy 110.652462 -245.414269)
			(xy 110.629591 -245.457846) (xy 110.600026 -245.49719) (xy 110.564533 -245.531282) (xy 110.52403 -245.559238)
			(xy 110.479568 -245.580336) (xy 110.432297 -245.594028) (xy 110.383442 -245.59996) (xy 110.334267 -245.597979)
			(xy 110.286048 -245.588135) (xy 110.240032 -245.570683) (xy 110.197411 -245.546076) (xy 110.15929 -245.514951)
			(xy 110.126655 -245.478114) (xy 110.100352 -245.436518) (xy 110.081061 -245.391242) (xy 110.069284 -245.343458)
			(xy 110.065324 -245.294404) (xy 109.746796 -245.294404) (xy 109.746284 -245.31985) (xy 109.73812 -245.370084)
			(xy 109.722004 -245.418358) (xy 109.698353 -245.463421) (xy 109.66778 -245.504107) (xy 109.631076 -245.539362)
			(xy 109.589192 -245.568272) (xy 109.543213 -245.590089) (xy 109.494329 -245.604249) (xy 109.443808 -245.610383)
			(xy 109.392956 -245.608334) (xy 109.343092 -245.598154) (xy 109.295506 -245.580107) (xy 109.251432 -245.554661)
			(xy 109.21201 -245.522474) (xy 109.178262 -245.48438) (xy 109.151061 -245.441366) (xy 109.131113 -245.394546)
			(xy 109.118934 -245.345132) (xy 109.114839 -245.294404) (xy 108.806742 -245.294404) (xy 108.80623 -245.31985)
			(xy 108.798066 -245.370084) (xy 108.78195 -245.418358) (xy 108.758299 -245.463421) (xy 108.727726 -245.504107)
			(xy 108.691022 -245.539362) (xy 108.649138 -245.568272) (xy 108.603159 -245.590089) (xy 108.554275 -245.604249)
			(xy 108.503754 -245.610383) (xy 108.452902 -245.608334) (xy 108.403038 -245.598154) (xy 108.355452 -245.580107)
			(xy 108.311378 -245.554661) (xy 108.271956 -245.522474) (xy 108.238208 -245.48438) (xy 108.211007 -245.441366)
			(xy 108.191059 -245.394546) (xy 108.17888 -245.345132) (xy 108.174785 -245.294404) (xy 107.856274 -245.294404)
			(xy 107.855779 -245.319011) (xy 107.847884 -245.367588) (xy 107.8323 -245.414269) (xy 107.809429 -245.457846)
			(xy 107.779864 -245.49719) (xy 107.744371 -245.531282) (xy 107.703868 -245.559238) (xy 107.659406 -245.580336)
			(xy 107.612135 -245.594028) (xy 107.56328 -245.59996) (xy 107.514105 -245.597979) (xy 107.465886 -245.588135)
			(xy 107.41987 -245.570683) (xy 107.377249 -245.546076) (xy 107.339128 -245.514951) (xy 107.306493 -245.478114)
			(xy 107.28019 -245.436518) (xy 107.260899 -245.391242) (xy 107.249122 -245.343458) (xy 107.245162 -245.294404)
			(xy 105.036366 -245.294404) (xy 105.035871 -245.319011) (xy 105.027976 -245.367588) (xy 105.012392 -245.414269)
			(xy 104.989521 -245.457846) (xy 104.959956 -245.49719) (xy 104.924463 -245.531282) (xy 104.88396 -245.559238)
			(xy 104.839498 -245.580336) (xy 104.792227 -245.594028) (xy 104.743372 -245.59996) (xy 104.694197 -245.597979)
			(xy 104.645978 -245.588135) (xy 104.599962 -245.570683) (xy 104.557341 -245.546076) (xy 104.51922 -245.514951)
			(xy 104.486585 -245.478114) (xy 104.460282 -245.436518) (xy 104.440991 -245.391242) (xy 104.429214 -245.343458)
			(xy 104.425254 -245.294404) (xy 102.216458 -245.294404) (xy 102.215963 -245.319011) (xy 102.208068 -245.367588)
			(xy 102.192484 -245.414269) (xy 102.169613 -245.457846) (xy 102.140048 -245.49719) (xy 102.104555 -245.531282)
			(xy 102.064052 -245.559238) (xy 102.01959 -245.580336) (xy 101.972319 -245.594028) (xy 101.923464 -245.59996)
			(xy 101.874289 -245.597979) (xy 101.82607 -245.588135) (xy 101.780054 -245.570683) (xy 101.737433 -245.546076)
			(xy 101.699312 -245.514951) (xy 101.666677 -245.478114) (xy 101.640374 -245.436518) (xy 101.621083 -245.391242)
			(xy 101.609306 -245.343458) (xy 101.605346 -245.294404) (xy 99.396296 -245.294404) (xy 99.395801 -245.319011)
			(xy 99.387906 -245.367588) (xy 99.372322 -245.414269) (xy 99.349451 -245.457846) (xy 99.319886 -245.49719)
			(xy 99.284393 -245.531282) (xy 99.24389 -245.559238) (xy 99.199428 -245.580336) (xy 99.152157 -245.594028)
			(xy 99.103302 -245.59996) (xy 99.054127 -245.597979) (xy 99.005908 -245.588135) (xy 98.959892 -245.570683)
			(xy 98.917271 -245.546076) (xy 98.87915 -245.514951) (xy 98.846515 -245.478114) (xy 98.820212 -245.436518)
			(xy 98.800921 -245.391242) (xy 98.789144 -245.343458) (xy 98.785184 -245.294404) (xy 96.576388 -245.294404)
			(xy 96.575893 -245.319011) (xy 96.567998 -245.367588) (xy 96.552414 -245.414269) (xy 96.529543 -245.457846)
			(xy 96.499978 -245.49719) (xy 96.464485 -245.531282) (xy 96.423982 -245.559238) (xy 96.37952 -245.580336)
			(xy 96.332249 -245.594028) (xy 96.283394 -245.59996) (xy 96.234219 -245.597979) (xy 96.186 -245.588135)
			(xy 96.139984 -245.570683) (xy 96.097363 -245.546076) (xy 96.059242 -245.514951) (xy 96.026607 -245.478114)
			(xy 96.000304 -245.436518) (xy 95.981013 -245.391242) (xy 95.969236 -245.343458) (xy 95.965276 -245.294404)
			(xy 95.646748 -245.294404) (xy 95.646236 -245.31985) (xy 95.638072 -245.370084) (xy 95.621956 -245.418358)
			(xy 95.598305 -245.463421) (xy 95.567732 -245.504107) (xy 95.531028 -245.539362) (xy 95.489144 -245.568272)
			(xy 95.443165 -245.590089) (xy 95.394281 -245.604249) (xy 95.34376 -245.610383) (xy 95.292908 -245.608334)
			(xy 95.243044 -245.598154) (xy 95.195458 -245.580107) (xy 95.151384 -245.554661) (xy 95.111962 -245.522474)
			(xy 95.078214 -245.48438) (xy 95.051013 -245.441366) (xy 95.031065 -245.394546) (xy 95.018886 -245.345132)
			(xy 95.014791 -245.294404) (xy 94.706694 -245.294404) (xy 94.706182 -245.31985) (xy 94.698018 -245.370084)
			(xy 94.681902 -245.418358) (xy 94.658251 -245.463421) (xy 94.627678 -245.504107) (xy 94.590974 -245.539362)
			(xy 94.54909 -245.568272) (xy 94.503111 -245.590089) (xy 94.454227 -245.604249) (xy 94.403706 -245.610383)
			(xy 94.352854 -245.608334) (xy 94.30299 -245.598154) (xy 94.255404 -245.580107) (xy 94.21133 -245.554661)
			(xy 94.171908 -245.522474) (xy 94.13816 -245.48438) (xy 94.110959 -245.441366) (xy 94.091011 -245.394546)
			(xy 94.078832 -245.345132) (xy 94.074737 -245.294404) (xy 93.756226 -245.294404) (xy 93.755731 -245.319011)
			(xy 93.747836 -245.367588) (xy 93.732252 -245.414269) (xy 93.709381 -245.457846) (xy 93.679816 -245.49719)
			(xy 93.644323 -245.531282) (xy 93.60382 -245.559238) (xy 93.559358 -245.580336) (xy 93.512087 -245.594028)
			(xy 93.463232 -245.59996) (xy 93.414057 -245.597979) (xy 93.365838 -245.588135) (xy 93.319822 -245.570683)
			(xy 93.277201 -245.546076) (xy 93.23908 -245.514951) (xy 93.206445 -245.478114) (xy 93.180142 -245.436518)
			(xy 93.160851 -245.391242) (xy 93.149074 -245.343458) (xy 93.145114 -245.294404) (xy 92.82684 -245.294404)
			(xy 92.826328 -245.31985) (xy 92.818164 -245.370084) (xy 92.802048 -245.418358) (xy 92.778397 -245.463421)
			(xy 92.747824 -245.504107) (xy 92.71112 -245.539362) (xy 92.669236 -245.568272) (xy 92.623257 -245.590089)
			(xy 92.574373 -245.604249) (xy 92.523852 -245.610383) (xy 92.473 -245.608334) (xy 92.423136 -245.598154)
			(xy 92.37555 -245.580107) (xy 92.331476 -245.554661) (xy 92.292054 -245.522474) (xy 92.258306 -245.48438)
			(xy 92.231105 -245.441366) (xy 92.211157 -245.394546) (xy 92.198978 -245.345132) (xy 92.194883 -245.294404)
			(xy 91.876372 -245.294404) (xy 91.875877 -245.319011) (xy 91.867982 -245.367588) (xy 91.852398 -245.414269)
			(xy 91.829527 -245.457846) (xy 91.799962 -245.49719) (xy 91.764469 -245.531282) (xy 91.723966 -245.559238)
			(xy 91.679504 -245.580336) (xy 91.632233 -245.594028) (xy 91.583378 -245.59996) (xy 91.534203 -245.597979)
			(xy 91.485984 -245.588135) (xy 91.439968 -245.570683) (xy 91.397347 -245.546076) (xy 91.359226 -245.514951)
			(xy 91.326591 -245.478114) (xy 91.300288 -245.436518) (xy 91.280997 -245.391242) (xy 91.26922 -245.343458)
			(xy 91.26526 -245.294404) (xy 90.946732 -245.294404) (xy 90.94622 -245.31985) (xy 90.938056 -245.370084)
			(xy 90.92194 -245.418358) (xy 90.898289 -245.463421) (xy 90.867716 -245.504107) (xy 90.831012 -245.539362)
			(xy 90.789128 -245.568272) (xy 90.743149 -245.590089) (xy 90.694265 -245.604249) (xy 90.643744 -245.610383)
			(xy 90.592892 -245.608334) (xy 90.543028 -245.598154) (xy 90.495442 -245.580107) (xy 90.451368 -245.554661)
			(xy 90.411946 -245.522474) (xy 90.378198 -245.48438) (xy 90.350997 -245.441366) (xy 90.331049 -245.394546)
			(xy 90.31887 -245.345132) (xy 90.314775 -245.294404) (xy 89.996264 -245.294404) (xy 89.995769 -245.319011)
			(xy 89.987874 -245.367588) (xy 89.97229 -245.414269) (xy 89.949419 -245.457846) (xy 89.919854 -245.49719)
			(xy 89.884361 -245.531282) (xy 89.843858 -245.559238) (xy 89.799396 -245.580336) (xy 89.752125 -245.594028)
			(xy 89.70327 -245.59996) (xy 89.654095 -245.597979) (xy 89.605876 -245.588135) (xy 89.55986 -245.570683)
			(xy 89.517239 -245.546076) (xy 89.479118 -245.514951) (xy 89.446483 -245.478114) (xy 89.42018 -245.436518)
			(xy 89.400889 -245.391242) (xy 89.389112 -245.343458) (xy 89.385152 -245.294404) (xy 89.066878 -245.294404)
			(xy 89.066366 -245.31985) (xy 89.058202 -245.370084) (xy 89.042086 -245.418358) (xy 89.018435 -245.463421)
			(xy 88.987862 -245.504107) (xy 88.951158 -245.539362) (xy 88.909274 -245.568272) (xy 88.863295 -245.590089)
			(xy 88.814411 -245.604249) (xy 88.76389 -245.610383) (xy 88.713038 -245.608334) (xy 88.663174 -245.598154)
			(xy 88.615588 -245.580107) (xy 88.571514 -245.554661) (xy 88.532092 -245.522474) (xy 88.498344 -245.48438)
			(xy 88.471143 -245.441366) (xy 88.451195 -245.394546) (xy 88.439016 -245.345132) (xy 88.434921 -245.294404)
			(xy 88.126824 -245.294404) (xy 88.126312 -245.31985) (xy 88.118148 -245.370084) (xy 88.102032 -245.418358)
			(xy 88.078381 -245.463421) (xy 88.047808 -245.504107) (xy 88.011104 -245.539362) (xy 87.96922 -245.568272)
			(xy 87.923241 -245.590089) (xy 87.874357 -245.604249) (xy 87.823836 -245.610383) (xy 87.772984 -245.608334)
			(xy 87.72312 -245.598154) (xy 87.675534 -245.580107) (xy 87.63146 -245.554661) (xy 87.592038 -245.522474)
			(xy 87.55829 -245.48438) (xy 87.531089 -245.441366) (xy 87.511141 -245.394546) (xy 87.498962 -245.345132)
			(xy 87.494867 -245.294404) (xy 87.176356 -245.294404) (xy 87.175861 -245.319011) (xy 87.167966 -245.367588)
			(xy 87.152382 -245.414269) (xy 87.129511 -245.457846) (xy 87.099946 -245.49719) (xy 87.064453 -245.531282)
			(xy 87.02395 -245.559238) (xy 86.979488 -245.580336) (xy 86.932217 -245.594028) (xy 86.883362 -245.59996)
			(xy 86.834187 -245.597979) (xy 86.785968 -245.588135) (xy 86.739952 -245.570683) (xy 86.697331 -245.546076)
			(xy 86.65921 -245.514951) (xy 86.626575 -245.478114) (xy 86.600272 -245.436518) (xy 86.580981 -245.391242)
			(xy 86.569204 -245.343458) (xy 86.565244 -245.294404) (xy 86.246716 -245.294404) (xy 86.246204 -245.31985)
			(xy 86.23804 -245.370084) (xy 86.221924 -245.418358) (xy 86.198273 -245.463421) (xy 86.1677 -245.504107)
			(xy 86.130996 -245.539362) (xy 86.089112 -245.568272) (xy 86.043133 -245.590089) (xy 85.994249 -245.604249)
			(xy 85.943728 -245.610383) (xy 85.892876 -245.608334) (xy 85.843012 -245.598154) (xy 85.795426 -245.580107)
			(xy 85.751352 -245.554661) (xy 85.71193 -245.522474) (xy 85.678182 -245.48438) (xy 85.650981 -245.441366)
			(xy 85.631033 -245.394546) (xy 85.618854 -245.345132) (xy 85.614759 -245.294404) (xy 85.296248 -245.294404)
			(xy 85.295753 -245.319011) (xy 85.287858 -245.367588) (xy 85.272274 -245.414269) (xy 85.249403 -245.457846)
			(xy 85.219838 -245.49719) (xy 85.184345 -245.531282) (xy 85.143842 -245.559238) (xy 85.09938 -245.580336)
			(xy 85.052109 -245.594028) (xy 85.003254 -245.59996) (xy 84.954079 -245.597979) (xy 84.90586 -245.588135)
			(xy 84.859844 -245.570683) (xy 84.817223 -245.546076) (xy 84.779102 -245.514951) (xy 84.746467 -245.478114)
			(xy 84.720164 -245.436518) (xy 84.700873 -245.391242) (xy 84.689096 -245.343458) (xy 84.685136 -245.294404)
			(xy 84.366862 -245.294404) (xy 84.36635 -245.31985) (xy 84.358186 -245.370084) (xy 84.34207 -245.418358)
			(xy 84.318419 -245.463421) (xy 84.287846 -245.504107) (xy 84.251142 -245.539362) (xy 84.209258 -245.568272)
			(xy 84.163279 -245.590089) (xy 84.114395 -245.604249) (xy 84.063874 -245.610383) (xy 84.013022 -245.608334)
			(xy 83.963158 -245.598154) (xy 83.915572 -245.580107) (xy 83.871498 -245.554661) (xy 83.832076 -245.522474)
			(xy 83.798328 -245.48438) (xy 83.771127 -245.441366) (xy 83.751179 -245.394546) (xy 83.739 -245.345132)
			(xy 83.734905 -245.294404) (xy 83.416394 -245.294404) (xy 83.415899 -245.319011) (xy 83.408004 -245.367588)
			(xy 83.39242 -245.414269) (xy 83.369549 -245.457846) (xy 83.339984 -245.49719) (xy 83.304491 -245.531282)
			(xy 83.263988 -245.559238) (xy 83.219526 -245.580336) (xy 83.172255 -245.594028) (xy 83.1234 -245.59996)
			(xy 83.074225 -245.597979) (xy 83.026006 -245.588135) (xy 82.97999 -245.570683) (xy 82.937369 -245.546076)
			(xy 82.899248 -245.514951) (xy 82.866613 -245.478114) (xy 82.84031 -245.436518) (xy 82.821019 -245.391242)
			(xy 82.809242 -245.343458) (xy 82.805282 -245.294404) (xy 82.486754 -245.294404) (xy 82.486242 -245.31985)
			(xy 82.478078 -245.370084) (xy 82.461962 -245.418358) (xy 82.438311 -245.463421) (xy 82.407738 -245.504107)
			(xy 82.371034 -245.539362) (xy 82.32915 -245.568272) (xy 82.283171 -245.590089) (xy 82.234287 -245.604249)
			(xy 82.183766 -245.610383) (xy 82.132914 -245.608334) (xy 82.08305 -245.598154) (xy 82.035464 -245.580107)
			(xy 81.99139 -245.554661) (xy 81.951968 -245.522474) (xy 81.91822 -245.48438) (xy 81.891019 -245.441366)
			(xy 81.871071 -245.394546) (xy 81.858892 -245.345132) (xy 81.854797 -245.294404) (xy 81.5467 -245.294404)
			(xy 81.546188 -245.31985) (xy 81.538024 -245.370084) (xy 81.521908 -245.418358) (xy 81.498257 -245.463421)
			(xy 81.467684 -245.504107) (xy 81.43098 -245.539362) (xy 81.389096 -245.568272) (xy 81.343117 -245.590089)
			(xy 81.294233 -245.604249) (xy 81.243712 -245.610383) (xy 81.19286 -245.608334) (xy 81.142996 -245.598154)
			(xy 81.09541 -245.580107) (xy 81.051336 -245.554661) (xy 81.011914 -245.522474) (xy 80.978166 -245.48438)
			(xy 80.950965 -245.441366) (xy 80.931017 -245.394546) (xy 80.918838 -245.345132) (xy 80.914743 -245.294404)
			(xy 80.596486 -245.294404) (xy 80.595991 -245.319011) (xy 80.588096 -245.367588) (xy 80.572512 -245.414269)
			(xy 80.549641 -245.457846) (xy 80.520076 -245.49719) (xy 80.484583 -245.531282) (xy 80.44408 -245.559238)
			(xy 80.399618 -245.580336) (xy 80.352347 -245.594028) (xy 80.303492 -245.59996) (xy 80.254317 -245.597979)
			(xy 80.206098 -245.588135) (xy 80.160082 -245.570683) (xy 80.117461 -245.546076) (xy 80.07934 -245.514951)
			(xy 80.046705 -245.478114) (xy 80.020402 -245.436518) (xy 80.001111 -245.391242) (xy 79.989334 -245.343458)
			(xy 79.985374 -245.294404) (xy 78.716378 -245.294404) (xy 78.715883 -245.319011) (xy 78.707988 -245.367588)
			(xy 78.692404 -245.414269) (xy 78.669533 -245.457846) (xy 78.639968 -245.49719) (xy 78.604475 -245.531282)
			(xy 78.563972 -245.559238) (xy 78.51951 -245.580336) (xy 78.472239 -245.594028) (xy 78.423384 -245.59996)
			(xy 78.374209 -245.597979) (xy 78.32599 -245.588135) (xy 78.279974 -245.570683) (xy 78.237353 -245.546076)
			(xy 78.199232 -245.514951) (xy 78.166597 -245.478114) (xy 78.140294 -245.436518) (xy 78.121003 -245.391242)
			(xy 78.109226 -245.343458) (xy 78.105266 -245.294404) (xy 62.37732 -245.294404) (xy 62.37732 -245.31447)
			(xy 62.378082 -245.322852) (xy 62.37959 -245.330461) (xy 62.386565 -245.344305) (xy 62.391798 -245.35003)
			(xy 63.412116 -246.370348) (xy 76.507098 -246.370348) (xy 76.511058 -246.321294) (xy 76.522835 -246.27351)
			(xy 76.542126 -246.228234) (xy 76.568429 -246.186638) (xy 76.601064 -246.149801) (xy 76.639185 -246.118676)
			(xy 76.681806 -246.094069) (xy 76.727822 -246.076617) (xy 76.776041 -246.066773) (xy 76.825216 -246.064792)
			(xy 76.874071 -246.070724) (xy 76.921342 -246.084416) (xy 76.963477 -246.10441) (xy 79.51522 -246.10441)
			(xy 79.51918 -246.055356) (xy 79.530957 -246.007572) (xy 79.550248 -245.962296) (xy 79.576551 -245.9207)
			(xy 79.609186 -245.883863) (xy 79.647307 -245.852738) (xy 79.689928 -245.828131) (xy 79.735944 -245.810679)
			(xy 79.784163 -245.800835) (xy 79.833338 -245.798854) (xy 79.882193 -245.804786) (xy 79.929464 -245.818478)
			(xy 79.973926 -245.839576) (xy 80.014429 -245.867532) (xy 80.049922 -245.901624) (xy 80.079487 -245.940968)
			(xy 80.102358 -245.984545) (xy 80.117942 -246.031226) (xy 80.125837 -246.079803) (xy 80.126332 -246.10441)
			(xy 80.444843 -246.10441) (xy 80.448938 -246.053682) (xy 80.461117 -246.004268) (xy 80.481065 -245.957448)
			(xy 80.508266 -245.914434) (xy 80.542014 -245.87634) (xy 80.581436 -245.844153) (xy 80.62551 -245.818707)
			(xy 80.673096 -245.80066) (xy 80.72296 -245.79048) (xy 80.773812 -245.788431) (xy 80.824333 -245.794565)
			(xy 80.873217 -245.808725) (xy 80.919196 -245.830542) (xy 80.96108 -245.859452) (xy 80.997784 -245.894707)
			(xy 81.028357 -245.935393) (xy 81.052008 -245.980456) (xy 81.068124 -246.02873) (xy 81.076288 -246.078964)
			(xy 81.0768 -246.10441) (xy 81.395328 -246.10441) (xy 81.399288 -246.055356) (xy 81.411065 -246.007572)
			(xy 81.430356 -245.962296) (xy 81.456659 -245.9207) (xy 81.489294 -245.883863) (xy 81.527415 -245.852738)
			(xy 81.570036 -245.828131) (xy 81.616052 -245.810679) (xy 81.664271 -245.800835) (xy 81.713446 -245.798854)
			(xy 81.762301 -245.804786) (xy 81.809572 -245.818478) (xy 81.854034 -245.839576) (xy 81.894537 -245.867532)
			(xy 81.93003 -245.901624) (xy 81.959595 -245.940968) (xy 81.982466 -245.984545) (xy 81.99805 -246.031226)
			(xy 82.005945 -246.079803) (xy 82.00644 -246.10441) (xy 82.324697 -246.10441) (xy 82.328792 -246.053682)
			(xy 82.340971 -246.004268) (xy 82.360919 -245.957448) (xy 82.38812 -245.914434) (xy 82.421868 -245.87634)
			(xy 82.46129 -245.844153) (xy 82.505364 -245.818707) (xy 82.55295 -245.80066) (xy 82.602814 -245.79048)
			(xy 82.653666 -245.788431) (xy 82.704187 -245.794565) (xy 82.753071 -245.808725) (xy 82.79905 -245.830542)
			(xy 82.840934 -245.859452) (xy 82.877638 -245.894707) (xy 82.908211 -245.935393) (xy 82.931862 -245.980456)
			(xy 82.947978 -246.02873) (xy 82.956142 -246.078964) (xy 82.956654 -246.10441) (xy 83.275182 -246.10441)
			(xy 83.279142 -246.055356) (xy 83.290919 -246.007572) (xy 83.31021 -245.962296) (xy 83.336513 -245.9207)
			(xy 83.369148 -245.883863) (xy 83.407269 -245.852738) (xy 83.44989 -245.828131) (xy 83.495906 -245.810679)
			(xy 83.544125 -245.800835) (xy 83.5933 -245.798854) (xy 83.642155 -245.804786) (xy 83.689426 -245.818478)
			(xy 83.733888 -245.839576) (xy 83.774391 -245.867532) (xy 83.809884 -245.901624) (xy 83.839449 -245.940968)
			(xy 83.86232 -245.984545) (xy 83.877904 -246.031226) (xy 83.885799 -246.079803) (xy 83.886294 -246.10441)
			(xy 84.204805 -246.10441) (xy 84.2089 -246.053682) (xy 84.221079 -246.004268) (xy 84.241027 -245.957448)
			(xy 84.268228 -245.914434) (xy 84.301976 -245.87634) (xy 84.341398 -245.844153) (xy 84.385472 -245.818707)
			(xy 84.433058 -245.80066) (xy 84.482922 -245.79048) (xy 84.533774 -245.788431) (xy 84.584295 -245.794565)
			(xy 84.633179 -245.808725) (xy 84.679158 -245.830542) (xy 84.721042 -245.859452) (xy 84.757746 -245.894707)
			(xy 84.788319 -245.935393) (xy 84.81197 -245.980456) (xy 84.828086 -246.02873) (xy 84.83625 -246.078964)
			(xy 84.836762 -246.10441) (xy 85.144859 -246.10441) (xy 85.148954 -246.053682) (xy 85.161133 -246.004268)
			(xy 85.181081 -245.957448) (xy 85.208282 -245.914434) (xy 85.24203 -245.87634) (xy 85.281452 -245.844153)
			(xy 85.325526 -245.818707) (xy 85.373112 -245.80066) (xy 85.422976 -245.79048) (xy 85.473828 -245.788431)
			(xy 85.524349 -245.794565) (xy 85.573233 -245.808725) (xy 85.619212 -245.830542) (xy 85.661096 -245.859452)
			(xy 85.6978 -245.894707) (xy 85.728373 -245.935393) (xy 85.752024 -245.980456) (xy 85.76814 -246.02873)
			(xy 85.776304 -246.078964) (xy 85.776816 -246.10441) (xy 86.095344 -246.10441) (xy 86.099304 -246.055356)
			(xy 86.111081 -246.007572) (xy 86.130372 -245.962296) (xy 86.156675 -245.9207) (xy 86.18931 -245.883863)
			(xy 86.227431 -245.852738) (xy 86.270052 -245.828131) (xy 86.316068 -245.810679) (xy 86.364287 -245.800835)
			(xy 86.413462 -245.798854) (xy 86.462317 -245.804786) (xy 86.509588 -245.818478) (xy 86.55405 -245.839576)
			(xy 86.594553 -245.867532) (xy 86.630046 -245.901624) (xy 86.659611 -245.940968) (xy 86.682482 -245.984545)
			(xy 86.698066 -246.031226) (xy 86.705961 -246.079803) (xy 86.706456 -246.10441) (xy 87.024713 -246.10441)
			(xy 87.028808 -246.053682) (xy 87.040987 -246.004268) (xy 87.060935 -245.957448) (xy 87.088136 -245.914434)
			(xy 87.121884 -245.87634) (xy 87.161306 -245.844153) (xy 87.20538 -245.818707) (xy 87.252966 -245.80066)
			(xy 87.30283 -245.79048) (xy 87.353682 -245.788431) (xy 87.404203 -245.794565) (xy 87.453087 -245.808725)
			(xy 87.499066 -245.830542) (xy 87.54095 -245.859452) (xy 87.577654 -245.894707) (xy 87.608227 -245.935393)
			(xy 87.631878 -245.980456) (xy 87.647994 -246.02873) (xy 87.656158 -246.078964) (xy 87.65667 -246.10441)
			(xy 87.975198 -246.10441) (xy 87.979158 -246.055356) (xy 87.990935 -246.007572) (xy 88.010226 -245.962296)
			(xy 88.036529 -245.9207) (xy 88.069164 -245.883863) (xy 88.107285 -245.852738) (xy 88.149906 -245.828131)
			(xy 88.195922 -245.810679) (xy 88.244141 -245.800835) (xy 88.293316 -245.798854) (xy 88.342171 -245.804786)
			(xy 88.389442 -245.818478) (xy 88.433904 -245.839576) (xy 88.474407 -245.867532) (xy 88.5099 -245.901624)
			(xy 88.539465 -245.940968) (xy 88.562336 -245.984545) (xy 88.57792 -246.031226) (xy 88.585815 -246.079803)
			(xy 88.58631 -246.10441) (xy 88.904821 -246.10441) (xy 88.908916 -246.053682) (xy 88.921095 -246.004268)
			(xy 88.941043 -245.957448) (xy 88.968244 -245.914434) (xy 89.001992 -245.87634) (xy 89.041414 -245.844153)
			(xy 89.085488 -245.818707) (xy 89.133074 -245.80066) (xy 89.182938 -245.79048) (xy 89.23379 -245.788431)
			(xy 89.284311 -245.794565) (xy 89.333195 -245.808725) (xy 89.379174 -245.830542) (xy 89.421058 -245.859452)
			(xy 89.457762 -245.894707) (xy 89.488335 -245.935393) (xy 89.511986 -245.980456) (xy 89.528102 -246.02873)
			(xy 89.536266 -246.078964) (xy 89.536778 -246.10441) (xy 89.855306 -246.10441) (xy 89.859266 -246.055356)
			(xy 89.871043 -246.007572) (xy 89.890334 -245.962296) (xy 89.916637 -245.9207) (xy 89.949272 -245.883863)
			(xy 89.987393 -245.852738) (xy 90.030014 -245.828131) (xy 90.07603 -245.810679) (xy 90.124249 -245.800835)
			(xy 90.173424 -245.798854) (xy 90.222279 -245.804786) (xy 90.26955 -245.818478) (xy 90.314012 -245.839576)
			(xy 90.354515 -245.867532) (xy 90.390008 -245.901624) (xy 90.419573 -245.940968) (xy 90.442444 -245.984545)
			(xy 90.458028 -246.031226) (xy 90.465923 -246.079803) (xy 90.466418 -246.10441) (xy 90.784675 -246.10441)
			(xy 90.78877 -246.053682) (xy 90.800949 -246.004268) (xy 90.820897 -245.957448) (xy 90.848098 -245.914434)
			(xy 90.881846 -245.87634) (xy 90.921268 -245.844153) (xy 90.965342 -245.818707) (xy 91.012928 -245.80066)
			(xy 91.062792 -245.79048) (xy 91.113644 -245.788431) (xy 91.164165 -245.794565) (xy 91.213049 -245.808725)
			(xy 91.259028 -245.830542) (xy 91.300912 -245.859452) (xy 91.337616 -245.894707) (xy 91.368189 -245.935393)
			(xy 91.39184 -245.980456) (xy 91.407956 -246.02873) (xy 91.41612 -246.078964) (xy 91.416632 -246.10441)
			(xy 91.724729 -246.10441) (xy 91.728824 -246.053682) (xy 91.741003 -246.004268) (xy 91.760951 -245.957448)
			(xy 91.788152 -245.914434) (xy 91.8219 -245.87634) (xy 91.861322 -245.844153) (xy 91.905396 -245.818707)
			(xy 91.952982 -245.80066) (xy 92.002846 -245.79048) (xy 92.053698 -245.788431) (xy 92.104219 -245.794565)
			(xy 92.153103 -245.808725) (xy 92.199082 -245.830542) (xy 92.240966 -245.859452) (xy 92.27767 -245.894707)
			(xy 92.308243 -245.935393) (xy 92.331894 -245.980456) (xy 92.34801 -246.02873) (xy 92.356174 -246.078964)
			(xy 92.356686 -246.10441) (xy 92.675214 -246.10441) (xy 92.679174 -246.055356) (xy 92.690951 -246.007572)
			(xy 92.710242 -245.962296) (xy 92.736545 -245.9207) (xy 92.76918 -245.883863) (xy 92.807301 -245.852738)
			(xy 92.849922 -245.828131) (xy 92.895938 -245.810679) (xy 92.944157 -245.800835) (xy 92.993332 -245.798854)
			(xy 93.042187 -245.804786) (xy 93.089458 -245.818478) (xy 93.13392 -245.839576) (xy 93.174423 -245.867532)
			(xy 93.209916 -245.901624) (xy 93.239481 -245.940968) (xy 93.262352 -245.984545) (xy 93.277936 -246.031226)
			(xy 93.285831 -246.079803) (xy 93.286326 -246.10441) (xy 93.604837 -246.10441) (xy 93.608932 -246.053682)
			(xy 93.621111 -246.004268) (xy 93.641059 -245.957448) (xy 93.66826 -245.914434) (xy 93.702008 -245.87634)
			(xy 93.74143 -245.844153) (xy 93.785504 -245.818707) (xy 93.83309 -245.80066) (xy 93.882954 -245.79048)
			(xy 93.933806 -245.788431) (xy 93.984327 -245.794565) (xy 94.033211 -245.808725) (xy 94.07919 -245.830542)
			(xy 94.121074 -245.859452) (xy 94.157778 -245.894707) (xy 94.188351 -245.935393) (xy 94.212002 -245.980456)
			(xy 94.228118 -246.02873) (xy 94.236282 -246.078964) (xy 94.236794 -246.10441) (xy 94.555322 -246.10441)
			(xy 94.559282 -246.055356) (xy 94.571059 -246.007572) (xy 94.59035 -245.962296) (xy 94.616653 -245.9207)
			(xy 94.649288 -245.883863) (xy 94.687409 -245.852738) (xy 94.73003 -245.828131) (xy 94.776046 -245.810679)
			(xy 94.824265 -245.800835) (xy 94.87344 -245.798854) (xy 94.922295 -245.804786) (xy 94.969566 -245.818478)
			(xy 95.014028 -245.839576) (xy 95.054531 -245.867532) (xy 95.090024 -245.901624) (xy 95.119589 -245.940968)
			(xy 95.14246 -245.984545) (xy 95.158044 -246.031226) (xy 95.165939 -246.079803) (xy 95.166434 -246.10441)
			(xy 95.484691 -246.10441) (xy 95.488786 -246.053682) (xy 95.500965 -246.004268) (xy 95.520913 -245.957448)
			(xy 95.548114 -245.914434) (xy 95.581862 -245.87634) (xy 95.621284 -245.844153) (xy 95.665358 -245.818707)
			(xy 95.712944 -245.80066) (xy 95.762808 -245.79048) (xy 95.81366 -245.788431) (xy 95.864181 -245.794565)
			(xy 95.913065 -245.808725) (xy 95.959044 -245.830542) (xy 96.000928 -245.859452) (xy 96.037632 -245.894707)
			(xy 96.068205 -245.935393) (xy 96.091856 -245.980456) (xy 96.107972 -246.02873) (xy 96.116136 -246.078964)
			(xy 96.116648 -246.10441) (xy 96.435176 -246.10441) (xy 96.439136 -246.055356) (xy 96.450913 -246.007572)
			(xy 96.470204 -245.962296) (xy 96.496507 -245.9207) (xy 96.529142 -245.883863) (xy 96.567263 -245.852738)
			(xy 96.609884 -245.828131) (xy 96.6559 -245.810679) (xy 96.704119 -245.800835) (xy 96.753294 -245.798854)
			(xy 96.802149 -245.804786) (xy 96.84942 -245.818478) (xy 96.893882 -245.839576) (xy 96.934385 -245.867532)
			(xy 96.969878 -245.901624) (xy 96.999443 -245.940968) (xy 97.022314 -245.984545) (xy 97.037898 -246.031226)
			(xy 97.045793 -246.079803) (xy 97.046288 -246.10441) (xy 97.364799 -246.10441) (xy 97.368894 -246.053682)
			(xy 97.381073 -246.004268) (xy 97.401021 -245.957448) (xy 97.428222 -245.914434) (xy 97.46197 -245.87634)
			(xy 97.501392 -245.844153) (xy 97.545466 -245.818707) (xy 97.593052 -245.80066) (xy 97.642916 -245.79048)
			(xy 97.693768 -245.788431) (xy 97.744289 -245.794565) (xy 97.793173 -245.808725) (xy 97.839152 -245.830542)
			(xy 97.881036 -245.859452) (xy 97.91774 -245.894707) (xy 97.948313 -245.935393) (xy 97.971964 -245.980456)
			(xy 97.98808 -246.02873) (xy 97.996244 -246.078964) (xy 97.996756 -246.10441) (xy 98.304853 -246.10441)
			(xy 98.308948 -246.053682) (xy 98.321127 -246.004268) (xy 98.341075 -245.957448) (xy 98.368276 -245.914434)
			(xy 98.402024 -245.87634) (xy 98.441446 -245.844153) (xy 98.48552 -245.818707) (xy 98.533106 -245.80066)
			(xy 98.58297 -245.79048) (xy 98.633822 -245.788431) (xy 98.684343 -245.794565) (xy 98.733227 -245.808725)
			(xy 98.779206 -245.830542) (xy 98.82109 -245.859452) (xy 98.857794 -245.894707) (xy 98.888367 -245.935393)
			(xy 98.912018 -245.980456) (xy 98.928134 -246.02873) (xy 98.936298 -246.078964) (xy 98.93681 -246.10441)
			(xy 99.255338 -246.10441) (xy 99.259298 -246.055356) (xy 99.271075 -246.007572) (xy 99.290366 -245.962296)
			(xy 99.316669 -245.9207) (xy 99.349304 -245.883863) (xy 99.387425 -245.852738) (xy 99.430046 -245.828131)
			(xy 99.476062 -245.810679) (xy 99.524281 -245.800835) (xy 99.573456 -245.798854) (xy 99.622311 -245.804786)
			(xy 99.669582 -245.818478) (xy 99.714044 -245.839576) (xy 99.754547 -245.867532) (xy 99.79004 -245.901624)
			(xy 99.819605 -245.940968) (xy 99.842476 -245.984545) (xy 99.85806 -246.031226) (xy 99.865955 -246.079803)
			(xy 99.86645 -246.10441) (xy 100.184707 -246.10441) (xy 100.188802 -246.053682) (xy 100.200981 -246.004268)
			(xy 100.220929 -245.957448) (xy 100.24813 -245.914434) (xy 100.281878 -245.87634) (xy 100.3213 -245.844153)
			(xy 100.365374 -245.818707) (xy 100.41296 -245.80066) (xy 100.462824 -245.79048) (xy 100.513676 -245.788431)
			(xy 100.564197 -245.794565) (xy 100.613081 -245.808725) (xy 100.65906 -245.830542) (xy 100.700944 -245.859452)
			(xy 100.737648 -245.894707) (xy 100.768221 -245.935393) (xy 100.791872 -245.980456) (xy 100.807988 -246.02873)
			(xy 100.816152 -246.078964) (xy 100.816664 -246.10441) (xy 101.124761 -246.10441) (xy 101.128856 -246.053682)
			(xy 101.141035 -246.004268) (xy 101.160983 -245.957448) (xy 101.188184 -245.914434) (xy 101.221932 -245.87634)
			(xy 101.261354 -245.844153) (xy 101.305428 -245.818707) (xy 101.353014 -245.80066) (xy 101.402878 -245.79048)
			(xy 101.45373 -245.788431) (xy 101.504251 -245.794565) (xy 101.553135 -245.808725) (xy 101.599114 -245.830542)
			(xy 101.640998 -245.859452) (xy 101.677702 -245.894707) (xy 101.708275 -245.935393) (xy 101.731926 -245.980456)
			(xy 101.748042 -246.02873) (xy 101.756206 -246.078964) (xy 101.756718 -246.10441) (xy 102.075246 -246.10441)
			(xy 102.079206 -246.055356) (xy 102.090983 -246.007572) (xy 102.110274 -245.962296) (xy 102.136577 -245.9207)
			(xy 102.169212 -245.883863) (xy 102.207333 -245.852738) (xy 102.249954 -245.828131) (xy 102.29597 -245.810679)
			(xy 102.344189 -245.800835) (xy 102.393364 -245.798854) (xy 102.442219 -245.804786) (xy 102.48949 -245.818478)
			(xy 102.533952 -245.839576) (xy 102.574455 -245.867532) (xy 102.609948 -245.901624) (xy 102.639513 -245.940968)
			(xy 102.662384 -245.984545) (xy 102.677968 -246.031226) (xy 102.685863 -246.079803) (xy 102.686358 -246.10441)
			(xy 103.004869 -246.10441) (xy 103.008964 -246.053682) (xy 103.021143 -246.004268) (xy 103.041091 -245.957448)
			(xy 103.068292 -245.914434) (xy 103.10204 -245.87634) (xy 103.141462 -245.844153) (xy 103.185536 -245.818707)
			(xy 103.233122 -245.80066) (xy 103.282986 -245.79048) (xy 103.333838 -245.788431) (xy 103.384359 -245.794565)
			(xy 103.433243 -245.808725) (xy 103.479222 -245.830542) (xy 103.521106 -245.859452) (xy 103.55781 -245.894707)
			(xy 103.588383 -245.935393) (xy 103.612034 -245.980456) (xy 103.62815 -246.02873) (xy 103.636314 -246.078964)
			(xy 103.636826 -246.10441) (xy 103.944923 -246.10441) (xy 103.949018 -246.053682) (xy 103.961197 -246.004268)
			(xy 103.981145 -245.957448) (xy 104.008346 -245.914434) (xy 104.042094 -245.87634) (xy 104.081516 -245.844153)
			(xy 104.12559 -245.818707) (xy 104.173176 -245.80066) (xy 104.22304 -245.79048) (xy 104.273892 -245.788431)
			(xy 104.324413 -245.794565) (xy 104.373297 -245.808725) (xy 104.419276 -245.830542) (xy 104.46116 -245.859452)
			(xy 104.497864 -245.894707) (xy 104.528437 -245.935393) (xy 104.552088 -245.980456) (xy 104.568204 -246.02873)
			(xy 104.576368 -246.078964) (xy 104.57688 -246.10441) (xy 104.895154 -246.10441) (xy 104.899114 -246.055356)
			(xy 104.910891 -246.007572) (xy 104.930182 -245.962296) (xy 104.956485 -245.9207) (xy 104.98912 -245.883863)
			(xy 105.027241 -245.852738) (xy 105.069862 -245.828131) (xy 105.115878 -245.810679) (xy 105.164097 -245.800835)
			(xy 105.213272 -245.798854) (xy 105.262127 -245.804786) (xy 105.309398 -245.818478) (xy 105.35386 -245.839576)
			(xy 105.394363 -245.867532) (xy 105.429856 -245.901624) (xy 105.459421 -245.940968) (xy 105.482292 -245.984545)
			(xy 105.497876 -246.031226) (xy 105.505771 -246.079803) (xy 105.506266 -246.10441) (xy 105.824777 -246.10441)
			(xy 105.828872 -246.053682) (xy 105.841051 -246.004268) (xy 105.860999 -245.957448) (xy 105.8882 -245.914434)
			(xy 105.921948 -245.87634) (xy 105.96137 -245.844153) (xy 106.005444 -245.818707) (xy 106.05303 -245.80066)
			(xy 106.102894 -245.79048) (xy 106.153746 -245.788431) (xy 106.204267 -245.794565) (xy 106.253151 -245.808725)
			(xy 106.29913 -245.830542) (xy 106.341014 -245.859452) (xy 106.377718 -245.894707) (xy 106.408291 -245.935393)
			(xy 106.431942 -245.980456) (xy 106.448058 -246.02873) (xy 106.456222 -246.078964) (xy 106.456734 -246.10441)
			(xy 106.764831 -246.10441) (xy 106.768926 -246.053682) (xy 106.781105 -246.004268) (xy 106.801053 -245.957448)
			(xy 106.828254 -245.914434) (xy 106.862002 -245.87634) (xy 106.901424 -245.844153) (xy 106.945498 -245.818707)
			(xy 106.993084 -245.80066) (xy 107.042948 -245.79048) (xy 107.0938 -245.788431) (xy 107.144321 -245.794565)
			(xy 107.193205 -245.808725) (xy 107.239184 -245.830542) (xy 107.281068 -245.859452) (xy 107.317772 -245.894707)
			(xy 107.348345 -245.935393) (xy 107.371996 -245.980456) (xy 107.388112 -246.02873) (xy 107.396276 -246.078964)
			(xy 107.396788 -246.10441) (xy 107.715316 -246.10441) (xy 107.719276 -246.055356) (xy 107.731053 -246.007572)
			(xy 107.750344 -245.962296) (xy 107.776647 -245.9207) (xy 107.809282 -245.883863) (xy 107.847403 -245.852738)
			(xy 107.890024 -245.828131) (xy 107.93604 -245.810679) (xy 107.984259 -245.800835) (xy 108.033434 -245.798854)
			(xy 108.082289 -245.804786) (xy 108.12956 -245.818478) (xy 108.174022 -245.839576) (xy 108.214525 -245.867532)
			(xy 108.250018 -245.901624) (xy 108.279583 -245.940968) (xy 108.302454 -245.984545) (xy 108.318038 -246.031226)
			(xy 108.325933 -246.079803) (xy 108.326428 -246.10441) (xy 108.325933 -246.129017) (xy 108.318038 -246.177594)
			(xy 108.302454 -246.224275) (xy 108.279583 -246.267852) (xy 108.250018 -246.307196) (xy 108.214525 -246.341288)
			(xy 108.174022 -246.369244) (xy 108.12956 -246.390342) (xy 108.082289 -246.404034) (xy 108.033434 -246.409966)
			(xy 107.984259 -246.407985) (xy 107.93604 -246.398141) (xy 107.890024 -246.380689) (xy 107.847403 -246.356082)
			(xy 107.809282 -246.324957) (xy 107.776647 -246.28812) (xy 107.750344 -246.246524) (xy 107.731053 -246.201248)
			(xy 107.719276 -246.153464) (xy 107.715316 -246.10441) (xy 107.396788 -246.10441) (xy 107.396276 -246.129856)
			(xy 107.388112 -246.18009) (xy 107.371996 -246.228364) (xy 107.348345 -246.273427) (xy 107.317772 -246.314113)
			(xy 107.281068 -246.349368) (xy 107.239184 -246.378278) (xy 107.193205 -246.400095) (xy 107.144321 -246.414255)
			(xy 107.0938 -246.420389) (xy 107.042948 -246.41834) (xy 106.993084 -246.40816) (xy 106.945498 -246.390113)
			(xy 106.901424 -246.364667) (xy 106.862002 -246.33248) (xy 106.828254 -246.294386) (xy 106.801053 -246.251372)
			(xy 106.781105 -246.204552) (xy 106.768926 -246.155138) (xy 106.764831 -246.10441) (xy 106.456734 -246.10441)
			(xy 106.456222 -246.129856) (xy 106.448058 -246.18009) (xy 106.431942 -246.228364) (xy 106.408291 -246.273427)
			(xy 106.377718 -246.314113) (xy 106.341014 -246.349368) (xy 106.29913 -246.378278) (xy 106.253151 -246.400095)
			(xy 106.204267 -246.414255) (xy 106.153746 -246.420389) (xy 106.102894 -246.41834) (xy 106.05303 -246.40816)
			(xy 106.005444 -246.390113) (xy 105.96137 -246.364667) (xy 105.921948 -246.33248) (xy 105.8882 -246.294386)
			(xy 105.860999 -246.251372) (xy 105.841051 -246.204552) (xy 105.828872 -246.155138) (xy 105.824777 -246.10441)
			(xy 105.506266 -246.10441) (xy 105.505771 -246.129017) (xy 105.497876 -246.177594) (xy 105.482292 -246.224275)
			(xy 105.459421 -246.267852) (xy 105.429856 -246.307196) (xy 105.394363 -246.341288) (xy 105.35386 -246.369244)
			(xy 105.309398 -246.390342) (xy 105.262127 -246.404034) (xy 105.213272 -246.409966) (xy 105.164097 -246.407985)
			(xy 105.115878 -246.398141) (xy 105.069862 -246.380689) (xy 105.027241 -246.356082) (xy 104.98912 -246.324957)
			(xy 104.956485 -246.28812) (xy 104.930182 -246.246524) (xy 104.910891 -246.201248) (xy 104.899114 -246.153464)
			(xy 104.895154 -246.10441) (xy 104.57688 -246.10441) (xy 104.576368 -246.129856) (xy 104.568204 -246.18009)
			(xy 104.552088 -246.228364) (xy 104.528437 -246.273427) (xy 104.497864 -246.314113) (xy 104.46116 -246.349368)
			(xy 104.419276 -246.378278) (xy 104.373297 -246.400095) (xy 104.324413 -246.414255) (xy 104.273892 -246.420389)
			(xy 104.22304 -246.41834) (xy 104.173176 -246.40816) (xy 104.12559 -246.390113) (xy 104.081516 -246.364667)
			(xy 104.042094 -246.33248) (xy 104.008346 -246.294386) (xy 103.981145 -246.251372) (xy 103.961197 -246.204552)
			(xy 103.949018 -246.155138) (xy 103.944923 -246.10441) (xy 103.636826 -246.10441) (xy 103.636314 -246.129856)
			(xy 103.62815 -246.18009) (xy 103.612034 -246.228364) (xy 103.588383 -246.273427) (xy 103.55781 -246.314113)
			(xy 103.521106 -246.349368) (xy 103.479222 -246.378278) (xy 103.433243 -246.400095) (xy 103.384359 -246.414255)
			(xy 103.333838 -246.420389) (xy 103.282986 -246.41834) (xy 103.233122 -246.40816) (xy 103.185536 -246.390113)
			(xy 103.141462 -246.364667) (xy 103.10204 -246.33248) (xy 103.068292 -246.294386) (xy 103.041091 -246.251372)
			(xy 103.021143 -246.204552) (xy 103.008964 -246.155138) (xy 103.004869 -246.10441) (xy 102.686358 -246.10441)
			(xy 102.685863 -246.129017) (xy 102.677968 -246.177594) (xy 102.662384 -246.224275) (xy 102.639513 -246.267852)
			(xy 102.609948 -246.307196) (xy 102.574455 -246.341288) (xy 102.533952 -246.369244) (xy 102.48949 -246.390342)
			(xy 102.442219 -246.404034) (xy 102.393364 -246.409966) (xy 102.344189 -246.407985) (xy 102.29597 -246.398141)
			(xy 102.249954 -246.380689) (xy 102.207333 -246.356082) (xy 102.169212 -246.324957) (xy 102.136577 -246.28812)
			(xy 102.110274 -246.246524) (xy 102.090983 -246.201248) (xy 102.079206 -246.153464) (xy 102.075246 -246.10441)
			(xy 101.756718 -246.10441) (xy 101.756206 -246.129856) (xy 101.748042 -246.18009) (xy 101.731926 -246.228364)
			(xy 101.708275 -246.273427) (xy 101.677702 -246.314113) (xy 101.640998 -246.349368) (xy 101.599114 -246.378278)
			(xy 101.553135 -246.400095) (xy 101.504251 -246.414255) (xy 101.45373 -246.420389) (xy 101.402878 -246.41834)
			(xy 101.353014 -246.40816) (xy 101.305428 -246.390113) (xy 101.261354 -246.364667) (xy 101.221932 -246.33248)
			(xy 101.188184 -246.294386) (xy 101.160983 -246.251372) (xy 101.141035 -246.204552) (xy 101.128856 -246.155138)
			(xy 101.124761 -246.10441) (xy 100.816664 -246.10441) (xy 100.816152 -246.129856) (xy 100.807988 -246.18009)
			(xy 100.791872 -246.228364) (xy 100.768221 -246.273427) (xy 100.737648 -246.314113) (xy 100.700944 -246.349368)
			(xy 100.65906 -246.378278) (xy 100.613081 -246.400095) (xy 100.564197 -246.414255) (xy 100.513676 -246.420389)
			(xy 100.462824 -246.41834) (xy 100.41296 -246.40816) (xy 100.365374 -246.390113) (xy 100.3213 -246.364667)
			(xy 100.281878 -246.33248) (xy 100.24813 -246.294386) (xy 100.220929 -246.251372) (xy 100.200981 -246.204552)
			(xy 100.188802 -246.155138) (xy 100.184707 -246.10441) (xy 99.86645 -246.10441) (xy 99.865955 -246.129017)
			(xy 99.85806 -246.177594) (xy 99.842476 -246.224275) (xy 99.819605 -246.267852) (xy 99.79004 -246.307196)
			(xy 99.754547 -246.341288) (xy 99.714044 -246.369244) (xy 99.669582 -246.390342) (xy 99.622311 -246.404034)
			(xy 99.573456 -246.409966) (xy 99.524281 -246.407985) (xy 99.476062 -246.398141) (xy 99.430046 -246.380689)
			(xy 99.387425 -246.356082) (xy 99.349304 -246.324957) (xy 99.316669 -246.28812) (xy 99.290366 -246.246524)
			(xy 99.271075 -246.201248) (xy 99.259298 -246.153464) (xy 99.255338 -246.10441) (xy 98.93681 -246.10441)
			(xy 98.936298 -246.129856) (xy 98.928134 -246.18009) (xy 98.912018 -246.228364) (xy 98.888367 -246.273427)
			(xy 98.857794 -246.314113) (xy 98.82109 -246.349368) (xy 98.779206 -246.378278) (xy 98.733227 -246.400095)
			(xy 98.684343 -246.414255) (xy 98.633822 -246.420389) (xy 98.58297 -246.41834) (xy 98.533106 -246.40816)
			(xy 98.48552 -246.390113) (xy 98.441446 -246.364667) (xy 98.402024 -246.33248) (xy 98.368276 -246.294386)
			(xy 98.341075 -246.251372) (xy 98.321127 -246.204552) (xy 98.308948 -246.155138) (xy 98.304853 -246.10441)
			(xy 97.996756 -246.10441) (xy 97.996244 -246.129856) (xy 97.98808 -246.18009) (xy 97.971964 -246.228364)
			(xy 97.948313 -246.273427) (xy 97.91774 -246.314113) (xy 97.881036 -246.349368) (xy 97.839152 -246.378278)
			(xy 97.793173 -246.400095) (xy 97.744289 -246.414255) (xy 97.693768 -246.420389) (xy 97.642916 -246.41834)
			(xy 97.593052 -246.40816) (xy 97.545466 -246.390113) (xy 97.501392 -246.364667) (xy 97.46197 -246.33248)
			(xy 97.428222 -246.294386) (xy 97.401021 -246.251372) (xy 97.381073 -246.204552) (xy 97.368894 -246.155138)
			(xy 97.364799 -246.10441) (xy 97.046288 -246.10441) (xy 97.045793 -246.129017) (xy 97.037898 -246.177594)
			(xy 97.022314 -246.224275) (xy 96.999443 -246.267852) (xy 96.969878 -246.307196) (xy 96.934385 -246.341288)
			(xy 96.893882 -246.369244) (xy 96.84942 -246.390342) (xy 96.802149 -246.404034) (xy 96.753294 -246.409966)
			(xy 96.704119 -246.407985) (xy 96.6559 -246.398141) (xy 96.609884 -246.380689) (xy 96.567263 -246.356082)
			(xy 96.529142 -246.324957) (xy 96.496507 -246.28812) (xy 96.470204 -246.246524) (xy 96.450913 -246.201248)
			(xy 96.439136 -246.153464) (xy 96.435176 -246.10441) (xy 96.116648 -246.10441) (xy 96.116136 -246.129856)
			(xy 96.107972 -246.18009) (xy 96.091856 -246.228364) (xy 96.068205 -246.273427) (xy 96.037632 -246.314113)
			(xy 96.000928 -246.349368) (xy 95.959044 -246.378278) (xy 95.913065 -246.400095) (xy 95.864181 -246.414255)
			(xy 95.81366 -246.420389) (xy 95.762808 -246.41834) (xy 95.712944 -246.40816) (xy 95.665358 -246.390113)
			(xy 95.621284 -246.364667) (xy 95.581862 -246.33248) (xy 95.548114 -246.294386) (xy 95.520913 -246.251372)
			(xy 95.500965 -246.204552) (xy 95.488786 -246.155138) (xy 95.484691 -246.10441) (xy 95.166434 -246.10441)
			(xy 95.165939 -246.129017) (xy 95.158044 -246.177594) (xy 95.14246 -246.224275) (xy 95.119589 -246.267852)
			(xy 95.090024 -246.307196) (xy 95.054531 -246.341288) (xy 95.014028 -246.369244) (xy 94.969566 -246.390342)
			(xy 94.922295 -246.404034) (xy 94.87344 -246.409966) (xy 94.824265 -246.407985) (xy 94.776046 -246.398141)
			(xy 94.73003 -246.380689) (xy 94.687409 -246.356082) (xy 94.649288 -246.324957) (xy 94.616653 -246.28812)
			(xy 94.59035 -246.246524) (xy 94.571059 -246.201248) (xy 94.559282 -246.153464) (xy 94.555322 -246.10441)
			(xy 94.236794 -246.10441) (xy 94.236282 -246.129856) (xy 94.228118 -246.18009) (xy 94.212002 -246.228364)
			(xy 94.188351 -246.273427) (xy 94.157778 -246.314113) (xy 94.121074 -246.349368) (xy 94.07919 -246.378278)
			(xy 94.033211 -246.400095) (xy 93.984327 -246.414255) (xy 93.933806 -246.420389) (xy 93.882954 -246.41834)
			(xy 93.83309 -246.40816) (xy 93.785504 -246.390113) (xy 93.74143 -246.364667) (xy 93.702008 -246.33248)
			(xy 93.66826 -246.294386) (xy 93.641059 -246.251372) (xy 93.621111 -246.204552) (xy 93.608932 -246.155138)
			(xy 93.604837 -246.10441) (xy 93.286326 -246.10441) (xy 93.285831 -246.129017) (xy 93.277936 -246.177594)
			(xy 93.262352 -246.224275) (xy 93.239481 -246.267852) (xy 93.209916 -246.307196) (xy 93.174423 -246.341288)
			(xy 93.13392 -246.369244) (xy 93.089458 -246.390342) (xy 93.042187 -246.404034) (xy 92.993332 -246.409966)
			(xy 92.944157 -246.407985) (xy 92.895938 -246.398141) (xy 92.849922 -246.380689) (xy 92.807301 -246.356082)
			(xy 92.76918 -246.324957) (xy 92.736545 -246.28812) (xy 92.710242 -246.246524) (xy 92.690951 -246.201248)
			(xy 92.679174 -246.153464) (xy 92.675214 -246.10441) (xy 92.356686 -246.10441) (xy 92.356174 -246.129856)
			(xy 92.34801 -246.18009) (xy 92.331894 -246.228364) (xy 92.308243 -246.273427) (xy 92.27767 -246.314113)
			(xy 92.240966 -246.349368) (xy 92.199082 -246.378278) (xy 92.153103 -246.400095) (xy 92.104219 -246.414255)
			(xy 92.053698 -246.420389) (xy 92.002846 -246.41834) (xy 91.952982 -246.40816) (xy 91.905396 -246.390113)
			(xy 91.861322 -246.364667) (xy 91.8219 -246.33248) (xy 91.788152 -246.294386) (xy 91.760951 -246.251372)
			(xy 91.741003 -246.204552) (xy 91.728824 -246.155138) (xy 91.724729 -246.10441) (xy 91.416632 -246.10441)
			(xy 91.41612 -246.129856) (xy 91.407956 -246.18009) (xy 91.39184 -246.228364) (xy 91.368189 -246.273427)
			(xy 91.337616 -246.314113) (xy 91.300912 -246.349368) (xy 91.259028 -246.378278) (xy 91.213049 -246.400095)
			(xy 91.164165 -246.414255) (xy 91.113644 -246.420389) (xy 91.062792 -246.41834) (xy 91.012928 -246.40816)
			(xy 90.965342 -246.390113) (xy 90.921268 -246.364667) (xy 90.881846 -246.33248) (xy 90.848098 -246.294386)
			(xy 90.820897 -246.251372) (xy 90.800949 -246.204552) (xy 90.78877 -246.155138) (xy 90.784675 -246.10441)
			(xy 90.466418 -246.10441) (xy 90.465923 -246.129017) (xy 90.458028 -246.177594) (xy 90.442444 -246.224275)
			(xy 90.419573 -246.267852) (xy 90.390008 -246.307196) (xy 90.354515 -246.341288) (xy 90.314012 -246.369244)
			(xy 90.26955 -246.390342) (xy 90.222279 -246.404034) (xy 90.173424 -246.409966) (xy 90.124249 -246.407985)
			(xy 90.07603 -246.398141) (xy 90.030014 -246.380689) (xy 89.987393 -246.356082) (xy 89.949272 -246.324957)
			(xy 89.916637 -246.28812) (xy 89.890334 -246.246524) (xy 89.871043 -246.201248) (xy 89.859266 -246.153464)
			(xy 89.855306 -246.10441) (xy 89.536778 -246.10441) (xy 89.536266 -246.129856) (xy 89.528102 -246.18009)
			(xy 89.511986 -246.228364) (xy 89.488335 -246.273427) (xy 89.457762 -246.314113) (xy 89.421058 -246.349368)
			(xy 89.379174 -246.378278) (xy 89.333195 -246.400095) (xy 89.284311 -246.414255) (xy 89.23379 -246.420389)
			(xy 89.182938 -246.41834) (xy 89.133074 -246.40816) (xy 89.085488 -246.390113) (xy 89.041414 -246.364667)
			(xy 89.001992 -246.33248) (xy 88.968244 -246.294386) (xy 88.941043 -246.251372) (xy 88.921095 -246.204552)
			(xy 88.908916 -246.155138) (xy 88.904821 -246.10441) (xy 88.58631 -246.10441) (xy 88.585815 -246.129017)
			(xy 88.57792 -246.177594) (xy 88.562336 -246.224275) (xy 88.539465 -246.267852) (xy 88.5099 -246.307196)
			(xy 88.474407 -246.341288) (xy 88.433904 -246.369244) (xy 88.389442 -246.390342) (xy 88.342171 -246.404034)
			(xy 88.293316 -246.409966) (xy 88.244141 -246.407985) (xy 88.195922 -246.398141) (xy 88.149906 -246.380689)
			(xy 88.107285 -246.356082) (xy 88.069164 -246.324957) (xy 88.036529 -246.28812) (xy 88.010226 -246.246524)
			(xy 87.990935 -246.201248) (xy 87.979158 -246.153464) (xy 87.975198 -246.10441) (xy 87.65667 -246.10441)
			(xy 87.656158 -246.129856) (xy 87.647994 -246.18009) (xy 87.631878 -246.228364) (xy 87.608227 -246.273427)
			(xy 87.577654 -246.314113) (xy 87.54095 -246.349368) (xy 87.499066 -246.378278) (xy 87.453087 -246.400095)
			(xy 87.404203 -246.414255) (xy 87.353682 -246.420389) (xy 87.30283 -246.41834) (xy 87.252966 -246.40816)
			(xy 87.20538 -246.390113) (xy 87.161306 -246.364667) (xy 87.121884 -246.33248) (xy 87.088136 -246.294386)
			(xy 87.060935 -246.251372) (xy 87.040987 -246.204552) (xy 87.028808 -246.155138) (xy 87.024713 -246.10441)
			(xy 86.706456 -246.10441) (xy 86.705961 -246.129017) (xy 86.698066 -246.177594) (xy 86.682482 -246.224275)
			(xy 86.659611 -246.267852) (xy 86.630046 -246.307196) (xy 86.594553 -246.341288) (xy 86.55405 -246.369244)
			(xy 86.509588 -246.390342) (xy 86.462317 -246.404034) (xy 86.413462 -246.409966) (xy 86.364287 -246.407985)
			(xy 86.316068 -246.398141) (xy 86.270052 -246.380689) (xy 86.227431 -246.356082) (xy 86.18931 -246.324957)
			(xy 86.156675 -246.28812) (xy 86.130372 -246.246524) (xy 86.111081 -246.201248) (xy 86.099304 -246.153464)
			(xy 86.095344 -246.10441) (xy 85.776816 -246.10441) (xy 85.776304 -246.129856) (xy 85.76814 -246.18009)
			(xy 85.752024 -246.228364) (xy 85.728373 -246.273427) (xy 85.6978 -246.314113) (xy 85.661096 -246.349368)
			(xy 85.619212 -246.378278) (xy 85.573233 -246.400095) (xy 85.524349 -246.414255) (xy 85.473828 -246.420389)
			(xy 85.422976 -246.41834) (xy 85.373112 -246.40816) (xy 85.325526 -246.390113) (xy 85.281452 -246.364667)
			(xy 85.24203 -246.33248) (xy 85.208282 -246.294386) (xy 85.181081 -246.251372) (xy 85.161133 -246.204552)
			(xy 85.148954 -246.155138) (xy 85.144859 -246.10441) (xy 84.836762 -246.10441) (xy 84.83625 -246.129856)
			(xy 84.828086 -246.18009) (xy 84.81197 -246.228364) (xy 84.788319 -246.273427) (xy 84.757746 -246.314113)
			(xy 84.721042 -246.349368) (xy 84.679158 -246.378278) (xy 84.633179 -246.400095) (xy 84.584295 -246.414255)
			(xy 84.533774 -246.420389) (xy 84.482922 -246.41834) (xy 84.433058 -246.40816) (xy 84.385472 -246.390113)
			(xy 84.341398 -246.364667) (xy 84.301976 -246.33248) (xy 84.268228 -246.294386) (xy 84.241027 -246.251372)
			(xy 84.221079 -246.204552) (xy 84.2089 -246.155138) (xy 84.204805 -246.10441) (xy 83.886294 -246.10441)
			(xy 83.885799 -246.129017) (xy 83.877904 -246.177594) (xy 83.86232 -246.224275) (xy 83.839449 -246.267852)
			(xy 83.809884 -246.307196) (xy 83.774391 -246.341288) (xy 83.733888 -246.369244) (xy 83.689426 -246.390342)
			(xy 83.642155 -246.404034) (xy 83.5933 -246.409966) (xy 83.544125 -246.407985) (xy 83.495906 -246.398141)
			(xy 83.44989 -246.380689) (xy 83.407269 -246.356082) (xy 83.369148 -246.324957) (xy 83.336513 -246.28812)
			(xy 83.31021 -246.246524) (xy 83.290919 -246.201248) (xy 83.279142 -246.153464) (xy 83.275182 -246.10441)
			(xy 82.956654 -246.10441) (xy 82.956142 -246.129856) (xy 82.947978 -246.18009) (xy 82.931862 -246.228364)
			(xy 82.908211 -246.273427) (xy 82.877638 -246.314113) (xy 82.840934 -246.349368) (xy 82.79905 -246.378278)
			(xy 82.753071 -246.400095) (xy 82.704187 -246.414255) (xy 82.653666 -246.420389) (xy 82.602814 -246.41834)
			(xy 82.55295 -246.40816) (xy 82.505364 -246.390113) (xy 82.46129 -246.364667) (xy 82.421868 -246.33248)
			(xy 82.38812 -246.294386) (xy 82.360919 -246.251372) (xy 82.340971 -246.204552) (xy 82.328792 -246.155138)
			(xy 82.324697 -246.10441) (xy 82.00644 -246.10441) (xy 82.005945 -246.129017) (xy 81.99805 -246.177594)
			(xy 81.982466 -246.224275) (xy 81.959595 -246.267852) (xy 81.93003 -246.307196) (xy 81.894537 -246.341288)
			(xy 81.854034 -246.369244) (xy 81.809572 -246.390342) (xy 81.762301 -246.404034) (xy 81.713446 -246.409966)
			(xy 81.664271 -246.407985) (xy 81.616052 -246.398141) (xy 81.570036 -246.380689) (xy 81.527415 -246.356082)
			(xy 81.489294 -246.324957) (xy 81.456659 -246.28812) (xy 81.430356 -246.246524) (xy 81.411065 -246.201248)
			(xy 81.399288 -246.153464) (xy 81.395328 -246.10441) (xy 81.0768 -246.10441) (xy 81.076288 -246.129856)
			(xy 81.068124 -246.18009) (xy 81.052008 -246.228364) (xy 81.028357 -246.273427) (xy 80.997784 -246.314113)
			(xy 80.96108 -246.349368) (xy 80.919196 -246.378278) (xy 80.873217 -246.400095) (xy 80.824333 -246.414255)
			(xy 80.773812 -246.420389) (xy 80.72296 -246.41834) (xy 80.673096 -246.40816) (xy 80.62551 -246.390113)
			(xy 80.581436 -246.364667) (xy 80.542014 -246.33248) (xy 80.508266 -246.294386) (xy 80.481065 -246.251372)
			(xy 80.461117 -246.204552) (xy 80.448938 -246.155138) (xy 80.444843 -246.10441) (xy 80.126332 -246.10441)
			(xy 80.125837 -246.129017) (xy 80.117942 -246.177594) (xy 80.102358 -246.224275) (xy 80.079487 -246.267852)
			(xy 80.049922 -246.307196) (xy 80.014429 -246.341288) (xy 79.973926 -246.369244) (xy 79.929464 -246.390342)
			(xy 79.882193 -246.404034) (xy 79.833338 -246.409966) (xy 79.784163 -246.407985) (xy 79.735944 -246.398141)
			(xy 79.689928 -246.380689) (xy 79.647307 -246.356082) (xy 79.609186 -246.324957) (xy 79.576551 -246.28812)
			(xy 79.550248 -246.246524) (xy 79.530957 -246.201248) (xy 79.51918 -246.153464) (xy 79.51522 -246.10441)
			(xy 76.963477 -246.10441) (xy 76.965804 -246.105514) (xy 77.006307 -246.13347) (xy 77.0418 -246.167562)
			(xy 77.071365 -246.206906) (xy 77.094236 -246.250483) (xy 77.10982 -246.297164) (xy 77.117715 -246.345741)
			(xy 77.11821 -246.370348) (xy 77.117715 -246.394955) (xy 77.10982 -246.443532) (xy 77.094236 -246.490213)
			(xy 77.071365 -246.53379) (xy 77.0418 -246.573134) (xy 77.006307 -246.607226) (xy 76.965804 -246.635182)
			(xy 76.921342 -246.65628) (xy 76.874071 -246.669972) (xy 76.825216 -246.675904) (xy 76.776041 -246.673923)
			(xy 76.727822 -246.664079) (xy 76.681806 -246.646627) (xy 76.639185 -246.62202) (xy 76.601064 -246.590895)
			(xy 76.568429 -246.554058) (xy 76.542126 -246.512462) (xy 76.522835 -246.467186) (xy 76.511058 -246.419402)
			(xy 76.507098 -246.370348) (xy 63.412116 -246.370348) (xy 63.956184 -246.914416) (xy 78.105266 -246.914416)
			(xy 78.109226 -246.865362) (xy 78.121003 -246.817578) (xy 78.140294 -246.772302) (xy 78.166597 -246.730706)
			(xy 78.199232 -246.693869) (xy 78.237353 -246.662744) (xy 78.279974 -246.638137) (xy 78.32599 -246.620685)
			(xy 78.374209 -246.610841) (xy 78.423384 -246.60886) (xy 78.472239 -246.614792) (xy 78.51951 -246.628484)
			(xy 78.563972 -246.649582) (xy 78.604475 -246.677538) (xy 78.639968 -246.71163) (xy 78.669533 -246.750974)
			(xy 78.692404 -246.794551) (xy 78.707988 -246.841232) (xy 78.715883 -246.889809) (xy 78.716378 -246.914416)
			(xy 79.985374 -246.914416) (xy 79.989334 -246.865362) (xy 80.001111 -246.817578) (xy 80.020402 -246.772302)
			(xy 80.046705 -246.730706) (xy 80.07934 -246.693869) (xy 80.117461 -246.662744) (xy 80.160082 -246.638137)
			(xy 80.206098 -246.620685) (xy 80.254317 -246.610841) (xy 80.303492 -246.60886) (xy 80.352347 -246.614792)
			(xy 80.399618 -246.628484) (xy 80.44408 -246.649582) (xy 80.484583 -246.677538) (xy 80.520076 -246.71163)
			(xy 80.549641 -246.750974) (xy 80.572512 -246.794551) (xy 80.588096 -246.841232) (xy 80.595991 -246.889809)
			(xy 80.596486 -246.914416) (xy 80.914743 -246.914416) (xy 80.918838 -246.863688) (xy 80.931017 -246.814274)
			(xy 80.950965 -246.767454) (xy 80.978166 -246.72444) (xy 81.011914 -246.686346) (xy 81.051336 -246.654159)
			(xy 81.09541 -246.628713) (xy 81.142996 -246.610666) (xy 81.19286 -246.600486) (xy 81.243712 -246.598437)
			(xy 81.294233 -246.604571) (xy 81.343117 -246.618731) (xy 81.389096 -246.640548) (xy 81.43098 -246.669458)
			(xy 81.467684 -246.704713) (xy 81.498257 -246.745399) (xy 81.521908 -246.790462) (xy 81.538024 -246.838736)
			(xy 81.546188 -246.88897) (xy 81.5467 -246.914416) (xy 81.854797 -246.914416) (xy 81.858892 -246.863688)
			(xy 81.871071 -246.814274) (xy 81.891019 -246.767454) (xy 81.91822 -246.72444) (xy 81.951968 -246.686346)
			(xy 81.99139 -246.654159) (xy 82.035464 -246.628713) (xy 82.08305 -246.610666) (xy 82.132914 -246.600486)
			(xy 82.183766 -246.598437) (xy 82.234287 -246.604571) (xy 82.283171 -246.618731) (xy 82.32915 -246.640548)
			(xy 82.371034 -246.669458) (xy 82.407738 -246.704713) (xy 82.438311 -246.745399) (xy 82.461962 -246.790462)
			(xy 82.478078 -246.838736) (xy 82.486242 -246.88897) (xy 82.486754 -246.914416) (xy 82.805282 -246.914416)
			(xy 82.809242 -246.865362) (xy 82.821019 -246.817578) (xy 82.84031 -246.772302) (xy 82.866613 -246.730706)
			(xy 82.899248 -246.693869) (xy 82.937369 -246.662744) (xy 82.97999 -246.638137) (xy 83.026006 -246.620685)
			(xy 83.074225 -246.610841) (xy 83.1234 -246.60886) (xy 83.172255 -246.614792) (xy 83.219526 -246.628484)
			(xy 83.263988 -246.649582) (xy 83.304491 -246.677538) (xy 83.339984 -246.71163) (xy 83.369549 -246.750974)
			(xy 83.39242 -246.794551) (xy 83.408004 -246.841232) (xy 83.415899 -246.889809) (xy 83.416394 -246.914416)
			(xy 83.734905 -246.914416) (xy 83.739 -246.863688) (xy 83.751179 -246.814274) (xy 83.771127 -246.767454)
			(xy 83.798328 -246.72444) (xy 83.832076 -246.686346) (xy 83.871498 -246.654159) (xy 83.915572 -246.628713)
			(xy 83.963158 -246.610666) (xy 84.013022 -246.600486) (xy 84.063874 -246.598437) (xy 84.114395 -246.604571)
			(xy 84.163279 -246.618731) (xy 84.209258 -246.640548) (xy 84.251142 -246.669458) (xy 84.287846 -246.704713)
			(xy 84.318419 -246.745399) (xy 84.34207 -246.790462) (xy 84.358186 -246.838736) (xy 84.36635 -246.88897)
			(xy 84.366862 -246.914416) (xy 84.685136 -246.914416) (xy 84.689096 -246.865362) (xy 84.700873 -246.817578)
			(xy 84.720164 -246.772302) (xy 84.746467 -246.730706) (xy 84.779102 -246.693869) (xy 84.817223 -246.662744)
			(xy 84.859844 -246.638137) (xy 84.90586 -246.620685) (xy 84.954079 -246.610841) (xy 85.003254 -246.60886)
			(xy 85.052109 -246.614792) (xy 85.09938 -246.628484) (xy 85.143842 -246.649582) (xy 85.184345 -246.677538)
			(xy 85.219838 -246.71163) (xy 85.249403 -246.750974) (xy 85.272274 -246.794551) (xy 85.287858 -246.841232)
			(xy 85.295753 -246.889809) (xy 85.296248 -246.914416) (xy 85.614759 -246.914416) (xy 85.618854 -246.863688)
			(xy 85.631033 -246.814274) (xy 85.650981 -246.767454) (xy 85.678182 -246.72444) (xy 85.71193 -246.686346)
			(xy 85.751352 -246.654159) (xy 85.795426 -246.628713) (xy 85.843012 -246.610666) (xy 85.892876 -246.600486)
			(xy 85.943728 -246.598437) (xy 85.994249 -246.604571) (xy 86.043133 -246.618731) (xy 86.089112 -246.640548)
			(xy 86.130996 -246.669458) (xy 86.1677 -246.704713) (xy 86.198273 -246.745399) (xy 86.221924 -246.790462)
			(xy 86.23804 -246.838736) (xy 86.246204 -246.88897) (xy 86.246716 -246.914416) (xy 86.565244 -246.914416)
			(xy 86.569204 -246.865362) (xy 86.580981 -246.817578) (xy 86.600272 -246.772302) (xy 86.626575 -246.730706)
			(xy 86.65921 -246.693869) (xy 86.697331 -246.662744) (xy 86.739952 -246.638137) (xy 86.785968 -246.620685)
			(xy 86.834187 -246.610841) (xy 86.883362 -246.60886) (xy 86.932217 -246.614792) (xy 86.979488 -246.628484)
			(xy 87.02395 -246.649582) (xy 87.064453 -246.677538) (xy 87.099946 -246.71163) (xy 87.129511 -246.750974)
			(xy 87.152382 -246.794551) (xy 87.167966 -246.841232) (xy 87.175861 -246.889809) (xy 87.176356 -246.914416)
			(xy 87.494867 -246.914416) (xy 87.498962 -246.863688) (xy 87.511141 -246.814274) (xy 87.531089 -246.767454)
			(xy 87.55829 -246.72444) (xy 87.592038 -246.686346) (xy 87.63146 -246.654159) (xy 87.675534 -246.628713)
			(xy 87.72312 -246.610666) (xy 87.772984 -246.600486) (xy 87.823836 -246.598437) (xy 87.874357 -246.604571)
			(xy 87.923241 -246.618731) (xy 87.96922 -246.640548) (xy 88.011104 -246.669458) (xy 88.047808 -246.704713)
			(xy 88.078381 -246.745399) (xy 88.102032 -246.790462) (xy 88.118148 -246.838736) (xy 88.126312 -246.88897)
			(xy 88.126824 -246.914416) (xy 88.434921 -246.914416) (xy 88.439016 -246.863688) (xy 88.451195 -246.814274)
			(xy 88.471143 -246.767454) (xy 88.498344 -246.72444) (xy 88.532092 -246.686346) (xy 88.571514 -246.654159)
			(xy 88.615588 -246.628713) (xy 88.663174 -246.610666) (xy 88.713038 -246.600486) (xy 88.76389 -246.598437)
			(xy 88.814411 -246.604571) (xy 88.863295 -246.618731) (xy 88.909274 -246.640548) (xy 88.951158 -246.669458)
			(xy 88.987862 -246.704713) (xy 89.018435 -246.745399) (xy 89.042086 -246.790462) (xy 89.058202 -246.838736)
			(xy 89.066366 -246.88897) (xy 89.066878 -246.914416) (xy 89.385152 -246.914416) (xy 89.389112 -246.865362)
			(xy 89.400889 -246.817578) (xy 89.42018 -246.772302) (xy 89.446483 -246.730706) (xy 89.479118 -246.693869)
			(xy 89.517239 -246.662744) (xy 89.55986 -246.638137) (xy 89.605876 -246.620685) (xy 89.654095 -246.610841)
			(xy 89.70327 -246.60886) (xy 89.752125 -246.614792) (xy 89.799396 -246.628484) (xy 89.843858 -246.649582)
			(xy 89.884361 -246.677538) (xy 89.919854 -246.71163) (xy 89.949419 -246.750974) (xy 89.97229 -246.794551)
			(xy 89.987874 -246.841232) (xy 89.995769 -246.889809) (xy 89.996264 -246.914416) (xy 90.314775 -246.914416)
			(xy 90.31887 -246.863688) (xy 90.331049 -246.814274) (xy 90.350997 -246.767454) (xy 90.378198 -246.72444)
			(xy 90.411946 -246.686346) (xy 90.451368 -246.654159) (xy 90.495442 -246.628713) (xy 90.543028 -246.610666)
			(xy 90.592892 -246.600486) (xy 90.643744 -246.598437) (xy 90.694265 -246.604571) (xy 90.743149 -246.618731)
			(xy 90.789128 -246.640548) (xy 90.831012 -246.669458) (xy 90.867716 -246.704713) (xy 90.898289 -246.745399)
			(xy 90.92194 -246.790462) (xy 90.938056 -246.838736) (xy 90.94622 -246.88897) (xy 90.946732 -246.914416)
			(xy 91.26526 -246.914416) (xy 91.26922 -246.865362) (xy 91.280997 -246.817578) (xy 91.300288 -246.772302)
			(xy 91.326591 -246.730706) (xy 91.359226 -246.693869) (xy 91.397347 -246.662744) (xy 91.439968 -246.638137)
			(xy 91.485984 -246.620685) (xy 91.534203 -246.610841) (xy 91.583378 -246.60886) (xy 91.632233 -246.614792)
			(xy 91.679504 -246.628484) (xy 91.723966 -246.649582) (xy 91.764469 -246.677538) (xy 91.799962 -246.71163)
			(xy 91.829527 -246.750974) (xy 91.852398 -246.794551) (xy 91.867982 -246.841232) (xy 91.875877 -246.889809)
			(xy 91.876372 -246.914416) (xy 92.194883 -246.914416) (xy 92.198978 -246.863688) (xy 92.211157 -246.814274)
			(xy 92.231105 -246.767454) (xy 92.258306 -246.72444) (xy 92.292054 -246.686346) (xy 92.331476 -246.654159)
			(xy 92.37555 -246.628713) (xy 92.423136 -246.610666) (xy 92.473 -246.600486) (xy 92.523852 -246.598437)
			(xy 92.574373 -246.604571) (xy 92.623257 -246.618731) (xy 92.669236 -246.640548) (xy 92.71112 -246.669458)
			(xy 92.747824 -246.704713) (xy 92.778397 -246.745399) (xy 92.802048 -246.790462) (xy 92.818164 -246.838736)
			(xy 92.826328 -246.88897) (xy 92.82684 -246.914416) (xy 93.145114 -246.914416) (xy 93.149074 -246.865362)
			(xy 93.160851 -246.817578) (xy 93.180142 -246.772302) (xy 93.206445 -246.730706) (xy 93.23908 -246.693869)
			(xy 93.277201 -246.662744) (xy 93.319822 -246.638137) (xy 93.365838 -246.620685) (xy 93.414057 -246.610841)
			(xy 93.463232 -246.60886) (xy 93.512087 -246.614792) (xy 93.559358 -246.628484) (xy 93.60382 -246.649582)
			(xy 93.644323 -246.677538) (xy 93.679816 -246.71163) (xy 93.709381 -246.750974) (xy 93.732252 -246.794551)
			(xy 93.747836 -246.841232) (xy 93.755731 -246.889809) (xy 93.756226 -246.914416) (xy 94.074737 -246.914416)
			(xy 94.078832 -246.863688) (xy 94.091011 -246.814274) (xy 94.110959 -246.767454) (xy 94.13816 -246.72444)
			(xy 94.171908 -246.686346) (xy 94.21133 -246.654159) (xy 94.255404 -246.628713) (xy 94.30299 -246.610666)
			(xy 94.352854 -246.600486) (xy 94.403706 -246.598437) (xy 94.454227 -246.604571) (xy 94.503111 -246.618731)
			(xy 94.54909 -246.640548) (xy 94.590974 -246.669458) (xy 94.627678 -246.704713) (xy 94.658251 -246.745399)
			(xy 94.681902 -246.790462) (xy 94.698018 -246.838736) (xy 94.706182 -246.88897) (xy 94.706694 -246.914416)
			(xy 95.014791 -246.914416) (xy 95.018886 -246.863688) (xy 95.031065 -246.814274) (xy 95.051013 -246.767454)
			(xy 95.078214 -246.72444) (xy 95.111962 -246.686346) (xy 95.151384 -246.654159) (xy 95.195458 -246.628713)
			(xy 95.243044 -246.610666) (xy 95.292908 -246.600486) (xy 95.34376 -246.598437) (xy 95.394281 -246.604571)
			(xy 95.443165 -246.618731) (xy 95.489144 -246.640548) (xy 95.531028 -246.669458) (xy 95.567732 -246.704713)
			(xy 95.598305 -246.745399) (xy 95.621956 -246.790462) (xy 95.638072 -246.838736) (xy 95.646236 -246.88897)
			(xy 95.646748 -246.914416) (xy 95.965276 -246.914416) (xy 95.969236 -246.865362) (xy 95.981013 -246.817578)
			(xy 96.000304 -246.772302) (xy 96.026607 -246.730706) (xy 96.059242 -246.693869) (xy 96.097363 -246.662744)
			(xy 96.139984 -246.638137) (xy 96.186 -246.620685) (xy 96.234219 -246.610841) (xy 96.283394 -246.60886)
			(xy 96.332249 -246.614792) (xy 96.37952 -246.628484) (xy 96.423982 -246.649582) (xy 96.464485 -246.677538)
			(xy 96.499978 -246.71163) (xy 96.529543 -246.750974) (xy 96.552414 -246.794551) (xy 96.567998 -246.841232)
			(xy 96.575893 -246.889809) (xy 96.576388 -246.914416) (xy 96.90533 -246.914416) (xy 96.90929 -246.865362)
			(xy 96.921067 -246.817578) (xy 96.940358 -246.772302) (xy 96.966661 -246.730706) (xy 96.999296 -246.693869)
			(xy 97.037417 -246.662744) (xy 97.080038 -246.638137) (xy 97.126054 -246.620685) (xy 97.174273 -246.610841)
			(xy 97.223448 -246.60886) (xy 97.272303 -246.614792) (xy 97.319574 -246.628484) (xy 97.364036 -246.649582)
			(xy 97.404539 -246.677538) (xy 97.440032 -246.71163) (xy 97.469597 -246.750974) (xy 97.492468 -246.794551)
			(xy 97.508052 -246.841232) (xy 97.515947 -246.889809) (xy 97.516442 -246.914416) (xy 97.84513 -246.914416)
			(xy 97.84909 -246.865362) (xy 97.860867 -246.817578) (xy 97.880158 -246.772302) (xy 97.906461 -246.730706)
			(xy 97.939096 -246.693869) (xy 97.977217 -246.662744) (xy 98.019838 -246.638137) (xy 98.065854 -246.620685)
			(xy 98.114073 -246.610841) (xy 98.163248 -246.60886) (xy 98.212103 -246.614792) (xy 98.259374 -246.628484)
			(xy 98.303836 -246.649582) (xy 98.344339 -246.677538) (xy 98.379832 -246.71163) (xy 98.409397 -246.750974)
			(xy 98.432268 -246.794551) (xy 98.447852 -246.841232) (xy 98.455747 -246.889809) (xy 98.456242 -246.914416)
			(xy 98.785184 -246.914416) (xy 98.789144 -246.865362) (xy 98.800921 -246.817578) (xy 98.820212 -246.772302)
			(xy 98.846515 -246.730706) (xy 98.87915 -246.693869) (xy 98.917271 -246.662744) (xy 98.959892 -246.638137)
			(xy 99.005908 -246.620685) (xy 99.054127 -246.610841) (xy 99.103302 -246.60886) (xy 99.152157 -246.614792)
			(xy 99.199428 -246.628484) (xy 99.24389 -246.649582) (xy 99.284393 -246.677538) (xy 99.319886 -246.71163)
			(xy 99.349451 -246.750974) (xy 99.372322 -246.794551) (xy 99.387906 -246.841232) (xy 99.395801 -246.889809)
			(xy 99.396296 -246.914416) (xy 99.725238 -246.914416) (xy 99.729198 -246.865362) (xy 99.740975 -246.817578)
			(xy 99.760266 -246.772302) (xy 99.786569 -246.730706) (xy 99.819204 -246.693869) (xy 99.857325 -246.662744)
			(xy 99.899946 -246.638137) (xy 99.945962 -246.620685) (xy 99.994181 -246.610841) (xy 100.043356 -246.60886)
			(xy 100.092211 -246.614792) (xy 100.139482 -246.628484) (xy 100.183944 -246.649582) (xy 100.224447 -246.677538)
			(xy 100.25994 -246.71163) (xy 100.289505 -246.750974) (xy 100.312376 -246.794551) (xy 100.32796 -246.841232)
			(xy 100.335855 -246.889809) (xy 100.33635 -246.914416) (xy 100.665292 -246.914416) (xy 100.669252 -246.865362)
			(xy 100.681029 -246.817578) (xy 100.70032 -246.772302) (xy 100.726623 -246.730706) (xy 100.759258 -246.693869)
			(xy 100.797379 -246.662744) (xy 100.84 -246.638137) (xy 100.886016 -246.620685) (xy 100.934235 -246.610841)
			(xy 100.98341 -246.60886) (xy 101.032265 -246.614792) (xy 101.079536 -246.628484) (xy 101.123998 -246.649582)
			(xy 101.164501 -246.677538) (xy 101.199994 -246.71163) (xy 101.229559 -246.750974) (xy 101.25243 -246.794551)
			(xy 101.268014 -246.841232) (xy 101.275909 -246.889809) (xy 101.276404 -246.914416) (xy 101.605346 -246.914416)
			(xy 101.609306 -246.865362) (xy 101.621083 -246.817578) (xy 101.640374 -246.772302) (xy 101.666677 -246.730706)
			(xy 101.699312 -246.693869) (xy 101.737433 -246.662744) (xy 101.780054 -246.638137) (xy 101.82607 -246.620685)
			(xy 101.874289 -246.610841) (xy 101.923464 -246.60886) (xy 101.972319 -246.614792) (xy 102.01959 -246.628484)
			(xy 102.064052 -246.649582) (xy 102.104555 -246.677538) (xy 102.140048 -246.71163) (xy 102.169613 -246.750974)
			(xy 102.192484 -246.794551) (xy 102.208068 -246.841232) (xy 102.215963 -246.889809) (xy 102.216458 -246.914416)
			(xy 102.545146 -246.914416) (xy 102.549106 -246.865362) (xy 102.560883 -246.817578) (xy 102.580174 -246.772302)
			(xy 102.606477 -246.730706) (xy 102.639112 -246.693869) (xy 102.677233 -246.662744) (xy 102.719854 -246.638137)
			(xy 102.76587 -246.620685) (xy 102.814089 -246.610841) (xy 102.863264 -246.60886) (xy 102.912119 -246.614792)
			(xy 102.95939 -246.628484) (xy 103.003852 -246.649582) (xy 103.044355 -246.677538) (xy 103.079848 -246.71163)
			(xy 103.109413 -246.750974) (xy 103.132284 -246.794551) (xy 103.147868 -246.841232) (xy 103.155763 -246.889809)
			(xy 103.156258 -246.914416) (xy 103.4852 -246.914416) (xy 103.48916 -246.865362) (xy 103.500937 -246.817578)
			(xy 103.520228 -246.772302) (xy 103.546531 -246.730706) (xy 103.579166 -246.693869) (xy 103.617287 -246.662744)
			(xy 103.659908 -246.638137) (xy 103.705924 -246.620685) (xy 103.754143 -246.610841) (xy 103.803318 -246.60886)
			(xy 103.852173 -246.614792) (xy 103.899444 -246.628484) (xy 103.943906 -246.649582) (xy 103.984409 -246.677538)
			(xy 104.019902 -246.71163) (xy 104.049467 -246.750974) (xy 104.072338 -246.794551) (xy 104.087922 -246.841232)
			(xy 104.095817 -246.889809) (xy 104.096312 -246.914416) (xy 104.425254 -246.914416) (xy 104.429214 -246.865362)
			(xy 104.440991 -246.817578) (xy 104.460282 -246.772302) (xy 104.486585 -246.730706) (xy 104.51922 -246.693869)
			(xy 104.557341 -246.662744) (xy 104.599962 -246.638137) (xy 104.645978 -246.620685) (xy 104.694197 -246.610841)
			(xy 104.743372 -246.60886) (xy 104.792227 -246.614792) (xy 104.839498 -246.628484) (xy 104.88396 -246.649582)
			(xy 104.924463 -246.677538) (xy 104.959956 -246.71163) (xy 104.989521 -246.750974) (xy 105.012392 -246.794551)
			(xy 105.027976 -246.841232) (xy 105.035871 -246.889809) (xy 105.036366 -246.914416) (xy 105.365308 -246.914416)
			(xy 105.369268 -246.865362) (xy 105.381045 -246.817578) (xy 105.400336 -246.772302) (xy 105.426639 -246.730706)
			(xy 105.459274 -246.693869) (xy 105.497395 -246.662744) (xy 105.540016 -246.638137) (xy 105.586032 -246.620685)
			(xy 105.634251 -246.610841) (xy 105.683426 -246.60886) (xy 105.732281 -246.614792) (xy 105.779552 -246.628484)
			(xy 105.824014 -246.649582) (xy 105.864517 -246.677538) (xy 105.90001 -246.71163) (xy 105.929575 -246.750974)
			(xy 105.952446 -246.794551) (xy 105.96803 -246.841232) (xy 105.975925 -246.889809) (xy 105.97642 -246.914416)
			(xy 106.305362 -246.914416) (xy 106.309322 -246.865362) (xy 106.321099 -246.817578) (xy 106.34039 -246.772302)
			(xy 106.366693 -246.730706) (xy 106.399328 -246.693869) (xy 106.437449 -246.662744) (xy 106.48007 -246.638137)
			(xy 106.526086 -246.620685) (xy 106.574305 -246.610841) (xy 106.62348 -246.60886) (xy 106.672335 -246.614792)
			(xy 106.719606 -246.628484) (xy 106.764068 -246.649582) (xy 106.804571 -246.677538) (xy 106.840064 -246.71163)
			(xy 106.869629 -246.750974) (xy 106.8925 -246.794551) (xy 106.908084 -246.841232) (xy 106.915979 -246.889809)
			(xy 106.916474 -246.914416) (xy 107.245162 -246.914416) (xy 107.249122 -246.865362) (xy 107.260899 -246.817578)
			(xy 107.28019 -246.772302) (xy 107.306493 -246.730706) (xy 107.339128 -246.693869) (xy 107.377249 -246.662744)
			(xy 107.41987 -246.638137) (xy 107.465886 -246.620685) (xy 107.514105 -246.610841) (xy 107.56328 -246.60886)
			(xy 107.612135 -246.614792) (xy 107.659406 -246.628484) (xy 107.703868 -246.649582) (xy 107.744371 -246.677538)
			(xy 107.779864 -246.71163) (xy 107.809429 -246.750974) (xy 107.8323 -246.794551) (xy 107.847884 -246.841232)
			(xy 107.855779 -246.889809) (xy 107.856274 -246.914416) (xy 108.174785 -246.914416) (xy 108.17888 -246.863688)
			(xy 108.191059 -246.814274) (xy 108.211007 -246.767454) (xy 108.238208 -246.72444) (xy 108.271956 -246.686346)
			(xy 108.311378 -246.654159) (xy 108.355452 -246.628713) (xy 108.403038 -246.610666) (xy 108.452902 -246.600486)
			(xy 108.503754 -246.598437) (xy 108.554275 -246.604571) (xy 108.603159 -246.618731) (xy 108.649138 -246.640548)
			(xy 108.691022 -246.669458) (xy 108.727726 -246.704713) (xy 108.758299 -246.745399) (xy 108.78195 -246.790462)
			(xy 108.798066 -246.838736) (xy 108.80623 -246.88897) (xy 108.806742 -246.914416) (xy 109.114839 -246.914416)
			(xy 109.118934 -246.863688) (xy 109.131113 -246.814274) (xy 109.151061 -246.767454) (xy 109.178262 -246.72444)
			(xy 109.21201 -246.686346) (xy 109.251432 -246.654159) (xy 109.295506 -246.628713) (xy 109.343092 -246.610666)
			(xy 109.392956 -246.600486) (xy 109.443808 -246.598437) (xy 109.494329 -246.604571) (xy 109.543213 -246.618731)
			(xy 109.589192 -246.640548) (xy 109.631076 -246.669458) (xy 109.66778 -246.704713) (xy 109.698353 -246.745399)
			(xy 109.722004 -246.790462) (xy 109.73812 -246.838736) (xy 109.746284 -246.88897) (xy 109.746796 -246.914416)
			(xy 110.065324 -246.914416) (xy 110.069284 -246.865362) (xy 110.081061 -246.817578) (xy 110.100352 -246.772302)
			(xy 110.126655 -246.730706) (xy 110.15929 -246.693869) (xy 110.197411 -246.662744) (xy 110.240032 -246.638137)
			(xy 110.286048 -246.620685) (xy 110.334267 -246.610841) (xy 110.383442 -246.60886) (xy 110.432297 -246.614792)
			(xy 110.479568 -246.628484) (xy 110.52403 -246.649582) (xy 110.564533 -246.677538) (xy 110.600026 -246.71163)
			(xy 110.629591 -246.750974) (xy 110.652462 -246.794551) (xy 110.668046 -246.841232) (xy 110.675941 -246.889809)
			(xy 110.676436 -246.914416) (xy 110.675941 -246.939023) (xy 110.668046 -246.9876) (xy 110.652462 -247.034281)
			(xy 110.629591 -247.077858) (xy 110.600026 -247.117202) (xy 110.564533 -247.151294) (xy 110.52403 -247.17925)
			(xy 110.479568 -247.200348) (xy 110.432297 -247.21404) (xy 110.383442 -247.219972) (xy 110.334267 -247.217991)
			(xy 110.286048 -247.208147) (xy 110.240032 -247.190695) (xy 110.197411 -247.166088) (xy 110.15929 -247.134963)
			(xy 110.126655 -247.098126) (xy 110.100352 -247.05653) (xy 110.081061 -247.011254) (xy 110.069284 -246.96347)
			(xy 110.065324 -246.914416) (xy 109.746796 -246.914416) (xy 109.746284 -246.939862) (xy 109.73812 -246.990096)
			(xy 109.722004 -247.03837) (xy 109.698353 -247.083433) (xy 109.66778 -247.124119) (xy 109.631076 -247.159374)
			(xy 109.589192 -247.188284) (xy 109.543213 -247.210101) (xy 109.494329 -247.224261) (xy 109.443808 -247.230395)
			(xy 109.392956 -247.228346) (xy 109.343092 -247.218166) (xy 109.295506 -247.200119) (xy 109.251432 -247.174673)
			(xy 109.21201 -247.142486) (xy 109.178262 -247.104392) (xy 109.151061 -247.061378) (xy 109.131113 -247.014558)
			(xy 109.118934 -246.965144) (xy 109.114839 -246.914416) (xy 108.806742 -246.914416) (xy 108.80623 -246.939862)
			(xy 108.798066 -246.990096) (xy 108.78195 -247.03837) (xy 108.758299 -247.083433) (xy 108.727726 -247.124119)
			(xy 108.691022 -247.159374) (xy 108.649138 -247.188284) (xy 108.603159 -247.210101) (xy 108.554275 -247.224261)
			(xy 108.503754 -247.230395) (xy 108.452902 -247.228346) (xy 108.403038 -247.218166) (xy 108.355452 -247.200119)
			(xy 108.311378 -247.174673) (xy 108.271956 -247.142486) (xy 108.238208 -247.104392) (xy 108.211007 -247.061378)
			(xy 108.191059 -247.014558) (xy 108.17888 -246.965144) (xy 108.174785 -246.914416) (xy 107.856274 -246.914416)
			(xy 107.855779 -246.939023) (xy 107.847884 -246.9876) (xy 107.8323 -247.034281) (xy 107.809429 -247.077858)
			(xy 107.779864 -247.117202) (xy 107.744371 -247.151294) (xy 107.703868 -247.17925) (xy 107.659406 -247.200348)
			(xy 107.612135 -247.21404) (xy 107.56328 -247.219972) (xy 107.514105 -247.217991) (xy 107.465886 -247.208147)
			(xy 107.41987 -247.190695) (xy 107.377249 -247.166088) (xy 107.339128 -247.134963) (xy 107.306493 -247.098126)
			(xy 107.28019 -247.05653) (xy 107.260899 -247.011254) (xy 107.249122 -246.96347) (xy 107.245162 -246.914416)
			(xy 106.916474 -246.914416) (xy 106.915979 -246.939023) (xy 106.908084 -246.9876) (xy 106.8925 -247.034281)
			(xy 106.869629 -247.077858) (xy 106.840064 -247.117202) (xy 106.804571 -247.151294) (xy 106.764068 -247.17925)
			(xy 106.719606 -247.200348) (xy 106.672335 -247.21404) (xy 106.62348 -247.219972) (xy 106.574305 -247.217991)
			(xy 106.526086 -247.208147) (xy 106.48007 -247.190695) (xy 106.437449 -247.166088) (xy 106.399328 -247.134963)
			(xy 106.366693 -247.098126) (xy 106.34039 -247.05653) (xy 106.321099 -247.011254) (xy 106.309322 -246.96347)
			(xy 106.305362 -246.914416) (xy 105.97642 -246.914416) (xy 105.975925 -246.939023) (xy 105.96803 -246.9876)
			(xy 105.952446 -247.034281) (xy 105.929575 -247.077858) (xy 105.90001 -247.117202) (xy 105.864517 -247.151294)
			(xy 105.824014 -247.17925) (xy 105.779552 -247.200348) (xy 105.732281 -247.21404) (xy 105.683426 -247.219972)
			(xy 105.634251 -247.217991) (xy 105.586032 -247.208147) (xy 105.540016 -247.190695) (xy 105.497395 -247.166088)
			(xy 105.459274 -247.134963) (xy 105.426639 -247.098126) (xy 105.400336 -247.05653) (xy 105.381045 -247.011254)
			(xy 105.369268 -246.96347) (xy 105.365308 -246.914416) (xy 105.036366 -246.914416) (xy 105.035871 -246.939023)
			(xy 105.027976 -246.9876) (xy 105.012392 -247.034281) (xy 104.989521 -247.077858) (xy 104.959956 -247.117202)
			(xy 104.924463 -247.151294) (xy 104.88396 -247.17925) (xy 104.839498 -247.200348) (xy 104.792227 -247.21404)
			(xy 104.743372 -247.219972) (xy 104.694197 -247.217991) (xy 104.645978 -247.208147) (xy 104.599962 -247.190695)
			(xy 104.557341 -247.166088) (xy 104.51922 -247.134963) (xy 104.486585 -247.098126) (xy 104.460282 -247.05653)
			(xy 104.440991 -247.011254) (xy 104.429214 -246.96347) (xy 104.425254 -246.914416) (xy 104.096312 -246.914416)
			(xy 104.095817 -246.939023) (xy 104.087922 -246.9876) (xy 104.072338 -247.034281) (xy 104.049467 -247.077858)
			(xy 104.019902 -247.117202) (xy 103.984409 -247.151294) (xy 103.943906 -247.17925) (xy 103.899444 -247.200348)
			(xy 103.852173 -247.21404) (xy 103.803318 -247.219972) (xy 103.754143 -247.217991) (xy 103.705924 -247.208147)
			(xy 103.659908 -247.190695) (xy 103.617287 -247.166088) (xy 103.579166 -247.134963) (xy 103.546531 -247.098126)
			(xy 103.520228 -247.05653) (xy 103.500937 -247.011254) (xy 103.48916 -246.96347) (xy 103.4852 -246.914416)
			(xy 103.156258 -246.914416) (xy 103.155763 -246.939023) (xy 103.147868 -246.9876) (xy 103.132284 -247.034281)
			(xy 103.109413 -247.077858) (xy 103.079848 -247.117202) (xy 103.044355 -247.151294) (xy 103.003852 -247.17925)
			(xy 102.95939 -247.200348) (xy 102.912119 -247.21404) (xy 102.863264 -247.219972) (xy 102.814089 -247.217991)
			(xy 102.76587 -247.208147) (xy 102.719854 -247.190695) (xy 102.677233 -247.166088) (xy 102.639112 -247.134963)
			(xy 102.606477 -247.098126) (xy 102.580174 -247.05653) (xy 102.560883 -247.011254) (xy 102.549106 -246.96347)
			(xy 102.545146 -246.914416) (xy 102.216458 -246.914416) (xy 102.215963 -246.939023) (xy 102.208068 -246.9876)
			(xy 102.192484 -247.034281) (xy 102.169613 -247.077858) (xy 102.140048 -247.117202) (xy 102.104555 -247.151294)
			(xy 102.064052 -247.17925) (xy 102.01959 -247.200348) (xy 101.972319 -247.21404) (xy 101.923464 -247.219972)
			(xy 101.874289 -247.217991) (xy 101.82607 -247.208147) (xy 101.780054 -247.190695) (xy 101.737433 -247.166088)
			(xy 101.699312 -247.134963) (xy 101.666677 -247.098126) (xy 101.640374 -247.05653) (xy 101.621083 -247.011254)
			(xy 101.609306 -246.96347) (xy 101.605346 -246.914416) (xy 101.276404 -246.914416) (xy 101.275909 -246.939023)
			(xy 101.268014 -246.9876) (xy 101.25243 -247.034281) (xy 101.229559 -247.077858) (xy 101.199994 -247.117202)
			(xy 101.164501 -247.151294) (xy 101.123998 -247.17925) (xy 101.079536 -247.200348) (xy 101.032265 -247.21404)
			(xy 100.98341 -247.219972) (xy 100.934235 -247.217991) (xy 100.886016 -247.208147) (xy 100.84 -247.190695)
			(xy 100.797379 -247.166088) (xy 100.759258 -247.134963) (xy 100.726623 -247.098126) (xy 100.70032 -247.05653)
			(xy 100.681029 -247.011254) (xy 100.669252 -246.96347) (xy 100.665292 -246.914416) (xy 100.33635 -246.914416)
			(xy 100.335855 -246.939023) (xy 100.32796 -246.9876) (xy 100.312376 -247.034281) (xy 100.289505 -247.077858)
			(xy 100.25994 -247.117202) (xy 100.224447 -247.151294) (xy 100.183944 -247.17925) (xy 100.139482 -247.200348)
			(xy 100.092211 -247.21404) (xy 100.043356 -247.219972) (xy 99.994181 -247.217991) (xy 99.945962 -247.208147)
			(xy 99.899946 -247.190695) (xy 99.857325 -247.166088) (xy 99.819204 -247.134963) (xy 99.786569 -247.098126)
			(xy 99.760266 -247.05653) (xy 99.740975 -247.011254) (xy 99.729198 -246.96347) (xy 99.725238 -246.914416)
			(xy 99.396296 -246.914416) (xy 99.395801 -246.939023) (xy 99.387906 -246.9876) (xy 99.372322 -247.034281)
			(xy 99.349451 -247.077858) (xy 99.319886 -247.117202) (xy 99.284393 -247.151294) (xy 99.24389 -247.17925)
			(xy 99.199428 -247.200348) (xy 99.152157 -247.21404) (xy 99.103302 -247.219972) (xy 99.054127 -247.217991)
			(xy 99.005908 -247.208147) (xy 98.959892 -247.190695) (xy 98.917271 -247.166088) (xy 98.87915 -247.134963)
			(xy 98.846515 -247.098126) (xy 98.820212 -247.05653) (xy 98.800921 -247.011254) (xy 98.789144 -246.96347)
			(xy 98.785184 -246.914416) (xy 98.456242 -246.914416) (xy 98.455747 -246.939023) (xy 98.447852 -246.9876)
			(xy 98.432268 -247.034281) (xy 98.409397 -247.077858) (xy 98.379832 -247.117202) (xy 98.344339 -247.151294)
			(xy 98.303836 -247.17925) (xy 98.259374 -247.200348) (xy 98.212103 -247.21404) (xy 98.163248 -247.219972)
			(xy 98.114073 -247.217991) (xy 98.065854 -247.208147) (xy 98.019838 -247.190695) (xy 97.977217 -247.166088)
			(xy 97.939096 -247.134963) (xy 97.906461 -247.098126) (xy 97.880158 -247.05653) (xy 97.860867 -247.011254)
			(xy 97.84909 -246.96347) (xy 97.84513 -246.914416) (xy 97.516442 -246.914416) (xy 97.515947 -246.939023)
			(xy 97.508052 -246.9876) (xy 97.492468 -247.034281) (xy 97.469597 -247.077858) (xy 97.440032 -247.117202)
			(xy 97.404539 -247.151294) (xy 97.364036 -247.17925) (xy 97.319574 -247.200348) (xy 97.272303 -247.21404)
			(xy 97.223448 -247.219972) (xy 97.174273 -247.217991) (xy 97.126054 -247.208147) (xy 97.080038 -247.190695)
			(xy 97.037417 -247.166088) (xy 96.999296 -247.134963) (xy 96.966661 -247.098126) (xy 96.940358 -247.05653)
			(xy 96.921067 -247.011254) (xy 96.90929 -246.96347) (xy 96.90533 -246.914416) (xy 96.576388 -246.914416)
			(xy 96.575893 -246.939023) (xy 96.567998 -246.9876) (xy 96.552414 -247.034281) (xy 96.529543 -247.077858)
			(xy 96.499978 -247.117202) (xy 96.464485 -247.151294) (xy 96.423982 -247.17925) (xy 96.37952 -247.200348)
			(xy 96.332249 -247.21404) (xy 96.283394 -247.219972) (xy 96.234219 -247.217991) (xy 96.186 -247.208147)
			(xy 96.139984 -247.190695) (xy 96.097363 -247.166088) (xy 96.059242 -247.134963) (xy 96.026607 -247.098126)
			(xy 96.000304 -247.05653) (xy 95.981013 -247.011254) (xy 95.969236 -246.96347) (xy 95.965276 -246.914416)
			(xy 95.646748 -246.914416) (xy 95.646236 -246.939862) (xy 95.638072 -246.990096) (xy 95.621956 -247.03837)
			(xy 95.598305 -247.083433) (xy 95.567732 -247.124119) (xy 95.531028 -247.159374) (xy 95.489144 -247.188284)
			(xy 95.443165 -247.210101) (xy 95.394281 -247.224261) (xy 95.34376 -247.230395) (xy 95.292908 -247.228346)
			(xy 95.243044 -247.218166) (xy 95.195458 -247.200119) (xy 95.151384 -247.174673) (xy 95.111962 -247.142486)
			(xy 95.078214 -247.104392) (xy 95.051013 -247.061378) (xy 95.031065 -247.014558) (xy 95.018886 -246.965144)
			(xy 95.014791 -246.914416) (xy 94.706694 -246.914416) (xy 94.706182 -246.939862) (xy 94.698018 -246.990096)
			(xy 94.681902 -247.03837) (xy 94.658251 -247.083433) (xy 94.627678 -247.124119) (xy 94.590974 -247.159374)
			(xy 94.54909 -247.188284) (xy 94.503111 -247.210101) (xy 94.454227 -247.224261) (xy 94.403706 -247.230395)
			(xy 94.352854 -247.228346) (xy 94.30299 -247.218166) (xy 94.255404 -247.200119) (xy 94.21133 -247.174673)
			(xy 94.171908 -247.142486) (xy 94.13816 -247.104392) (xy 94.110959 -247.061378) (xy 94.091011 -247.014558)
			(xy 94.078832 -246.965144) (xy 94.074737 -246.914416) (xy 93.756226 -246.914416) (xy 93.755731 -246.939023)
			(xy 93.747836 -246.9876) (xy 93.732252 -247.034281) (xy 93.709381 -247.077858) (xy 93.679816 -247.117202)
			(xy 93.644323 -247.151294) (xy 93.60382 -247.17925) (xy 93.559358 -247.200348) (xy 93.512087 -247.21404)
			(xy 93.463232 -247.219972) (xy 93.414057 -247.217991) (xy 93.365838 -247.208147) (xy 93.319822 -247.190695)
			(xy 93.277201 -247.166088) (xy 93.23908 -247.134963) (xy 93.206445 -247.098126) (xy 93.180142 -247.05653)
			(xy 93.160851 -247.011254) (xy 93.149074 -246.96347) (xy 93.145114 -246.914416) (xy 92.82684 -246.914416)
			(xy 92.826328 -246.939862) (xy 92.818164 -246.990096) (xy 92.802048 -247.03837) (xy 92.778397 -247.083433)
			(xy 92.747824 -247.124119) (xy 92.71112 -247.159374) (xy 92.669236 -247.188284) (xy 92.623257 -247.210101)
			(xy 92.574373 -247.224261) (xy 92.523852 -247.230395) (xy 92.473 -247.228346) (xy 92.423136 -247.218166)
			(xy 92.37555 -247.200119) (xy 92.331476 -247.174673) (xy 92.292054 -247.142486) (xy 92.258306 -247.104392)
			(xy 92.231105 -247.061378) (xy 92.211157 -247.014558) (xy 92.198978 -246.965144) (xy 92.194883 -246.914416)
			(xy 91.876372 -246.914416) (xy 91.875877 -246.939023) (xy 91.867982 -246.9876) (xy 91.852398 -247.034281)
			(xy 91.829527 -247.077858) (xy 91.799962 -247.117202) (xy 91.764469 -247.151294) (xy 91.723966 -247.17925)
			(xy 91.679504 -247.200348) (xy 91.632233 -247.21404) (xy 91.583378 -247.219972) (xy 91.534203 -247.217991)
			(xy 91.485984 -247.208147) (xy 91.439968 -247.190695) (xy 91.397347 -247.166088) (xy 91.359226 -247.134963)
			(xy 91.326591 -247.098126) (xy 91.300288 -247.05653) (xy 91.280997 -247.011254) (xy 91.26922 -246.96347)
			(xy 91.26526 -246.914416) (xy 90.946732 -246.914416) (xy 90.94622 -246.939862) (xy 90.938056 -246.990096)
			(xy 90.92194 -247.03837) (xy 90.898289 -247.083433) (xy 90.867716 -247.124119) (xy 90.831012 -247.159374)
			(xy 90.789128 -247.188284) (xy 90.743149 -247.210101) (xy 90.694265 -247.224261) (xy 90.643744 -247.230395)
			(xy 90.592892 -247.228346) (xy 90.543028 -247.218166) (xy 90.495442 -247.200119) (xy 90.451368 -247.174673)
			(xy 90.411946 -247.142486) (xy 90.378198 -247.104392) (xy 90.350997 -247.061378) (xy 90.331049 -247.014558)
			(xy 90.31887 -246.965144) (xy 90.314775 -246.914416) (xy 89.996264 -246.914416) (xy 89.995769 -246.939023)
			(xy 89.987874 -246.9876) (xy 89.97229 -247.034281) (xy 89.949419 -247.077858) (xy 89.919854 -247.117202)
			(xy 89.884361 -247.151294) (xy 89.843858 -247.17925) (xy 89.799396 -247.200348) (xy 89.752125 -247.21404)
			(xy 89.70327 -247.219972) (xy 89.654095 -247.217991) (xy 89.605876 -247.208147) (xy 89.55986 -247.190695)
			(xy 89.517239 -247.166088) (xy 89.479118 -247.134963) (xy 89.446483 -247.098126) (xy 89.42018 -247.05653)
			(xy 89.400889 -247.011254) (xy 89.389112 -246.96347) (xy 89.385152 -246.914416) (xy 89.066878 -246.914416)
			(xy 89.066366 -246.939862) (xy 89.058202 -246.990096) (xy 89.042086 -247.03837) (xy 89.018435 -247.083433)
			(xy 88.987862 -247.124119) (xy 88.951158 -247.159374) (xy 88.909274 -247.188284) (xy 88.863295 -247.210101)
			(xy 88.814411 -247.224261) (xy 88.76389 -247.230395) (xy 88.713038 -247.228346) (xy 88.663174 -247.218166)
			(xy 88.615588 -247.200119) (xy 88.571514 -247.174673) (xy 88.532092 -247.142486) (xy 88.498344 -247.104392)
			(xy 88.471143 -247.061378) (xy 88.451195 -247.014558) (xy 88.439016 -246.965144) (xy 88.434921 -246.914416)
			(xy 88.126824 -246.914416) (xy 88.126312 -246.939862) (xy 88.118148 -246.990096) (xy 88.102032 -247.03837)
			(xy 88.078381 -247.083433) (xy 88.047808 -247.124119) (xy 88.011104 -247.159374) (xy 87.96922 -247.188284)
			(xy 87.923241 -247.210101) (xy 87.874357 -247.224261) (xy 87.823836 -247.230395) (xy 87.772984 -247.228346)
			(xy 87.72312 -247.218166) (xy 87.675534 -247.200119) (xy 87.63146 -247.174673) (xy 87.592038 -247.142486)
			(xy 87.55829 -247.104392) (xy 87.531089 -247.061378) (xy 87.511141 -247.014558) (xy 87.498962 -246.965144)
			(xy 87.494867 -246.914416) (xy 87.176356 -246.914416) (xy 87.175861 -246.939023) (xy 87.167966 -246.9876)
			(xy 87.152382 -247.034281) (xy 87.129511 -247.077858) (xy 87.099946 -247.117202) (xy 87.064453 -247.151294)
			(xy 87.02395 -247.17925) (xy 86.979488 -247.200348) (xy 86.932217 -247.21404) (xy 86.883362 -247.219972)
			(xy 86.834187 -247.217991) (xy 86.785968 -247.208147) (xy 86.739952 -247.190695) (xy 86.697331 -247.166088)
			(xy 86.65921 -247.134963) (xy 86.626575 -247.098126) (xy 86.600272 -247.05653) (xy 86.580981 -247.011254)
			(xy 86.569204 -246.96347) (xy 86.565244 -246.914416) (xy 86.246716 -246.914416) (xy 86.246204 -246.939862)
			(xy 86.23804 -246.990096) (xy 86.221924 -247.03837) (xy 86.198273 -247.083433) (xy 86.1677 -247.124119)
			(xy 86.130996 -247.159374) (xy 86.089112 -247.188284) (xy 86.043133 -247.210101) (xy 85.994249 -247.224261)
			(xy 85.943728 -247.230395) (xy 85.892876 -247.228346) (xy 85.843012 -247.218166) (xy 85.795426 -247.200119)
			(xy 85.751352 -247.174673) (xy 85.71193 -247.142486) (xy 85.678182 -247.104392) (xy 85.650981 -247.061378)
			(xy 85.631033 -247.014558) (xy 85.618854 -246.965144) (xy 85.614759 -246.914416) (xy 85.296248 -246.914416)
			(xy 85.295753 -246.939023) (xy 85.287858 -246.9876) (xy 85.272274 -247.034281) (xy 85.249403 -247.077858)
			(xy 85.219838 -247.117202) (xy 85.184345 -247.151294) (xy 85.143842 -247.17925) (xy 85.09938 -247.200348)
			(xy 85.052109 -247.21404) (xy 85.003254 -247.219972) (xy 84.954079 -247.217991) (xy 84.90586 -247.208147)
			(xy 84.859844 -247.190695) (xy 84.817223 -247.166088) (xy 84.779102 -247.134963) (xy 84.746467 -247.098126)
			(xy 84.720164 -247.05653) (xy 84.700873 -247.011254) (xy 84.689096 -246.96347) (xy 84.685136 -246.914416)
			(xy 84.366862 -246.914416) (xy 84.36635 -246.939862) (xy 84.358186 -246.990096) (xy 84.34207 -247.03837)
			(xy 84.318419 -247.083433) (xy 84.287846 -247.124119) (xy 84.251142 -247.159374) (xy 84.209258 -247.188284)
			(xy 84.163279 -247.210101) (xy 84.114395 -247.224261) (xy 84.063874 -247.230395) (xy 84.013022 -247.228346)
			(xy 83.963158 -247.218166) (xy 83.915572 -247.200119) (xy 83.871498 -247.174673) (xy 83.832076 -247.142486)
			(xy 83.798328 -247.104392) (xy 83.771127 -247.061378) (xy 83.751179 -247.014558) (xy 83.739 -246.965144)
			(xy 83.734905 -246.914416) (xy 83.416394 -246.914416) (xy 83.415899 -246.939023) (xy 83.408004 -246.9876)
			(xy 83.39242 -247.034281) (xy 83.369549 -247.077858) (xy 83.339984 -247.117202) (xy 83.304491 -247.151294)
			(xy 83.263988 -247.17925) (xy 83.219526 -247.200348) (xy 83.172255 -247.21404) (xy 83.1234 -247.219972)
			(xy 83.074225 -247.217991) (xy 83.026006 -247.208147) (xy 82.97999 -247.190695) (xy 82.937369 -247.166088)
			(xy 82.899248 -247.134963) (xy 82.866613 -247.098126) (xy 82.84031 -247.05653) (xy 82.821019 -247.011254)
			(xy 82.809242 -246.96347) (xy 82.805282 -246.914416) (xy 82.486754 -246.914416) (xy 82.486242 -246.939862)
			(xy 82.478078 -246.990096) (xy 82.461962 -247.03837) (xy 82.438311 -247.083433) (xy 82.407738 -247.124119)
			(xy 82.371034 -247.159374) (xy 82.32915 -247.188284) (xy 82.283171 -247.210101) (xy 82.234287 -247.224261)
			(xy 82.183766 -247.230395) (xy 82.132914 -247.228346) (xy 82.08305 -247.218166) (xy 82.035464 -247.200119)
			(xy 81.99139 -247.174673) (xy 81.951968 -247.142486) (xy 81.91822 -247.104392) (xy 81.891019 -247.061378)
			(xy 81.871071 -247.014558) (xy 81.858892 -246.965144) (xy 81.854797 -246.914416) (xy 81.5467 -246.914416)
			(xy 81.546188 -246.939862) (xy 81.538024 -246.990096) (xy 81.521908 -247.03837) (xy 81.498257 -247.083433)
			(xy 81.467684 -247.124119) (xy 81.43098 -247.159374) (xy 81.389096 -247.188284) (xy 81.343117 -247.210101)
			(xy 81.294233 -247.224261) (xy 81.243712 -247.230395) (xy 81.19286 -247.228346) (xy 81.142996 -247.218166)
			(xy 81.09541 -247.200119) (xy 81.051336 -247.174673) (xy 81.011914 -247.142486) (xy 80.978166 -247.104392)
			(xy 80.950965 -247.061378) (xy 80.931017 -247.014558) (xy 80.918838 -246.965144) (xy 80.914743 -246.914416)
			(xy 80.596486 -246.914416) (xy 80.595991 -246.939023) (xy 80.588096 -246.9876) (xy 80.572512 -247.034281)
			(xy 80.549641 -247.077858) (xy 80.520076 -247.117202) (xy 80.484583 -247.151294) (xy 80.44408 -247.17925)
			(xy 80.399618 -247.200348) (xy 80.352347 -247.21404) (xy 80.303492 -247.219972) (xy 80.254317 -247.217991)
			(xy 80.206098 -247.208147) (xy 80.160082 -247.190695) (xy 80.117461 -247.166088) (xy 80.07934 -247.134963)
			(xy 80.046705 -247.098126) (xy 80.020402 -247.05653) (xy 80.001111 -247.011254) (xy 79.989334 -246.96347)
			(xy 79.985374 -246.914416) (xy 78.716378 -246.914416) (xy 78.715883 -246.939023) (xy 78.707988 -246.9876)
			(xy 78.692404 -247.034281) (xy 78.669533 -247.077858) (xy 78.639968 -247.117202) (xy 78.604475 -247.151294)
			(xy 78.563972 -247.17925) (xy 78.51951 -247.200348) (xy 78.472239 -247.21404) (xy 78.423384 -247.219972)
			(xy 78.374209 -247.217991) (xy 78.32599 -247.208147) (xy 78.279974 -247.190695) (xy 78.237353 -247.166088)
			(xy 78.199232 -247.134963) (xy 78.166597 -247.098126) (xy 78.140294 -247.05653) (xy 78.121003 -247.011254)
			(xy 78.109226 -246.96347) (xy 78.105266 -246.914416) (xy 63.956184 -246.914416) (xy 65.032128 -247.99036)
			(xy 76.507098 -247.99036) (xy 76.511058 -247.941306) (xy 76.522835 -247.893522) (xy 76.542126 -247.848246)
			(xy 76.568429 -247.80665) (xy 76.601064 -247.769813) (xy 76.639185 -247.738688) (xy 76.681806 -247.714081)
			(xy 76.727822 -247.696629) (xy 76.776041 -247.686785) (xy 76.825216 -247.684804) (xy 76.874071 -247.690736)
			(xy 76.921342 -247.704428) (xy 76.963477 -247.724422) (xy 79.51522 -247.724422) (xy 79.51918 -247.675368)
			(xy 79.530957 -247.627584) (xy 79.550248 -247.582308) (xy 79.576551 -247.540712) (xy 79.609186 -247.503875)
			(xy 79.647307 -247.47275) (xy 79.689928 -247.448143) (xy 79.735944 -247.430691) (xy 79.784163 -247.420847)
			(xy 79.833338 -247.418866) (xy 79.882193 -247.424798) (xy 79.929464 -247.43849) (xy 79.973926 -247.459588)
			(xy 80.014429 -247.487544) (xy 80.049922 -247.521636) (xy 80.079487 -247.56098) (xy 80.102358 -247.604557)
			(xy 80.117942 -247.651238) (xy 80.125837 -247.699815) (xy 80.126332 -247.724422) (xy 80.444843 -247.724422)
			(xy 80.448938 -247.673694) (xy 80.461117 -247.62428) (xy 80.481065 -247.57746) (xy 80.508266 -247.534446)
			(xy 80.542014 -247.496352) (xy 80.581436 -247.464165) (xy 80.62551 -247.438719) (xy 80.673096 -247.420672)
			(xy 80.72296 -247.410492) (xy 80.773812 -247.408443) (xy 80.824333 -247.414577) (xy 80.873217 -247.428737)
			(xy 80.919196 -247.450554) (xy 80.96108 -247.479464) (xy 80.997784 -247.514719) (xy 81.028357 -247.555405)
			(xy 81.052008 -247.600468) (xy 81.068124 -247.648742) (xy 81.076288 -247.698976) (xy 81.0768 -247.724422)
			(xy 81.395328 -247.724422) (xy 81.399288 -247.675368) (xy 81.411065 -247.627584) (xy 81.430356 -247.582308)
			(xy 81.456659 -247.540712) (xy 81.489294 -247.503875) (xy 81.527415 -247.47275) (xy 81.570036 -247.448143)
			(xy 81.616052 -247.430691) (xy 81.664271 -247.420847) (xy 81.713446 -247.418866) (xy 81.762301 -247.424798)
			(xy 81.809572 -247.43849) (xy 81.854034 -247.459588) (xy 81.894537 -247.487544) (xy 81.93003 -247.521636)
			(xy 81.959595 -247.56098) (xy 81.982466 -247.604557) (xy 81.99805 -247.651238) (xy 82.005945 -247.699815)
			(xy 82.00644 -247.724422) (xy 82.324697 -247.724422) (xy 82.328792 -247.673694) (xy 82.340971 -247.62428)
			(xy 82.360919 -247.57746) (xy 82.38812 -247.534446) (xy 82.421868 -247.496352) (xy 82.46129 -247.464165)
			(xy 82.505364 -247.438719) (xy 82.55295 -247.420672) (xy 82.602814 -247.410492) (xy 82.653666 -247.408443)
			(xy 82.704187 -247.414577) (xy 82.753071 -247.428737) (xy 82.79905 -247.450554) (xy 82.840934 -247.479464)
			(xy 82.877638 -247.514719) (xy 82.908211 -247.555405) (xy 82.931862 -247.600468) (xy 82.947978 -247.648742)
			(xy 82.956142 -247.698976) (xy 82.956654 -247.724422) (xy 83.275182 -247.724422) (xy 83.279142 -247.675368)
			(xy 83.290919 -247.627584) (xy 83.31021 -247.582308) (xy 83.336513 -247.540712) (xy 83.369148 -247.503875)
			(xy 83.407269 -247.47275) (xy 83.44989 -247.448143) (xy 83.495906 -247.430691) (xy 83.544125 -247.420847)
			(xy 83.5933 -247.418866) (xy 83.642155 -247.424798) (xy 83.689426 -247.43849) (xy 83.733888 -247.459588)
			(xy 83.774391 -247.487544) (xy 83.809884 -247.521636) (xy 83.839449 -247.56098) (xy 83.86232 -247.604557)
			(xy 83.877904 -247.651238) (xy 83.885799 -247.699815) (xy 83.886294 -247.724422) (xy 84.204805 -247.724422)
			(xy 84.2089 -247.673694) (xy 84.221079 -247.62428) (xy 84.241027 -247.57746) (xy 84.268228 -247.534446)
			(xy 84.301976 -247.496352) (xy 84.341398 -247.464165) (xy 84.385472 -247.438719) (xy 84.433058 -247.420672)
			(xy 84.482922 -247.410492) (xy 84.533774 -247.408443) (xy 84.584295 -247.414577) (xy 84.633179 -247.428737)
			(xy 84.679158 -247.450554) (xy 84.721042 -247.479464) (xy 84.757746 -247.514719) (xy 84.788319 -247.555405)
			(xy 84.81197 -247.600468) (xy 84.828086 -247.648742) (xy 84.83625 -247.698976) (xy 84.836762 -247.724422)
			(xy 85.144859 -247.724422) (xy 85.148954 -247.673694) (xy 85.161133 -247.62428) (xy 85.181081 -247.57746)
			(xy 85.208282 -247.534446) (xy 85.24203 -247.496352) (xy 85.281452 -247.464165) (xy 85.325526 -247.438719)
			(xy 85.373112 -247.420672) (xy 85.422976 -247.410492) (xy 85.473828 -247.408443) (xy 85.524349 -247.414577)
			(xy 85.573233 -247.428737) (xy 85.619212 -247.450554) (xy 85.661096 -247.479464) (xy 85.6978 -247.514719)
			(xy 85.728373 -247.555405) (xy 85.752024 -247.600468) (xy 85.76814 -247.648742) (xy 85.776304 -247.698976)
			(xy 85.776816 -247.724422) (xy 86.095344 -247.724422) (xy 86.099304 -247.675368) (xy 86.111081 -247.627584)
			(xy 86.130372 -247.582308) (xy 86.156675 -247.540712) (xy 86.18931 -247.503875) (xy 86.227431 -247.47275)
			(xy 86.270052 -247.448143) (xy 86.316068 -247.430691) (xy 86.364287 -247.420847) (xy 86.413462 -247.418866)
			(xy 86.462317 -247.424798) (xy 86.509588 -247.43849) (xy 86.55405 -247.459588) (xy 86.594553 -247.487544)
			(xy 86.630046 -247.521636) (xy 86.659611 -247.56098) (xy 86.682482 -247.604557) (xy 86.698066 -247.651238)
			(xy 86.705961 -247.699815) (xy 86.706456 -247.724422) (xy 87.024713 -247.724422) (xy 87.028808 -247.673694)
			(xy 87.040987 -247.62428) (xy 87.060935 -247.57746) (xy 87.088136 -247.534446) (xy 87.121884 -247.496352)
			(xy 87.161306 -247.464165) (xy 87.20538 -247.438719) (xy 87.252966 -247.420672) (xy 87.30283 -247.410492)
			(xy 87.353682 -247.408443) (xy 87.404203 -247.414577) (xy 87.453087 -247.428737) (xy 87.499066 -247.450554)
			(xy 87.54095 -247.479464) (xy 87.577654 -247.514719) (xy 87.608227 -247.555405) (xy 87.631878 -247.600468)
			(xy 87.647994 -247.648742) (xy 87.656158 -247.698976) (xy 87.65667 -247.724422) (xy 87.975198 -247.724422)
			(xy 87.979158 -247.675368) (xy 87.990935 -247.627584) (xy 88.010226 -247.582308) (xy 88.036529 -247.540712)
			(xy 88.069164 -247.503875) (xy 88.107285 -247.47275) (xy 88.149906 -247.448143) (xy 88.195922 -247.430691)
			(xy 88.244141 -247.420847) (xy 88.293316 -247.418866) (xy 88.342171 -247.424798) (xy 88.389442 -247.43849)
			(xy 88.433904 -247.459588) (xy 88.474407 -247.487544) (xy 88.5099 -247.521636) (xy 88.539465 -247.56098)
			(xy 88.562336 -247.604557) (xy 88.57792 -247.651238) (xy 88.585815 -247.699815) (xy 88.58631 -247.724422)
			(xy 88.904821 -247.724422) (xy 88.908916 -247.673694) (xy 88.921095 -247.62428) (xy 88.941043 -247.57746)
			(xy 88.968244 -247.534446) (xy 89.001992 -247.496352) (xy 89.041414 -247.464165) (xy 89.085488 -247.438719)
			(xy 89.133074 -247.420672) (xy 89.182938 -247.410492) (xy 89.23379 -247.408443) (xy 89.284311 -247.414577)
			(xy 89.333195 -247.428737) (xy 89.379174 -247.450554) (xy 89.421058 -247.479464) (xy 89.457762 -247.514719)
			(xy 89.488335 -247.555405) (xy 89.511986 -247.600468) (xy 89.528102 -247.648742) (xy 89.536266 -247.698976)
			(xy 89.536778 -247.724422) (xy 89.855306 -247.724422) (xy 89.859266 -247.675368) (xy 89.871043 -247.627584)
			(xy 89.890334 -247.582308) (xy 89.916637 -247.540712) (xy 89.949272 -247.503875) (xy 89.987393 -247.47275)
			(xy 90.030014 -247.448143) (xy 90.07603 -247.430691) (xy 90.124249 -247.420847) (xy 90.173424 -247.418866)
			(xy 90.222279 -247.424798) (xy 90.26955 -247.43849) (xy 90.314012 -247.459588) (xy 90.354515 -247.487544)
			(xy 90.390008 -247.521636) (xy 90.419573 -247.56098) (xy 90.442444 -247.604557) (xy 90.458028 -247.651238)
			(xy 90.465923 -247.699815) (xy 90.466418 -247.724422) (xy 90.784675 -247.724422) (xy 90.78877 -247.673694)
			(xy 90.800949 -247.62428) (xy 90.820897 -247.57746) (xy 90.848098 -247.534446) (xy 90.881846 -247.496352)
			(xy 90.921268 -247.464165) (xy 90.965342 -247.438719) (xy 91.012928 -247.420672) (xy 91.062792 -247.410492)
			(xy 91.113644 -247.408443) (xy 91.164165 -247.414577) (xy 91.213049 -247.428737) (xy 91.259028 -247.450554)
			(xy 91.300912 -247.479464) (xy 91.337616 -247.514719) (xy 91.368189 -247.555405) (xy 91.39184 -247.600468)
			(xy 91.407956 -247.648742) (xy 91.41612 -247.698976) (xy 91.416632 -247.724422) (xy 91.724729 -247.724422)
			(xy 91.728824 -247.673694) (xy 91.741003 -247.62428) (xy 91.760951 -247.57746) (xy 91.788152 -247.534446)
			(xy 91.8219 -247.496352) (xy 91.861322 -247.464165) (xy 91.905396 -247.438719) (xy 91.952982 -247.420672)
			(xy 92.002846 -247.410492) (xy 92.053698 -247.408443) (xy 92.104219 -247.414577) (xy 92.153103 -247.428737)
			(xy 92.199082 -247.450554) (xy 92.240966 -247.479464) (xy 92.27767 -247.514719) (xy 92.308243 -247.555405)
			(xy 92.331894 -247.600468) (xy 92.34801 -247.648742) (xy 92.356174 -247.698976) (xy 92.356686 -247.724422)
			(xy 92.675214 -247.724422) (xy 92.679174 -247.675368) (xy 92.690951 -247.627584) (xy 92.710242 -247.582308)
			(xy 92.736545 -247.540712) (xy 92.76918 -247.503875) (xy 92.807301 -247.47275) (xy 92.849922 -247.448143)
			(xy 92.895938 -247.430691) (xy 92.944157 -247.420847) (xy 92.993332 -247.418866) (xy 93.042187 -247.424798)
			(xy 93.089458 -247.43849) (xy 93.13392 -247.459588) (xy 93.174423 -247.487544) (xy 93.209916 -247.521636)
			(xy 93.239481 -247.56098) (xy 93.262352 -247.604557) (xy 93.277936 -247.651238) (xy 93.285831 -247.699815)
			(xy 93.286326 -247.724422) (xy 93.604837 -247.724422) (xy 93.608932 -247.673694) (xy 93.621111 -247.62428)
			(xy 93.641059 -247.57746) (xy 93.66826 -247.534446) (xy 93.702008 -247.496352) (xy 93.74143 -247.464165)
			(xy 93.785504 -247.438719) (xy 93.83309 -247.420672) (xy 93.882954 -247.410492) (xy 93.933806 -247.408443)
			(xy 93.984327 -247.414577) (xy 94.033211 -247.428737) (xy 94.07919 -247.450554) (xy 94.121074 -247.479464)
			(xy 94.157778 -247.514719) (xy 94.188351 -247.555405) (xy 94.212002 -247.600468) (xy 94.228118 -247.648742)
			(xy 94.236282 -247.698976) (xy 94.236794 -247.724422) (xy 94.555322 -247.724422) (xy 94.559282 -247.675368)
			(xy 94.571059 -247.627584) (xy 94.59035 -247.582308) (xy 94.616653 -247.540712) (xy 94.649288 -247.503875)
			(xy 94.687409 -247.47275) (xy 94.73003 -247.448143) (xy 94.776046 -247.430691) (xy 94.824265 -247.420847)
			(xy 94.87344 -247.418866) (xy 94.922295 -247.424798) (xy 94.969566 -247.43849) (xy 95.014028 -247.459588)
			(xy 95.054531 -247.487544) (xy 95.090024 -247.521636) (xy 95.119589 -247.56098) (xy 95.14246 -247.604557)
			(xy 95.158044 -247.651238) (xy 95.165939 -247.699815) (xy 95.166434 -247.724422) (xy 95.484691 -247.724422)
			(xy 95.488786 -247.673694) (xy 95.500965 -247.62428) (xy 95.520913 -247.57746) (xy 95.548114 -247.534446)
			(xy 95.581862 -247.496352) (xy 95.621284 -247.464165) (xy 95.665358 -247.438719) (xy 95.712944 -247.420672)
			(xy 95.762808 -247.410492) (xy 95.81366 -247.408443) (xy 95.864181 -247.414577) (xy 95.913065 -247.428737)
			(xy 95.959044 -247.450554) (xy 96.000928 -247.479464) (xy 96.037632 -247.514719) (xy 96.068205 -247.555405)
			(xy 96.091856 -247.600468) (xy 96.107972 -247.648742) (xy 96.116136 -247.698976) (xy 96.116648 -247.724422)
			(xy 96.435176 -247.724422) (xy 96.439136 -247.675368) (xy 96.450913 -247.627584) (xy 96.470204 -247.582308)
			(xy 96.496507 -247.540712) (xy 96.529142 -247.503875) (xy 96.567263 -247.47275) (xy 96.609884 -247.448143)
			(xy 96.6559 -247.430691) (xy 96.704119 -247.420847) (xy 96.753294 -247.418866) (xy 96.802149 -247.424798)
			(xy 96.84942 -247.43849) (xy 96.893882 -247.459588) (xy 96.934385 -247.487544) (xy 96.969878 -247.521636)
			(xy 96.999443 -247.56098) (xy 97.022314 -247.604557) (xy 97.037898 -247.651238) (xy 97.045793 -247.699815)
			(xy 97.046288 -247.724422) (xy 97.364799 -247.724422) (xy 97.368894 -247.673694) (xy 97.381073 -247.62428)
			(xy 97.401021 -247.57746) (xy 97.428222 -247.534446) (xy 97.46197 -247.496352) (xy 97.501392 -247.464165)
			(xy 97.545466 -247.438719) (xy 97.593052 -247.420672) (xy 97.642916 -247.410492) (xy 97.693768 -247.408443)
			(xy 97.744289 -247.414577) (xy 97.793173 -247.428737) (xy 97.839152 -247.450554) (xy 97.881036 -247.479464)
			(xy 97.91774 -247.514719) (xy 97.948313 -247.555405) (xy 97.971964 -247.600468) (xy 97.98808 -247.648742)
			(xy 97.996244 -247.698976) (xy 97.996756 -247.724422) (xy 98.304853 -247.724422) (xy 98.308948 -247.673694)
			(xy 98.321127 -247.62428) (xy 98.341075 -247.57746) (xy 98.368276 -247.534446) (xy 98.402024 -247.496352)
			(xy 98.441446 -247.464165) (xy 98.48552 -247.438719) (xy 98.533106 -247.420672) (xy 98.58297 -247.410492)
			(xy 98.633822 -247.408443) (xy 98.684343 -247.414577) (xy 98.733227 -247.428737) (xy 98.779206 -247.450554)
			(xy 98.82109 -247.479464) (xy 98.857794 -247.514719) (xy 98.888367 -247.555405) (xy 98.912018 -247.600468)
			(xy 98.928134 -247.648742) (xy 98.936298 -247.698976) (xy 98.93681 -247.724422) (xy 99.255338 -247.724422)
			(xy 99.259298 -247.675368) (xy 99.271075 -247.627584) (xy 99.290366 -247.582308) (xy 99.316669 -247.540712)
			(xy 99.349304 -247.503875) (xy 99.387425 -247.47275) (xy 99.430046 -247.448143) (xy 99.476062 -247.430691)
			(xy 99.524281 -247.420847) (xy 99.573456 -247.418866) (xy 99.622311 -247.424798) (xy 99.669582 -247.43849)
			(xy 99.714044 -247.459588) (xy 99.754547 -247.487544) (xy 99.79004 -247.521636) (xy 99.819605 -247.56098)
			(xy 99.842476 -247.604557) (xy 99.85806 -247.651238) (xy 99.865955 -247.699815) (xy 99.86645 -247.724422)
			(xy 100.184707 -247.724422) (xy 100.188802 -247.673694) (xy 100.200981 -247.62428) (xy 100.220929 -247.57746)
			(xy 100.24813 -247.534446) (xy 100.281878 -247.496352) (xy 100.3213 -247.464165) (xy 100.365374 -247.438719)
			(xy 100.41296 -247.420672) (xy 100.462824 -247.410492) (xy 100.513676 -247.408443) (xy 100.564197 -247.414577)
			(xy 100.613081 -247.428737) (xy 100.65906 -247.450554) (xy 100.700944 -247.479464) (xy 100.737648 -247.514719)
			(xy 100.768221 -247.555405) (xy 100.791872 -247.600468) (xy 100.807988 -247.648742) (xy 100.816152 -247.698976)
			(xy 100.816664 -247.724422) (xy 101.124761 -247.724422) (xy 101.128856 -247.673694) (xy 101.141035 -247.62428)
			(xy 101.160983 -247.57746) (xy 101.188184 -247.534446) (xy 101.221932 -247.496352) (xy 101.261354 -247.464165)
			(xy 101.305428 -247.438719) (xy 101.353014 -247.420672) (xy 101.402878 -247.410492) (xy 101.45373 -247.408443)
			(xy 101.504251 -247.414577) (xy 101.553135 -247.428737) (xy 101.599114 -247.450554) (xy 101.640998 -247.479464)
			(xy 101.677702 -247.514719) (xy 101.708275 -247.555405) (xy 101.731926 -247.600468) (xy 101.748042 -247.648742)
			(xy 101.756206 -247.698976) (xy 101.756718 -247.724422) (xy 102.075246 -247.724422) (xy 102.079206 -247.675368)
			(xy 102.090983 -247.627584) (xy 102.110274 -247.582308) (xy 102.136577 -247.540712) (xy 102.169212 -247.503875)
			(xy 102.207333 -247.47275) (xy 102.249954 -247.448143) (xy 102.29597 -247.430691) (xy 102.344189 -247.420847)
			(xy 102.393364 -247.418866) (xy 102.442219 -247.424798) (xy 102.48949 -247.43849) (xy 102.533952 -247.459588)
			(xy 102.574455 -247.487544) (xy 102.609948 -247.521636) (xy 102.639513 -247.56098) (xy 102.662384 -247.604557)
			(xy 102.677968 -247.651238) (xy 102.685863 -247.699815) (xy 102.686358 -247.724422) (xy 103.004869 -247.724422)
			(xy 103.008964 -247.673694) (xy 103.021143 -247.62428) (xy 103.041091 -247.57746) (xy 103.068292 -247.534446)
			(xy 103.10204 -247.496352) (xy 103.141462 -247.464165) (xy 103.185536 -247.438719) (xy 103.233122 -247.420672)
			(xy 103.282986 -247.410492) (xy 103.333838 -247.408443) (xy 103.384359 -247.414577) (xy 103.433243 -247.428737)
			(xy 103.479222 -247.450554) (xy 103.521106 -247.479464) (xy 103.55781 -247.514719) (xy 103.588383 -247.555405)
			(xy 103.612034 -247.600468) (xy 103.62815 -247.648742) (xy 103.636314 -247.698976) (xy 103.636826 -247.724422)
			(xy 103.944923 -247.724422) (xy 103.949018 -247.673694) (xy 103.961197 -247.62428) (xy 103.981145 -247.57746)
			(xy 104.008346 -247.534446) (xy 104.042094 -247.496352) (xy 104.081516 -247.464165) (xy 104.12559 -247.438719)
			(xy 104.173176 -247.420672) (xy 104.22304 -247.410492) (xy 104.273892 -247.408443) (xy 104.324413 -247.414577)
			(xy 104.373297 -247.428737) (xy 104.419276 -247.450554) (xy 104.46116 -247.479464) (xy 104.497864 -247.514719)
			(xy 104.528437 -247.555405) (xy 104.552088 -247.600468) (xy 104.568204 -247.648742) (xy 104.576368 -247.698976)
			(xy 104.57688 -247.724422) (xy 104.895154 -247.724422) (xy 104.899114 -247.675368) (xy 104.910891 -247.627584)
			(xy 104.930182 -247.582308) (xy 104.956485 -247.540712) (xy 104.98912 -247.503875) (xy 105.027241 -247.47275)
			(xy 105.069862 -247.448143) (xy 105.115878 -247.430691) (xy 105.164097 -247.420847) (xy 105.213272 -247.418866)
			(xy 105.262127 -247.424798) (xy 105.309398 -247.43849) (xy 105.35386 -247.459588) (xy 105.394363 -247.487544)
			(xy 105.429856 -247.521636) (xy 105.459421 -247.56098) (xy 105.482292 -247.604557) (xy 105.497876 -247.651238)
			(xy 105.505771 -247.699815) (xy 105.506266 -247.724422) (xy 105.824777 -247.724422) (xy 105.828872 -247.673694)
			(xy 105.841051 -247.62428) (xy 105.860999 -247.57746) (xy 105.8882 -247.534446) (xy 105.921948 -247.496352)
			(xy 105.96137 -247.464165) (xy 106.005444 -247.438719) (xy 106.05303 -247.420672) (xy 106.102894 -247.410492)
			(xy 106.153746 -247.408443) (xy 106.204267 -247.414577) (xy 106.253151 -247.428737) (xy 106.29913 -247.450554)
			(xy 106.341014 -247.479464) (xy 106.377718 -247.514719) (xy 106.408291 -247.555405) (xy 106.431942 -247.600468)
			(xy 106.448058 -247.648742) (xy 106.456222 -247.698976) (xy 106.456734 -247.724422) (xy 106.764831 -247.724422)
			(xy 106.768926 -247.673694) (xy 106.781105 -247.62428) (xy 106.801053 -247.57746) (xy 106.828254 -247.534446)
			(xy 106.862002 -247.496352) (xy 106.901424 -247.464165) (xy 106.945498 -247.438719) (xy 106.993084 -247.420672)
			(xy 107.042948 -247.410492) (xy 107.0938 -247.408443) (xy 107.144321 -247.414577) (xy 107.193205 -247.428737)
			(xy 107.239184 -247.450554) (xy 107.281068 -247.479464) (xy 107.317772 -247.514719) (xy 107.348345 -247.555405)
			(xy 107.371996 -247.600468) (xy 107.388112 -247.648742) (xy 107.396276 -247.698976) (xy 107.396788 -247.724422)
			(xy 107.715316 -247.724422) (xy 107.719276 -247.675368) (xy 107.731053 -247.627584) (xy 107.750344 -247.582308)
			(xy 107.776647 -247.540712) (xy 107.809282 -247.503875) (xy 107.847403 -247.47275) (xy 107.890024 -247.448143)
			(xy 107.93604 -247.430691) (xy 107.984259 -247.420847) (xy 108.033434 -247.418866) (xy 108.082289 -247.424798)
			(xy 108.12956 -247.43849) (xy 108.174022 -247.459588) (xy 108.214525 -247.487544) (xy 108.250018 -247.521636)
			(xy 108.279583 -247.56098) (xy 108.302454 -247.604557) (xy 108.318038 -247.651238) (xy 108.325933 -247.699815)
			(xy 108.326428 -247.724422) (xy 108.65537 -247.724422) (xy 108.65933 -247.675368) (xy 108.671107 -247.627584)
			(xy 108.690398 -247.582308) (xy 108.716701 -247.540712) (xy 108.749336 -247.503875) (xy 108.787457 -247.47275)
			(xy 108.830078 -247.448143) (xy 108.876094 -247.430691) (xy 108.924313 -247.420847) (xy 108.973488 -247.418866)
			(xy 109.022343 -247.424798) (xy 109.069614 -247.43849) (xy 109.114076 -247.459588) (xy 109.154579 -247.487544)
			(xy 109.190072 -247.521636) (xy 109.219637 -247.56098) (xy 109.242508 -247.604557) (xy 109.258092 -247.651238)
			(xy 109.265987 -247.699815) (xy 109.266482 -247.724422) (xy 109.59517 -247.724422) (xy 109.59913 -247.675368)
			(xy 109.610907 -247.627584) (xy 109.630198 -247.582308) (xy 109.656501 -247.540712) (xy 109.689136 -247.503875)
			(xy 109.727257 -247.47275) (xy 109.769878 -247.448143) (xy 109.815894 -247.430691) (xy 109.864113 -247.420847)
			(xy 109.913288 -247.418866) (xy 109.962143 -247.424798) (xy 110.009414 -247.43849) (xy 110.048873 -247.457214)
			(xy 111.456473 -247.457214) (xy 111.460503 -247.404716) (xy 111.4725 -247.353448) (xy 111.492183 -247.304613)
			(xy 111.519089 -247.259354) (xy 111.552589 -247.218733) (xy 111.591897 -247.183702) (xy 111.636092 -247.155082)
			(xy 111.684137 -247.133543) (xy 111.734908 -247.119591) (xy 111.787213 -247.113553) (xy 111.839827 -247.11557)
			(xy 111.891517 -247.125594) (xy 111.94107 -247.143392) (xy 111.987326 -247.168545) (xy 112.0292 -247.200464)
			(xy 112.065712 -247.238402) (xy 112.096004 -247.281468) (xy 112.119367 -247.328653) (xy 112.135253 -247.378852)
			(xy 112.14329 -247.430888) (xy 112.143794 -247.457214) (xy 112.14329 -247.48354) (xy 112.135253 -247.535576)
			(xy 112.119367 -247.585775) (xy 112.096004 -247.63296) (xy 112.065712 -247.676026) (xy 112.0292 -247.713964)
			(xy 111.987326 -247.745883) (xy 111.94107 -247.771036) (xy 111.891517 -247.788834) (xy 111.839827 -247.798858)
			(xy 111.787213 -247.800875) (xy 111.734908 -247.794837) (xy 111.684137 -247.780885) (xy 111.636092 -247.759346)
			(xy 111.591897 -247.730726) (xy 111.552589 -247.695695) (xy 111.519089 -247.655074) (xy 111.492183 -247.609815)
			(xy 111.4725 -247.56098) (xy 111.460503 -247.509712) (xy 111.456473 -247.457214) (xy 110.048873 -247.457214)
			(xy 110.053876 -247.459588) (xy 110.094379 -247.487544) (xy 110.129872 -247.521636) (xy 110.159437 -247.56098)
			(xy 110.182308 -247.604557) (xy 110.197892 -247.651238) (xy 110.205787 -247.699815) (xy 110.206282 -247.724422)
			(xy 110.205787 -247.749029) (xy 110.197892 -247.797606) (xy 110.182308 -247.844287) (xy 110.159437 -247.887864)
			(xy 110.129872 -247.927208) (xy 110.094379 -247.9613) (xy 110.053876 -247.989256) (xy 110.009414 -248.010354)
			(xy 109.962143 -248.024046) (xy 109.913288 -248.029978) (xy 109.864113 -248.027997) (xy 109.815894 -248.018153)
			(xy 109.769878 -248.000701) (xy 109.727257 -247.976094) (xy 109.689136 -247.944969) (xy 109.656501 -247.908132)
			(xy 109.630198 -247.866536) (xy 109.610907 -247.82126) (xy 109.59913 -247.773476) (xy 109.59517 -247.724422)
			(xy 109.266482 -247.724422) (xy 109.265987 -247.749029) (xy 109.258092 -247.797606) (xy 109.242508 -247.844287)
			(xy 109.219637 -247.887864) (xy 109.190072 -247.927208) (xy 109.154579 -247.9613) (xy 109.114076 -247.989256)
			(xy 109.069614 -248.010354) (xy 109.022343 -248.024046) (xy 108.973488 -248.029978) (xy 108.924313 -248.027997)
			(xy 108.876094 -248.018153) (xy 108.830078 -248.000701) (xy 108.787457 -247.976094) (xy 108.749336 -247.944969)
			(xy 108.716701 -247.908132) (xy 108.690398 -247.866536) (xy 108.671107 -247.82126) (xy 108.65933 -247.773476)
			(xy 108.65537 -247.724422) (xy 108.326428 -247.724422) (xy 108.325933 -247.749029) (xy 108.318038 -247.797606)
			(xy 108.302454 -247.844287) (xy 108.279583 -247.887864) (xy 108.250018 -247.927208) (xy 108.214525 -247.9613)
			(xy 108.174022 -247.989256) (xy 108.12956 -248.010354) (xy 108.082289 -248.024046) (xy 108.033434 -248.029978)
			(xy 107.984259 -248.027997) (xy 107.93604 -248.018153) (xy 107.890024 -248.000701) (xy 107.847403 -247.976094)
			(xy 107.809282 -247.944969) (xy 107.776647 -247.908132) (xy 107.750344 -247.866536) (xy 107.731053 -247.82126)
			(xy 107.719276 -247.773476) (xy 107.715316 -247.724422) (xy 107.396788 -247.724422) (xy 107.396276 -247.749868)
			(xy 107.388112 -247.800102) (xy 107.371996 -247.848376) (xy 107.348345 -247.893439) (xy 107.317772 -247.934125)
			(xy 107.281068 -247.96938) (xy 107.239184 -247.99829) (xy 107.193205 -248.020107) (xy 107.144321 -248.034267)
			(xy 107.0938 -248.040401) (xy 107.042948 -248.038352) (xy 106.993084 -248.028172) (xy 106.945498 -248.010125)
			(xy 106.901424 -247.984679) (xy 106.862002 -247.952492) (xy 106.828254 -247.914398) (xy 106.801053 -247.871384)
			(xy 106.781105 -247.824564) (xy 106.768926 -247.77515) (xy 106.764831 -247.724422) (xy 106.456734 -247.724422)
			(xy 106.456222 -247.749868) (xy 106.448058 -247.800102) (xy 106.431942 -247.848376) (xy 106.408291 -247.893439)
			(xy 106.377718 -247.934125) (xy 106.341014 -247.96938) (xy 106.29913 -247.99829) (xy 106.253151 -248.020107)
			(xy 106.204267 -248.034267) (xy 106.153746 -248.040401) (xy 106.102894 -248.038352) (xy 106.05303 -248.028172)
			(xy 106.005444 -248.010125) (xy 105.96137 -247.984679) (xy 105.921948 -247.952492) (xy 105.8882 -247.914398)
			(xy 105.860999 -247.871384) (xy 105.841051 -247.824564) (xy 105.828872 -247.77515) (xy 105.824777 -247.724422)
			(xy 105.506266 -247.724422) (xy 105.505771 -247.749029) (xy 105.497876 -247.797606) (xy 105.482292 -247.844287)
			(xy 105.459421 -247.887864) (xy 105.429856 -247.927208) (xy 105.394363 -247.9613) (xy 105.35386 -247.989256)
			(xy 105.309398 -248.010354) (xy 105.262127 -248.024046) (xy 105.213272 -248.029978) (xy 105.164097 -248.027997)
			(xy 105.115878 -248.018153) (xy 105.069862 -248.000701) (xy 105.027241 -247.976094) (xy 104.98912 -247.944969)
			(xy 104.956485 -247.908132) (xy 104.930182 -247.866536) (xy 104.910891 -247.82126) (xy 104.899114 -247.773476)
			(xy 104.895154 -247.724422) (xy 104.57688 -247.724422) (xy 104.576368 -247.749868) (xy 104.568204 -247.800102)
			(xy 104.552088 -247.848376) (xy 104.528437 -247.893439) (xy 104.497864 -247.934125) (xy 104.46116 -247.96938)
			(xy 104.419276 -247.99829) (xy 104.373297 -248.020107) (xy 104.324413 -248.034267) (xy 104.273892 -248.040401)
			(xy 104.22304 -248.038352) (xy 104.173176 -248.028172) (xy 104.12559 -248.010125) (xy 104.081516 -247.984679)
			(xy 104.042094 -247.952492) (xy 104.008346 -247.914398) (xy 103.981145 -247.871384) (xy 103.961197 -247.824564)
			(xy 103.949018 -247.77515) (xy 103.944923 -247.724422) (xy 103.636826 -247.724422) (xy 103.636314 -247.749868)
			(xy 103.62815 -247.800102) (xy 103.612034 -247.848376) (xy 103.588383 -247.893439) (xy 103.55781 -247.934125)
			(xy 103.521106 -247.96938) (xy 103.479222 -247.99829) (xy 103.433243 -248.020107) (xy 103.384359 -248.034267)
			(xy 103.333838 -248.040401) (xy 103.282986 -248.038352) (xy 103.233122 -248.028172) (xy 103.185536 -248.010125)
			(xy 103.141462 -247.984679) (xy 103.10204 -247.952492) (xy 103.068292 -247.914398) (xy 103.041091 -247.871384)
			(xy 103.021143 -247.824564) (xy 103.008964 -247.77515) (xy 103.004869 -247.724422) (xy 102.686358 -247.724422)
			(xy 102.685863 -247.749029) (xy 102.677968 -247.797606) (xy 102.662384 -247.844287) (xy 102.639513 -247.887864)
			(xy 102.609948 -247.927208) (xy 102.574455 -247.9613) (xy 102.533952 -247.989256) (xy 102.48949 -248.010354)
			(xy 102.442219 -248.024046) (xy 102.393364 -248.029978) (xy 102.344189 -248.027997) (xy 102.29597 -248.018153)
			(xy 102.249954 -248.000701) (xy 102.207333 -247.976094) (xy 102.169212 -247.944969) (xy 102.136577 -247.908132)
			(xy 102.110274 -247.866536) (xy 102.090983 -247.82126) (xy 102.079206 -247.773476) (xy 102.075246 -247.724422)
			(xy 101.756718 -247.724422) (xy 101.756206 -247.749868) (xy 101.748042 -247.800102) (xy 101.731926 -247.848376)
			(xy 101.708275 -247.893439) (xy 101.677702 -247.934125) (xy 101.640998 -247.96938) (xy 101.599114 -247.99829)
			(xy 101.553135 -248.020107) (xy 101.504251 -248.034267) (xy 101.45373 -248.040401) (xy 101.402878 -248.038352)
			(xy 101.353014 -248.028172) (xy 101.305428 -248.010125) (xy 101.261354 -247.984679) (xy 101.221932 -247.952492)
			(xy 101.188184 -247.914398) (xy 101.160983 -247.871384) (xy 101.141035 -247.824564) (xy 101.128856 -247.77515)
			(xy 101.124761 -247.724422) (xy 100.816664 -247.724422) (xy 100.816152 -247.749868) (xy 100.807988 -247.800102)
			(xy 100.791872 -247.848376) (xy 100.768221 -247.893439) (xy 100.737648 -247.934125) (xy 100.700944 -247.96938)
			(xy 100.65906 -247.99829) (xy 100.613081 -248.020107) (xy 100.564197 -248.034267) (xy 100.513676 -248.040401)
			(xy 100.462824 -248.038352) (xy 100.41296 -248.028172) (xy 100.365374 -248.010125) (xy 100.3213 -247.984679)
			(xy 100.281878 -247.952492) (xy 100.24813 -247.914398) (xy 100.220929 -247.871384) (xy 100.200981 -247.824564)
			(xy 100.188802 -247.77515) (xy 100.184707 -247.724422) (xy 99.86645 -247.724422) (xy 99.865955 -247.749029)
			(xy 99.85806 -247.797606) (xy 99.842476 -247.844287) (xy 99.819605 -247.887864) (xy 99.79004 -247.927208)
			(xy 99.754547 -247.9613) (xy 99.714044 -247.989256) (xy 99.669582 -248.010354) (xy 99.622311 -248.024046)
			(xy 99.573456 -248.029978) (xy 99.524281 -248.027997) (xy 99.476062 -248.018153) (xy 99.430046 -248.000701)
			(xy 99.387425 -247.976094) (xy 99.349304 -247.944969) (xy 99.316669 -247.908132) (xy 99.290366 -247.866536)
			(xy 99.271075 -247.82126) (xy 99.259298 -247.773476) (xy 99.255338 -247.724422) (xy 98.93681 -247.724422)
			(xy 98.936298 -247.749868) (xy 98.928134 -247.800102) (xy 98.912018 -247.848376) (xy 98.888367 -247.893439)
			(xy 98.857794 -247.934125) (xy 98.82109 -247.96938) (xy 98.779206 -247.99829) (xy 98.733227 -248.020107)
			(xy 98.684343 -248.034267) (xy 98.633822 -248.040401) (xy 98.58297 -248.038352) (xy 98.533106 -248.028172)
			(xy 98.48552 -248.010125) (xy 98.441446 -247.984679) (xy 98.402024 -247.952492) (xy 98.368276 -247.914398)
			(xy 98.341075 -247.871384) (xy 98.321127 -247.824564) (xy 98.308948 -247.77515) (xy 98.304853 -247.724422)
			(xy 97.996756 -247.724422) (xy 97.996244 -247.749868) (xy 97.98808 -247.800102) (xy 97.971964 -247.848376)
			(xy 97.948313 -247.893439) (xy 97.91774 -247.934125) (xy 97.881036 -247.96938) (xy 97.839152 -247.99829)
			(xy 97.793173 -248.020107) (xy 97.744289 -248.034267) (xy 97.693768 -248.040401) (xy 97.642916 -248.038352)
			(xy 97.593052 -248.028172) (xy 97.545466 -248.010125) (xy 97.501392 -247.984679) (xy 97.46197 -247.952492)
			(xy 97.428222 -247.914398) (xy 97.401021 -247.871384) (xy 97.381073 -247.824564) (xy 97.368894 -247.77515)
			(xy 97.364799 -247.724422) (xy 97.046288 -247.724422) (xy 97.045793 -247.749029) (xy 97.037898 -247.797606)
			(xy 97.022314 -247.844287) (xy 96.999443 -247.887864) (xy 96.969878 -247.927208) (xy 96.934385 -247.9613)
			(xy 96.893882 -247.989256) (xy 96.84942 -248.010354) (xy 96.802149 -248.024046) (xy 96.753294 -248.029978)
			(xy 96.704119 -248.027997) (xy 96.6559 -248.018153) (xy 96.609884 -248.000701) (xy 96.567263 -247.976094)
			(xy 96.529142 -247.944969) (xy 96.496507 -247.908132) (xy 96.470204 -247.866536) (xy 96.450913 -247.82126)
			(xy 96.439136 -247.773476) (xy 96.435176 -247.724422) (xy 96.116648 -247.724422) (xy 96.116136 -247.749868)
			(xy 96.107972 -247.800102) (xy 96.091856 -247.848376) (xy 96.068205 -247.893439) (xy 96.037632 -247.934125)
			(xy 96.000928 -247.96938) (xy 95.959044 -247.99829) (xy 95.913065 -248.020107) (xy 95.864181 -248.034267)
			(xy 95.81366 -248.040401) (xy 95.762808 -248.038352) (xy 95.712944 -248.028172) (xy 95.665358 -248.010125)
			(xy 95.621284 -247.984679) (xy 95.581862 -247.952492) (xy 95.548114 -247.914398) (xy 95.520913 -247.871384)
			(xy 95.500965 -247.824564) (xy 95.488786 -247.77515) (xy 95.484691 -247.724422) (xy 95.166434 -247.724422)
			(xy 95.165939 -247.749029) (xy 95.158044 -247.797606) (xy 95.14246 -247.844287) (xy 95.119589 -247.887864)
			(xy 95.090024 -247.927208) (xy 95.054531 -247.9613) (xy 95.014028 -247.989256) (xy 94.969566 -248.010354)
			(xy 94.922295 -248.024046) (xy 94.87344 -248.029978) (xy 94.824265 -248.027997) (xy 94.776046 -248.018153)
			(xy 94.73003 -248.000701) (xy 94.687409 -247.976094) (xy 94.649288 -247.944969) (xy 94.616653 -247.908132)
			(xy 94.59035 -247.866536) (xy 94.571059 -247.82126) (xy 94.559282 -247.773476) (xy 94.555322 -247.724422)
			(xy 94.236794 -247.724422) (xy 94.236282 -247.749868) (xy 94.228118 -247.800102) (xy 94.212002 -247.848376)
			(xy 94.188351 -247.893439) (xy 94.157778 -247.934125) (xy 94.121074 -247.96938) (xy 94.07919 -247.99829)
			(xy 94.033211 -248.020107) (xy 93.984327 -248.034267) (xy 93.933806 -248.040401) (xy 93.882954 -248.038352)
			(xy 93.83309 -248.028172) (xy 93.785504 -248.010125) (xy 93.74143 -247.984679) (xy 93.702008 -247.952492)
			(xy 93.66826 -247.914398) (xy 93.641059 -247.871384) (xy 93.621111 -247.824564) (xy 93.608932 -247.77515)
			(xy 93.604837 -247.724422) (xy 93.286326 -247.724422) (xy 93.285831 -247.749029) (xy 93.277936 -247.797606)
			(xy 93.262352 -247.844287) (xy 93.239481 -247.887864) (xy 93.209916 -247.927208) (xy 93.174423 -247.9613)
			(xy 93.13392 -247.989256) (xy 93.089458 -248.010354) (xy 93.042187 -248.024046) (xy 92.993332 -248.029978)
			(xy 92.944157 -248.027997) (xy 92.895938 -248.018153) (xy 92.849922 -248.000701) (xy 92.807301 -247.976094)
			(xy 92.76918 -247.944969) (xy 92.736545 -247.908132) (xy 92.710242 -247.866536) (xy 92.690951 -247.82126)
			(xy 92.679174 -247.773476) (xy 92.675214 -247.724422) (xy 92.356686 -247.724422) (xy 92.356174 -247.749868)
			(xy 92.34801 -247.800102) (xy 92.331894 -247.848376) (xy 92.308243 -247.893439) (xy 92.27767 -247.934125)
			(xy 92.240966 -247.96938) (xy 92.199082 -247.99829) (xy 92.153103 -248.020107) (xy 92.104219 -248.034267)
			(xy 92.053698 -248.040401) (xy 92.002846 -248.038352) (xy 91.952982 -248.028172) (xy 91.905396 -248.010125)
			(xy 91.861322 -247.984679) (xy 91.8219 -247.952492) (xy 91.788152 -247.914398) (xy 91.760951 -247.871384)
			(xy 91.741003 -247.824564) (xy 91.728824 -247.77515) (xy 91.724729 -247.724422) (xy 91.416632 -247.724422)
			(xy 91.41612 -247.749868) (xy 91.407956 -247.800102) (xy 91.39184 -247.848376) (xy 91.368189 -247.893439)
			(xy 91.337616 -247.934125) (xy 91.300912 -247.96938) (xy 91.259028 -247.99829) (xy 91.213049 -248.020107)
			(xy 91.164165 -248.034267) (xy 91.113644 -248.040401) (xy 91.062792 -248.038352) (xy 91.012928 -248.028172)
			(xy 90.965342 -248.010125) (xy 90.921268 -247.984679) (xy 90.881846 -247.952492) (xy 90.848098 -247.914398)
			(xy 90.820897 -247.871384) (xy 90.800949 -247.824564) (xy 90.78877 -247.77515) (xy 90.784675 -247.724422)
			(xy 90.466418 -247.724422) (xy 90.465923 -247.749029) (xy 90.458028 -247.797606) (xy 90.442444 -247.844287)
			(xy 90.419573 -247.887864) (xy 90.390008 -247.927208) (xy 90.354515 -247.9613) (xy 90.314012 -247.989256)
			(xy 90.26955 -248.010354) (xy 90.222279 -248.024046) (xy 90.173424 -248.029978) (xy 90.124249 -248.027997)
			(xy 90.07603 -248.018153) (xy 90.030014 -248.000701) (xy 89.987393 -247.976094) (xy 89.949272 -247.944969)
			(xy 89.916637 -247.908132) (xy 89.890334 -247.866536) (xy 89.871043 -247.82126) (xy 89.859266 -247.773476)
			(xy 89.855306 -247.724422) (xy 89.536778 -247.724422) (xy 89.536266 -247.749868) (xy 89.528102 -247.800102)
			(xy 89.511986 -247.848376) (xy 89.488335 -247.893439) (xy 89.457762 -247.934125) (xy 89.421058 -247.96938)
			(xy 89.379174 -247.99829) (xy 89.333195 -248.020107) (xy 89.284311 -248.034267) (xy 89.23379 -248.040401)
			(xy 89.182938 -248.038352) (xy 89.133074 -248.028172) (xy 89.085488 -248.010125) (xy 89.041414 -247.984679)
			(xy 89.001992 -247.952492) (xy 88.968244 -247.914398) (xy 88.941043 -247.871384) (xy 88.921095 -247.824564)
			(xy 88.908916 -247.77515) (xy 88.904821 -247.724422) (xy 88.58631 -247.724422) (xy 88.585815 -247.749029)
			(xy 88.57792 -247.797606) (xy 88.562336 -247.844287) (xy 88.539465 -247.887864) (xy 88.5099 -247.927208)
			(xy 88.474407 -247.9613) (xy 88.433904 -247.989256) (xy 88.389442 -248.010354) (xy 88.342171 -248.024046)
			(xy 88.293316 -248.029978) (xy 88.244141 -248.027997) (xy 88.195922 -248.018153) (xy 88.149906 -248.000701)
			(xy 88.107285 -247.976094) (xy 88.069164 -247.944969) (xy 88.036529 -247.908132) (xy 88.010226 -247.866536)
			(xy 87.990935 -247.82126) (xy 87.979158 -247.773476) (xy 87.975198 -247.724422) (xy 87.65667 -247.724422)
			(xy 87.656158 -247.749868) (xy 87.647994 -247.800102) (xy 87.631878 -247.848376) (xy 87.608227 -247.893439)
			(xy 87.577654 -247.934125) (xy 87.54095 -247.96938) (xy 87.499066 -247.99829) (xy 87.453087 -248.020107)
			(xy 87.404203 -248.034267) (xy 87.353682 -248.040401) (xy 87.30283 -248.038352) (xy 87.252966 -248.028172)
			(xy 87.20538 -248.010125) (xy 87.161306 -247.984679) (xy 87.121884 -247.952492) (xy 87.088136 -247.914398)
			(xy 87.060935 -247.871384) (xy 87.040987 -247.824564) (xy 87.028808 -247.77515) (xy 87.024713 -247.724422)
			(xy 86.706456 -247.724422) (xy 86.705961 -247.749029) (xy 86.698066 -247.797606) (xy 86.682482 -247.844287)
			(xy 86.659611 -247.887864) (xy 86.630046 -247.927208) (xy 86.594553 -247.9613) (xy 86.55405 -247.989256)
			(xy 86.509588 -248.010354) (xy 86.462317 -248.024046) (xy 86.413462 -248.029978) (xy 86.364287 -248.027997)
			(xy 86.316068 -248.018153) (xy 86.270052 -248.000701) (xy 86.227431 -247.976094) (xy 86.18931 -247.944969)
			(xy 86.156675 -247.908132) (xy 86.130372 -247.866536) (xy 86.111081 -247.82126) (xy 86.099304 -247.773476)
			(xy 86.095344 -247.724422) (xy 85.776816 -247.724422) (xy 85.776304 -247.749868) (xy 85.76814 -247.800102)
			(xy 85.752024 -247.848376) (xy 85.728373 -247.893439) (xy 85.6978 -247.934125) (xy 85.661096 -247.96938)
			(xy 85.619212 -247.99829) (xy 85.573233 -248.020107) (xy 85.524349 -248.034267) (xy 85.473828 -248.040401)
			(xy 85.422976 -248.038352) (xy 85.373112 -248.028172) (xy 85.325526 -248.010125) (xy 85.281452 -247.984679)
			(xy 85.24203 -247.952492) (xy 85.208282 -247.914398) (xy 85.181081 -247.871384) (xy 85.161133 -247.824564)
			(xy 85.148954 -247.77515) (xy 85.144859 -247.724422) (xy 84.836762 -247.724422) (xy 84.83625 -247.749868)
			(xy 84.828086 -247.800102) (xy 84.81197 -247.848376) (xy 84.788319 -247.893439) (xy 84.757746 -247.934125)
			(xy 84.721042 -247.96938) (xy 84.679158 -247.99829) (xy 84.633179 -248.020107) (xy 84.584295 -248.034267)
			(xy 84.533774 -248.040401) (xy 84.482922 -248.038352) (xy 84.433058 -248.028172) (xy 84.385472 -248.010125)
			(xy 84.341398 -247.984679) (xy 84.301976 -247.952492) (xy 84.268228 -247.914398) (xy 84.241027 -247.871384)
			(xy 84.221079 -247.824564) (xy 84.2089 -247.77515) (xy 84.204805 -247.724422) (xy 83.886294 -247.724422)
			(xy 83.885799 -247.749029) (xy 83.877904 -247.797606) (xy 83.86232 -247.844287) (xy 83.839449 -247.887864)
			(xy 83.809884 -247.927208) (xy 83.774391 -247.9613) (xy 83.733888 -247.989256) (xy 83.689426 -248.010354)
			(xy 83.642155 -248.024046) (xy 83.5933 -248.029978) (xy 83.544125 -248.027997) (xy 83.495906 -248.018153)
			(xy 83.44989 -248.000701) (xy 83.407269 -247.976094) (xy 83.369148 -247.944969) (xy 83.336513 -247.908132)
			(xy 83.31021 -247.866536) (xy 83.290919 -247.82126) (xy 83.279142 -247.773476) (xy 83.275182 -247.724422)
			(xy 82.956654 -247.724422) (xy 82.956142 -247.749868) (xy 82.947978 -247.800102) (xy 82.931862 -247.848376)
			(xy 82.908211 -247.893439) (xy 82.877638 -247.934125) (xy 82.840934 -247.96938) (xy 82.79905 -247.99829)
			(xy 82.753071 -248.020107) (xy 82.704187 -248.034267) (xy 82.653666 -248.040401) (xy 82.602814 -248.038352)
			(xy 82.55295 -248.028172) (xy 82.505364 -248.010125) (xy 82.46129 -247.984679) (xy 82.421868 -247.952492)
			(xy 82.38812 -247.914398) (xy 82.360919 -247.871384) (xy 82.340971 -247.824564) (xy 82.328792 -247.77515)
			(xy 82.324697 -247.724422) (xy 82.00644 -247.724422) (xy 82.005945 -247.749029) (xy 81.99805 -247.797606)
			(xy 81.982466 -247.844287) (xy 81.959595 -247.887864) (xy 81.93003 -247.927208) (xy 81.894537 -247.9613)
			(xy 81.854034 -247.989256) (xy 81.809572 -248.010354) (xy 81.762301 -248.024046) (xy 81.713446 -248.029978)
			(xy 81.664271 -248.027997) (xy 81.616052 -248.018153) (xy 81.570036 -248.000701) (xy 81.527415 -247.976094)
			(xy 81.489294 -247.944969) (xy 81.456659 -247.908132) (xy 81.430356 -247.866536) (xy 81.411065 -247.82126)
			(xy 81.399288 -247.773476) (xy 81.395328 -247.724422) (xy 81.0768 -247.724422) (xy 81.076288 -247.749868)
			(xy 81.068124 -247.800102) (xy 81.052008 -247.848376) (xy 81.028357 -247.893439) (xy 80.997784 -247.934125)
			(xy 80.96108 -247.96938) (xy 80.919196 -247.99829) (xy 80.873217 -248.020107) (xy 80.824333 -248.034267)
			(xy 80.773812 -248.040401) (xy 80.72296 -248.038352) (xy 80.673096 -248.028172) (xy 80.62551 -248.010125)
			(xy 80.581436 -247.984679) (xy 80.542014 -247.952492) (xy 80.508266 -247.914398) (xy 80.481065 -247.871384)
			(xy 80.461117 -247.824564) (xy 80.448938 -247.77515) (xy 80.444843 -247.724422) (xy 80.126332 -247.724422)
			(xy 80.125837 -247.749029) (xy 80.117942 -247.797606) (xy 80.102358 -247.844287) (xy 80.079487 -247.887864)
			(xy 80.049922 -247.927208) (xy 80.014429 -247.9613) (xy 79.973926 -247.989256) (xy 79.929464 -248.010354)
			(xy 79.882193 -248.024046) (xy 79.833338 -248.029978) (xy 79.784163 -248.027997) (xy 79.735944 -248.018153)
			(xy 79.689928 -248.000701) (xy 79.647307 -247.976094) (xy 79.609186 -247.944969) (xy 79.576551 -247.908132)
			(xy 79.550248 -247.866536) (xy 79.530957 -247.82126) (xy 79.51918 -247.773476) (xy 79.51522 -247.724422)
			(xy 76.963477 -247.724422) (xy 76.965804 -247.725526) (xy 77.006307 -247.753482) (xy 77.0418 -247.787574)
			(xy 77.071365 -247.826918) (xy 77.094236 -247.870495) (xy 77.10982 -247.917176) (xy 77.117715 -247.965753)
			(xy 77.11821 -247.99036) (xy 77.117715 -248.014967) (xy 77.10982 -248.063544) (xy 77.094236 -248.110225)
			(xy 77.071365 -248.153802) (xy 77.0418 -248.193146) (xy 77.006307 -248.227238) (xy 76.965804 -248.255194)
			(xy 76.921342 -248.276292) (xy 76.874071 -248.289984) (xy 76.825216 -248.295916) (xy 76.776041 -248.293935)
			(xy 76.727822 -248.284091) (xy 76.681806 -248.266639) (xy 76.639185 -248.242032) (xy 76.601064 -248.210907)
			(xy 76.568429 -248.17407) (xy 76.542126 -248.132474) (xy 76.522835 -248.087198) (xy 76.511058 -248.039414)
			(xy 76.507098 -247.99036) (xy 65.032128 -247.99036) (xy 65.576196 -248.534428) (xy 78.105266 -248.534428)
			(xy 78.109226 -248.485374) (xy 78.121003 -248.43759) (xy 78.140294 -248.392314) (xy 78.166597 -248.350718)
			(xy 78.199232 -248.313881) (xy 78.237353 -248.282756) (xy 78.279974 -248.258149) (xy 78.32599 -248.240697)
			(xy 78.374209 -248.230853) (xy 78.423384 -248.228872) (xy 78.472239 -248.234804) (xy 78.51951 -248.248496)
			(xy 78.563972 -248.269594) (xy 78.604475 -248.29755) (xy 78.639968 -248.331642) (xy 78.669533 -248.370986)
			(xy 78.692404 -248.414563) (xy 78.707988 -248.461244) (xy 78.715883 -248.509821) (xy 78.716378 -248.534428)
			(xy 79.985374 -248.534428) (xy 79.989334 -248.485374) (xy 80.001111 -248.43759) (xy 80.020402 -248.392314)
			(xy 80.046705 -248.350718) (xy 80.07934 -248.313881) (xy 80.117461 -248.282756) (xy 80.160082 -248.258149)
			(xy 80.206098 -248.240697) (xy 80.254317 -248.230853) (xy 80.303492 -248.228872) (xy 80.352347 -248.234804)
			(xy 80.399618 -248.248496) (xy 80.44408 -248.269594) (xy 80.484583 -248.29755) (xy 80.520076 -248.331642)
			(xy 80.549641 -248.370986) (xy 80.572512 -248.414563) (xy 80.588096 -248.461244) (xy 80.595991 -248.509821)
			(xy 80.596486 -248.534428) (xy 80.914743 -248.534428) (xy 80.918838 -248.4837) (xy 80.931017 -248.434286)
			(xy 80.950965 -248.387466) (xy 80.978166 -248.344452) (xy 81.011914 -248.306358) (xy 81.051336 -248.274171)
			(xy 81.09541 -248.248725) (xy 81.142996 -248.230678) (xy 81.19286 -248.220498) (xy 81.243712 -248.218449)
			(xy 81.294233 -248.224583) (xy 81.343117 -248.238743) (xy 81.389096 -248.26056) (xy 81.43098 -248.28947)
			(xy 81.467684 -248.324725) (xy 81.498257 -248.365411) (xy 81.521908 -248.410474) (xy 81.538024 -248.458748)
			(xy 81.546188 -248.508982) (xy 81.5467 -248.534428) (xy 81.854797 -248.534428) (xy 81.858892 -248.4837)
			(xy 81.871071 -248.434286) (xy 81.891019 -248.387466) (xy 81.91822 -248.344452) (xy 81.951968 -248.306358)
			(xy 81.99139 -248.274171) (xy 82.035464 -248.248725) (xy 82.08305 -248.230678) (xy 82.132914 -248.220498)
			(xy 82.183766 -248.218449) (xy 82.234287 -248.224583) (xy 82.283171 -248.238743) (xy 82.32915 -248.26056)
			(xy 82.371034 -248.28947) (xy 82.407738 -248.324725) (xy 82.438311 -248.365411) (xy 82.461962 -248.410474)
			(xy 82.478078 -248.458748) (xy 82.486242 -248.508982) (xy 82.486754 -248.534428) (xy 82.805282 -248.534428)
			(xy 82.809242 -248.485374) (xy 82.821019 -248.43759) (xy 82.84031 -248.392314) (xy 82.866613 -248.350718)
			(xy 82.899248 -248.313881) (xy 82.937369 -248.282756) (xy 82.97999 -248.258149) (xy 83.026006 -248.240697)
			(xy 83.074225 -248.230853) (xy 83.1234 -248.228872) (xy 83.172255 -248.234804) (xy 83.219526 -248.248496)
			(xy 83.263988 -248.269594) (xy 83.304491 -248.29755) (xy 83.339984 -248.331642) (xy 83.369549 -248.370986)
			(xy 83.39242 -248.414563) (xy 83.408004 -248.461244) (xy 83.415899 -248.509821) (xy 83.416394 -248.534428)
			(xy 83.734905 -248.534428) (xy 83.739 -248.4837) (xy 83.751179 -248.434286) (xy 83.771127 -248.387466)
			(xy 83.798328 -248.344452) (xy 83.832076 -248.306358) (xy 83.871498 -248.274171) (xy 83.915572 -248.248725)
			(xy 83.963158 -248.230678) (xy 84.013022 -248.220498) (xy 84.063874 -248.218449) (xy 84.114395 -248.224583)
			(xy 84.163279 -248.238743) (xy 84.209258 -248.26056) (xy 84.251142 -248.28947) (xy 84.287846 -248.324725)
			(xy 84.318419 -248.365411) (xy 84.34207 -248.410474) (xy 84.358186 -248.458748) (xy 84.36635 -248.508982)
			(xy 84.366862 -248.534428) (xy 84.685136 -248.534428) (xy 84.689096 -248.485374) (xy 84.700873 -248.43759)
			(xy 84.720164 -248.392314) (xy 84.746467 -248.350718) (xy 84.779102 -248.313881) (xy 84.817223 -248.282756)
			(xy 84.859844 -248.258149) (xy 84.90586 -248.240697) (xy 84.954079 -248.230853) (xy 85.003254 -248.228872)
			(xy 85.052109 -248.234804) (xy 85.09938 -248.248496) (xy 85.143842 -248.269594) (xy 85.184345 -248.29755)
			(xy 85.219838 -248.331642) (xy 85.249403 -248.370986) (xy 85.272274 -248.414563) (xy 85.287858 -248.461244)
			(xy 85.295753 -248.509821) (xy 85.296248 -248.534428) (xy 85.614759 -248.534428) (xy 85.618854 -248.4837)
			(xy 85.631033 -248.434286) (xy 85.650981 -248.387466) (xy 85.678182 -248.344452) (xy 85.71193 -248.306358)
			(xy 85.751352 -248.274171) (xy 85.795426 -248.248725) (xy 85.843012 -248.230678) (xy 85.892876 -248.220498)
			(xy 85.943728 -248.218449) (xy 85.994249 -248.224583) (xy 86.043133 -248.238743) (xy 86.089112 -248.26056)
			(xy 86.130996 -248.28947) (xy 86.1677 -248.324725) (xy 86.198273 -248.365411) (xy 86.221924 -248.410474)
			(xy 86.23804 -248.458748) (xy 86.246204 -248.508982) (xy 86.246716 -248.534428) (xy 86.565244 -248.534428)
			(xy 86.569204 -248.485374) (xy 86.580981 -248.43759) (xy 86.600272 -248.392314) (xy 86.626575 -248.350718)
			(xy 86.65921 -248.313881) (xy 86.697331 -248.282756) (xy 86.739952 -248.258149) (xy 86.785968 -248.240697)
			(xy 86.834187 -248.230853) (xy 86.883362 -248.228872) (xy 86.932217 -248.234804) (xy 86.979488 -248.248496)
			(xy 87.02395 -248.269594) (xy 87.064453 -248.29755) (xy 87.099946 -248.331642) (xy 87.129511 -248.370986)
			(xy 87.152382 -248.414563) (xy 87.167966 -248.461244) (xy 87.175861 -248.509821) (xy 87.176356 -248.534428)
			(xy 87.494867 -248.534428) (xy 87.498962 -248.4837) (xy 87.511141 -248.434286) (xy 87.531089 -248.387466)
			(xy 87.55829 -248.344452) (xy 87.592038 -248.306358) (xy 87.63146 -248.274171) (xy 87.675534 -248.248725)
			(xy 87.72312 -248.230678) (xy 87.772984 -248.220498) (xy 87.823836 -248.218449) (xy 87.874357 -248.224583)
			(xy 87.923241 -248.238743) (xy 87.96922 -248.26056) (xy 88.011104 -248.28947) (xy 88.047808 -248.324725)
			(xy 88.078381 -248.365411) (xy 88.102032 -248.410474) (xy 88.118148 -248.458748) (xy 88.126312 -248.508982)
			(xy 88.126824 -248.534428) (xy 88.434921 -248.534428) (xy 88.439016 -248.4837) (xy 88.451195 -248.434286)
			(xy 88.471143 -248.387466) (xy 88.498344 -248.344452) (xy 88.532092 -248.306358) (xy 88.571514 -248.274171)
			(xy 88.615588 -248.248725) (xy 88.663174 -248.230678) (xy 88.713038 -248.220498) (xy 88.76389 -248.218449)
			(xy 88.814411 -248.224583) (xy 88.863295 -248.238743) (xy 88.909274 -248.26056) (xy 88.951158 -248.28947)
			(xy 88.987862 -248.324725) (xy 89.018435 -248.365411) (xy 89.042086 -248.410474) (xy 89.058202 -248.458748)
			(xy 89.066366 -248.508982) (xy 89.066878 -248.534428) (xy 89.385152 -248.534428) (xy 89.389112 -248.485374)
			(xy 89.400889 -248.43759) (xy 89.42018 -248.392314) (xy 89.446483 -248.350718) (xy 89.479118 -248.313881)
			(xy 89.517239 -248.282756) (xy 89.55986 -248.258149) (xy 89.605876 -248.240697) (xy 89.654095 -248.230853)
			(xy 89.70327 -248.228872) (xy 89.752125 -248.234804) (xy 89.799396 -248.248496) (xy 89.843858 -248.269594)
			(xy 89.884361 -248.29755) (xy 89.919854 -248.331642) (xy 89.949419 -248.370986) (xy 89.97229 -248.414563)
			(xy 89.987874 -248.461244) (xy 89.995769 -248.509821) (xy 89.996264 -248.534428) (xy 90.314775 -248.534428)
			(xy 90.31887 -248.4837) (xy 90.331049 -248.434286) (xy 90.350997 -248.387466) (xy 90.378198 -248.344452)
			(xy 90.411946 -248.306358) (xy 90.451368 -248.274171) (xy 90.495442 -248.248725) (xy 90.543028 -248.230678)
			(xy 90.592892 -248.220498) (xy 90.643744 -248.218449) (xy 90.694265 -248.224583) (xy 90.743149 -248.238743)
			(xy 90.789128 -248.26056) (xy 90.831012 -248.28947) (xy 90.867716 -248.324725) (xy 90.898289 -248.365411)
			(xy 90.92194 -248.410474) (xy 90.938056 -248.458748) (xy 90.94622 -248.508982) (xy 90.946732 -248.534428)
			(xy 91.26526 -248.534428) (xy 91.26922 -248.485374) (xy 91.280997 -248.43759) (xy 91.300288 -248.392314)
			(xy 91.326591 -248.350718) (xy 91.359226 -248.313881) (xy 91.397347 -248.282756) (xy 91.439968 -248.258149)
			(xy 91.485984 -248.240697) (xy 91.534203 -248.230853) (xy 91.583378 -248.228872) (xy 91.632233 -248.234804)
			(xy 91.679504 -248.248496) (xy 91.723966 -248.269594) (xy 91.764469 -248.29755) (xy 91.799962 -248.331642)
			(xy 91.829527 -248.370986) (xy 91.852398 -248.414563) (xy 91.867982 -248.461244) (xy 91.875877 -248.509821)
			(xy 91.876372 -248.534428) (xy 92.194883 -248.534428) (xy 92.198978 -248.4837) (xy 92.211157 -248.434286)
			(xy 92.231105 -248.387466) (xy 92.258306 -248.344452) (xy 92.292054 -248.306358) (xy 92.331476 -248.274171)
			(xy 92.37555 -248.248725) (xy 92.423136 -248.230678) (xy 92.473 -248.220498) (xy 92.523852 -248.218449)
			(xy 92.574373 -248.224583) (xy 92.623257 -248.238743) (xy 92.669236 -248.26056) (xy 92.71112 -248.28947)
			(xy 92.747824 -248.324725) (xy 92.778397 -248.365411) (xy 92.802048 -248.410474) (xy 92.818164 -248.458748)
			(xy 92.826328 -248.508982) (xy 92.82684 -248.534428) (xy 93.145114 -248.534428) (xy 93.149074 -248.485374)
			(xy 93.160851 -248.43759) (xy 93.180142 -248.392314) (xy 93.206445 -248.350718) (xy 93.23908 -248.313881)
			(xy 93.277201 -248.282756) (xy 93.319822 -248.258149) (xy 93.365838 -248.240697) (xy 93.414057 -248.230853)
			(xy 93.463232 -248.228872) (xy 93.512087 -248.234804) (xy 93.559358 -248.248496) (xy 93.60382 -248.269594)
			(xy 93.644323 -248.29755) (xy 93.679816 -248.331642) (xy 93.709381 -248.370986) (xy 93.732252 -248.414563)
			(xy 93.747836 -248.461244) (xy 93.755731 -248.509821) (xy 93.756226 -248.534428) (xy 94.074737 -248.534428)
			(xy 94.078832 -248.4837) (xy 94.091011 -248.434286) (xy 94.110959 -248.387466) (xy 94.13816 -248.344452)
			(xy 94.171908 -248.306358) (xy 94.21133 -248.274171) (xy 94.255404 -248.248725) (xy 94.30299 -248.230678)
			(xy 94.352854 -248.220498) (xy 94.403706 -248.218449) (xy 94.454227 -248.224583) (xy 94.503111 -248.238743)
			(xy 94.54909 -248.26056) (xy 94.590974 -248.28947) (xy 94.627678 -248.324725) (xy 94.658251 -248.365411)
			(xy 94.681902 -248.410474) (xy 94.698018 -248.458748) (xy 94.706182 -248.508982) (xy 94.706694 -248.534428)
			(xy 95.014791 -248.534428) (xy 95.018886 -248.4837) (xy 95.031065 -248.434286) (xy 95.051013 -248.387466)
			(xy 95.078214 -248.344452) (xy 95.111962 -248.306358) (xy 95.151384 -248.274171) (xy 95.195458 -248.248725)
			(xy 95.243044 -248.230678) (xy 95.292908 -248.220498) (xy 95.34376 -248.218449) (xy 95.394281 -248.224583)
			(xy 95.443165 -248.238743) (xy 95.489144 -248.26056) (xy 95.531028 -248.28947) (xy 95.567732 -248.324725)
			(xy 95.598305 -248.365411) (xy 95.621956 -248.410474) (xy 95.638072 -248.458748) (xy 95.646236 -248.508982)
			(xy 95.646748 -248.534428) (xy 95.965276 -248.534428) (xy 95.969236 -248.485374) (xy 95.981013 -248.43759)
			(xy 96.000304 -248.392314) (xy 96.026607 -248.350718) (xy 96.059242 -248.313881) (xy 96.097363 -248.282756)
			(xy 96.139984 -248.258149) (xy 96.186 -248.240697) (xy 96.234219 -248.230853) (xy 96.283394 -248.228872)
			(xy 96.332249 -248.234804) (xy 96.37952 -248.248496) (xy 96.423982 -248.269594) (xy 96.464485 -248.29755)
			(xy 96.499978 -248.331642) (xy 96.529543 -248.370986) (xy 96.552414 -248.414563) (xy 96.567998 -248.461244)
			(xy 96.575893 -248.509821) (xy 96.576388 -248.534428) (xy 98.785184 -248.534428) (xy 98.789144 -248.485374)
			(xy 98.800921 -248.43759) (xy 98.820212 -248.392314) (xy 98.846515 -248.350718) (xy 98.87915 -248.313881)
			(xy 98.917271 -248.282756) (xy 98.959892 -248.258149) (xy 99.005908 -248.240697) (xy 99.054127 -248.230853)
			(xy 99.103302 -248.228872) (xy 99.152157 -248.234804) (xy 99.199428 -248.248496) (xy 99.24389 -248.269594)
			(xy 99.284393 -248.29755) (xy 99.319886 -248.331642) (xy 99.349451 -248.370986) (xy 99.372322 -248.414563)
			(xy 99.387906 -248.461244) (xy 99.395801 -248.509821) (xy 99.396296 -248.534428) (xy 101.605346 -248.534428)
			(xy 101.609306 -248.485374) (xy 101.621083 -248.43759) (xy 101.640374 -248.392314) (xy 101.666677 -248.350718)
			(xy 101.699312 -248.313881) (xy 101.737433 -248.282756) (xy 101.780054 -248.258149) (xy 101.82607 -248.240697)
			(xy 101.874289 -248.230853) (xy 101.923464 -248.228872) (xy 101.972319 -248.234804) (xy 102.01959 -248.248496)
			(xy 102.064052 -248.269594) (xy 102.104555 -248.29755) (xy 102.140048 -248.331642) (xy 102.169613 -248.370986)
			(xy 102.192484 -248.414563) (xy 102.208068 -248.461244) (xy 102.215963 -248.509821) (xy 102.216458 -248.534428)
			(xy 104.425254 -248.534428) (xy 104.429214 -248.485374) (xy 104.440991 -248.43759) (xy 104.460282 -248.392314)
			(xy 104.486585 -248.350718) (xy 104.51922 -248.313881) (xy 104.557341 -248.282756) (xy 104.599962 -248.258149)
			(xy 104.645978 -248.240697) (xy 104.694197 -248.230853) (xy 104.743372 -248.228872) (xy 104.792227 -248.234804)
			(xy 104.839498 -248.248496) (xy 104.88396 -248.269594) (xy 104.924463 -248.29755) (xy 104.959956 -248.331642)
			(xy 104.989521 -248.370986) (xy 105.012392 -248.414563) (xy 105.027976 -248.461244) (xy 105.035871 -248.509821)
			(xy 105.036366 -248.534428) (xy 107.245162 -248.534428) (xy 107.249122 -248.485374) (xy 107.260899 -248.43759)
			(xy 107.28019 -248.392314) (xy 107.306493 -248.350718) (xy 107.339128 -248.313881) (xy 107.377249 -248.282756)
			(xy 107.41987 -248.258149) (xy 107.465886 -248.240697) (xy 107.514105 -248.230853) (xy 107.56328 -248.228872)
			(xy 107.612135 -248.234804) (xy 107.659406 -248.248496) (xy 107.703868 -248.269594) (xy 107.744371 -248.29755)
			(xy 107.779864 -248.331642) (xy 107.809429 -248.370986) (xy 107.8323 -248.414563) (xy 107.847884 -248.461244)
			(xy 107.855779 -248.509821) (xy 107.856274 -248.534428) (xy 108.174785 -248.534428) (xy 108.17888 -248.4837)
			(xy 108.191059 -248.434286) (xy 108.211007 -248.387466) (xy 108.238208 -248.344452) (xy 108.271956 -248.306358)
			(xy 108.311378 -248.274171) (xy 108.355452 -248.248725) (xy 108.403038 -248.230678) (xy 108.452902 -248.220498)
			(xy 108.503754 -248.218449) (xy 108.554275 -248.224583) (xy 108.603159 -248.238743) (xy 108.649138 -248.26056)
			(xy 108.691022 -248.28947) (xy 108.727726 -248.324725) (xy 108.758299 -248.365411) (xy 108.78195 -248.410474)
			(xy 108.798066 -248.458748) (xy 108.80623 -248.508982) (xy 108.806742 -248.534428) (xy 109.114839 -248.534428)
			(xy 109.118934 -248.4837) (xy 109.131113 -248.434286) (xy 109.151061 -248.387466) (xy 109.178262 -248.344452)
			(xy 109.21201 -248.306358) (xy 109.251432 -248.274171) (xy 109.295506 -248.248725) (xy 109.343092 -248.230678)
			(xy 109.392956 -248.220498) (xy 109.443808 -248.218449) (xy 109.494329 -248.224583) (xy 109.543213 -248.238743)
			(xy 109.589192 -248.26056) (xy 109.631076 -248.28947) (xy 109.66778 -248.324725) (xy 109.698353 -248.365411)
			(xy 109.722004 -248.410474) (xy 109.73812 -248.458748) (xy 109.746284 -248.508982) (xy 109.746796 -248.534428)
			(xy 110.065324 -248.534428) (xy 110.069284 -248.485374) (xy 110.081061 -248.43759) (xy 110.100352 -248.392314)
			(xy 110.126655 -248.350718) (xy 110.15929 -248.313881) (xy 110.197411 -248.282756) (xy 110.240032 -248.258149)
			(xy 110.286048 -248.240697) (xy 110.334267 -248.230853) (xy 110.383442 -248.228872) (xy 110.432297 -248.234804)
			(xy 110.479568 -248.248496) (xy 110.52403 -248.269594) (xy 110.564533 -248.29755) (xy 110.600026 -248.331642)
			(xy 110.629591 -248.370986) (xy 110.652462 -248.414563) (xy 110.668046 -248.461244) (xy 110.675941 -248.509821)
			(xy 110.676436 -248.534428) (xy 110.675941 -248.559035) (xy 110.668046 -248.607612) (xy 110.652462 -248.654293)
			(xy 110.629591 -248.69787) (xy 110.600026 -248.737214) (xy 110.564533 -248.771306) (xy 110.52403 -248.799262)
			(xy 110.479568 -248.82036) (xy 110.432297 -248.834052) (xy 110.383442 -248.839984) (xy 110.334267 -248.838003)
			(xy 110.286048 -248.828159) (xy 110.240032 -248.810707) (xy 110.197411 -248.7861) (xy 110.15929 -248.754975)
			(xy 110.126655 -248.718138) (xy 110.100352 -248.676542) (xy 110.081061 -248.631266) (xy 110.069284 -248.583482)
			(xy 110.065324 -248.534428) (xy 109.746796 -248.534428) (xy 109.746284 -248.559874) (xy 109.73812 -248.610108)
			(xy 109.722004 -248.658382) (xy 109.698353 -248.703445) (xy 109.66778 -248.744131) (xy 109.631076 -248.779386)
			(xy 109.589192 -248.808296) (xy 109.543213 -248.830113) (xy 109.494329 -248.844273) (xy 109.443808 -248.850407)
			(xy 109.392956 -248.848358) (xy 109.343092 -248.838178) (xy 109.295506 -248.820131) (xy 109.251432 -248.794685)
			(xy 109.21201 -248.762498) (xy 109.178262 -248.724404) (xy 109.151061 -248.68139) (xy 109.131113 -248.63457)
			(xy 109.118934 -248.585156) (xy 109.114839 -248.534428) (xy 108.806742 -248.534428) (xy 108.80623 -248.559874)
			(xy 108.798066 -248.610108) (xy 108.78195 -248.658382) (xy 108.758299 -248.703445) (xy 108.727726 -248.744131)
			(xy 108.691022 -248.779386) (xy 108.649138 -248.808296) (xy 108.603159 -248.830113) (xy 108.554275 -248.844273)
			(xy 108.503754 -248.850407) (xy 108.452902 -248.848358) (xy 108.403038 -248.838178) (xy 108.355452 -248.820131)
			(xy 108.311378 -248.794685) (xy 108.271956 -248.762498) (xy 108.238208 -248.724404) (xy 108.211007 -248.68139)
			(xy 108.191059 -248.63457) (xy 108.17888 -248.585156) (xy 108.174785 -248.534428) (xy 107.856274 -248.534428)
			(xy 107.855779 -248.559035) (xy 107.847884 -248.607612) (xy 107.8323 -248.654293) (xy 107.809429 -248.69787)
			(xy 107.779864 -248.737214) (xy 107.744371 -248.771306) (xy 107.703868 -248.799262) (xy 107.659406 -248.82036)
			(xy 107.612135 -248.834052) (xy 107.56328 -248.839984) (xy 107.514105 -248.838003) (xy 107.465886 -248.828159)
			(xy 107.41987 -248.810707) (xy 107.377249 -248.7861) (xy 107.339128 -248.754975) (xy 107.306493 -248.718138)
			(xy 107.28019 -248.676542) (xy 107.260899 -248.631266) (xy 107.249122 -248.583482) (xy 107.245162 -248.534428)
			(xy 105.036366 -248.534428) (xy 105.035871 -248.559035) (xy 105.027976 -248.607612) (xy 105.012392 -248.654293)
			(xy 104.989521 -248.69787) (xy 104.959956 -248.737214) (xy 104.924463 -248.771306) (xy 104.88396 -248.799262)
			(xy 104.839498 -248.82036) (xy 104.792227 -248.834052) (xy 104.743372 -248.839984) (xy 104.694197 -248.838003)
			(xy 104.645978 -248.828159) (xy 104.599962 -248.810707) (xy 104.557341 -248.7861) (xy 104.51922 -248.754975)
			(xy 104.486585 -248.718138) (xy 104.460282 -248.676542) (xy 104.440991 -248.631266) (xy 104.429214 -248.583482)
			(xy 104.425254 -248.534428) (xy 102.216458 -248.534428) (xy 102.215963 -248.559035) (xy 102.208068 -248.607612)
			(xy 102.192484 -248.654293) (xy 102.169613 -248.69787) (xy 102.140048 -248.737214) (xy 102.104555 -248.771306)
			(xy 102.064052 -248.799262) (xy 102.01959 -248.82036) (xy 101.972319 -248.834052) (xy 101.923464 -248.839984)
			(xy 101.874289 -248.838003) (xy 101.82607 -248.828159) (xy 101.780054 -248.810707) (xy 101.737433 -248.7861)
			(xy 101.699312 -248.754975) (xy 101.666677 -248.718138) (xy 101.640374 -248.676542) (xy 101.621083 -248.631266)
			(xy 101.609306 -248.583482) (xy 101.605346 -248.534428) (xy 99.396296 -248.534428) (xy 99.395801 -248.559035)
			(xy 99.387906 -248.607612) (xy 99.372322 -248.654293) (xy 99.349451 -248.69787) (xy 99.319886 -248.737214)
			(xy 99.284393 -248.771306) (xy 99.24389 -248.799262) (xy 99.199428 -248.82036) (xy 99.152157 -248.834052)
			(xy 99.103302 -248.839984) (xy 99.054127 -248.838003) (xy 99.005908 -248.828159) (xy 98.959892 -248.810707)
			(xy 98.917271 -248.7861) (xy 98.87915 -248.754975) (xy 98.846515 -248.718138) (xy 98.820212 -248.676542)
			(xy 98.800921 -248.631266) (xy 98.789144 -248.583482) (xy 98.785184 -248.534428) (xy 96.576388 -248.534428)
			(xy 96.575893 -248.559035) (xy 96.567998 -248.607612) (xy 96.552414 -248.654293) (xy 96.529543 -248.69787)
			(xy 96.499978 -248.737214) (xy 96.464485 -248.771306) (xy 96.423982 -248.799262) (xy 96.37952 -248.82036)
			(xy 96.332249 -248.834052) (xy 96.283394 -248.839984) (xy 96.234219 -248.838003) (xy 96.186 -248.828159)
			(xy 96.139984 -248.810707) (xy 96.097363 -248.7861) (xy 96.059242 -248.754975) (xy 96.026607 -248.718138)
			(xy 96.000304 -248.676542) (xy 95.981013 -248.631266) (xy 95.969236 -248.583482) (xy 95.965276 -248.534428)
			(xy 95.646748 -248.534428) (xy 95.646236 -248.559874) (xy 95.638072 -248.610108) (xy 95.621956 -248.658382)
			(xy 95.598305 -248.703445) (xy 95.567732 -248.744131) (xy 95.531028 -248.779386) (xy 95.489144 -248.808296)
			(xy 95.443165 -248.830113) (xy 95.394281 -248.844273) (xy 95.34376 -248.850407) (xy 95.292908 -248.848358)
			(xy 95.243044 -248.838178) (xy 95.195458 -248.820131) (xy 95.151384 -248.794685) (xy 95.111962 -248.762498)
			(xy 95.078214 -248.724404) (xy 95.051013 -248.68139) (xy 95.031065 -248.63457) (xy 95.018886 -248.585156)
			(xy 95.014791 -248.534428) (xy 94.706694 -248.534428) (xy 94.706182 -248.559874) (xy 94.698018 -248.610108)
			(xy 94.681902 -248.658382) (xy 94.658251 -248.703445) (xy 94.627678 -248.744131) (xy 94.590974 -248.779386)
			(xy 94.54909 -248.808296) (xy 94.503111 -248.830113) (xy 94.454227 -248.844273) (xy 94.403706 -248.850407)
			(xy 94.352854 -248.848358) (xy 94.30299 -248.838178) (xy 94.255404 -248.820131) (xy 94.21133 -248.794685)
			(xy 94.171908 -248.762498) (xy 94.13816 -248.724404) (xy 94.110959 -248.68139) (xy 94.091011 -248.63457)
			(xy 94.078832 -248.585156) (xy 94.074737 -248.534428) (xy 93.756226 -248.534428) (xy 93.755731 -248.559035)
			(xy 93.747836 -248.607612) (xy 93.732252 -248.654293) (xy 93.709381 -248.69787) (xy 93.679816 -248.737214)
			(xy 93.644323 -248.771306) (xy 93.60382 -248.799262) (xy 93.559358 -248.82036) (xy 93.512087 -248.834052)
			(xy 93.463232 -248.839984) (xy 93.414057 -248.838003) (xy 93.365838 -248.828159) (xy 93.319822 -248.810707)
			(xy 93.277201 -248.7861) (xy 93.23908 -248.754975) (xy 93.206445 -248.718138) (xy 93.180142 -248.676542)
			(xy 93.160851 -248.631266) (xy 93.149074 -248.583482) (xy 93.145114 -248.534428) (xy 92.82684 -248.534428)
			(xy 92.826328 -248.559874) (xy 92.818164 -248.610108) (xy 92.802048 -248.658382) (xy 92.778397 -248.703445)
			(xy 92.747824 -248.744131) (xy 92.71112 -248.779386) (xy 92.669236 -248.808296) (xy 92.623257 -248.830113)
			(xy 92.574373 -248.844273) (xy 92.523852 -248.850407) (xy 92.473 -248.848358) (xy 92.423136 -248.838178)
			(xy 92.37555 -248.820131) (xy 92.331476 -248.794685) (xy 92.292054 -248.762498) (xy 92.258306 -248.724404)
			(xy 92.231105 -248.68139) (xy 92.211157 -248.63457) (xy 92.198978 -248.585156) (xy 92.194883 -248.534428)
			(xy 91.876372 -248.534428) (xy 91.875877 -248.559035) (xy 91.867982 -248.607612) (xy 91.852398 -248.654293)
			(xy 91.829527 -248.69787) (xy 91.799962 -248.737214) (xy 91.764469 -248.771306) (xy 91.723966 -248.799262)
			(xy 91.679504 -248.82036) (xy 91.632233 -248.834052) (xy 91.583378 -248.839984) (xy 91.534203 -248.838003)
			(xy 91.485984 -248.828159) (xy 91.439968 -248.810707) (xy 91.397347 -248.7861) (xy 91.359226 -248.754975)
			(xy 91.326591 -248.718138) (xy 91.300288 -248.676542) (xy 91.280997 -248.631266) (xy 91.26922 -248.583482)
			(xy 91.26526 -248.534428) (xy 90.946732 -248.534428) (xy 90.94622 -248.559874) (xy 90.938056 -248.610108)
			(xy 90.92194 -248.658382) (xy 90.898289 -248.703445) (xy 90.867716 -248.744131) (xy 90.831012 -248.779386)
			(xy 90.789128 -248.808296) (xy 90.743149 -248.830113) (xy 90.694265 -248.844273) (xy 90.643744 -248.850407)
			(xy 90.592892 -248.848358) (xy 90.543028 -248.838178) (xy 90.495442 -248.820131) (xy 90.451368 -248.794685)
			(xy 90.411946 -248.762498) (xy 90.378198 -248.724404) (xy 90.350997 -248.68139) (xy 90.331049 -248.63457)
			(xy 90.31887 -248.585156) (xy 90.314775 -248.534428) (xy 89.996264 -248.534428) (xy 89.995769 -248.559035)
			(xy 89.987874 -248.607612) (xy 89.97229 -248.654293) (xy 89.949419 -248.69787) (xy 89.919854 -248.737214)
			(xy 89.884361 -248.771306) (xy 89.843858 -248.799262) (xy 89.799396 -248.82036) (xy 89.752125 -248.834052)
			(xy 89.70327 -248.839984) (xy 89.654095 -248.838003) (xy 89.605876 -248.828159) (xy 89.55986 -248.810707)
			(xy 89.517239 -248.7861) (xy 89.479118 -248.754975) (xy 89.446483 -248.718138) (xy 89.42018 -248.676542)
			(xy 89.400889 -248.631266) (xy 89.389112 -248.583482) (xy 89.385152 -248.534428) (xy 89.066878 -248.534428)
			(xy 89.066366 -248.559874) (xy 89.058202 -248.610108) (xy 89.042086 -248.658382) (xy 89.018435 -248.703445)
			(xy 88.987862 -248.744131) (xy 88.951158 -248.779386) (xy 88.909274 -248.808296) (xy 88.863295 -248.830113)
			(xy 88.814411 -248.844273) (xy 88.76389 -248.850407) (xy 88.713038 -248.848358) (xy 88.663174 -248.838178)
			(xy 88.615588 -248.820131) (xy 88.571514 -248.794685) (xy 88.532092 -248.762498) (xy 88.498344 -248.724404)
			(xy 88.471143 -248.68139) (xy 88.451195 -248.63457) (xy 88.439016 -248.585156) (xy 88.434921 -248.534428)
			(xy 88.126824 -248.534428) (xy 88.126312 -248.559874) (xy 88.118148 -248.610108) (xy 88.102032 -248.658382)
			(xy 88.078381 -248.703445) (xy 88.047808 -248.744131) (xy 88.011104 -248.779386) (xy 87.96922 -248.808296)
			(xy 87.923241 -248.830113) (xy 87.874357 -248.844273) (xy 87.823836 -248.850407) (xy 87.772984 -248.848358)
			(xy 87.72312 -248.838178) (xy 87.675534 -248.820131) (xy 87.63146 -248.794685) (xy 87.592038 -248.762498)
			(xy 87.55829 -248.724404) (xy 87.531089 -248.68139) (xy 87.511141 -248.63457) (xy 87.498962 -248.585156)
			(xy 87.494867 -248.534428) (xy 87.176356 -248.534428) (xy 87.175861 -248.559035) (xy 87.167966 -248.607612)
			(xy 87.152382 -248.654293) (xy 87.129511 -248.69787) (xy 87.099946 -248.737214) (xy 87.064453 -248.771306)
			(xy 87.02395 -248.799262) (xy 86.979488 -248.82036) (xy 86.932217 -248.834052) (xy 86.883362 -248.839984)
			(xy 86.834187 -248.838003) (xy 86.785968 -248.828159) (xy 86.739952 -248.810707) (xy 86.697331 -248.7861)
			(xy 86.65921 -248.754975) (xy 86.626575 -248.718138) (xy 86.600272 -248.676542) (xy 86.580981 -248.631266)
			(xy 86.569204 -248.583482) (xy 86.565244 -248.534428) (xy 86.246716 -248.534428) (xy 86.246204 -248.559874)
			(xy 86.23804 -248.610108) (xy 86.221924 -248.658382) (xy 86.198273 -248.703445) (xy 86.1677 -248.744131)
			(xy 86.130996 -248.779386) (xy 86.089112 -248.808296) (xy 86.043133 -248.830113) (xy 85.994249 -248.844273)
			(xy 85.943728 -248.850407) (xy 85.892876 -248.848358) (xy 85.843012 -248.838178) (xy 85.795426 -248.820131)
			(xy 85.751352 -248.794685) (xy 85.71193 -248.762498) (xy 85.678182 -248.724404) (xy 85.650981 -248.68139)
			(xy 85.631033 -248.63457) (xy 85.618854 -248.585156) (xy 85.614759 -248.534428) (xy 85.296248 -248.534428)
			(xy 85.295753 -248.559035) (xy 85.287858 -248.607612) (xy 85.272274 -248.654293) (xy 85.249403 -248.69787)
			(xy 85.219838 -248.737214) (xy 85.184345 -248.771306) (xy 85.143842 -248.799262) (xy 85.09938 -248.82036)
			(xy 85.052109 -248.834052) (xy 85.003254 -248.839984) (xy 84.954079 -248.838003) (xy 84.90586 -248.828159)
			(xy 84.859844 -248.810707) (xy 84.817223 -248.7861) (xy 84.779102 -248.754975) (xy 84.746467 -248.718138)
			(xy 84.720164 -248.676542) (xy 84.700873 -248.631266) (xy 84.689096 -248.583482) (xy 84.685136 -248.534428)
			(xy 84.366862 -248.534428) (xy 84.36635 -248.559874) (xy 84.358186 -248.610108) (xy 84.34207 -248.658382)
			(xy 84.318419 -248.703445) (xy 84.287846 -248.744131) (xy 84.251142 -248.779386) (xy 84.209258 -248.808296)
			(xy 84.163279 -248.830113) (xy 84.114395 -248.844273) (xy 84.063874 -248.850407) (xy 84.013022 -248.848358)
			(xy 83.963158 -248.838178) (xy 83.915572 -248.820131) (xy 83.871498 -248.794685) (xy 83.832076 -248.762498)
			(xy 83.798328 -248.724404) (xy 83.771127 -248.68139) (xy 83.751179 -248.63457) (xy 83.739 -248.585156)
			(xy 83.734905 -248.534428) (xy 83.416394 -248.534428) (xy 83.415899 -248.559035) (xy 83.408004 -248.607612)
			(xy 83.39242 -248.654293) (xy 83.369549 -248.69787) (xy 83.339984 -248.737214) (xy 83.304491 -248.771306)
			(xy 83.263988 -248.799262) (xy 83.219526 -248.82036) (xy 83.172255 -248.834052) (xy 83.1234 -248.839984)
			(xy 83.074225 -248.838003) (xy 83.026006 -248.828159) (xy 82.97999 -248.810707) (xy 82.937369 -248.7861)
			(xy 82.899248 -248.754975) (xy 82.866613 -248.718138) (xy 82.84031 -248.676542) (xy 82.821019 -248.631266)
			(xy 82.809242 -248.583482) (xy 82.805282 -248.534428) (xy 82.486754 -248.534428) (xy 82.486242 -248.559874)
			(xy 82.478078 -248.610108) (xy 82.461962 -248.658382) (xy 82.438311 -248.703445) (xy 82.407738 -248.744131)
			(xy 82.371034 -248.779386) (xy 82.32915 -248.808296) (xy 82.283171 -248.830113) (xy 82.234287 -248.844273)
			(xy 82.183766 -248.850407) (xy 82.132914 -248.848358) (xy 82.08305 -248.838178) (xy 82.035464 -248.820131)
			(xy 81.99139 -248.794685) (xy 81.951968 -248.762498) (xy 81.91822 -248.724404) (xy 81.891019 -248.68139)
			(xy 81.871071 -248.63457) (xy 81.858892 -248.585156) (xy 81.854797 -248.534428) (xy 81.5467 -248.534428)
			(xy 81.546188 -248.559874) (xy 81.538024 -248.610108) (xy 81.521908 -248.658382) (xy 81.498257 -248.703445)
			(xy 81.467684 -248.744131) (xy 81.43098 -248.779386) (xy 81.389096 -248.808296) (xy 81.343117 -248.830113)
			(xy 81.294233 -248.844273) (xy 81.243712 -248.850407) (xy 81.19286 -248.848358) (xy 81.142996 -248.838178)
			(xy 81.09541 -248.820131) (xy 81.051336 -248.794685) (xy 81.011914 -248.762498) (xy 80.978166 -248.724404)
			(xy 80.950965 -248.68139) (xy 80.931017 -248.63457) (xy 80.918838 -248.585156) (xy 80.914743 -248.534428)
			(xy 80.596486 -248.534428) (xy 80.595991 -248.559035) (xy 80.588096 -248.607612) (xy 80.572512 -248.654293)
			(xy 80.549641 -248.69787) (xy 80.520076 -248.737214) (xy 80.484583 -248.771306) (xy 80.44408 -248.799262)
			(xy 80.399618 -248.82036) (xy 80.352347 -248.834052) (xy 80.303492 -248.839984) (xy 80.254317 -248.838003)
			(xy 80.206098 -248.828159) (xy 80.160082 -248.810707) (xy 80.117461 -248.7861) (xy 80.07934 -248.754975)
			(xy 80.046705 -248.718138) (xy 80.020402 -248.676542) (xy 80.001111 -248.631266) (xy 79.989334 -248.583482)
			(xy 79.985374 -248.534428) (xy 78.716378 -248.534428) (xy 78.715883 -248.559035) (xy 78.707988 -248.607612)
			(xy 78.692404 -248.654293) (xy 78.669533 -248.69787) (xy 78.639968 -248.737214) (xy 78.604475 -248.771306)
			(xy 78.563972 -248.799262) (xy 78.51951 -248.82036) (xy 78.472239 -248.834052) (xy 78.423384 -248.839984)
			(xy 78.374209 -248.838003) (xy 78.32599 -248.828159) (xy 78.279974 -248.810707) (xy 78.237353 -248.7861)
			(xy 78.199232 -248.754975) (xy 78.166597 -248.718138) (xy 78.140294 -248.676542) (xy 78.121003 -248.631266)
			(xy 78.109226 -248.583482) (xy 78.105266 -248.534428) (xy 65.576196 -248.534428) (xy 66.65214 -249.610372)
			(xy 76.507098 -249.610372) (xy 76.511058 -249.561318) (xy 76.522835 -249.513534) (xy 76.542126 -249.468258)
			(xy 76.568429 -249.426662) (xy 76.601064 -249.389825) (xy 76.639185 -249.3587) (xy 76.681806 -249.334093)
			(xy 76.727822 -249.316641) (xy 76.776041 -249.306797) (xy 76.825216 -249.304816) (xy 76.874071 -249.310748)
			(xy 76.921342 -249.32444) (xy 76.963477 -249.344434) (xy 79.51522 -249.344434) (xy 79.51918 -249.29538)
			(xy 79.530957 -249.247596) (xy 79.550248 -249.20232) (xy 79.576551 -249.160724) (xy 79.609186 -249.123887)
			(xy 79.647307 -249.092762) (xy 79.689928 -249.068155) (xy 79.735944 -249.050703) (xy 79.784163 -249.040859)
			(xy 79.833338 -249.038878) (xy 79.882193 -249.04481) (xy 79.929464 -249.058502) (xy 79.973926 -249.0796)
			(xy 80.014429 -249.107556) (xy 80.049922 -249.141648) (xy 80.079487 -249.180992) (xy 80.102358 -249.224569)
			(xy 80.117942 -249.27125) (xy 80.125837 -249.319827) (xy 80.126332 -249.344434) (xy 80.455274 -249.344434)
			(xy 80.459234 -249.29538) (xy 80.471011 -249.247596) (xy 80.490302 -249.20232) (xy 80.516605 -249.160724)
			(xy 80.54924 -249.123887) (xy 80.587361 -249.092762) (xy 80.629982 -249.068155) (xy 80.675998 -249.050703)
			(xy 80.724217 -249.040859) (xy 80.773392 -249.038878) (xy 80.822247 -249.04481) (xy 80.869518 -249.058502)
			(xy 80.91398 -249.0796) (xy 80.954483 -249.107556) (xy 80.989976 -249.141648) (xy 81.019541 -249.180992)
			(xy 81.042412 -249.224569) (xy 81.057996 -249.27125) (xy 81.065891 -249.319827) (xy 81.066386 -249.344434)
			(xy 81.395328 -249.344434) (xy 81.399288 -249.29538) (xy 81.411065 -249.247596) (xy 81.430356 -249.20232)
			(xy 81.456659 -249.160724) (xy 81.489294 -249.123887) (xy 81.527415 -249.092762) (xy 81.570036 -249.068155)
			(xy 81.616052 -249.050703) (xy 81.664271 -249.040859) (xy 81.713446 -249.038878) (xy 81.762301 -249.04481)
			(xy 81.809572 -249.058502) (xy 81.854034 -249.0796) (xy 81.894537 -249.107556) (xy 81.93003 -249.141648)
			(xy 81.959595 -249.180992) (xy 81.982466 -249.224569) (xy 81.99805 -249.27125) (xy 82.005945 -249.319827)
			(xy 82.00644 -249.344434) (xy 82.324697 -249.344434) (xy 82.328792 -249.293706) (xy 82.340971 -249.244292)
			(xy 82.360919 -249.197472) (xy 82.38812 -249.154458) (xy 82.421868 -249.116364) (xy 82.46129 -249.084177)
			(xy 82.505364 -249.058731) (xy 82.55295 -249.040684) (xy 82.602814 -249.030504) (xy 82.653666 -249.028455)
			(xy 82.704187 -249.034589) (xy 82.753071 -249.048749) (xy 82.79905 -249.070566) (xy 82.840934 -249.099476)
			(xy 82.877638 -249.134731) (xy 82.908211 -249.175417) (xy 82.931862 -249.22048) (xy 82.947978 -249.268754)
			(xy 82.956142 -249.318988) (xy 82.956654 -249.344434) (xy 83.275182 -249.344434) (xy 83.279142 -249.29538)
			(xy 83.290919 -249.247596) (xy 83.31021 -249.20232) (xy 83.336513 -249.160724) (xy 83.369148 -249.123887)
			(xy 83.407269 -249.092762) (xy 83.44989 -249.068155) (xy 83.495906 -249.050703) (xy 83.544125 -249.040859)
			(xy 83.5933 -249.038878) (xy 83.642155 -249.04481) (xy 83.689426 -249.058502) (xy 83.733888 -249.0796)
			(xy 83.774391 -249.107556) (xy 83.809884 -249.141648) (xy 83.839449 -249.180992) (xy 83.86232 -249.224569)
			(xy 83.877904 -249.27125) (xy 83.885799 -249.319827) (xy 83.886294 -249.344434) (xy 84.215236 -249.344434)
			(xy 84.219196 -249.29538) (xy 84.230973 -249.247596) (xy 84.250264 -249.20232) (xy 84.276567 -249.160724)
			(xy 84.309202 -249.123887) (xy 84.347323 -249.092762) (xy 84.389944 -249.068155) (xy 84.43596 -249.050703)
			(xy 84.484179 -249.040859) (xy 84.533354 -249.038878) (xy 84.582209 -249.04481) (xy 84.62948 -249.058502)
			(xy 84.673942 -249.0796) (xy 84.714445 -249.107556) (xy 84.749938 -249.141648) (xy 84.779503 -249.180992)
			(xy 84.802374 -249.224569) (xy 84.817958 -249.27125) (xy 84.825853 -249.319827) (xy 84.826348 -249.344434)
			(xy 85.144859 -249.344434) (xy 85.148954 -249.293706) (xy 85.161133 -249.244292) (xy 85.181081 -249.197472)
			(xy 85.208282 -249.154458) (xy 85.24203 -249.116364) (xy 85.281452 -249.084177) (xy 85.325526 -249.058731)
			(xy 85.373112 -249.040684) (xy 85.422976 -249.030504) (xy 85.473828 -249.028455) (xy 85.524349 -249.034589)
			(xy 85.573233 -249.048749) (xy 85.619212 -249.070566) (xy 85.661096 -249.099476) (xy 85.6978 -249.134731)
			(xy 85.728373 -249.175417) (xy 85.752024 -249.22048) (xy 85.76814 -249.268754) (xy 85.776304 -249.318988)
			(xy 85.776816 -249.344434) (xy 86.095344 -249.344434) (xy 86.099304 -249.29538) (xy 86.111081 -249.247596)
			(xy 86.130372 -249.20232) (xy 86.156675 -249.160724) (xy 86.18931 -249.123887) (xy 86.227431 -249.092762)
			(xy 86.270052 -249.068155) (xy 86.316068 -249.050703) (xy 86.364287 -249.040859) (xy 86.413462 -249.038878)
			(xy 86.462317 -249.04481) (xy 86.509588 -249.058502) (xy 86.55405 -249.0796) (xy 86.594553 -249.107556)
			(xy 86.630046 -249.141648) (xy 86.659611 -249.180992) (xy 86.682482 -249.224569) (xy 86.698066 -249.27125)
			(xy 86.705961 -249.319827) (xy 86.706456 -249.344434) (xy 87.035144 -249.344434) (xy 87.039104 -249.29538)
			(xy 87.050881 -249.247596) (xy 87.070172 -249.20232) (xy 87.096475 -249.160724) (xy 87.12911 -249.123887)
			(xy 87.167231 -249.092762) (xy 87.209852 -249.068155) (xy 87.255868 -249.050703) (xy 87.304087 -249.040859)
			(xy 87.353262 -249.038878) (xy 87.402117 -249.04481) (xy 87.449388 -249.058502) (xy 87.49385 -249.0796)
			(xy 87.534353 -249.107556) (xy 87.569846 -249.141648) (xy 87.599411 -249.180992) (xy 87.622282 -249.224569)
			(xy 87.637866 -249.27125) (xy 87.645761 -249.319827) (xy 87.646256 -249.344434) (xy 87.975198 -249.344434)
			(xy 87.979158 -249.29538) (xy 87.990935 -249.247596) (xy 88.010226 -249.20232) (xy 88.036529 -249.160724)
			(xy 88.069164 -249.123887) (xy 88.107285 -249.092762) (xy 88.149906 -249.068155) (xy 88.195922 -249.050703)
			(xy 88.244141 -249.040859) (xy 88.293316 -249.038878) (xy 88.342171 -249.04481) (xy 88.389442 -249.058502)
			(xy 88.433904 -249.0796) (xy 88.474407 -249.107556) (xy 88.5099 -249.141648) (xy 88.539465 -249.180992)
			(xy 88.562336 -249.224569) (xy 88.57792 -249.27125) (xy 88.585815 -249.319827) (xy 88.58631 -249.344434)
			(xy 88.904821 -249.344434) (xy 88.908916 -249.293706) (xy 88.921095 -249.244292) (xy 88.941043 -249.197472)
			(xy 88.968244 -249.154458) (xy 89.001992 -249.116364) (xy 89.041414 -249.084177) (xy 89.085488 -249.058731)
			(xy 89.133074 -249.040684) (xy 89.182938 -249.030504) (xy 89.23379 -249.028455) (xy 89.284311 -249.034589)
			(xy 89.333195 -249.048749) (xy 89.379174 -249.070566) (xy 89.421058 -249.099476) (xy 89.457762 -249.134731)
			(xy 89.488335 -249.175417) (xy 89.511986 -249.22048) (xy 89.528102 -249.268754) (xy 89.536266 -249.318988)
			(xy 89.536778 -249.344434) (xy 89.855306 -249.344434) (xy 89.859266 -249.29538) (xy 89.871043 -249.247596)
			(xy 89.890334 -249.20232) (xy 89.916637 -249.160724) (xy 89.949272 -249.123887) (xy 89.987393 -249.092762)
			(xy 90.030014 -249.068155) (xy 90.07603 -249.050703) (xy 90.124249 -249.040859) (xy 90.173424 -249.038878)
			(xy 90.222279 -249.04481) (xy 90.26955 -249.058502) (xy 90.314012 -249.0796) (xy 90.354515 -249.107556)
			(xy 90.390008 -249.141648) (xy 90.419573 -249.180992) (xy 90.442444 -249.224569) (xy 90.458028 -249.27125)
			(xy 90.465923 -249.319827) (xy 90.466418 -249.344434) (xy 90.795106 -249.344434) (xy 90.799066 -249.29538)
			(xy 90.810843 -249.247596) (xy 90.830134 -249.20232) (xy 90.856437 -249.160724) (xy 90.889072 -249.123887)
			(xy 90.927193 -249.092762) (xy 90.969814 -249.068155) (xy 91.01583 -249.050703) (xy 91.064049 -249.040859)
			(xy 91.113224 -249.038878) (xy 91.162079 -249.04481) (xy 91.20935 -249.058502) (xy 91.253812 -249.0796)
			(xy 91.294315 -249.107556) (xy 91.329808 -249.141648) (xy 91.359373 -249.180992) (xy 91.382244 -249.224569)
			(xy 91.397828 -249.27125) (xy 91.405723 -249.319827) (xy 91.406218 -249.344434) (xy 91.724729 -249.344434)
			(xy 91.728824 -249.293706) (xy 91.741003 -249.244292) (xy 91.760951 -249.197472) (xy 91.788152 -249.154458)
			(xy 91.8219 -249.116364) (xy 91.861322 -249.084177) (xy 91.905396 -249.058731) (xy 91.952982 -249.040684)
			(xy 92.002846 -249.030504) (xy 92.053698 -249.028455) (xy 92.104219 -249.034589) (xy 92.153103 -249.048749)
			(xy 92.199082 -249.070566) (xy 92.240966 -249.099476) (xy 92.27767 -249.134731) (xy 92.308243 -249.175417)
			(xy 92.331894 -249.22048) (xy 92.34801 -249.268754) (xy 92.356174 -249.318988) (xy 92.356686 -249.344434)
			(xy 92.675214 -249.344434) (xy 92.679174 -249.29538) (xy 92.690951 -249.247596) (xy 92.710242 -249.20232)
			(xy 92.736545 -249.160724) (xy 92.76918 -249.123887) (xy 92.807301 -249.092762) (xy 92.849922 -249.068155)
			(xy 92.895938 -249.050703) (xy 92.944157 -249.040859) (xy 92.993332 -249.038878) (xy 93.042187 -249.04481)
			(xy 93.089458 -249.058502) (xy 93.13392 -249.0796) (xy 93.174423 -249.107556) (xy 93.209916 -249.141648)
			(xy 93.239481 -249.180992) (xy 93.262352 -249.224569) (xy 93.277936 -249.27125) (xy 93.285831 -249.319827)
			(xy 93.286326 -249.344434) (xy 93.615268 -249.344434) (xy 93.619228 -249.29538) (xy 93.631005 -249.247596)
			(xy 93.650296 -249.20232) (xy 93.676599 -249.160724) (xy 93.709234 -249.123887) (xy 93.747355 -249.092762)
			(xy 93.789976 -249.068155) (xy 93.835992 -249.050703) (xy 93.884211 -249.040859) (xy 93.933386 -249.038878)
			(xy 93.982241 -249.04481) (xy 94.029512 -249.058502) (xy 94.073974 -249.0796) (xy 94.114477 -249.107556)
			(xy 94.14997 -249.141648) (xy 94.179535 -249.180992) (xy 94.202406 -249.224569) (xy 94.21799 -249.27125)
			(xy 94.225885 -249.319827) (xy 94.22638 -249.344434) (xy 94.555322 -249.344434) (xy 94.559282 -249.29538)
			(xy 94.571059 -249.247596) (xy 94.59035 -249.20232) (xy 94.616653 -249.160724) (xy 94.649288 -249.123887)
			(xy 94.687409 -249.092762) (xy 94.73003 -249.068155) (xy 94.776046 -249.050703) (xy 94.824265 -249.040859)
			(xy 94.87344 -249.038878) (xy 94.922295 -249.04481) (xy 94.969566 -249.058502) (xy 95.014028 -249.0796)
			(xy 95.054531 -249.107556) (xy 95.090024 -249.141648) (xy 95.119589 -249.180992) (xy 95.14246 -249.224569)
			(xy 95.158044 -249.27125) (xy 95.165939 -249.319827) (xy 95.166434 -249.344434) (xy 95.484691 -249.344434)
			(xy 95.488786 -249.293706) (xy 95.500965 -249.244292) (xy 95.520913 -249.197472) (xy 95.548114 -249.154458)
			(xy 95.581862 -249.116364) (xy 95.621284 -249.084177) (xy 95.665358 -249.058731) (xy 95.712944 -249.040684)
			(xy 95.762808 -249.030504) (xy 95.81366 -249.028455) (xy 95.864181 -249.034589) (xy 95.913065 -249.048749)
			(xy 95.959044 -249.070566) (xy 96.000928 -249.099476) (xy 96.037632 -249.134731) (xy 96.068205 -249.175417)
			(xy 96.091856 -249.22048) (xy 96.107972 -249.268754) (xy 96.116136 -249.318988) (xy 96.116648 -249.344434)
			(xy 96.435176 -249.344434) (xy 96.439136 -249.29538) (xy 96.450913 -249.247596) (xy 96.470204 -249.20232)
			(xy 96.496507 -249.160724) (xy 96.529142 -249.123887) (xy 96.567263 -249.092762) (xy 96.609884 -249.068155)
			(xy 96.6559 -249.050703) (xy 96.704119 -249.040859) (xy 96.753294 -249.038878) (xy 96.802149 -249.04481)
			(xy 96.84942 -249.058502) (xy 96.893882 -249.0796) (xy 96.934385 -249.107556) (xy 96.969878 -249.141648)
			(xy 96.999443 -249.180992) (xy 97.022314 -249.224569) (xy 97.037898 -249.27125) (xy 97.045793 -249.319827)
			(xy 97.046288 -249.344434) (xy 97.37523 -249.344434) (xy 97.37919 -249.29538) (xy 97.390967 -249.247596)
			(xy 97.410258 -249.20232) (xy 97.436561 -249.160724) (xy 97.469196 -249.123887) (xy 97.507317 -249.092762)
			(xy 97.549938 -249.068155) (xy 97.595954 -249.050703) (xy 97.644173 -249.040859) (xy 97.693348 -249.038878)
			(xy 97.742203 -249.04481) (xy 97.789474 -249.058502) (xy 97.833936 -249.0796) (xy 97.874439 -249.107556)
			(xy 97.909932 -249.141648) (xy 97.939497 -249.180992) (xy 97.962368 -249.224569) (xy 97.977952 -249.27125)
			(xy 97.985847 -249.319827) (xy 97.986342 -249.344434) (xy 98.315284 -249.344434) (xy 98.319244 -249.29538)
			(xy 98.331021 -249.247596) (xy 98.350312 -249.20232) (xy 98.376615 -249.160724) (xy 98.40925 -249.123887)
			(xy 98.447371 -249.092762) (xy 98.489992 -249.068155) (xy 98.536008 -249.050703) (xy 98.584227 -249.040859)
			(xy 98.633402 -249.038878) (xy 98.682257 -249.04481) (xy 98.729528 -249.058502) (xy 98.77399 -249.0796)
			(xy 98.814493 -249.107556) (xy 98.849986 -249.141648) (xy 98.879551 -249.180992) (xy 98.902422 -249.224569)
			(xy 98.918006 -249.27125) (xy 98.925901 -249.319827) (xy 98.926396 -249.344434) (xy 99.255338 -249.344434)
			(xy 99.259298 -249.29538) (xy 99.271075 -249.247596) (xy 99.290366 -249.20232) (xy 99.316669 -249.160724)
			(xy 99.349304 -249.123887) (xy 99.387425 -249.092762) (xy 99.430046 -249.068155) (xy 99.476062 -249.050703)
			(xy 99.524281 -249.040859) (xy 99.573456 -249.038878) (xy 99.622311 -249.04481) (xy 99.669582 -249.058502)
			(xy 99.714044 -249.0796) (xy 99.754547 -249.107556) (xy 99.79004 -249.141648) (xy 99.819605 -249.180992)
			(xy 99.842476 -249.224569) (xy 99.85806 -249.27125) (xy 99.865955 -249.319827) (xy 99.86645 -249.344434)
			(xy 101.135192 -249.344434) (xy 101.139152 -249.29538) (xy 101.150929 -249.247596) (xy 101.17022 -249.20232)
			(xy 101.196523 -249.160724) (xy 101.229158 -249.123887) (xy 101.267279 -249.092762) (xy 101.3099 -249.068155)
			(xy 101.355916 -249.050703) (xy 101.404135 -249.040859) (xy 101.45331 -249.038878) (xy 101.502165 -249.04481)
			(xy 101.549436 -249.058502) (xy 101.593898 -249.0796) (xy 101.634401 -249.107556) (xy 101.669894 -249.141648)
			(xy 101.699459 -249.180992) (xy 101.72233 -249.224569) (xy 101.737914 -249.27125) (xy 101.745809 -249.319827)
			(xy 101.746304 -249.344434) (xy 103.0153 -249.344434) (xy 103.01926 -249.29538) (xy 103.031037 -249.247596)
			(xy 103.050328 -249.20232) (xy 103.076631 -249.160724) (xy 103.109266 -249.123887) (xy 103.147387 -249.092762)
			(xy 103.190008 -249.068155) (xy 103.236024 -249.050703) (xy 103.284243 -249.040859) (xy 103.333418 -249.038878)
			(xy 103.382273 -249.04481) (xy 103.429544 -249.058502) (xy 103.474006 -249.0796) (xy 103.514509 -249.107556)
			(xy 103.550002 -249.141648) (xy 103.579567 -249.180992) (xy 103.602438 -249.224569) (xy 103.618022 -249.27125)
			(xy 103.625917 -249.319827) (xy 103.626412 -249.344434) (xy 104.895154 -249.344434) (xy 104.899114 -249.29538)
			(xy 104.910891 -249.247596) (xy 104.930182 -249.20232) (xy 104.956485 -249.160724) (xy 104.98912 -249.123887)
			(xy 105.027241 -249.092762) (xy 105.069862 -249.068155) (xy 105.115878 -249.050703) (xy 105.164097 -249.040859)
			(xy 105.213272 -249.038878) (xy 105.262127 -249.04481) (xy 105.309398 -249.058502) (xy 105.35386 -249.0796)
			(xy 105.394363 -249.107556) (xy 105.429856 -249.141648) (xy 105.459421 -249.180992) (xy 105.482292 -249.224569)
			(xy 105.497876 -249.27125) (xy 105.505771 -249.319827) (xy 105.506266 -249.344434) (xy 106.775262 -249.344434)
			(xy 106.779222 -249.29538) (xy 106.790999 -249.247596) (xy 106.81029 -249.20232) (xy 106.836593 -249.160724)
			(xy 106.869228 -249.123887) (xy 106.907349 -249.092762) (xy 106.94997 -249.068155) (xy 106.995986 -249.050703)
			(xy 107.044205 -249.040859) (xy 107.09338 -249.038878) (xy 107.142235 -249.04481) (xy 107.189506 -249.058502)
			(xy 107.233968 -249.0796) (xy 107.274471 -249.107556) (xy 107.309964 -249.141648) (xy 107.339529 -249.180992)
			(xy 107.3624 -249.224569) (xy 107.377984 -249.27125) (xy 107.385879 -249.319827) (xy 107.386374 -249.344434)
			(xy 108.65537 -249.344434) (xy 108.65933 -249.29538) (xy 108.671107 -249.247596) (xy 108.690398 -249.20232)
			(xy 108.716701 -249.160724) (xy 108.749336 -249.123887) (xy 108.787457 -249.092762) (xy 108.830078 -249.068155)
			(xy 108.876094 -249.050703) (xy 108.924313 -249.040859) (xy 108.973488 -249.038878) (xy 109.022343 -249.04481)
			(xy 109.069614 -249.058502) (xy 109.114076 -249.0796) (xy 109.154579 -249.107556) (xy 109.190072 -249.141648)
			(xy 109.219637 -249.180992) (xy 109.242508 -249.224569) (xy 109.258092 -249.27125) (xy 109.265987 -249.319827)
			(xy 109.266482 -249.344434) (xy 109.266124 -249.362214) (xy 111.456473 -249.362214) (xy 111.460503 -249.309716)
			(xy 111.4725 -249.258448) (xy 111.492183 -249.209613) (xy 111.519089 -249.164354) (xy 111.552589 -249.123733)
			(xy 111.591897 -249.088702) (xy 111.636092 -249.060082) (xy 111.684137 -249.038543) (xy 111.734908 -249.024591)
			(xy 111.787213 -249.018553) (xy 111.839827 -249.02057) (xy 111.891517 -249.030594) (xy 111.94107 -249.048392)
			(xy 111.987326 -249.073545) (xy 112.0292 -249.105464) (xy 112.065712 -249.143402) (xy 112.096004 -249.186468)
			(xy 112.119367 -249.233653) (xy 112.135253 -249.283852) (xy 112.14329 -249.335888) (xy 112.143794 -249.362214)
			(xy 112.14329 -249.38854) (xy 112.135253 -249.440576) (xy 112.119367 -249.490775) (xy 112.096004 -249.53796)
			(xy 112.065712 -249.581026) (xy 112.0292 -249.618964) (xy 111.987326 -249.650883) (xy 111.94107 -249.676036)
			(xy 111.891517 -249.693834) (xy 111.839827 -249.703858) (xy 111.787213 -249.705875) (xy 111.734908 -249.699837)
			(xy 111.684137 -249.685885) (xy 111.636092 -249.664346) (xy 111.591897 -249.635726) (xy 111.552589 -249.600695)
			(xy 111.519089 -249.560074) (xy 111.492183 -249.514815) (xy 111.4725 -249.46598) (xy 111.460503 -249.414712)
			(xy 111.456473 -249.362214) (xy 109.266124 -249.362214) (xy 109.265987 -249.369041) (xy 109.258092 -249.417618)
			(xy 109.242508 -249.464299) (xy 109.219637 -249.507876) (xy 109.190072 -249.54722) (xy 109.154579 -249.581312)
			(xy 109.114076 -249.609268) (xy 109.069614 -249.630366) (xy 109.022343 -249.644058) (xy 108.973488 -249.64999)
			(xy 108.924313 -249.648009) (xy 108.876094 -249.638165) (xy 108.830078 -249.620713) (xy 108.787457 -249.596106)
			(xy 108.749336 -249.564981) (xy 108.716701 -249.528144) (xy 108.690398 -249.486548) (xy 108.671107 -249.441272)
			(xy 108.65933 -249.393488) (xy 108.65537 -249.344434) (xy 107.386374 -249.344434) (xy 107.385879 -249.369041)
			(xy 107.377984 -249.417618) (xy 107.3624 -249.464299) (xy 107.339529 -249.507876) (xy 107.309964 -249.54722)
			(xy 107.274471 -249.581312) (xy 107.233968 -249.609268) (xy 107.189506 -249.630366) (xy 107.142235 -249.644058)
			(xy 107.09338 -249.64999) (xy 107.044205 -249.648009) (xy 106.995986 -249.638165) (xy 106.94997 -249.620713)
			(xy 106.907349 -249.596106) (xy 106.869228 -249.564981) (xy 106.836593 -249.528144) (xy 106.81029 -249.486548)
			(xy 106.790999 -249.441272) (xy 106.779222 -249.393488) (xy 106.775262 -249.344434) (xy 105.506266 -249.344434)
			(xy 105.505771 -249.369041) (xy 105.497876 -249.417618) (xy 105.482292 -249.464299) (xy 105.459421 -249.507876)
			(xy 105.429856 -249.54722) (xy 105.394363 -249.581312) (xy 105.35386 -249.609268) (xy 105.309398 -249.630366)
			(xy 105.262127 -249.644058) (xy 105.213272 -249.64999) (xy 105.164097 -249.648009) (xy 105.115878 -249.638165)
			(xy 105.069862 -249.620713) (xy 105.027241 -249.596106) (xy 104.98912 -249.564981) (xy 104.956485 -249.528144)
			(xy 104.930182 -249.486548) (xy 104.910891 -249.441272) (xy 104.899114 -249.393488) (xy 104.895154 -249.344434)
			(xy 103.626412 -249.344434) (xy 103.625917 -249.369041) (xy 103.618022 -249.417618) (xy 103.602438 -249.464299)
			(xy 103.579567 -249.507876) (xy 103.550002 -249.54722) (xy 103.514509 -249.581312) (xy 103.474006 -249.609268)
			(xy 103.429544 -249.630366) (xy 103.382273 -249.644058) (xy 103.333418 -249.64999) (xy 103.284243 -249.648009)
			(xy 103.236024 -249.638165) (xy 103.190008 -249.620713) (xy 103.147387 -249.596106) (xy 103.109266 -249.564981)
			(xy 103.076631 -249.528144) (xy 103.050328 -249.486548) (xy 103.031037 -249.441272) (xy 103.01926 -249.393488)
			(xy 103.0153 -249.344434) (xy 101.746304 -249.344434) (xy 101.745809 -249.369041) (xy 101.737914 -249.417618)
			(xy 101.72233 -249.464299) (xy 101.699459 -249.507876) (xy 101.669894 -249.54722) (xy 101.634401 -249.581312)
			(xy 101.593898 -249.609268) (xy 101.549436 -249.630366) (xy 101.502165 -249.644058) (xy 101.45331 -249.64999)
			(xy 101.404135 -249.648009) (xy 101.355916 -249.638165) (xy 101.3099 -249.620713) (xy 101.267279 -249.596106)
			(xy 101.229158 -249.564981) (xy 101.196523 -249.528144) (xy 101.17022 -249.486548) (xy 101.150929 -249.441272)
			(xy 101.139152 -249.393488) (xy 101.135192 -249.344434) (xy 99.86645 -249.344434) (xy 99.865955 -249.369041)
			(xy 99.85806 -249.417618) (xy 99.842476 -249.464299) (xy 99.819605 -249.507876) (xy 99.79004 -249.54722)
			(xy 99.754547 -249.581312) (xy 99.714044 -249.609268) (xy 99.669582 -249.630366) (xy 99.622311 -249.644058)
			(xy 99.573456 -249.64999) (xy 99.524281 -249.648009) (xy 99.476062 -249.638165) (xy 99.430046 -249.620713)
			(xy 99.387425 -249.596106) (xy 99.349304 -249.564981) (xy 99.316669 -249.528144) (xy 99.290366 -249.486548)
			(xy 99.271075 -249.441272) (xy 99.259298 -249.393488) (xy 99.255338 -249.344434) (xy 98.926396 -249.344434)
			(xy 98.925901 -249.369041) (xy 98.918006 -249.417618) (xy 98.902422 -249.464299) (xy 98.879551 -249.507876)
			(xy 98.849986 -249.54722) (xy 98.814493 -249.581312) (xy 98.77399 -249.609268) (xy 98.729528 -249.630366)
			(xy 98.682257 -249.644058) (xy 98.633402 -249.64999) (xy 98.584227 -249.648009) (xy 98.536008 -249.638165)
			(xy 98.489992 -249.620713) (xy 98.447371 -249.596106) (xy 98.40925 -249.564981) (xy 98.376615 -249.528144)
			(xy 98.350312 -249.486548) (xy 98.331021 -249.441272) (xy 98.319244 -249.393488) (xy 98.315284 -249.344434)
			(xy 97.986342 -249.344434) (xy 97.985847 -249.369041) (xy 97.977952 -249.417618) (xy 97.962368 -249.464299)
			(xy 97.939497 -249.507876) (xy 97.909932 -249.54722) (xy 97.874439 -249.581312) (xy 97.833936 -249.609268)
			(xy 97.789474 -249.630366) (xy 97.742203 -249.644058) (xy 97.693348 -249.64999) (xy 97.644173 -249.648009)
			(xy 97.595954 -249.638165) (xy 97.549938 -249.620713) (xy 97.507317 -249.596106) (xy 97.469196 -249.564981)
			(xy 97.436561 -249.528144) (xy 97.410258 -249.486548) (xy 97.390967 -249.441272) (xy 97.37919 -249.393488)
			(xy 97.37523 -249.344434) (xy 97.046288 -249.344434) (xy 97.045793 -249.369041) (xy 97.037898 -249.417618)
			(xy 97.022314 -249.464299) (xy 96.999443 -249.507876) (xy 96.969878 -249.54722) (xy 96.934385 -249.581312)
			(xy 96.893882 -249.609268) (xy 96.84942 -249.630366) (xy 96.802149 -249.644058) (xy 96.753294 -249.64999)
			(xy 96.704119 -249.648009) (xy 96.6559 -249.638165) (xy 96.609884 -249.620713) (xy 96.567263 -249.596106)
			(xy 96.529142 -249.564981) (xy 96.496507 -249.528144) (xy 96.470204 -249.486548) (xy 96.450913 -249.441272)
			(xy 96.439136 -249.393488) (xy 96.435176 -249.344434) (xy 96.116648 -249.344434) (xy 96.116136 -249.36988)
			(xy 96.107972 -249.420114) (xy 96.091856 -249.468388) (xy 96.068205 -249.513451) (xy 96.037632 -249.554137)
			(xy 96.000928 -249.589392) (xy 95.959044 -249.618302) (xy 95.913065 -249.640119) (xy 95.864181 -249.654279)
			(xy 95.81366 -249.660413) (xy 95.762808 -249.658364) (xy 95.712944 -249.648184) (xy 95.665358 -249.630137)
			(xy 95.621284 -249.604691) (xy 95.581862 -249.572504) (xy 95.548114 -249.53441) (xy 95.520913 -249.491396)
			(xy 95.500965 -249.444576) (xy 95.488786 -249.395162) (xy 95.484691 -249.344434) (xy 95.166434 -249.344434)
			(xy 95.165939 -249.369041) (xy 95.158044 -249.417618) (xy 95.14246 -249.464299) (xy 95.119589 -249.507876)
			(xy 95.090024 -249.54722) (xy 95.054531 -249.581312) (xy 95.014028 -249.609268) (xy 94.969566 -249.630366)
			(xy 94.922295 -249.644058) (xy 94.87344 -249.64999) (xy 94.824265 -249.648009) (xy 94.776046 -249.638165)
			(xy 94.73003 -249.620713) (xy 94.687409 -249.596106) (xy 94.649288 -249.564981) (xy 94.616653 -249.528144)
			(xy 94.59035 -249.486548) (xy 94.571059 -249.441272) (xy 94.559282 -249.393488) (xy 94.555322 -249.344434)
			(xy 94.22638 -249.344434) (xy 94.225885 -249.369041) (xy 94.21799 -249.417618) (xy 94.202406 -249.464299)
			(xy 94.179535 -249.507876) (xy 94.14997 -249.54722) (xy 94.114477 -249.581312) (xy 94.073974 -249.609268)
			(xy 94.029512 -249.630366) (xy 93.982241 -249.644058) (xy 93.933386 -249.64999) (xy 93.884211 -249.648009)
			(xy 93.835992 -249.638165) (xy 93.789976 -249.620713) (xy 93.747355 -249.596106) (xy 93.709234 -249.564981)
			(xy 93.676599 -249.528144) (xy 93.650296 -249.486548) (xy 93.631005 -249.441272) (xy 93.619228 -249.393488)
			(xy 93.615268 -249.344434) (xy 93.286326 -249.344434) (xy 93.285831 -249.369041) (xy 93.277936 -249.417618)
			(xy 93.262352 -249.464299) (xy 93.239481 -249.507876) (xy 93.209916 -249.54722) (xy 93.174423 -249.581312)
			(xy 93.13392 -249.609268) (xy 93.089458 -249.630366) (xy 93.042187 -249.644058) (xy 92.993332 -249.64999)
			(xy 92.944157 -249.648009) (xy 92.895938 -249.638165) (xy 92.849922 -249.620713) (xy 92.807301 -249.596106)
			(xy 92.76918 -249.564981) (xy 92.736545 -249.528144) (xy 92.710242 -249.486548) (xy 92.690951 -249.441272)
			(xy 92.679174 -249.393488) (xy 92.675214 -249.344434) (xy 92.356686 -249.344434) (xy 92.356174 -249.36988)
			(xy 92.34801 -249.420114) (xy 92.331894 -249.468388) (xy 92.308243 -249.513451) (xy 92.27767 -249.554137)
			(xy 92.240966 -249.589392) (xy 92.199082 -249.618302) (xy 92.153103 -249.640119) (xy 92.104219 -249.654279)
			(xy 92.053698 -249.660413) (xy 92.002846 -249.658364) (xy 91.952982 -249.648184) (xy 91.905396 -249.630137)
			(xy 91.861322 -249.604691) (xy 91.8219 -249.572504) (xy 91.788152 -249.53441) (xy 91.760951 -249.491396)
			(xy 91.741003 -249.444576) (xy 91.728824 -249.395162) (xy 91.724729 -249.344434) (xy 91.406218 -249.344434)
			(xy 91.405723 -249.369041) (xy 91.397828 -249.417618) (xy 91.382244 -249.464299) (xy 91.359373 -249.507876)
			(xy 91.329808 -249.54722) (xy 91.294315 -249.581312) (xy 91.253812 -249.609268) (xy 91.20935 -249.630366)
			(xy 91.162079 -249.644058) (xy 91.113224 -249.64999) (xy 91.064049 -249.648009) (xy 91.01583 -249.638165)
			(xy 90.969814 -249.620713) (xy 90.927193 -249.596106) (xy 90.889072 -249.564981) (xy 90.856437 -249.528144)
			(xy 90.830134 -249.486548) (xy 90.810843 -249.441272) (xy 90.799066 -249.393488) (xy 90.795106 -249.344434)
			(xy 90.466418 -249.344434) (xy 90.465923 -249.369041) (xy 90.458028 -249.417618) (xy 90.442444 -249.464299)
			(xy 90.419573 -249.507876) (xy 90.390008 -249.54722) (xy 90.354515 -249.581312) (xy 90.314012 -249.609268)
			(xy 90.26955 -249.630366) (xy 90.222279 -249.644058) (xy 90.173424 -249.64999) (xy 90.124249 -249.648009)
			(xy 90.07603 -249.638165) (xy 90.030014 -249.620713) (xy 89.987393 -249.596106) (xy 89.949272 -249.564981)
			(xy 89.916637 -249.528144) (xy 89.890334 -249.486548) (xy 89.871043 -249.441272) (xy 89.859266 -249.393488)
			(xy 89.855306 -249.344434) (xy 89.536778 -249.344434) (xy 89.536266 -249.36988) (xy 89.528102 -249.420114)
			(xy 89.511986 -249.468388) (xy 89.488335 -249.513451) (xy 89.457762 -249.554137) (xy 89.421058 -249.589392)
			(xy 89.379174 -249.618302) (xy 89.333195 -249.640119) (xy 89.284311 -249.654279) (xy 89.23379 -249.660413)
			(xy 89.182938 -249.658364) (xy 89.133074 -249.648184) (xy 89.085488 -249.630137) (xy 89.041414 -249.604691)
			(xy 89.001992 -249.572504) (xy 88.968244 -249.53441) (xy 88.941043 -249.491396) (xy 88.921095 -249.444576)
			(xy 88.908916 -249.395162) (xy 88.904821 -249.344434) (xy 88.58631 -249.344434) (xy 88.585815 -249.369041)
			(xy 88.57792 -249.417618) (xy 88.562336 -249.464299) (xy 88.539465 -249.507876) (xy 88.5099 -249.54722)
			(xy 88.474407 -249.581312) (xy 88.433904 -249.609268) (xy 88.389442 -249.630366) (xy 88.342171 -249.644058)
			(xy 88.293316 -249.64999) (xy 88.244141 -249.648009) (xy 88.195922 -249.638165) (xy 88.149906 -249.620713)
			(xy 88.107285 -249.596106) (xy 88.069164 -249.564981) (xy 88.036529 -249.528144) (xy 88.010226 -249.486548)
			(xy 87.990935 -249.441272) (xy 87.979158 -249.393488) (xy 87.975198 -249.344434) (xy 87.646256 -249.344434)
			(xy 87.645761 -249.369041) (xy 87.637866 -249.417618) (xy 87.622282 -249.464299) (xy 87.599411 -249.507876)
			(xy 87.569846 -249.54722) (xy 87.534353 -249.581312) (xy 87.49385 -249.609268) (xy 87.449388 -249.630366)
			(xy 87.402117 -249.644058) (xy 87.353262 -249.64999) (xy 87.304087 -249.648009) (xy 87.255868 -249.638165)
			(xy 87.209852 -249.620713) (xy 87.167231 -249.596106) (xy 87.12911 -249.564981) (xy 87.096475 -249.528144)
			(xy 87.070172 -249.486548) (xy 87.050881 -249.441272) (xy 87.039104 -249.393488) (xy 87.035144 -249.344434)
			(xy 86.706456 -249.344434) (xy 86.705961 -249.369041) (xy 86.698066 -249.417618) (xy 86.682482 -249.464299)
			(xy 86.659611 -249.507876) (xy 86.630046 -249.54722) (xy 86.594553 -249.581312) (xy 86.55405 -249.609268)
			(xy 86.509588 -249.630366) (xy 86.462317 -249.644058) (xy 86.413462 -249.64999) (xy 86.364287 -249.648009)
			(xy 86.316068 -249.638165) (xy 86.270052 -249.620713) (xy 86.227431 -249.596106) (xy 86.18931 -249.564981)
			(xy 86.156675 -249.528144) (xy 86.130372 -249.486548) (xy 86.111081 -249.441272) (xy 86.099304 -249.393488)
			(xy 86.095344 -249.344434) (xy 85.776816 -249.344434) (xy 85.776304 -249.36988) (xy 85.76814 -249.420114)
			(xy 85.752024 -249.468388) (xy 85.728373 -249.513451) (xy 85.6978 -249.554137) (xy 85.661096 -249.589392)
			(xy 85.619212 -249.618302) (xy 85.573233 -249.640119) (xy 85.524349 -249.654279) (xy 85.473828 -249.660413)
			(xy 85.422976 -249.658364) (xy 85.373112 -249.648184) (xy 85.325526 -249.630137) (xy 85.281452 -249.604691)
			(xy 85.24203 -249.572504) (xy 85.208282 -249.53441) (xy 85.181081 -249.491396) (xy 85.161133 -249.444576)
			(xy 85.148954 -249.395162) (xy 85.144859 -249.344434) (xy 84.826348 -249.344434) (xy 84.825853 -249.369041)
			(xy 84.817958 -249.417618) (xy 84.802374 -249.464299) (xy 84.779503 -249.507876) (xy 84.749938 -249.54722)
			(xy 84.714445 -249.581312) (xy 84.673942 -249.609268) (xy 84.62948 -249.630366) (xy 84.582209 -249.644058)
			(xy 84.533354 -249.64999) (xy 84.484179 -249.648009) (xy 84.43596 -249.638165) (xy 84.389944 -249.620713)
			(xy 84.347323 -249.596106) (xy 84.309202 -249.564981) (xy 84.276567 -249.528144) (xy 84.250264 -249.486548)
			(xy 84.230973 -249.441272) (xy 84.219196 -249.393488) (xy 84.215236 -249.344434) (xy 83.886294 -249.344434)
			(xy 83.885799 -249.369041) (xy 83.877904 -249.417618) (xy 83.86232 -249.464299) (xy 83.839449 -249.507876)
			(xy 83.809884 -249.54722) (xy 83.774391 -249.581312) (xy 83.733888 -249.609268) (xy 83.689426 -249.630366)
			(xy 83.642155 -249.644058) (xy 83.5933 -249.64999) (xy 83.544125 -249.648009) (xy 83.495906 -249.638165)
			(xy 83.44989 -249.620713) (xy 83.407269 -249.596106) (xy 83.369148 -249.564981) (xy 83.336513 -249.528144)
			(xy 83.31021 -249.486548) (xy 83.290919 -249.441272) (xy 83.279142 -249.393488) (xy 83.275182 -249.344434)
			(xy 82.956654 -249.344434) (xy 82.956142 -249.36988) (xy 82.947978 -249.420114) (xy 82.931862 -249.468388)
			(xy 82.908211 -249.513451) (xy 82.877638 -249.554137) (xy 82.840934 -249.589392) (xy 82.79905 -249.618302)
			(xy 82.753071 -249.640119) (xy 82.704187 -249.654279) (xy 82.653666 -249.660413) (xy 82.602814 -249.658364)
			(xy 82.55295 -249.648184) (xy 82.505364 -249.630137) (xy 82.46129 -249.604691) (xy 82.421868 -249.572504)
			(xy 82.38812 -249.53441) (xy 82.360919 -249.491396) (xy 82.340971 -249.444576) (xy 82.328792 -249.395162)
			(xy 82.324697 -249.344434) (xy 82.00644 -249.344434) (xy 82.005945 -249.369041) (xy 81.99805 -249.417618)
			(xy 81.982466 -249.464299) (xy 81.959595 -249.507876) (xy 81.93003 -249.54722) (xy 81.894537 -249.581312)
			(xy 81.854034 -249.609268) (xy 81.809572 -249.630366) (xy 81.762301 -249.644058) (xy 81.713446 -249.64999)
			(xy 81.664271 -249.648009) (xy 81.616052 -249.638165) (xy 81.570036 -249.620713) (xy 81.527415 -249.596106)
			(xy 81.489294 -249.564981) (xy 81.456659 -249.528144) (xy 81.430356 -249.486548) (xy 81.411065 -249.441272)
			(xy 81.399288 -249.393488) (xy 81.395328 -249.344434) (xy 81.066386 -249.344434) (xy 81.065891 -249.369041)
			(xy 81.057996 -249.417618) (xy 81.042412 -249.464299) (xy 81.019541 -249.507876) (xy 80.989976 -249.54722)
			(xy 80.954483 -249.581312) (xy 80.91398 -249.609268) (xy 80.869518 -249.630366) (xy 80.822247 -249.644058)
			(xy 80.773392 -249.64999) (xy 80.724217 -249.648009) (xy 80.675998 -249.638165) (xy 80.629982 -249.620713)
			(xy 80.587361 -249.596106) (xy 80.54924 -249.564981) (xy 80.516605 -249.528144) (xy 80.490302 -249.486548)
			(xy 80.471011 -249.441272) (xy 80.459234 -249.393488) (xy 80.455274 -249.344434) (xy 80.126332 -249.344434)
			(xy 80.125837 -249.369041) (xy 80.117942 -249.417618) (xy 80.102358 -249.464299) (xy 80.079487 -249.507876)
			(xy 80.049922 -249.54722) (xy 80.014429 -249.581312) (xy 79.973926 -249.609268) (xy 79.929464 -249.630366)
			(xy 79.882193 -249.644058) (xy 79.833338 -249.64999) (xy 79.784163 -249.648009) (xy 79.735944 -249.638165)
			(xy 79.689928 -249.620713) (xy 79.647307 -249.596106) (xy 79.609186 -249.564981) (xy 79.576551 -249.528144)
			(xy 79.550248 -249.486548) (xy 79.530957 -249.441272) (xy 79.51918 -249.393488) (xy 79.51522 -249.344434)
			(xy 76.963477 -249.344434) (xy 76.965804 -249.345538) (xy 77.006307 -249.373494) (xy 77.0418 -249.407586)
			(xy 77.071365 -249.44693) (xy 77.094236 -249.490507) (xy 77.10982 -249.537188) (xy 77.117715 -249.585765)
			(xy 77.11821 -249.610372) (xy 77.117715 -249.634979) (xy 77.10982 -249.683556) (xy 77.094236 -249.730237)
			(xy 77.071365 -249.773814) (xy 77.0418 -249.813158) (xy 77.006307 -249.84725) (xy 76.965804 -249.875206)
			(xy 76.921342 -249.896304) (xy 76.874071 -249.909996) (xy 76.825216 -249.915928) (xy 76.776041 -249.913947)
			(xy 76.727822 -249.904103) (xy 76.681806 -249.886651) (xy 76.639185 -249.862044) (xy 76.601064 -249.830919)
			(xy 76.568429 -249.794082) (xy 76.542126 -249.752486) (xy 76.522835 -249.70721) (xy 76.511058 -249.659426)
			(xy 76.507098 -249.610372) (xy 66.65214 -249.610372) (xy 67.196208 -250.15444) (xy 78.105266 -250.15444)
			(xy 78.109226 -250.105386) (xy 78.121003 -250.057602) (xy 78.140294 -250.012326) (xy 78.166597 -249.97073)
			(xy 78.199232 -249.933893) (xy 78.237353 -249.902768) (xy 78.279974 -249.878161) (xy 78.32599 -249.860709)
			(xy 78.374209 -249.850865) (xy 78.423384 -249.848884) (xy 78.472239 -249.854816) (xy 78.51951 -249.868508)
			(xy 78.563972 -249.889606) (xy 78.604475 -249.917562) (xy 78.639968 -249.951654) (xy 78.669533 -249.990998)
			(xy 78.692404 -250.034575) (xy 78.707988 -250.081256) (xy 78.715883 -250.129833) (xy 78.716378 -250.15444)
			(xy 79.04532 -250.15444) (xy 79.04928 -250.105386) (xy 79.061057 -250.057602) (xy 79.080348 -250.012326)
			(xy 79.106651 -249.97073) (xy 79.139286 -249.933893) (xy 79.177407 -249.902768) (xy 79.220028 -249.878161)
			(xy 79.266044 -249.860709) (xy 79.314263 -249.850865) (xy 79.363438 -249.848884) (xy 79.412293 -249.854816)
			(xy 79.459564 -249.868508) (xy 79.504026 -249.889606) (xy 79.544529 -249.917562) (xy 79.580022 -249.951654)
			(xy 79.609587 -249.990998) (xy 79.632458 -250.034575) (xy 79.648042 -250.081256) (xy 79.655937 -250.129833)
			(xy 79.656432 -250.15444) (xy 79.985374 -250.15444) (xy 79.989334 -250.105386) (xy 80.001111 -250.057602)
			(xy 80.020402 -250.012326) (xy 80.046705 -249.97073) (xy 80.07934 -249.933893) (xy 80.117461 -249.902768)
			(xy 80.160082 -249.878161) (xy 80.206098 -249.860709) (xy 80.254317 -249.850865) (xy 80.303492 -249.848884)
			(xy 80.352347 -249.854816) (xy 80.399618 -249.868508) (xy 80.44408 -249.889606) (xy 80.484583 -249.917562)
			(xy 80.520076 -249.951654) (xy 80.549641 -249.990998) (xy 80.572512 -250.034575) (xy 80.588096 -250.081256)
			(xy 80.595991 -250.129833) (xy 80.596486 -250.15444) (xy 80.925174 -250.15444) (xy 80.929134 -250.105386)
			(xy 80.940911 -250.057602) (xy 80.960202 -250.012326) (xy 80.986505 -249.97073) (xy 81.01914 -249.933893)
			(xy 81.057261 -249.902768) (xy 81.099882 -249.878161) (xy 81.145898 -249.860709) (xy 81.194117 -249.850865)
			(xy 81.243292 -249.848884) (xy 81.292147 -249.854816) (xy 81.339418 -249.868508) (xy 81.38388 -249.889606)
			(xy 81.424383 -249.917562) (xy 81.459876 -249.951654) (xy 81.489441 -249.990998) (xy 81.512312 -250.034575)
			(xy 81.527896 -250.081256) (xy 81.535791 -250.129833) (xy 81.536286 -250.15444) (xy 81.854797 -250.15444)
			(xy 81.858892 -250.103712) (xy 81.871071 -250.054298) (xy 81.891019 -250.007478) (xy 81.91822 -249.964464)
			(xy 81.951968 -249.92637) (xy 81.99139 -249.894183) (xy 82.035464 -249.868737) (xy 82.08305 -249.85069)
			(xy 82.132914 -249.84051) (xy 82.183766 -249.838461) (xy 82.234287 -249.844595) (xy 82.283171 -249.858755)
			(xy 82.32915 -249.880572) (xy 82.371034 -249.909482) (xy 82.407738 -249.944737) (xy 82.438311 -249.985423)
			(xy 82.461962 -250.030486) (xy 82.478078 -250.07876) (xy 82.486242 -250.128994) (xy 82.486754 -250.15444)
			(xy 82.805282 -250.15444) (xy 82.809242 -250.105386) (xy 82.821019 -250.057602) (xy 82.84031 -250.012326)
			(xy 82.866613 -249.97073) (xy 82.899248 -249.933893) (xy 82.937369 -249.902768) (xy 82.97999 -249.878161)
			(xy 83.026006 -249.860709) (xy 83.074225 -249.850865) (xy 83.1234 -249.848884) (xy 83.172255 -249.854816)
			(xy 83.219526 -249.868508) (xy 83.263988 -249.889606) (xy 83.304491 -249.917562) (xy 83.339984 -249.951654)
			(xy 83.369549 -249.990998) (xy 83.39242 -250.034575) (xy 83.408004 -250.081256) (xy 83.415899 -250.129833)
			(xy 83.416394 -250.15444) (xy 83.745336 -250.15444) (xy 83.749296 -250.105386) (xy 83.761073 -250.057602)
			(xy 83.780364 -250.012326) (xy 83.806667 -249.97073) (xy 83.839302 -249.933893) (xy 83.877423 -249.902768)
			(xy 83.920044 -249.878161) (xy 83.96606 -249.860709) (xy 84.014279 -249.850865) (xy 84.063454 -249.848884)
			(xy 84.112309 -249.854816) (xy 84.15958 -249.868508) (xy 84.204042 -249.889606) (xy 84.244545 -249.917562)
			(xy 84.280038 -249.951654) (xy 84.309603 -249.990998) (xy 84.332474 -250.034575) (xy 84.348058 -250.081256)
			(xy 84.355953 -250.129833) (xy 84.356448 -250.15444) (xy 84.685136 -250.15444) (xy 84.689096 -250.105386)
			(xy 84.700873 -250.057602) (xy 84.720164 -250.012326) (xy 84.746467 -249.97073) (xy 84.779102 -249.933893)
			(xy 84.817223 -249.902768) (xy 84.859844 -249.878161) (xy 84.90586 -249.860709) (xy 84.954079 -249.850865)
			(xy 85.003254 -249.848884) (xy 85.052109 -249.854816) (xy 85.09938 -249.868508) (xy 85.143842 -249.889606)
			(xy 85.184345 -249.917562) (xy 85.219838 -249.951654) (xy 85.249403 -249.990998) (xy 85.272274 -250.034575)
			(xy 85.287858 -250.081256) (xy 85.295753 -250.129833) (xy 85.296248 -250.15444) (xy 85.614759 -250.15444)
			(xy 85.618854 -250.103712) (xy 85.631033 -250.054298) (xy 85.650981 -250.007478) (xy 85.678182 -249.964464)
			(xy 85.71193 -249.92637) (xy 85.751352 -249.894183) (xy 85.795426 -249.868737) (xy 85.843012 -249.85069)
			(xy 85.892876 -249.84051) (xy 85.943728 -249.838461) (xy 85.994249 -249.844595) (xy 86.043133 -249.858755)
			(xy 86.089112 -249.880572) (xy 86.130996 -249.909482) (xy 86.1677 -249.944737) (xy 86.198273 -249.985423)
			(xy 86.221924 -250.030486) (xy 86.23804 -250.07876) (xy 86.246204 -250.128994) (xy 86.246716 -250.15444)
			(xy 86.565244 -250.15444) (xy 86.569204 -250.105386) (xy 86.580981 -250.057602) (xy 86.600272 -250.012326)
			(xy 86.626575 -249.97073) (xy 86.65921 -249.933893) (xy 86.697331 -249.902768) (xy 86.739952 -249.878161)
			(xy 86.785968 -249.860709) (xy 86.834187 -249.850865) (xy 86.883362 -249.848884) (xy 86.932217 -249.854816)
			(xy 86.979488 -249.868508) (xy 87.02395 -249.889606) (xy 87.064453 -249.917562) (xy 87.099946 -249.951654)
			(xy 87.129511 -249.990998) (xy 87.152382 -250.034575) (xy 87.167966 -250.081256) (xy 87.175861 -250.129833)
			(xy 87.176356 -250.15444) (xy 87.505298 -250.15444) (xy 87.509258 -250.105386) (xy 87.521035 -250.057602)
			(xy 87.540326 -250.012326) (xy 87.566629 -249.97073) (xy 87.599264 -249.933893) (xy 87.637385 -249.902768)
			(xy 87.680006 -249.878161) (xy 87.726022 -249.860709) (xy 87.774241 -249.850865) (xy 87.823416 -249.848884)
			(xy 87.872271 -249.854816) (xy 87.919542 -249.868508) (xy 87.964004 -249.889606) (xy 88.004507 -249.917562)
			(xy 88.04 -249.951654) (xy 88.069565 -249.990998) (xy 88.092436 -250.034575) (xy 88.10802 -250.081256)
			(xy 88.115915 -250.129833) (xy 88.11641 -250.15444) (xy 88.434921 -250.15444) (xy 88.439016 -250.103712)
			(xy 88.451195 -250.054298) (xy 88.471143 -250.007478) (xy 88.498344 -249.964464) (xy 88.532092 -249.92637)
			(xy 88.571514 -249.894183) (xy 88.615588 -249.868737) (xy 88.663174 -249.85069) (xy 88.713038 -249.84051)
			(xy 88.76389 -249.838461) (xy 88.814411 -249.844595) (xy 88.863295 -249.858755) (xy 88.909274 -249.880572)
			(xy 88.951158 -249.909482) (xy 88.987862 -249.944737) (xy 89.018435 -249.985423) (xy 89.042086 -250.030486)
			(xy 89.058202 -250.07876) (xy 89.066366 -250.128994) (xy 89.066878 -250.15444) (xy 89.385152 -250.15444)
			(xy 89.389112 -250.105386) (xy 89.400889 -250.057602) (xy 89.42018 -250.012326) (xy 89.446483 -249.97073)
			(xy 89.479118 -249.933893) (xy 89.517239 -249.902768) (xy 89.55986 -249.878161) (xy 89.605876 -249.860709)
			(xy 89.654095 -249.850865) (xy 89.70327 -249.848884) (xy 89.752125 -249.854816) (xy 89.799396 -249.868508)
			(xy 89.843858 -249.889606) (xy 89.884361 -249.917562) (xy 89.919854 -249.951654) (xy 89.949419 -249.990998)
			(xy 89.97229 -250.034575) (xy 89.987874 -250.081256) (xy 89.995769 -250.129833) (xy 89.996264 -250.15444)
			(xy 90.325206 -250.15444) (xy 90.329166 -250.105386) (xy 90.340943 -250.057602) (xy 90.360234 -250.012326)
			(xy 90.386537 -249.97073) (xy 90.419172 -249.933893) (xy 90.457293 -249.902768) (xy 90.499914 -249.878161)
			(xy 90.54593 -249.860709) (xy 90.594149 -249.850865) (xy 90.643324 -249.848884) (xy 90.692179 -249.854816)
			(xy 90.73945 -249.868508) (xy 90.783912 -249.889606) (xy 90.824415 -249.917562) (xy 90.859908 -249.951654)
			(xy 90.889473 -249.990998) (xy 90.912344 -250.034575) (xy 90.927928 -250.081256) (xy 90.935823 -250.129833)
			(xy 90.936318 -250.15444) (xy 91.26526 -250.15444) (xy 91.26922 -250.105386) (xy 91.280997 -250.057602)
			(xy 91.300288 -250.012326) (xy 91.326591 -249.97073) (xy 91.359226 -249.933893) (xy 91.397347 -249.902768)
			(xy 91.439968 -249.878161) (xy 91.485984 -249.860709) (xy 91.534203 -249.850865) (xy 91.583378 -249.848884)
			(xy 91.632233 -249.854816) (xy 91.679504 -249.868508) (xy 91.723966 -249.889606) (xy 91.764469 -249.917562)
			(xy 91.799962 -249.951654) (xy 91.829527 -249.990998) (xy 91.852398 -250.034575) (xy 91.867982 -250.081256)
			(xy 91.875877 -250.129833) (xy 91.876372 -250.15444) (xy 92.194883 -250.15444) (xy 92.198978 -250.103712)
			(xy 92.211157 -250.054298) (xy 92.231105 -250.007478) (xy 92.258306 -249.964464) (xy 92.292054 -249.92637)
			(xy 92.331476 -249.894183) (xy 92.37555 -249.868737) (xy 92.423136 -249.85069) (xy 92.473 -249.84051)
			(xy 92.523852 -249.838461) (xy 92.574373 -249.844595) (xy 92.623257 -249.858755) (xy 92.669236 -249.880572)
			(xy 92.71112 -249.909482) (xy 92.747824 -249.944737) (xy 92.778397 -249.985423) (xy 92.802048 -250.030486)
			(xy 92.818164 -250.07876) (xy 92.826328 -250.128994) (xy 92.82684 -250.15444) (xy 93.145114 -250.15444)
			(xy 93.149074 -250.105386) (xy 93.160851 -250.057602) (xy 93.180142 -250.012326) (xy 93.206445 -249.97073)
			(xy 93.23908 -249.933893) (xy 93.277201 -249.902768) (xy 93.319822 -249.878161) (xy 93.365838 -249.860709)
			(xy 93.414057 -249.850865) (xy 93.463232 -249.848884) (xy 93.512087 -249.854816) (xy 93.559358 -249.868508)
			(xy 93.60382 -249.889606) (xy 93.644323 -249.917562) (xy 93.679816 -249.951654) (xy 93.709381 -249.990998)
			(xy 93.732252 -250.034575) (xy 93.747836 -250.081256) (xy 93.755731 -250.129833) (xy 93.756226 -250.15444)
			(xy 94.085168 -250.15444) (xy 94.089128 -250.105386) (xy 94.100905 -250.057602) (xy 94.120196 -250.012326)
			(xy 94.146499 -249.97073) (xy 94.179134 -249.933893) (xy 94.217255 -249.902768) (xy 94.259876 -249.878161)
			(xy 94.305892 -249.860709) (xy 94.354111 -249.850865) (xy 94.403286 -249.848884) (xy 94.452141 -249.854816)
			(xy 94.499412 -249.868508) (xy 94.543874 -249.889606) (xy 94.584377 -249.917562) (xy 94.61987 -249.951654)
			(xy 94.649435 -249.990998) (xy 94.672306 -250.034575) (xy 94.68789 -250.081256) (xy 94.695785 -250.129833)
			(xy 94.69628 -250.15444) (xy 95.014791 -250.15444) (xy 95.018886 -250.103712) (xy 95.031065 -250.054298)
			(xy 95.051013 -250.007478) (xy 95.078214 -249.964464) (xy 95.111962 -249.92637) (xy 95.151384 -249.894183)
			(xy 95.195458 -249.868737) (xy 95.243044 -249.85069) (xy 95.292908 -249.84051) (xy 95.34376 -249.838461)
			(xy 95.394281 -249.844595) (xy 95.443165 -249.858755) (xy 95.489144 -249.880572) (xy 95.531028 -249.909482)
			(xy 95.567732 -249.944737) (xy 95.598305 -249.985423) (xy 95.621956 -250.030486) (xy 95.638072 -250.07876)
			(xy 95.646236 -250.128994) (xy 95.646748 -250.15444) (xy 95.965276 -250.15444) (xy 95.969236 -250.105386)
			(xy 95.981013 -250.057602) (xy 96.000304 -250.012326) (xy 96.026607 -249.97073) (xy 96.059242 -249.933893)
			(xy 96.097363 -249.902768) (xy 96.139984 -249.878161) (xy 96.186 -249.860709) (xy 96.234219 -249.850865)
			(xy 96.283394 -249.848884) (xy 96.332249 -249.854816) (xy 96.37952 -249.868508) (xy 96.423982 -249.889606)
			(xy 96.464485 -249.917562) (xy 96.499978 -249.951654) (xy 96.529543 -249.990998) (xy 96.552414 -250.034575)
			(xy 96.567998 -250.081256) (xy 96.575893 -250.129833) (xy 96.576388 -250.15444) (xy 96.90533 -250.15444)
			(xy 96.90929 -250.105386) (xy 96.921067 -250.057602) (xy 96.940358 -250.012326) (xy 96.966661 -249.97073)
			(xy 96.999296 -249.933893) (xy 97.037417 -249.902768) (xy 97.080038 -249.878161) (xy 97.126054 -249.860709)
			(xy 97.174273 -249.850865) (xy 97.223448 -249.848884) (xy 97.272303 -249.854816) (xy 97.319574 -249.868508)
			(xy 97.364036 -249.889606) (xy 97.404539 -249.917562) (xy 97.440032 -249.951654) (xy 97.469597 -249.990998)
			(xy 97.492468 -250.034575) (xy 97.508052 -250.081256) (xy 97.515947 -250.129833) (xy 97.516442 -250.15444)
			(xy 97.84513 -250.15444) (xy 97.84909 -250.105386) (xy 97.860867 -250.057602) (xy 97.880158 -250.012326)
			(xy 97.906461 -249.97073) (xy 97.939096 -249.933893) (xy 97.977217 -249.902768) (xy 98.019838 -249.878161)
			(xy 98.065854 -249.860709) (xy 98.114073 -249.850865) (xy 98.163248 -249.848884) (xy 98.212103 -249.854816)
			(xy 98.259374 -249.868508) (xy 98.303836 -249.889606) (xy 98.344339 -249.917562) (xy 98.379832 -249.951654)
			(xy 98.409397 -249.990998) (xy 98.432268 -250.034575) (xy 98.447852 -250.081256) (xy 98.455747 -250.129833)
			(xy 98.456242 -250.15444) (xy 98.785184 -250.15444) (xy 98.789144 -250.105386) (xy 98.800921 -250.057602)
			(xy 98.820212 -250.012326) (xy 98.846515 -249.97073) (xy 98.87915 -249.933893) (xy 98.917271 -249.902768)
			(xy 98.959892 -249.878161) (xy 99.005908 -249.860709) (xy 99.054127 -249.850865) (xy 99.103302 -249.848884)
			(xy 99.152157 -249.854816) (xy 99.199428 -249.868508) (xy 99.24389 -249.889606) (xy 99.284393 -249.917562)
			(xy 99.319886 -249.951654) (xy 99.349451 -249.990998) (xy 99.372322 -250.034575) (xy 99.387906 -250.081256)
			(xy 99.395801 -250.129833) (xy 99.396296 -250.15444) (xy 99.725238 -250.15444) (xy 99.729198 -250.105386)
			(xy 99.740975 -250.057602) (xy 99.760266 -250.012326) (xy 99.786569 -249.97073) (xy 99.819204 -249.933893)
			(xy 99.857325 -249.902768) (xy 99.899946 -249.878161) (xy 99.945962 -249.860709) (xy 99.994181 -249.850865)
			(xy 100.043356 -249.848884) (xy 100.092211 -249.854816) (xy 100.139482 -249.868508) (xy 100.183944 -249.889606)
			(xy 100.224447 -249.917562) (xy 100.25994 -249.951654) (xy 100.289505 -249.990998) (xy 100.312376 -250.034575)
			(xy 100.32796 -250.081256) (xy 100.335855 -250.129833) (xy 100.33635 -250.15444) (xy 101.605346 -250.15444)
			(xy 101.609306 -250.105386) (xy 101.621083 -250.057602) (xy 101.640374 -250.012326) (xy 101.666677 -249.97073)
			(xy 101.699312 -249.933893) (xy 101.737433 -249.902768) (xy 101.780054 -249.878161) (xy 101.82607 -249.860709)
			(xy 101.874289 -249.850865) (xy 101.923464 -249.848884) (xy 101.972319 -249.854816) (xy 102.01959 -249.868508)
			(xy 102.064052 -249.889606) (xy 102.104555 -249.917562) (xy 102.140048 -249.951654) (xy 102.169613 -249.990998)
			(xy 102.192484 -250.034575) (xy 102.208068 -250.081256) (xy 102.215963 -250.129833) (xy 102.216458 -250.15444)
			(xy 103.4852 -250.15444) (xy 103.48916 -250.105386) (xy 103.500937 -250.057602) (xy 103.520228 -250.012326)
			(xy 103.546531 -249.97073) (xy 103.579166 -249.933893) (xy 103.617287 -249.902768) (xy 103.659908 -249.878161)
			(xy 103.705924 -249.860709) (xy 103.754143 -249.850865) (xy 103.803318 -249.848884) (xy 103.852173 -249.854816)
			(xy 103.899444 -249.868508) (xy 103.943906 -249.889606) (xy 103.984409 -249.917562) (xy 104.019902 -249.951654)
			(xy 104.049467 -249.990998) (xy 104.072338 -250.034575) (xy 104.087922 -250.081256) (xy 104.095817 -250.129833)
			(xy 104.096312 -250.15444) (xy 105.365308 -250.15444) (xy 105.369268 -250.105386) (xy 105.381045 -250.057602)
			(xy 105.400336 -250.012326) (xy 105.426639 -249.97073) (xy 105.459274 -249.933893) (xy 105.497395 -249.902768)
			(xy 105.540016 -249.878161) (xy 105.586032 -249.860709) (xy 105.634251 -249.850865) (xy 105.683426 -249.848884)
			(xy 105.732281 -249.854816) (xy 105.779552 -249.868508) (xy 105.824014 -249.889606) (xy 105.864517 -249.917562)
			(xy 105.90001 -249.951654) (xy 105.929575 -249.990998) (xy 105.952446 -250.034575) (xy 105.96803 -250.081256)
			(xy 105.975925 -250.129833) (xy 105.97642 -250.15444) (xy 107.245162 -250.15444) (xy 107.249122 -250.105386)
			(xy 107.260899 -250.057602) (xy 107.28019 -250.012326) (xy 107.306493 -249.97073) (xy 107.339128 -249.933893)
			(xy 107.377249 -249.902768) (xy 107.41987 -249.878161) (xy 107.465886 -249.860709) (xy 107.514105 -249.850865)
			(xy 107.56328 -249.848884) (xy 107.612135 -249.854816) (xy 107.659406 -249.868508) (xy 107.703868 -249.889606)
			(xy 107.744371 -249.917562) (xy 107.779864 -249.951654) (xy 107.809429 -249.990998) (xy 107.8323 -250.034575)
			(xy 107.847884 -250.081256) (xy 107.855779 -250.129833) (xy 107.856274 -250.15444) (xy 109.12527 -250.15444)
			(xy 109.12923 -250.105386) (xy 109.141007 -250.057602) (xy 109.160298 -250.012326) (xy 109.186601 -249.97073)
			(xy 109.219236 -249.933893) (xy 109.257357 -249.902768) (xy 109.299978 -249.878161) (xy 109.345994 -249.860709)
			(xy 109.394213 -249.850865) (xy 109.443388 -249.848884) (xy 109.492243 -249.854816) (xy 109.539514 -249.868508)
			(xy 109.583976 -249.889606) (xy 109.624479 -249.917562) (xy 109.659972 -249.951654) (xy 109.689537 -249.990998)
			(xy 109.712408 -250.034575) (xy 109.727992 -250.081256) (xy 109.735887 -250.129833) (xy 109.736382 -250.15444)
			(xy 112.878882 -250.15444) (xy 112.882842 -250.105386) (xy 112.894619 -250.057602) (xy 112.91391 -250.012326)
			(xy 112.940213 -249.97073) (xy 112.972848 -249.933893) (xy 113.010969 -249.902768) (xy 113.05359 -249.878161)
			(xy 113.099606 -249.860709) (xy 113.147825 -249.850865) (xy 113.197 -249.848884) (xy 113.245855 -249.854816)
			(xy 113.293126 -249.868508) (xy 113.337588 -249.889606) (xy 113.378091 -249.917562) (xy 113.413584 -249.951654)
			(xy 113.443149 -249.990998) (xy 113.46602 -250.034575) (xy 113.481604 -250.081256) (xy 113.489499 -250.129833)
			(xy 113.489994 -250.15444) (xy 114.75899 -250.15444) (xy 114.76295 -250.105386) (xy 114.774727 -250.057602)
			(xy 114.794018 -250.012326) (xy 114.820321 -249.97073) (xy 114.852956 -249.933893) (xy 114.891077 -249.902768)
			(xy 114.933698 -249.878161) (xy 114.979714 -249.860709) (xy 115.027933 -249.850865) (xy 115.077108 -249.848884)
			(xy 115.125963 -249.854816) (xy 115.173234 -249.868508) (xy 115.217696 -249.889606) (xy 115.258199 -249.917562)
			(xy 115.293692 -249.951654) (xy 115.323257 -249.990998) (xy 115.346128 -250.034575) (xy 115.361712 -250.081256)
			(xy 115.369607 -250.129833) (xy 115.370102 -250.15444) (xy 116.638844 -250.15444) (xy 116.642804 -250.105386)
			(xy 116.654581 -250.057602) (xy 116.673872 -250.012326) (xy 116.700175 -249.97073) (xy 116.73281 -249.933893)
			(xy 116.770931 -249.902768) (xy 116.813552 -249.878161) (xy 116.859568 -249.860709) (xy 116.907787 -249.850865)
			(xy 116.956962 -249.848884) (xy 117.005817 -249.854816) (xy 117.053088 -249.868508) (xy 117.09755 -249.889606)
			(xy 117.138053 -249.917562) (xy 117.173546 -249.951654) (xy 117.203111 -249.990998) (xy 117.225982 -250.034575)
			(xy 117.241566 -250.081256) (xy 117.249461 -250.129833) (xy 117.249956 -250.15444) (xy 118.518952 -250.15444)
			(xy 118.522912 -250.105386) (xy 118.534689 -250.057602) (xy 118.55398 -250.012326) (xy 118.580283 -249.97073)
			(xy 118.612918 -249.933893) (xy 118.651039 -249.902768) (xy 118.69366 -249.878161) (xy 118.739676 -249.860709)
			(xy 118.787895 -249.850865) (xy 118.83707 -249.848884) (xy 118.885925 -249.854816) (xy 118.933196 -249.868508)
			(xy 118.977658 -249.889606) (xy 119.018161 -249.917562) (xy 119.053654 -249.951654) (xy 119.083219 -249.990998)
			(xy 119.10609 -250.034575) (xy 119.121674 -250.081256) (xy 119.129569 -250.129833) (xy 119.130064 -250.15444)
			(xy 120.398806 -250.15444) (xy 120.402766 -250.105386) (xy 120.414543 -250.057602) (xy 120.433834 -250.012326)
			(xy 120.460137 -249.97073) (xy 120.492772 -249.933893) (xy 120.530893 -249.902768) (xy 120.573514 -249.878161)
			(xy 120.61953 -249.860709) (xy 120.667749 -249.850865) (xy 120.716924 -249.848884) (xy 120.765779 -249.854816)
			(xy 120.81305 -249.868508) (xy 120.857512 -249.889606) (xy 120.898015 -249.917562) (xy 120.933508 -249.951654)
			(xy 120.963073 -249.990998) (xy 120.985944 -250.034575) (xy 121.001528 -250.081256) (xy 121.009423 -250.129833)
			(xy 121.009918 -250.15444) (xy 122.278914 -250.15444) (xy 122.282874 -250.105386) (xy 122.294651 -250.057602)
			(xy 122.313942 -250.012326) (xy 122.340245 -249.97073) (xy 122.37288 -249.933893) (xy 122.411001 -249.902768)
			(xy 122.453622 -249.878161) (xy 122.499638 -249.860709) (xy 122.547857 -249.850865) (xy 122.597032 -249.848884)
			(xy 122.645887 -249.854816) (xy 122.693158 -249.868508) (xy 122.73762 -249.889606) (xy 122.778123 -249.917562)
			(xy 122.813616 -249.951654) (xy 122.843181 -249.990998) (xy 122.866052 -250.034575) (xy 122.881636 -250.081256)
			(xy 122.889531 -250.129833) (xy 122.890026 -250.15444) (xy 124.159022 -250.15444) (xy 124.162982 -250.105386)
			(xy 124.174759 -250.057602) (xy 124.19405 -250.012326) (xy 124.220353 -249.97073) (xy 124.252988 -249.933893)
			(xy 124.291109 -249.902768) (xy 124.33373 -249.878161) (xy 124.379746 -249.860709) (xy 124.427965 -249.850865)
			(xy 124.47714 -249.848884) (xy 124.525995 -249.854816) (xy 124.573266 -249.868508) (xy 124.617728 -249.889606)
			(xy 124.658231 -249.917562) (xy 124.693724 -249.951654) (xy 124.723289 -249.990998) (xy 124.74616 -250.034575)
			(xy 124.761744 -250.081256) (xy 124.769639 -250.129833) (xy 124.770134 -250.15444) (xy 126.038876 -250.15444)
			(xy 126.042836 -250.105386) (xy 126.054613 -250.057602) (xy 126.073904 -250.012326) (xy 126.100207 -249.97073)
			(xy 126.132842 -249.933893) (xy 126.170963 -249.902768) (xy 126.213584 -249.878161) (xy 126.2596 -249.860709)
			(xy 126.307819 -249.850865) (xy 126.356994 -249.848884) (xy 126.405849 -249.854816) (xy 126.45312 -249.868508)
			(xy 126.497582 -249.889606) (xy 126.538085 -249.917562) (xy 126.573578 -249.951654) (xy 126.603143 -249.990998)
			(xy 126.626014 -250.034575) (xy 126.641598 -250.081256) (xy 126.649493 -250.129833) (xy 126.649988 -250.15444)
			(xy 126.649493 -250.179047) (xy 126.641598 -250.227624) (xy 126.626014 -250.274305) (xy 126.603143 -250.317882)
			(xy 126.573578 -250.357226) (xy 126.538085 -250.391318) (xy 126.497582 -250.419274) (xy 126.45312 -250.440372)
			(xy 126.405849 -250.454064) (xy 126.356994 -250.459996) (xy 126.307819 -250.458015) (xy 126.2596 -250.448171)
			(xy 126.213584 -250.430719) (xy 126.170963 -250.406112) (xy 126.132842 -250.374987) (xy 126.100207 -250.33815)
			(xy 126.073904 -250.296554) (xy 126.054613 -250.251278) (xy 126.042836 -250.203494) (xy 126.038876 -250.15444)
			(xy 124.770134 -250.15444) (xy 124.769639 -250.179047) (xy 124.761744 -250.227624) (xy 124.74616 -250.274305)
			(xy 124.723289 -250.317882) (xy 124.693724 -250.357226) (xy 124.658231 -250.391318) (xy 124.617728 -250.419274)
			(xy 124.573266 -250.440372) (xy 124.525995 -250.454064) (xy 124.47714 -250.459996) (xy 124.427965 -250.458015)
			(xy 124.379746 -250.448171) (xy 124.33373 -250.430719) (xy 124.291109 -250.406112) (xy 124.252988 -250.374987)
			(xy 124.220353 -250.33815) (xy 124.19405 -250.296554) (xy 124.174759 -250.251278) (xy 124.162982 -250.203494)
			(xy 124.159022 -250.15444) (xy 122.890026 -250.15444) (xy 122.889531 -250.179047) (xy 122.881636 -250.227624)
			(xy 122.866052 -250.274305) (xy 122.843181 -250.317882) (xy 122.813616 -250.357226) (xy 122.778123 -250.391318)
			(xy 122.73762 -250.419274) (xy 122.693158 -250.440372) (xy 122.645887 -250.454064) (xy 122.597032 -250.459996)
			(xy 122.547857 -250.458015) (xy 122.499638 -250.448171) (xy 122.453622 -250.430719) (xy 122.411001 -250.406112)
			(xy 122.37288 -250.374987) (xy 122.340245 -250.33815) (xy 122.313942 -250.296554) (xy 122.294651 -250.251278)
			(xy 122.282874 -250.203494) (xy 122.278914 -250.15444) (xy 121.009918 -250.15444) (xy 121.009423 -250.179047)
			(xy 121.001528 -250.227624) (xy 120.985944 -250.274305) (xy 120.963073 -250.317882) (xy 120.933508 -250.357226)
			(xy 120.898015 -250.391318) (xy 120.857512 -250.419274) (xy 120.81305 -250.440372) (xy 120.765779 -250.454064)
			(xy 120.716924 -250.459996) (xy 120.667749 -250.458015) (xy 120.61953 -250.448171) (xy 120.573514 -250.430719)
			(xy 120.530893 -250.406112) (xy 120.492772 -250.374987) (xy 120.460137 -250.33815) (xy 120.433834 -250.296554)
			(xy 120.414543 -250.251278) (xy 120.402766 -250.203494) (xy 120.398806 -250.15444) (xy 119.130064 -250.15444)
			(xy 119.129569 -250.179047) (xy 119.121674 -250.227624) (xy 119.10609 -250.274305) (xy 119.083219 -250.317882)
			(xy 119.053654 -250.357226) (xy 119.018161 -250.391318) (xy 118.977658 -250.419274) (xy 118.933196 -250.440372)
			(xy 118.885925 -250.454064) (xy 118.83707 -250.459996) (xy 118.787895 -250.458015) (xy 118.739676 -250.448171)
			(xy 118.69366 -250.430719) (xy 118.651039 -250.406112) (xy 118.612918 -250.374987) (xy 118.580283 -250.33815)
			(xy 118.55398 -250.296554) (xy 118.534689 -250.251278) (xy 118.522912 -250.203494) (xy 118.518952 -250.15444)
			(xy 117.249956 -250.15444) (xy 117.249461 -250.179047) (xy 117.241566 -250.227624) (xy 117.225982 -250.274305)
			(xy 117.203111 -250.317882) (xy 117.173546 -250.357226) (xy 117.138053 -250.391318) (xy 117.09755 -250.419274)
			(xy 117.053088 -250.440372) (xy 117.005817 -250.454064) (xy 116.956962 -250.459996) (xy 116.907787 -250.458015)
			(xy 116.859568 -250.448171) (xy 116.813552 -250.430719) (xy 116.770931 -250.406112) (xy 116.73281 -250.374987)
			(xy 116.700175 -250.33815) (xy 116.673872 -250.296554) (xy 116.654581 -250.251278) (xy 116.642804 -250.203494)
			(xy 116.638844 -250.15444) (xy 115.370102 -250.15444) (xy 115.369607 -250.179047) (xy 115.361712 -250.227624)
			(xy 115.346128 -250.274305) (xy 115.323257 -250.317882) (xy 115.293692 -250.357226) (xy 115.258199 -250.391318)
			(xy 115.217696 -250.419274) (xy 115.173234 -250.440372) (xy 115.125963 -250.454064) (xy 115.077108 -250.459996)
			(xy 115.027933 -250.458015) (xy 114.979714 -250.448171) (xy 114.933698 -250.430719) (xy 114.891077 -250.406112)
			(xy 114.852956 -250.374987) (xy 114.820321 -250.33815) (xy 114.794018 -250.296554) (xy 114.774727 -250.251278)
			(xy 114.76295 -250.203494) (xy 114.75899 -250.15444) (xy 113.489994 -250.15444) (xy 113.489499 -250.179047)
			(xy 113.481604 -250.227624) (xy 113.46602 -250.274305) (xy 113.443149 -250.317882) (xy 113.413584 -250.357226)
			(xy 113.378091 -250.391318) (xy 113.337588 -250.419274) (xy 113.293126 -250.440372) (xy 113.245855 -250.454064)
			(xy 113.197 -250.459996) (xy 113.147825 -250.458015) (xy 113.099606 -250.448171) (xy 113.05359 -250.430719)
			(xy 113.010969 -250.406112) (xy 112.972848 -250.374987) (xy 112.940213 -250.33815) (xy 112.91391 -250.296554)
			(xy 112.894619 -250.251278) (xy 112.882842 -250.203494) (xy 112.878882 -250.15444) (xy 109.736382 -250.15444)
			(xy 109.735887 -250.179047) (xy 109.727992 -250.227624) (xy 109.712408 -250.274305) (xy 109.689537 -250.317882)
			(xy 109.659972 -250.357226) (xy 109.624479 -250.391318) (xy 109.583976 -250.419274) (xy 109.539514 -250.440372)
			(xy 109.492243 -250.454064) (xy 109.443388 -250.459996) (xy 109.394213 -250.458015) (xy 109.345994 -250.448171)
			(xy 109.299978 -250.430719) (xy 109.257357 -250.406112) (xy 109.219236 -250.374987) (xy 109.186601 -250.33815)
			(xy 109.160298 -250.296554) (xy 109.141007 -250.251278) (xy 109.12923 -250.203494) (xy 109.12527 -250.15444)
			(xy 107.856274 -250.15444) (xy 107.855779 -250.179047) (xy 107.847884 -250.227624) (xy 107.8323 -250.274305)
			(xy 107.809429 -250.317882) (xy 107.779864 -250.357226) (xy 107.744371 -250.391318) (xy 107.703868 -250.419274)
			(xy 107.659406 -250.440372) (xy 107.612135 -250.454064) (xy 107.56328 -250.459996) (xy 107.514105 -250.458015)
			(xy 107.465886 -250.448171) (xy 107.41987 -250.430719) (xy 107.377249 -250.406112) (xy 107.339128 -250.374987)
			(xy 107.306493 -250.33815) (xy 107.28019 -250.296554) (xy 107.260899 -250.251278) (xy 107.249122 -250.203494)
			(xy 107.245162 -250.15444) (xy 105.97642 -250.15444) (xy 105.975925 -250.179047) (xy 105.96803 -250.227624)
			(xy 105.952446 -250.274305) (xy 105.929575 -250.317882) (xy 105.90001 -250.357226) (xy 105.864517 -250.391318)
			(xy 105.824014 -250.419274) (xy 105.779552 -250.440372) (xy 105.732281 -250.454064) (xy 105.683426 -250.459996)
			(xy 105.634251 -250.458015) (xy 105.586032 -250.448171) (xy 105.540016 -250.430719) (xy 105.497395 -250.406112)
			(xy 105.459274 -250.374987) (xy 105.426639 -250.33815) (xy 105.400336 -250.296554) (xy 105.381045 -250.251278)
			(xy 105.369268 -250.203494) (xy 105.365308 -250.15444) (xy 104.096312 -250.15444) (xy 104.095817 -250.179047)
			(xy 104.087922 -250.227624) (xy 104.072338 -250.274305) (xy 104.049467 -250.317882) (xy 104.019902 -250.357226)
			(xy 103.984409 -250.391318) (xy 103.943906 -250.419274) (xy 103.899444 -250.440372) (xy 103.852173 -250.454064)
			(xy 103.803318 -250.459996) (xy 103.754143 -250.458015) (xy 103.705924 -250.448171) (xy 103.659908 -250.430719)
			(xy 103.617287 -250.406112) (xy 103.579166 -250.374987) (xy 103.546531 -250.33815) (xy 103.520228 -250.296554)
			(xy 103.500937 -250.251278) (xy 103.48916 -250.203494) (xy 103.4852 -250.15444) (xy 102.216458 -250.15444)
			(xy 102.215963 -250.179047) (xy 102.208068 -250.227624) (xy 102.192484 -250.274305) (xy 102.169613 -250.317882)
			(xy 102.140048 -250.357226) (xy 102.104555 -250.391318) (xy 102.064052 -250.419274) (xy 102.01959 -250.440372)
			(xy 101.972319 -250.454064) (xy 101.923464 -250.459996) (xy 101.874289 -250.458015) (xy 101.82607 -250.448171)
			(xy 101.780054 -250.430719) (xy 101.737433 -250.406112) (xy 101.699312 -250.374987) (xy 101.666677 -250.33815)
			(xy 101.640374 -250.296554) (xy 101.621083 -250.251278) (xy 101.609306 -250.203494) (xy 101.605346 -250.15444)
			(xy 100.33635 -250.15444) (xy 100.335855 -250.179047) (xy 100.32796 -250.227624) (xy 100.312376 -250.274305)
			(xy 100.289505 -250.317882) (xy 100.25994 -250.357226) (xy 100.224447 -250.391318) (xy 100.183944 -250.419274)
			(xy 100.139482 -250.440372) (xy 100.092211 -250.454064) (xy 100.043356 -250.459996) (xy 99.994181 -250.458015)
			(xy 99.945962 -250.448171) (xy 99.899946 -250.430719) (xy 99.857325 -250.406112) (xy 99.819204 -250.374987)
			(xy 99.786569 -250.33815) (xy 99.760266 -250.296554) (xy 99.740975 -250.251278) (xy 99.729198 -250.203494)
			(xy 99.725238 -250.15444) (xy 99.396296 -250.15444) (xy 99.395801 -250.179047) (xy 99.387906 -250.227624)
			(xy 99.372322 -250.274305) (xy 99.349451 -250.317882) (xy 99.319886 -250.357226) (xy 99.284393 -250.391318)
			(xy 99.24389 -250.419274) (xy 99.199428 -250.440372) (xy 99.152157 -250.454064) (xy 99.103302 -250.459996)
			(xy 99.054127 -250.458015) (xy 99.005908 -250.448171) (xy 98.959892 -250.430719) (xy 98.917271 -250.406112)
			(xy 98.87915 -250.374987) (xy 98.846515 -250.33815) (xy 98.820212 -250.296554) (xy 98.800921 -250.251278)
			(xy 98.789144 -250.203494) (xy 98.785184 -250.15444) (xy 98.456242 -250.15444) (xy 98.455747 -250.179047)
			(xy 98.447852 -250.227624) (xy 98.432268 -250.274305) (xy 98.409397 -250.317882) (xy 98.379832 -250.357226)
			(xy 98.344339 -250.391318) (xy 98.303836 -250.419274) (xy 98.259374 -250.440372) (xy 98.212103 -250.454064)
			(xy 98.163248 -250.459996) (xy 98.114073 -250.458015) (xy 98.065854 -250.448171) (xy 98.019838 -250.430719)
			(xy 97.977217 -250.406112) (xy 97.939096 -250.374987) (xy 97.906461 -250.33815) (xy 97.880158 -250.296554)
			(xy 97.860867 -250.251278) (xy 97.84909 -250.203494) (xy 97.84513 -250.15444) (xy 97.516442 -250.15444)
			(xy 97.515947 -250.179047) (xy 97.508052 -250.227624) (xy 97.492468 -250.274305) (xy 97.469597 -250.317882)
			(xy 97.440032 -250.357226) (xy 97.404539 -250.391318) (xy 97.364036 -250.419274) (xy 97.319574 -250.440372)
			(xy 97.272303 -250.454064) (xy 97.223448 -250.459996) (xy 97.174273 -250.458015) (xy 97.126054 -250.448171)
			(xy 97.080038 -250.430719) (xy 97.037417 -250.406112) (xy 96.999296 -250.374987) (xy 96.966661 -250.33815)
			(xy 96.940358 -250.296554) (xy 96.921067 -250.251278) (xy 96.90929 -250.203494) (xy 96.90533 -250.15444)
			(xy 96.576388 -250.15444) (xy 96.575893 -250.179047) (xy 96.567998 -250.227624) (xy 96.552414 -250.274305)
			(xy 96.529543 -250.317882) (xy 96.499978 -250.357226) (xy 96.464485 -250.391318) (xy 96.423982 -250.419274)
			(xy 96.37952 -250.440372) (xy 96.332249 -250.454064) (xy 96.283394 -250.459996) (xy 96.234219 -250.458015)
			(xy 96.186 -250.448171) (xy 96.139984 -250.430719) (xy 96.097363 -250.406112) (xy 96.059242 -250.374987)
			(xy 96.026607 -250.33815) (xy 96.000304 -250.296554) (xy 95.981013 -250.251278) (xy 95.969236 -250.203494)
			(xy 95.965276 -250.15444) (xy 95.646748 -250.15444) (xy 95.646236 -250.179886) (xy 95.638072 -250.23012)
			(xy 95.621956 -250.278394) (xy 95.598305 -250.323457) (xy 95.567732 -250.364143) (xy 95.531028 -250.399398)
			(xy 95.489144 -250.428308) (xy 95.443165 -250.450125) (xy 95.394281 -250.464285) (xy 95.34376 -250.470419)
			(xy 95.292908 -250.46837) (xy 95.243044 -250.45819) (xy 95.195458 -250.440143) (xy 95.151384 -250.414697)
			(xy 95.111962 -250.38251) (xy 95.078214 -250.344416) (xy 95.051013 -250.301402) (xy 95.031065 -250.254582)
			(xy 95.018886 -250.205168) (xy 95.014791 -250.15444) (xy 94.69628 -250.15444) (xy 94.695785 -250.179047)
			(xy 94.68789 -250.227624) (xy 94.672306 -250.274305) (xy 94.649435 -250.317882) (xy 94.61987 -250.357226)
			(xy 94.584377 -250.391318) (xy 94.543874 -250.419274) (xy 94.499412 -250.440372) (xy 94.452141 -250.454064)
			(xy 94.403286 -250.459996) (xy 94.354111 -250.458015) (xy 94.305892 -250.448171) (xy 94.259876 -250.430719)
			(xy 94.217255 -250.406112) (xy 94.179134 -250.374987) (xy 94.146499 -250.33815) (xy 94.120196 -250.296554)
			(xy 94.100905 -250.251278) (xy 94.089128 -250.203494) (xy 94.085168 -250.15444) (xy 93.756226 -250.15444)
			(xy 93.755731 -250.179047) (xy 93.747836 -250.227624) (xy 93.732252 -250.274305) (xy 93.709381 -250.317882)
			(xy 93.679816 -250.357226) (xy 93.644323 -250.391318) (xy 93.60382 -250.419274) (xy 93.559358 -250.440372)
			(xy 93.512087 -250.454064) (xy 93.463232 -250.459996) (xy 93.414057 -250.458015) (xy 93.365838 -250.448171)
			(xy 93.319822 -250.430719) (xy 93.277201 -250.406112) (xy 93.23908 -250.374987) (xy 93.206445 -250.33815)
			(xy 93.180142 -250.296554) (xy 93.160851 -250.251278) (xy 93.149074 -250.203494) (xy 93.145114 -250.15444)
			(xy 92.82684 -250.15444) (xy 92.826328 -250.179886) (xy 92.818164 -250.23012) (xy 92.802048 -250.278394)
			(xy 92.778397 -250.323457) (xy 92.747824 -250.364143) (xy 92.71112 -250.399398) (xy 92.669236 -250.428308)
			(xy 92.623257 -250.450125) (xy 92.574373 -250.464285) (xy 92.523852 -250.470419) (xy 92.473 -250.46837)
			(xy 92.423136 -250.45819) (xy 92.37555 -250.440143) (xy 92.331476 -250.414697) (xy 92.292054 -250.38251)
			(xy 92.258306 -250.344416) (xy 92.231105 -250.301402) (xy 92.211157 -250.254582) (xy 92.198978 -250.205168)
			(xy 92.194883 -250.15444) (xy 91.876372 -250.15444) (xy 91.875877 -250.179047) (xy 91.867982 -250.227624)
			(xy 91.852398 -250.274305) (xy 91.829527 -250.317882) (xy 91.799962 -250.357226) (xy 91.764469 -250.391318)
			(xy 91.723966 -250.419274) (xy 91.679504 -250.440372) (xy 91.632233 -250.454064) (xy 91.583378 -250.459996)
			(xy 91.534203 -250.458015) (xy 91.485984 -250.448171) (xy 91.439968 -250.430719) (xy 91.397347 -250.406112)
			(xy 91.359226 -250.374987) (xy 91.326591 -250.33815) (xy 91.300288 -250.296554) (xy 91.280997 -250.251278)
			(xy 91.26922 -250.203494) (xy 91.26526 -250.15444) (xy 90.936318 -250.15444) (xy 90.935823 -250.179047)
			(xy 90.927928 -250.227624) (xy 90.912344 -250.274305) (xy 90.889473 -250.317882) (xy 90.859908 -250.357226)
			(xy 90.824415 -250.391318) (xy 90.783912 -250.419274) (xy 90.73945 -250.440372) (xy 90.692179 -250.454064)
			(xy 90.643324 -250.459996) (xy 90.594149 -250.458015) (xy 90.54593 -250.448171) (xy 90.499914 -250.430719)
			(xy 90.457293 -250.406112) (xy 90.419172 -250.374987) (xy 90.386537 -250.33815) (xy 90.360234 -250.296554)
			(xy 90.340943 -250.251278) (xy 90.329166 -250.203494) (xy 90.325206 -250.15444) (xy 89.996264 -250.15444)
			(xy 89.995769 -250.179047) (xy 89.987874 -250.227624) (xy 89.97229 -250.274305) (xy 89.949419 -250.317882)
			(xy 89.919854 -250.357226) (xy 89.884361 -250.391318) (xy 89.843858 -250.419274) (xy 89.799396 -250.440372)
			(xy 89.752125 -250.454064) (xy 89.70327 -250.459996) (xy 89.654095 -250.458015) (xy 89.605876 -250.448171)
			(xy 89.55986 -250.430719) (xy 89.517239 -250.406112) (xy 89.479118 -250.374987) (xy 89.446483 -250.33815)
			(xy 89.42018 -250.296554) (xy 89.400889 -250.251278) (xy 89.389112 -250.203494) (xy 89.385152 -250.15444)
			(xy 89.066878 -250.15444) (xy 89.066366 -250.179886) (xy 89.058202 -250.23012) (xy 89.042086 -250.278394)
			(xy 89.018435 -250.323457) (xy 88.987862 -250.364143) (xy 88.951158 -250.399398) (xy 88.909274 -250.428308)
			(xy 88.863295 -250.450125) (xy 88.814411 -250.464285) (xy 88.76389 -250.470419) (xy 88.713038 -250.46837)
			(xy 88.663174 -250.45819) (xy 88.615588 -250.440143) (xy 88.571514 -250.414697) (xy 88.532092 -250.38251)
			(xy 88.498344 -250.344416) (xy 88.471143 -250.301402) (xy 88.451195 -250.254582) (xy 88.439016 -250.205168)
			(xy 88.434921 -250.15444) (xy 88.11641 -250.15444) (xy 88.115915 -250.179047) (xy 88.10802 -250.227624)
			(xy 88.092436 -250.274305) (xy 88.069565 -250.317882) (xy 88.04 -250.357226) (xy 88.004507 -250.391318)
			(xy 87.964004 -250.419274) (xy 87.919542 -250.440372) (xy 87.872271 -250.454064) (xy 87.823416 -250.459996)
			(xy 87.774241 -250.458015) (xy 87.726022 -250.448171) (xy 87.680006 -250.430719) (xy 87.637385 -250.406112)
			(xy 87.599264 -250.374987) (xy 87.566629 -250.33815) (xy 87.540326 -250.296554) (xy 87.521035 -250.251278)
			(xy 87.509258 -250.203494) (xy 87.505298 -250.15444) (xy 87.176356 -250.15444) (xy 87.175861 -250.179047)
			(xy 87.167966 -250.227624) (xy 87.152382 -250.274305) (xy 87.129511 -250.317882) (xy 87.099946 -250.357226)
			(xy 87.064453 -250.391318) (xy 87.02395 -250.419274) (xy 86.979488 -250.440372) (xy 86.932217 -250.454064)
			(xy 86.883362 -250.459996) (xy 86.834187 -250.458015) (xy 86.785968 -250.448171) (xy 86.739952 -250.430719)
			(xy 86.697331 -250.406112) (xy 86.65921 -250.374987) (xy 86.626575 -250.33815) (xy 86.600272 -250.296554)
			(xy 86.580981 -250.251278) (xy 86.569204 -250.203494) (xy 86.565244 -250.15444) (xy 86.246716 -250.15444)
			(xy 86.246204 -250.179886) (xy 86.23804 -250.23012) (xy 86.221924 -250.278394) (xy 86.198273 -250.323457)
			(xy 86.1677 -250.364143) (xy 86.130996 -250.399398) (xy 86.089112 -250.428308) (xy 86.043133 -250.450125)
			(xy 85.994249 -250.464285) (xy 85.943728 -250.470419) (xy 85.892876 -250.46837) (xy 85.843012 -250.45819)
			(xy 85.795426 -250.440143) (xy 85.751352 -250.414697) (xy 85.71193 -250.38251) (xy 85.678182 -250.344416)
			(xy 85.650981 -250.301402) (xy 85.631033 -250.254582) (xy 85.618854 -250.205168) (xy 85.614759 -250.15444)
			(xy 85.296248 -250.15444) (xy 85.295753 -250.179047) (xy 85.287858 -250.227624) (xy 85.272274 -250.274305)
			(xy 85.249403 -250.317882) (xy 85.219838 -250.357226) (xy 85.184345 -250.391318) (xy 85.143842 -250.419274)
			(xy 85.09938 -250.440372) (xy 85.052109 -250.454064) (xy 85.003254 -250.459996) (xy 84.954079 -250.458015)
			(xy 84.90586 -250.448171) (xy 84.859844 -250.430719) (xy 84.817223 -250.406112) (xy 84.779102 -250.374987)
			(xy 84.746467 -250.33815) (xy 84.720164 -250.296554) (xy 84.700873 -250.251278) (xy 84.689096 -250.203494)
			(xy 84.685136 -250.15444) (xy 84.356448 -250.15444) (xy 84.355953 -250.179047) (xy 84.348058 -250.227624)
			(xy 84.332474 -250.274305) (xy 84.309603 -250.317882) (xy 84.280038 -250.357226) (xy 84.244545 -250.391318)
			(xy 84.204042 -250.419274) (xy 84.15958 -250.440372) (xy 84.112309 -250.454064) (xy 84.063454 -250.459996)
			(xy 84.014279 -250.458015) (xy 83.96606 -250.448171) (xy 83.920044 -250.430719) (xy 83.877423 -250.406112)
			(xy 83.839302 -250.374987) (xy 83.806667 -250.33815) (xy 83.780364 -250.296554) (xy 83.761073 -250.251278)
			(xy 83.749296 -250.203494) (xy 83.745336 -250.15444) (xy 83.416394 -250.15444) (xy 83.415899 -250.179047)
			(xy 83.408004 -250.227624) (xy 83.39242 -250.274305) (xy 83.369549 -250.317882) (xy 83.339984 -250.357226)
			(xy 83.304491 -250.391318) (xy 83.263988 -250.419274) (xy 83.219526 -250.440372) (xy 83.172255 -250.454064)
			(xy 83.1234 -250.459996) (xy 83.074225 -250.458015) (xy 83.026006 -250.448171) (xy 82.97999 -250.430719)
			(xy 82.937369 -250.406112) (xy 82.899248 -250.374987) (xy 82.866613 -250.33815) (xy 82.84031 -250.296554)
			(xy 82.821019 -250.251278) (xy 82.809242 -250.203494) (xy 82.805282 -250.15444) (xy 82.486754 -250.15444)
			(xy 82.486242 -250.179886) (xy 82.478078 -250.23012) (xy 82.461962 -250.278394) (xy 82.438311 -250.323457)
			(xy 82.407738 -250.364143) (xy 82.371034 -250.399398) (xy 82.32915 -250.428308) (xy 82.283171 -250.450125)
			(xy 82.234287 -250.464285) (xy 82.183766 -250.470419) (xy 82.132914 -250.46837) (xy 82.08305 -250.45819)
			(xy 82.035464 -250.440143) (xy 81.99139 -250.414697) (xy 81.951968 -250.38251) (xy 81.91822 -250.344416)
			(xy 81.891019 -250.301402) (xy 81.871071 -250.254582) (xy 81.858892 -250.205168) (xy 81.854797 -250.15444)
			(xy 81.536286 -250.15444) (xy 81.535791 -250.179047) (xy 81.527896 -250.227624) (xy 81.512312 -250.274305)
			(xy 81.489441 -250.317882) (xy 81.459876 -250.357226) (xy 81.424383 -250.391318) (xy 81.38388 -250.419274)
			(xy 81.339418 -250.440372) (xy 81.292147 -250.454064) (xy 81.243292 -250.459996) (xy 81.194117 -250.458015)
			(xy 81.145898 -250.448171) (xy 81.099882 -250.430719) (xy 81.057261 -250.406112) (xy 81.01914 -250.374987)
			(xy 80.986505 -250.33815) (xy 80.960202 -250.296554) (xy 80.940911 -250.251278) (xy 80.929134 -250.203494)
			(xy 80.925174 -250.15444) (xy 80.596486 -250.15444) (xy 80.595991 -250.179047) (xy 80.588096 -250.227624)
			(xy 80.572512 -250.274305) (xy 80.549641 -250.317882) (xy 80.520076 -250.357226) (xy 80.484583 -250.391318)
			(xy 80.44408 -250.419274) (xy 80.399618 -250.440372) (xy 80.352347 -250.454064) (xy 80.303492 -250.459996)
			(xy 80.254317 -250.458015) (xy 80.206098 -250.448171) (xy 80.160082 -250.430719) (xy 80.117461 -250.406112)
			(xy 80.07934 -250.374987) (xy 80.046705 -250.33815) (xy 80.020402 -250.296554) (xy 80.001111 -250.251278)
			(xy 79.989334 -250.203494) (xy 79.985374 -250.15444) (xy 79.656432 -250.15444) (xy 79.655937 -250.179047)
			(xy 79.648042 -250.227624) (xy 79.632458 -250.274305) (xy 79.609587 -250.317882) (xy 79.580022 -250.357226)
			(xy 79.544529 -250.391318) (xy 79.504026 -250.419274) (xy 79.459564 -250.440372) (xy 79.412293 -250.454064)
			(xy 79.363438 -250.459996) (xy 79.314263 -250.458015) (xy 79.266044 -250.448171) (xy 79.220028 -250.430719)
			(xy 79.177407 -250.406112) (xy 79.139286 -250.374987) (xy 79.106651 -250.33815) (xy 79.080348 -250.296554)
			(xy 79.061057 -250.251278) (xy 79.04928 -250.203494) (xy 79.04532 -250.15444) (xy 78.716378 -250.15444)
			(xy 78.715883 -250.179047) (xy 78.707988 -250.227624) (xy 78.692404 -250.274305) (xy 78.669533 -250.317882)
			(xy 78.639968 -250.357226) (xy 78.604475 -250.391318) (xy 78.563972 -250.419274) (xy 78.51951 -250.440372)
			(xy 78.472239 -250.454064) (xy 78.423384 -250.459996) (xy 78.374209 -250.458015) (xy 78.32599 -250.448171)
			(xy 78.279974 -250.430719) (xy 78.237353 -250.406112) (xy 78.199232 -250.374987) (xy 78.166597 -250.33815)
			(xy 78.140294 -250.296554) (xy 78.121003 -250.251278) (xy 78.109226 -250.203494) (xy 78.105266 -250.15444)
			(xy 67.196208 -250.15444) (xy 68.272152 -251.230384) (xy 76.507098 -251.230384) (xy 76.511058 -251.18133)
			(xy 76.522835 -251.133546) (xy 76.542126 -251.08827) (xy 76.568429 -251.046674) (xy 76.601064 -251.009837)
			(xy 76.639185 -250.978712) (xy 76.681806 -250.954105) (xy 76.727822 -250.936653) (xy 76.776041 -250.926809)
			(xy 76.825216 -250.924828) (xy 76.874071 -250.93076) (xy 76.921342 -250.944452) (xy 76.963477 -250.964446)
			(xy 78.575166 -250.964446) (xy 78.579126 -250.915392) (xy 78.590903 -250.867608) (xy 78.610194 -250.822332)
			(xy 78.636497 -250.780736) (xy 78.669132 -250.743899) (xy 78.707253 -250.712774) (xy 78.749874 -250.688167)
			(xy 78.79589 -250.670715) (xy 78.844109 -250.660871) (xy 78.893284 -250.65889) (xy 78.942139 -250.664822)
			(xy 78.98941 -250.678514) (xy 79.033872 -250.699612) (xy 79.074375 -250.727568) (xy 79.109868 -250.76166)
			(xy 79.139433 -250.801004) (xy 79.162304 -250.844581) (xy 79.177888 -250.891262) (xy 79.185783 -250.939839)
			(xy 79.186278 -250.964446) (xy 79.51522 -250.964446) (xy 79.51918 -250.915392) (xy 79.530957 -250.867608)
			(xy 79.550248 -250.822332) (xy 79.576551 -250.780736) (xy 79.609186 -250.743899) (xy 79.647307 -250.712774)
			(xy 79.689928 -250.688167) (xy 79.735944 -250.670715) (xy 79.784163 -250.660871) (xy 79.833338 -250.65889)
			(xy 79.882193 -250.664822) (xy 79.929464 -250.678514) (xy 79.973926 -250.699612) (xy 80.014429 -250.727568)
			(xy 80.049922 -250.76166) (xy 80.079487 -250.801004) (xy 80.102358 -250.844581) (xy 80.117942 -250.891262)
			(xy 80.125837 -250.939839) (xy 80.126332 -250.964446) (xy 80.455274 -250.964446) (xy 80.459234 -250.915392)
			(xy 80.471011 -250.867608) (xy 80.490302 -250.822332) (xy 80.516605 -250.780736) (xy 80.54924 -250.743899)
			(xy 80.587361 -250.712774) (xy 80.629982 -250.688167) (xy 80.675998 -250.670715) (xy 80.724217 -250.660871)
			(xy 80.773392 -250.65889) (xy 80.822247 -250.664822) (xy 80.869518 -250.678514) (xy 80.91398 -250.699612)
			(xy 80.954483 -250.727568) (xy 80.989976 -250.76166) (xy 81.019541 -250.801004) (xy 81.042412 -250.844581)
			(xy 81.057996 -250.891262) (xy 81.065891 -250.939839) (xy 81.066386 -250.964446) (xy 81.395328 -250.964446)
			(xy 81.399288 -250.915392) (xy 81.411065 -250.867608) (xy 81.430356 -250.822332) (xy 81.456659 -250.780736)
			(xy 81.489294 -250.743899) (xy 81.527415 -250.712774) (xy 81.570036 -250.688167) (xy 81.616052 -250.670715)
			(xy 81.664271 -250.660871) (xy 81.713446 -250.65889) (xy 81.762301 -250.664822) (xy 81.809572 -250.678514)
			(xy 81.854034 -250.699612) (xy 81.894537 -250.727568) (xy 81.93003 -250.76166) (xy 81.959595 -250.801004)
			(xy 81.982466 -250.844581) (xy 81.99805 -250.891262) (xy 82.005945 -250.939839) (xy 82.00644 -250.964446)
			(xy 82.324697 -250.964446) (xy 82.328792 -250.913718) (xy 82.340971 -250.864304) (xy 82.360919 -250.817484)
			(xy 82.38812 -250.77447) (xy 82.421868 -250.736376) (xy 82.46129 -250.704189) (xy 82.505364 -250.678743)
			(xy 82.55295 -250.660696) (xy 82.602814 -250.650516) (xy 82.653666 -250.648467) (xy 82.704187 -250.654601)
			(xy 82.753071 -250.668761) (xy 82.79905 -250.690578) (xy 82.840934 -250.719488) (xy 82.877638 -250.754743)
			(xy 82.908211 -250.795429) (xy 82.931862 -250.840492) (xy 82.947978 -250.888766) (xy 82.956142 -250.939)
			(xy 82.956654 -250.964446) (xy 83.275182 -250.964446) (xy 83.279142 -250.915392) (xy 83.290919 -250.867608)
			(xy 83.31021 -250.822332) (xy 83.336513 -250.780736) (xy 83.369148 -250.743899) (xy 83.407269 -250.712774)
			(xy 83.44989 -250.688167) (xy 83.495906 -250.670715) (xy 83.544125 -250.660871) (xy 83.5933 -250.65889)
			(xy 83.642155 -250.664822) (xy 83.689426 -250.678514) (xy 83.733888 -250.699612) (xy 83.774391 -250.727568)
			(xy 83.809884 -250.76166) (xy 83.839449 -250.801004) (xy 83.86232 -250.844581) (xy 83.877904 -250.891262)
			(xy 83.885799 -250.939839) (xy 83.886294 -250.964446) (xy 84.215236 -250.964446) (xy 84.219196 -250.915392)
			(xy 84.230973 -250.867608) (xy 84.250264 -250.822332) (xy 84.276567 -250.780736) (xy 84.309202 -250.743899)
			(xy 84.347323 -250.712774) (xy 84.389944 -250.688167) (xy 84.43596 -250.670715) (xy 84.484179 -250.660871)
			(xy 84.533354 -250.65889) (xy 84.582209 -250.664822) (xy 84.62948 -250.678514) (xy 84.673942 -250.699612)
			(xy 84.714445 -250.727568) (xy 84.749938 -250.76166) (xy 84.779503 -250.801004) (xy 84.802374 -250.844581)
			(xy 84.817958 -250.891262) (xy 84.825853 -250.939839) (xy 84.826348 -250.964446) (xy 85.144859 -250.964446)
			(xy 85.148954 -250.913718) (xy 85.161133 -250.864304) (xy 85.181081 -250.817484) (xy 85.208282 -250.77447)
			(xy 85.24203 -250.736376) (xy 85.281452 -250.704189) (xy 85.325526 -250.678743) (xy 85.373112 -250.660696)
			(xy 85.422976 -250.650516) (xy 85.473828 -250.648467) (xy 85.524349 -250.654601) (xy 85.573233 -250.668761)
			(xy 85.619212 -250.690578) (xy 85.661096 -250.719488) (xy 85.6978 -250.754743) (xy 85.728373 -250.795429)
			(xy 85.752024 -250.840492) (xy 85.76814 -250.888766) (xy 85.776304 -250.939) (xy 85.776816 -250.964446)
			(xy 86.095344 -250.964446) (xy 86.099304 -250.915392) (xy 86.111081 -250.867608) (xy 86.130372 -250.822332)
			(xy 86.156675 -250.780736) (xy 86.18931 -250.743899) (xy 86.227431 -250.712774) (xy 86.270052 -250.688167)
			(xy 86.316068 -250.670715) (xy 86.364287 -250.660871) (xy 86.413462 -250.65889) (xy 86.462317 -250.664822)
			(xy 86.509588 -250.678514) (xy 86.55405 -250.699612) (xy 86.594553 -250.727568) (xy 86.630046 -250.76166)
			(xy 86.659611 -250.801004) (xy 86.682482 -250.844581) (xy 86.698066 -250.891262) (xy 86.705961 -250.939839)
			(xy 86.706456 -250.964446) (xy 87.035144 -250.964446) (xy 87.039104 -250.915392) (xy 87.050881 -250.867608)
			(xy 87.070172 -250.822332) (xy 87.096475 -250.780736) (xy 87.12911 -250.743899) (xy 87.167231 -250.712774)
			(xy 87.209852 -250.688167) (xy 87.255868 -250.670715) (xy 87.304087 -250.660871) (xy 87.353262 -250.65889)
			(xy 87.402117 -250.664822) (xy 87.449388 -250.678514) (xy 87.49385 -250.699612) (xy 87.534353 -250.727568)
			(xy 87.569846 -250.76166) (xy 87.599411 -250.801004) (xy 87.622282 -250.844581) (xy 87.637866 -250.891262)
			(xy 87.645761 -250.939839) (xy 87.646256 -250.964446) (xy 87.975198 -250.964446) (xy 87.979158 -250.915392)
			(xy 87.990935 -250.867608) (xy 88.010226 -250.822332) (xy 88.036529 -250.780736) (xy 88.069164 -250.743899)
			(xy 88.107285 -250.712774) (xy 88.149906 -250.688167) (xy 88.195922 -250.670715) (xy 88.244141 -250.660871)
			(xy 88.293316 -250.65889) (xy 88.342171 -250.664822) (xy 88.389442 -250.678514) (xy 88.433904 -250.699612)
			(xy 88.474407 -250.727568) (xy 88.5099 -250.76166) (xy 88.539465 -250.801004) (xy 88.562336 -250.844581)
			(xy 88.57792 -250.891262) (xy 88.585815 -250.939839) (xy 88.58631 -250.964446) (xy 88.904821 -250.964446)
			(xy 88.908916 -250.913718) (xy 88.921095 -250.864304) (xy 88.941043 -250.817484) (xy 88.968244 -250.77447)
			(xy 89.001992 -250.736376) (xy 89.041414 -250.704189) (xy 89.085488 -250.678743) (xy 89.133074 -250.660696)
			(xy 89.182938 -250.650516) (xy 89.23379 -250.648467) (xy 89.284311 -250.654601) (xy 89.333195 -250.668761)
			(xy 89.379174 -250.690578) (xy 89.421058 -250.719488) (xy 89.457762 -250.754743) (xy 89.488335 -250.795429)
			(xy 89.511986 -250.840492) (xy 89.528102 -250.888766) (xy 89.536266 -250.939) (xy 89.536778 -250.964446)
			(xy 89.855306 -250.964446) (xy 89.859266 -250.915392) (xy 89.871043 -250.867608) (xy 89.890334 -250.822332)
			(xy 89.916637 -250.780736) (xy 89.949272 -250.743899) (xy 89.987393 -250.712774) (xy 90.030014 -250.688167)
			(xy 90.07603 -250.670715) (xy 90.124249 -250.660871) (xy 90.173424 -250.65889) (xy 90.222279 -250.664822)
			(xy 90.26955 -250.678514) (xy 90.314012 -250.699612) (xy 90.354515 -250.727568) (xy 90.390008 -250.76166)
			(xy 90.419573 -250.801004) (xy 90.442444 -250.844581) (xy 90.458028 -250.891262) (xy 90.465923 -250.939839)
			(xy 90.466418 -250.964446) (xy 90.79536 -250.964446) (xy 90.79932 -250.915392) (xy 90.811097 -250.867608)
			(xy 90.830388 -250.822332) (xy 90.856691 -250.780736) (xy 90.889326 -250.743899) (xy 90.927447 -250.712774)
			(xy 90.970068 -250.688167) (xy 91.016084 -250.670715) (xy 91.064303 -250.660871) (xy 91.113478 -250.65889)
			(xy 91.162333 -250.664822) (xy 91.209604 -250.678514) (xy 91.254066 -250.699612) (xy 91.294569 -250.727568)
			(xy 91.330062 -250.76166) (xy 91.359627 -250.801004) (xy 91.382498 -250.844581) (xy 91.398082 -250.891262)
			(xy 91.405977 -250.939839) (xy 91.406472 -250.964446) (xy 91.724729 -250.964446) (xy 91.728824 -250.913718)
			(xy 91.741003 -250.864304) (xy 91.760951 -250.817484) (xy 91.788152 -250.77447) (xy 91.8219 -250.736376)
			(xy 91.861322 -250.704189) (xy 91.905396 -250.678743) (xy 91.952982 -250.660696) (xy 92.002846 -250.650516)
			(xy 92.053698 -250.648467) (xy 92.104219 -250.654601) (xy 92.153103 -250.668761) (xy 92.199082 -250.690578)
			(xy 92.240966 -250.719488) (xy 92.27767 -250.754743) (xy 92.308243 -250.795429) (xy 92.331894 -250.840492)
			(xy 92.34801 -250.888766) (xy 92.356174 -250.939) (xy 92.356686 -250.964446) (xy 92.675214 -250.964446)
			(xy 92.679174 -250.915392) (xy 92.690951 -250.867608) (xy 92.710242 -250.822332) (xy 92.736545 -250.780736)
			(xy 92.76918 -250.743899) (xy 92.807301 -250.712774) (xy 92.849922 -250.688167) (xy 92.895938 -250.670715)
			(xy 92.944157 -250.660871) (xy 92.993332 -250.65889) (xy 93.042187 -250.664822) (xy 93.089458 -250.678514)
			(xy 93.13392 -250.699612) (xy 93.174423 -250.727568) (xy 93.209916 -250.76166) (xy 93.239481 -250.801004)
			(xy 93.262352 -250.844581) (xy 93.277936 -250.891262) (xy 93.285831 -250.939839) (xy 93.286326 -250.964446)
			(xy 93.615268 -250.964446) (xy 93.619228 -250.915392) (xy 93.631005 -250.867608) (xy 93.650296 -250.822332)
			(xy 93.676599 -250.780736) (xy 93.709234 -250.743899) (xy 93.747355 -250.712774) (xy 93.789976 -250.688167)
			(xy 93.835992 -250.670715) (xy 93.884211 -250.660871) (xy 93.933386 -250.65889) (xy 93.982241 -250.664822)
			(xy 94.029512 -250.678514) (xy 94.073974 -250.699612) (xy 94.114477 -250.727568) (xy 94.14997 -250.76166)
			(xy 94.179535 -250.801004) (xy 94.202406 -250.844581) (xy 94.21799 -250.891262) (xy 94.225885 -250.939839)
			(xy 94.22638 -250.964446) (xy 94.555322 -250.964446) (xy 94.559282 -250.915392) (xy 94.571059 -250.867608)
			(xy 94.59035 -250.822332) (xy 94.616653 -250.780736) (xy 94.649288 -250.743899) (xy 94.687409 -250.712774)
			(xy 94.73003 -250.688167) (xy 94.776046 -250.670715) (xy 94.824265 -250.660871) (xy 94.87344 -250.65889)
			(xy 94.922295 -250.664822) (xy 94.969566 -250.678514) (xy 95.014028 -250.699612) (xy 95.054531 -250.727568)
			(xy 95.090024 -250.76166) (xy 95.119589 -250.801004) (xy 95.14246 -250.844581) (xy 95.158044 -250.891262)
			(xy 95.165939 -250.939839) (xy 95.166434 -250.964446) (xy 95.484691 -250.964446) (xy 95.488786 -250.913718)
			(xy 95.500965 -250.864304) (xy 95.520913 -250.817484) (xy 95.548114 -250.77447) (xy 95.581862 -250.736376)
			(xy 95.621284 -250.704189) (xy 95.665358 -250.678743) (xy 95.712944 -250.660696) (xy 95.762808 -250.650516)
			(xy 95.81366 -250.648467) (xy 95.864181 -250.654601) (xy 95.913065 -250.668761) (xy 95.959044 -250.690578)
			(xy 96.000928 -250.719488) (xy 96.037632 -250.754743) (xy 96.068205 -250.795429) (xy 96.091856 -250.840492)
			(xy 96.107972 -250.888766) (xy 96.116136 -250.939) (xy 96.116648 -250.964446) (xy 96.435176 -250.964446)
			(xy 96.439136 -250.915392) (xy 96.450913 -250.867608) (xy 96.470204 -250.822332) (xy 96.496507 -250.780736)
			(xy 96.529142 -250.743899) (xy 96.567263 -250.712774) (xy 96.609884 -250.688167) (xy 96.6559 -250.670715)
			(xy 96.704119 -250.660871) (xy 96.753294 -250.65889) (xy 96.802149 -250.664822) (xy 96.84942 -250.678514)
			(xy 96.893882 -250.699612) (xy 96.934385 -250.727568) (xy 96.969878 -250.76166) (xy 96.999443 -250.801004)
			(xy 97.022314 -250.844581) (xy 97.037898 -250.891262) (xy 97.045793 -250.939839) (xy 97.046288 -250.964446)
			(xy 97.37523 -250.964446) (xy 97.37919 -250.915392) (xy 97.390967 -250.867608) (xy 97.410258 -250.822332)
			(xy 97.436561 -250.780736) (xy 97.469196 -250.743899) (xy 97.507317 -250.712774) (xy 97.549938 -250.688167)
			(xy 97.595954 -250.670715) (xy 97.644173 -250.660871) (xy 97.693348 -250.65889) (xy 97.742203 -250.664822)
			(xy 97.789474 -250.678514) (xy 97.833936 -250.699612) (xy 97.874439 -250.727568) (xy 97.909932 -250.76166)
			(xy 97.939497 -250.801004) (xy 97.962368 -250.844581) (xy 97.977952 -250.891262) (xy 97.985847 -250.939839)
			(xy 97.986342 -250.964446) (xy 98.315284 -250.964446) (xy 98.319244 -250.915392) (xy 98.331021 -250.867608)
			(xy 98.350312 -250.822332) (xy 98.376615 -250.780736) (xy 98.40925 -250.743899) (xy 98.447371 -250.712774)
			(xy 98.489992 -250.688167) (xy 98.536008 -250.670715) (xy 98.584227 -250.660871) (xy 98.633402 -250.65889)
			(xy 98.682257 -250.664822) (xy 98.729528 -250.678514) (xy 98.77399 -250.699612) (xy 98.814493 -250.727568)
			(xy 98.849986 -250.76166) (xy 98.879551 -250.801004) (xy 98.902422 -250.844581) (xy 98.918006 -250.891262)
			(xy 98.925901 -250.939839) (xy 98.926396 -250.964446) (xy 99.255338 -250.964446) (xy 99.259298 -250.915392)
			(xy 99.271075 -250.867608) (xy 99.290366 -250.822332) (xy 99.316669 -250.780736) (xy 99.349304 -250.743899)
			(xy 99.387425 -250.712774) (xy 99.430046 -250.688167) (xy 99.476062 -250.670715) (xy 99.524281 -250.660871)
			(xy 99.573456 -250.65889) (xy 99.622311 -250.664822) (xy 99.669582 -250.678514) (xy 99.714044 -250.699612)
			(xy 99.754547 -250.727568) (xy 99.79004 -250.76166) (xy 99.819605 -250.801004) (xy 99.842476 -250.844581)
			(xy 99.85806 -250.891262) (xy 99.865955 -250.939839) (xy 99.86645 -250.964446) (xy 100.195138 -250.964446)
			(xy 100.199098 -250.915392) (xy 100.210875 -250.867608) (xy 100.230166 -250.822332) (xy 100.256469 -250.780736)
			(xy 100.289104 -250.743899) (xy 100.327225 -250.712774) (xy 100.369846 -250.688167) (xy 100.415862 -250.670715)
			(xy 100.464081 -250.660871) (xy 100.513256 -250.65889) (xy 100.562111 -250.664822) (xy 100.609382 -250.678514)
			(xy 100.653844 -250.699612) (xy 100.694347 -250.727568) (xy 100.72984 -250.76166) (xy 100.759405 -250.801004)
			(xy 100.782276 -250.844581) (xy 100.79786 -250.891262) (xy 100.805755 -250.939839) (xy 100.80625 -250.964446)
			(xy 100.805755 -250.989053) (xy 100.79786 -251.03763) (xy 100.782276 -251.084311) (xy 100.759405 -251.127888)
			(xy 100.72984 -251.167232) (xy 100.694347 -251.201324) (xy 100.653844 -251.22928) (xy 100.609382 -251.250378)
			(xy 100.562111 -251.26407) (xy 100.513256 -251.270002) (xy 100.464081 -251.268021) (xy 100.415862 -251.258177)
			(xy 100.369846 -251.240725) (xy 100.327225 -251.216118) (xy 100.289104 -251.184993) (xy 100.256469 -251.148156)
			(xy 100.230166 -251.10656) (xy 100.210875 -251.061284) (xy 100.199098 -251.0135) (xy 100.195138 -250.964446)
			(xy 99.86645 -250.964446) (xy 99.865955 -250.989053) (xy 99.85806 -251.03763) (xy 99.842476 -251.084311)
			(xy 99.819605 -251.127888) (xy 99.79004 -251.167232) (xy 99.754547 -251.201324) (xy 99.714044 -251.22928)
			(xy 99.669582 -251.250378) (xy 99.622311 -251.26407) (xy 99.573456 -251.270002) (xy 99.524281 -251.268021)
			(xy 99.476062 -251.258177) (xy 99.430046 -251.240725) (xy 99.387425 -251.216118) (xy 99.349304 -251.184993)
			(xy 99.316669 -251.148156) (xy 99.290366 -251.10656) (xy 99.271075 -251.061284) (xy 99.259298 -251.0135)
			(xy 99.255338 -250.964446) (xy 98.926396 -250.964446) (xy 98.925901 -250.989053) (xy 98.918006 -251.03763)
			(xy 98.902422 -251.084311) (xy 98.879551 -251.127888) (xy 98.849986 -251.167232) (xy 98.814493 -251.201324)
			(xy 98.77399 -251.22928) (xy 98.729528 -251.250378) (xy 98.682257 -251.26407) (xy 98.633402 -251.270002)
			(xy 98.584227 -251.268021) (xy 98.536008 -251.258177) (xy 98.489992 -251.240725) (xy 98.447371 -251.216118)
			(xy 98.40925 -251.184993) (xy 98.376615 -251.148156) (xy 98.350312 -251.10656) (xy 98.331021 -251.061284)
			(xy 98.319244 -251.0135) (xy 98.315284 -250.964446) (xy 97.986342 -250.964446) (xy 97.985847 -250.989053)
			(xy 97.977952 -251.03763) (xy 97.962368 -251.084311) (xy 97.939497 -251.127888) (xy 97.909932 -251.167232)
			(xy 97.874439 -251.201324) (xy 97.833936 -251.22928) (xy 97.789474 -251.250378) (xy 97.742203 -251.26407)
			(xy 97.693348 -251.270002) (xy 97.644173 -251.268021) (xy 97.595954 -251.258177) (xy 97.549938 -251.240725)
			(xy 97.507317 -251.216118) (xy 97.469196 -251.184993) (xy 97.436561 -251.148156) (xy 97.410258 -251.10656)
			(xy 97.390967 -251.061284) (xy 97.37919 -251.0135) (xy 97.37523 -250.964446) (xy 97.046288 -250.964446)
			(xy 97.045793 -250.989053) (xy 97.037898 -251.03763) (xy 97.022314 -251.084311) (xy 96.999443 -251.127888)
			(xy 96.969878 -251.167232) (xy 96.934385 -251.201324) (xy 96.893882 -251.22928) (xy 96.84942 -251.250378)
			(xy 96.802149 -251.26407) (xy 96.753294 -251.270002) (xy 96.704119 -251.268021) (xy 96.6559 -251.258177)
			(xy 96.609884 -251.240725) (xy 96.567263 -251.216118) (xy 96.529142 -251.184993) (xy 96.496507 -251.148156)
			(xy 96.470204 -251.10656) (xy 96.450913 -251.061284) (xy 96.439136 -251.0135) (xy 96.435176 -250.964446)
			(xy 96.116648 -250.964446) (xy 96.116136 -250.989892) (xy 96.107972 -251.040126) (xy 96.091856 -251.0884)
			(xy 96.068205 -251.133463) (xy 96.037632 -251.174149) (xy 96.000928 -251.209404) (xy 95.959044 -251.238314)
			(xy 95.913065 -251.260131) (xy 95.864181 -251.274291) (xy 95.81366 -251.280425) (xy 95.762808 -251.278376)
			(xy 95.712944 -251.268196) (xy 95.665358 -251.250149) (xy 95.621284 -251.224703) (xy 95.581862 -251.192516)
			(xy 95.548114 -251.154422) (xy 95.520913 -251.111408) (xy 95.500965 -251.064588) (xy 95.488786 -251.015174)
			(xy 95.484691 -250.964446) (xy 95.166434 -250.964446) (xy 95.165939 -250.989053) (xy 95.158044 -251.03763)
			(xy 95.14246 -251.084311) (xy 95.119589 -251.127888) (xy 95.090024 -251.167232) (xy 95.054531 -251.201324)
			(xy 95.014028 -251.22928) (xy 94.969566 -251.250378) (xy 94.922295 -251.26407) (xy 94.87344 -251.270002)
			(xy 94.824265 -251.268021) (xy 94.776046 -251.258177) (xy 94.73003 -251.240725) (xy 94.687409 -251.216118)
			(xy 94.649288 -251.184993) (xy 94.616653 -251.148156) (xy 94.59035 -251.10656) (xy 94.571059 -251.061284)
			(xy 94.559282 -251.0135) (xy 94.555322 -250.964446) (xy 94.22638 -250.964446) (xy 94.225885 -250.989053)
			(xy 94.21799 -251.03763) (xy 94.202406 -251.084311) (xy 94.179535 -251.127888) (xy 94.14997 -251.167232)
			(xy 94.114477 -251.201324) (xy 94.073974 -251.22928) (xy 94.029512 -251.250378) (xy 93.982241 -251.26407)
			(xy 93.933386 -251.270002) (xy 93.884211 -251.268021) (xy 93.835992 -251.258177) (xy 93.789976 -251.240725)
			(xy 93.747355 -251.216118) (xy 93.709234 -251.184993) (xy 93.676599 -251.148156) (xy 93.650296 -251.10656)
			(xy 93.631005 -251.061284) (xy 93.619228 -251.0135) (xy 93.615268 -250.964446) (xy 93.286326 -250.964446)
			(xy 93.285831 -250.989053) (xy 93.277936 -251.03763) (xy 93.262352 -251.084311) (xy 93.239481 -251.127888)
			(xy 93.209916 -251.167232) (xy 93.174423 -251.201324) (xy 93.13392 -251.22928) (xy 93.089458 -251.250378)
			(xy 93.042187 -251.26407) (xy 92.993332 -251.270002) (xy 92.944157 -251.268021) (xy 92.895938 -251.258177)
			(xy 92.849922 -251.240725) (xy 92.807301 -251.216118) (xy 92.76918 -251.184993) (xy 92.736545 -251.148156)
			(xy 92.710242 -251.10656) (xy 92.690951 -251.061284) (xy 92.679174 -251.0135) (xy 92.675214 -250.964446)
			(xy 92.356686 -250.964446) (xy 92.356174 -250.989892) (xy 92.34801 -251.040126) (xy 92.331894 -251.0884)
			(xy 92.308243 -251.133463) (xy 92.27767 -251.174149) (xy 92.240966 -251.209404) (xy 92.199082 -251.238314)
			(xy 92.153103 -251.260131) (xy 92.104219 -251.274291) (xy 92.053698 -251.280425) (xy 92.002846 -251.278376)
			(xy 91.952982 -251.268196) (xy 91.905396 -251.250149) (xy 91.861322 -251.224703) (xy 91.8219 -251.192516)
			(xy 91.788152 -251.154422) (xy 91.760951 -251.111408) (xy 91.741003 -251.064588) (xy 91.728824 -251.015174)
			(xy 91.724729 -250.964446) (xy 91.406472 -250.964446) (xy 91.405977 -250.989053) (xy 91.398082 -251.03763)
			(xy 91.382498 -251.084311) (xy 91.359627 -251.127888) (xy 91.330062 -251.167232) (xy 91.294569 -251.201324)
			(xy 91.254066 -251.22928) (xy 91.209604 -251.250378) (xy 91.162333 -251.26407) (xy 91.113478 -251.270002)
			(xy 91.064303 -251.268021) (xy 91.016084 -251.258177) (xy 90.970068 -251.240725) (xy 90.927447 -251.216118)
			(xy 90.889326 -251.184993) (xy 90.856691 -251.148156) (xy 90.830388 -251.10656) (xy 90.811097 -251.061284)
			(xy 90.79932 -251.0135) (xy 90.79536 -250.964446) (xy 90.466418 -250.964446) (xy 90.465923 -250.989053)
			(xy 90.458028 -251.03763) (xy 90.442444 -251.084311) (xy 90.419573 -251.127888) (xy 90.390008 -251.167232)
			(xy 90.354515 -251.201324) (xy 90.314012 -251.22928) (xy 90.26955 -251.250378) (xy 90.222279 -251.26407)
			(xy 90.173424 -251.270002) (xy 90.124249 -251.268021) (xy 90.07603 -251.258177) (xy 90.030014 -251.240725)
			(xy 89.987393 -251.216118) (xy 89.949272 -251.184993) (xy 89.916637 -251.148156) (xy 89.890334 -251.10656)
			(xy 89.871043 -251.061284) (xy 89.859266 -251.0135) (xy 89.855306 -250.964446) (xy 89.536778 -250.964446)
			(xy 89.536266 -250.989892) (xy 89.528102 -251.040126) (xy 89.511986 -251.0884) (xy 89.488335 -251.133463)
			(xy 89.457762 -251.174149) (xy 89.421058 -251.209404) (xy 89.379174 -251.238314) (xy 89.333195 -251.260131)
			(xy 89.284311 -251.274291) (xy 89.23379 -251.280425) (xy 89.182938 -251.278376) (xy 89.133074 -251.268196)
			(xy 89.085488 -251.250149) (xy 89.041414 -251.224703) (xy 89.001992 -251.192516) (xy 88.968244 -251.154422)
			(xy 88.941043 -251.111408) (xy 88.921095 -251.064588) (xy 88.908916 -251.015174) (xy 88.904821 -250.964446)
			(xy 88.58631 -250.964446) (xy 88.585815 -250.989053) (xy 88.57792 -251.03763) (xy 88.562336 -251.084311)
			(xy 88.539465 -251.127888) (xy 88.5099 -251.167232) (xy 88.474407 -251.201324) (xy 88.433904 -251.22928)
			(xy 88.389442 -251.250378) (xy 88.342171 -251.26407) (xy 88.293316 -251.270002) (xy 88.244141 -251.268021)
			(xy 88.195922 -251.258177) (xy 88.149906 -251.240725) (xy 88.107285 -251.216118) (xy 88.069164 -251.184993)
			(xy 88.036529 -251.148156) (xy 88.010226 -251.10656) (xy 87.990935 -251.061284) (xy 87.979158 -251.0135)
			(xy 87.975198 -250.964446) (xy 87.646256 -250.964446) (xy 87.645761 -250.989053) (xy 87.637866 -251.03763)
			(xy 87.622282 -251.084311) (xy 87.599411 -251.127888) (xy 87.569846 -251.167232) (xy 87.534353 -251.201324)
			(xy 87.49385 -251.22928) (xy 87.449388 -251.250378) (xy 87.402117 -251.26407) (xy 87.353262 -251.270002)
			(xy 87.304087 -251.268021) (xy 87.255868 -251.258177) (xy 87.209852 -251.240725) (xy 87.167231 -251.216118)
			(xy 87.12911 -251.184993) (xy 87.096475 -251.148156) (xy 87.070172 -251.10656) (xy 87.050881 -251.061284)
			(xy 87.039104 -251.0135) (xy 87.035144 -250.964446) (xy 86.706456 -250.964446) (xy 86.705961 -250.989053)
			(xy 86.698066 -251.03763) (xy 86.682482 -251.084311) (xy 86.659611 -251.127888) (xy 86.630046 -251.167232)
			(xy 86.594553 -251.201324) (xy 86.55405 -251.22928) (xy 86.509588 -251.250378) (xy 86.462317 -251.26407)
			(xy 86.413462 -251.270002) (xy 86.364287 -251.268021) (xy 86.316068 -251.258177) (xy 86.270052 -251.240725)
			(xy 86.227431 -251.216118) (xy 86.18931 -251.184993) (xy 86.156675 -251.148156) (xy 86.130372 -251.10656)
			(xy 86.111081 -251.061284) (xy 86.099304 -251.0135) (xy 86.095344 -250.964446) (xy 85.776816 -250.964446)
			(xy 85.776304 -250.989892) (xy 85.76814 -251.040126) (xy 85.752024 -251.0884) (xy 85.728373 -251.133463)
			(xy 85.6978 -251.174149) (xy 85.661096 -251.209404) (xy 85.619212 -251.238314) (xy 85.573233 -251.260131)
			(xy 85.524349 -251.274291) (xy 85.473828 -251.280425) (xy 85.422976 -251.278376) (xy 85.373112 -251.268196)
			(xy 85.325526 -251.250149) (xy 85.281452 -251.224703) (xy 85.24203 -251.192516) (xy 85.208282 -251.154422)
			(xy 85.181081 -251.111408) (xy 85.161133 -251.064588) (xy 85.148954 -251.015174) (xy 85.144859 -250.964446)
			(xy 84.826348 -250.964446) (xy 84.825853 -250.989053) (xy 84.817958 -251.03763) (xy 84.802374 -251.084311)
			(xy 84.779503 -251.127888) (xy 84.749938 -251.167232) (xy 84.714445 -251.201324) (xy 84.673942 -251.22928)
			(xy 84.62948 -251.250378) (xy 84.582209 -251.26407) (xy 84.533354 -251.270002) (xy 84.484179 -251.268021)
			(xy 84.43596 -251.258177) (xy 84.389944 -251.240725) (xy 84.347323 -251.216118) (xy 84.309202 -251.184993)
			(xy 84.276567 -251.148156) (xy 84.250264 -251.10656) (xy 84.230973 -251.061284) (xy 84.219196 -251.0135)
			(xy 84.215236 -250.964446) (xy 83.886294 -250.964446) (xy 83.885799 -250.989053) (xy 83.877904 -251.03763)
			(xy 83.86232 -251.084311) (xy 83.839449 -251.127888) (xy 83.809884 -251.167232) (xy 83.774391 -251.201324)
			(xy 83.733888 -251.22928) (xy 83.689426 -251.250378) (xy 83.642155 -251.26407) (xy 83.5933 -251.270002)
			(xy 83.544125 -251.268021) (xy 83.495906 -251.258177) (xy 83.44989 -251.240725) (xy 83.407269 -251.216118)
			(xy 83.369148 -251.184993) (xy 83.336513 -251.148156) (xy 83.31021 -251.10656) (xy 83.290919 -251.061284)
			(xy 83.279142 -251.0135) (xy 83.275182 -250.964446) (xy 82.956654 -250.964446) (xy 82.956142 -250.989892)
			(xy 82.947978 -251.040126) (xy 82.931862 -251.0884) (xy 82.908211 -251.133463) (xy 82.877638 -251.174149)
			(xy 82.840934 -251.209404) (xy 82.79905 -251.238314) (xy 82.753071 -251.260131) (xy 82.704187 -251.274291)
			(xy 82.653666 -251.280425) (xy 82.602814 -251.278376) (xy 82.55295 -251.268196) (xy 82.505364 -251.250149)
			(xy 82.46129 -251.224703) (xy 82.421868 -251.192516) (xy 82.38812 -251.154422) (xy 82.360919 -251.111408)
			(xy 82.340971 -251.064588) (xy 82.328792 -251.015174) (xy 82.324697 -250.964446) (xy 82.00644 -250.964446)
			(xy 82.005945 -250.989053) (xy 81.99805 -251.03763) (xy 81.982466 -251.084311) (xy 81.959595 -251.127888)
			(xy 81.93003 -251.167232) (xy 81.894537 -251.201324) (xy 81.854034 -251.22928) (xy 81.809572 -251.250378)
			(xy 81.762301 -251.26407) (xy 81.713446 -251.270002) (xy 81.664271 -251.268021) (xy 81.616052 -251.258177)
			(xy 81.570036 -251.240725) (xy 81.527415 -251.216118) (xy 81.489294 -251.184993) (xy 81.456659 -251.148156)
			(xy 81.430356 -251.10656) (xy 81.411065 -251.061284) (xy 81.399288 -251.0135) (xy 81.395328 -250.964446)
			(xy 81.066386 -250.964446) (xy 81.065891 -250.989053) (xy 81.057996 -251.03763) (xy 81.042412 -251.084311)
			(xy 81.019541 -251.127888) (xy 80.989976 -251.167232) (xy 80.954483 -251.201324) (xy 80.91398 -251.22928)
			(xy 80.869518 -251.250378) (xy 80.822247 -251.26407) (xy 80.773392 -251.270002) (xy 80.724217 -251.268021)
			(xy 80.675998 -251.258177) (xy 80.629982 -251.240725) (xy 80.587361 -251.216118) (xy 80.54924 -251.184993)
			(xy 80.516605 -251.148156) (xy 80.490302 -251.10656) (xy 80.471011 -251.061284) (xy 80.459234 -251.0135)
			(xy 80.455274 -250.964446) (xy 80.126332 -250.964446) (xy 80.125837 -250.989053) (xy 80.117942 -251.03763)
			(xy 80.102358 -251.084311) (xy 80.079487 -251.127888) (xy 80.049922 -251.167232) (xy 80.014429 -251.201324)
			(xy 79.973926 -251.22928) (xy 79.929464 -251.250378) (xy 79.882193 -251.26407) (xy 79.833338 -251.270002)
			(xy 79.784163 -251.268021) (xy 79.735944 -251.258177) (xy 79.689928 -251.240725) (xy 79.647307 -251.216118)
			(xy 79.609186 -251.184993) (xy 79.576551 -251.148156) (xy 79.550248 -251.10656) (xy 79.530957 -251.061284)
			(xy 79.51918 -251.0135) (xy 79.51522 -250.964446) (xy 79.186278 -250.964446) (xy 79.185783 -250.989053)
			(xy 79.177888 -251.03763) (xy 79.162304 -251.084311) (xy 79.139433 -251.127888) (xy 79.109868 -251.167232)
			(xy 79.074375 -251.201324) (xy 79.033872 -251.22928) (xy 78.98941 -251.250378) (xy 78.942139 -251.26407)
			(xy 78.893284 -251.270002) (xy 78.844109 -251.268021) (xy 78.79589 -251.258177) (xy 78.749874 -251.240725)
			(xy 78.707253 -251.216118) (xy 78.669132 -251.184993) (xy 78.636497 -251.148156) (xy 78.610194 -251.10656)
			(xy 78.590903 -251.061284) (xy 78.579126 -251.0135) (xy 78.575166 -250.964446) (xy 76.963477 -250.964446)
			(xy 76.965804 -250.96555) (xy 77.006307 -250.993506) (xy 77.0418 -251.027598) (xy 77.071365 -251.066942)
			(xy 77.094236 -251.110519) (xy 77.10982 -251.1572) (xy 77.117715 -251.205777) (xy 77.11821 -251.230384)
			(xy 77.117715 -251.254991) (xy 77.10982 -251.303568) (xy 77.094236 -251.350249) (xy 77.071365 -251.393826)
			(xy 77.0418 -251.43317) (xy 77.006307 -251.467262) (xy 76.965804 -251.495218) (xy 76.921342 -251.516316)
			(xy 76.874071 -251.530008) (xy 76.825216 -251.53594) (xy 76.776041 -251.533959) (xy 76.727822 -251.524115)
			(xy 76.681806 -251.506663) (xy 76.639185 -251.482056) (xy 76.601064 -251.450931) (xy 76.568429 -251.414094)
			(xy 76.542126 -251.372498) (xy 76.522835 -251.327222) (xy 76.511058 -251.279438) (xy 76.507098 -251.230384)
			(xy 68.272152 -251.230384) (xy 69.147944 -252.106176) (xy 69.153693 -252.111375) (xy 69.167525 -252.118355)
			(xy 69.175122 -252.119892) (xy 69.183504 -252.120654) (xy 78.08595 -252.120654)
		)
		(stroke
			(width 0)
			(type solid)
		)
		(fill yes)
		(layer "In15.Cu")
		(net "PVDDCR_CPU0_P1")
	)
	(gr_poly
		(pts
			(xy 196.176138 -342.14562) (xy 196.186014 -342.145157) (xy 196.204309 -342.137711) (xy 196.211698 -342.131142)
			(xy 196.211952 -342.130888) (xy 196.344794 -341.998046) (xy 196.345302 -341.997538) (xy 196.351888 -341.990159)
			(xy 196.359343 -341.971859) (xy 196.35978 -341.961978) (xy 196.35978 -329.33767) (xy 196.359351 -329.327603)
			(xy 196.351627 -329.309008) (xy 196.344794 -329.301602) (xy 193.090546 -326.047354) (xy 193.083702 -326.039955)
			(xy 193.075977 -326.021357) (xy 193.07556 -326.011286) (xy 193.07556 -321.912742) (xy 193.075125 -321.902677)
			(xy 193.067391 -321.884092) (xy 193.060574 -321.876674) (xy 192.663826 -321.479926) (xy 192.656714 -321.47256)
			(xy 192.637918 -321.46494) (xy 186.327542 -321.46494) (xy 186.317478 -321.464505) (xy 186.298894 -321.456769)
			(xy 186.291474 -321.449954) (xy 185.473086 -320.631566) (xy 185.466235 -320.62417) (xy 185.4585 -320.605571)
			(xy 185.4581 -320.595498) (xy 185.4581 -257.950462) (xy 185.45767 -257.940395) (xy 185.449946 -257.921801)
			(xy 185.443114 -257.914394) (xy 184.662826 -257.134106) (xy 184.655714 -257.12674) (xy 184.636918 -257.11912)
			(xy 156.05125 -257.11912) (xy 156.041663 -257.119528) (xy 156.023821 -257.126549) (xy 156.009775 -257.139602)
			(xy 156.005276 -257.148076) (xy 155.959556 -257.244596) (xy 155.963112 -257.273552) (xy 155.97251 -257.285236)
			(xy 156.017146 -257.340437) (xy 156.100852 -257.455112) (xy 156.177955 -257.574327) (xy 156.248209 -257.697702)
			(xy 156.311392 -257.824844) (xy 156.367302 -257.955348) (xy 156.41576 -258.088798) (xy 156.456612 -258.224769)
			(xy 156.489729 -258.362828) (xy 156.515004 -258.502536) (xy 156.532358 -258.643447) (xy 156.541735 -258.785113)
			(xy 156.543104 -258.927082) (xy 156.536463 -259.068902) (xy 156.521831 -259.210122) (xy 156.499255 -259.350291)
			(xy 156.480591 -259.4353) (xy 164.610392 -259.4353) (xy 164.614383 -259.346443) (xy 164.626322 -259.258301)
			(xy 164.646114 -259.171584) (xy 164.673599 -259.08699) (xy 164.708557 -259.005201) (xy 164.750704 -258.926874)
			(xy 164.799704 -258.85264) (xy 164.85516 -258.783098) (xy 164.916626 -258.718806) (xy 164.983608 -258.660282)
			(xy 165.055565 -258.607999) (xy 165.13192 -258.562375) (xy 165.212057 -258.52378) (xy 165.295331 -258.492523)
			(xy 165.381072 -258.468856) (xy 165.468588 -258.45297) (xy 165.557177 -258.444993) (xy 165.60165 -258.444492)
			(xy 167.35425 -258.444492) (xy 167.398731 -258.444882) (xy 167.487335 -258.452852) (xy 167.574869 -258.468733)
			(xy 167.660626 -258.492397) (xy 167.743916 -258.523653) (xy 167.82407 -258.562249) (xy 167.900441 -258.607875)
			(xy 167.972414 -258.660163) (xy 168.039411 -258.718693) (xy 168.100891 -258.782993) (xy 168.156359 -258.852545)
			(xy 168.205369 -258.92679) (xy 168.247527 -259.005129) (xy 168.282492 -259.086931) (xy 168.309984 -259.171539)
			(xy 168.329781 -259.258271) (xy 168.341723 -259.346427) (xy 168.345714 -259.4353) (xy 172.154378 -259.4353)
			(xy 172.158369 -259.346438) (xy 172.170309 -259.258292) (xy 172.190103 -259.171571) (xy 172.21759 -259.086974)
			(xy 172.25255 -259.00518) (xy 172.294702 -258.92685) (xy 172.343705 -258.852614) (xy 172.399165 -258.783069)
			(xy 172.460636 -258.718776) (xy 172.527623 -258.660252) (xy 172.599586 -258.607968) (xy 172.675946 -258.562345)
			(xy 172.756088 -258.523751) (xy 172.839368 -258.492496) (xy 172.925113 -258.468832) (xy 173.012635 -258.452949)
			(xy 173.101228 -258.444976) (xy 173.145704 -258.444492) (xy 174.898304 -258.444492) (xy 174.942783 -258.444899)
			(xy 175.031382 -258.452873) (xy 175.11891 -258.468758) (xy 175.204662 -258.492424) (xy 175.287948 -258.523682)
			(xy 175.368096 -258.562279) (xy 175.444461 -258.607906) (xy 175.516429 -258.660194) (xy 175.583421 -258.718723)
			(xy 175.644896 -258.783021) (xy 175.70036 -258.852571) (xy 175.749366 -258.926813) (xy 175.791521 -259.005149)
			(xy 175.826483 -259.086948) (xy 175.853972 -259.171552) (xy 175.873767 -259.258279) (xy 175.885708 -259.346432)
			(xy 175.8897 -259.4353) (xy 179.698492 -259.4353) (xy 179.702483 -259.346442) (xy 179.714422 -259.2583)
			(xy 179.734214 -259.171583) (xy 179.7617 -259.086988) (xy 179.796658 -259.005199) (xy 179.838806 -258.926871)
			(xy 179.887806 -258.852638) (xy 179.943262 -258.783095) (xy 180.004729 -258.718803) (xy 180.071711 -258.66028)
			(xy 180.14367 -258.607996) (xy 180.220025 -258.562373) (xy 180.300163 -258.523777) (xy 180.383437 -258.492521)
			(xy 180.469178 -258.468855) (xy 180.556695 -258.452969) (xy 180.645284 -258.444993) (xy 180.689758 -258.444492)
			(xy 182.442358 -258.444492) (xy 182.486839 -258.444882) (xy 182.575443 -258.452853) (xy 182.662975 -258.468735)
			(xy 182.748732 -258.492399) (xy 182.832022 -258.523655) (xy 182.912175 -258.562252) (xy 182.988545 -258.607878)
			(xy 183.060518 -258.660166) (xy 183.127514 -258.718696) (xy 183.188993 -258.782996) (xy 183.244461 -258.852548)
			(xy 183.293471 -258.926792) (xy 183.335628 -259.005131) (xy 183.370593 -259.086933) (xy 183.398084 -259.17154)
			(xy 183.417881 -259.258271) (xy 183.429823 -259.346428) (xy 183.433814 -259.4353) (xy 183.429823 -259.524172)
			(xy 183.417881 -259.612329) (xy 183.398084 -259.69906) (xy 183.370593 -259.783667) (xy 183.335628 -259.865469)
			(xy 183.293471 -259.943808) (xy 183.244461 -260.018052) (xy 183.188993 -260.087604) (xy 183.127514 -260.151904)
			(xy 183.060518 -260.210434) (xy 182.988545 -260.262722) (xy 182.912175 -260.308348) (xy 182.832022 -260.346945)
			(xy 182.748732 -260.378201) (xy 182.662975 -260.401865) (xy 182.575443 -260.417747) (xy 182.486839 -260.425718)
			(xy 182.442358 -260.4262) (xy 180.689758 -260.4262) (xy 180.645284 -260.425607) (xy 180.556695 -260.417631)
			(xy 180.469178 -260.401745) (xy 180.383437 -260.378079) (xy 180.300163 -260.346823) (xy 180.220025 -260.308227)
			(xy 180.14367 -260.262604) (xy 180.071711 -260.21032) (xy 180.004729 -260.151797) (xy 179.943262 -260.087505)
			(xy 179.887806 -260.017962) (xy 179.838806 -259.943729) (xy 179.796658 -259.865401) (xy 179.7617 -259.783612)
			(xy 179.734214 -259.699017) (xy 179.714422 -259.6123) (xy 179.702483 -259.524158) (xy 179.698492 -259.4353)
			(xy 175.8897 -259.4353) (xy 175.885708 -259.524168) (xy 175.873767 -259.612321) (xy 175.853972 -259.699048)
			(xy 175.826483 -259.783652) (xy 175.791521 -259.865451) (xy 175.749366 -259.943787) (xy 175.70036 -260.018029)
			(xy 175.644896 -260.087579) (xy 175.583421 -260.151877) (xy 175.516429 -260.210406) (xy 175.444461 -260.262694)
			(xy 175.368096 -260.308321) (xy 175.287948 -260.346918) (xy 175.204662 -260.378176) (xy 175.11891 -260.401842)
			(xy 175.031382 -260.417727) (xy 174.942783 -260.425701) (xy 174.898304 -260.4262) (xy 173.145704 -260.4262)
			(xy 173.101228 -260.425624) (xy 173.012635 -260.417651) (xy 172.925113 -260.401768) (xy 172.839368 -260.378104)
			(xy 172.756088 -260.346849) (xy 172.675946 -260.308255) (xy 172.599586 -260.262632) (xy 172.527623 -260.210348)
			(xy 172.460636 -260.151824) (xy 172.399165 -260.087531) (xy 172.343705 -260.017986) (xy 172.294702 -259.94375)
			(xy 172.25255 -259.86542) (xy 172.21759 -259.783626) (xy 172.190103 -259.699029) (xy 172.170309 -259.612308)
			(xy 172.158369 -259.524162) (xy 172.154378 -259.4353) (xy 168.345714 -259.4353) (xy 168.341723 -259.524173)
			(xy 168.329781 -259.612329) (xy 168.309984 -259.699061) (xy 168.282492 -259.783669) (xy 168.247527 -259.865471)
			(xy 168.205369 -259.94381) (xy 168.156359 -260.018055) (xy 168.100891 -260.087607) (xy 168.039411 -260.151907)
			(xy 167.972414 -260.210437) (xy 167.900441 -260.262725) (xy 167.82407 -260.308351) (xy 167.743916 -260.346947)
			(xy 167.660626 -260.378203) (xy 167.574869 -260.401867) (xy 167.487335 -260.417748) (xy 167.398731 -260.425718)
			(xy 167.35425 -260.4262) (xy 165.60165 -260.4262) (xy 165.557177 -260.425607) (xy 165.468588 -260.41763)
			(xy 165.381072 -260.401744) (xy 165.295331 -260.378077) (xy 165.212057 -260.34682) (xy 165.13192 -260.308225)
			(xy 165.055565 -260.262601) (xy 164.983608 -260.210318) (xy 164.916626 -260.151794) (xy 164.85516 -260.087502)
			(xy 164.799704 -260.01796) (xy 164.750704 -259.943726) (xy 164.708557 -259.865399) (xy 164.673599 -259.78361)
			(xy 164.646114 -259.699016) (xy 164.626322 -259.612299) (xy 164.614383 -259.524157) (xy 164.610392 -259.4353)
			(xy 156.480591 -259.4353) (xy 156.468809 -259.488963) (xy 156.430587 -259.625697) (xy 156.384712 -259.760058)
			(xy 156.331331 -259.891616) (xy 156.270613 -260.019953) (xy 156.202752 -260.14466) (xy 156.127963 -260.26534)
			(xy 156.046486 -260.381609) (xy 155.958578 -260.493097) (xy 155.864522 -260.599447) (xy 155.764615 -260.700322)
			(xy 155.659177 -260.7954) (xy 155.548543 -260.884379) (xy 155.433065 -260.966975) (xy 155.313112 -261.042924)
			(xy 155.189065 -261.111985) (xy 155.06132 -261.173938) (xy 154.930283 -261.228586) (xy 154.796372 -261.275755)
			(xy 154.660013 -261.315294) (xy 154.52164 -261.347077) (xy 154.381695 -261.371003) (xy 154.240623 -261.386997)
			(xy 154.098874 -261.395006) (xy 153.956898 -261.395006) (xy 153.815149 -261.386997) (xy 153.674077 -261.371003)
			(xy 153.534132 -261.347077) (xy 153.395759 -261.315294) (xy 153.2594 -261.275755) (xy 153.125489 -261.228586)
			(xy 152.994452 -261.173938) (xy 152.866707 -261.111985) (xy 152.74266 -261.042924) (xy 152.622707 -260.966975)
			(xy 152.507229 -260.884379) (xy 152.396595 -260.7954) (xy 152.291157 -260.700322) (xy 152.19125 -260.599447)
			(xy 152.097194 -260.493097) (xy 152.009286 -260.381609) (xy 151.927809 -260.26534) (xy 151.85302 -260.14466)
			(xy 151.785159 -260.019953) (xy 151.724441 -259.891616) (xy 151.67106 -259.760058) (xy 151.625185 -259.625697)
			(xy 151.586963 -259.488963) (xy 151.556517 -259.350291) (xy 151.533941 -259.210122) (xy 151.519309 -259.068902)
			(xy 151.512668 -258.927082) (xy 151.514037 -258.785113) (xy 151.523414 -258.643447) (xy 151.540768 -258.502536)
			(xy 151.566043 -258.362828) (xy 151.59916 -258.224769) (xy 151.640012 -258.088798) (xy 151.68847 -257.955348)
			(xy 151.74438 -257.824844) (xy 151.807563 -257.697702) (xy 151.877817 -257.574327) (xy 151.95492 -257.455112)
			(xy 152.038626 -257.340437) (xy 152.083262 -257.285236) (xy 152.09266 -257.273552) (xy 152.096216 -257.244596)
			(xy 152.050496 -257.148076) (xy 152.046018 -257.139582) (xy 152.031988 -257.126493) (xy 152.014118 -257.119508)
			(xy 152.004522 -257.11912) (xy 148.920962 -257.11912) (xy 148.910895 -257.119551) (xy 148.892303 -257.127277)
			(xy 148.884894 -257.134106) (xy 147.977606 -258.041394) (xy 147.97024 -258.048506) (xy 147.96262 -258.067302)
			(xy 147.96262 -261.098538) (xy 147.962191 -261.108606) (xy 147.954469 -261.127202) (xy 147.947634 -261.134606)
			(xy 147.34921 -261.73303) (xy 147.341336 -261.74319) (xy 147.338034 -261.748778) (xy 147.336256 -261.755128)
			(xy 147.328621 -261.779636) (xy 147.306321 -261.825865) (xy 147.276605 -261.867716) (xy 147.24031 -261.90401)
			(xy 147.198459 -261.933724) (xy 147.19537 -261.935214) (xy 168.158683 -261.935214) (xy 168.162618 -261.881443)
			(xy 168.174341 -261.828819) (xy 168.193601 -261.778462) (xy 168.219987 -261.731445) (xy 168.252939 -261.688772)
			(xy 168.291752 -261.651351) (xy 168.3356 -261.619981) (xy 168.383548 -261.595329) (xy 168.434575 -261.577921)
			(xy 168.487593 -261.568128) (xy 168.541472 -261.566159) (xy 168.595063 -261.572056) (xy 168.647224 -261.585692)
			(xy 168.696844 -261.606779) (xy 168.742865 -261.634865) (xy 168.784307 -261.669353) (xy 168.820285 -261.709507)
			(xy 168.850033 -261.754471) (xy 168.872918 -261.803288) (xy 168.88845 -261.854917) (xy 168.8963 -261.908257)
			(xy 168.896792 -261.935214) (xy 168.8963 -261.962171) (xy 168.88845 -262.015511) (xy 168.872918 -262.06714)
			(xy 168.850033 -262.115957) (xy 168.820285 -262.160921) (xy 168.784307 -262.201075) (xy 168.742865 -262.235563)
			(xy 168.696844 -262.263649) (xy 168.647224 -262.284736) (xy 168.595063 -262.298372) (xy 168.541472 -262.304269)
			(xy 168.487593 -262.3023) (xy 168.434575 -262.292507) (xy 168.383548 -262.275099) (xy 168.3356 -262.250447)
			(xy 168.291752 -262.219077) (xy 168.252939 -262.181656) (xy 168.219987 -262.138983) (xy 168.193601 -262.091966)
			(xy 168.174341 -262.041609) (xy 168.162618 -261.988985) (xy 168.158683 -261.935214) (xy 147.19537 -261.935214)
			(xy 147.152229 -261.956024) (xy 147.127722 -261.963662) (xy 147.115784 -261.968742) (xy 147.110196 -261.972044)
			(xy 146.296888 -262.785352) (xy 164.058615 -262.785352) (xy 164.06255 -262.731581) (xy 164.074273 -262.678957)
			(xy 164.093533 -262.6286) (xy 164.119919 -262.581583) (xy 164.152871 -262.53891) (xy 164.191684 -262.501489)
			(xy 164.235532 -262.470119) (xy 164.28348 -262.445467) (xy 164.334507 -262.428059) (xy 164.387525 -262.418266)
			(xy 164.441404 -262.416297) (xy 164.494995 -262.422194) (xy 164.547156 -262.43583) (xy 164.596776 -262.456917)
			(xy 164.642797 -262.485003) (xy 164.684239 -262.519491) (xy 164.720217 -262.559645) (xy 164.749965 -262.604609)
			(xy 164.77285 -262.653426) (xy 164.788382 -262.705055) (xy 164.796232 -262.758395) (xy 164.796724 -262.785352)
			(xy 164.796232 -262.812309) (xy 164.788382 -262.865649) (xy 164.77285 -262.917278) (xy 164.749965 -262.966095)
			(xy 164.720217 -263.011059) (xy 164.684239 -263.051213) (xy 164.642797 -263.085701) (xy 164.596776 -263.113787)
			(xy 164.547156 -263.134874) (xy 164.494995 -263.14851) (xy 164.441404 -263.154407) (xy 164.387525 -263.152438)
			(xy 164.334507 -263.142645) (xy 164.28348 -263.125237) (xy 164.235532 -263.100585) (xy 164.191684 -263.069215)
			(xy 164.152871 -263.031794) (xy 164.119919 -262.989121) (xy 164.093533 -262.942104) (xy 164.074273 -262.891747)
			(xy 164.06255 -262.839123) (xy 164.058615 -262.785352) (xy 146.296888 -262.785352) (xy 145.892266 -263.189974)
			(xy 145.884867 -263.196818) (xy 145.866269 -263.204544) (xy 145.856198 -263.20496) (xy 144.356074 -263.20496)
			(xy 144.35201 -263.205214) (xy 144.339945 -263.206815) (xy 144.319243 -263.219544) (xy 144.312386 -263.229598)
			(xy 144.310354 -263.233408) (xy 144.282589 -263.290304) (xy 146.737082 -263.290304) (xy 146.741042 -263.24125)
			(xy 146.752819 -263.193466) (xy 146.77211 -263.14819) (xy 146.798413 -263.106594) (xy 146.831048 -263.069757)
			(xy 146.869169 -263.038632) (xy 146.91179 -263.014025) (xy 146.957806 -262.996573) (xy 147.006025 -262.986729)
			(xy 147.0552 -262.984748) (xy 147.104055 -262.99068) (xy 147.151326 -263.004372) (xy 147.195788 -263.02547)
			(xy 147.236291 -263.053426) (xy 147.271784 -263.087518) (xy 147.301349 -263.126862) (xy 147.32422 -263.170439)
			(xy 147.339804 -263.21712) (xy 147.347699 -263.265697) (xy 147.348194 -263.290304) (xy 147.347699 -263.314911)
			(xy 147.339804 -263.363488) (xy 147.32422 -263.410169) (xy 147.301349 -263.453746) (xy 147.271784 -263.49309)
			(xy 147.236291 -263.527182) (xy 147.195788 -263.555138) (xy 147.151326 -263.576236) (xy 147.104055 -263.589928)
			(xy 147.0552 -263.59586) (xy 147.006025 -263.593879) (xy 146.957806 -263.584035) (xy 146.91179 -263.566583)
			(xy 146.869169 -263.541976) (xy 146.831048 -263.510851) (xy 146.798413 -263.474014) (xy 146.77211 -263.432418)
			(xy 146.752819 -263.387142) (xy 146.741042 -263.339358) (xy 146.737082 -263.290304) (xy 144.282589 -263.290304)
			(xy 144.263872 -263.328658) (xy 144.26692 -263.35736) (xy 144.27581 -263.36879) (xy 144.290884 -263.389042)
			(xy 144.314879 -263.433455) (xy 144.331251 -263.481208) (xy 144.339555 -263.531002) (xy 144.340072 -263.556242)
			(xy 144.33955 -263.581497) (xy 144.331237 -263.631319) (xy 144.329892 -263.635236) (xy 168.158683 -263.635236)
			(xy 168.162618 -263.581465) (xy 168.174341 -263.528841) (xy 168.193601 -263.478484) (xy 168.219987 -263.431467)
			(xy 168.252939 -263.388794) (xy 168.291752 -263.351373) (xy 168.3356 -263.320003) (xy 168.383548 -263.295351)
			(xy 168.434575 -263.277943) (xy 168.487593 -263.26815) (xy 168.541472 -263.266181) (xy 168.595063 -263.272078)
			(xy 168.647224 -263.285714) (xy 168.696844 -263.306801) (xy 168.742865 -263.334887) (xy 168.784307 -263.369375)
			(xy 168.820285 -263.409529) (xy 168.850033 -263.454493) (xy 168.872918 -263.50331) (xy 168.88845 -263.554939)
			(xy 168.8963 -263.608279) (xy 168.896792 -263.635236) (xy 168.8963 -263.662193) (xy 168.88845 -263.715533)
			(xy 168.872918 -263.767162) (xy 168.850033 -263.815979) (xy 168.820285 -263.860943) (xy 168.784307 -263.901097)
			(xy 168.742865 -263.935585) (xy 168.696844 -263.963671) (xy 168.647224 -263.984758) (xy 168.595063 -263.998394)
			(xy 168.541472 -264.004291) (xy 168.487593 -264.002322) (xy 168.434575 -263.992529) (xy 168.383548 -263.975121)
			(xy 168.3356 -263.950469) (xy 168.291752 -263.919099) (xy 168.252939 -263.881678) (xy 168.219987 -263.839005)
			(xy 168.193601 -263.791988) (xy 168.174341 -263.741631) (xy 168.162618 -263.689007) (xy 168.158683 -263.635236)
			(xy 144.329892 -263.635236) (xy 144.314836 -263.679093) (xy 144.290795 -263.723516) (xy 144.259771 -263.763376)
			(xy 144.222609 -263.797586) (xy 144.180323 -263.825212) (xy 144.134067 -263.845502) (xy 144.085102 -263.857902)
			(xy 144.034764 -263.862073) (xy 143.984426 -263.857902) (xy 143.935461 -263.845502) (xy 143.889205 -263.825212)
			(xy 143.846919 -263.797586) (xy 143.809757 -263.763376) (xy 143.778733 -263.723516) (xy 143.754692 -263.679093)
			(xy 143.738291 -263.631319) (xy 143.729978 -263.581497) (xy 143.729456 -263.556242) (xy 143.729972 -263.531001)
			(xy 143.738266 -263.481204) (xy 143.754635 -263.433449) (xy 143.778634 -263.389035) (xy 143.793718 -263.36879)
			(xy 143.802608 -263.35736) (xy 143.805656 -263.328658) (xy 143.759174 -263.233408) (xy 143.757142 -263.229598)
			(xy 143.750275 -263.219554) (xy 143.729579 -263.206832) (xy 143.717518 -263.205214) (xy 143.713454 -263.20496)
			(xy 143.420846 -263.20496) (xy 143.419068 -263.20496) (xy 143.407117 -263.206082) (xy 143.386164 -263.217731)
			(xy 143.378936 -263.227312) (xy 143.37538 -263.233408) (xy 143.334994 -263.314942) (xy 143.332059 -263.321385)
			(xy 143.329496 -263.335305) (xy 143.329914 -263.342374) (xy 143.330422 -263.346438) (xy 143.345398 -263.363858)
			(xy 143.370674 -263.402215) (xy 143.390124 -263.443832) (xy 143.403336 -263.487827) (xy 143.410032 -263.533274)
			(xy 143.410432 -263.556242) (xy 143.409945 -263.581052) (xy 143.402183 -263.63006) (xy 143.38685 -263.67725)
			(xy 143.364323 -263.721461) (xy 143.335158 -263.761604) (xy 143.300072 -263.79669) (xy 143.259929 -263.825855)
			(xy 143.215718 -263.848382) (xy 143.168528 -263.863715) (xy 143.11952 -263.871477) (xy 143.0699 -263.871477)
			(xy 143.020892 -263.863715) (xy 142.973702 -263.848382) (xy 142.929491 -263.825855) (xy 142.889348 -263.79669)
			(xy 142.854262 -263.761604) (xy 142.825097 -263.721461) (xy 142.80257 -263.67725) (xy 142.787237 -263.63006)
			(xy 142.779475 -263.581052) (xy 142.778988 -263.556242) (xy 142.779534 -263.529369) (xy 142.788646 -263.4764)
			(xy 142.806597 -263.425739) (xy 142.832868 -263.37885) (xy 142.849346 -263.357614) (xy 142.853849 -263.351653)
			(xy 142.859524 -263.33784) (xy 142.860522 -263.330436) (xy 142.860776 -263.327896) (xy 142.81404 -263.233408)
			(xy 142.810484 -263.227312) (xy 142.803241 -263.217743) (xy 142.782301 -263.206087) (xy 142.770352 -263.20496)
			(xy 142.475966 -263.20496) (xy 142.471902 -263.205214) (xy 142.459838 -263.206817) (xy 142.439139 -263.219547)
			(xy 142.432278 -263.229598) (xy 142.430246 -263.233408) (xy 142.383764 -263.328658) (xy 142.386812 -263.35736)
			(xy 142.395702 -263.36879) (xy 142.410776 -263.389041) (xy 142.434772 -263.433455) (xy 142.451145 -263.481208)
			(xy 142.459448 -263.531001) (xy 142.459964 -263.556242) (xy 142.459442 -263.581497) (xy 142.451129 -263.631319)
			(xy 142.434728 -263.679093) (xy 142.410687 -263.723516) (xy 142.379663 -263.763376) (xy 142.342501 -263.797586)
			(xy 142.300215 -263.825212) (xy 142.253959 -263.845502) (xy 142.204994 -263.857902) (xy 142.154656 -263.862073)
			(xy 142.104318 -263.857902) (xy 142.055353 -263.845502) (xy 142.009097 -263.825212) (xy 141.966811 -263.797586)
			(xy 141.929649 -263.763376) (xy 141.898625 -263.723516) (xy 141.874584 -263.679093) (xy 141.858183 -263.631319)
			(xy 141.84987 -263.581497) (xy 141.849348 -263.556242) (xy 141.849864 -263.531001) (xy 141.858158 -263.481204)
			(xy 141.874527 -263.433448) (xy 141.898525 -263.389035) (xy 141.91361 -263.36879) (xy 141.9225 -263.35736)
			(xy 141.925548 -263.328658) (xy 141.879066 -263.233408) (xy 141.877034 -263.229598) (xy 141.870174 -263.219539)
			(xy 141.849481 -263.206781) (xy 141.83741 -263.205214) (xy 141.833346 -263.20496) (xy 141.540992 -263.20496)
			(xy 141.539214 -263.20496) (xy 141.527269 -263.206093) (xy 141.506336 -263.217754) (xy 141.499082 -263.227312)
			(xy 141.495526 -263.233408) (xy 141.45514 -263.314942) (xy 141.452202 -263.321385) (xy 141.449637 -263.335305)
			(xy 141.45006 -263.342374) (xy 141.450568 -263.346438) (xy 141.465533 -263.363858) (xy 141.490779 -263.402218)
			(xy 141.510184 -263.443839) (xy 141.523338 -263.487838) (xy 141.52996 -263.53328) (xy 141.530324 -263.556242)
			(xy 141.529838 -263.581032) (xy 141.522082 -263.63) (xy 141.506761 -263.677153) (xy 141.484252 -263.721328)
			(xy 141.45511 -263.761439) (xy 141.420053 -263.796496) (xy 141.379942 -263.825638) (xy 141.335767 -263.848147)
			(xy 141.288614 -263.863468) (xy 141.239646 -263.871224) (xy 141.190066 -263.871224) (xy 141.141098 -263.863468)
			(xy 141.093945 -263.848147) (xy 141.04977 -263.825638) (xy 141.009659 -263.796496) (xy 140.974602 -263.761439)
			(xy 140.94546 -263.721328) (xy 140.922951 -263.677153) (xy 140.90763 -263.63) (xy 140.899874 -263.581032)
			(xy 140.899388 -263.556242) (xy 140.899914 -263.529381) (xy 140.908976 -263.476428) (xy 140.926862 -263.425771)
			(xy 140.953058 -263.378868) (xy 140.969492 -263.357614) (xy 140.973991 -263.351651) (xy 140.979661 -263.337838)
			(xy 140.980668 -263.330436) (xy 140.980922 -263.327896) (xy 140.934186 -263.233408) (xy 140.93063 -263.227312)
			(xy 140.92339 -263.217736) (xy 140.902451 -263.206061) (xy 140.890498 -263.20496) (xy 140.596112 -263.20496)
			(xy 140.592048 -263.205214) (xy 140.579991 -263.206828) (xy 140.559312 -263.219569) (xy 140.552424 -263.229598)
			(xy 140.550392 -263.233408) (xy 140.50391 -263.328658) (xy 140.506958 -263.35736) (xy 140.515848 -263.36879)
			(xy 140.530924 -263.389041) (xy 140.554924 -263.433453) (xy 140.5713 -263.481206) (xy 140.579605 -263.531001)
			(xy 140.58011 -263.556242) (xy 140.579588 -263.581497) (xy 140.571275 -263.631319) (xy 140.554874 -263.679093)
			(xy 140.530833 -263.723516) (xy 140.499809 -263.763376) (xy 140.462647 -263.797586) (xy 140.420361 -263.825212)
			(xy 140.374105 -263.845502) (xy 140.32514 -263.857902) (xy 140.274802 -263.862073) (xy 140.224464 -263.857902)
			(xy 140.175499 -263.845502) (xy 140.129243 -263.825212) (xy 140.086957 -263.797586) (xy 140.049795 -263.763376)
			(xy 140.018771 -263.723516) (xy 139.99473 -263.679093) (xy 139.978329 -263.631319) (xy 139.970016 -263.581497)
			(xy 139.969494 -263.556242) (xy 139.97001 -263.531) (xy 139.978302 -263.481203) (xy 139.994669 -263.433446)
			(xy 140.018664 -263.389029) (xy 140.033756 -263.36879) (xy 140.042646 -263.35736) (xy 140.045694 -263.328658)
			(xy 139.999212 -263.233408) (xy 139.99718 -263.229598) (xy 139.990316 -263.219548) (xy 139.969621 -263.206811)
			(xy 139.957556 -263.205214) (xy 139.953492 -263.20496) (xy 139.660884 -263.20496) (xy 139.659106 -263.20496)
			(xy 139.647162 -263.206094) (xy 139.626231 -263.217758) (xy 139.618974 -263.227312) (xy 139.615418 -263.233408)
			(xy 139.575032 -263.314942) (xy 139.572095 -263.321385) (xy 139.56953 -263.335305) (xy 139.569952 -263.342374)
			(xy 139.57046 -263.346438) (xy 139.585425 -263.363858) (xy 139.610672 -263.402218) (xy 139.630078 -263.443839)
			(xy 139.643232 -263.487837) (xy 139.649854 -263.53328) (xy 139.650216 -263.556242) (xy 139.64973 -263.581032)
			(xy 139.641974 -263.63) (xy 139.626653 -263.677153) (xy 139.604144 -263.721328) (xy 139.575002 -263.761439)
			(xy 139.539945 -263.796496) (xy 139.499834 -263.825638) (xy 139.455659 -263.848147) (xy 139.408506 -263.863468)
			(xy 139.359538 -263.871224) (xy 139.309958 -263.871224) (xy 139.26099 -263.863468) (xy 139.213837 -263.848147)
			(xy 139.169662 -263.825638) (xy 139.129551 -263.796496) (xy 139.094494 -263.761439) (xy 139.065352 -263.721328)
			(xy 139.042843 -263.677153) (xy 139.027522 -263.63) (xy 139.019766 -263.581032) (xy 139.01928 -263.556242)
			(xy 139.019806 -263.529381) (xy 139.028868 -263.476428) (xy 139.046753 -263.425771) (xy 139.072949 -263.378868)
			(xy 139.089384 -263.357614) (xy 139.093884 -263.351651) (xy 139.099555 -263.337839) (xy 139.10056 -263.330436)
			(xy 139.100814 -263.327896) (xy 139.054078 -263.233408) (xy 139.050522 -263.227312) (xy 139.043282 -263.217737)
			(xy 139.022342 -263.206066) (xy 139.01039 -263.20496) (xy 138.72083 -263.20496) (xy 138.719052 -263.20496)
			(xy 138.707103 -263.206085) (xy 138.686156 -263.217738) (xy 138.67892 -263.227312) (xy 138.675364 -263.233408)
			(xy 138.634978 -263.314942) (xy 138.632038 -263.321384) (xy 138.629471 -263.335305) (xy 138.629898 -263.342374)
			(xy 138.630406 -263.346438) (xy 138.645379 -263.363859) (xy 138.670649 -263.402219) (xy 138.690093 -263.443835)
			(xy 138.703301 -263.48783) (xy 138.709995 -263.533275) (xy 138.710416 -263.556242) (xy 138.709929 -263.581052)
			(xy 138.702167 -263.63006) (xy 138.686834 -263.67725) (xy 138.664307 -263.721461) (xy 138.635142 -263.761604)
			(xy 138.600056 -263.79669) (xy 138.559913 -263.825855) (xy 138.515702 -263.848382) (xy 138.468512 -263.863715)
			(xy 138.419504 -263.871477) (xy 138.369884 -263.871477) (xy 138.320876 -263.863715) (xy 138.273686 -263.848382)
			(xy 138.229475 -263.825855) (xy 138.189332 -263.79669) (xy 138.154246 -263.761604) (xy 138.125081 -263.721461)
			(xy 138.102554 -263.67725) (xy 138.087221 -263.63006) (xy 138.079459 -263.581052) (xy 138.078972 -263.556242)
			(xy 138.079518 -263.529369) (xy 138.08863 -263.476399) (xy 138.10658 -263.425738) (xy 138.13285 -263.378849)
			(xy 138.14933 -263.357614) (xy 138.153834 -263.351653) (xy 138.159511 -263.337841) (xy 138.160506 -263.330436)
			(xy 138.16076 -263.327896) (xy 138.114024 -263.233408) (xy 138.110468 -263.227312) (xy 138.103224 -263.217746)
			(xy 138.082283 -263.206096) (xy 138.070336 -263.20496) (xy 137.77595 -263.20496) (xy 137.771886 -263.205214)
			(xy 137.759824 -263.20682) (xy 137.739131 -263.219554) (xy 137.732262 -263.229598) (xy 137.73023 -263.233408)
			(xy 137.683748 -263.328658) (xy 137.686796 -263.35736) (xy 137.695686 -263.36879) (xy 137.710761 -263.389041)
			(xy 137.734758 -263.433455) (xy 137.751131 -263.481207) (xy 137.759436 -263.531001) (xy 137.759948 -263.556242)
			(xy 137.759426 -263.581497) (xy 137.751113 -263.631319) (xy 137.734712 -263.679093) (xy 137.710671 -263.723516)
			(xy 137.679647 -263.763376) (xy 137.642485 -263.797586) (xy 137.600199 -263.825212) (xy 137.553943 -263.845502)
			(xy 137.504978 -263.857902) (xy 137.45464 -263.862073) (xy 137.404302 -263.857902) (xy 137.355337 -263.845502)
			(xy 137.309081 -263.825212) (xy 137.266795 -263.797586) (xy 137.229633 -263.763376) (xy 137.198609 -263.723516)
			(xy 137.174568 -263.679093) (xy 137.158167 -263.631319) (xy 137.149854 -263.581497) (xy 137.149332 -263.556242)
			(xy 137.149848 -263.531) (xy 137.158141 -263.481203) (xy 137.17451 -263.433448) (xy 137.198507 -263.389033)
			(xy 137.213594 -263.36879) (xy 137.222484 -263.35736) (xy 137.225532 -263.328658) (xy 137.17905 -263.233408)
			(xy 137.177018 -263.229598) (xy 137.170157 -263.219542) (xy 137.149463 -263.20679) (xy 137.137394 -263.205214)
			(xy 137.13333 -263.20496) (xy 136.840976 -263.20496) (xy 136.839198 -263.20496) (xy 136.827255 -263.206096)
			(xy 136.806327 -263.217761) (xy 136.799066 -263.227312) (xy 136.79551 -263.233408) (xy 136.755124 -263.314942)
			(xy 136.752187 -263.321385) (xy 136.749623 -263.335305) (xy 136.750044 -263.342374) (xy 136.750552 -263.346438)
			(xy 136.765513 -263.36386) (xy 136.790753 -263.402222) (xy 136.810153 -263.443843) (xy 136.823303 -263.48784)
			(xy 136.829923 -263.533281) (xy 136.830308 -263.556242) (xy 136.829822 -263.581032) (xy 136.822066 -263.63)
			(xy 136.806745 -263.677153) (xy 136.784236 -263.721328) (xy 136.755094 -263.761439) (xy 136.720037 -263.796496)
			(xy 136.679926 -263.825638) (xy 136.635751 -263.848147) (xy 136.588598 -263.863468) (xy 136.53963 -263.871224)
			(xy 136.49005 -263.871224) (xy 136.441082 -263.863468) (xy 136.393929 -263.848147) (xy 136.349754 -263.825638)
			(xy 136.309643 -263.796496) (xy 136.274586 -263.761439) (xy 136.245444 -263.721328) (xy 136.222935 -263.677153)
			(xy 136.207614 -263.63) (xy 136.199858 -263.581032) (xy 136.199372 -263.556242) (xy 136.199898 -263.529381)
			(xy 136.208959 -263.476428) (xy 136.226845 -263.42577) (xy 136.253039 -263.378867) (xy 136.269476 -263.357614)
			(xy 136.273976 -263.351652) (xy 136.279648 -263.337839) (xy 136.280652 -263.330436) (xy 136.280906 -263.327896)
			(xy 136.23417 -263.233408) (xy 136.230614 -263.227312) (xy 136.223373 -263.217738) (xy 136.202433 -263.20607)
			(xy 136.190482 -263.20496) (xy 135.896096 -263.20496) (xy 135.892032 -263.205214) (xy 135.879977 -263.206831)
			(xy 135.859304 -263.219576) (xy 135.852408 -263.229598) (xy 135.850376 -263.233408) (xy 135.803894 -263.328658)
			(xy 135.806942 -263.35736) (xy 135.815832 -263.36879) (xy 135.830909 -263.38904) (xy 135.85491 -263.433453)
			(xy 135.871287 -263.481206) (xy 135.879592 -263.531001) (xy 135.880094 -263.556242) (xy 135.879572 -263.581497)
			(xy 135.871259 -263.631319) (xy 135.854858 -263.679093) (xy 135.830817 -263.723516) (xy 135.799793 -263.763376)
			(xy 135.762631 -263.797586) (xy 135.720345 -263.825212) (xy 135.674089 -263.845502) (xy 135.625124 -263.857902)
			(xy 135.574786 -263.862073) (xy 135.524448 -263.857902) (xy 135.475483 -263.845502) (xy 135.429227 -263.825212)
			(xy 135.386941 -263.797586) (xy 135.349779 -263.763376) (xy 135.318755 -263.723516) (xy 135.294714 -263.679093)
			(xy 135.278313 -263.631319) (xy 135.27 -263.581497) (xy 135.269478 -263.556242) (xy 135.269994 -263.531)
			(xy 135.278286 -263.481202) (xy 135.294652 -263.433445) (xy 135.318646 -263.389028) (xy 135.33374 -263.36879)
			(xy 135.34263 -263.35736) (xy 135.345678 -263.328658) (xy 135.299196 -263.233408) (xy 135.297164 -263.229598)
			(xy 135.290299 -263.21955) (xy 135.269603 -263.20682) (xy 135.25754 -263.205214) (xy 135.253476 -263.20496)
			(xy 134.960868 -263.20496) (xy 134.95909 -263.20496) (xy 134.947148 -263.206098) (xy 134.926223 -263.217764)
			(xy 134.918958 -263.227312) (xy 134.915402 -263.233408) (xy 134.875016 -263.314942) (xy 134.87208 -263.321385)
			(xy 134.869516 -263.335305) (xy 134.869936 -263.342374) (xy 134.870444 -263.346438) (xy 134.885406 -263.363859)
			(xy 134.910646 -263.402221) (xy 134.930046 -263.443843) (xy 134.943196 -263.48784) (xy 134.949817 -263.533281)
			(xy 134.9502 -263.556242) (xy 134.949714 -263.581032) (xy 134.941958 -263.63) (xy 134.926637 -263.677153)
			(xy 134.904128 -263.721328) (xy 134.874986 -263.761439) (xy 134.839929 -263.796496) (xy 134.799818 -263.825638)
			(xy 134.755643 -263.848147) (xy 134.70849 -263.863468) (xy 134.659522 -263.871224) (xy 134.609942 -263.871224)
			(xy 134.560974 -263.863468) (xy 134.513821 -263.848147) (xy 134.469646 -263.825638) (xy 134.429535 -263.796496)
			(xy 134.394478 -263.761439) (xy 134.365336 -263.721328) (xy 134.342827 -263.677153) (xy 134.327506 -263.63)
			(xy 134.31975 -263.581032) (xy 134.319264 -263.556242) (xy 134.31979 -263.529381) (xy 134.328851 -263.476428)
			(xy 134.346736 -263.42577) (xy 134.37293 -263.378866) (xy 134.389368 -263.357614) (xy 134.393869 -263.351652)
			(xy 134.399542 -263.337839) (xy 134.400544 -263.330436) (xy 134.400798 -263.327896) (xy 134.354062 -263.233408)
			(xy 134.350506 -263.227312) (xy 134.343265 -263.21774) (xy 134.322325 -263.206075) (xy 134.310374 -263.20496)
			(xy 134.015988 -263.20496) (xy 134.011924 -263.205214) (xy 133.99987 -263.206833) (xy 133.9792 -263.219579)
			(xy 133.9723 -263.229598) (xy 133.970268 -263.233408) (xy 133.923786 -263.328658) (xy 133.926834 -263.35736)
			(xy 133.935724 -263.36879) (xy 133.950801 -263.38904) (xy 133.974803 -263.433453) (xy 133.99118 -263.481206)
			(xy 133.999486 -263.531001) (xy 133.999986 -263.556242) (xy 133.999464 -263.581497) (xy 133.991151 -263.631319)
			(xy 133.97475 -263.679093) (xy 133.950709 -263.723516) (xy 133.919685 -263.763376) (xy 133.882523 -263.797586)
			(xy 133.840237 -263.825212) (xy 133.793981 -263.845502) (xy 133.745016 -263.857902) (xy 133.694678 -263.862073)
			(xy 133.64434 -263.857902) (xy 133.595375 -263.845502) (xy 133.549119 -263.825212) (xy 133.506833 -263.797586)
			(xy 133.469671 -263.763376) (xy 133.438647 -263.723516) (xy 133.414606 -263.679093) (xy 133.398205 -263.631319)
			(xy 133.389892 -263.581497) (xy 133.38937 -263.556242) (xy 133.389886 -263.531) (xy 133.398178 -263.481202)
			(xy 133.414543 -263.433445) (xy 133.438537 -263.389027) (xy 133.453632 -263.36879) (xy 133.462522 -263.35736)
			(xy 133.46557 -263.328658) (xy 133.419088 -263.233408) (xy 133.417056 -263.229598) (xy 133.410191 -263.219551)
			(xy 133.389494 -263.206824) (xy 133.377432 -263.205214) (xy 133.373368 -263.20496) (xy 133.081014 -263.20496)
			(xy 133.079236 -263.20496) (xy 133.067289 -263.206088) (xy 133.046347 -263.217745) (xy 133.039104 -263.227312)
			(xy 133.035548 -263.233408) (xy 132.995162 -263.314942) (xy 132.992223 -263.321385) (xy 132.989657 -263.335305)
			(xy 132.990082 -263.342374) (xy 132.99059 -263.346438) (xy 133.005563 -263.363859) (xy 133.030834 -263.402218)
			(xy 133.050279 -263.443835) (xy 133.063488 -263.48783) (xy 133.070182 -263.533275) (xy 133.0706 -263.556242)
			(xy 133.070113 -263.581052) (xy 133.062351 -263.63006) (xy 133.047018 -263.67725) (xy 133.024491 -263.721461)
			(xy 132.995326 -263.761604) (xy 132.96024 -263.79669) (xy 132.920097 -263.825855) (xy 132.875886 -263.848382)
			(xy 132.828696 -263.863715) (xy 132.779688 -263.871477) (xy 132.730068 -263.871477) (xy 132.68106 -263.863715)
			(xy 132.63387 -263.848382) (xy 132.589659 -263.825855) (xy 132.549516 -263.79669) (xy 132.51443 -263.761604)
			(xy 132.485265 -263.721461) (xy 132.462738 -263.67725) (xy 132.447405 -263.63006) (xy 132.439643 -263.581052)
			(xy 132.439156 -263.556242) (xy 132.439702 -263.529368) (xy 132.448813 -263.476399) (xy 132.466763 -263.425737)
			(xy 132.493032 -263.378847) (xy 132.509514 -263.357614) (xy 132.514019 -263.351654) (xy 132.519698 -263.337841)
			(xy 132.52069 -263.330436) (xy 132.520944 -263.327896) (xy 132.474208 -263.233408) (xy 132.470652 -263.227312)
			(xy 132.463407 -263.217748) (xy 132.442465 -263.206106) (xy 132.43052 -263.20496) (xy 132.14096 -263.20496)
			(xy 132.139182 -263.20496) (xy 132.127229 -263.206079) (xy 132.106272 -263.217725) (xy 132.09905 -263.227312)
			(xy 132.095494 -263.233408) (xy 132.055108 -263.314942) (xy 132.052172 -263.321385) (xy 132.049608 -263.335305)
			(xy 132.050028 -263.342374) (xy 132.050536 -263.346438) (xy 132.065498 -263.363859) (xy 132.090739 -263.402221)
			(xy 132.11014 -263.443842) (xy 132.12329 -263.48784) (xy 132.129911 -263.533281) (xy 132.130292 -263.556242)
			(xy 132.129806 -263.581032) (xy 132.12205 -263.63) (xy 132.106729 -263.677153) (xy 132.08422 -263.721328)
			(xy 132.055078 -263.761439) (xy 132.020021 -263.796496) (xy 131.97991 -263.825638) (xy 131.935735 -263.848147)
			(xy 131.888582 -263.863468) (xy 131.839614 -263.871224) (xy 131.790034 -263.871224) (xy 131.741066 -263.863468)
			(xy 131.693913 -263.848147) (xy 131.649738 -263.825638) (xy 131.609627 -263.796496) (xy 131.57457 -263.761439)
			(xy 131.545428 -263.721328) (xy 131.522919 -263.677153) (xy 131.507598 -263.63) (xy 131.499842 -263.581032)
			(xy 131.499356 -263.556242) (xy 131.499882 -263.52938) (xy 131.508943 -263.476428) (xy 131.526828 -263.425769)
			(xy 131.553021 -263.378865) (xy 131.56946 -263.357614) (xy 131.573962 -263.351652) (xy 131.579635 -263.33784)
			(xy 131.580636 -263.330436) (xy 131.58089 -263.327896) (xy 131.534154 -263.233408) (xy 131.530598 -263.227312)
			(xy 131.523356 -263.217741) (xy 131.502416 -263.206079) (xy 131.490466 -263.20496) (xy 130.260852 -263.20496)
			(xy 130.259074 -263.20496) (xy 130.247122 -263.206081) (xy 130.226167 -263.217728) (xy 130.218942 -263.227312)
			(xy 130.215386 -263.233408) (xy 130.175 -263.314942) (xy 130.172064 -263.321385) (xy 130.169501 -263.335305)
			(xy 130.16992 -263.342374) (xy 130.170428 -263.346438) (xy 130.18539 -263.363859) (xy 130.210632 -263.402221)
			(xy 130.230033 -263.443842) (xy 130.243184 -263.48784) (xy 130.249805 -263.533281) (xy 130.250184 -263.556242)
			(xy 130.249698 -263.581032) (xy 130.241942 -263.63) (xy 130.226621 -263.677153) (xy 130.204112 -263.721328)
			(xy 130.17497 -263.761439) (xy 130.139913 -263.796496) (xy 130.099802 -263.825638) (xy 130.055627 -263.848147)
			(xy 130.008474 -263.863468) (xy 129.959506 -263.871224) (xy 129.909926 -263.871224) (xy 129.860958 -263.863468)
			(xy 129.813805 -263.848147) (xy 129.76963 -263.825638) (xy 129.729519 -263.796496) (xy 129.694462 -263.761439)
			(xy 129.66532 -263.721328) (xy 129.642811 -263.677153) (xy 129.62749 -263.63) (xy 129.619734 -263.581032)
			(xy 129.619248 -263.556242) (xy 129.619774 -263.52938) (xy 129.628835 -263.476427) (xy 129.646719 -263.425769)
			(xy 129.672912 -263.378864) (xy 129.689352 -263.357614) (xy 129.693854 -263.351652) (xy 129.699529 -263.33784)
			(xy 129.700528 -263.330436) (xy 129.700782 -263.327896) (xy 129.654046 -263.233408) (xy 129.65049 -263.227312)
			(xy 129.643248 -263.217742) (xy 129.622307 -263.206084) (xy 129.610358 -263.20496) (xy 129.315972 -263.20496)
			(xy 129.311908 -263.205214) (xy 129.299843 -263.206816) (xy 129.279142 -263.219545) (xy 129.272284 -263.229598)
			(xy 129.270252 -263.233408) (xy 129.22377 -263.328658) (xy 129.226818 -263.35736) (xy 129.235708 -263.36879)
			(xy 129.250782 -263.389042) (xy 129.274777 -263.433455) (xy 129.291149 -263.481208) (xy 129.299453 -263.531001)
			(xy 129.29997 -263.556242) (xy 129.299448 -263.581497) (xy 129.291135 -263.631319) (xy 129.274734 -263.679093)
			(xy 129.250693 -263.723516) (xy 129.219669 -263.763376) (xy 129.182507 -263.797586) (xy 129.140221 -263.825212)
			(xy 129.093965 -263.845502) (xy 129.045 -263.857902) (xy 128.994662 -263.862073) (xy 128.944324 -263.857902)
			(xy 128.895359 -263.845502) (xy 128.849103 -263.825212) (xy 128.806817 -263.797586) (xy 128.769655 -263.763376)
			(xy 128.738631 -263.723516) (xy 128.71459 -263.679093) (xy 128.698189 -263.631319) (xy 128.689876 -263.581497)
			(xy 128.689354 -263.556242) (xy 128.68987 -263.531001) (xy 128.698164 -263.481204) (xy 128.714533 -263.433449)
			(xy 128.738532 -263.389035) (xy 128.753616 -263.36879) (xy 128.762506 -263.35736) (xy 128.765554 -263.328658)
			(xy 128.719072 -263.233408) (xy 128.71704 -263.229598) (xy 128.710173 -263.219554) (xy 128.689476 -263.206833)
			(xy 128.677416 -263.205214) (xy 128.673352 -263.20496) (xy 128.380998 -263.20496) (xy 128.37922 -263.20496)
			(xy 128.367274 -263.206092) (xy 128.346339 -263.217752) (xy 128.339088 -263.227312) (xy 128.335532 -263.233408)
			(xy 128.295146 -263.314942) (xy 128.292208 -263.321385) (xy 128.289642 -263.335305) (xy 128.290066 -263.342374)
			(xy 128.290574 -263.346438) (xy 128.305548 -263.363859) (xy 128.33082 -263.402218) (xy 128.350266 -263.443834)
			(xy 128.363476 -263.487829) (xy 128.37017 -263.533274) (xy 128.370584 -263.556242) (xy 128.370097 -263.581052)
			(xy 128.362335 -263.63006) (xy 128.347002 -263.67725) (xy 128.324475 -263.721461) (xy 128.29531 -263.761604)
			(xy 128.260224 -263.79669) (xy 128.220081 -263.825855) (xy 128.17587 -263.848382) (xy 128.12868 -263.863715)
			(xy 128.079672 -263.871477) (xy 128.030052 -263.871477) (xy 127.981044 -263.863715) (xy 127.933854 -263.848382)
			(xy 127.889643 -263.825855) (xy 127.8495 -263.79669) (xy 127.814414 -263.761604) (xy 127.785249 -263.721461)
			(xy 127.762722 -263.67725) (xy 127.747389 -263.63006) (xy 127.739627 -263.581052) (xy 127.73914 -263.556242)
			(xy 127.739686 -263.529368) (xy 127.748797 -263.476399) (xy 127.766745 -263.425737) (xy 127.793014 -263.378845)
			(xy 127.809498 -263.357614) (xy 127.813997 -263.351651) (xy 127.819666 -263.337838) (xy 127.820674 -263.330436)
			(xy 127.820928 -263.327896) (xy 127.774192 -263.233408) (xy 127.770636 -263.227312) (xy 127.763397 -263.217735)
			(xy 127.742458 -263.206058) (xy 127.730504 -263.20496) (xy 127.436118 -263.20496) (xy 127.432054 -263.205214)
			(xy 127.419996 -263.206827) (xy 127.399315 -263.219567) (xy 127.39243 -263.229598) (xy 127.390398 -263.233408)
			(xy 127.343916 -263.328658) (xy 127.346964 -263.35736) (xy 127.355854 -263.36879) (xy 127.37093 -263.389041)
			(xy 127.39493 -263.433454) (xy 127.411305 -263.481206) (xy 127.41961 -263.531001) (xy 127.420116 -263.556242)
			(xy 127.419594 -263.581497) (xy 127.411281 -263.631319) (xy 127.39488 -263.679093) (xy 127.370839 -263.723516)
			(xy 127.339815 -263.763376) (xy 127.302653 -263.797586) (xy 127.260367 -263.825212) (xy 127.214111 -263.845502)
			(xy 127.165146 -263.857902) (xy 127.114808 -263.862073) (xy 127.06447 -263.857902) (xy 127.015505 -263.845502)
			(xy 126.969249 -263.825212) (xy 126.926963 -263.797586) (xy 126.889801 -263.763376) (xy 126.858777 -263.723516)
			(xy 126.834736 -263.679093) (xy 126.818335 -263.631319) (xy 126.810022 -263.581497) (xy 126.8095 -263.556242)
			(xy 126.810016 -263.531) (xy 126.818309 -263.481203) (xy 126.834675 -263.433446) (xy 126.858671 -263.38903)
			(xy 126.873762 -263.36879) (xy 126.882652 -263.35736) (xy 126.8857 -263.328658) (xy 126.839218 -263.233408)
			(xy 126.837186 -263.229598) (xy 126.830323 -263.219547) (xy 126.809628 -263.206808) (xy 126.797562 -263.205214)
			(xy 126.793498 -263.20496) (xy 125.55601 -263.20496) (xy 125.551946 -263.205214) (xy 125.539889 -263.206828)
			(xy 125.519211 -263.21957) (xy 125.512322 -263.229598) (xy 125.51029 -263.233408) (xy 125.463808 -263.328658)
			(xy 125.466856 -263.35736) (xy 125.475746 -263.36879) (xy 125.490822 -263.389041) (xy 125.514823 -263.433453)
			(xy 125.531198 -263.481206) (xy 125.539503 -263.531001) (xy 125.540008 -263.556242) (xy 125.539486 -263.581497)
			(xy 125.531173 -263.631319) (xy 125.514772 -263.679093) (xy 125.490731 -263.723516) (xy 125.459707 -263.763376)
			(xy 125.422545 -263.797586) (xy 125.380259 -263.825212) (xy 125.334003 -263.845502) (xy 125.285038 -263.857902)
			(xy 125.2347 -263.862073) (xy 125.184362 -263.857902) (xy 125.135397 -263.845502) (xy 125.089141 -263.825212)
			(xy 125.046855 -263.797586) (xy 125.009693 -263.763376) (xy 124.978669 -263.723516) (xy 124.954628 -263.679093)
			(xy 124.938227 -263.631319) (xy 124.929914 -263.581497) (xy 124.929392 -263.556242) (xy 124.929908 -263.531)
			(xy 124.9382 -263.481202) (xy 124.954567 -263.433446) (xy 124.978562 -263.389029) (xy 124.993654 -263.36879)
			(xy 125.002544 -263.35736) (xy 125.005592 -263.328658) (xy 124.95911 -263.233408) (xy 124.957078 -263.229598)
			(xy 124.950214 -263.219548) (xy 124.929519 -263.206812) (xy 124.917454 -263.205214) (xy 124.91339 -263.20496)
			(xy 123.676156 -263.20496) (xy 123.672092 -263.205214) (xy 123.660029 -263.206819) (xy 123.639334 -263.219551)
			(xy 123.632468 -263.229598) (xy 123.630436 -263.233408) (xy 123.583954 -263.328658) (xy 123.587002 -263.35736)
			(xy 123.595892 -263.36879) (xy 123.610967 -263.389041) (xy 123.634963 -263.433455) (xy 123.651336 -263.481207)
			(xy 123.65964 -263.531001) (xy 123.660154 -263.556242) (xy 123.659632 -263.581497) (xy 123.651319 -263.631319)
			(xy 123.634918 -263.679093) (xy 123.610877 -263.723516) (xy 123.579853 -263.763376) (xy 123.542691 -263.797586)
			(xy 123.500405 -263.825212) (xy 123.454149 -263.845502) (xy 123.405184 -263.857902) (xy 123.354846 -263.862073)
			(xy 123.304508 -263.857902) (xy 123.255543 -263.845502) (xy 123.209287 -263.825212) (xy 123.167001 -263.797586)
			(xy 123.129839 -263.763376) (xy 123.098815 -263.723516) (xy 123.074774 -263.679093) (xy 123.058373 -263.631319)
			(xy 123.05006 -263.581497) (xy 123.049538 -263.556242) (xy 123.050054 -263.531) (xy 123.058348 -263.481203)
			(xy 123.074716 -263.433448) (xy 123.098714 -263.389034) (xy 123.1138 -263.36879) (xy 123.12269 -263.35736)
			(xy 123.125738 -263.328658) (xy 123.079256 -263.233408) (xy 123.077224 -263.229598) (xy 123.070363 -263.219541)
			(xy 123.04967 -263.206787) (xy 123.0376 -263.205214) (xy 123.033536 -263.20496) (xy 121.796048 -263.20496)
			(xy 121.791984 -263.205214) (xy 121.779922 -263.206821) (xy 121.75923 -263.219555) (xy 121.75236 -263.229598)
			(xy 121.750328 -263.233408) (xy 121.703846 -263.328658) (xy 121.706894 -263.35736) (xy 121.715784 -263.36879)
			(xy 121.730859 -263.389041) (xy 121.754856 -263.433454) (xy 121.77123 -263.481207) (xy 121.779534 -263.531001)
			(xy 121.780046 -263.556242) (xy 121.779524 -263.581497) (xy 121.771211 -263.631319) (xy 121.75481 -263.679093)
			(xy 121.730769 -263.723516) (xy 121.699745 -263.763376) (xy 121.662583 -263.797586) (xy 121.620297 -263.825212)
			(xy 121.574041 -263.845502) (xy 121.525076 -263.857902) (xy 121.474738 -263.862073) (xy 121.4244 -263.857902)
			(xy 121.375435 -263.845502) (xy 121.329179 -263.825212) (xy 121.286893 -263.797586) (xy 121.249731 -263.763376)
			(xy 121.218707 -263.723516) (xy 121.194666 -263.679093) (xy 121.178265 -263.631319) (xy 121.169952 -263.581497)
			(xy 121.16943 -263.556242) (xy 121.169946 -263.531) (xy 121.178239 -263.481203) (xy 121.194608 -263.433447)
			(xy 121.218605 -263.389033) (xy 121.233692 -263.36879) (xy 121.242582 -263.35736) (xy 121.24563 -263.328658)
			(xy 121.199148 -263.233408) (xy 121.197116 -263.229598) (xy 121.190255 -263.219542) (xy 121.169561 -263.206791)
			(xy 121.157492 -263.205214) (xy 121.153428 -263.20496) (xy 119.787162 -263.20496) (xy 119.777096 -263.204529)
			(xy 119.758505 -263.1968) (xy 119.751094 -263.189974) (xy 118.500906 -261.939786) (xy 118.493794 -261.93242)
			(xy 118.474998 -261.9248) (xy 118.026942 -261.9248) (xy 118.016877 -261.924366) (xy 117.998287 -261.916637)
			(xy 117.990874 -261.909814) (xy 117.625114 -261.544054) (xy 117.594126 -261.538212) (xy 117.579648 -261.544562)
			(xy 117.557789 -261.553777) (xy 117.512168 -261.566774) (xy 117.46519 -261.573354) (xy 117.441472 -261.573772)
			(xy 117.44071 -261.573772) (xy 117.413723 -261.573271) (xy 117.360414 -261.564828) (xy 117.309082 -261.54815)
			(xy 117.260992 -261.523646) (xy 117.217327 -261.49192) (xy 117.179163 -261.453753) (xy 117.147441 -261.410086)
			(xy 117.12294 -261.361994) (xy 117.106266 -261.310661) (xy 117.097827 -261.257351) (xy 117.097302 -261.230364)
			(xy 117.097302 -261.229602) (xy 117.09774 -261.205886) (xy 117.104335 -261.158914) (xy 117.117317 -261.113291)
			(xy 117.126512 -261.091426) (xy 117.132862 -261.076948) (xy 117.12702 -261.04596) (xy 116.27104 -260.18998)
			(xy 116.24818 -260.182614) (xy 116.235988 -260.184392) (xy 116.222617 -260.186406) (xy 116.195661 -260.188571)
			(xy 116.18214 -260.18871) (xy 116.155151 -260.188211) (xy 116.101836 -260.179773) (xy 116.050497 -260.163097)
			(xy 116.0024 -260.138595) (xy 115.958728 -260.106871) (xy 115.920557 -260.068704) (xy 115.888827 -260.025036)
			(xy 115.864319 -259.976942) (xy 115.847637 -259.925605) (xy 115.839192 -259.872291) (xy 115.838732 -259.845302)
			(xy 115.838887 -259.831782) (xy 115.84105 -259.804827) (xy 115.84305 -259.791454) (xy 115.844828 -259.779262)
			(xy 115.837462 -259.756402) (xy 115.546886 -259.465826) (xy 115.539774 -259.45846) (xy 115.520978 -259.45084)
			(xy 113.917222 -259.45084) (xy 113.907505 -259.451265) (xy 113.889459 -259.458479) (xy 113.875385 -259.471881)
			(xy 113.870994 -259.480558) (xy 113.832894 -259.564886) (xy 113.82933 -259.573863) (xy 113.828491 -259.593145)
			(xy 113.834816 -259.611379) (xy 113.840768 -259.618988) (xy 113.840768 -259.619242) (xy 113.856687 -259.638113)
			(xy 113.883516 -259.679557) (xy 113.904139 -259.724412) (xy 113.918133 -259.771757) (xy 113.92521 -259.820617)
			(xy 113.925604 -259.845302) (xy 113.925124 -259.871001) (xy 113.917463 -259.921825) (xy 113.902314 -259.970939)
			(xy 113.880013 -260.017247) (xy 113.85106 -260.059714) (xy 113.8161 -260.097391) (xy 113.775916 -260.129437)
			(xy 113.731404 -260.155136) (xy 113.683559 -260.173913) (xy 113.63345 -260.185351) (xy 113.582196 -260.189192)
			(xy 113.530942 -260.185351) (xy 113.480833 -260.173913) (xy 113.432988 -260.155136) (xy 113.388476 -260.129437)
			(xy 113.348292 -260.097391) (xy 113.313332 -260.059714) (xy 113.284379 -260.017247) (xy 113.262078 -259.970939)
			(xy 113.246929 -259.921825) (xy 113.239268 -259.871001) (xy 113.238788 -259.845302) (xy 113.238534 -259.845302)
			(xy 113.238961 -259.820618) (xy 113.246027 -259.771759) (xy 113.260013 -259.724415) (xy 113.280631 -259.679559)
			(xy 113.307457 -259.638117) (xy 113.32337 -259.619242) (xy 113.333276 -259.608066) (xy 113.337848 -259.578602)
			(xy 113.293398 -259.480558) (xy 113.288979 -259.471896) (xy 113.274923 -259.458481) (xy 113.256885 -259.451261)
			(xy 113.24717 -259.45084) (xy 111.807498 -259.45084) (xy 111.797429 -259.450415) (xy 111.778831 -259.442693)
			(xy 111.77143 -259.435854) (xy 111.474504 -259.138928) (xy 111.467892 -259.132851) (xy 111.451591 -259.12534)
			(xy 111.433703 -259.123874) (xy 111.424974 -259.125974) (xy 111.42472 -259.125974) (xy 111.402065 -259.131892)
			(xy 111.355676 -259.138259) (xy 111.332264 -259.138674) (xy 111.329216 -259.138674) (xy 111.302542 -259.137929)
			(xy 111.249903 -259.129202) (xy 111.199246 -259.112439) (xy 111.151792 -259.088041) (xy 111.108684 -259.056597)
			(xy 111.070957 -259.018863) (xy 111.039522 -258.975747) (xy 111.015134 -258.928289) (xy 110.998381 -258.877629)
			(xy 110.989665 -258.824987) (xy 110.988856 -258.798314) (xy 110.988856 -258.795012) (xy 110.989265 -258.771663)
			(xy 110.995638 -258.725401) (xy 111.001556 -258.70281) (xy 111.001556 -258.702556) (xy 111.003652 -258.693816)
			(xy 111.002246 -258.67591) (xy 110.994731 -258.659597) (xy 110.988602 -258.653026) (xy 110.873286 -258.53771)
			(xy 110.866174 -258.530344) (xy 110.847378 -258.522724) (xy 109.24286 -258.522724) (xy 109.230309 -258.523375)
			(xy 109.208192 -258.535242) (xy 109.200696 -258.54533) (xy 109.146594 -258.626356) (xy 109.144054 -258.651248)
			(xy 109.149134 -258.663186) (xy 109.158684 -258.687346) (xy 109.171214 -258.737762) (xy 109.176007 -258.789491)
			(xy 109.172954 -258.841351) (xy 109.162124 -258.892159) (xy 109.143765 -258.940757) (xy 109.118295 -258.986035)
			(xy 109.086296 -259.02696) (xy 109.048498 -259.062598) (xy 109.005763 -259.092137) (xy 108.959067 -259.114901)
			(xy 108.909474 -259.130372) (xy 108.858117 -259.138197) (xy 108.806167 -259.138197) (xy 108.75481 -259.130372)
			(xy 108.705217 -259.114901) (xy 108.658521 -259.092137) (xy 108.615786 -259.062598) (xy 108.577988 -259.02696)
			(xy 108.545989 -258.986035) (xy 108.520519 -258.940757) (xy 108.50216 -258.892159) (xy 108.49133 -258.841351)
			(xy 108.488277 -258.789491) (xy 108.49307 -258.737762) (xy 108.5056 -258.687346) (xy 108.51515 -258.663186)
			(xy 108.52023 -258.651248) (xy 108.51769 -258.626356) (xy 108.463588 -258.54533) (xy 108.456069 -258.535274)
			(xy 108.433961 -258.523429) (xy 108.421424 -258.522724) (xy 108.32846 -258.522724) (xy 108.315909 -258.523375)
			(xy 108.293792 -258.535242) (xy 108.286296 -258.54533) (xy 108.232194 -258.626356) (xy 108.229654 -258.651248)
			(xy 108.234734 -258.663186) (xy 108.244284 -258.687346) (xy 108.256814 -258.737762) (xy 108.261607 -258.789491)
			(xy 108.258554 -258.841351) (xy 108.247724 -258.892159) (xy 108.229365 -258.940757) (xy 108.203895 -258.986035)
			(xy 108.171896 -259.02696) (xy 108.134098 -259.062598) (xy 108.091363 -259.092137) (xy 108.044667 -259.114901)
			(xy 107.995074 -259.130372) (xy 107.943717 -259.138197) (xy 107.891767 -259.138197) (xy 107.84041 -259.130372)
			(xy 107.790817 -259.114901) (xy 107.744121 -259.092137) (xy 107.701386 -259.062598) (xy 107.663588 -259.02696)
			(xy 107.631589 -258.986035) (xy 107.606119 -258.940757) (xy 107.58776 -258.892159) (xy 107.57693 -258.841351)
			(xy 107.573877 -258.789491) (xy 107.57867 -258.737762) (xy 107.5912 -258.687346) (xy 107.60075 -258.663186)
			(xy 107.60583 -258.651248) (xy 107.60329 -258.626356) (xy 107.549188 -258.54533) (xy 107.541669 -258.535274)
			(xy 107.519561 -258.523429) (xy 107.507024 -258.522724) (xy 106.734864 -258.522724) (xy 106.711242 -258.53644)
			(xy 106.704384 -258.548632) (xy 106.691234 -258.571025) (xy 106.659239 -258.611928) (xy 106.62145 -258.647546)
			(xy 106.578728 -258.677067) (xy 106.532048 -258.699818) (xy 106.482474 -258.71528) (xy 106.431137 -258.7231)
			(xy 106.379207 -258.7231) (xy 106.32787 -258.71528) (xy 106.278296 -258.699818) (xy 106.231616 -258.677067)
			(xy 106.188894 -258.647546) (xy 106.151105 -258.611928) (xy 106.11911 -258.571025) (xy 106.10596 -258.548632)
			(xy 106.099102 -258.53644) (xy 106.07548 -258.522724) (xy 105.820464 -258.522724) (xy 105.796842 -258.53644)
			(xy 105.789984 -258.548632) (xy 105.776834 -258.571025) (xy 105.744839 -258.611928) (xy 105.70705 -258.647546)
			(xy 105.664328 -258.677067) (xy 105.617648 -258.699818) (xy 105.568074 -258.71528) (xy 105.516737 -258.7231)
			(xy 105.464807 -258.7231) (xy 105.41347 -258.71528) (xy 105.363896 -258.699818) (xy 105.317216 -258.677067)
			(xy 105.274494 -258.647546) (xy 105.236705 -258.611928) (xy 105.20471 -258.571025) (xy 105.19156 -258.548632)
			(xy 105.184702 -258.53644) (xy 105.16108 -258.522724) (xy 103.249476 -258.522724) (xy 103.240775 -258.523077)
			(xy 103.224375 -258.528895) (xy 103.210858 -258.539854) (xy 103.206042 -258.547108) (xy 103.153972 -258.63296)
			(xy 103.15321 -258.659376) (xy 103.159306 -258.671314) (xy 103.171608 -258.695996) (xy 103.189037 -258.748313)
			(xy 103.197864 -258.802746) (xy 103.198422 -258.830318) (xy 103.197891 -258.857303) (xy 103.189446 -258.910607)
			(xy 103.172767 -258.961934) (xy 103.148265 -259.010021) (xy 103.116542 -259.053682) (xy 103.078379 -259.091844)
			(xy 103.034717 -259.123567) (xy 102.986631 -259.148069) (xy 102.935303 -259.164747) (xy 102.881999 -259.173192)
			(xy 102.855014 -259.173726) (xy 102.82668 -259.173148) (xy 102.770778 -259.163856) (xy 102.717158 -259.145519)
			(xy 102.691946 -259.132578) (xy 102.680008 -259.125974) (xy 102.653338 -259.126736) (xy 102.566978 -259.178298)
			(xy 102.559606 -259.183099) (xy 102.54841 -259.196654) (xy 102.542459 -259.213196) (xy 102.542086 -259.221986)
			(xy 102.542086 -259.330444) (xy 105.146859 -259.330444) (xy 105.150889 -259.277946) (xy 105.162886 -259.226678)
			(xy 105.182569 -259.177843) (xy 105.209475 -259.132584) (xy 105.242975 -259.091963) (xy 105.282283 -259.056932)
			(xy 105.326478 -259.028312) (xy 105.374523 -259.006773) (xy 105.425294 -258.992821) (xy 105.477599 -258.986783)
			(xy 105.530213 -258.9888) (xy 105.581903 -258.998824) (xy 105.631456 -259.016622) (xy 105.677712 -259.041775)
			(xy 105.719586 -259.073694) (xy 105.756098 -259.111632) (xy 105.78639 -259.154698) (xy 105.809753 -259.201883)
			(xy 105.825639 -259.252082) (xy 105.833676 -259.304118) (xy 105.83418 -259.330444) (xy 106.061259 -259.330444)
			(xy 106.065289 -259.277946) (xy 106.077286 -259.226678) (xy 106.096969 -259.177843) (xy 106.123875 -259.132584)
			(xy 106.157375 -259.091963) (xy 106.196683 -259.056932) (xy 106.240878 -259.028312) (xy 106.288923 -259.006773)
			(xy 106.339694 -258.992821) (xy 106.391999 -258.986783) (xy 106.444613 -258.9888) (xy 106.496303 -258.998824)
			(xy 106.545856 -259.016622) (xy 106.592112 -259.041775) (xy 106.633986 -259.073694) (xy 106.670498 -259.111632)
			(xy 106.70079 -259.154698) (xy 106.724153 -259.201883) (xy 106.740039 -259.252082) (xy 106.748076 -259.304118)
			(xy 106.74858 -259.330444) (xy 106.748076 -259.35677) (xy 106.740039 -259.408806) (xy 106.724153 -259.459005)
			(xy 106.70079 -259.50619) (xy 106.670498 -259.549256) (xy 106.633986 -259.587194) (xy 106.592112 -259.619113)
			(xy 106.545856 -259.644266) (xy 106.496303 -259.662064) (xy 106.444613 -259.672088) (xy 106.391999 -259.674105)
			(xy 106.339694 -259.668067) (xy 106.288923 -259.654115) (xy 106.240878 -259.632576) (xy 106.196683 -259.603956)
			(xy 106.157375 -259.568925) (xy 106.123875 -259.528304) (xy 106.096969 -259.483045) (xy 106.077286 -259.43421)
			(xy 106.065289 -259.382942) (xy 106.061259 -259.330444) (xy 105.83418 -259.330444) (xy 105.833676 -259.35677)
			(xy 105.825639 -259.408806) (xy 105.809753 -259.459005) (xy 105.78639 -259.50619) (xy 105.756098 -259.549256)
			(xy 105.719586 -259.587194) (xy 105.677712 -259.619113) (xy 105.631456 -259.644266) (xy 105.581903 -259.662064)
			(xy 105.530213 -259.672088) (xy 105.477599 -259.674105) (xy 105.425294 -259.668067) (xy 105.374523 -259.654115)
			(xy 105.326478 -259.632576) (xy 105.282283 -259.603956) (xy 105.242975 -259.568925) (xy 105.209475 -259.528304)
			(xy 105.182569 -259.483045) (xy 105.162886 -259.43421) (xy 105.150889 -259.382942) (xy 105.146859 -259.330444)
			(xy 102.542086 -259.330444) (xy 102.542086 -259.338572) (xy 102.54245 -259.347366) (xy 102.548392 -259.36392)
			(xy 102.559585 -259.377487) (xy 102.566978 -259.38226) (xy 102.653338 -259.433822) (xy 102.680008 -259.434584)
			(xy 102.691946 -259.42798) (xy 102.717161 -259.415043) (xy 102.770779 -259.396699) (xy 102.82668 -259.387402)
			(xy 102.855014 -259.386832) (xy 102.880709 -259.387313) (xy 102.931525 -259.394974) (xy 102.980632 -259.410123)
			(xy 103.026933 -259.432422) (xy 103.069393 -259.461373) (xy 103.107064 -259.496328) (xy 103.139105 -259.536507)
			(xy 103.164799 -259.581013) (xy 103.183574 -259.628851) (xy 103.195009 -259.678953) (xy 103.19885 -259.7302)
			(xy 103.195009 -259.781447) (xy 103.183574 -259.831549) (xy 103.178176 -259.845302) (xy 107.573829 -259.845302)
			(xy 107.577859 -259.792804) (xy 107.589856 -259.741536) (xy 107.609539 -259.692701) (xy 107.636445 -259.647442)
			(xy 107.669945 -259.606821) (xy 107.709253 -259.57179) (xy 107.753448 -259.54317) (xy 107.801493 -259.521631)
			(xy 107.852264 -259.507679) (xy 107.904569 -259.501641) (xy 107.957183 -259.503658) (xy 108.008873 -259.513682)
			(xy 108.058426 -259.53148) (xy 108.104682 -259.556633) (xy 108.146556 -259.588552) (xy 108.183068 -259.62649)
			(xy 108.21336 -259.669556) (xy 108.236723 -259.716741) (xy 108.252609 -259.76694) (xy 108.260646 -259.818976)
			(xy 108.26115 -259.845302) (xy 108.488229 -259.845302) (xy 108.492259 -259.792804) (xy 108.504256 -259.741536)
			(xy 108.523939 -259.692701) (xy 108.550845 -259.647442) (xy 108.584345 -259.606821) (xy 108.623653 -259.57179)
			(xy 108.667848 -259.54317) (xy 108.715893 -259.521631) (xy 108.766664 -259.507679) (xy 108.818969 -259.501641)
			(xy 108.871583 -259.503658) (xy 108.923273 -259.513682) (xy 108.972826 -259.53148) (xy 109.019082 -259.556633)
			(xy 109.060956 -259.588552) (xy 109.097468 -259.62649) (xy 109.12776 -259.669556) (xy 109.151123 -259.716741)
			(xy 109.167009 -259.76694) (xy 109.175046 -259.818976) (xy 109.17555 -259.845302) (xy 110.988351 -259.845302)
			(xy 110.992381 -259.792804) (xy 111.004378 -259.741536) (xy 111.024061 -259.692701) (xy 111.050967 -259.647442)
			(xy 111.084467 -259.606821) (xy 111.123775 -259.57179) (xy 111.16797 -259.54317) (xy 111.216015 -259.521631)
			(xy 111.266786 -259.507679) (xy 111.319091 -259.501641) (xy 111.371705 -259.503658) (xy 111.423395 -259.513682)
			(xy 111.472948 -259.53148) (xy 111.519204 -259.556633) (xy 111.561078 -259.588552) (xy 111.59759 -259.62649)
			(xy 111.627882 -259.669556) (xy 111.651245 -259.716741) (xy 111.667131 -259.76694) (xy 111.675168 -259.818976)
			(xy 111.675672 -259.845302) (xy 111.675168 -259.871628) (xy 111.667131 -259.923664) (xy 111.651245 -259.973863)
			(xy 111.627882 -260.021048) (xy 111.59759 -260.064114) (xy 111.561078 -260.102052) (xy 111.519204 -260.133971)
			(xy 111.472948 -260.159124) (xy 111.423395 -260.176922) (xy 111.371705 -260.186946) (xy 111.319091 -260.188963)
			(xy 111.266786 -260.182925) (xy 111.216015 -260.168973) (xy 111.16797 -260.147434) (xy 111.123775 -260.118814)
			(xy 111.084467 -260.083783) (xy 111.050967 -260.043162) (xy 111.024061 -259.997903) (xy 111.004378 -259.949068)
			(xy 110.992381 -259.8978) (xy 110.988351 -259.845302) (xy 109.17555 -259.845302) (xy 109.175046 -259.871628)
			(xy 109.167009 -259.923664) (xy 109.151123 -259.973863) (xy 109.12776 -260.021048) (xy 109.097468 -260.064114)
			(xy 109.060956 -260.102052) (xy 109.019082 -260.133971) (xy 108.972826 -260.159124) (xy 108.923273 -260.176922)
			(xy 108.871583 -260.186946) (xy 108.818969 -260.188963) (xy 108.766664 -260.182925) (xy 108.715893 -260.168973)
			(xy 108.667848 -260.147434) (xy 108.623653 -260.118814) (xy 108.584345 -260.083783) (xy 108.550845 -260.043162)
			(xy 108.523939 -259.997903) (xy 108.504256 -259.949068) (xy 108.492259 -259.8978) (xy 108.488229 -259.845302)
			(xy 108.26115 -259.845302) (xy 108.260646 -259.871628) (xy 108.252609 -259.923664) (xy 108.236723 -259.973863)
			(xy 108.21336 -260.021048) (xy 108.183068 -260.064114) (xy 108.146556 -260.102052) (xy 108.104682 -260.133971)
			(xy 108.058426 -260.159124) (xy 108.008873 -260.176922) (xy 107.957183 -260.186946) (xy 107.904569 -260.188963)
			(xy 107.852264 -260.182925) (xy 107.801493 -260.168973) (xy 107.753448 -260.147434) (xy 107.709253 -260.118814)
			(xy 107.669945 -260.083783) (xy 107.636445 -260.043162) (xy 107.609539 -259.997903) (xy 107.589856 -259.949068)
			(xy 107.577859 -259.8978) (xy 107.573829 -259.845302) (xy 103.178176 -259.845302) (xy 103.164799 -259.879387)
			(xy 103.139105 -259.923893) (xy 103.107064 -259.964072) (xy 103.069393 -259.999027) (xy 103.026933 -260.027978)
			(xy 102.980632 -260.050277) (xy 102.931525 -260.065426) (xy 102.880709 -260.073087) (xy 102.855014 -260.073648)
			(xy 102.82668 -260.07307) (xy 102.770778 -260.063778) (xy 102.717158 -260.045443) (xy 102.691946 -260.0325)
			(xy 102.680008 -260.025896) (xy 102.653338 -260.026658) (xy 102.566978 -260.07822) (xy 102.559608 -260.083022)
			(xy 102.548418 -260.096577) (xy 102.542474 -260.113119) (xy 102.542086 -260.121908) (xy 102.542086 -260.264148)
			(xy 102.541654 -260.274214) (xy 102.539081 -260.280404) (xy 105.146859 -260.280404) (xy 105.150889 -260.227906)
			(xy 105.162886 -260.176638) (xy 105.182569 -260.127803) (xy 105.209475 -260.082544) (xy 105.242975 -260.041923)
			(xy 105.282283 -260.006892) (xy 105.326478 -259.978272) (xy 105.374523 -259.956733) (xy 105.425294 -259.942781)
			(xy 105.477599 -259.936743) (xy 105.530213 -259.93876) (xy 105.581903 -259.948784) (xy 105.631456 -259.966582)
			(xy 105.677712 -259.991735) (xy 105.719586 -260.023654) (xy 105.756098 -260.061592) (xy 105.78639 -260.104658)
			(xy 105.809753 -260.151843) (xy 105.825639 -260.202042) (xy 105.833676 -260.254078) (xy 105.83418 -260.280404)
			(xy 106.061259 -260.280404) (xy 106.065289 -260.227906) (xy 106.077286 -260.176638) (xy 106.096969 -260.127803)
			(xy 106.123875 -260.082544) (xy 106.157375 -260.041923) (xy 106.196683 -260.006892) (xy 106.240878 -259.978272)
			(xy 106.288923 -259.956733) (xy 106.339694 -259.942781) (xy 106.391999 -259.936743) (xy 106.444613 -259.93876)
			(xy 106.496303 -259.948784) (xy 106.545856 -259.966582) (xy 106.592112 -259.991735) (xy 106.633986 -260.023654)
			(xy 106.670498 -260.061592) (xy 106.70079 -260.104658) (xy 106.724153 -260.151843) (xy 106.740039 -260.202042)
			(xy 106.748076 -260.254078) (xy 106.74858 -260.280404) (xy 106.748076 -260.30673) (xy 106.740039 -260.358766)
			(xy 106.724153 -260.408965) (xy 106.70079 -260.45615) (xy 106.670498 -260.499216) (xy 106.633986 -260.537154)
			(xy 106.592112 -260.569073) (xy 106.545856 -260.594226) (xy 106.496303 -260.612024) (xy 106.444613 -260.622048)
			(xy 106.391999 -260.624065) (xy 106.339694 -260.618027) (xy 106.288923 -260.604075) (xy 106.240878 -260.582536)
			(xy 106.196683 -260.553916) (xy 106.157375 -260.518885) (xy 106.123875 -260.478264) (xy 106.096969 -260.433005)
			(xy 106.077286 -260.38417) (xy 106.065289 -260.332902) (xy 106.061259 -260.280404) (xy 105.83418 -260.280404)
			(xy 105.833676 -260.30673) (xy 105.825639 -260.358766) (xy 105.809753 -260.408965) (xy 105.78639 -260.45615)
			(xy 105.756098 -260.499216) (xy 105.719586 -260.537154) (xy 105.677712 -260.569073) (xy 105.631456 -260.594226)
			(xy 105.581903 -260.612024) (xy 105.530213 -260.622048) (xy 105.477599 -260.624065) (xy 105.425294 -260.618027)
			(xy 105.374523 -260.604075) (xy 105.326478 -260.582536) (xy 105.282283 -260.553916) (xy 105.242975 -260.518885)
			(xy 105.209475 -260.478264) (xy 105.182569 -260.433005) (xy 105.162886 -260.38417) (xy 105.150889 -260.332902)
			(xy 105.146859 -260.280404) (xy 102.539081 -260.280404) (xy 102.533926 -260.292804) (xy 102.5271 -260.300216)
			(xy 102.349808 -260.477508) (xy 102.342409 -260.484355) (xy 102.323812 -260.492091) (xy 102.31374 -260.492494)
			(xy 101.327712 -260.492494) (xy 101.317641 -260.492914) (xy 101.299032 -260.500625) (xy 101.291644 -260.50748)
			(xy 101.09327 -260.705854) (xy 101.086001 -260.713885) (xy 101.078375 -260.734139) (xy 101.078538 -260.74497)
			(xy 101.0793 -260.755638) (xy 101.08946 -260.774942) (xy 101.149912 -260.821932) (xy 101.159526 -260.828578)
			(xy 101.182412 -260.833207) (xy 101.193854 -260.830822) (xy 101.212818 -260.826173) (xy 101.251547 -260.821209)
			(xy 101.27107 -260.820916) (xy 101.273864 -260.820916) (xy 101.297712 -260.821592) (xy 101.34477 -260.829439)
			(xy 101.390034 -260.84451) (xy 101.432402 -260.866439) (xy 101.470844 -260.894691) (xy 101.504424 -260.928578)
			(xy 101.532324 -260.967277) (xy 101.553864 -261.009844) (xy 101.568522 -261.055243) (xy 101.575939 -261.10237)
			(xy 101.576378 -261.126224) (xy 101.90532 -261.126224) (xy 101.90928 -261.07717) (xy 101.921057 -261.029386)
			(xy 101.940348 -260.98411) (xy 101.966651 -260.942514) (xy 101.999286 -260.905677) (xy 102.037407 -260.874552)
			(xy 102.080028 -260.849945) (xy 102.126044 -260.832493) (xy 102.174263 -260.822649) (xy 102.223438 -260.820668)
			(xy 102.272293 -260.8266) (xy 102.319564 -260.840292) (xy 102.364026 -260.86139) (xy 102.404529 -260.889346)
			(xy 102.440022 -260.923438) (xy 102.469587 -260.962782) (xy 102.492458 -261.006359) (xy 102.508042 -261.05304)
			(xy 102.515937 -261.101617) (xy 102.516432 -261.126224) (xy 102.516391 -261.128256) (xy 102.842072 -261.128256)
			(xy 102.846032 -261.079202) (xy 102.857809 -261.031418) (xy 102.8771 -260.986142) (xy 102.903403 -260.944546)
			(xy 102.936038 -260.907709) (xy 102.974159 -260.876584) (xy 103.01678 -260.851977) (xy 103.062796 -260.834525)
			(xy 103.111015 -260.824681) (xy 103.16019 -260.8227) (xy 103.209045 -260.828632) (xy 103.256316 -260.842324)
			(xy 103.300778 -260.863422) (xy 103.341281 -260.891378) (xy 103.376774 -260.92547) (xy 103.406339 -260.964814)
			(xy 103.42921 -261.008391) (xy 103.444794 -261.055072) (xy 103.452689 -261.103649) (xy 103.453184 -261.128256)
			(xy 103.782126 -261.128256) (xy 103.786086 -261.079202) (xy 103.797863 -261.031418) (xy 103.817154 -260.986142)
			(xy 103.843457 -260.944546) (xy 103.876092 -260.907709) (xy 103.914213 -260.876584) (xy 103.956834 -260.851977)
			(xy 104.00285 -260.834525) (xy 104.051069 -260.824681) (xy 104.100244 -260.8227) (xy 104.149099 -260.828632)
			(xy 104.19637 -260.842324) (xy 104.240832 -260.863422) (xy 104.281335 -260.891378) (xy 104.316828 -260.92547)
			(xy 104.346393 -260.964814) (xy 104.369264 -261.008391) (xy 104.384848 -261.055072) (xy 104.392743 -261.103649)
			(xy 104.393238 -261.128256) (xy 104.392743 -261.152863) (xy 104.384848 -261.20144) (xy 104.375192 -261.230364)
			(xy 105.146859 -261.230364) (xy 105.150889 -261.177866) (xy 105.162886 -261.126598) (xy 105.182569 -261.077763)
			(xy 105.209475 -261.032504) (xy 105.242975 -260.991883) (xy 105.282283 -260.956852) (xy 105.326478 -260.928232)
			(xy 105.374523 -260.906693) (xy 105.425294 -260.892741) (xy 105.477599 -260.886703) (xy 105.530213 -260.88872)
			(xy 105.581903 -260.898744) (xy 105.631456 -260.916542) (xy 105.677712 -260.941695) (xy 105.719586 -260.973614)
			(xy 105.756098 -261.011552) (xy 105.78639 -261.054618) (xy 105.809753 -261.101803) (xy 105.825639 -261.152002)
			(xy 105.833676 -261.204038) (xy 105.83418 -261.230364) (xy 106.061259 -261.230364) (xy 106.065289 -261.177866)
			(xy 106.077286 -261.126598) (xy 106.096969 -261.077763) (xy 106.123875 -261.032504) (xy 106.157375 -260.991883)
			(xy 106.196683 -260.956852) (xy 106.240878 -260.928232) (xy 106.288923 -260.906693) (xy 106.339694 -260.892741)
			(xy 106.391999 -260.886703) (xy 106.444613 -260.88872) (xy 106.496303 -260.898744) (xy 106.545856 -260.916542)
			(xy 106.592112 -260.941695) (xy 106.633986 -260.973614) (xy 106.670498 -261.011552) (xy 106.70079 -261.054618)
			(xy 106.724153 -261.101803) (xy 106.740039 -261.152002) (xy 106.748076 -261.204038) (xy 106.74858 -261.230364)
			(xy 106.748076 -261.25669) (xy 106.740039 -261.308726) (xy 106.735498 -261.323074) (xy 107.304081 -261.323074)
			(xy 107.308111 -261.270576) (xy 107.320108 -261.219308) (xy 107.339791 -261.170473) (xy 107.366697 -261.125214)
			(xy 107.400197 -261.084593) (xy 107.439505 -261.049562) (xy 107.4837 -261.020942) (xy 107.531745 -260.999403)
			(xy 107.582516 -260.985451) (xy 107.634821 -260.979413) (xy 107.687435 -260.98143) (xy 107.739125 -260.991454)
			(xy 107.788678 -261.009252) (xy 107.834934 -261.034405) (xy 107.876808 -261.066324) (xy 107.91332 -261.104262)
			(xy 107.943612 -261.147328) (xy 107.966975 -261.194513) (xy 107.982861 -261.244712) (xy 107.990898 -261.296748)
			(xy 107.991402 -261.323074) (xy 108.254041 -261.323074) (xy 108.258071 -261.270576) (xy 108.270068 -261.219308)
			(xy 108.289751 -261.170473) (xy 108.316657 -261.125214) (xy 108.350157 -261.084593) (xy 108.389465 -261.049562)
			(xy 108.43366 -261.020942) (xy 108.481705 -260.999403) (xy 108.532476 -260.985451) (xy 108.584781 -260.979413)
			(xy 108.637395 -260.98143) (xy 108.689085 -260.991454) (xy 108.738638 -261.009252) (xy 108.784894 -261.034405)
			(xy 108.826768 -261.066324) (xy 108.86328 -261.104262) (xy 108.893572 -261.147328) (xy 108.916935 -261.194513)
			(xy 108.932821 -261.244712) (xy 108.940858 -261.296748) (xy 108.941362 -261.323074) (xy 109.204001 -261.323074)
			(xy 109.208031 -261.270576) (xy 109.220028 -261.219308) (xy 109.239711 -261.170473) (xy 109.266617 -261.125214)
			(xy 109.300117 -261.084593) (xy 109.339425 -261.049562) (xy 109.38362 -261.020942) (xy 109.431665 -260.999403)
			(xy 109.482436 -260.985451) (xy 109.534741 -260.979413) (xy 109.587355 -260.98143) (xy 109.639045 -260.991454)
			(xy 109.688598 -261.009252) (xy 109.734854 -261.034405) (xy 109.776728 -261.066324) (xy 109.81324 -261.104262)
			(xy 109.843532 -261.147328) (xy 109.866895 -261.194513) (xy 109.882781 -261.244712) (xy 109.890818 -261.296748)
			(xy 109.891322 -261.323074) (xy 110.153961 -261.323074) (xy 110.157991 -261.270576) (xy 110.169988 -261.219308)
			(xy 110.189671 -261.170473) (xy 110.216577 -261.125214) (xy 110.250077 -261.084593) (xy 110.289385 -261.049562)
			(xy 110.33358 -261.020942) (xy 110.381625 -260.999403) (xy 110.432396 -260.985451) (xy 110.484701 -260.979413)
			(xy 110.537315 -260.98143) (xy 110.589005 -260.991454) (xy 110.638558 -261.009252) (xy 110.684814 -261.034405)
			(xy 110.726688 -261.066324) (xy 110.7632 -261.104262) (xy 110.793492 -261.147328) (xy 110.816855 -261.194513)
			(xy 110.832741 -261.244712) (xy 110.840778 -261.296748) (xy 110.841282 -261.323074) (xy 111.103921 -261.323074)
			(xy 111.107951 -261.270576) (xy 111.119948 -261.219308) (xy 111.139631 -261.170473) (xy 111.166537 -261.125214)
			(xy 111.200037 -261.084593) (xy 111.239345 -261.049562) (xy 111.28354 -261.020942) (xy 111.331585 -260.999403)
			(xy 111.382356 -260.985451) (xy 111.434661 -260.979413) (xy 111.487275 -260.98143) (xy 111.538965 -260.991454)
			(xy 111.588518 -261.009252) (xy 111.634774 -261.034405) (xy 111.676648 -261.066324) (xy 111.71316 -261.104262)
			(xy 111.743452 -261.147328) (xy 111.766815 -261.194513) (xy 111.782701 -261.244712) (xy 111.790738 -261.296748)
			(xy 111.791242 -261.323074) (xy 112.053881 -261.323074) (xy 112.057911 -261.270576) (xy 112.069908 -261.219308)
			(xy 112.089591 -261.170473) (xy 112.116497 -261.125214) (xy 112.149997 -261.084593) (xy 112.189305 -261.049562)
			(xy 112.2335 -261.020942) (xy 112.281545 -260.999403) (xy 112.332316 -260.985451) (xy 112.384621 -260.979413)
			(xy 112.437235 -260.98143) (xy 112.488925 -260.991454) (xy 112.538478 -261.009252) (xy 112.584734 -261.034405)
			(xy 112.626608 -261.066324) (xy 112.66312 -261.104262) (xy 112.693412 -261.147328) (xy 112.716775 -261.194513)
			(xy 112.732661 -261.244712) (xy 112.740698 -261.296748) (xy 112.741202 -261.323074) (xy 113.004095 -261.323074)
			(xy 113.008125 -261.270576) (xy 113.020122 -261.219308) (xy 113.039805 -261.170473) (xy 113.066711 -261.125214)
			(xy 113.100211 -261.084593) (xy 113.139519 -261.049562) (xy 113.183714 -261.020942) (xy 113.231759 -260.999403)
			(xy 113.28253 -260.985451) (xy 113.334835 -260.979413) (xy 113.387449 -260.98143) (xy 113.439139 -260.991454)
			(xy 113.488692 -261.009252) (xy 113.534948 -261.034405) (xy 113.576822 -261.066324) (xy 113.613334 -261.104262)
			(xy 113.643626 -261.147328) (xy 113.666989 -261.194513) (xy 113.682875 -261.244712) (xy 113.690912 -261.296748)
			(xy 113.691416 -261.323074) (xy 113.954055 -261.323074) (xy 113.958085 -261.270576) (xy 113.970082 -261.219308)
			(xy 113.989765 -261.170473) (xy 114.016671 -261.125214) (xy 114.050171 -261.084593) (xy 114.089479 -261.049562)
			(xy 114.133674 -261.020942) (xy 114.181719 -260.999403) (xy 114.23249 -260.985451) (xy 114.284795 -260.979413)
			(xy 114.337409 -260.98143) (xy 114.389099 -260.991454) (xy 114.438652 -261.009252) (xy 114.484908 -261.034405)
			(xy 114.526782 -261.066324) (xy 114.563294 -261.104262) (xy 114.593586 -261.147328) (xy 114.616949 -261.194513)
			(xy 114.632835 -261.244712) (xy 114.640872 -261.296748) (xy 114.641376 -261.323074) (xy 114.904015 -261.323074)
			(xy 114.908045 -261.270576) (xy 114.920042 -261.219308) (xy 114.939725 -261.170473) (xy 114.966631 -261.125214)
			(xy 115.000131 -261.084593) (xy 115.039439 -261.049562) (xy 115.083634 -261.020942) (xy 115.131679 -260.999403)
			(xy 115.18245 -260.985451) (xy 115.234755 -260.979413) (xy 115.287369 -260.98143) (xy 115.339059 -260.991454)
			(xy 115.388612 -261.009252) (xy 115.434868 -261.034405) (xy 115.476742 -261.066324) (xy 115.513254 -261.104262)
			(xy 115.543546 -261.147328) (xy 115.566909 -261.194513) (xy 115.582795 -261.244712) (xy 115.590832 -261.296748)
			(xy 115.591336 -261.323074) (xy 115.853975 -261.323074) (xy 115.858005 -261.270576) (xy 115.870002 -261.219308)
			(xy 115.889685 -261.170473) (xy 115.916591 -261.125214) (xy 115.950091 -261.084593) (xy 115.989399 -261.049562)
			(xy 116.033594 -261.020942) (xy 116.081639 -260.999403) (xy 116.13241 -260.985451) (xy 116.184715 -260.979413)
			(xy 116.237329 -260.98143) (xy 116.289019 -260.991454) (xy 116.338572 -261.009252) (xy 116.384828 -261.034405)
			(xy 116.426702 -261.066324) (xy 116.463214 -261.104262) (xy 116.493506 -261.147328) (xy 116.516869 -261.194513)
			(xy 116.532755 -261.244712) (xy 116.540792 -261.296748) (xy 116.541296 -261.323074) (xy 116.540792 -261.3494)
			(xy 116.532755 -261.401436) (xy 116.516869 -261.451635) (xy 116.493506 -261.49882) (xy 116.463214 -261.541886)
			(xy 116.426702 -261.579824) (xy 116.384828 -261.611743) (xy 116.338572 -261.636896) (xy 116.289019 -261.654694)
			(xy 116.237329 -261.664718) (xy 116.184715 -261.666735) (xy 116.13241 -261.660697) (xy 116.081639 -261.646745)
			(xy 116.033594 -261.625206) (xy 115.989399 -261.596586) (xy 115.950091 -261.561555) (xy 115.916591 -261.520934)
			(xy 115.889685 -261.475675) (xy 115.870002 -261.42684) (xy 115.858005 -261.375572) (xy 115.853975 -261.323074)
			(xy 115.591336 -261.323074) (xy 115.590832 -261.3494) (xy 115.582795 -261.401436) (xy 115.566909 -261.451635)
			(xy 115.543546 -261.49882) (xy 115.513254 -261.541886) (xy 115.476742 -261.579824) (xy 115.434868 -261.611743)
			(xy 115.388612 -261.636896) (xy 115.339059 -261.654694) (xy 115.287369 -261.664718) (xy 115.234755 -261.666735)
			(xy 115.18245 -261.660697) (xy 115.131679 -261.646745) (xy 115.083634 -261.625206) (xy 115.039439 -261.596586)
			(xy 115.000131 -261.561555) (xy 114.966631 -261.520934) (xy 114.939725 -261.475675) (xy 114.920042 -261.42684)
			(xy 114.908045 -261.375572) (xy 114.904015 -261.323074) (xy 114.641376 -261.323074) (xy 114.640872 -261.3494)
			(xy 114.632835 -261.401436) (xy 114.616949 -261.451635) (xy 114.593586 -261.49882) (xy 114.563294 -261.541886)
			(xy 114.526782 -261.579824) (xy 114.484908 -261.611743) (xy 114.438652 -261.636896) (xy 114.389099 -261.654694)
			(xy 114.337409 -261.664718) (xy 114.284795 -261.666735) (xy 114.23249 -261.660697) (xy 114.181719 -261.646745)
			(xy 114.133674 -261.625206) (xy 114.089479 -261.596586) (xy 114.050171 -261.561555) (xy 114.016671 -261.520934)
			(xy 113.989765 -261.475675) (xy 113.970082 -261.42684) (xy 113.958085 -261.375572) (xy 113.954055 -261.323074)
			(xy 113.691416 -261.323074) (xy 113.690912 -261.3494) (xy 113.682875 -261.401436) (xy 113.666989 -261.451635)
			(xy 113.643626 -261.49882) (xy 113.613334 -261.541886) (xy 113.576822 -261.579824) (xy 113.534948 -261.611743)
			(xy 113.488692 -261.636896) (xy 113.439139 -261.654694) (xy 113.387449 -261.664718) (xy 113.334835 -261.666735)
			(xy 113.28253 -261.660697) (xy 113.231759 -261.646745) (xy 113.183714 -261.625206) (xy 113.139519 -261.596586)
			(xy 113.100211 -261.561555) (xy 113.066711 -261.520934) (xy 113.039805 -261.475675) (xy 113.020122 -261.42684)
			(xy 113.008125 -261.375572) (xy 113.004095 -261.323074) (xy 112.741202 -261.323074) (xy 112.740698 -261.3494)
			(xy 112.732661 -261.401436) (xy 112.716775 -261.451635) (xy 112.693412 -261.49882) (xy 112.66312 -261.541886)
			(xy 112.626608 -261.579824) (xy 112.584734 -261.611743) (xy 112.538478 -261.636896) (xy 112.488925 -261.654694)
			(xy 112.437235 -261.664718) (xy 112.384621 -261.666735) (xy 112.332316 -261.660697) (xy 112.281545 -261.646745)
			(xy 112.2335 -261.625206) (xy 112.189305 -261.596586) (xy 112.149997 -261.561555) (xy 112.116497 -261.520934)
			(xy 112.089591 -261.475675) (xy 112.069908 -261.42684) (xy 112.057911 -261.375572) (xy 112.053881 -261.323074)
			(xy 111.791242 -261.323074) (xy 111.790738 -261.3494) (xy 111.782701 -261.401436) (xy 111.766815 -261.451635)
			(xy 111.743452 -261.49882) (xy 111.71316 -261.541886) (xy 111.676648 -261.579824) (xy 111.634774 -261.611743)
			(xy 111.588518 -261.636896) (xy 111.538965 -261.654694) (xy 111.487275 -261.664718) (xy 111.434661 -261.666735)
			(xy 111.382356 -261.660697) (xy 111.331585 -261.646745) (xy 111.28354 -261.625206) (xy 111.239345 -261.596586)
			(xy 111.200037 -261.561555) (xy 111.166537 -261.520934) (xy 111.139631 -261.475675) (xy 111.119948 -261.42684)
			(xy 111.107951 -261.375572) (xy 111.103921 -261.323074) (xy 110.841282 -261.323074) (xy 110.840778 -261.3494)
			(xy 110.832741 -261.401436) (xy 110.816855 -261.451635) (xy 110.793492 -261.49882) (xy 110.7632 -261.541886)
			(xy 110.726688 -261.579824) (xy 110.684814 -261.611743) (xy 110.638558 -261.636896) (xy 110.589005 -261.654694)
			(xy 110.537315 -261.664718) (xy 110.484701 -261.666735) (xy 110.432396 -261.660697) (xy 110.381625 -261.646745)
			(xy 110.33358 -261.625206) (xy 110.289385 -261.596586) (xy 110.250077 -261.561555) (xy 110.216577 -261.520934)
			(xy 110.189671 -261.475675) (xy 110.169988 -261.42684) (xy 110.157991 -261.375572) (xy 110.153961 -261.323074)
			(xy 109.891322 -261.323074) (xy 109.890818 -261.3494) (xy 109.882781 -261.401436) (xy 109.866895 -261.451635)
			(xy 109.843532 -261.49882) (xy 109.81324 -261.541886) (xy 109.776728 -261.579824) (xy 109.734854 -261.611743)
			(xy 109.688598 -261.636896) (xy 109.639045 -261.654694) (xy 109.587355 -261.664718) (xy 109.534741 -261.666735)
			(xy 109.482436 -261.660697) (xy 109.431665 -261.646745) (xy 109.38362 -261.625206) (xy 109.339425 -261.596586)
			(xy 109.300117 -261.561555) (xy 109.266617 -261.520934) (xy 109.239711 -261.475675) (xy 109.220028 -261.42684)
			(xy 109.208031 -261.375572) (xy 109.204001 -261.323074) (xy 108.941362 -261.323074) (xy 108.940858 -261.3494)
			(xy 108.932821 -261.401436) (xy 108.916935 -261.451635) (xy 108.893572 -261.49882) (xy 108.86328 -261.541886)
			(xy 108.826768 -261.579824) (xy 108.784894 -261.611743) (xy 108.738638 -261.636896) (xy 108.689085 -261.654694)
			(xy 108.637395 -261.664718) (xy 108.584781 -261.666735) (xy 108.532476 -261.660697) (xy 108.481705 -261.646745)
			(xy 108.43366 -261.625206) (xy 108.389465 -261.596586) (xy 108.350157 -261.561555) (xy 108.316657 -261.520934)
			(xy 108.289751 -261.475675) (xy 108.270068 -261.42684) (xy 108.258071 -261.375572) (xy 108.254041 -261.323074)
			(xy 107.991402 -261.323074) (xy 107.990898 -261.3494) (xy 107.982861 -261.401436) (xy 107.966975 -261.451635)
			(xy 107.943612 -261.49882) (xy 107.91332 -261.541886) (xy 107.876808 -261.579824) (xy 107.834934 -261.611743)
			(xy 107.788678 -261.636896) (xy 107.739125 -261.654694) (xy 107.687435 -261.664718) (xy 107.634821 -261.666735)
			(xy 107.582516 -261.660697) (xy 107.531745 -261.646745) (xy 107.4837 -261.625206) (xy 107.439505 -261.596586)
			(xy 107.400197 -261.561555) (xy 107.366697 -261.520934) (xy 107.339791 -261.475675) (xy 107.320108 -261.42684)
			(xy 107.308111 -261.375572) (xy 107.304081 -261.323074) (xy 106.735498 -261.323074) (xy 106.724153 -261.358925)
			(xy 106.70079 -261.40611) (xy 106.670498 -261.449176) (xy 106.633986 -261.487114) (xy 106.592112 -261.519033)
			(xy 106.545856 -261.544186) (xy 106.496303 -261.561984) (xy 106.444613 -261.572008) (xy 106.391999 -261.574025)
			(xy 106.339694 -261.567987) (xy 106.288923 -261.554035) (xy 106.240878 -261.532496) (xy 106.196683 -261.503876)
			(xy 106.157375 -261.468845) (xy 106.123875 -261.428224) (xy 106.096969 -261.382965) (xy 106.077286 -261.33413)
			(xy 106.065289 -261.282862) (xy 106.061259 -261.230364) (xy 105.83418 -261.230364) (xy 105.833676 -261.25669)
			(xy 105.825639 -261.308726) (xy 105.809753 -261.358925) (xy 105.78639 -261.40611) (xy 105.756098 -261.449176)
			(xy 105.719586 -261.487114) (xy 105.677712 -261.519033) (xy 105.631456 -261.544186) (xy 105.581903 -261.561984)
			(xy 105.530213 -261.572008) (xy 105.477599 -261.574025) (xy 105.425294 -261.567987) (xy 105.374523 -261.554035)
			(xy 105.326478 -261.532496) (xy 105.282283 -261.503876) (xy 105.242975 -261.468845) (xy 105.209475 -261.428224)
			(xy 105.182569 -261.382965) (xy 105.162886 -261.33413) (xy 105.150889 -261.282862) (xy 105.146859 -261.230364)
			(xy 104.375192 -261.230364) (xy 104.369264 -261.248121) (xy 104.346393 -261.291698) (xy 104.316828 -261.331042)
			(xy 104.281335 -261.365134) (xy 104.240832 -261.39309) (xy 104.19637 -261.414188) (xy 104.149099 -261.42788)
			(xy 104.100244 -261.433812) (xy 104.051069 -261.431831) (xy 104.00285 -261.421987) (xy 103.956834 -261.404535)
			(xy 103.914213 -261.379928) (xy 103.876092 -261.348803) (xy 103.843457 -261.311966) (xy 103.817154 -261.27037)
			(xy 103.797863 -261.225094) (xy 103.786086 -261.17731) (xy 103.782126 -261.128256) (xy 103.453184 -261.128256)
			(xy 103.452689 -261.152863) (xy 103.444794 -261.20144) (xy 103.42921 -261.248121) (xy 103.406339 -261.291698)
			(xy 103.376774 -261.331042) (xy 103.341281 -261.365134) (xy 103.300778 -261.39309) (xy 103.256316 -261.414188)
			(xy 103.209045 -261.42788) (xy 103.16019 -261.433812) (xy 103.111015 -261.431831) (xy 103.062796 -261.421987)
			(xy 103.01678 -261.404535) (xy 102.974159 -261.379928) (xy 102.936038 -261.348803) (xy 102.903403 -261.311966)
			(xy 102.8771 -261.27037) (xy 102.857809 -261.225094) (xy 102.846032 -261.17731) (xy 102.842072 -261.128256)
			(xy 102.516391 -261.128256) (xy 102.515937 -261.150831) (xy 102.508042 -261.199408) (xy 102.492458 -261.246089)
			(xy 102.469587 -261.289666) (xy 102.440022 -261.32901) (xy 102.404529 -261.363102) (xy 102.364026 -261.391058)
			(xy 102.319564 -261.412156) (xy 102.272293 -261.425848) (xy 102.223438 -261.43178) (xy 102.174263 -261.429799)
			(xy 102.126044 -261.419955) (xy 102.080028 -261.402503) (xy 102.037407 -261.377896) (xy 101.999286 -261.346771)
			(xy 101.966651 -261.309934) (xy 101.940348 -261.268338) (xy 101.921057 -261.223062) (xy 101.90928 -261.175278)
			(xy 101.90532 -261.126224) (xy 101.576378 -261.126224) (xy 101.57593 -261.150215) (xy 101.56842 -261.197606)
			(xy 101.553589 -261.243238) (xy 101.531802 -261.285989) (xy 101.503595 -261.324805) (xy 101.469664 -261.358731)
			(xy 101.430843 -261.38693) (xy 101.388088 -261.40871) (xy 101.342453 -261.423533) (xy 101.295061 -261.431034)
			(xy 101.27107 -261.431532) (xy 101.251548 -261.431224) (xy 101.21282 -261.42626) (xy 101.193854 -261.421626)
			(xy 101.182411 -261.419208) (xy 101.159512 -261.423836) (xy 101.149912 -261.430516) (xy 101.086412 -261.479792)
			(xy 101.077554 -261.487379) (xy 101.067255 -261.508278) (xy 101.0666 -261.519924) (xy 101.0666 -261.77875)
			(xy 101.069394 -261.79018) (xy 101.072188 -261.795768) (xy 101.082967 -261.817599) (xy 101.098236 -261.863827)
			(xy 101.105998 -261.911888) (xy 101.106478 -261.93623) (xy 101.435166 -261.93623) (xy 101.439126 -261.887176)
			(xy 101.450903 -261.839392) (xy 101.470194 -261.794116) (xy 101.496497 -261.75252) (xy 101.529132 -261.715683)
			(xy 101.567253 -261.684558) (xy 101.609874 -261.659951) (xy 101.65589 -261.642499) (xy 101.704109 -261.632655)
			(xy 101.753284 -261.630674) (xy 101.802139 -261.636606) (xy 101.84941 -261.650298) (xy 101.893872 -261.671396)
			(xy 101.934375 -261.699352) (xy 101.969868 -261.733444) (xy 101.999433 -261.772788) (xy 102.022304 -261.816365)
			(xy 102.037888 -261.863046) (xy 102.045783 -261.911623) (xy 102.046278 -261.93623) (xy 102.37522 -261.93623)
			(xy 102.37918 -261.887176) (xy 102.390957 -261.839392) (xy 102.410248 -261.794116) (xy 102.436551 -261.75252)
			(xy 102.469186 -261.715683) (xy 102.507307 -261.684558) (xy 102.549928 -261.659951) (xy 102.595944 -261.642499)
			(xy 102.644163 -261.632655) (xy 102.693338 -261.630674) (xy 102.742193 -261.636606) (xy 102.789464 -261.650298)
			(xy 102.833926 -261.671396) (xy 102.874429 -261.699352) (xy 102.909922 -261.733444) (xy 102.939487 -261.772788)
			(xy 102.962358 -261.816365) (xy 102.977942 -261.863046) (xy 102.985837 -261.911623) (xy 102.986332 -261.93623)
			(xy 102.985837 -261.960837) (xy 102.977942 -262.009414) (xy 102.962358 -262.056095) (xy 102.939487 -262.099672)
			(xy 102.909922 -262.139016) (xy 102.874429 -262.173108) (xy 102.863974 -262.180324) (xy 105.146859 -262.180324)
			(xy 105.150889 -262.127826) (xy 105.162886 -262.076558) (xy 105.182569 -262.027723) (xy 105.209475 -261.982464)
			(xy 105.242975 -261.941843) (xy 105.282283 -261.906812) (xy 105.326478 -261.878192) (xy 105.374523 -261.856653)
			(xy 105.425294 -261.842701) (xy 105.477599 -261.836663) (xy 105.530213 -261.83868) (xy 105.581903 -261.848704)
			(xy 105.631456 -261.866502) (xy 105.677712 -261.891655) (xy 105.719586 -261.923574) (xy 105.756098 -261.961512)
			(xy 105.78639 -262.004578) (xy 105.809753 -262.051763) (xy 105.825639 -262.101962) (xy 105.833676 -262.153998)
			(xy 105.83418 -262.180324) (xy 117.096797 -262.180324) (xy 117.100827 -262.127826) (xy 117.112824 -262.076558)
			(xy 117.132507 -262.027723) (xy 117.159413 -261.982464) (xy 117.192913 -261.941843) (xy 117.232221 -261.906812)
			(xy 117.276416 -261.878192) (xy 117.324461 -261.856653) (xy 117.375232 -261.842701) (xy 117.427537 -261.836663)
			(xy 117.480151 -261.83868) (xy 117.531841 -261.848704) (xy 117.581394 -261.866502) (xy 117.62765 -261.891655)
			(xy 117.669524 -261.923574) (xy 117.706036 -261.961512) (xy 117.736328 -262.004578) (xy 117.759691 -262.051763)
			(xy 117.775577 -262.101962) (xy 117.783614 -262.153998) (xy 117.784118 -262.180324) (xy 117.783614 -262.20665)
			(xy 117.775577 -262.258686) (xy 117.759691 -262.308885) (xy 117.736328 -262.35607) (xy 117.706036 -262.399136)
			(xy 117.669524 -262.437074) (xy 117.62765 -262.468993) (xy 117.581394 -262.494146) (xy 117.531841 -262.511944)
			(xy 117.480151 -262.521968) (xy 117.427537 -262.523985) (xy 117.375232 -262.517947) (xy 117.324461 -262.503995)
			(xy 117.276416 -262.482456) (xy 117.232221 -262.453836) (xy 117.192913 -262.418805) (xy 117.159413 -262.378184)
			(xy 117.132507 -262.332925) (xy 117.112824 -262.28409) (xy 117.100827 -262.232822) (xy 117.096797 -262.180324)
			(xy 105.83418 -262.180324) (xy 105.833676 -262.20665) (xy 105.825639 -262.258686) (xy 105.809753 -262.308885)
			(xy 105.78639 -262.35607) (xy 105.756098 -262.399136) (xy 105.719586 -262.437074) (xy 105.677712 -262.468993)
			(xy 105.631456 -262.494146) (xy 105.581903 -262.511944) (xy 105.530213 -262.521968) (xy 105.477599 -262.523985)
			(xy 105.425294 -262.517947) (xy 105.374523 -262.503995) (xy 105.326478 -262.482456) (xy 105.282283 -262.453836)
			(xy 105.242975 -262.418805) (xy 105.209475 -262.378184) (xy 105.182569 -262.332925) (xy 105.162886 -262.28409)
			(xy 105.150889 -262.232822) (xy 105.146859 -262.180324) (xy 102.863974 -262.180324) (xy 102.833926 -262.201064)
			(xy 102.789464 -262.222162) (xy 102.742193 -262.235854) (xy 102.693338 -262.241786) (xy 102.644163 -262.239805)
			(xy 102.595944 -262.229961) (xy 102.549928 -262.212509) (xy 102.507307 -262.187902) (xy 102.469186 -262.156777)
			(xy 102.436551 -262.11994) (xy 102.410248 -262.078344) (xy 102.390957 -262.033068) (xy 102.37918 -261.985284)
			(xy 102.37522 -261.93623) (xy 102.046278 -261.93623) (xy 102.045783 -261.960837) (xy 102.037888 -262.009414)
			(xy 102.022304 -262.056095) (xy 101.999433 -262.099672) (xy 101.969868 -262.139016) (xy 101.934375 -262.173108)
			(xy 101.893872 -262.201064) (xy 101.84941 -262.222162) (xy 101.802139 -262.235854) (xy 101.753284 -262.241786)
			(xy 101.704109 -262.239805) (xy 101.65589 -262.229961) (xy 101.609874 -262.212509) (xy 101.567253 -262.187902)
			(xy 101.529132 -262.156777) (xy 101.496497 -262.11994) (xy 101.470194 -262.078344) (xy 101.450903 -262.033068)
			(xy 101.439126 -261.985284) (xy 101.435166 -261.93623) (xy 101.106478 -261.93623) (xy 101.106005 -261.960573)
			(xy 101.098266 -262.008641) (xy 101.082974 -262.054863) (xy 101.072188 -262.076692) (xy 101.069394 -262.08228)
			(xy 101.0666 -262.09371) (xy 101.0666 -262.352536) (xy 101.067182 -262.364196) (xy 101.077524 -262.385095)
			(xy 101.086412 -262.392668) (xy 101.149912 -262.441944) (xy 101.159527 -262.448589) (xy 101.182412 -262.453217)
			(xy 101.193854 -262.450834) (xy 101.212818 -262.446184) (xy 101.251547 -262.44122) (xy 101.27107 -262.440928)
			(xy 101.273864 -262.440928) (xy 101.297712 -262.441604) (xy 101.344769 -262.449451) (xy 101.390032 -262.464522)
			(xy 101.4324 -262.486451) (xy 101.470841 -262.514703) (xy 101.504419 -262.548591) (xy 101.532317 -262.58729)
			(xy 101.553857 -262.629857) (xy 101.568512 -262.675256) (xy 101.575927 -262.722383) (xy 101.576378 -262.746236)
			(xy 101.90532 -262.746236) (xy 101.90928 -262.697182) (xy 101.921057 -262.649398) (xy 101.940348 -262.604122)
			(xy 101.966651 -262.562526) (xy 101.999286 -262.525689) (xy 102.037407 -262.494564) (xy 102.080028 -262.469957)
			(xy 102.126044 -262.452505) (xy 102.174263 -262.442661) (xy 102.223438 -262.44068) (xy 102.272293 -262.446612)
			(xy 102.319564 -262.460304) (xy 102.364026 -262.481402) (xy 102.404529 -262.509358) (xy 102.440022 -262.54345)
			(xy 102.469587 -262.582794) (xy 102.492458 -262.626371) (xy 102.508042 -262.673052) (xy 102.515937 -262.721629)
			(xy 102.516432 -262.746236) (xy 102.516391 -262.748268) (xy 102.842072 -262.748268) (xy 102.846032 -262.699214)
			(xy 102.857809 -262.65143) (xy 102.8771 -262.606154) (xy 102.903403 -262.564558) (xy 102.936038 -262.527721)
			(xy 102.974159 -262.496596) (xy 103.01678 -262.471989) (xy 103.062796 -262.454537) (xy 103.111015 -262.444693)
			(xy 103.16019 -262.442712) (xy 103.209045 -262.448644) (xy 103.256316 -262.462336) (xy 103.300778 -262.483434)
			(xy 103.341281 -262.51139) (xy 103.376774 -262.545482) (xy 103.406339 -262.584826) (xy 103.42921 -262.628403)
			(xy 103.444794 -262.675084) (xy 103.452689 -262.723661) (xy 103.453184 -262.748268) (xy 103.782126 -262.748268)
			(xy 103.786086 -262.699214) (xy 103.797863 -262.65143) (xy 103.817154 -262.606154) (xy 103.843457 -262.564558)
			(xy 103.876092 -262.527721) (xy 103.914213 -262.496596) (xy 103.956834 -262.471989) (xy 104.00285 -262.454537)
			(xy 104.051069 -262.444693) (xy 104.100244 -262.442712) (xy 104.149099 -262.448644) (xy 104.19637 -262.462336)
			(xy 104.240832 -262.483434) (xy 104.281335 -262.51139) (xy 104.316828 -262.545482) (xy 104.346393 -262.584826)
			(xy 104.369264 -262.628403) (xy 104.384848 -262.675084) (xy 104.392743 -262.723661) (xy 104.393238 -262.748268)
			(xy 104.392743 -262.772875) (xy 104.384848 -262.821452) (xy 104.369264 -262.868133) (xy 104.346393 -262.91171)
			(xy 104.316828 -262.951054) (xy 104.281335 -262.985146) (xy 104.240832 -263.013102) (xy 104.19637 -263.0342)
			(xy 104.149099 -263.047892) (xy 104.100244 -263.053824) (xy 104.051069 -263.051843) (xy 104.00285 -263.041999)
			(xy 103.956834 -263.024547) (xy 103.914213 -262.99994) (xy 103.876092 -262.968815) (xy 103.843457 -262.931978)
			(xy 103.817154 -262.890382) (xy 103.797863 -262.845106) (xy 103.786086 -262.797322) (xy 103.782126 -262.748268)
			(xy 103.453184 -262.748268) (xy 103.452689 -262.772875) (xy 103.444794 -262.821452) (xy 103.42921 -262.868133)
			(xy 103.406339 -262.91171) (xy 103.376774 -262.951054) (xy 103.341281 -262.985146) (xy 103.300778 -263.013102)
			(xy 103.256316 -263.0342) (xy 103.209045 -263.047892) (xy 103.16019 -263.053824) (xy 103.111015 -263.051843)
			(xy 103.062796 -263.041999) (xy 103.01678 -263.024547) (xy 102.974159 -262.99994) (xy 102.936038 -262.968815)
			(xy 102.903403 -262.931978) (xy 102.8771 -262.890382) (xy 102.857809 -262.845106) (xy 102.846032 -262.797322)
			(xy 102.842072 -262.748268) (xy 102.516391 -262.748268) (xy 102.515937 -262.770843) (xy 102.508042 -262.81942)
			(xy 102.492458 -262.866101) (xy 102.469587 -262.909678) (xy 102.440022 -262.949022) (xy 102.404529 -262.983114)
			(xy 102.364026 -263.01107) (xy 102.319564 -263.032168) (xy 102.272293 -263.04586) (xy 102.223438 -263.051792)
			(xy 102.174263 -263.049811) (xy 102.126044 -263.039967) (xy 102.080028 -263.022515) (xy 102.037407 -262.997908)
			(xy 101.999286 -262.966783) (xy 101.966651 -262.929946) (xy 101.940348 -262.88835) (xy 101.921057 -262.843074)
			(xy 101.90928 -262.79529) (xy 101.90532 -262.746236) (xy 101.576378 -262.746236) (xy 101.575905 -262.770225)
			(xy 101.568394 -262.81761) (xy 101.553563 -262.863237) (xy 101.531777 -262.905983) (xy 101.503572 -262.944794)
			(xy 101.469644 -262.978715) (xy 101.430827 -263.006912) (xy 101.388076 -263.028688) (xy 101.342446 -263.043509)
			(xy 101.295059 -263.05101) (xy 101.27107 -263.051544) (xy 101.251548 -263.051236) (xy 101.21282 -263.046273)
			(xy 101.193854 -263.041638) (xy 101.182411 -263.039219) (xy 101.159512 -263.043848) (xy 101.149912 -263.050528)
			(xy 101.086412 -263.099804) (xy 101.077556 -263.107392) (xy 101.067262 -263.128291) (xy 101.0666 -263.139936)
			(xy 101.0666 -263.398762) (xy 101.069394 -263.410192) (xy 101.072188 -263.41578) (xy 101.082966 -263.437611)
			(xy 101.098234 -263.483839) (xy 101.105993 -263.531901) (xy 101.106478 -263.556242) (xy 101.435166 -263.556242)
			(xy 101.439126 -263.507188) (xy 101.450903 -263.459404) (xy 101.470194 -263.414128) (xy 101.496497 -263.372532)
			(xy 101.529132 -263.335695) (xy 101.567253 -263.30457) (xy 101.609874 -263.279963) (xy 101.65589 -263.262511)
			(xy 101.704109 -263.252667) (xy 101.753284 -263.250686) (xy 101.802139 -263.256618) (xy 101.84941 -263.27031)
			(xy 101.893872 -263.291408) (xy 101.934375 -263.319364) (xy 101.969868 -263.353456) (xy 101.999433 -263.3928)
			(xy 102.022304 -263.436377) (xy 102.037888 -263.483058) (xy 102.045783 -263.531635) (xy 102.046278 -263.556242)
			(xy 102.37522 -263.556242) (xy 102.37918 -263.507188) (xy 102.390957 -263.459404) (xy 102.410248 -263.414128)
			(xy 102.436551 -263.372532) (xy 102.469186 -263.335695) (xy 102.507307 -263.30457) (xy 102.549928 -263.279963)
			(xy 102.595944 -263.262511) (xy 102.644163 -263.252667) (xy 102.693338 -263.250686) (xy 102.742193 -263.256618)
			(xy 102.789464 -263.27031) (xy 102.833926 -263.291408) (xy 102.874429 -263.319364) (xy 102.909922 -263.353456)
			(xy 102.939487 -263.3928) (xy 102.962358 -263.436377) (xy 102.977942 -263.483058) (xy 102.985837 -263.531635)
			(xy 102.986332 -263.556242) (xy 102.985837 -263.580849) (xy 102.977942 -263.629426) (xy 102.962358 -263.676107)
			(xy 102.939487 -263.719684) (xy 102.909922 -263.759028) (xy 102.874429 -263.79312) (xy 102.833926 -263.821076)
			(xy 102.789464 -263.842174) (xy 102.774308 -263.846564) (xy 111.234223 -263.846564) (xy 111.238253 -263.794066)
			(xy 111.25025 -263.742798) (xy 111.269933 -263.693963) (xy 111.296839 -263.648704) (xy 111.330339 -263.608083)
			(xy 111.369647 -263.573052) (xy 111.413842 -263.544432) (xy 111.461887 -263.522893) (xy 111.512658 -263.508941)
			(xy 111.564963 -263.502903) (xy 111.617577 -263.50492) (xy 111.669267 -263.514944) (xy 111.71882 -263.532742)
			(xy 111.765076 -263.557895) (xy 111.80695 -263.589814) (xy 111.843462 -263.627752) (xy 111.873754 -263.670818)
			(xy 111.897117 -263.718003) (xy 111.913003 -263.768202) (xy 111.92104 -263.820238) (xy 111.921544 -263.846564)
			(xy 111.92104 -263.87289) (xy 111.913003 -263.924926) (xy 111.897117 -263.975125) (xy 111.873754 -264.02231)
			(xy 111.843462 -264.065376) (xy 111.80695 -264.103314) (xy 111.765076 -264.135233) (xy 111.71882 -264.160386)
			(xy 111.669267 -264.178184) (xy 111.617577 -264.188208) (xy 111.564963 -264.190225) (xy 111.512658 -264.184187)
			(xy 111.461887 -264.170235) (xy 111.413842 -264.148696) (xy 111.369647 -264.120076) (xy 111.330339 -264.085045)
			(xy 111.296839 -264.044424) (xy 111.269933 -263.999165) (xy 111.25025 -263.95033) (xy 111.238253 -263.899062)
			(xy 111.234223 -263.846564) (xy 102.774308 -263.846564) (xy 102.742193 -263.855866) (xy 102.693338 -263.861798)
			(xy 102.644163 -263.859817) (xy 102.595944 -263.849973) (xy 102.549928 -263.832521) (xy 102.507307 -263.807914)
			(xy 102.469186 -263.776789) (xy 102.436551 -263.739952) (xy 102.410248 -263.698356) (xy 102.390957 -263.65308)
			(xy 102.37918 -263.605296) (xy 102.37522 -263.556242) (xy 102.046278 -263.556242) (xy 102.045783 -263.580849)
			(xy 102.037888 -263.629426) (xy 102.022304 -263.676107) (xy 101.999433 -263.719684) (xy 101.969868 -263.759028)
			(xy 101.934375 -263.79312) (xy 101.893872 -263.821076) (xy 101.84941 -263.842174) (xy 101.802139 -263.855866)
			(xy 101.753284 -263.861798) (xy 101.704109 -263.859817) (xy 101.65589 -263.849973) (xy 101.609874 -263.832521)
			(xy 101.567253 -263.807914) (xy 101.529132 -263.776789) (xy 101.496497 -263.739952) (xy 101.470194 -263.698356)
			(xy 101.450903 -263.65308) (xy 101.439126 -263.605296) (xy 101.435166 -263.556242) (xy 101.106478 -263.556242)
			(xy 101.106012 -263.580587) (xy 101.098286 -263.62866) (xy 101.083005 -263.67489) (xy 101.072188 -263.696704)
			(xy 101.069394 -263.702292) (xy 101.0666 -263.713722) (xy 101.0666 -264.366248) (xy 101.90532 -264.366248)
			(xy 101.90928 -264.317194) (xy 101.921057 -264.26941) (xy 101.940348 -264.224134) (xy 101.966651 -264.182538)
			(xy 101.999286 -264.145701) (xy 102.037407 -264.114576) (xy 102.080028 -264.089969) (xy 102.126044 -264.072517)
			(xy 102.174263 -264.062673) (xy 102.223438 -264.060692) (xy 102.272293 -264.066624) (xy 102.319564 -264.080316)
			(xy 102.364026 -264.101414) (xy 102.404529 -264.12937) (xy 102.440022 -264.163462) (xy 102.469587 -264.202806)
			(xy 102.492458 -264.246383) (xy 102.508042 -264.293064) (xy 102.515937 -264.341641) (xy 102.516432 -264.366248)
			(xy 102.516391 -264.36828) (xy 103.782126 -264.36828) (xy 103.786086 -264.319226) (xy 103.797863 -264.271442)
			(xy 103.817154 -264.226166) (xy 103.843457 -264.18457) (xy 103.876092 -264.147733) (xy 103.914213 -264.116608)
			(xy 103.956834 -264.092001) (xy 104.00285 -264.074549) (xy 104.051069 -264.064705) (xy 104.100244 -264.062724)
			(xy 104.149099 -264.068656) (xy 104.19637 -264.082348) (xy 104.240832 -264.103446) (xy 104.281335 -264.131402)
			(xy 104.316828 -264.165494) (xy 104.346393 -264.204838) (xy 104.369264 -264.248415) (xy 104.384848 -264.295096)
			(xy 104.392743 -264.343673) (xy 104.393238 -264.36828) (xy 105.662234 -264.36828) (xy 105.666194 -264.319226)
			(xy 105.677971 -264.271442) (xy 105.697262 -264.226166) (xy 105.723565 -264.18457) (xy 105.7562 -264.147733)
			(xy 105.794321 -264.116608) (xy 105.836942 -264.092001) (xy 105.882958 -264.074549) (xy 105.931177 -264.064705)
			(xy 105.980352 -264.062724) (xy 106.029207 -264.068656) (xy 106.076478 -264.082348) (xy 106.12094 -264.103446)
			(xy 106.161443 -264.131402) (xy 106.196936 -264.165494) (xy 106.226501 -264.204838) (xy 106.249372 -264.248415)
			(xy 106.264956 -264.295096) (xy 106.272851 -264.343673) (xy 106.273346 -264.36828) (xy 107.542088 -264.36828)
			(xy 107.546048 -264.319226) (xy 107.557825 -264.271442) (xy 107.577116 -264.226166) (xy 107.603419 -264.18457)
			(xy 107.636054 -264.147733) (xy 107.674175 -264.116608) (xy 107.716796 -264.092001) (xy 107.762812 -264.074549)
			(xy 107.811031 -264.064705) (xy 107.860206 -264.062724) (xy 107.909061 -264.068656) (xy 107.956332 -264.082348)
			(xy 108.000794 -264.103446) (xy 108.041297 -264.131402) (xy 108.07679 -264.165494) (xy 108.106355 -264.204838)
			(xy 108.129226 -264.248415) (xy 108.14481 -264.295096) (xy 108.152705 -264.343673) (xy 108.1532 -264.36828)
			(xy 115.062012 -264.36828) (xy 115.065972 -264.319226) (xy 115.077749 -264.271442) (xy 115.09704 -264.226166)
			(xy 115.123343 -264.18457) (xy 115.155978 -264.147733) (xy 115.194099 -264.116608) (xy 115.23672 -264.092001)
			(xy 115.282736 -264.074549) (xy 115.330955 -264.064705) (xy 115.38013 -264.062724) (xy 115.428985 -264.068656)
			(xy 115.476256 -264.082348) (xy 115.520718 -264.103446) (xy 115.561221 -264.131402) (xy 115.596714 -264.165494)
			(xy 115.626279 -264.204838) (xy 115.64915 -264.248415) (xy 115.664734 -264.295096) (xy 115.672629 -264.343673)
			(xy 115.673124 -264.36828) (xy 116.94212 -264.36828) (xy 116.94608 -264.319226) (xy 116.957857 -264.271442)
			(xy 116.977148 -264.226166) (xy 117.003451 -264.18457) (xy 117.036086 -264.147733) (xy 117.074207 -264.116608)
			(xy 117.116828 -264.092001) (xy 117.162844 -264.074549) (xy 117.211063 -264.064705) (xy 117.260238 -264.062724)
			(xy 117.309093 -264.068656) (xy 117.356364 -264.082348) (xy 117.400826 -264.103446) (xy 117.441329 -264.131402)
			(xy 117.476822 -264.165494) (xy 117.506387 -264.204838) (xy 117.529258 -264.248415) (xy 117.544842 -264.295096)
			(xy 117.552737 -264.343673) (xy 117.553232 -264.36828) (xy 118.821974 -264.36828) (xy 118.825934 -264.319226)
			(xy 118.837711 -264.271442) (xy 118.857002 -264.226166) (xy 118.883305 -264.18457) (xy 118.91594 -264.147733)
			(xy 118.954061 -264.116608) (xy 118.996682 -264.092001) (xy 119.042698 -264.074549) (xy 119.090917 -264.064705)
			(xy 119.140092 -264.062724) (xy 119.188947 -264.068656) (xy 119.236218 -264.082348) (xy 119.28068 -264.103446)
			(xy 119.321183 -264.131402) (xy 119.356676 -264.165494) (xy 119.386241 -264.204838) (xy 119.409112 -264.248415)
			(xy 119.424696 -264.295096) (xy 119.432591 -264.343673) (xy 119.433086 -264.36828) (xy 120.699796 -264.36828)
			(xy 120.703756 -264.319226) (xy 120.715533 -264.271442) (xy 120.734824 -264.226166) (xy 120.761127 -264.18457)
			(xy 120.793762 -264.147733) (xy 120.831883 -264.116608) (xy 120.874504 -264.092001) (xy 120.92052 -264.074549)
			(xy 120.968739 -264.064705) (xy 121.017914 -264.062724) (xy 121.066769 -264.068656) (xy 121.11404 -264.082348)
			(xy 121.158502 -264.103446) (xy 121.199005 -264.131402) (xy 121.234498 -264.165494) (xy 121.264063 -264.204838)
			(xy 121.286934 -264.248415) (xy 121.302518 -264.295096) (xy 121.310413 -264.343673) (xy 121.310867 -264.366248)
			(xy 122.578888 -264.366248) (xy 122.582848 -264.317194) (xy 122.594625 -264.26941) (xy 122.613916 -264.224134)
			(xy 122.640219 -264.182538) (xy 122.672854 -264.145701) (xy 122.710975 -264.114576) (xy 122.753596 -264.089969)
			(xy 122.799612 -264.072517) (xy 122.847831 -264.062673) (xy 122.897006 -264.060692) (xy 122.945861 -264.066624)
			(xy 122.993132 -264.080316) (xy 123.037594 -264.101414) (xy 123.078097 -264.12937) (xy 123.11359 -264.163462)
			(xy 123.143155 -264.202806) (xy 123.166026 -264.246383) (xy 123.18161 -264.293064) (xy 123.189505 -264.341641)
			(xy 123.19 -264.366248) (xy 124.458996 -264.366248) (xy 124.462956 -264.317194) (xy 124.474733 -264.26941)
			(xy 124.494024 -264.224134) (xy 124.520327 -264.182538) (xy 124.552962 -264.145701) (xy 124.591083 -264.114576)
			(xy 124.633704 -264.089969) (xy 124.67972 -264.072517) (xy 124.727939 -264.062673) (xy 124.777114 -264.060692)
			(xy 124.825969 -264.066624) (xy 124.87324 -264.080316) (xy 124.917702 -264.101414) (xy 124.958205 -264.12937)
			(xy 124.993698 -264.163462) (xy 125.023263 -264.202806) (xy 125.046134 -264.246383) (xy 125.061718 -264.293064)
			(xy 125.069613 -264.341641) (xy 125.070108 -264.366248) (xy 126.33885 -264.366248) (xy 126.34281 -264.317194)
			(xy 126.354587 -264.26941) (xy 126.373878 -264.224134) (xy 126.400181 -264.182538) (xy 126.432816 -264.145701)
			(xy 126.470937 -264.114576) (xy 126.513558 -264.089969) (xy 126.559574 -264.072517) (xy 126.607793 -264.062673)
			(xy 126.656968 -264.060692) (xy 126.705823 -264.066624) (xy 126.753094 -264.080316) (xy 126.797556 -264.101414)
			(xy 126.838059 -264.12937) (xy 126.873552 -264.163462) (xy 126.903117 -264.202806) (xy 126.925988 -264.246383)
			(xy 126.941572 -264.293064) (xy 126.949467 -264.341641) (xy 126.949962 -264.366248) (xy 128.208527 -264.366248)
			(xy 128.212622 -264.31552) (xy 128.224801 -264.266106) (xy 128.244749 -264.219286) (xy 128.27195 -264.176272)
			(xy 128.305698 -264.138178) (xy 128.34512 -264.105991) (xy 128.389194 -264.080545) (xy 128.43678 -264.062498)
			(xy 128.486644 -264.052318) (xy 128.537496 -264.050269) (xy 128.588017 -264.056403) (xy 128.636901 -264.070563)
			(xy 128.68288 -264.09238) (xy 128.724764 -264.12129) (xy 128.761468 -264.156545) (xy 128.792041 -264.197231)
			(xy 128.815692 -264.242294) (xy 128.831808 -264.290568) (xy 128.839972 -264.340802) (xy 128.840484 -264.366248)
			(xy 129.148581 -264.366248) (xy 129.152676 -264.31552) (xy 129.164855 -264.266106) (xy 129.184803 -264.219286)
			(xy 129.212004 -264.176272) (xy 129.245752 -264.138178) (xy 129.285174 -264.105991) (xy 129.329248 -264.080545)
			(xy 129.376834 -264.062498) (xy 129.426698 -264.052318) (xy 129.47755 -264.050269) (xy 129.528071 -264.056403)
			(xy 129.576955 -264.070563) (xy 129.622934 -264.09238) (xy 129.664818 -264.12129) (xy 129.701522 -264.156545)
			(xy 129.732095 -264.197231) (xy 129.755746 -264.242294) (xy 129.771862 -264.290568) (xy 129.780026 -264.340802)
			(xy 129.780538 -264.366248) (xy 130.099066 -264.366248) (xy 130.103026 -264.317194) (xy 130.114803 -264.26941)
			(xy 130.134094 -264.224134) (xy 130.160397 -264.182538) (xy 130.193032 -264.145701) (xy 130.231153 -264.114576)
			(xy 130.273774 -264.089969) (xy 130.31979 -264.072517) (xy 130.368009 -264.062673) (xy 130.417184 -264.060692)
			(xy 130.466039 -264.066624) (xy 130.51331 -264.080316) (xy 130.557772 -264.101414) (xy 130.598275 -264.12937)
			(xy 130.633768 -264.163462) (xy 130.663333 -264.202806) (xy 130.686204 -264.246383) (xy 130.701788 -264.293064)
			(xy 130.709683 -264.341641) (xy 130.710178 -264.366248) (xy 131.028435 -264.366248) (xy 131.03253 -264.31552)
			(xy 131.044709 -264.266106) (xy 131.064657 -264.219286) (xy 131.091858 -264.176272) (xy 131.125606 -264.138178)
			(xy 131.165028 -264.105991) (xy 131.209102 -264.080545) (xy 131.256688 -264.062498) (xy 131.306552 -264.052318)
			(xy 131.357404 -264.050269) (xy 131.407925 -264.056403) (xy 131.456809 -264.070563) (xy 131.502788 -264.09238)
			(xy 131.544672 -264.12129) (xy 131.581376 -264.156545) (xy 131.611949 -264.197231) (xy 131.6356 -264.242294)
			(xy 131.651716 -264.290568) (xy 131.65988 -264.340802) (xy 131.660392 -264.366248) (xy 131.97892 -264.366248)
			(xy 131.98288 -264.317194) (xy 131.994657 -264.26941) (xy 132.013948 -264.224134) (xy 132.040251 -264.182538)
			(xy 132.072886 -264.145701) (xy 132.111007 -264.114576) (xy 132.153628 -264.089969) (xy 132.199644 -264.072517)
			(xy 132.247863 -264.062673) (xy 132.297038 -264.060692) (xy 132.345893 -264.066624) (xy 132.393164 -264.080316)
			(xy 132.437626 -264.101414) (xy 132.478129 -264.12937) (xy 132.513622 -264.163462) (xy 132.543187 -264.202806)
			(xy 132.566058 -264.246383) (xy 132.581642 -264.293064) (xy 132.589537 -264.341641) (xy 132.590032 -264.366248)
			(xy 132.908543 -264.366248) (xy 132.912638 -264.31552) (xy 132.924817 -264.266106) (xy 132.944765 -264.219286)
			(xy 132.971966 -264.176272) (xy 133.005714 -264.138178) (xy 133.045136 -264.105991) (xy 133.08921 -264.080545)
			(xy 133.136796 -264.062498) (xy 133.18666 -264.052318) (xy 133.237512 -264.050269) (xy 133.288033 -264.056403)
			(xy 133.336917 -264.070563) (xy 133.382896 -264.09238) (xy 133.42478 -264.12129) (xy 133.461484 -264.156545)
			(xy 133.492057 -264.197231) (xy 133.515708 -264.242294) (xy 133.531824 -264.290568) (xy 133.539988 -264.340802)
			(xy 133.5405 -264.366248) (xy 133.859028 -264.366248) (xy 133.862988 -264.317194) (xy 133.874765 -264.26941)
			(xy 133.894056 -264.224134) (xy 133.920359 -264.182538) (xy 133.952994 -264.145701) (xy 133.991115 -264.114576)
			(xy 134.033736 -264.089969) (xy 134.079752 -264.072517) (xy 134.127971 -264.062673) (xy 134.177146 -264.060692)
			(xy 134.226001 -264.066624) (xy 134.273272 -264.080316) (xy 134.317734 -264.101414) (xy 134.358237 -264.12937)
			(xy 134.39373 -264.163462) (xy 134.423295 -264.202806) (xy 134.446166 -264.246383) (xy 134.46175 -264.293064)
			(xy 134.469645 -264.341641) (xy 134.47014 -264.366248) (xy 134.788397 -264.366248) (xy 134.792492 -264.31552)
			(xy 134.804671 -264.266106) (xy 134.824619 -264.219286) (xy 134.85182 -264.176272) (xy 134.885568 -264.138178)
			(xy 134.92499 -264.105991) (xy 134.969064 -264.080545) (xy 135.01665 -264.062498) (xy 135.066514 -264.052318)
			(xy 135.117366 -264.050269) (xy 135.167887 -264.056403) (xy 135.216771 -264.070563) (xy 135.26275 -264.09238)
			(xy 135.304634 -264.12129) (xy 135.341338 -264.156545) (xy 135.371911 -264.197231) (xy 135.395562 -264.242294)
			(xy 135.411678 -264.290568) (xy 135.419842 -264.340802) (xy 135.420354 -264.366248) (xy 135.728451 -264.366248)
			(xy 135.732546 -264.31552) (xy 135.744725 -264.266106) (xy 135.764673 -264.219286) (xy 135.791874 -264.176272)
			(xy 135.825622 -264.138178) (xy 135.865044 -264.105991) (xy 135.909118 -264.080545) (xy 135.956704 -264.062498)
			(xy 136.006568 -264.052318) (xy 136.05742 -264.050269) (xy 136.107941 -264.056403) (xy 136.156825 -264.070563)
			(xy 136.202804 -264.09238) (xy 136.244688 -264.12129) (xy 136.281392 -264.156545) (xy 136.311965 -264.197231)
			(xy 136.335616 -264.242294) (xy 136.351732 -264.290568) (xy 136.359896 -264.340802) (xy 136.360408 -264.366248)
			(xy 136.678936 -264.366248) (xy 136.682896 -264.317194) (xy 136.694673 -264.26941) (xy 136.713964 -264.224134)
			(xy 136.740267 -264.182538) (xy 136.772902 -264.145701) (xy 136.811023 -264.114576) (xy 136.853644 -264.089969)
			(xy 136.89966 -264.072517) (xy 136.947879 -264.062673) (xy 136.997054 -264.060692) (xy 137.045909 -264.066624)
			(xy 137.09318 -264.080316) (xy 137.137642 -264.101414) (xy 137.178145 -264.12937) (xy 137.213638 -264.163462)
			(xy 137.243203 -264.202806) (xy 137.266074 -264.246383) (xy 137.281658 -264.293064) (xy 137.289553 -264.341641)
			(xy 137.290048 -264.366248) (xy 137.608559 -264.366248) (xy 137.612654 -264.31552) (xy 137.624833 -264.266106)
			(xy 137.644781 -264.219286) (xy 137.671982 -264.176272) (xy 137.70573 -264.138178) (xy 137.745152 -264.105991)
			(xy 137.789226 -264.080545) (xy 137.836812 -264.062498) (xy 137.886676 -264.052318) (xy 137.937528 -264.050269)
			(xy 137.988049 -264.056403) (xy 138.036933 -264.070563) (xy 138.082912 -264.09238) (xy 138.124796 -264.12129)
			(xy 138.1615 -264.156545) (xy 138.192073 -264.197231) (xy 138.215724 -264.242294) (xy 138.23184 -264.290568)
			(xy 138.240004 -264.340802) (xy 138.240516 -264.366248) (xy 138.559044 -264.366248) (xy 138.563004 -264.317194)
			(xy 138.574781 -264.26941) (xy 138.594072 -264.224134) (xy 138.620375 -264.182538) (xy 138.65301 -264.145701)
			(xy 138.691131 -264.114576) (xy 138.733752 -264.089969) (xy 138.779768 -264.072517) (xy 138.827987 -264.062673)
			(xy 138.877162 -264.060692) (xy 138.926017 -264.066624) (xy 138.973288 -264.080316) (xy 139.01775 -264.101414)
			(xy 139.058253 -264.12937) (xy 139.093746 -264.163462) (xy 139.123311 -264.202806) (xy 139.146182 -264.246383)
			(xy 139.161766 -264.293064) (xy 139.169661 -264.341641) (xy 139.170156 -264.366248) (xy 139.488413 -264.366248)
			(xy 139.492508 -264.31552) (xy 139.504687 -264.266106) (xy 139.524635 -264.219286) (xy 139.551836 -264.176272)
			(xy 139.585584 -264.138178) (xy 139.625006 -264.105991) (xy 139.66908 -264.080545) (xy 139.716666 -264.062498)
			(xy 139.76653 -264.052318) (xy 139.817382 -264.050269) (xy 139.867903 -264.056403) (xy 139.916787 -264.070563)
			(xy 139.962766 -264.09238) (xy 140.00465 -264.12129) (xy 140.041354 -264.156545) (xy 140.071927 -264.197231)
			(xy 140.095578 -264.242294) (xy 140.111694 -264.290568) (xy 140.119858 -264.340802) (xy 140.12037 -264.366248)
			(xy 140.438898 -264.366248) (xy 140.442858 -264.317194) (xy 140.454635 -264.26941) (xy 140.473926 -264.224134)
			(xy 140.500229 -264.182538) (xy 140.532864 -264.145701) (xy 140.570985 -264.114576) (xy 140.613606 -264.089969)
			(xy 140.659622 -264.072517) (xy 140.707841 -264.062673) (xy 140.757016 -264.060692) (xy 140.805871 -264.066624)
			(xy 140.853142 -264.080316) (xy 140.897604 -264.101414) (xy 140.938107 -264.12937) (xy 140.9736 -264.163462)
			(xy 141.003165 -264.202806) (xy 141.026036 -264.246383) (xy 141.04162 -264.293064) (xy 141.049515 -264.341641)
			(xy 141.05001 -264.366248) (xy 141.368521 -264.366248) (xy 141.372616 -264.31552) (xy 141.384795 -264.266106)
			(xy 141.404743 -264.219286) (xy 141.431944 -264.176272) (xy 141.465692 -264.138178) (xy 141.505114 -264.105991)
			(xy 141.549188 -264.080545) (xy 141.596774 -264.062498) (xy 141.646638 -264.052318) (xy 141.69749 -264.050269)
			(xy 141.748011 -264.056403) (xy 141.796895 -264.070563) (xy 141.842874 -264.09238) (xy 141.884758 -264.12129)
			(xy 141.921462 -264.156545) (xy 141.952035 -264.197231) (xy 141.975686 -264.242294) (xy 141.991802 -264.290568)
			(xy 141.999966 -264.340802) (xy 142.000478 -264.366248) (xy 142.308575 -264.366248) (xy 142.31267 -264.31552)
			(xy 142.324849 -264.266106) (xy 142.344797 -264.219286) (xy 142.371998 -264.176272) (xy 142.405746 -264.138178)
			(xy 142.445168 -264.105991) (xy 142.489242 -264.080545) (xy 142.536828 -264.062498) (xy 142.586692 -264.052318)
			(xy 142.637544 -264.050269) (xy 142.688065 -264.056403) (xy 142.736949 -264.070563) (xy 142.782928 -264.09238)
			(xy 142.824812 -264.12129) (xy 142.861516 -264.156545) (xy 142.892089 -264.197231) (xy 142.91574 -264.242294)
			(xy 142.931856 -264.290568) (xy 142.94002 -264.340802) (xy 142.940532 -264.366248) (xy 143.258806 -264.366248)
			(xy 143.262766 -264.317194) (xy 143.274543 -264.26941) (xy 143.293834 -264.224134) (xy 143.320137 -264.182538)
			(xy 143.352772 -264.145701) (xy 143.390893 -264.114576) (xy 143.433514 -264.089969) (xy 143.47953 -264.072517)
			(xy 143.527749 -264.062673) (xy 143.576924 -264.060692) (xy 143.625779 -264.066624) (xy 143.67305 -264.080316)
			(xy 143.717512 -264.101414) (xy 143.758015 -264.12937) (xy 143.793508 -264.163462) (xy 143.823073 -264.202806)
			(xy 143.845944 -264.246383) (xy 143.861528 -264.293064) (xy 143.869423 -264.341641) (xy 143.869918 -264.366248)
			(xy 145.138914 -264.366248) (xy 145.142874 -264.317194) (xy 145.154651 -264.26941) (xy 145.173942 -264.224134)
			(xy 145.200245 -264.182538) (xy 145.23288 -264.145701) (xy 145.271001 -264.114576) (xy 145.313622 -264.089969)
			(xy 145.359638 -264.072517) (xy 145.407857 -264.062673) (xy 145.457032 -264.060692) (xy 145.505887 -264.066624)
			(xy 145.553158 -264.080316) (xy 145.59762 -264.101414) (xy 145.638123 -264.12937) (xy 145.673616 -264.163462)
			(xy 145.703181 -264.202806) (xy 145.726052 -264.246383) (xy 145.741636 -264.293064) (xy 145.749531 -264.341641)
			(xy 145.750026 -264.366248) (xy 145.749531 -264.390855) (xy 145.741636 -264.439432) (xy 145.726299 -264.485374)
			(xy 164.058615 -264.485374) (xy 164.06255 -264.431603) (xy 164.074273 -264.378979) (xy 164.093533 -264.328622)
			(xy 164.119919 -264.281605) (xy 164.152871 -264.238932) (xy 164.191684 -264.201511) (xy 164.235532 -264.170141)
			(xy 164.28348 -264.145489) (xy 164.334507 -264.128081) (xy 164.387525 -264.118288) (xy 164.441404 -264.116319)
			(xy 164.494995 -264.122216) (xy 164.547156 -264.135852) (xy 164.596776 -264.156939) (xy 164.642797 -264.185025)
			(xy 164.684239 -264.219513) (xy 164.720217 -264.259667) (xy 164.749965 -264.304631) (xy 164.77285 -264.353448)
			(xy 164.788382 -264.405077) (xy 164.796232 -264.458417) (xy 164.796724 -264.485374) (xy 164.796232 -264.512331)
			(xy 164.788382 -264.565671) (xy 164.77285 -264.6173) (xy 164.749965 -264.666117) (xy 164.720217 -264.711081)
			(xy 164.684239 -264.751235) (xy 164.642797 -264.785723) (xy 164.596776 -264.813809) (xy 164.547156 -264.834896)
			(xy 164.494995 -264.848532) (xy 164.441404 -264.854429) (xy 164.387525 -264.85246) (xy 164.334507 -264.842667)
			(xy 164.28348 -264.825259) (xy 164.235532 -264.800607) (xy 164.191684 -264.769237) (xy 164.152871 -264.731816)
			(xy 164.119919 -264.689143) (xy 164.093533 -264.642126) (xy 164.074273 -264.591769) (xy 164.06255 -264.539145)
			(xy 164.058615 -264.485374) (xy 145.726299 -264.485374) (xy 145.726052 -264.486113) (xy 145.703181 -264.52969)
			(xy 145.673616 -264.569034) (xy 145.638123 -264.603126) (xy 145.59762 -264.631082) (xy 145.553158 -264.65218)
			(xy 145.505887 -264.665872) (xy 145.457032 -264.671804) (xy 145.407857 -264.669823) (xy 145.359638 -264.659979)
			(xy 145.313622 -264.642527) (xy 145.271001 -264.61792) (xy 145.23288 -264.586795) (xy 145.200245 -264.549958)
			(xy 145.173942 -264.508362) (xy 145.154651 -264.463086) (xy 145.142874 -264.415302) (xy 145.138914 -264.366248)
			(xy 143.869918 -264.366248) (xy 143.869423 -264.390855) (xy 143.861528 -264.439432) (xy 143.845944 -264.486113)
			(xy 143.823073 -264.52969) (xy 143.793508 -264.569034) (xy 143.758015 -264.603126) (xy 143.717512 -264.631082)
			(xy 143.67305 -264.65218) (xy 143.625779 -264.665872) (xy 143.576924 -264.671804) (xy 143.527749 -264.669823)
			(xy 143.47953 -264.659979) (xy 143.433514 -264.642527) (xy 143.390893 -264.61792) (xy 143.352772 -264.586795)
			(xy 143.320137 -264.549958) (xy 143.293834 -264.508362) (xy 143.274543 -264.463086) (xy 143.262766 -264.415302)
			(xy 143.258806 -264.366248) (xy 142.940532 -264.366248) (xy 142.94002 -264.391694) (xy 142.931856 -264.441928)
			(xy 142.91574 -264.490202) (xy 142.892089 -264.535265) (xy 142.861516 -264.575951) (xy 142.824812 -264.611206)
			(xy 142.782928 -264.640116) (xy 142.736949 -264.661933) (xy 142.688065 -264.676093) (xy 142.637544 -264.682227)
			(xy 142.586692 -264.680178) (xy 142.536828 -264.669998) (xy 142.489242 -264.651951) (xy 142.445168 -264.626505)
			(xy 142.405746 -264.594318) (xy 142.371998 -264.556224) (xy 142.344797 -264.51321) (xy 142.324849 -264.46639)
			(xy 142.31267 -264.416976) (xy 142.308575 -264.366248) (xy 142.000478 -264.366248) (xy 141.999966 -264.391694)
			(xy 141.991802 -264.441928) (xy 141.975686 -264.490202) (xy 141.952035 -264.535265) (xy 141.921462 -264.575951)
			(xy 141.884758 -264.611206) (xy 141.842874 -264.640116) (xy 141.796895 -264.661933) (xy 141.748011 -264.676093)
			(xy 141.69749 -264.682227) (xy 141.646638 -264.680178) (xy 141.596774 -264.669998) (xy 141.549188 -264.651951)
			(xy 141.505114 -264.626505) (xy 141.465692 -264.594318) (xy 141.431944 -264.556224) (xy 141.404743 -264.51321)
			(xy 141.384795 -264.46639) (xy 141.372616 -264.416976) (xy 141.368521 -264.366248) (xy 141.05001 -264.366248)
			(xy 141.049515 -264.390855) (xy 141.04162 -264.439432) (xy 141.026036 -264.486113) (xy 141.003165 -264.52969)
			(xy 140.9736 -264.569034) (xy 140.938107 -264.603126) (xy 140.897604 -264.631082) (xy 140.853142 -264.65218)
			(xy 140.805871 -264.665872) (xy 140.757016 -264.671804) (xy 140.707841 -264.669823) (xy 140.659622 -264.659979)
			(xy 140.613606 -264.642527) (xy 140.570985 -264.61792) (xy 140.532864 -264.586795) (xy 140.500229 -264.549958)
			(xy 140.473926 -264.508362) (xy 140.454635 -264.463086) (xy 140.442858 -264.415302) (xy 140.438898 -264.366248)
			(xy 140.12037 -264.366248) (xy 140.119858 -264.391694) (xy 140.111694 -264.441928) (xy 140.095578 -264.490202)
			(xy 140.071927 -264.535265) (xy 140.041354 -264.575951) (xy 140.00465 -264.611206) (xy 139.962766 -264.640116)
			(xy 139.916787 -264.661933) (xy 139.867903 -264.676093) (xy 139.817382 -264.682227) (xy 139.76653 -264.680178)
			(xy 139.716666 -264.669998) (xy 139.66908 -264.651951) (xy 139.625006 -264.626505) (xy 139.585584 -264.594318)
			(xy 139.551836 -264.556224) (xy 139.524635 -264.51321) (xy 139.504687 -264.46639) (xy 139.492508 -264.416976)
			(xy 139.488413 -264.366248) (xy 139.170156 -264.366248) (xy 139.169661 -264.390855) (xy 139.161766 -264.439432)
			(xy 139.146182 -264.486113) (xy 139.123311 -264.52969) (xy 139.093746 -264.569034) (xy 139.058253 -264.603126)
			(xy 139.01775 -264.631082) (xy 138.973288 -264.65218) (xy 138.926017 -264.665872) (xy 138.877162 -264.671804)
			(xy 138.827987 -264.669823) (xy 138.779768 -264.659979) (xy 138.733752 -264.642527) (xy 138.691131 -264.61792)
			(xy 138.65301 -264.586795) (xy 138.620375 -264.549958) (xy 138.594072 -264.508362) (xy 138.574781 -264.463086)
			(xy 138.563004 -264.415302) (xy 138.559044 -264.366248) (xy 138.240516 -264.366248) (xy 138.240004 -264.391694)
			(xy 138.23184 -264.441928) (xy 138.215724 -264.490202) (xy 138.192073 -264.535265) (xy 138.1615 -264.575951)
			(xy 138.124796 -264.611206) (xy 138.082912 -264.640116) (xy 138.036933 -264.661933) (xy 137.988049 -264.676093)
			(xy 137.937528 -264.682227) (xy 137.886676 -264.680178) (xy 137.836812 -264.669998) (xy 137.789226 -264.651951)
			(xy 137.745152 -264.626505) (xy 137.70573 -264.594318) (xy 137.671982 -264.556224) (xy 137.644781 -264.51321)
			(xy 137.624833 -264.46639) (xy 137.612654 -264.416976) (xy 137.608559 -264.366248) (xy 137.290048 -264.366248)
			(xy 137.289553 -264.390855) (xy 137.281658 -264.439432) (xy 137.266074 -264.486113) (xy 137.243203 -264.52969)
			(xy 137.213638 -264.569034) (xy 137.178145 -264.603126) (xy 137.137642 -264.631082) (xy 137.09318 -264.65218)
			(xy 137.045909 -264.665872) (xy 136.997054 -264.671804) (xy 136.947879 -264.669823) (xy 136.89966 -264.659979)
			(xy 136.853644 -264.642527) (xy 136.811023 -264.61792) (xy 136.772902 -264.586795) (xy 136.740267 -264.549958)
			(xy 136.713964 -264.508362) (xy 136.694673 -264.463086) (xy 136.682896 -264.415302) (xy 136.678936 -264.366248)
			(xy 136.360408 -264.366248) (xy 136.359896 -264.391694) (xy 136.351732 -264.441928) (xy 136.335616 -264.490202)
			(xy 136.311965 -264.535265) (xy 136.281392 -264.575951) (xy 136.244688 -264.611206) (xy 136.202804 -264.640116)
			(xy 136.156825 -264.661933) (xy 136.107941 -264.676093) (xy 136.05742 -264.682227) (xy 136.006568 -264.680178)
			(xy 135.956704 -264.669998) (xy 135.909118 -264.651951) (xy 135.865044 -264.626505) (xy 135.825622 -264.594318)
			(xy 135.791874 -264.556224) (xy 135.764673 -264.51321) (xy 135.744725 -264.46639) (xy 135.732546 -264.416976)
			(xy 135.728451 -264.366248) (xy 135.420354 -264.366248) (xy 135.419842 -264.391694) (xy 135.411678 -264.441928)
			(xy 135.395562 -264.490202) (xy 135.371911 -264.535265) (xy 135.341338 -264.575951) (xy 135.304634 -264.611206)
			(xy 135.26275 -264.640116) (xy 135.216771 -264.661933) (xy 135.167887 -264.676093) (xy 135.117366 -264.682227)
			(xy 135.066514 -264.680178) (xy 135.01665 -264.669998) (xy 134.969064 -264.651951) (xy 134.92499 -264.626505)
			(xy 134.885568 -264.594318) (xy 134.85182 -264.556224) (xy 134.824619 -264.51321) (xy 134.804671 -264.46639)
			(xy 134.792492 -264.416976) (xy 134.788397 -264.366248) (xy 134.47014 -264.366248) (xy 134.469645 -264.390855)
			(xy 134.46175 -264.439432) (xy 134.446166 -264.486113) (xy 134.423295 -264.52969) (xy 134.39373 -264.569034)
			(xy 134.358237 -264.603126) (xy 134.317734 -264.631082) (xy 134.273272 -264.65218) (xy 134.226001 -264.665872)
			(xy 134.177146 -264.671804) (xy 134.127971 -264.669823) (xy 134.079752 -264.659979) (xy 134.033736 -264.642527)
			(xy 133.991115 -264.61792) (xy 133.952994 -264.586795) (xy 133.920359 -264.549958) (xy 133.894056 -264.508362)
			(xy 133.874765 -264.463086) (xy 133.862988 -264.415302) (xy 133.859028 -264.366248) (xy 133.5405 -264.366248)
			(xy 133.539988 -264.391694) (xy 133.531824 -264.441928) (xy 133.515708 -264.490202) (xy 133.492057 -264.535265)
			(xy 133.461484 -264.575951) (xy 133.42478 -264.611206) (xy 133.382896 -264.640116) (xy 133.336917 -264.661933)
			(xy 133.288033 -264.676093) (xy 133.237512 -264.682227) (xy 133.18666 -264.680178) (xy 133.136796 -264.669998)
			(xy 133.08921 -264.651951) (xy 133.045136 -264.626505) (xy 133.005714 -264.594318) (xy 132.971966 -264.556224)
			(xy 132.944765 -264.51321) (xy 132.924817 -264.46639) (xy 132.912638 -264.416976) (xy 132.908543 -264.366248)
			(xy 132.590032 -264.366248) (xy 132.589537 -264.390855) (xy 132.581642 -264.439432) (xy 132.566058 -264.486113)
			(xy 132.543187 -264.52969) (xy 132.513622 -264.569034) (xy 132.478129 -264.603126) (xy 132.437626 -264.631082)
			(xy 132.393164 -264.65218) (xy 132.345893 -264.665872) (xy 132.297038 -264.671804) (xy 132.247863 -264.669823)
			(xy 132.199644 -264.659979) (xy 132.153628 -264.642527) (xy 132.111007 -264.61792) (xy 132.072886 -264.586795)
			(xy 132.040251 -264.549958) (xy 132.013948 -264.508362) (xy 131.994657 -264.463086) (xy 131.98288 -264.415302)
			(xy 131.97892 -264.366248) (xy 131.660392 -264.366248) (xy 131.65988 -264.391694) (xy 131.651716 -264.441928)
			(xy 131.6356 -264.490202) (xy 131.611949 -264.535265) (xy 131.581376 -264.575951) (xy 131.544672 -264.611206)
			(xy 131.502788 -264.640116) (xy 131.456809 -264.661933) (xy 131.407925 -264.676093) (xy 131.357404 -264.682227)
			(xy 131.306552 -264.680178) (xy 131.256688 -264.669998) (xy 131.209102 -264.651951) (xy 131.165028 -264.626505)
			(xy 131.125606 -264.594318) (xy 131.091858 -264.556224) (xy 131.064657 -264.51321) (xy 131.044709 -264.46639)
			(xy 131.03253 -264.416976) (xy 131.028435 -264.366248) (xy 130.710178 -264.366248) (xy 130.709683 -264.390855)
			(xy 130.701788 -264.439432) (xy 130.686204 -264.486113) (xy 130.663333 -264.52969) (xy 130.633768 -264.569034)
			(xy 130.598275 -264.603126) (xy 130.557772 -264.631082) (xy 130.51331 -264.65218) (xy 130.466039 -264.665872)
			(xy 130.417184 -264.671804) (xy 130.368009 -264.669823) (xy 130.31979 -264.659979) (xy 130.273774 -264.642527)
			(xy 130.231153 -264.61792) (xy 130.193032 -264.586795) (xy 130.160397 -264.549958) (xy 130.134094 -264.508362)
			(xy 130.114803 -264.463086) (xy 130.103026 -264.415302) (xy 130.099066 -264.366248) (xy 129.780538 -264.366248)
			(xy 129.780026 -264.391694) (xy 129.771862 -264.441928) (xy 129.755746 -264.490202) (xy 129.732095 -264.535265)
			(xy 129.701522 -264.575951) (xy 129.664818 -264.611206) (xy 129.622934 -264.640116) (xy 129.576955 -264.661933)
			(xy 129.528071 -264.676093) (xy 129.47755 -264.682227) (xy 129.426698 -264.680178) (xy 129.376834 -264.669998)
			(xy 129.329248 -264.651951) (xy 129.285174 -264.626505) (xy 129.245752 -264.594318) (xy 129.212004 -264.556224)
			(xy 129.184803 -264.51321) (xy 129.164855 -264.46639) (xy 129.152676 -264.416976) (xy 129.148581 -264.366248)
			(xy 128.840484 -264.366248) (xy 128.839972 -264.391694) (xy 128.831808 -264.441928) (xy 128.815692 -264.490202)
			(xy 128.792041 -264.535265) (xy 128.761468 -264.575951) (xy 128.724764 -264.611206) (xy 128.68288 -264.640116)
			(xy 128.636901 -264.661933) (xy 128.588017 -264.676093) (xy 128.537496 -264.682227) (xy 128.486644 -264.680178)
			(xy 128.43678 -264.669998) (xy 128.389194 -264.651951) (xy 128.34512 -264.626505) (xy 128.305698 -264.594318)
			(xy 128.27195 -264.556224) (xy 128.244749 -264.51321) (xy 128.224801 -264.46639) (xy 128.212622 -264.416976)
			(xy 128.208527 -264.366248) (xy 126.949962 -264.366248) (xy 126.949467 -264.390855) (xy 126.941572 -264.439432)
			(xy 126.925988 -264.486113) (xy 126.903117 -264.52969) (xy 126.873552 -264.569034) (xy 126.838059 -264.603126)
			(xy 126.797556 -264.631082) (xy 126.753094 -264.65218) (xy 126.705823 -264.665872) (xy 126.656968 -264.671804)
			(xy 126.607793 -264.669823) (xy 126.559574 -264.659979) (xy 126.513558 -264.642527) (xy 126.470937 -264.61792)
			(xy 126.432816 -264.586795) (xy 126.400181 -264.549958) (xy 126.373878 -264.508362) (xy 126.354587 -264.463086)
			(xy 126.34281 -264.415302) (xy 126.33885 -264.366248) (xy 125.070108 -264.366248) (xy 125.069613 -264.390855)
			(xy 125.061718 -264.439432) (xy 125.046134 -264.486113) (xy 125.023263 -264.52969) (xy 124.993698 -264.569034)
			(xy 124.958205 -264.603126) (xy 124.917702 -264.631082) (xy 124.87324 -264.65218) (xy 124.825969 -264.665872)
			(xy 124.777114 -264.671804) (xy 124.727939 -264.669823) (xy 124.67972 -264.659979) (xy 124.633704 -264.642527)
			(xy 124.591083 -264.61792) (xy 124.552962 -264.586795) (xy 124.520327 -264.549958) (xy 124.494024 -264.508362)
			(xy 124.474733 -264.463086) (xy 124.462956 -264.415302) (xy 124.458996 -264.366248) (xy 123.19 -264.366248)
			(xy 123.189505 -264.390855) (xy 123.18161 -264.439432) (xy 123.166026 -264.486113) (xy 123.143155 -264.52969)
			(xy 123.11359 -264.569034) (xy 123.078097 -264.603126) (xy 123.037594 -264.631082) (xy 122.993132 -264.65218)
			(xy 122.945861 -264.665872) (xy 122.897006 -264.671804) (xy 122.847831 -264.669823) (xy 122.799612 -264.659979)
			(xy 122.753596 -264.642527) (xy 122.710975 -264.61792) (xy 122.672854 -264.586795) (xy 122.640219 -264.549958)
			(xy 122.613916 -264.508362) (xy 122.594625 -264.463086) (xy 122.582848 -264.415302) (xy 122.578888 -264.366248)
			(xy 121.310867 -264.366248) (xy 121.310908 -264.36828) (xy 121.310413 -264.392887) (xy 121.302518 -264.441464)
			(xy 121.286934 -264.488145) (xy 121.264063 -264.531722) (xy 121.234498 -264.571066) (xy 121.199005 -264.605158)
			(xy 121.158502 -264.633114) (xy 121.11404 -264.654212) (xy 121.066769 -264.667904) (xy 121.017914 -264.673836)
			(xy 120.968739 -264.671855) (xy 120.92052 -264.662011) (xy 120.874504 -264.644559) (xy 120.831883 -264.619952)
			(xy 120.793762 -264.588827) (xy 120.761127 -264.55199) (xy 120.734824 -264.510394) (xy 120.715533 -264.465118)
			(xy 120.703756 -264.417334) (xy 120.699796 -264.36828) (xy 119.433086 -264.36828) (xy 119.432591 -264.392887)
			(xy 119.424696 -264.441464) (xy 119.409112 -264.488145) (xy 119.386241 -264.531722) (xy 119.356676 -264.571066)
			(xy 119.321183 -264.605158) (xy 119.28068 -264.633114) (xy 119.236218 -264.654212) (xy 119.188947 -264.667904)
			(xy 119.140092 -264.673836) (xy 119.090917 -264.671855) (xy 119.042698 -264.662011) (xy 118.996682 -264.644559)
			(xy 118.954061 -264.619952) (xy 118.91594 -264.588827) (xy 118.883305 -264.55199) (xy 118.857002 -264.510394)
			(xy 118.837711 -264.465118) (xy 118.825934 -264.417334) (xy 118.821974 -264.36828) (xy 117.553232 -264.36828)
			(xy 117.552737 -264.392887) (xy 117.544842 -264.441464) (xy 117.529258 -264.488145) (xy 117.506387 -264.531722)
			(xy 117.476822 -264.571066) (xy 117.441329 -264.605158) (xy 117.400826 -264.633114) (xy 117.356364 -264.654212)
			(xy 117.309093 -264.667904) (xy 117.260238 -264.673836) (xy 117.211063 -264.671855) (xy 117.162844 -264.662011)
			(xy 117.116828 -264.644559) (xy 117.074207 -264.619952) (xy 117.036086 -264.588827) (xy 117.003451 -264.55199)
			(xy 116.977148 -264.510394) (xy 116.957857 -264.465118) (xy 116.94608 -264.417334) (xy 116.94212 -264.36828)
			(xy 115.673124 -264.36828) (xy 115.672629 -264.392887) (xy 115.664734 -264.441464) (xy 115.64915 -264.488145)
			(xy 115.626279 -264.531722) (xy 115.596714 -264.571066) (xy 115.561221 -264.605158) (xy 115.520718 -264.633114)
			(xy 115.476256 -264.654212) (xy 115.428985 -264.667904) (xy 115.38013 -264.673836) (xy 115.330955 -264.671855)
			(xy 115.282736 -264.662011) (xy 115.23672 -264.644559) (xy 115.194099 -264.619952) (xy 115.155978 -264.588827)
			(xy 115.123343 -264.55199) (xy 115.09704 -264.510394) (xy 115.077749 -264.465118) (xy 115.065972 -264.417334)
			(xy 115.062012 -264.36828) (xy 108.1532 -264.36828) (xy 108.152705 -264.392887) (xy 108.14481 -264.441464)
			(xy 108.129226 -264.488145) (xy 108.106355 -264.531722) (xy 108.07679 -264.571066) (xy 108.041297 -264.605158)
			(xy 108.000794 -264.633114) (xy 107.956332 -264.654212) (xy 107.909061 -264.667904) (xy 107.860206 -264.673836)
			(xy 107.811031 -264.671855) (xy 107.762812 -264.662011) (xy 107.716796 -264.644559) (xy 107.674175 -264.619952)
			(xy 107.636054 -264.588827) (xy 107.603419 -264.55199) (xy 107.577116 -264.510394) (xy 107.557825 -264.465118)
			(xy 107.546048 -264.417334) (xy 107.542088 -264.36828) (xy 106.273346 -264.36828) (xy 106.272851 -264.392887)
			(xy 106.264956 -264.441464) (xy 106.249372 -264.488145) (xy 106.226501 -264.531722) (xy 106.196936 -264.571066)
			(xy 106.161443 -264.605158) (xy 106.12094 -264.633114) (xy 106.076478 -264.654212) (xy 106.029207 -264.667904)
			(xy 105.980352 -264.673836) (xy 105.931177 -264.671855) (xy 105.882958 -264.662011) (xy 105.836942 -264.644559)
			(xy 105.794321 -264.619952) (xy 105.7562 -264.588827) (xy 105.723565 -264.55199) (xy 105.697262 -264.510394)
			(xy 105.677971 -264.465118) (xy 105.666194 -264.417334) (xy 105.662234 -264.36828) (xy 104.393238 -264.36828)
			(xy 104.392743 -264.392887) (xy 104.384848 -264.441464) (xy 104.369264 -264.488145) (xy 104.346393 -264.531722)
			(xy 104.316828 -264.571066) (xy 104.281335 -264.605158) (xy 104.240832 -264.633114) (xy 104.19637 -264.654212)
			(xy 104.149099 -264.667904) (xy 104.100244 -264.673836) (xy 104.051069 -264.671855) (xy 104.00285 -264.662011)
			(xy 103.956834 -264.644559) (xy 103.914213 -264.619952) (xy 103.876092 -264.588827) (xy 103.843457 -264.55199)
			(xy 103.817154 -264.510394) (xy 103.797863 -264.465118) (xy 103.786086 -264.417334) (xy 103.782126 -264.36828)
			(xy 102.516391 -264.36828) (xy 102.515937 -264.390855) (xy 102.508042 -264.439432) (xy 102.492458 -264.486113)
			(xy 102.469587 -264.52969) (xy 102.440022 -264.569034) (xy 102.404529 -264.603126) (xy 102.364026 -264.631082)
			(xy 102.319564 -264.65218) (xy 102.272293 -264.665872) (xy 102.223438 -264.671804) (xy 102.174263 -264.669823)
			(xy 102.126044 -264.659979) (xy 102.080028 -264.642527) (xy 102.037407 -264.61792) (xy 101.999286 -264.586795)
			(xy 101.966651 -264.549958) (xy 101.940348 -264.508362) (xy 101.921057 -264.463086) (xy 101.90928 -264.415302)
			(xy 101.90532 -264.366248) (xy 101.0666 -264.366248) (xy 101.0666 -264.862564) (xy 111.234223 -264.862564)
			(xy 111.238253 -264.810066) (xy 111.25025 -264.758798) (xy 111.269933 -264.709963) (xy 111.296839 -264.664704)
			(xy 111.330339 -264.624083) (xy 111.369647 -264.589052) (xy 111.413842 -264.560432) (xy 111.461887 -264.538893)
			(xy 111.512658 -264.524941) (xy 111.564963 -264.518903) (xy 111.617577 -264.52092) (xy 111.669267 -264.530944)
			(xy 111.71882 -264.548742) (xy 111.765076 -264.573895) (xy 111.80695 -264.605814) (xy 111.843462 -264.643752)
			(xy 111.873754 -264.686818) (xy 111.897117 -264.734003) (xy 111.913003 -264.784202) (xy 111.92104 -264.836238)
			(xy 111.921544 -264.862564) (xy 111.92104 -264.88889) (xy 111.913003 -264.940926) (xy 111.897117 -264.991125)
			(xy 111.873754 -265.03831) (xy 111.843462 -265.081376) (xy 111.80695 -265.119314) (xy 111.765076 -265.151233)
			(xy 111.719063 -265.176254) (xy 121.168934 -265.176254) (xy 121.172894 -265.1272) (xy 121.184671 -265.079416)
			(xy 121.203962 -265.03414) (xy 121.230265 -264.992544) (xy 121.2629 -264.955707) (xy 121.301021 -264.924582)
			(xy 121.343642 -264.899975) (xy 121.389658 -264.882523) (xy 121.437877 -264.872679) (xy 121.487052 -264.870698)
			(xy 121.535907 -264.87663) (xy 121.583178 -264.890322) (xy 121.62764 -264.91142) (xy 121.668143 -264.939376)
			(xy 121.703636 -264.973468) (xy 121.733201 -265.012812) (xy 121.756072 -265.056389) (xy 121.771656 -265.10307)
			(xy 121.779551 -265.151647) (xy 121.780046 -265.176254) (xy 123.049042 -265.176254) (xy 123.053002 -265.1272)
			(xy 123.064779 -265.079416) (xy 123.08407 -265.03414) (xy 123.110373 -264.992544) (xy 123.143008 -264.955707)
			(xy 123.181129 -264.924582) (xy 123.22375 -264.899975) (xy 123.269766 -264.882523) (xy 123.317985 -264.872679)
			(xy 123.36716 -264.870698) (xy 123.416015 -264.87663) (xy 123.463286 -264.890322) (xy 123.507748 -264.91142)
			(xy 123.548251 -264.939376) (xy 123.583744 -264.973468) (xy 123.613309 -265.012812) (xy 123.63618 -265.056389)
			(xy 123.651764 -265.10307) (xy 123.659659 -265.151647) (xy 123.660154 -265.176254) (xy 124.928896 -265.176254)
			(xy 124.932856 -265.1272) (xy 124.944633 -265.079416) (xy 124.963924 -265.03414) (xy 124.990227 -264.992544)
			(xy 125.022862 -264.955707) (xy 125.060983 -264.924582) (xy 125.103604 -264.899975) (xy 125.14962 -264.882523)
			(xy 125.197839 -264.872679) (xy 125.247014 -264.870698) (xy 125.295869 -264.87663) (xy 125.34314 -264.890322)
			(xy 125.387602 -264.91142) (xy 125.428105 -264.939376) (xy 125.463598 -264.973468) (xy 125.493163 -265.012812)
			(xy 125.516034 -265.056389) (xy 125.531618 -265.10307) (xy 125.539513 -265.151647) (xy 125.540008 -265.176254)
			(xy 126.809004 -265.176254) (xy 126.812964 -265.1272) (xy 126.824741 -265.079416) (xy 126.844032 -265.03414)
			(xy 126.870335 -264.992544) (xy 126.90297 -264.955707) (xy 126.941091 -264.924582) (xy 126.983712 -264.899975)
			(xy 127.029728 -264.882523) (xy 127.077947 -264.872679) (xy 127.127122 -264.870698) (xy 127.175977 -264.87663)
			(xy 127.223248 -264.890322) (xy 127.26771 -264.91142) (xy 127.308213 -264.939376) (xy 127.343706 -264.973468)
			(xy 127.373271 -265.012812) (xy 127.396142 -265.056389) (xy 127.411726 -265.10307) (xy 127.419621 -265.151647)
			(xy 127.420116 -265.176254) (xy 127.738627 -265.176254) (xy 127.742722 -265.125526) (xy 127.754901 -265.076112)
			(xy 127.774849 -265.029292) (xy 127.80205 -264.986278) (xy 127.835798 -264.948184) (xy 127.87522 -264.915997)
			(xy 127.919294 -264.890551) (xy 127.96688 -264.872504) (xy 128.016744 -264.862324) (xy 128.067596 -264.860275)
			(xy 128.118117 -264.866409) (xy 128.167001 -264.880569) (xy 128.21298 -264.902386) (xy 128.254864 -264.931296)
			(xy 128.291568 -264.966551) (xy 128.322141 -265.007237) (xy 128.345792 -265.0523) (xy 128.361908 -265.100574)
			(xy 128.370072 -265.150808) (xy 128.370584 -265.176254) (xy 128.688858 -265.176254) (xy 128.692818 -265.1272)
			(xy 128.704595 -265.079416) (xy 128.723886 -265.03414) (xy 128.750189 -264.992544) (xy 128.782824 -264.955707)
			(xy 128.820945 -264.924582) (xy 128.863566 -264.899975) (xy 128.909582 -264.882523) (xy 128.957801 -264.872679)
			(xy 129.006976 -264.870698) (xy 129.055831 -264.87663) (xy 129.103102 -264.890322) (xy 129.147564 -264.91142)
			(xy 129.188067 -264.939376) (xy 129.22356 -264.973468) (xy 129.253125 -265.012812) (xy 129.275996 -265.056389)
			(xy 129.29158 -265.10307) (xy 129.299475 -265.151647) (xy 129.29997 -265.176254) (xy 129.628912 -265.176254)
			(xy 129.632872 -265.1272) (xy 129.644649 -265.079416) (xy 129.66394 -265.03414) (xy 129.690243 -264.992544)
			(xy 129.722878 -264.955707) (xy 129.760999 -264.924582) (xy 129.80362 -264.899975) (xy 129.849636 -264.882523)
			(xy 129.897855 -264.872679) (xy 129.94703 -264.870698) (xy 129.995885 -264.87663) (xy 130.043156 -264.890322)
			(xy 130.087618 -264.91142) (xy 130.128121 -264.939376) (xy 130.163614 -264.973468) (xy 130.193179 -265.012812)
			(xy 130.21605 -265.056389) (xy 130.231634 -265.10307) (xy 130.239529 -265.151647) (xy 130.240024 -265.176254)
			(xy 130.568966 -265.176254) (xy 130.572926 -265.1272) (xy 130.584703 -265.079416) (xy 130.603994 -265.03414)
			(xy 130.630297 -264.992544) (xy 130.662932 -264.955707) (xy 130.701053 -264.924582) (xy 130.743674 -264.899975)
			(xy 130.78969 -264.882523) (xy 130.837909 -264.872679) (xy 130.887084 -264.870698) (xy 130.935939 -264.87663)
			(xy 130.98321 -264.890322) (xy 131.027672 -264.91142) (xy 131.068175 -264.939376) (xy 131.103668 -264.973468)
			(xy 131.133233 -265.012812) (xy 131.156104 -265.056389) (xy 131.171688 -265.10307) (xy 131.179583 -265.151647)
			(xy 131.180078 -265.176254) (xy 131.498589 -265.176254) (xy 131.502684 -265.125526) (xy 131.514863 -265.076112)
			(xy 131.534811 -265.029292) (xy 131.562012 -264.986278) (xy 131.59576 -264.948184) (xy 131.635182 -264.915997)
			(xy 131.679256 -264.890551) (xy 131.726842 -264.872504) (xy 131.776706 -264.862324) (xy 131.827558 -264.860275)
			(xy 131.878079 -264.866409) (xy 131.926963 -264.880569) (xy 131.972942 -264.902386) (xy 132.014826 -264.931296)
			(xy 132.05153 -264.966551) (xy 132.082103 -265.007237) (xy 132.105754 -265.0523) (xy 132.12187 -265.100574)
			(xy 132.130034 -265.150808) (xy 132.130546 -265.176254) (xy 132.44882 -265.176254) (xy 132.45278 -265.1272)
			(xy 132.464557 -265.079416) (xy 132.483848 -265.03414) (xy 132.510151 -264.992544) (xy 132.542786 -264.955707)
			(xy 132.580907 -264.924582) (xy 132.623528 -264.899975) (xy 132.669544 -264.882523) (xy 132.717763 -264.872679)
			(xy 132.766938 -264.870698) (xy 132.815793 -264.87663) (xy 132.863064 -264.890322) (xy 132.907526 -264.91142)
			(xy 132.948029 -264.939376) (xy 132.983522 -264.973468) (xy 133.013087 -265.012812) (xy 133.035958 -265.056389)
			(xy 133.051542 -265.10307) (xy 133.059437 -265.151647) (xy 133.059932 -265.176254) (xy 133.388874 -265.176254)
			(xy 133.392834 -265.1272) (xy 133.404611 -265.079416) (xy 133.423902 -265.03414) (xy 133.450205 -264.992544)
			(xy 133.48284 -264.955707) (xy 133.520961 -264.924582) (xy 133.563582 -264.899975) (xy 133.609598 -264.882523)
			(xy 133.657817 -264.872679) (xy 133.706992 -264.870698) (xy 133.755847 -264.87663) (xy 133.803118 -264.890322)
			(xy 133.84758 -264.91142) (xy 133.888083 -264.939376) (xy 133.923576 -264.973468) (xy 133.953141 -265.012812)
			(xy 133.976012 -265.056389) (xy 133.991596 -265.10307) (xy 133.999491 -265.151647) (xy 133.999986 -265.176254)
			(xy 134.318497 -265.176254) (xy 134.322592 -265.125526) (xy 134.334771 -265.076112) (xy 134.354719 -265.029292)
			(xy 134.38192 -264.986278) (xy 134.415668 -264.948184) (xy 134.45509 -264.915997) (xy 134.499164 -264.890551)
			(xy 134.54675 -264.872504) (xy 134.596614 -264.862324) (xy 134.647466 -264.860275) (xy 134.697987 -264.866409)
			(xy 134.746871 -264.880569) (xy 134.79285 -264.902386) (xy 134.834734 -264.931296) (xy 134.871438 -264.966551)
			(xy 134.902011 -265.007237) (xy 134.925662 -265.0523) (xy 134.941778 -265.100574) (xy 134.949942 -265.150808)
			(xy 134.950454 -265.176254) (xy 135.268982 -265.176254) (xy 135.272942 -265.1272) (xy 135.284719 -265.079416)
			(xy 135.30401 -265.03414) (xy 135.330313 -264.992544) (xy 135.362948 -264.955707) (xy 135.401069 -264.924582)
			(xy 135.44369 -264.899975) (xy 135.489706 -264.882523) (xy 135.537925 -264.872679) (xy 135.5871 -264.870698)
			(xy 135.635955 -264.87663) (xy 135.683226 -264.890322) (xy 135.727688 -264.91142) (xy 135.768191 -264.939376)
			(xy 135.803684 -264.973468) (xy 135.833249 -265.012812) (xy 135.85612 -265.056389) (xy 135.871704 -265.10307)
			(xy 135.879599 -265.151647) (xy 135.880094 -265.176254) (xy 136.209036 -265.176254) (xy 136.212996 -265.1272)
			(xy 136.224773 -265.079416) (xy 136.244064 -265.03414) (xy 136.270367 -264.992544) (xy 136.303002 -264.955707)
			(xy 136.341123 -264.924582) (xy 136.383744 -264.899975) (xy 136.42976 -264.882523) (xy 136.477979 -264.872679)
			(xy 136.527154 -264.870698) (xy 136.576009 -264.87663) (xy 136.62328 -264.890322) (xy 136.667742 -264.91142)
			(xy 136.708245 -264.939376) (xy 136.743738 -264.973468) (xy 136.773303 -265.012812) (xy 136.796174 -265.056389)
			(xy 136.811758 -265.10307) (xy 136.819653 -265.151647) (xy 136.820148 -265.176254) (xy 137.148836 -265.176254)
			(xy 137.152796 -265.1272) (xy 137.164573 -265.079416) (xy 137.183864 -265.03414) (xy 137.210167 -264.992544)
			(xy 137.242802 -264.955707) (xy 137.280923 -264.924582) (xy 137.323544 -264.899975) (xy 137.36956 -264.882523)
			(xy 137.417779 -264.872679) (xy 137.466954 -264.870698) (xy 137.515809 -264.87663) (xy 137.56308 -264.890322)
			(xy 137.607542 -264.91142) (xy 137.648045 -264.939376) (xy 137.683538 -264.973468) (xy 137.713103 -265.012812)
			(xy 137.735974 -265.056389) (xy 137.751558 -265.10307) (xy 137.759453 -265.151647) (xy 137.759948 -265.176254)
			(xy 138.078459 -265.176254) (xy 138.082554 -265.125526) (xy 138.094733 -265.076112) (xy 138.114681 -265.029292)
			(xy 138.141882 -264.986278) (xy 138.17563 -264.948184) (xy 138.215052 -264.915997) (xy 138.259126 -264.890551)
			(xy 138.306712 -264.872504) (xy 138.356576 -264.862324) (xy 138.407428 -264.860275) (xy 138.457949 -264.866409)
			(xy 138.506833 -264.880569) (xy 138.552812 -264.902386) (xy 138.594696 -264.931296) (xy 138.6314 -264.966551)
			(xy 138.661973 -265.007237) (xy 138.685624 -265.0523) (xy 138.70174 -265.100574) (xy 138.709904 -265.150808)
			(xy 138.710416 -265.176254) (xy 139.028944 -265.176254) (xy 139.032904 -265.1272) (xy 139.044681 -265.079416)
			(xy 139.063972 -265.03414) (xy 139.090275 -264.992544) (xy 139.12291 -264.955707) (xy 139.161031 -264.924582)
			(xy 139.203652 -264.899975) (xy 139.249668 -264.882523) (xy 139.297887 -264.872679) (xy 139.347062 -264.870698)
			(xy 139.395917 -264.87663) (xy 139.443188 -264.890322) (xy 139.48765 -264.91142) (xy 139.528153 -264.939376)
			(xy 139.563646 -264.973468) (xy 139.593211 -265.012812) (xy 139.616082 -265.056389) (xy 139.631666 -265.10307)
			(xy 139.639561 -265.151647) (xy 139.640056 -265.176254) (xy 139.968998 -265.176254) (xy 139.972958 -265.1272)
			(xy 139.984735 -265.079416) (xy 140.004026 -265.03414) (xy 140.030329 -264.992544) (xy 140.062964 -264.955707)
			(xy 140.101085 -264.924582) (xy 140.143706 -264.899975) (xy 140.189722 -264.882523) (xy 140.237941 -264.872679)
			(xy 140.287116 -264.870698) (xy 140.335971 -264.87663) (xy 140.383242 -264.890322) (xy 140.427704 -264.91142)
			(xy 140.468207 -264.939376) (xy 140.5037 -264.973468) (xy 140.533265 -265.012812) (xy 140.556136 -265.056389)
			(xy 140.57172 -265.10307) (xy 140.579615 -265.151647) (xy 140.58011 -265.176254) (xy 140.898621 -265.176254)
			(xy 140.902716 -265.125526) (xy 140.914895 -265.076112) (xy 140.934843 -265.029292) (xy 140.962044 -264.986278)
			(xy 140.995792 -264.948184) (xy 141.035214 -264.915997) (xy 141.079288 -264.890551) (xy 141.126874 -264.872504)
			(xy 141.176738 -264.862324) (xy 141.22759 -264.860275) (xy 141.278111 -264.866409) (xy 141.326995 -264.880569)
			(xy 141.372974 -264.902386) (xy 141.414858 -264.931296) (xy 141.451562 -264.966551) (xy 141.482135 -265.007237)
			(xy 141.505786 -265.0523) (xy 141.521902 -265.100574) (xy 141.530066 -265.150808) (xy 141.530578 -265.176254)
			(xy 141.848852 -265.176254) (xy 141.852812 -265.1272) (xy 141.864589 -265.079416) (xy 141.88388 -265.03414)
			(xy 141.910183 -264.992544) (xy 141.942818 -264.955707) (xy 141.980939 -264.924582) (xy 142.02356 -264.899975)
			(xy 142.069576 -264.882523) (xy 142.117795 -264.872679) (xy 142.16697 -264.870698) (xy 142.215825 -264.87663)
			(xy 142.263096 -264.890322) (xy 142.307558 -264.91142) (xy 142.348061 -264.939376) (xy 142.383554 -264.973468)
			(xy 142.413119 -265.012812) (xy 142.43599 -265.056389) (xy 142.451574 -265.10307) (xy 142.459469 -265.151647)
			(xy 142.459964 -265.176254) (xy 142.788906 -265.176254) (xy 142.792866 -265.1272) (xy 142.804643 -265.079416)
			(xy 142.823934 -265.03414) (xy 142.850237 -264.992544) (xy 142.882872 -264.955707) (xy 142.920993 -264.924582)
			(xy 142.963614 -264.899975) (xy 143.00963 -264.882523) (xy 143.057849 -264.872679) (xy 143.107024 -264.870698)
			(xy 143.155879 -264.87663) (xy 143.20315 -264.890322) (xy 143.247612 -264.91142) (xy 143.288115 -264.939376)
			(xy 143.323608 -264.973468) (xy 143.353173 -265.012812) (xy 143.376044 -265.056389) (xy 143.391628 -265.10307)
			(xy 143.399523 -265.151647) (xy 143.400018 -265.176254) (xy 143.72896 -265.176254) (xy 143.73292 -265.1272)
			(xy 143.744697 -265.079416) (xy 143.763988 -265.03414) (xy 143.790291 -264.992544) (xy 143.822926 -264.955707)
			(xy 143.861047 -264.924582) (xy 143.903668 -264.899975) (xy 143.949684 -264.882523) (xy 143.997903 -264.872679)
			(xy 144.047078 -264.870698) (xy 144.095933 -264.87663) (xy 144.143204 -264.890322) (xy 144.185339 -264.910316)
			(xy 146.737082 -264.910316) (xy 146.741042 -264.861262) (xy 146.752819 -264.813478) (xy 146.77211 -264.768202)
			(xy 146.798413 -264.726606) (xy 146.831048 -264.689769) (xy 146.869169 -264.658644) (xy 146.91179 -264.634037)
			(xy 146.957806 -264.616585) (xy 147.006025 -264.606741) (xy 147.0552 -264.60476) (xy 147.104055 -264.610692)
			(xy 147.151326 -264.624384) (xy 147.195788 -264.645482) (xy 147.236291 -264.673438) (xy 147.271784 -264.70753)
			(xy 147.301349 -264.746874) (xy 147.32422 -264.790451) (xy 147.339804 -264.837132) (xy 147.347699 -264.885709)
			(xy 147.348194 -264.910316) (xy 147.347699 -264.934923) (xy 147.339804 -264.9835) (xy 147.32422 -265.030181)
			(xy 147.301349 -265.073758) (xy 147.271784 -265.113102) (xy 147.236291 -265.147194) (xy 147.195788 -265.17515)
			(xy 147.151326 -265.196248) (xy 147.104055 -265.20994) (xy 147.0552 -265.215872) (xy 147.006025 -265.213891)
			(xy 146.957806 -265.204047) (xy 146.91179 -265.186595) (xy 146.869169 -265.161988) (xy 146.831048 -265.130863)
			(xy 146.798413 -265.094026) (xy 146.77211 -265.05243) (xy 146.752819 -265.007154) (xy 146.741042 -264.95937)
			(xy 146.737082 -264.910316) (xy 144.185339 -264.910316) (xy 144.187666 -264.91142) (xy 144.228169 -264.939376)
			(xy 144.263662 -264.973468) (xy 144.293227 -265.012812) (xy 144.316098 -265.056389) (xy 144.331682 -265.10307)
			(xy 144.339577 -265.151647) (xy 144.340072 -265.176254) (xy 144.339577 -265.200861) (xy 144.331682 -265.249438)
			(xy 144.316098 -265.296119) (xy 144.295556 -265.335258) (xy 168.158683 -265.335258) (xy 168.162618 -265.281487)
			(xy 168.174341 -265.228863) (xy 168.193601 -265.178506) (xy 168.219987 -265.131489) (xy 168.252939 -265.088816)
			(xy 168.291752 -265.051395) (xy 168.3356 -265.020025) (xy 168.383548 -264.995373) (xy 168.434575 -264.977965)
			(xy 168.487593 -264.968172) (xy 168.541472 -264.966203) (xy 168.595063 -264.9721) (xy 168.647224 -264.985736)
			(xy 168.696844 -265.006823) (xy 168.742865 -265.034909) (xy 168.784307 -265.069397) (xy 168.820285 -265.109551)
			(xy 168.850033 -265.154515) (xy 168.872918 -265.203332) (xy 168.88845 -265.254961) (xy 168.8963 -265.308301)
			(xy 168.896792 -265.335258) (xy 168.8963 -265.362215) (xy 168.88845 -265.415555) (xy 168.872918 -265.467184)
			(xy 168.850033 -265.516001) (xy 168.820285 -265.560965) (xy 168.784307 -265.601119) (xy 168.742865 -265.635607)
			(xy 168.696844 -265.663693) (xy 168.647224 -265.68478) (xy 168.595063 -265.698416) (xy 168.541472 -265.704313)
			(xy 168.487593 -265.702344) (xy 168.434575 -265.692551) (xy 168.383548 -265.675143) (xy 168.3356 -265.650491)
			(xy 168.291752 -265.619121) (xy 168.252939 -265.5817) (xy 168.219987 -265.539027) (xy 168.193601 -265.49201)
			(xy 168.174341 -265.441653) (xy 168.162618 -265.389029) (xy 168.158683 -265.335258) (xy 144.295556 -265.335258)
			(xy 144.293227 -265.339696) (xy 144.263662 -265.37904) (xy 144.228169 -265.413132) (xy 144.187666 -265.441088)
			(xy 144.143204 -265.462186) (xy 144.095933 -265.475878) (xy 144.047078 -265.48181) (xy 143.997903 -265.479829)
			(xy 143.949684 -265.469985) (xy 143.903668 -265.452533) (xy 143.861047 -265.427926) (xy 143.822926 -265.396801)
			(xy 143.790291 -265.359964) (xy 143.763988 -265.318368) (xy 143.744697 -265.273092) (xy 143.73292 -265.225308)
			(xy 143.72896 -265.176254) (xy 143.400018 -265.176254) (xy 143.399523 -265.200861) (xy 143.391628 -265.249438)
			(xy 143.376044 -265.296119) (xy 143.353173 -265.339696) (xy 143.323608 -265.37904) (xy 143.288115 -265.413132)
			(xy 143.247612 -265.441088) (xy 143.20315 -265.462186) (xy 143.155879 -265.475878) (xy 143.107024 -265.48181)
			(xy 143.057849 -265.479829) (xy 143.00963 -265.469985) (xy 142.963614 -265.452533) (xy 142.920993 -265.427926)
			(xy 142.882872 -265.396801) (xy 142.850237 -265.359964) (xy 142.823934 -265.318368) (xy 142.804643 -265.273092)
			(xy 142.792866 -265.225308) (xy 142.788906 -265.176254) (xy 142.459964 -265.176254) (xy 142.459469 -265.200861)
			(xy 142.451574 -265.249438) (xy 142.43599 -265.296119) (xy 142.413119 -265.339696) (xy 142.383554 -265.37904)
			(xy 142.348061 -265.413132) (xy 142.307558 -265.441088) (xy 142.263096 -265.462186) (xy 142.215825 -265.475878)
			(xy 142.16697 -265.48181) (xy 142.117795 -265.479829) (xy 142.069576 -265.469985) (xy 142.02356 -265.452533)
			(xy 141.980939 -265.427926) (xy 141.942818 -265.396801) (xy 141.910183 -265.359964) (xy 141.88388 -265.318368)
			(xy 141.864589 -265.273092) (xy 141.852812 -265.225308) (xy 141.848852 -265.176254) (xy 141.530578 -265.176254)
			(xy 141.530066 -265.2017) (xy 141.521902 -265.251934) (xy 141.505786 -265.300208) (xy 141.482135 -265.345271)
			(xy 141.451562 -265.385957) (xy 141.414858 -265.421212) (xy 141.372974 -265.450122) (xy 141.326995 -265.471939)
			(xy 141.278111 -265.486099) (xy 141.22759 -265.492233) (xy 141.176738 -265.490184) (xy 141.126874 -265.480004)
			(xy 141.079288 -265.461957) (xy 141.035214 -265.436511) (xy 140.995792 -265.404324) (xy 140.962044 -265.36623)
			(xy 140.934843 -265.323216) (xy 140.914895 -265.276396) (xy 140.902716 -265.226982) (xy 140.898621 -265.176254)
			(xy 140.58011 -265.176254) (xy 140.579615 -265.200861) (xy 140.57172 -265.249438) (xy 140.556136 -265.296119)
			(xy 140.533265 -265.339696) (xy 140.5037 -265.37904) (xy 140.468207 -265.413132) (xy 140.427704 -265.441088)
			(xy 140.383242 -265.462186) (xy 140.335971 -265.475878) (xy 140.287116 -265.48181) (xy 140.237941 -265.479829)
			(xy 140.189722 -265.469985) (xy 140.143706 -265.452533) (xy 140.101085 -265.427926) (xy 140.062964 -265.396801)
			(xy 140.030329 -265.359964) (xy 140.004026 -265.318368) (xy 139.984735 -265.273092) (xy 139.972958 -265.225308)
			(xy 139.968998 -265.176254) (xy 139.640056 -265.176254) (xy 139.639561 -265.200861) (xy 139.631666 -265.249438)
			(xy 139.616082 -265.296119) (xy 139.593211 -265.339696) (xy 139.563646 -265.37904) (xy 139.528153 -265.413132)
			(xy 139.48765 -265.441088) (xy 139.443188 -265.462186) (xy 139.395917 -265.475878) (xy 139.347062 -265.48181)
			(xy 139.297887 -265.479829) (xy 139.249668 -265.469985) (xy 139.203652 -265.452533) (xy 139.161031 -265.427926)
			(xy 139.12291 -265.396801) (xy 139.090275 -265.359964) (xy 139.063972 -265.318368) (xy 139.044681 -265.273092)
			(xy 139.032904 -265.225308) (xy 139.028944 -265.176254) (xy 138.710416 -265.176254) (xy 138.709904 -265.2017)
			(xy 138.70174 -265.251934) (xy 138.685624 -265.300208) (xy 138.661973 -265.345271) (xy 138.6314 -265.385957)
			(xy 138.594696 -265.421212) (xy 138.552812 -265.450122) (xy 138.506833 -265.471939) (xy 138.457949 -265.486099)
			(xy 138.407428 -265.492233) (xy 138.356576 -265.490184) (xy 138.306712 -265.480004) (xy 138.259126 -265.461957)
			(xy 138.215052 -265.436511) (xy 138.17563 -265.404324) (xy 138.141882 -265.36623) (xy 138.114681 -265.323216)
			(xy 138.094733 -265.276396) (xy 138.082554 -265.226982) (xy 138.078459 -265.176254) (xy 137.759948 -265.176254)
			(xy 137.759453 -265.200861) (xy 137.751558 -265.249438) (xy 137.735974 -265.296119) (xy 137.713103 -265.339696)
			(xy 137.683538 -265.37904) (xy 137.648045 -265.413132) (xy 137.607542 -265.441088) (xy 137.56308 -265.462186)
			(xy 137.515809 -265.475878) (xy 137.466954 -265.48181) (xy 137.417779 -265.479829) (xy 137.36956 -265.469985)
			(xy 137.323544 -265.452533) (xy 137.280923 -265.427926) (xy 137.242802 -265.396801) (xy 137.210167 -265.359964)
			(xy 137.183864 -265.318368) (xy 137.164573 -265.273092) (xy 137.152796 -265.225308) (xy 137.148836 -265.176254)
			(xy 136.820148 -265.176254) (xy 136.819653 -265.200861) (xy 136.811758 -265.249438) (xy 136.796174 -265.296119)
			(xy 136.773303 -265.339696) (xy 136.743738 -265.37904) (xy 136.708245 -265.413132) (xy 136.667742 -265.441088)
			(xy 136.62328 -265.462186) (xy 136.576009 -265.475878) (xy 136.527154 -265.48181) (xy 136.477979 -265.479829)
			(xy 136.42976 -265.469985) (xy 136.383744 -265.452533) (xy 136.341123 -265.427926) (xy 136.303002 -265.396801)
			(xy 136.270367 -265.359964) (xy 136.244064 -265.318368) (xy 136.224773 -265.273092) (xy 136.212996 -265.225308)
			(xy 136.209036 -265.176254) (xy 135.880094 -265.176254) (xy 135.879599 -265.200861) (xy 135.871704 -265.249438)
			(xy 135.85612 -265.296119) (xy 135.833249 -265.339696) (xy 135.803684 -265.37904) (xy 135.768191 -265.413132)
			(xy 135.727688 -265.441088) (xy 135.683226 -265.462186) (xy 135.635955 -265.475878) (xy 135.5871 -265.48181)
			(xy 135.537925 -265.479829) (xy 135.489706 -265.469985) (xy 135.44369 -265.452533) (xy 135.401069 -265.427926)
			(xy 135.362948 -265.396801) (xy 135.330313 -265.359964) (xy 135.30401 -265.318368) (xy 135.284719 -265.273092)
			(xy 135.272942 -265.225308) (xy 135.268982 -265.176254) (xy 134.950454 -265.176254) (xy 134.949942 -265.2017)
			(xy 134.941778 -265.251934) (xy 134.925662 -265.300208) (xy 134.902011 -265.345271) (xy 134.871438 -265.385957)
			(xy 134.834734 -265.421212) (xy 134.79285 -265.450122) (xy 134.746871 -265.471939) (xy 134.697987 -265.486099)
			(xy 134.647466 -265.492233) (xy 134.596614 -265.490184) (xy 134.54675 -265.480004) (xy 134.499164 -265.461957)
			(xy 134.45509 -265.436511) (xy 134.415668 -265.404324) (xy 134.38192 -265.36623) (xy 134.354719 -265.323216)
			(xy 134.334771 -265.276396) (xy 134.322592 -265.226982) (xy 134.318497 -265.176254) (xy 133.999986 -265.176254)
			(xy 133.999491 -265.200861) (xy 133.991596 -265.249438) (xy 133.976012 -265.296119) (xy 133.953141 -265.339696)
			(xy 133.923576 -265.37904) (xy 133.888083 -265.413132) (xy 133.84758 -265.441088) (xy 133.803118 -265.462186)
			(xy 133.755847 -265.475878) (xy 133.706992 -265.48181) (xy 133.657817 -265.479829) (xy 133.609598 -265.469985)
			(xy 133.563582 -265.452533) (xy 133.520961 -265.427926) (xy 133.48284 -265.396801) (xy 133.450205 -265.359964)
			(xy 133.423902 -265.318368) (xy 133.404611 -265.273092) (xy 133.392834 -265.225308) (xy 133.388874 -265.176254)
			(xy 133.059932 -265.176254) (xy 133.059437 -265.200861) (xy 133.051542 -265.249438) (xy 133.035958 -265.296119)
			(xy 133.013087 -265.339696) (xy 132.983522 -265.37904) (xy 132.948029 -265.413132) (xy 132.907526 -265.441088)
			(xy 132.863064 -265.462186) (xy 132.815793 -265.475878) (xy 132.766938 -265.48181) (xy 132.717763 -265.479829)
			(xy 132.669544 -265.469985) (xy 132.623528 -265.452533) (xy 132.580907 -265.427926) (xy 132.542786 -265.396801)
			(xy 132.510151 -265.359964) (xy 132.483848 -265.318368) (xy 132.464557 -265.273092) (xy 132.45278 -265.225308)
			(xy 132.44882 -265.176254) (xy 132.130546 -265.176254) (xy 132.130034 -265.2017) (xy 132.12187 -265.251934)
			(xy 132.105754 -265.300208) (xy 132.082103 -265.345271) (xy 132.05153 -265.385957) (xy 132.014826 -265.421212)
			(xy 131.972942 -265.450122) (xy 131.926963 -265.471939) (xy 131.878079 -265.486099) (xy 131.827558 -265.492233)
			(xy 131.776706 -265.490184) (xy 131.726842 -265.480004) (xy 131.679256 -265.461957) (xy 131.635182 -265.436511)
			(xy 131.59576 -265.404324) (xy 131.562012 -265.36623) (xy 131.534811 -265.323216) (xy 131.514863 -265.276396)
			(xy 131.502684 -265.226982) (xy 131.498589 -265.176254) (xy 131.180078 -265.176254) (xy 131.179583 -265.200861)
			(xy 131.171688 -265.249438) (xy 131.156104 -265.296119) (xy 131.133233 -265.339696) (xy 131.103668 -265.37904)
			(xy 131.068175 -265.413132) (xy 131.027672 -265.441088) (xy 130.98321 -265.462186) (xy 130.935939 -265.475878)
			(xy 130.887084 -265.48181) (xy 130.837909 -265.479829) (xy 130.78969 -265.469985) (xy 130.743674 -265.452533)
			(xy 130.701053 -265.427926) (xy 130.662932 -265.396801) (xy 130.630297 -265.359964) (xy 130.603994 -265.318368)
			(xy 130.584703 -265.273092) (xy 130.572926 -265.225308) (xy 130.568966 -265.176254) (xy 130.240024 -265.176254)
			(xy 130.239529 -265.200861) (xy 130.231634 -265.249438) (xy 130.21605 -265.296119) (xy 130.193179 -265.339696)
			(xy 130.163614 -265.37904) (xy 130.128121 -265.413132) (xy 130.087618 -265.441088) (xy 130.043156 -265.462186)
			(xy 129.995885 -265.475878) (xy 129.94703 -265.48181) (xy 129.897855 -265.479829) (xy 129.849636 -265.469985)
			(xy 129.80362 -265.452533) (xy 129.760999 -265.427926) (xy 129.722878 -265.396801) (xy 129.690243 -265.359964)
			(xy 129.66394 -265.318368) (xy 129.644649 -265.273092) (xy 129.632872 -265.225308) (xy 129.628912 -265.176254)
			(xy 129.29997 -265.176254) (xy 129.299475 -265.200861) (xy 129.29158 -265.249438) (xy 129.275996 -265.296119)
			(xy 129.253125 -265.339696) (xy 129.22356 -265.37904) (xy 129.188067 -265.413132) (xy 129.147564 -265.441088)
			(xy 129.103102 -265.462186) (xy 129.055831 -265.475878) (xy 129.006976 -265.48181) (xy 128.957801 -265.479829)
			(xy 128.909582 -265.469985) (xy 128.863566 -265.452533) (xy 128.820945 -265.427926) (xy 128.782824 -265.396801)
			(xy 128.750189 -265.359964) (xy 128.723886 -265.318368) (xy 128.704595 -265.273092) (xy 128.692818 -265.225308)
			(xy 128.688858 -265.176254) (xy 128.370584 -265.176254) (xy 128.370072 -265.2017) (xy 128.361908 -265.251934)
			(xy 128.345792 -265.300208) (xy 128.322141 -265.345271) (xy 128.291568 -265.385957) (xy 128.254864 -265.421212)
			(xy 128.21298 -265.450122) (xy 128.167001 -265.471939) (xy 128.118117 -265.486099) (xy 128.067596 -265.492233)
			(xy 128.016744 -265.490184) (xy 127.96688 -265.480004) (xy 127.919294 -265.461957) (xy 127.87522 -265.436511)
			(xy 127.835798 -265.404324) (xy 127.80205 -265.36623) (xy 127.774849 -265.323216) (xy 127.754901 -265.276396)
			(xy 127.742722 -265.226982) (xy 127.738627 -265.176254) (xy 127.420116 -265.176254) (xy 127.419621 -265.200861)
			(xy 127.411726 -265.249438) (xy 127.396142 -265.296119) (xy 127.373271 -265.339696) (xy 127.343706 -265.37904)
			(xy 127.308213 -265.413132) (xy 127.26771 -265.441088) (xy 127.223248 -265.462186) (xy 127.175977 -265.475878)
			(xy 127.127122 -265.48181) (xy 127.077947 -265.479829) (xy 127.029728 -265.469985) (xy 126.983712 -265.452533)
			(xy 126.941091 -265.427926) (xy 126.90297 -265.396801) (xy 126.870335 -265.359964) (xy 126.844032 -265.318368)
			(xy 126.824741 -265.273092) (xy 126.812964 -265.225308) (xy 126.809004 -265.176254) (xy 125.540008 -265.176254)
			(xy 125.539513 -265.200861) (xy 125.531618 -265.249438) (xy 125.516034 -265.296119) (xy 125.493163 -265.339696)
			(xy 125.463598 -265.37904) (xy 125.428105 -265.413132) (xy 125.387602 -265.441088) (xy 125.34314 -265.462186)
			(xy 125.295869 -265.475878) (xy 125.247014 -265.48181) (xy 125.197839 -265.479829) (xy 125.14962 -265.469985)
			(xy 125.103604 -265.452533) (xy 125.060983 -265.427926) (xy 125.022862 -265.396801) (xy 124.990227 -265.359964)
			(xy 124.963924 -265.318368) (xy 124.944633 -265.273092) (xy 124.932856 -265.225308) (xy 124.928896 -265.176254)
			(xy 123.660154 -265.176254) (xy 123.659659 -265.200861) (xy 123.651764 -265.249438) (xy 123.63618 -265.296119)
			(xy 123.613309 -265.339696) (xy 123.583744 -265.37904) (xy 123.548251 -265.413132) (xy 123.507748 -265.441088)
			(xy 123.463286 -265.462186) (xy 123.416015 -265.475878) (xy 123.36716 -265.48181) (xy 123.317985 -265.479829)
			(xy 123.269766 -265.469985) (xy 123.22375 -265.452533) (xy 123.181129 -265.427926) (xy 123.143008 -265.396801)
			(xy 123.110373 -265.359964) (xy 123.08407 -265.318368) (xy 123.064779 -265.273092) (xy 123.053002 -265.225308)
			(xy 123.049042 -265.176254) (xy 121.780046 -265.176254) (xy 121.779551 -265.200861) (xy 121.771656 -265.249438)
			(xy 121.756072 -265.296119) (xy 121.733201 -265.339696) (xy 121.703636 -265.37904) (xy 121.668143 -265.413132)
			(xy 121.62764 -265.441088) (xy 121.583178 -265.462186) (xy 121.535907 -265.475878) (xy 121.487052 -265.48181)
			(xy 121.437877 -265.479829) (xy 121.389658 -265.469985) (xy 121.343642 -265.452533) (xy 121.301021 -265.427926)
			(xy 121.2629 -265.396801) (xy 121.230265 -265.359964) (xy 121.203962 -265.318368) (xy 121.184671 -265.273092)
			(xy 121.172894 -265.225308) (xy 121.168934 -265.176254) (xy 111.719063 -265.176254) (xy 111.71882 -265.176386)
			(xy 111.669267 -265.194184) (xy 111.617577 -265.204208) (xy 111.564963 -265.206225) (xy 111.512658 -265.200187)
			(xy 111.461887 -265.186235) (xy 111.413842 -265.164696) (xy 111.369647 -265.136076) (xy 111.330339 -265.101045)
			(xy 111.296839 -265.060424) (xy 111.269933 -265.015165) (xy 111.25025 -264.96633) (xy 111.238253 -264.915062)
			(xy 111.234223 -264.862564) (xy 101.0666 -264.862564) (xy 101.0666 -265.018774) (xy 101.069394 -265.030204)
			(xy 101.072188 -265.035792) (xy 101.082965 -265.057623) (xy 101.098231 -265.103851) (xy 101.105989 -265.151913)
			(xy 101.106478 -265.176254) (xy 101.435166 -265.176254) (xy 101.439126 -265.1272) (xy 101.450903 -265.079416)
			(xy 101.470194 -265.03414) (xy 101.496497 -264.992544) (xy 101.529132 -264.955707) (xy 101.567253 -264.924582)
			(xy 101.609874 -264.899975) (xy 101.65589 -264.882523) (xy 101.704109 -264.872679) (xy 101.753284 -264.870698)
			(xy 101.802139 -264.87663) (xy 101.84941 -264.890322) (xy 101.893872 -264.91142) (xy 101.934375 -264.939376)
			(xy 101.969868 -264.973468) (xy 101.999433 -265.012812) (xy 102.022304 -265.056389) (xy 102.037888 -265.10307)
			(xy 102.045783 -265.151647) (xy 102.046278 -265.176254) (xy 102.045783 -265.200861) (xy 102.037888 -265.249438)
			(xy 102.022304 -265.296119) (xy 101.999433 -265.339696) (xy 101.969868 -265.37904) (xy 101.934375 -265.413132)
			(xy 101.893872 -265.441088) (xy 101.84941 -265.462186) (xy 101.802139 -265.475878) (xy 101.753284 -265.48181)
			(xy 101.704109 -265.479829) (xy 101.65589 -265.469985) (xy 101.609874 -265.452533) (xy 101.567253 -265.427926)
			(xy 101.529132 -265.396801) (xy 101.496497 -265.359964) (xy 101.470194 -265.318368) (xy 101.450903 -265.273092)
			(xy 101.439126 -265.225308) (xy 101.435166 -265.176254) (xy 101.106478 -265.176254) (xy 101.106011 -265.200599)
			(xy 101.098283 -265.248671) (xy 101.083001 -265.2949) (xy 101.072188 -265.316716) (xy 101.069394 -265.322304)
			(xy 101.0666 -265.333734) (xy 101.0666 -265.98626) (xy 101.90532 -265.98626) (xy 101.90928 -265.937206)
			(xy 101.921057 -265.889422) (xy 101.940348 -265.844146) (xy 101.966651 -265.80255) (xy 101.999286 -265.765713)
			(xy 102.037407 -265.734588) (xy 102.080028 -265.709981) (xy 102.126044 -265.692529) (xy 102.174263 -265.682685)
			(xy 102.223438 -265.680704) (xy 102.272293 -265.686636) (xy 102.319564 -265.700328) (xy 102.364026 -265.721426)
			(xy 102.404529 -265.749382) (xy 102.440022 -265.783474) (xy 102.469587 -265.822818) (xy 102.492458 -265.866395)
			(xy 102.508042 -265.913076) (xy 102.515937 -265.961653) (xy 102.516432 -265.98626) (xy 102.515937 -266.010867)
			(xy 102.508042 -266.059444) (xy 102.492458 -266.106125) (xy 102.469587 -266.149702) (xy 102.440022 -266.189046)
			(xy 102.404529 -266.223138) (xy 102.364026 -266.251094) (xy 102.319564 -266.272192) (xy 102.272293 -266.285884)
			(xy 102.223438 -266.291816) (xy 102.174263 -266.289835) (xy 102.126044 -266.279991) (xy 102.080028 -266.262539)
			(xy 102.037407 -266.237932) (xy 101.999286 -266.206807) (xy 101.966651 -266.16997) (xy 101.940348 -266.128374)
			(xy 101.921057 -266.083098) (xy 101.90928 -266.035314) (xy 101.90532 -265.98626) (xy 101.0666 -265.98626)
			(xy 101.0666 -266.328398) (xy 101.067056 -266.338277) (xy 101.074495 -266.35658) (xy 101.081078 -266.363958)
			(xy 101.081332 -266.364212) (xy 101.342444 -266.625324) (xy 101.350568 -266.632693) (xy 101.371104 -266.640333)
			(xy 101.382068 -266.640056) (xy 101.469698 -266.633706) (xy 101.489256 -266.623038) (xy 101.49586 -266.614148)
			(xy 101.510382 -266.595389) (xy 101.544245 -266.562169) (xy 101.582832 -266.534577) (xy 101.625219 -266.513277)
			(xy 101.670387 -266.498779) (xy 101.717252 -266.491432) (xy 101.74097 -266.490958) (xy 101.764657 -266.49141)
			(xy 101.811462 -266.498735) (xy 101.856574 -266.513199) (xy 101.898912 -266.534454) (xy 101.937461 -266.561992)
			(xy 101.971296 -266.595151) (xy 101.999606 -266.633137) (xy 102.021711 -266.675038) (xy 102.037081 -266.719849)
			(xy 102.045349 -266.766497) (xy 102.046278 -266.79017) (xy 102.046278 -266.79652) (xy 102.045679 -266.82348)
			(xy 102.036168 -266.876556) (xy 102.017496 -266.927142) (xy 102.004368 -266.950698) (xy 101.99751 -266.962636)
			(xy 101.997256 -266.989814) (xy 102.047802 -267.078206) (xy 102.052528 -267.085827) (xy 102.066204 -267.097408)
			(xy 102.083037 -267.10356) (xy 102.091998 -267.10386) (xy 103.234998 -267.10386) (xy 103.244878 -267.103405)
			(xy 103.263187 -267.095973) (xy 103.270558 -267.089382) (xy 103.270812 -267.089128) (xy 103.349044 -267.010896)
			(xy 103.356507 -267.002578) (xy 103.364074 -266.981578) (xy 103.362063 -266.959346) (xy 103.356918 -266.949428)
			(xy 103.343983 -266.925997) (xy 103.325629 -266.875725) (xy 103.316312 -266.823025) (xy 103.31577 -266.796266)
			(xy 103.316243 -266.772276) (xy 103.323753 -266.724887) (xy 103.338583 -266.679256) (xy 103.360368 -266.636507)
			(xy 103.388572 -266.597691) (xy 103.4225 -266.563764) (xy 103.461317 -266.535562) (xy 103.504067 -266.513779)
			(xy 103.549699 -266.498951) (xy 103.597088 -266.491442) (xy 103.621078 -266.490958) (xy 103.647837 -266.49151)
			(xy 103.700537 -266.500822) (xy 103.750812 -266.519166) (xy 103.77424 -266.532106) (xy 103.784167 -266.537255)
			(xy 103.806407 -266.539308) (xy 103.827421 -266.531737) (xy 103.835708 -266.524232) (xy 103.953056 -266.406884)
			(xy 103.960856 -266.39827) (xy 103.968384 -266.376311) (xy 103.967534 -266.36472) (xy 103.956358 -266.273534)
			(xy 103.943658 -266.253976) (xy 103.933498 -266.24788) (xy 103.911325 -266.233909) (xy 103.871694 -266.199624)
			(xy 103.8385 -266.159075) (xy 103.812719 -266.113453) (xy 103.795106 -266.064099) (xy 103.786181 -266.012462)
			(xy 103.78567 -265.98626) (xy 103.786144 -265.96227) (xy 103.793655 -265.914882) (xy 103.808485 -265.869252)
			(xy 103.830271 -265.826503) (xy 103.858474 -265.787688) (xy 103.892402 -265.753762) (xy 103.931219 -265.725561)
			(xy 103.973969 -265.703778) (xy 104.0196 -265.68895) (xy 104.066988 -265.681442) (xy 104.090978 -265.680952)
			(xy 104.114713 -265.681408) (xy 104.161609 -265.688767) (xy 104.206801 -265.703293) (xy 104.249201 -265.724639)
			(xy 104.287787 -265.752289) (xy 104.321629 -265.785577) (xy 104.349912 -265.823701) (xy 104.371955 -265.865743)
			(xy 104.387226 -265.910689) (xy 104.395357 -265.957457) (xy 104.396286 -265.98118) (xy 104.396286 -265.98626)
			(xy 105.665282 -265.98626) (xy 105.669242 -265.937206) (xy 105.681019 -265.889422) (xy 105.70031 -265.844146)
			(xy 105.726613 -265.80255) (xy 105.759248 -265.765713) (xy 105.797369 -265.734588) (xy 105.83999 -265.709981)
			(xy 105.886006 -265.692529) (xy 105.934225 -265.682685) (xy 105.9834 -265.680704) (xy 106.032255 -265.686636)
			(xy 106.079526 -265.700328) (xy 106.123988 -265.721426) (xy 106.164491 -265.749382) (xy 106.199984 -265.783474)
			(xy 106.229549 -265.822818) (xy 106.25242 -265.866395) (xy 106.268004 -265.913076) (xy 106.275899 -265.961653)
			(xy 106.276394 -265.98626) (xy 106.275899 -266.010867) (xy 106.268004 -266.059444) (xy 106.25242 -266.106125)
			(xy 106.229549 -266.149702) (xy 106.199984 -266.189046) (xy 106.164491 -266.223138) (xy 106.123988 -266.251094)
			(xy 106.079526 -266.272192) (xy 106.032255 -266.285884) (xy 105.9834 -266.291816) (xy 105.934225 -266.289835)
			(xy 105.886006 -266.279991) (xy 105.83999 -266.262539) (xy 105.797369 -266.237932) (xy 105.759248 -266.206807)
			(xy 105.726613 -266.16997) (xy 105.70031 -266.128374) (xy 105.681019 -266.083098) (xy 105.669242 -266.035314)
			(xy 105.665282 -265.98626) (xy 104.396286 -265.98626) (xy 104.395894 -266.00894) (xy 104.389219 -266.053806)
			(xy 104.375967 -266.097187) (xy 104.366568 -266.117832) (xy 104.360726 -266.12977) (xy 104.36225 -266.155678)
			(xy 104.415336 -266.239498) (xy 104.420188 -266.246536) (xy 104.433581 -266.257143) (xy 104.449719 -266.262748)
			(xy 104.458262 -266.26312) (xy 105.279698 -266.26312) (xy 105.289768 -266.263543) (xy 105.308371 -266.271259)
			(xy 105.315766 -266.278106) (xy 105.517696 -266.480036) (xy 105.523634 -266.485465) (xy 105.537997 -266.492693)
			(xy 105.54589 -266.49426) (xy 105.546144 -266.49426) (xy 105.570127 -266.498329) (xy 105.616481 -266.513069)
			(xy 105.659914 -266.53497) (xy 105.699326 -266.563478) (xy 105.733721 -266.597872) (xy 105.762229 -266.637284)
			(xy 105.78413 -266.680716) (xy 105.79887 -266.727071) (xy 105.802938 -266.751054) (xy 105.802938 -266.751308)
			(xy 105.804423 -266.759227) (xy 105.811673 -266.773605) (xy 105.817162 -266.779502) (xy 106.108754 -267.071094)
			(xy 106.109262 -267.071602) (xy 106.116641 -267.078188) (xy 106.134941 -267.085643) (xy 106.144822 -267.08608)
			(xy 106.938318 -267.08608) (xy 106.948195 -267.08562) (xy 106.966491 -267.078174) (xy 106.973878 -267.071602)
			(xy 106.974132 -267.071348) (xy 107.095544 -266.949936) (xy 107.101894 -266.920726) (xy 107.096306 -266.906502)
			(xy 107.086732 -266.879953) (xy 107.07638 -266.824481) (xy 107.075732 -266.796266) (xy 107.076181 -266.772276)
			(xy 107.083692 -266.724887) (xy 107.098524 -266.679256) (xy 107.120312 -266.636508) (xy 107.148519 -266.597694)
			(xy 107.18245 -266.563771) (xy 107.221271 -266.535573) (xy 107.264025 -266.513796) (xy 107.309659 -266.498975)
			(xy 107.35705 -266.491475) (xy 107.38104 -266.490958) (xy 107.409254 -266.491609) (xy 107.464724 -266.501968)
			(xy 107.491276 -266.511532) (xy 107.5055 -266.51712) (xy 107.53471 -266.51077) (xy 107.669076 -266.376404)
			(xy 107.670854 -266.374626) (xy 107.6774 -266.366772) (xy 107.684214 -266.347512) (xy 107.684062 -266.337288)
			(xy 107.678982 -266.250674) (xy 107.669076 -266.231878) (xy 107.660694 -266.22502) (xy 107.64307 -266.210457)
			(xy 107.611963 -266.176955) (xy 107.586198 -266.13919) (xy 107.56635 -266.098006) (xy 107.552864 -266.054323)
			(xy 107.54604 -266.009118) (xy 107.545632 -265.98626) (xy 107.546154 -265.961005) (xy 107.554467 -265.911183)
			(xy 107.570868 -265.863409) (xy 107.594909 -265.818986) (xy 107.625933 -265.779126) (xy 107.663095 -265.744916)
			(xy 107.705381 -265.71729) (xy 107.751637 -265.697) (xy 107.800602 -265.6846) (xy 107.85094 -265.680429)
			(xy 107.901278 -265.6846) (xy 107.950243 -265.697) (xy 107.996499 -265.71729) (xy 108.038785 -265.744916)
			(xy 108.075947 -265.779126) (xy 108.106971 -265.818986) (xy 108.131012 -265.863409) (xy 108.147413 -265.911183)
			(xy 108.155726 -265.961005) (xy 108.156248 -265.98626) (xy 109.425244 -265.98626) (xy 109.429204 -265.937206)
			(xy 109.440981 -265.889422) (xy 109.460272 -265.844146) (xy 109.486575 -265.80255) (xy 109.51921 -265.765713)
			(xy 109.557331 -265.734588) (xy 109.599952 -265.709981) (xy 109.645968 -265.692529) (xy 109.694187 -265.682685)
			(xy 109.743362 -265.680704) (xy 109.792217 -265.686636) (xy 109.839488 -265.700328) (xy 109.88395 -265.721426)
			(xy 109.924453 -265.749382) (xy 109.959946 -265.783474) (xy 109.989511 -265.822818) (xy 110.012382 -265.866395)
			(xy 110.027966 -265.913076) (xy 110.035861 -265.961653) (xy 110.036356 -265.98626) (xy 110.035861 -266.010867)
			(xy 110.027966 -266.059444) (xy 110.012382 -266.106125) (xy 109.989511 -266.149702) (xy 109.959946 -266.189046)
			(xy 109.924453 -266.223138) (xy 109.88395 -266.251094) (xy 109.839488 -266.272192) (xy 109.792217 -266.285884)
			(xy 109.743362 -266.291816) (xy 109.694187 -266.289835) (xy 109.645968 -266.279991) (xy 109.599952 -266.262539)
			(xy 109.557331 -266.237932) (xy 109.51921 -266.206807) (xy 109.486575 -266.16997) (xy 109.460272 -266.128374)
			(xy 109.440981 -266.083098) (xy 109.429204 -266.035314) (xy 109.425244 -265.98626) (xy 108.156248 -265.98626)
			(xy 108.155854 -266.008764) (xy 108.14925 -266.053285) (xy 108.136166 -266.096349) (xy 108.116887 -266.137018)
			(xy 108.104686 -266.155932) (xy 108.096812 -266.167616) (xy 108.095542 -266.195556) (xy 108.144564 -266.286996)
			(xy 108.149223 -266.294949) (xy 108.163058 -266.307105) (xy 108.180311 -266.313545) (xy 108.189522 -266.31392)
			(xy 109.102398 -266.31392) (xy 109.112468 -266.314343) (xy 109.131071 -266.322059) (xy 109.138466 -266.328906)
			(xy 109.29747 -266.48791) (xy 109.310678 -266.494768) (xy 109.318298 -266.496292) (xy 109.343805 -266.501693)
			(xy 109.392615 -266.520008) (xy 109.437608 -266.546344) (xy 109.477477 -266.579934) (xy 109.511066 -266.619806)
			(xy 109.537399 -266.6648) (xy 109.555711 -266.713611) (xy 109.561122 -266.739116) (xy 109.562646 -266.746736)
			(xy 109.569504 -266.759944) (xy 109.847634 -267.038074) (xy 109.848142 -267.038582) (xy 109.855524 -267.045163)
			(xy 109.873823 -267.052613) (xy 109.883702 -267.05306) (xy 110.743238 -267.05306) (xy 110.753115 -267.052598)
			(xy 110.771413 -267.045156) (xy 110.778798 -267.038582) (xy 110.779052 -267.038328) (xy 111.432594 -266.384786)
			(xy 111.439988 -266.377929) (xy 111.458587 -266.370179) (xy 111.468662 -266.3698) (xy 113.19129 -266.3698)
			(xy 113.201225 -266.369325) (xy 113.2196 -266.361764) (xy 113.233712 -266.347775) (xy 113.238026 -266.338812)
			(xy 113.280698 -266.23899) (xy 113.27511 -266.209018) (xy 113.264442 -266.197842) (xy 113.24857 -266.180665)
			(xy 113.221704 -266.142386) (xy 113.200986 -266.100459) (xy 113.186902 -266.055864) (xy 113.179779 -266.009643)
			(xy 113.179352 -265.98626) (xy 113.179874 -265.961005) (xy 113.188187 -265.911183) (xy 113.204588 -265.863409)
			(xy 113.228629 -265.818986) (xy 113.259653 -265.779126) (xy 113.296815 -265.744916) (xy 113.339101 -265.71729)
			(xy 113.385357 -265.697) (xy 113.434322 -265.6846) (xy 113.48466 -265.680429) (xy 113.534998 -265.6846)
			(xy 113.583963 -265.697) (xy 113.630219 -265.71729) (xy 113.672505 -265.744916) (xy 113.709667 -265.779126)
			(xy 113.740691 -265.818986) (xy 113.764732 -265.863409) (xy 113.781133 -265.911183) (xy 113.789446 -265.961005)
			(xy 113.789968 -265.98626) (xy 113.789519 -266.009641) (xy 113.782388 -266.055855) (xy 113.768301 -266.100445)
			(xy 113.747586 -266.142368) (xy 113.720728 -266.180648) (xy 113.704878 -266.197842) (xy 113.69421 -266.209018)
			(xy 113.688622 -266.23899) (xy 113.731294 -266.338812) (xy 113.735614 -266.347765) (xy 113.749738 -266.361723)
			(xy 113.768102 -266.369281) (xy 113.77803 -266.3698) (xy 115.071398 -266.3698) (xy 115.081332 -266.369324)
			(xy 115.099705 -266.36176) (xy 115.113815 -266.347772) (xy 115.118134 -266.338812) (xy 115.160806 -266.23899)
			(xy 115.155218 -266.209018) (xy 115.14455 -266.197842) (xy 115.128677 -266.180665) (xy 115.101811 -266.142386)
			(xy 115.081093 -266.100459) (xy 115.067008 -266.055864) (xy 115.059885 -266.009643) (xy 115.05946 -265.98626)
			(xy 115.059982 -265.961005) (xy 115.068295 -265.911183) (xy 115.084696 -265.863409) (xy 115.108737 -265.818986)
			(xy 115.139761 -265.779126) (xy 115.176923 -265.744916) (xy 115.219209 -265.71729) (xy 115.265465 -265.697)
			(xy 115.31443 -265.6846) (xy 115.364768 -265.680429) (xy 115.415106 -265.6846) (xy 115.464071 -265.697)
			(xy 115.510327 -265.71729) (xy 115.552613 -265.744916) (xy 115.589775 -265.779126) (xy 115.620799 -265.818986)
			(xy 115.64484 -265.863409) (xy 115.661241 -265.911183) (xy 115.669554 -265.961005) (xy 115.670076 -265.98626)
			(xy 116.938818 -265.98626) (xy 116.942778 -265.937206) (xy 116.954555 -265.889422) (xy 116.973846 -265.844146)
			(xy 117.000149 -265.80255) (xy 117.032784 -265.765713) (xy 117.070905 -265.734588) (xy 117.113526 -265.709981)
			(xy 117.159542 -265.692529) (xy 117.207761 -265.682685) (xy 117.256936 -265.680704) (xy 117.305791 -265.686636)
			(xy 117.353062 -265.700328) (xy 117.397524 -265.721426) (xy 117.438027 -265.749382) (xy 117.47352 -265.783474)
			(xy 117.503085 -265.822818) (xy 117.525956 -265.866395) (xy 117.54154 -265.913076) (xy 117.549435 -265.961653)
			(xy 117.54993 -265.98626) (xy 117.549435 -266.010867) (xy 117.54154 -266.059444) (xy 117.525956 -266.106125)
			(xy 117.503085 -266.149702) (xy 117.47352 -266.189046) (xy 117.438027 -266.223138) (xy 117.397524 -266.251094)
			(xy 117.353062 -266.272192) (xy 117.305791 -266.285884) (xy 117.256936 -266.291816) (xy 117.207761 -266.289835)
			(xy 117.159542 -266.279991) (xy 117.113526 -266.262539) (xy 117.070905 -266.237932) (xy 117.032784 -266.206807)
			(xy 117.000149 -266.16997) (xy 116.973846 -266.128374) (xy 116.954555 -266.083098) (xy 116.942778 -266.035314)
			(xy 116.938818 -265.98626) (xy 115.670076 -265.98626) (xy 115.669627 -266.009641) (xy 115.662496 -266.055856)
			(xy 115.648409 -266.100445) (xy 115.627695 -266.142369) (xy 115.600838 -266.180649) (xy 115.584986 -266.197842)
			(xy 115.574318 -266.209018) (xy 115.56873 -266.23899) (xy 115.611402 -266.338812) (xy 115.615722 -266.347763)
			(xy 115.629847 -266.36172) (xy 115.64821 -266.369275) (xy 115.658138 -266.3698) (xy 115.729258 -266.3698)
			(xy 115.739323 -266.370234) (xy 115.757913 -266.377963) (xy 115.765326 -266.384786) (xy 115.867688 -266.487148)
			(xy 115.881404 -266.49426) (xy 115.889024 -266.495784) (xy 115.914976 -266.501048) (xy 115.964675 -266.519309)
			(xy 116.010483 -266.545864) (xy 116.051026 -266.579919) (xy 116.085092 -266.620454) (xy 116.111658 -266.666255)
			(xy 116.129931 -266.71595) (xy 116.13515 -266.74191) (xy 116.136674 -266.74953) (xy 116.143786 -266.763246)
			(xy 116.421154 -267.040614) (xy 116.421662 -267.041122) (xy 116.429042 -267.047706) (xy 116.447342 -267.055158)
			(xy 116.457222 -267.0556) (xy 117.375178 -267.0556) (xy 117.38505 -267.055129) (xy 117.403333 -267.047671)
			(xy 117.410738 -267.041122) (xy 117.410992 -267.040868) (xy 117.44198 -267.00988) (xy 117.449436 -267.001615)
			(xy 117.457056 -266.980727) (xy 117.45518 -266.958572) (xy 117.450108 -266.948666) (xy 117.450108 -266.948412)
			(xy 117.437347 -266.925059) (xy 117.419216 -266.87503) (xy 117.41002 -266.822618) (xy 117.409468 -266.796012)
			(xy 117.409468 -266.790424) (xy 117.410493 -266.764423) (xy 117.420294 -266.713322) (xy 117.438612 -266.664621)
			(xy 117.464917 -266.619728) (xy 117.498449 -266.579941) (xy 117.538237 -266.546412) (xy 117.583131 -266.520108)
			(xy 117.631832 -266.501792) (xy 117.682933 -266.491992) (xy 117.708934 -266.490958) (xy 117.714522 -266.490958)
			(xy 117.741129 -266.491512) (xy 117.793543 -266.500697) (xy 117.843568 -266.518837) (xy 117.866922 -266.531598)
			(xy 117.867176 -266.531598) (xy 117.877088 -266.536678) (xy 117.899249 -266.538608) (xy 117.920135 -266.530948)
			(xy 117.92839 -266.52347) (xy 118.102634 -266.349226) (xy 118.110033 -266.342382) (xy 118.128631 -266.334656)
			(xy 118.138702 -266.33424) (xy 118.80088 -266.33424) (xy 118.810311 -266.333865) (xy 118.827896 -266.327048)
			(xy 118.841824 -266.31433) (xy 118.846346 -266.306046) (xy 118.893336 -266.211304) (xy 118.890542 -266.182602)
			(xy 118.881652 -266.170918) (xy 118.867022 -266.150878) (xy 118.843776 -266.107046) (xy 118.827932 -266.060029)
			(xy 118.819907 -266.011067) (xy 118.819422 -265.98626) (xy 118.819422 -265.978894) (xy 118.82043 -265.955282)
			(xy 118.828829 -265.908775) (xy 118.844294 -265.864118) (xy 118.866457 -265.822378) (xy 118.894788 -265.784552)
			(xy 118.92861 -265.751544) (xy 118.967115 -265.724143) (xy 119.009382 -265.703004) (xy 119.054403 -265.68863)
			(xy 119.1011 -265.681367) (xy 119.12473 -265.680952) (xy 119.148721 -265.681425) (xy 119.196111 -265.688934)
			(xy 119.241744 -265.703764) (xy 119.284495 -265.725548) (xy 119.323313 -265.753752) (xy 119.357242 -265.787679)
			(xy 119.385446 -265.826496) (xy 119.407232 -265.869247) (xy 119.422063 -265.914879) (xy 119.429574 -265.962269)
			(xy 119.430038 -265.98626) (xy 120.699034 -265.98626) (xy 120.702994 -265.937206) (xy 120.714771 -265.889422)
			(xy 120.734062 -265.844146) (xy 120.760365 -265.80255) (xy 120.793 -265.765713) (xy 120.831121 -265.734588)
			(xy 120.873742 -265.709981) (xy 120.919758 -265.692529) (xy 120.967977 -265.682685) (xy 121.017152 -265.680704)
			(xy 121.066007 -265.686636) (xy 121.113278 -265.700328) (xy 121.15774 -265.721426) (xy 121.198243 -265.749382)
			(xy 121.233736 -265.783474) (xy 121.263301 -265.822818) (xy 121.286172 -265.866395) (xy 121.301756 -265.913076)
			(xy 121.309651 -265.961653) (xy 121.310146 -265.98626) (xy 121.309651 -266.010867) (xy 121.301756 -266.059444)
			(xy 121.286172 -266.106125) (xy 121.263301 -266.149702) (xy 121.233736 -266.189046) (xy 121.198243 -266.223138)
			(xy 121.15774 -266.251094) (xy 121.113278 -266.272192) (xy 121.066007 -266.285884) (xy 121.017152 -266.291816)
			(xy 120.967977 -266.289835) (xy 120.919758 -266.279991) (xy 120.873742 -266.262539) (xy 120.831121 -266.237932)
			(xy 120.793 -266.206807) (xy 120.760365 -266.16997) (xy 120.734062 -266.128374) (xy 120.714771 -266.083098)
			(xy 120.702994 -266.035314) (xy 120.699034 -265.98626) (xy 119.430038 -265.98626) (xy 119.429522 -266.011395)
			(xy 119.421278 -266.060984) (xy 119.405023 -266.108553) (xy 119.381195 -266.152817) (xy 119.35044 -266.19258)
			(xy 119.313586 -266.226768) (xy 119.292878 -266.241022) (xy 119.28221 -266.248134) (xy 119.270018 -266.270486)
			(xy 119.270018 -266.28344) (xy 119.270513 -266.293441) (xy 119.27818 -266.311916) (xy 119.292333 -266.326052)
			(xy 119.310816 -266.333698) (xy 119.320818 -266.33424) (xy 119.328438 -266.33424) (xy 119.337582 -266.33805)
			(xy 119.342144 -266.34006) (xy 119.350454 -266.345563) (xy 119.354092 -266.348972) (xy 119.497348 -266.492228)
			(xy 119.521732 -266.499594) (xy 119.534178 -266.497054) (xy 119.54913 -266.494212) (xy 119.579412 -266.491156)
			(xy 119.59463 -266.490958) (xy 119.618621 -266.491431) (xy 119.666011 -266.49894) (xy 119.711643 -266.51377)
			(xy 119.754394 -266.535555) (xy 119.793211 -266.563758) (xy 119.827139 -266.597686) (xy 119.855343 -266.636503)
			(xy 119.877128 -266.679253) (xy 119.891959 -266.724885) (xy 119.899469 -266.772275) (xy 119.899938 -266.796266)
			(xy 119.899735 -266.811484) (xy 119.89668 -266.841766) (xy 119.893842 -266.856718) (xy 119.891302 -266.869164)
			(xy 119.898668 -266.893548) (xy 120.096534 -267.091414) (xy 120.097042 -267.091922) (xy 120.104421 -267.098509)
			(xy 120.12272 -267.105969) (xy 120.132602 -267.1064) (xy 120.898158 -267.1064) (xy 120.908032 -267.105933)
			(xy 120.92632 -267.098479) (xy 120.933718 -267.091922) (xy 120.933972 -267.091668) (xy 121.164604 -266.861036)
			(xy 121.172224 -266.839954) (xy 121.170954 -266.82827) (xy 121.16943 -266.796266) (xy 121.169879 -266.772276)
			(xy 121.17739 -266.724887) (xy 121.192222 -266.679256) (xy 121.21401 -266.636507) (xy 121.242217 -266.597693)
			(xy 121.276148 -266.56377) (xy 121.314969 -266.535572) (xy 121.357722 -266.513794) (xy 121.403357 -266.498973)
			(xy 121.450748 -266.491473) (xy 121.474738 -266.490958) (xy 121.506742 -266.492482) (xy 121.518426 -266.493752)
			(xy 121.539508 -266.486132) (xy 121.727214 -266.298426) (xy 121.734612 -266.291579) (xy 121.75321 -266.283846)
			(xy 121.763282 -266.28344) (xy 122.527822 -266.28344) (xy 122.536609 -266.283067) (xy 122.553144 -266.277109)
			(xy 122.566684 -266.265903) (xy 122.57151 -266.258548) (xy 122.616214 -266.183364) (xy 122.61945 -266.177514)
			(xy 122.623053 -266.164644) (xy 122.623326 -266.157964) (xy 122.623326 -266.144756) (xy 122.616976 -266.133072)
			(xy 122.605157 -266.110425) (xy 122.588404 -266.062169) (xy 122.579904 -266.0118) (xy 122.579384 -265.98626)
			(xy 122.579906 -265.961005) (xy 122.588219 -265.911183) (xy 122.60462 -265.863409) (xy 122.628661 -265.818986)
			(xy 122.659685 -265.779126) (xy 122.696847 -265.744916) (xy 122.739133 -265.71729) (xy 122.785389 -265.697)
			(xy 122.834354 -265.6846) (xy 122.884692 -265.680429) (xy 122.93503 -265.6846) (xy 122.983995 -265.697)
			(xy 123.030251 -265.71729) (xy 123.072537 -265.744916) (xy 123.109699 -265.779126) (xy 123.140723 -265.818986)
			(xy 123.164764 -265.863409) (xy 123.181165 -265.911183) (xy 123.189478 -265.961005) (xy 123.19 -265.98626)
			(xy 124.458996 -265.98626) (xy 124.462956 -265.937206) (xy 124.474733 -265.889422) (xy 124.494024 -265.844146)
			(xy 124.520327 -265.80255) (xy 124.552962 -265.765713) (xy 124.591083 -265.734588) (xy 124.633704 -265.709981)
			(xy 124.67972 -265.692529) (xy 124.727939 -265.682685) (xy 124.777114 -265.680704) (xy 124.825969 -265.686636)
			(xy 124.87324 -265.700328) (xy 124.917702 -265.721426) (xy 124.958205 -265.749382) (xy 124.993698 -265.783474)
			(xy 125.023263 -265.822818) (xy 125.046134 -265.866395) (xy 125.061718 -265.913076) (xy 125.069613 -265.961653)
			(xy 125.070108 -265.98626) (xy 126.33885 -265.98626) (xy 126.34281 -265.937206) (xy 126.354587 -265.889422)
			(xy 126.373878 -265.844146) (xy 126.400181 -265.80255) (xy 126.432816 -265.765713) (xy 126.470937 -265.734588)
			(xy 126.513558 -265.709981) (xy 126.559574 -265.692529) (xy 126.607793 -265.682685) (xy 126.656968 -265.680704)
			(xy 126.705823 -265.686636) (xy 126.753094 -265.700328) (xy 126.797556 -265.721426) (xy 126.838059 -265.749382)
			(xy 126.873552 -265.783474) (xy 126.903117 -265.822818) (xy 126.925988 -265.866395) (xy 126.941572 -265.913076)
			(xy 126.949467 -265.961653) (xy 126.949962 -265.98626) (xy 128.208527 -265.98626) (xy 128.212622 -265.935532)
			(xy 128.224801 -265.886118) (xy 128.244749 -265.839298) (xy 128.27195 -265.796284) (xy 128.305698 -265.75819)
			(xy 128.34512 -265.726003) (xy 128.389194 -265.700557) (xy 128.43678 -265.68251) (xy 128.486644 -265.67233)
			(xy 128.537496 -265.670281) (xy 128.588017 -265.676415) (xy 128.636901 -265.690575) (xy 128.68288 -265.712392)
			(xy 128.724764 -265.741302) (xy 128.761468 -265.776557) (xy 128.792041 -265.817243) (xy 128.815692 -265.862306)
			(xy 128.831808 -265.91058) (xy 128.839972 -265.960814) (xy 128.840484 -265.98626) (xy 129.159012 -265.98626)
			(xy 129.162972 -265.937206) (xy 129.174749 -265.889422) (xy 129.19404 -265.844146) (xy 129.220343 -265.80255)
			(xy 129.252978 -265.765713) (xy 129.291099 -265.734588) (xy 129.33372 -265.709981) (xy 129.379736 -265.692529)
			(xy 129.427955 -265.682685) (xy 129.47713 -265.680704) (xy 129.525985 -265.686636) (xy 129.573256 -265.700328)
			(xy 129.617718 -265.721426) (xy 129.658221 -265.749382) (xy 129.693714 -265.783474) (xy 129.723279 -265.822818)
			(xy 129.74615 -265.866395) (xy 129.761734 -265.913076) (xy 129.769629 -265.961653) (xy 129.770124 -265.98626)
			(xy 131.028435 -265.98626) (xy 131.03253 -265.935532) (xy 131.044709 -265.886118) (xy 131.064657 -265.839298)
			(xy 131.091858 -265.796284) (xy 131.125606 -265.75819) (xy 131.165028 -265.726003) (xy 131.209102 -265.700557)
			(xy 131.256688 -265.68251) (xy 131.306552 -265.67233) (xy 131.357404 -265.670281) (xy 131.407925 -265.676415)
			(xy 131.456809 -265.690575) (xy 131.502788 -265.712392) (xy 131.544672 -265.741302) (xy 131.581376 -265.776557)
			(xy 131.611949 -265.817243) (xy 131.6356 -265.862306) (xy 131.651716 -265.91058) (xy 131.65988 -265.960814)
			(xy 131.660392 -265.98626) (xy 131.97892 -265.98626) (xy 131.98288 -265.937206) (xy 131.994657 -265.889422)
			(xy 132.013948 -265.844146) (xy 132.040251 -265.80255) (xy 132.072886 -265.765713) (xy 132.111007 -265.734588)
			(xy 132.153628 -265.709981) (xy 132.199644 -265.692529) (xy 132.247863 -265.682685) (xy 132.297038 -265.680704)
			(xy 132.345893 -265.686636) (xy 132.393164 -265.700328) (xy 132.437626 -265.721426) (xy 132.478129 -265.749382)
			(xy 132.513622 -265.783474) (xy 132.543187 -265.822818) (xy 132.566058 -265.866395) (xy 132.581642 -265.913076)
			(xy 132.589537 -265.961653) (xy 132.590032 -265.98626) (xy 132.918974 -265.98626) (xy 132.922934 -265.937206)
			(xy 132.934711 -265.889422) (xy 132.954002 -265.844146) (xy 132.980305 -265.80255) (xy 133.01294 -265.765713)
			(xy 133.051061 -265.734588) (xy 133.093682 -265.709981) (xy 133.139698 -265.692529) (xy 133.187917 -265.682685)
			(xy 133.237092 -265.680704) (xy 133.285947 -265.686636) (xy 133.333218 -265.700328) (xy 133.37768 -265.721426)
			(xy 133.418183 -265.749382) (xy 133.453676 -265.783474) (xy 133.483241 -265.822818) (xy 133.506112 -265.866395)
			(xy 133.521696 -265.913076) (xy 133.529591 -265.961653) (xy 133.530086 -265.98626) (xy 133.859028 -265.98626)
			(xy 133.862988 -265.937206) (xy 133.874765 -265.889422) (xy 133.894056 -265.844146) (xy 133.920359 -265.80255)
			(xy 133.952994 -265.765713) (xy 133.991115 -265.734588) (xy 134.033736 -265.709981) (xy 134.079752 -265.692529)
			(xy 134.127971 -265.682685) (xy 134.177146 -265.680704) (xy 134.226001 -265.686636) (xy 134.273272 -265.700328)
			(xy 134.317734 -265.721426) (xy 134.358237 -265.749382) (xy 134.39373 -265.783474) (xy 134.423295 -265.822818)
			(xy 134.446166 -265.866395) (xy 134.46175 -265.913076) (xy 134.469645 -265.961653) (xy 134.47014 -265.98626)
			(xy 134.788397 -265.98626) (xy 134.792492 -265.935532) (xy 134.804671 -265.886118) (xy 134.824619 -265.839298)
			(xy 134.85182 -265.796284) (xy 134.885568 -265.75819) (xy 134.92499 -265.726003) (xy 134.969064 -265.700557)
			(xy 135.01665 -265.68251) (xy 135.066514 -265.67233) (xy 135.117366 -265.670281) (xy 135.167887 -265.676415)
			(xy 135.216771 -265.690575) (xy 135.26275 -265.712392) (xy 135.304634 -265.741302) (xy 135.341338 -265.776557)
			(xy 135.371911 -265.817243) (xy 135.395562 -265.862306) (xy 135.411678 -265.91058) (xy 135.419842 -265.960814)
			(xy 135.420354 -265.98626) (xy 135.738882 -265.98626) (xy 135.742842 -265.937206) (xy 135.754619 -265.889422)
			(xy 135.77391 -265.844146) (xy 135.800213 -265.80255) (xy 135.832848 -265.765713) (xy 135.870969 -265.734588)
			(xy 135.91359 -265.709981) (xy 135.959606 -265.692529) (xy 136.007825 -265.682685) (xy 136.057 -265.680704)
			(xy 136.105855 -265.686636) (xy 136.153126 -265.700328) (xy 136.197588 -265.721426) (xy 136.238091 -265.749382)
			(xy 136.273584 -265.783474) (xy 136.303149 -265.822818) (xy 136.32602 -265.866395) (xy 136.341604 -265.913076)
			(xy 136.349499 -265.961653) (xy 136.349994 -265.98626) (xy 137.608559 -265.98626) (xy 137.612654 -265.935532)
			(xy 137.624833 -265.886118) (xy 137.644781 -265.839298) (xy 137.671982 -265.796284) (xy 137.70573 -265.75819)
			(xy 137.745152 -265.726003) (xy 137.789226 -265.700557) (xy 137.836812 -265.68251) (xy 137.886676 -265.67233)
			(xy 137.937528 -265.670281) (xy 137.988049 -265.676415) (xy 138.036933 -265.690575) (xy 138.082912 -265.712392)
			(xy 138.124796 -265.741302) (xy 138.1615 -265.776557) (xy 138.192073 -265.817243) (xy 138.215724 -265.862306)
			(xy 138.23184 -265.91058) (xy 138.240004 -265.960814) (xy 138.240516 -265.98626) (xy 138.559044 -265.98626)
			(xy 138.563004 -265.937206) (xy 138.574781 -265.889422) (xy 138.594072 -265.844146) (xy 138.620375 -265.80255)
			(xy 138.65301 -265.765713) (xy 138.691131 -265.734588) (xy 138.733752 -265.709981) (xy 138.779768 -265.692529)
			(xy 138.827987 -265.682685) (xy 138.877162 -265.680704) (xy 138.926017 -265.686636) (xy 138.973288 -265.700328)
			(xy 139.01775 -265.721426) (xy 139.058253 -265.749382) (xy 139.093746 -265.783474) (xy 139.123311 -265.822818)
			(xy 139.146182 -265.866395) (xy 139.161766 -265.913076) (xy 139.169661 -265.961653) (xy 139.170156 -265.98626)
			(xy 139.498844 -265.98626) (xy 139.502804 -265.937206) (xy 139.514581 -265.889422) (xy 139.533872 -265.844146)
			(xy 139.560175 -265.80255) (xy 139.59281 -265.765713) (xy 139.630931 -265.734588) (xy 139.673552 -265.709981)
			(xy 139.719568 -265.692529) (xy 139.767787 -265.682685) (xy 139.816962 -265.680704) (xy 139.865817 -265.686636)
			(xy 139.913088 -265.700328) (xy 139.95755 -265.721426) (xy 139.998053 -265.749382) (xy 140.033546 -265.783474)
			(xy 140.063111 -265.822818) (xy 140.085982 -265.866395) (xy 140.101566 -265.913076) (xy 140.109461 -265.961653)
			(xy 140.109956 -265.98626) (xy 140.438898 -265.98626) (xy 140.442858 -265.937206) (xy 140.454635 -265.889422)
			(xy 140.473926 -265.844146) (xy 140.500229 -265.80255) (xy 140.532864 -265.765713) (xy 140.570985 -265.734588)
			(xy 140.613606 -265.709981) (xy 140.659622 -265.692529) (xy 140.707841 -265.682685) (xy 140.757016 -265.680704)
			(xy 140.805871 -265.686636) (xy 140.853142 -265.700328) (xy 140.897604 -265.721426) (xy 140.938107 -265.749382)
			(xy 140.9736 -265.783474) (xy 141.003165 -265.822818) (xy 141.026036 -265.866395) (xy 141.04162 -265.913076)
			(xy 141.049515 -265.961653) (xy 141.05001 -265.98626) (xy 141.368521 -265.98626) (xy 141.372616 -265.935532)
			(xy 141.384795 -265.886118) (xy 141.404743 -265.839298) (xy 141.431944 -265.796284) (xy 141.465692 -265.75819)
			(xy 141.505114 -265.726003) (xy 141.549188 -265.700557) (xy 141.596774 -265.68251) (xy 141.646638 -265.67233)
			(xy 141.69749 -265.670281) (xy 141.748011 -265.676415) (xy 141.796895 -265.690575) (xy 141.842874 -265.712392)
			(xy 141.884758 -265.741302) (xy 141.921462 -265.776557) (xy 141.952035 -265.817243) (xy 141.975686 -265.862306)
			(xy 141.991802 -265.91058) (xy 141.999966 -265.960814) (xy 142.000478 -265.98626) (xy 142.319006 -265.98626)
			(xy 142.322966 -265.937206) (xy 142.334743 -265.889422) (xy 142.354034 -265.844146) (xy 142.380337 -265.80255)
			(xy 142.412972 -265.765713) (xy 142.451093 -265.734588) (xy 142.493714 -265.709981) (xy 142.53973 -265.692529)
			(xy 142.587949 -265.682685) (xy 142.637124 -265.680704) (xy 142.685979 -265.686636) (xy 142.73325 -265.700328)
			(xy 142.777712 -265.721426) (xy 142.818215 -265.749382) (xy 142.853708 -265.783474) (xy 142.883273 -265.822818)
			(xy 142.906144 -265.866395) (xy 142.921728 -265.913076) (xy 142.929623 -265.961653) (xy 142.930118 -265.98626)
			(xy 143.258806 -265.98626) (xy 143.262766 -265.937206) (xy 143.274543 -265.889422) (xy 143.293834 -265.844146)
			(xy 143.320137 -265.80255) (xy 143.352772 -265.765713) (xy 143.390893 -265.734588) (xy 143.433514 -265.709981)
			(xy 143.47953 -265.692529) (xy 143.527749 -265.682685) (xy 143.576924 -265.680704) (xy 143.625779 -265.686636)
			(xy 143.67305 -265.700328) (xy 143.717512 -265.721426) (xy 143.758015 -265.749382) (xy 143.793508 -265.783474)
			(xy 143.823073 -265.822818) (xy 143.845944 -265.866395) (xy 143.861528 -265.913076) (xy 143.869423 -265.961653)
			(xy 143.869918 -265.98626) (xy 145.138914 -265.98626) (xy 145.142874 -265.937206) (xy 145.154651 -265.889422)
			(xy 145.173942 -265.844146) (xy 145.200245 -265.80255) (xy 145.23288 -265.765713) (xy 145.271001 -265.734588)
			(xy 145.313622 -265.709981) (xy 145.359638 -265.692529) (xy 145.407857 -265.682685) (xy 145.457032 -265.680704)
			(xy 145.505887 -265.686636) (xy 145.553158 -265.700328) (xy 145.59762 -265.721426) (xy 145.638123 -265.749382)
			(xy 145.673616 -265.783474) (xy 145.703181 -265.822818) (xy 145.726052 -265.866395) (xy 145.741636 -265.913076)
			(xy 145.749531 -265.961653) (xy 145.750026 -265.98626) (xy 145.749531 -266.010867) (xy 145.741636 -266.059444)
			(xy 145.726052 -266.106125) (xy 145.703181 -266.149702) (xy 145.676359 -266.185396) (xy 164.058615 -266.185396)
			(xy 164.06255 -266.131625) (xy 164.074273 -266.079001) (xy 164.093533 -266.028644) (xy 164.119919 -265.981627)
			(xy 164.152871 -265.938954) (xy 164.191684 -265.901533) (xy 164.235532 -265.870163) (xy 164.28348 -265.845511)
			(xy 164.334507 -265.828103) (xy 164.387525 -265.81831) (xy 164.441404 -265.816341) (xy 164.494995 -265.822238)
			(xy 164.547156 -265.835874) (xy 164.596776 -265.856961) (xy 164.642797 -265.885047) (xy 164.684239 -265.919535)
			(xy 164.720217 -265.959689) (xy 164.749965 -266.004653) (xy 164.77285 -266.05347) (xy 164.788382 -266.105099)
			(xy 164.796232 -266.158439) (xy 164.796724 -266.185396) (xy 164.796232 -266.212353) (xy 164.788382 -266.265693)
			(xy 164.77285 -266.317322) (xy 164.749965 -266.366139) (xy 164.720217 -266.411103) (xy 164.684239 -266.451257)
			(xy 164.642797 -266.485745) (xy 164.596776 -266.513831) (xy 164.547156 -266.534918) (xy 164.494995 -266.548554)
			(xy 164.441404 -266.554451) (xy 164.387525 -266.552482) (xy 164.334507 -266.542689) (xy 164.28348 -266.525281)
			(xy 164.235532 -266.500629) (xy 164.191684 -266.469259) (xy 164.152871 -266.431838) (xy 164.119919 -266.389165)
			(xy 164.093533 -266.342148) (xy 164.074273 -266.291791) (xy 164.06255 -266.239167) (xy 164.058615 -266.185396)
			(xy 145.676359 -266.185396) (xy 145.673616 -266.189046) (xy 145.638123 -266.223138) (xy 145.59762 -266.251094)
			(xy 145.553158 -266.272192) (xy 145.505887 -266.285884) (xy 145.457032 -266.291816) (xy 145.407857 -266.289835)
			(xy 145.359638 -266.279991) (xy 145.313622 -266.262539) (xy 145.271001 -266.237932) (xy 145.23288 -266.206807)
			(xy 145.200245 -266.16997) (xy 145.173942 -266.128374) (xy 145.154651 -266.083098) (xy 145.142874 -266.035314)
			(xy 145.138914 -265.98626) (xy 143.869918 -265.98626) (xy 143.869423 -266.010867) (xy 143.861528 -266.059444)
			(xy 143.845944 -266.106125) (xy 143.823073 -266.149702) (xy 143.793508 -266.189046) (xy 143.758015 -266.223138)
			(xy 143.717512 -266.251094) (xy 143.67305 -266.272192) (xy 143.625779 -266.285884) (xy 143.576924 -266.291816)
			(xy 143.527749 -266.289835) (xy 143.47953 -266.279991) (xy 143.433514 -266.262539) (xy 143.390893 -266.237932)
			(xy 143.352772 -266.206807) (xy 143.320137 -266.16997) (xy 143.293834 -266.128374) (xy 143.274543 -266.083098)
			(xy 143.262766 -266.035314) (xy 143.258806 -265.98626) (xy 142.930118 -265.98626) (xy 142.929623 -266.010867)
			(xy 142.921728 -266.059444) (xy 142.906144 -266.106125) (xy 142.883273 -266.149702) (xy 142.853708 -266.189046)
			(xy 142.818215 -266.223138) (xy 142.777712 -266.251094) (xy 142.73325 -266.272192) (xy 142.685979 -266.285884)
			(xy 142.637124 -266.291816) (xy 142.587949 -266.289835) (xy 142.53973 -266.279991) (xy 142.493714 -266.262539)
			(xy 142.451093 -266.237932) (xy 142.412972 -266.206807) (xy 142.380337 -266.16997) (xy 142.354034 -266.128374)
			(xy 142.334743 -266.083098) (xy 142.322966 -266.035314) (xy 142.319006 -265.98626) (xy 142.000478 -265.98626)
			(xy 141.999966 -266.011706) (xy 141.991802 -266.06194) (xy 141.975686 -266.110214) (xy 141.952035 -266.155277)
			(xy 141.921462 -266.195963) (xy 141.884758 -266.231218) (xy 141.842874 -266.260128) (xy 141.796895 -266.281945)
			(xy 141.748011 -266.296105) (xy 141.69749 -266.302239) (xy 141.646638 -266.30019) (xy 141.596774 -266.29001)
			(xy 141.549188 -266.271963) (xy 141.505114 -266.246517) (xy 141.465692 -266.21433) (xy 141.431944 -266.176236)
			(xy 141.404743 -266.133222) (xy 141.384795 -266.086402) (xy 141.372616 -266.036988) (xy 141.368521 -265.98626)
			(xy 141.05001 -265.98626) (xy 141.049515 -266.010867) (xy 141.04162 -266.059444) (xy 141.026036 -266.106125)
			(xy 141.003165 -266.149702) (xy 140.9736 -266.189046) (xy 140.938107 -266.223138) (xy 140.897604 -266.251094)
			(xy 140.853142 -266.272192) (xy 140.805871 -266.285884) (xy 140.757016 -266.291816) (xy 140.707841 -266.289835)
			(xy 140.659622 -266.279991) (xy 140.613606 -266.262539) (xy 140.570985 -266.237932) (xy 140.532864 -266.206807)
			(xy 140.500229 -266.16997) (xy 140.473926 -266.128374) (xy 140.454635 -266.083098) (xy 140.442858 -266.035314)
			(xy 140.438898 -265.98626) (xy 140.109956 -265.98626) (xy 140.109461 -266.010867) (xy 140.101566 -266.059444)
			(xy 140.085982 -266.106125) (xy 140.063111 -266.149702) (xy 140.033546 -266.189046) (xy 139.998053 -266.223138)
			(xy 139.95755 -266.251094) (xy 139.913088 -266.272192) (xy 139.865817 -266.285884) (xy 139.816962 -266.291816)
			(xy 139.767787 -266.289835) (xy 139.719568 -266.279991) (xy 139.673552 -266.262539) (xy 139.630931 -266.237932)
			(xy 139.59281 -266.206807) (xy 139.560175 -266.16997) (xy 139.533872 -266.128374) (xy 139.514581 -266.083098)
			(xy 139.502804 -266.035314) (xy 139.498844 -265.98626) (xy 139.170156 -265.98626) (xy 139.169661 -266.010867)
			(xy 139.161766 -266.059444) (xy 139.146182 -266.106125) (xy 139.123311 -266.149702) (xy 139.093746 -266.189046)
			(xy 139.058253 -266.223138) (xy 139.01775 -266.251094) (xy 138.973288 -266.272192) (xy 138.926017 -266.285884)
			(xy 138.877162 -266.291816) (xy 138.827987 -266.289835) (xy 138.779768 -266.279991) (xy 138.733752 -266.262539)
			(xy 138.691131 -266.237932) (xy 138.65301 -266.206807) (xy 138.620375 -266.16997) (xy 138.594072 -266.128374)
			(xy 138.574781 -266.083098) (xy 138.563004 -266.035314) (xy 138.559044 -265.98626) (xy 138.240516 -265.98626)
			(xy 138.240004 -266.011706) (xy 138.23184 -266.06194) (xy 138.215724 -266.110214) (xy 138.192073 -266.155277)
			(xy 138.1615 -266.195963) (xy 138.124796 -266.231218) (xy 138.082912 -266.260128) (xy 138.036933 -266.281945)
			(xy 137.988049 -266.296105) (xy 137.937528 -266.302239) (xy 137.886676 -266.30019) (xy 137.836812 -266.29001)
			(xy 137.789226 -266.271963) (xy 137.745152 -266.246517) (xy 137.70573 -266.21433) (xy 137.671982 -266.176236)
			(xy 137.644781 -266.133222) (xy 137.624833 -266.086402) (xy 137.612654 -266.036988) (xy 137.608559 -265.98626)
			(xy 136.349994 -265.98626) (xy 136.349499 -266.010867) (xy 136.341604 -266.059444) (xy 136.32602 -266.106125)
			(xy 136.303149 -266.149702) (xy 136.273584 -266.189046) (xy 136.238091 -266.223138) (xy 136.197588 -266.251094)
			(xy 136.153126 -266.272192) (xy 136.105855 -266.285884) (xy 136.057 -266.291816) (xy 136.007825 -266.289835)
			(xy 135.959606 -266.279991) (xy 135.91359 -266.262539) (xy 135.870969 -266.237932) (xy 135.832848 -266.206807)
			(xy 135.800213 -266.16997) (xy 135.77391 -266.128374) (xy 135.754619 -266.083098) (xy 135.742842 -266.035314)
			(xy 135.738882 -265.98626) (xy 135.420354 -265.98626) (xy 135.419842 -266.011706) (xy 135.411678 -266.06194)
			(xy 135.395562 -266.110214) (xy 135.371911 -266.155277) (xy 135.341338 -266.195963) (xy 135.304634 -266.231218)
			(xy 135.26275 -266.260128) (xy 135.216771 -266.281945) (xy 135.167887 -266.296105) (xy 135.117366 -266.302239)
			(xy 135.066514 -266.30019) (xy 135.01665 -266.29001) (xy 134.969064 -266.271963) (xy 134.92499 -266.246517)
			(xy 134.885568 -266.21433) (xy 134.85182 -266.176236) (xy 134.824619 -266.133222) (xy 134.804671 -266.086402)
			(xy 134.792492 -266.036988) (xy 134.788397 -265.98626) (xy 134.47014 -265.98626) (xy 134.469645 -266.010867)
			(xy 134.46175 -266.059444) (xy 134.446166 -266.106125) (xy 134.423295 -266.149702) (xy 134.39373 -266.189046)
			(xy 134.358237 -266.223138) (xy 134.317734 -266.251094) (xy 134.273272 -266.272192) (xy 134.226001 -266.285884)
			(xy 134.177146 -266.291816) (xy 134.127971 -266.289835) (xy 134.079752 -266.279991) (xy 134.033736 -266.262539)
			(xy 133.991115 -266.237932) (xy 133.952994 -266.206807) (xy 133.920359 -266.16997) (xy 133.894056 -266.128374)
			(xy 133.874765 -266.083098) (xy 133.862988 -266.035314) (xy 133.859028 -265.98626) (xy 133.530086 -265.98626)
			(xy 133.529591 -266.010867) (xy 133.521696 -266.059444) (xy 133.506112 -266.106125) (xy 133.483241 -266.149702)
			(xy 133.453676 -266.189046) (xy 133.418183 -266.223138) (xy 133.37768 -266.251094) (xy 133.333218 -266.272192)
			(xy 133.285947 -266.285884) (xy 133.237092 -266.291816) (xy 133.187917 -266.289835) (xy 133.139698 -266.279991)
			(xy 133.093682 -266.262539) (xy 133.051061 -266.237932) (xy 133.01294 -266.206807) (xy 132.980305 -266.16997)
			(xy 132.954002 -266.128374) (xy 132.934711 -266.083098) (xy 132.922934 -266.035314) (xy 132.918974 -265.98626)
			(xy 132.590032 -265.98626) (xy 132.589537 -266.010867) (xy 132.581642 -266.059444) (xy 132.566058 -266.106125)
			(xy 132.543187 -266.149702) (xy 132.513622 -266.189046) (xy 132.478129 -266.223138) (xy 132.437626 -266.251094)
			(xy 132.393164 -266.272192) (xy 132.345893 -266.285884) (xy 132.297038 -266.291816) (xy 132.247863 -266.289835)
			(xy 132.199644 -266.279991) (xy 132.153628 -266.262539) (xy 132.111007 -266.237932) (xy 132.072886 -266.206807)
			(xy 132.040251 -266.16997) (xy 132.013948 -266.128374) (xy 131.994657 -266.083098) (xy 131.98288 -266.035314)
			(xy 131.97892 -265.98626) (xy 131.660392 -265.98626) (xy 131.65988 -266.011706) (xy 131.651716 -266.06194)
			(xy 131.6356 -266.110214) (xy 131.611949 -266.155277) (xy 131.581376 -266.195963) (xy 131.544672 -266.231218)
			(xy 131.502788 -266.260128) (xy 131.456809 -266.281945) (xy 131.407925 -266.296105) (xy 131.357404 -266.302239)
			(xy 131.306552 -266.30019) (xy 131.256688 -266.29001) (xy 131.209102 -266.271963) (xy 131.165028 -266.246517)
			(xy 131.125606 -266.21433) (xy 131.091858 -266.176236) (xy 131.064657 -266.133222) (xy 131.044709 -266.086402)
			(xy 131.03253 -266.036988) (xy 131.028435 -265.98626) (xy 129.770124 -265.98626) (xy 129.769629 -266.010867)
			(xy 129.761734 -266.059444) (xy 129.74615 -266.106125) (xy 129.723279 -266.149702) (xy 129.693714 -266.189046)
			(xy 129.658221 -266.223138) (xy 129.617718 -266.251094) (xy 129.573256 -266.272192) (xy 129.525985 -266.285884)
			(xy 129.47713 -266.291816) (xy 129.427955 -266.289835) (xy 129.379736 -266.279991) (xy 129.33372 -266.262539)
			(xy 129.291099 -266.237932) (xy 129.252978 -266.206807) (xy 129.220343 -266.16997) (xy 129.19404 -266.128374)
			(xy 129.174749 -266.083098) (xy 129.162972 -266.035314) (xy 129.159012 -265.98626) (xy 128.840484 -265.98626)
			(xy 128.839972 -266.011706) (xy 128.831808 -266.06194) (xy 128.815692 -266.110214) (xy 128.792041 -266.155277)
			(xy 128.761468 -266.195963) (xy 128.724764 -266.231218) (xy 128.68288 -266.260128) (xy 128.636901 -266.281945)
			(xy 128.588017 -266.296105) (xy 128.537496 -266.302239) (xy 128.486644 -266.30019) (xy 128.43678 -266.29001)
			(xy 128.389194 -266.271963) (xy 128.34512 -266.246517) (xy 128.305698 -266.21433) (xy 128.27195 -266.176236)
			(xy 128.244749 -266.133222) (xy 128.224801 -266.086402) (xy 128.212622 -266.036988) (xy 128.208527 -265.98626)
			(xy 126.949962 -265.98626) (xy 126.949467 -266.010867) (xy 126.941572 -266.059444) (xy 126.925988 -266.106125)
			(xy 126.903117 -266.149702) (xy 126.873552 -266.189046) (xy 126.838059 -266.223138) (xy 126.797556 -266.251094)
			(xy 126.753094 -266.272192) (xy 126.705823 -266.285884) (xy 126.656968 -266.291816) (xy 126.607793 -266.289835)
			(xy 126.559574 -266.279991) (xy 126.513558 -266.262539) (xy 126.470937 -266.237932) (xy 126.432816 -266.206807)
			(xy 126.400181 -266.16997) (xy 126.373878 -266.128374) (xy 126.354587 -266.083098) (xy 126.34281 -266.035314)
			(xy 126.33885 -265.98626) (xy 125.070108 -265.98626) (xy 125.069613 -266.010867) (xy 125.061718 -266.059444)
			(xy 125.046134 -266.106125) (xy 125.023263 -266.149702) (xy 124.993698 -266.189046) (xy 124.958205 -266.223138)
			(xy 124.917702 -266.251094) (xy 124.87324 -266.272192) (xy 124.825969 -266.285884) (xy 124.777114 -266.291816)
			(xy 124.727939 -266.289835) (xy 124.67972 -266.279991) (xy 124.633704 -266.262539) (xy 124.591083 -266.237932)
			(xy 124.552962 -266.206807) (xy 124.520327 -266.16997) (xy 124.494024 -266.128374) (xy 124.474733 -266.083098)
			(xy 124.462956 -266.035314) (xy 124.458996 -265.98626) (xy 123.19 -265.98626) (xy 123.18949 -266.01175)
			(xy 123.181027 -266.062021) (xy 123.164328 -266.110188) (xy 123.139858 -266.154911) (xy 123.124468 -266.175236)
			(xy 123.115578 -266.186412) (xy 123.112022 -266.213844) (xy 123.11761 -266.226798) (xy 123.128532 -266.252452)
			(xy 123.13285 -266.26058) (xy 123.140368 -266.270766) (xy 123.162626 -266.282762) (xy 123.175268 -266.28344)
			(xy 123.184158 -266.28344) (xy 123.194223 -266.283875) (xy 123.212808 -266.291609) (xy 123.220226 -266.298426)
			(xy 123.414536 -266.492736) (xy 123.425966 -266.49934) (xy 123.43257 -266.501118) (xy 123.454732 -266.507391)
			(xy 123.497001 -266.525683) (xy 123.536043 -266.550117) (xy 123.570971 -266.58014) (xy 123.600991 -266.615069)
			(xy 123.625424 -266.654112) (xy 123.643714 -266.696382) (xy 123.649994 -266.718542) (xy 123.651772 -266.725146)
			(xy 123.658376 -266.736576) (xy 124.073666 -267.151866) (xy 124.081066 -267.158706) (xy 124.099665 -267.166421)
			(xy 124.109734 -267.166852) (xy 124.43333 -267.166852) (xy 124.45549 -267.167456) (xy 124.498746 -267.177123)
			(xy 124.538883 -267.195927) (xy 124.556774 -267.209016) (xy 124.572522 -267.221208) (xy 124.578489 -267.224496)
			(xy 124.591621 -267.228106) (xy 124.59843 -267.22832) (xy 124.94006 -267.22832) (xy 124.957332 -267.221716)
			(xy 124.96419 -267.215874) (xy 124.964444 -267.21562) (xy 124.964952 -267.215112) (xy 124.965206 -267.214858)
			(xy 124.966984 -267.213334) (xy 124.974096 -267.208) (xy 124.974604 -267.207746) (xy 124.984764 -267.20038)
			(xy 124.989082 -267.197586) (xy 124.9934 -267.193522) (xy 125.00356 -267.188696) (xy 125.016006 -267.183362)
			(xy 125.032008 -267.16228) (xy 125.046994 -267.053822) (xy 125.038612 -267.030708) (xy 125.029214 -267.022072)
			(xy 125.010747 -267.004579) (xy 124.979326 -266.964582) (xy 124.954967 -266.91993) (xy 124.938346 -266.871859)
			(xy 124.929922 -266.821698) (xy 124.929392 -266.796266) (xy 124.929914 -266.771011) (xy 124.938227 -266.721189)
			(xy 124.954628 -266.673415) (xy 124.978669 -266.628992) (xy 125.009693 -266.589132) (xy 125.046855 -266.554922)
			(xy 125.089141 -266.527296) (xy 125.135397 -266.507006) (xy 125.184362 -266.494606) (xy 125.2347 -266.490435)
			(xy 125.285038 -266.494606) (xy 125.334003 -266.507006) (xy 125.380259 -266.527296) (xy 125.422545 -266.554922)
			(xy 125.459707 -266.589132) (xy 125.490731 -266.628992) (xy 125.514772 -266.673415) (xy 125.531173 -266.721189)
			(xy 125.539486 -266.771011) (xy 125.540008 -266.796266) (xy 125.86895 -266.796266) (xy 125.87291 -266.747212)
			(xy 125.884687 -266.699428) (xy 125.903978 -266.654152) (xy 125.930281 -266.612556) (xy 125.962916 -266.575719)
			(xy 126.001037 -266.544594) (xy 126.043658 -266.519987) (xy 126.089674 -266.502535) (xy 126.137893 -266.492691)
			(xy 126.187068 -266.49071) (xy 126.235923 -266.496642) (xy 126.283194 -266.510334) (xy 126.327656 -266.531432)
			(xy 126.368159 -266.559388) (xy 126.403652 -266.59348) (xy 126.433217 -266.632824) (xy 126.456088 -266.676401)
			(xy 126.471672 -266.723082) (xy 126.479567 -266.771659) (xy 126.480062 -266.796266) (xy 126.809004 -266.796266)
			(xy 126.812964 -266.747212) (xy 126.824741 -266.699428) (xy 126.844032 -266.654152) (xy 126.870335 -266.612556)
			(xy 126.90297 -266.575719) (xy 126.941091 -266.544594) (xy 126.983712 -266.519987) (xy 127.029728 -266.502535)
			(xy 127.077947 -266.492691) (xy 127.127122 -266.49071) (xy 127.175977 -266.496642) (xy 127.223248 -266.510334)
			(xy 127.26771 -266.531432) (xy 127.308213 -266.559388) (xy 127.343706 -266.59348) (xy 127.373271 -266.632824)
			(xy 127.396142 -266.676401) (xy 127.411726 -266.723082) (xy 127.419621 -266.771659) (xy 127.420116 -266.796266)
			(xy 127.738627 -266.796266) (xy 127.742722 -266.745538) (xy 127.754901 -266.696124) (xy 127.774849 -266.649304)
			(xy 127.80205 -266.60629) (xy 127.835798 -266.568196) (xy 127.87522 -266.536009) (xy 127.919294 -266.510563)
			(xy 127.96688 -266.492516) (xy 128.016744 -266.482336) (xy 128.067596 -266.480287) (xy 128.118117 -266.486421)
			(xy 128.167001 -266.500581) (xy 128.21298 -266.522398) (xy 128.254864 -266.551308) (xy 128.291568 -266.586563)
			(xy 128.322141 -266.627249) (xy 128.345792 -266.672312) (xy 128.361908 -266.720586) (xy 128.370072 -266.77082)
			(xy 128.370584 -266.796266) (xy 128.688858 -266.796266) (xy 128.692818 -266.747212) (xy 128.704595 -266.699428)
			(xy 128.723886 -266.654152) (xy 128.750189 -266.612556) (xy 128.782824 -266.575719) (xy 128.820945 -266.544594)
			(xy 128.863566 -266.519987) (xy 128.909582 -266.502535) (xy 128.957801 -266.492691) (xy 129.006976 -266.49071)
			(xy 129.055831 -266.496642) (xy 129.103102 -266.510334) (xy 129.147564 -266.531432) (xy 129.188067 -266.559388)
			(xy 129.22356 -266.59348) (xy 129.253125 -266.632824) (xy 129.275996 -266.676401) (xy 129.29158 -266.723082)
			(xy 129.299475 -266.771659) (xy 129.29997 -266.796266) (xy 129.618481 -266.796266) (xy 129.622576 -266.745538)
			(xy 129.634755 -266.696124) (xy 129.654703 -266.649304) (xy 129.681904 -266.60629) (xy 129.715652 -266.568196)
			(xy 129.755074 -266.536009) (xy 129.799148 -266.510563) (xy 129.846734 -266.492516) (xy 129.896598 -266.482336)
			(xy 129.94745 -266.480287) (xy 129.997971 -266.486421) (xy 130.046855 -266.500581) (xy 130.092834 -266.522398)
			(xy 130.134718 -266.551308) (xy 130.171422 -266.586563) (xy 130.201995 -266.627249) (xy 130.225646 -266.672312)
			(xy 130.241762 -266.720586) (xy 130.249926 -266.77082) (xy 130.250438 -266.796266) (xy 130.568966 -266.796266)
			(xy 130.572926 -266.747212) (xy 130.584703 -266.699428) (xy 130.603994 -266.654152) (xy 130.630297 -266.612556)
			(xy 130.662932 -266.575719) (xy 130.701053 -266.544594) (xy 130.743674 -266.519987) (xy 130.78969 -266.502535)
			(xy 130.837909 -266.492691) (xy 130.887084 -266.49071) (xy 130.935939 -266.496642) (xy 130.98321 -266.510334)
			(xy 131.027672 -266.531432) (xy 131.068175 -266.559388) (xy 131.103668 -266.59348) (xy 131.133233 -266.632824)
			(xy 131.156104 -266.676401) (xy 131.171688 -266.723082) (xy 131.179583 -266.771659) (xy 131.180078 -266.796266)
			(xy 131.498589 -266.796266) (xy 131.502684 -266.745538) (xy 131.514863 -266.696124) (xy 131.534811 -266.649304)
			(xy 131.562012 -266.60629) (xy 131.59576 -266.568196) (xy 131.635182 -266.536009) (xy 131.679256 -266.510563)
			(xy 131.726842 -266.492516) (xy 131.776706 -266.482336) (xy 131.827558 -266.480287) (xy 131.878079 -266.486421)
			(xy 131.926963 -266.500581) (xy 131.972942 -266.522398) (xy 132.014826 -266.551308) (xy 132.05153 -266.586563)
			(xy 132.082103 -266.627249) (xy 132.105754 -266.672312) (xy 132.12187 -266.720586) (xy 132.130034 -266.77082)
			(xy 132.130546 -266.796266) (xy 132.438643 -266.796266) (xy 132.442738 -266.745538) (xy 132.454917 -266.696124)
			(xy 132.474865 -266.649304) (xy 132.502066 -266.60629) (xy 132.535814 -266.568196) (xy 132.575236 -266.536009)
			(xy 132.61931 -266.510563) (xy 132.666896 -266.492516) (xy 132.71676 -266.482336) (xy 132.767612 -266.480287)
			(xy 132.818133 -266.486421) (xy 132.867017 -266.500581) (xy 132.912996 -266.522398) (xy 132.95488 -266.551308)
			(xy 132.991584 -266.586563) (xy 133.022157 -266.627249) (xy 133.045808 -266.672312) (xy 133.061924 -266.720586)
			(xy 133.070088 -266.77082) (xy 133.0706 -266.796266) (xy 133.388874 -266.796266) (xy 133.392834 -266.747212)
			(xy 133.404611 -266.699428) (xy 133.423902 -266.654152) (xy 133.450205 -266.612556) (xy 133.48284 -266.575719)
			(xy 133.520961 -266.544594) (xy 133.563582 -266.519987) (xy 133.609598 -266.502535) (xy 133.657817 -266.492691)
			(xy 133.706992 -266.49071) (xy 133.755847 -266.496642) (xy 133.803118 -266.510334) (xy 133.84758 -266.531432)
			(xy 133.888083 -266.559388) (xy 133.923576 -266.59348) (xy 133.953141 -266.632824) (xy 133.976012 -266.676401)
			(xy 133.991596 -266.723082) (xy 133.999491 -266.771659) (xy 133.999986 -266.796266) (xy 134.318497 -266.796266)
			(xy 134.322592 -266.745538) (xy 134.334771 -266.696124) (xy 134.354719 -266.649304) (xy 134.38192 -266.60629)
			(xy 134.415668 -266.568196) (xy 134.45509 -266.536009) (xy 134.499164 -266.510563) (xy 134.54675 -266.492516)
			(xy 134.596614 -266.482336) (xy 134.647466 -266.480287) (xy 134.697987 -266.486421) (xy 134.746871 -266.500581)
			(xy 134.79285 -266.522398) (xy 134.834734 -266.551308) (xy 134.871438 -266.586563) (xy 134.902011 -266.627249)
			(xy 134.925662 -266.672312) (xy 134.941778 -266.720586) (xy 134.949942 -266.77082) (xy 134.950454 -266.796266)
			(xy 135.268982 -266.796266) (xy 135.272942 -266.747212) (xy 135.284719 -266.699428) (xy 135.30401 -266.654152)
			(xy 135.330313 -266.612556) (xy 135.362948 -266.575719) (xy 135.401069 -266.544594) (xy 135.44369 -266.519987)
			(xy 135.489706 -266.502535) (xy 135.537925 -266.492691) (xy 135.5871 -266.49071) (xy 135.635955 -266.496642)
			(xy 135.683226 -266.510334) (xy 135.727688 -266.531432) (xy 135.768191 -266.559388) (xy 135.803684 -266.59348)
			(xy 135.833249 -266.632824) (xy 135.85612 -266.676401) (xy 135.871704 -266.723082) (xy 135.879599 -266.771659)
			(xy 135.880094 -266.796266) (xy 136.198605 -266.796266) (xy 136.2027 -266.745538) (xy 136.214879 -266.696124)
			(xy 136.234827 -266.649304) (xy 136.262028 -266.60629) (xy 136.295776 -266.568196) (xy 136.335198 -266.536009)
			(xy 136.379272 -266.510563) (xy 136.426858 -266.492516) (xy 136.476722 -266.482336) (xy 136.527574 -266.480287)
			(xy 136.578095 -266.486421) (xy 136.626979 -266.500581) (xy 136.672958 -266.522398) (xy 136.714842 -266.551308)
			(xy 136.751546 -266.586563) (xy 136.782119 -266.627249) (xy 136.80577 -266.672312) (xy 136.821886 -266.720586)
			(xy 136.83005 -266.77082) (xy 136.830562 -266.796266) (xy 137.148836 -266.796266) (xy 137.152796 -266.747212)
			(xy 137.164573 -266.699428) (xy 137.183864 -266.654152) (xy 137.210167 -266.612556) (xy 137.242802 -266.575719)
			(xy 137.280923 -266.544594) (xy 137.323544 -266.519987) (xy 137.36956 -266.502535) (xy 137.417779 -266.492691)
			(xy 137.466954 -266.49071) (xy 137.515809 -266.496642) (xy 137.56308 -266.510334) (xy 137.607542 -266.531432)
			(xy 137.648045 -266.559388) (xy 137.683538 -266.59348) (xy 137.713103 -266.632824) (xy 137.735974 -266.676401)
			(xy 137.751558 -266.723082) (xy 137.759453 -266.771659) (xy 137.759948 -266.796266) (xy 138.078459 -266.796266)
			(xy 138.082554 -266.745538) (xy 138.094733 -266.696124) (xy 138.114681 -266.649304) (xy 138.141882 -266.60629)
			(xy 138.17563 -266.568196) (xy 138.215052 -266.536009) (xy 138.259126 -266.510563) (xy 138.306712 -266.492516)
			(xy 138.356576 -266.482336) (xy 138.407428 -266.480287) (xy 138.457949 -266.486421) (xy 138.506833 -266.500581)
			(xy 138.552812 -266.522398) (xy 138.594696 -266.551308) (xy 138.6314 -266.586563) (xy 138.661973 -266.627249)
			(xy 138.685624 -266.672312) (xy 138.70174 -266.720586) (xy 138.709904 -266.77082) (xy 138.710416 -266.796266)
			(xy 139.018513 -266.796266) (xy 139.022608 -266.745538) (xy 139.034787 -266.696124) (xy 139.054735 -266.649304)
			(xy 139.081936 -266.60629) (xy 139.115684 -266.568196) (xy 139.155106 -266.536009) (xy 139.19918 -266.510563)
			(xy 139.246766 -266.492516) (xy 139.29663 -266.482336) (xy 139.347482 -266.480287) (xy 139.398003 -266.486421)
			(xy 139.446887 -266.500581) (xy 139.492866 -266.522398) (xy 139.53475 -266.551308) (xy 139.571454 -266.586563)
			(xy 139.602027 -266.627249) (xy 139.625678 -266.672312) (xy 139.641794 -266.720586) (xy 139.649958 -266.77082)
			(xy 139.65047 -266.796266) (xy 139.968998 -266.796266) (xy 139.972958 -266.747212) (xy 139.984735 -266.699428)
			(xy 140.004026 -266.654152) (xy 140.030329 -266.612556) (xy 140.062964 -266.575719) (xy 140.101085 -266.544594)
			(xy 140.143706 -266.519987) (xy 140.189722 -266.502535) (xy 140.237941 -266.492691) (xy 140.287116 -266.49071)
			(xy 140.335971 -266.496642) (xy 140.383242 -266.510334) (xy 140.427704 -266.531432) (xy 140.468207 -266.559388)
			(xy 140.5037 -266.59348) (xy 140.533265 -266.632824) (xy 140.556136 -266.676401) (xy 140.57172 -266.723082)
			(xy 140.579615 -266.771659) (xy 140.58011 -266.796266) (xy 140.898621 -266.796266) (xy 140.902716 -266.745538)
			(xy 140.914895 -266.696124) (xy 140.934843 -266.649304) (xy 140.962044 -266.60629) (xy 140.995792 -266.568196)
			(xy 141.035214 -266.536009) (xy 141.079288 -266.510563) (xy 141.126874 -266.492516) (xy 141.176738 -266.482336)
			(xy 141.22759 -266.480287) (xy 141.278111 -266.486421) (xy 141.326995 -266.500581) (xy 141.372974 -266.522398)
			(xy 141.414858 -266.551308) (xy 141.451562 -266.586563) (xy 141.482135 -266.627249) (xy 141.505786 -266.672312)
			(xy 141.521902 -266.720586) (xy 141.530066 -266.77082) (xy 141.530578 -266.796266) (xy 141.848852 -266.796266)
			(xy 141.852812 -266.747212) (xy 141.864589 -266.699428) (xy 141.88388 -266.654152) (xy 141.910183 -266.612556)
			(xy 141.942818 -266.575719) (xy 141.980939 -266.544594) (xy 142.02356 -266.519987) (xy 142.069576 -266.502535)
			(xy 142.117795 -266.492691) (xy 142.16697 -266.49071) (xy 142.215825 -266.496642) (xy 142.263096 -266.510334)
			(xy 142.307558 -266.531432) (xy 142.348061 -266.559388) (xy 142.383554 -266.59348) (xy 142.413119 -266.632824)
			(xy 142.43599 -266.676401) (xy 142.451574 -266.723082) (xy 142.459469 -266.771659) (xy 142.459964 -266.796266)
			(xy 142.778475 -266.796266) (xy 142.78257 -266.745538) (xy 142.794749 -266.696124) (xy 142.814697 -266.649304)
			(xy 142.841898 -266.60629) (xy 142.875646 -266.568196) (xy 142.915068 -266.536009) (xy 142.959142 -266.510563)
			(xy 143.006728 -266.492516) (xy 143.056592 -266.482336) (xy 143.107444 -266.480287) (xy 143.157965 -266.486421)
			(xy 143.206849 -266.500581) (xy 143.252828 -266.522398) (xy 143.294712 -266.551308) (xy 143.331416 -266.586563)
			(xy 143.361989 -266.627249) (xy 143.38564 -266.672312) (xy 143.401756 -266.720586) (xy 143.40992 -266.77082)
			(xy 143.410432 -266.796266) (xy 143.72896 -266.796266) (xy 143.73292 -266.747212) (xy 143.744697 -266.699428)
			(xy 143.763988 -266.654152) (xy 143.790291 -266.612556) (xy 143.822926 -266.575719) (xy 143.861047 -266.544594)
			(xy 143.903668 -266.519987) (xy 143.949684 -266.502535) (xy 143.997903 -266.492691) (xy 144.047078 -266.49071)
			(xy 144.095933 -266.496642) (xy 144.143204 -266.510334) (xy 144.185339 -266.530328) (xy 146.737082 -266.530328)
			(xy 146.741042 -266.481274) (xy 146.752819 -266.43349) (xy 146.77211 -266.388214) (xy 146.798413 -266.346618)
			(xy 146.831048 -266.309781) (xy 146.869169 -266.278656) (xy 146.91179 -266.254049) (xy 146.957806 -266.236597)
			(xy 147.006025 -266.226753) (xy 147.0552 -266.224772) (xy 147.104055 -266.230704) (xy 147.151326 -266.244396)
			(xy 147.195788 -266.265494) (xy 147.236291 -266.29345) (xy 147.271784 -266.327542) (xy 147.301349 -266.366886)
			(xy 147.32422 -266.410463) (xy 147.339804 -266.457144) (xy 147.347699 -266.505721) (xy 147.348194 -266.530328)
			(xy 147.347699 -266.554935) (xy 147.339804 -266.603512) (xy 147.32422 -266.650193) (xy 147.301349 -266.69377)
			(xy 147.271784 -266.733114) (xy 147.236291 -266.767206) (xy 147.195788 -266.795162) (xy 147.151326 -266.81626)
			(xy 147.104055 -266.829952) (xy 147.0552 -266.835884) (xy 147.006025 -266.833903) (xy 146.957806 -266.824059)
			(xy 146.91179 -266.806607) (xy 146.869169 -266.782) (xy 146.831048 -266.750875) (xy 146.798413 -266.714038)
			(xy 146.77211 -266.672442) (xy 146.752819 -266.627166) (xy 146.741042 -266.579382) (xy 146.737082 -266.530328)
			(xy 144.185339 -266.530328) (xy 144.187666 -266.531432) (xy 144.228169 -266.559388) (xy 144.263662 -266.59348)
			(xy 144.293227 -266.632824) (xy 144.316098 -266.676401) (xy 144.331682 -266.723082) (xy 144.339577 -266.771659)
			(xy 144.340072 -266.796266) (xy 144.339577 -266.820873) (xy 144.331682 -266.86945) (xy 144.316098 -266.916131)
			(xy 144.293227 -266.959708) (xy 144.263662 -266.999052) (xy 144.228169 -267.033144) (xy 144.225074 -267.03528)
			(xy 168.158683 -267.03528) (xy 168.162618 -266.981509) (xy 168.174341 -266.928885) (xy 168.193601 -266.878528)
			(xy 168.219987 -266.831511) (xy 168.252939 -266.788838) (xy 168.291752 -266.751417) (xy 168.3356 -266.720047)
			(xy 168.383548 -266.695395) (xy 168.434575 -266.677987) (xy 168.487593 -266.668194) (xy 168.541472 -266.666225)
			(xy 168.595063 -266.672122) (xy 168.647224 -266.685758) (xy 168.696844 -266.706845) (xy 168.742865 -266.734931)
			(xy 168.784307 -266.769419) (xy 168.820285 -266.809573) (xy 168.850033 -266.854537) (xy 168.872918 -266.903354)
			(xy 168.88845 -266.954983) (xy 168.8963 -267.008323) (xy 168.896792 -267.03528) (xy 168.8963 -267.062237)
			(xy 168.88845 -267.115577) (xy 168.872918 -267.167206) (xy 168.850033 -267.216023) (xy 168.820285 -267.260987)
			(xy 168.784307 -267.301141) (xy 168.742865 -267.335629) (xy 168.696844 -267.363715) (xy 168.647224 -267.384802)
			(xy 168.595063 -267.398438) (xy 168.541472 -267.404335) (xy 168.487593 -267.402366) (xy 168.434575 -267.392573)
			(xy 168.383548 -267.375165) (xy 168.3356 -267.350513) (xy 168.291752 -267.319143) (xy 168.252939 -267.281722)
			(xy 168.219987 -267.239049) (xy 168.193601 -267.192032) (xy 168.174341 -267.141675) (xy 168.162618 -267.089051)
			(xy 168.158683 -267.03528) (xy 144.225074 -267.03528) (xy 144.187666 -267.0611) (xy 144.143204 -267.082198)
			(xy 144.095933 -267.09589) (xy 144.047078 -267.101822) (xy 143.997903 -267.099841) (xy 143.949684 -267.089997)
			(xy 143.903668 -267.072545) (xy 143.861047 -267.047938) (xy 143.822926 -267.016813) (xy 143.790291 -266.979976)
			(xy 143.763988 -266.93838) (xy 143.744697 -266.893104) (xy 143.73292 -266.84532) (xy 143.72896 -266.796266)
			(xy 143.410432 -266.796266) (xy 143.40992 -266.821712) (xy 143.401756 -266.871946) (xy 143.38564 -266.92022)
			(xy 143.361989 -266.965283) (xy 143.331416 -267.005969) (xy 143.294712 -267.041224) (xy 143.252828 -267.070134)
			(xy 143.206849 -267.091951) (xy 143.157965 -267.106111) (xy 143.107444 -267.112245) (xy 143.056592 -267.110196)
			(xy 143.006728 -267.100016) (xy 142.959142 -267.081969) (xy 142.915068 -267.056523) (xy 142.875646 -267.024336)
			(xy 142.841898 -266.986242) (xy 142.814697 -266.943228) (xy 142.794749 -266.896408) (xy 142.78257 -266.846994)
			(xy 142.778475 -266.796266) (xy 142.459964 -266.796266) (xy 142.459469 -266.820873) (xy 142.451574 -266.86945)
			(xy 142.43599 -266.916131) (xy 142.413119 -266.959708) (xy 142.383554 -266.999052) (xy 142.348061 -267.033144)
			(xy 142.307558 -267.0611) (xy 142.263096 -267.082198) (xy 142.215825 -267.09589) (xy 142.16697 -267.101822)
			(xy 142.117795 -267.099841) (xy 142.069576 -267.089997) (xy 142.02356 -267.072545) (xy 141.980939 -267.047938)
			(xy 141.942818 -267.016813) (xy 141.910183 -266.979976) (xy 141.88388 -266.93838) (xy 141.864589 -266.893104)
			(xy 141.852812 -266.84532) (xy 141.848852 -266.796266) (xy 141.530578 -266.796266) (xy 141.530066 -266.821712)
			(xy 141.521902 -266.871946) (xy 141.505786 -266.92022) (xy 141.482135 -266.965283) (xy 141.451562 -267.005969)
			(xy 141.414858 -267.041224) (xy 141.372974 -267.070134) (xy 141.326995 -267.091951) (xy 141.278111 -267.106111)
			(xy 141.22759 -267.112245) (xy 141.176738 -267.110196) (xy 141.126874 -267.100016) (xy 141.079288 -267.081969)
			(xy 141.035214 -267.056523) (xy 140.995792 -267.024336) (xy 140.962044 -266.986242) (xy 140.934843 -266.943228)
			(xy 140.914895 -266.896408) (xy 140.902716 -266.846994) (xy 140.898621 -266.796266) (xy 140.58011 -266.796266)
			(xy 140.579615 -266.820873) (xy 140.57172 -266.86945) (xy 140.556136 -266.916131) (xy 140.533265 -266.959708)
			(xy 140.5037 -266.999052) (xy 140.468207 -267.033144) (xy 140.427704 -267.0611) (xy 140.383242 -267.082198)
			(xy 140.335971 -267.09589) (xy 140.287116 -267.101822) (xy 140.237941 -267.099841) (xy 140.189722 -267.089997)
			(xy 140.143706 -267.072545) (xy 140.101085 -267.047938) (xy 140.062964 -267.016813) (xy 140.030329 -266.979976)
			(xy 140.004026 -266.93838) (xy 139.984735 -266.893104) (xy 139.972958 -266.84532) (xy 139.968998 -266.796266)
			(xy 139.65047 -266.796266) (xy 139.649958 -266.821712) (xy 139.641794 -266.871946) (xy 139.625678 -266.92022)
			(xy 139.602027 -266.965283) (xy 139.571454 -267.005969) (xy 139.53475 -267.041224) (xy 139.492866 -267.070134)
			(xy 139.446887 -267.091951) (xy 139.398003 -267.106111) (xy 139.347482 -267.112245) (xy 139.29663 -267.110196)
			(xy 139.246766 -267.100016) (xy 139.19918 -267.081969) (xy 139.155106 -267.056523) (xy 139.115684 -267.024336)
			(xy 139.081936 -266.986242) (xy 139.054735 -266.943228) (xy 139.034787 -266.896408) (xy 139.022608 -266.846994)
			(xy 139.018513 -266.796266) (xy 138.710416 -266.796266) (xy 138.709904 -266.821712) (xy 138.70174 -266.871946)
			(xy 138.685624 -266.92022) (xy 138.661973 -266.965283) (xy 138.6314 -267.005969) (xy 138.594696 -267.041224)
			(xy 138.552812 -267.070134) (xy 138.506833 -267.091951) (xy 138.457949 -267.106111) (xy 138.407428 -267.112245)
			(xy 138.356576 -267.110196) (xy 138.306712 -267.100016) (xy 138.259126 -267.081969) (xy 138.215052 -267.056523)
			(xy 138.17563 -267.024336) (xy 138.141882 -266.986242) (xy 138.114681 -266.943228) (xy 138.094733 -266.896408)
			(xy 138.082554 -266.846994) (xy 138.078459 -266.796266) (xy 137.759948 -266.796266) (xy 137.759453 -266.820873)
			(xy 137.751558 -266.86945) (xy 137.735974 -266.916131) (xy 137.713103 -266.959708) (xy 137.683538 -266.999052)
			(xy 137.648045 -267.033144) (xy 137.607542 -267.0611) (xy 137.56308 -267.082198) (xy 137.515809 -267.09589)
			(xy 137.466954 -267.101822) (xy 137.417779 -267.099841) (xy 137.36956 -267.089997) (xy 137.323544 -267.072545)
			(xy 137.280923 -267.047938) (xy 137.242802 -267.016813) (xy 137.210167 -266.979976) (xy 137.183864 -266.93838)
			(xy 137.164573 -266.893104) (xy 137.152796 -266.84532) (xy 137.148836 -266.796266) (xy 136.830562 -266.796266)
			(xy 136.83005 -266.821712) (xy 136.821886 -266.871946) (xy 136.80577 -266.92022) (xy 136.782119 -266.965283)
			(xy 136.751546 -267.005969) (xy 136.714842 -267.041224) (xy 136.672958 -267.070134) (xy 136.626979 -267.091951)
			(xy 136.578095 -267.106111) (xy 136.527574 -267.112245) (xy 136.476722 -267.110196) (xy 136.426858 -267.100016)
			(xy 136.379272 -267.081969) (xy 136.335198 -267.056523) (xy 136.295776 -267.024336) (xy 136.262028 -266.986242)
			(xy 136.234827 -266.943228) (xy 136.214879 -266.896408) (xy 136.2027 -266.846994) (xy 136.198605 -266.796266)
			(xy 135.880094 -266.796266) (xy 135.879599 -266.820873) (xy 135.871704 -266.86945) (xy 135.85612 -266.916131)
			(xy 135.833249 -266.959708) (xy 135.803684 -266.999052) (xy 135.768191 -267.033144) (xy 135.727688 -267.0611)
			(xy 135.683226 -267.082198) (xy 135.635955 -267.09589) (xy 135.5871 -267.101822) (xy 135.537925 -267.099841)
			(xy 135.489706 -267.089997) (xy 135.44369 -267.072545) (xy 135.401069 -267.047938) (xy 135.362948 -267.016813)
			(xy 135.330313 -266.979976) (xy 135.30401 -266.93838) (xy 135.284719 -266.893104) (xy 135.272942 -266.84532)
			(xy 135.268982 -266.796266) (xy 134.950454 -266.796266) (xy 134.949942 -266.821712) (xy 134.941778 -266.871946)
			(xy 134.925662 -266.92022) (xy 134.902011 -266.965283) (xy 134.871438 -267.005969) (xy 134.834734 -267.041224)
			(xy 134.79285 -267.070134) (xy 134.746871 -267.091951) (xy 134.697987 -267.106111) (xy 134.647466 -267.112245)
			(xy 134.596614 -267.110196) (xy 134.54675 -267.100016) (xy 134.499164 -267.081969) (xy 134.45509 -267.056523)
			(xy 134.415668 -267.024336) (xy 134.38192 -266.986242) (xy 134.354719 -266.943228) (xy 134.334771 -266.896408)
			(xy 134.322592 -266.846994) (xy 134.318497 -266.796266) (xy 133.999986 -266.796266) (xy 133.999491 -266.820873)
			(xy 133.991596 -266.86945) (xy 133.976012 -266.916131) (xy 133.953141 -266.959708) (xy 133.923576 -266.999052)
			(xy 133.888083 -267.033144) (xy 133.84758 -267.0611) (xy 133.803118 -267.082198) (xy 133.755847 -267.09589)
			(xy 133.706992 -267.101822) (xy 133.657817 -267.099841) (xy 133.609598 -267.089997) (xy 133.563582 -267.072545)
			(xy 133.520961 -267.047938) (xy 133.48284 -267.016813) (xy 133.450205 -266.979976) (xy 133.423902 -266.93838)
			(xy 133.404611 -266.893104) (xy 133.392834 -266.84532) (xy 133.388874 -266.796266) (xy 133.0706 -266.796266)
			(xy 133.070088 -266.821712) (xy 133.061924 -266.871946) (xy 133.045808 -266.92022) (xy 133.022157 -266.965283)
			(xy 132.991584 -267.005969) (xy 132.95488 -267.041224) (xy 132.912996 -267.070134) (xy 132.867017 -267.091951)
			(xy 132.818133 -267.106111) (xy 132.767612 -267.112245) (xy 132.71676 -267.110196) (xy 132.666896 -267.100016)
			(xy 132.61931 -267.081969) (xy 132.575236 -267.056523) (xy 132.535814 -267.024336) (xy 132.502066 -266.986242)
			(xy 132.474865 -266.943228) (xy 132.454917 -266.896408) (xy 132.442738 -266.846994) (xy 132.438643 -266.796266)
			(xy 132.130546 -266.796266) (xy 132.130034 -266.821712) (xy 132.12187 -266.871946) (xy 132.105754 -266.92022)
			(xy 132.082103 -266.965283) (xy 132.05153 -267.005969) (xy 132.014826 -267.041224) (xy 131.972942 -267.070134)
			(xy 131.926963 -267.091951) (xy 131.878079 -267.106111) (xy 131.827558 -267.112245) (xy 131.776706 -267.110196)
			(xy 131.726842 -267.100016) (xy 131.679256 -267.081969) (xy 131.635182 -267.056523) (xy 131.59576 -267.024336)
			(xy 131.562012 -266.986242) (xy 131.534811 -266.943228) (xy 131.514863 -266.896408) (xy 131.502684 -266.846994)
			(xy 131.498589 -266.796266) (xy 131.180078 -266.796266) (xy 131.179583 -266.820873) (xy 131.171688 -266.86945)
			(xy 131.156104 -266.916131) (xy 131.133233 -266.959708) (xy 131.103668 -266.999052) (xy 131.068175 -267.033144)
			(xy 131.027672 -267.0611) (xy 130.98321 -267.082198) (xy 130.935939 -267.09589) (xy 130.887084 -267.101822)
			(xy 130.837909 -267.099841) (xy 130.78969 -267.089997) (xy 130.743674 -267.072545) (xy 130.701053 -267.047938)
			(xy 130.662932 -267.016813) (xy 130.630297 -266.979976) (xy 130.603994 -266.93838) (xy 130.584703 -266.893104)
			(xy 130.572926 -266.84532) (xy 130.568966 -266.796266) (xy 130.250438 -266.796266) (xy 130.249926 -266.821712)
			(xy 130.241762 -266.871946) (xy 130.225646 -266.92022) (xy 130.201995 -266.965283) (xy 130.171422 -267.005969)
			(xy 130.134718 -267.041224) (xy 130.092834 -267.070134) (xy 130.046855 -267.091951) (xy 129.997971 -267.106111)
			(xy 129.94745 -267.112245) (xy 129.896598 -267.110196) (xy 129.846734 -267.100016) (xy 129.799148 -267.081969)
			(xy 129.755074 -267.056523) (xy 129.715652 -267.024336) (xy 129.681904 -266.986242) (xy 129.654703 -266.943228)
			(xy 129.634755 -266.896408) (xy 129.622576 -266.846994) (xy 129.618481 -266.796266) (xy 129.29997 -266.796266)
			(xy 129.299475 -266.820873) (xy 129.29158 -266.86945) (xy 129.275996 -266.916131) (xy 129.253125 -266.959708)
			(xy 129.22356 -266.999052) (xy 129.188067 -267.033144) (xy 129.147564 -267.0611) (xy 129.103102 -267.082198)
			(xy 129.055831 -267.09589) (xy 129.006976 -267.101822) (xy 128.957801 -267.099841) (xy 128.909582 -267.089997)
			(xy 128.863566 -267.072545) (xy 128.820945 -267.047938) (xy 128.782824 -267.016813) (xy 128.750189 -266.979976)
			(xy 128.723886 -266.93838) (xy 128.704595 -266.893104) (xy 128.692818 -266.84532) (xy 128.688858 -266.796266)
			(xy 128.370584 -266.796266) (xy 128.370072 -266.821712) (xy 128.361908 -266.871946) (xy 128.345792 -266.92022)
			(xy 128.322141 -266.965283) (xy 128.291568 -267.005969) (xy 128.254864 -267.041224) (xy 128.21298 -267.070134)
			(xy 128.167001 -267.091951) (xy 128.118117 -267.106111) (xy 128.067596 -267.112245) (xy 128.016744 -267.110196)
			(xy 127.96688 -267.100016) (xy 127.919294 -267.081969) (xy 127.87522 -267.056523) (xy 127.835798 -267.024336)
			(xy 127.80205 -266.986242) (xy 127.774849 -266.943228) (xy 127.754901 -266.896408) (xy 127.742722 -266.846994)
			(xy 127.738627 -266.796266) (xy 127.420116 -266.796266) (xy 127.419621 -266.820873) (xy 127.411726 -266.86945)
			(xy 127.396142 -266.916131) (xy 127.373271 -266.959708) (xy 127.343706 -266.999052) (xy 127.308213 -267.033144)
			(xy 127.26771 -267.0611) (xy 127.223248 -267.082198) (xy 127.175977 -267.09589) (xy 127.127122 -267.101822)
			(xy 127.077947 -267.099841) (xy 127.029728 -267.089997) (xy 126.983712 -267.072545) (xy 126.941091 -267.047938)
			(xy 126.90297 -267.016813) (xy 126.870335 -266.979976) (xy 126.844032 -266.93838) (xy 126.824741 -266.893104)
			(xy 126.812964 -266.84532) (xy 126.809004 -266.796266) (xy 126.480062 -266.796266) (xy 126.479567 -266.820873)
			(xy 126.471672 -266.86945) (xy 126.456088 -266.916131) (xy 126.433217 -266.959708) (xy 126.403652 -266.999052)
			(xy 126.368159 -267.033144) (xy 126.327656 -267.0611) (xy 126.283194 -267.082198) (xy 126.235923 -267.09589)
			(xy 126.187068 -267.101822) (xy 126.137893 -267.099841) (xy 126.089674 -267.089997) (xy 126.043658 -267.072545)
			(xy 126.001037 -267.047938) (xy 125.962916 -267.016813) (xy 125.930281 -266.979976) (xy 125.903978 -266.93838)
			(xy 125.884687 -266.893104) (xy 125.87291 -266.84532) (xy 125.86895 -266.796266) (xy 125.540008 -266.796266)
			(xy 125.539444 -266.823894) (xy 125.529571 -266.878261) (xy 125.510088 -266.929967) (xy 125.481628 -266.97733)
			(xy 125.463808 -266.99845) (xy 125.453902 -267.009626) (xy 125.44933 -267.03909) (xy 125.493526 -267.13688)
			(xy 125.497936 -267.145568) (xy 125.51198 -267.159048) (xy 125.530023 -267.166356) (xy 125.539754 -267.166852)
			(xy 125.843538 -267.166852) (xy 125.863557 -267.167441) (xy 125.902232 -267.177802) (xy 125.9369 -267.197832)
			(xy 125.951488 -267.211556) (xy 125.951742 -267.21181) (xy 125.954028 -267.214096) (xy 125.961381 -267.220575)
			(xy 125.979543 -267.227889) (xy 125.989334 -267.22832) (xy 126.275338 -267.22832) (xy 126.285405 -267.228751)
			(xy 126.303997 -267.236477) (xy 126.311406 -267.243306) (xy 126.412752 -267.344652) (xy 126.421398 -267.35254)
			(xy 126.4435 -267.360157) (xy 126.466693 -267.357224) (xy 126.47676 -267.351256) (xy 126.495548 -267.339364)
			(xy 126.535837 -267.320556) (xy 126.578429 -267.307794) (xy 126.622422 -267.301349) (xy 126.644654 -267.300964)
			(xy 126.66865 -267.301407) (xy 126.716053 -267.308908) (xy 126.761699 -267.323732) (xy 126.804463 -267.345514)
			(xy 126.843293 -267.373718) (xy 126.877233 -267.40765) (xy 126.905447 -267.446474) (xy 126.92724 -267.489233)
			(xy 126.942075 -267.534875) (xy 126.949587 -267.582276) (xy 126.949962 -267.606272) (xy 128.218958 -267.606272)
			(xy 128.222918 -267.557218) (xy 128.234695 -267.509434) (xy 128.253986 -267.464158) (xy 128.280289 -267.422562)
			(xy 128.312924 -267.385725) (xy 128.351045 -267.3546) (xy 128.393666 -267.329993) (xy 128.439682 -267.312541)
			(xy 128.487901 -267.302697) (xy 128.537076 -267.300716) (xy 128.585931 -267.306648) (xy 128.633202 -267.32034)
			(xy 128.677664 -267.341438) (xy 128.718167 -267.369394) (xy 128.75366 -267.403486) (xy 128.783225 -267.44283)
			(xy 128.806096 -267.486407) (xy 128.82168 -267.533088) (xy 128.829575 -267.581665) (xy 128.83007 -267.606272)
			(xy 129.148581 -267.606272) (xy 129.152676 -267.555544) (xy 129.164855 -267.50613) (xy 129.184803 -267.45931)
			(xy 129.212004 -267.416296) (xy 129.245752 -267.378202) (xy 129.285174 -267.346015) (xy 129.329248 -267.320569)
			(xy 129.376834 -267.302522) (xy 129.426698 -267.292342) (xy 129.47755 -267.290293) (xy 129.528071 -267.296427)
			(xy 129.576955 -267.310587) (xy 129.622934 -267.332404) (xy 129.664818 -267.361314) (xy 129.701522 -267.396569)
			(xy 129.732095 -267.437255) (xy 129.755746 -267.482318) (xy 129.771862 -267.530592) (xy 129.780026 -267.580826)
			(xy 129.780538 -267.606272) (xy 130.099066 -267.606272) (xy 130.103026 -267.557218) (xy 130.114803 -267.509434)
			(xy 130.134094 -267.464158) (xy 130.160397 -267.422562) (xy 130.193032 -267.385725) (xy 130.231153 -267.3546)
			(xy 130.273774 -267.329993) (xy 130.31979 -267.312541) (xy 130.368009 -267.302697) (xy 130.417184 -267.300716)
			(xy 130.466039 -267.306648) (xy 130.51331 -267.32034) (xy 130.557772 -267.341438) (xy 130.598275 -267.369394)
			(xy 130.633768 -267.403486) (xy 130.663333 -267.44283) (xy 130.686204 -267.486407) (xy 130.701788 -267.533088)
			(xy 130.709683 -267.581665) (xy 130.710178 -267.606272) (xy 131.038866 -267.606272) (xy 131.042826 -267.557218)
			(xy 131.054603 -267.509434) (xy 131.073894 -267.464158) (xy 131.100197 -267.422562) (xy 131.132832 -267.385725)
			(xy 131.170953 -267.3546) (xy 131.213574 -267.329993) (xy 131.25959 -267.312541) (xy 131.307809 -267.302697)
			(xy 131.356984 -267.300716) (xy 131.405839 -267.306648) (xy 131.45311 -267.32034) (xy 131.497572 -267.341438)
			(xy 131.538075 -267.369394) (xy 131.573568 -267.403486) (xy 131.603133 -267.44283) (xy 131.626004 -267.486407)
			(xy 131.641588 -267.533088) (xy 131.649483 -267.581665) (xy 131.649978 -267.606272) (xy 131.97892 -267.606272)
			(xy 131.98288 -267.557218) (xy 131.994657 -267.509434) (xy 132.013948 -267.464158) (xy 132.040251 -267.422562)
			(xy 132.072886 -267.385725) (xy 132.111007 -267.3546) (xy 132.153628 -267.329993) (xy 132.199644 -267.312541)
			(xy 132.247863 -267.302697) (xy 132.297038 -267.300716) (xy 132.345893 -267.306648) (xy 132.393164 -267.32034)
			(xy 132.437626 -267.341438) (xy 132.478129 -267.369394) (xy 132.513622 -267.403486) (xy 132.543187 -267.44283)
			(xy 132.566058 -267.486407) (xy 132.581642 -267.533088) (xy 132.589537 -267.581665) (xy 132.590032 -267.606272)
			(xy 132.908543 -267.606272) (xy 132.912638 -267.555544) (xy 132.924817 -267.50613) (xy 132.944765 -267.45931)
			(xy 132.971966 -267.416296) (xy 133.005714 -267.378202) (xy 133.045136 -267.346015) (xy 133.08921 -267.320569)
			(xy 133.136796 -267.302522) (xy 133.18666 -267.292342) (xy 133.237512 -267.290293) (xy 133.288033 -267.296427)
			(xy 133.336917 -267.310587) (xy 133.382896 -267.332404) (xy 133.42478 -267.361314) (xy 133.461484 -267.396569)
			(xy 133.492057 -267.437255) (xy 133.515708 -267.482318) (xy 133.531824 -267.530592) (xy 133.539988 -267.580826)
			(xy 133.5405 -267.606272) (xy 133.859028 -267.606272) (xy 133.862988 -267.557218) (xy 133.874765 -267.509434)
			(xy 133.894056 -267.464158) (xy 133.920359 -267.422562) (xy 133.952994 -267.385725) (xy 133.991115 -267.3546)
			(xy 134.033736 -267.329993) (xy 134.079752 -267.312541) (xy 134.127971 -267.302697) (xy 134.177146 -267.300716)
			(xy 134.226001 -267.306648) (xy 134.273272 -267.32034) (xy 134.317734 -267.341438) (xy 134.358237 -267.369394)
			(xy 134.39373 -267.403486) (xy 134.423295 -267.44283) (xy 134.446166 -267.486407) (xy 134.46175 -267.533088)
			(xy 134.469645 -267.581665) (xy 134.47014 -267.606272) (xy 134.798828 -267.606272) (xy 134.802788 -267.557218)
			(xy 134.814565 -267.509434) (xy 134.833856 -267.464158) (xy 134.860159 -267.422562) (xy 134.892794 -267.385725)
			(xy 134.930915 -267.3546) (xy 134.973536 -267.329993) (xy 135.019552 -267.312541) (xy 135.067771 -267.302697)
			(xy 135.116946 -267.300716) (xy 135.165801 -267.306648) (xy 135.213072 -267.32034) (xy 135.257534 -267.341438)
			(xy 135.298037 -267.369394) (xy 135.33353 -267.403486) (xy 135.363095 -267.44283) (xy 135.385966 -267.486407)
			(xy 135.40155 -267.533088) (xy 135.409445 -267.581665) (xy 135.40994 -267.606272) (xy 135.728451 -267.606272)
			(xy 135.732546 -267.555544) (xy 135.744725 -267.50613) (xy 135.764673 -267.45931) (xy 135.791874 -267.416296)
			(xy 135.825622 -267.378202) (xy 135.865044 -267.346015) (xy 135.909118 -267.320569) (xy 135.956704 -267.302522)
			(xy 136.006568 -267.292342) (xy 136.05742 -267.290293) (xy 136.107941 -267.296427) (xy 136.156825 -267.310587)
			(xy 136.202804 -267.332404) (xy 136.244688 -267.361314) (xy 136.281392 -267.396569) (xy 136.311965 -267.437255)
			(xy 136.335616 -267.482318) (xy 136.351732 -267.530592) (xy 136.359896 -267.580826) (xy 136.360408 -267.606272)
			(xy 136.678936 -267.606272) (xy 136.682896 -267.557218) (xy 136.694673 -267.509434) (xy 136.713964 -267.464158)
			(xy 136.740267 -267.422562) (xy 136.772902 -267.385725) (xy 136.811023 -267.3546) (xy 136.853644 -267.329993)
			(xy 136.89966 -267.312541) (xy 136.947879 -267.302697) (xy 136.997054 -267.300716) (xy 137.045909 -267.306648)
			(xy 137.09318 -267.32034) (xy 137.137642 -267.341438) (xy 137.178145 -267.369394) (xy 137.213638 -267.403486)
			(xy 137.243203 -267.44283) (xy 137.266074 -267.486407) (xy 137.281658 -267.533088) (xy 137.289553 -267.581665)
			(xy 137.290048 -267.606272) (xy 137.61899 -267.606272) (xy 137.62295 -267.557218) (xy 137.634727 -267.509434)
			(xy 137.654018 -267.464158) (xy 137.680321 -267.422562) (xy 137.712956 -267.385725) (xy 137.751077 -267.3546)
			(xy 137.793698 -267.329993) (xy 137.839714 -267.312541) (xy 137.887933 -267.302697) (xy 137.937108 -267.300716)
			(xy 137.985963 -267.306648) (xy 138.033234 -267.32034) (xy 138.077696 -267.341438) (xy 138.118199 -267.369394)
			(xy 138.153692 -267.403486) (xy 138.183257 -267.44283) (xy 138.206128 -267.486407) (xy 138.221712 -267.533088)
			(xy 138.229607 -267.581665) (xy 138.230102 -267.606272) (xy 138.559044 -267.606272) (xy 138.563004 -267.557218)
			(xy 138.574781 -267.509434) (xy 138.594072 -267.464158) (xy 138.620375 -267.422562) (xy 138.65301 -267.385725)
			(xy 138.691131 -267.3546) (xy 138.733752 -267.329993) (xy 138.779768 -267.312541) (xy 138.827987 -267.302697)
			(xy 138.877162 -267.300716) (xy 138.926017 -267.306648) (xy 138.973288 -267.32034) (xy 139.01775 -267.341438)
			(xy 139.058253 -267.369394) (xy 139.093746 -267.403486) (xy 139.123311 -267.44283) (xy 139.146182 -267.486407)
			(xy 139.161766 -267.533088) (xy 139.169661 -267.581665) (xy 139.170156 -267.606272) (xy 139.488413 -267.606272)
			(xy 139.492508 -267.555544) (xy 139.504687 -267.50613) (xy 139.524635 -267.45931) (xy 139.551836 -267.416296)
			(xy 139.585584 -267.378202) (xy 139.625006 -267.346015) (xy 139.66908 -267.320569) (xy 139.716666 -267.302522)
			(xy 139.76653 -267.292342) (xy 139.817382 -267.290293) (xy 139.867903 -267.296427) (xy 139.916787 -267.310587)
			(xy 139.962766 -267.332404) (xy 140.00465 -267.361314) (xy 140.041354 -267.396569) (xy 140.071927 -267.437255)
			(xy 140.095578 -267.482318) (xy 140.111694 -267.530592) (xy 140.119858 -267.580826) (xy 140.12037 -267.606272)
			(xy 140.438898 -267.606272) (xy 140.442858 -267.557218) (xy 140.454635 -267.509434) (xy 140.473926 -267.464158)
			(xy 140.500229 -267.422562) (xy 140.532864 -267.385725) (xy 140.570985 -267.3546) (xy 140.613606 -267.329993)
			(xy 140.659622 -267.312541) (xy 140.707841 -267.302697) (xy 140.757016 -267.300716) (xy 140.805871 -267.306648)
			(xy 140.853142 -267.32034) (xy 140.897604 -267.341438) (xy 140.938107 -267.369394) (xy 140.9736 -267.403486)
			(xy 141.003165 -267.44283) (xy 141.026036 -267.486407) (xy 141.04162 -267.533088) (xy 141.049515 -267.581665)
			(xy 141.05001 -267.606272) (xy 141.378952 -267.606272) (xy 141.382912 -267.557218) (xy 141.394689 -267.509434)
			(xy 141.41398 -267.464158) (xy 141.440283 -267.422562) (xy 141.472918 -267.385725) (xy 141.511039 -267.3546)
			(xy 141.55366 -267.329993) (xy 141.599676 -267.312541) (xy 141.647895 -267.302697) (xy 141.69707 -267.300716)
			(xy 141.745925 -267.306648) (xy 141.793196 -267.32034) (xy 141.837658 -267.341438) (xy 141.878161 -267.369394)
			(xy 141.913654 -267.403486) (xy 141.943219 -267.44283) (xy 141.96609 -267.486407) (xy 141.981674 -267.533088)
			(xy 141.989569 -267.581665) (xy 141.990064 -267.606272) (xy 142.308575 -267.606272) (xy 142.31267 -267.555544)
			(xy 142.324849 -267.50613) (xy 142.344797 -267.45931) (xy 142.371998 -267.416296) (xy 142.405746 -267.378202)
			(xy 142.445168 -267.346015) (xy 142.489242 -267.320569) (xy 142.536828 -267.302522) (xy 142.586692 -267.292342)
			(xy 142.637544 -267.290293) (xy 142.688065 -267.296427) (xy 142.736949 -267.310587) (xy 142.782928 -267.332404)
			(xy 142.824812 -267.361314) (xy 142.861516 -267.396569) (xy 142.892089 -267.437255) (xy 142.91574 -267.482318)
			(xy 142.931856 -267.530592) (xy 142.94002 -267.580826) (xy 142.940532 -267.606272) (xy 143.258806 -267.606272)
			(xy 143.262766 -267.557218) (xy 143.274543 -267.509434) (xy 143.293834 -267.464158) (xy 143.320137 -267.422562)
			(xy 143.352772 -267.385725) (xy 143.390893 -267.3546) (xy 143.433514 -267.329993) (xy 143.47953 -267.312541)
			(xy 143.527749 -267.302697) (xy 143.576924 -267.300716) (xy 143.625779 -267.306648) (xy 143.67305 -267.32034)
			(xy 143.717512 -267.341438) (xy 143.758015 -267.369394) (xy 143.793508 -267.403486) (xy 143.823073 -267.44283)
			(xy 143.845944 -267.486407) (xy 143.861528 -267.533088) (xy 143.869423 -267.581665) (xy 143.869918 -267.606272)
			(xy 145.138914 -267.606272) (xy 145.142874 -267.557218) (xy 145.154651 -267.509434) (xy 145.173942 -267.464158)
			(xy 145.200245 -267.422562) (xy 145.23288 -267.385725) (xy 145.271001 -267.3546) (xy 145.313622 -267.329993)
			(xy 145.359638 -267.312541) (xy 145.407857 -267.302697) (xy 145.457032 -267.300716) (xy 145.505887 -267.306648)
			(xy 145.553158 -267.32034) (xy 145.59762 -267.341438) (xy 145.638123 -267.369394) (xy 145.673616 -267.403486)
			(xy 145.703181 -267.44283) (xy 145.726052 -267.486407) (xy 145.741636 -267.533088) (xy 145.749531 -267.581665)
			(xy 145.750026 -267.606272) (xy 145.749531 -267.630879) (xy 145.741636 -267.679456) (xy 145.726052 -267.726137)
			(xy 145.703181 -267.769714) (xy 145.673616 -267.809058) (xy 145.638123 -267.84315) (xy 145.59762 -267.871106)
			(xy 145.553158 -267.892204) (xy 145.505887 -267.905896) (xy 145.457032 -267.911828) (xy 145.407857 -267.909847)
			(xy 145.359638 -267.900003) (xy 145.313622 -267.882551) (xy 145.271001 -267.857944) (xy 145.23288 -267.826819)
			(xy 145.200245 -267.789982) (xy 145.173942 -267.748386) (xy 145.154651 -267.70311) (xy 145.142874 -267.655326)
			(xy 145.138914 -267.606272) (xy 143.869918 -267.606272) (xy 143.869423 -267.630879) (xy 143.861528 -267.679456)
			(xy 143.845944 -267.726137) (xy 143.823073 -267.769714) (xy 143.793508 -267.809058) (xy 143.758015 -267.84315)
			(xy 143.717512 -267.871106) (xy 143.67305 -267.892204) (xy 143.625779 -267.905896) (xy 143.576924 -267.911828)
			(xy 143.527749 -267.909847) (xy 143.47953 -267.900003) (xy 143.433514 -267.882551) (xy 143.390893 -267.857944)
			(xy 143.352772 -267.826819) (xy 143.320137 -267.789982) (xy 143.293834 -267.748386) (xy 143.274543 -267.70311)
			(xy 143.262766 -267.655326) (xy 143.258806 -267.606272) (xy 142.940532 -267.606272) (xy 142.94002 -267.631718)
			(xy 142.931856 -267.681952) (xy 142.91574 -267.730226) (xy 142.892089 -267.775289) (xy 142.861516 -267.815975)
			(xy 142.824812 -267.85123) (xy 142.782928 -267.88014) (xy 142.736949 -267.901957) (xy 142.688065 -267.916117)
			(xy 142.637544 -267.922251) (xy 142.586692 -267.920202) (xy 142.536828 -267.910022) (xy 142.489242 -267.891975)
			(xy 142.445168 -267.866529) (xy 142.405746 -267.834342) (xy 142.371998 -267.796248) (xy 142.344797 -267.753234)
			(xy 142.324849 -267.706414) (xy 142.31267 -267.657) (xy 142.308575 -267.606272) (xy 141.990064 -267.606272)
			(xy 141.989569 -267.630879) (xy 141.981674 -267.679456) (xy 141.96609 -267.726137) (xy 141.943219 -267.769714)
			(xy 141.913654 -267.809058) (xy 141.878161 -267.84315) (xy 141.837658 -267.871106) (xy 141.793196 -267.892204)
			(xy 141.745925 -267.905896) (xy 141.69707 -267.911828) (xy 141.647895 -267.909847) (xy 141.599676 -267.900003)
			(xy 141.55366 -267.882551) (xy 141.511039 -267.857944) (xy 141.472918 -267.826819) (xy 141.440283 -267.789982)
			(xy 141.41398 -267.748386) (xy 141.394689 -267.70311) (xy 141.382912 -267.655326) (xy 141.378952 -267.606272)
			(xy 141.05001 -267.606272) (xy 141.049515 -267.630879) (xy 141.04162 -267.679456) (xy 141.026036 -267.726137)
			(xy 141.003165 -267.769714) (xy 140.9736 -267.809058) (xy 140.938107 -267.84315) (xy 140.897604 -267.871106)
			(xy 140.853142 -267.892204) (xy 140.805871 -267.905896) (xy 140.757016 -267.911828) (xy 140.707841 -267.909847)
			(xy 140.659622 -267.900003) (xy 140.613606 -267.882551) (xy 140.570985 -267.857944) (xy 140.532864 -267.826819)
			(xy 140.500229 -267.789982) (xy 140.473926 -267.748386) (xy 140.454635 -267.70311) (xy 140.442858 -267.655326)
			(xy 140.438898 -267.606272) (xy 140.12037 -267.606272) (xy 140.119858 -267.631718) (xy 140.111694 -267.681952)
			(xy 140.095578 -267.730226) (xy 140.071927 -267.775289) (xy 140.041354 -267.815975) (xy 140.00465 -267.85123)
			(xy 139.962766 -267.88014) (xy 139.916787 -267.901957) (xy 139.867903 -267.916117) (xy 139.817382 -267.922251)
			(xy 139.76653 -267.920202) (xy 139.716666 -267.910022) (xy 139.66908 -267.891975) (xy 139.625006 -267.866529)
			(xy 139.585584 -267.834342) (xy 139.551836 -267.796248) (xy 139.524635 -267.753234) (xy 139.504687 -267.706414)
			(xy 139.492508 -267.657) (xy 139.488413 -267.606272) (xy 139.170156 -267.606272) (xy 139.169661 -267.630879)
			(xy 139.161766 -267.679456) (xy 139.146182 -267.726137) (xy 139.123311 -267.769714) (xy 139.093746 -267.809058)
			(xy 139.058253 -267.84315) (xy 139.01775 -267.871106) (xy 138.973288 -267.892204) (xy 138.926017 -267.905896)
			(xy 138.877162 -267.911828) (xy 138.827987 -267.909847) (xy 138.779768 -267.900003) (xy 138.733752 -267.882551)
			(xy 138.691131 -267.857944) (xy 138.65301 -267.826819) (xy 138.620375 -267.789982) (xy 138.594072 -267.748386)
			(xy 138.574781 -267.70311) (xy 138.563004 -267.655326) (xy 138.559044 -267.606272) (xy 138.230102 -267.606272)
			(xy 138.229607 -267.630879) (xy 138.221712 -267.679456) (xy 138.206128 -267.726137) (xy 138.183257 -267.769714)
			(xy 138.153692 -267.809058) (xy 138.118199 -267.84315) (xy 138.077696 -267.871106) (xy 138.033234 -267.892204)
			(xy 137.985963 -267.905896) (xy 137.937108 -267.911828) (xy 137.887933 -267.909847) (xy 137.839714 -267.900003)
			(xy 137.793698 -267.882551) (xy 137.751077 -267.857944) (xy 137.712956 -267.826819) (xy 137.680321 -267.789982)
			(xy 137.654018 -267.748386) (xy 137.634727 -267.70311) (xy 137.62295 -267.655326) (xy 137.61899 -267.606272)
			(xy 137.290048 -267.606272) (xy 137.289553 -267.630879) (xy 137.281658 -267.679456) (xy 137.266074 -267.726137)
			(xy 137.243203 -267.769714) (xy 137.213638 -267.809058) (xy 137.178145 -267.84315) (xy 137.137642 -267.871106)
			(xy 137.09318 -267.892204) (xy 137.045909 -267.905896) (xy 136.997054 -267.911828) (xy 136.947879 -267.909847)
			(xy 136.89966 -267.900003) (xy 136.853644 -267.882551) (xy 136.811023 -267.857944) (xy 136.772902 -267.826819)
			(xy 136.740267 -267.789982) (xy 136.713964 -267.748386) (xy 136.694673 -267.70311) (xy 136.682896 -267.655326)
			(xy 136.678936 -267.606272) (xy 136.360408 -267.606272) (xy 136.359896 -267.631718) (xy 136.351732 -267.681952)
			(xy 136.335616 -267.730226) (xy 136.311965 -267.775289) (xy 136.281392 -267.815975) (xy 136.244688 -267.85123)
			(xy 136.202804 -267.88014) (xy 136.156825 -267.901957) (xy 136.107941 -267.916117) (xy 136.05742 -267.922251)
			(xy 136.006568 -267.920202) (xy 135.956704 -267.910022) (xy 135.909118 -267.891975) (xy 135.865044 -267.866529)
			(xy 135.825622 -267.834342) (xy 135.791874 -267.796248) (xy 135.764673 -267.753234) (xy 135.744725 -267.706414)
			(xy 135.732546 -267.657) (xy 135.728451 -267.606272) (xy 135.40994 -267.606272) (xy 135.409445 -267.630879)
			(xy 135.40155 -267.679456) (xy 135.385966 -267.726137) (xy 135.363095 -267.769714) (xy 135.33353 -267.809058)
			(xy 135.298037 -267.84315) (xy 135.257534 -267.871106) (xy 135.213072 -267.892204) (xy 135.165801 -267.905896)
			(xy 135.116946 -267.911828) (xy 135.067771 -267.909847) (xy 135.019552 -267.900003) (xy 134.973536 -267.882551)
			(xy 134.930915 -267.857944) (xy 134.892794 -267.826819) (xy 134.860159 -267.789982) (xy 134.833856 -267.748386)
			(xy 134.814565 -267.70311) (xy 134.802788 -267.655326) (xy 134.798828 -267.606272) (xy 134.47014 -267.606272)
			(xy 134.469645 -267.630879) (xy 134.46175 -267.679456) (xy 134.446166 -267.726137) (xy 134.423295 -267.769714)
			(xy 134.39373 -267.809058) (xy 134.358237 -267.84315) (xy 134.317734 -267.871106) (xy 134.273272 -267.892204)
			(xy 134.226001 -267.905896) (xy 134.177146 -267.911828) (xy 134.127971 -267.909847) (xy 134.079752 -267.900003)
			(xy 134.033736 -267.882551) (xy 133.991115 -267.857944) (xy 133.952994 -267.826819) (xy 133.920359 -267.789982)
			(xy 133.894056 -267.748386) (xy 133.874765 -267.70311) (xy 133.862988 -267.655326) (xy 133.859028 -267.606272)
			(xy 133.5405 -267.606272) (xy 133.539988 -267.631718) (xy 133.531824 -267.681952) (xy 133.515708 -267.730226)
			(xy 133.492057 -267.775289) (xy 133.461484 -267.815975) (xy 133.42478 -267.85123) (xy 133.382896 -267.88014)
			(xy 133.336917 -267.901957) (xy 133.288033 -267.916117) (xy 133.237512 -267.922251) (xy 133.18666 -267.920202)
			(xy 133.136796 -267.910022) (xy 133.08921 -267.891975) (xy 133.045136 -267.866529) (xy 133.005714 -267.834342)
			(xy 132.971966 -267.796248) (xy 132.944765 -267.753234) (xy 132.924817 -267.706414) (xy 132.912638 -267.657)
			(xy 132.908543 -267.606272) (xy 132.590032 -267.606272) (xy 132.589537 -267.630879) (xy 132.581642 -267.679456)
			(xy 132.566058 -267.726137) (xy 132.543187 -267.769714) (xy 132.513622 -267.809058) (xy 132.478129 -267.84315)
			(xy 132.437626 -267.871106) (xy 132.393164 -267.892204) (xy 132.345893 -267.905896) (xy 132.297038 -267.911828)
			(xy 132.247863 -267.909847) (xy 132.199644 -267.900003) (xy 132.153628 -267.882551) (xy 132.111007 -267.857944)
			(xy 132.072886 -267.826819) (xy 132.040251 -267.789982) (xy 132.013948 -267.748386) (xy 131.994657 -267.70311)
			(xy 131.98288 -267.655326) (xy 131.97892 -267.606272) (xy 131.649978 -267.606272) (xy 131.649483 -267.630879)
			(xy 131.641588 -267.679456) (xy 131.626004 -267.726137) (xy 131.603133 -267.769714) (xy 131.573568 -267.809058)
			(xy 131.538075 -267.84315) (xy 131.497572 -267.871106) (xy 131.45311 -267.892204) (xy 131.405839 -267.905896)
			(xy 131.356984 -267.911828) (xy 131.307809 -267.909847) (xy 131.25959 -267.900003) (xy 131.213574 -267.882551)
			(xy 131.170953 -267.857944) (xy 131.132832 -267.826819) (xy 131.100197 -267.789982) (xy 131.073894 -267.748386)
			(xy 131.054603 -267.70311) (xy 131.042826 -267.655326) (xy 131.038866 -267.606272) (xy 130.710178 -267.606272)
			(xy 130.709683 -267.630879) (xy 130.701788 -267.679456) (xy 130.686204 -267.726137) (xy 130.663333 -267.769714)
			(xy 130.633768 -267.809058) (xy 130.598275 -267.84315) (xy 130.557772 -267.871106) (xy 130.51331 -267.892204)
			(xy 130.466039 -267.905896) (xy 130.417184 -267.911828) (xy 130.368009 -267.909847) (xy 130.31979 -267.900003)
			(xy 130.273774 -267.882551) (xy 130.231153 -267.857944) (xy 130.193032 -267.826819) (xy 130.160397 -267.789982)
			(xy 130.134094 -267.748386) (xy 130.114803 -267.70311) (xy 130.103026 -267.655326) (xy 130.099066 -267.606272)
			(xy 129.780538 -267.606272) (xy 129.780026 -267.631718) (xy 129.771862 -267.681952) (xy 129.755746 -267.730226)
			(xy 129.732095 -267.775289) (xy 129.701522 -267.815975) (xy 129.664818 -267.85123) (xy 129.622934 -267.88014)
			(xy 129.576955 -267.901957) (xy 129.528071 -267.916117) (xy 129.47755 -267.922251) (xy 129.426698 -267.920202)
			(xy 129.376834 -267.910022) (xy 129.329248 -267.891975) (xy 129.285174 -267.866529) (xy 129.245752 -267.834342)
			(xy 129.212004 -267.796248) (xy 129.184803 -267.753234) (xy 129.164855 -267.706414) (xy 129.152676 -267.657)
			(xy 129.148581 -267.606272) (xy 128.83007 -267.606272) (xy 128.829575 -267.630879) (xy 128.82168 -267.679456)
			(xy 128.806096 -267.726137) (xy 128.783225 -267.769714) (xy 128.75366 -267.809058) (xy 128.718167 -267.84315)
			(xy 128.677664 -267.871106) (xy 128.633202 -267.892204) (xy 128.585931 -267.905896) (xy 128.537076 -267.911828)
			(xy 128.487901 -267.909847) (xy 128.439682 -267.900003) (xy 128.393666 -267.882551) (xy 128.351045 -267.857944)
			(xy 128.312924 -267.826819) (xy 128.280289 -267.789982) (xy 128.253986 -267.748386) (xy 128.234695 -267.70311)
			(xy 128.222918 -267.655326) (xy 128.218958 -267.606272) (xy 126.949962 -267.606272) (xy 126.949822 -267.619035)
			(xy 126.947657 -267.644468) (xy 126.945644 -267.657072) (xy 126.945898 -267.657072) (xy 126.941987 -267.677851)
			(xy 126.929205 -267.718154) (xy 126.911008 -267.756319) (xy 126.89967 -267.774166) (xy 126.89374 -267.784243)
			(xy 126.89083 -267.807418) (xy 126.898426 -267.829505) (xy 126.906274 -267.838174) (xy 127.18288 -268.11478)
			(xy 127.193802 -268.121384) (xy 127.200152 -268.123162) (xy 127.223614 -268.130507) (xy 127.268 -268.151634)
			(xy 127.308428 -268.179601) (xy 127.343853 -268.213685) (xy 127.373359 -268.253004) (xy 127.396183 -268.296542)
			(xy 127.411736 -268.343176) (xy 127.419616 -268.391699) (xy 127.420116 -268.416278) (xy 127.749058 -268.416278)
			(xy 127.753018 -268.367224) (xy 127.764795 -268.31944) (xy 127.784086 -268.274164) (xy 127.810389 -268.232568)
			(xy 127.843024 -268.195731) (xy 127.881145 -268.164606) (xy 127.923766 -268.139999) (xy 127.969782 -268.122547)
			(xy 128.018001 -268.112703) (xy 128.067176 -268.110722) (xy 128.116031 -268.116654) (xy 128.163302 -268.130346)
			(xy 128.207764 -268.151444) (xy 128.248267 -268.1794) (xy 128.28376 -268.213492) (xy 128.313325 -268.252836)
			(xy 128.336196 -268.296413) (xy 128.35178 -268.343094) (xy 128.359675 -268.391671) (xy 128.36017 -268.416278)
			(xy 128.688858 -268.416278) (xy 128.692818 -268.367224) (xy 128.704595 -268.31944) (xy 128.723886 -268.274164)
			(xy 128.750189 -268.232568) (xy 128.782824 -268.195731) (xy 128.820945 -268.164606) (xy 128.863566 -268.139999)
			(xy 128.909582 -268.122547) (xy 128.957801 -268.112703) (xy 129.006976 -268.110722) (xy 129.055831 -268.116654)
			(xy 129.103102 -268.130346) (xy 129.147564 -268.151444) (xy 129.188067 -268.1794) (xy 129.22356 -268.213492)
			(xy 129.253125 -268.252836) (xy 129.275996 -268.296413) (xy 129.29158 -268.343094) (xy 129.299475 -268.391671)
			(xy 129.29997 -268.416278) (xy 129.628912 -268.416278) (xy 129.632872 -268.367224) (xy 129.644649 -268.31944)
			(xy 129.66394 -268.274164) (xy 129.690243 -268.232568) (xy 129.722878 -268.195731) (xy 129.760999 -268.164606)
			(xy 129.80362 -268.139999) (xy 129.849636 -268.122547) (xy 129.897855 -268.112703) (xy 129.94703 -268.110722)
			(xy 129.995885 -268.116654) (xy 130.043156 -268.130346) (xy 130.087618 -268.151444) (xy 130.128121 -268.1794)
			(xy 130.163614 -268.213492) (xy 130.193179 -268.252836) (xy 130.21605 -268.296413) (xy 130.231634 -268.343094)
			(xy 130.239529 -268.391671) (xy 130.240024 -268.416278) (xy 131.50902 -268.416278) (xy 131.51298 -268.367224)
			(xy 131.524757 -268.31944) (xy 131.544048 -268.274164) (xy 131.570351 -268.232568) (xy 131.602986 -268.195731)
			(xy 131.641107 -268.164606) (xy 131.683728 -268.139999) (xy 131.729744 -268.122547) (xy 131.777963 -268.112703)
			(xy 131.827138 -268.110722) (xy 131.875993 -268.116654) (xy 131.923264 -268.130346) (xy 131.967726 -268.151444)
			(xy 132.008229 -268.1794) (xy 132.043722 -268.213492) (xy 132.073287 -268.252836) (xy 132.096158 -268.296413)
			(xy 132.111742 -268.343094) (xy 132.119637 -268.391671) (xy 132.120132 -268.416278) (xy 132.44882 -268.416278)
			(xy 132.45278 -268.367224) (xy 132.464557 -268.31944) (xy 132.483848 -268.274164) (xy 132.510151 -268.232568)
			(xy 132.542786 -268.195731) (xy 132.580907 -268.164606) (xy 132.623528 -268.139999) (xy 132.669544 -268.122547)
			(xy 132.717763 -268.112703) (xy 132.766938 -268.110722) (xy 132.815793 -268.116654) (xy 132.863064 -268.130346)
			(xy 132.907526 -268.151444) (xy 132.948029 -268.1794) (xy 132.983522 -268.213492) (xy 133.013087 -268.252836)
			(xy 133.035958 -268.296413) (xy 133.051542 -268.343094) (xy 133.059437 -268.391671) (xy 133.059932 -268.416278)
			(xy 133.388874 -268.416278) (xy 133.392834 -268.367224) (xy 133.404611 -268.31944) (xy 133.423902 -268.274164)
			(xy 133.450205 -268.232568) (xy 133.48284 -268.195731) (xy 133.520961 -268.164606) (xy 133.563582 -268.139999)
			(xy 133.609598 -268.122547) (xy 133.657817 -268.112703) (xy 133.706992 -268.110722) (xy 133.755847 -268.116654)
			(xy 133.803118 -268.130346) (xy 133.84758 -268.151444) (xy 133.888083 -268.1794) (xy 133.923576 -268.213492)
			(xy 133.953141 -268.252836) (xy 133.976012 -268.296413) (xy 133.991596 -268.343094) (xy 133.999491 -268.391671)
			(xy 133.999986 -268.416278) (xy 134.328928 -268.416278) (xy 134.332888 -268.367224) (xy 134.344665 -268.31944)
			(xy 134.363956 -268.274164) (xy 134.390259 -268.232568) (xy 134.422894 -268.195731) (xy 134.461015 -268.164606)
			(xy 134.503636 -268.139999) (xy 134.549652 -268.122547) (xy 134.597871 -268.112703) (xy 134.647046 -268.110722)
			(xy 134.695901 -268.116654) (xy 134.743172 -268.130346) (xy 134.787634 -268.151444) (xy 134.828137 -268.1794)
			(xy 134.86363 -268.213492) (xy 134.893195 -268.252836) (xy 134.916066 -268.296413) (xy 134.93165 -268.343094)
			(xy 134.939545 -268.391671) (xy 134.94004 -268.416278) (xy 135.268982 -268.416278) (xy 135.272942 -268.367224)
			(xy 135.284719 -268.31944) (xy 135.30401 -268.274164) (xy 135.330313 -268.232568) (xy 135.362948 -268.195731)
			(xy 135.401069 -268.164606) (xy 135.44369 -268.139999) (xy 135.489706 -268.122547) (xy 135.537925 -268.112703)
			(xy 135.5871 -268.110722) (xy 135.635955 -268.116654) (xy 135.683226 -268.130346) (xy 135.727688 -268.151444)
			(xy 135.768191 -268.1794) (xy 135.803684 -268.213492) (xy 135.833249 -268.252836) (xy 135.85612 -268.296413)
			(xy 135.871704 -268.343094) (xy 135.879599 -268.391671) (xy 135.880094 -268.416278) (xy 136.209036 -268.416278)
			(xy 136.212996 -268.367224) (xy 136.224773 -268.31944) (xy 136.244064 -268.274164) (xy 136.270367 -268.232568)
			(xy 136.303002 -268.195731) (xy 136.341123 -268.164606) (xy 136.383744 -268.139999) (xy 136.42976 -268.122547)
			(xy 136.477979 -268.112703) (xy 136.527154 -268.110722) (xy 136.576009 -268.116654) (xy 136.62328 -268.130346)
			(xy 136.667742 -268.151444) (xy 136.708245 -268.1794) (xy 136.743738 -268.213492) (xy 136.773303 -268.252836)
			(xy 136.796174 -268.296413) (xy 136.811758 -268.343094) (xy 136.819653 -268.391671) (xy 136.820148 -268.416278)
			(xy 138.08889 -268.416278) (xy 138.09285 -268.367224) (xy 138.104627 -268.31944) (xy 138.123918 -268.274164)
			(xy 138.150221 -268.232568) (xy 138.182856 -268.195731) (xy 138.220977 -268.164606) (xy 138.263598 -268.139999)
			(xy 138.309614 -268.122547) (xy 138.357833 -268.112703) (xy 138.407008 -268.110722) (xy 138.455863 -268.116654)
			(xy 138.503134 -268.130346) (xy 138.547596 -268.151444) (xy 138.588099 -268.1794) (xy 138.623592 -268.213492)
			(xy 138.653157 -268.252836) (xy 138.676028 -268.296413) (xy 138.691612 -268.343094) (xy 138.699507 -268.391671)
			(xy 138.700002 -268.416278) (xy 139.028944 -268.416278) (xy 139.032904 -268.367224) (xy 139.044681 -268.31944)
			(xy 139.063972 -268.274164) (xy 139.090275 -268.232568) (xy 139.12291 -268.195731) (xy 139.161031 -268.164606)
			(xy 139.203652 -268.139999) (xy 139.249668 -268.122547) (xy 139.297887 -268.112703) (xy 139.347062 -268.110722)
			(xy 139.395917 -268.116654) (xy 139.443188 -268.130346) (xy 139.48765 -268.151444) (xy 139.528153 -268.1794)
			(xy 139.563646 -268.213492) (xy 139.593211 -268.252836) (xy 139.616082 -268.296413) (xy 139.631666 -268.343094)
			(xy 139.639561 -268.391671) (xy 139.640056 -268.416278) (xy 139.968998 -268.416278) (xy 139.972958 -268.367224)
			(xy 139.984735 -268.31944) (xy 140.004026 -268.274164) (xy 140.030329 -268.232568) (xy 140.062964 -268.195731)
			(xy 140.101085 -268.164606) (xy 140.143706 -268.139999) (xy 140.189722 -268.122547) (xy 140.237941 -268.112703)
			(xy 140.287116 -268.110722) (xy 140.335971 -268.116654) (xy 140.383242 -268.130346) (xy 140.427704 -268.151444)
			(xy 140.468207 -268.1794) (xy 140.5037 -268.213492) (xy 140.533265 -268.252836) (xy 140.556136 -268.296413)
			(xy 140.57172 -268.343094) (xy 140.579615 -268.391671) (xy 140.58011 -268.416278) (xy 140.909052 -268.416278)
			(xy 140.913012 -268.367224) (xy 140.924789 -268.31944) (xy 140.94408 -268.274164) (xy 140.970383 -268.232568)
			(xy 141.003018 -268.195731) (xy 141.041139 -268.164606) (xy 141.08376 -268.139999) (xy 141.129776 -268.122547)
			(xy 141.177995 -268.112703) (xy 141.22717 -268.110722) (xy 141.276025 -268.116654) (xy 141.323296 -268.130346)
			(xy 141.367758 -268.151444) (xy 141.408261 -268.1794) (xy 141.443754 -268.213492) (xy 141.473319 -268.252836)
			(xy 141.49619 -268.296413) (xy 141.511774 -268.343094) (xy 141.519669 -268.391671) (xy 141.520164 -268.416278)
			(xy 141.848852 -268.416278) (xy 141.852812 -268.367224) (xy 141.864589 -268.31944) (xy 141.88388 -268.274164)
			(xy 141.910183 -268.232568) (xy 141.942818 -268.195731) (xy 141.980939 -268.164606) (xy 142.02356 -268.139999)
			(xy 142.069576 -268.122547) (xy 142.117795 -268.112703) (xy 142.16697 -268.110722) (xy 142.215825 -268.116654)
			(xy 142.263096 -268.130346) (xy 142.307558 -268.151444) (xy 142.348061 -268.1794) (xy 142.383554 -268.213492)
			(xy 142.413119 -268.252836) (xy 142.43599 -268.296413) (xy 142.451574 -268.343094) (xy 142.459469 -268.391671)
			(xy 142.459964 -268.416278) (xy 142.788906 -268.416278) (xy 142.792866 -268.367224) (xy 142.804643 -268.31944)
			(xy 142.823934 -268.274164) (xy 142.850237 -268.232568) (xy 142.882872 -268.195731) (xy 142.920993 -268.164606)
			(xy 142.963614 -268.139999) (xy 143.00963 -268.122547) (xy 143.057849 -268.112703) (xy 143.107024 -268.110722)
			(xy 143.155879 -268.116654) (xy 143.20315 -268.130346) (xy 143.247612 -268.151444) (xy 143.288115 -268.1794)
			(xy 143.323608 -268.213492) (xy 143.353173 -268.252836) (xy 143.376044 -268.296413) (xy 143.391628 -268.343094)
			(xy 143.399523 -268.391671) (xy 143.400018 -268.416278) (xy 144.669014 -268.416278) (xy 144.672974 -268.367224)
			(xy 144.684751 -268.31944) (xy 144.704042 -268.274164) (xy 144.730345 -268.232568) (xy 144.76298 -268.195731)
			(xy 144.801101 -268.164606) (xy 144.843722 -268.139999) (xy 144.889738 -268.122547) (xy 144.937957 -268.112703)
			(xy 144.987132 -268.110722) (xy 145.035987 -268.116654) (xy 145.083258 -268.130346) (xy 145.125393 -268.15034)
			(xy 146.737082 -268.15034) (xy 146.741042 -268.101286) (xy 146.752819 -268.053502) (xy 146.77211 -268.008226)
			(xy 146.798413 -267.96663) (xy 146.831048 -267.929793) (xy 146.869169 -267.898668) (xy 146.91179 -267.874061)
			(xy 146.957806 -267.856609) (xy 147.006025 -267.846765) (xy 147.0552 -267.844784) (xy 147.104055 -267.850716)
			(xy 147.151326 -267.864408) (xy 147.195603 -267.885418) (xy 164.058615 -267.885418) (xy 164.06255 -267.831647)
			(xy 164.074273 -267.779023) (xy 164.093533 -267.728666) (xy 164.119919 -267.681649) (xy 164.152871 -267.638976)
			(xy 164.191684 -267.601555) (xy 164.235532 -267.570185) (xy 164.28348 -267.545533) (xy 164.334507 -267.528125)
			(xy 164.387525 -267.518332) (xy 164.441404 -267.516363) (xy 164.494995 -267.52226) (xy 164.547156 -267.535896)
			(xy 164.596776 -267.556983) (xy 164.642797 -267.585069) (xy 164.684239 -267.619557) (xy 164.720217 -267.659711)
			(xy 164.749965 -267.704675) (xy 164.77285 -267.753492) (xy 164.788382 -267.805121) (xy 164.796232 -267.858461)
			(xy 164.796724 -267.885418) (xy 164.796232 -267.912375) (xy 164.788382 -267.965715) (xy 164.77285 -268.017344)
			(xy 164.749965 -268.066161) (xy 164.720217 -268.111125) (xy 164.684239 -268.151279) (xy 164.642797 -268.185767)
			(xy 164.596776 -268.213853) (xy 164.547156 -268.23494) (xy 164.494995 -268.248576) (xy 164.441404 -268.254473)
			(xy 164.387525 -268.252504) (xy 164.334507 -268.242711) (xy 164.28348 -268.225303) (xy 164.235532 -268.200651)
			(xy 164.191684 -268.169281) (xy 164.152871 -268.13186) (xy 164.119919 -268.089187) (xy 164.093533 -268.04217)
			(xy 164.074273 -267.991813) (xy 164.06255 -267.939189) (xy 164.058615 -267.885418) (xy 147.195603 -267.885418)
			(xy 147.195788 -267.885506) (xy 147.236291 -267.913462) (xy 147.271784 -267.947554) (xy 147.301349 -267.986898)
			(xy 147.32422 -268.030475) (xy 147.339804 -268.077156) (xy 147.347699 -268.125733) (xy 147.348194 -268.15034)
			(xy 147.347699 -268.174947) (xy 147.339804 -268.223524) (xy 147.32422 -268.270205) (xy 147.301349 -268.313782)
			(xy 147.271784 -268.353126) (xy 147.236291 -268.387218) (xy 147.195788 -268.415174) (xy 147.151326 -268.436272)
			(xy 147.104055 -268.449964) (xy 147.0552 -268.455896) (xy 147.006025 -268.453915) (xy 146.957806 -268.444071)
			(xy 146.91179 -268.426619) (xy 146.869169 -268.402012) (xy 146.831048 -268.370887) (xy 146.798413 -268.33405)
			(xy 146.77211 -268.292454) (xy 146.752819 -268.247178) (xy 146.741042 -268.199394) (xy 146.737082 -268.15034)
			(xy 145.125393 -268.15034) (xy 145.12772 -268.151444) (xy 145.168223 -268.1794) (xy 145.203716 -268.213492)
			(xy 145.233281 -268.252836) (xy 145.256152 -268.296413) (xy 145.271736 -268.343094) (xy 145.279631 -268.391671)
			(xy 145.280126 -268.416278) (xy 145.279631 -268.440885) (xy 145.271736 -268.489462) (xy 145.256152 -268.536143)
			(xy 145.233281 -268.57972) (xy 145.203716 -268.619064) (xy 145.168223 -268.653156) (xy 145.12772 -268.681112)
			(xy 145.083258 -268.70221) (xy 145.035987 -268.715902) (xy 144.987132 -268.721834) (xy 144.937957 -268.719853)
			(xy 144.889738 -268.710009) (xy 144.843722 -268.692557) (xy 144.801101 -268.66795) (xy 144.76298 -268.636825)
			(xy 144.730345 -268.599988) (xy 144.704042 -268.558392) (xy 144.684751 -268.513116) (xy 144.672974 -268.465332)
			(xy 144.669014 -268.416278) (xy 143.400018 -268.416278) (xy 143.399523 -268.440885) (xy 143.391628 -268.489462)
			(xy 143.376044 -268.536143) (xy 143.353173 -268.57972) (xy 143.323608 -268.619064) (xy 143.288115 -268.653156)
			(xy 143.247612 -268.681112) (xy 143.20315 -268.70221) (xy 143.155879 -268.715902) (xy 143.107024 -268.721834)
			(xy 143.057849 -268.719853) (xy 143.00963 -268.710009) (xy 142.963614 -268.692557) (xy 142.920993 -268.66795)
			(xy 142.882872 -268.636825) (xy 142.850237 -268.599988) (xy 142.823934 -268.558392) (xy 142.804643 -268.513116)
			(xy 142.792866 -268.465332) (xy 142.788906 -268.416278) (xy 142.459964 -268.416278) (xy 142.459469 -268.440885)
			(xy 142.451574 -268.489462) (xy 142.43599 -268.536143) (xy 142.413119 -268.57972) (xy 142.383554 -268.619064)
			(xy 142.348061 -268.653156) (xy 142.307558 -268.681112) (xy 142.263096 -268.70221) (xy 142.215825 -268.715902)
			(xy 142.16697 -268.721834) (xy 142.117795 -268.719853) (xy 142.069576 -268.710009) (xy 142.02356 -268.692557)
			(xy 141.980939 -268.66795) (xy 141.942818 -268.636825) (xy 141.910183 -268.599988) (xy 141.88388 -268.558392)
			(xy 141.864589 -268.513116) (xy 141.852812 -268.465332) (xy 141.848852 -268.416278) (xy 141.520164 -268.416278)
			(xy 141.519669 -268.440885) (xy 141.511774 -268.489462) (xy 141.49619 -268.536143) (xy 141.473319 -268.57972)
			(xy 141.443754 -268.619064) (xy 141.408261 -268.653156) (xy 141.367758 -268.681112) (xy 141.323296 -268.70221)
			(xy 141.276025 -268.715902) (xy 141.22717 -268.721834) (xy 141.177995 -268.719853) (xy 141.129776 -268.710009)
			(xy 141.08376 -268.692557) (xy 141.041139 -268.66795) (xy 141.003018 -268.636825) (xy 140.970383 -268.599988)
			(xy 140.94408 -268.558392) (xy 140.924789 -268.513116) (xy 140.913012 -268.465332) (xy 140.909052 -268.416278)
			(xy 140.58011 -268.416278) (xy 140.579615 -268.440885) (xy 140.57172 -268.489462) (xy 140.556136 -268.536143)
			(xy 140.533265 -268.57972) (xy 140.5037 -268.619064) (xy 140.468207 -268.653156) (xy 140.427704 -268.681112)
			(xy 140.383242 -268.70221) (xy 140.335971 -268.715902) (xy 140.287116 -268.721834) (xy 140.237941 -268.719853)
			(xy 140.189722 -268.710009) (xy 140.143706 -268.692557) (xy 140.101085 -268.66795) (xy 140.062964 -268.636825)
			(xy 140.030329 -268.599988) (xy 140.004026 -268.558392) (xy 139.984735 -268.513116) (xy 139.972958 -268.465332)
			(xy 139.968998 -268.416278) (xy 139.640056 -268.416278) (xy 139.639561 -268.440885) (xy 139.631666 -268.489462)
			(xy 139.616082 -268.536143) (xy 139.593211 -268.57972) (xy 139.563646 -268.619064) (xy 139.528153 -268.653156)
			(xy 139.48765 -268.681112) (xy 139.443188 -268.70221) (xy 139.395917 -268.715902) (xy 139.347062 -268.721834)
			(xy 139.297887 -268.719853) (xy 139.249668 -268.710009) (xy 139.203652 -268.692557) (xy 139.161031 -268.66795)
			(xy 139.12291 -268.636825) (xy 139.090275 -268.599988) (xy 139.063972 -268.558392) (xy 139.044681 -268.513116)
			(xy 139.032904 -268.465332) (xy 139.028944 -268.416278) (xy 138.700002 -268.416278) (xy 138.699507 -268.440885)
			(xy 138.691612 -268.489462) (xy 138.676028 -268.536143) (xy 138.653157 -268.57972) (xy 138.623592 -268.619064)
			(xy 138.588099 -268.653156) (xy 138.547596 -268.681112) (xy 138.503134 -268.70221) (xy 138.455863 -268.715902)
			(xy 138.407008 -268.721834) (xy 138.357833 -268.719853) (xy 138.309614 -268.710009) (xy 138.263598 -268.692557)
			(xy 138.220977 -268.66795) (xy 138.182856 -268.636825) (xy 138.150221 -268.599988) (xy 138.123918 -268.558392)
			(xy 138.104627 -268.513116) (xy 138.09285 -268.465332) (xy 138.08889 -268.416278) (xy 136.820148 -268.416278)
			(xy 136.819653 -268.440885) (xy 136.811758 -268.489462) (xy 136.796174 -268.536143) (xy 136.773303 -268.57972)
			(xy 136.743738 -268.619064) (xy 136.708245 -268.653156) (xy 136.667742 -268.681112) (xy 136.62328 -268.70221)
			(xy 136.576009 -268.715902) (xy 136.527154 -268.721834) (xy 136.477979 -268.719853) (xy 136.42976 -268.710009)
			(xy 136.383744 -268.692557) (xy 136.341123 -268.66795) (xy 136.303002 -268.636825) (xy 136.270367 -268.599988)
			(xy 136.244064 -268.558392) (xy 136.224773 -268.513116) (xy 136.212996 -268.465332) (xy 136.209036 -268.416278)
			(xy 135.880094 -268.416278) (xy 135.879599 -268.440885) (xy 135.871704 -268.489462) (xy 135.85612 -268.536143)
			(xy 135.833249 -268.57972) (xy 135.803684 -268.619064) (xy 135.768191 -268.653156) (xy 135.727688 -268.681112)
			(xy 135.683226 -268.70221) (xy 135.635955 -268.715902) (xy 135.5871 -268.721834) (xy 135.537925 -268.719853)
			(xy 135.489706 -268.710009) (xy 135.44369 -268.692557) (xy 135.401069 -268.66795) (xy 135.362948 -268.636825)
			(xy 135.330313 -268.599988) (xy 135.30401 -268.558392) (xy 135.284719 -268.513116) (xy 135.272942 -268.465332)
			(xy 135.268982 -268.416278) (xy 134.94004 -268.416278) (xy 134.939545 -268.440885) (xy 134.93165 -268.489462)
			(xy 134.916066 -268.536143) (xy 134.893195 -268.57972) (xy 134.86363 -268.619064) (xy 134.828137 -268.653156)
			(xy 134.787634 -268.681112) (xy 134.743172 -268.70221) (xy 134.695901 -268.715902) (xy 134.647046 -268.721834)
			(xy 134.597871 -268.719853) (xy 134.549652 -268.710009) (xy 134.503636 -268.692557) (xy 134.461015 -268.66795)
			(xy 134.422894 -268.636825) (xy 134.390259 -268.599988) (xy 134.363956 -268.558392) (xy 134.344665 -268.513116)
			(xy 134.332888 -268.465332) (xy 134.328928 -268.416278) (xy 133.999986 -268.416278) (xy 133.999491 -268.440885)
			(xy 133.991596 -268.489462) (xy 133.976012 -268.536143) (xy 133.953141 -268.57972) (xy 133.923576 -268.619064)
			(xy 133.888083 -268.653156) (xy 133.84758 -268.681112) (xy 133.803118 -268.70221) (xy 133.755847 -268.715902)
			(xy 133.706992 -268.721834) (xy 133.657817 -268.719853) (xy 133.609598 -268.710009) (xy 133.563582 -268.692557)
			(xy 133.520961 -268.66795) (xy 133.48284 -268.636825) (xy 133.450205 -268.599988) (xy 133.423902 -268.558392)
			(xy 133.404611 -268.513116) (xy 133.392834 -268.465332) (xy 133.388874 -268.416278) (xy 133.059932 -268.416278)
			(xy 133.059437 -268.440885) (xy 133.051542 -268.489462) (xy 133.035958 -268.536143) (xy 133.013087 -268.57972)
			(xy 132.983522 -268.619064) (xy 132.948029 -268.653156) (xy 132.907526 -268.681112) (xy 132.863064 -268.70221)
			(xy 132.815793 -268.715902) (xy 132.766938 -268.721834) (xy 132.717763 -268.719853) (xy 132.669544 -268.710009)
			(xy 132.623528 -268.692557) (xy 132.580907 -268.66795) (xy 132.542786 -268.636825) (xy 132.510151 -268.599988)
			(xy 132.483848 -268.558392) (xy 132.464557 -268.513116) (xy 132.45278 -268.465332) (xy 132.44882 -268.416278)
			(xy 132.120132 -268.416278) (xy 132.119637 -268.440885) (xy 132.111742 -268.489462) (xy 132.096158 -268.536143)
			(xy 132.073287 -268.57972) (xy 132.043722 -268.619064) (xy 132.008229 -268.653156) (xy 131.967726 -268.681112)
			(xy 131.923264 -268.70221) (xy 131.875993 -268.715902) (xy 131.827138 -268.721834) (xy 131.777963 -268.719853)
			(xy 131.729744 -268.710009) (xy 131.683728 -268.692557) (xy 131.641107 -268.66795) (xy 131.602986 -268.636825)
			(xy 131.570351 -268.599988) (xy 131.544048 -268.558392) (xy 131.524757 -268.513116) (xy 131.51298 -268.465332)
			(xy 131.50902 -268.416278) (xy 130.240024 -268.416278) (xy 130.239529 -268.440885) (xy 130.231634 -268.489462)
			(xy 130.21605 -268.536143) (xy 130.193179 -268.57972) (xy 130.163614 -268.619064) (xy 130.128121 -268.653156)
			(xy 130.087618 -268.681112) (xy 130.043156 -268.70221) (xy 129.995885 -268.715902) (xy 129.94703 -268.721834)
			(xy 129.897855 -268.719853) (xy 129.849636 -268.710009) (xy 129.80362 -268.692557) (xy 129.760999 -268.66795)
			(xy 129.722878 -268.636825) (xy 129.690243 -268.599988) (xy 129.66394 -268.558392) (xy 129.644649 -268.513116)
			(xy 129.632872 -268.465332) (xy 129.628912 -268.416278) (xy 129.29997 -268.416278) (xy 129.299475 -268.440885)
			(xy 129.29158 -268.489462) (xy 129.275996 -268.536143) (xy 129.253125 -268.57972) (xy 129.22356 -268.619064)
			(xy 129.188067 -268.653156) (xy 129.147564 -268.681112) (xy 129.103102 -268.70221) (xy 129.055831 -268.715902)
			(xy 129.006976 -268.721834) (xy 128.957801 -268.719853) (xy 128.909582 -268.710009) (xy 128.863566 -268.692557)
			(xy 128.820945 -268.66795) (xy 128.782824 -268.636825) (xy 128.750189 -268.599988) (xy 128.723886 -268.558392)
			(xy 128.704595 -268.513116) (xy 128.692818 -268.465332) (xy 128.688858 -268.416278) (xy 128.36017 -268.416278)
			(xy 128.359675 -268.440885) (xy 128.35178 -268.489462) (xy 128.336196 -268.536143) (xy 128.313325 -268.57972)
			(xy 128.28376 -268.619064) (xy 128.248267 -268.653156) (xy 128.207764 -268.681112) (xy 128.163302 -268.70221)
			(xy 128.116031 -268.715902) (xy 128.067176 -268.721834) (xy 128.018001 -268.719853) (xy 127.969782 -268.710009)
			(xy 127.923766 -268.692557) (xy 127.881145 -268.66795) (xy 127.843024 -268.636825) (xy 127.810389 -268.599988)
			(xy 127.784086 -268.558392) (xy 127.764795 -268.513116) (xy 127.753018 -268.465332) (xy 127.749058 -268.416278)
			(xy 127.420116 -268.416278) (xy 127.419976 -268.429041) (xy 127.41781 -268.454474) (xy 127.415798 -268.467078)
			(xy 127.411085 -268.491958) (xy 127.394524 -268.539809) (xy 127.370301 -268.584275) (xy 127.33908 -268.624141)
			(xy 127.301715 -268.658314) (xy 127.259228 -268.685861) (xy 127.23622 -268.69644) (xy 127.22225 -268.702536)
			(xy 127.20574 -268.727682) (xy 127.20574 -268.735302) (xy 168.158683 -268.735302) (xy 168.162618 -268.681531)
			(xy 168.174341 -268.628907) (xy 168.193601 -268.57855) (xy 168.219987 -268.531533) (xy 168.252939 -268.48886)
			(xy 168.291752 -268.451439) (xy 168.3356 -268.420069) (xy 168.383548 -268.395417) (xy 168.434575 -268.378009)
			(xy 168.487593 -268.368216) (xy 168.541472 -268.366247) (xy 168.595063 -268.372144) (xy 168.647224 -268.38578)
			(xy 168.696844 -268.406867) (xy 168.742865 -268.434953) (xy 168.784307 -268.469441) (xy 168.820285 -268.509595)
			(xy 168.850033 -268.554559) (xy 168.872918 -268.603376) (xy 168.88845 -268.655005) (xy 168.8963 -268.708345)
			(xy 168.896792 -268.735302) (xy 168.8963 -268.762259) (xy 168.88845 -268.815599) (xy 168.872918 -268.867228)
			(xy 168.850033 -268.916045) (xy 168.820285 -268.961009) (xy 168.784307 -269.001163) (xy 168.742865 -269.035651)
			(xy 168.696844 -269.063737) (xy 168.647224 -269.084824) (xy 168.595063 -269.09846) (xy 168.541472 -269.104357)
			(xy 168.487593 -269.102388) (xy 168.434575 -269.092595) (xy 168.383548 -269.075187) (xy 168.3356 -269.050535)
			(xy 168.291752 -269.019165) (xy 168.252939 -268.981744) (xy 168.219987 -268.939071) (xy 168.193601 -268.892054)
			(xy 168.174341 -268.841697) (xy 168.162618 -268.789073) (xy 168.158683 -268.735302) (xy 127.20574 -268.735302)
			(xy 127.20574 -268.928596) (xy 127.206182 -268.938442) (xy 127.213596 -268.956683) (xy 127.227361 -268.970762)
			(xy 127.23622 -268.975078) (xy 127.335534 -269.018512) (xy 127.365252 -269.013432) (xy 127.376682 -269.003018)
			(xy 127.39371 -268.987687) (xy 127.431501 -268.961783) (xy 127.472741 -268.94182) (xy 127.516502 -268.928247)
			(xy 127.5618 -268.921369) (xy 127.584708 -268.920976) (xy 127.609964 -268.921498) (xy 127.659788 -268.929813)
			(xy 127.707563 -268.946216) (xy 127.751987 -268.970258) (xy 127.791848 -269.001284) (xy 127.826058 -269.038448)
			(xy 127.853686 -269.080735) (xy 127.873976 -269.126993) (xy 127.886376 -269.17596) (xy 127.890546 -269.226284)
			(xy 128.218958 -269.226284) (xy 128.222918 -269.17723) (xy 128.234695 -269.129446) (xy 128.253986 -269.08417)
			(xy 128.280289 -269.042574) (xy 128.312924 -269.005737) (xy 128.351045 -268.974612) (xy 128.393666 -268.950005)
			(xy 128.439682 -268.932553) (xy 128.487901 -268.922709) (xy 128.537076 -268.920728) (xy 128.585931 -268.92666)
			(xy 128.633202 -268.940352) (xy 128.677664 -268.96145) (xy 128.718167 -268.989406) (xy 128.75366 -269.023498)
			(xy 128.783225 -269.062842) (xy 128.806096 -269.106419) (xy 128.82168 -269.1531) (xy 128.829575 -269.201677)
			(xy 128.83007 -269.226284) (xy 129.148581 -269.226284) (xy 129.152676 -269.175556) (xy 129.164855 -269.126142)
			(xy 129.184803 -269.079322) (xy 129.212004 -269.036308) (xy 129.245752 -268.998214) (xy 129.285174 -268.966027)
			(xy 129.329248 -268.940581) (xy 129.376834 -268.922534) (xy 129.426698 -268.912354) (xy 129.47755 -268.910305)
			(xy 129.528071 -268.916439) (xy 129.576955 -268.930599) (xy 129.622934 -268.952416) (xy 129.664818 -268.981326)
			(xy 129.701522 -269.016581) (xy 129.732095 -269.057267) (xy 129.755746 -269.10233) (xy 129.771862 -269.150604)
			(xy 129.780026 -269.200838) (xy 129.780538 -269.226284) (xy 130.099066 -269.226284) (xy 130.103026 -269.17723)
			(xy 130.114803 -269.129446) (xy 130.134094 -269.08417) (xy 130.160397 -269.042574) (xy 130.193032 -269.005737)
			(xy 130.231153 -268.974612) (xy 130.273774 -268.950005) (xy 130.31979 -268.932553) (xy 130.368009 -268.922709)
			(xy 130.417184 -268.920728) (xy 130.466039 -268.92666) (xy 130.51331 -268.940352) (xy 130.557772 -268.96145)
			(xy 130.598275 -268.989406) (xy 130.633768 -269.023498) (xy 130.663333 -269.062842) (xy 130.686204 -269.106419)
			(xy 130.701788 -269.1531) (xy 130.709683 -269.201677) (xy 130.710178 -269.226284) (xy 131.038866 -269.226284)
			(xy 131.042826 -269.17723) (xy 131.054603 -269.129446) (xy 131.073894 -269.08417) (xy 131.100197 -269.042574)
			(xy 131.132832 -269.005737) (xy 131.170953 -268.974612) (xy 131.213574 -268.950005) (xy 131.25959 -268.932553)
			(xy 131.307809 -268.922709) (xy 131.356984 -268.920728) (xy 131.405839 -268.92666) (xy 131.45311 -268.940352)
			(xy 131.497572 -268.96145) (xy 131.538075 -268.989406) (xy 131.573568 -269.023498) (xy 131.603133 -269.062842)
			(xy 131.626004 -269.106419) (xy 131.641588 -269.1531) (xy 131.649483 -269.201677) (xy 131.649978 -269.226284)
			(xy 131.97892 -269.226284) (xy 131.98288 -269.17723) (xy 131.994657 -269.129446) (xy 132.013948 -269.08417)
			(xy 132.040251 -269.042574) (xy 132.072886 -269.005737) (xy 132.111007 -268.974612) (xy 132.153628 -268.950005)
			(xy 132.199644 -268.932553) (xy 132.247863 -268.922709) (xy 132.297038 -268.920728) (xy 132.345893 -268.92666)
			(xy 132.393164 -268.940352) (xy 132.437626 -268.96145) (xy 132.478129 -268.989406) (xy 132.513622 -269.023498)
			(xy 132.543187 -269.062842) (xy 132.566058 -269.106419) (xy 132.581642 -269.1531) (xy 132.589537 -269.201677)
			(xy 132.590032 -269.226284) (xy 132.908543 -269.226284) (xy 132.912638 -269.175556) (xy 132.924817 -269.126142)
			(xy 132.944765 -269.079322) (xy 132.971966 -269.036308) (xy 133.005714 -268.998214) (xy 133.045136 -268.966027)
			(xy 133.08921 -268.940581) (xy 133.136796 -268.922534) (xy 133.18666 -268.912354) (xy 133.237512 -268.910305)
			(xy 133.288033 -268.916439) (xy 133.336917 -268.930599) (xy 133.382896 -268.952416) (xy 133.42478 -268.981326)
			(xy 133.461484 -269.016581) (xy 133.492057 -269.057267) (xy 133.515708 -269.10233) (xy 133.531824 -269.150604)
			(xy 133.539988 -269.200838) (xy 133.5405 -269.226284) (xy 133.859028 -269.226284) (xy 133.862988 -269.17723)
			(xy 133.874765 -269.129446) (xy 133.894056 -269.08417) (xy 133.920359 -269.042574) (xy 133.952994 -269.005737)
			(xy 133.991115 -268.974612) (xy 134.033736 -268.950005) (xy 134.079752 -268.932553) (xy 134.127971 -268.922709)
			(xy 134.177146 -268.920728) (xy 134.226001 -268.92666) (xy 134.273272 -268.940352) (xy 134.317734 -268.96145)
			(xy 134.358237 -268.989406) (xy 134.39373 -269.023498) (xy 134.423295 -269.062842) (xy 134.446166 -269.106419)
			(xy 134.46175 -269.1531) (xy 134.469645 -269.201677) (xy 134.47014 -269.226284) (xy 134.798828 -269.226284)
			(xy 134.802788 -269.17723) (xy 134.814565 -269.129446) (xy 134.833856 -269.08417) (xy 134.860159 -269.042574)
			(xy 134.892794 -269.005737) (xy 134.930915 -268.974612) (xy 134.973536 -268.950005) (xy 135.019552 -268.932553)
			(xy 135.067771 -268.922709) (xy 135.116946 -268.920728) (xy 135.165801 -268.92666) (xy 135.213072 -268.940352)
			(xy 135.257534 -268.96145) (xy 135.298037 -268.989406) (xy 135.33353 -269.023498) (xy 135.363095 -269.062842)
			(xy 135.385966 -269.106419) (xy 135.40155 -269.1531) (xy 135.409445 -269.201677) (xy 135.40994 -269.226284)
			(xy 135.728451 -269.226284) (xy 135.732546 -269.175556) (xy 135.744725 -269.126142) (xy 135.764673 -269.079322)
			(xy 135.791874 -269.036308) (xy 135.825622 -268.998214) (xy 135.865044 -268.966027) (xy 135.909118 -268.940581)
			(xy 135.956704 -268.922534) (xy 136.006568 -268.912354) (xy 136.05742 -268.910305) (xy 136.107941 -268.916439)
			(xy 136.156825 -268.930599) (xy 136.202804 -268.952416) (xy 136.244688 -268.981326) (xy 136.281392 -269.016581)
			(xy 136.311965 -269.057267) (xy 136.335616 -269.10233) (xy 136.351732 -269.150604) (xy 136.359896 -269.200838)
			(xy 136.360408 -269.226284) (xy 136.678936 -269.226284) (xy 136.682896 -269.17723) (xy 136.694673 -269.129446)
			(xy 136.713964 -269.08417) (xy 136.740267 -269.042574) (xy 136.772902 -269.005737) (xy 136.811023 -268.974612)
			(xy 136.853644 -268.950005) (xy 136.89966 -268.932553) (xy 136.947879 -268.922709) (xy 136.997054 -268.920728)
			(xy 137.045909 -268.92666) (xy 137.09318 -268.940352) (xy 137.137642 -268.96145) (xy 137.178145 -268.989406)
			(xy 137.213638 -269.023498) (xy 137.243203 -269.062842) (xy 137.266074 -269.106419) (xy 137.281658 -269.1531)
			(xy 137.289553 -269.201677) (xy 137.290048 -269.226284) (xy 137.61899 -269.226284) (xy 137.62295 -269.17723)
			(xy 137.634727 -269.129446) (xy 137.654018 -269.08417) (xy 137.680321 -269.042574) (xy 137.712956 -269.005737)
			(xy 137.751077 -268.974612) (xy 137.793698 -268.950005) (xy 137.839714 -268.932553) (xy 137.887933 -268.922709)
			(xy 137.937108 -268.920728) (xy 137.985963 -268.92666) (xy 138.033234 -268.940352) (xy 138.077696 -268.96145)
			(xy 138.118199 -268.989406) (xy 138.153692 -269.023498) (xy 138.183257 -269.062842) (xy 138.206128 -269.106419)
			(xy 138.221712 -269.1531) (xy 138.229607 -269.201677) (xy 138.230102 -269.226284) (xy 138.559044 -269.226284)
			(xy 138.563004 -269.17723) (xy 138.574781 -269.129446) (xy 138.594072 -269.08417) (xy 138.620375 -269.042574)
			(xy 138.65301 -269.005737) (xy 138.691131 -268.974612) (xy 138.733752 -268.950005) (xy 138.779768 -268.932553)
			(xy 138.827987 -268.922709) (xy 138.877162 -268.920728) (xy 138.926017 -268.92666) (xy 138.973288 -268.940352)
			(xy 139.01775 -268.96145) (xy 139.058253 -268.989406) (xy 139.093746 -269.023498) (xy 139.123311 -269.062842)
			(xy 139.146182 -269.106419) (xy 139.161766 -269.1531) (xy 139.169661 -269.201677) (xy 139.170156 -269.226284)
			(xy 139.488413 -269.226284) (xy 139.492508 -269.175556) (xy 139.504687 -269.126142) (xy 139.524635 -269.079322)
			(xy 139.551836 -269.036308) (xy 139.585584 -268.998214) (xy 139.625006 -268.966027) (xy 139.66908 -268.940581)
			(xy 139.716666 -268.922534) (xy 139.76653 -268.912354) (xy 139.817382 -268.910305) (xy 139.867903 -268.916439)
			(xy 139.916787 -268.930599) (xy 139.962766 -268.952416) (xy 140.00465 -268.981326) (xy 140.041354 -269.016581)
			(xy 140.071927 -269.057267) (xy 140.095578 -269.10233) (xy 140.111694 -269.150604) (xy 140.119858 -269.200838)
			(xy 140.12037 -269.226284) (xy 140.438898 -269.226284) (xy 140.442858 -269.17723) (xy 140.454635 -269.129446)
			(xy 140.473926 -269.08417) (xy 140.500229 -269.042574) (xy 140.532864 -269.005737) (xy 140.570985 -268.974612)
			(xy 140.613606 -268.950005) (xy 140.659622 -268.932553) (xy 140.707841 -268.922709) (xy 140.757016 -268.920728)
			(xy 140.805871 -268.92666) (xy 140.853142 -268.940352) (xy 140.897604 -268.96145) (xy 140.938107 -268.989406)
			(xy 140.9736 -269.023498) (xy 141.003165 -269.062842) (xy 141.026036 -269.106419) (xy 141.04162 -269.1531)
			(xy 141.049515 -269.201677) (xy 141.05001 -269.226284) (xy 141.378952 -269.226284) (xy 141.382912 -269.17723)
			(xy 141.394689 -269.129446) (xy 141.41398 -269.08417) (xy 141.440283 -269.042574) (xy 141.472918 -269.005737)
			(xy 141.511039 -268.974612) (xy 141.55366 -268.950005) (xy 141.599676 -268.932553) (xy 141.647895 -268.922709)
			(xy 141.69707 -268.920728) (xy 141.745925 -268.92666) (xy 141.793196 -268.940352) (xy 141.837658 -268.96145)
			(xy 141.878161 -268.989406) (xy 141.913654 -269.023498) (xy 141.943219 -269.062842) (xy 141.96609 -269.106419)
			(xy 141.981674 -269.1531) (xy 141.989569 -269.201677) (xy 141.990064 -269.226284) (xy 142.308575 -269.226284)
			(xy 142.31267 -269.175556) (xy 142.324849 -269.126142) (xy 142.344797 -269.079322) (xy 142.371998 -269.036308)
			(xy 142.405746 -268.998214) (xy 142.445168 -268.966027) (xy 142.489242 -268.940581) (xy 142.536828 -268.922534)
			(xy 142.586692 -268.912354) (xy 142.637544 -268.910305) (xy 142.688065 -268.916439) (xy 142.736949 -268.930599)
			(xy 142.782928 -268.952416) (xy 142.824812 -268.981326) (xy 142.861516 -269.016581) (xy 142.892089 -269.057267)
			(xy 142.91574 -269.10233) (xy 142.931856 -269.150604) (xy 142.94002 -269.200838) (xy 142.940532 -269.226284)
			(xy 143.258806 -269.226284) (xy 143.262766 -269.17723) (xy 143.274543 -269.129446) (xy 143.293834 -269.08417)
			(xy 143.320137 -269.042574) (xy 143.352772 -269.005737) (xy 143.390893 -268.974612) (xy 143.433514 -268.950005)
			(xy 143.47953 -268.932553) (xy 143.527749 -268.922709) (xy 143.576924 -268.920728) (xy 143.625779 -268.92666)
			(xy 143.67305 -268.940352) (xy 143.717512 -268.96145) (xy 143.758015 -268.989406) (xy 143.793508 -269.023498)
			(xy 143.823073 -269.062842) (xy 143.845944 -269.106419) (xy 143.861528 -269.1531) (xy 143.869423 -269.201677)
			(xy 143.869918 -269.226284) (xy 144.19886 -269.226284) (xy 144.20282 -269.17723) (xy 144.214597 -269.129446)
			(xy 144.233888 -269.08417) (xy 144.260191 -269.042574) (xy 144.292826 -269.005737) (xy 144.330947 -268.974612)
			(xy 144.373568 -268.950005) (xy 144.419584 -268.932553) (xy 144.467803 -268.922709) (xy 144.516978 -268.920728)
			(xy 144.565833 -268.92666) (xy 144.613104 -268.940352) (xy 144.657566 -268.96145) (xy 144.698069 -268.989406)
			(xy 144.733562 -269.023498) (xy 144.763127 -269.062842) (xy 144.785998 -269.106419) (xy 144.801582 -269.1531)
			(xy 144.809477 -269.201677) (xy 144.809972 -269.226284) (xy 145.138914 -269.226284) (xy 145.142874 -269.17723)
			(xy 145.154651 -269.129446) (xy 145.173942 -269.08417) (xy 145.200245 -269.042574) (xy 145.23288 -269.005737)
			(xy 145.271001 -268.974612) (xy 145.313622 -268.950005) (xy 145.359638 -268.932553) (xy 145.407857 -268.922709)
			(xy 145.457032 -268.920728) (xy 145.505887 -268.92666) (xy 145.553158 -268.940352) (xy 145.59762 -268.96145)
			(xy 145.638123 -268.989406) (xy 145.673616 -269.023498) (xy 145.703181 -269.062842) (xy 145.726052 -269.106419)
			(xy 145.741636 -269.1531) (xy 145.749531 -269.201677) (xy 145.750026 -269.226284) (xy 145.749531 -269.250891)
			(xy 145.741636 -269.299468) (xy 145.726052 -269.346149) (xy 145.703181 -269.389726) (xy 145.673616 -269.42907)
			(xy 145.638123 -269.463162) (xy 145.59762 -269.491118) (xy 145.553158 -269.512216) (xy 145.505887 -269.525908)
			(xy 145.457032 -269.53184) (xy 145.407857 -269.529859) (xy 145.359638 -269.520015) (xy 145.313622 -269.502563)
			(xy 145.271001 -269.477956) (xy 145.23288 -269.446831) (xy 145.200245 -269.409994) (xy 145.173942 -269.368398)
			(xy 145.154651 -269.323122) (xy 145.142874 -269.275338) (xy 145.138914 -269.226284) (xy 144.809972 -269.226284)
			(xy 144.809477 -269.250891) (xy 144.801582 -269.299468) (xy 144.785998 -269.346149) (xy 144.763127 -269.389726)
			(xy 144.733562 -269.42907) (xy 144.698069 -269.463162) (xy 144.657566 -269.491118) (xy 144.613104 -269.512216)
			(xy 144.565833 -269.525908) (xy 144.516978 -269.53184) (xy 144.467803 -269.529859) (xy 144.419584 -269.520015)
			(xy 144.373568 -269.502563) (xy 144.330947 -269.477956) (xy 144.292826 -269.446831) (xy 144.260191 -269.409994)
			(xy 144.233888 -269.368398) (xy 144.214597 -269.323122) (xy 144.20282 -269.275338) (xy 144.19886 -269.226284)
			(xy 143.869918 -269.226284) (xy 143.869423 -269.250891) (xy 143.861528 -269.299468) (xy 143.845944 -269.346149)
			(xy 143.823073 -269.389726) (xy 143.793508 -269.42907) (xy 143.758015 -269.463162) (xy 143.717512 -269.491118)
			(xy 143.67305 -269.512216) (xy 143.625779 -269.525908) (xy 143.576924 -269.53184) (xy 143.527749 -269.529859)
			(xy 143.47953 -269.520015) (xy 143.433514 -269.502563) (xy 143.390893 -269.477956) (xy 143.352772 -269.446831)
			(xy 143.320137 -269.409994) (xy 143.293834 -269.368398) (xy 143.274543 -269.323122) (xy 143.262766 -269.275338)
			(xy 143.258806 -269.226284) (xy 142.940532 -269.226284) (xy 142.94002 -269.25173) (xy 142.931856 -269.301964)
			(xy 142.91574 -269.350238) (xy 142.892089 -269.395301) (xy 142.861516 -269.435987) (xy 142.824812 -269.471242)
			(xy 142.782928 -269.500152) (xy 142.736949 -269.521969) (xy 142.688065 -269.536129) (xy 142.637544 -269.542263)
			(xy 142.586692 -269.540214) (xy 142.536828 -269.530034) (xy 142.489242 -269.511987) (xy 142.445168 -269.486541)
			(xy 142.405746 -269.454354) (xy 142.371998 -269.41626) (xy 142.344797 -269.373246) (xy 142.324849 -269.326426)
			(xy 142.31267 -269.277012) (xy 142.308575 -269.226284) (xy 141.990064 -269.226284) (xy 141.989569 -269.250891)
			(xy 141.981674 -269.299468) (xy 141.96609 -269.346149) (xy 141.943219 -269.389726) (xy 141.913654 -269.42907)
			(xy 141.878161 -269.463162) (xy 141.837658 -269.491118) (xy 141.793196 -269.512216) (xy 141.745925 -269.525908)
			(xy 141.69707 -269.53184) (xy 141.647895 -269.529859) (xy 141.599676 -269.520015) (xy 141.55366 -269.502563)
			(xy 141.511039 -269.477956) (xy 141.472918 -269.446831) (xy 141.440283 -269.409994) (xy 141.41398 -269.368398)
			(xy 141.394689 -269.323122) (xy 141.382912 -269.275338) (xy 141.378952 -269.226284) (xy 141.05001 -269.226284)
			(xy 141.049515 -269.250891) (xy 141.04162 -269.299468) (xy 141.026036 -269.346149) (xy 141.003165 -269.389726)
			(xy 140.9736 -269.42907) (xy 140.938107 -269.463162) (xy 140.897604 -269.491118) (xy 140.853142 -269.512216)
			(xy 140.805871 -269.525908) (xy 140.757016 -269.53184) (xy 140.707841 -269.529859) (xy 140.659622 -269.520015)
			(xy 140.613606 -269.502563) (xy 140.570985 -269.477956) (xy 140.532864 -269.446831) (xy 140.500229 -269.409994)
			(xy 140.473926 -269.368398) (xy 140.454635 -269.323122) (xy 140.442858 -269.275338) (xy 140.438898 -269.226284)
			(xy 140.12037 -269.226284) (xy 140.119858 -269.25173) (xy 140.111694 -269.301964) (xy 140.095578 -269.350238)
			(xy 140.071927 -269.395301) (xy 140.041354 -269.435987) (xy 140.00465 -269.471242) (xy 139.962766 -269.500152)
			(xy 139.916787 -269.521969) (xy 139.867903 -269.536129) (xy 139.817382 -269.542263) (xy 139.76653 -269.540214)
			(xy 139.716666 -269.530034) (xy 139.66908 -269.511987) (xy 139.625006 -269.486541) (xy 139.585584 -269.454354)
			(xy 139.551836 -269.41626) (xy 139.524635 -269.373246) (xy 139.504687 -269.326426) (xy 139.492508 -269.277012)
			(xy 139.488413 -269.226284) (xy 139.170156 -269.226284) (xy 139.169661 -269.250891) (xy 139.161766 -269.299468)
			(xy 139.146182 -269.346149) (xy 139.123311 -269.389726) (xy 139.093746 -269.42907) (xy 139.058253 -269.463162)
			(xy 139.01775 -269.491118) (xy 138.973288 -269.512216) (xy 138.926017 -269.525908) (xy 138.877162 -269.53184)
			(xy 138.827987 -269.529859) (xy 138.779768 -269.520015) (xy 138.733752 -269.502563) (xy 138.691131 -269.477956)
			(xy 138.65301 -269.446831) (xy 138.620375 -269.409994) (xy 138.594072 -269.368398) (xy 138.574781 -269.323122)
			(xy 138.563004 -269.275338) (xy 138.559044 -269.226284) (xy 138.230102 -269.226284) (xy 138.229607 -269.250891)
			(xy 138.221712 -269.299468) (xy 138.206128 -269.346149) (xy 138.183257 -269.389726) (xy 138.153692 -269.42907)
			(xy 138.118199 -269.463162) (xy 138.077696 -269.491118) (xy 138.033234 -269.512216) (xy 137.985963 -269.525908)
			(xy 137.937108 -269.53184) (xy 137.887933 -269.529859) (xy 137.839714 -269.520015) (xy 137.793698 -269.502563)
			(xy 137.751077 -269.477956) (xy 137.712956 -269.446831) (xy 137.680321 -269.409994) (xy 137.654018 -269.368398)
			(xy 137.634727 -269.323122) (xy 137.62295 -269.275338) (xy 137.61899 -269.226284) (xy 137.290048 -269.226284)
			(xy 137.289553 -269.250891) (xy 137.281658 -269.299468) (xy 137.266074 -269.346149) (xy 137.243203 -269.389726)
			(xy 137.213638 -269.42907) (xy 137.178145 -269.463162) (xy 137.137642 -269.491118) (xy 137.09318 -269.512216)
			(xy 137.045909 -269.525908) (xy 136.997054 -269.53184) (xy 136.947879 -269.529859) (xy 136.89966 -269.520015)
			(xy 136.853644 -269.502563) (xy 136.811023 -269.477956) (xy 136.772902 -269.446831) (xy 136.740267 -269.409994)
			(xy 136.713964 -269.368398) (xy 136.694673 -269.323122) (xy 136.682896 -269.275338) (xy 136.678936 -269.226284)
			(xy 136.360408 -269.226284) (xy 136.359896 -269.25173) (xy 136.351732 -269.301964) (xy 136.335616 -269.350238)
			(xy 136.311965 -269.395301) (xy 136.281392 -269.435987) (xy 136.244688 -269.471242) (xy 136.202804 -269.500152)
			(xy 136.156825 -269.521969) (xy 136.107941 -269.536129) (xy 136.05742 -269.542263) (xy 136.006568 -269.540214)
			(xy 135.956704 -269.530034) (xy 135.909118 -269.511987) (xy 135.865044 -269.486541) (xy 135.825622 -269.454354)
			(xy 135.791874 -269.41626) (xy 135.764673 -269.373246) (xy 135.744725 -269.326426) (xy 135.732546 -269.277012)
			(xy 135.728451 -269.226284) (xy 135.40994 -269.226284) (xy 135.409445 -269.250891) (xy 135.40155 -269.299468)
			(xy 135.385966 -269.346149) (xy 135.363095 -269.389726) (xy 135.33353 -269.42907) (xy 135.298037 -269.463162)
			(xy 135.257534 -269.491118) (xy 135.213072 -269.512216) (xy 135.165801 -269.525908) (xy 135.116946 -269.53184)
			(xy 135.067771 -269.529859) (xy 135.019552 -269.520015) (xy 134.973536 -269.502563) (xy 134.930915 -269.477956)
			(xy 134.892794 -269.446831) (xy 134.860159 -269.409994) (xy 134.833856 -269.368398) (xy 134.814565 -269.323122)
			(xy 134.802788 -269.275338) (xy 134.798828 -269.226284) (xy 134.47014 -269.226284) (xy 134.469645 -269.250891)
			(xy 134.46175 -269.299468) (xy 134.446166 -269.346149) (xy 134.423295 -269.389726) (xy 134.39373 -269.42907)
			(xy 134.358237 -269.463162) (xy 134.317734 -269.491118) (xy 134.273272 -269.512216) (xy 134.226001 -269.525908)
			(xy 134.177146 -269.53184) (xy 134.127971 -269.529859) (xy 134.079752 -269.520015) (xy 134.033736 -269.502563)
			(xy 133.991115 -269.477956) (xy 133.952994 -269.446831) (xy 133.920359 -269.409994) (xy 133.894056 -269.368398)
			(xy 133.874765 -269.323122) (xy 133.862988 -269.275338) (xy 133.859028 -269.226284) (xy 133.5405 -269.226284)
			(xy 133.539988 -269.25173) (xy 133.531824 -269.301964) (xy 133.515708 -269.350238) (xy 133.492057 -269.395301)
			(xy 133.461484 -269.435987) (xy 133.42478 -269.471242) (xy 133.382896 -269.500152) (xy 133.336917 -269.521969)
			(xy 133.288033 -269.536129) (xy 133.237512 -269.542263) (xy 133.18666 -269.540214) (xy 133.136796 -269.530034)
			(xy 133.08921 -269.511987) (xy 133.045136 -269.486541) (xy 133.005714 -269.454354) (xy 132.971966 -269.41626)
			(xy 132.944765 -269.373246) (xy 132.924817 -269.326426) (xy 132.912638 -269.277012) (xy 132.908543 -269.226284)
			(xy 132.590032 -269.226284) (xy 132.589537 -269.250891) (xy 132.581642 -269.299468) (xy 132.566058 -269.346149)
			(xy 132.543187 -269.389726) (xy 132.513622 -269.42907) (xy 132.478129 -269.463162) (xy 132.437626 -269.491118)
			(xy 132.393164 -269.512216) (xy 132.345893 -269.525908) (xy 132.297038 -269.53184) (xy 132.247863 -269.529859)
			(xy 132.199644 -269.520015) (xy 132.153628 -269.502563) (xy 132.111007 -269.477956) (xy 132.072886 -269.446831)
			(xy 132.040251 -269.409994) (xy 132.013948 -269.368398) (xy 131.994657 -269.323122) (xy 131.98288 -269.275338)
			(xy 131.97892 -269.226284) (xy 131.649978 -269.226284) (xy 131.649483 -269.250891) (xy 131.641588 -269.299468)
			(xy 131.626004 -269.346149) (xy 131.603133 -269.389726) (xy 131.573568 -269.42907) (xy 131.538075 -269.463162)
			(xy 131.497572 -269.491118) (xy 131.45311 -269.512216) (xy 131.405839 -269.525908) (xy 131.356984 -269.53184)
			(xy 131.307809 -269.529859) (xy 131.25959 -269.520015) (xy 131.213574 -269.502563) (xy 131.170953 -269.477956)
			(xy 131.132832 -269.446831) (xy 131.100197 -269.409994) (xy 131.073894 -269.368398) (xy 131.054603 -269.323122)
			(xy 131.042826 -269.275338) (xy 131.038866 -269.226284) (xy 130.710178 -269.226284) (xy 130.709683 -269.250891)
			(xy 130.701788 -269.299468) (xy 130.686204 -269.346149) (xy 130.663333 -269.389726) (xy 130.633768 -269.42907)
			(xy 130.598275 -269.463162) (xy 130.557772 -269.491118) (xy 130.51331 -269.512216) (xy 130.466039 -269.525908)
			(xy 130.417184 -269.53184) (xy 130.368009 -269.529859) (xy 130.31979 -269.520015) (xy 130.273774 -269.502563)
			(xy 130.231153 -269.477956) (xy 130.193032 -269.446831) (xy 130.160397 -269.409994) (xy 130.134094 -269.368398)
			(xy 130.114803 -269.323122) (xy 130.103026 -269.275338) (xy 130.099066 -269.226284) (xy 129.780538 -269.226284)
			(xy 129.780026 -269.25173) (xy 129.771862 -269.301964) (xy 129.755746 -269.350238) (xy 129.732095 -269.395301)
			(xy 129.701522 -269.435987) (xy 129.664818 -269.471242) (xy 129.622934 -269.500152) (xy 129.576955 -269.521969)
			(xy 129.528071 -269.536129) (xy 129.47755 -269.542263) (xy 129.426698 -269.540214) (xy 129.376834 -269.530034)
			(xy 129.329248 -269.511987) (xy 129.285174 -269.486541) (xy 129.245752 -269.454354) (xy 129.212004 -269.41626)
			(xy 129.184803 -269.373246) (xy 129.164855 -269.326426) (xy 129.152676 -269.277012) (xy 129.148581 -269.226284)
			(xy 128.83007 -269.226284) (xy 128.829575 -269.250891) (xy 128.82168 -269.299468) (xy 128.806096 -269.346149)
			(xy 128.783225 -269.389726) (xy 128.75366 -269.42907) (xy 128.718167 -269.463162) (xy 128.677664 -269.491118)
			(xy 128.633202 -269.512216) (xy 128.585931 -269.525908) (xy 128.537076 -269.53184) (xy 128.487901 -269.529859)
			(xy 128.439682 -269.520015) (xy 128.393666 -269.502563) (xy 128.351045 -269.477956) (xy 128.312924 -269.446831)
			(xy 128.280289 -269.409994) (xy 128.253986 -269.368398) (xy 128.234695 -269.323122) (xy 128.222918 -269.275338)
			(xy 128.218958 -269.226284) (xy 127.890546 -269.226284) (xy 127.890547 -269.2263) (xy 127.886376 -269.27664)
			(xy 127.873976 -269.325607) (xy 127.853686 -269.371865) (xy 127.826058 -269.414152) (xy 127.791848 -269.451316)
			(xy 127.751987 -269.482342) (xy 127.707563 -269.506384) (xy 127.659788 -269.522787) (xy 127.609964 -269.531102)
			(xy 127.584708 -269.531592) (xy 127.561802 -269.531161) (xy 127.51651 -269.524277) (xy 127.472754 -269.510707)
			(xy 127.431514 -269.490755) (xy 127.393716 -269.46487) (xy 127.376682 -269.44955) (xy 127.365252 -269.439136)
			(xy 127.335534 -269.434056) (xy 127.23622 -269.47749) (xy 127.227402 -269.481856) (xy 127.213688 -269.495941)
			(xy 127.206264 -269.514144) (xy 127.20574 -269.523972) (xy 127.20574 -269.724886) (xy 127.22225 -269.750032)
			(xy 127.23622 -269.756128) (xy 127.259287 -269.766671) (xy 127.301849 -269.794248) (xy 127.339269 -269.828477)
			(xy 127.37052 -269.868419) (xy 127.394742 -269.912975) (xy 127.41127 -269.960921) (xy 127.41965 -270.010939)
			(xy 127.41965 -270.03629) (xy 127.738627 -270.03629) (xy 127.742722 -269.985562) (xy 127.754901 -269.936148)
			(xy 127.774849 -269.889328) (xy 127.80205 -269.846314) (xy 127.835798 -269.80822) (xy 127.87522 -269.776033)
			(xy 127.919294 -269.750587) (xy 127.96688 -269.73254) (xy 128.016744 -269.72236) (xy 128.067596 -269.720311)
			(xy 128.118117 -269.726445) (xy 128.167001 -269.740605) (xy 128.21298 -269.762422) (xy 128.254864 -269.791332)
			(xy 128.291568 -269.826587) (xy 128.322141 -269.867273) (xy 128.345792 -269.912336) (xy 128.361908 -269.96061)
			(xy 128.370072 -270.010844) (xy 128.370584 -270.03629) (xy 128.688858 -270.03629) (xy 128.692818 -269.987236)
			(xy 128.704595 -269.939452) (xy 128.723886 -269.894176) (xy 128.750189 -269.85258) (xy 128.782824 -269.815743)
			(xy 128.820945 -269.784618) (xy 128.863566 -269.760011) (xy 128.909582 -269.742559) (xy 128.957801 -269.732715)
			(xy 129.006976 -269.730734) (xy 129.055831 -269.736666) (xy 129.103102 -269.750358) (xy 129.147564 -269.771456)
			(xy 129.188067 -269.799412) (xy 129.22356 -269.833504) (xy 129.253125 -269.872848) (xy 129.275996 -269.916425)
			(xy 129.29158 -269.963106) (xy 129.299475 -270.011683) (xy 129.29997 -270.03629) (xy 129.618481 -270.03629)
			(xy 129.622576 -269.985562) (xy 129.634755 -269.936148) (xy 129.654703 -269.889328) (xy 129.681904 -269.846314)
			(xy 129.715652 -269.80822) (xy 129.755074 -269.776033) (xy 129.799148 -269.750587) (xy 129.846734 -269.73254)
			(xy 129.896598 -269.72236) (xy 129.94745 -269.720311) (xy 129.997971 -269.726445) (xy 130.046855 -269.740605)
			(xy 130.092834 -269.762422) (xy 130.134718 -269.791332) (xy 130.171422 -269.826587) (xy 130.201995 -269.867273)
			(xy 130.225646 -269.912336) (xy 130.241762 -269.96061) (xy 130.249926 -270.010844) (xy 130.250438 -270.03629)
			(xy 130.568966 -270.03629) (xy 130.572926 -269.987236) (xy 130.584703 -269.939452) (xy 130.603994 -269.894176)
			(xy 130.630297 -269.85258) (xy 130.662932 -269.815743) (xy 130.701053 -269.784618) (xy 130.743674 -269.760011)
			(xy 130.78969 -269.742559) (xy 130.837909 -269.732715) (xy 130.887084 -269.730734) (xy 130.935939 -269.736666)
			(xy 130.98321 -269.750358) (xy 131.027672 -269.771456) (xy 131.068175 -269.799412) (xy 131.103668 -269.833504)
			(xy 131.133233 -269.872848) (xy 131.156104 -269.916425) (xy 131.171688 -269.963106) (xy 131.179583 -270.011683)
			(xy 131.180078 -270.03629) (xy 131.498589 -270.03629) (xy 131.502684 -269.985562) (xy 131.514863 -269.936148)
			(xy 131.534811 -269.889328) (xy 131.562012 -269.846314) (xy 131.59576 -269.80822) (xy 131.635182 -269.776033)
			(xy 131.679256 -269.750587) (xy 131.726842 -269.73254) (xy 131.776706 -269.72236) (xy 131.827558 -269.720311)
			(xy 131.878079 -269.726445) (xy 131.926963 -269.740605) (xy 131.972942 -269.762422) (xy 132.014826 -269.791332)
			(xy 132.05153 -269.826587) (xy 132.082103 -269.867273) (xy 132.105754 -269.912336) (xy 132.12187 -269.96061)
			(xy 132.130034 -270.010844) (xy 132.130546 -270.03629) (xy 132.438643 -270.03629) (xy 132.442738 -269.985562)
			(xy 132.454917 -269.936148) (xy 132.474865 -269.889328) (xy 132.502066 -269.846314) (xy 132.535814 -269.80822)
			(xy 132.575236 -269.776033) (xy 132.61931 -269.750587) (xy 132.666896 -269.73254) (xy 132.71676 -269.72236)
			(xy 132.767612 -269.720311) (xy 132.818133 -269.726445) (xy 132.867017 -269.740605) (xy 132.912996 -269.762422)
			(xy 132.95488 -269.791332) (xy 132.991584 -269.826587) (xy 133.022157 -269.867273) (xy 133.045808 -269.912336)
			(xy 133.061924 -269.96061) (xy 133.070088 -270.010844) (xy 133.0706 -270.03629) (xy 133.388874 -270.03629)
			(xy 133.392834 -269.987236) (xy 133.404611 -269.939452) (xy 133.423902 -269.894176) (xy 133.450205 -269.85258)
			(xy 133.48284 -269.815743) (xy 133.520961 -269.784618) (xy 133.563582 -269.760011) (xy 133.609598 -269.742559)
			(xy 133.657817 -269.732715) (xy 133.706992 -269.730734) (xy 133.755847 -269.736666) (xy 133.803118 -269.750358)
			(xy 133.84758 -269.771456) (xy 133.888083 -269.799412) (xy 133.923576 -269.833504) (xy 133.953141 -269.872848)
			(xy 133.976012 -269.916425) (xy 133.991596 -269.963106) (xy 133.999491 -270.011683) (xy 133.999986 -270.03629)
			(xy 134.318497 -270.03629) (xy 134.322592 -269.985562) (xy 134.334771 -269.936148) (xy 134.354719 -269.889328)
			(xy 134.38192 -269.846314) (xy 134.415668 -269.80822) (xy 134.45509 -269.776033) (xy 134.499164 -269.750587)
			(xy 134.54675 -269.73254) (xy 134.596614 -269.72236) (xy 134.647466 -269.720311) (xy 134.697987 -269.726445)
			(xy 134.746871 -269.740605) (xy 134.79285 -269.762422) (xy 134.834734 -269.791332) (xy 134.871438 -269.826587)
			(xy 134.902011 -269.867273) (xy 134.925662 -269.912336) (xy 134.941778 -269.96061) (xy 134.949942 -270.010844)
			(xy 134.950454 -270.03629) (xy 135.268982 -270.03629) (xy 135.272942 -269.987236) (xy 135.284719 -269.939452)
			(xy 135.30401 -269.894176) (xy 135.330313 -269.85258) (xy 135.362948 -269.815743) (xy 135.401069 -269.784618)
			(xy 135.44369 -269.760011) (xy 135.489706 -269.742559) (xy 135.537925 -269.732715) (xy 135.5871 -269.730734)
			(xy 135.635955 -269.736666) (xy 135.683226 -269.750358) (xy 135.727688 -269.771456) (xy 135.768191 -269.799412)
			(xy 135.803684 -269.833504) (xy 135.833249 -269.872848) (xy 135.85612 -269.916425) (xy 135.871704 -269.963106)
			(xy 135.879599 -270.011683) (xy 135.880094 -270.03629) (xy 136.198605 -270.03629) (xy 136.2027 -269.985562)
			(xy 136.214879 -269.936148) (xy 136.234827 -269.889328) (xy 136.262028 -269.846314) (xy 136.295776 -269.80822)
			(xy 136.335198 -269.776033) (xy 136.379272 -269.750587) (xy 136.426858 -269.73254) (xy 136.476722 -269.72236)
			(xy 136.527574 -269.720311) (xy 136.578095 -269.726445) (xy 136.626979 -269.740605) (xy 136.672958 -269.762422)
			(xy 136.714842 -269.791332) (xy 136.751546 -269.826587) (xy 136.782119 -269.867273) (xy 136.80577 -269.912336)
			(xy 136.821886 -269.96061) (xy 136.83005 -270.010844) (xy 136.830562 -270.03629) (xy 137.148836 -270.03629)
			(xy 137.152796 -269.987236) (xy 137.164573 -269.939452) (xy 137.183864 -269.894176) (xy 137.210167 -269.85258)
			(xy 137.242802 -269.815743) (xy 137.280923 -269.784618) (xy 137.323544 -269.760011) (xy 137.36956 -269.742559)
			(xy 137.417779 -269.732715) (xy 137.466954 -269.730734) (xy 137.515809 -269.736666) (xy 137.56308 -269.750358)
			(xy 137.607542 -269.771456) (xy 137.648045 -269.799412) (xy 137.683538 -269.833504) (xy 137.713103 -269.872848)
			(xy 137.735974 -269.916425) (xy 137.751558 -269.963106) (xy 137.759453 -270.011683) (xy 137.759948 -270.03629)
			(xy 138.078459 -270.03629) (xy 138.082554 -269.985562) (xy 138.094733 -269.936148) (xy 138.114681 -269.889328)
			(xy 138.141882 -269.846314) (xy 138.17563 -269.80822) (xy 138.215052 -269.776033) (xy 138.259126 -269.750587)
			(xy 138.306712 -269.73254) (xy 138.356576 -269.72236) (xy 138.407428 -269.720311) (xy 138.457949 -269.726445)
			(xy 138.506833 -269.740605) (xy 138.552812 -269.762422) (xy 138.594696 -269.791332) (xy 138.6314 -269.826587)
			(xy 138.661973 -269.867273) (xy 138.685624 -269.912336) (xy 138.70174 -269.96061) (xy 138.709904 -270.010844)
			(xy 138.710416 -270.03629) (xy 139.018513 -270.03629) (xy 139.022608 -269.985562) (xy 139.034787 -269.936148)
			(xy 139.054735 -269.889328) (xy 139.081936 -269.846314) (xy 139.115684 -269.80822) (xy 139.155106 -269.776033)
			(xy 139.19918 -269.750587) (xy 139.246766 -269.73254) (xy 139.29663 -269.72236) (xy 139.347482 -269.720311)
			(xy 139.398003 -269.726445) (xy 139.446887 -269.740605) (xy 139.492866 -269.762422) (xy 139.53475 -269.791332)
			(xy 139.571454 -269.826587) (xy 139.602027 -269.867273) (xy 139.625678 -269.912336) (xy 139.641794 -269.96061)
			(xy 139.649958 -270.010844) (xy 139.65047 -270.03629) (xy 139.968998 -270.03629) (xy 139.972958 -269.987236)
			(xy 139.984735 -269.939452) (xy 140.004026 -269.894176) (xy 140.030329 -269.85258) (xy 140.062964 -269.815743)
			(xy 140.101085 -269.784618) (xy 140.143706 -269.760011) (xy 140.189722 -269.742559) (xy 140.237941 -269.732715)
			(xy 140.287116 -269.730734) (xy 140.335971 -269.736666) (xy 140.383242 -269.750358) (xy 140.427704 -269.771456)
			(xy 140.468207 -269.799412) (xy 140.5037 -269.833504) (xy 140.533265 -269.872848) (xy 140.556136 -269.916425)
			(xy 140.57172 -269.963106) (xy 140.579615 -270.011683) (xy 140.58011 -270.03629) (xy 140.898621 -270.03629)
			(xy 140.902716 -269.985562) (xy 140.914895 -269.936148) (xy 140.934843 -269.889328) (xy 140.962044 -269.846314)
			(xy 140.995792 -269.80822) (xy 141.035214 -269.776033) (xy 141.079288 -269.750587) (xy 141.126874 -269.73254)
			(xy 141.176738 -269.72236) (xy 141.22759 -269.720311) (xy 141.278111 -269.726445) (xy 141.326995 -269.740605)
			(xy 141.372974 -269.762422) (xy 141.414858 -269.791332) (xy 141.451562 -269.826587) (xy 141.482135 -269.867273)
			(xy 141.505786 -269.912336) (xy 141.521902 -269.96061) (xy 141.530066 -270.010844) (xy 141.530578 -270.03629)
			(xy 141.848852 -270.03629) (xy 141.852812 -269.987236) (xy 141.864589 -269.939452) (xy 141.88388 -269.894176)
			(xy 141.910183 -269.85258) (xy 141.942818 -269.815743) (xy 141.980939 -269.784618) (xy 142.02356 -269.760011)
			(xy 142.069576 -269.742559) (xy 142.117795 -269.732715) (xy 142.16697 -269.730734) (xy 142.215825 -269.736666)
			(xy 142.263096 -269.750358) (xy 142.307558 -269.771456) (xy 142.348061 -269.799412) (xy 142.383554 -269.833504)
			(xy 142.413119 -269.872848) (xy 142.43599 -269.916425) (xy 142.451574 -269.963106) (xy 142.459469 -270.011683)
			(xy 142.459964 -270.03629) (xy 142.778475 -270.03629) (xy 142.78257 -269.985562) (xy 142.794749 -269.936148)
			(xy 142.814697 -269.889328) (xy 142.841898 -269.846314) (xy 142.875646 -269.80822) (xy 142.915068 -269.776033)
			(xy 142.959142 -269.750587) (xy 143.006728 -269.73254) (xy 143.056592 -269.72236) (xy 143.107444 -269.720311)
			(xy 143.157965 -269.726445) (xy 143.206849 -269.740605) (xy 143.252828 -269.762422) (xy 143.294712 -269.791332)
			(xy 143.331416 -269.826587) (xy 143.361989 -269.867273) (xy 143.38564 -269.912336) (xy 143.401756 -269.96061)
			(xy 143.40992 -270.010844) (xy 143.410432 -270.03629) (xy 143.72896 -270.03629) (xy 143.73292 -269.987236)
			(xy 143.744697 -269.939452) (xy 143.763988 -269.894176) (xy 143.790291 -269.85258) (xy 143.822926 -269.815743)
			(xy 143.861047 -269.784618) (xy 143.903668 -269.760011) (xy 143.949684 -269.742559) (xy 143.997903 -269.732715)
			(xy 144.047078 -269.730734) (xy 144.095933 -269.736666) (xy 144.143204 -269.750358) (xy 144.185339 -269.770352)
			(xy 146.737082 -269.770352) (xy 146.741042 -269.721298) (xy 146.752819 -269.673514) (xy 146.77211 -269.628238)
			(xy 146.798413 -269.586642) (xy 146.831048 -269.549805) (xy 146.869169 -269.51868) (xy 146.91179 -269.494073)
			(xy 146.957806 -269.476621) (xy 147.006025 -269.466777) (xy 147.0552 -269.464796) (xy 147.104055 -269.470728)
			(xy 147.151326 -269.48442) (xy 147.195788 -269.505518) (xy 147.236291 -269.533474) (xy 147.271784 -269.567566)
			(xy 147.285215 -269.58544) (xy 164.058615 -269.58544) (xy 164.06255 -269.531669) (xy 164.074273 -269.479045)
			(xy 164.093533 -269.428688) (xy 164.119919 -269.381671) (xy 164.152871 -269.338998) (xy 164.191684 -269.301577)
			(xy 164.235532 -269.270207) (xy 164.28348 -269.245555) (xy 164.334507 -269.228147) (xy 164.387525 -269.218354)
			(xy 164.441404 -269.216385) (xy 164.494995 -269.222282) (xy 164.547156 -269.235918) (xy 164.596776 -269.257005)
			(xy 164.642797 -269.285091) (xy 164.684239 -269.319579) (xy 164.720217 -269.359733) (xy 164.749965 -269.404697)
			(xy 164.77285 -269.453514) (xy 164.788382 -269.505143) (xy 164.796232 -269.558483) (xy 164.796724 -269.58544)
			(xy 164.796232 -269.612397) (xy 164.788382 -269.665737) (xy 164.77285 -269.717366) (xy 164.749965 -269.766183)
			(xy 164.720217 -269.811147) (xy 164.684239 -269.851301) (xy 164.642797 -269.885789) (xy 164.596776 -269.913875)
			(xy 164.547156 -269.934962) (xy 164.494995 -269.948598) (xy 164.441404 -269.954495) (xy 164.387525 -269.952526)
			(xy 164.334507 -269.942733) (xy 164.28348 -269.925325) (xy 164.235532 -269.900673) (xy 164.191684 -269.869303)
			(xy 164.152871 -269.831882) (xy 164.119919 -269.789209) (xy 164.093533 -269.742192) (xy 164.074273 -269.691835)
			(xy 164.06255 -269.639211) (xy 164.058615 -269.58544) (xy 147.285215 -269.58544) (xy 147.301349 -269.60691)
			(xy 147.32422 -269.650487) (xy 147.339804 -269.697168) (xy 147.347699 -269.745745) (xy 147.348194 -269.770352)
			(xy 147.347699 -269.794959) (xy 147.339804 -269.843536) (xy 147.32422 -269.890217) (xy 147.301349 -269.933794)
			(xy 147.271784 -269.973138) (xy 147.236291 -270.00723) (xy 147.195788 -270.035186) (xy 147.151326 -270.056284)
			(xy 147.104055 -270.069976) (xy 147.0552 -270.075908) (xy 147.006025 -270.073927) (xy 146.957806 -270.064083)
			(xy 146.91179 -270.046631) (xy 146.869169 -270.022024) (xy 146.831048 -269.990899) (xy 146.798413 -269.954062)
			(xy 146.77211 -269.912466) (xy 146.752819 -269.86719) (xy 146.741042 -269.819406) (xy 146.737082 -269.770352)
			(xy 144.185339 -269.770352) (xy 144.187666 -269.771456) (xy 144.228169 -269.799412) (xy 144.263662 -269.833504)
			(xy 144.293227 -269.872848) (xy 144.316098 -269.916425) (xy 144.331682 -269.963106) (xy 144.339577 -270.011683)
			(xy 144.340072 -270.03629) (xy 144.339577 -270.060897) (xy 144.331682 -270.109474) (xy 144.316098 -270.156155)
			(xy 144.293227 -270.199732) (xy 144.263662 -270.239076) (xy 144.228169 -270.273168) (xy 144.187666 -270.301124)
			(xy 144.143204 -270.322222) (xy 144.095933 -270.335914) (xy 144.047078 -270.341846) (xy 143.997903 -270.339865)
			(xy 143.949684 -270.330021) (xy 143.903668 -270.312569) (xy 143.861047 -270.287962) (xy 143.822926 -270.256837)
			(xy 143.790291 -270.22) (xy 143.763988 -270.178404) (xy 143.744697 -270.133128) (xy 143.73292 -270.085344)
			(xy 143.72896 -270.03629) (xy 143.410432 -270.03629) (xy 143.40992 -270.061736) (xy 143.401756 -270.11197)
			(xy 143.38564 -270.160244) (xy 143.361989 -270.205307) (xy 143.331416 -270.245993) (xy 143.294712 -270.281248)
			(xy 143.252828 -270.310158) (xy 143.206849 -270.331975) (xy 143.157965 -270.346135) (xy 143.107444 -270.352269)
			(xy 143.056592 -270.35022) (xy 143.006728 -270.34004) (xy 142.959142 -270.321993) (xy 142.915068 -270.296547)
			(xy 142.875646 -270.26436) (xy 142.841898 -270.226266) (xy 142.814697 -270.183252) (xy 142.794749 -270.136432)
			(xy 142.78257 -270.087018) (xy 142.778475 -270.03629) (xy 142.459964 -270.03629) (xy 142.459469 -270.060897)
			(xy 142.451574 -270.109474) (xy 142.43599 -270.156155) (xy 142.413119 -270.199732) (xy 142.383554 -270.239076)
			(xy 142.348061 -270.273168) (xy 142.307558 -270.301124) (xy 142.263096 -270.322222) (xy 142.215825 -270.335914)
			(xy 142.16697 -270.341846) (xy 142.117795 -270.339865) (xy 142.069576 -270.330021) (xy 142.02356 -270.312569)
			(xy 141.980939 -270.287962) (xy 141.942818 -270.256837) (xy 141.910183 -270.22) (xy 141.88388 -270.178404)
			(xy 141.864589 -270.133128) (xy 141.852812 -270.085344) (xy 141.848852 -270.03629) (xy 141.530578 -270.03629)
			(xy 141.530066 -270.061736) (xy 141.521902 -270.11197) (xy 141.505786 -270.160244) (xy 141.482135 -270.205307)
			(xy 141.451562 -270.245993) (xy 141.414858 -270.281248) (xy 141.372974 -270.310158) (xy 141.326995 -270.331975)
			(xy 141.278111 -270.346135) (xy 141.22759 -270.352269) (xy 141.176738 -270.35022) (xy 141.126874 -270.34004)
			(xy 141.079288 -270.321993) (xy 141.035214 -270.296547) (xy 140.995792 -270.26436) (xy 140.962044 -270.226266)
			(xy 140.934843 -270.183252) (xy 140.914895 -270.136432) (xy 140.902716 -270.087018) (xy 140.898621 -270.03629)
			(xy 140.58011 -270.03629) (xy 140.579615 -270.060897) (xy 140.57172 -270.109474) (xy 140.556136 -270.156155)
			(xy 140.533265 -270.199732) (xy 140.5037 -270.239076) (xy 140.468207 -270.273168) (xy 140.427704 -270.301124)
			(xy 140.383242 -270.322222) (xy 140.335971 -270.335914) (xy 140.287116 -270.341846) (xy 140.237941 -270.339865)
			(xy 140.189722 -270.330021) (xy 140.143706 -270.312569) (xy 140.101085 -270.287962) (xy 140.062964 -270.256837)
			(xy 140.030329 -270.22) (xy 140.004026 -270.178404) (xy 139.984735 -270.133128) (xy 139.972958 -270.085344)
			(xy 139.968998 -270.03629) (xy 139.65047 -270.03629) (xy 139.649958 -270.061736) (xy 139.641794 -270.11197)
			(xy 139.625678 -270.160244) (xy 139.602027 -270.205307) (xy 139.571454 -270.245993) (xy 139.53475 -270.281248)
			(xy 139.492866 -270.310158) (xy 139.446887 -270.331975) (xy 139.398003 -270.346135) (xy 139.347482 -270.352269)
			(xy 139.29663 -270.35022) (xy 139.246766 -270.34004) (xy 139.19918 -270.321993) (xy 139.155106 -270.296547)
			(xy 139.115684 -270.26436) (xy 139.081936 -270.226266) (xy 139.054735 -270.183252) (xy 139.034787 -270.136432)
			(xy 139.022608 -270.087018) (xy 139.018513 -270.03629) (xy 138.710416 -270.03629) (xy 138.709904 -270.061736)
			(xy 138.70174 -270.11197) (xy 138.685624 -270.160244) (xy 138.661973 -270.205307) (xy 138.6314 -270.245993)
			(xy 138.594696 -270.281248) (xy 138.552812 -270.310158) (xy 138.506833 -270.331975) (xy 138.457949 -270.346135)
			(xy 138.407428 -270.352269) (xy 138.356576 -270.35022) (xy 138.306712 -270.34004) (xy 138.259126 -270.321993)
			(xy 138.215052 -270.296547) (xy 138.17563 -270.26436) (xy 138.141882 -270.226266) (xy 138.114681 -270.183252)
			(xy 138.094733 -270.136432) (xy 138.082554 -270.087018) (xy 138.078459 -270.03629) (xy 137.759948 -270.03629)
			(xy 137.759453 -270.060897) (xy 137.751558 -270.109474) (xy 137.735974 -270.156155) (xy 137.713103 -270.199732)
			(xy 137.683538 -270.239076) (xy 137.648045 -270.273168) (xy 137.607542 -270.301124) (xy 137.56308 -270.322222)
			(xy 137.515809 -270.335914) (xy 137.466954 -270.341846) (xy 137.417779 -270.339865) (xy 137.36956 -270.330021)
			(xy 137.323544 -270.312569) (xy 137.280923 -270.287962) (xy 137.242802 -270.256837) (xy 137.210167 -270.22)
			(xy 137.183864 -270.178404) (xy 137.164573 -270.133128) (xy 137.152796 -270.085344) (xy 137.148836 -270.03629)
			(xy 136.830562 -270.03629) (xy 136.83005 -270.061736) (xy 136.821886 -270.11197) (xy 136.80577 -270.160244)
			(xy 136.782119 -270.205307) (xy 136.751546 -270.245993) (xy 136.714842 -270.281248) (xy 136.672958 -270.310158)
			(xy 136.626979 -270.331975) (xy 136.578095 -270.346135) (xy 136.527574 -270.352269) (xy 136.476722 -270.35022)
			(xy 136.426858 -270.34004) (xy 136.379272 -270.321993) (xy 136.335198 -270.296547) (xy 136.295776 -270.26436)
			(xy 136.262028 -270.226266) (xy 136.234827 -270.183252) (xy 136.214879 -270.136432) (xy 136.2027 -270.087018)
			(xy 136.198605 -270.03629) (xy 135.880094 -270.03629) (xy 135.879599 -270.060897) (xy 135.871704 -270.109474)
			(xy 135.85612 -270.156155) (xy 135.833249 -270.199732) (xy 135.803684 -270.239076) (xy 135.768191 -270.273168)
			(xy 135.727688 -270.301124) (xy 135.683226 -270.322222) (xy 135.635955 -270.335914) (xy 135.5871 -270.341846)
			(xy 135.537925 -270.339865) (xy 135.489706 -270.330021) (xy 135.44369 -270.312569) (xy 135.401069 -270.287962)
			(xy 135.362948 -270.256837) (xy 135.330313 -270.22) (xy 135.30401 -270.178404) (xy 135.284719 -270.133128)
			(xy 135.272942 -270.085344) (xy 135.268982 -270.03629) (xy 134.950454 -270.03629) (xy 134.949942 -270.061736)
			(xy 134.941778 -270.11197) (xy 134.925662 -270.160244) (xy 134.902011 -270.205307) (xy 134.871438 -270.245993)
			(xy 134.834734 -270.281248) (xy 134.79285 -270.310158) (xy 134.746871 -270.331975) (xy 134.697987 -270.346135)
			(xy 134.647466 -270.352269) (xy 134.596614 -270.35022) (xy 134.54675 -270.34004) (xy 134.499164 -270.321993)
			(xy 134.45509 -270.296547) (xy 134.415668 -270.26436) (xy 134.38192 -270.226266) (xy 134.354719 -270.183252)
			(xy 134.334771 -270.136432) (xy 134.322592 -270.087018) (xy 134.318497 -270.03629) (xy 133.999986 -270.03629)
			(xy 133.999491 -270.060897) (xy 133.991596 -270.109474) (xy 133.976012 -270.156155) (xy 133.953141 -270.199732)
			(xy 133.923576 -270.239076) (xy 133.888083 -270.273168) (xy 133.84758 -270.301124) (xy 133.803118 -270.322222)
			(xy 133.755847 -270.335914) (xy 133.706992 -270.341846) (xy 133.657817 -270.339865) (xy 133.609598 -270.330021)
			(xy 133.563582 -270.312569) (xy 133.520961 -270.287962) (xy 133.48284 -270.256837) (xy 133.450205 -270.22)
			(xy 133.423902 -270.178404) (xy 133.404611 -270.133128) (xy 133.392834 -270.085344) (xy 133.388874 -270.03629)
			(xy 133.0706 -270.03629) (xy 133.070088 -270.061736) (xy 133.061924 -270.11197) (xy 133.045808 -270.160244)
			(xy 133.022157 -270.205307) (xy 132.991584 -270.245993) (xy 132.95488 -270.281248) (xy 132.912996 -270.310158)
			(xy 132.867017 -270.331975) (xy 132.818133 -270.346135) (xy 132.767612 -270.352269) (xy 132.71676 -270.35022)
			(xy 132.666896 -270.34004) (xy 132.61931 -270.321993) (xy 132.575236 -270.296547) (xy 132.535814 -270.26436)
			(xy 132.502066 -270.226266) (xy 132.474865 -270.183252) (xy 132.454917 -270.136432) (xy 132.442738 -270.087018)
			(xy 132.438643 -270.03629) (xy 132.130546 -270.03629) (xy 132.130034 -270.061736) (xy 132.12187 -270.11197)
			(xy 132.105754 -270.160244) (xy 132.082103 -270.205307) (xy 132.05153 -270.245993) (xy 132.014826 -270.281248)
			(xy 131.972942 -270.310158) (xy 131.926963 -270.331975) (xy 131.878079 -270.346135) (xy 131.827558 -270.352269)
			(xy 131.776706 -270.35022) (xy 131.726842 -270.34004) (xy 131.679256 -270.321993) (xy 131.635182 -270.296547)
			(xy 131.59576 -270.26436) (xy 131.562012 -270.226266) (xy 131.534811 -270.183252) (xy 131.514863 -270.136432)
			(xy 131.502684 -270.087018) (xy 131.498589 -270.03629) (xy 131.180078 -270.03629) (xy 131.179583 -270.060897)
			(xy 131.171688 -270.109474) (xy 131.156104 -270.156155) (xy 131.133233 -270.199732) (xy 131.103668 -270.239076)
			(xy 131.068175 -270.273168) (xy 131.027672 -270.301124) (xy 130.98321 -270.322222) (xy 130.935939 -270.335914)
			(xy 130.887084 -270.341846) (xy 130.837909 -270.339865) (xy 130.78969 -270.330021) (xy 130.743674 -270.312569)
			(xy 130.701053 -270.287962) (xy 130.662932 -270.256837) (xy 130.630297 -270.22) (xy 130.603994 -270.178404)
			(xy 130.584703 -270.133128) (xy 130.572926 -270.085344) (xy 130.568966 -270.03629) (xy 130.250438 -270.03629)
			(xy 130.249926 -270.061736) (xy 130.241762 -270.11197) (xy 130.225646 -270.160244) (xy 130.201995 -270.205307)
			(xy 130.171422 -270.245993) (xy 130.134718 -270.281248) (xy 130.092834 -270.310158) (xy 130.046855 -270.331975)
			(xy 129.997971 -270.346135) (xy 129.94745 -270.352269) (xy 129.896598 -270.35022) (xy 129.846734 -270.34004)
			(xy 129.799148 -270.321993) (xy 129.755074 -270.296547) (xy 129.715652 -270.26436) (xy 129.681904 -270.226266)
			(xy 129.654703 -270.183252) (xy 129.634755 -270.136432) (xy 129.622576 -270.087018) (xy 129.618481 -270.03629)
			(xy 129.29997 -270.03629) (xy 129.299475 -270.060897) (xy 129.29158 -270.109474) (xy 129.275996 -270.156155)
			(xy 129.253125 -270.199732) (xy 129.22356 -270.239076) (xy 129.188067 -270.273168) (xy 129.147564 -270.301124)
			(xy 129.103102 -270.322222) (xy 129.055831 -270.335914) (xy 129.006976 -270.341846) (xy 128.957801 -270.339865)
			(xy 128.909582 -270.330021) (xy 128.863566 -270.312569) (xy 128.820945 -270.287962) (xy 128.782824 -270.256837)
			(xy 128.750189 -270.22) (xy 128.723886 -270.178404) (xy 128.704595 -270.133128) (xy 128.692818 -270.085344)
			(xy 128.688858 -270.03629) (xy 128.370584 -270.03629) (xy 128.370072 -270.061736) (xy 128.361908 -270.11197)
			(xy 128.345792 -270.160244) (xy 128.322141 -270.205307) (xy 128.291568 -270.245993) (xy 128.254864 -270.281248)
			(xy 128.21298 -270.310158) (xy 128.167001 -270.331975) (xy 128.118117 -270.346135) (xy 128.067596 -270.352269)
			(xy 128.016744 -270.35022) (xy 127.96688 -270.34004) (xy 127.919294 -270.321993) (xy 127.87522 -270.296547)
			(xy 127.835798 -270.26436) (xy 127.80205 -270.226266) (xy 127.774849 -270.183252) (xy 127.754901 -270.136432)
			(xy 127.742722 -270.087018) (xy 127.738627 -270.03629) (xy 127.41965 -270.03629) (xy 127.41965 -270.061653)
			(xy 127.411272 -270.111671) (xy 127.394745 -270.159617) (xy 127.370524 -270.204174) (xy 127.339274 -270.244117)
			(xy 127.301855 -270.278348) (xy 127.259294 -270.305926) (xy 127.23622 -270.316452) (xy 127.22225 -270.322548)
			(xy 127.20574 -270.347694) (xy 127.20574 -270.846296) (xy 128.208527 -270.846296) (xy 128.212622 -270.795568)
			(xy 128.224801 -270.746154) (xy 128.244749 -270.699334) (xy 128.27195 -270.65632) (xy 128.305698 -270.618226)
			(xy 128.34512 -270.586039) (xy 128.389194 -270.560593) (xy 128.43678 -270.542546) (xy 128.486644 -270.532366)
			(xy 128.537496 -270.530317) (xy 128.588017 -270.536451) (xy 128.636901 -270.550611) (xy 128.68288 -270.572428)
			(xy 128.724764 -270.601338) (xy 128.761468 -270.636593) (xy 128.792041 -270.677279) (xy 128.815692 -270.722342)
			(xy 128.831808 -270.770616) (xy 128.839972 -270.82085) (xy 128.840484 -270.846296) (xy 129.148581 -270.846296)
			(xy 129.152676 -270.795568) (xy 129.164855 -270.746154) (xy 129.184803 -270.699334) (xy 129.212004 -270.65632)
			(xy 129.245752 -270.618226) (xy 129.285174 -270.586039) (xy 129.329248 -270.560593) (xy 129.376834 -270.542546)
			(xy 129.426698 -270.532366) (xy 129.47755 -270.530317) (xy 129.528071 -270.536451) (xy 129.576955 -270.550611)
			(xy 129.622934 -270.572428) (xy 129.664818 -270.601338) (xy 129.701522 -270.636593) (xy 129.732095 -270.677279)
			(xy 129.755746 -270.722342) (xy 129.771862 -270.770616) (xy 129.780026 -270.82085) (xy 129.780538 -270.846296)
			(xy 131.028435 -270.846296) (xy 131.03253 -270.795568) (xy 131.044709 -270.746154) (xy 131.064657 -270.699334)
			(xy 131.091858 -270.65632) (xy 131.125606 -270.618226) (xy 131.165028 -270.586039) (xy 131.209102 -270.560593)
			(xy 131.256688 -270.542546) (xy 131.306552 -270.532366) (xy 131.357404 -270.530317) (xy 131.407925 -270.536451)
			(xy 131.456809 -270.550611) (xy 131.502788 -270.572428) (xy 131.544672 -270.601338) (xy 131.581376 -270.636593)
			(xy 131.611949 -270.677279) (xy 131.6356 -270.722342) (xy 131.651716 -270.770616) (xy 131.65988 -270.82085)
			(xy 131.660392 -270.846296) (xy 131.97892 -270.846296) (xy 131.98288 -270.797242) (xy 131.994657 -270.749458)
			(xy 132.013948 -270.704182) (xy 132.040251 -270.662586) (xy 132.072886 -270.625749) (xy 132.111007 -270.594624)
			(xy 132.153628 -270.570017) (xy 132.199644 -270.552565) (xy 132.247863 -270.542721) (xy 132.297038 -270.54074)
			(xy 132.345893 -270.546672) (xy 132.393164 -270.560364) (xy 132.437626 -270.581462) (xy 132.478129 -270.609418)
			(xy 132.513622 -270.64351) (xy 132.543187 -270.682854) (xy 132.566058 -270.726431) (xy 132.581642 -270.773112)
			(xy 132.589537 -270.821689) (xy 132.590032 -270.846296) (xy 132.908543 -270.846296) (xy 132.912638 -270.795568)
			(xy 132.924817 -270.746154) (xy 132.944765 -270.699334) (xy 132.971966 -270.65632) (xy 133.005714 -270.618226)
			(xy 133.045136 -270.586039) (xy 133.08921 -270.560593) (xy 133.136796 -270.542546) (xy 133.18666 -270.532366)
			(xy 133.237512 -270.530317) (xy 133.288033 -270.536451) (xy 133.336917 -270.550611) (xy 133.382896 -270.572428)
			(xy 133.42478 -270.601338) (xy 133.461484 -270.636593) (xy 133.492057 -270.677279) (xy 133.515708 -270.722342)
			(xy 133.531824 -270.770616) (xy 133.539988 -270.82085) (xy 133.5405 -270.846296) (xy 133.859028 -270.846296)
			(xy 133.862988 -270.797242) (xy 133.874765 -270.749458) (xy 133.894056 -270.704182) (xy 133.920359 -270.662586)
			(xy 133.952994 -270.625749) (xy 133.991115 -270.594624) (xy 134.033736 -270.570017) (xy 134.079752 -270.552565)
			(xy 134.127971 -270.542721) (xy 134.177146 -270.54074) (xy 134.226001 -270.546672) (xy 134.273272 -270.560364)
			(xy 134.317734 -270.581462) (xy 134.358237 -270.609418) (xy 134.39373 -270.64351) (xy 134.423295 -270.682854)
			(xy 134.446166 -270.726431) (xy 134.46175 -270.773112) (xy 134.469645 -270.821689) (xy 134.47014 -270.846296)
			(xy 134.788397 -270.846296) (xy 134.792492 -270.795568) (xy 134.804671 -270.746154) (xy 134.824619 -270.699334)
			(xy 134.85182 -270.65632) (xy 134.885568 -270.618226) (xy 134.92499 -270.586039) (xy 134.969064 -270.560593)
			(xy 135.01665 -270.542546) (xy 135.066514 -270.532366) (xy 135.117366 -270.530317) (xy 135.167887 -270.536451)
			(xy 135.216771 -270.550611) (xy 135.26275 -270.572428) (xy 135.304634 -270.601338) (xy 135.341338 -270.636593)
			(xy 135.371911 -270.677279) (xy 135.395562 -270.722342) (xy 135.411678 -270.770616) (xy 135.419842 -270.82085)
			(xy 135.420354 -270.846296) (xy 135.728451 -270.846296) (xy 135.732546 -270.795568) (xy 135.744725 -270.746154)
			(xy 135.764673 -270.699334) (xy 135.791874 -270.65632) (xy 135.825622 -270.618226) (xy 135.865044 -270.586039)
			(xy 135.909118 -270.560593) (xy 135.956704 -270.542546) (xy 136.006568 -270.532366) (xy 136.05742 -270.530317)
			(xy 136.107941 -270.536451) (xy 136.156825 -270.550611) (xy 136.202804 -270.572428) (xy 136.244688 -270.601338)
			(xy 136.281392 -270.636593) (xy 136.311965 -270.677279) (xy 136.335616 -270.722342) (xy 136.351732 -270.770616)
			(xy 136.359896 -270.82085) (xy 136.360408 -270.846296) (xy 137.608559 -270.846296) (xy 137.612654 -270.795568)
			(xy 137.624833 -270.746154) (xy 137.644781 -270.699334) (xy 137.671982 -270.65632) (xy 137.70573 -270.618226)
			(xy 137.745152 -270.586039) (xy 137.789226 -270.560593) (xy 137.836812 -270.542546) (xy 137.886676 -270.532366)
			(xy 137.937528 -270.530317) (xy 137.988049 -270.536451) (xy 138.036933 -270.550611) (xy 138.082912 -270.572428)
			(xy 138.124796 -270.601338) (xy 138.1615 -270.636593) (xy 138.192073 -270.677279) (xy 138.215724 -270.722342)
			(xy 138.23184 -270.770616) (xy 138.240004 -270.82085) (xy 138.240516 -270.846296) (xy 138.559044 -270.846296)
			(xy 138.563004 -270.797242) (xy 138.574781 -270.749458) (xy 138.594072 -270.704182) (xy 138.620375 -270.662586)
			(xy 138.65301 -270.625749) (xy 138.691131 -270.594624) (xy 138.733752 -270.570017) (xy 138.779768 -270.552565)
			(xy 138.827987 -270.542721) (xy 138.877162 -270.54074) (xy 138.926017 -270.546672) (xy 138.973288 -270.560364)
			(xy 139.01775 -270.581462) (xy 139.058253 -270.609418) (xy 139.093746 -270.64351) (xy 139.123311 -270.682854)
			(xy 139.146182 -270.726431) (xy 139.161766 -270.773112) (xy 139.169661 -270.821689) (xy 139.170156 -270.846296)
			(xy 139.488413 -270.846296) (xy 139.492508 -270.795568) (xy 139.504687 -270.746154) (xy 139.524635 -270.699334)
			(xy 139.551836 -270.65632) (xy 139.585584 -270.618226) (xy 139.625006 -270.586039) (xy 139.66908 -270.560593)
			(xy 139.716666 -270.542546) (xy 139.76653 -270.532366) (xy 139.817382 -270.530317) (xy 139.867903 -270.536451)
			(xy 139.916787 -270.550611) (xy 139.962766 -270.572428) (xy 140.00465 -270.601338) (xy 140.041354 -270.636593)
			(xy 140.071927 -270.677279) (xy 140.095578 -270.722342) (xy 140.111694 -270.770616) (xy 140.119858 -270.82085)
			(xy 140.12037 -270.846296) (xy 140.438898 -270.846296) (xy 140.442858 -270.797242) (xy 140.454635 -270.749458)
			(xy 140.473926 -270.704182) (xy 140.500229 -270.662586) (xy 140.532864 -270.625749) (xy 140.570985 -270.594624)
			(xy 140.613606 -270.570017) (xy 140.659622 -270.552565) (xy 140.707841 -270.542721) (xy 140.757016 -270.54074)
			(xy 140.805871 -270.546672) (xy 140.853142 -270.560364) (xy 140.897604 -270.581462) (xy 140.938107 -270.609418)
			(xy 140.9736 -270.64351) (xy 141.003165 -270.682854) (xy 141.026036 -270.726431) (xy 141.04162 -270.773112)
			(xy 141.049515 -270.821689) (xy 141.05001 -270.846296) (xy 141.368521 -270.846296) (xy 141.372616 -270.795568)
			(xy 141.384795 -270.746154) (xy 141.404743 -270.699334) (xy 141.431944 -270.65632) (xy 141.465692 -270.618226)
			(xy 141.505114 -270.586039) (xy 141.549188 -270.560593) (xy 141.596774 -270.542546) (xy 141.646638 -270.532366)
			(xy 141.69749 -270.530317) (xy 141.748011 -270.536451) (xy 141.796895 -270.550611) (xy 141.842874 -270.572428)
			(xy 141.884758 -270.601338) (xy 141.921462 -270.636593) (xy 141.952035 -270.677279) (xy 141.975686 -270.722342)
			(xy 141.991802 -270.770616) (xy 141.999966 -270.82085) (xy 142.000478 -270.846296) (xy 142.308575 -270.846296)
			(xy 142.31267 -270.795568) (xy 142.324849 -270.746154) (xy 142.344797 -270.699334) (xy 142.371998 -270.65632)
			(xy 142.405746 -270.618226) (xy 142.445168 -270.586039) (xy 142.489242 -270.560593) (xy 142.536828 -270.542546)
			(xy 142.586692 -270.532366) (xy 142.637544 -270.530317) (xy 142.688065 -270.536451) (xy 142.736949 -270.550611)
			(xy 142.782928 -270.572428) (xy 142.824812 -270.601338) (xy 142.861516 -270.636593) (xy 142.892089 -270.677279)
			(xy 142.91574 -270.722342) (xy 142.931856 -270.770616) (xy 142.94002 -270.82085) (xy 142.940532 -270.846296)
			(xy 145.138914 -270.846296) (xy 145.142874 -270.797242) (xy 145.154651 -270.749458) (xy 145.173942 -270.704182)
			(xy 145.200245 -270.662586) (xy 145.23288 -270.625749) (xy 145.271001 -270.594624) (xy 145.313622 -270.570017)
			(xy 145.359638 -270.552565) (xy 145.407857 -270.542721) (xy 145.457032 -270.54074) (xy 145.505887 -270.546672)
			(xy 145.553158 -270.560364) (xy 145.59762 -270.581462) (xy 145.638123 -270.609418) (xy 145.673616 -270.64351)
			(xy 145.703181 -270.682854) (xy 145.726052 -270.726431) (xy 145.741636 -270.773112) (xy 145.749531 -270.821689)
			(xy 145.750026 -270.846296) (xy 145.749531 -270.870903) (xy 145.741636 -270.91948) (xy 145.726052 -270.966161)
			(xy 145.703181 -271.009738) (xy 145.673616 -271.049082) (xy 145.638123 -271.083174) (xy 145.59762 -271.11113)
			(xy 145.553158 -271.132228) (xy 145.505887 -271.14592) (xy 145.457032 -271.151852) (xy 145.407857 -271.149871)
			(xy 145.359638 -271.140027) (xy 145.313622 -271.122575) (xy 145.271001 -271.097968) (xy 145.23288 -271.066843)
			(xy 145.200245 -271.030006) (xy 145.173942 -270.98841) (xy 145.154651 -270.943134) (xy 145.142874 -270.89535)
			(xy 145.138914 -270.846296) (xy 142.940532 -270.846296) (xy 142.94002 -270.871742) (xy 142.931856 -270.921976)
			(xy 142.91574 -270.97025) (xy 142.892089 -271.015313) (xy 142.861516 -271.055999) (xy 142.824812 -271.091254)
			(xy 142.782928 -271.120164) (xy 142.736949 -271.141981) (xy 142.688065 -271.156141) (xy 142.637544 -271.162275)
			(xy 142.586692 -271.160226) (xy 142.536828 -271.150046) (xy 142.489242 -271.131999) (xy 142.445168 -271.106553)
			(xy 142.405746 -271.074366) (xy 142.371998 -271.036272) (xy 142.344797 -270.993258) (xy 142.324849 -270.946438)
			(xy 142.31267 -270.897024) (xy 142.308575 -270.846296) (xy 142.000478 -270.846296) (xy 141.999966 -270.871742)
			(xy 141.991802 -270.921976) (xy 141.975686 -270.97025) (xy 141.952035 -271.015313) (xy 141.921462 -271.055999)
			(xy 141.884758 -271.091254) (xy 141.842874 -271.120164) (xy 141.796895 -271.141981) (xy 141.748011 -271.156141)
			(xy 141.69749 -271.162275) (xy 141.646638 -271.160226) (xy 141.596774 -271.150046) (xy 141.549188 -271.131999)
			(xy 141.505114 -271.106553) (xy 141.465692 -271.074366) (xy 141.431944 -271.036272) (xy 141.404743 -270.993258)
			(xy 141.384795 -270.946438) (xy 141.372616 -270.897024) (xy 141.368521 -270.846296) (xy 141.05001 -270.846296)
			(xy 141.049515 -270.870903) (xy 141.04162 -270.91948) (xy 141.026036 -270.966161) (xy 141.003165 -271.009738)
			(xy 140.9736 -271.049082) (xy 140.938107 -271.083174) (xy 140.897604 -271.11113) (xy 140.853142 -271.132228)
			(xy 140.805871 -271.14592) (xy 140.757016 -271.151852) (xy 140.707841 -271.149871) (xy 140.659622 -271.140027)
			(xy 140.613606 -271.122575) (xy 140.570985 -271.097968) (xy 140.532864 -271.066843) (xy 140.500229 -271.030006)
			(xy 140.473926 -270.98841) (xy 140.454635 -270.943134) (xy 140.442858 -270.89535) (xy 140.438898 -270.846296)
			(xy 140.12037 -270.846296) (xy 140.119858 -270.871742) (xy 140.111694 -270.921976) (xy 140.095578 -270.97025)
			(xy 140.071927 -271.015313) (xy 140.041354 -271.055999) (xy 140.00465 -271.091254) (xy 139.962766 -271.120164)
			(xy 139.916787 -271.141981) (xy 139.867903 -271.156141) (xy 139.817382 -271.162275) (xy 139.76653 -271.160226)
			(xy 139.716666 -271.150046) (xy 139.66908 -271.131999) (xy 139.625006 -271.106553) (xy 139.585584 -271.074366)
			(xy 139.551836 -271.036272) (xy 139.524635 -270.993258) (xy 139.504687 -270.946438) (xy 139.492508 -270.897024)
			(xy 139.488413 -270.846296) (xy 139.170156 -270.846296) (xy 139.169661 -270.870903) (xy 139.161766 -270.91948)
			(xy 139.146182 -270.966161) (xy 139.123311 -271.009738) (xy 139.093746 -271.049082) (xy 139.058253 -271.083174)
			(xy 139.01775 -271.11113) (xy 138.973288 -271.132228) (xy 138.926017 -271.14592) (xy 138.877162 -271.151852)
			(xy 138.827987 -271.149871) (xy 138.779768 -271.140027) (xy 138.733752 -271.122575) (xy 138.691131 -271.097968)
			(xy 138.65301 -271.066843) (xy 138.620375 -271.030006) (xy 138.594072 -270.98841) (xy 138.574781 -270.943134)
			(xy 138.563004 -270.89535) (xy 138.559044 -270.846296) (xy 138.240516 -270.846296) (xy 138.240004 -270.871742)
			(xy 138.23184 -270.921976) (xy 138.215724 -270.97025) (xy 138.192073 -271.015313) (xy 138.1615 -271.055999)
			(xy 138.124796 -271.091254) (xy 138.082912 -271.120164) (xy 138.036933 -271.141981) (xy 137.988049 -271.156141)
			(xy 137.937528 -271.162275) (xy 137.886676 -271.160226) (xy 137.836812 -271.150046) (xy 137.789226 -271.131999)
			(xy 137.745152 -271.106553) (xy 137.70573 -271.074366) (xy 137.671982 -271.036272) (xy 137.644781 -270.993258)
			(xy 137.624833 -270.946438) (xy 137.612654 -270.897024) (xy 137.608559 -270.846296) (xy 136.360408 -270.846296)
			(xy 136.359896 -270.871742) (xy 136.351732 -270.921976) (xy 136.335616 -270.97025) (xy 136.311965 -271.015313)
			(xy 136.281392 -271.055999) (xy 136.244688 -271.091254) (xy 136.202804 -271.120164) (xy 136.156825 -271.141981)
			(xy 136.107941 -271.156141) (xy 136.05742 -271.162275) (xy 136.006568 -271.160226) (xy 135.956704 -271.150046)
			(xy 135.909118 -271.131999) (xy 135.865044 -271.106553) (xy 135.825622 -271.074366) (xy 135.791874 -271.036272)
			(xy 135.764673 -270.993258) (xy 135.744725 -270.946438) (xy 135.732546 -270.897024) (xy 135.728451 -270.846296)
			(xy 135.420354 -270.846296) (xy 135.419842 -270.871742) (xy 135.411678 -270.921976) (xy 135.395562 -270.97025)
			(xy 135.371911 -271.015313) (xy 135.341338 -271.055999) (xy 135.304634 -271.091254) (xy 135.26275 -271.120164)
			(xy 135.216771 -271.141981) (xy 135.167887 -271.156141) (xy 135.117366 -271.162275) (xy 135.066514 -271.160226)
			(xy 135.01665 -271.150046) (xy 134.969064 -271.131999) (xy 134.92499 -271.106553) (xy 134.885568 -271.074366)
			(xy 134.85182 -271.036272) (xy 134.824619 -270.993258) (xy 134.804671 -270.946438) (xy 134.792492 -270.897024)
			(xy 134.788397 -270.846296) (xy 134.47014 -270.846296) (xy 134.469645 -270.870903) (xy 134.46175 -270.91948)
			(xy 134.446166 -270.966161) (xy 134.423295 -271.009738) (xy 134.39373 -271.049082) (xy 134.358237 -271.083174)
			(xy 134.317734 -271.11113) (xy 134.273272 -271.132228) (xy 134.226001 -271.14592) (xy 134.177146 -271.151852)
			(xy 134.127971 -271.149871) (xy 134.079752 -271.140027) (xy 134.033736 -271.122575) (xy 133.991115 -271.097968)
			(xy 133.952994 -271.066843) (xy 133.920359 -271.030006) (xy 133.894056 -270.98841) (xy 133.874765 -270.943134)
			(xy 133.862988 -270.89535) (xy 133.859028 -270.846296) (xy 133.5405 -270.846296) (xy 133.539988 -270.871742)
			(xy 133.531824 -270.921976) (xy 133.515708 -270.97025) (xy 133.492057 -271.015313) (xy 133.461484 -271.055999)
			(xy 133.42478 -271.091254) (xy 133.382896 -271.120164) (xy 133.336917 -271.141981) (xy 133.288033 -271.156141)
			(xy 133.237512 -271.162275) (xy 133.18666 -271.160226) (xy 133.136796 -271.150046) (xy 133.08921 -271.131999)
			(xy 133.045136 -271.106553) (xy 133.005714 -271.074366) (xy 132.971966 -271.036272) (xy 132.944765 -270.993258)
			(xy 132.924817 -270.946438) (xy 132.912638 -270.897024) (xy 132.908543 -270.846296) (xy 132.590032 -270.846296)
			(xy 132.589537 -270.870903) (xy 132.581642 -270.91948) (xy 132.566058 -270.966161) (xy 132.543187 -271.009738)
			(xy 132.513622 -271.049082) (xy 132.478129 -271.083174) (xy 132.437626 -271.11113) (xy 132.393164 -271.132228)
			(xy 132.345893 -271.14592) (xy 132.297038 -271.151852) (xy 132.247863 -271.149871) (xy 132.199644 -271.140027)
			(xy 132.153628 -271.122575) (xy 132.111007 -271.097968) (xy 132.072886 -271.066843) (xy 132.040251 -271.030006)
			(xy 132.013948 -270.98841) (xy 131.994657 -270.943134) (xy 131.98288 -270.89535) (xy 131.97892 -270.846296)
			(xy 131.660392 -270.846296) (xy 131.65988 -270.871742) (xy 131.651716 -270.921976) (xy 131.6356 -270.97025)
			(xy 131.611949 -271.015313) (xy 131.581376 -271.055999) (xy 131.544672 -271.091254) (xy 131.502788 -271.120164)
			(xy 131.456809 -271.141981) (xy 131.407925 -271.156141) (xy 131.357404 -271.162275) (xy 131.306552 -271.160226)
			(xy 131.256688 -271.150046) (xy 131.209102 -271.131999) (xy 131.165028 -271.106553) (xy 131.125606 -271.074366)
			(xy 131.091858 -271.036272) (xy 131.064657 -270.993258) (xy 131.044709 -270.946438) (xy 131.03253 -270.897024)
			(xy 131.028435 -270.846296) (xy 129.780538 -270.846296) (xy 129.780026 -270.871742) (xy 129.771862 -270.921976)
			(xy 129.755746 -270.97025) (xy 129.732095 -271.015313) (xy 129.701522 -271.055999) (xy 129.664818 -271.091254)
			(xy 129.622934 -271.120164) (xy 129.576955 -271.141981) (xy 129.528071 -271.156141) (xy 129.47755 -271.162275)
			(xy 129.426698 -271.160226) (xy 129.376834 -271.150046) (xy 129.329248 -271.131999) (xy 129.285174 -271.106553)
			(xy 129.245752 -271.074366) (xy 129.212004 -271.036272) (xy 129.184803 -270.993258) (xy 129.164855 -270.946438)
			(xy 129.152676 -270.897024) (xy 129.148581 -270.846296) (xy 128.840484 -270.846296) (xy 128.839972 -270.871742)
			(xy 128.831808 -270.921976) (xy 128.815692 -270.97025) (xy 128.792041 -271.015313) (xy 128.761468 -271.055999)
			(xy 128.724764 -271.091254) (xy 128.68288 -271.120164) (xy 128.636901 -271.141981) (xy 128.588017 -271.156141)
			(xy 128.537496 -271.162275) (xy 128.486644 -271.160226) (xy 128.43678 -271.150046) (xy 128.389194 -271.131999)
			(xy 128.34512 -271.106553) (xy 128.305698 -271.074366) (xy 128.27195 -271.036272) (xy 128.244749 -270.993258)
			(xy 128.224801 -270.946438) (xy 128.212622 -270.897024) (xy 128.208527 -270.846296) (xy 127.20574 -270.846296)
			(xy 127.20574 -271.344898) (xy 127.22225 -271.370044) (xy 127.23622 -271.37614) (xy 127.259286 -271.386683)
			(xy 127.301846 -271.414259) (xy 127.339264 -271.448488) (xy 127.370513 -271.488429) (xy 127.394734 -271.532984)
			(xy 127.411261 -271.580929) (xy 127.419639 -271.630944) (xy 127.419639 -271.656302) (xy 127.738627 -271.656302)
			(xy 127.742722 -271.605574) (xy 127.754901 -271.55616) (xy 127.774849 -271.50934) (xy 127.80205 -271.466326)
			(xy 127.835798 -271.428232) (xy 127.87522 -271.396045) (xy 127.919294 -271.370599) (xy 127.96688 -271.352552)
			(xy 128.016744 -271.342372) (xy 128.067596 -271.340323) (xy 128.118117 -271.346457) (xy 128.167001 -271.360617)
			(xy 128.21298 -271.382434) (xy 128.254864 -271.411344) (xy 128.291568 -271.446599) (xy 128.322141 -271.487285)
			(xy 128.345792 -271.532348) (xy 128.361908 -271.580622) (xy 128.370072 -271.630856) (xy 128.370584 -271.656302)
			(xy 128.688858 -271.656302) (xy 128.692818 -271.607248) (xy 128.704595 -271.559464) (xy 128.723886 -271.514188)
			(xy 128.750189 -271.472592) (xy 128.782824 -271.435755) (xy 128.820945 -271.40463) (xy 128.863566 -271.380023)
			(xy 128.909582 -271.362571) (xy 128.957801 -271.352727) (xy 129.006976 -271.350746) (xy 129.055831 -271.356678)
			(xy 129.103102 -271.37037) (xy 129.147564 -271.391468) (xy 129.188067 -271.419424) (xy 129.22356 -271.453516)
			(xy 129.253125 -271.49286) (xy 129.275996 -271.536437) (xy 129.29158 -271.583118) (xy 129.299475 -271.631695)
			(xy 129.29997 -271.656302) (xy 129.618481 -271.656302) (xy 129.622576 -271.605574) (xy 129.634755 -271.55616)
			(xy 129.654703 -271.50934) (xy 129.681904 -271.466326) (xy 129.715652 -271.428232) (xy 129.755074 -271.396045)
			(xy 129.799148 -271.370599) (xy 129.846734 -271.352552) (xy 129.896598 -271.342372) (xy 129.94745 -271.340323)
			(xy 129.997971 -271.346457) (xy 130.046855 -271.360617) (xy 130.092834 -271.382434) (xy 130.134718 -271.411344)
			(xy 130.171422 -271.446599) (xy 130.201995 -271.487285) (xy 130.225646 -271.532348) (xy 130.241762 -271.580622)
			(xy 130.249926 -271.630856) (xy 130.250438 -271.656302) (xy 130.568966 -271.656302) (xy 130.572926 -271.607248)
			(xy 130.584703 -271.559464) (xy 130.603994 -271.514188) (xy 130.630297 -271.472592) (xy 130.662932 -271.435755)
			(xy 130.701053 -271.40463) (xy 130.743674 -271.380023) (xy 130.78969 -271.362571) (xy 130.837909 -271.352727)
			(xy 130.887084 -271.350746) (xy 130.935939 -271.356678) (xy 130.98321 -271.37037) (xy 131.027672 -271.391468)
			(xy 131.068175 -271.419424) (xy 131.103668 -271.453516) (xy 131.133233 -271.49286) (xy 131.156104 -271.536437)
			(xy 131.171688 -271.583118) (xy 131.179583 -271.631695) (xy 131.180078 -271.656302) (xy 131.498589 -271.656302)
			(xy 131.502684 -271.605574) (xy 131.514863 -271.55616) (xy 131.534811 -271.50934) (xy 131.562012 -271.466326)
			(xy 131.59576 -271.428232) (xy 131.635182 -271.396045) (xy 131.679256 -271.370599) (xy 131.726842 -271.352552)
			(xy 131.776706 -271.342372) (xy 131.827558 -271.340323) (xy 131.878079 -271.346457) (xy 131.926963 -271.360617)
			(xy 131.972942 -271.382434) (xy 132.014826 -271.411344) (xy 132.05153 -271.446599) (xy 132.082103 -271.487285)
			(xy 132.105754 -271.532348) (xy 132.12187 -271.580622) (xy 132.130034 -271.630856) (xy 132.130546 -271.656302)
			(xy 132.438643 -271.656302) (xy 132.442738 -271.605574) (xy 132.454917 -271.55616) (xy 132.474865 -271.50934)
			(xy 132.502066 -271.466326) (xy 132.535814 -271.428232) (xy 132.575236 -271.396045) (xy 132.61931 -271.370599)
			(xy 132.666896 -271.352552) (xy 132.71676 -271.342372) (xy 132.767612 -271.340323) (xy 132.818133 -271.346457)
			(xy 132.867017 -271.360617) (xy 132.912996 -271.382434) (xy 132.95488 -271.411344) (xy 132.991584 -271.446599)
			(xy 133.022157 -271.487285) (xy 133.045808 -271.532348) (xy 133.061924 -271.580622) (xy 133.070088 -271.630856)
			(xy 133.0706 -271.656302) (xy 133.388874 -271.656302) (xy 133.392834 -271.607248) (xy 133.404611 -271.559464)
			(xy 133.423902 -271.514188) (xy 133.450205 -271.472592) (xy 133.48284 -271.435755) (xy 133.520961 -271.40463)
			(xy 133.563582 -271.380023) (xy 133.609598 -271.362571) (xy 133.657817 -271.352727) (xy 133.706992 -271.350746)
			(xy 133.755847 -271.356678) (xy 133.803118 -271.37037) (xy 133.84758 -271.391468) (xy 133.888083 -271.419424)
			(xy 133.923576 -271.453516) (xy 133.953141 -271.49286) (xy 133.976012 -271.536437) (xy 133.991596 -271.583118)
			(xy 133.999491 -271.631695) (xy 133.999986 -271.656302) (xy 134.318497 -271.656302) (xy 134.322592 -271.605574)
			(xy 134.334771 -271.55616) (xy 134.354719 -271.50934) (xy 134.38192 -271.466326) (xy 134.415668 -271.428232)
			(xy 134.45509 -271.396045) (xy 134.499164 -271.370599) (xy 134.54675 -271.352552) (xy 134.596614 -271.342372)
			(xy 134.647466 -271.340323) (xy 134.697987 -271.346457) (xy 134.746871 -271.360617) (xy 134.79285 -271.382434)
			(xy 134.834734 -271.411344) (xy 134.871438 -271.446599) (xy 134.902011 -271.487285) (xy 134.925662 -271.532348)
			(xy 134.941778 -271.580622) (xy 134.949942 -271.630856) (xy 134.950454 -271.656302) (xy 135.268982 -271.656302)
			(xy 135.272942 -271.607248) (xy 135.284719 -271.559464) (xy 135.30401 -271.514188) (xy 135.330313 -271.472592)
			(xy 135.362948 -271.435755) (xy 135.401069 -271.40463) (xy 135.44369 -271.380023) (xy 135.489706 -271.362571)
			(xy 135.537925 -271.352727) (xy 135.5871 -271.350746) (xy 135.635955 -271.356678) (xy 135.683226 -271.37037)
			(xy 135.727688 -271.391468) (xy 135.768191 -271.419424) (xy 135.803684 -271.453516) (xy 135.833249 -271.49286)
			(xy 135.85612 -271.536437) (xy 135.871704 -271.583118) (xy 135.879599 -271.631695) (xy 135.880094 -271.656302)
			(xy 136.198605 -271.656302) (xy 136.2027 -271.605574) (xy 136.214879 -271.55616) (xy 136.234827 -271.50934)
			(xy 136.262028 -271.466326) (xy 136.295776 -271.428232) (xy 136.335198 -271.396045) (xy 136.379272 -271.370599)
			(xy 136.426858 -271.352552) (xy 136.476722 -271.342372) (xy 136.527574 -271.340323) (xy 136.578095 -271.346457)
			(xy 136.626979 -271.360617) (xy 136.672958 -271.382434) (xy 136.714842 -271.411344) (xy 136.751546 -271.446599)
			(xy 136.782119 -271.487285) (xy 136.80577 -271.532348) (xy 136.821886 -271.580622) (xy 136.83005 -271.630856)
			(xy 136.830562 -271.656302) (xy 137.148836 -271.656302) (xy 137.152796 -271.607248) (xy 137.164573 -271.559464)
			(xy 137.183864 -271.514188) (xy 137.210167 -271.472592) (xy 137.242802 -271.435755) (xy 137.280923 -271.40463)
			(xy 137.323544 -271.380023) (xy 137.36956 -271.362571) (xy 137.417779 -271.352727) (xy 137.466954 -271.350746)
			(xy 137.515809 -271.356678) (xy 137.56308 -271.37037) (xy 137.607542 -271.391468) (xy 137.648045 -271.419424)
			(xy 137.683538 -271.453516) (xy 137.713103 -271.49286) (xy 137.735974 -271.536437) (xy 137.751558 -271.583118)
			(xy 137.759453 -271.631695) (xy 137.759948 -271.656302) (xy 138.078459 -271.656302) (xy 138.082554 -271.605574)
			(xy 138.094733 -271.55616) (xy 138.114681 -271.50934) (xy 138.141882 -271.466326) (xy 138.17563 -271.428232)
			(xy 138.215052 -271.396045) (xy 138.259126 -271.370599) (xy 138.306712 -271.352552) (xy 138.356576 -271.342372)
			(xy 138.407428 -271.340323) (xy 138.457949 -271.346457) (xy 138.506833 -271.360617) (xy 138.552812 -271.382434)
			(xy 138.594696 -271.411344) (xy 138.6314 -271.446599) (xy 138.661973 -271.487285) (xy 138.685624 -271.532348)
			(xy 138.70174 -271.580622) (xy 138.709904 -271.630856) (xy 138.710416 -271.656302) (xy 139.018513 -271.656302)
			(xy 139.022608 -271.605574) (xy 139.034787 -271.55616) (xy 139.054735 -271.50934) (xy 139.081936 -271.466326)
			(xy 139.115684 -271.428232) (xy 139.155106 -271.396045) (xy 139.19918 -271.370599) (xy 139.246766 -271.352552)
			(xy 139.29663 -271.342372) (xy 139.347482 -271.340323) (xy 139.398003 -271.346457) (xy 139.446887 -271.360617)
			(xy 139.492866 -271.382434) (xy 139.53475 -271.411344) (xy 139.571454 -271.446599) (xy 139.602027 -271.487285)
			(xy 139.625678 -271.532348) (xy 139.641794 -271.580622) (xy 139.649958 -271.630856) (xy 139.65047 -271.656302)
			(xy 139.968998 -271.656302) (xy 139.972958 -271.607248) (xy 139.984735 -271.559464) (xy 140.004026 -271.514188)
			(xy 140.030329 -271.472592) (xy 140.062964 -271.435755) (xy 140.101085 -271.40463) (xy 140.143706 -271.380023)
			(xy 140.189722 -271.362571) (xy 140.237941 -271.352727) (xy 140.287116 -271.350746) (xy 140.335971 -271.356678)
			(xy 140.383242 -271.37037) (xy 140.427704 -271.391468) (xy 140.468207 -271.419424) (xy 140.5037 -271.453516)
			(xy 140.533265 -271.49286) (xy 140.556136 -271.536437) (xy 140.57172 -271.583118) (xy 140.579615 -271.631695)
			(xy 140.58011 -271.656302) (xy 140.898621 -271.656302) (xy 140.902716 -271.605574) (xy 140.914895 -271.55616)
			(xy 140.934843 -271.50934) (xy 140.962044 -271.466326) (xy 140.995792 -271.428232) (xy 141.035214 -271.396045)
			(xy 141.079288 -271.370599) (xy 141.126874 -271.352552) (xy 141.176738 -271.342372) (xy 141.22759 -271.340323)
			(xy 141.278111 -271.346457) (xy 141.326995 -271.360617) (xy 141.372974 -271.382434) (xy 141.414858 -271.411344)
			(xy 141.451562 -271.446599) (xy 141.482135 -271.487285) (xy 141.505786 -271.532348) (xy 141.521902 -271.580622)
			(xy 141.530066 -271.630856) (xy 141.530578 -271.656302) (xy 141.848852 -271.656302) (xy 141.852812 -271.607248)
			(xy 141.864589 -271.559464) (xy 141.88388 -271.514188) (xy 141.910183 -271.472592) (xy 141.942818 -271.435755)
			(xy 141.980939 -271.40463) (xy 142.02356 -271.380023) (xy 142.069576 -271.362571) (xy 142.117795 -271.352727)
			(xy 142.16697 -271.350746) (xy 142.215825 -271.356678) (xy 142.263096 -271.37037) (xy 142.307558 -271.391468)
			(xy 142.348061 -271.419424) (xy 142.383554 -271.453516) (xy 142.413119 -271.49286) (xy 142.43599 -271.536437)
			(xy 142.451574 -271.583118) (xy 142.459469 -271.631695) (xy 142.459964 -271.656302) (xy 142.778475 -271.656302)
			(xy 142.78257 -271.605574) (xy 142.794749 -271.55616) (xy 142.814697 -271.50934) (xy 142.841898 -271.466326)
			(xy 142.875646 -271.428232) (xy 142.915068 -271.396045) (xy 142.959142 -271.370599) (xy 143.006728 -271.352552)
			(xy 143.056592 -271.342372) (xy 143.107444 -271.340323) (xy 143.157965 -271.346457) (xy 143.206849 -271.360617)
			(xy 143.252828 -271.382434) (xy 143.294712 -271.411344) (xy 143.331416 -271.446599) (xy 143.361989 -271.487285)
			(xy 143.38564 -271.532348) (xy 143.401756 -271.580622) (xy 143.40992 -271.630856) (xy 143.410432 -271.656302)
			(xy 143.72896 -271.656302) (xy 143.73292 -271.607248) (xy 143.744697 -271.559464) (xy 143.763988 -271.514188)
			(xy 143.790291 -271.472592) (xy 143.822926 -271.435755) (xy 143.861047 -271.40463) (xy 143.903668 -271.380023)
			(xy 143.949684 -271.362571) (xy 143.997903 -271.352727) (xy 144.047078 -271.350746) (xy 144.095933 -271.356678)
			(xy 144.143204 -271.37037) (xy 144.185339 -271.390364) (xy 146.737082 -271.390364) (xy 146.741042 -271.34131)
			(xy 146.752819 -271.293526) (xy 146.77211 -271.24825) (xy 146.798413 -271.206654) (xy 146.831048 -271.169817)
			(xy 146.869169 -271.138692) (xy 146.91179 -271.114085) (xy 146.957806 -271.096633) (xy 147.006025 -271.086789)
			(xy 147.0552 -271.084808) (xy 147.104055 -271.09074) (xy 147.151326 -271.104432) (xy 147.195788 -271.12553)
			(xy 147.236291 -271.153486) (xy 147.271784 -271.187578) (xy 147.301349 -271.226922) (xy 147.32422 -271.270499)
			(xy 147.32913 -271.285208) (xy 168.158683 -271.285208) (xy 168.162618 -271.231437) (xy 168.174341 -271.178813)
			(xy 168.193601 -271.128456) (xy 168.219987 -271.081439) (xy 168.252939 -271.038766) (xy 168.291752 -271.001345)
			(xy 168.3356 -270.969975) (xy 168.383548 -270.945323) (xy 168.434575 -270.927915) (xy 168.487593 -270.918122)
			(xy 168.541472 -270.916153) (xy 168.595063 -270.92205) (xy 168.647224 -270.935686) (xy 168.696844 -270.956773)
			(xy 168.742865 -270.984859) (xy 168.784307 -271.019347) (xy 168.820285 -271.059501) (xy 168.850033 -271.104465)
			(xy 168.872918 -271.153282) (xy 168.88845 -271.204911) (xy 168.8963 -271.258251) (xy 168.896792 -271.285208)
			(xy 168.8963 -271.312165) (xy 168.88845 -271.365505) (xy 168.872918 -271.417134) (xy 168.850033 -271.465951)
			(xy 168.820285 -271.510915) (xy 168.784307 -271.551069) (xy 168.742865 -271.585557) (xy 168.696844 -271.613643)
			(xy 168.647224 -271.63473) (xy 168.595063 -271.648366) (xy 168.541472 -271.654263) (xy 168.487593 -271.652294)
			(xy 168.434575 -271.642501) (xy 168.383548 -271.625093) (xy 168.3356 -271.600441) (xy 168.291752 -271.569071)
			(xy 168.252939 -271.53165) (xy 168.219987 -271.488977) (xy 168.193601 -271.44196) (xy 168.174341 -271.391603)
			(xy 168.162618 -271.338979) (xy 168.158683 -271.285208) (xy 147.32913 -271.285208) (xy 147.339804 -271.31718)
			(xy 147.347699 -271.365757) (xy 147.348194 -271.390364) (xy 147.347699 -271.414971) (xy 147.339804 -271.463548)
			(xy 147.32422 -271.510229) (xy 147.301349 -271.553806) (xy 147.271784 -271.59315) (xy 147.236291 -271.627242)
			(xy 147.195788 -271.655198) (xy 147.151326 -271.676296) (xy 147.104055 -271.689988) (xy 147.0552 -271.69592)
			(xy 147.006025 -271.693939) (xy 146.957806 -271.684095) (xy 146.91179 -271.666643) (xy 146.869169 -271.642036)
			(xy 146.831048 -271.610911) (xy 146.798413 -271.574074) (xy 146.77211 -271.532478) (xy 146.752819 -271.487202)
			(xy 146.741042 -271.439418) (xy 146.737082 -271.390364) (xy 144.185339 -271.390364) (xy 144.187666 -271.391468)
			(xy 144.228169 -271.419424) (xy 144.263662 -271.453516) (xy 144.293227 -271.49286) (xy 144.316098 -271.536437)
			(xy 144.331682 -271.583118) (xy 144.339577 -271.631695) (xy 144.340072 -271.656302) (xy 144.339577 -271.680909)
			(xy 144.331682 -271.729486) (xy 144.316098 -271.776167) (xy 144.293227 -271.819744) (xy 144.263662 -271.859088)
			(xy 144.228169 -271.89318) (xy 144.187666 -271.921136) (xy 144.143204 -271.942234) (xy 144.095933 -271.955926)
			(xy 144.047078 -271.961858) (xy 143.997903 -271.959877) (xy 143.949684 -271.950033) (xy 143.903668 -271.932581)
			(xy 143.861047 -271.907974) (xy 143.822926 -271.876849) (xy 143.790291 -271.840012) (xy 143.763988 -271.798416)
			(xy 143.744697 -271.75314) (xy 143.73292 -271.705356) (xy 143.72896 -271.656302) (xy 143.410432 -271.656302)
			(xy 143.40992 -271.681748) (xy 143.401756 -271.731982) (xy 143.38564 -271.780256) (xy 143.361989 -271.825319)
			(xy 143.331416 -271.866005) (xy 143.294712 -271.90126) (xy 143.252828 -271.93017) (xy 143.206849 -271.951987)
			(xy 143.157965 -271.966147) (xy 143.107444 -271.972281) (xy 143.056592 -271.970232) (xy 143.006728 -271.960052)
			(xy 142.959142 -271.942005) (xy 142.915068 -271.916559) (xy 142.875646 -271.884372) (xy 142.841898 -271.846278)
			(xy 142.814697 -271.803264) (xy 142.794749 -271.756444) (xy 142.78257 -271.70703) (xy 142.778475 -271.656302)
			(xy 142.459964 -271.656302) (xy 142.459469 -271.680909) (xy 142.451574 -271.729486) (xy 142.43599 -271.776167)
			(xy 142.413119 -271.819744) (xy 142.383554 -271.859088) (xy 142.348061 -271.89318) (xy 142.307558 -271.921136)
			(xy 142.263096 -271.942234) (xy 142.215825 -271.955926) (xy 142.16697 -271.961858) (xy 142.117795 -271.959877)
			(xy 142.069576 -271.950033) (xy 142.02356 -271.932581) (xy 141.980939 -271.907974) (xy 141.942818 -271.876849)
			(xy 141.910183 -271.840012) (xy 141.88388 -271.798416) (xy 141.864589 -271.75314) (xy 141.852812 -271.705356)
			(xy 141.848852 -271.656302) (xy 141.530578 -271.656302) (xy 141.530066 -271.681748) (xy 141.521902 -271.731982)
			(xy 141.505786 -271.780256) (xy 141.482135 -271.825319) (xy 141.451562 -271.866005) (xy 141.414858 -271.90126)
			(xy 141.372974 -271.93017) (xy 141.326995 -271.951987) (xy 141.278111 -271.966147) (xy 141.22759 -271.972281)
			(xy 141.176738 -271.970232) (xy 141.126874 -271.960052) (xy 141.079288 -271.942005) (xy 141.035214 -271.916559)
			(xy 140.995792 -271.884372) (xy 140.962044 -271.846278) (xy 140.934843 -271.803264) (xy 140.914895 -271.756444)
			(xy 140.902716 -271.70703) (xy 140.898621 -271.656302) (xy 140.58011 -271.656302) (xy 140.579615 -271.680909)
			(xy 140.57172 -271.729486) (xy 140.556136 -271.776167) (xy 140.533265 -271.819744) (xy 140.5037 -271.859088)
			(xy 140.468207 -271.89318) (xy 140.427704 -271.921136) (xy 140.383242 -271.942234) (xy 140.335971 -271.955926)
			(xy 140.287116 -271.961858) (xy 140.237941 -271.959877) (xy 140.189722 -271.950033) (xy 140.143706 -271.932581)
			(xy 140.101085 -271.907974) (xy 140.062964 -271.876849) (xy 140.030329 -271.840012) (xy 140.004026 -271.798416)
			(xy 139.984735 -271.75314) (xy 139.972958 -271.705356) (xy 139.968998 -271.656302) (xy 139.65047 -271.656302)
			(xy 139.649958 -271.681748) (xy 139.641794 -271.731982) (xy 139.625678 -271.780256) (xy 139.602027 -271.825319)
			(xy 139.571454 -271.866005) (xy 139.53475 -271.90126) (xy 139.492866 -271.93017) (xy 139.446887 -271.951987)
			(xy 139.398003 -271.966147) (xy 139.347482 -271.972281) (xy 139.29663 -271.970232) (xy 139.246766 -271.960052)
			(xy 139.19918 -271.942005) (xy 139.155106 -271.916559) (xy 139.115684 -271.884372) (xy 139.081936 -271.846278)
			(xy 139.054735 -271.803264) (xy 139.034787 -271.756444) (xy 139.022608 -271.70703) (xy 139.018513 -271.656302)
			(xy 138.710416 -271.656302) (xy 138.709904 -271.681748) (xy 138.70174 -271.731982) (xy 138.685624 -271.780256)
			(xy 138.661973 -271.825319) (xy 138.6314 -271.866005) (xy 138.594696 -271.90126) (xy 138.552812 -271.93017)
			(xy 138.506833 -271.951987) (xy 138.457949 -271.966147) (xy 138.407428 -271.972281) (xy 138.356576 -271.970232)
			(xy 138.306712 -271.960052) (xy 138.259126 -271.942005) (xy 138.215052 -271.916559) (xy 138.17563 -271.884372)
			(xy 138.141882 -271.846278) (xy 138.114681 -271.803264) (xy 138.094733 -271.756444) (xy 138.082554 -271.70703)
			(xy 138.078459 -271.656302) (xy 137.759948 -271.656302) (xy 137.759453 -271.680909) (xy 137.751558 -271.729486)
			(xy 137.735974 -271.776167) (xy 137.713103 -271.819744) (xy 137.683538 -271.859088) (xy 137.648045 -271.89318)
			(xy 137.607542 -271.921136) (xy 137.56308 -271.942234) (xy 137.515809 -271.955926) (xy 137.466954 -271.961858)
			(xy 137.417779 -271.959877) (xy 137.36956 -271.950033) (xy 137.323544 -271.932581) (xy 137.280923 -271.907974)
			(xy 137.242802 -271.876849) (xy 137.210167 -271.840012) (xy 137.183864 -271.798416) (xy 137.164573 -271.75314)
			(xy 137.152796 -271.705356) (xy 137.148836 -271.656302) (xy 136.830562 -271.656302) (xy 136.83005 -271.681748)
			(xy 136.821886 -271.731982) (xy 136.80577 -271.780256) (xy 136.782119 -271.825319) (xy 136.751546 -271.866005)
			(xy 136.714842 -271.90126) (xy 136.672958 -271.93017) (xy 136.626979 -271.951987) (xy 136.578095 -271.966147)
			(xy 136.527574 -271.972281) (xy 136.476722 -271.970232) (xy 136.426858 -271.960052) (xy 136.379272 -271.942005)
			(xy 136.335198 -271.916559) (xy 136.295776 -271.884372) (xy 136.262028 -271.846278) (xy 136.234827 -271.803264)
			(xy 136.214879 -271.756444) (xy 136.2027 -271.70703) (xy 136.198605 -271.656302) (xy 135.880094 -271.656302)
			(xy 135.879599 -271.680909) (xy 135.871704 -271.729486) (xy 135.85612 -271.776167) (xy 135.833249 -271.819744)
			(xy 135.803684 -271.859088) (xy 135.768191 -271.89318) (xy 135.727688 -271.921136) (xy 135.683226 -271.942234)
			(xy 135.635955 -271.955926) (xy 135.5871 -271.961858) (xy 135.537925 -271.959877) (xy 135.489706 -271.950033)
			(xy 135.44369 -271.932581) (xy 135.401069 -271.907974) (xy 135.362948 -271.876849) (xy 135.330313 -271.840012)
			(xy 135.30401 -271.798416) (xy 135.284719 -271.75314) (xy 135.272942 -271.705356) (xy 135.268982 -271.656302)
			(xy 134.950454 -271.656302) (xy 134.949942 -271.681748) (xy 134.941778 -271.731982) (xy 134.925662 -271.780256)
			(xy 134.902011 -271.825319) (xy 134.871438 -271.866005) (xy 134.834734 -271.90126) (xy 134.79285 -271.93017)
			(xy 134.746871 -271.951987) (xy 134.697987 -271.966147) (xy 134.647466 -271.972281) (xy 134.596614 -271.970232)
			(xy 134.54675 -271.960052) (xy 134.499164 -271.942005) (xy 134.45509 -271.916559) (xy 134.415668 -271.884372)
			(xy 134.38192 -271.846278) (xy 134.354719 -271.803264) (xy 134.334771 -271.756444) (xy 134.322592 -271.70703)
			(xy 134.318497 -271.656302) (xy 133.999986 -271.656302) (xy 133.999491 -271.680909) (xy 133.991596 -271.729486)
			(xy 133.976012 -271.776167) (xy 133.953141 -271.819744) (xy 133.923576 -271.859088) (xy 133.888083 -271.89318)
			(xy 133.84758 -271.921136) (xy 133.803118 -271.942234) (xy 133.755847 -271.955926) (xy 133.706992 -271.961858)
			(xy 133.657817 -271.959877) (xy 133.609598 -271.950033) (xy 133.563582 -271.932581) (xy 133.520961 -271.907974)
			(xy 133.48284 -271.876849) (xy 133.450205 -271.840012) (xy 133.423902 -271.798416) (xy 133.404611 -271.75314)
			(xy 133.392834 -271.705356) (xy 133.388874 -271.656302) (xy 133.0706 -271.656302) (xy 133.070088 -271.681748)
			(xy 133.061924 -271.731982) (xy 133.045808 -271.780256) (xy 133.022157 -271.825319) (xy 132.991584 -271.866005)
			(xy 132.95488 -271.90126) (xy 132.912996 -271.93017) (xy 132.867017 -271.951987) (xy 132.818133 -271.966147)
			(xy 132.767612 -271.972281) (xy 132.71676 -271.970232) (xy 132.666896 -271.960052) (xy 132.61931 -271.942005)
			(xy 132.575236 -271.916559) (xy 132.535814 -271.884372) (xy 132.502066 -271.846278) (xy 132.474865 -271.803264)
			(xy 132.454917 -271.756444) (xy 132.442738 -271.70703) (xy 132.438643 -271.656302) (xy 132.130546 -271.656302)
			(xy 132.130034 -271.681748) (xy 132.12187 -271.731982) (xy 132.105754 -271.780256) (xy 132.082103 -271.825319)
			(xy 132.05153 -271.866005) (xy 132.014826 -271.90126) (xy 131.972942 -271.93017) (xy 131.926963 -271.951987)
			(xy 131.878079 -271.966147) (xy 131.827558 -271.972281) (xy 131.776706 -271.970232) (xy 131.726842 -271.960052)
			(xy 131.679256 -271.942005) (xy 131.635182 -271.916559) (xy 131.59576 -271.884372) (xy 131.562012 -271.846278)
			(xy 131.534811 -271.803264) (xy 131.514863 -271.756444) (xy 131.502684 -271.70703) (xy 131.498589 -271.656302)
			(xy 131.180078 -271.656302) (xy 131.179583 -271.680909) (xy 131.171688 -271.729486) (xy 131.156104 -271.776167)
			(xy 131.133233 -271.819744) (xy 131.103668 -271.859088) (xy 131.068175 -271.89318) (xy 131.027672 -271.921136)
			(xy 130.98321 -271.942234) (xy 130.935939 -271.955926) (xy 130.887084 -271.961858) (xy 130.837909 -271.959877)
			(xy 130.78969 -271.950033) (xy 130.743674 -271.932581) (xy 130.701053 -271.907974) (xy 130.662932 -271.876849)
			(xy 130.630297 -271.840012) (xy 130.603994 -271.798416) (xy 130.584703 -271.75314) (xy 130.572926 -271.705356)
			(xy 130.568966 -271.656302) (xy 130.250438 -271.656302) (xy 130.249926 -271.681748) (xy 130.241762 -271.731982)
			(xy 130.225646 -271.780256) (xy 130.201995 -271.825319) (xy 130.171422 -271.866005) (xy 130.134718 -271.90126)
			(xy 130.092834 -271.93017) (xy 130.046855 -271.951987) (xy 129.997971 -271.966147) (xy 129.94745 -271.972281)
			(xy 129.896598 -271.970232) (xy 129.846734 -271.960052) (xy 129.799148 -271.942005) (xy 129.755074 -271.916559)
			(xy 129.715652 -271.884372) (xy 129.681904 -271.846278) (xy 129.654703 -271.803264) (xy 129.634755 -271.756444)
			(xy 129.622576 -271.70703) (xy 129.618481 -271.656302) (xy 129.29997 -271.656302) (xy 129.299475 -271.680909)
			(xy 129.29158 -271.729486) (xy 129.275996 -271.776167) (xy 129.253125 -271.819744) (xy 129.22356 -271.859088)
			(xy 129.188067 -271.89318) (xy 129.147564 -271.921136) (xy 129.103102 -271.942234) (xy 129.055831 -271.955926)
			(xy 129.006976 -271.961858) (xy 128.957801 -271.959877) (xy 128.909582 -271.950033) (xy 128.863566 -271.932581)
			(xy 128.820945 -271.907974) (xy 128.782824 -271.876849) (xy 128.750189 -271.840012) (xy 128.723886 -271.798416)
			(xy 128.704595 -271.75314) (xy 128.692818 -271.705356) (xy 128.688858 -271.656302) (xy 128.370584 -271.656302)
			(xy 128.370072 -271.681748) (xy 128.361908 -271.731982) (xy 128.345792 -271.780256) (xy 128.322141 -271.825319)
			(xy 128.291568 -271.866005) (xy 128.254864 -271.90126) (xy 128.21298 -271.93017) (xy 128.167001 -271.951987)
			(xy 128.118117 -271.966147) (xy 128.067596 -271.972281) (xy 128.016744 -271.970232) (xy 127.96688 -271.960052)
			(xy 127.919294 -271.942005) (xy 127.87522 -271.916559) (xy 127.835798 -271.884372) (xy 127.80205 -271.846278)
			(xy 127.774849 -271.803264) (xy 127.754901 -271.756444) (xy 127.742722 -271.70703) (xy 127.738627 -271.656302)
			(xy 127.419639 -271.656302) (xy 127.419639 -271.681657) (xy 127.41126 -271.731673) (xy 127.394733 -271.779617)
			(xy 127.370512 -271.824172) (xy 127.339263 -271.864113) (xy 127.301844 -271.898342) (xy 127.259285 -271.925918)
			(xy 127.23622 -271.936464) (xy 127.22225 -271.94256) (xy 127.20574 -271.967706) (xy 127.20574 -272.135346)
			(xy 164.058615 -272.135346) (xy 164.06255 -272.081575) (xy 164.074273 -272.028951) (xy 164.093533 -271.978594)
			(xy 164.119919 -271.931577) (xy 164.152871 -271.888904) (xy 164.191684 -271.851483) (xy 164.235532 -271.820113)
			(xy 164.28348 -271.795461) (xy 164.334507 -271.778053) (xy 164.387525 -271.76826) (xy 164.441404 -271.766291)
			(xy 164.494995 -271.772188) (xy 164.547156 -271.785824) (xy 164.596776 -271.806911) (xy 164.642797 -271.834997)
			(xy 164.684239 -271.869485) (xy 164.720217 -271.909639) (xy 164.749965 -271.954603) (xy 164.77285 -272.00342)
			(xy 164.788382 -272.055049) (xy 164.796232 -272.108389) (xy 164.796724 -272.135346) (xy 164.796232 -272.162303)
			(xy 164.788382 -272.215643) (xy 164.77285 -272.267272) (xy 164.749965 -272.316089) (xy 164.720217 -272.361053)
			(xy 164.684239 -272.401207) (xy 164.642797 -272.435695) (xy 164.596776 -272.463781) (xy 164.547156 -272.484868)
			(xy 164.494995 -272.498504) (xy 164.441404 -272.504401) (xy 164.387525 -272.502432) (xy 164.334507 -272.492639)
			(xy 164.28348 -272.475231) (xy 164.235532 -272.450579) (xy 164.191684 -272.419209) (xy 164.152871 -272.381788)
			(xy 164.119919 -272.339115) (xy 164.093533 -272.292098) (xy 164.074273 -272.241741) (xy 164.06255 -272.189117)
			(xy 164.058615 -272.135346) (xy 127.20574 -272.135346) (xy 127.20574 -272.16862) (xy 127.206187 -272.178463)
			(xy 127.213605 -272.196697) (xy 127.227371 -272.210769) (xy 127.23622 -272.215102) (xy 127.335534 -272.258536)
			(xy 127.365252 -272.253456) (xy 127.376682 -272.243042) (xy 127.393709 -272.22771) (xy 127.4315 -272.201804)
			(xy 127.47274 -272.18184) (xy 127.516501 -272.168266) (xy 127.561799 -272.161387) (xy 127.584708 -272.161)
			(xy 127.609962 -272.161522) (xy 127.659782 -272.169837) (xy 127.707553 -272.186238) (xy 127.751974 -272.210278)
			(xy 127.791831 -272.241302) (xy 127.826039 -272.278462) (xy 127.853665 -272.320747) (xy 127.873953 -272.367001)
			(xy 127.886352 -272.415964) (xy 127.890523 -272.4663) (xy 127.890522 -272.466308) (xy 128.208527 -272.466308)
			(xy 128.212622 -272.41558) (xy 128.224801 -272.366166) (xy 128.244749 -272.319346) (xy 128.27195 -272.276332)
			(xy 128.305698 -272.238238) (xy 128.34512 -272.206051) (xy 128.389194 -272.180605) (xy 128.43678 -272.162558)
			(xy 128.486644 -272.152378) (xy 128.537496 -272.150329) (xy 128.588017 -272.156463) (xy 128.636901 -272.170623)
			(xy 128.68288 -272.19244) (xy 128.724764 -272.22135) (xy 128.761468 -272.256605) (xy 128.792041 -272.297291)
			(xy 128.815692 -272.342354) (xy 128.831808 -272.390628) (xy 128.839972 -272.440862) (xy 128.840484 -272.466308)
			(xy 129.148581 -272.466308) (xy 129.152676 -272.41558) (xy 129.164855 -272.366166) (xy 129.184803 -272.319346)
			(xy 129.212004 -272.276332) (xy 129.245752 -272.238238) (xy 129.285174 -272.206051) (xy 129.329248 -272.180605)
			(xy 129.376834 -272.162558) (xy 129.426698 -272.152378) (xy 129.47755 -272.150329) (xy 129.528071 -272.156463)
			(xy 129.576955 -272.170623) (xy 129.622934 -272.19244) (xy 129.664818 -272.22135) (xy 129.701522 -272.256605)
			(xy 129.732095 -272.297291) (xy 129.755746 -272.342354) (xy 129.771862 -272.390628) (xy 129.780026 -272.440862)
			(xy 129.780538 -272.466308) (xy 130.099066 -272.466308) (xy 130.103026 -272.417254) (xy 130.114803 -272.36947)
			(xy 130.134094 -272.324194) (xy 130.160397 -272.282598) (xy 130.193032 -272.245761) (xy 130.231153 -272.214636)
			(xy 130.273774 -272.190029) (xy 130.31979 -272.172577) (xy 130.368009 -272.162733) (xy 130.417184 -272.160752)
			(xy 130.466039 -272.166684) (xy 130.51331 -272.180376) (xy 130.557772 -272.201474) (xy 130.598275 -272.22943)
			(xy 130.633768 -272.263522) (xy 130.663333 -272.302866) (xy 130.686204 -272.346443) (xy 130.701788 -272.393124)
			(xy 130.709683 -272.441701) (xy 130.710178 -272.466308) (xy 131.028435 -272.466308) (xy 131.03253 -272.41558)
			(xy 131.044709 -272.366166) (xy 131.064657 -272.319346) (xy 131.091858 -272.276332) (xy 131.125606 -272.238238)
			(xy 131.165028 -272.206051) (xy 131.209102 -272.180605) (xy 131.256688 -272.162558) (xy 131.306552 -272.152378)
			(xy 131.357404 -272.150329) (xy 131.407925 -272.156463) (xy 131.456809 -272.170623) (xy 131.502788 -272.19244)
			(xy 131.544672 -272.22135) (xy 131.581376 -272.256605) (xy 131.611949 -272.297291) (xy 131.6356 -272.342354)
			(xy 131.651716 -272.390628) (xy 131.65988 -272.440862) (xy 131.660392 -272.466308) (xy 131.97892 -272.466308)
			(xy 131.98288 -272.417254) (xy 131.994657 -272.36947) (xy 132.013948 -272.324194) (xy 132.040251 -272.282598)
			(xy 132.072886 -272.245761) (xy 132.111007 -272.214636) (xy 132.153628 -272.190029) (xy 132.199644 -272.172577)
			(xy 132.247863 -272.162733) (xy 132.297038 -272.160752) (xy 132.345893 -272.166684) (xy 132.393164 -272.180376)
			(xy 132.437626 -272.201474) (xy 132.478129 -272.22943) (xy 132.513622 -272.263522) (xy 132.543187 -272.302866)
			(xy 132.566058 -272.346443) (xy 132.581642 -272.393124) (xy 132.589537 -272.441701) (xy 132.590032 -272.466308)
			(xy 132.908543 -272.466308) (xy 132.912638 -272.41558) (xy 132.924817 -272.366166) (xy 132.944765 -272.319346)
			(xy 132.971966 -272.276332) (xy 133.005714 -272.238238) (xy 133.045136 -272.206051) (xy 133.08921 -272.180605)
			(xy 133.136796 -272.162558) (xy 133.18666 -272.152378) (xy 133.237512 -272.150329) (xy 133.288033 -272.156463)
			(xy 133.336917 -272.170623) (xy 133.382896 -272.19244) (xy 133.42478 -272.22135) (xy 133.461484 -272.256605)
			(xy 133.492057 -272.297291) (xy 133.515708 -272.342354) (xy 133.531824 -272.390628) (xy 133.539988 -272.440862)
			(xy 133.5405 -272.466308) (xy 133.859028 -272.466308) (xy 133.862988 -272.417254) (xy 133.874765 -272.36947)
			(xy 133.894056 -272.324194) (xy 133.920359 -272.282598) (xy 133.952994 -272.245761) (xy 133.991115 -272.214636)
			(xy 134.033736 -272.190029) (xy 134.079752 -272.172577) (xy 134.127971 -272.162733) (xy 134.177146 -272.160752)
			(xy 134.226001 -272.166684) (xy 134.273272 -272.180376) (xy 134.317734 -272.201474) (xy 134.358237 -272.22943)
			(xy 134.39373 -272.263522) (xy 134.423295 -272.302866) (xy 134.446166 -272.346443) (xy 134.46175 -272.393124)
			(xy 134.469645 -272.441701) (xy 134.47014 -272.466308) (xy 134.788397 -272.466308) (xy 134.792492 -272.41558)
			(xy 134.804671 -272.366166) (xy 134.824619 -272.319346) (xy 134.85182 -272.276332) (xy 134.885568 -272.238238)
			(xy 134.92499 -272.206051) (xy 134.969064 -272.180605) (xy 135.01665 -272.162558) (xy 135.066514 -272.152378)
			(xy 135.117366 -272.150329) (xy 135.167887 -272.156463) (xy 135.216771 -272.170623) (xy 135.26275 -272.19244)
			(xy 135.304634 -272.22135) (xy 135.341338 -272.256605) (xy 135.371911 -272.297291) (xy 135.395562 -272.342354)
			(xy 135.411678 -272.390628) (xy 135.419842 -272.440862) (xy 135.420354 -272.466308) (xy 135.728451 -272.466308)
			(xy 135.732546 -272.41558) (xy 135.744725 -272.366166) (xy 135.764673 -272.319346) (xy 135.791874 -272.276332)
			(xy 135.825622 -272.238238) (xy 135.865044 -272.206051) (xy 135.909118 -272.180605) (xy 135.956704 -272.162558)
			(xy 136.006568 -272.152378) (xy 136.05742 -272.150329) (xy 136.107941 -272.156463) (xy 136.156825 -272.170623)
			(xy 136.202804 -272.19244) (xy 136.244688 -272.22135) (xy 136.281392 -272.256605) (xy 136.311965 -272.297291)
			(xy 136.335616 -272.342354) (xy 136.351732 -272.390628) (xy 136.359896 -272.440862) (xy 136.360408 -272.466308)
			(xy 136.678936 -272.466308) (xy 136.682896 -272.417254) (xy 136.694673 -272.36947) (xy 136.713964 -272.324194)
			(xy 136.740267 -272.282598) (xy 136.772902 -272.245761) (xy 136.811023 -272.214636) (xy 136.853644 -272.190029)
			(xy 136.89966 -272.172577) (xy 136.947879 -272.162733) (xy 136.997054 -272.160752) (xy 137.045909 -272.166684)
			(xy 137.09318 -272.180376) (xy 137.137642 -272.201474) (xy 137.178145 -272.22943) (xy 137.213638 -272.263522)
			(xy 137.243203 -272.302866) (xy 137.266074 -272.346443) (xy 137.281658 -272.393124) (xy 137.289553 -272.441701)
			(xy 137.290048 -272.466308) (xy 137.608559 -272.466308) (xy 137.612654 -272.41558) (xy 137.624833 -272.366166)
			(xy 137.644781 -272.319346) (xy 137.671982 -272.276332) (xy 137.70573 -272.238238) (xy 137.745152 -272.206051)
			(xy 137.789226 -272.180605) (xy 137.836812 -272.162558) (xy 137.886676 -272.152378) (xy 137.937528 -272.150329)
			(xy 137.988049 -272.156463) (xy 138.036933 -272.170623) (xy 138.082912 -272.19244) (xy 138.124796 -272.22135)
			(xy 138.1615 -272.256605) (xy 138.192073 -272.297291) (xy 138.215724 -272.342354) (xy 138.23184 -272.390628)
			(xy 138.240004 -272.440862) (xy 138.240516 -272.466308) (xy 138.559044 -272.466308) (xy 138.563004 -272.417254)
			(xy 138.574781 -272.36947) (xy 138.594072 -272.324194) (xy 138.620375 -272.282598) (xy 138.65301 -272.245761)
			(xy 138.691131 -272.214636) (xy 138.733752 -272.190029) (xy 138.779768 -272.172577) (xy 138.827987 -272.162733)
			(xy 138.877162 -272.160752) (xy 138.926017 -272.166684) (xy 138.973288 -272.180376) (xy 139.01775 -272.201474)
			(xy 139.058253 -272.22943) (xy 139.093746 -272.263522) (xy 139.123311 -272.302866) (xy 139.146182 -272.346443)
			(xy 139.161766 -272.393124) (xy 139.169661 -272.441701) (xy 139.170156 -272.466308) (xy 139.488413 -272.466308)
			(xy 139.492508 -272.41558) (xy 139.504687 -272.366166) (xy 139.524635 -272.319346) (xy 139.551836 -272.276332)
			(xy 139.585584 -272.238238) (xy 139.625006 -272.206051) (xy 139.66908 -272.180605) (xy 139.716666 -272.162558)
			(xy 139.76653 -272.152378) (xy 139.817382 -272.150329) (xy 139.867903 -272.156463) (xy 139.916787 -272.170623)
			(xy 139.962766 -272.19244) (xy 140.00465 -272.22135) (xy 140.041354 -272.256605) (xy 140.071927 -272.297291)
			(xy 140.095578 -272.342354) (xy 140.111694 -272.390628) (xy 140.119858 -272.440862) (xy 140.12037 -272.466308)
			(xy 140.438898 -272.466308) (xy 140.442858 -272.417254) (xy 140.454635 -272.36947) (xy 140.473926 -272.324194)
			(xy 140.500229 -272.282598) (xy 140.532864 -272.245761) (xy 140.570985 -272.214636) (xy 140.613606 -272.190029)
			(xy 140.659622 -272.172577) (xy 140.707841 -272.162733) (xy 140.757016 -272.160752) (xy 140.805871 -272.166684)
			(xy 140.853142 -272.180376) (xy 140.897604 -272.201474) (xy 140.938107 -272.22943) (xy 140.9736 -272.263522)
			(xy 141.003165 -272.302866) (xy 141.026036 -272.346443) (xy 141.04162 -272.393124) (xy 141.049515 -272.441701)
			(xy 141.05001 -272.466308) (xy 141.368521 -272.466308) (xy 141.372616 -272.41558) (xy 141.384795 -272.366166)
			(xy 141.404743 -272.319346) (xy 141.431944 -272.276332) (xy 141.465692 -272.238238) (xy 141.505114 -272.206051)
			(xy 141.549188 -272.180605) (xy 141.596774 -272.162558) (xy 141.646638 -272.152378) (xy 141.69749 -272.150329)
			(xy 141.748011 -272.156463) (xy 141.796895 -272.170623) (xy 141.842874 -272.19244) (xy 141.884758 -272.22135)
			(xy 141.921462 -272.256605) (xy 141.952035 -272.297291) (xy 141.975686 -272.342354) (xy 141.991802 -272.390628)
			(xy 141.999966 -272.440862) (xy 142.000478 -272.466308) (xy 142.308575 -272.466308) (xy 142.31267 -272.41558)
			(xy 142.324849 -272.366166) (xy 142.344797 -272.319346) (xy 142.371998 -272.276332) (xy 142.405746 -272.238238)
			(xy 142.445168 -272.206051) (xy 142.489242 -272.180605) (xy 142.536828 -272.162558) (xy 142.586692 -272.152378)
			(xy 142.637544 -272.150329) (xy 142.688065 -272.156463) (xy 142.736949 -272.170623) (xy 142.782928 -272.19244)
			(xy 142.824812 -272.22135) (xy 142.861516 -272.256605) (xy 142.892089 -272.297291) (xy 142.91574 -272.342354)
			(xy 142.931856 -272.390628) (xy 142.94002 -272.440862) (xy 142.940532 -272.466308) (xy 143.258806 -272.466308)
			(xy 143.262766 -272.417254) (xy 143.274543 -272.36947) (xy 143.293834 -272.324194) (xy 143.320137 -272.282598)
			(xy 143.352772 -272.245761) (xy 143.390893 -272.214636) (xy 143.433514 -272.190029) (xy 143.47953 -272.172577)
			(xy 143.527749 -272.162733) (xy 143.576924 -272.160752) (xy 143.625779 -272.166684) (xy 143.67305 -272.180376)
			(xy 143.717512 -272.201474) (xy 143.758015 -272.22943) (xy 143.793508 -272.263522) (xy 143.823073 -272.302866)
			(xy 143.845944 -272.346443) (xy 143.861528 -272.393124) (xy 143.869423 -272.441701) (xy 143.869918 -272.466308)
			(xy 145.138914 -272.466308) (xy 145.142874 -272.417254) (xy 145.154651 -272.36947) (xy 145.173942 -272.324194)
			(xy 145.200245 -272.282598) (xy 145.23288 -272.245761) (xy 145.271001 -272.214636) (xy 145.313622 -272.190029)
			(xy 145.359638 -272.172577) (xy 145.407857 -272.162733) (xy 145.457032 -272.160752) (xy 145.505887 -272.166684)
			(xy 145.553158 -272.180376) (xy 145.59762 -272.201474) (xy 145.638123 -272.22943) (xy 145.673616 -272.263522)
			(xy 145.703181 -272.302866) (xy 145.726052 -272.346443) (xy 145.741636 -272.393124) (xy 145.749531 -272.441701)
			(xy 145.750026 -272.466308) (xy 145.749531 -272.490915) (xy 145.741636 -272.539492) (xy 145.726052 -272.586173)
			(xy 145.703181 -272.62975) (xy 145.673616 -272.669094) (xy 145.638123 -272.703186) (xy 145.59762 -272.731142)
			(xy 145.553158 -272.75224) (xy 145.505887 -272.765932) (xy 145.457032 -272.771864) (xy 145.407857 -272.769883)
			(xy 145.359638 -272.760039) (xy 145.313622 -272.742587) (xy 145.271001 -272.71798) (xy 145.23288 -272.686855)
			(xy 145.200245 -272.650018) (xy 145.173942 -272.608422) (xy 145.154651 -272.563146) (xy 145.142874 -272.515362)
			(xy 145.138914 -272.466308) (xy 143.869918 -272.466308) (xy 143.869423 -272.490915) (xy 143.861528 -272.539492)
			(xy 143.845944 -272.586173) (xy 143.823073 -272.62975) (xy 143.793508 -272.669094) (xy 143.758015 -272.703186)
			(xy 143.717512 -272.731142) (xy 143.67305 -272.75224) (xy 143.625779 -272.765932) (xy 143.576924 -272.771864)
			(xy 143.527749 -272.769883) (xy 143.47953 -272.760039) (xy 143.433514 -272.742587) (xy 143.390893 -272.71798)
			(xy 143.352772 -272.686855) (xy 143.320137 -272.650018) (xy 143.293834 -272.608422) (xy 143.274543 -272.563146)
			(xy 143.262766 -272.515362) (xy 143.258806 -272.466308) (xy 142.940532 -272.466308) (xy 142.94002 -272.491754)
			(xy 142.931856 -272.541988) (xy 142.91574 -272.590262) (xy 142.892089 -272.635325) (xy 142.861516 -272.676011)
			(xy 142.824812 -272.711266) (xy 142.782928 -272.740176) (xy 142.736949 -272.761993) (xy 142.688065 -272.776153)
			(xy 142.637544 -272.782287) (xy 142.586692 -272.780238) (xy 142.536828 -272.770058) (xy 142.489242 -272.752011)
			(xy 142.445168 -272.726565) (xy 142.405746 -272.694378) (xy 142.371998 -272.656284) (xy 142.344797 -272.61327)
			(xy 142.324849 -272.56645) (xy 142.31267 -272.517036) (xy 142.308575 -272.466308) (xy 142.000478 -272.466308)
			(xy 141.999966 -272.491754) (xy 141.991802 -272.541988) (xy 141.975686 -272.590262) (xy 141.952035 -272.635325)
			(xy 141.921462 -272.676011) (xy 141.884758 -272.711266) (xy 141.842874 -272.740176) (xy 141.796895 -272.761993)
			(xy 141.748011 -272.776153) (xy 141.69749 -272.782287) (xy 141.646638 -272.780238) (xy 141.596774 -272.770058)
			(xy 141.549188 -272.752011) (xy 141.505114 -272.726565) (xy 141.465692 -272.694378) (xy 141.431944 -272.656284)
			(xy 141.404743 -272.61327) (xy 141.384795 -272.56645) (xy 141.372616 -272.517036) (xy 141.368521 -272.466308)
			(xy 141.05001 -272.466308) (xy 141.049515 -272.490915) (xy 141.04162 -272.539492) (xy 141.026036 -272.586173)
			(xy 141.003165 -272.62975) (xy 140.9736 -272.669094) (xy 140.938107 -272.703186) (xy 140.897604 -272.731142)
			(xy 140.853142 -272.75224) (xy 140.805871 -272.765932) (xy 140.757016 -272.771864) (xy 140.707841 -272.769883)
			(xy 140.659622 -272.760039) (xy 140.613606 -272.742587) (xy 140.570985 -272.71798) (xy 140.532864 -272.686855)
			(xy 140.500229 -272.650018) (xy 140.473926 -272.608422) (xy 140.454635 -272.563146) (xy 140.442858 -272.515362)
			(xy 140.438898 -272.466308) (xy 140.12037 -272.466308) (xy 140.119858 -272.491754) (xy 140.111694 -272.541988)
			(xy 140.095578 -272.590262) (xy 140.071927 -272.635325) (xy 140.041354 -272.676011) (xy 140.00465 -272.711266)
			(xy 139.962766 -272.740176) (xy 139.916787 -272.761993) (xy 139.867903 -272.776153) (xy 139.817382 -272.782287)
			(xy 139.76653 -272.780238) (xy 139.716666 -272.770058) (xy 139.66908 -272.752011) (xy 139.625006 -272.726565)
			(xy 139.585584 -272.694378) (xy 139.551836 -272.656284) (xy 139.524635 -272.61327) (xy 139.504687 -272.56645)
			(xy 139.492508 -272.517036) (xy 139.488413 -272.466308) (xy 139.170156 -272.466308) (xy 139.169661 -272.490915)
			(xy 139.161766 -272.539492) (xy 139.146182 -272.586173) (xy 139.123311 -272.62975) (xy 139.093746 -272.669094)
			(xy 139.058253 -272.703186) (xy 139.01775 -272.731142) (xy 138.973288 -272.75224) (xy 138.926017 -272.765932)
			(xy 138.877162 -272.771864) (xy 138.827987 -272.769883) (xy 138.779768 -272.760039) (xy 138.733752 -272.742587)
			(xy 138.691131 -272.71798) (xy 138.65301 -272.686855) (xy 138.620375 -272.650018) (xy 138.594072 -272.608422)
			(xy 138.574781 -272.563146) (xy 138.563004 -272.515362) (xy 138.559044 -272.466308) (xy 138.240516 -272.466308)
			(xy 138.240004 -272.491754) (xy 138.23184 -272.541988) (xy 138.215724 -272.590262) (xy 138.192073 -272.635325)
			(xy 138.1615 -272.676011) (xy 138.124796 -272.711266) (xy 138.082912 -272.740176) (xy 138.036933 -272.761993)
			(xy 137.988049 -272.776153) (xy 137.937528 -272.782287) (xy 137.886676 -272.780238) (xy 137.836812 -272.770058)
			(xy 137.789226 -272.752011) (xy 137.745152 -272.726565) (xy 137.70573 -272.694378) (xy 137.671982 -272.656284)
			(xy 137.644781 -272.61327) (xy 137.624833 -272.56645) (xy 137.612654 -272.517036) (xy 137.608559 -272.466308)
			(xy 137.290048 -272.466308) (xy 137.289553 -272.490915) (xy 137.281658 -272.539492) (xy 137.266074 -272.586173)
			(xy 137.243203 -272.62975) (xy 137.213638 -272.669094) (xy 137.178145 -272.703186) (xy 137.137642 -272.731142)
			(xy 137.09318 -272.75224) (xy 137.045909 -272.765932) (xy 136.997054 -272.771864) (xy 136.947879 -272.769883)
			(xy 136.89966 -272.760039) (xy 136.853644 -272.742587) (xy 136.811023 -272.71798) (xy 136.772902 -272.686855)
			(xy 136.740267 -272.650018) (xy 136.713964 -272.608422) (xy 136.694673 -272.563146) (xy 136.682896 -272.515362)
			(xy 136.678936 -272.466308) (xy 136.360408 -272.466308) (xy 136.359896 -272.491754) (xy 136.351732 -272.541988)
			(xy 136.335616 -272.590262) (xy 136.311965 -272.635325) (xy 136.281392 -272.676011) (xy 136.244688 -272.711266)
			(xy 136.202804 -272.740176) (xy 136.156825 -272.761993) (xy 136.107941 -272.776153) (xy 136.05742 -272.782287)
			(xy 136.006568 -272.780238) (xy 135.956704 -272.770058) (xy 135.909118 -272.752011) (xy 135.865044 -272.726565)
			(xy 135.825622 -272.694378) (xy 135.791874 -272.656284) (xy 135.764673 -272.61327) (xy 135.744725 -272.56645)
			(xy 135.732546 -272.517036) (xy 135.728451 -272.466308) (xy 135.420354 -272.466308) (xy 135.419842 -272.491754)
			(xy 135.411678 -272.541988) (xy 135.395562 -272.590262) (xy 135.371911 -272.635325) (xy 135.341338 -272.676011)
			(xy 135.304634 -272.711266) (xy 135.26275 -272.740176) (xy 135.216771 -272.761993) (xy 135.167887 -272.776153)
			(xy 135.117366 -272.782287) (xy 135.066514 -272.780238) (xy 135.01665 -272.770058) (xy 134.969064 -272.752011)
			(xy 134.92499 -272.726565) (xy 134.885568 -272.694378) (xy 134.85182 -272.656284) (xy 134.824619 -272.61327)
			(xy 134.804671 -272.56645) (xy 134.792492 -272.517036) (xy 134.788397 -272.466308) (xy 134.47014 -272.466308)
			(xy 134.469645 -272.490915) (xy 134.46175 -272.539492) (xy 134.446166 -272.586173) (xy 134.423295 -272.62975)
			(xy 134.39373 -272.669094) (xy 134.358237 -272.703186) (xy 134.317734 -272.731142) (xy 134.273272 -272.75224)
			(xy 134.226001 -272.765932) (xy 134.177146 -272.771864) (xy 134.127971 -272.769883) (xy 134.079752 -272.760039)
			(xy 134.033736 -272.742587) (xy 133.991115 -272.71798) (xy 133.952994 -272.686855) (xy 133.920359 -272.650018)
			(xy 133.894056 -272.608422) (xy 133.874765 -272.563146) (xy 133.862988 -272.515362) (xy 133.859028 -272.466308)
			(xy 133.5405 -272.466308) (xy 133.539988 -272.491754) (xy 133.531824 -272.541988) (xy 133.515708 -272.590262)
			(xy 133.492057 -272.635325) (xy 133.461484 -272.676011) (xy 133.42478 -272.711266) (xy 133.382896 -272.740176)
			(xy 133.336917 -272.761993) (xy 133.288033 -272.776153) (xy 133.237512 -272.782287) (xy 133.18666 -272.780238)
			(xy 133.136796 -272.770058) (xy 133.08921 -272.752011) (xy 133.045136 -272.726565) (xy 133.005714 -272.694378)
			(xy 132.971966 -272.656284) (xy 132.944765 -272.61327) (xy 132.924817 -272.56645) (xy 132.912638 -272.517036)
			(xy 132.908543 -272.466308) (xy 132.590032 -272.466308) (xy 132.589537 -272.490915) (xy 132.581642 -272.539492)
			(xy 132.566058 -272.586173) (xy 132.543187 -272.62975) (xy 132.513622 -272.669094) (xy 132.478129 -272.703186)
			(xy 132.437626 -272.731142) (xy 132.393164 -272.75224) (xy 132.345893 -272.765932) (xy 132.297038 -272.771864)
			(xy 132.247863 -272.769883) (xy 132.199644 -272.760039) (xy 132.153628 -272.742587) (xy 132.111007 -272.71798)
			(xy 132.072886 -272.686855) (xy 132.040251 -272.650018) (xy 132.013948 -272.608422) (xy 131.994657 -272.563146)
			(xy 131.98288 -272.515362) (xy 131.97892 -272.466308) (xy 131.660392 -272.466308) (xy 131.65988 -272.491754)
			(xy 131.651716 -272.541988) (xy 131.6356 -272.590262) (xy 131.611949 -272.635325) (xy 131.581376 -272.676011)
			(xy 131.544672 -272.711266) (xy 131.502788 -272.740176) (xy 131.456809 -272.761993) (xy 131.407925 -272.776153)
			(xy 131.357404 -272.782287) (xy 131.306552 -272.780238) (xy 131.256688 -272.770058) (xy 131.209102 -272.752011)
			(xy 131.165028 -272.726565) (xy 131.125606 -272.694378) (xy 131.091858 -272.656284) (xy 131.064657 -272.61327)
			(xy 131.044709 -272.56645) (xy 131.03253 -272.517036) (xy 131.028435 -272.466308) (xy 130.710178 -272.466308)
			(xy 130.709683 -272.490915) (xy 130.701788 -272.539492) (xy 130.686204 -272.586173) (xy 130.663333 -272.62975)
			(xy 130.633768 -272.669094) (xy 130.598275 -272.703186) (xy 130.557772 -272.731142) (xy 130.51331 -272.75224)
			(xy 130.466039 -272.765932) (xy 130.417184 -272.771864) (xy 130.368009 -272.769883) (xy 130.31979 -272.760039)
			(xy 130.273774 -272.742587) (xy 130.231153 -272.71798) (xy 130.193032 -272.686855) (xy 130.160397 -272.650018)
			(xy 130.134094 -272.608422) (xy 130.114803 -272.563146) (xy 130.103026 -272.515362) (xy 130.099066 -272.466308)
			(xy 129.780538 -272.466308) (xy 129.780026 -272.491754) (xy 129.771862 -272.541988) (xy 129.755746 -272.590262)
			(xy 129.732095 -272.635325) (xy 129.701522 -272.676011) (xy 129.664818 -272.711266) (xy 129.622934 -272.740176)
			(xy 129.576955 -272.761993) (xy 129.528071 -272.776153) (xy 129.47755 -272.782287) (xy 129.426698 -272.780238)
			(xy 129.376834 -272.770058) (xy 129.329248 -272.752011) (xy 129.285174 -272.726565) (xy 129.245752 -272.694378)
			(xy 129.212004 -272.656284) (xy 129.184803 -272.61327) (xy 129.164855 -272.56645) (xy 129.152676 -272.517036)
			(xy 129.148581 -272.466308) (xy 128.840484 -272.466308) (xy 128.839972 -272.491754) (xy 128.831808 -272.541988)
			(xy 128.815692 -272.590262) (xy 128.792041 -272.635325) (xy 128.761468 -272.676011) (xy 128.724764 -272.711266)
			(xy 128.68288 -272.740176) (xy 128.636901 -272.761993) (xy 128.588017 -272.776153) (xy 128.537496 -272.782287)
			(xy 128.486644 -272.780238) (xy 128.43678 -272.770058) (xy 128.389194 -272.752011) (xy 128.34512 -272.726565)
			(xy 128.305698 -272.694378) (xy 128.27195 -272.656284) (xy 128.244749 -272.61327) (xy 128.224801 -272.56645)
			(xy 128.212622 -272.517036) (xy 128.208527 -272.466308) (xy 127.890522 -272.466308) (xy 127.886352 -272.516636)
			(xy 127.873953 -272.565599) (xy 127.853665 -272.611853) (xy 127.826039 -272.654138) (xy 127.791831 -272.691298)
			(xy 127.751974 -272.722322) (xy 127.707553 -272.746362) (xy 127.659782 -272.762763) (xy 127.609962 -272.771078)
			(xy 127.584708 -272.771616) (xy 127.561802 -272.771185) (xy 127.51651 -272.764301) (xy 127.472753 -272.750732)
			(xy 127.431512 -272.730782) (xy 127.393713 -272.704897) (xy 127.376682 -272.689574) (xy 127.365252 -272.67916)
			(xy 127.335534 -272.67408) (xy 127.23622 -272.717514) (xy 127.227393 -272.721876) (xy 127.213659 -272.735958)
			(xy 127.206208 -272.754162) (xy 127.20574 -272.763996) (xy 127.20574 -272.96491) (xy 127.22225 -272.990056)
			(xy 127.23622 -272.996152) (xy 127.259285 -273.006695) (xy 127.301843 -273.034271) (xy 127.339259 -273.068499)
			(xy 127.370507 -273.108439) (xy 127.394726 -273.152993) (xy 127.411251 -273.200936) (xy 127.419629 -273.25095)
			(xy 127.419628 -273.276314) (xy 127.738627 -273.276314) (xy 127.742722 -273.225586) (xy 127.754901 -273.176172)
			(xy 127.774849 -273.129352) (xy 127.80205 -273.086338) (xy 127.835798 -273.048244) (xy 127.87522 -273.016057)
			(xy 127.919294 -272.990611) (xy 127.96688 -272.972564) (xy 128.016744 -272.962384) (xy 128.067596 -272.960335)
			(xy 128.118117 -272.966469) (xy 128.167001 -272.980629) (xy 128.21298 -273.002446) (xy 128.254864 -273.031356)
			(xy 128.291568 -273.066611) (xy 128.322141 -273.107297) (xy 128.345792 -273.15236) (xy 128.361908 -273.200634)
			(xy 128.370072 -273.250868) (xy 128.370584 -273.276314) (xy 128.688858 -273.276314) (xy 128.692818 -273.22726)
			(xy 128.704595 -273.179476) (xy 128.723886 -273.1342) (xy 128.750189 -273.092604) (xy 128.782824 -273.055767)
			(xy 128.820945 -273.024642) (xy 128.863566 -273.000035) (xy 128.909582 -272.982583) (xy 128.957801 -272.972739)
			(xy 129.006976 -272.970758) (xy 129.055831 -272.97669) (xy 129.103102 -272.990382) (xy 129.147564 -273.01148)
			(xy 129.188067 -273.039436) (xy 129.22356 -273.073528) (xy 129.253125 -273.112872) (xy 129.275996 -273.156449)
			(xy 129.29158 -273.20313) (xy 129.299475 -273.251707) (xy 129.29997 -273.276314) (xy 129.618481 -273.276314)
			(xy 129.622576 -273.225586) (xy 129.634755 -273.176172) (xy 129.654703 -273.129352) (xy 129.681904 -273.086338)
			(xy 129.715652 -273.048244) (xy 129.755074 -273.016057) (xy 129.799148 -272.990611) (xy 129.846734 -272.972564)
			(xy 129.896598 -272.962384) (xy 129.94745 -272.960335) (xy 129.997971 -272.966469) (xy 130.046855 -272.980629)
			(xy 130.092834 -273.002446) (xy 130.134718 -273.031356) (xy 130.171422 -273.066611) (xy 130.201995 -273.107297)
			(xy 130.225646 -273.15236) (xy 130.241762 -273.200634) (xy 130.249926 -273.250868) (xy 130.250438 -273.276314)
			(xy 131.498589 -273.276314) (xy 131.502684 -273.225586) (xy 131.514863 -273.176172) (xy 131.534811 -273.129352)
			(xy 131.562012 -273.086338) (xy 131.59576 -273.048244) (xy 131.635182 -273.016057) (xy 131.679256 -272.990611)
			(xy 131.726842 -272.972564) (xy 131.776706 -272.962384) (xy 131.827558 -272.960335) (xy 131.878079 -272.966469)
			(xy 131.926963 -272.980629) (xy 131.972942 -273.002446) (xy 132.014826 -273.031356) (xy 132.05153 -273.066611)
			(xy 132.082103 -273.107297) (xy 132.105754 -273.15236) (xy 132.12187 -273.200634) (xy 132.130034 -273.250868)
			(xy 132.130546 -273.276314) (xy 132.438643 -273.276314) (xy 132.442738 -273.225586) (xy 132.454917 -273.176172)
			(xy 132.474865 -273.129352) (xy 132.502066 -273.086338) (xy 132.535814 -273.048244) (xy 132.575236 -273.016057)
			(xy 132.61931 -272.990611) (xy 132.666896 -272.972564) (xy 132.71676 -272.962384) (xy 132.767612 -272.960335)
			(xy 132.818133 -272.966469) (xy 132.867017 -272.980629) (xy 132.912996 -273.002446) (xy 132.95488 -273.031356)
			(xy 132.991584 -273.066611) (xy 133.022157 -273.107297) (xy 133.045808 -273.15236) (xy 133.061924 -273.200634)
			(xy 133.070088 -273.250868) (xy 133.0706 -273.276314) (xy 133.388874 -273.276314) (xy 133.392834 -273.22726)
			(xy 133.404611 -273.179476) (xy 133.423902 -273.1342) (xy 133.450205 -273.092604) (xy 133.48284 -273.055767)
			(xy 133.520961 -273.024642) (xy 133.563582 -273.000035) (xy 133.609598 -272.982583) (xy 133.657817 -272.972739)
			(xy 133.706992 -272.970758) (xy 133.755847 -272.97669) (xy 133.803118 -272.990382) (xy 133.84758 -273.01148)
			(xy 133.888083 -273.039436) (xy 133.923576 -273.073528) (xy 133.953141 -273.112872) (xy 133.976012 -273.156449)
			(xy 133.991596 -273.20313) (xy 133.999491 -273.251707) (xy 133.999986 -273.276314) (xy 134.318497 -273.276314)
			(xy 134.322592 -273.225586) (xy 134.334771 -273.176172) (xy 134.354719 -273.129352) (xy 134.38192 -273.086338)
			(xy 134.415668 -273.048244) (xy 134.45509 -273.016057) (xy 134.499164 -272.990611) (xy 134.54675 -272.972564)
			(xy 134.596614 -272.962384) (xy 134.647466 -272.960335) (xy 134.697987 -272.966469) (xy 134.746871 -272.980629)
			(xy 134.79285 -273.002446) (xy 134.834734 -273.031356) (xy 134.871438 -273.066611) (xy 134.902011 -273.107297)
			(xy 134.925662 -273.15236) (xy 134.941778 -273.200634) (xy 134.949942 -273.250868) (xy 134.950454 -273.276314)
			(xy 135.268982 -273.276314) (xy 135.272942 -273.22726) (xy 135.284719 -273.179476) (xy 135.30401 -273.1342)
			(xy 135.330313 -273.092604) (xy 135.362948 -273.055767) (xy 135.401069 -273.024642) (xy 135.44369 -273.000035)
			(xy 135.489706 -272.982583) (xy 135.537925 -272.972739) (xy 135.5871 -272.970758) (xy 135.635955 -272.97669)
			(xy 135.683226 -272.990382) (xy 135.727688 -273.01148) (xy 135.768191 -273.039436) (xy 135.803684 -273.073528)
			(xy 135.833249 -273.112872) (xy 135.85612 -273.156449) (xy 135.871704 -273.20313) (xy 135.879599 -273.251707)
			(xy 135.880094 -273.276314) (xy 136.198605 -273.276314) (xy 136.2027 -273.225586) (xy 136.214879 -273.176172)
			(xy 136.234827 -273.129352) (xy 136.262028 -273.086338) (xy 136.295776 -273.048244) (xy 136.335198 -273.016057)
			(xy 136.379272 -272.990611) (xy 136.426858 -272.972564) (xy 136.476722 -272.962384) (xy 136.527574 -272.960335)
			(xy 136.578095 -272.966469) (xy 136.626979 -272.980629) (xy 136.672958 -273.002446) (xy 136.714842 -273.031356)
			(xy 136.751546 -273.066611) (xy 136.782119 -273.107297) (xy 136.80577 -273.15236) (xy 136.821886 -273.200634)
			(xy 136.83005 -273.250868) (xy 136.830562 -273.276314) (xy 138.078459 -273.276314) (xy 138.082554 -273.225586)
			(xy 138.094733 -273.176172) (xy 138.114681 -273.129352) (xy 138.141882 -273.086338) (xy 138.17563 -273.048244)
			(xy 138.215052 -273.016057) (xy 138.259126 -272.990611) (xy 138.306712 -272.972564) (xy 138.356576 -272.962384)
			(xy 138.407428 -272.960335) (xy 138.457949 -272.966469) (xy 138.506833 -272.980629) (xy 138.552812 -273.002446)
			(xy 138.594696 -273.031356) (xy 138.6314 -273.066611) (xy 138.661973 -273.107297) (xy 138.685624 -273.15236)
			(xy 138.70174 -273.200634) (xy 138.709904 -273.250868) (xy 138.710416 -273.276314) (xy 139.018513 -273.276314)
			(xy 139.022608 -273.225586) (xy 139.034787 -273.176172) (xy 139.054735 -273.129352) (xy 139.081936 -273.086338)
			(xy 139.115684 -273.048244) (xy 139.155106 -273.016057) (xy 139.19918 -272.990611) (xy 139.246766 -272.972564)
			(xy 139.29663 -272.962384) (xy 139.347482 -272.960335) (xy 139.398003 -272.966469) (xy 139.446887 -272.980629)
			(xy 139.492866 -273.002446) (xy 139.53475 -273.031356) (xy 139.571454 -273.066611) (xy 139.602027 -273.107297)
			(xy 139.625678 -273.15236) (xy 139.641794 -273.200634) (xy 139.649958 -273.250868) (xy 139.65047 -273.276314)
			(xy 139.968998 -273.276314) (xy 139.972958 -273.22726) (xy 139.984735 -273.179476) (xy 140.004026 -273.1342)
			(xy 140.030329 -273.092604) (xy 140.062964 -273.055767) (xy 140.101085 -273.024642) (xy 140.143706 -273.000035)
			(xy 140.189722 -272.982583) (xy 140.237941 -272.972739) (xy 140.287116 -272.970758) (xy 140.335971 -272.97669)
			(xy 140.383242 -272.990382) (xy 140.427704 -273.01148) (xy 140.468207 -273.039436) (xy 140.5037 -273.073528)
			(xy 140.533265 -273.112872) (xy 140.556136 -273.156449) (xy 140.57172 -273.20313) (xy 140.579615 -273.251707)
			(xy 140.58011 -273.276314) (xy 140.898621 -273.276314) (xy 140.902716 -273.225586) (xy 140.914895 -273.176172)
			(xy 140.934843 -273.129352) (xy 140.962044 -273.086338) (xy 140.995792 -273.048244) (xy 141.035214 -273.016057)
			(xy 141.079288 -272.990611) (xy 141.126874 -272.972564) (xy 141.176738 -272.962384) (xy 141.22759 -272.960335)
			(xy 141.278111 -272.966469) (xy 141.326995 -272.980629) (xy 141.372974 -273.002446) (xy 141.414858 -273.031356)
			(xy 141.451562 -273.066611) (xy 141.482135 -273.107297) (xy 141.505786 -273.15236) (xy 141.521902 -273.200634)
			(xy 141.530066 -273.250868) (xy 141.530578 -273.276314) (xy 141.848852 -273.276314) (xy 141.852812 -273.22726)
			(xy 141.864589 -273.179476) (xy 141.88388 -273.1342) (xy 141.910183 -273.092604) (xy 141.942818 -273.055767)
			(xy 141.980939 -273.024642) (xy 142.02356 -273.000035) (xy 142.069576 -272.982583) (xy 142.117795 -272.972739)
			(xy 142.16697 -272.970758) (xy 142.215825 -272.97669) (xy 142.263096 -272.990382) (xy 142.307558 -273.01148)
			(xy 142.348061 -273.039436) (xy 142.383554 -273.073528) (xy 142.413119 -273.112872) (xy 142.43599 -273.156449)
			(xy 142.451574 -273.20313) (xy 142.459469 -273.251707) (xy 142.459964 -273.276314) (xy 142.778475 -273.276314)
			(xy 142.78257 -273.225586) (xy 142.794749 -273.176172) (xy 142.814697 -273.129352) (xy 142.841898 -273.086338)
			(xy 142.875646 -273.048244) (xy 142.915068 -273.016057) (xy 142.959142 -272.990611) (xy 143.006728 -272.972564)
			(xy 143.056592 -272.962384) (xy 143.107444 -272.960335) (xy 143.157965 -272.966469) (xy 143.206849 -272.980629)
			(xy 143.252828 -273.002446) (xy 143.264317 -273.010376) (xy 146.737082 -273.010376) (xy 146.741042 -272.961322)
			(xy 146.752819 -272.913538) (xy 146.77211 -272.868262) (xy 146.798413 -272.826666) (xy 146.831048 -272.789829)
			(xy 146.869169 -272.758704) (xy 146.91179 -272.734097) (xy 146.957806 -272.716645) (xy 147.006025 -272.706801)
			(xy 147.0552 -272.70482) (xy 147.104055 -272.710752) (xy 147.151326 -272.724444) (xy 147.195788 -272.745542)
			(xy 147.236291 -272.773498) (xy 147.271784 -272.80759) (xy 147.301349 -272.846934) (xy 147.32422 -272.890511)
			(xy 147.339804 -272.937192) (xy 147.347611 -272.98523) (xy 168.158683 -272.98523) (xy 168.162618 -272.931459)
			(xy 168.174341 -272.878835) (xy 168.193601 -272.828478) (xy 168.219987 -272.781461) (xy 168.252939 -272.738788)
			(xy 168.291752 -272.701367) (xy 168.3356 -272.669997) (xy 168.383548 -272.645345) (xy 168.434575 -272.627937)
			(xy 168.487593 -272.618144) (xy 168.541472 -272.616175) (xy 168.595063 -272.622072) (xy 168.647224 -272.635708)
			(xy 168.696844 -272.656795) (xy 168.742865 -272.684881) (xy 168.784307 -272.719369) (xy 168.820285 -272.759523)
			(xy 168.850033 -272.804487) (xy 168.872918 -272.853304) (xy 168.88845 -272.904933) (xy 168.8963 -272.958273)
			(xy 168.896792 -272.98523) (xy 168.8963 -273.012187) (xy 168.88845 -273.065527) (xy 168.872918 -273.117156)
			(xy 168.850033 -273.165973) (xy 168.820285 -273.210937) (xy 168.784307 -273.251091) (xy 168.742865 -273.285579)
			(xy 168.696844 -273.313665) (xy 168.647224 -273.334752) (xy 168.595063 -273.348388) (xy 168.541472 -273.354285)
			(xy 168.487593 -273.352316) (xy 168.434575 -273.342523) (xy 168.383548 -273.325115) (xy 168.3356 -273.300463)
			(xy 168.291752 -273.269093) (xy 168.252939 -273.231672) (xy 168.219987 -273.188999) (xy 168.193601 -273.141982)
			(xy 168.174341 -273.091625) (xy 168.162618 -273.039001) (xy 168.158683 -272.98523) (xy 147.347611 -272.98523)
			(xy 147.347699 -272.985769) (xy 147.348194 -273.010376) (xy 147.347699 -273.034983) (xy 147.339804 -273.08356)
			(xy 147.32422 -273.130241) (xy 147.301349 -273.173818) (xy 147.271784 -273.213162) (xy 147.236291 -273.247254)
			(xy 147.195788 -273.27521) (xy 147.151326 -273.296308) (xy 147.104055 -273.31) (xy 147.0552 -273.315932)
			(xy 147.006025 -273.313951) (xy 146.957806 -273.304107) (xy 146.91179 -273.286655) (xy 146.869169 -273.262048)
			(xy 146.831048 -273.230923) (xy 146.798413 -273.194086) (xy 146.77211 -273.15249) (xy 146.752819 -273.107214)
			(xy 146.741042 -273.05943) (xy 146.737082 -273.010376) (xy 143.264317 -273.010376) (xy 143.294712 -273.031356)
			(xy 143.331416 -273.066611) (xy 143.361989 -273.107297) (xy 143.38564 -273.15236) (xy 143.401756 -273.200634)
			(xy 143.40992 -273.250868) (xy 143.410432 -273.276314) (xy 143.40992 -273.30176) (xy 143.401756 -273.351994)
			(xy 143.38564 -273.400268) (xy 143.361989 -273.445331) (xy 143.331416 -273.486017) (xy 143.294712 -273.521272)
			(xy 143.252828 -273.550182) (xy 143.206849 -273.571999) (xy 143.157965 -273.586159) (xy 143.107444 -273.592293)
			(xy 143.056592 -273.590244) (xy 143.006728 -273.580064) (xy 142.959142 -273.562017) (xy 142.915068 -273.536571)
			(xy 142.875646 -273.504384) (xy 142.841898 -273.46629) (xy 142.814697 -273.423276) (xy 142.794749 -273.376456)
			(xy 142.78257 -273.327042) (xy 142.778475 -273.276314) (xy 142.459964 -273.276314) (xy 142.459469 -273.300921)
			(xy 142.451574 -273.349498) (xy 142.43599 -273.396179) (xy 142.413119 -273.439756) (xy 142.383554 -273.4791)
			(xy 142.348061 -273.513192) (xy 142.307558 -273.541148) (xy 142.263096 -273.562246) (xy 142.215825 -273.575938)
			(xy 142.16697 -273.58187) (xy 142.117795 -273.579889) (xy 142.069576 -273.570045) (xy 142.02356 -273.552593)
			(xy 141.980939 -273.527986) (xy 141.942818 -273.496861) (xy 141.910183 -273.460024) (xy 141.88388 -273.418428)
			(xy 141.864589 -273.373152) (xy 141.852812 -273.325368) (xy 141.848852 -273.276314) (xy 141.530578 -273.276314)
			(xy 141.530066 -273.30176) (xy 141.521902 -273.351994) (xy 141.505786 -273.400268) (xy 141.482135 -273.445331)
			(xy 141.451562 -273.486017) (xy 141.414858 -273.521272) (xy 141.372974 -273.550182) (xy 141.326995 -273.571999)
			(xy 141.278111 -273.586159) (xy 141.22759 -273.592293) (xy 141.176738 -273.590244) (xy 141.126874 -273.580064)
			(xy 141.079288 -273.562017) (xy 141.035214 -273.536571) (xy 140.995792 -273.504384) (xy 140.962044 -273.46629)
			(xy 140.934843 -273.423276) (xy 140.914895 -273.376456) (xy 140.902716 -273.327042) (xy 140.898621 -273.276314)
			(xy 140.58011 -273.276314) (xy 140.579615 -273.300921) (xy 140.57172 -273.349498) (xy 140.556136 -273.396179)
			(xy 140.533265 -273.439756) (xy 140.5037 -273.4791) (xy 140.468207 -273.513192) (xy 140.427704 -273.541148)
			(xy 140.383242 -273.562246) (xy 140.335971 -273.575938) (xy 140.287116 -273.58187) (xy 140.237941 -273.579889)
			(xy 140.189722 -273.570045) (xy 140.143706 -273.552593) (xy 140.101085 -273.527986) (xy 140.062964 -273.496861)
			(xy 140.030329 -273.460024) (xy 140.004026 -273.418428) (xy 139.984735 -273.373152) (xy 139.972958 -273.325368)
			(xy 139.968998 -273.276314) (xy 139.65047 -273.276314) (xy 139.649958 -273.30176) (xy 139.641794 -273.351994)
			(xy 139.625678 -273.400268) (xy 139.602027 -273.445331) (xy 139.571454 -273.486017) (xy 139.53475 -273.521272)
			(xy 139.492866 -273.550182) (xy 139.446887 -273.571999) (xy 139.398003 -273.586159) (xy 139.347482 -273.592293)
			(xy 139.29663 -273.590244) (xy 139.246766 -273.580064) (xy 139.19918 -273.562017) (xy 139.155106 -273.536571)
			(xy 139.115684 -273.504384) (xy 139.081936 -273.46629) (xy 139.054735 -273.423276) (xy 139.034787 -273.376456)
			(xy 139.022608 -273.327042) (xy 139.018513 -273.276314) (xy 138.710416 -273.276314) (xy 138.709904 -273.30176)
			(xy 138.70174 -273.351994) (xy 138.685624 -273.400268) (xy 138.661973 -273.445331) (xy 138.6314 -273.486017)
			(xy 138.594696 -273.521272) (xy 138.552812 -273.550182) (xy 138.506833 -273.571999) (xy 138.457949 -273.586159)
			(xy 138.407428 -273.592293) (xy 138.356576 -273.590244) (xy 138.306712 -273.580064) (xy 138.259126 -273.562017)
			(xy 138.215052 -273.536571) (xy 138.17563 -273.504384) (xy 138.141882 -273.46629) (xy 138.114681 -273.423276)
			(xy 138.094733 -273.376456) (xy 138.082554 -273.327042) (xy 138.078459 -273.276314) (xy 136.830562 -273.276314)
			(xy 136.83005 -273.30176) (xy 136.821886 -273.351994) (xy 136.80577 -273.400268) (xy 136.782119 -273.445331)
			(xy 136.751546 -273.486017) (xy 136.714842 -273.521272) (xy 136.672958 -273.550182) (xy 136.626979 -273.571999)
			(xy 136.578095 -273.586159) (xy 136.527574 -273.592293) (xy 136.476722 -273.590244) (xy 136.426858 -273.580064)
			(xy 136.379272 -273.562017) (xy 136.335198 -273.536571) (xy 136.295776 -273.504384) (xy 136.262028 -273.46629)
			(xy 136.234827 -273.423276) (xy 136.214879 -273.376456) (xy 136.2027 -273.327042) (xy 136.198605 -273.276314)
			(xy 135.880094 -273.276314) (xy 135.879599 -273.300921) (xy 135.871704 -273.349498) (xy 135.85612 -273.396179)
			(xy 135.833249 -273.439756) (xy 135.803684 -273.4791) (xy 135.768191 -273.513192) (xy 135.727688 -273.541148)
			(xy 135.683226 -273.562246) (xy 135.635955 -273.575938) (xy 135.5871 -273.58187) (xy 135.537925 -273.579889)
			(xy 135.489706 -273.570045) (xy 135.44369 -273.552593) (xy 135.401069 -273.527986) (xy 135.362948 -273.496861)
			(xy 135.330313 -273.460024) (xy 135.30401 -273.418428) (xy 135.284719 -273.373152) (xy 135.272942 -273.325368)
			(xy 135.268982 -273.276314) (xy 134.950454 -273.276314) (xy 134.949942 -273.30176) (xy 134.941778 -273.351994)
			(xy 134.925662 -273.400268) (xy 134.902011 -273.445331) (xy 134.871438 -273.486017) (xy 134.834734 -273.521272)
			(xy 134.79285 -273.550182) (xy 134.746871 -273.571999) (xy 134.697987 -273.586159) (xy 134.647466 -273.592293)
			(xy 134.596614 -273.590244) (xy 134.54675 -273.580064) (xy 134.499164 -273.562017) (xy 134.45509 -273.536571)
			(xy 134.415668 -273.504384) (xy 134.38192 -273.46629) (xy 134.354719 -273.423276) (xy 134.334771 -273.376456)
			(xy 134.322592 -273.327042) (xy 134.318497 -273.276314) (xy 133.999986 -273.276314) (xy 133.999491 -273.300921)
			(xy 133.991596 -273.349498) (xy 133.976012 -273.396179) (xy 133.953141 -273.439756) (xy 133.923576 -273.4791)
			(xy 133.888083 -273.513192) (xy 133.84758 -273.541148) (xy 133.803118 -273.562246) (xy 133.755847 -273.575938)
			(xy 133.706992 -273.58187) (xy 133.657817 -273.579889) (xy 133.609598 -273.570045) (xy 133.563582 -273.552593)
			(xy 133.520961 -273.527986) (xy 133.48284 -273.496861) (xy 133.450205 -273.460024) (xy 133.423902 -273.418428)
			(xy 133.404611 -273.373152) (xy 133.392834 -273.325368) (xy 133.388874 -273.276314) (xy 133.0706 -273.276314)
			(xy 133.070088 -273.30176) (xy 133.061924 -273.351994) (xy 133.045808 -273.400268) (xy 133.022157 -273.445331)
			(xy 132.991584 -273.486017) (xy 132.95488 -273.521272) (xy 132.912996 -273.550182) (xy 132.867017 -273.571999)
			(xy 132.818133 -273.586159) (xy 132.767612 -273.592293) (xy 132.71676 -273.590244) (xy 132.666896 -273.580064)
			(xy 132.61931 -273.562017) (xy 132.575236 -273.536571) (xy 132.535814 -273.504384) (xy 132.502066 -273.46629)
			(xy 132.474865 -273.423276) (xy 132.454917 -273.376456) (xy 132.442738 -273.327042) (xy 132.438643 -273.276314)
			(xy 132.130546 -273.276314) (xy 132.130034 -273.30176) (xy 132.12187 -273.351994) (xy 132.105754 -273.400268)
			(xy 132.082103 -273.445331) (xy 132.05153 -273.486017) (xy 132.014826 -273.521272) (xy 131.972942 -273.550182)
			(xy 131.926963 -273.571999) (xy 131.878079 -273.586159) (xy 131.827558 -273.592293) (xy 131.776706 -273.590244)
			(xy 131.726842 -273.580064) (xy 131.679256 -273.562017) (xy 131.635182 -273.536571) (xy 131.59576 -273.504384)
			(xy 131.562012 -273.46629) (xy 131.534811 -273.423276) (xy 131.514863 -273.376456) (xy 131.502684 -273.327042)
			(xy 131.498589 -273.276314) (xy 130.250438 -273.276314) (xy 130.249926 -273.30176) (xy 130.241762 -273.351994)
			(xy 130.225646 -273.400268) (xy 130.201995 -273.445331) (xy 130.171422 -273.486017) (xy 130.134718 -273.521272)
			(xy 130.092834 -273.550182) (xy 130.046855 -273.571999) (xy 129.997971 -273.586159) (xy 129.94745 -273.592293)
			(xy 129.896598 -273.590244) (xy 129.846734 -273.580064) (xy 129.799148 -273.562017) (xy 129.755074 -273.536571)
			(xy 129.715652 -273.504384) (xy 129.681904 -273.46629) (xy 129.654703 -273.423276) (xy 129.634755 -273.376456)
			(xy 129.622576 -273.327042) (xy 129.618481 -273.276314) (xy 129.29997 -273.276314) (xy 129.299475 -273.300921)
			(xy 129.29158 -273.349498) (xy 129.275996 -273.396179) (xy 129.253125 -273.439756) (xy 129.22356 -273.4791)
			(xy 129.188067 -273.513192) (xy 129.147564 -273.541148) (xy 129.103102 -273.562246) (xy 129.055831 -273.575938)
			(xy 129.006976 -273.58187) (xy 128.957801 -273.579889) (xy 128.909582 -273.570045) (xy 128.863566 -273.552593)
			(xy 128.820945 -273.527986) (xy 128.782824 -273.496861) (xy 128.750189 -273.460024) (xy 128.723886 -273.418428)
			(xy 128.704595 -273.373152) (xy 128.692818 -273.325368) (xy 128.688858 -273.276314) (xy 128.370584 -273.276314)
			(xy 128.370072 -273.30176) (xy 128.361908 -273.351994) (xy 128.345792 -273.400268) (xy 128.322141 -273.445331)
			(xy 128.291568 -273.486017) (xy 128.254864 -273.521272) (xy 128.21298 -273.550182) (xy 128.167001 -273.571999)
			(xy 128.118117 -273.586159) (xy 128.067596 -273.592293) (xy 128.016744 -273.590244) (xy 127.96688 -273.580064)
			(xy 127.919294 -273.562017) (xy 127.87522 -273.536571) (xy 127.835798 -273.504384) (xy 127.80205 -273.46629)
			(xy 127.774849 -273.423276) (xy 127.754901 -273.376456) (xy 127.742722 -273.327042) (xy 127.738627 -273.276314)
			(xy 127.419628 -273.276314) (xy 127.419628 -273.301661) (xy 127.411249 -273.351675) (xy 127.394721 -273.399617)
			(xy 127.370501 -273.44417) (xy 127.339252 -273.484109) (xy 127.301834 -273.518336) (xy 127.259275 -273.545911)
			(xy 127.23622 -273.556476) (xy 127.22225 -273.562572) (xy 127.20574 -273.587718) (xy 127.20574 -274.08632)
			(xy 128.208527 -274.08632) (xy 128.212622 -274.035592) (xy 128.224801 -273.986178) (xy 128.244749 -273.939358)
			(xy 128.27195 -273.896344) (xy 128.305698 -273.85825) (xy 128.34512 -273.826063) (xy 128.389194 -273.800617)
			(xy 128.43678 -273.78257) (xy 128.486644 -273.77239) (xy 128.537496 -273.770341) (xy 128.588017 -273.776475)
			(xy 128.636901 -273.790635) (xy 128.68288 -273.812452) (xy 128.724764 -273.841362) (xy 128.761468 -273.876617)
			(xy 128.792041 -273.917303) (xy 128.815692 -273.962366) (xy 128.831808 -274.01064) (xy 128.839972 -274.060874)
			(xy 128.840484 -274.08632) (xy 129.148581 -274.08632) (xy 129.152676 -274.035592) (xy 129.164855 -273.986178)
			(xy 129.184803 -273.939358) (xy 129.212004 -273.896344) (xy 129.245752 -273.85825) (xy 129.285174 -273.826063)
			(xy 129.329248 -273.800617) (xy 129.376834 -273.78257) (xy 129.426698 -273.77239) (xy 129.47755 -273.770341)
			(xy 129.528071 -273.776475) (xy 129.576955 -273.790635) (xy 129.622934 -273.812452) (xy 129.664818 -273.841362)
			(xy 129.701522 -273.876617) (xy 129.732095 -273.917303) (xy 129.755746 -273.962366) (xy 129.771862 -274.01064)
			(xy 129.780026 -274.060874) (xy 129.780538 -274.08632) (xy 130.099066 -274.08632) (xy 130.103026 -274.037266)
			(xy 130.114803 -273.989482) (xy 130.134094 -273.944206) (xy 130.160397 -273.90261) (xy 130.193032 -273.865773)
			(xy 130.231153 -273.834648) (xy 130.273774 -273.810041) (xy 130.31979 -273.792589) (xy 130.368009 -273.782745)
			(xy 130.417184 -273.780764) (xy 130.466039 -273.786696) (xy 130.51331 -273.800388) (xy 130.557772 -273.821486)
			(xy 130.598275 -273.849442) (xy 130.633768 -273.883534) (xy 130.663333 -273.922878) (xy 130.686204 -273.966455)
			(xy 130.701788 -274.013136) (xy 130.709683 -274.061713) (xy 130.710178 -274.08632) (xy 131.028435 -274.08632)
			(xy 131.03253 -274.035592) (xy 131.044709 -273.986178) (xy 131.064657 -273.939358) (xy 131.091858 -273.896344)
			(xy 131.125606 -273.85825) (xy 131.165028 -273.826063) (xy 131.209102 -273.800617) (xy 131.256688 -273.78257)
			(xy 131.306552 -273.77239) (xy 131.357404 -273.770341) (xy 131.407925 -273.776475) (xy 131.456809 -273.790635)
			(xy 131.502788 -273.812452) (xy 131.544672 -273.841362) (xy 131.581376 -273.876617) (xy 131.611949 -273.917303)
			(xy 131.6356 -273.962366) (xy 131.651716 -274.01064) (xy 131.65988 -274.060874) (xy 131.660392 -274.08632)
			(xy 131.97892 -274.08632) (xy 131.98288 -274.037266) (xy 131.994657 -273.989482) (xy 132.013948 -273.944206)
			(xy 132.040251 -273.90261) (xy 132.072886 -273.865773) (xy 132.111007 -273.834648) (xy 132.153628 -273.810041)
			(xy 132.199644 -273.792589) (xy 132.247863 -273.782745) (xy 132.297038 -273.780764) (xy 132.345893 -273.786696)
			(xy 132.393164 -273.800388) (xy 132.437626 -273.821486) (xy 132.478129 -273.849442) (xy 132.513622 -273.883534)
			(xy 132.543187 -273.922878) (xy 132.566058 -273.966455) (xy 132.581642 -274.013136) (xy 132.589537 -274.061713)
			(xy 132.590032 -274.08632) (xy 132.908543 -274.08632) (xy 132.912638 -274.035592) (xy 132.924817 -273.986178)
			(xy 132.944765 -273.939358) (xy 132.971966 -273.896344) (xy 133.005714 -273.85825) (xy 133.045136 -273.826063)
			(xy 133.08921 -273.800617) (xy 133.136796 -273.78257) (xy 133.18666 -273.77239) (xy 133.237512 -273.770341)
			(xy 133.288033 -273.776475) (xy 133.336917 -273.790635) (xy 133.382896 -273.812452) (xy 133.42478 -273.841362)
			(xy 133.461484 -273.876617) (xy 133.492057 -273.917303) (xy 133.515708 -273.962366) (xy 133.531824 -274.01064)
			(xy 133.539988 -274.060874) (xy 133.5405 -274.08632) (xy 133.859028 -274.08632) (xy 133.862988 -274.037266)
			(xy 133.874765 -273.989482) (xy 133.894056 -273.944206) (xy 133.920359 -273.90261) (xy 133.952994 -273.865773)
			(xy 133.991115 -273.834648) (xy 134.033736 -273.810041) (xy 134.079752 -273.792589) (xy 134.127971 -273.782745)
			(xy 134.177146 -273.780764) (xy 134.226001 -273.786696) (xy 134.273272 -273.800388) (xy 134.317734 -273.821486)
			(xy 134.358237 -273.849442) (xy 134.39373 -273.883534) (xy 134.423295 -273.922878) (xy 134.446166 -273.966455)
			(xy 134.46175 -274.013136) (xy 134.469645 -274.061713) (xy 134.47014 -274.08632) (xy 134.788397 -274.08632)
			(xy 134.792492 -274.035592) (xy 134.804671 -273.986178) (xy 134.824619 -273.939358) (xy 134.85182 -273.896344)
			(xy 134.885568 -273.85825) (xy 134.92499 -273.826063) (xy 134.969064 -273.800617) (xy 135.01665 -273.78257)
			(xy 135.066514 -273.77239) (xy 135.117366 -273.770341) (xy 135.167887 -273.776475) (xy 135.216771 -273.790635)
			(xy 135.26275 -273.812452) (xy 135.304634 -273.841362) (xy 135.341338 -273.876617) (xy 135.371911 -273.917303)
			(xy 135.395562 -273.962366) (xy 135.411678 -274.01064) (xy 135.419842 -274.060874) (xy 135.420354 -274.08632)
			(xy 135.728451 -274.08632) (xy 135.732546 -274.035592) (xy 135.744725 -273.986178) (xy 135.764673 -273.939358)
			(xy 135.791874 -273.896344) (xy 135.825622 -273.85825) (xy 135.865044 -273.826063) (xy 135.909118 -273.800617)
			(xy 135.956704 -273.78257) (xy 136.006568 -273.77239) (xy 136.05742 -273.770341) (xy 136.107941 -273.776475)
			(xy 136.156825 -273.790635) (xy 136.202804 -273.812452) (xy 136.244688 -273.841362) (xy 136.281392 -273.876617)
			(xy 136.311965 -273.917303) (xy 136.335616 -273.962366) (xy 136.351732 -274.01064) (xy 136.359896 -274.060874)
			(xy 136.360408 -274.08632) (xy 136.678936 -274.08632) (xy 136.682896 -274.037266) (xy 136.694673 -273.989482)
			(xy 136.713964 -273.944206) (xy 136.740267 -273.90261) (xy 136.772902 -273.865773) (xy 136.811023 -273.834648)
			(xy 136.853644 -273.810041) (xy 136.89966 -273.792589) (xy 136.947879 -273.782745) (xy 136.997054 -273.780764)
			(xy 137.045909 -273.786696) (xy 137.09318 -273.800388) (xy 137.137642 -273.821486) (xy 137.178145 -273.849442)
			(xy 137.213638 -273.883534) (xy 137.243203 -273.922878) (xy 137.266074 -273.966455) (xy 137.281658 -274.013136)
			(xy 137.289553 -274.061713) (xy 137.290048 -274.08632) (xy 137.608559 -274.08632) (xy 137.612654 -274.035592)
			(xy 137.624833 -273.986178) (xy 137.644781 -273.939358) (xy 137.671982 -273.896344) (xy 137.70573 -273.85825)
			(xy 137.745152 -273.826063) (xy 137.789226 -273.800617) (xy 137.836812 -273.78257) (xy 137.886676 -273.77239)
			(xy 137.937528 -273.770341) (xy 137.988049 -273.776475) (xy 138.036933 -273.790635) (xy 138.082912 -273.812452)
			(xy 138.124796 -273.841362) (xy 138.1615 -273.876617) (xy 138.192073 -273.917303) (xy 138.215724 -273.962366)
			(xy 138.23184 -274.01064) (xy 138.240004 -274.060874) (xy 138.240516 -274.08632) (xy 138.559044 -274.08632)
			(xy 138.563004 -274.037266) (xy 138.574781 -273.989482) (xy 138.594072 -273.944206) (xy 138.620375 -273.90261)
			(xy 138.65301 -273.865773) (xy 138.691131 -273.834648) (xy 138.733752 -273.810041) (xy 138.779768 -273.792589)
			(xy 138.827987 -273.782745) (xy 138.877162 -273.780764) (xy 138.926017 -273.786696) (xy 138.973288 -273.800388)
			(xy 139.01775 -273.821486) (xy 139.058253 -273.849442) (xy 139.093746 -273.883534) (xy 139.123311 -273.922878)
			(xy 139.146182 -273.966455) (xy 139.161766 -274.013136) (xy 139.169661 -274.061713) (xy 139.170156 -274.08632)
			(xy 139.488413 -274.08632) (xy 139.492508 -274.035592) (xy 139.504687 -273.986178) (xy 139.524635 -273.939358)
			(xy 139.551836 -273.896344) (xy 139.585584 -273.85825) (xy 139.625006 -273.826063) (xy 139.66908 -273.800617)
			(xy 139.716666 -273.78257) (xy 139.76653 -273.77239) (xy 139.817382 -273.770341) (xy 139.867903 -273.776475)
			(xy 139.916787 -273.790635) (xy 139.962766 -273.812452) (xy 140.00465 -273.841362) (xy 140.041354 -273.876617)
			(xy 140.071927 -273.917303) (xy 140.095578 -273.962366) (xy 140.111694 -274.01064) (xy 140.119858 -274.060874)
			(xy 140.12037 -274.08632) (xy 140.438898 -274.08632) (xy 140.442858 -274.037266) (xy 140.454635 -273.989482)
			(xy 140.473926 -273.944206) (xy 140.500229 -273.90261) (xy 140.532864 -273.865773) (xy 140.570985 -273.834648)
			(xy 140.613606 -273.810041) (xy 140.659622 -273.792589) (xy 140.707841 -273.782745) (xy 140.757016 -273.780764)
			(xy 140.805871 -273.786696) (xy 140.853142 -273.800388) (xy 140.897604 -273.821486) (xy 140.938107 -273.849442)
			(xy 140.9736 -273.883534) (xy 141.003165 -273.922878) (xy 141.026036 -273.966455) (xy 141.04162 -274.013136)
			(xy 141.049515 -274.061713) (xy 141.05001 -274.08632) (xy 141.368521 -274.08632) (xy 141.372616 -274.035592)
			(xy 141.384795 -273.986178) (xy 141.404743 -273.939358) (xy 141.431944 -273.896344) (xy 141.465692 -273.85825)
			(xy 141.505114 -273.826063) (xy 141.549188 -273.800617) (xy 141.596774 -273.78257) (xy 141.646638 -273.77239)
			(xy 141.69749 -273.770341) (xy 141.748011 -273.776475) (xy 141.796895 -273.790635) (xy 141.842874 -273.812452)
			(xy 141.884758 -273.841362) (xy 141.921462 -273.876617) (xy 141.952035 -273.917303) (xy 141.975686 -273.962366)
			(xy 141.991802 -274.01064) (xy 141.999966 -274.060874) (xy 142.000478 -274.08632) (xy 142.308575 -274.08632)
			(xy 142.31267 -274.035592) (xy 142.324849 -273.986178) (xy 142.344797 -273.939358) (xy 142.371998 -273.896344)
			(xy 142.405746 -273.85825) (xy 142.445168 -273.826063) (xy 142.489242 -273.800617) (xy 142.536828 -273.78257)
			(xy 142.586692 -273.77239) (xy 142.637544 -273.770341) (xy 142.688065 -273.776475) (xy 142.736949 -273.790635)
			(xy 142.782928 -273.812452) (xy 142.824812 -273.841362) (xy 142.861516 -273.876617) (xy 142.892089 -273.917303)
			(xy 142.91574 -273.962366) (xy 142.931856 -274.01064) (xy 142.94002 -274.060874) (xy 142.940532 -274.08632)
			(xy 143.258806 -274.08632) (xy 143.262766 -274.037266) (xy 143.274543 -273.989482) (xy 143.293834 -273.944206)
			(xy 143.320137 -273.90261) (xy 143.352772 -273.865773) (xy 143.390893 -273.834648) (xy 143.433514 -273.810041)
			(xy 143.47953 -273.792589) (xy 143.527749 -273.782745) (xy 143.576924 -273.780764) (xy 143.625779 -273.786696)
			(xy 143.67305 -273.800388) (xy 143.717512 -273.821486) (xy 143.758015 -273.849442) (xy 143.793508 -273.883534)
			(xy 143.823073 -273.922878) (xy 143.845944 -273.966455) (xy 143.861528 -274.013136) (xy 143.869423 -274.061713)
			(xy 143.869918 -274.08632) (xy 145.138914 -274.08632) (xy 145.142874 -274.037266) (xy 145.154651 -273.989482)
			(xy 145.173942 -273.944206) (xy 145.200245 -273.90261) (xy 145.23288 -273.865773) (xy 145.271001 -273.834648)
			(xy 145.313622 -273.810041) (xy 145.359638 -273.792589) (xy 145.407857 -273.782745) (xy 145.457032 -273.780764)
			(xy 145.505887 -273.786696) (xy 145.553158 -273.800388) (xy 145.59762 -273.821486) (xy 145.617732 -273.835368)
			(xy 164.058615 -273.835368) (xy 164.06255 -273.781597) (xy 164.074273 -273.728973) (xy 164.093533 -273.678616)
			(xy 164.119919 -273.631599) (xy 164.152871 -273.588926) (xy 164.191684 -273.551505) (xy 164.235532 -273.520135)
			(xy 164.28348 -273.495483) (xy 164.334507 -273.478075) (xy 164.387525 -273.468282) (xy 164.441404 -273.466313)
			(xy 164.494995 -273.47221) (xy 164.547156 -273.485846) (xy 164.596776 -273.506933) (xy 164.642797 -273.535019)
			(xy 164.684239 -273.569507) (xy 164.720217 -273.609661) (xy 164.749965 -273.654625) (xy 164.77285 -273.703442)
			(xy 164.788382 -273.755071) (xy 164.796232 -273.808411) (xy 164.796724 -273.835368) (xy 164.796232 -273.862325)
			(xy 164.788382 -273.915665) (xy 164.77285 -273.967294) (xy 164.749965 -274.016111) (xy 164.720217 -274.061075)
			(xy 164.684239 -274.101229) (xy 164.642797 -274.135717) (xy 164.596776 -274.163803) (xy 164.547156 -274.18489)
			(xy 164.494995 -274.198526) (xy 164.441404 -274.204423) (xy 164.387525 -274.202454) (xy 164.334507 -274.192661)
			(xy 164.28348 -274.175253) (xy 164.235532 -274.150601) (xy 164.191684 -274.119231) (xy 164.152871 -274.08181)
			(xy 164.119919 -274.039137) (xy 164.093533 -273.99212) (xy 164.074273 -273.941763) (xy 164.06255 -273.889139)
			(xy 164.058615 -273.835368) (xy 145.617732 -273.835368) (xy 145.638123 -273.849442) (xy 145.673616 -273.883534)
			(xy 145.703181 -273.922878) (xy 145.726052 -273.966455) (xy 145.741636 -274.013136) (xy 145.749531 -274.061713)
			(xy 145.750026 -274.08632) (xy 145.749531 -274.110927) (xy 145.741636 -274.159504) (xy 145.726052 -274.206185)
			(xy 145.703181 -274.249762) (xy 145.673616 -274.289106) (xy 145.638123 -274.323198) (xy 145.59762 -274.351154)
			(xy 145.553158 -274.372252) (xy 145.505887 -274.385944) (xy 145.457032 -274.391876) (xy 145.407857 -274.389895)
			(xy 145.359638 -274.380051) (xy 145.313622 -274.362599) (xy 145.271001 -274.337992) (xy 145.23288 -274.306867)
			(xy 145.200245 -274.27003) (xy 145.173942 -274.228434) (xy 145.154651 -274.183158) (xy 145.142874 -274.135374)
			(xy 145.138914 -274.08632) (xy 143.869918 -274.08632) (xy 143.869423 -274.110927) (xy 143.861528 -274.159504)
			(xy 143.845944 -274.206185) (xy 143.823073 -274.249762) (xy 143.793508 -274.289106) (xy 143.758015 -274.323198)
			(xy 143.717512 -274.351154) (xy 143.67305 -274.372252) (xy 143.625779 -274.385944) (xy 143.576924 -274.391876)
			(xy 143.527749 -274.389895) (xy 143.47953 -274.380051) (xy 143.433514 -274.362599) (xy 143.390893 -274.337992)
			(xy 143.352772 -274.306867) (xy 143.320137 -274.27003) (xy 143.293834 -274.228434) (xy 143.274543 -274.183158)
			(xy 143.262766 -274.135374) (xy 143.258806 -274.08632) (xy 142.940532 -274.08632) (xy 142.94002 -274.111766)
			(xy 142.931856 -274.162) (xy 142.91574 -274.210274) (xy 142.892089 -274.255337) (xy 142.861516 -274.296023)
			(xy 142.824812 -274.331278) (xy 142.782928 -274.360188) (xy 142.736949 -274.382005) (xy 142.688065 -274.396165)
			(xy 142.637544 -274.402299) (xy 142.586692 -274.40025) (xy 142.536828 -274.39007) (xy 142.489242 -274.372023)
			(xy 142.445168 -274.346577) (xy 142.405746 -274.31439) (xy 142.371998 -274.276296) (xy 142.344797 -274.233282)
			(xy 142.324849 -274.186462) (xy 142.31267 -274.137048) (xy 142.308575 -274.08632) (xy 142.000478 -274.08632)
			(xy 141.999966 -274.111766) (xy 141.991802 -274.162) (xy 141.975686 -274.210274) (xy 141.952035 -274.255337)
			(xy 141.921462 -274.296023) (xy 141.884758 -274.331278) (xy 141.842874 -274.360188) (xy 141.796895 -274.382005)
			(xy 141.748011 -274.396165) (xy 141.69749 -274.402299) (xy 141.646638 -274.40025) (xy 141.596774 -274.39007)
			(xy 141.549188 -274.372023) (xy 141.505114 -274.346577) (xy 141.465692 -274.31439) (xy 141.431944 -274.276296)
			(xy 141.404743 -274.233282) (xy 141.384795 -274.186462) (xy 141.372616 -274.137048) (xy 141.368521 -274.08632)
			(xy 141.05001 -274.08632) (xy 141.049515 -274.110927) (xy 141.04162 -274.159504) (xy 141.026036 -274.206185)
			(xy 141.003165 -274.249762) (xy 140.9736 -274.289106) (xy 140.938107 -274.323198) (xy 140.897604 -274.351154)
			(xy 140.853142 -274.372252) (xy 140.805871 -274.385944) (xy 140.757016 -274.391876) (xy 140.707841 -274.389895)
			(xy 140.659622 -274.380051) (xy 140.613606 -274.362599) (xy 140.570985 -274.337992) (xy 140.532864 -274.306867)
			(xy 140.500229 -274.27003) (xy 140.473926 -274.228434) (xy 140.454635 -274.183158) (xy 140.442858 -274.135374)
			(xy 140.438898 -274.08632) (xy 140.12037 -274.08632) (xy 140.119858 -274.111766) (xy 140.111694 -274.162)
			(xy 140.095578 -274.210274) (xy 140.071927 -274.255337) (xy 140.041354 -274.296023) (xy 140.00465 -274.331278)
			(xy 139.962766 -274.360188) (xy 139.916787 -274.382005) (xy 139.867903 -274.396165) (xy 139.817382 -274.402299)
			(xy 139.76653 -274.40025) (xy 139.716666 -274.39007) (xy 139.66908 -274.372023) (xy 139.625006 -274.346577)
			(xy 139.585584 -274.31439) (xy 139.551836 -274.276296) (xy 139.524635 -274.233282) (xy 139.504687 -274.186462)
			(xy 139.492508 -274.137048) (xy 139.488413 -274.08632) (xy 139.170156 -274.08632) (xy 139.169661 -274.110927)
			(xy 139.161766 -274.159504) (xy 139.146182 -274.206185) (xy 139.123311 -274.249762) (xy 139.093746 -274.289106)
			(xy 139.058253 -274.323198) (xy 139.01775 -274.351154) (xy 138.973288 -274.372252) (xy 138.926017 -274.385944)
			(xy 138.877162 -274.391876) (xy 138.827987 -274.389895) (xy 138.779768 -274.380051) (xy 138.733752 -274.362599)
			(xy 138.691131 -274.337992) (xy 138.65301 -274.306867) (xy 138.620375 -274.27003) (xy 138.594072 -274.228434)
			(xy 138.574781 -274.183158) (xy 138.563004 -274.135374) (xy 138.559044 -274.08632) (xy 138.240516 -274.08632)
			(xy 138.240004 -274.111766) (xy 138.23184 -274.162) (xy 138.215724 -274.210274) (xy 138.192073 -274.255337)
			(xy 138.1615 -274.296023) (xy 138.124796 -274.331278) (xy 138.082912 -274.360188) (xy 138.036933 -274.382005)
			(xy 137.988049 -274.396165) (xy 137.937528 -274.402299) (xy 137.886676 -274.40025) (xy 137.836812 -274.39007)
			(xy 137.789226 -274.372023) (xy 137.745152 -274.346577) (xy 137.70573 -274.31439) (xy 137.671982 -274.276296)
			(xy 137.644781 -274.233282) (xy 137.624833 -274.186462) (xy 137.612654 -274.137048) (xy 137.608559 -274.08632)
			(xy 137.290048 -274.08632) (xy 137.289553 -274.110927) (xy 137.281658 -274.159504) (xy 137.266074 -274.206185)
			(xy 137.243203 -274.249762) (xy 137.213638 -274.289106) (xy 137.178145 -274.323198) (xy 137.137642 -274.351154)
			(xy 137.09318 -274.372252) (xy 137.045909 -274.385944) (xy 136.997054 -274.391876) (xy 136.947879 -274.389895)
			(xy 136.89966 -274.380051) (xy 136.853644 -274.362599) (xy 136.811023 -274.337992) (xy 136.772902 -274.306867)
			(xy 136.740267 -274.27003) (xy 136.713964 -274.228434) (xy 136.694673 -274.183158) (xy 136.682896 -274.135374)
			(xy 136.678936 -274.08632) (xy 136.360408 -274.08632) (xy 136.359896 -274.111766) (xy 136.351732 -274.162)
			(xy 136.335616 -274.210274) (xy 136.311965 -274.255337) (xy 136.281392 -274.296023) (xy 136.244688 -274.331278)
			(xy 136.202804 -274.360188) (xy 136.156825 -274.382005) (xy 136.107941 -274.396165) (xy 136.05742 -274.402299)
			(xy 136.006568 -274.40025) (xy 135.956704 -274.39007) (xy 135.909118 -274.372023) (xy 135.865044 -274.346577)
			(xy 135.825622 -274.31439) (xy 135.791874 -274.276296) (xy 135.764673 -274.233282) (xy 135.744725 -274.186462)
			(xy 135.732546 -274.137048) (xy 135.728451 -274.08632) (xy 135.420354 -274.08632) (xy 135.419842 -274.111766)
			(xy 135.411678 -274.162) (xy 135.395562 -274.210274) (xy 135.371911 -274.255337) (xy 135.341338 -274.296023)
			(xy 135.304634 -274.331278) (xy 135.26275 -274.360188) (xy 135.216771 -274.382005) (xy 135.167887 -274.396165)
			(xy 135.117366 -274.402299) (xy 135.066514 -274.40025) (xy 135.01665 -274.39007) (xy 134.969064 -274.372023)
			(xy 134.92499 -274.346577) (xy 134.885568 -274.31439) (xy 134.85182 -274.276296) (xy 134.824619 -274.233282)
			(xy 134.804671 -274.186462) (xy 134.792492 -274.137048) (xy 134.788397 -274.08632) (xy 134.47014 -274.08632)
			(xy 134.469645 -274.110927) (xy 134.46175 -274.159504) (xy 134.446166 -274.206185) (xy 134.423295 -274.249762)
			(xy 134.39373 -274.289106) (xy 134.358237 -274.323198) (xy 134.317734 -274.351154) (xy 134.273272 -274.372252)
			(xy 134.226001 -274.385944) (xy 134.177146 -274.391876) (xy 134.127971 -274.389895) (xy 134.079752 -274.380051)
			(xy 134.033736 -274.362599) (xy 133.991115 -274.337992) (xy 133.952994 -274.306867) (xy 133.920359 -274.27003)
			(xy 133.894056 -274.228434) (xy 133.874765 -274.183158) (xy 133.862988 -274.135374) (xy 133.859028 -274.08632)
			(xy 133.5405 -274.08632) (xy 133.539988 -274.111766) (xy 133.531824 -274.162) (xy 133.515708 -274.210274)
			(xy 133.492057 -274.255337) (xy 133.461484 -274.296023) (xy 133.42478 -274.331278) (xy 133.382896 -274.360188)
			(xy 133.336917 -274.382005) (xy 133.288033 -274.396165) (xy 133.237512 -274.402299) (xy 133.18666 -274.40025)
			(xy 133.136796 -274.39007) (xy 133.08921 -274.372023) (xy 133.045136 -274.346577) (xy 133.005714 -274.31439)
			(xy 132.971966 -274.276296) (xy 132.944765 -274.233282) (xy 132.924817 -274.186462) (xy 132.912638 -274.137048)
			(xy 132.908543 -274.08632) (xy 132.590032 -274.08632) (xy 132.589537 -274.110927) (xy 132.581642 -274.159504)
			(xy 132.566058 -274.206185) (xy 132.543187 -274.249762) (xy 132.513622 -274.289106) (xy 132.478129 -274.323198)
			(xy 132.437626 -274.351154) (xy 132.393164 -274.372252) (xy 132.345893 -274.385944) (xy 132.297038 -274.391876)
			(xy 132.247863 -274.389895) (xy 132.199644 -274.380051) (xy 132.153628 -274.362599) (xy 132.111007 -274.337992)
			(xy 132.072886 -274.306867) (xy 132.040251 -274.27003) (xy 132.013948 -274.228434) (xy 131.994657 -274.183158)
			(xy 131.98288 -274.135374) (xy 131.97892 -274.08632) (xy 131.660392 -274.08632) (xy 131.65988 -274.111766)
			(xy 131.651716 -274.162) (xy 131.6356 -274.210274) (xy 131.611949 -274.255337) (xy 131.581376 -274.296023)
			(xy 131.544672 -274.331278) (xy 131.502788 -274.360188) (xy 131.456809 -274.382005) (xy 131.407925 -274.396165)
			(xy 131.357404 -274.402299) (xy 131.306552 -274.40025) (xy 131.256688 -274.39007) (xy 131.209102 -274.372023)
			(xy 131.165028 -274.346577) (xy 131.125606 -274.31439) (xy 131.091858 -274.276296) (xy 131.064657 -274.233282)
			(xy 131.044709 -274.186462) (xy 131.03253 -274.137048) (xy 131.028435 -274.08632) (xy 130.710178 -274.08632)
			(xy 130.709683 -274.110927) (xy 130.701788 -274.159504) (xy 130.686204 -274.206185) (xy 130.663333 -274.249762)
			(xy 130.633768 -274.289106) (xy 130.598275 -274.323198) (xy 130.557772 -274.351154) (xy 130.51331 -274.372252)
			(xy 130.466039 -274.385944) (xy 130.417184 -274.391876) (xy 130.368009 -274.389895) (xy 130.31979 -274.380051)
			(xy 130.273774 -274.362599) (xy 130.231153 -274.337992) (xy 130.193032 -274.306867) (xy 130.160397 -274.27003)
			(xy 130.134094 -274.228434) (xy 130.114803 -274.183158) (xy 130.103026 -274.135374) (xy 130.099066 -274.08632)
			(xy 129.780538 -274.08632) (xy 129.780026 -274.111766) (xy 129.771862 -274.162) (xy 129.755746 -274.210274)
			(xy 129.732095 -274.255337) (xy 129.701522 -274.296023) (xy 129.664818 -274.331278) (xy 129.622934 -274.360188)
			(xy 129.576955 -274.382005) (xy 129.528071 -274.396165) (xy 129.47755 -274.402299) (xy 129.426698 -274.40025)
			(xy 129.376834 -274.39007) (xy 129.329248 -274.372023) (xy 129.285174 -274.346577) (xy 129.245752 -274.31439)
			(xy 129.212004 -274.276296) (xy 129.184803 -274.233282) (xy 129.164855 -274.186462) (xy 129.152676 -274.137048)
			(xy 129.148581 -274.08632) (xy 128.840484 -274.08632) (xy 128.839972 -274.111766) (xy 128.831808 -274.162)
			(xy 128.815692 -274.210274) (xy 128.792041 -274.255337) (xy 128.761468 -274.296023) (xy 128.724764 -274.331278)
			(xy 128.68288 -274.360188) (xy 128.636901 -274.382005) (xy 128.588017 -274.396165) (xy 128.537496 -274.402299)
			(xy 128.486644 -274.40025) (xy 128.43678 -274.39007) (xy 128.389194 -274.372023) (xy 128.34512 -274.346577)
			(xy 128.305698 -274.31439) (xy 128.27195 -274.276296) (xy 128.244749 -274.233282) (xy 128.224801 -274.186462)
			(xy 128.212622 -274.137048) (xy 128.208527 -274.08632) (xy 127.20574 -274.08632) (xy 127.20574 -274.584922)
			(xy 127.22225 -274.610068) (xy 127.23622 -274.616164) (xy 127.259284 -274.626706) (xy 127.30184 -274.654282)
			(xy 127.339255 -274.68851) (xy 127.3705 -274.728449) (xy 127.394718 -274.773002) (xy 127.411242 -274.820943)
			(xy 127.419618 -274.870956) (xy 127.419617 -274.896326) (xy 127.738627 -274.896326) (xy 127.742722 -274.845598)
			(xy 127.754901 -274.796184) (xy 127.774849 -274.749364) (xy 127.80205 -274.70635) (xy 127.835798 -274.668256)
			(xy 127.87522 -274.636069) (xy 127.919294 -274.610623) (xy 127.96688 -274.592576) (xy 128.016744 -274.582396)
			(xy 128.067596 -274.580347) (xy 128.118117 -274.586481) (xy 128.167001 -274.600641) (xy 128.21298 -274.622458)
			(xy 128.254864 -274.651368) (xy 128.291568 -274.686623) (xy 128.322141 -274.727309) (xy 128.345792 -274.772372)
			(xy 128.361908 -274.820646) (xy 128.370072 -274.87088) (xy 128.370584 -274.896326) (xy 128.688858 -274.896326)
			(xy 128.692818 -274.847272) (xy 128.704595 -274.799488) (xy 128.723886 -274.754212) (xy 128.750189 -274.712616)
			(xy 128.782824 -274.675779) (xy 128.820945 -274.644654) (xy 128.863566 -274.620047) (xy 128.909582 -274.602595)
			(xy 128.957801 -274.592751) (xy 129.006976 -274.59077) (xy 129.055831 -274.596702) (xy 129.103102 -274.610394)
			(xy 129.147564 -274.631492) (xy 129.188067 -274.659448) (xy 129.22356 -274.69354) (xy 129.253125 -274.732884)
			(xy 129.275996 -274.776461) (xy 129.29158 -274.823142) (xy 129.299475 -274.871719) (xy 129.29997 -274.896326)
			(xy 129.618481 -274.896326) (xy 129.622576 -274.845598) (xy 129.634755 -274.796184) (xy 129.654703 -274.749364)
			(xy 129.681904 -274.70635) (xy 129.715652 -274.668256) (xy 129.755074 -274.636069) (xy 129.799148 -274.610623)
			(xy 129.846734 -274.592576) (xy 129.896598 -274.582396) (xy 129.94745 -274.580347) (xy 129.997971 -274.586481)
			(xy 130.046855 -274.600641) (xy 130.092834 -274.622458) (xy 130.134718 -274.651368) (xy 130.171422 -274.686623)
			(xy 130.201995 -274.727309) (xy 130.225646 -274.772372) (xy 130.241762 -274.820646) (xy 130.249926 -274.87088)
			(xy 130.250438 -274.896326) (xy 130.568966 -274.896326) (xy 130.572926 -274.847272) (xy 130.584703 -274.799488)
			(xy 130.603994 -274.754212) (xy 130.630297 -274.712616) (xy 130.662932 -274.675779) (xy 130.701053 -274.644654)
			(xy 130.743674 -274.620047) (xy 130.78969 -274.602595) (xy 130.837909 -274.592751) (xy 130.887084 -274.59077)
			(xy 130.935939 -274.596702) (xy 130.98321 -274.610394) (xy 131.027672 -274.631492) (xy 131.068175 -274.659448)
			(xy 131.103668 -274.69354) (xy 131.133233 -274.732884) (xy 131.156104 -274.776461) (xy 131.171688 -274.823142)
			(xy 131.179583 -274.871719) (xy 131.180078 -274.896326) (xy 131.498589 -274.896326) (xy 131.502684 -274.845598)
			(xy 131.514863 -274.796184) (xy 131.534811 -274.749364) (xy 131.562012 -274.70635) (xy 131.59576 -274.668256)
			(xy 131.635182 -274.636069) (xy 131.679256 -274.610623) (xy 131.726842 -274.592576) (xy 131.776706 -274.582396)
			(xy 131.827558 -274.580347) (xy 131.878079 -274.586481) (xy 131.926963 -274.600641) (xy 131.972942 -274.622458)
			(xy 132.014826 -274.651368) (xy 132.05153 -274.686623) (xy 132.082103 -274.727309) (xy 132.105754 -274.772372)
			(xy 132.12187 -274.820646) (xy 132.130034 -274.87088) (xy 132.130546 -274.896326) (xy 132.438643 -274.896326)
			(xy 132.442738 -274.845598) (xy 132.454917 -274.796184) (xy 132.474865 -274.749364) (xy 132.502066 -274.70635)
			(xy 132.535814 -274.668256) (xy 132.575236 -274.636069) (xy 132.61931 -274.610623) (xy 132.666896 -274.592576)
			(xy 132.71676 -274.582396) (xy 132.767612 -274.580347) (xy 132.818133 -274.586481) (xy 132.867017 -274.600641)
			(xy 132.912996 -274.622458) (xy 132.95488 -274.651368) (xy 132.991584 -274.686623) (xy 133.022157 -274.727309)
			(xy 133.045808 -274.772372) (xy 133.061924 -274.820646) (xy 133.070088 -274.87088) (xy 133.0706 -274.896326)
			(xy 133.388874 -274.896326) (xy 133.392834 -274.847272) (xy 133.404611 -274.799488) (xy 133.423902 -274.754212)
			(xy 133.450205 -274.712616) (xy 133.48284 -274.675779) (xy 133.520961 -274.644654) (xy 133.563582 -274.620047)
			(xy 133.609598 -274.602595) (xy 133.657817 -274.592751) (xy 133.706992 -274.59077) (xy 133.755847 -274.596702)
			(xy 133.803118 -274.610394) (xy 133.84758 -274.631492) (xy 133.888083 -274.659448) (xy 133.923576 -274.69354)
			(xy 133.953141 -274.732884) (xy 133.976012 -274.776461) (xy 133.991596 -274.823142) (xy 133.999491 -274.871719)
			(xy 133.999986 -274.896326) (xy 134.318497 -274.896326) (xy 134.322592 -274.845598) (xy 134.334771 -274.796184)
			(xy 134.354719 -274.749364) (xy 134.38192 -274.70635) (xy 134.415668 -274.668256) (xy 134.45509 -274.636069)
			(xy 134.499164 -274.610623) (xy 134.54675 -274.592576) (xy 134.596614 -274.582396) (xy 134.647466 -274.580347)
			(xy 134.697987 -274.586481) (xy 134.746871 -274.600641) (xy 134.79285 -274.622458) (xy 134.834734 -274.651368)
			(xy 134.871438 -274.686623) (xy 134.902011 -274.727309) (xy 134.925662 -274.772372) (xy 134.941778 -274.820646)
			(xy 134.949942 -274.87088) (xy 134.950454 -274.896326) (xy 135.268982 -274.896326) (xy 135.272942 -274.847272)
			(xy 135.284719 -274.799488) (xy 135.30401 -274.754212) (xy 135.330313 -274.712616) (xy 135.362948 -274.675779)
			(xy 135.401069 -274.644654) (xy 135.44369 -274.620047) (xy 135.489706 -274.602595) (xy 135.537925 -274.592751)
			(xy 135.5871 -274.59077) (xy 135.635955 -274.596702) (xy 135.683226 -274.610394) (xy 135.727688 -274.631492)
			(xy 135.768191 -274.659448) (xy 135.803684 -274.69354) (xy 135.833249 -274.732884) (xy 135.85612 -274.776461)
			(xy 135.871704 -274.823142) (xy 135.879599 -274.871719) (xy 135.880094 -274.896326) (xy 136.198605 -274.896326)
			(xy 136.2027 -274.845598) (xy 136.214879 -274.796184) (xy 136.234827 -274.749364) (xy 136.262028 -274.70635)
			(xy 136.295776 -274.668256) (xy 136.335198 -274.636069) (xy 136.379272 -274.610623) (xy 136.426858 -274.592576)
			(xy 136.476722 -274.582396) (xy 136.527574 -274.580347) (xy 136.578095 -274.586481) (xy 136.626979 -274.600641)
			(xy 136.672958 -274.622458) (xy 136.714842 -274.651368) (xy 136.751546 -274.686623) (xy 136.782119 -274.727309)
			(xy 136.80577 -274.772372) (xy 136.821886 -274.820646) (xy 136.83005 -274.87088) (xy 136.830562 -274.896326)
			(xy 137.148836 -274.896326) (xy 137.152796 -274.847272) (xy 137.164573 -274.799488) (xy 137.183864 -274.754212)
			(xy 137.210167 -274.712616) (xy 137.242802 -274.675779) (xy 137.280923 -274.644654) (xy 137.323544 -274.620047)
			(xy 137.36956 -274.602595) (xy 137.417779 -274.592751) (xy 137.466954 -274.59077) (xy 137.515809 -274.596702)
			(xy 137.56308 -274.610394) (xy 137.607542 -274.631492) (xy 137.648045 -274.659448) (xy 137.683538 -274.69354)
			(xy 137.713103 -274.732884) (xy 137.735974 -274.776461) (xy 137.751558 -274.823142) (xy 137.759453 -274.871719)
			(xy 137.759948 -274.896326) (xy 138.078459 -274.896326) (xy 138.082554 -274.845598) (xy 138.094733 -274.796184)
			(xy 138.114681 -274.749364) (xy 138.141882 -274.70635) (xy 138.17563 -274.668256) (xy 138.215052 -274.636069)
			(xy 138.259126 -274.610623) (xy 138.306712 -274.592576) (xy 138.356576 -274.582396) (xy 138.407428 -274.580347)
			(xy 138.457949 -274.586481) (xy 138.506833 -274.600641) (xy 138.552812 -274.622458) (xy 138.594696 -274.651368)
			(xy 138.6314 -274.686623) (xy 138.661973 -274.727309) (xy 138.685624 -274.772372) (xy 138.70174 -274.820646)
			(xy 138.709904 -274.87088) (xy 138.710416 -274.896326) (xy 139.018513 -274.896326) (xy 139.022608 -274.845598)
			(xy 139.034787 -274.796184) (xy 139.054735 -274.749364) (xy 139.081936 -274.70635) (xy 139.115684 -274.668256)
			(xy 139.155106 -274.636069) (xy 139.19918 -274.610623) (xy 139.246766 -274.592576) (xy 139.29663 -274.582396)
			(xy 139.347482 -274.580347) (xy 139.398003 -274.586481) (xy 139.446887 -274.600641) (xy 139.492866 -274.622458)
			(xy 139.53475 -274.651368) (xy 139.571454 -274.686623) (xy 139.602027 -274.727309) (xy 139.625678 -274.772372)
			(xy 139.641794 -274.820646) (xy 139.649958 -274.87088) (xy 139.65047 -274.896326) (xy 139.968998 -274.896326)
			(xy 139.972958 -274.847272) (xy 139.984735 -274.799488) (xy 140.004026 -274.754212) (xy 140.030329 -274.712616)
			(xy 140.062964 -274.675779) (xy 140.101085 -274.644654) (xy 140.143706 -274.620047) (xy 140.189722 -274.602595)
			(xy 140.237941 -274.592751) (xy 140.287116 -274.59077) (xy 140.335971 -274.596702) (xy 140.383242 -274.610394)
			(xy 140.427704 -274.631492) (xy 140.468207 -274.659448) (xy 140.5037 -274.69354) (xy 140.533265 -274.732884)
			(xy 140.556136 -274.776461) (xy 140.57172 -274.823142) (xy 140.579615 -274.871719) (xy 140.58011 -274.896326)
			(xy 140.898621 -274.896326) (xy 140.902716 -274.845598) (xy 140.914895 -274.796184) (xy 140.934843 -274.749364)
			(xy 140.962044 -274.70635) (xy 140.995792 -274.668256) (xy 141.035214 -274.636069) (xy 141.079288 -274.610623)
			(xy 141.126874 -274.592576) (xy 141.176738 -274.582396) (xy 141.22759 -274.580347) (xy 141.278111 -274.586481)
			(xy 141.326995 -274.600641) (xy 141.372974 -274.622458) (xy 141.414858 -274.651368) (xy 141.451562 -274.686623)
			(xy 141.482135 -274.727309) (xy 141.505786 -274.772372) (xy 141.521902 -274.820646) (xy 141.530066 -274.87088)
			(xy 141.530578 -274.896326) (xy 141.848852 -274.896326) (xy 141.852812 -274.847272) (xy 141.864589 -274.799488)
			(xy 141.88388 -274.754212) (xy 141.910183 -274.712616) (xy 141.942818 -274.675779) (xy 141.980939 -274.644654)
			(xy 142.02356 -274.620047) (xy 142.069576 -274.602595) (xy 142.117795 -274.592751) (xy 142.16697 -274.59077)
			(xy 142.215825 -274.596702) (xy 142.263096 -274.610394) (xy 142.307558 -274.631492) (xy 142.348061 -274.659448)
			(xy 142.383554 -274.69354) (xy 142.413119 -274.732884) (xy 142.43599 -274.776461) (xy 142.451574 -274.823142)
			(xy 142.459469 -274.871719) (xy 142.459964 -274.896326) (xy 142.778475 -274.896326) (xy 142.78257 -274.845598)
			(xy 142.794749 -274.796184) (xy 142.814697 -274.749364) (xy 142.841898 -274.70635) (xy 142.875646 -274.668256)
			(xy 142.915068 -274.636069) (xy 142.959142 -274.610623) (xy 143.006728 -274.592576) (xy 143.056592 -274.582396)
			(xy 143.107444 -274.580347) (xy 143.157965 -274.586481) (xy 143.206849 -274.600641) (xy 143.252828 -274.622458)
			(xy 143.294712 -274.651368) (xy 143.331416 -274.686623) (xy 143.361989 -274.727309) (xy 143.38564 -274.772372)
			(xy 143.401756 -274.820646) (xy 143.40992 -274.87088) (xy 143.410432 -274.896326) (xy 143.72896 -274.896326)
			(xy 143.73292 -274.847272) (xy 143.744697 -274.799488) (xy 143.763988 -274.754212) (xy 143.790291 -274.712616)
			(xy 143.822926 -274.675779) (xy 143.861047 -274.644654) (xy 143.903668 -274.620047) (xy 143.949684 -274.602595)
			(xy 143.997903 -274.592751) (xy 144.047078 -274.59077) (xy 144.095933 -274.596702) (xy 144.143204 -274.610394)
			(xy 144.185339 -274.630388) (xy 146.737082 -274.630388) (xy 146.741042 -274.581334) (xy 146.752819 -274.53355)
			(xy 146.77211 -274.488274) (xy 146.798413 -274.446678) (xy 146.831048 -274.409841) (xy 146.869169 -274.378716)
			(xy 146.91179 -274.354109) (xy 146.957806 -274.336657) (xy 147.006025 -274.326813) (xy 147.0552 -274.324832)
			(xy 147.104055 -274.330764) (xy 147.151326 -274.344456) (xy 147.195788 -274.365554) (xy 147.236291 -274.39351)
			(xy 147.271784 -274.427602) (xy 147.301349 -274.466946) (xy 147.32422 -274.510523) (xy 147.339804 -274.557204)
			(xy 147.347699 -274.605781) (xy 147.348194 -274.630388) (xy 147.347699 -274.654995) (xy 147.342781 -274.685252)
			(xy 166.774383 -274.685252) (xy 166.778318 -274.631481) (xy 166.790041 -274.578857) (xy 166.809301 -274.5285)
			(xy 166.835687 -274.481483) (xy 166.868639 -274.43881) (xy 166.907452 -274.401389) (xy 166.9513 -274.370019)
			(xy 166.999248 -274.345367) (xy 167.050275 -274.327959) (xy 167.103293 -274.318166) (xy 167.157172 -274.316197)
			(xy 167.210763 -274.322094) (xy 167.262924 -274.33573) (xy 167.312544 -274.356817) (xy 167.358565 -274.384903)
			(xy 167.400007 -274.419391) (xy 167.435985 -274.459545) (xy 167.465733 -274.504509) (xy 167.488618 -274.553326)
			(xy 167.50415 -274.604955) (xy 167.512 -274.658295) (xy 167.512492 -274.685252) (xy 171.476162 -274.685252)
			(xy 171.476657 -274.654056) (xy 171.484472 -274.592155) (xy 171.499998 -274.531726) (xy 171.522988 -274.473724)
			(xy 171.55308 -274.419068) (xy 171.589796 -274.368623) (xy 171.632555 -274.323187) (xy 171.680681 -274.28348)
			(xy 171.706794 -274.266406) (xy 171.716954 -274.259802) (xy 171.729146 -274.23999) (xy 171.738544 -274.13585)
			(xy 171.730162 -274.11426) (xy 171.721272 -274.105878) (xy 171.702972 -274.088378) (xy 171.670894 -274.049197)
			(xy 171.644478 -274.005997) (xy 171.62422 -273.95959) (xy 171.610501 -273.910847) (xy 171.603578 -273.860686)
			(xy 171.603162 -273.835368) (xy 171.603584 -273.81002) (xy 171.61052 -273.759801) (xy 171.62427 -273.711006)
			(xy 171.644576 -273.664554) (xy 171.671053 -273.621322) (xy 171.703203 -273.582125) (xy 171.721526 -273.564604)
			(xy 171.730416 -273.556476) (xy 171.738798 -273.534632) (xy 171.729146 -273.430492) (xy 171.716954 -273.41068)
			(xy 171.706794 -273.40433) (xy 171.680688 -273.387223) (xy 171.632566 -273.347472) (xy 171.58981 -273.301999)
			(xy 171.553096 -273.251522) (xy 171.523002 -273.196839) (xy 171.500005 -273.138814) (xy 171.484467 -273.078362)
			(xy 171.476635 -273.016438) (xy 171.476162 -272.98523) (xy 171.47664 -272.954033) (xy 171.484457 -272.892132)
			(xy 171.499986 -272.831702) (xy 171.522979 -272.7737) (xy 171.553073 -272.719044) (xy 171.589791 -272.668599)
			(xy 171.632552 -272.623164) (xy 171.68068 -272.583458) (xy 171.706794 -272.566384) (xy 171.716954 -272.55978)
			(xy 171.729146 -272.539968) (xy 171.738544 -272.435828) (xy 171.730162 -272.414238) (xy 171.721272 -272.405856)
			(xy 171.703009 -272.388318) (xy 171.670929 -272.349146) (xy 171.644508 -272.305954) (xy 171.624243 -272.259554)
			(xy 171.610515 -272.210818) (xy 171.603583 -272.160662) (xy 171.603162 -272.135346) (xy 171.60357 -272.109998)
			(xy 171.610508 -272.059778) (xy 171.624262 -272.010982) (xy 171.64457 -271.964531) (xy 171.67105 -271.921299)
			(xy 171.703202 -271.882102) (xy 171.721526 -271.864582) (xy 171.730416 -271.856454) (xy 171.738798 -271.83461)
			(xy 171.729146 -271.73047) (xy 171.716954 -271.710658) (xy 171.706794 -271.704308) (xy 171.680678 -271.687215)
			(xy 171.632556 -271.647462) (xy 171.589801 -271.601987) (xy 171.553087 -271.551508) (xy 171.522995 -271.496823)
			(xy 171.499999 -271.438796) (xy 171.484464 -271.378342) (xy 171.476634 -271.316417) (xy 171.476162 -271.285208)
			(xy 171.476666 -271.252507) (xy 171.485279 -271.187674) (xy 171.502344 -271.124537) (xy 171.527565 -271.064193)
			(xy 171.560502 -271.00769) (xy 171.600585 -270.956009) (xy 171.623482 -270.932656) (xy 171.630848 -270.92529)
			(xy 171.638468 -270.906748) (xy 171.638468 -270.813784) (xy 171.630848 -270.795242) (xy 171.623482 -270.787876)
			(xy 171.600608 -270.764501) (xy 171.56052 -270.712828) (xy 171.52758 -270.65633) (xy 171.502359 -270.595989)
			(xy 171.485296 -270.532855) (xy 171.476688 -270.468024) (xy 171.476162 -270.435324) (xy 171.476635 -270.404127)
			(xy 171.484454 -270.342226) (xy 171.499983 -270.281796) (xy 171.522976 -270.223794) (xy 171.553071 -270.169138)
			(xy 171.589789 -270.118693) (xy 171.632551 -270.073258) (xy 171.68068 -270.033552) (xy 171.706794 -270.016478)
			(xy 171.716954 -270.009874) (xy 171.729146 -269.990062) (xy 171.738544 -269.885922) (xy 171.730162 -269.864332)
			(xy 171.721272 -269.85595) (xy 171.703006 -269.838415) (xy 171.670926 -269.799242) (xy 171.644505 -269.756049)
			(xy 171.624241 -269.709649) (xy 171.610514 -269.660912) (xy 171.603583 -269.610756) (xy 171.603162 -269.58544)
			(xy 171.603566 -269.560091) (xy 171.610505 -269.509872) (xy 171.624259 -269.461076) (xy 171.644568 -269.414624)
			(xy 171.671049 -269.371393) (xy 171.703202 -269.332196) (xy 171.721526 -269.314676) (xy 171.730416 -269.306548)
			(xy 171.738798 -269.284704) (xy 171.729146 -269.180564) (xy 171.716954 -269.160752) (xy 171.706794 -269.154402)
			(xy 171.680675 -269.137313) (xy 171.632553 -269.09756) (xy 171.589798 -269.052084) (xy 171.553085 -269.001605)
			(xy 171.522993 -268.946919) (xy 171.499998 -268.888891) (xy 171.484463 -268.828437) (xy 171.476633 -268.766511)
			(xy 171.476162 -268.735302) (xy 171.476618 -268.704105) (xy 171.484439 -268.642202) (xy 171.499971 -268.581772)
			(xy 171.522967 -268.52377) (xy 171.553064 -268.469114) (xy 171.589785 -268.41867) (xy 171.632549 -268.373235)
			(xy 171.680679 -268.333529) (xy 171.706794 -268.316456) (xy 171.716954 -268.309852) (xy 171.729146 -268.29004)
			(xy 171.738544 -268.1859) (xy 171.730162 -268.16431) (xy 171.721272 -268.155928) (xy 171.702996 -268.138403)
			(xy 171.670916 -268.099228) (xy 171.644497 -268.056033) (xy 171.624235 -268.009631) (xy 171.61051 -267.960892)
			(xy 171.603582 -267.910735) (xy 171.603162 -267.885418) (xy 171.603618 -267.860071) (xy 171.610547 -267.809854)
			(xy 171.62429 -267.761059) (xy 171.644589 -267.714607) (xy 171.671061 -267.671374) (xy 171.703206 -267.632176)
			(xy 171.721526 -267.614654) (xy 171.730416 -267.606526) (xy 171.738798 -267.584682) (xy 171.729146 -267.480542)
			(xy 171.716954 -267.46073) (xy 171.706794 -267.45438) (xy 171.680665 -267.437306) (xy 171.632543 -267.39755)
			(xy 171.589789 -267.352072) (xy 171.553076 -267.301591) (xy 171.522985 -267.246903) (xy 171.499992 -267.188873)
			(xy 171.484459 -267.128417) (xy 171.476632 -267.06649) (xy 171.476162 -267.03528) (xy 171.476601 -267.004082)
			(xy 171.484425 -266.942179) (xy 171.499959 -266.881748) (xy 171.522958 -266.823746) (xy 171.553057 -266.76909)
			(xy 171.58978 -266.718646) (xy 171.632546 -266.673212) (xy 171.680678 -266.633507) (xy 171.706794 -266.616434)
			(xy 171.716954 -266.60983) (xy 171.729146 -266.590018) (xy 171.738544 -266.485878) (xy 171.730162 -266.464288)
			(xy 171.721272 -266.455906) (xy 171.702985 -266.438392) (xy 171.670907 -266.399215) (xy 171.644489 -266.356018)
			(xy 171.624228 -266.309613) (xy 171.610506 -266.260873) (xy 171.60358 -266.210713) (xy 171.603162 -266.185396)
			(xy 171.603603 -266.160049) (xy 171.610535 -266.10983) (xy 171.624281 -266.061035) (xy 171.644583 -266.014584)
			(xy 171.671057 -265.971351) (xy 171.703205 -265.932153) (xy 171.721526 -265.914632) (xy 171.730416 -265.906504)
			(xy 171.738798 -265.88466) (xy 171.729146 -265.78052) (xy 171.716954 -265.760708) (xy 171.706794 -265.754358)
			(xy 171.680701 -265.737232) (xy 171.632579 -265.697483) (xy 171.589822 -265.652013) (xy 171.553107 -265.60154)
			(xy 171.523012 -265.546859) (xy 171.500012 -265.488836) (xy 171.484472 -265.428387) (xy 171.476637 -265.366465)
			(xy 171.476162 -265.335258) (xy 171.476662 -265.304062) (xy 171.484476 -265.242161) (xy 171.500001 -265.181732)
			(xy 171.522991 -265.12373) (xy 171.553081 -265.069074) (xy 171.589797 -265.018629) (xy 171.632556 -264.973193)
			(xy 171.680681 -264.933486) (xy 171.706794 -264.916412) (xy 171.716954 -264.909808) (xy 171.729146 -264.889996)
			(xy 171.738544 -264.785856) (xy 171.730162 -264.764266) (xy 171.721272 -264.755884) (xy 171.702974 -264.738381)
			(xy 171.670897 -264.699201) (xy 171.64448 -264.656002) (xy 171.624222 -264.609595) (xy 171.610502 -264.560853)
			(xy 171.603579 -264.510692) (xy 171.603162 -264.485374) (xy 171.603588 -264.460026) (xy 171.610523 -264.409807)
			(xy 171.624273 -264.361012) (xy 171.644577 -264.31456) (xy 171.671054 -264.271328) (xy 171.703204 -264.232131)
			(xy 171.721526 -264.21461) (xy 171.730416 -264.206482) (xy 171.738798 -264.184638) (xy 171.729146 -264.080498)
			(xy 171.716954 -264.060686) (xy 171.706794 -264.054336) (xy 171.680691 -264.037225) (xy 171.632569 -263.997474)
			(xy 171.589813 -263.952002) (xy 171.553098 -263.901526) (xy 171.523004 -263.846844) (xy 171.500007 -263.788818)
			(xy 171.484468 -263.728367) (xy 171.476635 -263.666444) (xy 171.476162 -263.635236) (xy 171.476644 -263.604039)
			(xy 171.484461 -263.542138) (xy 171.499989 -263.481708) (xy 171.522981 -263.423707) (xy 171.553074 -263.369051)
			(xy 171.589792 -263.318606) (xy 171.632553 -263.27317) (xy 171.68068 -263.233464) (xy 171.706794 -263.21639)
			(xy 171.716954 -263.209786) (xy 171.729146 -263.189974) (xy 171.738544 -263.085834) (xy 171.730162 -263.064244)
			(xy 171.721272 -263.055862) (xy 171.703012 -263.038321) (xy 171.670931 -262.999149) (xy 171.64451 -262.955958)
			(xy 171.624245 -262.909558) (xy 171.610517 -262.860823) (xy 171.603584 -262.810668) (xy 171.603162 -262.785352)
			(xy 171.603574 -262.760004) (xy 171.610512 -262.709784) (xy 171.624264 -262.660989) (xy 171.644571 -262.614537)
			(xy 171.671051 -262.571305) (xy 171.703203 -262.532108) (xy 171.721526 -262.514588) (xy 171.730416 -262.50646)
			(xy 171.738798 -262.484616) (xy 171.729146 -262.380476) (xy 171.716954 -262.360664) (xy 171.706794 -262.354314)
			(xy 171.680681 -262.337217) (xy 171.632559 -262.297465) (xy 171.589803 -262.25199) (xy 171.553089 -262.201512)
			(xy 171.522997 -262.146828) (xy 171.500001 -262.088801) (xy 171.484465 -262.028347) (xy 171.476634 -261.966423)
			(xy 171.476162 -261.935214) (xy 171.476651 -261.904051) (xy 171.484463 -261.842217) (xy 171.499963 -261.781849)
			(xy 171.522906 -261.723901) (xy 171.552932 -261.669284) (xy 171.589566 -261.618862) (xy 171.632231 -261.573428)
			(xy 171.680253 -261.5337) (xy 171.732877 -261.500305) (xy 171.789271 -261.473768) (xy 171.848546 -261.454508)
			(xy 171.909767 -261.442829) (xy 171.97197 -261.438916) (xy 172.034173 -261.442829) (xy 172.095394 -261.454508)
			(xy 172.154669 -261.473768) (xy 172.211063 -261.500305) (xy 172.263687 -261.5337) (xy 172.311709 -261.573428)
			(xy 172.354374 -261.618862) (xy 172.391008 -261.669284) (xy 172.421034 -261.723901) (xy 172.443977 -261.781849)
			(xy 172.459477 -261.842217) (xy 172.467289 -261.904051) (xy 172.467778 -261.935214) (xy 172.467299 -261.966423)
			(xy 172.459478 -262.02835) (xy 172.443948 -262.088806) (xy 172.420956 -262.146835) (xy 172.390863 -262.201521)
			(xy 172.354147 -262.251999) (xy 172.311388 -262.297471) (xy 172.263261 -262.337218) (xy 172.237146 -262.354314)
			(xy 172.226986 -262.360664) (xy 172.214794 -262.380476) (xy 172.205142 -262.484616) (xy 172.213524 -262.50646)
			(xy 172.222414 -262.514588) (xy 172.24073 -262.532114) (xy 172.272873 -262.571315) (xy 172.299347 -262.614547)
			(xy 172.319652 -262.660997) (xy 172.333408 -262.709789) (xy 172.340355 -262.760005) (xy 172.340778 -262.785352)
			(xy 172.340345 -262.810669) (xy 172.333423 -262.860828) (xy 172.319705 -262.909568) (xy 172.299447 -262.955972)
			(xy 172.27303 -262.999169) (xy 172.240952 -263.038345) (xy 172.222668 -263.055862) (xy 172.213778 -263.064244)
			(xy 172.205396 -263.085834) (xy 172.214794 -263.189974) (xy 172.226986 -263.209786) (xy 172.237146 -263.21639)
			(xy 172.263234 -263.233499) (xy 172.311354 -263.273209) (xy 172.35411 -263.318643) (xy 172.390826 -263.369083)
			(xy 172.420923 -263.423732) (xy 172.443924 -263.481726) (xy 172.459466 -263.542148) (xy 172.467303 -263.604042)
			(xy 172.467778 -263.635236) (xy 172.467316 -263.666446) (xy 172.459492 -263.728373) (xy 172.44396 -263.788829)
			(xy 172.420965 -263.846859) (xy 172.39087 -263.901545) (xy 172.354152 -263.952022) (xy 172.311391 -263.997494)
			(xy 172.263262 -264.037241) (xy 172.237146 -264.054336) (xy 172.226986 -264.060686) (xy 172.214794 -264.080498)
			(xy 172.205142 -264.184638) (xy 172.213524 -264.206482) (xy 172.222414 -264.21461) (xy 172.240741 -264.232125)
			(xy 172.272883 -264.271329) (xy 172.299355 -264.314563) (xy 172.319659 -264.361015) (xy 172.333412 -264.409809)
			(xy 172.340356 -264.460026) (xy 172.340778 -264.485374) (xy 172.34036 -264.510692) (xy 172.333436 -264.560851)
			(xy 172.319714 -264.609591) (xy 172.299453 -264.655996) (xy 172.273034 -264.699192) (xy 172.240953 -264.738368)
			(xy 172.222668 -264.755884) (xy 172.213778 -264.764266) (xy 172.205396 -264.785856) (xy 172.214794 -264.889996)
			(xy 172.226986 -264.909808) (xy 172.237146 -264.916412) (xy 172.263245 -264.933507) (xy 172.311364 -264.973218)
			(xy 172.354119 -265.018655) (xy 172.390835 -265.069097) (xy 172.42093 -265.123748) (xy 172.44393 -265.181744)
			(xy 172.45947 -265.242167) (xy 172.467304 -265.304063) (xy 172.467778 -265.335258) (xy 172.467333 -265.366468)
			(xy 172.459507 -265.428396) (xy 172.443972 -265.488853) (xy 172.420974 -265.546883) (xy 172.390877 -265.601569)
			(xy 172.354157 -265.652046) (xy 172.311393 -265.697517) (xy 172.263263 -265.737263) (xy 172.237146 -265.754358)
			(xy 172.226986 -265.760708) (xy 172.214794 -265.78052) (xy 172.205142 -265.88466) (xy 172.213524 -265.906504)
			(xy 172.222414 -265.914632) (xy 172.240752 -265.932137) (xy 172.272893 -265.971342) (xy 172.299363 -266.014579)
			(xy 172.319665 -266.061033) (xy 172.333416 -266.109829) (xy 172.340358 -266.160048) (xy 172.340778 -266.185396)
			(xy 172.340374 -266.210714) (xy 172.333447 -266.260874) (xy 172.319723 -266.309615) (xy 172.299459 -266.356019)
			(xy 172.273037 -266.399215) (xy 172.240954 -266.43839) (xy 172.222668 -266.455906) (xy 172.213778 -266.464288)
			(xy 172.205396 -266.485878) (xy 172.214794 -266.590018) (xy 172.226986 -266.60983) (xy 172.237146 -266.616434)
			(xy 172.263255 -266.633514) (xy 172.311374 -266.673228) (xy 172.354129 -266.718666) (xy 172.390844 -266.769111)
			(xy 172.420938 -266.823764) (xy 172.443936 -266.881762) (xy 172.459474 -266.942187) (xy 172.467306 -267.004085)
			(xy 172.467778 -267.03528) (xy 172.467351 -267.066491) (xy 172.459521 -267.12842) (xy 172.443984 -267.188877)
			(xy 172.420984 -267.246907) (xy 172.390884 -267.301592) (xy 172.354162 -267.352069) (xy 172.311396 -267.39754)
			(xy 172.263263 -267.437285) (xy 172.237146 -267.45438) (xy 172.226986 -267.46073) (xy 172.214794 -267.480542)
			(xy 172.205142 -267.584682) (xy 172.213524 -267.606526) (xy 172.222414 -267.614654) (xy 172.240762 -267.632148)
			(xy 172.272902 -267.671356) (xy 172.299372 -267.714595) (xy 172.319672 -267.761051) (xy 172.333421 -267.809849)
			(xy 172.340359 -267.860069) (xy 172.340778 -267.885418) (xy 172.340389 -267.910737) (xy 172.333459 -267.960897)
			(xy 172.319732 -268.009638) (xy 172.299465 -268.056043) (xy 172.273041 -268.099238) (xy 172.240955 -268.138413)
			(xy 172.222668 -268.155928) (xy 172.213778 -268.16431) (xy 172.205396 -268.1859) (xy 172.214794 -268.29004)
			(xy 172.226986 -268.309852) (xy 172.237146 -268.316456) (xy 172.263265 -268.333521) (xy 172.311384 -268.373237)
			(xy 172.354138 -268.418678) (xy 172.390852 -268.469124) (xy 172.420945 -268.52378) (xy 172.443942 -268.58178)
			(xy 172.459477 -268.642207) (xy 172.467307 -268.704106) (xy 172.467778 -268.735302) (xy 172.46729 -268.766511)
			(xy 172.45947 -268.828437) (xy 172.443942 -268.888893) (xy 172.42095 -268.946922) (xy 172.39086 -269.001608)
			(xy 172.354145 -269.052086) (xy 172.311386 -269.097559) (xy 172.26326 -269.137306) (xy 172.237146 -269.154402)
			(xy 172.226986 -269.160752) (xy 172.214794 -269.180564) (xy 172.205142 -269.284704) (xy 172.213524 -269.306548)
			(xy 172.222414 -269.314676) (xy 172.240725 -269.332208) (xy 172.272868 -269.371408) (xy 172.299342 -269.414639)
			(xy 172.319649 -269.461087) (xy 172.333406 -269.509878) (xy 172.340354 -269.560093) (xy 172.340778 -269.58544)
			(xy 172.340337 -269.610757) (xy 172.333417 -269.660915) (xy 172.3197 -269.709655) (xy 172.299443 -269.75606)
			(xy 172.273028 -269.799257) (xy 172.240951 -269.838433) (xy 172.222668 -269.85595) (xy 172.213778 -269.864332)
			(xy 172.205396 -269.885922) (xy 172.214794 -269.990062) (xy 172.226986 -270.009874) (xy 172.237146 -270.016478)
			(xy 172.263229 -270.033595) (xy 172.311348 -270.073304) (xy 172.354104 -270.118737) (xy 172.390822 -270.169176)
			(xy 172.420919 -270.223824) (xy 172.443921 -270.281816) (xy 172.459464 -270.342237) (xy 172.467302 -270.40413)
			(xy 172.467778 -270.435324) (xy 172.467218 -270.468023) (xy 172.458615 -270.532853) (xy 172.44156 -270.595989)
			(xy 172.416349 -270.656333) (xy 172.383422 -270.712837) (xy 172.34335 -270.764521) (xy 172.320458 -270.787876)
			(xy 172.313092 -270.795242) (xy 172.305472 -270.813784) (xy 172.305472 -270.906748) (xy 172.313092 -270.92529)
			(xy 172.320458 -270.932656) (xy 172.343355 -270.956009) (xy 172.383439 -271.007688) (xy 172.416375 -271.064191)
			(xy 172.441592 -271.124536) (xy 172.458651 -271.187674) (xy 172.467254 -271.252507) (xy 172.467778 -271.285208)
			(xy 172.467294 -271.316417) (xy 172.459474 -271.378344) (xy 172.443945 -271.438799) (xy 172.420953 -271.496829)
			(xy 172.390862 -271.551515) (xy 172.354146 -271.601993) (xy 172.311387 -271.647465) (xy 172.263261 -271.687212)
			(xy 172.237146 -271.704308) (xy 172.226986 -271.710658) (xy 172.214794 -271.73047) (xy 172.205142 -271.83461)
			(xy 172.213524 -271.856454) (xy 172.222414 -271.864582) (xy 172.240728 -271.882111) (xy 172.272871 -271.921311)
			(xy 172.299344 -271.964543) (xy 172.319651 -272.010992) (xy 172.333407 -272.059784) (xy 172.340354 -272.109999)
			(xy 172.340778 -272.135346) (xy 172.340341 -272.160663) (xy 172.33342 -272.210821) (xy 172.319702 -272.259561)
			(xy 172.299445 -272.305966) (xy 172.273029 -272.349163) (xy 172.240951 -272.388339) (xy 172.222668 -272.405856)
			(xy 172.213778 -272.414238) (xy 172.205396 -272.435828) (xy 172.214794 -272.539968) (xy 172.226986 -272.55978)
			(xy 172.237146 -272.566384) (xy 172.263232 -272.583497) (xy 172.311351 -272.623206) (xy 172.354107 -272.66864)
			(xy 172.390824 -272.71908) (xy 172.420921 -272.773728) (xy 172.443923 -272.831721) (xy 172.459465 -272.892142)
			(xy 172.467303 -272.954036) (xy 172.467778 -272.98523) (xy 172.467311 -273.01644) (xy 172.459488 -273.078367)
			(xy 172.443957 -273.138823) (xy 172.420962 -273.196853) (xy 172.390869 -273.251538) (xy 172.354151 -273.302016)
			(xy 172.31139 -273.347488) (xy 172.263261 -273.387235) (xy 172.237146 -273.40433) (xy 172.226986 -273.41068)
			(xy 172.214794 -273.430492) (xy 172.205142 -273.534632) (xy 172.213524 -273.556476) (xy 172.222414 -273.564604)
			(xy 172.240738 -273.582122) (xy 172.27288 -273.621325) (xy 172.299353 -273.664559) (xy 172.319657 -273.71101)
			(xy 172.333411 -273.759804) (xy 172.340356 -273.810021) (xy 172.340778 -273.835368) (xy 175.57623 -273.835368)
			(xy 175.576691 -273.804158) (xy 175.584515 -273.742231) (xy 175.600047 -273.681774) (xy 175.623042 -273.623744)
			(xy 175.653137 -273.569059) (xy 175.689855 -273.518581) (xy 175.732617 -273.47311) (xy 175.780746 -273.433363)
			(xy 175.806862 -273.416268) (xy 175.817022 -273.409918) (xy 175.829214 -273.390106) (xy 175.838866 -273.285966)
			(xy 175.830484 -273.264122) (xy 175.821594 -273.255994) (xy 175.80327 -273.238475) (xy 175.771128 -273.199273)
			(xy 175.744655 -273.156039) (xy 175.724351 -273.109588) (xy 175.710597 -273.060794) (xy 175.703652 -273.010577)
			(xy 175.70323 -272.98523) (xy 175.703649 -272.959912) (xy 175.710573 -272.909753) (xy 175.724294 -272.861013)
			(xy 175.744555 -272.814608) (xy 175.770974 -272.771412) (xy 175.803055 -272.732236) (xy 175.82134 -272.71472)
			(xy 175.83023 -272.706338) (xy 175.838612 -272.684748) (xy 175.829214 -272.580608) (xy 175.817022 -272.560796)
			(xy 175.806862 -272.554192) (xy 175.780744 -272.537126) (xy 175.732629 -272.497407) (xy 175.689878 -272.451965)
			(xy 175.653165 -272.401518) (xy 175.623073 -272.346863) (xy 175.600076 -272.288865) (xy 175.584538 -272.228439)
			(xy 175.576704 -272.166542) (xy 175.57623 -272.135346) (xy 175.576674 -272.104136) (xy 175.5845 -272.042207)
			(xy 175.600035 -271.98175) (xy 175.623033 -271.923721) (xy 175.65313 -271.869035) (xy 175.68985 -271.818558)
			(xy 175.732614 -271.773087) (xy 175.780745 -271.733341) (xy 175.806862 -271.716246) (xy 175.817022 -271.709896)
			(xy 175.829214 -271.690084) (xy 175.838866 -271.585944) (xy 175.830484 -271.5641) (xy 175.821594 -271.555972)
			(xy 175.80326 -271.538464) (xy 175.771118 -271.499259) (xy 175.744647 -271.456023) (xy 175.724344 -271.40957)
			(xy 175.710592 -271.360775) (xy 175.703651 -271.310556) (xy 175.70323 -271.285208) (xy 175.703634 -271.25989)
			(xy 175.710561 -271.20973) (xy 175.724285 -271.160989) (xy 175.744548 -271.114584) (xy 175.77097 -271.071388)
			(xy 175.803054 -271.032213) (xy 175.82134 -271.014698) (xy 175.83023 -271.006316) (xy 175.838612 -270.984726)
			(xy 175.829214 -270.880586) (xy 175.817022 -270.860774) (xy 175.806862 -270.85417) (xy 175.780734 -270.837119)
			(xy 175.732619 -270.797398) (xy 175.689868 -270.751953) (xy 175.653157 -270.701504) (xy 175.623066 -270.646847)
			(xy 175.60007 -270.588847) (xy 175.584534 -270.52842) (xy 175.576702 -270.46652) (xy 175.57623 -270.435324)
			(xy 175.576754 -270.402624) (xy 175.585364 -270.337792) (xy 175.602426 -270.274656) (xy 175.627643 -270.214312)
			(xy 175.660577 -270.157808) (xy 175.700655 -270.106126) (xy 175.72355 -270.082772) (xy 175.730916 -270.075406)
			(xy 175.738536 -270.056864) (xy 175.738536 -269.9639) (xy 175.730916 -269.945358) (xy 175.72355 -269.937992)
			(xy 175.70063 -269.914661) (xy 175.660548 -269.862978) (xy 175.627614 -269.80647) (xy 175.602401 -269.746121)
			(xy 175.585348 -269.682979) (xy 175.576751 -269.618142) (xy 175.57623 -269.58544) (xy 175.576669 -269.554229)
			(xy 175.584496 -269.492301) (xy 175.600032 -269.431844) (xy 175.62303 -269.373814) (xy 175.653128 -269.319128)
			(xy 175.689849 -269.268651) (xy 175.732613 -269.22318) (xy 175.780745 -269.183435) (xy 175.806862 -269.16634)
			(xy 175.817022 -269.15999) (xy 175.829214 -269.140178) (xy 175.838866 -269.036038) (xy 175.830484 -269.014194)
			(xy 175.821594 -269.006066) (xy 175.803257 -268.988561) (xy 175.771116 -268.949355) (xy 175.744645 -268.906119)
			(xy 175.724342 -268.859665) (xy 175.710591 -268.810869) (xy 175.70365 -268.76065) (xy 175.70323 -268.735302)
			(xy 175.70363 -268.709984) (xy 175.710557 -268.659824) (xy 175.724282 -268.611083) (xy 175.744547 -268.564678)
			(xy 175.770969 -268.521482) (xy 175.803053 -268.482307) (xy 175.82134 -268.464792) (xy 175.83023 -268.45641)
			(xy 175.838612 -268.43482) (xy 175.829214 -268.33068) (xy 175.817022 -268.310868) (xy 175.806862 -268.304264)
			(xy 175.780731 -268.287217) (xy 175.732616 -268.247495) (xy 175.689865 -268.20205) (xy 175.653154 -268.1516)
			(xy 175.623064 -268.096943) (xy 175.600069 -268.038942) (xy 175.584533 -267.978514) (xy 175.576702 -267.916614)
			(xy 175.57623 -267.885418) (xy 175.576652 -267.854207) (xy 175.584482 -267.792278) (xy 175.60002 -267.73182)
			(xy 175.623021 -267.67379) (xy 175.653121 -267.619105) (xy 175.689844 -267.568628) (xy 175.732611 -267.523157)
			(xy 175.780744 -267.483412) (xy 175.806862 -267.466318) (xy 175.817022 -267.459968) (xy 175.829214 -267.440156)
			(xy 175.838866 -267.336016) (xy 175.830484 -267.314172) (xy 175.821594 -267.306044) (xy 175.803246 -267.28855)
			(xy 175.771106 -267.249342) (xy 175.744636 -267.206103) (xy 175.724336 -267.159647) (xy 175.710587 -267.110849)
			(xy 175.703649 -267.060629) (xy 175.70323 -267.03528) (xy 175.703615 -267.009961) (xy 175.710546 -266.9598)
			(xy 175.724274 -266.911059) (xy 175.744541 -266.864655) (xy 175.770966 -266.821459) (xy 175.803052 -266.782285)
			(xy 175.82134 -266.76477) (xy 175.83023 -266.756388) (xy 175.838612 -266.734798) (xy 175.829214 -266.630658)
			(xy 175.817022 -266.610846) (xy 175.806862 -266.604242) (xy 175.780721 -266.58721) (xy 175.732606 -266.547486)
			(xy 175.689856 -266.502039) (xy 175.653146 -266.451587) (xy 175.623056 -266.396927) (xy 175.600063 -266.338924)
			(xy 175.584529 -266.278494) (xy 175.576701 -266.216593) (xy 175.57623 -266.185396) (xy 175.576713 -266.154187)
			(xy 175.584533 -266.09226) (xy 175.600062 -266.031804) (xy 175.623054 -265.973775) (xy 175.653145 -265.919089)
			(xy 175.689861 -265.868611) (xy 175.73262 -265.823139) (xy 175.780747 -265.783391) (xy 175.806862 -265.766296)
			(xy 175.817022 -265.759946) (xy 175.829214 -265.740134) (xy 175.838866 -265.635994) (xy 175.830484 -265.61415)
			(xy 175.821594 -265.606022) (xy 175.803284 -265.58849) (xy 175.77114 -265.54929) (xy 175.744666 -265.506059)
			(xy 175.724359 -265.459611) (xy 175.710602 -265.41082) (xy 175.703654 -265.360605) (xy 175.70323 -265.335258)
			(xy 175.703668 -265.309941) (xy 175.710587 -265.259783) (xy 175.724305 -265.211042) (xy 175.744563 -265.164638)
			(xy 175.770979 -265.121441) (xy 175.803057 -265.082265) (xy 175.82134 -265.064748) (xy 175.83023 -265.056366)
			(xy 175.838612 -265.034776) (xy 175.829214 -264.930636) (xy 175.817022 -264.910824) (xy 175.806862 -264.90422)
			(xy 175.780757 -264.887136) (xy 175.732642 -264.847419) (xy 175.68989 -264.80198) (xy 175.653177 -264.751535)
			(xy 175.623083 -264.696883) (xy 175.600083 -264.638888) (xy 175.584543 -264.578464) (xy 175.576706 -264.516569)
			(xy 175.57623 -264.485374) (xy 175.576696 -264.454164) (xy 175.584519 -264.392237) (xy 175.60005 -264.331781)
			(xy 175.623045 -264.273751) (xy 175.653138 -264.219065) (xy 175.689856 -264.168587) (xy 175.732617 -264.123116)
			(xy 175.780746 -264.083369) (xy 175.806862 -264.066274) (xy 175.817022 -264.059924) (xy 175.829214 -264.040112)
			(xy 175.838866 -263.935972) (xy 175.830484 -263.914128) (xy 175.821594 -263.906) (xy 175.803273 -263.888478)
			(xy 175.771131 -263.849276) (xy 175.744657 -263.806043) (xy 175.724352 -263.759593) (xy 175.710598 -263.7108)
			(xy 175.703653 -263.660583) (xy 175.70323 -263.635236) (xy 175.703653 -263.609919) (xy 175.710576 -263.559759)
			(xy 175.724296 -263.511019) (xy 175.744557 -263.464614) (xy 175.770975 -263.421418) (xy 175.803056 -263.382242)
			(xy 175.82134 -263.364726) (xy 175.83023 -263.356344) (xy 175.838612 -263.334754) (xy 175.829214 -263.230614)
			(xy 175.817022 -263.210802) (xy 175.806862 -263.204198) (xy 175.780747 -263.187128) (xy 175.732632 -263.14741)
			(xy 175.68988 -263.101968) (xy 175.653168 -263.051522) (xy 175.623075 -262.996868) (xy 175.600078 -262.93887)
			(xy 175.584539 -262.878445) (xy 175.576704 -262.816547) (xy 175.57623 -262.785352) (xy 175.576679 -262.754142)
			(xy 175.584504 -262.692214) (xy 175.600038 -262.631757) (xy 175.623035 -262.573727) (xy 175.653131 -262.519041)
			(xy 175.689851 -262.468564) (xy 175.732615 -262.423093) (xy 175.780745 -262.383347) (xy 175.806862 -262.366252)
			(xy 175.817022 -262.359902) (xy 175.829214 -262.34009) (xy 175.838866 -262.23595) (xy 175.830484 -262.214106)
			(xy 175.821594 -262.205978) (xy 175.803263 -262.188467) (xy 175.771121 -262.149263) (xy 175.744649 -262.106027)
			(xy 175.724346 -262.059575) (xy 175.710594 -262.01078) (xy 175.703651 -261.960562) (xy 175.70323 -261.935214)
			(xy 175.703638 -261.909896) (xy 175.710564 -261.859736) (xy 175.724287 -261.810995) (xy 175.74455 -261.764591)
			(xy 175.770971 -261.721395) (xy 175.803054 -261.68222) (xy 175.82134 -261.664704) (xy 175.83023 -261.656322)
			(xy 175.838612 -261.634732) (xy 175.829214 -261.530592) (xy 175.817022 -261.51078) (xy 175.806862 -261.504176)
			(xy 175.780737 -261.487121) (xy 175.732622 -261.4474) (xy 175.689871 -261.401957) (xy 175.653159 -261.351508)
			(xy 175.623068 -261.296852) (xy 175.600072 -261.238852) (xy 175.584535 -261.178425) (xy 175.576703 -261.116526)
			(xy 175.57623 -261.08533) (xy 175.576719 -261.054167) (xy 175.584531 -260.992333) (xy 175.600031 -260.931965)
			(xy 175.622974 -260.874017) (xy 175.653 -260.8194) (xy 175.689634 -260.768978) (xy 175.732299 -260.723544)
			(xy 175.780321 -260.683816) (xy 175.832945 -260.650421) (xy 175.889339 -260.623884) (xy 175.948614 -260.604624)
			(xy 176.009835 -260.592945) (xy 176.072038 -260.589032) (xy 176.134241 -260.592945) (xy 176.195462 -260.604624)
			(xy 176.254737 -260.623884) (xy 176.311131 -260.650421) (xy 176.363755 -260.683816) (xy 176.411777 -260.723544)
			(xy 176.454442 -260.768978) (xy 176.491076 -260.8194) (xy 176.521102 -260.874017) (xy 176.544045 -260.931965)
			(xy 176.559545 -260.992333) (xy 176.567357 -261.054167) (xy 176.567846 -261.08533) (xy 176.567333 -261.116526)
			(xy 176.559521 -261.178425) (xy 176.543997 -261.238854) (xy 176.521009 -261.296856) (xy 176.49092 -261.351512)
			(xy 176.454207 -261.401957) (xy 176.41145 -261.447393) (xy 176.363326 -261.487101) (xy 176.337214 -261.504176)
			(xy 176.327054 -261.51078) (xy 176.314862 -261.530592) (xy 176.305464 -261.634732) (xy 176.313846 -261.656322)
			(xy 176.322736 -261.664704) (xy 176.341029 -261.682211) (xy 176.373107 -261.72139) (xy 176.399524 -261.764589)
			(xy 176.419783 -261.810995) (xy 176.433504 -261.859736) (xy 176.440429 -261.909896) (xy 176.440846 -261.935214)
			(xy 176.440409 -261.960561) (xy 176.433476 -262.01078) (xy 176.419728 -262.059575) (xy 176.399426 -262.106027)
			(xy 176.372951 -262.149259) (xy 176.340803 -262.188457) (xy 176.322482 -262.205978) (xy 176.313592 -262.214106)
			(xy 176.30521 -262.23595) (xy 176.314862 -262.34009) (xy 176.327054 -262.359902) (xy 176.337214 -262.366252)
			(xy 176.363314 -262.383369) (xy 176.411435 -262.423119) (xy 176.454191 -262.46859) (xy 176.490906 -262.519066)
			(xy 176.521 -262.573747) (xy 176.543999 -262.631771) (xy 176.559538 -262.692222) (xy 176.567372 -262.754144)
			(xy 176.567846 -262.785352) (xy 176.567351 -262.816548) (xy 176.559535 -262.878449) (xy 176.544009 -262.938878)
			(xy 176.521019 -262.99688) (xy 176.490927 -263.051535) (xy 176.454212 -263.101981) (xy 176.411453 -263.147416)
			(xy 176.363327 -263.187124) (xy 176.337214 -263.204198) (xy 176.327054 -263.210802) (xy 176.314862 -263.230614)
			(xy 176.305464 -263.334754) (xy 176.313846 -263.356344) (xy 176.322736 -263.364726) (xy 176.34104 -263.382223)
			(xy 176.373117 -263.421404) (xy 176.399532 -263.464605) (xy 176.419789 -263.511013) (xy 176.433508 -263.559756)
			(xy 176.44043 -263.609918) (xy 176.440846 -263.635236) (xy 176.440424 -263.660584) (xy 176.433488 -263.710803)
			(xy 176.419737 -263.759598) (xy 176.399432 -263.80605) (xy 176.372955 -263.849282) (xy 176.340804 -263.888479)
			(xy 176.322482 -263.906) (xy 176.313592 -263.914128) (xy 176.30521 -263.935972) (xy 176.314862 -264.040112)
			(xy 176.327054 -264.059924) (xy 176.337214 -264.066274) (xy 176.363324 -264.083376) (xy 176.411445 -264.123128)
			(xy 176.454201 -264.168602) (xy 176.490915 -264.219079) (xy 176.521008 -264.273763) (xy 176.544004 -264.331789)
			(xy 176.559541 -264.392242) (xy 176.567373 -264.454165) (xy 176.567846 -264.485374) (xy 176.567368 -264.516571)
			(xy 176.55955 -264.578472) (xy 176.544021 -264.638902) (xy 176.521028 -264.696903) (xy 176.490934 -264.751559)
			(xy 176.454216 -264.802004) (xy 176.411455 -264.847439) (xy 176.363328 -264.887146) (xy 176.337214 -264.90422)
			(xy 176.327054 -264.910824) (xy 176.314862 -264.930636) (xy 176.305464 -265.034776) (xy 176.313846 -265.056366)
			(xy 176.322736 -265.064748) (xy 176.341002 -265.082283) (xy 176.373082 -265.121456) (xy 176.399503 -265.164649)
			(xy 176.419767 -265.211049) (xy 176.433493 -265.259786) (xy 176.440425 -265.309942) (xy 176.440846 -265.335258)
			(xy 176.440438 -265.360606) (xy 176.433499 -265.410826) (xy 176.419746 -265.459622) (xy 176.399438 -265.506073)
			(xy 176.372958 -265.549305) (xy 176.340805 -265.588501) (xy 176.322482 -265.606022) (xy 176.313592 -265.61415)
			(xy 176.30521 -265.635994) (xy 176.314862 -265.740134) (xy 176.327054 -265.759946) (xy 176.337214 -265.766296)
			(xy 176.363334 -265.783383) (xy 176.411455 -265.823137) (xy 176.45421 -265.868613) (xy 176.490923 -265.919093)
			(xy 176.521015 -265.973779) (xy 176.54401 -266.031807) (xy 176.559545 -266.092261) (xy 176.567375 -266.154187)
			(xy 176.567846 -266.185396) (xy 176.567385 -266.216593) (xy 176.559564 -266.278495) (xy 176.544033 -266.338925)
			(xy 176.521037 -266.396927) (xy 176.490941 -266.451583) (xy 176.454221 -266.502027) (xy 176.411458 -266.547462)
			(xy 176.363329 -266.587168) (xy 176.337214 -266.604242) (xy 176.327054 -266.610846) (xy 176.314862 -266.630658)
			(xy 176.305464 -266.734798) (xy 176.313846 -266.756388) (xy 176.322736 -266.76477) (xy 176.341013 -266.782294)
			(xy 176.373092 -266.821469) (xy 176.399511 -266.864664) (xy 176.419773 -266.911067) (xy 176.433498 -266.959806)
			(xy 176.440426 -267.009963) (xy 176.440846 -267.03528) (xy 176.440387 -267.060627) (xy 176.433458 -267.110844)
			(xy 176.419715 -267.159639) (xy 176.399417 -267.20609) (xy 176.372946 -267.249323) (xy 176.340802 -267.288522)
			(xy 176.322482 -267.306044) (xy 176.313592 -267.314172) (xy 176.30521 -267.336016) (xy 176.314862 -267.440156)
			(xy 176.327054 -267.459968) (xy 176.337214 -267.466318) (xy 176.363344 -267.483391) (xy 176.411465 -267.523147)
			(xy 176.45422 -267.568625) (xy 176.490932 -267.619107) (xy 176.521023 -267.673795) (xy 176.544016 -267.731825)
			(xy 176.559549 -267.792281) (xy 176.567376 -267.854208) (xy 176.567846 -267.885418) (xy 176.567402 -267.916616)
			(xy 176.559579 -267.978518) (xy 176.544045 -268.038949) (xy 176.521047 -268.096951) (xy 176.490948 -268.151607)
			(xy 176.454226 -268.202051) (xy 176.411461 -268.247485) (xy 176.363329 -268.287191) (xy 176.337214 -268.304264)
			(xy 176.327054 -268.310868) (xy 176.314862 -268.33068) (xy 176.305464 -268.43482) (xy 176.313846 -268.45641)
			(xy 176.322736 -268.464792) (xy 176.341023 -268.482305) (xy 176.373102 -268.521483) (xy 176.399519 -268.56468)
			(xy 176.41978 -268.611085) (xy 176.433502 -268.659825) (xy 176.440428 -268.709985) (xy 176.440846 -268.735302)
			(xy 176.440401 -268.760649) (xy 176.43347 -268.810867) (xy 176.419724 -268.859662) (xy 176.399423 -268.906114)
			(xy 176.372949 -268.949346) (xy 176.340803 -268.988544) (xy 176.322482 -269.006066) (xy 176.313592 -269.014194)
			(xy 176.30521 -269.036038) (xy 176.314862 -269.140178) (xy 176.327054 -269.15999) (xy 176.337214 -269.16634)
			(xy 176.363308 -269.183465) (xy 176.41143 -269.223214) (xy 176.454186 -269.268684) (xy 176.490901 -269.319158)
			(xy 176.520996 -269.373838) (xy 176.543995 -269.431862) (xy 176.559536 -269.492311) (xy 176.567371 -269.554232)
			(xy 176.567846 -269.58544) (xy 176.567306 -269.61814) (xy 176.5587 -269.682971) (xy 176.541641 -269.746107)
			(xy 176.516428 -269.806452) (xy 176.483497 -269.862956) (xy 176.44342 -269.914638) (xy 176.420526 -269.937992)
			(xy 176.41316 -269.945358) (xy 176.40554 -269.9639) (xy 176.40554 -270.056864) (xy 176.41316 -270.075406)
			(xy 176.420526 -270.082772) (xy 176.443425 -270.106123) (xy 176.48351 -270.157802) (xy 176.516447 -270.214305)
			(xy 176.541663 -270.27465) (xy 176.558721 -270.337789) (xy 176.567323 -270.402623) (xy 176.567846 -270.435324)
			(xy 176.567407 -270.466522) (xy 176.559583 -270.528425) (xy 176.544048 -270.588855) (xy 176.521049 -270.646857)
			(xy 176.49095 -270.701513) (xy 176.454227 -270.751957) (xy 176.411461 -270.797391) (xy 176.36333 -270.837097)
			(xy 176.337214 -270.85417) (xy 176.327054 -270.860774) (xy 176.314862 -270.880586) (xy 176.305464 -270.984726)
			(xy 176.313846 -271.006316) (xy 176.322736 -271.014698) (xy 176.341026 -271.032208) (xy 176.373104 -271.071387)
			(xy 176.399521 -271.114585) (xy 176.419781 -271.16099) (xy 176.433503 -271.209731) (xy 176.440428 -271.25989)
			(xy 176.440846 -271.285208) (xy 176.440405 -271.310555) (xy 176.433473 -271.360773) (xy 176.419726 -271.409568)
			(xy 176.399424 -271.45602) (xy 176.37295 -271.499253) (xy 176.340803 -271.538451) (xy 176.322482 -271.555972)
			(xy 176.313592 -271.5641) (xy 176.30521 -271.585944) (xy 176.314862 -271.690084) (xy 176.327054 -271.709896)
			(xy 176.337214 -271.716246) (xy 176.363311 -271.733367) (xy 176.411432 -271.773116) (xy 176.454188 -271.818587)
			(xy 176.490904 -271.869062) (xy 176.520998 -271.923743) (xy 176.543997 -271.981766) (xy 176.559537 -272.042217)
			(xy 176.567372 -272.104138) (xy 176.567846 -272.135346) (xy 176.567346 -272.166542) (xy 176.559531 -272.228442)
			(xy 176.544006 -272.288871) (xy 176.521016 -272.346873) (xy 176.490925 -272.401529) (xy 176.45421 -272.451974)
			(xy 176.411452 -272.49741) (xy 176.363327 -272.537118) (xy 176.337214 -272.554192) (xy 176.327054 -272.560796)
			(xy 176.314862 -272.580608) (xy 176.305464 -272.684748) (xy 176.313846 -272.706338) (xy 176.322736 -272.71472)
			(xy 176.341037 -272.73222) (xy 176.373114 -272.7714) (xy 176.39953 -272.814601) (xy 176.419788 -272.861008)
			(xy 176.433507 -272.909751) (xy 176.44043 -272.959912) (xy 176.440846 -272.98523) (xy 176.44042 -273.010578)
			(xy 176.433484 -273.060797) (xy 176.419735 -273.109592) (xy 176.39943 -273.156043) (xy 176.372954 -273.199276)
			(xy 176.340804 -273.238473) (xy 176.322482 -273.255994) (xy 176.313592 -273.264122) (xy 176.30521 -273.285966)
			(xy 176.314862 -273.390106) (xy 176.327054 -273.409918) (xy 176.337214 -273.416268) (xy 176.363321 -273.433374)
			(xy 176.411442 -273.473126) (xy 176.454198 -273.518599) (xy 176.490912 -273.569076) (xy 176.521006 -273.623759)
			(xy 176.544003 -273.681784) (xy 176.55954 -273.742236) (xy 176.567373 -273.80416) (xy 176.567846 -273.835368)
			(xy 176.567357 -273.866531) (xy 176.559545 -273.928365) (xy 176.544045 -273.988733) (xy 176.521102 -274.046681)
			(xy 176.491076 -274.101298) (xy 176.454442 -274.15172) (xy 176.411777 -274.197154) (xy 176.363755 -274.236882)
			(xy 176.311131 -274.270277) (xy 176.254737 -274.296814) (xy 176.195462 -274.316074) (xy 176.134241 -274.327753)
			(xy 176.072038 -274.331666) (xy 176.009835 -274.327753) (xy 175.948614 -274.316074) (xy 175.889339 -274.296814)
			(xy 175.832945 -274.270277) (xy 175.780321 -274.236882) (xy 175.732299 -274.197154) (xy 175.689634 -274.15172)
			(xy 175.653 -274.101298) (xy 175.622974 -274.046681) (xy 175.600031 -273.988733) (xy 175.584531 -273.928365)
			(xy 175.576719 -273.866531) (xy 175.57623 -273.835368) (xy 172.340778 -273.835368) (xy 172.340356 -273.860685)
			(xy 172.333432 -273.910845) (xy 172.319712 -273.959585) (xy 172.299451 -274.00599) (xy 172.273033 -274.049186)
			(xy 172.240953 -274.088362) (xy 172.222668 -274.105878) (xy 172.213778 -274.11426) (xy 172.205396 -274.13585)
			(xy 172.214794 -274.23999) (xy 172.226986 -274.259802) (xy 172.237146 -274.266406) (xy 172.263242 -274.283505)
			(xy 172.311361 -274.323216) (xy 172.354117 -274.368651) (xy 172.390833 -274.419093) (xy 172.420928 -274.473744)
			(xy 172.443928 -274.531739) (xy 172.459469 -274.592162) (xy 172.467304 -274.654057) (xy 172.467778 -274.685252)
			(xy 174.318437 -274.685252) (xy 174.322372 -274.631481) (xy 174.334095 -274.578857) (xy 174.353355 -274.5285)
			(xy 174.379741 -274.481483) (xy 174.412693 -274.43881) (xy 174.451506 -274.401389) (xy 174.495354 -274.370019)
			(xy 174.543302 -274.345367) (xy 174.594329 -274.327959) (xy 174.647347 -274.318166) (xy 174.701226 -274.316197)
			(xy 174.754817 -274.322094) (xy 174.806978 -274.33573) (xy 174.856598 -274.356817) (xy 174.902619 -274.384903)
			(xy 174.944061 -274.419391) (xy 174.980039 -274.459545) (xy 175.009787 -274.504509) (xy 175.032672 -274.553326)
			(xy 175.048204 -274.604955) (xy 175.056054 -274.658295) (xy 175.056546 -274.685252) (xy 179.020216 -274.685252)
			(xy 179.020686 -274.654055) (xy 179.028502 -274.592152) (xy 179.04403 -274.531721) (xy 179.067023 -274.473718)
			(xy 179.097118 -274.419062) (xy 179.133838 -274.368617) (xy 179.176602 -274.323183) (xy 179.224733 -274.283478)
			(xy 179.250848 -274.266406) (xy 179.261008 -274.259802) (xy 179.2732 -274.23999) (xy 179.282598 -274.13585)
			(xy 179.274216 -274.11426) (xy 179.265326 -274.105878) (xy 179.247017 -274.088387) (xy 179.214942 -274.049203)
			(xy 179.188528 -274.006001) (xy 179.168272 -273.959592) (xy 179.154554 -273.910848) (xy 179.147632 -273.860687)
			(xy 179.147216 -273.835368) (xy 179.147621 -273.810019) (xy 179.154558 -273.759799) (xy 179.16831 -273.711002)
			(xy 179.188619 -273.66455) (xy 179.2151 -273.621319) (xy 179.247255 -273.582123) (xy 179.26558 -273.564604)
			(xy 179.27447 -273.556476) (xy 179.282852 -273.534632) (xy 179.2732 -273.430492) (xy 179.261008 -273.41068)
			(xy 179.250848 -273.40433) (xy 179.224731 -273.387239) (xy 179.176611 -273.347484) (xy 179.133857 -273.302008)
			(xy 179.097145 -273.251529) (xy 179.067053 -273.196844) (xy 179.044057 -273.138816) (xy 179.02852 -273.078363)
			(xy 179.020688 -273.016439) (xy 179.020216 -272.98523) (xy 179.020669 -272.954032) (xy 179.028487 -272.892129)
			(xy 179.044018 -272.831697) (xy 179.067013 -272.773694) (xy 179.097111 -272.719038) (xy 179.133833 -272.668594)
			(xy 179.176599 -272.62316) (xy 179.224732 -272.583456) (xy 179.250848 -272.566384) (xy 179.261008 -272.55978)
			(xy 179.2732 -272.539968) (xy 179.282598 -272.435828) (xy 179.274216 -272.414238) (xy 179.265326 -272.405856)
			(xy 179.247055 -272.388327) (xy 179.214976 -272.349152) (xy 179.188558 -272.305957) (xy 179.168295 -272.259556)
			(xy 179.154569 -272.210819) (xy 179.147637 -272.160662) (xy 179.147216 -272.135346) (xy 179.147606 -272.109997)
			(xy 179.154546 -272.059776) (xy 179.168302 -272.010979) (xy 179.188613 -271.964527) (xy 179.215097 -271.921296)
			(xy 179.247254 -271.882101) (xy 179.26558 -271.864582) (xy 179.27447 -271.856454) (xy 179.282852 -271.83461)
			(xy 179.2732 -271.73047) (xy 179.261008 -271.710658) (xy 179.250848 -271.704308) (xy 179.224721 -271.687231)
			(xy 179.176601 -271.647474) (xy 179.133848 -271.601996) (xy 179.097136 -271.551515) (xy 179.067045 -271.496828)
			(xy 179.044051 -271.438798) (xy 179.028517 -271.378343) (xy 179.020687 -271.316417) (xy 179.020216 -271.285208)
			(xy 179.020704 -271.252506) (xy 179.029318 -271.187672) (xy 179.046386 -271.124534) (xy 179.071609 -271.06419)
			(xy 179.10455 -271.007687) (xy 179.144637 -270.956008) (xy 179.167536 -270.932656) (xy 179.174902 -270.92529)
			(xy 179.182522 -270.906748) (xy 179.182522 -270.813784) (xy 179.174902 -270.795242) (xy 179.167536 -270.787876)
			(xy 179.144654 -270.764509) (xy 179.104568 -270.712834) (xy 179.07163 -270.656334) (xy 179.046411 -270.595991)
			(xy 179.029349 -270.532856) (xy 179.020742 -270.468024) (xy 179.020216 -270.435324) (xy 179.020664 -270.404126)
			(xy 179.028483 -270.342223) (xy 179.044014 -270.281791) (xy 179.067011 -270.223788) (xy 179.097109 -270.169132)
			(xy 179.133832 -270.118687) (xy 179.176598 -270.073254) (xy 179.224731 -270.03355) (xy 179.250848 -270.016478)
			(xy 179.261008 -270.009874) (xy 179.2732 -269.990062) (xy 179.282598 -269.885922) (xy 179.274216 -269.864332)
			(xy 179.265326 -269.85595) (xy 179.247052 -269.838424) (xy 179.214974 -269.799248) (xy 179.188555 -269.756053)
			(xy 179.168293 -269.709651) (xy 179.154568 -269.660913) (xy 179.147637 -269.610757) (xy 179.147216 -269.58544)
			(xy 179.147602 -269.560091) (xy 179.154543 -269.509869) (xy 179.168299 -269.461073) (xy 179.188611 -269.414621)
			(xy 179.215096 -269.37139) (xy 179.247254 -269.332195) (xy 179.26558 -269.314676) (xy 179.27447 -269.306548)
			(xy 179.282852 -269.284704) (xy 179.2732 -269.180564) (xy 179.261008 -269.160752) (xy 179.250848 -269.154402)
			(xy 179.224718 -269.137329) (xy 179.176599 -269.097572) (xy 179.133845 -269.052093) (xy 179.097134 -269.001611)
			(xy 179.067043 -268.946923) (xy 179.04405 -268.888894) (xy 179.028516 -268.828438) (xy 179.020687 -268.766512)
			(xy 179.020216 -268.735302) (xy 179.020647 -268.704104) (xy 179.028469 -268.642199) (xy 179.044003 -268.581767)
			(xy 179.067002 -268.523764) (xy 179.097102 -268.469108) (xy 179.133827 -268.418664) (xy 179.176596 -268.373231)
			(xy 179.224731 -268.333528) (xy 179.250848 -268.316456) (xy 179.261008 -268.309852) (xy 179.2732 -268.29004)
			(xy 179.282598 -268.1859) (xy 179.274216 -268.16431) (xy 179.265326 -268.155928) (xy 179.247041 -268.138412)
			(xy 179.214964 -268.099234) (xy 179.188547 -268.056037) (xy 179.168287 -268.009633) (xy 179.154563 -267.960894)
			(xy 179.147635 -267.910735) (xy 179.147216 -267.885418) (xy 179.147654 -267.86007) (xy 179.154585 -267.809851)
			(xy 179.16833 -267.761055) (xy 179.188633 -267.714603) (xy 179.215108 -267.671371) (xy 179.247258 -267.632174)
			(xy 179.26558 -267.614654) (xy 179.27447 -267.606526) (xy 179.282852 -267.584682) (xy 179.2732 -267.480542)
			(xy 179.261008 -267.46073) (xy 179.250848 -267.45438) (xy 179.224708 -267.437322) (xy 179.176589 -267.397563)
			(xy 179.133836 -267.352081) (xy 179.097125 -267.301597) (xy 179.067036 -267.246908) (xy 179.044044 -267.188876)
			(xy 179.028512 -267.128418) (xy 179.020685 -267.06649) (xy 179.020216 -267.03528) (xy 179.020629 -267.004081)
			(xy 179.028454 -266.942176) (xy 179.043991 -266.881744) (xy 179.066992 -266.82374) (xy 179.097095 -266.769084)
			(xy 179.133822 -266.718641) (xy 179.176593 -266.673208) (xy 179.22473 -266.633505) (xy 179.250848 -266.616434)
			(xy 179.261008 -266.60983) (xy 179.2732 -266.590018) (xy 179.282598 -266.485878) (xy 179.274216 -266.464288)
			(xy 179.265326 -266.455906) (xy 179.24703 -266.438401) (xy 179.214954 -266.399221) (xy 179.188539 -266.356021)
			(xy 179.16828 -266.309615) (xy 179.154559 -266.260874) (xy 179.147634 -266.210714) (xy 179.147216 -266.185396)
			(xy 179.14764 -266.160048) (xy 179.154573 -266.109828) (xy 179.168322 -266.061032) (xy 179.188626 -266.01458)
			(xy 179.215105 -265.971348) (xy 179.247256 -265.932152) (xy 179.26558 -265.914632) (xy 179.27447 -265.906504)
			(xy 179.282852 -265.88466) (xy 179.2732 -265.78052) (xy 179.261008 -265.760708) (xy 179.250848 -265.754358)
			(xy 179.224744 -265.737248) (xy 179.176624 -265.697496) (xy 179.13387 -265.652022) (xy 179.097156 -265.601546)
			(xy 179.067062 -265.546864) (xy 179.044064 -265.488839) (xy 179.028525 -265.428388) (xy 179.02069 -265.366466)
			(xy 179.020216 -265.335258) (xy 179.020691 -265.304061) (xy 179.028506 -265.242158) (xy 179.044033 -265.181727)
			(xy 179.067025 -265.123725) (xy 179.09712 -265.069068) (xy 179.133839 -265.018623) (xy 179.176602 -264.973189)
			(xy 179.224733 -264.933484) (xy 179.250848 -264.916412) (xy 179.261008 -264.909808) (xy 179.2732 -264.889996)
			(xy 179.282598 -264.785856) (xy 179.274216 -264.764266) (xy 179.265326 -264.755884) (xy 179.24702 -264.73839)
			(xy 179.214945 -264.699207) (xy 179.188531 -264.656005) (xy 179.168274 -264.609597) (xy 179.154555 -264.560854)
			(xy 179.147633 -264.510692) (xy 179.147216 -264.485374) (xy 179.147625 -264.460025) (xy 179.154561 -264.409805)
			(xy 179.168313 -264.361009) (xy 179.18862 -264.314557) (xy 179.215101 -264.271325) (xy 179.247255 -264.23213)
			(xy 179.26558 -264.21461) (xy 179.27447 -264.206482) (xy 179.282852 -264.184638) (xy 179.2732 -264.080498)
			(xy 179.261008 -264.060686) (xy 179.250848 -264.054336) (xy 179.224734 -264.037241) (xy 179.176614 -263.997486)
			(xy 179.13386 -263.952011) (xy 179.097147 -263.901532) (xy 179.067055 -263.846848) (xy 179.044059 -263.788821)
			(xy 179.028521 -263.728369) (xy 179.020689 -263.666445) (xy 179.020216 -263.635236) (xy 179.020673 -263.604038)
			(xy 179.028491 -263.542135) (xy 179.044021 -263.481704) (xy 179.067016 -263.423701) (xy 179.097113 -263.369044)
			(xy 179.133834 -263.3186) (xy 179.1766 -263.273166) (xy 179.224732 -263.233462) (xy 179.250848 -263.21639)
			(xy 179.261008 -263.209786) (xy 179.2732 -263.189974) (xy 179.282598 -263.085834) (xy 179.274216 -263.064244)
			(xy 179.265326 -263.055862) (xy 179.247058 -263.03833) (xy 179.214979 -262.999155) (xy 179.18856 -262.955962)
			(xy 179.168297 -262.909561) (xy 179.15457 -262.860824) (xy 179.147638 -262.810668) (xy 179.147216 -262.785352)
			(xy 179.14761 -262.760003) (xy 179.15455 -262.709782) (xy 179.168304 -262.660985) (xy 179.188614 -262.614533)
			(xy 179.215098 -262.571302) (xy 179.247254 -262.532107) (xy 179.26558 -262.514588) (xy 179.27447 -262.50646)
			(xy 179.282852 -262.484616) (xy 179.2732 -262.380476) (xy 179.261008 -262.360664) (xy 179.250848 -262.354314)
			(xy 179.224724 -262.337233) (xy 179.176604 -262.297477) (xy 179.13385 -262.251999) (xy 179.097138 -262.201519)
			(xy 179.067047 -262.146832) (xy 179.044053 -262.088803) (xy 179.028518 -262.028349) (xy 179.020687 -261.966423)
			(xy 179.020216 -261.935214) (xy 179.020705 -261.904051) (xy 179.028517 -261.842217) (xy 179.044017 -261.781849)
			(xy 179.06696 -261.723901) (xy 179.096986 -261.669284) (xy 179.13362 -261.618862) (xy 179.176285 -261.573428)
			(xy 179.224307 -261.5337) (xy 179.276931 -261.500305) (xy 179.333325 -261.473768) (xy 179.3926 -261.454508)
			(xy 179.453821 -261.442829) (xy 179.516024 -261.438916) (xy 179.578227 -261.442829) (xy 179.639448 -261.454508)
			(xy 179.698723 -261.473768) (xy 179.755117 -261.500305) (xy 179.807741 -261.5337) (xy 179.855763 -261.573428)
			(xy 179.898428 -261.618862) (xy 179.935062 -261.669284) (xy 179.965088 -261.723901) (xy 179.988031 -261.781849)
			(xy 180.003531 -261.842217) (xy 180.011343 -261.904051) (xy 180.011832 -261.935214) (xy 180.011328 -261.966422)
			(xy 180.003508 -262.028347) (xy 179.98798 -262.088801) (xy 179.96499 -262.14683) (xy 179.934902 -262.201515)
			(xy 179.89819 -262.251993) (xy 179.855435 -262.297467) (xy 179.807312 -262.337217) (xy 179.7812 -262.354314)
			(xy 179.77104 -262.360664) (xy 179.758848 -262.380476) (xy 179.749196 -262.484616) (xy 179.757578 -262.50646)
			(xy 179.766468 -262.514588) (xy 179.784776 -262.532123) (xy 179.816921 -262.571321) (xy 179.843397 -262.614551)
			(xy 179.863704 -262.660999) (xy 179.877461 -262.70979) (xy 179.884409 -262.760005) (xy 179.884832 -262.785352)
			(xy 179.884413 -262.81067) (xy 179.877491 -262.86083) (xy 179.863771 -262.90957) (xy 179.84351 -262.955975)
			(xy 179.81709 -262.999172) (xy 179.785008 -263.038346) (xy 179.766722 -263.055862) (xy 179.757832 -263.064244)
			(xy 179.74945 -263.085834) (xy 179.758848 -263.189974) (xy 179.77104 -263.209786) (xy 179.7812 -263.21639)
			(xy 179.807301 -263.233481) (xy 179.855418 -263.273195) (xy 179.898171 -263.318633) (xy 179.934886 -263.369076)
			(xy 179.96498 -263.423727) (xy 179.98798 -263.481723) (xy 180.003521 -263.542146) (xy 180.011357 -263.604041)
			(xy 180.011832 -263.635236) (xy 180.011345 -263.666445) (xy 180.003522 -263.72837) (xy 179.987992 -263.788825)
			(xy 179.965 -263.846853) (xy 179.934909 -263.901539) (xy 179.898195 -263.952017) (xy 179.855438 -263.99749)
			(xy 179.807313 -264.037239) (xy 179.7812 -264.054336) (xy 179.77104 -264.060686) (xy 179.758848 -264.080498)
			(xy 179.749196 -264.184638) (xy 179.757578 -264.206482) (xy 179.766468 -264.21461) (xy 179.784786 -264.232134)
			(xy 179.816931 -264.271335) (xy 179.843405 -264.314567) (xy 179.863711 -264.361017) (xy 179.877465 -264.40981)
			(xy 179.88441 -264.460027) (xy 179.884832 -264.485374) (xy 179.884428 -264.510692) (xy 179.877503 -264.560853)
			(xy 179.863779 -264.609594) (xy 179.843516 -264.655999) (xy 179.817093 -264.699195) (xy 179.785009 -264.738369)
			(xy 179.766722 -264.755884) (xy 179.757832 -264.764266) (xy 179.74945 -264.785856) (xy 179.758848 -264.889996)
			(xy 179.77104 -264.909808) (xy 179.7812 -264.916412) (xy 179.807311 -264.933488) (xy 179.855428 -264.973204)
			(xy 179.898181 -265.018644) (xy 179.934894 -265.06909) (xy 179.964988 -265.123743) (xy 179.987986 -265.181741)
			(xy 180.003524 -265.242166) (xy 180.011358 -265.304063) (xy 180.011832 -265.335258) (xy 180.011362 -265.366467)
			(xy 180.003537 -265.428393) (xy 179.988004 -265.488848) (xy 179.965009 -265.546877) (xy 179.934916 -265.601562)
			(xy 179.898199 -265.65204) (xy 179.85544 -265.697513) (xy 179.807314 -265.737261) (xy 179.7812 -265.754358)
			(xy 179.77104 -265.760708) (xy 179.758848 -265.78052) (xy 179.749196 -265.88466) (xy 179.757578 -265.906504)
			(xy 179.766468 -265.914632) (xy 179.784797 -265.932146) (xy 179.81694 -265.971348) (xy 179.843413 -266.014583)
			(xy 179.863717 -266.061035) (xy 179.87747 -266.10983) (xy 179.884411 -266.160048) (xy 179.884832 -266.185396)
			(xy 179.884442 -266.210715) (xy 179.877514 -266.260876) (xy 179.863788 -266.309617) (xy 179.843522 -266.356022)
			(xy 179.817097 -266.399218) (xy 179.78501 -266.438391) (xy 179.766722 -266.455906) (xy 179.757832 -266.464288)
			(xy 179.74945 -266.485878) (xy 179.758848 -266.590018) (xy 179.77104 -266.60983) (xy 179.7812 -266.616434)
			(xy 179.807321 -266.633495) (xy 179.855438 -266.673214) (xy 179.89819 -266.718656) (xy 179.934903 -266.769103)
			(xy 179.964995 -266.823759) (xy 179.987992 -266.881759) (xy 180.003528 -266.942185) (xy 180.01136 -267.004084)
			(xy 180.011832 -267.03528) (xy 180.01138 -267.06649) (xy 180.003551 -267.128417) (xy 179.988016 -267.188872)
			(xy 179.965018 -267.246901) (xy 179.934922 -267.301586) (xy 179.898204 -267.352063) (xy 179.855443 -267.397536)
			(xy 179.807315 -267.437284) (xy 179.7812 -267.45438) (xy 179.77104 -267.46073) (xy 179.758848 -267.480542)
			(xy 179.749196 -267.584682) (xy 179.757578 -267.606526) (xy 179.766468 -267.614654) (xy 179.784808 -267.632157)
			(xy 179.81695 -267.671362) (xy 179.843422 -267.714599) (xy 179.863724 -267.761053) (xy 179.877474 -267.80985)
			(xy 179.884413 -267.86007) (xy 179.884832 -267.885418) (xy 179.884458 -267.910737) (xy 179.877527 -267.960899)
			(xy 179.863797 -268.009641) (xy 179.843528 -268.056046) (xy 179.817101 -268.099241) (xy 179.785011 -268.138414)
			(xy 179.766722 -268.155928) (xy 179.757832 -268.16431) (xy 179.74945 -268.1859) (xy 179.758848 -268.29004)
			(xy 179.77104 -268.309852) (xy 179.7812 -268.316456) (xy 179.807331 -268.333503) (xy 179.855448 -268.373223)
			(xy 179.8982 -268.418667) (xy 179.934912 -268.469117) (xy 179.965003 -268.523775) (xy 179.987997 -268.581776)
			(xy 180.003532 -268.642205) (xy 180.011361 -268.704105) (xy 180.011832 -268.735302) (xy 180.011319 -268.76651)
			(xy 180.0035 -268.828434) (xy 179.987974 -268.888888) (xy 179.964985 -268.946917) (xy 179.934898 -269.001602)
			(xy 179.898187 -269.052081) (xy 179.855433 -269.097554) (xy 179.807312 -269.137305) (xy 179.7812 -269.154402)
			(xy 179.77104 -269.160752) (xy 179.758848 -269.180564) (xy 179.749196 -269.284704) (xy 179.757578 -269.306548)
			(xy 179.766468 -269.314676) (xy 179.78477 -269.332217) (xy 179.816916 -269.371414) (xy 179.843392 -269.414643)
			(xy 179.863701 -269.461089) (xy 179.877459 -269.509879) (xy 179.884408 -269.560094) (xy 179.884832 -269.58544)
			(xy 179.884405 -269.610757) (xy 179.877485 -269.660917) (xy 179.863766 -269.709658) (xy 179.843506 -269.756063)
			(xy 179.817088 -269.799259) (xy 179.785007 -269.838434) (xy 179.766722 -269.85595) (xy 179.757832 -269.864332)
			(xy 179.74945 -269.885922) (xy 179.758848 -269.990062) (xy 179.77104 -270.009874) (xy 179.7812 -270.016478)
			(xy 179.807295 -270.033577) (xy 179.855412 -270.07329) (xy 179.898166 -270.118726) (xy 179.934881 -270.169169)
			(xy 179.964976 -270.223819) (xy 179.987977 -270.281813) (xy 180.003519 -270.342235) (xy 180.011356 -270.40413)
			(xy 180.011832 -270.435324) (xy 180.011286 -270.468024) (xy 180.002681 -270.532855) (xy 179.985625 -270.595991)
			(xy 179.960412 -270.656336) (xy 179.927482 -270.71284) (xy 179.887406 -270.764522) (xy 179.864512 -270.787876)
			(xy 179.857146 -270.795242) (xy 179.849526 -270.813784) (xy 179.849526 -270.906748) (xy 179.857146 -270.92529)
			(xy 179.864512 -270.932656) (xy 179.8874 -270.956017) (xy 179.927487 -271.007693) (xy 179.960426 -271.064194)
			(xy 179.985644 -271.124537) (xy 180.002704 -271.187675) (xy 180.011308 -271.252507) (xy 180.011832 -271.285208)
			(xy 180.011323 -271.316416) (xy 180.003504 -271.378341) (xy 179.987977 -271.438795) (xy 179.964988 -271.496823)
			(xy 179.9349 -271.551509) (xy 179.898188 -271.601987) (xy 179.855434 -271.647461) (xy 179.807312 -271.687211)
			(xy 179.7812 -271.704308) (xy 179.77104 -271.710658) (xy 179.758848 -271.73047) (xy 179.749196 -271.83461)
			(xy 179.757578 -271.856454) (xy 179.766468 -271.864582) (xy 179.784773 -271.88212) (xy 179.816918 -271.921317)
			(xy 179.843395 -271.964547) (xy 179.863703 -272.010994) (xy 179.87746 -272.059785) (xy 179.884408 -272.11)
			(xy 179.884832 -272.135346) (xy 179.884409 -272.160664) (xy 179.877488 -272.210823) (xy 179.863768 -272.259564)
			(xy 179.843508 -272.305969) (xy 179.817089 -272.349165) (xy 179.785007 -272.38834) (xy 179.766722 -272.405856)
			(xy 179.757832 -272.414238) (xy 179.74945 -272.435828) (xy 179.758848 -272.539968) (xy 179.77104 -272.55978)
			(xy 179.7812 -272.566384) (xy 179.807298 -272.583479) (xy 179.855415 -272.623192) (xy 179.898169 -272.66863)
			(xy 179.934883 -272.719072) (xy 179.964978 -272.773723) (xy 179.987978 -272.831718) (xy 180.00352 -272.89214)
			(xy 180.011357 -272.954035) (xy 180.011832 -272.98523) (xy 180.01134 -273.016439) (xy 180.003518 -273.078364)
			(xy 179.987989 -273.138818) (xy 179.964997 -273.196847) (xy 179.934907 -273.251532) (xy 179.898193 -273.30201)
			(xy 179.855437 -273.347483) (xy 179.807313 -273.387233) (xy 179.7812 -273.40433) (xy 179.77104 -273.41068)
			(xy 179.758848 -273.430492) (xy 179.749196 -273.534632) (xy 179.757578 -273.556476) (xy 179.766468 -273.564604)
			(xy 179.784783 -273.582131) (xy 179.816928 -273.621331) (xy 179.843403 -273.664563) (xy 179.863709 -273.711012)
			(xy 179.877464 -273.759805) (xy 179.88441 -273.810021) (xy 179.884832 -273.835368) (xy 183.120284 -273.835368)
			(xy 183.120767 -273.804159) (xy 183.128589 -273.742233) (xy 183.14412 -273.681778) (xy 183.167112 -273.623749)
			(xy 183.197204 -273.569064) (xy 183.233919 -273.518586) (xy 183.276677 -273.473113) (xy 183.324802 -273.433364)
			(xy 183.350916 -273.416268) (xy 183.361076 -273.409918) (xy 183.373268 -273.390106) (xy 183.38292 -273.285966)
			(xy 183.374538 -273.264122) (xy 183.365648 -273.255994) (xy 183.347335 -273.238465) (xy 183.315189 -273.199266)
			(xy 183.288714 -273.156034) (xy 183.268407 -273.109585) (xy 183.254652 -273.060793) (xy 183.247706 -273.010577)
			(xy 183.247284 -272.98523) (xy 183.247717 -272.959913) (xy 183.25464 -272.909755) (xy 183.268359 -272.861015)
			(xy 183.288618 -272.814611) (xy 183.315034 -272.771414) (xy 183.347111 -272.732237) (xy 183.365394 -272.71472)
			(xy 183.374284 -272.706338) (xy 183.382666 -272.684748) (xy 183.373268 -272.580608) (xy 183.361076 -272.560796)
			(xy 183.350916 -272.554192) (xy 183.324811 -272.537108) (xy 183.276693 -272.497393) (xy 183.233939 -272.451955)
			(xy 183.197225 -272.401511) (xy 183.16713 -272.346858) (xy 183.144132 -272.288862) (xy 183.128592 -272.228438)
			(xy 183.120758 -272.166541) (xy 183.120284 -272.135346) (xy 183.120749 -272.104136) (xy 183.128575 -272.04221)
			(xy 183.144108 -271.981754) (xy 183.167103 -271.923725) (xy 183.197197 -271.86904) (xy 183.233914 -271.818562)
			(xy 183.276674 -271.77309) (xy 183.324801 -271.733342) (xy 183.350916 -271.716246) (xy 183.361076 -271.709896)
			(xy 183.373268 -271.690084) (xy 183.38292 -271.585944) (xy 183.374538 -271.5641) (xy 183.365648 -271.555972)
			(xy 183.347324 -271.538453) (xy 183.31518 -271.499252) (xy 183.288706 -271.456019) (xy 183.268401 -271.409567)
			(xy 183.254647 -271.360773) (xy 183.247705 -271.310556) (xy 183.247284 -271.285208) (xy 183.247702 -271.259891)
			(xy 183.254628 -271.209732) (xy 183.268351 -271.160992) (xy 183.288612 -271.114587) (xy 183.31503 -271.071391)
			(xy 183.34711 -271.032215) (xy 183.365394 -271.014698) (xy 183.374284 -271.006316) (xy 183.382666 -270.984726)
			(xy 183.373268 -270.880586) (xy 183.361076 -270.860774) (xy 183.350916 -270.85417) (xy 183.324801 -270.8371)
			(xy 183.276683 -270.797384) (xy 183.23393 -270.751943) (xy 183.197216 -270.701497) (xy 183.167123 -270.646842)
			(xy 183.144126 -270.588844) (xy 183.128589 -270.528418) (xy 183.120757 -270.46652) (xy 183.120284 -270.435324)
			(xy 183.120792 -270.402623) (xy 183.129403 -270.33779) (xy 183.146467 -270.274653) (xy 183.171687 -270.214309)
			(xy 183.204624 -270.157805) (xy 183.244707 -270.106125) (xy 183.267604 -270.082772) (xy 183.27497 -270.075406)
			(xy 183.28259 -270.056864) (xy 183.28259 -269.9639) (xy 183.27497 -269.945358) (xy 183.267604 -269.937992)
			(xy 183.244693 -269.914652) (xy 183.204608 -269.862972) (xy 183.171672 -269.806466) (xy 183.146458 -269.746119)
			(xy 183.129403 -269.682978) (xy 183.120805 -269.618142) (xy 183.120284 -269.58544) (xy 183.120745 -269.55423)
			(xy 183.128571 -269.492304) (xy 183.144105 -269.431848) (xy 183.167101 -269.373819) (xy 183.197195 -269.319134)
			(xy 183.233913 -269.268656) (xy 183.276673 -269.223184) (xy 183.324801 -269.183436) (xy 183.350916 -269.16634)
			(xy 183.361076 -269.15999) (xy 183.373268 -269.140178) (xy 183.38292 -269.036038) (xy 183.374538 -269.014194)
			(xy 183.365648 -269.006066) (xy 183.347321 -268.98855) (xy 183.315177 -268.949348) (xy 183.288703 -268.906114)
			(xy 183.268399 -268.859662) (xy 183.254646 -268.810868) (xy 183.247704 -268.76065) (xy 183.247284 -268.735302)
			(xy 183.247698 -268.709984) (xy 183.254625 -268.659825) (xy 183.268348 -268.611085) (xy 183.28861 -268.564681)
			(xy 183.315029 -268.521485) (xy 183.347109 -268.482309) (xy 183.365394 -268.464792) (xy 183.374284 -268.45641)
			(xy 183.382666 -268.43482) (xy 183.373268 -268.33068) (xy 183.361076 -268.310868) (xy 183.350916 -268.304264)
			(xy 183.324798 -268.287198) (xy 183.27668 -268.247481) (xy 183.233927 -268.20204) (xy 183.197214 -268.151593)
			(xy 183.167121 -268.096938) (xy 183.144124 -268.038939) (xy 183.128588 -267.978512) (xy 183.120756 -267.916614)
			(xy 183.120284 -267.885418) (xy 183.120727 -267.854208) (xy 183.128556 -267.79228) (xy 183.144093 -267.731824)
			(xy 183.167091 -267.673795) (xy 183.197188 -267.61911) (xy 183.233908 -267.568633) (xy 183.276671 -267.523161)
			(xy 183.3248 -267.483414) (xy 183.350916 -267.466318) (xy 183.361076 -267.459968) (xy 183.373268 -267.440156)
			(xy 183.38292 -267.336016) (xy 183.374538 -267.314172) (xy 183.365648 -267.306044) (xy 183.34731 -267.288539)
			(xy 183.315167 -267.249335) (xy 183.288695 -267.206098) (xy 183.268392 -267.159644) (xy 183.254642 -267.110848)
			(xy 183.247703 -267.060628) (xy 183.247284 -267.03528) (xy 183.247684 -267.009962) (xy 183.254613 -266.959802)
			(xy 183.268339 -266.911062) (xy 183.288604 -266.864658) (xy 183.315026 -266.821462) (xy 183.347108 -266.782286)
			(xy 183.365394 -266.76477) (xy 183.374284 -266.756388) (xy 183.382666 -266.734798) (xy 183.373268 -266.630658)
			(xy 183.361076 -266.610846) (xy 183.350916 -266.604242) (xy 183.324788 -266.587191) (xy 183.27667 -266.547472)
			(xy 183.233917 -266.502029) (xy 183.197205 -266.451579) (xy 183.167114 -266.396922) (xy 183.144119 -266.338921)
			(xy 183.128584 -266.278493) (xy 183.120755 -266.216593) (xy 183.120284 -266.185396) (xy 183.120788 -266.154188)
			(xy 183.128608 -266.092263) (xy 183.144135 -266.031808) (xy 183.167124 -265.97378) (xy 183.197213 -265.919094)
			(xy 183.233925 -265.868616) (xy 183.27668 -265.823142) (xy 183.324803 -265.783393) (xy 183.350916 -265.766296)
			(xy 183.361076 -265.759946) (xy 183.373268 -265.740134) (xy 183.38292 -265.635994) (xy 183.374538 -265.61415)
			(xy 183.365648 -265.606022) (xy 183.347348 -265.588479) (xy 183.315202 -265.549283) (xy 183.288724 -265.506055)
			(xy 183.268415 -265.459608) (xy 183.254657 -265.410818) (xy 183.247708 -265.360604) (xy 183.247284 -265.335258)
			(xy 183.247736 -265.309942) (xy 183.254655 -265.259784) (xy 183.268371 -265.211045) (xy 183.288625 -265.16464)
			(xy 183.315038 -265.121443) (xy 183.347112 -265.082266) (xy 183.365394 -265.064748) (xy 183.374284 -265.056366)
			(xy 183.382666 -265.034776) (xy 183.373268 -264.930636) (xy 183.361076 -264.910824) (xy 183.350916 -264.90422)
			(xy 183.324823 -264.887117) (xy 183.276706 -264.847405) (xy 183.233951 -264.801969) (xy 183.197236 -264.751528)
			(xy 183.16714 -264.696878) (xy 183.144139 -264.638884) (xy 183.128597 -264.578463) (xy 183.12076 -264.516568)
			(xy 183.120284 -264.485374) (xy 183.120771 -264.454165) (xy 183.128593 -264.392239) (xy 183.144123 -264.331785)
			(xy 183.167115 -264.273756) (xy 183.197206 -264.21907) (xy 183.23392 -264.168592) (xy 183.276678 -264.123119)
			(xy 183.324802 -264.083371) (xy 183.350916 -264.066274) (xy 183.361076 -264.059924) (xy 183.373268 -264.040112)
			(xy 183.38292 -263.935972) (xy 183.374538 -263.914128) (xy 183.365648 -263.906) (xy 183.347338 -263.888468)
			(xy 183.315192 -263.849269) (xy 183.288716 -263.806039) (xy 183.268409 -263.75959) (xy 183.254653 -263.710798)
			(xy 183.247707 -263.660583) (xy 183.247284 -263.635236) (xy 183.247721 -263.609919) (xy 183.254643 -263.559761)
			(xy 183.268362 -263.511022) (xy 183.288619 -263.464617) (xy 183.315035 -263.42142) (xy 183.347111 -263.382243)
			(xy 183.365394 -263.364726) (xy 183.374284 -263.356344) (xy 183.382666 -263.334754) (xy 183.373268 -263.230614)
			(xy 183.361076 -263.210802) (xy 183.350916 -263.204198) (xy 183.324813 -263.18711) (xy 183.276696 -263.147396)
			(xy 183.233942 -263.101958) (xy 183.197227 -263.051514) (xy 183.167133 -262.996863) (xy 183.144133 -262.938867)
			(xy 183.128593 -262.878443) (xy 183.120758 -262.816547) (xy 183.120284 -262.785352) (xy 183.120754 -262.754143)
			(xy 183.128579 -262.692216) (xy 183.144111 -262.631761) (xy 183.167106 -262.573732) (xy 183.197199 -262.519047)
			(xy 183.233915 -262.468569) (xy 183.276675 -262.423097) (xy 183.324802 -262.383348) (xy 183.350916 -262.366252)
			(xy 183.361076 -262.359902) (xy 183.373268 -262.34009) (xy 183.38292 -262.23595) (xy 183.374538 -262.214106)
			(xy 183.365648 -262.205978) (xy 183.347327 -262.188456) (xy 183.315182 -262.149256) (xy 183.288708 -262.106023)
			(xy 183.268402 -262.059572) (xy 183.254649 -262.010779) (xy 183.247705 -261.960561) (xy 183.247284 -261.935214)
			(xy 183.247706 -261.909897) (xy 183.254631 -261.859738) (xy 183.268353 -261.810998) (xy 183.288613 -261.764594)
			(xy 183.315031 -261.721397) (xy 183.34711 -261.682221) (xy 183.365394 -261.664704) (xy 183.374284 -261.656322)
			(xy 183.382666 -261.634732) (xy 183.373268 -261.530592) (xy 183.361076 -261.51078) (xy 183.350916 -261.504176)
			(xy 183.324803 -261.487102) (xy 183.276686 -261.447386) (xy 183.233932 -261.401946) (xy 183.197218 -261.351501)
			(xy 183.167125 -261.296847) (xy 183.144128 -261.238849) (xy 183.12859 -261.178423) (xy 183.120757 -261.116526)
			(xy 183.120284 -261.08533) (xy 183.120773 -261.054167) (xy 183.128585 -260.992333) (xy 183.144085 -260.931965)
			(xy 183.167028 -260.874017) (xy 183.197054 -260.8194) (xy 183.233688 -260.768978) (xy 183.276353 -260.723544)
			(xy 183.324375 -260.683816) (xy 183.376999 -260.650421) (xy 183.433393 -260.623884) (xy 183.492668 -260.604624)
			(xy 183.553889 -260.592945) (xy 183.616092 -260.589032) (xy 183.678295 -260.592945) (xy 183.739516 -260.604624)
			(xy 183.798791 -260.623884) (xy 183.855185 -260.650421) (xy 183.907809 -260.683816) (xy 183.955831 -260.723544)
			(xy 183.998496 -260.768978) (xy 184.03513 -260.8194) (xy 184.065156 -260.874017) (xy 184.088099 -260.931965)
			(xy 184.103599 -260.992333) (xy 184.111411 -261.054167) (xy 184.1119 -261.08533) (xy 184.111409 -261.116526)
			(xy 184.103595 -261.178428) (xy 184.08807 -261.238858) (xy 184.06508 -261.296861) (xy 184.034988 -261.351517)
			(xy 183.998271 -261.401962) (xy 183.95551 -261.447397) (xy 183.907382 -261.487103) (xy 183.881268 -261.504176)
			(xy 183.871108 -261.51078) (xy 183.858916 -261.530592) (xy 183.849518 -261.634732) (xy 183.8579 -261.656322)
			(xy 183.86679 -261.664704) (xy 183.885093 -261.682201) (xy 183.917168 -261.721383) (xy 183.943582 -261.764585)
			(xy 183.963839 -261.810992) (xy 183.977559 -261.859735) (xy 183.984483 -261.909896) (xy 183.9849 -261.935214)
			(xy 183.984478 -261.960562) (xy 183.977544 -262.010782) (xy 183.963794 -262.059578) (xy 183.943489 -262.10603)
			(xy 183.917011 -262.149261) (xy 183.884859 -262.188458) (xy 183.866536 -262.205978) (xy 183.857646 -262.214106)
			(xy 183.849264 -262.23595) (xy 183.858916 -262.34009) (xy 183.871108 -262.359902) (xy 183.881268 -262.366252)
			(xy 183.907357 -262.383385) (xy 183.955481 -262.423131) (xy 183.998239 -262.468599) (xy 184.034955 -262.519072)
			(xy 184.065051 -262.573751) (xy 184.088051 -262.631774) (xy 184.103591 -262.692223) (xy 184.111426 -262.754145)
			(xy 184.1119 -262.785352) (xy 184.111426 -262.816549) (xy 184.10361 -262.878451) (xy 184.088082 -262.938882)
			(xy 184.065089 -262.996884) (xy 184.034995 -263.051541) (xy 183.998276 -263.101985) (xy 183.955513 -263.14742)
			(xy 183.907383 -263.187125) (xy 183.881268 -263.204198) (xy 183.871108 -263.210802) (xy 183.858916 -263.230614)
			(xy 183.849518 -263.334754) (xy 183.8579 -263.356344) (xy 183.86679 -263.364726) (xy 183.885104 -263.382212)
			(xy 183.917178 -263.421397) (xy 183.943591 -263.4646) (xy 183.963846 -263.51101) (xy 183.977563 -263.559755)
			(xy 183.984484 -263.609917) (xy 183.9849 -263.635236) (xy 183.984492 -263.660585) (xy 183.977555 -263.710805)
			(xy 183.963803 -263.759601) (xy 183.943495 -263.806053) (xy 183.917014 -263.849284) (xy 183.88486 -263.88848)
			(xy 183.866536 -263.906) (xy 183.857646 -263.914128) (xy 183.849264 -263.935972) (xy 183.858916 -264.040112)
			(xy 183.871108 -264.059924) (xy 183.881268 -264.066274) (xy 183.907367 -264.083392) (xy 183.955491 -264.12314)
			(xy 183.998248 -264.168611) (xy 184.034964 -264.219086) (xy 184.065059 -264.273767) (xy 184.088057 -264.331792)
			(xy 184.103595 -264.392243) (xy 184.111427 -264.454166) (xy 184.1119 -264.485374) (xy 184.111443 -264.516571)
			(xy 184.103624 -264.578474) (xy 184.088094 -264.638906) (xy 184.065099 -264.696908) (xy 184.035002 -264.751564)
			(xy 183.99828 -264.802009) (xy 183.955515 -264.847443) (xy 183.907384 -264.887148) (xy 183.881268 -264.90422)
			(xy 183.871108 -264.910824) (xy 183.858916 -264.930636) (xy 183.849518 -265.034776) (xy 183.8579 -265.056366)
			(xy 183.86679 -265.064748) (xy 183.885066 -265.082272) (xy 183.917143 -265.121449) (xy 183.943561 -265.164644)
			(xy 183.963823 -265.211047) (xy 183.977548 -265.259784) (xy 183.984479 -265.309941) (xy 183.9849 -265.335258)
			(xy 183.984507 -265.360607) (xy 183.977567 -265.410828) (xy 183.963812 -265.459624) (xy 183.943501 -265.506076)
			(xy 183.917018 -265.549307) (xy 183.884861 -265.588503) (xy 183.866536 -265.606022) (xy 183.857646 -265.61415)
			(xy 183.849264 -265.635994) (xy 183.858916 -265.740134) (xy 183.871108 -265.759946) (xy 183.881268 -265.766296)
			(xy 183.907377 -265.783399) (xy 183.955501 -265.823149) (xy 183.998258 -265.868622) (xy 184.034973 -265.919099)
			(xy 184.065066 -265.973783) (xy 184.088063 -266.03181) (xy 184.103599 -266.092263) (xy 184.111429 -266.154187)
			(xy 184.1119 -266.185396) (xy 184.11146 -266.216594) (xy 184.103639 -266.278498) (xy 184.088106 -266.338929)
			(xy 184.065108 -266.396932) (xy 184.035009 -266.451588) (xy 183.998285 -266.502032) (xy 183.955518 -266.547466)
			(xy 183.907385 -266.58717) (xy 183.881268 -266.604242) (xy 183.871108 -266.610846) (xy 183.858916 -266.630658)
			(xy 183.849518 -266.734798) (xy 183.8579 -266.756388) (xy 183.86679 -266.76477) (xy 183.885077 -266.782283)
			(xy 183.917153 -266.821462) (xy 183.94357 -266.86466) (xy 183.96383 -266.911065) (xy 183.977552 -266.959804)
			(xy 183.98448 -267.009963) (xy 183.9849 -267.03528) (xy 183.984455 -267.060627) (xy 183.977526 -267.110846)
			(xy 183.963781 -267.159641) (xy 183.94348 -267.206093) (xy 183.917006 -267.249326) (xy 183.884858 -267.288523)
			(xy 183.866536 -267.306044) (xy 183.857646 -267.314172) (xy 183.849264 -267.336016) (xy 183.858916 -267.440156)
			(xy 183.871108 -267.459968) (xy 183.881268 -267.466318) (xy 183.907387 -267.483406) (xy 183.955511 -267.523159)
			(xy 183.998267 -267.568634) (xy 184.034982 -267.619113) (xy 184.065074 -267.673799) (xy 184.088069 -267.731828)
			(xy 184.103602 -267.792283) (xy 184.11143 -267.854209) (xy 184.1119 -267.885418) (xy 184.111478 -267.916617)
			(xy 184.103653 -267.978521) (xy 184.088118 -268.038953) (xy 184.065117 -268.096956) (xy 184.035016 -268.151612)
			(xy 183.99829 -268.202056) (xy 183.955521 -268.247489) (xy 183.907385 -268.287192) (xy 183.881268 -268.304264)
			(xy 183.871108 -268.310868) (xy 183.858916 -268.33068) (xy 183.849518 -268.43482) (xy 183.8579 -268.45641)
			(xy 183.86679 -268.464792) (xy 183.885088 -268.482295) (xy 183.917163 -268.521476) (xy 183.943578 -268.564676)
			(xy 183.963836 -268.611083) (xy 183.977557 -268.659824) (xy 183.984482 -268.709984) (xy 183.9849 -268.735302)
			(xy 183.98447 -268.76065) (xy 183.977537 -268.810869) (xy 183.96379 -268.859665) (xy 183.943486 -268.906117)
			(xy 183.917009 -268.949349) (xy 183.884859 -268.988546) (xy 183.866536 -269.006066) (xy 183.857646 -269.014194)
			(xy 183.849264 -269.036038) (xy 183.858916 -269.140178) (xy 183.871108 -269.15999) (xy 183.881268 -269.16634)
			(xy 183.907352 -269.183481) (xy 183.955475 -269.223226) (xy 183.998233 -269.268693) (xy 184.034951 -269.319164)
			(xy 184.065047 -269.373843) (xy 184.088048 -269.431864) (xy 184.103589 -269.492313) (xy 184.111425 -269.554233)
			(xy 184.1119 -269.58544) (xy 184.111374 -269.618141) (xy 184.102766 -269.682973) (xy 184.085706 -269.74611)
			(xy 184.06049 -269.806454) (xy 184.027556 -269.862958) (xy 183.987476 -269.914639) (xy 183.96458 -269.937992)
			(xy 183.957214 -269.945358) (xy 183.949594 -269.9639) (xy 183.949594 -270.056864) (xy 183.957214 -270.075406)
			(xy 183.96458 -270.082772) (xy 183.987488 -270.106114) (xy 184.027571 -270.157795) (xy 184.060505 -270.214301)
			(xy 184.08572 -270.274648) (xy 184.102776 -270.337788) (xy 184.111377 -270.402623) (xy 184.1119 -270.435324)
			(xy 184.111482 -270.466523) (xy 184.103657 -270.528427) (xy 184.088121 -270.588859) (xy 184.06512 -270.646862)
			(xy 184.035018 -270.701518) (xy 183.998291 -270.751962) (xy 183.955522 -270.797395) (xy 183.907386 -270.837098)
			(xy 183.881268 -270.85417) (xy 183.871108 -270.860774) (xy 183.858916 -270.880586) (xy 183.849518 -270.984726)
			(xy 183.8579 -271.006316) (xy 183.86679 -271.014698) (xy 183.885091 -271.032198) (xy 183.917166 -271.07138)
			(xy 183.94358 -271.11458) (xy 183.963838 -271.160988) (xy 183.977558 -271.20973) (xy 183.984482 -271.25989)
			(xy 183.9849 -271.285208) (xy 183.984474 -271.310556) (xy 183.97754 -271.360775) (xy 183.963792 -271.409571)
			(xy 183.943487 -271.456023) (xy 183.91701 -271.499255) (xy 183.884859 -271.538452) (xy 183.866536 -271.555972)
			(xy 183.857646 -271.5641) (xy 183.849264 -271.585944) (xy 183.858916 -271.690084) (xy 183.871108 -271.709896)
			(xy 183.881268 -271.716246) (xy 183.907354 -271.733383) (xy 183.955478 -271.773128) (xy 183.998236 -271.818596)
			(xy 184.034953 -271.869068) (xy 184.065049 -271.923747) (xy 184.088049 -271.981769) (xy 184.10359 -272.042218)
			(xy 184.111426 -272.104139) (xy 184.1119 -272.135346) (xy 184.111421 -272.166543) (xy 184.103606 -272.228445)
			(xy 184.088079 -272.288875) (xy 184.065087 -272.346878) (xy 184.034993 -272.401534) (xy 183.998274 -272.451979)
			(xy 183.955512 -272.497414) (xy 183.907383 -272.537119) (xy 183.881268 -272.554192) (xy 183.871108 -272.560796)
			(xy 183.858916 -272.580608) (xy 183.849518 -272.684748) (xy 183.8579 -272.706338) (xy 183.86679 -272.71472)
			(xy 183.885101 -272.732209) (xy 183.917175 -272.771393) (xy 183.943588 -272.814596) (xy 183.963844 -272.861006)
			(xy 183.977562 -272.909749) (xy 183.984484 -272.959911) (xy 183.9849 -272.98523) (xy 183.984488 -273.010578)
			(xy 183.977552 -273.060798) (xy 183.963801 -273.109595) (xy 183.943493 -273.156047) (xy 183.917013 -273.199278)
			(xy 183.88486 -273.238474) (xy 183.866536 -273.255994) (xy 183.857646 -273.264122) (xy 183.849264 -273.285966)
			(xy 183.858916 -273.390106) (xy 183.871108 -273.409918) (xy 183.881268 -273.416268) (xy 183.907364 -273.43339)
			(xy 183.955488 -273.473137) (xy 183.998245 -273.518608) (xy 184.034962 -273.569082) (xy 184.065057 -273.623763)
			(xy 184.088055 -273.681787) (xy 184.103594 -273.742238) (xy 184.111427 -273.80416) (xy 184.1119 -273.835368)
			(xy 184.111411 -273.866531) (xy 184.103599 -273.928365) (xy 184.088099 -273.988733) (xy 184.065156 -274.046681)
			(xy 184.03513 -274.101298) (xy 183.998496 -274.15172) (xy 183.955831 -274.197154) (xy 183.907809 -274.236882)
			(xy 183.855185 -274.270277) (xy 183.798791 -274.296814) (xy 183.739516 -274.316074) (xy 183.678295 -274.327753)
			(xy 183.616092 -274.331666) (xy 183.553889 -274.327753) (xy 183.492668 -274.316074) (xy 183.433393 -274.296814)
			(xy 183.376999 -274.270277) (xy 183.324375 -274.236882) (xy 183.276353 -274.197154) (xy 183.233688 -274.15172)
			(xy 183.197054 -274.101298) (xy 183.167028 -274.046681) (xy 183.144085 -273.988733) (xy 183.128585 -273.928365)
			(xy 183.120773 -273.866531) (xy 183.120284 -273.835368) (xy 179.884832 -273.835368) (xy 179.884424 -273.860686)
			(xy 179.8775 -273.910846) (xy 179.863777 -273.959587) (xy 179.843514 -274.005992) (xy 179.817092 -274.049188)
			(xy 179.785008 -274.088363) (xy 179.766722 -274.105878) (xy 179.757832 -274.11426) (xy 179.74945 -274.13585)
			(xy 179.758848 -274.23999) (xy 179.77104 -274.259802) (xy 179.7812 -274.266406) (xy 179.807308 -274.283486)
			(xy 179.855425 -274.323202) (xy 179.898178 -274.368641) (xy 179.934892 -274.419086) (xy 179.964986 -274.473739)
			(xy 179.987984 -274.531736) (xy 180.003523 -274.59216) (xy 180.011358 -274.654057) (xy 180.011832 -274.685252)
			(xy 181.862491 -274.685252) (xy 181.866426 -274.631481) (xy 181.878149 -274.578857) (xy 181.897409 -274.5285)
			(xy 181.923795 -274.481483) (xy 181.956747 -274.43881) (xy 181.99556 -274.401389) (xy 182.039408 -274.370019)
			(xy 182.087356 -274.345367) (xy 182.138383 -274.327959) (xy 182.191401 -274.318166) (xy 182.24528 -274.316197)
			(xy 182.298871 -274.322094) (xy 182.351032 -274.33573) (xy 182.400652 -274.356817) (xy 182.446673 -274.384903)
			(xy 182.488115 -274.419391) (xy 182.524093 -274.459545) (xy 182.553841 -274.504509) (xy 182.576726 -274.553326)
			(xy 182.592258 -274.604955) (xy 182.600108 -274.658295) (xy 182.6006 -274.685252) (xy 182.600108 -274.712209)
			(xy 182.592258 -274.765549) (xy 182.576726 -274.817178) (xy 182.553841 -274.865995) (xy 182.524093 -274.910959)
			(xy 182.488115 -274.951113) (xy 182.446673 -274.985601) (xy 182.400652 -275.013687) (xy 182.351032 -275.034774)
			(xy 182.298871 -275.04841) (xy 182.24528 -275.054307) (xy 182.191401 -275.052338) (xy 182.138383 -275.042545)
			(xy 182.087356 -275.025137) (xy 182.039408 -275.000485) (xy 181.99556 -274.969115) (xy 181.956747 -274.931694)
			(xy 181.923795 -274.889021) (xy 181.897409 -274.842004) (xy 181.878149 -274.791647) (xy 181.866426 -274.739023)
			(xy 181.862491 -274.685252) (xy 180.011832 -274.685252) (xy 180.011343 -274.716415) (xy 180.003531 -274.778249)
			(xy 179.988031 -274.838617) (xy 179.965088 -274.896565) (xy 179.935062 -274.951182) (xy 179.898428 -275.001604)
			(xy 179.855763 -275.047038) (xy 179.807741 -275.086766) (xy 179.755117 -275.120161) (xy 179.698723 -275.146698)
			(xy 179.639448 -275.165958) (xy 179.578227 -275.177637) (xy 179.516024 -275.18155) (xy 179.453821 -275.177637)
			(xy 179.3926 -275.165958) (xy 179.333325 -275.146698) (xy 179.276931 -275.120161) (xy 179.224307 -275.086766)
			(xy 179.176285 -275.047038) (xy 179.13362 -275.001604) (xy 179.096986 -274.951182) (xy 179.06696 -274.896565)
			(xy 179.044017 -274.838617) (xy 179.028517 -274.778249) (xy 179.020705 -274.716415) (xy 179.020216 -274.685252)
			(xy 175.056546 -274.685252) (xy 175.056054 -274.712209) (xy 175.048204 -274.765549) (xy 175.032672 -274.817178)
			(xy 175.009787 -274.865995) (xy 174.980039 -274.910959) (xy 174.944061 -274.951113) (xy 174.902619 -274.985601)
			(xy 174.856598 -275.013687) (xy 174.806978 -275.034774) (xy 174.754817 -275.04841) (xy 174.701226 -275.054307)
			(xy 174.647347 -275.052338) (xy 174.594329 -275.042545) (xy 174.543302 -275.025137) (xy 174.495354 -275.000485)
			(xy 174.451506 -274.969115) (xy 174.412693 -274.931694) (xy 174.379741 -274.889021) (xy 174.353355 -274.842004)
			(xy 174.334095 -274.791647) (xy 174.322372 -274.739023) (xy 174.318437 -274.685252) (xy 172.467778 -274.685252)
			(xy 172.467289 -274.716415) (xy 172.459477 -274.778249) (xy 172.443977 -274.838617) (xy 172.421034 -274.896565)
			(xy 172.391008 -274.951182) (xy 172.354374 -275.001604) (xy 172.311709 -275.047038) (xy 172.263687 -275.086766)
			(xy 172.211063 -275.120161) (xy 172.154669 -275.146698) (xy 172.095394 -275.165958) (xy 172.034173 -275.177637)
			(xy 171.97197 -275.18155) (xy 171.909767 -275.177637) (xy 171.848546 -275.165958) (xy 171.789271 -275.146698)
			(xy 171.732877 -275.120161) (xy 171.680253 -275.086766) (xy 171.632231 -275.047038) (xy 171.589566 -275.001604)
			(xy 171.552932 -274.951182) (xy 171.522906 -274.896565) (xy 171.499963 -274.838617) (xy 171.484463 -274.778249)
			(xy 171.476651 -274.716415) (xy 171.476162 -274.685252) (xy 167.512492 -274.685252) (xy 167.512 -274.712209)
			(xy 167.50415 -274.765549) (xy 167.488618 -274.817178) (xy 167.465733 -274.865995) (xy 167.435985 -274.910959)
			(xy 167.400007 -274.951113) (xy 167.358565 -274.985601) (xy 167.312544 -275.013687) (xy 167.262924 -275.034774)
			(xy 167.210763 -275.04841) (xy 167.157172 -275.054307) (xy 167.103293 -275.052338) (xy 167.050275 -275.042545)
			(xy 166.999248 -275.025137) (xy 166.9513 -275.000485) (xy 166.907452 -274.969115) (xy 166.868639 -274.931694)
			(xy 166.835687 -274.889021) (xy 166.809301 -274.842004) (xy 166.790041 -274.791647) (xy 166.778318 -274.739023)
			(xy 166.774383 -274.685252) (xy 147.342781 -274.685252) (xy 147.339804 -274.703572) (xy 147.32422 -274.750253)
			(xy 147.301349 -274.79383) (xy 147.271784 -274.833174) (xy 147.236291 -274.867266) (xy 147.195788 -274.895222)
			(xy 147.151326 -274.91632) (xy 147.104055 -274.930012) (xy 147.0552 -274.935944) (xy 147.006025 -274.933963)
			(xy 146.957806 -274.924119) (xy 146.91179 -274.906667) (xy 146.869169 -274.88206) (xy 146.831048 -274.850935)
			(xy 146.798413 -274.814098) (xy 146.77211 -274.772502) (xy 146.752819 -274.727226) (xy 146.741042 -274.679442)
			(xy 146.737082 -274.630388) (xy 144.185339 -274.630388) (xy 144.187666 -274.631492) (xy 144.228169 -274.659448)
			(xy 144.263662 -274.69354) (xy 144.293227 -274.732884) (xy 144.316098 -274.776461) (xy 144.331682 -274.823142)
			(xy 144.339577 -274.871719) (xy 144.340072 -274.896326) (xy 144.339577 -274.920933) (xy 144.331682 -274.96951)
			(xy 144.316098 -275.016191) (xy 144.293227 -275.059768) (xy 144.263662 -275.099112) (xy 144.228169 -275.133204)
			(xy 144.187666 -275.16116) (xy 144.143204 -275.182258) (xy 144.095933 -275.19595) (xy 144.047078 -275.201882)
			(xy 143.997903 -275.199901) (xy 143.949684 -275.190057) (xy 143.903668 -275.172605) (xy 143.861047 -275.147998)
			(xy 143.822926 -275.116873) (xy 143.790291 -275.080036) (xy 143.763988 -275.03844) (xy 143.744697 -274.993164)
			(xy 143.73292 -274.94538) (xy 143.72896 -274.896326) (xy 143.410432 -274.896326) (xy 143.40992 -274.921772)
			(xy 143.401756 -274.972006) (xy 143.38564 -275.02028) (xy 143.361989 -275.065343) (xy 143.331416 -275.106029)
			(xy 143.294712 -275.141284) (xy 143.252828 -275.170194) (xy 143.206849 -275.192011) (xy 143.157965 -275.206171)
			(xy 143.107444 -275.212305) (xy 143.056592 -275.210256) (xy 143.006728 -275.200076) (xy 142.959142 -275.182029)
			(xy 142.915068 -275.156583) (xy 142.875646 -275.124396) (xy 142.841898 -275.086302) (xy 142.814697 -275.043288)
			(xy 142.794749 -274.996468) (xy 142.78257 -274.947054) (xy 142.778475 -274.896326) (xy 142.459964 -274.896326)
			(xy 142.459469 -274.920933) (xy 142.451574 -274.96951) (xy 142.43599 -275.016191) (xy 142.413119 -275.059768)
			(xy 142.383554 -275.099112) (xy 142.348061 -275.133204) (xy 142.307558 -275.16116) (xy 142.263096 -275.182258)
			(xy 142.215825 -275.19595) (xy 142.16697 -275.201882) (xy 142.117795 -275.199901) (xy 142.069576 -275.190057)
			(xy 142.02356 -275.172605) (xy 141.980939 -275.147998) (xy 141.942818 -275.116873) (xy 141.910183 -275.080036)
			(xy 141.88388 -275.03844) (xy 141.864589 -274.993164) (xy 141.852812 -274.94538) (xy 141.848852 -274.896326)
			(xy 141.530578 -274.896326) (xy 141.530066 -274.921772) (xy 141.521902 -274.972006) (xy 141.505786 -275.02028)
			(xy 141.482135 -275.065343) (xy 141.451562 -275.106029) (xy 141.414858 -275.141284) (xy 141.372974 -275.170194)
			(xy 141.326995 -275.192011) (xy 141.278111 -275.206171) (xy 141.22759 -275.212305) (xy 141.176738 -275.210256)
			(xy 141.126874 -275.200076) (xy 141.079288 -275.182029) (xy 141.035214 -275.156583) (xy 140.995792 -275.124396)
			(xy 140.962044 -275.086302) (xy 140.934843 -275.043288) (xy 140.914895 -274.996468) (xy 140.902716 -274.947054)
			(xy 140.898621 -274.896326) (xy 140.58011 -274.896326) (xy 140.579615 -274.920933) (xy 140.57172 -274.96951)
			(xy 140.556136 -275.016191) (xy 140.533265 -275.059768) (xy 140.5037 -275.099112) (xy 140.468207 -275.133204)
			(xy 140.427704 -275.16116) (xy 140.383242 -275.182258) (xy 140.335971 -275.19595) (xy 140.287116 -275.201882)
			(xy 140.237941 -275.199901) (xy 140.189722 -275.190057) (xy 140.143706 -275.172605) (xy 140.101085 -275.147998)
			(xy 140.062964 -275.116873) (xy 140.030329 -275.080036) (xy 140.004026 -275.03844) (xy 139.984735 -274.993164)
			(xy 139.972958 -274.94538) (xy 139.968998 -274.896326) (xy 139.65047 -274.896326) (xy 139.649958 -274.921772)
			(xy 139.641794 -274.972006) (xy 139.625678 -275.02028) (xy 139.602027 -275.065343) (xy 139.571454 -275.106029)
			(xy 139.53475 -275.141284) (xy 139.492866 -275.170194) (xy 139.446887 -275.192011) (xy 139.398003 -275.206171)
			(xy 139.347482 -275.212305) (xy 139.29663 -275.210256) (xy 139.246766 -275.200076) (xy 139.19918 -275.182029)
			(xy 139.155106 -275.156583) (xy 139.115684 -275.124396) (xy 139.081936 -275.086302) (xy 139.054735 -275.043288)
			(xy 139.034787 -274.996468) (xy 139.022608 -274.947054) (xy 139.018513 -274.896326) (xy 138.710416 -274.896326)
			(xy 138.709904 -274.921772) (xy 138.70174 -274.972006) (xy 138.685624 -275.02028) (xy 138.661973 -275.065343)
			(xy 138.6314 -275.106029) (xy 138.594696 -275.141284) (xy 138.552812 -275.170194) (xy 138.506833 -275.192011)
			(xy 138.457949 -275.206171) (xy 138.407428 -275.212305) (xy 138.356576 -275.210256) (xy 138.306712 -275.200076)
			(xy 138.259126 -275.182029) (xy 138.215052 -275.156583) (xy 138.17563 -275.124396) (xy 138.141882 -275.086302)
			(xy 138.114681 -275.043288) (xy 138.094733 -274.996468) (xy 138.082554 -274.947054) (xy 138.078459 -274.896326)
			(xy 137.759948 -274.896326) (xy 137.759453 -274.920933) (xy 137.751558 -274.96951) (xy 137.735974 -275.016191)
			(xy 137.713103 -275.059768) (xy 137.683538 -275.099112) (xy 137.648045 -275.133204) (xy 137.607542 -275.16116)
			(xy 137.56308 -275.182258) (xy 137.515809 -275.19595) (xy 137.466954 -275.201882) (xy 137.417779 -275.199901)
			(xy 137.36956 -275.190057) (xy 137.323544 -275.172605) (xy 137.280923 -275.147998) (xy 137.242802 -275.116873)
			(xy 137.210167 -275.080036) (xy 137.183864 -275.03844) (xy 137.164573 -274.993164) (xy 137.152796 -274.94538)
			(xy 137.148836 -274.896326) (xy 136.830562 -274.896326) (xy 136.83005 -274.921772) (xy 136.821886 -274.972006)
			(xy 136.80577 -275.02028) (xy 136.782119 -275.065343) (xy 136.751546 -275.106029) (xy 136.714842 -275.141284)
			(xy 136.672958 -275.170194) (xy 136.626979 -275.192011) (xy 136.578095 -275.206171) (xy 136.527574 -275.212305)
			(xy 136.476722 -275.210256) (xy 136.426858 -275.200076) (xy 136.379272 -275.182029) (xy 136.335198 -275.156583)
			(xy 136.295776 -275.124396) (xy 136.262028 -275.086302) (xy 136.234827 -275.043288) (xy 136.214879 -274.996468)
			(xy 136.2027 -274.947054) (xy 136.198605 -274.896326) (xy 135.880094 -274.896326) (xy 135.879599 -274.920933)
			(xy 135.871704 -274.96951) (xy 135.85612 -275.016191) (xy 135.833249 -275.059768) (xy 135.803684 -275.099112)
			(xy 135.768191 -275.133204) (xy 135.727688 -275.16116) (xy 135.683226 -275.182258) (xy 135.635955 -275.19595)
			(xy 135.5871 -275.201882) (xy 135.537925 -275.199901) (xy 135.489706 -275.190057) (xy 135.44369 -275.172605)
			(xy 135.401069 -275.147998) (xy 135.362948 -275.116873) (xy 135.330313 -275.080036) (xy 135.30401 -275.03844)
			(xy 135.284719 -274.993164) (xy 135.272942 -274.94538) (xy 135.268982 -274.896326) (xy 134.950454 -274.896326)
			(xy 134.949942 -274.921772) (xy 134.941778 -274.972006) (xy 134.925662 -275.02028) (xy 134.902011 -275.065343)
			(xy 134.871438 -275.106029) (xy 134.834734 -275.141284) (xy 134.79285 -275.170194) (xy 134.746871 -275.192011)
			(xy 134.697987 -275.206171) (xy 134.647466 -275.212305) (xy 134.596614 -275.210256) (xy 134.54675 -275.200076)
			(xy 134.499164 -275.182029) (xy 134.45509 -275.156583) (xy 134.415668 -275.124396) (xy 134.38192 -275.086302)
			(xy 134.354719 -275.043288) (xy 134.334771 -274.996468) (xy 134.322592 -274.947054) (xy 134.318497 -274.896326)
			(xy 133.999986 -274.896326) (xy 133.999491 -274.920933) (xy 133.991596 -274.96951) (xy 133.976012 -275.016191)
			(xy 133.953141 -275.059768) (xy 133.923576 -275.099112) (xy 133.888083 -275.133204) (xy 133.84758 -275.16116)
			(xy 133.803118 -275.182258) (xy 133.755847 -275.19595) (xy 133.706992 -275.201882) (xy 133.657817 -275.199901)
			(xy 133.609598 -275.190057) (xy 133.563582 -275.172605) (xy 133.520961 -275.147998) (xy 133.48284 -275.116873)
			(xy 133.450205 -275.080036) (xy 133.423902 -275.03844) (xy 133.404611 -274.993164) (xy 133.392834 -274.94538)
			(xy 133.388874 -274.896326) (xy 133.0706 -274.896326) (xy 133.070088 -274.921772) (xy 133.061924 -274.972006)
			(xy 133.045808 -275.02028) (xy 133.022157 -275.065343) (xy 132.991584 -275.106029) (xy 132.95488 -275.141284)
			(xy 132.912996 -275.170194) (xy 132.867017 -275.192011) (xy 132.818133 -275.206171) (xy 132.767612 -275.212305)
			(xy 132.71676 -275.210256) (xy 132.666896 -275.200076) (xy 132.61931 -275.182029) (xy 132.575236 -275.156583)
			(xy 132.535814 -275.124396) (xy 132.502066 -275.086302) (xy 132.474865 -275.043288) (xy 132.454917 -274.996468)
			(xy 132.442738 -274.947054) (xy 132.438643 -274.896326) (xy 132.130546 -274.896326) (xy 132.130034 -274.921772)
			(xy 132.12187 -274.972006) (xy 132.105754 -275.02028) (xy 132.082103 -275.065343) (xy 132.05153 -275.106029)
			(xy 132.014826 -275.141284) (xy 131.972942 -275.170194) (xy 131.926963 -275.192011) (xy 131.878079 -275.206171)
			(xy 131.827558 -275.212305) (xy 131.776706 -275.210256) (xy 131.726842 -275.200076) (xy 131.679256 -275.182029)
			(xy 131.635182 -275.156583) (xy 131.59576 -275.124396) (xy 131.562012 -275.086302) (xy 131.534811 -275.043288)
			(xy 131.514863 -274.996468) (xy 131.502684 -274.947054) (xy 131.498589 -274.896326) (xy 131.180078 -274.896326)
			(xy 131.179583 -274.920933) (xy 131.171688 -274.96951) (xy 131.156104 -275.016191) (xy 131.133233 -275.059768)
			(xy 131.103668 -275.099112) (xy 131.068175 -275.133204) (xy 131.027672 -275.16116) (xy 130.98321 -275.182258)
			(xy 130.935939 -275.19595) (xy 130.887084 -275.201882) (xy 130.837909 -275.199901) (xy 130.78969 -275.190057)
			(xy 130.743674 -275.172605) (xy 130.701053 -275.147998) (xy 130.662932 -275.116873) (xy 130.630297 -275.080036)
			(xy 130.603994 -275.03844) (xy 130.584703 -274.993164) (xy 130.572926 -274.94538) (xy 130.568966 -274.896326)
			(xy 130.250438 -274.896326) (xy 130.249926 -274.921772) (xy 130.241762 -274.972006) (xy 130.225646 -275.02028)
			(xy 130.201995 -275.065343) (xy 130.171422 -275.106029) (xy 130.134718 -275.141284) (xy 130.092834 -275.170194)
			(xy 130.046855 -275.192011) (xy 129.997971 -275.206171) (xy 129.94745 -275.212305) (xy 129.896598 -275.210256)
			(xy 129.846734 -275.200076) (xy 129.799148 -275.182029) (xy 129.755074 -275.156583) (xy 129.715652 -275.124396)
			(xy 129.681904 -275.086302) (xy 129.654703 -275.043288) (xy 129.634755 -274.996468) (xy 129.622576 -274.947054)
			(xy 129.618481 -274.896326) (xy 129.29997 -274.896326) (xy 129.299475 -274.920933) (xy 129.29158 -274.96951)
			(xy 129.275996 -275.016191) (xy 129.253125 -275.059768) (xy 129.22356 -275.099112) (xy 129.188067 -275.133204)
			(xy 129.147564 -275.16116) (xy 129.103102 -275.182258) (xy 129.055831 -275.19595) (xy 129.006976 -275.201882)
			(xy 128.957801 -275.199901) (xy 128.909582 -275.190057) (xy 128.863566 -275.172605) (xy 128.820945 -275.147998)
			(xy 128.782824 -275.116873) (xy 128.750189 -275.080036) (xy 128.723886 -275.03844) (xy 128.704595 -274.993164)
			(xy 128.692818 -274.94538) (xy 128.688858 -274.896326) (xy 128.370584 -274.896326) (xy 128.370072 -274.921772)
			(xy 128.361908 -274.972006) (xy 128.345792 -275.02028) (xy 128.322141 -275.065343) (xy 128.291568 -275.106029)
			(xy 128.254864 -275.141284) (xy 128.21298 -275.170194) (xy 128.167001 -275.192011) (xy 128.118117 -275.206171)
			(xy 128.067596 -275.212305) (xy 128.016744 -275.210256) (xy 127.96688 -275.200076) (xy 127.919294 -275.182029)
			(xy 127.87522 -275.156583) (xy 127.835798 -275.124396) (xy 127.80205 -275.086302) (xy 127.774849 -275.043288)
			(xy 127.754901 -274.996468) (xy 127.742722 -274.947054) (xy 127.738627 -274.896326) (xy 127.419617 -274.896326)
			(xy 127.419616 -274.921665) (xy 127.411237 -274.971677) (xy 127.394709 -275.019617) (xy 127.370489 -275.064168)
			(xy 127.339241 -275.104105) (xy 127.301823 -275.13833) (xy 127.259266 -275.165903) (xy 127.23622 -275.176488)
			(xy 127.22225 -275.182584) (xy 127.20574 -275.20773) (xy 127.20574 -275.408644) (xy 127.206191 -275.418485)
			(xy 127.213615 -275.436711) (xy 127.227381 -275.450775) (xy 127.23622 -275.455126) (xy 127.335534 -275.49856)
			(xy 127.365252 -275.49348) (xy 127.376682 -275.483066) (xy 127.393711 -275.467737) (xy 127.431504 -275.441838)
			(xy 127.472743 -275.421879) (xy 127.516503 -275.408308) (xy 127.5618 -275.401431) (xy 127.584708 -275.401024)
			(xy 127.60996 -275.401546) (xy 127.659776 -275.40986) (xy 127.707543 -275.42626) (xy 127.75196 -275.450298)
			(xy 127.791815 -275.481319) (xy 127.82602 -275.518477) (xy 127.853643 -275.560758) (xy 127.873931 -275.607009)
			(xy 127.886328 -275.655968) (xy 127.890499 -275.7063) (xy 127.890496 -275.706332) (xy 128.208527 -275.706332)
			(xy 128.212622 -275.655604) (xy 128.224801 -275.60619) (xy 128.244749 -275.55937) (xy 128.27195 -275.516356)
			(xy 128.305698 -275.478262) (xy 128.34512 -275.446075) (xy 128.389194 -275.420629) (xy 128.43678 -275.402582)
			(xy 128.486644 -275.392402) (xy 128.537496 -275.390353) (xy 128.588017 -275.396487) (xy 128.636901 -275.410647)
			(xy 128.68288 -275.432464) (xy 128.724764 -275.461374) (xy 128.761468 -275.496629) (xy 128.792041 -275.537315)
			(xy 128.815692 -275.582378) (xy 128.831808 -275.630652) (xy 128.839972 -275.680886) (xy 128.840484 -275.706332)
			(xy 129.148581 -275.706332) (xy 129.152676 -275.655604) (xy 129.164855 -275.60619) (xy 129.184803 -275.55937)
			(xy 129.212004 -275.516356) (xy 129.245752 -275.478262) (xy 129.285174 -275.446075) (xy 129.329248 -275.420629)
			(xy 129.376834 -275.402582) (xy 129.426698 -275.392402) (xy 129.47755 -275.390353) (xy 129.528071 -275.396487)
			(xy 129.576955 -275.410647) (xy 129.622934 -275.432464) (xy 129.664818 -275.461374) (xy 129.701522 -275.496629)
			(xy 129.732095 -275.537315) (xy 129.755746 -275.582378) (xy 129.771862 -275.630652) (xy 129.780026 -275.680886)
			(xy 129.780538 -275.706332) (xy 131.028435 -275.706332) (xy 131.03253 -275.655604) (xy 131.044709 -275.60619)
			(xy 131.064657 -275.55937) (xy 131.091858 -275.516356) (xy 131.125606 -275.478262) (xy 131.165028 -275.446075)
			(xy 131.209102 -275.420629) (xy 131.256688 -275.402582) (xy 131.306552 -275.392402) (xy 131.357404 -275.390353)
			(xy 131.407925 -275.396487) (xy 131.456809 -275.410647) (xy 131.502788 -275.432464) (xy 131.544672 -275.461374)
			(xy 131.581376 -275.496629) (xy 131.611949 -275.537315) (xy 131.6356 -275.582378) (xy 131.651716 -275.630652)
			(xy 131.65988 -275.680886) (xy 131.660392 -275.706332) (xy 131.97892 -275.706332) (xy 131.98288 -275.657278)
			(xy 131.994657 -275.609494) (xy 132.013948 -275.564218) (xy 132.040251 -275.522622) (xy 132.072886 -275.485785)
			(xy 132.111007 -275.45466) (xy 132.153628 -275.430053) (xy 132.199644 -275.412601) (xy 132.247863 -275.402757)
			(xy 132.297038 -275.400776) (xy 132.345893 -275.406708) (xy 132.393164 -275.4204) (xy 132.437626 -275.441498)
			(xy 132.478129 -275.469454) (xy 132.513622 -275.503546) (xy 132.543187 -275.54289) (xy 132.566058 -275.586467)
			(xy 132.581642 -275.633148) (xy 132.589537 -275.681725) (xy 132.590032 -275.706332) (xy 132.908543 -275.706332)
			(xy 132.912638 -275.655604) (xy 132.924817 -275.60619) (xy 132.944765 -275.55937) (xy 132.971966 -275.516356)
			(xy 133.005714 -275.478262) (xy 133.045136 -275.446075) (xy 133.08921 -275.420629) (xy 133.136796 -275.402582)
			(xy 133.18666 -275.392402) (xy 133.237512 -275.390353) (xy 133.288033 -275.396487) (xy 133.336917 -275.410647)
			(xy 133.382896 -275.432464) (xy 133.42478 -275.461374) (xy 133.461484 -275.496629) (xy 133.492057 -275.537315)
			(xy 133.515708 -275.582378) (xy 133.531824 -275.630652) (xy 133.539988 -275.680886) (xy 133.5405 -275.706332)
			(xy 133.859028 -275.706332) (xy 133.862988 -275.657278) (xy 133.874765 -275.609494) (xy 133.894056 -275.564218)
			(xy 133.920359 -275.522622) (xy 133.952994 -275.485785) (xy 133.991115 -275.45466) (xy 134.033736 -275.430053)
			(xy 134.079752 -275.412601) (xy 134.127971 -275.402757) (xy 134.177146 -275.400776) (xy 134.226001 -275.406708)
			(xy 134.273272 -275.4204) (xy 134.317734 -275.441498) (xy 134.358237 -275.469454) (xy 134.39373 -275.503546)
			(xy 134.423295 -275.54289) (xy 134.446166 -275.586467) (xy 134.46175 -275.633148) (xy 134.469645 -275.681725)
			(xy 134.47014 -275.706332) (xy 134.788397 -275.706332) (xy 134.792492 -275.655604) (xy 134.804671 -275.60619)
			(xy 134.824619 -275.55937) (xy 134.85182 -275.516356) (xy 134.885568 -275.478262) (xy 134.92499 -275.446075)
			(xy 134.969064 -275.420629) (xy 135.01665 -275.402582) (xy 135.066514 -275.392402) (xy 135.117366 -275.390353)
			(xy 135.167887 -275.396487) (xy 135.216771 -275.410647) (xy 135.26275 -275.432464) (xy 135.304634 -275.461374)
			(xy 135.341338 -275.496629) (xy 135.371911 -275.537315) (xy 135.395562 -275.582378) (xy 135.411678 -275.630652)
			(xy 135.419842 -275.680886) (xy 135.420354 -275.706332) (xy 135.728451 -275.706332) (xy 135.732546 -275.655604)
			(xy 135.744725 -275.60619) (xy 135.764673 -275.55937) (xy 135.791874 -275.516356) (xy 135.825622 -275.478262)
			(xy 135.865044 -275.446075) (xy 135.909118 -275.420629) (xy 135.956704 -275.402582) (xy 136.006568 -275.392402)
			(xy 136.05742 -275.390353) (xy 136.107941 -275.396487) (xy 136.156825 -275.410647) (xy 136.202804 -275.432464)
			(xy 136.244688 -275.461374) (xy 136.281392 -275.496629) (xy 136.311965 -275.537315) (xy 136.335616 -275.582378)
			(xy 136.351732 -275.630652) (xy 136.359896 -275.680886) (xy 136.360408 -275.706332) (xy 137.608559 -275.706332)
			(xy 137.612654 -275.655604) (xy 137.624833 -275.60619) (xy 137.644781 -275.55937) (xy 137.671982 -275.516356)
			(xy 137.70573 -275.478262) (xy 137.745152 -275.446075) (xy 137.789226 -275.420629) (xy 137.836812 -275.402582)
			(xy 137.886676 -275.392402) (xy 137.937528 -275.390353) (xy 137.988049 -275.396487) (xy 138.036933 -275.410647)
			(xy 138.082912 -275.432464) (xy 138.124796 -275.461374) (xy 138.1615 -275.496629) (xy 138.192073 -275.537315)
			(xy 138.215724 -275.582378) (xy 138.23184 -275.630652) (xy 138.240004 -275.680886) (xy 138.240516 -275.706332)
			(xy 138.559044 -275.706332) (xy 138.563004 -275.657278) (xy 138.574781 -275.609494) (xy 138.594072 -275.564218)
			(xy 138.620375 -275.522622) (xy 138.65301 -275.485785) (xy 138.691131 -275.45466) (xy 138.733752 -275.430053)
			(xy 138.779768 -275.412601) (xy 138.827987 -275.402757) (xy 138.877162 -275.400776) (xy 138.926017 -275.406708)
			(xy 138.973288 -275.4204) (xy 139.01775 -275.441498) (xy 139.058253 -275.469454) (xy 139.093746 -275.503546)
			(xy 139.123311 -275.54289) (xy 139.146182 -275.586467) (xy 139.161766 -275.633148) (xy 139.169661 -275.681725)
			(xy 139.170156 -275.706332) (xy 139.488413 -275.706332) (xy 139.492508 -275.655604) (xy 139.504687 -275.60619)
			(xy 139.524635 -275.55937) (xy 139.551836 -275.516356) (xy 139.585584 -275.478262) (xy 139.625006 -275.446075)
			(xy 139.66908 -275.420629) (xy 139.716666 -275.402582) (xy 139.76653 -275.392402) (xy 139.817382 -275.390353)
			(xy 139.867903 -275.396487) (xy 139.916787 -275.410647) (xy 139.962766 -275.432464) (xy 140.00465 -275.461374)
			(xy 140.041354 -275.496629) (xy 140.071927 -275.537315) (xy 140.095578 -275.582378) (xy 140.111694 -275.630652)
			(xy 140.119858 -275.680886) (xy 140.12037 -275.706332) (xy 140.438898 -275.706332) (xy 140.442858 -275.657278)
			(xy 140.454635 -275.609494) (xy 140.473926 -275.564218) (xy 140.500229 -275.522622) (xy 140.532864 -275.485785)
			(xy 140.570985 -275.45466) (xy 140.613606 -275.430053) (xy 140.659622 -275.412601) (xy 140.707841 -275.402757)
			(xy 140.757016 -275.400776) (xy 140.805871 -275.406708) (xy 140.853142 -275.4204) (xy 140.897604 -275.441498)
			(xy 140.938107 -275.469454) (xy 140.9736 -275.503546) (xy 141.003165 -275.54289) (xy 141.026036 -275.586467)
			(xy 141.04162 -275.633148) (xy 141.049515 -275.681725) (xy 141.05001 -275.706332) (xy 141.368521 -275.706332)
			(xy 141.372616 -275.655604) (xy 141.384795 -275.60619) (xy 141.404743 -275.55937) (xy 141.431944 -275.516356)
			(xy 141.465692 -275.478262) (xy 141.505114 -275.446075) (xy 141.549188 -275.420629) (xy 141.596774 -275.402582)
			(xy 141.646638 -275.392402) (xy 141.69749 -275.390353) (xy 141.748011 -275.396487) (xy 141.796895 -275.410647)
			(xy 141.842874 -275.432464) (xy 141.884758 -275.461374) (xy 141.921462 -275.496629) (xy 141.952035 -275.537315)
			(xy 141.975686 -275.582378) (xy 141.991802 -275.630652) (xy 141.999966 -275.680886) (xy 142.000478 -275.706332)
			(xy 142.308575 -275.706332) (xy 142.31267 -275.655604) (xy 142.324849 -275.60619) (xy 142.344797 -275.55937)
			(xy 142.371998 -275.516356) (xy 142.405746 -275.478262) (xy 142.445168 -275.446075) (xy 142.489242 -275.420629)
			(xy 142.536828 -275.402582) (xy 142.586692 -275.392402) (xy 142.637544 -275.390353) (xy 142.688065 -275.396487)
			(xy 142.736949 -275.410647) (xy 142.782928 -275.432464) (xy 142.824812 -275.461374) (xy 142.861516 -275.496629)
			(xy 142.892089 -275.537315) (xy 142.91574 -275.582378) (xy 142.931856 -275.630652) (xy 142.94002 -275.680886)
			(xy 142.940532 -275.706332) (xy 145.138914 -275.706332) (xy 145.142874 -275.657278) (xy 145.154651 -275.609494)
			(xy 145.173942 -275.564218) (xy 145.200245 -275.522622) (xy 145.23288 -275.485785) (xy 145.271001 -275.45466)
			(xy 145.313622 -275.430053) (xy 145.359638 -275.412601) (xy 145.407857 -275.402757) (xy 145.457032 -275.400776)
			(xy 145.505887 -275.406708) (xy 145.553158 -275.4204) (xy 145.59762 -275.441498) (xy 145.638123 -275.469454)
			(xy 145.673616 -275.503546) (xy 145.697545 -275.53539) (xy 165.442915 -275.53539) (xy 165.44685 -275.481619)
			(xy 165.458573 -275.428995) (xy 165.477833 -275.378638) (xy 165.504219 -275.331621) (xy 165.537171 -275.288948)
			(xy 165.575984 -275.251527) (xy 165.619832 -275.220157) (xy 165.66778 -275.195505) (xy 165.718807 -275.178097)
			(xy 165.771825 -275.168304) (xy 165.825704 -275.166335) (xy 165.879295 -275.172232) (xy 165.931456 -275.185868)
			(xy 165.981076 -275.206955) (xy 166.027097 -275.235041) (xy 166.068539 -275.269529) (xy 166.104517 -275.309683)
			(xy 166.134265 -275.354647) (xy 166.15715 -275.403464) (xy 166.172682 -275.455093) (xy 166.180532 -275.508433)
			(xy 166.181024 -275.53539) (xy 172.986969 -275.53539) (xy 172.990904 -275.481619) (xy 173.002627 -275.428995)
			(xy 173.021887 -275.378638) (xy 173.048273 -275.331621) (xy 173.081225 -275.288948) (xy 173.120038 -275.251527)
			(xy 173.163886 -275.220157) (xy 173.211834 -275.195505) (xy 173.262861 -275.178097) (xy 173.315879 -275.168304)
			(xy 173.369758 -275.166335) (xy 173.423349 -275.172232) (xy 173.47551 -275.185868) (xy 173.52513 -275.206955)
			(xy 173.571151 -275.235041) (xy 173.612593 -275.269529) (xy 173.648571 -275.309683) (xy 173.678319 -275.354647)
			(xy 173.701204 -275.403464) (xy 173.716736 -275.455093) (xy 173.724586 -275.508433) (xy 173.725078 -275.53539)
			(xy 173.724586 -275.562347) (xy 173.716736 -275.615687) (xy 173.701204 -275.667316) (xy 173.678319 -275.716133)
			(xy 173.648571 -275.761097) (xy 173.612593 -275.801251) (xy 173.571151 -275.835739) (xy 173.52513 -275.863825)
			(xy 173.47551 -275.884912) (xy 173.423349 -275.898548) (xy 173.369758 -275.904445) (xy 173.315879 -275.902476)
			(xy 173.262861 -275.892683) (xy 173.211834 -275.875275) (xy 173.163886 -275.850623) (xy 173.120038 -275.819253)
			(xy 173.081225 -275.781832) (xy 173.048273 -275.739159) (xy 173.021887 -275.692142) (xy 173.002627 -275.641785)
			(xy 172.990904 -275.589161) (xy 172.986969 -275.53539) (xy 166.181024 -275.53539) (xy 166.180532 -275.562347)
			(xy 166.172682 -275.615687) (xy 166.15715 -275.667316) (xy 166.134265 -275.716133) (xy 166.104517 -275.761097)
			(xy 166.068539 -275.801251) (xy 166.027097 -275.835739) (xy 165.981076 -275.863825) (xy 165.931456 -275.884912)
			(xy 165.879295 -275.898548) (xy 165.825704 -275.904445) (xy 165.771825 -275.902476) (xy 165.718807 -275.892683)
			(xy 165.66778 -275.875275) (xy 165.619832 -275.850623) (xy 165.575984 -275.819253) (xy 165.537171 -275.781832)
			(xy 165.504219 -275.739159) (xy 165.477833 -275.692142) (xy 165.458573 -275.641785) (xy 165.44685 -275.589161)
			(xy 165.442915 -275.53539) (xy 145.697545 -275.53539) (xy 145.703181 -275.54289) (xy 145.726052 -275.586467)
			(xy 145.741636 -275.633148) (xy 145.749531 -275.681725) (xy 145.750026 -275.706332) (xy 145.749531 -275.730939)
			(xy 145.741636 -275.779516) (xy 145.726052 -275.826197) (xy 145.703181 -275.869774) (xy 145.673616 -275.909118)
			(xy 145.638123 -275.94321) (xy 145.59762 -275.971166) (xy 145.553158 -275.992264) (xy 145.505887 -276.005956)
			(xy 145.457032 -276.011888) (xy 145.407857 -276.009907) (xy 145.359638 -276.000063) (xy 145.313622 -275.982611)
			(xy 145.271001 -275.958004) (xy 145.23288 -275.926879) (xy 145.200245 -275.890042) (xy 145.173942 -275.848446)
			(xy 145.154651 -275.80317) (xy 145.142874 -275.755386) (xy 145.138914 -275.706332) (xy 142.940532 -275.706332)
			(xy 142.94002 -275.731778) (xy 142.931856 -275.782012) (xy 142.91574 -275.830286) (xy 142.892089 -275.875349)
			(xy 142.861516 -275.916035) (xy 142.824812 -275.95129) (xy 142.782928 -275.9802) (xy 142.736949 -276.002017)
			(xy 142.688065 -276.016177) (xy 142.637544 -276.022311) (xy 142.586692 -276.020262) (xy 142.536828 -276.010082)
			(xy 142.489242 -275.992035) (xy 142.445168 -275.966589) (xy 142.405746 -275.934402) (xy 142.371998 -275.896308)
			(xy 142.344797 -275.853294) (xy 142.324849 -275.806474) (xy 142.31267 -275.75706) (xy 142.308575 -275.706332)
			(xy 142.000478 -275.706332) (xy 141.999966 -275.731778) (xy 141.991802 -275.782012) (xy 141.975686 -275.830286)
			(xy 141.952035 -275.875349) (xy 141.921462 -275.916035) (xy 141.884758 -275.95129) (xy 141.842874 -275.9802)
			(xy 141.796895 -276.002017) (xy 141.748011 -276.016177) (xy 141.69749 -276.022311) (xy 141.646638 -276.020262)
			(xy 141.596774 -276.010082) (xy 141.549188 -275.992035) (xy 141.505114 -275.966589) (xy 141.465692 -275.934402)
			(xy 141.431944 -275.896308) (xy 141.404743 -275.853294) (xy 141.384795 -275.806474) (xy 141.372616 -275.75706)
			(xy 141.368521 -275.706332) (xy 141.05001 -275.706332) (xy 141.049515 -275.730939) (xy 141.04162 -275.779516)
			(xy 141.026036 -275.826197) (xy 141.003165 -275.869774) (xy 140.9736 -275.909118) (xy 140.938107 -275.94321)
			(xy 140.897604 -275.971166) (xy 140.853142 -275.992264) (xy 140.805871 -276.005956) (xy 140.757016 -276.011888)
			(xy 140.707841 -276.009907) (xy 140.659622 -276.000063) (xy 140.613606 -275.982611) (xy 140.570985 -275.958004)
			(xy 140.532864 -275.926879) (xy 140.500229 -275.890042) (xy 140.473926 -275.848446) (xy 140.454635 -275.80317)
			(xy 140.442858 -275.755386) (xy 140.438898 -275.706332) (xy 140.12037 -275.706332) (xy 140.119858 -275.731778)
			(xy 140.111694 -275.782012) (xy 140.095578 -275.830286) (xy 140.071927 -275.875349) (xy 140.041354 -275.916035)
			(xy 140.00465 -275.95129) (xy 139.962766 -275.9802) (xy 139.916787 -276.002017) (xy 139.867903 -276.016177)
			(xy 139.817382 -276.022311) (xy 139.76653 -276.020262) (xy 139.716666 -276.010082) (xy 139.66908 -275.992035)
			(xy 139.625006 -275.966589) (xy 139.585584 -275.934402) (xy 139.551836 -275.896308) (xy 139.524635 -275.853294)
			(xy 139.504687 -275.806474) (xy 139.492508 -275.75706) (xy 139.488413 -275.706332) (xy 139.170156 -275.706332)
			(xy 139.169661 -275.730939) (xy 139.161766 -275.779516) (xy 139.146182 -275.826197) (xy 139.123311 -275.869774)
			(xy 139.093746 -275.909118) (xy 139.058253 -275.94321) (xy 139.01775 -275.971166) (xy 138.973288 -275.992264)
			(xy 138.926017 -276.005956) (xy 138.877162 -276.011888) (xy 138.827987 -276.009907) (xy 138.779768 -276.000063)
			(xy 138.733752 -275.982611) (xy 138.691131 -275.958004) (xy 138.65301 -275.926879) (xy 138.620375 -275.890042)
			(xy 138.594072 -275.848446) (xy 138.574781 -275.80317) (xy 138.563004 -275.755386) (xy 138.559044 -275.706332)
			(xy 138.240516 -275.706332) (xy 138.240004 -275.731778) (xy 138.23184 -275.782012) (xy 138.215724 -275.830286)
			(xy 138.192073 -275.875349) (xy 138.1615 -275.916035) (xy 138.124796 -275.95129) (xy 138.082912 -275.9802)
			(xy 138.036933 -276.002017) (xy 137.988049 -276.016177) (xy 137.937528 -276.022311) (xy 137.886676 -276.020262)
			(xy 137.836812 -276.010082) (xy 137.789226 -275.992035) (xy 137.745152 -275.966589) (xy 137.70573 -275.934402)
			(xy 137.671982 -275.896308) (xy 137.644781 -275.853294) (xy 137.624833 -275.806474) (xy 137.612654 -275.75706)
			(xy 137.608559 -275.706332) (xy 136.360408 -275.706332) (xy 136.359896 -275.731778) (xy 136.351732 -275.782012)
			(xy 136.335616 -275.830286) (xy 136.311965 -275.875349) (xy 136.281392 -275.916035) (xy 136.244688 -275.95129)
			(xy 136.202804 -275.9802) (xy 136.156825 -276.002017) (xy 136.107941 -276.016177) (xy 136.05742 -276.022311)
			(xy 136.006568 -276.020262) (xy 135.956704 -276.010082) (xy 135.909118 -275.992035) (xy 135.865044 -275.966589)
			(xy 135.825622 -275.934402) (xy 135.791874 -275.896308) (xy 135.764673 -275.853294) (xy 135.744725 -275.806474)
			(xy 135.732546 -275.75706) (xy 135.728451 -275.706332) (xy 135.420354 -275.706332) (xy 135.419842 -275.731778)
			(xy 135.411678 -275.782012) (xy 135.395562 -275.830286) (xy 135.371911 -275.875349) (xy 135.341338 -275.916035)
			(xy 135.304634 -275.95129) (xy 135.26275 -275.9802) (xy 135.216771 -276.002017) (xy 135.167887 -276.016177)
			(xy 135.117366 -276.022311) (xy 135.066514 -276.020262) (xy 135.01665 -276.010082) (xy 134.969064 -275.992035)
			(xy 134.92499 -275.966589) (xy 134.885568 -275.934402) (xy 134.85182 -275.896308) (xy 134.824619 -275.853294)
			(xy 134.804671 -275.806474) (xy 134.792492 -275.75706) (xy 134.788397 -275.706332) (xy 134.47014 -275.706332)
			(xy 134.469645 -275.730939) (xy 134.46175 -275.779516) (xy 134.446166 -275.826197) (xy 134.423295 -275.869774)
			(xy 134.39373 -275.909118) (xy 134.358237 -275.94321) (xy 134.317734 -275.971166) (xy 134.273272 -275.992264)
			(xy 134.226001 -276.005956) (xy 134.177146 -276.011888) (xy 134.127971 -276.009907) (xy 134.079752 -276.000063)
			(xy 134.033736 -275.982611) (xy 133.991115 -275.958004) (xy 133.952994 -275.926879) (xy 133.920359 -275.890042)
			(xy 133.894056 -275.848446) (xy 133.874765 -275.80317) (xy 133.862988 -275.755386) (xy 133.859028 -275.706332)
			(xy 133.5405 -275.706332) (xy 133.539988 -275.731778) (xy 133.531824 -275.782012) (xy 133.515708 -275.830286)
			(xy 133.492057 -275.875349) (xy 133.461484 -275.916035) (xy 133.42478 -275.95129) (xy 133.382896 -275.9802)
			(xy 133.336917 -276.002017) (xy 133.288033 -276.016177) (xy 133.237512 -276.022311) (xy 133.18666 -276.020262)
			(xy 133.136796 -276.010082) (xy 133.08921 -275.992035) (xy 133.045136 -275.966589) (xy 133.005714 -275.934402)
			(xy 132.971966 -275.896308) (xy 132.944765 -275.853294) (xy 132.924817 -275.806474) (xy 132.912638 -275.75706)
			(xy 132.908543 -275.706332) (xy 132.590032 -275.706332) (xy 132.589537 -275.730939) (xy 132.581642 -275.779516)
			(xy 132.566058 -275.826197) (xy 132.543187 -275.869774) (xy 132.513622 -275.909118) (xy 132.478129 -275.94321)
			(xy 132.437626 -275.971166) (xy 132.393164 -275.992264) (xy 132.345893 -276.005956) (xy 132.297038 -276.011888)
			(xy 132.247863 -276.009907) (xy 132.199644 -276.000063) (xy 132.153628 -275.982611) (xy 132.111007 -275.958004)
			(xy 132.072886 -275.926879) (xy 132.040251 -275.890042) (xy 132.013948 -275.848446) (xy 131.994657 -275.80317)
			(xy 131.98288 -275.755386) (xy 131.97892 -275.706332) (xy 131.660392 -275.706332) (xy 131.65988 -275.731778)
			(xy 131.651716 -275.782012) (xy 131.6356 -275.830286) (xy 131.611949 -275.875349) (xy 131.581376 -275.916035)
			(xy 131.544672 -275.95129) (xy 131.502788 -275.9802) (xy 131.456809 -276.002017) (xy 131.407925 -276.016177)
			(xy 131.357404 -276.022311) (xy 131.306552 -276.020262) (xy 131.256688 -276.010082) (xy 131.209102 -275.992035)
			(xy 131.165028 -275.966589) (xy 131.125606 -275.934402) (xy 131.091858 -275.896308) (xy 131.064657 -275.853294)
			(xy 131.044709 -275.806474) (xy 131.03253 -275.75706) (xy 131.028435 -275.706332) (xy 129.780538 -275.706332)
			(xy 129.780026 -275.731778) (xy 129.771862 -275.782012) (xy 129.755746 -275.830286) (xy 129.732095 -275.875349)
			(xy 129.701522 -275.916035) (xy 129.664818 -275.95129) (xy 129.622934 -275.9802) (xy 129.576955 -276.002017)
			(xy 129.528071 -276.016177) (xy 129.47755 -276.022311) (xy 129.426698 -276.020262) (xy 129.376834 -276.010082)
			(xy 129.329248 -275.992035) (xy 129.285174 -275.966589) (xy 129.245752 -275.934402) (xy 129.212004 -275.896308)
			(xy 129.184803 -275.853294) (xy 129.164855 -275.806474) (xy 129.152676 -275.75706) (xy 129.148581 -275.706332)
			(xy 128.840484 -275.706332) (xy 128.839972 -275.731778) (xy 128.831808 -275.782012) (xy 128.815692 -275.830286)
			(xy 128.792041 -275.875349) (xy 128.761468 -275.916035) (xy 128.724764 -275.95129) (xy 128.68288 -275.9802)
			(xy 128.636901 -276.002017) (xy 128.588017 -276.016177) (xy 128.537496 -276.022311) (xy 128.486644 -276.020262)
			(xy 128.43678 -276.010082) (xy 128.389194 -275.992035) (xy 128.34512 -275.966589) (xy 128.305698 -275.934402)
			(xy 128.27195 -275.896308) (xy 128.244749 -275.853294) (xy 128.224801 -275.806474) (xy 128.212622 -275.75706)
			(xy 128.208527 -275.706332) (xy 127.890496 -275.706332) (xy 127.886328 -275.756632) (xy 127.873931 -275.805591)
			(xy 127.853643 -275.851842) (xy 127.82602 -275.894123) (xy 127.791815 -275.931281) (xy 127.75196 -275.962302)
			(xy 127.707543 -275.98634) (xy 127.659776 -276.00274) (xy 127.60996 -276.011054) (xy 127.584708 -276.01164)
			(xy 127.561803 -276.011209) (xy 127.516511 -276.004324) (xy 127.472756 -275.990752) (xy 127.431519 -275.970798)
			(xy 127.393724 -275.944909) (xy 127.376682 -275.929598) (xy 127.365252 -275.919184) (xy 127.335534 -275.914104)
			(xy 127.23622 -275.957538) (xy 127.227396 -275.961901) (xy 127.213668 -275.975984) (xy 127.206226 -275.994188)
			(xy 127.20574 -276.00402) (xy 127.20574 -276.204934) (xy 127.22225 -276.23008) (xy 127.23622 -276.236176)
			(xy 127.259283 -276.246718) (xy 127.301837 -276.274294) (xy 127.33925 -276.308521) (xy 127.370494 -276.34846)
			(xy 127.39471 -276.393011) (xy 127.411232 -276.440951) (xy 127.419607 -276.490961) (xy 127.419606 -276.516338)
			(xy 127.738627 -276.516338) (xy 127.742722 -276.46561) (xy 127.754901 -276.416196) (xy 127.774849 -276.369376)
			(xy 127.80205 -276.326362) (xy 127.835798 -276.288268) (xy 127.87522 -276.256081) (xy 127.919294 -276.230635)
			(xy 127.96688 -276.212588) (xy 128.016744 -276.202408) (xy 128.067596 -276.200359) (xy 128.118117 -276.206493)
			(xy 128.167001 -276.220653) (xy 128.21298 -276.24247) (xy 128.254864 -276.27138) (xy 128.291568 -276.306635)
			(xy 128.322141 -276.347321) (xy 128.345792 -276.392384) (xy 128.361908 -276.440658) (xy 128.370072 -276.490892)
			(xy 128.370584 -276.516338) (xy 128.688858 -276.516338) (xy 128.692818 -276.467284) (xy 128.704595 -276.4195)
			(xy 128.723886 -276.374224) (xy 128.750189 -276.332628) (xy 128.782824 -276.295791) (xy 128.820945 -276.264666)
			(xy 128.863566 -276.240059) (xy 128.909582 -276.222607) (xy 128.957801 -276.212763) (xy 129.006976 -276.210782)
			(xy 129.055831 -276.216714) (xy 129.103102 -276.230406) (xy 129.147564 -276.251504) (xy 129.188067 -276.27946)
			(xy 129.22356 -276.313552) (xy 129.253125 -276.352896) (xy 129.275996 -276.396473) (xy 129.29158 -276.443154)
			(xy 129.299475 -276.491731) (xy 129.29997 -276.516338) (xy 129.618481 -276.516338) (xy 129.622576 -276.46561)
			(xy 129.634755 -276.416196) (xy 129.654703 -276.369376) (xy 129.681904 -276.326362) (xy 129.715652 -276.288268)
			(xy 129.755074 -276.256081) (xy 129.799148 -276.230635) (xy 129.846734 -276.212588) (xy 129.896598 -276.202408)
			(xy 129.94745 -276.200359) (xy 129.997971 -276.206493) (xy 130.046855 -276.220653) (xy 130.092834 -276.24247)
			(xy 130.134718 -276.27138) (xy 130.171422 -276.306635) (xy 130.201995 -276.347321) (xy 130.225646 -276.392384)
			(xy 130.241762 -276.440658) (xy 130.249926 -276.490892) (xy 130.250438 -276.516338) (xy 130.568966 -276.516338)
			(xy 130.572926 -276.467284) (xy 130.584703 -276.4195) (xy 130.603994 -276.374224) (xy 130.630297 -276.332628)
			(xy 130.662932 -276.295791) (xy 130.701053 -276.264666) (xy 130.743674 -276.240059) (xy 130.78969 -276.222607)
			(xy 130.837909 -276.212763) (xy 130.887084 -276.210782) (xy 130.935939 -276.216714) (xy 130.98321 -276.230406)
			(xy 131.027672 -276.251504) (xy 131.068175 -276.27946) (xy 131.103668 -276.313552) (xy 131.133233 -276.352896)
			(xy 131.156104 -276.396473) (xy 131.171688 -276.443154) (xy 131.179583 -276.491731) (xy 131.180078 -276.516338)
			(xy 131.498589 -276.516338) (xy 131.502684 -276.46561) (xy 131.514863 -276.416196) (xy 131.534811 -276.369376)
			(xy 131.562012 -276.326362) (xy 131.59576 -276.288268) (xy 131.635182 -276.256081) (xy 131.679256 -276.230635)
			(xy 131.726842 -276.212588) (xy 131.776706 -276.202408) (xy 131.827558 -276.200359) (xy 131.878079 -276.206493)
			(xy 131.926963 -276.220653) (xy 131.972942 -276.24247) (xy 132.014826 -276.27138) (xy 132.05153 -276.306635)
			(xy 132.082103 -276.347321) (xy 132.105754 -276.392384) (xy 132.12187 -276.440658) (xy 132.130034 -276.490892)
			(xy 132.130546 -276.516338) (xy 132.438643 -276.516338) (xy 132.442738 -276.46561) (xy 132.454917 -276.416196)
			(xy 132.474865 -276.369376) (xy 132.502066 -276.326362) (xy 132.535814 -276.288268) (xy 132.575236 -276.256081)
			(xy 132.61931 -276.230635) (xy 132.666896 -276.212588) (xy 132.71676 -276.202408) (xy 132.767612 -276.200359)
			(xy 132.818133 -276.206493) (xy 132.867017 -276.220653) (xy 132.912996 -276.24247) (xy 132.95488 -276.27138)
			(xy 132.991584 -276.306635) (xy 133.022157 -276.347321) (xy 133.045808 -276.392384) (xy 133.061924 -276.440658)
			(xy 133.070088 -276.490892) (xy 133.0706 -276.516338) (xy 133.388874 -276.516338) (xy 133.392834 -276.467284)
			(xy 133.404611 -276.4195) (xy 133.423902 -276.374224) (xy 133.450205 -276.332628) (xy 133.48284 -276.295791)
			(xy 133.520961 -276.264666) (xy 133.563582 -276.240059) (xy 133.609598 -276.222607) (xy 133.657817 -276.212763)
			(xy 133.706992 -276.210782) (xy 133.755847 -276.216714) (xy 133.803118 -276.230406) (xy 133.84758 -276.251504)
			(xy 133.888083 -276.27946) (xy 133.923576 -276.313552) (xy 133.953141 -276.352896) (xy 133.976012 -276.396473)
			(xy 133.991596 -276.443154) (xy 133.999491 -276.491731) (xy 133.999986 -276.516338) (xy 134.318497 -276.516338)
			(xy 134.322592 -276.46561) (xy 134.334771 -276.416196) (xy 134.354719 -276.369376) (xy 134.38192 -276.326362)
			(xy 134.415668 -276.288268) (xy 134.45509 -276.256081) (xy 134.499164 -276.230635) (xy 134.54675 -276.212588)
			(xy 134.596614 -276.202408) (xy 134.647466 -276.200359) (xy 134.697987 -276.206493) (xy 134.746871 -276.220653)
			(xy 134.79285 -276.24247) (xy 134.834734 -276.27138) (xy 134.871438 -276.306635) (xy 134.902011 -276.347321)
			(xy 134.925662 -276.392384) (xy 134.941778 -276.440658) (xy 134.949942 -276.490892) (xy 134.950454 -276.516338)
			(xy 135.268982 -276.516338) (xy 135.272942 -276.467284) (xy 135.284719 -276.4195) (xy 135.30401 -276.374224)
			(xy 135.330313 -276.332628) (xy 135.362948 -276.295791) (xy 135.401069 -276.264666) (xy 135.44369 -276.240059)
			(xy 135.489706 -276.222607) (xy 135.537925 -276.212763) (xy 135.5871 -276.210782) (xy 135.635955 -276.216714)
			(xy 135.683226 -276.230406) (xy 135.727688 -276.251504) (xy 135.768191 -276.27946) (xy 135.803684 -276.313552)
			(xy 135.833249 -276.352896) (xy 135.85612 -276.396473) (xy 135.871704 -276.443154) (xy 135.879599 -276.491731)
			(xy 135.880094 -276.516338) (xy 136.198605 -276.516338) (xy 136.2027 -276.46561) (xy 136.214879 -276.416196)
			(xy 136.234827 -276.369376) (xy 136.262028 -276.326362) (xy 136.295776 -276.288268) (xy 136.335198 -276.256081)
			(xy 136.379272 -276.230635) (xy 136.426858 -276.212588) (xy 136.476722 -276.202408) (xy 136.527574 -276.200359)
			(xy 136.578095 -276.206493) (xy 136.626979 -276.220653) (xy 136.672958 -276.24247) (xy 136.714842 -276.27138)
			(xy 136.751546 -276.306635) (xy 136.782119 -276.347321) (xy 136.80577 -276.392384) (xy 136.821886 -276.440658)
			(xy 136.83005 -276.490892) (xy 136.830562 -276.516338) (xy 137.148836 -276.516338) (xy 137.152796 -276.467284)
			(xy 137.164573 -276.4195) (xy 137.183864 -276.374224) (xy 137.210167 -276.332628) (xy 137.242802 -276.295791)
			(xy 137.280923 -276.264666) (xy 137.323544 -276.240059) (xy 137.36956 -276.222607) (xy 137.417779 -276.212763)
			(xy 137.466954 -276.210782) (xy 137.515809 -276.216714) (xy 137.56308 -276.230406) (xy 137.607542 -276.251504)
			(xy 137.648045 -276.27946) (xy 137.683538 -276.313552) (xy 137.713103 -276.352896) (xy 137.735974 -276.396473)
			(xy 137.751558 -276.443154) (xy 137.759453 -276.491731) (xy 137.759948 -276.516338) (xy 138.078459 -276.516338)
			(xy 138.082554 -276.46561) (xy 138.094733 -276.416196) (xy 138.114681 -276.369376) (xy 138.141882 -276.326362)
			(xy 138.17563 -276.288268) (xy 138.215052 -276.256081) (xy 138.259126 -276.230635) (xy 138.306712 -276.212588)
			(xy 138.356576 -276.202408) (xy 138.407428 -276.200359) (xy 138.457949 -276.206493) (xy 138.506833 -276.220653)
			(xy 138.552812 -276.24247) (xy 138.594696 -276.27138) (xy 138.6314 -276.306635) (xy 138.661973 -276.347321)
			(xy 138.685624 -276.392384) (xy 138.70174 -276.440658) (xy 138.709904 -276.490892) (xy 138.710416 -276.516338)
			(xy 139.018513 -276.516338) (xy 139.022608 -276.46561) (xy 139.034787 -276.416196) (xy 139.054735 -276.369376)
			(xy 139.081936 -276.326362) (xy 139.115684 -276.288268) (xy 139.155106 -276.256081) (xy 139.19918 -276.230635)
			(xy 139.246766 -276.212588) (xy 139.29663 -276.202408) (xy 139.347482 -276.200359) (xy 139.398003 -276.206493)
			(xy 139.446887 -276.220653) (xy 139.492866 -276.24247) (xy 139.53475 -276.27138) (xy 139.571454 -276.306635)
			(xy 139.602027 -276.347321) (xy 139.625678 -276.392384) (xy 139.641794 -276.440658) (xy 139.649958 -276.490892)
			(xy 139.65047 -276.516338) (xy 139.968998 -276.516338) (xy 139.972958 -276.467284) (xy 139.984735 -276.4195)
			(xy 140.004026 -276.374224) (xy 140.030329 -276.332628) (xy 140.062964 -276.295791) (xy 140.101085 -276.264666)
			(xy 140.143706 -276.240059) (xy 140.189722 -276.222607) (xy 140.237941 -276.212763) (xy 140.287116 -276.210782)
			(xy 140.335971 -276.216714) (xy 140.383242 -276.230406) (xy 140.427704 -276.251504) (xy 140.468207 -276.27946)
			(xy 140.5037 -276.313552) (xy 140.533265 -276.352896) (xy 140.556136 -276.396473) (xy 140.57172 -276.443154)
			(xy 140.579615 -276.491731) (xy 140.58011 -276.516338) (xy 140.898621 -276.516338) (xy 140.902716 -276.46561)
			(xy 140.914895 -276.416196) (xy 140.934843 -276.369376) (xy 140.962044 -276.326362) (xy 140.995792 -276.288268)
			(xy 141.035214 -276.256081) (xy 141.079288 -276.230635) (xy 141.126874 -276.212588) (xy 141.176738 -276.202408)
			(xy 141.22759 -276.200359) (xy 141.278111 -276.206493) (xy 141.326995 -276.220653) (xy 141.372974 -276.24247)
			(xy 141.414858 -276.27138) (xy 141.451562 -276.306635) (xy 141.482135 -276.347321) (xy 141.505786 -276.392384)
			(xy 141.521902 -276.440658) (xy 141.530066 -276.490892) (xy 141.530578 -276.516338) (xy 141.848852 -276.516338)
			(xy 141.852812 -276.467284) (xy 141.864589 -276.4195) (xy 141.88388 -276.374224) (xy 141.910183 -276.332628)
			(xy 141.942818 -276.295791) (xy 141.980939 -276.264666) (xy 142.02356 -276.240059) (xy 142.069576 -276.222607)
			(xy 142.117795 -276.212763) (xy 142.16697 -276.210782) (xy 142.215825 -276.216714) (xy 142.263096 -276.230406)
			(xy 142.307558 -276.251504) (xy 142.348061 -276.27946) (xy 142.383554 -276.313552) (xy 142.413119 -276.352896)
			(xy 142.43599 -276.396473) (xy 142.451574 -276.443154) (xy 142.459469 -276.491731) (xy 142.459964 -276.516338)
			(xy 142.778475 -276.516338) (xy 142.78257 -276.46561) (xy 142.794749 -276.416196) (xy 142.814697 -276.369376)
			(xy 142.841898 -276.326362) (xy 142.875646 -276.288268) (xy 142.915068 -276.256081) (xy 142.959142 -276.230635)
			(xy 143.006728 -276.212588) (xy 143.056592 -276.202408) (xy 143.107444 -276.200359) (xy 143.157965 -276.206493)
			(xy 143.206849 -276.220653) (xy 143.252828 -276.24247) (xy 143.294712 -276.27138) (xy 143.331416 -276.306635)
			(xy 143.361989 -276.347321) (xy 143.38564 -276.392384) (xy 143.401756 -276.440658) (xy 143.40992 -276.490892)
			(xy 143.410432 -276.516338) (xy 143.72896 -276.516338) (xy 143.73292 -276.467284) (xy 143.744697 -276.4195)
			(xy 143.763988 -276.374224) (xy 143.790291 -276.332628) (xy 143.822926 -276.295791) (xy 143.861047 -276.264666)
			(xy 143.903668 -276.240059) (xy 143.949684 -276.222607) (xy 143.997903 -276.212763) (xy 144.047078 -276.210782)
			(xy 144.095933 -276.216714) (xy 144.143204 -276.230406) (xy 144.185339 -276.2504) (xy 146.737082 -276.2504)
			(xy 146.741042 -276.201346) (xy 146.752819 -276.153562) (xy 146.77211 -276.108286) (xy 146.798413 -276.06669)
			(xy 146.831048 -276.029853) (xy 146.869169 -275.998728) (xy 146.91179 -275.974121) (xy 146.957806 -275.956669)
			(xy 147.006025 -275.946825) (xy 147.0552 -275.944844) (xy 147.104055 -275.950776) (xy 147.137047 -275.960332)
			(xy 169.276283 -275.960332) (xy 169.280218 -275.906561) (xy 169.291941 -275.853937) (xy 169.311201 -275.80358)
			(xy 169.337587 -275.756563) (xy 169.370539 -275.71389) (xy 169.409352 -275.676469) (xy 169.4532 -275.645099)
			(xy 169.501148 -275.620447) (xy 169.552175 -275.603039) (xy 169.605193 -275.593246) (xy 169.659072 -275.591277)
			(xy 169.712663 -275.597174) (xy 169.764824 -275.61081) (xy 169.814444 -275.631897) (xy 169.860465 -275.659983)
			(xy 169.901907 -275.694471) (xy 169.937885 -275.734625) (xy 169.967633 -275.779589) (xy 169.990518 -275.828406)
			(xy 170.00605 -275.880035) (xy 170.0139 -275.933375) (xy 170.014392 -275.960332) (xy 170.0139 -275.987289)
			(xy 170.00605 -276.040629) (xy 169.990518 -276.092258) (xy 169.967633 -276.141075) (xy 169.937885 -276.186039)
			(xy 169.901907 -276.226193) (xy 169.860465 -276.260681) (xy 169.814444 -276.288767) (xy 169.764824 -276.309854)
			(xy 169.712663 -276.32349) (xy 169.659072 -276.329387) (xy 169.605193 -276.327418) (xy 169.552175 -276.317625)
			(xy 169.501148 -276.300217) (xy 169.4532 -276.275565) (xy 169.409352 -276.244195) (xy 169.370539 -276.206774)
			(xy 169.337587 -276.164101) (xy 169.311201 -276.117084) (xy 169.291941 -276.066727) (xy 169.280218 -276.014103)
			(xy 169.276283 -275.960332) (xy 147.137047 -275.960332) (xy 147.151326 -275.964468) (xy 147.195788 -275.985566)
			(xy 147.236291 -276.013522) (xy 147.271784 -276.047614) (xy 147.301349 -276.086958) (xy 147.32422 -276.130535)
			(xy 147.339804 -276.177216) (xy 147.347699 -276.225793) (xy 147.348194 -276.2504) (xy 147.347699 -276.275007)
			(xy 147.339804 -276.323584) (xy 147.32422 -276.370265) (xy 147.301349 -276.413842) (xy 147.271784 -276.453186)
			(xy 147.236291 -276.487278) (xy 147.195788 -276.515234) (xy 147.151326 -276.536332) (xy 147.104055 -276.550024)
			(xy 147.0552 -276.555956) (xy 147.006025 -276.553975) (xy 146.957806 -276.544131) (xy 146.91179 -276.526679)
			(xy 146.869169 -276.502072) (xy 146.831048 -276.470947) (xy 146.798413 -276.43411) (xy 146.77211 -276.392514)
			(xy 146.752819 -276.347238) (xy 146.741042 -276.299454) (xy 146.737082 -276.2504) (xy 144.185339 -276.2504)
			(xy 144.187666 -276.251504) (xy 144.228169 -276.27946) (xy 144.263662 -276.313552) (xy 144.293227 -276.352896)
			(xy 144.316098 -276.396473) (xy 144.331682 -276.443154) (xy 144.339577 -276.491731) (xy 144.340072 -276.516338)
			(xy 144.339577 -276.540945) (xy 144.331682 -276.589522) (xy 144.316098 -276.636203) (xy 144.293227 -276.67978)
			(xy 144.263662 -276.719124) (xy 144.228169 -276.753216) (xy 144.187666 -276.781172) (xy 144.143204 -276.80227)
			(xy 144.114894 -276.81047) (xy 165.176215 -276.81047) (xy 165.18015 -276.756699) (xy 165.191873 -276.704075)
			(xy 165.211133 -276.653718) (xy 165.237519 -276.606701) (xy 165.270471 -276.564028) (xy 165.309284 -276.526607)
			(xy 165.353132 -276.495237) (xy 165.40108 -276.470585) (xy 165.452107 -276.453177) (xy 165.505125 -276.443384)
			(xy 165.559004 -276.441415) (xy 165.612595 -276.447312) (xy 165.664756 -276.460948) (xy 165.714376 -276.482035)
			(xy 165.760397 -276.510121) (xy 165.801839 -276.544609) (xy 165.837817 -276.584763) (xy 165.867565 -276.629727)
			(xy 165.89045 -276.678544) (xy 165.905982 -276.730173) (xy 165.913832 -276.783513) (xy 165.914324 -276.81047)
			(xy 165.913832 -276.837427) (xy 165.905982 -276.890767) (xy 165.89045 -276.942396) (xy 165.867565 -276.991213)
			(xy 165.837817 -277.036177) (xy 165.801839 -277.076331) (xy 165.760397 -277.110819) (xy 165.714376 -277.138905)
			(xy 165.664756 -277.159992) (xy 165.612595 -277.173628) (xy 165.559004 -277.179525) (xy 165.505125 -277.177556)
			(xy 165.452107 -277.167763) (xy 165.40108 -277.150355) (xy 165.353132 -277.125703) (xy 165.309284 -277.094333)
			(xy 165.270471 -277.056912) (xy 165.237519 -277.014239) (xy 165.211133 -276.967222) (xy 165.191873 -276.916865)
			(xy 165.18015 -276.864241) (xy 165.176215 -276.81047) (xy 144.114894 -276.81047) (xy 144.095933 -276.815962)
			(xy 144.047078 -276.821894) (xy 143.997903 -276.819913) (xy 143.949684 -276.810069) (xy 143.903668 -276.792617)
			(xy 143.861047 -276.76801) (xy 143.822926 -276.736885) (xy 143.790291 -276.700048) (xy 143.763988 -276.658452)
			(xy 143.744697 -276.613176) (xy 143.73292 -276.565392) (xy 143.72896 -276.516338) (xy 143.410432 -276.516338)
			(xy 143.40992 -276.541784) (xy 143.401756 -276.592018) (xy 143.38564 -276.640292) (xy 143.361989 -276.685355)
			(xy 143.331416 -276.726041) (xy 143.294712 -276.761296) (xy 143.252828 -276.790206) (xy 143.206849 -276.812023)
			(xy 143.157965 -276.826183) (xy 143.107444 -276.832317) (xy 143.056592 -276.830268) (xy 143.006728 -276.820088)
			(xy 142.959142 -276.802041) (xy 142.915068 -276.776595) (xy 142.875646 -276.744408) (xy 142.841898 -276.706314)
			(xy 142.814697 -276.6633) (xy 142.794749 -276.61648) (xy 142.78257 -276.567066) (xy 142.778475 -276.516338)
			(xy 142.459964 -276.516338) (xy 142.459469 -276.540945) (xy 142.451574 -276.589522) (xy 142.43599 -276.636203)
			(xy 142.413119 -276.67978) (xy 142.383554 -276.719124) (xy 142.348061 -276.753216) (xy 142.307558 -276.781172)
			(xy 142.263096 -276.80227) (xy 142.215825 -276.815962) (xy 142.16697 -276.821894) (xy 142.117795 -276.819913)
			(xy 142.069576 -276.810069) (xy 142.02356 -276.792617) (xy 141.980939 -276.76801) (xy 141.942818 -276.736885)
			(xy 141.910183 -276.700048) (xy 141.88388 -276.658452) (xy 141.864589 -276.613176) (xy 141.852812 -276.565392)
			(xy 141.848852 -276.516338) (xy 141.530578 -276.516338) (xy 141.530066 -276.541784) (xy 141.521902 -276.592018)
			(xy 141.505786 -276.640292) (xy 141.482135 -276.685355) (xy 141.451562 -276.726041) (xy 141.414858 -276.761296)
			(xy 141.372974 -276.790206) (xy 141.326995 -276.812023) (xy 141.278111 -276.826183) (xy 141.22759 -276.832317)
			(xy 141.176738 -276.830268) (xy 141.126874 -276.820088) (xy 141.079288 -276.802041) (xy 141.035214 -276.776595)
			(xy 140.995792 -276.744408) (xy 140.962044 -276.706314) (xy 140.934843 -276.6633) (xy 140.914895 -276.61648)
			(xy 140.902716 -276.567066) (xy 140.898621 -276.516338) (xy 140.58011 -276.516338) (xy 140.579615 -276.540945)
			(xy 140.57172 -276.589522) (xy 140.556136 -276.636203) (xy 140.533265 -276.67978) (xy 140.5037 -276.719124)
			(xy 140.468207 -276.753216) (xy 140.427704 -276.781172) (xy 140.383242 -276.80227) (xy 140.335971 -276.815962)
			(xy 140.287116 -276.821894) (xy 140.237941 -276.819913) (xy 140.189722 -276.810069) (xy 140.143706 -276.792617)
			(xy 140.101085 -276.76801) (xy 140.062964 -276.736885) (xy 140.030329 -276.700048) (xy 140.004026 -276.658452)
			(xy 139.984735 -276.613176) (xy 139.972958 -276.565392) (xy 139.968998 -276.516338) (xy 139.65047 -276.516338)
			(xy 139.649958 -276.541784) (xy 139.641794 -276.592018) (xy 139.625678 -276.640292) (xy 139.602027 -276.685355)
			(xy 139.571454 -276.726041) (xy 139.53475 -276.761296) (xy 139.492866 -276.790206) (xy 139.446887 -276.812023)
			(xy 139.398003 -276.826183) (xy 139.347482 -276.832317) (xy 139.29663 -276.830268) (xy 139.246766 -276.820088)
			(xy 139.19918 -276.802041) (xy 139.155106 -276.776595) (xy 139.115684 -276.744408) (xy 139.081936 -276.706314)
			(xy 139.054735 -276.6633) (xy 139.034787 -276.61648) (xy 139.022608 -276.567066) (xy 139.018513 -276.516338)
			(xy 138.710416 -276.516338) (xy 138.709904 -276.541784) (xy 138.70174 -276.592018) (xy 138.685624 -276.640292)
			(xy 138.661973 -276.685355) (xy 138.6314 -276.726041) (xy 138.594696 -276.761296) (xy 138.552812 -276.790206)
			(xy 138.506833 -276.812023) (xy 138.457949 -276.826183) (xy 138.407428 -276.832317) (xy 138.356576 -276.830268)
			(xy 138.306712 -276.820088) (xy 138.259126 -276.802041) (xy 138.215052 -276.776595) (xy 138.17563 -276.744408)
			(xy 138.141882 -276.706314) (xy 138.114681 -276.6633) (xy 138.094733 -276.61648) (xy 138.082554 -276.567066)
			(xy 138.078459 -276.516338) (xy 137.759948 -276.516338) (xy 137.759453 -276.540945) (xy 137.751558 -276.589522)
			(xy 137.735974 -276.636203) (xy 137.713103 -276.67978) (xy 137.683538 -276.719124) (xy 137.648045 -276.753216)
			(xy 137.607542 -276.781172) (xy 137.56308 -276.80227) (xy 137.515809 -276.815962) (xy 137.466954 -276.821894)
			(xy 137.417779 -276.819913) (xy 137.36956 -276.810069) (xy 137.323544 -276.792617) (xy 137.280923 -276.76801)
			(xy 137.242802 -276.736885) (xy 137.210167 -276.700048) (xy 137.183864 -276.658452) (xy 137.164573 -276.613176)
			(xy 137.152796 -276.565392) (xy 137.148836 -276.516338) (xy 136.830562 -276.516338) (xy 136.83005 -276.541784)
			(xy 136.821886 -276.592018) (xy 136.80577 -276.640292) (xy 136.782119 -276.685355) (xy 136.751546 -276.726041)
			(xy 136.714842 -276.761296) (xy 136.672958 -276.790206) (xy 136.626979 -276.812023) (xy 136.578095 -276.826183)
			(xy 136.527574 -276.832317) (xy 136.476722 -276.830268) (xy 136.426858 -276.820088) (xy 136.379272 -276.802041)
			(xy 136.335198 -276.776595) (xy 136.295776 -276.744408) (xy 136.262028 -276.706314) (xy 136.234827 -276.6633)
			(xy 136.214879 -276.61648) (xy 136.2027 -276.567066) (xy 136.198605 -276.516338) (xy 135.880094 -276.516338)
			(xy 135.879599 -276.540945) (xy 135.871704 -276.589522) (xy 135.85612 -276.636203) (xy 135.833249 -276.67978)
			(xy 135.803684 -276.719124) (xy 135.768191 -276.753216) (xy 135.727688 -276.781172) (xy 135.683226 -276.80227)
			(xy 135.635955 -276.815962) (xy 135.5871 -276.821894) (xy 135.537925 -276.819913) (xy 135.489706 -276.810069)
			(xy 135.44369 -276.792617) (xy 135.401069 -276.76801) (xy 135.362948 -276.736885) (xy 135.330313 -276.700048)
			(xy 135.30401 -276.658452) (xy 135.284719 -276.613176) (xy 135.272942 -276.565392) (xy 135.268982 -276.516338)
			(xy 134.950454 -276.516338) (xy 134.949942 -276.541784) (xy 134.941778 -276.592018) (xy 134.925662 -276.640292)
			(xy 134.902011 -276.685355) (xy 134.871438 -276.726041) (xy 134.834734 -276.761296) (xy 134.79285 -276.790206)
			(xy 134.746871 -276.812023) (xy 134.697987 -276.826183) (xy 134.647466 -276.832317) (xy 134.596614 -276.830268)
			(xy 134.54675 -276.820088) (xy 134.499164 -276.802041) (xy 134.45509 -276.776595) (xy 134.415668 -276.744408)
			(xy 134.38192 -276.706314) (xy 134.354719 -276.6633) (xy 134.334771 -276.61648) (xy 134.322592 -276.567066)
			(xy 134.318497 -276.516338) (xy 133.999986 -276.516338) (xy 133.999491 -276.540945) (xy 133.991596 -276.589522)
			(xy 133.976012 -276.636203) (xy 133.953141 -276.67978) (xy 133.923576 -276.719124) (xy 133.888083 -276.753216)
			(xy 133.84758 -276.781172) (xy 133.803118 -276.80227) (xy 133.755847 -276.815962) (xy 133.706992 -276.821894)
			(xy 133.657817 -276.819913) (xy 133.609598 -276.810069) (xy 133.563582 -276.792617) (xy 133.520961 -276.76801)
			(xy 133.48284 -276.736885) (xy 133.450205 -276.700048) (xy 133.423902 -276.658452) (xy 133.404611 -276.613176)
			(xy 133.392834 -276.565392) (xy 133.388874 -276.516338) (xy 133.0706 -276.516338) (xy 133.070088 -276.541784)
			(xy 133.061924 -276.592018) (xy 133.045808 -276.640292) (xy 133.022157 -276.685355) (xy 132.991584 -276.726041)
			(xy 132.95488 -276.761296) (xy 132.912996 -276.790206) (xy 132.867017 -276.812023) (xy 132.818133 -276.826183)
			(xy 132.767612 -276.832317) (xy 132.71676 -276.830268) (xy 132.666896 -276.820088) (xy 132.61931 -276.802041)
			(xy 132.575236 -276.776595) (xy 132.535814 -276.744408) (xy 132.502066 -276.706314) (xy 132.474865 -276.6633)
			(xy 132.454917 -276.61648) (xy 132.442738 -276.567066) (xy 132.438643 -276.516338) (xy 132.130546 -276.516338)
			(xy 132.130034 -276.541784) (xy 132.12187 -276.592018) (xy 132.105754 -276.640292) (xy 132.082103 -276.685355)
			(xy 132.05153 -276.726041) (xy 132.014826 -276.761296) (xy 131.972942 -276.790206) (xy 131.926963 -276.812023)
			(xy 131.878079 -276.826183) (xy 131.827558 -276.832317) (xy 131.776706 -276.830268) (xy 131.726842 -276.820088)
			(xy 131.679256 -276.802041) (xy 131.635182 -276.776595) (xy 131.59576 -276.744408) (xy 131.562012 -276.706314)
			(xy 131.534811 -276.6633) (xy 131.514863 -276.61648) (xy 131.502684 -276.567066) (xy 131.498589 -276.516338)
			(xy 131.180078 -276.516338) (xy 131.179583 -276.540945) (xy 131.171688 -276.589522) (xy 131.156104 -276.636203)
			(xy 131.133233 -276.67978) (xy 131.103668 -276.719124) (xy 131.068175 -276.753216) (xy 131.027672 -276.781172)
			(xy 130.98321 -276.80227) (xy 130.935939 -276.815962) (xy 130.887084 -276.821894) (xy 130.837909 -276.819913)
			(xy 130.78969 -276.810069) (xy 130.743674 -276.792617) (xy 130.701053 -276.76801) (xy 130.662932 -276.736885)
			(xy 130.630297 -276.700048) (xy 130.603994 -276.658452) (xy 130.584703 -276.613176) (xy 130.572926 -276.565392)
			(xy 130.568966 -276.516338) (xy 130.250438 -276.516338) (xy 130.249926 -276.541784) (xy 130.241762 -276.592018)
			(xy 130.225646 -276.640292) (xy 130.201995 -276.685355) (xy 130.171422 -276.726041) (xy 130.134718 -276.761296)
			(xy 130.092834 -276.790206) (xy 130.046855 -276.812023) (xy 129.997971 -276.826183) (xy 129.94745 -276.832317)
			(xy 129.896598 -276.830268) (xy 129.846734 -276.820088) (xy 129.799148 -276.802041) (xy 129.755074 -276.776595)
			(xy 129.715652 -276.744408) (xy 129.681904 -276.706314) (xy 129.654703 -276.6633) (xy 129.634755 -276.61648)
			(xy 129.622576 -276.567066) (xy 129.618481 -276.516338) (xy 129.29997 -276.516338) (xy 129.299475 -276.540945)
			(xy 129.29158 -276.589522) (xy 129.275996 -276.636203) (xy 129.253125 -276.67978) (xy 129.22356 -276.719124)
			(xy 129.188067 -276.753216) (xy 129.147564 -276.781172) (xy 129.103102 -276.80227) (xy 129.055831 -276.815962)
			(xy 129.006976 -276.821894) (xy 128.957801 -276.819913) (xy 128.909582 -276.810069) (xy 128.863566 -276.792617)
			(xy 128.820945 -276.76801) (xy 128.782824 -276.736885) (xy 128.750189 -276.700048) (xy 128.723886 -276.658452)
			(xy 128.704595 -276.613176) (xy 128.692818 -276.565392) (xy 128.688858 -276.516338) (xy 128.370584 -276.516338)
			(xy 128.370072 -276.541784) (xy 128.361908 -276.592018) (xy 128.345792 -276.640292) (xy 128.322141 -276.685355)
			(xy 128.291568 -276.726041) (xy 128.254864 -276.761296) (xy 128.21298 -276.790206) (xy 128.167001 -276.812023)
			(xy 128.118117 -276.826183) (xy 128.067596 -276.832317) (xy 128.016744 -276.830268) (xy 127.96688 -276.820088)
			(xy 127.919294 -276.802041) (xy 127.87522 -276.776595) (xy 127.835798 -276.744408) (xy 127.80205 -276.706314)
			(xy 127.774849 -276.6633) (xy 127.754901 -276.61648) (xy 127.742722 -276.567066) (xy 127.738627 -276.516338)
			(xy 127.419606 -276.516338) (xy 127.419605 -276.541669) (xy 127.411225 -276.591679) (xy 127.394697 -276.639617)
			(xy 127.370477 -276.684166) (xy 127.339229 -276.724101) (xy 127.301813 -276.758324) (xy 127.259257 -276.785896)
			(xy 127.23622 -276.7965) (xy 127.22225 -276.802596) (xy 127.20574 -276.827742) (xy 127.20574 -277.326344)
			(xy 128.208527 -277.326344) (xy 128.212622 -277.275616) (xy 128.224801 -277.226202) (xy 128.244749 -277.179382)
			(xy 128.27195 -277.136368) (xy 128.305698 -277.098274) (xy 128.34512 -277.066087) (xy 128.389194 -277.040641)
			(xy 128.43678 -277.022594) (xy 128.486644 -277.012414) (xy 128.537496 -277.010365) (xy 128.588017 -277.016499)
			(xy 128.636901 -277.030659) (xy 128.68288 -277.052476) (xy 128.724764 -277.081386) (xy 128.761468 -277.116641)
			(xy 128.792041 -277.157327) (xy 128.815692 -277.20239) (xy 128.831808 -277.250664) (xy 128.839972 -277.300898)
			(xy 128.840484 -277.326344) (xy 129.148581 -277.326344) (xy 129.152676 -277.275616) (xy 129.164855 -277.226202)
			(xy 129.184803 -277.179382) (xy 129.212004 -277.136368) (xy 129.245752 -277.098274) (xy 129.285174 -277.066087)
			(xy 129.329248 -277.040641) (xy 129.376834 -277.022594) (xy 129.426698 -277.012414) (xy 129.47755 -277.010365)
			(xy 129.528071 -277.016499) (xy 129.576955 -277.030659) (xy 129.622934 -277.052476) (xy 129.664818 -277.081386)
			(xy 129.701522 -277.116641) (xy 129.732095 -277.157327) (xy 129.755746 -277.20239) (xy 129.771862 -277.250664)
			(xy 129.780026 -277.300898) (xy 129.780538 -277.326344) (xy 130.099066 -277.326344) (xy 130.103026 -277.27729)
			(xy 130.114803 -277.229506) (xy 130.134094 -277.18423) (xy 130.160397 -277.142634) (xy 130.193032 -277.105797)
			(xy 130.231153 -277.074672) (xy 130.273774 -277.050065) (xy 130.31979 -277.032613) (xy 130.368009 -277.022769)
			(xy 130.417184 -277.020788) (xy 130.466039 -277.02672) (xy 130.51331 -277.040412) (xy 130.557772 -277.06151)
			(xy 130.598275 -277.089466) (xy 130.633768 -277.123558) (xy 130.663333 -277.162902) (xy 130.686204 -277.206479)
			(xy 130.701788 -277.25316) (xy 130.709683 -277.301737) (xy 130.710178 -277.326344) (xy 131.028435 -277.326344)
			(xy 131.03253 -277.275616) (xy 131.044709 -277.226202) (xy 131.064657 -277.179382) (xy 131.091858 -277.136368)
			(xy 131.125606 -277.098274) (xy 131.165028 -277.066087) (xy 131.209102 -277.040641) (xy 131.256688 -277.022594)
			(xy 131.306552 -277.012414) (xy 131.357404 -277.010365) (xy 131.407925 -277.016499) (xy 131.456809 -277.030659)
			(xy 131.502788 -277.052476) (xy 131.544672 -277.081386) (xy 131.581376 -277.116641) (xy 131.611949 -277.157327)
			(xy 131.6356 -277.20239) (xy 131.651716 -277.250664) (xy 131.65988 -277.300898) (xy 131.660392 -277.326344)
			(xy 131.97892 -277.326344) (xy 131.98288 -277.27729) (xy 131.994657 -277.229506) (xy 132.013948 -277.18423)
			(xy 132.040251 -277.142634) (xy 132.072886 -277.105797) (xy 132.111007 -277.074672) (xy 132.153628 -277.050065)
			(xy 132.199644 -277.032613) (xy 132.247863 -277.022769) (xy 132.297038 -277.020788) (xy 132.345893 -277.02672)
			(xy 132.393164 -277.040412) (xy 132.437626 -277.06151) (xy 132.478129 -277.089466) (xy 132.513622 -277.123558)
			(xy 132.543187 -277.162902) (xy 132.566058 -277.206479) (xy 132.581642 -277.25316) (xy 132.589537 -277.301737)
			(xy 132.590032 -277.326344) (xy 132.908543 -277.326344) (xy 132.912638 -277.275616) (xy 132.924817 -277.226202)
			(xy 132.944765 -277.179382) (xy 132.971966 -277.136368) (xy 133.005714 -277.098274) (xy 133.045136 -277.066087)
			(xy 133.08921 -277.040641) (xy 133.136796 -277.022594) (xy 133.18666 -277.012414) (xy 133.237512 -277.010365)
			(xy 133.288033 -277.016499) (xy 133.336917 -277.030659) (xy 133.382896 -277.052476) (xy 133.42478 -277.081386)
			(xy 133.461484 -277.116641) (xy 133.492057 -277.157327) (xy 133.515708 -277.20239) (xy 133.531824 -277.250664)
			(xy 133.539988 -277.300898) (xy 133.5405 -277.326344) (xy 133.859028 -277.326344) (xy 133.862988 -277.27729)
			(xy 133.874765 -277.229506) (xy 133.894056 -277.18423) (xy 133.920359 -277.142634) (xy 133.952994 -277.105797)
			(xy 133.991115 -277.074672) (xy 134.033736 -277.050065) (xy 134.079752 -277.032613) (xy 134.127971 -277.022769)
			(xy 134.177146 -277.020788) (xy 134.226001 -277.02672) (xy 134.273272 -277.040412) (xy 134.317734 -277.06151)
			(xy 134.358237 -277.089466) (xy 134.39373 -277.123558) (xy 134.423295 -277.162902) (xy 134.446166 -277.206479)
			(xy 134.46175 -277.25316) (xy 134.469645 -277.301737) (xy 134.47014 -277.326344) (xy 134.788397 -277.326344)
			(xy 134.792492 -277.275616) (xy 134.804671 -277.226202) (xy 134.824619 -277.179382) (xy 134.85182 -277.136368)
			(xy 134.885568 -277.098274) (xy 134.92499 -277.066087) (xy 134.969064 -277.040641) (xy 135.01665 -277.022594)
			(xy 135.066514 -277.012414) (xy 135.117366 -277.010365) (xy 135.167887 -277.016499) (xy 135.216771 -277.030659)
			(xy 135.26275 -277.052476) (xy 135.304634 -277.081386) (xy 135.341338 -277.116641) (xy 135.371911 -277.157327)
			(xy 135.395562 -277.20239) (xy 135.411678 -277.250664) (xy 135.419842 -277.300898) (xy 135.420354 -277.326344)
			(xy 135.728451 -277.326344) (xy 135.732546 -277.275616) (xy 135.744725 -277.226202) (xy 135.764673 -277.179382)
			(xy 135.791874 -277.136368) (xy 135.825622 -277.098274) (xy 135.865044 -277.066087) (xy 135.909118 -277.040641)
			(xy 135.956704 -277.022594) (xy 136.006568 -277.012414) (xy 136.05742 -277.010365) (xy 136.107941 -277.016499)
			(xy 136.156825 -277.030659) (xy 136.202804 -277.052476) (xy 136.244688 -277.081386) (xy 136.281392 -277.116641)
			(xy 136.311965 -277.157327) (xy 136.335616 -277.20239) (xy 136.351732 -277.250664) (xy 136.359896 -277.300898)
			(xy 136.360408 -277.326344) (xy 136.678936 -277.326344) (xy 136.682896 -277.27729) (xy 136.694673 -277.229506)
			(xy 136.713964 -277.18423) (xy 136.740267 -277.142634) (xy 136.772902 -277.105797) (xy 136.811023 -277.074672)
			(xy 136.853644 -277.050065) (xy 136.89966 -277.032613) (xy 136.947879 -277.022769) (xy 136.997054 -277.020788)
			(xy 137.045909 -277.02672) (xy 137.09318 -277.040412) (xy 137.137642 -277.06151) (xy 137.178145 -277.089466)
			(xy 137.213638 -277.123558) (xy 137.243203 -277.162902) (xy 137.266074 -277.206479) (xy 137.281658 -277.25316)
			(xy 137.289553 -277.301737) (xy 137.290048 -277.326344) (xy 137.608559 -277.326344) (xy 137.612654 -277.275616)
			(xy 137.624833 -277.226202) (xy 137.644781 -277.179382) (xy 137.671982 -277.136368) (xy 137.70573 -277.098274)
			(xy 137.745152 -277.066087) (xy 137.789226 -277.040641) (xy 137.836812 -277.022594) (xy 137.886676 -277.012414)
			(xy 137.937528 -277.010365) (xy 137.988049 -277.016499) (xy 138.036933 -277.030659) (xy 138.082912 -277.052476)
			(xy 138.124796 -277.081386) (xy 138.1615 -277.116641) (xy 138.192073 -277.157327) (xy 138.215724 -277.20239)
			(xy 138.23184 -277.250664) (xy 138.240004 -277.300898) (xy 138.240516 -277.326344) (xy 138.559044 -277.326344)
			(xy 138.563004 -277.27729) (xy 138.574781 -277.229506) (xy 138.594072 -277.18423) (xy 138.620375 -277.142634)
			(xy 138.65301 -277.105797) (xy 138.691131 -277.074672) (xy 138.733752 -277.050065) (xy 138.779768 -277.032613)
			(xy 138.827987 -277.022769) (xy 138.877162 -277.020788) (xy 138.926017 -277.02672) (xy 138.973288 -277.040412)
			(xy 139.01775 -277.06151) (xy 139.058253 -277.089466) (xy 139.093746 -277.123558) (xy 139.123311 -277.162902)
			(xy 139.146182 -277.206479) (xy 139.161766 -277.25316) (xy 139.169661 -277.301737) (xy 139.170156 -277.326344)
			(xy 139.488413 -277.326344) (xy 139.492508 -277.275616) (xy 139.504687 -277.226202) (xy 139.524635 -277.179382)
			(xy 139.551836 -277.136368) (xy 139.585584 -277.098274) (xy 139.625006 -277.066087) (xy 139.66908 -277.040641)
			(xy 139.716666 -277.022594) (xy 139.76653 -277.012414) (xy 139.817382 -277.010365) (xy 139.867903 -277.016499)
			(xy 139.916787 -277.030659) (xy 139.962766 -277.052476) (xy 140.00465 -277.081386) (xy 140.041354 -277.116641)
			(xy 140.071927 -277.157327) (xy 140.095578 -277.20239) (xy 140.111694 -277.250664) (xy 140.119858 -277.300898)
			(xy 140.12037 -277.326344) (xy 140.438898 -277.326344) (xy 140.442858 -277.27729) (xy 140.454635 -277.229506)
			(xy 140.473926 -277.18423) (xy 140.500229 -277.142634) (xy 140.532864 -277.105797) (xy 140.570985 -277.074672)
			(xy 140.613606 -277.050065) (xy 140.659622 -277.032613) (xy 140.707841 -277.022769) (xy 140.757016 -277.020788)
			(xy 140.805871 -277.02672) (xy 140.853142 -277.040412) (xy 140.897604 -277.06151) (xy 140.938107 -277.089466)
			(xy 140.9736 -277.123558) (xy 141.003165 -277.162902) (xy 141.026036 -277.206479) (xy 141.04162 -277.25316)
			(xy 141.049515 -277.301737) (xy 141.05001 -277.326344) (xy 141.368521 -277.326344) (xy 141.372616 -277.275616)
			(xy 141.384795 -277.226202) (xy 141.404743 -277.179382) (xy 141.431944 -277.136368) (xy 141.465692 -277.098274)
			(xy 141.505114 -277.066087) (xy 141.549188 -277.040641) (xy 141.596774 -277.022594) (xy 141.646638 -277.012414)
			(xy 141.69749 -277.010365) (xy 141.748011 -277.016499) (xy 141.796895 -277.030659) (xy 141.842874 -277.052476)
			(xy 141.884758 -277.081386) (xy 141.921462 -277.116641) (xy 141.952035 -277.157327) (xy 141.975686 -277.20239)
			(xy 141.991802 -277.250664) (xy 141.999966 -277.300898) (xy 142.000478 -277.326344) (xy 142.308575 -277.326344)
			(xy 142.31267 -277.275616) (xy 142.324849 -277.226202) (xy 142.344797 -277.179382) (xy 142.371998 -277.136368)
			(xy 142.405746 -277.098274) (xy 142.445168 -277.066087) (xy 142.489242 -277.040641) (xy 142.536828 -277.022594)
			(xy 142.586692 -277.012414) (xy 142.637544 -277.010365) (xy 142.688065 -277.016499) (xy 142.736949 -277.030659)
			(xy 142.782928 -277.052476) (xy 142.824812 -277.081386) (xy 142.861516 -277.116641) (xy 142.892089 -277.157327)
			(xy 142.91574 -277.20239) (xy 142.931856 -277.250664) (xy 142.94002 -277.300898) (xy 142.940532 -277.326344)
			(xy 143.258806 -277.326344) (xy 143.262766 -277.27729) (xy 143.274543 -277.229506) (xy 143.293834 -277.18423)
			(xy 143.320137 -277.142634) (xy 143.352772 -277.105797) (xy 143.390893 -277.074672) (xy 143.433514 -277.050065)
			(xy 143.47953 -277.032613) (xy 143.527749 -277.022769) (xy 143.576924 -277.020788) (xy 143.625779 -277.02672)
			(xy 143.67305 -277.040412) (xy 143.717512 -277.06151) (xy 143.758015 -277.089466) (xy 143.793508 -277.123558)
			(xy 143.823073 -277.162902) (xy 143.845944 -277.206479) (xy 143.861528 -277.25316) (xy 143.869423 -277.301737)
			(xy 143.869918 -277.326344) (xy 145.138914 -277.326344) (xy 145.142874 -277.27729) (xy 145.154651 -277.229506)
			(xy 145.173942 -277.18423) (xy 145.200245 -277.142634) (xy 145.23288 -277.105797) (xy 145.271001 -277.074672)
			(xy 145.313622 -277.050065) (xy 145.359638 -277.032613) (xy 145.407857 -277.022769) (xy 145.457032 -277.020788)
			(xy 145.505887 -277.02672) (xy 145.553158 -277.040412) (xy 145.59762 -277.06151) (xy 145.638123 -277.089466)
			(xy 145.673616 -277.123558) (xy 145.703181 -277.162902) (xy 145.726052 -277.206479) (xy 145.735711 -277.235412)
			(xy 166.774383 -277.235412) (xy 166.778318 -277.181641) (xy 166.790041 -277.129017) (xy 166.809301 -277.07866)
			(xy 166.835687 -277.031643) (xy 166.868639 -276.98897) (xy 166.907452 -276.951549) (xy 166.9513 -276.920179)
			(xy 166.999248 -276.895527) (xy 167.050275 -276.878119) (xy 167.103293 -276.868326) (xy 167.157172 -276.866357)
			(xy 167.210763 -276.872254) (xy 167.262924 -276.88589) (xy 167.312544 -276.906977) (xy 167.358565 -276.935063)
			(xy 167.400007 -276.969551) (xy 167.435985 -277.009705) (xy 167.465733 -277.054669) (xy 167.488618 -277.103486)
			(xy 167.50415 -277.155115) (xy 167.512 -277.208455) (xy 167.512492 -277.235412) (xy 171.476162 -277.235412)
			(xy 171.476642 -277.20269) (xy 171.485247 -277.137815) (xy 171.502309 -277.074634) (xy 171.527533 -277.014247)
			(xy 171.560479 -276.957701) (xy 171.600575 -276.905979) (xy 171.623482 -276.882606) (xy 171.630848 -276.875494)
			(xy 171.638722 -276.856698) (xy 171.638722 -276.763988) (xy 171.630848 -276.745192) (xy 171.623482 -276.73808)
			(xy 171.600565 -276.714719) (xy 171.560484 -276.662989) (xy 171.527551 -276.606438) (xy 171.502338 -276.546049)
			(xy 171.485284 -276.482868) (xy 171.476684 -276.417995) (xy 171.476162 -276.385274) (xy 171.476651 -276.354111)
			(xy 171.484463 -276.292277) (xy 171.499963 -276.231909) (xy 171.522906 -276.173961) (xy 171.552932 -276.119344)
			(xy 171.589566 -276.068922) (xy 171.632231 -276.023488) (xy 171.680253 -275.98376) (xy 171.732877 -275.950365)
			(xy 171.789271 -275.923828) (xy 171.848546 -275.904568) (xy 171.909767 -275.892889) (xy 171.97197 -275.888976)
			(xy 172.034173 -275.892889) (xy 172.095394 -275.904568) (xy 172.154669 -275.923828) (xy 172.211063 -275.950365)
			(xy 172.263687 -275.98376) (xy 172.311709 -276.023488) (xy 172.354374 -276.068922) (xy 172.391008 -276.119344)
			(xy 172.421034 -276.173961) (xy 172.443977 -276.231909) (xy 172.459477 -276.292277) (xy 172.467289 -276.354111)
			(xy 172.467778 -276.385274) (xy 175.57623 -276.385274) (xy 175.576786 -276.352575) (xy 175.58539 -276.287744)
			(xy 175.602446 -276.224609) (xy 175.627657 -276.164265) (xy 175.660584 -276.10776) (xy 175.700657 -276.056077)
			(xy 175.72355 -276.032722) (xy 175.730916 -276.025356) (xy 175.738536 -276.006814) (xy 175.738536 -275.91385)
			(xy 175.730916 -275.895308) (xy 175.72355 -275.887942) (xy 175.700654 -275.864588) (xy 175.660569 -275.81291)
			(xy 175.627632 -275.756407) (xy 175.602416 -275.696062) (xy 175.585357 -275.632924) (xy 175.576754 -275.568091)
			(xy 175.57623 -275.53539) (xy 175.576719 -275.504227) (xy 175.584531 -275.442393) (xy 175.600031 -275.382025)
			(xy 175.622974 -275.324077) (xy 175.653 -275.26946) (xy 175.689634 -275.219038) (xy 175.732299 -275.173604)
			(xy 175.780321 -275.133876) (xy 175.832945 -275.100481) (xy 175.889339 -275.073944) (xy 175.948614 -275.054684)
			(xy 176.009835 -275.043005) (xy 176.072038 -275.039092) (xy 176.134241 -275.043005) (xy 176.195462 -275.054684)
			(xy 176.254737 -275.073944) (xy 176.311131 -275.100481) (xy 176.363755 -275.133876) (xy 176.411777 -275.173604)
			(xy 176.454442 -275.219038) (xy 176.491076 -275.26946) (xy 176.521102 -275.324077) (xy 176.544045 -275.382025)
			(xy 176.559545 -275.442393) (xy 176.567357 -275.504227) (xy 176.567846 -275.53539) (xy 180.531023 -275.53539)
			(xy 180.534958 -275.481619) (xy 180.546681 -275.428995) (xy 180.565941 -275.378638) (xy 180.592327 -275.331621)
			(xy 180.625279 -275.288948) (xy 180.664092 -275.251527) (xy 180.70794 -275.220157) (xy 180.755888 -275.195505)
			(xy 180.806915 -275.178097) (xy 180.859933 -275.168304) (xy 180.913812 -275.166335) (xy 180.967403 -275.172232)
			(xy 181.019564 -275.185868) (xy 181.069184 -275.206955) (xy 181.115205 -275.235041) (xy 181.156647 -275.269529)
			(xy 181.192625 -275.309683) (xy 181.222373 -275.354647) (xy 181.245258 -275.403464) (xy 181.26079 -275.455093)
			(xy 181.26864 -275.508433) (xy 181.269132 -275.53539) (xy 181.26864 -275.562347) (xy 181.26079 -275.615687)
			(xy 181.245258 -275.667316) (xy 181.222373 -275.716133) (xy 181.192625 -275.761097) (xy 181.156647 -275.801251)
			(xy 181.115205 -275.835739) (xy 181.069184 -275.863825) (xy 181.019564 -275.884912) (xy 180.967403 -275.898548)
			(xy 180.913812 -275.904445) (xy 180.859933 -275.902476) (xy 180.806915 -275.892683) (xy 180.755888 -275.875275)
			(xy 180.70794 -275.850623) (xy 180.664092 -275.819253) (xy 180.625279 -275.781832) (xy 180.592327 -275.739159)
			(xy 180.565941 -275.692142) (xy 180.546681 -275.641785) (xy 180.534958 -275.589161) (xy 180.531023 -275.53539)
			(xy 176.567846 -275.53539) (xy 176.567339 -275.568091) (xy 176.558725 -275.632924) (xy 176.541661 -275.69606)
			(xy 176.516441 -275.756405) (xy 176.483504 -275.812908) (xy 176.443423 -275.864589) (xy 176.420526 -275.887942)
			(xy 176.41316 -275.895308) (xy 176.40554 -275.91385) (xy 176.40554 -275.960332) (xy 176.820337 -275.960332)
			(xy 176.824272 -275.906561) (xy 176.835995 -275.853937) (xy 176.855255 -275.80358) (xy 176.881641 -275.756563)
			(xy 176.914593 -275.71389) (xy 176.953406 -275.676469) (xy 176.997254 -275.645099) (xy 177.045202 -275.620447)
			(xy 177.096229 -275.603039) (xy 177.149247 -275.593246) (xy 177.203126 -275.591277) (xy 177.256717 -275.597174)
			(xy 177.308878 -275.61081) (xy 177.358498 -275.631897) (xy 177.404519 -275.659983) (xy 177.445961 -275.694471)
			(xy 177.481939 -275.734625) (xy 177.511687 -275.779589) (xy 177.534572 -275.828406) (xy 177.550104 -275.880035)
			(xy 177.557954 -275.933375) (xy 177.558446 -275.960332) (xy 177.557954 -275.987289) (xy 177.550104 -276.040629)
			(xy 177.534572 -276.092258) (xy 177.511687 -276.141075) (xy 177.481939 -276.186039) (xy 177.445961 -276.226193)
			(xy 177.404519 -276.260681) (xy 177.358498 -276.288767) (xy 177.308878 -276.309854) (xy 177.256717 -276.32349)
			(xy 177.203126 -276.329387) (xy 177.149247 -276.327418) (xy 177.096229 -276.317625) (xy 177.045202 -276.300217)
			(xy 176.997254 -276.275565) (xy 176.953406 -276.244195) (xy 176.914593 -276.206774) (xy 176.881641 -276.164101)
			(xy 176.855255 -276.117084) (xy 176.835995 -276.066727) (xy 176.824272 -276.014103) (xy 176.820337 -275.960332)
			(xy 176.40554 -275.960332) (xy 176.40554 -276.006814) (xy 176.41316 -276.025356) (xy 176.420526 -276.032722)
			(xy 176.4434 -276.056096) (xy 176.483488 -276.107769) (xy 176.516428 -276.164268) (xy 176.541649 -276.224609)
			(xy 176.558712 -276.287743) (xy 176.56732 -276.352574) (xy 176.567846 -276.385274) (xy 176.567357 -276.416437)
			(xy 176.559545 -276.478271) (xy 176.544045 -276.538639) (xy 176.521102 -276.596587) (xy 176.491076 -276.651204)
			(xy 176.454442 -276.701626) (xy 176.411777 -276.74706) (xy 176.363755 -276.786788) (xy 176.311131 -276.820183)
			(xy 176.254737 -276.84672) (xy 176.195462 -276.86598) (xy 176.134241 -276.877659) (xy 176.072038 -276.881572)
			(xy 176.009835 -276.877659) (xy 175.948614 -276.86598) (xy 175.889339 -276.84672) (xy 175.832945 -276.820183)
			(xy 175.780321 -276.786788) (xy 175.732299 -276.74706) (xy 175.689634 -276.701626) (xy 175.653 -276.651204)
			(xy 175.622974 -276.596587) (xy 175.600031 -276.538639) (xy 175.584531 -276.478271) (xy 175.576719 -276.416437)
			(xy 175.57623 -276.385274) (xy 172.467778 -276.385274) (xy 172.467278 -276.417995) (xy 172.458675 -276.482869)
			(xy 172.441616 -276.546049) (xy 172.416396 -276.606436) (xy 172.383454 -276.662983) (xy 172.343362 -276.714706)
			(xy 172.320458 -276.73808) (xy 172.313092 -276.745192) (xy 172.305218 -276.763988) (xy 172.305218 -276.81047)
			(xy 172.720269 -276.81047) (xy 172.724204 -276.756699) (xy 172.735927 -276.704075) (xy 172.755187 -276.653718)
			(xy 172.781573 -276.606701) (xy 172.814525 -276.564028) (xy 172.853338 -276.526607) (xy 172.897186 -276.495237)
			(xy 172.945134 -276.470585) (xy 172.996161 -276.453177) (xy 173.049179 -276.443384) (xy 173.103058 -276.441415)
			(xy 173.156649 -276.447312) (xy 173.20881 -276.460948) (xy 173.25843 -276.482035) (xy 173.304451 -276.510121)
			(xy 173.345893 -276.544609) (xy 173.381871 -276.584763) (xy 173.411619 -276.629727) (xy 173.434504 -276.678544)
			(xy 173.450036 -276.730173) (xy 173.457886 -276.783513) (xy 173.458378 -276.81047) (xy 173.457886 -276.837427)
			(xy 173.450036 -276.890767) (xy 173.434504 -276.942396) (xy 173.411619 -276.991213) (xy 173.381871 -277.036177)
			(xy 173.345893 -277.076331) (xy 173.304451 -277.110819) (xy 173.25843 -277.138905) (xy 173.20881 -277.159992)
			(xy 173.156649 -277.173628) (xy 173.103058 -277.179525) (xy 173.049179 -277.177556) (xy 172.996161 -277.167763)
			(xy 172.945134 -277.150355) (xy 172.897186 -277.125703) (xy 172.853338 -277.094333) (xy 172.814525 -277.056912)
			(xy 172.781573 -277.014239) (xy 172.755187 -276.967222) (xy 172.735927 -276.916865) (xy 172.724204 -276.864241)
			(xy 172.720269 -276.81047) (xy 172.305218 -276.81047) (xy 172.305218 -276.856698) (xy 172.313092 -276.875494)
			(xy 172.320458 -276.882606) (xy 172.343376 -276.905966) (xy 172.383456 -276.957697) (xy 172.416388 -277.014248)
			(xy 172.4416 -277.074638) (xy 172.458654 -277.137818) (xy 172.467255 -277.202691) (xy 172.467778 -277.235412)
			(xy 174.318437 -277.235412) (xy 174.322372 -277.181641) (xy 174.334095 -277.129017) (xy 174.353355 -277.07866)
			(xy 174.379741 -277.031643) (xy 174.412693 -276.98897) (xy 174.451506 -276.951549) (xy 174.495354 -276.920179)
			(xy 174.543302 -276.895527) (xy 174.594329 -276.878119) (xy 174.647347 -276.868326) (xy 174.701226 -276.866357)
			(xy 174.754817 -276.872254) (xy 174.806978 -276.88589) (xy 174.856598 -276.906977) (xy 174.902619 -276.935063)
			(xy 174.944061 -276.969551) (xy 174.980039 -277.009705) (xy 175.009787 -277.054669) (xy 175.032672 -277.103486)
			(xy 175.048204 -277.155115) (xy 175.056054 -277.208455) (xy 175.056546 -277.235412) (xy 179.020216 -277.235412)
			(xy 179.020709 -277.202691) (xy 179.029313 -277.137816) (xy 179.046374 -277.074637) (xy 179.071595 -277.014249)
			(xy 179.104538 -276.957703) (xy 179.144631 -276.90598) (xy 179.167536 -276.882606) (xy 179.174902 -276.875494)
			(xy 179.182776 -276.856698) (xy 179.182776 -276.763988) (xy 179.174902 -276.745192) (xy 179.167536 -276.73808)
			(xy 179.144611 -276.714728) (xy 179.104531 -276.662995) (xy 179.071601 -276.606442) (xy 179.04639 -276.546051)
			(xy 179.029337 -276.48287) (xy 179.020738 -276.417995) (xy 179.020216 -276.385274) (xy 179.020705 -276.354111)
			(xy 179.028517 -276.292277) (xy 179.044017 -276.231909) (xy 179.06696 -276.173961) (xy 179.096986 -276.119344)
			(xy 179.13362 -276.068922) (xy 179.176285 -276.023488) (xy 179.224307 -275.98376) (xy 179.276931 -275.950365)
			(xy 179.333325 -275.923828) (xy 179.3926 -275.904568) (xy 179.453821 -275.892889) (xy 179.516024 -275.888976)
			(xy 179.578227 -275.892889) (xy 179.639448 -275.904568) (xy 179.698723 -275.923828) (xy 179.755117 -275.950365)
			(xy 179.807741 -275.98376) (xy 179.855763 -276.023488) (xy 179.898428 -276.068922) (xy 179.935062 -276.119344)
			(xy 179.965088 -276.173961) (xy 179.988031 -276.231909) (xy 180.003531 -276.292277) (xy 180.011343 -276.354111)
			(xy 180.011832 -276.385274) (xy 183.120284 -276.385274) (xy 183.120824 -276.352574) (xy 183.129429 -276.287742)
			(xy 183.146487 -276.224606) (xy 183.1717 -276.164261) (xy 183.204632 -276.107757) (xy 183.244709 -276.056076)
			(xy 183.267604 -276.032722) (xy 183.27497 -276.025356) (xy 183.28259 -276.006814) (xy 183.28259 -275.91385)
			(xy 183.27497 -275.895308) (xy 183.267604 -275.887942) (xy 183.244718 -275.864579) (xy 183.20463 -275.812904)
			(xy 183.171691 -275.756403) (xy 183.146472 -275.69606) (xy 183.129412 -275.632923) (xy 183.120808 -275.568091)
			(xy 183.120284 -275.53539) (xy 183.120773 -275.504227) (xy 183.128585 -275.442393) (xy 183.144085 -275.382025)
			(xy 183.167028 -275.324077) (xy 183.197054 -275.26946) (xy 183.233688 -275.219038) (xy 183.276353 -275.173604)
			(xy 183.324375 -275.133876) (xy 183.376999 -275.100481) (xy 183.433393 -275.073944) (xy 183.492668 -275.054684)
			(xy 183.553889 -275.043005) (xy 183.616092 -275.039092) (xy 183.678295 -275.043005) (xy 183.739516 -275.054684)
			(xy 183.798791 -275.073944) (xy 183.855185 -275.100481) (xy 183.907809 -275.133876) (xy 183.955831 -275.173604)
			(xy 183.998496 -275.219038) (xy 184.03513 -275.26946) (xy 184.065156 -275.324077) (xy 184.088099 -275.382025)
			(xy 184.103599 -275.442393) (xy 184.111411 -275.504227) (xy 184.1119 -275.53539) (xy 184.111406 -275.568092)
			(xy 184.102792 -275.632925) (xy 184.085726 -275.696063) (xy 184.060504 -275.756407) (xy 184.027564 -275.81291)
			(xy 183.987479 -275.86459) (xy 183.96458 -275.887942) (xy 183.957214 -275.895308) (xy 183.949594 -275.91385)
			(xy 183.949594 -275.960332) (xy 184.364391 -275.960332) (xy 184.368326 -275.906561) (xy 184.380049 -275.853937)
			(xy 184.399309 -275.80358) (xy 184.425695 -275.756563) (xy 184.458647 -275.71389) (xy 184.49746 -275.676469)
			(xy 184.541308 -275.645099) (xy 184.589256 -275.620447) (xy 184.640283 -275.603039) (xy 184.693301 -275.593246)
			(xy 184.74718 -275.591277) (xy 184.800771 -275.597174) (xy 184.852932 -275.61081) (xy 184.902552 -275.631897)
			(xy 184.948573 -275.659983) (xy 184.990015 -275.694471) (xy 185.025993 -275.734625) (xy 185.055741 -275.779589)
			(xy 185.078626 -275.828406) (xy 185.094158 -275.880035) (xy 185.102008 -275.933375) (xy 185.1025 -275.960332)
			(xy 185.102008 -275.987289) (xy 185.094158 -276.040629) (xy 185.078626 -276.092258) (xy 185.055741 -276.141075)
			(xy 185.025993 -276.186039) (xy 184.990015 -276.226193) (xy 184.948573 -276.260681) (xy 184.902552 -276.288767)
			(xy 184.852932 -276.309854) (xy 184.800771 -276.32349) (xy 184.74718 -276.329387) (xy 184.693301 -276.327418)
			(xy 184.640283 -276.317625) (xy 184.589256 -276.300217) (xy 184.541308 -276.275565) (xy 184.49746 -276.244195)
			(xy 184.458647 -276.206774) (xy 184.425695 -276.164101) (xy 184.399309 -276.117084) (xy 184.380049 -276.066727)
			(xy 184.368326 -276.014103) (xy 184.364391 -275.960332) (xy 183.949594 -275.960332) (xy 183.949594 -276.006814)
			(xy 183.957214 -276.025356) (xy 183.96458 -276.032722) (xy 183.987464 -276.056087) (xy 184.027549 -276.107763)
			(xy 184.060487 -276.164264) (xy 184.085705 -276.224606) (xy 184.102767 -276.287742) (xy 184.111374 -276.352574)
			(xy 184.1119 -276.385274) (xy 184.111411 -276.416437) (xy 184.103599 -276.478271) (xy 184.088099 -276.538639)
			(xy 184.065156 -276.596587) (xy 184.03513 -276.651204) (xy 183.998496 -276.701626) (xy 183.955831 -276.74706)
			(xy 183.907809 -276.786788) (xy 183.855185 -276.820183) (xy 183.798791 -276.84672) (xy 183.739516 -276.86598)
			(xy 183.678295 -276.877659) (xy 183.616092 -276.881572) (xy 183.553889 -276.877659) (xy 183.492668 -276.86598)
			(xy 183.433393 -276.84672) (xy 183.376999 -276.820183) (xy 183.324375 -276.786788) (xy 183.276353 -276.74706)
			(xy 183.233688 -276.701626) (xy 183.197054 -276.651204) (xy 183.167028 -276.596587) (xy 183.144085 -276.538639)
			(xy 183.128585 -276.478271) (xy 183.120773 -276.416437) (xy 183.120284 -276.385274) (xy 180.011832 -276.385274)
			(xy 180.011345 -276.417996) (xy 180.002742 -276.482871) (xy 179.985681 -276.546051) (xy 179.960459 -276.606439)
			(xy 179.927514 -276.662985) (xy 179.887418 -276.714707) (xy 179.864512 -276.73808) (xy 179.857146 -276.745192)
			(xy 179.849272 -276.763988) (xy 179.849272 -276.81047) (xy 180.264323 -276.81047) (xy 180.268258 -276.756699)
			(xy 180.279981 -276.704075) (xy 180.299241 -276.653718) (xy 180.325627 -276.606701) (xy 180.358579 -276.564028)
			(xy 180.397392 -276.526607) (xy 180.44124 -276.495237) (xy 180.489188 -276.470585) (xy 180.540215 -276.453177)
			(xy 180.593233 -276.443384) (xy 180.647112 -276.441415) (xy 180.700703 -276.447312) (xy 180.752864 -276.460948)
			(xy 180.802484 -276.482035) (xy 180.848505 -276.510121) (xy 180.889947 -276.544609) (xy 180.925925 -276.584763)
			(xy 180.955673 -276.629727) (xy 180.978558 -276.678544) (xy 180.99409 -276.730173) (xy 181.00194 -276.783513)
			(xy 181.002432 -276.81047) (xy 181.00194 -276.837427) (xy 180.99409 -276.890767) (xy 180.978558 -276.942396)
			(xy 180.955673 -276.991213) (xy 180.925925 -277.036177) (xy 180.889947 -277.076331) (xy 180.848505 -277.110819)
			(xy 180.802484 -277.138905) (xy 180.752864 -277.159992) (xy 180.700703 -277.173628) (xy 180.647112 -277.179525)
			(xy 180.593233 -277.177556) (xy 180.540215 -277.167763) (xy 180.489188 -277.150355) (xy 180.44124 -277.125703)
			(xy 180.397392 -277.094333) (xy 180.358579 -277.056912) (xy 180.325627 -277.014239) (xy 180.299241 -276.967222)
			(xy 180.279981 -276.916865) (xy 180.268258 -276.864241) (xy 180.264323 -276.81047) (xy 179.849272 -276.81047)
			(xy 179.849272 -276.856698) (xy 179.857146 -276.875494) (xy 179.864512 -276.882606) (xy 179.887421 -276.905974)
			(xy 179.927503 -276.957703) (xy 179.960438 -277.014252) (xy 179.985651 -277.07464) (xy 180.002707 -277.137819)
			(xy 180.011309 -277.202692) (xy 180.011832 -277.235412) (xy 181.862491 -277.235412) (xy 181.866426 -277.181641)
			(xy 181.878149 -277.129017) (xy 181.897409 -277.07866) (xy 181.923795 -277.031643) (xy 181.956747 -276.98897)
			(xy 181.99556 -276.951549) (xy 182.039408 -276.920179) (xy 182.087356 -276.895527) (xy 182.138383 -276.878119)
			(xy 182.191401 -276.868326) (xy 182.24528 -276.866357) (xy 182.298871 -276.872254) (xy 182.351032 -276.88589)
			(xy 182.400652 -276.906977) (xy 182.446673 -276.935063) (xy 182.488115 -276.969551) (xy 182.524093 -277.009705)
			(xy 182.553841 -277.054669) (xy 182.576726 -277.103486) (xy 182.592258 -277.155115) (xy 182.600108 -277.208455)
			(xy 182.6006 -277.235412) (xy 182.600108 -277.262369) (xy 182.592258 -277.315709) (xy 182.576726 -277.367338)
			(xy 182.553841 -277.416155) (xy 182.524093 -277.461119) (xy 182.488115 -277.501273) (xy 182.446673 -277.535761)
			(xy 182.400652 -277.563847) (xy 182.351032 -277.584934) (xy 182.298871 -277.59857) (xy 182.24528 -277.604467)
			(xy 182.191401 -277.602498) (xy 182.138383 -277.592705) (xy 182.087356 -277.575297) (xy 182.039408 -277.550645)
			(xy 181.99556 -277.519275) (xy 181.956747 -277.481854) (xy 181.923795 -277.439181) (xy 181.897409 -277.392164)
			(xy 181.878149 -277.341807) (xy 181.866426 -277.289183) (xy 181.862491 -277.235412) (xy 180.011832 -277.235412)
			(xy 180.011343 -277.266575) (xy 180.003531 -277.328409) (xy 179.988031 -277.388777) (xy 179.965088 -277.446725)
			(xy 179.935062 -277.501342) (xy 179.898428 -277.551764) (xy 179.855763 -277.597198) (xy 179.807741 -277.636926)
			(xy 179.755117 -277.670321) (xy 179.698723 -277.696858) (xy 179.639448 -277.716118) (xy 179.578227 -277.727797)
			(xy 179.516024 -277.73171) (xy 179.453821 -277.727797) (xy 179.3926 -277.716118) (xy 179.333325 -277.696858)
			(xy 179.276931 -277.670321) (xy 179.224307 -277.636926) (xy 179.176285 -277.597198) (xy 179.13362 -277.551764)
			(xy 179.096986 -277.501342) (xy 179.06696 -277.446725) (xy 179.044017 -277.388777) (xy 179.028517 -277.328409)
			(xy 179.020705 -277.266575) (xy 179.020216 -277.235412) (xy 175.056546 -277.235412) (xy 175.056054 -277.262369)
			(xy 175.048204 -277.315709) (xy 175.032672 -277.367338) (xy 175.009787 -277.416155) (xy 174.980039 -277.461119)
			(xy 174.944061 -277.501273) (xy 174.902619 -277.535761) (xy 174.856598 -277.563847) (xy 174.806978 -277.584934)
			(xy 174.754817 -277.59857) (xy 174.701226 -277.604467) (xy 174.647347 -277.602498) (xy 174.594329 -277.592705)
			(xy 174.543302 -277.575297) (xy 174.495354 -277.550645) (xy 174.451506 -277.519275) (xy 174.412693 -277.481854)
			(xy 174.379741 -277.439181) (xy 174.353355 -277.392164) (xy 174.334095 -277.341807) (xy 174.322372 -277.289183)
			(xy 174.318437 -277.235412) (xy 172.467778 -277.235412) (xy 172.467289 -277.266575) (xy 172.459477 -277.328409)
			(xy 172.443977 -277.388777) (xy 172.421034 -277.446725) (xy 172.391008 -277.501342) (xy 172.354374 -277.551764)
			(xy 172.311709 -277.597198) (xy 172.263687 -277.636926) (xy 172.211063 -277.670321) (xy 172.154669 -277.696858)
			(xy 172.095394 -277.716118) (xy 172.034173 -277.727797) (xy 171.97197 -277.73171) (xy 171.909767 -277.727797)
			(xy 171.848546 -277.716118) (xy 171.789271 -277.696858) (xy 171.732877 -277.670321) (xy 171.680253 -277.636926)
			(xy 171.632231 -277.597198) (xy 171.589566 -277.551764) (xy 171.552932 -277.501342) (xy 171.522906 -277.446725)
			(xy 171.499963 -277.388777) (xy 171.484463 -277.328409) (xy 171.476651 -277.266575) (xy 171.476162 -277.235412)
			(xy 167.512492 -277.235412) (xy 167.512 -277.262369) (xy 167.50415 -277.315709) (xy 167.488618 -277.367338)
			(xy 167.465733 -277.416155) (xy 167.435985 -277.461119) (xy 167.400007 -277.501273) (xy 167.358565 -277.535761)
			(xy 167.312544 -277.563847) (xy 167.262924 -277.584934) (xy 167.210763 -277.59857) (xy 167.157172 -277.604467)
			(xy 167.103293 -277.602498) (xy 167.050275 -277.592705) (xy 166.999248 -277.575297) (xy 166.9513 -277.550645)
			(xy 166.907452 -277.519275) (xy 166.868639 -277.481854) (xy 166.835687 -277.439181) (xy 166.809301 -277.392164)
			(xy 166.790041 -277.341807) (xy 166.778318 -277.289183) (xy 166.774383 -277.235412) (xy 145.735711 -277.235412)
			(xy 145.741636 -277.25316) (xy 145.749531 -277.301737) (xy 145.750026 -277.326344) (xy 145.749531 -277.350951)
			(xy 145.741636 -277.399528) (xy 145.726052 -277.446209) (xy 145.703181 -277.489786) (xy 145.673616 -277.52913)
			(xy 145.638123 -277.563222) (xy 145.59762 -277.591178) (xy 145.553158 -277.612276) (xy 145.505887 -277.625968)
			(xy 145.457032 -277.6319) (xy 145.407857 -277.629919) (xy 145.359638 -277.620075) (xy 145.313622 -277.602623)
			(xy 145.271001 -277.578016) (xy 145.23288 -277.546891) (xy 145.200245 -277.510054) (xy 145.173942 -277.468458)
			(xy 145.154651 -277.423182) (xy 145.142874 -277.375398) (xy 145.138914 -277.326344) (xy 143.869918 -277.326344)
			(xy 143.869423 -277.350951) (xy 143.861528 -277.399528) (xy 143.845944 -277.446209) (xy 143.823073 -277.489786)
			(xy 143.793508 -277.52913) (xy 143.758015 -277.563222) (xy 143.717512 -277.591178) (xy 143.67305 -277.612276)
			(xy 143.625779 -277.625968) (xy 143.576924 -277.6319) (xy 143.527749 -277.629919) (xy 143.47953 -277.620075)
			(xy 143.433514 -277.602623) (xy 143.390893 -277.578016) (xy 143.352772 -277.546891) (xy 143.320137 -277.510054)
			(xy 143.293834 -277.468458) (xy 143.274543 -277.423182) (xy 143.262766 -277.375398) (xy 143.258806 -277.326344)
			(xy 142.940532 -277.326344) (xy 142.94002 -277.35179) (xy 142.931856 -277.402024) (xy 142.91574 -277.450298)
			(xy 142.892089 -277.495361) (xy 142.861516 -277.536047) (xy 142.824812 -277.571302) (xy 142.782928 -277.600212)
			(xy 142.736949 -277.622029) (xy 142.688065 -277.636189) (xy 142.637544 -277.642323) (xy 142.586692 -277.640274)
			(xy 142.536828 -277.630094) (xy 142.489242 -277.612047) (xy 142.445168 -277.586601) (xy 142.405746 -277.554414)
			(xy 142.371998 -277.51632) (xy 142.344797 -277.473306) (xy 142.324849 -277.426486) (xy 142.31267 -277.377072)
			(xy 142.308575 -277.326344) (xy 142.000478 -277.326344) (xy 141.999966 -277.35179) (xy 141.991802 -277.402024)
			(xy 141.975686 -277.450298) (xy 141.952035 -277.495361) (xy 141.921462 -277.536047) (xy 141.884758 -277.571302)
			(xy 141.842874 -277.600212) (xy 141.796895 -277.622029) (xy 141.748011 -277.636189) (xy 141.69749 -277.642323)
			(xy 141.646638 -277.640274) (xy 141.596774 -277.630094) (xy 141.549188 -277.612047) (xy 141.505114 -277.586601)
			(xy 141.465692 -277.554414) (xy 141.431944 -277.51632) (xy 141.404743 -277.473306) (xy 141.384795 -277.426486)
			(xy 141.372616 -277.377072) (xy 141.368521 -277.326344) (xy 141.05001 -277.326344) (xy 141.049515 -277.350951)
			(xy 141.04162 -277.399528) (xy 141.026036 -277.446209) (xy 141.003165 -277.489786) (xy 140.9736 -277.52913)
			(xy 140.938107 -277.563222) (xy 140.897604 -277.591178) (xy 140.853142 -277.612276) (xy 140.805871 -277.625968)
			(xy 140.757016 -277.6319) (xy 140.707841 -277.629919) (xy 140.659622 -277.620075) (xy 140.613606 -277.602623)
			(xy 140.570985 -277.578016) (xy 140.532864 -277.546891) (xy 140.500229 -277.510054) (xy 140.473926 -277.468458)
			(xy 140.454635 -277.423182) (xy 140.442858 -277.375398) (xy 140.438898 -277.326344) (xy 140.12037 -277.326344)
			(xy 140.119858 -277.35179) (xy 140.111694 -277.402024) (xy 140.095578 -277.450298) (xy 140.071927 -277.495361)
			(xy 140.041354 -277.536047) (xy 140.00465 -277.571302) (xy 139.962766 -277.600212) (xy 139.916787 -277.622029)
			(xy 139.867903 -277.636189) (xy 139.817382 -277.642323) (xy 139.76653 -277.640274) (xy 139.716666 -277.630094)
			(xy 139.66908 -277.612047) (xy 139.625006 -277.586601) (xy 139.585584 -277.554414) (xy 139.551836 -277.51632)
			(xy 139.524635 -277.473306) (xy 139.504687 -277.426486) (xy 139.492508 -277.377072) (xy 139.488413 -277.326344)
			(xy 139.170156 -277.326344) (xy 139.169661 -277.350951) (xy 139.161766 -277.399528) (xy 139.146182 -277.446209)
			(xy 139.123311 -277.489786) (xy 139.093746 -277.52913) (xy 139.058253 -277.563222) (xy 139.01775 -277.591178)
			(xy 138.973288 -277.612276) (xy 138.926017 -277.625968) (xy 138.877162 -277.6319) (xy 138.827987 -277.629919)
			(xy 138.779768 -277.620075) (xy 138.733752 -277.602623) (xy 138.691131 -277.578016) (xy 138.65301 -277.546891)
			(xy 138.620375 -277.510054) (xy 138.594072 -277.468458) (xy 138.574781 -277.423182) (xy 138.563004 -277.375398)
			(xy 138.559044 -277.326344) (xy 138.240516 -277.326344) (xy 138.240004 -277.35179) (xy 138.23184 -277.402024)
			(xy 138.215724 -277.450298) (xy 138.192073 -277.495361) (xy 138.1615 -277.536047) (xy 138.124796 -277.571302)
			(xy 138.082912 -277.600212) (xy 138.036933 -277.622029) (xy 137.988049 -277.636189) (xy 137.937528 -277.642323)
			(xy 137.886676 -277.640274) (xy 137.836812 -277.630094) (xy 137.789226 -277.612047) (xy 137.745152 -277.586601)
			(xy 137.70573 -277.554414) (xy 137.671982 -277.51632) (xy 137.644781 -277.473306) (xy 137.624833 -277.426486)
			(xy 137.612654 -277.377072) (xy 137.608559 -277.326344) (xy 137.290048 -277.326344) (xy 137.289553 -277.350951)
			(xy 137.281658 -277.399528) (xy 137.266074 -277.446209) (xy 137.243203 -277.489786) (xy 137.213638 -277.52913)
			(xy 137.178145 -277.563222) (xy 137.137642 -277.591178) (xy 137.09318 -277.612276) (xy 137.045909 -277.625968)
			(xy 136.997054 -277.6319) (xy 136.947879 -277.629919) (xy 136.89966 -277.620075) (xy 136.853644 -277.602623)
			(xy 136.811023 -277.578016) (xy 136.772902 -277.546891) (xy 136.740267 -277.510054) (xy 136.713964 -277.468458)
			(xy 136.694673 -277.423182) (xy 136.682896 -277.375398) (xy 136.678936 -277.326344) (xy 136.360408 -277.326344)
			(xy 136.359896 -277.35179) (xy 136.351732 -277.402024) (xy 136.335616 -277.450298) (xy 136.311965 -277.495361)
			(xy 136.281392 -277.536047) (xy 136.244688 -277.571302) (xy 136.202804 -277.600212) (xy 136.156825 -277.622029)
			(xy 136.107941 -277.636189) (xy 136.05742 -277.642323) (xy 136.006568 -277.640274) (xy 135.956704 -277.630094)
			(xy 135.909118 -277.612047) (xy 135.865044 -277.586601) (xy 135.825622 -277.554414) (xy 135.791874 -277.51632)
			(xy 135.764673 -277.473306) (xy 135.744725 -277.426486) (xy 135.732546 -277.377072) (xy 135.728451 -277.326344)
			(xy 135.420354 -277.326344) (xy 135.419842 -277.35179) (xy 135.411678 -277.402024) (xy 135.395562 -277.450298)
			(xy 135.371911 -277.495361) (xy 135.341338 -277.536047) (xy 135.304634 -277.571302) (xy 135.26275 -277.600212)
			(xy 135.216771 -277.622029) (xy 135.167887 -277.636189) (xy 135.117366 -277.642323) (xy 135.066514 -277.640274)
			(xy 135.01665 -277.630094) (xy 134.969064 -277.612047) (xy 134.92499 -277.586601) (xy 134.885568 -277.554414)
			(xy 134.85182 -277.51632) (xy 134.824619 -277.473306) (xy 134.804671 -277.426486) (xy 134.792492 -277.377072)
			(xy 134.788397 -277.326344) (xy 134.47014 -277.326344) (xy 134.469645 -277.350951) (xy 134.46175 -277.399528)
			(xy 134.446166 -277.446209) (xy 134.423295 -277.489786) (xy 134.39373 -277.52913) (xy 134.358237 -277.563222)
			(xy 134.317734 -277.591178) (xy 134.273272 -277.612276) (xy 134.226001 -277.625968) (xy 134.177146 -277.6319)
			(xy 134.127971 -277.629919) (xy 134.079752 -277.620075) (xy 134.033736 -277.602623) (xy 133.991115 -277.578016)
			(xy 133.952994 -277.546891) (xy 133.920359 -277.510054) (xy 133.894056 -277.468458) (xy 133.874765 -277.423182)
			(xy 133.862988 -277.375398) (xy 133.859028 -277.326344) (xy 133.5405 -277.326344) (xy 133.539988 -277.35179)
			(xy 133.531824 -277.402024) (xy 133.515708 -277.450298) (xy 133.492057 -277.495361) (xy 133.461484 -277.536047)
			(xy 133.42478 -277.571302) (xy 133.382896 -277.600212) (xy 133.336917 -277.622029) (xy 133.288033 -277.636189)
			(xy 133.237512 -277.642323) (xy 133.18666 -277.640274) (xy 133.136796 -277.630094) (xy 133.08921 -277.612047)
			(xy 133.045136 -277.586601) (xy 133.005714 -277.554414) (xy 132.971966 -277.51632) (xy 132.944765 -277.473306)
			(xy 132.924817 -277.426486) (xy 132.912638 -277.377072) (xy 132.908543 -277.326344) (xy 132.590032 -277.326344)
			(xy 132.589537 -277.350951) (xy 132.581642 -277.399528) (xy 132.566058 -277.446209) (xy 132.543187 -277.489786)
			(xy 132.513622 -277.52913) (xy 132.478129 -277.563222) (xy 132.437626 -277.591178) (xy 132.393164 -277.612276)
			(xy 132.345893 -277.625968) (xy 132.297038 -277.6319) (xy 132.247863 -277.629919) (xy 132.199644 -277.620075)
			(xy 132.153628 -277.602623) (xy 132.111007 -277.578016) (xy 132.072886 -277.546891) (xy 132.040251 -277.510054)
			(xy 132.013948 -277.468458) (xy 131.994657 -277.423182) (xy 131.98288 -277.375398) (xy 131.97892 -277.326344)
			(xy 131.660392 -277.326344) (xy 131.65988 -277.35179) (xy 131.651716 -277.402024) (xy 131.6356 -277.450298)
			(xy 131.611949 -277.495361) (xy 131.581376 -277.536047) (xy 131.544672 -277.571302) (xy 131.502788 -277.600212)
			(xy 131.456809 -277.622029) (xy 131.407925 -277.636189) (xy 131.357404 -277.642323) (xy 131.306552 -277.640274)
			(xy 131.256688 -277.630094) (xy 131.209102 -277.612047) (xy 131.165028 -277.586601) (xy 131.125606 -277.554414)
			(xy 131.091858 -277.51632) (xy 131.064657 -277.473306) (xy 131.044709 -277.426486) (xy 131.03253 -277.377072)
			(xy 131.028435 -277.326344) (xy 130.710178 -277.326344) (xy 130.709683 -277.350951) (xy 130.701788 -277.399528)
			(xy 130.686204 -277.446209) (xy 130.663333 -277.489786) (xy 130.633768 -277.52913) (xy 130.598275 -277.563222)
			(xy 130.557772 -277.591178) (xy 130.51331 -277.612276) (xy 130.466039 -277.625968) (xy 130.417184 -277.6319)
			(xy 130.368009 -277.629919) (xy 130.31979 -277.620075) (xy 130.273774 -277.602623) (xy 130.231153 -277.578016)
			(xy 130.193032 -277.546891) (xy 130.160397 -277.510054) (xy 130.134094 -277.468458) (xy 130.114803 -277.423182)
			(xy 130.103026 -277.375398) (xy 130.099066 -277.326344) (xy 129.780538 -277.326344) (xy 129.780026 -277.35179)
			(xy 129.771862 -277.402024) (xy 129.755746 -277.450298) (xy 129.732095 -277.495361) (xy 129.701522 -277.536047)
			(xy 129.664818 -277.571302) (xy 129.622934 -277.600212) (xy 129.576955 -277.622029) (xy 129.528071 -277.636189)
			(xy 129.47755 -277.642323) (xy 129.426698 -277.640274) (xy 129.376834 -277.630094) (xy 129.329248 -277.612047)
			(xy 129.285174 -277.586601) (xy 129.245752 -277.554414) (xy 129.212004 -277.51632) (xy 129.184803 -277.473306)
			(xy 129.164855 -277.426486) (xy 129.152676 -277.377072) (xy 129.148581 -277.326344) (xy 128.840484 -277.326344)
			(xy 128.839972 -277.35179) (xy 128.831808 -277.402024) (xy 128.815692 -277.450298) (xy 128.792041 -277.495361)
			(xy 128.761468 -277.536047) (xy 128.724764 -277.571302) (xy 128.68288 -277.600212) (xy 128.636901 -277.622029)
			(xy 128.588017 -277.636189) (xy 128.537496 -277.642323) (xy 128.486644 -277.640274) (xy 128.43678 -277.630094)
			(xy 128.389194 -277.612047) (xy 128.34512 -277.586601) (xy 128.305698 -277.554414) (xy 128.27195 -277.51632)
			(xy 128.244749 -277.473306) (xy 128.224801 -277.426486) (xy 128.212622 -277.377072) (xy 128.208527 -277.326344)
			(xy 127.20574 -277.326344) (xy 127.20574 -277.824946) (xy 127.22225 -277.850092) (xy 127.23622 -277.856188)
			(xy 127.259282 -277.86673) (xy 127.301834 -277.894306) (xy 127.339245 -277.928532) (xy 127.370487 -277.96847)
			(xy 127.394701 -278.01302) (xy 127.411223 -278.060958) (xy 127.419597 -278.110967) (xy 127.419595 -278.13635)
			(xy 127.738627 -278.13635) (xy 127.742722 -278.085622) (xy 127.754901 -278.036208) (xy 127.774849 -277.989388)
			(xy 127.80205 -277.946374) (xy 127.835798 -277.90828) (xy 127.87522 -277.876093) (xy 127.919294 -277.850647)
			(xy 127.96688 -277.8326) (xy 128.016744 -277.82242) (xy 128.067596 -277.820371) (xy 128.118117 -277.826505)
			(xy 128.167001 -277.840665) (xy 128.21298 -277.862482) (xy 128.254864 -277.891392) (xy 128.291568 -277.926647)
			(xy 128.322141 -277.967333) (xy 128.345792 -278.012396) (xy 128.361908 -278.06067) (xy 128.370072 -278.110904)
			(xy 128.370584 -278.13635) (xy 128.688858 -278.13635) (xy 128.692818 -278.087296) (xy 128.704595 -278.039512)
			(xy 128.723886 -277.994236) (xy 128.750189 -277.95264) (xy 128.782824 -277.915803) (xy 128.820945 -277.884678)
			(xy 128.863566 -277.860071) (xy 128.909582 -277.842619) (xy 128.957801 -277.832775) (xy 129.006976 -277.830794)
			(xy 129.055831 -277.836726) (xy 129.103102 -277.850418) (xy 129.147564 -277.871516) (xy 129.188067 -277.899472)
			(xy 129.22356 -277.933564) (xy 129.253125 -277.972908) (xy 129.275996 -278.016485) (xy 129.29158 -278.063166)
			(xy 129.299475 -278.111743) (xy 129.29997 -278.13635) (xy 129.618481 -278.13635) (xy 129.622576 -278.085622)
			(xy 129.634755 -278.036208) (xy 129.654703 -277.989388) (xy 129.681904 -277.946374) (xy 129.715652 -277.90828)
			(xy 129.755074 -277.876093) (xy 129.799148 -277.850647) (xy 129.846734 -277.8326) (xy 129.896598 -277.82242)
			(xy 129.94745 -277.820371) (xy 129.997971 -277.826505) (xy 130.046855 -277.840665) (xy 130.092834 -277.862482)
			(xy 130.134718 -277.891392) (xy 130.171422 -277.926647) (xy 130.201995 -277.967333) (xy 130.225646 -278.012396)
			(xy 130.241762 -278.06067) (xy 130.249926 -278.110904) (xy 130.250438 -278.13635) (xy 131.498589 -278.13635)
			(xy 131.502684 -278.085622) (xy 131.514863 -278.036208) (xy 131.534811 -277.989388) (xy 131.562012 -277.946374)
			(xy 131.59576 -277.90828) (xy 131.635182 -277.876093) (xy 131.679256 -277.850647) (xy 131.726842 -277.8326)
			(xy 131.776706 -277.82242) (xy 131.827558 -277.820371) (xy 131.878079 -277.826505) (xy 131.926963 -277.840665)
			(xy 131.972942 -277.862482) (xy 132.014826 -277.891392) (xy 132.05153 -277.926647) (xy 132.082103 -277.967333)
			(xy 132.105754 -278.012396) (xy 132.12187 -278.06067) (xy 132.130034 -278.110904) (xy 132.130546 -278.13635)
			(xy 132.438643 -278.13635) (xy 132.442738 -278.085622) (xy 132.454917 -278.036208) (xy 132.474865 -277.989388)
			(xy 132.502066 -277.946374) (xy 132.535814 -277.90828) (xy 132.575236 -277.876093) (xy 132.61931 -277.850647)
			(xy 132.666896 -277.8326) (xy 132.71676 -277.82242) (xy 132.767612 -277.820371) (xy 132.818133 -277.826505)
			(xy 132.867017 -277.840665) (xy 132.912996 -277.862482) (xy 132.95488 -277.891392) (xy 132.991584 -277.926647)
			(xy 133.022157 -277.967333) (xy 133.045808 -278.012396) (xy 133.061924 -278.06067) (xy 133.070088 -278.110904)
			(xy 133.0706 -278.13635) (xy 133.388874 -278.13635) (xy 133.392834 -278.087296) (xy 133.404611 -278.039512)
			(xy 133.423902 -277.994236) (xy 133.450205 -277.95264) (xy 133.48284 -277.915803) (xy 133.520961 -277.884678)
			(xy 133.563582 -277.860071) (xy 133.609598 -277.842619) (xy 133.657817 -277.832775) (xy 133.706992 -277.830794)
			(xy 133.755847 -277.836726) (xy 133.803118 -277.850418) (xy 133.84758 -277.871516) (xy 133.888083 -277.899472)
			(xy 133.923576 -277.933564) (xy 133.953141 -277.972908) (xy 133.976012 -278.016485) (xy 133.991596 -278.063166)
			(xy 133.999491 -278.111743) (xy 133.999986 -278.13635) (xy 134.318497 -278.13635) (xy 134.322592 -278.085622)
			(xy 134.334771 -278.036208) (xy 134.354719 -277.989388) (xy 134.38192 -277.946374) (xy 134.415668 -277.90828)
			(xy 134.45509 -277.876093) (xy 134.499164 -277.850647) (xy 134.54675 -277.8326) (xy 134.596614 -277.82242)
			(xy 134.647466 -277.820371) (xy 134.697987 -277.826505) (xy 134.746871 -277.840665) (xy 134.79285 -277.862482)
			(xy 134.834734 -277.891392) (xy 134.871438 -277.926647) (xy 134.902011 -277.967333) (xy 134.925662 -278.012396)
			(xy 134.941778 -278.06067) (xy 134.949942 -278.110904) (xy 134.950454 -278.13635) (xy 135.268982 -278.13635)
			(xy 135.272942 -278.087296) (xy 135.284719 -278.039512) (xy 135.30401 -277.994236) (xy 135.330313 -277.95264)
			(xy 135.362948 -277.915803) (xy 135.401069 -277.884678) (xy 135.44369 -277.860071) (xy 135.489706 -277.842619)
			(xy 135.537925 -277.832775) (xy 135.5871 -277.830794) (xy 135.635955 -277.836726) (xy 135.683226 -277.850418)
			(xy 135.727688 -277.871516) (xy 135.768191 -277.899472) (xy 135.803684 -277.933564) (xy 135.833249 -277.972908)
			(xy 135.85612 -278.016485) (xy 135.871704 -278.063166) (xy 135.879599 -278.111743) (xy 135.880094 -278.13635)
			(xy 136.198605 -278.13635) (xy 136.2027 -278.085622) (xy 136.214879 -278.036208) (xy 136.234827 -277.989388)
			(xy 136.262028 -277.946374) (xy 136.295776 -277.90828) (xy 136.335198 -277.876093) (xy 136.379272 -277.850647)
			(xy 136.426858 -277.8326) (xy 136.476722 -277.82242) (xy 136.527574 -277.820371) (xy 136.578095 -277.826505)
			(xy 136.626979 -277.840665) (xy 136.672958 -277.862482) (xy 136.714842 -277.891392) (xy 136.751546 -277.926647)
			(xy 136.782119 -277.967333) (xy 136.80577 -278.012396) (xy 136.821886 -278.06067) (xy 136.83005 -278.110904)
			(xy 136.830562 -278.13635) (xy 138.078459 -278.13635) (xy 138.082554 -278.085622) (xy 138.094733 -278.036208)
			(xy 138.114681 -277.989388) (xy 138.141882 -277.946374) (xy 138.17563 -277.90828) (xy 138.215052 -277.876093)
			(xy 138.259126 -277.850647) (xy 138.306712 -277.8326) (xy 138.356576 -277.82242) (xy 138.407428 -277.820371)
			(xy 138.457949 -277.826505) (xy 138.506833 -277.840665) (xy 138.552812 -277.862482) (xy 138.594696 -277.891392)
			(xy 138.6314 -277.926647) (xy 138.661973 -277.967333) (xy 138.685624 -278.012396) (xy 138.70174 -278.06067)
			(xy 138.709904 -278.110904) (xy 138.710416 -278.13635) (xy 139.018513 -278.13635) (xy 139.022608 -278.085622)
			(xy 139.034787 -278.036208) (xy 139.054735 -277.989388) (xy 139.081936 -277.946374) (xy 139.115684 -277.90828)
			(xy 139.155106 -277.876093) (xy 139.19918 -277.850647) (xy 139.246766 -277.8326) (xy 139.29663 -277.82242)
			(xy 139.347482 -277.820371) (xy 139.398003 -277.826505) (xy 139.446887 -277.840665) (xy 139.492866 -277.862482)
			(xy 139.53475 -277.891392) (xy 139.571454 -277.926647) (xy 139.602027 -277.967333) (xy 139.625678 -278.012396)
			(xy 139.641794 -278.06067) (xy 139.649958 -278.110904) (xy 139.65047 -278.13635) (xy 139.968998 -278.13635)
			(xy 139.972958 -278.087296) (xy 139.984735 -278.039512) (xy 140.004026 -277.994236) (xy 140.030329 -277.95264)
			(xy 140.062964 -277.915803) (xy 140.101085 -277.884678) (xy 140.143706 -277.860071) (xy 140.189722 -277.842619)
			(xy 140.237941 -277.832775) (xy 140.287116 -277.830794) (xy 140.335971 -277.836726) (xy 140.383242 -277.850418)
			(xy 140.427704 -277.871516) (xy 140.468207 -277.899472) (xy 140.5037 -277.933564) (xy 140.533265 -277.972908)
			(xy 140.556136 -278.016485) (xy 140.57172 -278.063166) (xy 140.579615 -278.111743) (xy 140.58011 -278.13635)
			(xy 140.898621 -278.13635) (xy 140.902716 -278.085622) (xy 140.914895 -278.036208) (xy 140.934843 -277.989388)
			(xy 140.962044 -277.946374) (xy 140.995792 -277.90828) (xy 141.035214 -277.876093) (xy 141.079288 -277.850647)
			(xy 141.126874 -277.8326) (xy 141.176738 -277.82242) (xy 141.22759 -277.820371) (xy 141.278111 -277.826505)
			(xy 141.326995 -277.840665) (xy 141.372974 -277.862482) (xy 141.414858 -277.891392) (xy 141.451562 -277.926647)
			(xy 141.482135 -277.967333) (xy 141.505786 -278.012396) (xy 141.521902 -278.06067) (xy 141.530066 -278.110904)
			(xy 141.530578 -278.13635) (xy 141.848852 -278.13635) (xy 141.852812 -278.087296) (xy 141.864589 -278.039512)
			(xy 141.88388 -277.994236) (xy 141.910183 -277.95264) (xy 141.942818 -277.915803) (xy 141.980939 -277.884678)
			(xy 142.02356 -277.860071) (xy 142.069576 -277.842619) (xy 142.117795 -277.832775) (xy 142.16697 -277.830794)
			(xy 142.215825 -277.836726) (xy 142.263096 -277.850418) (xy 142.307558 -277.871516) (xy 142.348061 -277.899472)
			(xy 142.383554 -277.933564) (xy 142.413119 -277.972908) (xy 142.43599 -278.016485) (xy 142.451574 -278.063166)
			(xy 142.459469 -278.111743) (xy 142.459964 -278.13635) (xy 142.778475 -278.13635) (xy 142.78257 -278.085622)
			(xy 142.794749 -278.036208) (xy 142.814697 -277.989388) (xy 142.841898 -277.946374) (xy 142.875646 -277.90828)
			(xy 142.915068 -277.876093) (xy 142.959142 -277.850647) (xy 143.006728 -277.8326) (xy 143.056592 -277.82242)
			(xy 143.107444 -277.820371) (xy 143.157965 -277.826505) (xy 143.206849 -277.840665) (xy 143.252828 -277.862482)
			(xy 143.264317 -277.870412) (xy 146.737082 -277.870412) (xy 146.741042 -277.821358) (xy 146.752819 -277.773574)
			(xy 146.77211 -277.728298) (xy 146.798413 -277.686702) (xy 146.831048 -277.649865) (xy 146.869169 -277.61874)
			(xy 146.91179 -277.594133) (xy 146.957806 -277.576681) (xy 147.006025 -277.566837) (xy 147.0552 -277.564856)
			(xy 147.104055 -277.570788) (xy 147.151326 -277.58448) (xy 147.195788 -277.605578) (xy 147.236291 -277.633534)
			(xy 147.271784 -277.667626) (xy 147.301349 -277.70697) (xy 147.32422 -277.750547) (xy 147.339804 -277.797228)
			(xy 147.347699 -277.845805) (xy 147.348194 -277.870412) (xy 147.347699 -277.895019) (xy 147.339804 -277.943596)
			(xy 147.32422 -277.990277) (xy 147.301349 -278.033854) (xy 147.271784 -278.073198) (xy 147.259189 -278.085296)
			(xy 165.442915 -278.085296) (xy 165.44685 -278.031525) (xy 165.458573 -277.978901) (xy 165.477833 -277.928544)
			(xy 165.504219 -277.881527) (xy 165.537171 -277.838854) (xy 165.575984 -277.801433) (xy 165.619832 -277.770063)
			(xy 165.66778 -277.745411) (xy 165.718807 -277.728003) (xy 165.771825 -277.71821) (xy 165.825704 -277.716241)
			(xy 165.879295 -277.722138) (xy 165.931456 -277.735774) (xy 165.981076 -277.756861) (xy 166.027097 -277.784947)
			(xy 166.068539 -277.819435) (xy 166.104517 -277.859589) (xy 166.134265 -277.904553) (xy 166.15715 -277.95337)
			(xy 166.172682 -278.004999) (xy 166.180532 -278.058339) (xy 166.181024 -278.085296) (xy 172.986969 -278.085296)
			(xy 172.990904 -278.031525) (xy 173.002627 -277.978901) (xy 173.021887 -277.928544) (xy 173.048273 -277.881527)
			(xy 173.081225 -277.838854) (xy 173.120038 -277.801433) (xy 173.163886 -277.770063) (xy 173.211834 -277.745411)
			(xy 173.262861 -277.728003) (xy 173.315879 -277.71821) (xy 173.369758 -277.716241) (xy 173.423349 -277.722138)
			(xy 173.47551 -277.735774) (xy 173.52513 -277.756861) (xy 173.571151 -277.784947) (xy 173.612593 -277.819435)
			(xy 173.648571 -277.859589) (xy 173.678319 -277.904553) (xy 173.701204 -277.95337) (xy 173.716736 -278.004999)
			(xy 173.724586 -278.058339) (xy 173.725078 -278.085296) (xy 173.724586 -278.112253) (xy 173.716736 -278.165593)
			(xy 173.701204 -278.217222) (xy 173.678319 -278.266039) (xy 173.648571 -278.311003) (xy 173.612593 -278.351157)
			(xy 173.571151 -278.385645) (xy 173.52513 -278.413731) (xy 173.47551 -278.434818) (xy 173.423349 -278.448454)
			(xy 173.369758 -278.454351) (xy 173.315879 -278.452382) (xy 173.262861 -278.442589) (xy 173.211834 -278.425181)
			(xy 173.163886 -278.400529) (xy 173.120038 -278.369159) (xy 173.081225 -278.331738) (xy 173.048273 -278.289065)
			(xy 173.021887 -278.242048) (xy 173.002627 -278.191691) (xy 172.990904 -278.139067) (xy 172.986969 -278.085296)
			(xy 166.181024 -278.085296) (xy 166.180532 -278.112253) (xy 166.172682 -278.165593) (xy 166.15715 -278.217222)
			(xy 166.134265 -278.266039) (xy 166.104517 -278.311003) (xy 166.068539 -278.351157) (xy 166.027097 -278.385645)
			(xy 165.981076 -278.413731) (xy 165.931456 -278.434818) (xy 165.879295 -278.448454) (xy 165.825704 -278.454351)
			(xy 165.771825 -278.452382) (xy 165.718807 -278.442589) (xy 165.66778 -278.425181) (xy 165.619832 -278.400529)
			(xy 165.575984 -278.369159) (xy 165.537171 -278.331738) (xy 165.504219 -278.289065) (xy 165.477833 -278.242048)
			(xy 165.458573 -278.191691) (xy 165.44685 -278.139067) (xy 165.442915 -278.085296) (xy 147.259189 -278.085296)
			(xy 147.236291 -278.10729) (xy 147.195788 -278.135246) (xy 147.151326 -278.156344) (xy 147.104055 -278.170036)
			(xy 147.0552 -278.175968) (xy 147.006025 -278.173987) (xy 146.957806 -278.164143) (xy 146.91179 -278.146691)
			(xy 146.869169 -278.122084) (xy 146.831048 -278.090959) (xy 146.798413 -278.054122) (xy 146.77211 -278.012526)
			(xy 146.752819 -277.96725) (xy 146.741042 -277.919466) (xy 146.737082 -277.870412) (xy 143.264317 -277.870412)
			(xy 143.294712 -277.891392) (xy 143.331416 -277.926647) (xy 143.361989 -277.967333) (xy 143.38564 -278.012396)
			(xy 143.401756 -278.06067) (xy 143.40992 -278.110904) (xy 143.410432 -278.13635) (xy 143.40992 -278.161796)
			(xy 143.401756 -278.21203) (xy 143.38564 -278.260304) (xy 143.361989 -278.305367) (xy 143.331416 -278.346053)
			(xy 143.294712 -278.381308) (xy 143.252828 -278.410218) (xy 143.206849 -278.432035) (xy 143.157965 -278.446195)
			(xy 143.107444 -278.452329) (xy 143.056592 -278.45028) (xy 143.006728 -278.4401) (xy 142.959142 -278.422053)
			(xy 142.915068 -278.396607) (xy 142.875646 -278.36442) (xy 142.841898 -278.326326) (xy 142.814697 -278.283312)
			(xy 142.794749 -278.236492) (xy 142.78257 -278.187078) (xy 142.778475 -278.13635) (xy 142.459964 -278.13635)
			(xy 142.459469 -278.160957) (xy 142.451574 -278.209534) (xy 142.43599 -278.256215) (xy 142.413119 -278.299792)
			(xy 142.383554 -278.339136) (xy 142.348061 -278.373228) (xy 142.307558 -278.401184) (xy 142.263096 -278.422282)
			(xy 142.215825 -278.435974) (xy 142.16697 -278.441906) (xy 142.117795 -278.439925) (xy 142.069576 -278.430081)
			(xy 142.02356 -278.412629) (xy 141.980939 -278.388022) (xy 141.942818 -278.356897) (xy 141.910183 -278.32006)
			(xy 141.88388 -278.278464) (xy 141.864589 -278.233188) (xy 141.852812 -278.185404) (xy 141.848852 -278.13635)
			(xy 141.530578 -278.13635) (xy 141.530066 -278.161796) (xy 141.521902 -278.21203) (xy 141.505786 -278.260304)
			(xy 141.482135 -278.305367) (xy 141.451562 -278.346053) (xy 141.414858 -278.381308) (xy 141.372974 -278.410218)
			(xy 141.326995 -278.432035) (xy 141.278111 -278.446195) (xy 141.22759 -278.452329) (xy 141.176738 -278.45028)
			(xy 141.126874 -278.4401) (xy 141.079288 -278.422053) (xy 141.035214 -278.396607) (xy 140.995792 -278.36442)
			(xy 140.962044 -278.326326) (xy 140.934843 -278.283312) (xy 140.914895 -278.236492) (xy 140.902716 -278.187078)
			(xy 140.898621 -278.13635) (xy 140.58011 -278.13635) (xy 140.579615 -278.160957) (xy 140.57172 -278.209534)
			(xy 140.556136 -278.256215) (xy 140.533265 -278.299792) (xy 140.5037 -278.339136) (xy 140.468207 -278.373228)
			(xy 140.427704 -278.401184) (xy 140.383242 -278.422282) (xy 140.335971 -278.435974) (xy 140.287116 -278.441906)
			(xy 140.237941 -278.439925) (xy 140.189722 -278.430081) (xy 140.143706 -278.412629) (xy 140.101085 -278.388022)
			(xy 140.062964 -278.356897) (xy 140.030329 -278.32006) (xy 140.004026 -278.278464) (xy 139.984735 -278.233188)
			(xy 139.972958 -278.185404) (xy 139.968998 -278.13635) (xy 139.65047 -278.13635) (xy 139.649958 -278.161796)
			(xy 139.641794 -278.21203) (xy 139.625678 -278.260304) (xy 139.602027 -278.305367) (xy 139.571454 -278.346053)
			(xy 139.53475 -278.381308) (xy 139.492866 -278.410218) (xy 139.446887 -278.432035) (xy 139.398003 -278.446195)
			(xy 139.347482 -278.452329) (xy 139.29663 -278.45028) (xy 139.246766 -278.4401) (xy 139.19918 -278.422053)
			(xy 139.155106 -278.396607) (xy 139.115684 -278.36442) (xy 139.081936 -278.326326) (xy 139.054735 -278.283312)
			(xy 139.034787 -278.236492) (xy 139.022608 -278.187078) (xy 139.018513 -278.13635) (xy 138.710416 -278.13635)
			(xy 138.709904 -278.161796) (xy 138.70174 -278.21203) (xy 138.685624 -278.260304) (xy 138.661973 -278.305367)
			(xy 138.6314 -278.346053) (xy 138.594696 -278.381308) (xy 138.552812 -278.410218) (xy 138.506833 -278.432035)
			(xy 138.457949 -278.446195) (xy 138.407428 -278.452329) (xy 138.356576 -278.45028) (xy 138.306712 -278.4401)
			(xy 138.259126 -278.422053) (xy 138.215052 -278.396607) (xy 138.17563 -278.36442) (xy 138.141882 -278.326326)
			(xy 138.114681 -278.283312) (xy 138.094733 -278.236492) (xy 138.082554 -278.187078) (xy 138.078459 -278.13635)
			(xy 136.830562 -278.13635) (xy 136.83005 -278.161796) (xy 136.821886 -278.21203) (xy 136.80577 -278.260304)
			(xy 136.782119 -278.305367) (xy 136.751546 -278.346053) (xy 136.714842 -278.381308) (xy 136.672958 -278.410218)
			(xy 136.626979 -278.432035) (xy 136.578095 -278.446195) (xy 136.527574 -278.452329) (xy 136.476722 -278.45028)
			(xy 136.426858 -278.4401) (xy 136.379272 -278.422053) (xy 136.335198 -278.396607) (xy 136.295776 -278.36442)
			(xy 136.262028 -278.326326) (xy 136.234827 -278.283312) (xy 136.214879 -278.236492) (xy 136.2027 -278.187078)
			(xy 136.198605 -278.13635) (xy 135.880094 -278.13635) (xy 135.879599 -278.160957) (xy 135.871704 -278.209534)
			(xy 135.85612 -278.256215) (xy 135.833249 -278.299792) (xy 135.803684 -278.339136) (xy 135.768191 -278.373228)
			(xy 135.727688 -278.401184) (xy 135.683226 -278.422282) (xy 135.635955 -278.435974) (xy 135.5871 -278.441906)
			(xy 135.537925 -278.439925) (xy 135.489706 -278.430081) (xy 135.44369 -278.412629) (xy 135.401069 -278.388022)
			(xy 135.362948 -278.356897) (xy 135.330313 -278.32006) (xy 135.30401 -278.278464) (xy 135.284719 -278.233188)
			(xy 135.272942 -278.185404) (xy 135.268982 -278.13635) (xy 134.950454 -278.13635) (xy 134.949942 -278.161796)
			(xy 134.941778 -278.21203) (xy 134.925662 -278.260304) (xy 134.902011 -278.305367) (xy 134.871438 -278.346053)
			(xy 134.834734 -278.381308) (xy 134.79285 -278.410218) (xy 134.746871 -278.432035) (xy 134.697987 -278.446195)
			(xy 134.647466 -278.452329) (xy 134.596614 -278.45028) (xy 134.54675 -278.4401) (xy 134.499164 -278.422053)
			(xy 134.45509 -278.396607) (xy 134.415668 -278.36442) (xy 134.38192 -278.326326) (xy 134.354719 -278.283312)
			(xy 134.334771 -278.236492) (xy 134.322592 -278.187078) (xy 134.318497 -278.13635) (xy 133.999986 -278.13635)
			(xy 133.999491 -278.160957) (xy 133.991596 -278.209534) (xy 133.976012 -278.256215) (xy 133.953141 -278.299792)
			(xy 133.923576 -278.339136) (xy 133.888083 -278.373228) (xy 133.84758 -278.401184) (xy 133.803118 -278.422282)
			(xy 133.755847 -278.435974) (xy 133.706992 -278.441906) (xy 133.657817 -278.439925) (xy 133.609598 -278.430081)
			(xy 133.563582 -278.412629) (xy 133.520961 -278.388022) (xy 133.48284 -278.356897) (xy 133.450205 -278.32006)
			(xy 133.423902 -278.278464) (xy 133.404611 -278.233188) (xy 133.392834 -278.185404) (xy 133.388874 -278.13635)
			(xy 133.0706 -278.13635) (xy 133.070088 -278.161796) (xy 133.061924 -278.21203) (xy 133.045808 -278.260304)
			(xy 133.022157 -278.305367) (xy 132.991584 -278.346053) (xy 132.95488 -278.381308) (xy 132.912996 -278.410218)
			(xy 132.867017 -278.432035) (xy 132.818133 -278.446195) (xy 132.767612 -278.452329) (xy 132.71676 -278.45028)
			(xy 132.666896 -278.4401) (xy 132.61931 -278.422053) (xy 132.575236 -278.396607) (xy 132.535814 -278.36442)
			(xy 132.502066 -278.326326) (xy 132.474865 -278.283312) (xy 132.454917 -278.236492) (xy 132.442738 -278.187078)
			(xy 132.438643 -278.13635) (xy 132.130546 -278.13635) (xy 132.130034 -278.161796) (xy 132.12187 -278.21203)
			(xy 132.105754 -278.260304) (xy 132.082103 -278.305367) (xy 132.05153 -278.346053) (xy 132.014826 -278.381308)
			(xy 131.972942 -278.410218) (xy 131.926963 -278.432035) (xy 131.878079 -278.446195) (xy 131.827558 -278.452329)
			(xy 131.776706 -278.45028) (xy 131.726842 -278.4401) (xy 131.679256 -278.422053) (xy 131.635182 -278.396607)
			(xy 131.59576 -278.36442) (xy 131.562012 -278.326326) (xy 131.534811 -278.283312) (xy 131.514863 -278.236492)
			(xy 131.502684 -278.187078) (xy 131.498589 -278.13635) (xy 130.250438 -278.13635) (xy 130.249926 -278.161796)
			(xy 130.241762 -278.21203) (xy 130.225646 -278.260304) (xy 130.201995 -278.305367) (xy 130.171422 -278.346053)
			(xy 130.134718 -278.381308) (xy 130.092834 -278.410218) (xy 130.046855 -278.432035) (xy 129.997971 -278.446195)
			(xy 129.94745 -278.452329) (xy 129.896598 -278.45028) (xy 129.846734 -278.4401) (xy 129.799148 -278.422053)
			(xy 129.755074 -278.396607) (xy 129.715652 -278.36442) (xy 129.681904 -278.326326) (xy 129.654703 -278.283312)
			(xy 129.634755 -278.236492) (xy 129.622576 -278.187078) (xy 129.618481 -278.13635) (xy 129.29997 -278.13635)
			(xy 129.299475 -278.160957) (xy 129.29158 -278.209534) (xy 129.275996 -278.256215) (xy 129.253125 -278.299792)
			(xy 129.22356 -278.339136) (xy 129.188067 -278.373228) (xy 129.147564 -278.401184) (xy 129.103102 -278.422282)
			(xy 129.055831 -278.435974) (xy 129.006976 -278.441906) (xy 128.957801 -278.439925) (xy 128.909582 -278.430081)
			(xy 128.863566 -278.412629) (xy 128.820945 -278.388022) (xy 128.782824 -278.356897) (xy 128.750189 -278.32006)
			(xy 128.723886 -278.278464) (xy 128.704595 -278.233188) (xy 128.692818 -278.185404) (xy 128.688858 -278.13635)
			(xy 128.370584 -278.13635) (xy 128.370072 -278.161796) (xy 128.361908 -278.21203) (xy 128.345792 -278.260304)
			(xy 128.322141 -278.305367) (xy 128.291568 -278.346053) (xy 128.254864 -278.381308) (xy 128.21298 -278.410218)
			(xy 128.167001 -278.432035) (xy 128.118117 -278.446195) (xy 128.067596 -278.452329) (xy 128.016744 -278.45028)
			(xy 127.96688 -278.4401) (xy 127.919294 -278.422053) (xy 127.87522 -278.396607) (xy 127.835798 -278.36442)
			(xy 127.80205 -278.326326) (xy 127.774849 -278.283312) (xy 127.754901 -278.236492) (xy 127.742722 -278.187078)
			(xy 127.738627 -278.13635) (xy 127.419595 -278.13635) (xy 127.419594 -278.161673) (xy 127.411213 -278.211681)
			(xy 127.394685 -278.259617) (xy 127.370465 -278.304164) (xy 127.339218 -278.344097) (xy 127.301802 -278.378319)
			(xy 127.259247 -278.405888) (xy 127.23622 -278.416512) (xy 127.22225 -278.422608) (xy 127.20574 -278.447754)
			(xy 127.20574 -278.648668) (xy 127.206195 -278.658506) (xy 127.213624 -278.676725) (xy 127.227391 -278.690782)
			(xy 127.23622 -278.69515) (xy 127.335534 -278.738584) (xy 127.365252 -278.733504) (xy 127.376682 -278.72309)
			(xy 127.39371 -278.70776) (xy 127.431503 -278.681859) (xy 127.472742 -278.661898) (xy 127.516503 -278.648326)
			(xy 127.5618 -278.641449) (xy 127.584708 -278.641048) (xy 127.609967 -278.64157) (xy 127.659795 -278.649886)
			(xy 127.707574 -278.66629) (xy 127.752002 -278.690334) (xy 127.791867 -278.721363) (xy 127.826081 -278.75853)
			(xy 127.853711 -278.800822) (xy 127.874003 -278.847084) (xy 127.886404 -278.896055) (xy 127.890572 -278.946356)
			(xy 128.208527 -278.946356) (xy 128.212622 -278.895628) (xy 128.224801 -278.846214) (xy 128.244749 -278.799394)
			(xy 128.27195 -278.75638) (xy 128.305698 -278.718286) (xy 128.34512 -278.686099) (xy 128.389194 -278.660653)
			(xy 128.43678 -278.642606) (xy 128.486644 -278.632426) (xy 128.537496 -278.630377) (xy 128.588017 -278.636511)
			(xy 128.636901 -278.650671) (xy 128.68288 -278.672488) (xy 128.724764 -278.701398) (xy 128.761468 -278.736653)
			(xy 128.792041 -278.777339) (xy 128.815692 -278.822402) (xy 128.831808 -278.870676) (xy 128.839972 -278.92091)
			(xy 128.840484 -278.946356) (xy 129.148581 -278.946356) (xy 129.152676 -278.895628) (xy 129.164855 -278.846214)
			(xy 129.184803 -278.799394) (xy 129.212004 -278.75638) (xy 129.245752 -278.718286) (xy 129.285174 -278.686099)
			(xy 129.329248 -278.660653) (xy 129.376834 -278.642606) (xy 129.426698 -278.632426) (xy 129.47755 -278.630377)
			(xy 129.528071 -278.636511) (xy 129.576955 -278.650671) (xy 129.622934 -278.672488) (xy 129.664818 -278.701398)
			(xy 129.701522 -278.736653) (xy 129.732095 -278.777339) (xy 129.755746 -278.822402) (xy 129.771862 -278.870676)
			(xy 129.780026 -278.92091) (xy 129.780538 -278.946356) (xy 130.099066 -278.946356) (xy 130.103026 -278.897302)
			(xy 130.114803 -278.849518) (xy 130.134094 -278.804242) (xy 130.160397 -278.762646) (xy 130.193032 -278.725809)
			(xy 130.231153 -278.694684) (xy 130.273774 -278.670077) (xy 130.31979 -278.652625) (xy 130.368009 -278.642781)
			(xy 130.417184 -278.6408) (xy 130.466039 -278.646732) (xy 130.51331 -278.660424) (xy 130.557772 -278.681522)
			(xy 130.598275 -278.709478) (xy 130.633768 -278.74357) (xy 130.663333 -278.782914) (xy 130.686204 -278.826491)
			(xy 130.701788 -278.873172) (xy 130.709683 -278.921749) (xy 130.710178 -278.946356) (xy 131.028435 -278.946356)
			(xy 131.03253 -278.895628) (xy 131.044709 -278.846214) (xy 131.064657 -278.799394) (xy 131.091858 -278.75638)
			(xy 131.125606 -278.718286) (xy 131.165028 -278.686099) (xy 131.209102 -278.660653) (xy 131.256688 -278.642606)
			(xy 131.306552 -278.632426) (xy 131.357404 -278.630377) (xy 131.407925 -278.636511) (xy 131.456809 -278.650671)
			(xy 131.502788 -278.672488) (xy 131.544672 -278.701398) (xy 131.581376 -278.736653) (xy 131.611949 -278.777339)
			(xy 131.6356 -278.822402) (xy 131.651716 -278.870676) (xy 131.65988 -278.92091) (xy 131.660392 -278.946356)
			(xy 131.97892 -278.946356) (xy 131.98288 -278.897302) (xy 131.994657 -278.849518) (xy 132.013948 -278.804242)
			(xy 132.040251 -278.762646) (xy 132.072886 -278.725809) (xy 132.111007 -278.694684) (xy 132.153628 -278.670077)
			(xy 132.199644 -278.652625) (xy 132.247863 -278.642781) (xy 132.297038 -278.6408) (xy 132.345893 -278.646732)
			(xy 132.393164 -278.660424) (xy 132.437626 -278.681522) (xy 132.478129 -278.709478) (xy 132.513622 -278.74357)
			(xy 132.543187 -278.782914) (xy 132.566058 -278.826491) (xy 132.581642 -278.873172) (xy 132.589537 -278.921749)
			(xy 132.590032 -278.946356) (xy 132.908543 -278.946356) (xy 132.912638 -278.895628) (xy 132.924817 -278.846214)
			(xy 132.944765 -278.799394) (xy 132.971966 -278.75638) (xy 133.005714 -278.718286) (xy 133.045136 -278.686099)
			(xy 133.08921 -278.660653) (xy 133.136796 -278.642606) (xy 133.18666 -278.632426) (xy 133.237512 -278.630377)
			(xy 133.288033 -278.636511) (xy 133.336917 -278.650671) (xy 133.382896 -278.672488) (xy 133.42478 -278.701398)
			(xy 133.461484 -278.736653) (xy 133.492057 -278.777339) (xy 133.515708 -278.822402) (xy 133.531824 -278.870676)
			(xy 133.539988 -278.92091) (xy 133.5405 -278.946356) (xy 133.859028 -278.946356) (xy 133.862988 -278.897302)
			(xy 133.874765 -278.849518) (xy 133.894056 -278.804242) (xy 133.920359 -278.762646) (xy 133.952994 -278.725809)
			(xy 133.991115 -278.694684) (xy 134.033736 -278.670077) (xy 134.079752 -278.652625) (xy 134.127971 -278.642781)
			(xy 134.177146 -278.6408) (xy 134.226001 -278.646732) (xy 134.273272 -278.660424) (xy 134.317734 -278.681522)
			(xy 134.358237 -278.709478) (xy 134.39373 -278.74357) (xy 134.423295 -278.782914) (xy 134.446166 -278.826491)
			(xy 134.46175 -278.873172) (xy 134.469645 -278.921749) (xy 134.47014 -278.946356) (xy 134.788397 -278.946356)
			(xy 134.792492 -278.895628) (xy 134.804671 -278.846214) (xy 134.824619 -278.799394) (xy 134.85182 -278.75638)
			(xy 134.885568 -278.718286) (xy 134.92499 -278.686099) (xy 134.969064 -278.660653) (xy 135.01665 -278.642606)
			(xy 135.066514 -278.632426) (xy 135.117366 -278.630377) (xy 135.167887 -278.636511) (xy 135.216771 -278.650671)
			(xy 135.26275 -278.672488) (xy 135.304634 -278.701398) (xy 135.341338 -278.736653) (xy 135.371911 -278.777339)
			(xy 135.395562 -278.822402) (xy 135.411678 -278.870676) (xy 135.419842 -278.92091) (xy 135.420354 -278.946356)
			(xy 135.728451 -278.946356) (xy 135.732546 -278.895628) (xy 135.744725 -278.846214) (xy 135.764673 -278.799394)
			(xy 135.791874 -278.75638) (xy 135.825622 -278.718286) (xy 135.865044 -278.686099) (xy 135.909118 -278.660653)
			(xy 135.956704 -278.642606) (xy 136.006568 -278.632426) (xy 136.05742 -278.630377) (xy 136.107941 -278.636511)
			(xy 136.156825 -278.650671) (xy 136.202804 -278.672488) (xy 136.244688 -278.701398) (xy 136.281392 -278.736653)
			(xy 136.311965 -278.777339) (xy 136.335616 -278.822402) (xy 136.351732 -278.870676) (xy 136.359896 -278.92091)
			(xy 136.360408 -278.946356) (xy 136.678936 -278.946356) (xy 136.682896 -278.897302) (xy 136.694673 -278.849518)
			(xy 136.713964 -278.804242) (xy 136.740267 -278.762646) (xy 136.772902 -278.725809) (xy 136.811023 -278.694684)
			(xy 136.853644 -278.670077) (xy 136.89966 -278.652625) (xy 136.947879 -278.642781) (xy 136.997054 -278.6408)
			(xy 137.045909 -278.646732) (xy 137.09318 -278.660424) (xy 137.137642 -278.681522) (xy 137.178145 -278.709478)
			(xy 137.213638 -278.74357) (xy 137.243203 -278.782914) (xy 137.266074 -278.826491) (xy 137.281658 -278.873172)
			(xy 137.289553 -278.921749) (xy 137.290048 -278.946356) (xy 137.608559 -278.946356) (xy 137.612654 -278.895628)
			(xy 137.624833 -278.846214) (xy 137.644781 -278.799394) (xy 137.671982 -278.75638) (xy 137.70573 -278.718286)
			(xy 137.745152 -278.686099) (xy 137.789226 -278.660653) (xy 137.836812 -278.642606) (xy 137.886676 -278.632426)
			(xy 137.937528 -278.630377) (xy 137.988049 -278.636511) (xy 138.036933 -278.650671) (xy 138.082912 -278.672488)
			(xy 138.124796 -278.701398) (xy 138.1615 -278.736653) (xy 138.192073 -278.777339) (xy 138.215724 -278.822402)
			(xy 138.23184 -278.870676) (xy 138.240004 -278.92091) (xy 138.240516 -278.946356) (xy 138.559044 -278.946356)
			(xy 138.563004 -278.897302) (xy 138.574781 -278.849518) (xy 138.594072 -278.804242) (xy 138.620375 -278.762646)
			(xy 138.65301 -278.725809) (xy 138.691131 -278.694684) (xy 138.733752 -278.670077) (xy 138.779768 -278.652625)
			(xy 138.827987 -278.642781) (xy 138.877162 -278.6408) (xy 138.926017 -278.646732) (xy 138.973288 -278.660424)
			(xy 139.01775 -278.681522) (xy 139.058253 -278.709478) (xy 139.093746 -278.74357) (xy 139.123311 -278.782914)
			(xy 139.146182 -278.826491) (xy 139.161766 -278.873172) (xy 139.169661 -278.921749) (xy 139.170156 -278.946356)
			(xy 139.488413 -278.946356) (xy 139.492508 -278.895628) (xy 139.504687 -278.846214) (xy 139.524635 -278.799394)
			(xy 139.551836 -278.75638) (xy 139.585584 -278.718286) (xy 139.625006 -278.686099) (xy 139.66908 -278.660653)
			(xy 139.716666 -278.642606) (xy 139.76653 -278.632426) (xy 139.817382 -278.630377) (xy 139.867903 -278.636511)
			(xy 139.916787 -278.650671) (xy 139.962766 -278.672488) (xy 140.00465 -278.701398) (xy 140.041354 -278.736653)
			(xy 140.071927 -278.777339) (xy 140.095578 -278.822402) (xy 140.111694 -278.870676) (xy 140.119858 -278.92091)
			(xy 140.12037 -278.946356) (xy 140.438898 -278.946356) (xy 140.442858 -278.897302) (xy 140.454635 -278.849518)
			(xy 140.473926 -278.804242) (xy 140.500229 -278.762646) (xy 140.532864 -278.725809) (xy 140.570985 -278.694684)
			(xy 140.613606 -278.670077) (xy 140.659622 -278.652625) (xy 140.707841 -278.642781) (xy 140.757016 -278.6408)
			(xy 140.805871 -278.646732) (xy 140.853142 -278.660424) (xy 140.897604 -278.681522) (xy 140.938107 -278.709478)
			(xy 140.9736 -278.74357) (xy 141.003165 -278.782914) (xy 141.026036 -278.826491) (xy 141.04162 -278.873172)
			(xy 141.049515 -278.921749) (xy 141.05001 -278.946356) (xy 141.368521 -278.946356) (xy 141.372616 -278.895628)
			(xy 141.384795 -278.846214) (xy 141.404743 -278.799394) (xy 141.431944 -278.75638) (xy 141.465692 -278.718286)
			(xy 141.505114 -278.686099) (xy 141.549188 -278.660653) (xy 141.596774 -278.642606) (xy 141.646638 -278.632426)
			(xy 141.69749 -278.630377) (xy 141.748011 -278.636511) (xy 141.796895 -278.650671) (xy 141.842874 -278.672488)
			(xy 141.884758 -278.701398) (xy 141.921462 -278.736653) (xy 141.952035 -278.777339) (xy 141.975686 -278.822402)
			(xy 141.991802 -278.870676) (xy 141.999966 -278.92091) (xy 142.000478 -278.946356) (xy 142.308575 -278.946356)
			(xy 142.31267 -278.895628) (xy 142.324849 -278.846214) (xy 142.344797 -278.799394) (xy 142.371998 -278.75638)
			(xy 142.405746 -278.718286) (xy 142.445168 -278.686099) (xy 142.489242 -278.660653) (xy 142.536828 -278.642606)
			(xy 142.586692 -278.632426) (xy 142.637544 -278.630377) (xy 142.688065 -278.636511) (xy 142.736949 -278.650671)
			(xy 142.782928 -278.672488) (xy 142.824812 -278.701398) (xy 142.861516 -278.736653) (xy 142.892089 -278.777339)
			(xy 142.91574 -278.822402) (xy 142.931856 -278.870676) (xy 142.94002 -278.92091) (xy 142.940532 -278.946356)
			(xy 143.258806 -278.946356) (xy 143.262766 -278.897302) (xy 143.274543 -278.849518) (xy 143.293834 -278.804242)
			(xy 143.320137 -278.762646) (xy 143.352772 -278.725809) (xy 143.390893 -278.694684) (xy 143.433514 -278.670077)
			(xy 143.47953 -278.652625) (xy 143.527749 -278.642781) (xy 143.576924 -278.6408) (xy 143.625779 -278.646732)
			(xy 143.67305 -278.660424) (xy 143.717512 -278.681522) (xy 143.758015 -278.709478) (xy 143.793508 -278.74357)
			(xy 143.823073 -278.782914) (xy 143.845944 -278.826491) (xy 143.861528 -278.873172) (xy 143.869423 -278.921749)
			(xy 143.869918 -278.946356) (xy 145.138914 -278.946356) (xy 145.142874 -278.897302) (xy 145.154651 -278.849518)
			(xy 145.173942 -278.804242) (xy 145.200245 -278.762646) (xy 145.23288 -278.725809) (xy 145.271001 -278.694684)
			(xy 145.313622 -278.670077) (xy 145.359638 -278.652625) (xy 145.407857 -278.642781) (xy 145.457032 -278.6408)
			(xy 145.505887 -278.646732) (xy 145.553158 -278.660424) (xy 145.59762 -278.681522) (xy 145.638123 -278.709478)
			(xy 145.673616 -278.74357) (xy 145.703181 -278.782914) (xy 145.726052 -278.826491) (xy 145.741636 -278.873172)
			(xy 145.749531 -278.921749) (xy 145.749806 -278.935434) (xy 168.158683 -278.935434) (xy 168.162618 -278.881663)
			(xy 168.174341 -278.829039) (xy 168.193601 -278.778682) (xy 168.219987 -278.731665) (xy 168.252939 -278.688992)
			(xy 168.291752 -278.651571) (xy 168.3356 -278.620201) (xy 168.383548 -278.595549) (xy 168.434575 -278.578141)
			(xy 168.487593 -278.568348) (xy 168.541472 -278.566379) (xy 168.595063 -278.572276) (xy 168.647224 -278.585912)
			(xy 168.696844 -278.606999) (xy 168.742865 -278.635085) (xy 168.784307 -278.669573) (xy 168.820285 -278.709727)
			(xy 168.850033 -278.754691) (xy 168.872918 -278.803508) (xy 168.88845 -278.855137) (xy 168.8963 -278.908477)
			(xy 168.896792 -278.935434) (xy 168.8963 -278.962391) (xy 168.88845 -279.015731) (xy 168.872918 -279.06736)
			(xy 168.850033 -279.116177) (xy 168.820285 -279.161141) (xy 168.784307 -279.201295) (xy 168.742865 -279.235783)
			(xy 168.696844 -279.263869) (xy 168.647224 -279.284956) (xy 168.595063 -279.298592) (xy 168.541472 -279.304489)
			(xy 168.487593 -279.30252) (xy 168.434575 -279.292727) (xy 168.383548 -279.275319) (xy 168.3356 -279.250667)
			(xy 168.291752 -279.219297) (xy 168.252939 -279.181876) (xy 168.219987 -279.139203) (xy 168.193601 -279.092186)
			(xy 168.174341 -279.041829) (xy 168.162618 -278.989205) (xy 168.158683 -278.935434) (xy 145.749806 -278.935434)
			(xy 145.750026 -278.946356) (xy 145.749531 -278.970963) (xy 145.741636 -279.01954) (xy 145.726052 -279.066221)
			(xy 145.703181 -279.109798) (xy 145.673616 -279.149142) (xy 145.638123 -279.183234) (xy 145.59762 -279.21119)
			(xy 145.553158 -279.232288) (xy 145.505887 -279.24598) (xy 145.457032 -279.251912) (xy 145.407857 -279.249931)
			(xy 145.359638 -279.240087) (xy 145.313622 -279.222635) (xy 145.271001 -279.198028) (xy 145.23288 -279.166903)
			(xy 145.200245 -279.130066) (xy 145.173942 -279.08847) (xy 145.154651 -279.043194) (xy 145.142874 -278.99541)
			(xy 145.138914 -278.946356) (xy 143.869918 -278.946356) (xy 143.869423 -278.970963) (xy 143.861528 -279.01954)
			(xy 143.845944 -279.066221) (xy 143.823073 -279.109798) (xy 143.793508 -279.149142) (xy 143.758015 -279.183234)
			(xy 143.717512 -279.21119) (xy 143.67305 -279.232288) (xy 143.625779 -279.24598) (xy 143.576924 -279.251912)
			(xy 143.527749 -279.249931) (xy 143.47953 -279.240087) (xy 143.433514 -279.222635) (xy 143.390893 -279.198028)
			(xy 143.352772 -279.166903) (xy 143.320137 -279.130066) (xy 143.293834 -279.08847) (xy 143.274543 -279.043194)
			(xy 143.262766 -278.99541) (xy 143.258806 -278.946356) (xy 142.940532 -278.946356) (xy 142.94002 -278.971802)
			(xy 142.931856 -279.022036) (xy 142.91574 -279.07031) (xy 142.892089 -279.115373) (xy 142.861516 -279.156059)
			(xy 142.824812 -279.191314) (xy 142.782928 -279.220224) (xy 142.736949 -279.242041) (xy 142.688065 -279.256201)
			(xy 142.637544 -279.262335) (xy 142.586692 -279.260286) (xy 142.536828 -279.250106) (xy 142.489242 -279.232059)
			(xy 142.445168 -279.206613) (xy 142.405746 -279.174426) (xy 142.371998 -279.136332) (xy 142.344797 -279.093318)
			(xy 142.324849 -279.046498) (xy 142.31267 -278.997084) (xy 142.308575 -278.946356) (xy 142.000478 -278.946356)
			(xy 141.999966 -278.971802) (xy 141.991802 -279.022036) (xy 141.975686 -279.07031) (xy 141.952035 -279.115373)
			(xy 141.921462 -279.156059) (xy 141.884758 -279.191314) (xy 141.842874 -279.220224) (xy 141.796895 -279.242041)
			(xy 141.748011 -279.256201) (xy 141.69749 -279.262335) (xy 141.646638 -279.260286) (xy 141.596774 -279.250106)
			(xy 141.549188 -279.232059) (xy 141.505114 -279.206613) (xy 141.465692 -279.174426) (xy 141.431944 -279.136332)
			(xy 141.404743 -279.093318) (xy 141.384795 -279.046498) (xy 141.372616 -278.997084) (xy 141.368521 -278.946356)
			(xy 141.05001 -278.946356) (xy 141.049515 -278.970963) (xy 141.04162 -279.01954) (xy 141.026036 -279.066221)
			(xy 141.003165 -279.109798) (xy 140.9736 -279.149142) (xy 140.938107 -279.183234) (xy 140.897604 -279.21119)
			(xy 140.853142 -279.232288) (xy 140.805871 -279.24598) (xy 140.757016 -279.251912) (xy 140.707841 -279.249931)
			(xy 140.659622 -279.240087) (xy 140.613606 -279.222635) (xy 140.570985 -279.198028) (xy 140.532864 -279.166903)
			(xy 140.500229 -279.130066) (xy 140.473926 -279.08847) (xy 140.454635 -279.043194) (xy 140.442858 -278.99541)
			(xy 140.438898 -278.946356) (xy 140.12037 -278.946356) (xy 140.119858 -278.971802) (xy 140.111694 -279.022036)
			(xy 140.095578 -279.07031) (xy 140.071927 -279.115373) (xy 140.041354 -279.156059) (xy 140.00465 -279.191314)
			(xy 139.962766 -279.220224) (xy 139.916787 -279.242041) (xy 139.867903 -279.256201) (xy 139.817382 -279.262335)
			(xy 139.76653 -279.260286) (xy 139.716666 -279.250106) (xy 139.66908 -279.232059) (xy 139.625006 -279.206613)
			(xy 139.585584 -279.174426) (xy 139.551836 -279.136332) (xy 139.524635 -279.093318) (xy 139.504687 -279.046498)
			(xy 139.492508 -278.997084) (xy 139.488413 -278.946356) (xy 139.170156 -278.946356) (xy 139.169661 -278.970963)
			(xy 139.161766 -279.01954) (xy 139.146182 -279.066221) (xy 139.123311 -279.109798) (xy 139.093746 -279.149142)
			(xy 139.058253 -279.183234) (xy 139.01775 -279.21119) (xy 138.973288 -279.232288) (xy 138.926017 -279.24598)
			(xy 138.877162 -279.251912) (xy 138.827987 -279.249931) (xy 138.779768 -279.240087) (xy 138.733752 -279.222635)
			(xy 138.691131 -279.198028) (xy 138.65301 -279.166903) (xy 138.620375 -279.130066) (xy 138.594072 -279.08847)
			(xy 138.574781 -279.043194) (xy 138.563004 -278.99541) (xy 138.559044 -278.946356) (xy 138.240516 -278.946356)
			(xy 138.240004 -278.971802) (xy 138.23184 -279.022036) (xy 138.215724 -279.07031) (xy 138.192073 -279.115373)
			(xy 138.1615 -279.156059) (xy 138.124796 -279.191314) (xy 138.082912 -279.220224) (xy 138.036933 -279.242041)
			(xy 137.988049 -279.256201) (xy 137.937528 -279.262335) (xy 137.886676 -279.260286) (xy 137.836812 -279.250106)
			(xy 137.789226 -279.232059) (xy 137.745152 -279.206613) (xy 137.70573 -279.174426) (xy 137.671982 -279.136332)
			(xy 137.644781 -279.093318) (xy 137.624833 -279.046498) (xy 137.612654 -278.997084) (xy 137.608559 -278.946356)
			(xy 137.290048 -278.946356) (xy 137.289553 -278.970963) (xy 137.281658 -279.01954) (xy 137.266074 -279.066221)
			(xy 137.243203 -279.109798) (xy 137.213638 -279.149142) (xy 137.178145 -279.183234) (xy 137.137642 -279.21119)
			(xy 137.09318 -279.232288) (xy 137.045909 -279.24598) (xy 136.997054 -279.251912) (xy 136.947879 -279.249931)
			(xy 136.89966 -279.240087) (xy 136.853644 -279.222635) (xy 136.811023 -279.198028) (xy 136.772902 -279.166903)
			(xy 136.740267 -279.130066) (xy 136.713964 -279.08847) (xy 136.694673 -279.043194) (xy 136.682896 -278.99541)
			(xy 136.678936 -278.946356) (xy 136.360408 -278.946356) (xy 136.359896 -278.971802) (xy 136.351732 -279.022036)
			(xy 136.335616 -279.07031) (xy 136.311965 -279.115373) (xy 136.281392 -279.156059) (xy 136.244688 -279.191314)
			(xy 136.202804 -279.220224) (xy 136.156825 -279.242041) (xy 136.107941 -279.256201) (xy 136.05742 -279.262335)
			(xy 136.006568 -279.260286) (xy 135.956704 -279.250106) (xy 135.909118 -279.232059) (xy 135.865044 -279.206613)
			(xy 135.825622 -279.174426) (xy 135.791874 -279.136332) (xy 135.764673 -279.093318) (xy 135.744725 -279.046498)
			(xy 135.732546 -278.997084) (xy 135.728451 -278.946356) (xy 135.420354 -278.946356) (xy 135.419842 -278.971802)
			(xy 135.411678 -279.022036) (xy 135.395562 -279.07031) (xy 135.371911 -279.115373) (xy 135.341338 -279.156059)
			(xy 135.304634 -279.191314) (xy 135.26275 -279.220224) (xy 135.216771 -279.242041) (xy 135.167887 -279.256201)
			(xy 135.117366 -279.262335) (xy 135.066514 -279.260286) (xy 135.01665 -279.250106) (xy 134.969064 -279.232059)
			(xy 134.92499 -279.206613) (xy 134.885568 -279.174426) (xy 134.85182 -279.136332) (xy 134.824619 -279.093318)
			(xy 134.804671 -279.046498) (xy 134.792492 -278.997084) (xy 134.788397 -278.946356) (xy 134.47014 -278.946356)
			(xy 134.469645 -278.970963) (xy 134.46175 -279.01954) (xy 134.446166 -279.066221) (xy 134.423295 -279.109798)
			(xy 134.39373 -279.149142) (xy 134.358237 -279.183234) (xy 134.317734 -279.21119) (xy 134.273272 -279.232288)
			(xy 134.226001 -279.24598) (xy 134.177146 -279.251912) (xy 134.127971 -279.249931) (xy 134.079752 -279.240087)
			(xy 134.033736 -279.222635) (xy 133.991115 -279.198028) (xy 133.952994 -279.166903) (xy 133.920359 -279.130066)
			(xy 133.894056 -279.08847) (xy 133.874765 -279.043194) (xy 133.862988 -278.99541) (xy 133.859028 -278.946356)
			(xy 133.5405 -278.946356) (xy 133.539988 -278.971802) (xy 133.531824 -279.022036) (xy 133.515708 -279.07031)
			(xy 133.492057 -279.115373) (xy 133.461484 -279.156059) (xy 133.42478 -279.191314) (xy 133.382896 -279.220224)
			(xy 133.336917 -279.242041) (xy 133.288033 -279.256201) (xy 133.237512 -279.262335) (xy 133.18666 -279.260286)
			(xy 133.136796 -279.250106) (xy 133.08921 -279.232059) (xy 133.045136 -279.206613) (xy 133.005714 -279.174426)
			(xy 132.971966 -279.136332) (xy 132.944765 -279.093318) (xy 132.924817 -279.046498) (xy 132.912638 -278.997084)
			(xy 132.908543 -278.946356) (xy 132.590032 -278.946356) (xy 132.589537 -278.970963) (xy 132.581642 -279.01954)
			(xy 132.566058 -279.066221) (xy 132.543187 -279.109798) (xy 132.513622 -279.149142) (xy 132.478129 -279.183234)
			(xy 132.437626 -279.21119) (xy 132.393164 -279.232288) (xy 132.345893 -279.24598) (xy 132.297038 -279.251912)
			(xy 132.247863 -279.249931) (xy 132.199644 -279.240087) (xy 132.153628 -279.222635) (xy 132.111007 -279.198028)
			(xy 132.072886 -279.166903) (xy 132.040251 -279.130066) (xy 132.013948 -279.08847) (xy 131.994657 -279.043194)
			(xy 131.98288 -278.99541) (xy 131.97892 -278.946356) (xy 131.660392 -278.946356) (xy 131.65988 -278.971802)
			(xy 131.651716 -279.022036) (xy 131.6356 -279.07031) (xy 131.611949 -279.115373) (xy 131.581376 -279.156059)
			(xy 131.544672 -279.191314) (xy 131.502788 -279.220224) (xy 131.456809 -279.242041) (xy 131.407925 -279.256201)
			(xy 131.357404 -279.262335) (xy 131.306552 -279.260286) (xy 131.256688 -279.250106) (xy 131.209102 -279.232059)
			(xy 131.165028 -279.206613) (xy 131.125606 -279.174426) (xy 131.091858 -279.136332) (xy 131.064657 -279.093318)
			(xy 131.044709 -279.046498) (xy 131.03253 -278.997084) (xy 131.028435 -278.946356) (xy 130.710178 -278.946356)
			(xy 130.709683 -278.970963) (xy 130.701788 -279.01954) (xy 130.686204 -279.066221) (xy 130.663333 -279.109798)
			(xy 130.633768 -279.149142) (xy 130.598275 -279.183234) (xy 130.557772 -279.21119) (xy 130.51331 -279.232288)
			(xy 130.466039 -279.24598) (xy 130.417184 -279.251912) (xy 130.368009 -279.249931) (xy 130.31979 -279.240087)
			(xy 130.273774 -279.222635) (xy 130.231153 -279.198028) (xy 130.193032 -279.166903) (xy 130.160397 -279.130066)
			(xy 130.134094 -279.08847) (xy 130.114803 -279.043194) (xy 130.103026 -278.99541) (xy 130.099066 -278.946356)
			(xy 129.780538 -278.946356) (xy 129.780026 -278.971802) (xy 129.771862 -279.022036) (xy 129.755746 -279.07031)
			(xy 129.732095 -279.115373) (xy 129.701522 -279.156059) (xy 129.664818 -279.191314) (xy 129.622934 -279.220224)
			(xy 129.576955 -279.242041) (xy 129.528071 -279.256201) (xy 129.47755 -279.262335) (xy 129.426698 -279.260286)
			(xy 129.376834 -279.250106) (xy 129.329248 -279.232059) (xy 129.285174 -279.206613) (xy 129.245752 -279.174426)
			(xy 129.212004 -279.136332) (xy 129.184803 -279.093318) (xy 129.164855 -279.046498) (xy 129.152676 -278.997084)
			(xy 129.148581 -278.946356) (xy 128.840484 -278.946356) (xy 128.839972 -278.971802) (xy 128.831808 -279.022036)
			(xy 128.815692 -279.07031) (xy 128.792041 -279.115373) (xy 128.761468 -279.156059) (xy 128.724764 -279.191314)
			(xy 128.68288 -279.220224) (xy 128.636901 -279.242041) (xy 128.588017 -279.256201) (xy 128.537496 -279.262335)
			(xy 128.486644 -279.260286) (xy 128.43678 -279.250106) (xy 128.389194 -279.232059) (xy 128.34512 -279.206613)
			(xy 128.305698 -279.174426) (xy 128.27195 -279.136332) (xy 128.244749 -279.093318) (xy 128.224801 -279.046498)
			(xy 128.212622 -278.997084) (xy 128.208527 -278.946356) (xy 127.890572 -278.946356) (xy 127.890576 -278.9464)
			(xy 127.886404 -278.996745) (xy 127.874003 -279.045716) (xy 127.853711 -279.091978) (xy 127.826081 -279.13427)
			(xy 127.791867 -279.171437) (xy 127.752002 -279.202466) (xy 127.707574 -279.22651) (xy 127.659795 -279.242914)
			(xy 127.609967 -279.25123) (xy 127.584708 -279.251664) (xy 127.561802 -279.251233) (xy 127.516511 -279.244348)
			(xy 127.472755 -279.230777) (xy 127.431517 -279.210824) (xy 127.39372 -279.184937) (xy 127.376682 -279.169622)
			(xy 127.365252 -279.159208) (xy 127.335534 -279.154128) (xy 127.23622 -279.197562) (xy 127.227399 -279.201926)
			(xy 127.213677 -279.21601) (xy 127.206243 -279.234214) (xy 127.20574 -279.244044) (xy 127.20574 -279.402032)
			(xy 127.206186 -279.412175) (xy 127.214028 -279.430884) (xy 127.228483 -279.445117) (xy 127.237744 -279.449276)
			(xy 127.261935 -279.459503) (xy 127.306997 -279.48648) (xy 127.34723 -279.520237) (xy 127.381624 -279.559927)
			(xy 127.409315 -279.604553) (xy 127.429608 -279.652994) (xy 127.441991 -279.704032) (xy 127.446154 -279.756362)
			(xy 127.738627 -279.756362) (xy 127.742722 -279.705634) (xy 127.754901 -279.65622) (xy 127.774849 -279.6094)
			(xy 127.80205 -279.566386) (xy 127.835798 -279.528292) (xy 127.87522 -279.496105) (xy 127.919294 -279.470659)
			(xy 127.96688 -279.452612) (xy 128.016744 -279.442432) (xy 128.067596 -279.440383) (xy 128.118117 -279.446517)
			(xy 128.167001 -279.460677) (xy 128.21298 -279.482494) (xy 128.254864 -279.511404) (xy 128.291568 -279.546659)
			(xy 128.322141 -279.587345) (xy 128.345792 -279.632408) (xy 128.361908 -279.680682) (xy 128.370072 -279.730916)
			(xy 128.370584 -279.756362) (xy 128.688858 -279.756362) (xy 128.692818 -279.707308) (xy 128.704595 -279.659524)
			(xy 128.723886 -279.614248) (xy 128.750189 -279.572652) (xy 128.782824 -279.535815) (xy 128.820945 -279.50469)
			(xy 128.863566 -279.480083) (xy 128.909582 -279.462631) (xy 128.957801 -279.452787) (xy 129.006976 -279.450806)
			(xy 129.055831 -279.456738) (xy 129.103102 -279.47043) (xy 129.147564 -279.491528) (xy 129.188067 -279.519484)
			(xy 129.22356 -279.553576) (xy 129.253125 -279.59292) (xy 129.275996 -279.636497) (xy 129.29158 -279.683178)
			(xy 129.299475 -279.731755) (xy 129.29997 -279.756362) (xy 129.618481 -279.756362) (xy 129.622576 -279.705634)
			(xy 129.634755 -279.65622) (xy 129.654703 -279.6094) (xy 129.681904 -279.566386) (xy 129.715652 -279.528292)
			(xy 129.755074 -279.496105) (xy 129.799148 -279.470659) (xy 129.846734 -279.452612) (xy 129.896598 -279.442432)
			(xy 129.94745 -279.440383) (xy 129.997971 -279.446517) (xy 130.046855 -279.460677) (xy 130.092834 -279.482494)
			(xy 130.134718 -279.511404) (xy 130.171422 -279.546659) (xy 130.201995 -279.587345) (xy 130.225646 -279.632408)
			(xy 130.241762 -279.680682) (xy 130.249926 -279.730916) (xy 130.250438 -279.756362) (xy 130.568966 -279.756362)
			(xy 130.572926 -279.707308) (xy 130.584703 -279.659524) (xy 130.603994 -279.614248) (xy 130.630297 -279.572652)
			(xy 130.662932 -279.535815) (xy 130.701053 -279.50469) (xy 130.743674 -279.480083) (xy 130.78969 -279.462631)
			(xy 130.837909 -279.452787) (xy 130.887084 -279.450806) (xy 130.935939 -279.456738) (xy 130.98321 -279.47043)
			(xy 131.027672 -279.491528) (xy 131.068175 -279.519484) (xy 131.103668 -279.553576) (xy 131.133233 -279.59292)
			(xy 131.156104 -279.636497) (xy 131.171688 -279.683178) (xy 131.179583 -279.731755) (xy 131.180078 -279.756362)
			(xy 131.498589 -279.756362) (xy 131.502684 -279.705634) (xy 131.514863 -279.65622) (xy 131.534811 -279.6094)
			(xy 131.562012 -279.566386) (xy 131.59576 -279.528292) (xy 131.635182 -279.496105) (xy 131.679256 -279.470659)
			(xy 131.726842 -279.452612) (xy 131.776706 -279.442432) (xy 131.827558 -279.440383) (xy 131.878079 -279.446517)
			(xy 131.926963 -279.460677) (xy 131.972942 -279.482494) (xy 132.014826 -279.511404) (xy 132.05153 -279.546659)
			(xy 132.082103 -279.587345) (xy 132.105754 -279.632408) (xy 132.12187 -279.680682) (xy 132.130034 -279.730916)
			(xy 132.130546 -279.756362) (xy 132.438643 -279.756362) (xy 132.442738 -279.705634) (xy 132.454917 -279.65622)
			(xy 132.474865 -279.6094) (xy 132.502066 -279.566386) (xy 132.535814 -279.528292) (xy 132.575236 -279.496105)
			(xy 132.61931 -279.470659) (xy 132.666896 -279.452612) (xy 132.71676 -279.442432) (xy 132.767612 -279.440383)
			(xy 132.818133 -279.446517) (xy 132.867017 -279.460677) (xy 132.912996 -279.482494) (xy 132.95488 -279.511404)
			(xy 132.991584 -279.546659) (xy 133.022157 -279.587345) (xy 133.045808 -279.632408) (xy 133.061924 -279.680682)
			(xy 133.070088 -279.730916) (xy 133.0706 -279.756362) (xy 133.388874 -279.756362) (xy 133.392834 -279.707308)
			(xy 133.404611 -279.659524) (xy 133.423902 -279.614248) (xy 133.450205 -279.572652) (xy 133.48284 -279.535815)
			(xy 133.520961 -279.50469) (xy 133.563582 -279.480083) (xy 133.609598 -279.462631) (xy 133.657817 -279.452787)
			(xy 133.706992 -279.450806) (xy 133.755847 -279.456738) (xy 133.803118 -279.47043) (xy 133.84758 -279.491528)
			(xy 133.888083 -279.519484) (xy 133.923576 -279.553576) (xy 133.953141 -279.59292) (xy 133.976012 -279.636497)
			(xy 133.991596 -279.683178) (xy 133.999491 -279.731755) (xy 133.999986 -279.756362) (xy 134.318497 -279.756362)
			(xy 134.322592 -279.705634) (xy 134.334771 -279.65622) (xy 134.354719 -279.6094) (xy 134.38192 -279.566386)
			(xy 134.415668 -279.528292) (xy 134.45509 -279.496105) (xy 134.499164 -279.470659) (xy 134.54675 -279.452612)
			(xy 134.596614 -279.442432) (xy 134.647466 -279.440383) (xy 134.697987 -279.446517) (xy 134.746871 -279.460677)
			(xy 134.79285 -279.482494) (xy 134.834734 -279.511404) (xy 134.871438 -279.546659) (xy 134.902011 -279.587345)
			(xy 134.925662 -279.632408) (xy 134.941778 -279.680682) (xy 134.949942 -279.730916) (xy 134.950454 -279.756362)
			(xy 135.268982 -279.756362) (xy 135.272942 -279.707308) (xy 135.284719 -279.659524) (xy 135.30401 -279.614248)
			(xy 135.330313 -279.572652) (xy 135.362948 -279.535815) (xy 135.401069 -279.50469) (xy 135.44369 -279.480083)
			(xy 135.489706 -279.462631) (xy 135.537925 -279.452787) (xy 135.5871 -279.450806) (xy 135.635955 -279.456738)
			(xy 135.683226 -279.47043) (xy 135.727688 -279.491528) (xy 135.768191 -279.519484) (xy 135.803684 -279.553576)
			(xy 135.833249 -279.59292) (xy 135.85612 -279.636497) (xy 135.871704 -279.683178) (xy 135.879599 -279.731755)
			(xy 135.880094 -279.756362) (xy 136.198605 -279.756362) (xy 136.2027 -279.705634) (xy 136.214879 -279.65622)
			(xy 136.234827 -279.6094) (xy 136.262028 -279.566386) (xy 136.295776 -279.528292) (xy 136.335198 -279.496105)
			(xy 136.379272 -279.470659) (xy 136.426858 -279.452612) (xy 136.476722 -279.442432) (xy 136.527574 -279.440383)
			(xy 136.578095 -279.446517) (xy 136.626979 -279.460677) (xy 136.672958 -279.482494) (xy 136.714842 -279.511404)
			(xy 136.751546 -279.546659) (xy 136.782119 -279.587345) (xy 136.80577 -279.632408) (xy 136.821886 -279.680682)
			(xy 136.83005 -279.730916) (xy 136.830562 -279.756362) (xy 137.148836 -279.756362) (xy 137.152796 -279.707308)
			(xy 137.164573 -279.659524) (xy 137.183864 -279.614248) (xy 137.210167 -279.572652) (xy 137.242802 -279.535815)
			(xy 137.280923 -279.50469) (xy 137.323544 -279.480083) (xy 137.36956 -279.462631) (xy 137.417779 -279.452787)
			(xy 137.466954 -279.450806) (xy 137.515809 -279.456738) (xy 137.56308 -279.47043) (xy 137.607542 -279.491528)
			(xy 137.648045 -279.519484) (xy 137.683538 -279.553576) (xy 137.713103 -279.59292) (xy 137.735974 -279.636497)
			(xy 137.751558 -279.683178) (xy 137.759453 -279.731755) (xy 137.759948 -279.756362) (xy 138.078459 -279.756362)
			(xy 138.082554 -279.705634) (xy 138.094733 -279.65622) (xy 138.114681 -279.6094) (xy 138.141882 -279.566386)
			(xy 138.17563 -279.528292) (xy 138.215052 -279.496105) (xy 138.259126 -279.470659) (xy 138.306712 -279.452612)
			(xy 138.356576 -279.442432) (xy 138.407428 -279.440383) (xy 138.457949 -279.446517) (xy 138.506833 -279.460677)
			(xy 138.552812 -279.482494) (xy 138.594696 -279.511404) (xy 138.6314 -279.546659) (xy 138.661973 -279.587345)
			(xy 138.685624 -279.632408) (xy 138.70174 -279.680682) (xy 138.709904 -279.730916) (xy 138.710416 -279.756362)
			(xy 139.018513 -279.756362) (xy 139.022608 -279.705634) (xy 139.034787 -279.65622) (xy 139.054735 -279.6094)
			(xy 139.081936 -279.566386) (xy 139.115684 -279.528292) (xy 139.155106 -279.496105) (xy 139.19918 -279.470659)
			(xy 139.246766 -279.452612) (xy 139.29663 -279.442432) (xy 139.347482 -279.440383) (xy 139.398003 -279.446517)
			(xy 139.446887 -279.460677) (xy 139.492866 -279.482494) (xy 139.53475 -279.511404) (xy 139.571454 -279.546659)
			(xy 139.602027 -279.587345) (xy 139.625678 -279.632408) (xy 139.641794 -279.680682) (xy 139.649958 -279.730916)
			(xy 139.65047 -279.756362) (xy 139.968998 -279.756362) (xy 139.972958 -279.707308) (xy 139.984735 -279.659524)
			(xy 140.004026 -279.614248) (xy 140.030329 -279.572652) (xy 140.062964 -279.535815) (xy 140.101085 -279.50469)
			(xy 140.143706 -279.480083) (xy 140.189722 -279.462631) (xy 140.237941 -279.452787) (xy 140.287116 -279.450806)
			(xy 140.335971 -279.456738) (xy 140.383242 -279.47043) (xy 140.427704 -279.491528) (xy 140.468207 -279.519484)
			(xy 140.5037 -279.553576) (xy 140.533265 -279.59292) (xy 140.556136 -279.636497) (xy 140.57172 -279.683178)
			(xy 140.579615 -279.731755) (xy 140.58011 -279.756362) (xy 140.898621 -279.756362) (xy 140.902716 -279.705634)
			(xy 140.914895 -279.65622) (xy 140.934843 -279.6094) (xy 140.962044 -279.566386) (xy 140.995792 -279.528292)
			(xy 141.035214 -279.496105) (xy 141.079288 -279.470659) (xy 141.126874 -279.452612) (xy 141.176738 -279.442432)
			(xy 141.22759 -279.440383) (xy 141.278111 -279.446517) (xy 141.326995 -279.460677) (xy 141.372974 -279.482494)
			(xy 141.414858 -279.511404) (xy 141.451562 -279.546659) (xy 141.482135 -279.587345) (xy 141.505786 -279.632408)
			(xy 141.521902 -279.680682) (xy 141.530066 -279.730916) (xy 141.530578 -279.756362) (xy 141.848852 -279.756362)
			(xy 141.852812 -279.707308) (xy 141.864589 -279.659524) (xy 141.88388 -279.614248) (xy 141.910183 -279.572652)
			(xy 141.942818 -279.535815) (xy 141.980939 -279.50469) (xy 142.02356 -279.480083) (xy 142.069576 -279.462631)
			(xy 142.117795 -279.452787) (xy 142.16697 -279.450806) (xy 142.215825 -279.456738) (xy 142.263096 -279.47043)
			(xy 142.307558 -279.491528) (xy 142.348061 -279.519484) (xy 142.383554 -279.553576) (xy 142.413119 -279.59292)
			(xy 142.43599 -279.636497) (xy 142.451574 -279.683178) (xy 142.459469 -279.731755) (xy 142.459964 -279.756362)
			(xy 142.778475 -279.756362) (xy 142.78257 -279.705634) (xy 142.794749 -279.65622) (xy 142.814697 -279.6094)
			(xy 142.841898 -279.566386) (xy 142.875646 -279.528292) (xy 142.915068 -279.496105) (xy 142.959142 -279.470659)
			(xy 143.006728 -279.452612) (xy 143.056592 -279.442432) (xy 143.107444 -279.440383) (xy 143.157965 -279.446517)
			(xy 143.206849 -279.460677) (xy 143.252828 -279.482494) (xy 143.294712 -279.511404) (xy 143.331416 -279.546659)
			(xy 143.361989 -279.587345) (xy 143.38564 -279.632408) (xy 143.401756 -279.680682) (xy 143.40992 -279.730916)
			(xy 143.410432 -279.756362) (xy 143.72896 -279.756362) (xy 143.73292 -279.707308) (xy 143.744697 -279.659524)
			(xy 143.763988 -279.614248) (xy 143.790291 -279.572652) (xy 143.822926 -279.535815) (xy 143.861047 -279.50469)
			(xy 143.903668 -279.480083) (xy 143.949684 -279.462631) (xy 143.997903 -279.452787) (xy 144.047078 -279.450806)
			(xy 144.095933 -279.456738) (xy 144.143204 -279.47043) (xy 144.185339 -279.490424) (xy 146.737082 -279.490424)
			(xy 146.741042 -279.44137) (xy 146.752819 -279.393586) (xy 146.77211 -279.34831) (xy 146.798413 -279.306714)
			(xy 146.831048 -279.269877) (xy 146.869169 -279.238752) (xy 146.91179 -279.214145) (xy 146.957806 -279.196693)
			(xy 147.006025 -279.186849) (xy 147.0552 -279.184868) (xy 147.104055 -279.1908) (xy 147.151326 -279.204492)
			(xy 147.195788 -279.22559) (xy 147.236291 -279.253546) (xy 147.271784 -279.287638) (xy 147.301349 -279.326982)
			(xy 147.32422 -279.370559) (xy 147.339804 -279.41724) (xy 147.347699 -279.465817) (xy 147.348194 -279.490424)
			(xy 147.347699 -279.515031) (xy 147.339804 -279.563608) (xy 147.32422 -279.610289) (xy 147.301349 -279.653866)
			(xy 147.271784 -279.69321) (xy 147.236291 -279.727302) (xy 147.195788 -279.755258) (xy 147.151326 -279.776356)
			(xy 147.120385 -279.785318) (xy 164.058615 -279.785318) (xy 164.06255 -279.731547) (xy 164.074273 -279.678923)
			(xy 164.093533 -279.628566) (xy 164.119919 -279.581549) (xy 164.152871 -279.538876) (xy 164.191684 -279.501455)
			(xy 164.235532 -279.470085) (xy 164.28348 -279.445433) (xy 164.334507 -279.428025) (xy 164.387525 -279.418232)
			(xy 164.441404 -279.416263) (xy 164.494995 -279.42216) (xy 164.547156 -279.435796) (xy 164.596776 -279.456883)
			(xy 164.642797 -279.484969) (xy 164.684239 -279.519457) (xy 164.720217 -279.559611) (xy 164.749965 -279.604575)
			(xy 164.77285 -279.653392) (xy 164.788382 -279.705021) (xy 164.796232 -279.758361) (xy 164.796724 -279.785318)
			(xy 164.796232 -279.812275) (xy 164.788382 -279.865615) (xy 164.77285 -279.917244) (xy 164.749965 -279.966061)
			(xy 164.720217 -280.011025) (xy 164.684239 -280.051179) (xy 164.642797 -280.085667) (xy 164.596776 -280.113753)
			(xy 164.547156 -280.13484) (xy 164.494995 -280.148476) (xy 164.441404 -280.154373) (xy 164.387525 -280.152404)
			(xy 164.334507 -280.142611) (xy 164.28348 -280.125203) (xy 164.235532 -280.100551) (xy 164.191684 -280.069181)
			(xy 164.152871 -280.03176) (xy 164.119919 -279.989087) (xy 164.093533 -279.94207) (xy 164.074273 -279.891713)
			(xy 164.06255 -279.839089) (xy 164.058615 -279.785318) (xy 147.120385 -279.785318) (xy 147.104055 -279.790048)
			(xy 147.0552 -279.79598) (xy 147.006025 -279.793999) (xy 146.957806 -279.784155) (xy 146.91179 -279.766703)
			(xy 146.869169 -279.742096) (xy 146.831048 -279.710971) (xy 146.798413 -279.674134) (xy 146.77211 -279.632538)
			(xy 146.752819 -279.587262) (xy 146.741042 -279.539478) (xy 146.737082 -279.490424) (xy 144.185339 -279.490424)
			(xy 144.187666 -279.491528) (xy 144.228169 -279.519484) (xy 144.263662 -279.553576) (xy 144.293227 -279.59292)
			(xy 144.316098 -279.636497) (xy 144.331682 -279.683178) (xy 144.339577 -279.731755) (xy 144.340072 -279.756362)
			(xy 144.339577 -279.780969) (xy 144.331682 -279.829546) (xy 144.316098 -279.876227) (xy 144.293227 -279.919804)
			(xy 144.263662 -279.959148) (xy 144.228169 -279.99324) (xy 144.187666 -280.021196) (xy 144.143204 -280.042294)
			(xy 144.095933 -280.055986) (xy 144.047078 -280.061918) (xy 143.997903 -280.059937) (xy 143.949684 -280.050093)
			(xy 143.903668 -280.032641) (xy 143.861047 -280.008034) (xy 143.822926 -279.976909) (xy 143.790291 -279.940072)
			(xy 143.763988 -279.898476) (xy 143.744697 -279.8532) (xy 143.73292 -279.805416) (xy 143.72896 -279.756362)
			(xy 143.410432 -279.756362) (xy 143.40992 -279.781808) (xy 143.401756 -279.832042) (xy 143.38564 -279.880316)
			(xy 143.361989 -279.925379) (xy 143.331416 -279.966065) (xy 143.294712 -280.00132) (xy 143.252828 -280.03023)
			(xy 143.206849 -280.052047) (xy 143.157965 -280.066207) (xy 143.107444 -280.072341) (xy 143.056592 -280.070292)
			(xy 143.006728 -280.060112) (xy 142.959142 -280.042065) (xy 142.915068 -280.016619) (xy 142.875646 -279.984432)
			(xy 142.841898 -279.946338) (xy 142.814697 -279.903324) (xy 142.794749 -279.856504) (xy 142.78257 -279.80709)
			(xy 142.778475 -279.756362) (xy 142.459964 -279.756362) (xy 142.459469 -279.780969) (xy 142.451574 -279.829546)
			(xy 142.43599 -279.876227) (xy 142.413119 -279.919804) (xy 142.383554 -279.959148) (xy 142.348061 -279.99324)
			(xy 142.307558 -280.021196) (xy 142.263096 -280.042294) (xy 142.215825 -280.055986) (xy 142.16697 -280.061918)
			(xy 142.117795 -280.059937) (xy 142.069576 -280.050093) (xy 142.02356 -280.032641) (xy 141.980939 -280.008034)
			(xy 141.942818 -279.976909) (xy 141.910183 -279.940072) (xy 141.88388 -279.898476) (xy 141.864589 -279.8532)
			(xy 141.852812 -279.805416) (xy 141.848852 -279.756362) (xy 141.530578 -279.756362) (xy 141.530066 -279.781808)
			(xy 141.521902 -279.832042) (xy 141.505786 -279.880316) (xy 141.482135 -279.925379) (xy 141.451562 -279.966065)
			(xy 141.414858 -280.00132) (xy 141.372974 -280.03023) (xy 141.326995 -280.052047) (xy 141.278111 -280.066207)
			(xy 141.22759 -280.072341) (xy 141.176738 -280.070292) (xy 141.126874 -280.060112) (xy 141.079288 -280.042065)
			(xy 141.035214 -280.016619) (xy 140.995792 -279.984432) (xy 140.962044 -279.946338) (xy 140.934843 -279.903324)
			(xy 140.914895 -279.856504) (xy 140.902716 -279.80709) (xy 140.898621 -279.756362) (xy 140.58011 -279.756362)
			(xy 140.579615 -279.780969) (xy 140.57172 -279.829546) (xy 140.556136 -279.876227) (xy 140.533265 -279.919804)
			(xy 140.5037 -279.959148) (xy 140.468207 -279.99324) (xy 140.427704 -280.021196) (xy 140.383242 -280.042294)
			(xy 140.335971 -280.055986) (xy 140.287116 -280.061918) (xy 140.237941 -280.059937) (xy 140.189722 -280.050093)
			(xy 140.143706 -280.032641) (xy 140.101085 -280.008034) (xy 140.062964 -279.976909) (xy 140.030329 -279.940072)
			(xy 140.004026 -279.898476) (xy 139.984735 -279.8532) (xy 139.972958 -279.805416) (xy 139.968998 -279.756362)
			(xy 139.65047 -279.756362) (xy 139.649958 -279.781808) (xy 139.641794 -279.832042) (xy 139.625678 -279.880316)
			(xy 139.602027 -279.925379) (xy 139.571454 -279.966065) (xy 139.53475 -280.00132) (xy 139.492866 -280.03023)
			(xy 139.446887 -280.052047) (xy 139.398003 -280.066207) (xy 139.347482 -280.072341) (xy 139.29663 -280.070292)
			(xy 139.246766 -280.060112) (xy 139.19918 -280.042065) (xy 139.155106 -280.016619) (xy 139.115684 -279.984432)
			(xy 139.081936 -279.946338) (xy 139.054735 -279.903324) (xy 139.034787 -279.856504) (xy 139.022608 -279.80709)
			(xy 139.018513 -279.756362) (xy 138.710416 -279.756362) (xy 138.709904 -279.781808) (xy 138.70174 -279.832042)
			(xy 138.685624 -279.880316) (xy 138.661973 -279.925379) (xy 138.6314 -279.966065) (xy 138.594696 -280.00132)
			(xy 138.552812 -280.03023) (xy 138.506833 -280.052047) (xy 138.457949 -280.066207) (xy 138.407428 -280.072341)
			(xy 138.356576 -280.070292) (xy 138.306712 -280.060112) (xy 138.259126 -280.042065) (xy 138.215052 -280.016619)
			(xy 138.17563 -279.984432) (xy 138.141882 -279.946338) (xy 138.114681 -279.903324) (xy 138.094733 -279.856504)
			(xy 138.082554 -279.80709) (xy 138.078459 -279.756362) (xy 137.759948 -279.756362) (xy 137.759453 -279.780969)
			(xy 137.751558 -279.829546) (xy 137.735974 -279.876227) (xy 137.713103 -279.919804) (xy 137.683538 -279.959148)
			(xy 137.648045 -279.99324) (xy 137.607542 -280.021196) (xy 137.56308 -280.042294) (xy 137.515809 -280.055986)
			(xy 137.466954 -280.061918) (xy 137.417779 -280.059937) (xy 137.36956 -280.050093) (xy 137.323544 -280.032641)
			(xy 137.280923 -280.008034) (xy 137.242802 -279.976909) (xy 137.210167 -279.940072) (xy 137.183864 -279.898476)
			(xy 137.164573 -279.8532) (xy 137.152796 -279.805416) (xy 137.148836 -279.756362) (xy 136.830562 -279.756362)
			(xy 136.83005 -279.781808) (xy 136.821886 -279.832042) (xy 136.80577 -279.880316) (xy 136.782119 -279.925379)
			(xy 136.751546 -279.966065) (xy 136.714842 -280.00132) (xy 136.672958 -280.03023) (xy 136.626979 -280.052047)
			(xy 136.578095 -280.066207) (xy 136.527574 -280.072341) (xy 136.476722 -280.070292) (xy 136.426858 -280.060112)
			(xy 136.379272 -280.042065) (xy 136.335198 -280.016619) (xy 136.295776 -279.984432) (xy 136.262028 -279.946338)
			(xy 136.234827 -279.903324) (xy 136.214879 -279.856504) (xy 136.2027 -279.80709) (xy 136.198605 -279.756362)
			(xy 135.880094 -279.756362) (xy 135.879599 -279.780969) (xy 135.871704 -279.829546) (xy 135.85612 -279.876227)
			(xy 135.833249 -279.919804) (xy 135.803684 -279.959148) (xy 135.768191 -279.99324) (xy 135.727688 -280.021196)
			(xy 135.683226 -280.042294) (xy 135.635955 -280.055986) (xy 135.5871 -280.061918) (xy 135.537925 -280.059937)
			(xy 135.489706 -280.050093) (xy 135.44369 -280.032641) (xy 135.401069 -280.008034) (xy 135.362948 -279.976909)
			(xy 135.330313 -279.940072) (xy 135.30401 -279.898476) (xy 135.284719 -279.8532) (xy 135.272942 -279.805416)
			(xy 135.268982 -279.756362) (xy 134.950454 -279.756362) (xy 134.949942 -279.781808) (xy 134.941778 -279.832042)
			(xy 134.925662 -279.880316) (xy 134.902011 -279.925379) (xy 134.871438 -279.966065) (xy 134.834734 -280.00132)
			(xy 134.79285 -280.03023) (xy 134.746871 -280.052047) (xy 134.697987 -280.066207) (xy 134.647466 -280.072341)
			(xy 134.596614 -280.070292) (xy 134.54675 -280.060112) (xy 134.499164 -280.042065) (xy 134.45509 -280.016619)
			(xy 134.415668 -279.984432) (xy 134.38192 -279.946338) (xy 134.354719 -279.903324) (xy 134.334771 -279.856504)
			(xy 134.322592 -279.80709) (xy 134.318497 -279.756362) (xy 133.999986 -279.756362) (xy 133.999491 -279.780969)
			(xy 133.991596 -279.829546) (xy 133.976012 -279.876227) (xy 133.953141 -279.919804) (xy 133.923576 -279.959148)
			(xy 133.888083 -279.99324) (xy 133.84758 -280.021196) (xy 133.803118 -280.042294) (xy 133.755847 -280.055986)
			(xy 133.706992 -280.061918) (xy 133.657817 -280.059937) (xy 133.609598 -280.050093) (xy 133.563582 -280.032641)
			(xy 133.520961 -280.008034) (xy 133.48284 -279.976909) (xy 133.450205 -279.940072) (xy 133.423902 -279.898476)
			(xy 133.404611 -279.8532) (xy 133.392834 -279.805416) (xy 133.388874 -279.756362) (xy 133.0706 -279.756362)
			(xy 133.070088 -279.781808) (xy 133.061924 -279.832042) (xy 133.045808 -279.880316) (xy 133.022157 -279.925379)
			(xy 132.991584 -279.966065) (xy 132.95488 -280.00132) (xy 132.912996 -280.03023) (xy 132.867017 -280.052047)
			(xy 132.818133 -280.066207) (xy 132.767612 -280.072341) (xy 132.71676 -280.070292) (xy 132.666896 -280.060112)
			(xy 132.61931 -280.042065) (xy 132.575236 -280.016619) (xy 132.535814 -279.984432) (xy 132.502066 -279.946338)
			(xy 132.474865 -279.903324) (xy 132.454917 -279.856504) (xy 132.442738 -279.80709) (xy 132.438643 -279.756362)
			(xy 132.130546 -279.756362) (xy 132.130034 -279.781808) (xy 132.12187 -279.832042) (xy 132.105754 -279.880316)
			(xy 132.082103 -279.925379) (xy 132.05153 -279.966065) (xy 132.014826 -280.00132) (xy 131.972942 -280.03023)
			(xy 131.926963 -280.052047) (xy 131.878079 -280.066207) (xy 131.827558 -280.072341) (xy 131.776706 -280.070292)
			(xy 131.726842 -280.060112) (xy 131.679256 -280.042065) (xy 131.635182 -280.016619) (xy 131.59576 -279.984432)
			(xy 131.562012 -279.946338) (xy 131.534811 -279.903324) (xy 131.514863 -279.856504) (xy 131.502684 -279.80709)
			(xy 131.498589 -279.756362) (xy 131.180078 -279.756362) (xy 131.179583 -279.780969) (xy 131.171688 -279.829546)
			(xy 131.156104 -279.876227) (xy 131.133233 -279.919804) (xy 131.103668 -279.959148) (xy 131.068175 -279.99324)
			(xy 131.027672 -280.021196) (xy 130.98321 -280.042294) (xy 130.935939 -280.055986) (xy 130.887084 -280.061918)
			(xy 130.837909 -280.059937) (xy 130.78969 -280.050093) (xy 130.743674 -280.032641) (xy 130.701053 -280.008034)
			(xy 130.662932 -279.976909) (xy 130.630297 -279.940072) (xy 130.603994 -279.898476) (xy 130.584703 -279.8532)
			(xy 130.572926 -279.805416) (xy 130.568966 -279.756362) (xy 130.250438 -279.756362) (xy 130.249926 -279.781808)
			(xy 130.241762 -279.832042) (xy 130.225646 -279.880316) (xy 130.201995 -279.925379) (xy 130.171422 -279.966065)
			(xy 130.134718 -280.00132) (xy 130.092834 -280.03023) (xy 130.046855 -280.052047) (xy 129.997971 -280.066207)
			(xy 129.94745 -280.072341) (xy 129.896598 -280.070292) (xy 129.846734 -280.060112) (xy 129.799148 -280.042065)
			(xy 129.755074 -280.016619) (xy 129.715652 -279.984432) (xy 129.681904 -279.946338) (xy 129.654703 -279.903324)
			(xy 129.634755 -279.856504) (xy 129.622576 -279.80709) (xy 129.618481 -279.756362) (xy 129.29997 -279.756362)
			(xy 129.299475 -279.780969) (xy 129.29158 -279.829546) (xy 129.275996 -279.876227) (xy 129.253125 -279.919804)
			(xy 129.22356 -279.959148) (xy 129.188067 -279.99324) (xy 129.147564 -280.021196) (xy 129.103102 -280.042294)
			(xy 129.055831 -280.055986) (xy 129.006976 -280.061918) (xy 128.957801 -280.059937) (xy 128.909582 -280.050093)
			(xy 128.863566 -280.032641) (xy 128.820945 -280.008034) (xy 128.782824 -279.976909) (xy 128.750189 -279.940072)
			(xy 128.723886 -279.898476) (xy 128.704595 -279.8532) (xy 128.692818 -279.805416) (xy 128.688858 -279.756362)
			(xy 128.370584 -279.756362) (xy 128.370072 -279.781808) (xy 128.361908 -279.832042) (xy 128.345792 -279.880316)
			(xy 128.322141 -279.925379) (xy 128.291568 -279.966065) (xy 128.254864 -280.00132) (xy 128.21298 -280.03023)
			(xy 128.167001 -280.052047) (xy 128.118117 -280.066207) (xy 128.067596 -280.072341) (xy 128.016744 -280.070292)
			(xy 127.96688 -280.060112) (xy 127.919294 -280.042065) (xy 127.87522 -280.016619) (xy 127.835798 -279.984432)
			(xy 127.80205 -279.946338) (xy 127.774849 -279.903324) (xy 127.754901 -279.856504) (xy 127.742722 -279.80709)
			(xy 127.738627 -279.756362) (xy 127.446154 -279.756362) (xy 127.446156 -279.756386) (xy 127.441996 -279.80874)
			(xy 127.429616 -279.859779) (xy 127.409328 -279.908222) (xy 127.381641 -279.95285) (xy 127.34725 -279.992543)
			(xy 127.30702 -280.026304) (xy 127.261961 -280.053284) (xy 127.237744 -280.063448) (xy 127.228483 -280.067611)
			(xy 127.214011 -280.081831) (xy 127.206182 -280.100547) (xy 127.20574 -280.110692) (xy 127.20574 -280.26868)
			(xy 127.206197 -280.278517) (xy 127.213628 -280.296732) (xy 127.227396 -280.310786) (xy 127.23622 -280.315162)
			(xy 127.335534 -280.358596) (xy 127.365252 -280.353516) (xy 127.376682 -280.343102) (xy 127.39371 -280.327772)
			(xy 127.431502 -280.301869) (xy 127.472742 -280.281908) (xy 127.516502 -280.268335) (xy 127.5618 -280.261457)
			(xy 127.584708 -280.26106) (xy 127.609966 -280.261582) (xy 127.659791 -280.269898) (xy 127.707569 -280.286301)
			(xy 127.751995 -280.310345) (xy 127.791858 -280.341372) (xy 127.826071 -280.378538) (xy 127.8537 -280.420828)
			(xy 127.873991 -280.467088) (xy 127.886392 -280.516057) (xy 127.89056 -280.566368) (xy 128.208527 -280.566368)
			(xy 128.212622 -280.51564) (xy 128.224801 -280.466226) (xy 128.244749 -280.419406) (xy 128.27195 -280.376392)
			(xy 128.305698 -280.338298) (xy 128.34512 -280.306111) (xy 128.389194 -280.280665) (xy 128.43678 -280.262618)
			(xy 128.486644 -280.252438) (xy 128.537496 -280.250389) (xy 128.588017 -280.256523) (xy 128.636901 -280.270683)
			(xy 128.68288 -280.2925) (xy 128.724764 -280.32141) (xy 128.761468 -280.356665) (xy 128.792041 -280.397351)
			(xy 128.815692 -280.442414) (xy 128.831808 -280.490688) (xy 128.839972 -280.540922) (xy 128.840484 -280.566368)
			(xy 129.148581 -280.566368) (xy 129.152676 -280.51564) (xy 129.164855 -280.466226) (xy 129.184803 -280.419406)
			(xy 129.212004 -280.376392) (xy 129.245752 -280.338298) (xy 129.285174 -280.306111) (xy 129.329248 -280.280665)
			(xy 129.376834 -280.262618) (xy 129.426698 -280.252438) (xy 129.47755 -280.250389) (xy 129.528071 -280.256523)
			(xy 129.576955 -280.270683) (xy 129.622934 -280.2925) (xy 129.664818 -280.32141) (xy 129.701522 -280.356665)
			(xy 129.732095 -280.397351) (xy 129.755746 -280.442414) (xy 129.771862 -280.490688) (xy 129.780026 -280.540922)
			(xy 129.780538 -280.566368) (xy 131.028435 -280.566368) (xy 131.03253 -280.51564) (xy 131.044709 -280.466226)
			(xy 131.064657 -280.419406) (xy 131.091858 -280.376392) (xy 131.125606 -280.338298) (xy 131.165028 -280.306111)
			(xy 131.209102 -280.280665) (xy 131.256688 -280.262618) (xy 131.306552 -280.252438) (xy 131.357404 -280.250389)
			(xy 131.407925 -280.256523) (xy 131.456809 -280.270683) (xy 131.502788 -280.2925) (xy 131.544672 -280.32141)
			(xy 131.581376 -280.356665) (xy 131.611949 -280.397351) (xy 131.6356 -280.442414) (xy 131.651716 -280.490688)
			(xy 131.65988 -280.540922) (xy 131.660392 -280.566368) (xy 131.97892 -280.566368) (xy 131.98288 -280.517314)
			(xy 131.994657 -280.46953) (xy 132.013948 -280.424254) (xy 132.040251 -280.382658) (xy 132.072886 -280.345821)
			(xy 132.111007 -280.314696) (xy 132.153628 -280.290089) (xy 132.199644 -280.272637) (xy 132.247863 -280.262793)
			(xy 132.297038 -280.260812) (xy 132.345893 -280.266744) (xy 132.393164 -280.280436) (xy 132.437626 -280.301534)
			(xy 132.478129 -280.32949) (xy 132.513622 -280.363582) (xy 132.543187 -280.402926) (xy 132.566058 -280.446503)
			(xy 132.581642 -280.493184) (xy 132.589537 -280.541761) (xy 132.590032 -280.566368) (xy 132.908543 -280.566368)
			(xy 132.912638 -280.51564) (xy 132.924817 -280.466226) (xy 132.944765 -280.419406) (xy 132.971966 -280.376392)
			(xy 133.005714 -280.338298) (xy 133.045136 -280.306111) (xy 133.08921 -280.280665) (xy 133.136796 -280.262618)
			(xy 133.18666 -280.252438) (xy 133.237512 -280.250389) (xy 133.288033 -280.256523) (xy 133.336917 -280.270683)
			(xy 133.382896 -280.2925) (xy 133.42478 -280.32141) (xy 133.461484 -280.356665) (xy 133.492057 -280.397351)
			(xy 133.515708 -280.442414) (xy 133.531824 -280.490688) (xy 133.539988 -280.540922) (xy 133.5405 -280.566368)
			(xy 133.859028 -280.566368) (xy 133.862988 -280.517314) (xy 133.874765 -280.46953) (xy 133.894056 -280.424254)
			(xy 133.920359 -280.382658) (xy 133.952994 -280.345821) (xy 133.991115 -280.314696) (xy 134.033736 -280.290089)
			(xy 134.079752 -280.272637) (xy 134.127971 -280.262793) (xy 134.177146 -280.260812) (xy 134.226001 -280.266744)
			(xy 134.273272 -280.280436) (xy 134.317734 -280.301534) (xy 134.358237 -280.32949) (xy 134.39373 -280.363582)
			(xy 134.423295 -280.402926) (xy 134.446166 -280.446503) (xy 134.46175 -280.493184) (xy 134.469645 -280.541761)
			(xy 134.47014 -280.566368) (xy 134.788397 -280.566368) (xy 134.792492 -280.51564) (xy 134.804671 -280.466226)
			(xy 134.824619 -280.419406) (xy 134.85182 -280.376392) (xy 134.885568 -280.338298) (xy 134.92499 -280.306111)
			(xy 134.969064 -280.280665) (xy 135.01665 -280.262618) (xy 135.066514 -280.252438) (xy 135.117366 -280.250389)
			(xy 135.167887 -280.256523) (xy 135.216771 -280.270683) (xy 135.26275 -280.2925) (xy 135.304634 -280.32141)
			(xy 135.341338 -280.356665) (xy 135.371911 -280.397351) (xy 135.395562 -280.442414) (xy 135.411678 -280.490688)
			(xy 135.419842 -280.540922) (xy 135.420354 -280.566368) (xy 135.728451 -280.566368) (xy 135.732546 -280.51564)
			(xy 135.744725 -280.466226) (xy 135.764673 -280.419406) (xy 135.791874 -280.376392) (xy 135.825622 -280.338298)
			(xy 135.865044 -280.306111) (xy 135.909118 -280.280665) (xy 135.956704 -280.262618) (xy 136.006568 -280.252438)
			(xy 136.05742 -280.250389) (xy 136.107941 -280.256523) (xy 136.156825 -280.270683) (xy 136.202804 -280.2925)
			(xy 136.244688 -280.32141) (xy 136.281392 -280.356665) (xy 136.311965 -280.397351) (xy 136.335616 -280.442414)
			(xy 136.351732 -280.490688) (xy 136.359896 -280.540922) (xy 136.360408 -280.566368) (xy 137.608559 -280.566368)
			(xy 137.612654 -280.51564) (xy 137.624833 -280.466226) (xy 137.644781 -280.419406) (xy 137.671982 -280.376392)
			(xy 137.70573 -280.338298) (xy 137.745152 -280.306111) (xy 137.789226 -280.280665) (xy 137.836812 -280.262618)
			(xy 137.886676 -280.252438) (xy 137.937528 -280.250389) (xy 137.988049 -280.256523) (xy 138.036933 -280.270683)
			(xy 138.082912 -280.2925) (xy 138.124796 -280.32141) (xy 138.1615 -280.356665) (xy 138.192073 -280.397351)
			(xy 138.215724 -280.442414) (xy 138.23184 -280.490688) (xy 138.240004 -280.540922) (xy 138.240516 -280.566368)
			(xy 138.559044 -280.566368) (xy 138.563004 -280.517314) (xy 138.574781 -280.46953) (xy 138.594072 -280.424254)
			(xy 138.620375 -280.382658) (xy 138.65301 -280.345821) (xy 138.691131 -280.314696) (xy 138.733752 -280.290089)
			(xy 138.779768 -280.272637) (xy 138.827987 -280.262793) (xy 138.877162 -280.260812) (xy 138.926017 -280.266744)
			(xy 138.973288 -280.280436) (xy 139.01775 -280.301534) (xy 139.058253 -280.32949) (xy 139.093746 -280.363582)
			(xy 139.123311 -280.402926) (xy 139.146182 -280.446503) (xy 139.161766 -280.493184) (xy 139.169661 -280.541761)
			(xy 139.170156 -280.566368) (xy 139.488413 -280.566368) (xy 139.492508 -280.51564) (xy 139.504687 -280.466226)
			(xy 139.524635 -280.419406) (xy 139.551836 -280.376392) (xy 139.585584 -280.338298) (xy 139.625006 -280.306111)
			(xy 139.66908 -280.280665) (xy 139.716666 -280.262618) (xy 139.76653 -280.252438) (xy 139.817382 -280.250389)
			(xy 139.867903 -280.256523) (xy 139.916787 -280.270683) (xy 139.962766 -280.2925) (xy 140.00465 -280.32141)
			(xy 140.041354 -280.356665) (xy 140.071927 -280.397351) (xy 140.095578 -280.442414) (xy 140.111694 -280.490688)
			(xy 140.119858 -280.540922) (xy 140.12037 -280.566368) (xy 140.438898 -280.566368) (xy 140.442858 -280.517314)
			(xy 140.454635 -280.46953) (xy 140.473926 -280.424254) (xy 140.500229 -280.382658) (xy 140.532864 -280.345821)
			(xy 140.570985 -280.314696) (xy 140.613606 -280.290089) (xy 140.659622 -280.272637) (xy 140.707841 -280.262793)
			(xy 140.757016 -280.260812) (xy 140.805871 -280.266744) (xy 140.853142 -280.280436) (xy 140.897604 -280.301534)
			(xy 140.938107 -280.32949) (xy 140.9736 -280.363582) (xy 141.003165 -280.402926) (xy 141.026036 -280.446503)
			(xy 141.04162 -280.493184) (xy 141.049515 -280.541761) (xy 141.05001 -280.566368) (xy 141.368521 -280.566368)
			(xy 141.372616 -280.51564) (xy 141.384795 -280.466226) (xy 141.404743 -280.419406) (xy 141.431944 -280.376392)
			(xy 141.465692 -280.338298) (xy 141.505114 -280.306111) (xy 141.549188 -280.280665) (xy 141.596774 -280.262618)
			(xy 141.646638 -280.252438) (xy 141.69749 -280.250389) (xy 141.748011 -280.256523) (xy 141.796895 -280.270683)
			(xy 141.842874 -280.2925) (xy 141.884758 -280.32141) (xy 141.921462 -280.356665) (xy 141.952035 -280.397351)
			(xy 141.975686 -280.442414) (xy 141.991802 -280.490688) (xy 141.999966 -280.540922) (xy 142.000478 -280.566368)
			(xy 142.308575 -280.566368) (xy 142.31267 -280.51564) (xy 142.324849 -280.466226) (xy 142.344797 -280.419406)
			(xy 142.371998 -280.376392) (xy 142.405746 -280.338298) (xy 142.445168 -280.306111) (xy 142.489242 -280.280665)
			(xy 142.536828 -280.262618) (xy 142.586692 -280.252438) (xy 142.637544 -280.250389) (xy 142.688065 -280.256523)
			(xy 142.736949 -280.270683) (xy 142.782928 -280.2925) (xy 142.824812 -280.32141) (xy 142.861516 -280.356665)
			(xy 142.892089 -280.397351) (xy 142.91574 -280.442414) (xy 142.931856 -280.490688) (xy 142.94002 -280.540922)
			(xy 142.940532 -280.566368) (xy 145.138914 -280.566368) (xy 145.142874 -280.517314) (xy 145.154651 -280.46953)
			(xy 145.173942 -280.424254) (xy 145.200245 -280.382658) (xy 145.23288 -280.345821) (xy 145.271001 -280.314696)
			(xy 145.313622 -280.290089) (xy 145.359638 -280.272637) (xy 145.407857 -280.262793) (xy 145.457032 -280.260812)
			(xy 145.505887 -280.266744) (xy 145.553158 -280.280436) (xy 145.59762 -280.301534) (xy 145.638123 -280.32949)
			(xy 145.673616 -280.363582) (xy 145.703181 -280.402926) (xy 145.726052 -280.446503) (xy 145.741636 -280.493184)
			(xy 145.749531 -280.541761) (xy 145.750026 -280.566368) (xy 145.749531 -280.590975) (xy 145.742343 -280.635202)
			(xy 168.158683 -280.635202) (xy 168.162618 -280.581431) (xy 168.174341 -280.528807) (xy 168.193601 -280.47845)
			(xy 168.219987 -280.431433) (xy 168.252939 -280.38876) (xy 168.291752 -280.351339) (xy 168.3356 -280.319969)
			(xy 168.383548 -280.295317) (xy 168.434575 -280.277909) (xy 168.487593 -280.268116) (xy 168.541472 -280.266147)
			(xy 168.595063 -280.272044) (xy 168.647224 -280.28568) (xy 168.696844 -280.306767) (xy 168.742865 -280.334853)
			(xy 168.784307 -280.369341) (xy 168.820285 -280.409495) (xy 168.850033 -280.454459) (xy 168.872918 -280.503276)
			(xy 168.88845 -280.554905) (xy 168.8963 -280.608245) (xy 168.896792 -280.635202) (xy 168.8963 -280.662159)
			(xy 168.88845 -280.715499) (xy 168.872918 -280.767128) (xy 168.850033 -280.815945) (xy 168.820285 -280.860909)
			(xy 168.784307 -280.901063) (xy 168.742865 -280.935551) (xy 168.696844 -280.963637) (xy 168.647224 -280.984724)
			(xy 168.595063 -280.99836) (xy 168.541472 -281.004257) (xy 168.487593 -281.002288) (xy 168.434575 -280.992495)
			(xy 168.383548 -280.975087) (xy 168.3356 -280.950435) (xy 168.291752 -280.919065) (xy 168.252939 -280.881644)
			(xy 168.219987 -280.838971) (xy 168.193601 -280.791954) (xy 168.174341 -280.741597) (xy 168.162618 -280.688973)
			(xy 168.158683 -280.635202) (xy 145.742343 -280.635202) (xy 145.741636 -280.639552) (xy 145.726052 -280.686233)
			(xy 145.703181 -280.72981) (xy 145.673616 -280.769154) (xy 145.638123 -280.803246) (xy 145.59762 -280.831202)
			(xy 145.553158 -280.8523) (xy 145.505887 -280.865992) (xy 145.457032 -280.871924) (xy 145.407857 -280.869943)
			(xy 145.359638 -280.860099) (xy 145.313622 -280.842647) (xy 145.271001 -280.81804) (xy 145.23288 -280.786915)
			(xy 145.200245 -280.750078) (xy 145.173942 -280.708482) (xy 145.154651 -280.663206) (xy 145.142874 -280.615422)
			(xy 145.138914 -280.566368) (xy 142.940532 -280.566368) (xy 142.94002 -280.591814) (xy 142.931856 -280.642048)
			(xy 142.91574 -280.690322) (xy 142.892089 -280.735385) (xy 142.861516 -280.776071) (xy 142.824812 -280.811326)
			(xy 142.782928 -280.840236) (xy 142.736949 -280.862053) (xy 142.688065 -280.876213) (xy 142.637544 -280.882347)
			(xy 142.586692 -280.880298) (xy 142.536828 -280.870118) (xy 142.489242 -280.852071) (xy 142.445168 -280.826625)
			(xy 142.405746 -280.794438) (xy 142.371998 -280.756344) (xy 142.344797 -280.71333) (xy 142.324849 -280.66651)
			(xy 142.31267 -280.617096) (xy 142.308575 -280.566368) (xy 142.000478 -280.566368) (xy 141.999966 -280.591814)
			(xy 141.991802 -280.642048) (xy 141.975686 -280.690322) (xy 141.952035 -280.735385) (xy 141.921462 -280.776071)
			(xy 141.884758 -280.811326) (xy 141.842874 -280.840236) (xy 141.796895 -280.862053) (xy 141.748011 -280.876213)
			(xy 141.69749 -280.882347) (xy 141.646638 -280.880298) (xy 141.596774 -280.870118) (xy 141.549188 -280.852071)
			(xy 141.505114 -280.826625) (xy 141.465692 -280.794438) (xy 141.431944 -280.756344) (xy 141.404743 -280.71333)
			(xy 141.384795 -280.66651) (xy 141.372616 -280.617096) (xy 141.368521 -280.566368) (xy 141.05001 -280.566368)
			(xy 141.049515 -280.590975) (xy 141.04162 -280.639552) (xy 141.026036 -280.686233) (xy 141.003165 -280.72981)
			(xy 140.9736 -280.769154) (xy 140.938107 -280.803246) (xy 140.897604 -280.831202) (xy 140.853142 -280.8523)
			(xy 140.805871 -280.865992) (xy 140.757016 -280.871924) (xy 140.707841 -280.869943) (xy 140.659622 -280.860099)
			(xy 140.613606 -280.842647) (xy 140.570985 -280.81804) (xy 140.532864 -280.786915) (xy 140.500229 -280.750078)
			(xy 140.473926 -280.708482) (xy 140.454635 -280.663206) (xy 140.442858 -280.615422) (xy 140.438898 -280.566368)
			(xy 140.12037 -280.566368) (xy 140.119858 -280.591814) (xy 140.111694 -280.642048) (xy 140.095578 -280.690322)
			(xy 140.071927 -280.735385) (xy 140.041354 -280.776071) (xy 140.00465 -280.811326) (xy 139.962766 -280.840236)
			(xy 139.916787 -280.862053) (xy 139.867903 -280.876213) (xy 139.817382 -280.882347) (xy 139.76653 -280.880298)
			(xy 139.716666 -280.870118) (xy 139.66908 -280.852071) (xy 139.625006 -280.826625) (xy 139.585584 -280.794438)
			(xy 139.551836 -280.756344) (xy 139.524635 -280.71333) (xy 139.504687 -280.66651) (xy 139.492508 -280.617096)
			(xy 139.488413 -280.566368) (xy 139.170156 -280.566368) (xy 139.169661 -280.590975) (xy 139.161766 -280.639552)
			(xy 139.146182 -280.686233) (xy 139.123311 -280.72981) (xy 139.093746 -280.769154) (xy 139.058253 -280.803246)
			(xy 139.01775 -280.831202) (xy 138.973288 -280.8523) (xy 138.926017 -280.865992) (xy 138.877162 -280.871924)
			(xy 138.827987 -280.869943) (xy 138.779768 -280.860099) (xy 138.733752 -280.842647) (xy 138.691131 -280.81804)
			(xy 138.65301 -280.786915) (xy 138.620375 -280.750078) (xy 138.594072 -280.708482) (xy 138.574781 -280.663206)
			(xy 138.563004 -280.615422) (xy 138.559044 -280.566368) (xy 138.240516 -280.566368) (xy 138.240004 -280.591814)
			(xy 138.23184 -280.642048) (xy 138.215724 -280.690322) (xy 138.192073 -280.735385) (xy 138.1615 -280.776071)
			(xy 138.124796 -280.811326) (xy 138.082912 -280.840236) (xy 138.036933 -280.862053) (xy 137.988049 -280.876213)
			(xy 137.937528 -280.882347) (xy 137.886676 -280.880298) (xy 137.836812 -280.870118) (xy 137.789226 -280.852071)
			(xy 137.745152 -280.826625) (xy 137.70573 -280.794438) (xy 137.671982 -280.756344) (xy 137.644781 -280.71333)
			(xy 137.624833 -280.66651) (xy 137.612654 -280.617096) (xy 137.608559 -280.566368) (xy 136.360408 -280.566368)
			(xy 136.359896 -280.591814) (xy 136.351732 -280.642048) (xy 136.335616 -280.690322) (xy 136.311965 -280.735385)
			(xy 136.281392 -280.776071) (xy 136.244688 -280.811326) (xy 136.202804 -280.840236) (xy 136.156825 -280.862053)
			(xy 136.107941 -280.876213) (xy 136.05742 -280.882347) (xy 136.006568 -280.880298) (xy 135.956704 -280.870118)
			(xy 135.909118 -280.852071) (xy 135.865044 -280.826625) (xy 135.825622 -280.794438) (xy 135.791874 -280.756344)
			(xy 135.764673 -280.71333) (xy 135.744725 -280.66651) (xy 135.732546 -280.617096) (xy 135.728451 -280.566368)
			(xy 135.420354 -280.566368) (xy 135.419842 -280.591814) (xy 135.411678 -280.642048) (xy 135.395562 -280.690322)
			(xy 135.371911 -280.735385) (xy 135.341338 -280.776071) (xy 135.304634 -280.811326) (xy 135.26275 -280.840236)
			(xy 135.216771 -280.862053) (xy 135.167887 -280.876213) (xy 135.117366 -280.882347) (xy 135.066514 -280.880298)
			(xy 135.01665 -280.870118) (xy 134.969064 -280.852071) (xy 134.92499 -280.826625) (xy 134.885568 -280.794438)
			(xy 134.85182 -280.756344) (xy 134.824619 -280.71333) (xy 134.804671 -280.66651) (xy 134.792492 -280.617096)
			(xy 134.788397 -280.566368) (xy 134.47014 -280.566368) (xy 134.469645 -280.590975) (xy 134.46175 -280.639552)
			(xy 134.446166 -280.686233) (xy 134.423295 -280.72981) (xy 134.39373 -280.769154) (xy 134.358237 -280.803246)
			(xy 134.317734 -280.831202) (xy 134.273272 -280.8523) (xy 134.226001 -280.865992) (xy 134.177146 -280.871924)
			(xy 134.127971 -280.869943) (xy 134.079752 -280.860099) (xy 134.033736 -280.842647) (xy 133.991115 -280.81804)
			(xy 133.952994 -280.786915) (xy 133.920359 -280.750078) (xy 133.894056 -280.708482) (xy 133.874765 -280.663206)
			(xy 133.862988 -280.615422) (xy 133.859028 -280.566368) (xy 133.5405 -280.566368) (xy 133.539988 -280.591814)
			(xy 133.531824 -280.642048) (xy 133.515708 -280.690322) (xy 133.492057 -280.735385) (xy 133.461484 -280.776071)
			(xy 133.42478 -280.811326) (xy 133.382896 -280.840236) (xy 133.336917 -280.862053) (xy 133.288033 -280.876213)
			(xy 133.237512 -280.882347) (xy 133.18666 -280.880298) (xy 133.136796 -280.870118) (xy 133.08921 -280.852071)
			(xy 133.045136 -280.826625) (xy 133.005714 -280.794438) (xy 132.971966 -280.756344) (xy 132.944765 -280.71333)
			(xy 132.924817 -280.66651) (xy 132.912638 -280.617096) (xy 132.908543 -280.566368) (xy 132.590032 -280.566368)
			(xy 132.589537 -280.590975) (xy 132.581642 -280.639552) (xy 132.566058 -280.686233) (xy 132.543187 -280.72981)
			(xy 132.513622 -280.769154) (xy 132.478129 -280.803246) (xy 132.437626 -280.831202) (xy 132.393164 -280.8523)
			(xy 132.345893 -280.865992) (xy 132.297038 -280.871924) (xy 132.247863 -280.869943) (xy 132.199644 -280.860099)
			(xy 132.153628 -280.842647) (xy 132.111007 -280.81804) (xy 132.072886 -280.786915) (xy 132.040251 -280.750078)
			(xy 132.013948 -280.708482) (xy 131.994657 -280.663206) (xy 131.98288 -280.615422) (xy 131.97892 -280.566368)
			(xy 131.660392 -280.566368) (xy 131.65988 -280.591814) (xy 131.651716 -280.642048) (xy 131.6356 -280.690322)
			(xy 131.611949 -280.735385) (xy 131.581376 -280.776071) (xy 131.544672 -280.811326) (xy 131.502788 -280.840236)
			(xy 131.456809 -280.862053) (xy 131.407925 -280.876213) (xy 131.357404 -280.882347) (xy 131.306552 -280.880298)
			(xy 131.256688 -280.870118) (xy 131.209102 -280.852071) (xy 131.165028 -280.826625) (xy 131.125606 -280.794438)
			(xy 131.091858 -280.756344) (xy 131.064657 -280.71333) (xy 131.044709 -280.66651) (xy 131.03253 -280.617096)
			(xy 131.028435 -280.566368) (xy 129.780538 -280.566368) (xy 129.780026 -280.591814) (xy 129.771862 -280.642048)
			(xy 129.755746 -280.690322) (xy 129.732095 -280.735385) (xy 129.701522 -280.776071) (xy 129.664818 -280.811326)
			(xy 129.622934 -280.840236) (xy 129.576955 -280.862053) (xy 129.528071 -280.876213) (xy 129.47755 -280.882347)
			(xy 129.426698 -280.880298) (xy 129.376834 -280.870118) (xy 129.329248 -280.852071) (xy 129.285174 -280.826625)
			(xy 129.245752 -280.794438) (xy 129.212004 -280.756344) (xy 129.184803 -280.71333) (xy 129.164855 -280.66651)
			(xy 129.152676 -280.617096) (xy 129.148581 -280.566368) (xy 128.840484 -280.566368) (xy 128.839972 -280.591814)
			(xy 128.831808 -280.642048) (xy 128.815692 -280.690322) (xy 128.792041 -280.735385) (xy 128.761468 -280.776071)
			(xy 128.724764 -280.811326) (xy 128.68288 -280.840236) (xy 128.636901 -280.862053) (xy 128.588017 -280.876213)
			(xy 128.537496 -280.882347) (xy 128.486644 -280.880298) (xy 128.43678 -280.870118) (xy 128.389194 -280.852071)
			(xy 128.34512 -280.826625) (xy 128.305698 -280.794438) (xy 128.27195 -280.756344) (xy 128.244749 -280.71333)
			(xy 128.224801 -280.66651) (xy 128.212622 -280.617096) (xy 128.208527 -280.566368) (xy 127.89056 -280.566368)
			(xy 127.890563 -280.5664) (xy 127.886392 -280.616743) (xy 127.873991 -280.665712) (xy 127.8537 -280.711972)
			(xy 127.826071 -280.754262) (xy 127.791858 -280.791428) (xy 127.751995 -280.822455) (xy 127.707569 -280.846499)
			(xy 127.659791 -280.862902) (xy 127.609966 -280.871218) (xy 127.584708 -280.871676) (xy 127.561802 -280.871245)
			(xy 127.516511 -280.864361) (xy 127.472755 -280.85079) (xy 127.431516 -280.830838) (xy 127.393719 -280.804951)
			(xy 127.376682 -280.789634) (xy 127.365252 -280.77922) (xy 127.335534 -280.77414) (xy 127.23622 -280.817574)
			(xy 127.2274 -280.821939) (xy 127.213682 -280.836023) (xy 127.206252 -280.854227) (xy 127.20574 -280.864056)
			(xy 127.20574 -281.06497) (xy 127.22225 -281.090116) (xy 127.23622 -281.096212) (xy 127.259289 -281.106755)
			(xy 127.301853 -281.134332) (xy 127.339276 -281.168563) (xy 127.370529 -281.208506) (xy 127.394753 -281.253064)
			(xy 127.411283 -281.301011) (xy 127.419664 -281.351031) (xy 127.419665 -281.376374) (xy 127.738627 -281.376374)
			(xy 127.742722 -281.325646) (xy 127.754901 -281.276232) (xy 127.774849 -281.229412) (xy 127.80205 -281.186398)
			(xy 127.835798 -281.148304) (xy 127.87522 -281.116117) (xy 127.919294 -281.090671) (xy 127.96688 -281.072624)
			(xy 128.016744 -281.062444) (xy 128.067596 -281.060395) (xy 128.118117 -281.066529) (xy 128.167001 -281.080689)
			(xy 128.21298 -281.102506) (xy 128.254864 -281.131416) (xy 128.291568 -281.166671) (xy 128.322141 -281.207357)
			(xy 128.345792 -281.25242) (xy 128.361908 -281.300694) (xy 128.370072 -281.350928) (xy 128.370584 -281.376374)
			(xy 128.688858 -281.376374) (xy 128.692818 -281.32732) (xy 128.704595 -281.279536) (xy 128.723886 -281.23426)
			(xy 128.750189 -281.192664) (xy 128.782824 -281.155827) (xy 128.820945 -281.124702) (xy 128.863566 -281.100095)
			(xy 128.909582 -281.082643) (xy 128.957801 -281.072799) (xy 129.006976 -281.070818) (xy 129.055831 -281.07675)
			(xy 129.103102 -281.090442) (xy 129.147564 -281.11154) (xy 129.188067 -281.139496) (xy 129.22356 -281.173588)
			(xy 129.253125 -281.212932) (xy 129.275996 -281.256509) (xy 129.29158 -281.30319) (xy 129.299475 -281.351767)
			(xy 129.29997 -281.376374) (xy 129.618481 -281.376374) (xy 129.622576 -281.325646) (xy 129.634755 -281.276232)
			(xy 129.654703 -281.229412) (xy 129.681904 -281.186398) (xy 129.715652 -281.148304) (xy 129.755074 -281.116117)
			(xy 129.799148 -281.090671) (xy 129.846734 -281.072624) (xy 129.896598 -281.062444) (xy 129.94745 -281.060395)
			(xy 129.997971 -281.066529) (xy 130.046855 -281.080689) (xy 130.092834 -281.102506) (xy 130.134718 -281.131416)
			(xy 130.171422 -281.166671) (xy 130.201995 -281.207357) (xy 130.225646 -281.25242) (xy 130.241762 -281.300694)
			(xy 130.249926 -281.350928) (xy 130.250438 -281.376374) (xy 130.568966 -281.376374) (xy 130.572926 -281.32732)
			(xy 130.584703 -281.279536) (xy 130.603994 -281.23426) (xy 130.630297 -281.192664) (xy 130.662932 -281.155827)
			(xy 130.701053 -281.124702) (xy 130.743674 -281.100095) (xy 130.78969 -281.082643) (xy 130.837909 -281.072799)
			(xy 130.887084 -281.070818) (xy 130.935939 -281.07675) (xy 130.98321 -281.090442) (xy 131.027672 -281.11154)
			(xy 131.068175 -281.139496) (xy 131.103668 -281.173588) (xy 131.133233 -281.212932) (xy 131.156104 -281.256509)
			(xy 131.171688 -281.30319) (xy 131.179583 -281.351767) (xy 131.180078 -281.376374) (xy 131.498589 -281.376374)
			(xy 131.502684 -281.325646) (xy 131.514863 -281.276232) (xy 131.534811 -281.229412) (xy 131.562012 -281.186398)
			(xy 131.59576 -281.148304) (xy 131.635182 -281.116117) (xy 131.679256 -281.090671) (xy 131.726842 -281.072624)
			(xy 131.776706 -281.062444) (xy 131.827558 -281.060395) (xy 131.878079 -281.066529) (xy 131.926963 -281.080689)
			(xy 131.972942 -281.102506) (xy 132.014826 -281.131416) (xy 132.05153 -281.166671) (xy 132.082103 -281.207357)
			(xy 132.105754 -281.25242) (xy 132.12187 -281.300694) (xy 132.130034 -281.350928) (xy 132.130546 -281.376374)
			(xy 132.438643 -281.376374) (xy 132.442738 -281.325646) (xy 132.454917 -281.276232) (xy 132.474865 -281.229412)
			(xy 132.502066 -281.186398) (xy 132.535814 -281.148304) (xy 132.575236 -281.116117) (xy 132.61931 -281.090671)
			(xy 132.666896 -281.072624) (xy 132.71676 -281.062444) (xy 132.767612 -281.060395) (xy 132.818133 -281.066529)
			(xy 132.867017 -281.080689) (xy 132.912996 -281.102506) (xy 132.95488 -281.131416) (xy 132.991584 -281.166671)
			(xy 133.022157 -281.207357) (xy 133.045808 -281.25242) (xy 133.061924 -281.300694) (xy 133.070088 -281.350928)
			(xy 133.0706 -281.376374) (xy 133.388874 -281.376374) (xy 133.392834 -281.32732) (xy 133.404611 -281.279536)
			(xy 133.423902 -281.23426) (xy 133.450205 -281.192664) (xy 133.48284 -281.155827) (xy 133.520961 -281.124702)
			(xy 133.563582 -281.100095) (xy 133.609598 -281.082643) (xy 133.657817 -281.072799) (xy 133.706992 -281.070818)
			(xy 133.755847 -281.07675) (xy 133.803118 -281.090442) (xy 133.84758 -281.11154) (xy 133.888083 -281.139496)
			(xy 133.923576 -281.173588) (xy 133.953141 -281.212932) (xy 133.976012 -281.256509) (xy 133.991596 -281.30319)
			(xy 133.999491 -281.351767) (xy 133.999986 -281.376374) (xy 134.318497 -281.376374) (xy 134.322592 -281.325646)
			(xy 134.334771 -281.276232) (xy 134.354719 -281.229412) (xy 134.38192 -281.186398) (xy 134.415668 -281.148304)
			(xy 134.45509 -281.116117) (xy 134.499164 -281.090671) (xy 134.54675 -281.072624) (xy 134.596614 -281.062444)
			(xy 134.647466 -281.060395) (xy 134.697987 -281.066529) (xy 134.746871 -281.080689) (xy 134.79285 -281.102506)
			(xy 134.834734 -281.131416) (xy 134.871438 -281.166671) (xy 134.902011 -281.207357) (xy 134.925662 -281.25242)
			(xy 134.941778 -281.300694) (xy 134.949942 -281.350928) (xy 134.950454 -281.376374) (xy 135.268982 -281.376374)
			(xy 135.272942 -281.32732) (xy 135.284719 -281.279536) (xy 135.30401 -281.23426) (xy 135.330313 -281.192664)
			(xy 135.362948 -281.155827) (xy 135.401069 -281.124702) (xy 135.44369 -281.100095) (xy 135.489706 -281.082643)
			(xy 135.537925 -281.072799) (xy 135.5871 -281.070818) (xy 135.635955 -281.07675) (xy 135.683226 -281.090442)
			(xy 135.727688 -281.11154) (xy 135.768191 -281.139496) (xy 135.803684 -281.173588) (xy 135.833249 -281.212932)
			(xy 135.85612 -281.256509) (xy 135.871704 -281.30319) (xy 135.879599 -281.351767) (xy 135.880094 -281.376374)
			(xy 136.198605 -281.376374) (xy 136.2027 -281.325646) (xy 136.214879 -281.276232) (xy 136.234827 -281.229412)
			(xy 136.262028 -281.186398) (xy 136.295776 -281.148304) (xy 136.335198 -281.116117) (xy 136.379272 -281.090671)
			(xy 136.426858 -281.072624) (xy 136.476722 -281.062444) (xy 136.527574 -281.060395) (xy 136.578095 -281.066529)
			(xy 136.626979 -281.080689) (xy 136.672958 -281.102506) (xy 136.714842 -281.131416) (xy 136.751546 -281.166671)
			(xy 136.782119 -281.207357) (xy 136.80577 -281.25242) (xy 136.821886 -281.300694) (xy 136.83005 -281.350928)
			(xy 136.830562 -281.376374) (xy 137.148836 -281.376374) (xy 137.152796 -281.32732) (xy 137.164573 -281.279536)
			(xy 137.183864 -281.23426) (xy 137.210167 -281.192664) (xy 137.242802 -281.155827) (xy 137.280923 -281.124702)
			(xy 137.323544 -281.100095) (xy 137.36956 -281.082643) (xy 137.417779 -281.072799) (xy 137.466954 -281.070818)
			(xy 137.515809 -281.07675) (xy 137.56308 -281.090442) (xy 137.607542 -281.11154) (xy 137.648045 -281.139496)
			(xy 137.683538 -281.173588) (xy 137.713103 -281.212932) (xy 137.735974 -281.256509) (xy 137.751558 -281.30319)
			(xy 137.759453 -281.351767) (xy 137.759948 -281.376374) (xy 138.078459 -281.376374) (xy 138.082554 -281.325646)
			(xy 138.094733 -281.276232) (xy 138.114681 -281.229412) (xy 138.141882 -281.186398) (xy 138.17563 -281.148304)
			(xy 138.215052 -281.116117) (xy 138.259126 -281.090671) (xy 138.306712 -281.072624) (xy 138.356576 -281.062444)
			(xy 138.407428 -281.060395) (xy 138.457949 -281.066529) (xy 138.506833 -281.080689) (xy 138.552812 -281.102506)
			(xy 138.594696 -281.131416) (xy 138.6314 -281.166671) (xy 138.661973 -281.207357) (xy 138.685624 -281.25242)
			(xy 138.70174 -281.300694) (xy 138.709904 -281.350928) (xy 138.710416 -281.376374) (xy 139.018513 -281.376374)
			(xy 139.022608 -281.325646) (xy 139.034787 -281.276232) (xy 139.054735 -281.229412) (xy 139.081936 -281.186398)
			(xy 139.115684 -281.148304) (xy 139.155106 -281.116117) (xy 139.19918 -281.090671) (xy 139.246766 -281.072624)
			(xy 139.29663 -281.062444) (xy 139.347482 -281.060395) (xy 139.398003 -281.066529) (xy 139.446887 -281.080689)
			(xy 139.492866 -281.102506) (xy 139.53475 -281.131416) (xy 139.571454 -281.166671) (xy 139.602027 -281.207357)
			(xy 139.625678 -281.25242) (xy 139.641794 -281.300694) (xy 139.649958 -281.350928) (xy 139.65047 -281.376374)
			(xy 139.968998 -281.376374) (xy 139.972958 -281.32732) (xy 139.984735 -281.279536) (xy 140.004026 -281.23426)
			(xy 140.030329 -281.192664) (xy 140.062964 -281.155827) (xy 140.101085 -281.124702) (xy 140.143706 -281.100095)
			(xy 140.189722 -281.082643) (xy 140.237941 -281.072799) (xy 140.287116 -281.070818) (xy 140.335971 -281.07675)
			(xy 140.383242 -281.090442) (xy 140.427704 -281.11154) (xy 140.468207 -281.139496) (xy 140.5037 -281.173588)
			(xy 140.533265 -281.212932) (xy 140.556136 -281.256509) (xy 140.57172 -281.30319) (xy 140.579615 -281.351767)
			(xy 140.58011 -281.376374) (xy 140.898621 -281.376374) (xy 140.902716 -281.325646) (xy 140.914895 -281.276232)
			(xy 140.934843 -281.229412) (xy 140.962044 -281.186398) (xy 140.995792 -281.148304) (xy 141.035214 -281.116117)
			(xy 141.079288 -281.090671) (xy 141.126874 -281.072624) (xy 141.176738 -281.062444) (xy 141.22759 -281.060395)
			(xy 141.278111 -281.066529) (xy 141.326995 -281.080689) (xy 141.372974 -281.102506) (xy 141.414858 -281.131416)
			(xy 141.451562 -281.166671) (xy 141.482135 -281.207357) (xy 141.505786 -281.25242) (xy 141.521902 -281.300694)
			(xy 141.530066 -281.350928) (xy 141.530578 -281.376374) (xy 141.848852 -281.376374) (xy 141.852812 -281.32732)
			(xy 141.864589 -281.279536) (xy 141.88388 -281.23426) (xy 141.910183 -281.192664) (xy 141.942818 -281.155827)
			(xy 141.980939 -281.124702) (xy 142.02356 -281.100095) (xy 142.069576 -281.082643) (xy 142.117795 -281.072799)
			(xy 142.16697 -281.070818) (xy 142.215825 -281.07675) (xy 142.263096 -281.090442) (xy 142.307558 -281.11154)
			(xy 142.348061 -281.139496) (xy 142.383554 -281.173588) (xy 142.413119 -281.212932) (xy 142.43599 -281.256509)
			(xy 142.451574 -281.30319) (xy 142.459469 -281.351767) (xy 142.459964 -281.376374) (xy 142.778475 -281.376374)
			(xy 142.78257 -281.325646) (xy 142.794749 -281.276232) (xy 142.814697 -281.229412) (xy 142.841898 -281.186398)
			(xy 142.875646 -281.148304) (xy 142.915068 -281.116117) (xy 142.959142 -281.090671) (xy 143.006728 -281.072624)
			(xy 143.056592 -281.062444) (xy 143.107444 -281.060395) (xy 143.157965 -281.066529) (xy 143.206849 -281.080689)
			(xy 143.252828 -281.102506) (xy 143.294712 -281.131416) (xy 143.331416 -281.166671) (xy 143.361989 -281.207357)
			(xy 143.38564 -281.25242) (xy 143.401756 -281.300694) (xy 143.40992 -281.350928) (xy 143.410432 -281.376374)
			(xy 143.72896 -281.376374) (xy 143.73292 -281.32732) (xy 143.744697 -281.279536) (xy 143.763988 -281.23426)
			(xy 143.790291 -281.192664) (xy 143.822926 -281.155827) (xy 143.861047 -281.124702) (xy 143.903668 -281.100095)
			(xy 143.949684 -281.082643) (xy 143.997903 -281.072799) (xy 144.047078 -281.070818) (xy 144.095933 -281.07675)
			(xy 144.143204 -281.090442) (xy 144.185339 -281.110436) (xy 146.737082 -281.110436) (xy 146.741042 -281.061382)
			(xy 146.752819 -281.013598) (xy 146.77211 -280.968322) (xy 146.798413 -280.926726) (xy 146.831048 -280.889889)
			(xy 146.869169 -280.858764) (xy 146.91179 -280.834157) (xy 146.957806 -280.816705) (xy 147.006025 -280.806861)
			(xy 147.0552 -280.80488) (xy 147.104055 -280.810812) (xy 147.151326 -280.824504) (xy 147.195788 -280.845602)
			(xy 147.236291 -280.873558) (xy 147.271784 -280.90765) (xy 147.301349 -280.946994) (xy 147.32422 -280.990571)
			(xy 147.339804 -281.037252) (xy 147.347699 -281.085829) (xy 147.348194 -281.110436) (xy 147.347699 -281.135043)
			(xy 147.339804 -281.18362) (xy 147.32422 -281.230301) (xy 147.301349 -281.273878) (xy 147.271784 -281.313222)
			(xy 147.236291 -281.347314) (xy 147.195788 -281.37527) (xy 147.151326 -281.396368) (xy 147.104055 -281.41006)
			(xy 147.0552 -281.415992) (xy 147.006025 -281.414011) (xy 146.957806 -281.404167) (xy 146.91179 -281.386715)
			(xy 146.869169 -281.362108) (xy 146.831048 -281.330983) (xy 146.798413 -281.294146) (xy 146.77211 -281.25255)
			(xy 146.752819 -281.207274) (xy 146.741042 -281.15949) (xy 146.737082 -281.110436) (xy 144.185339 -281.110436)
			(xy 144.187666 -281.11154) (xy 144.228169 -281.139496) (xy 144.263662 -281.173588) (xy 144.293227 -281.212932)
			(xy 144.316098 -281.256509) (xy 144.331682 -281.30319) (xy 144.339577 -281.351767) (xy 144.340072 -281.376374)
			(xy 144.339577 -281.400981) (xy 144.331682 -281.449558) (xy 144.319737 -281.48534) (xy 164.058615 -281.48534)
			(xy 164.06255 -281.431569) (xy 164.074273 -281.378945) (xy 164.093533 -281.328588) (xy 164.119919 -281.281571)
			(xy 164.152871 -281.238898) (xy 164.191684 -281.201477) (xy 164.235532 -281.170107) (xy 164.28348 -281.145455)
			(xy 164.334507 -281.128047) (xy 164.387525 -281.118254) (xy 164.441404 -281.116285) (xy 164.494995 -281.122182)
			(xy 164.547156 -281.135818) (xy 164.596776 -281.156905) (xy 164.642797 -281.184991) (xy 164.684239 -281.219479)
			(xy 164.720217 -281.259633) (xy 164.749965 -281.304597) (xy 164.77285 -281.353414) (xy 164.788382 -281.405043)
			(xy 164.796232 -281.458383) (xy 164.796724 -281.48534) (xy 164.796232 -281.512297) (xy 164.788382 -281.565637)
			(xy 164.77285 -281.617266) (xy 164.749965 -281.666083) (xy 164.720217 -281.711047) (xy 164.684239 -281.751201)
			(xy 164.642797 -281.785689) (xy 164.596776 -281.813775) (xy 164.547156 -281.834862) (xy 164.494995 -281.848498)
			(xy 164.441404 -281.854395) (xy 164.387525 -281.852426) (xy 164.334507 -281.842633) (xy 164.28348 -281.825225)
			(xy 164.235532 -281.800573) (xy 164.191684 -281.769203) (xy 164.152871 -281.731782) (xy 164.119919 -281.689109)
			(xy 164.093533 -281.642092) (xy 164.074273 -281.591735) (xy 164.06255 -281.539111) (xy 164.058615 -281.48534)
			(xy 144.319737 -281.48534) (xy 144.316098 -281.496239) (xy 144.293227 -281.539816) (xy 144.263662 -281.57916)
			(xy 144.228169 -281.613252) (xy 144.187666 -281.641208) (xy 144.143204 -281.662306) (xy 144.095933 -281.675998)
			(xy 144.047078 -281.68193) (xy 143.997903 -281.679949) (xy 143.949684 -281.670105) (xy 143.903668 -281.652653)
			(xy 143.861047 -281.628046) (xy 143.822926 -281.596921) (xy 143.790291 -281.560084) (xy 143.763988 -281.518488)
			(xy 143.744697 -281.473212) (xy 143.73292 -281.425428) (xy 143.72896 -281.376374) (xy 143.410432 -281.376374)
			(xy 143.40992 -281.40182) (xy 143.401756 -281.452054) (xy 143.38564 -281.500328) (xy 143.361989 -281.545391)
			(xy 143.331416 -281.586077) (xy 143.294712 -281.621332) (xy 143.252828 -281.650242) (xy 143.206849 -281.672059)
			(xy 143.157965 -281.686219) (xy 143.107444 -281.692353) (xy 143.056592 -281.690304) (xy 143.006728 -281.680124)
			(xy 142.959142 -281.662077) (xy 142.915068 -281.636631) (xy 142.875646 -281.604444) (xy 142.841898 -281.56635)
			(xy 142.814697 -281.523336) (xy 142.794749 -281.476516) (xy 142.78257 -281.427102) (xy 142.778475 -281.376374)
			(xy 142.459964 -281.376374) (xy 142.459469 -281.400981) (xy 142.451574 -281.449558) (xy 142.43599 -281.496239)
			(xy 142.413119 -281.539816) (xy 142.383554 -281.57916) (xy 142.348061 -281.613252) (xy 142.307558 -281.641208)
			(xy 142.263096 -281.662306) (xy 142.215825 -281.675998) (xy 142.16697 -281.68193) (xy 142.117795 -281.679949)
			(xy 142.069576 -281.670105) (xy 142.02356 -281.652653) (xy 141.980939 -281.628046) (xy 141.942818 -281.596921)
			(xy 141.910183 -281.560084) (xy 141.88388 -281.518488) (xy 141.864589 -281.473212) (xy 141.852812 -281.425428)
			(xy 141.848852 -281.376374) (xy 141.530578 -281.376374) (xy 141.530066 -281.40182) (xy 141.521902 -281.452054)
			(xy 141.505786 -281.500328) (xy 141.482135 -281.545391) (xy 141.451562 -281.586077) (xy 141.414858 -281.621332)
			(xy 141.372974 -281.650242) (xy 141.326995 -281.672059) (xy 141.278111 -281.686219) (xy 141.22759 -281.692353)
			(xy 141.176738 -281.690304) (xy 141.126874 -281.680124) (xy 141.079288 -281.662077) (xy 141.035214 -281.636631)
			(xy 140.995792 -281.604444) (xy 140.962044 -281.56635) (xy 140.934843 -281.523336) (xy 140.914895 -281.476516)
			(xy 140.902716 -281.427102) (xy 140.898621 -281.376374) (xy 140.58011 -281.376374) (xy 140.579615 -281.400981)
			(xy 140.57172 -281.449558) (xy 140.556136 -281.496239) (xy 140.533265 -281.539816) (xy 140.5037 -281.57916)
			(xy 140.468207 -281.613252) (xy 140.427704 -281.641208) (xy 140.383242 -281.662306) (xy 140.335971 -281.675998)
			(xy 140.287116 -281.68193) (xy 140.237941 -281.679949) (xy 140.189722 -281.670105) (xy 140.143706 -281.652653)
			(xy 140.101085 -281.628046) (xy 140.062964 -281.596921) (xy 140.030329 -281.560084) (xy 140.004026 -281.518488)
			(xy 139.984735 -281.473212) (xy 139.972958 -281.425428) (xy 139.968998 -281.376374) (xy 139.65047 -281.376374)
			(xy 139.649958 -281.40182) (xy 139.641794 -281.452054) (xy 139.625678 -281.500328) (xy 139.602027 -281.545391)
			(xy 139.571454 -281.586077) (xy 139.53475 -281.621332) (xy 139.492866 -281.650242) (xy 139.446887 -281.672059)
			(xy 139.398003 -281.686219) (xy 139.347482 -281.692353) (xy 139.29663 -281.690304) (xy 139.246766 -281.680124)
			(xy 139.19918 -281.662077) (xy 139.155106 -281.636631) (xy 139.115684 -281.604444) (xy 139.081936 -281.56635)
			(xy 139.054735 -281.523336) (xy 139.034787 -281.476516) (xy 139.022608 -281.427102) (xy 139.018513 -281.376374)
			(xy 138.710416 -281.376374) (xy 138.709904 -281.40182) (xy 138.70174 -281.452054) (xy 138.685624 -281.500328)
			(xy 138.661973 -281.545391) (xy 138.6314 -281.586077) (xy 138.594696 -281.621332) (xy 138.552812 -281.650242)
			(xy 138.506833 -281.672059) (xy 138.457949 -281.686219) (xy 138.407428 -281.692353) (xy 138.356576 -281.690304)
			(xy 138.306712 -281.680124) (xy 138.259126 -281.662077) (xy 138.215052 -281.636631) (xy 138.17563 -281.604444)
			(xy 138.141882 -281.56635) (xy 138.114681 -281.523336) (xy 138.094733 -281.476516) (xy 138.082554 -281.427102)
			(xy 138.078459 -281.376374) (xy 137.759948 -281.376374) (xy 137.759453 -281.400981) (xy 137.751558 -281.449558)
			(xy 137.735974 -281.496239) (xy 137.713103 -281.539816) (xy 137.683538 -281.57916) (xy 137.648045 -281.613252)
			(xy 137.607542 -281.641208) (xy 137.56308 -281.662306) (xy 137.515809 -281.675998) (xy 137.466954 -281.68193)
			(xy 137.417779 -281.679949) (xy 137.36956 -281.670105) (xy 137.323544 -281.652653) (xy 137.280923 -281.628046)
			(xy 137.242802 -281.596921) (xy 137.210167 -281.560084) (xy 137.183864 -281.518488) (xy 137.164573 -281.473212)
			(xy 137.152796 -281.425428) (xy 137.148836 -281.376374) (xy 136.830562 -281.376374) (xy 136.83005 -281.40182)
			(xy 136.821886 -281.452054) (xy 136.80577 -281.500328) (xy 136.782119 -281.545391) (xy 136.751546 -281.586077)
			(xy 136.714842 -281.621332) (xy 136.672958 -281.650242) (xy 136.626979 -281.672059) (xy 136.578095 -281.686219)
			(xy 136.527574 -281.692353) (xy 136.476722 -281.690304) (xy 136.426858 -281.680124) (xy 136.379272 -281.662077)
			(xy 136.335198 -281.636631) (xy 136.295776 -281.604444) (xy 136.262028 -281.56635) (xy 136.234827 -281.523336)
			(xy 136.214879 -281.476516) (xy 136.2027 -281.427102) (xy 136.198605 -281.376374) (xy 135.880094 -281.376374)
			(xy 135.879599 -281.400981) (xy 135.871704 -281.449558) (xy 135.85612 -281.496239) (xy 135.833249 -281.539816)
			(xy 135.803684 -281.57916) (xy 135.768191 -281.613252) (xy 135.727688 -281.641208) (xy 135.683226 -281.662306)
			(xy 135.635955 -281.675998) (xy 135.5871 -281.68193) (xy 135.537925 -281.679949) (xy 135.489706 -281.670105)
			(xy 135.44369 -281.652653) (xy 135.401069 -281.628046) (xy 135.362948 -281.596921) (xy 135.330313 -281.560084)
			(xy 135.30401 -281.518488) (xy 135.284719 -281.473212) (xy 135.272942 -281.425428) (xy 135.268982 -281.376374)
			(xy 134.950454 -281.376374) (xy 134.949942 -281.40182) (xy 134.941778 -281.452054) (xy 134.925662 -281.500328)
			(xy 134.902011 -281.545391) (xy 134.871438 -281.586077) (xy 134.834734 -281.621332) (xy 134.79285 -281.650242)
			(xy 134.746871 -281.672059) (xy 134.697987 -281.686219) (xy 134.647466 -281.692353) (xy 134.596614 -281.690304)
			(xy 134.54675 -281.680124) (xy 134.499164 -281.662077) (xy 134.45509 -281.636631) (xy 134.415668 -281.604444)
			(xy 134.38192 -281.56635) (xy 134.354719 -281.523336) (xy 134.334771 -281.476516) (xy 134.322592 -281.427102)
			(xy 134.318497 -281.376374) (xy 133.999986 -281.376374) (xy 133.999491 -281.400981) (xy 133.991596 -281.449558)
			(xy 133.976012 -281.496239) (xy 133.953141 -281.539816) (xy 133.923576 -281.57916) (xy 133.888083 -281.613252)
			(xy 133.84758 -281.641208) (xy 133.803118 -281.662306) (xy 133.755847 -281.675998) (xy 133.706992 -281.68193)
			(xy 133.657817 -281.679949) (xy 133.609598 -281.670105) (xy 133.563582 -281.652653) (xy 133.520961 -281.628046)
			(xy 133.48284 -281.596921) (xy 133.450205 -281.560084) (xy 133.423902 -281.518488) (xy 133.404611 -281.473212)
			(xy 133.392834 -281.425428) (xy 133.388874 -281.376374) (xy 133.0706 -281.376374) (xy 133.070088 -281.40182)
			(xy 133.061924 -281.452054) (xy 133.045808 -281.500328) (xy 133.022157 -281.545391) (xy 132.991584 -281.586077)
			(xy 132.95488 -281.621332) (xy 132.912996 -281.650242) (xy 132.867017 -281.672059) (xy 132.818133 -281.686219)
			(xy 132.767612 -281.692353) (xy 132.71676 -281.690304) (xy 132.666896 -281.680124) (xy 132.61931 -281.662077)
			(xy 132.575236 -281.636631) (xy 132.535814 -281.604444) (xy 132.502066 -281.56635) (xy 132.474865 -281.523336)
			(xy 132.454917 -281.476516) (xy 132.442738 -281.427102) (xy 132.438643 -281.376374) (xy 132.130546 -281.376374)
			(xy 132.130034 -281.40182) (xy 132.12187 -281.452054) (xy 132.105754 -281.500328) (xy 132.082103 -281.545391)
			(xy 132.05153 -281.586077) (xy 132.014826 -281.621332) (xy 131.972942 -281.650242) (xy 131.926963 -281.672059)
			(xy 131.878079 -281.686219) (xy 131.827558 -281.692353) (xy 131.776706 -281.690304) (xy 131.726842 -281.680124)
			(xy 131.679256 -281.662077) (xy 131.635182 -281.636631) (xy 131.59576 -281.604444) (xy 131.562012 -281.56635)
			(xy 131.534811 -281.523336) (xy 131.514863 -281.476516) (xy 131.502684 -281.427102) (xy 131.498589 -281.376374)
			(xy 131.180078 -281.376374) (xy 131.179583 -281.400981) (xy 131.171688 -281.449558) (xy 131.156104 -281.496239)
			(xy 131.133233 -281.539816) (xy 131.103668 -281.57916) (xy 131.068175 -281.613252) (xy 131.027672 -281.641208)
			(xy 130.98321 -281.662306) (xy 130.935939 -281.675998) (xy 130.887084 -281.68193) (xy 130.837909 -281.679949)
			(xy 130.78969 -281.670105) (xy 130.743674 -281.652653) (xy 130.701053 -281.628046) (xy 130.662932 -281.596921)
			(xy 130.630297 -281.560084) (xy 130.603994 -281.518488) (xy 130.584703 -281.473212) (xy 130.572926 -281.425428)
			(xy 130.568966 -281.376374) (xy 130.250438 -281.376374) (xy 130.249926 -281.40182) (xy 130.241762 -281.452054)
			(xy 130.225646 -281.500328) (xy 130.201995 -281.545391) (xy 130.171422 -281.586077) (xy 130.134718 -281.621332)
			(xy 130.092834 -281.650242) (xy 130.046855 -281.672059) (xy 129.997971 -281.686219) (xy 129.94745 -281.692353)
			(xy 129.896598 -281.690304) (xy 129.846734 -281.680124) (xy 129.799148 -281.662077) (xy 129.755074 -281.636631)
			(xy 129.715652 -281.604444) (xy 129.681904 -281.56635) (xy 129.654703 -281.523336) (xy 129.634755 -281.476516)
			(xy 129.622576 -281.427102) (xy 129.618481 -281.376374) (xy 129.29997 -281.376374) (xy 129.299475 -281.400981)
			(xy 129.29158 -281.449558) (xy 129.275996 -281.496239) (xy 129.253125 -281.539816) (xy 129.22356 -281.57916)
			(xy 129.188067 -281.613252) (xy 129.147564 -281.641208) (xy 129.103102 -281.662306) (xy 129.055831 -281.675998)
			(xy 129.006976 -281.68193) (xy 128.957801 -281.679949) (xy 128.909582 -281.670105) (xy 128.863566 -281.652653)
			(xy 128.820945 -281.628046) (xy 128.782824 -281.596921) (xy 128.750189 -281.560084) (xy 128.723886 -281.518488)
			(xy 128.704595 -281.473212) (xy 128.692818 -281.425428) (xy 128.688858 -281.376374) (xy 128.370584 -281.376374)
			(xy 128.370072 -281.40182) (xy 128.361908 -281.452054) (xy 128.345792 -281.500328) (xy 128.322141 -281.545391)
			(xy 128.291568 -281.586077) (xy 128.254864 -281.621332) (xy 128.21298 -281.650242) (xy 128.167001 -281.672059)
			(xy 128.118117 -281.686219) (xy 128.067596 -281.692353) (xy 128.016744 -281.690304) (xy 127.96688 -281.680124)
			(xy 127.919294 -281.662077) (xy 127.87522 -281.636631) (xy 127.835798 -281.604444) (xy 127.80205 -281.56635)
			(xy 127.774849 -281.523336) (xy 127.754901 -281.476516) (xy 127.742722 -281.427102) (xy 127.738627 -281.376374)
			(xy 127.419665 -281.376374) (xy 127.419666 -281.401748) (xy 127.411288 -281.451769) (xy 127.394761 -281.499717)
			(xy 127.37054 -281.544277) (xy 127.33929 -281.584222) (xy 127.301869 -281.618455) (xy 127.259307 -281.646036)
			(xy 127.23622 -281.656536) (xy 127.22225 -281.662632) (xy 127.20574 -281.687778) (xy 127.20574 -282.18638)
			(xy 128.208527 -282.18638) (xy 128.212622 -282.135652) (xy 128.224801 -282.086238) (xy 128.244749 -282.039418)
			(xy 128.27195 -281.996404) (xy 128.305698 -281.95831) (xy 128.34512 -281.926123) (xy 128.389194 -281.900677)
			(xy 128.43678 -281.88263) (xy 128.486644 -281.87245) (xy 128.537496 -281.870401) (xy 128.588017 -281.876535)
			(xy 128.636901 -281.890695) (xy 128.68288 -281.912512) (xy 128.724764 -281.941422) (xy 128.761468 -281.976677)
			(xy 128.792041 -282.017363) (xy 128.815692 -282.062426) (xy 128.831808 -282.1107) (xy 128.839972 -282.160934)
			(xy 128.840484 -282.18638) (xy 129.148581 -282.18638) (xy 129.152676 -282.135652) (xy 129.164855 -282.086238)
			(xy 129.184803 -282.039418) (xy 129.212004 -281.996404) (xy 129.245752 -281.95831) (xy 129.285174 -281.926123)
			(xy 129.329248 -281.900677) (xy 129.376834 -281.88263) (xy 129.426698 -281.87245) (xy 129.47755 -281.870401)
			(xy 129.528071 -281.876535) (xy 129.576955 -281.890695) (xy 129.622934 -281.912512) (xy 129.664818 -281.941422)
			(xy 129.701522 -281.976677) (xy 129.732095 -282.017363) (xy 129.755746 -282.062426) (xy 129.771862 -282.1107)
			(xy 129.780026 -282.160934) (xy 129.780538 -282.18638) (xy 130.099066 -282.18638) (xy 130.103026 -282.137326)
			(xy 130.114803 -282.089542) (xy 130.134094 -282.044266) (xy 130.160397 -282.00267) (xy 130.193032 -281.965833)
			(xy 130.231153 -281.934708) (xy 130.273774 -281.910101) (xy 130.31979 -281.892649) (xy 130.368009 -281.882805)
			(xy 130.417184 -281.880824) (xy 130.466039 -281.886756) (xy 130.51331 -281.900448) (xy 130.557772 -281.921546)
			(xy 130.598275 -281.949502) (xy 130.633768 -281.983594) (xy 130.663333 -282.022938) (xy 130.686204 -282.066515)
			(xy 130.701788 -282.113196) (xy 130.709683 -282.161773) (xy 130.710178 -282.18638) (xy 131.028435 -282.18638)
			(xy 131.03253 -282.135652) (xy 131.044709 -282.086238) (xy 131.064657 -282.039418) (xy 131.091858 -281.996404)
			(xy 131.125606 -281.95831) (xy 131.165028 -281.926123) (xy 131.209102 -281.900677) (xy 131.256688 -281.88263)
			(xy 131.306552 -281.87245) (xy 131.357404 -281.870401) (xy 131.407925 -281.876535) (xy 131.456809 -281.890695)
			(xy 131.502788 -281.912512) (xy 131.544672 -281.941422) (xy 131.581376 -281.976677) (xy 131.611949 -282.017363)
			(xy 131.6356 -282.062426) (xy 131.651716 -282.1107) (xy 131.65988 -282.160934) (xy 131.660392 -282.18638)
			(xy 131.97892 -282.18638) (xy 131.98288 -282.137326) (xy 131.994657 -282.089542) (xy 132.013948 -282.044266)
			(xy 132.040251 -282.00267) (xy 132.072886 -281.965833) (xy 132.111007 -281.934708) (xy 132.153628 -281.910101)
			(xy 132.199644 -281.892649) (xy 132.247863 -281.882805) (xy 132.297038 -281.880824) (xy 132.345893 -281.886756)
			(xy 132.393164 -281.900448) (xy 132.437626 -281.921546) (xy 132.478129 -281.949502) (xy 132.513622 -281.983594)
			(xy 132.543187 -282.022938) (xy 132.566058 -282.066515) (xy 132.581642 -282.113196) (xy 132.589537 -282.161773)
			(xy 132.590032 -282.18638) (xy 132.908543 -282.18638) (xy 132.912638 -282.135652) (xy 132.924817 -282.086238)
			(xy 132.944765 -282.039418) (xy 132.971966 -281.996404) (xy 133.005714 -281.95831) (xy 133.045136 -281.926123)
			(xy 133.08921 -281.900677) (xy 133.136796 -281.88263) (xy 133.18666 -281.87245) (xy 133.237512 -281.870401)
			(xy 133.288033 -281.876535) (xy 133.336917 -281.890695) (xy 133.382896 -281.912512) (xy 133.42478 -281.941422)
			(xy 133.461484 -281.976677) (xy 133.492057 -282.017363) (xy 133.515708 -282.062426) (xy 133.531824 -282.1107)
			(xy 133.539988 -282.160934) (xy 133.5405 -282.18638) (xy 133.859028 -282.18638) (xy 133.862988 -282.137326)
			(xy 133.874765 -282.089542) (xy 133.894056 -282.044266) (xy 133.920359 -282.00267) (xy 133.952994 -281.965833)
			(xy 133.991115 -281.934708) (xy 134.033736 -281.910101) (xy 134.079752 -281.892649) (xy 134.127971 -281.882805)
			(xy 134.177146 -281.880824) (xy 134.226001 -281.886756) (xy 134.273272 -281.900448) (xy 134.317734 -281.921546)
			(xy 134.358237 -281.949502) (xy 134.39373 -281.983594) (xy 134.423295 -282.022938) (xy 134.446166 -282.066515)
			(xy 134.46175 -282.113196) (xy 134.469645 -282.161773) (xy 134.47014 -282.18638) (xy 134.788397 -282.18638)
			(xy 134.792492 -282.135652) (xy 134.804671 -282.086238) (xy 134.824619 -282.039418) (xy 134.85182 -281.996404)
			(xy 134.885568 -281.95831) (xy 134.92499 -281.926123) (xy 134.969064 -281.900677) (xy 135.01665 -281.88263)
			(xy 135.066514 -281.87245) (xy 135.117366 -281.870401) (xy 135.167887 -281.876535) (xy 135.216771 -281.890695)
			(xy 135.26275 -281.912512) (xy 135.304634 -281.941422) (xy 135.341338 -281.976677) (xy 135.371911 -282.017363)
			(xy 135.395562 -282.062426) (xy 135.411678 -282.1107) (xy 135.419842 -282.160934) (xy 135.420354 -282.18638)
			(xy 135.728451 -282.18638) (xy 135.732546 -282.135652) (xy 135.744725 -282.086238) (xy 135.764673 -282.039418)
			(xy 135.791874 -281.996404) (xy 135.825622 -281.95831) (xy 135.865044 -281.926123) (xy 135.909118 -281.900677)
			(xy 135.956704 -281.88263) (xy 136.006568 -281.87245) (xy 136.05742 -281.870401) (xy 136.107941 -281.876535)
			(xy 136.156825 -281.890695) (xy 136.202804 -281.912512) (xy 136.244688 -281.941422) (xy 136.281392 -281.976677)
			(xy 136.311965 -282.017363) (xy 136.335616 -282.062426) (xy 136.351732 -282.1107) (xy 136.359896 -282.160934)
			(xy 136.360408 -282.18638) (xy 136.678936 -282.18638) (xy 136.682896 -282.137326) (xy 136.694673 -282.089542)
			(xy 136.713964 -282.044266) (xy 136.740267 -282.00267) (xy 136.772902 -281.965833) (xy 136.811023 -281.934708)
			(xy 136.853644 -281.910101) (xy 136.89966 -281.892649) (xy 136.947879 -281.882805) (xy 136.997054 -281.880824)
			(xy 137.045909 -281.886756) (xy 137.09318 -281.900448) (xy 137.137642 -281.921546) (xy 137.178145 -281.949502)
			(xy 137.213638 -281.983594) (xy 137.243203 -282.022938) (xy 137.266074 -282.066515) (xy 137.281658 -282.113196)
			(xy 137.289553 -282.161773) (xy 137.290048 -282.18638) (xy 137.608559 -282.18638) (xy 137.612654 -282.135652)
			(xy 137.624833 -282.086238) (xy 137.644781 -282.039418) (xy 137.671982 -281.996404) (xy 137.70573 -281.95831)
			(xy 137.745152 -281.926123) (xy 137.789226 -281.900677) (xy 137.836812 -281.88263) (xy 137.886676 -281.87245)
			(xy 137.937528 -281.870401) (xy 137.988049 -281.876535) (xy 138.036933 -281.890695) (xy 138.082912 -281.912512)
			(xy 138.124796 -281.941422) (xy 138.1615 -281.976677) (xy 138.192073 -282.017363) (xy 138.215724 -282.062426)
			(xy 138.23184 -282.1107) (xy 138.240004 -282.160934) (xy 138.240516 -282.18638) (xy 138.559044 -282.18638)
			(xy 138.563004 -282.137326) (xy 138.574781 -282.089542) (xy 138.594072 -282.044266) (xy 138.620375 -282.00267)
			(xy 138.65301 -281.965833) (xy 138.691131 -281.934708) (xy 138.733752 -281.910101) (xy 138.779768 -281.892649)
			(xy 138.827987 -281.882805) (xy 138.877162 -281.880824) (xy 138.926017 -281.886756) (xy 138.973288 -281.900448)
			(xy 139.01775 -281.921546) (xy 139.058253 -281.949502) (xy 139.093746 -281.983594) (xy 139.123311 -282.022938)
			(xy 139.146182 -282.066515) (xy 139.161766 -282.113196) (xy 139.169661 -282.161773) (xy 139.170156 -282.18638)
			(xy 139.488413 -282.18638) (xy 139.492508 -282.135652) (xy 139.504687 -282.086238) (xy 139.524635 -282.039418)
			(xy 139.551836 -281.996404) (xy 139.585584 -281.95831) (xy 139.625006 -281.926123) (xy 139.66908 -281.900677)
			(xy 139.716666 -281.88263) (xy 139.76653 -281.87245) (xy 139.817382 -281.870401) (xy 139.867903 -281.876535)
			(xy 139.916787 -281.890695) (xy 139.962766 -281.912512) (xy 140.00465 -281.941422) (xy 140.041354 -281.976677)
			(xy 140.071927 -282.017363) (xy 140.095578 -282.062426) (xy 140.111694 -282.1107) (xy 140.119858 -282.160934)
			(xy 140.12037 -282.18638) (xy 140.438898 -282.18638) (xy 140.442858 -282.137326) (xy 140.454635 -282.089542)
			(xy 140.473926 -282.044266) (xy 140.500229 -282.00267) (xy 140.532864 -281.965833) (xy 140.570985 -281.934708)
			(xy 140.613606 -281.910101) (xy 140.659622 -281.892649) (xy 140.707841 -281.882805) (xy 140.757016 -281.880824)
			(xy 140.805871 -281.886756) (xy 140.853142 -281.900448) (xy 140.897604 -281.921546) (xy 140.938107 -281.949502)
			(xy 140.9736 -281.983594) (xy 141.003165 -282.022938) (xy 141.026036 -282.066515) (xy 141.04162 -282.113196)
			(xy 141.049515 -282.161773) (xy 141.05001 -282.18638) (xy 141.368521 -282.18638) (xy 141.372616 -282.135652)
			(xy 141.384795 -282.086238) (xy 141.404743 -282.039418) (xy 141.431944 -281.996404) (xy 141.465692 -281.95831)
			(xy 141.505114 -281.926123) (xy 141.549188 -281.900677) (xy 141.596774 -281.88263) (xy 141.646638 -281.87245)
			(xy 141.69749 -281.870401) (xy 141.748011 -281.876535) (xy 141.796895 -281.890695) (xy 141.842874 -281.912512)
			(xy 141.884758 -281.941422) (xy 141.921462 -281.976677) (xy 141.952035 -282.017363) (xy 141.975686 -282.062426)
			(xy 141.991802 -282.1107) (xy 141.999966 -282.160934) (xy 142.000478 -282.18638) (xy 142.308575 -282.18638)
			(xy 142.31267 -282.135652) (xy 142.324849 -282.086238) (xy 142.344797 -282.039418) (xy 142.371998 -281.996404)
			(xy 142.405746 -281.95831) (xy 142.445168 -281.926123) (xy 142.489242 -281.900677) (xy 142.536828 -281.88263)
			(xy 142.586692 -281.87245) (xy 142.637544 -281.870401) (xy 142.688065 -281.876535) (xy 142.736949 -281.890695)
			(xy 142.782928 -281.912512) (xy 142.824812 -281.941422) (xy 142.861516 -281.976677) (xy 142.892089 -282.017363)
			(xy 142.91574 -282.062426) (xy 142.931856 -282.1107) (xy 142.94002 -282.160934) (xy 142.940532 -282.18638)
			(xy 143.258806 -282.18638) (xy 143.262766 -282.137326) (xy 143.274543 -282.089542) (xy 143.293834 -282.044266)
			(xy 143.320137 -282.00267) (xy 143.352772 -281.965833) (xy 143.390893 -281.934708) (xy 143.433514 -281.910101)
			(xy 143.47953 -281.892649) (xy 143.527749 -281.882805) (xy 143.576924 -281.880824) (xy 143.625779 -281.886756)
			(xy 143.67305 -281.900448) (xy 143.717512 -281.921546) (xy 143.758015 -281.949502) (xy 143.793508 -281.983594)
			(xy 143.823073 -282.022938) (xy 143.845944 -282.066515) (xy 143.861528 -282.113196) (xy 143.869423 -282.161773)
			(xy 143.869918 -282.18638) (xy 145.138914 -282.18638) (xy 145.142874 -282.137326) (xy 145.154651 -282.089542)
			(xy 145.173942 -282.044266) (xy 145.200245 -282.00267) (xy 145.23288 -281.965833) (xy 145.271001 -281.934708)
			(xy 145.313622 -281.910101) (xy 145.359638 -281.892649) (xy 145.407857 -281.882805) (xy 145.457032 -281.880824)
			(xy 145.505887 -281.886756) (xy 145.553158 -281.900448) (xy 145.59762 -281.921546) (xy 145.638123 -281.949502)
			(xy 145.673616 -281.983594) (xy 145.703181 -282.022938) (xy 145.726052 -282.066515) (xy 145.741636 -282.113196)
			(xy 145.749531 -282.161773) (xy 145.750026 -282.18638) (xy 145.749531 -282.210987) (xy 145.741636 -282.259564)
			(xy 145.726052 -282.306245) (xy 145.710843 -282.335224) (xy 168.158683 -282.335224) (xy 168.162618 -282.281453)
			(xy 168.174341 -282.228829) (xy 168.193601 -282.178472) (xy 168.219987 -282.131455) (xy 168.252939 -282.088782)
			(xy 168.291752 -282.051361) (xy 168.3356 -282.019991) (xy 168.383548 -281.995339) (xy 168.434575 -281.977931)
			(xy 168.487593 -281.968138) (xy 168.541472 -281.966169) (xy 168.595063 -281.972066) (xy 168.647224 -281.985702)
			(xy 168.696844 -282.006789) (xy 168.742865 -282.034875) (xy 168.784307 -282.069363) (xy 168.820285 -282.109517)
			(xy 168.850033 -282.154481) (xy 168.872918 -282.203298) (xy 168.88845 -282.254927) (xy 168.8963 -282.308267)
			(xy 168.896792 -282.335224) (xy 168.8963 -282.362181) (xy 168.88845 -282.415521) (xy 168.872918 -282.46715)
			(xy 168.850033 -282.515967) (xy 168.820285 -282.560931) (xy 168.784307 -282.601085) (xy 168.742865 -282.635573)
			(xy 168.696844 -282.663659) (xy 168.647224 -282.684746) (xy 168.595063 -282.698382) (xy 168.541472 -282.704279)
			(xy 168.487593 -282.70231) (xy 168.434575 -282.692517) (xy 168.383548 -282.675109) (xy 168.3356 -282.650457)
			(xy 168.291752 -282.619087) (xy 168.252939 -282.581666) (xy 168.219987 -282.538993) (xy 168.193601 -282.491976)
			(xy 168.174341 -282.441619) (xy 168.162618 -282.388995) (xy 168.158683 -282.335224) (xy 145.710843 -282.335224)
			(xy 145.703181 -282.349822) (xy 145.673616 -282.389166) (xy 145.638123 -282.423258) (xy 145.59762 -282.451214)
			(xy 145.553158 -282.472312) (xy 145.505887 -282.486004) (xy 145.457032 -282.491936) (xy 145.407857 -282.489955)
			(xy 145.359638 -282.480111) (xy 145.313622 -282.462659) (xy 145.271001 -282.438052) (xy 145.23288 -282.406927)
			(xy 145.200245 -282.37009) (xy 145.173942 -282.328494) (xy 145.154651 -282.283218) (xy 145.142874 -282.235434)
			(xy 145.138914 -282.18638) (xy 143.869918 -282.18638) (xy 143.869423 -282.210987) (xy 143.861528 -282.259564)
			(xy 143.845944 -282.306245) (xy 143.823073 -282.349822) (xy 143.793508 -282.389166) (xy 143.758015 -282.423258)
			(xy 143.717512 -282.451214) (xy 143.67305 -282.472312) (xy 143.625779 -282.486004) (xy 143.576924 -282.491936)
			(xy 143.527749 -282.489955) (xy 143.47953 -282.480111) (xy 143.433514 -282.462659) (xy 143.390893 -282.438052)
			(xy 143.352772 -282.406927) (xy 143.320137 -282.37009) (xy 143.293834 -282.328494) (xy 143.274543 -282.283218)
			(xy 143.262766 -282.235434) (xy 143.258806 -282.18638) (xy 142.940532 -282.18638) (xy 142.94002 -282.211826)
			(xy 142.931856 -282.26206) (xy 142.91574 -282.310334) (xy 142.892089 -282.355397) (xy 142.861516 -282.396083)
			(xy 142.824812 -282.431338) (xy 142.782928 -282.460248) (xy 142.736949 -282.482065) (xy 142.688065 -282.496225)
			(xy 142.637544 -282.502359) (xy 142.586692 -282.50031) (xy 142.536828 -282.49013) (xy 142.489242 -282.472083)
			(xy 142.445168 -282.446637) (xy 142.405746 -282.41445) (xy 142.371998 -282.376356) (xy 142.344797 -282.333342)
			(xy 142.324849 -282.286522) (xy 142.31267 -282.237108) (xy 142.308575 -282.18638) (xy 142.000478 -282.18638)
			(xy 141.999966 -282.211826) (xy 141.991802 -282.26206) (xy 141.975686 -282.310334) (xy 141.952035 -282.355397)
			(xy 141.921462 -282.396083) (xy 141.884758 -282.431338) (xy 141.842874 -282.460248) (xy 141.796895 -282.482065)
			(xy 141.748011 -282.496225) (xy 141.69749 -282.502359) (xy 141.646638 -282.50031) (xy 141.596774 -282.49013)
			(xy 141.549188 -282.472083) (xy 141.505114 -282.446637) (xy 141.465692 -282.41445) (xy 141.431944 -282.376356)
			(xy 141.404743 -282.333342) (xy 141.384795 -282.286522) (xy 141.372616 -282.237108) (xy 141.368521 -282.18638)
			(xy 141.05001 -282.18638) (xy 141.049515 -282.210987) (xy 141.04162 -282.259564) (xy 141.026036 -282.306245)
			(xy 141.003165 -282.349822) (xy 140.9736 -282.389166) (xy 140.938107 -282.423258) (xy 140.897604 -282.451214)
			(xy 140.853142 -282.472312) (xy 140.805871 -282.486004) (xy 140.757016 -282.491936) (xy 140.707841 -282.489955)
			(xy 140.659622 -282.480111) (xy 140.613606 -282.462659) (xy 140.570985 -282.438052) (xy 140.532864 -282.406927)
			(xy 140.500229 -282.37009) (xy 140.473926 -282.328494) (xy 140.454635 -282.283218) (xy 140.442858 -282.235434)
			(xy 140.438898 -282.18638) (xy 140.12037 -282.18638) (xy 140.119858 -282.211826) (xy 140.111694 -282.26206)
			(xy 140.095578 -282.310334) (xy 140.071927 -282.355397) (xy 140.041354 -282.396083) (xy 140.00465 -282.431338)
			(xy 139.962766 -282.460248) (xy 139.916787 -282.482065) (xy 139.867903 -282.496225) (xy 139.817382 -282.502359)
			(xy 139.76653 -282.50031) (xy 139.716666 -282.49013) (xy 139.66908 -282.472083) (xy 139.625006 -282.446637)
			(xy 139.585584 -282.41445) (xy 139.551836 -282.376356) (xy 139.524635 -282.333342) (xy 139.504687 -282.286522)
			(xy 139.492508 -282.237108) (xy 139.488413 -282.18638) (xy 139.170156 -282.18638) (xy 139.169661 -282.210987)
			(xy 139.161766 -282.259564) (xy 139.146182 -282.306245) (xy 139.123311 -282.349822) (xy 139.093746 -282.389166)
			(xy 139.058253 -282.423258) (xy 139.01775 -282.451214) (xy 138.973288 -282.472312) (xy 138.926017 -282.486004)
			(xy 138.877162 -282.491936) (xy 138.827987 -282.489955) (xy 138.779768 -282.480111) (xy 138.733752 -282.462659)
			(xy 138.691131 -282.438052) (xy 138.65301 -282.406927) (xy 138.620375 -282.37009) (xy 138.594072 -282.328494)
			(xy 138.574781 -282.283218) (xy 138.563004 -282.235434) (xy 138.559044 -282.18638) (xy 138.240516 -282.18638)
			(xy 138.240004 -282.211826) (xy 138.23184 -282.26206) (xy 138.215724 -282.310334) (xy 138.192073 -282.355397)
			(xy 138.1615 -282.396083) (xy 138.124796 -282.431338) (xy 138.082912 -282.460248) (xy 138.036933 -282.482065)
			(xy 137.988049 -282.496225) (xy 137.937528 -282.502359) (xy 137.886676 -282.50031) (xy 137.836812 -282.49013)
			(xy 137.789226 -282.472083) (xy 137.745152 -282.446637) (xy 137.70573 -282.41445) (xy 137.671982 -282.376356)
			(xy 137.644781 -282.333342) (xy 137.624833 -282.286522) (xy 137.612654 -282.237108) (xy 137.608559 -282.18638)
			(xy 137.290048 -282.18638) (xy 137.289553 -282.210987) (xy 137.281658 -282.259564) (xy 137.266074 -282.306245)
			(xy 137.243203 -282.349822) (xy 137.213638 -282.389166) (xy 137.178145 -282.423258) (xy 137.137642 -282.451214)
			(xy 137.09318 -282.472312) (xy 137.045909 -282.486004) (xy 136.997054 -282.491936) (xy 136.947879 -282.489955)
			(xy 136.89966 -282.480111) (xy 136.853644 -282.462659) (xy 136.811023 -282.438052) (xy 136.772902 -282.406927)
			(xy 136.740267 -282.37009) (xy 136.713964 -282.328494) (xy 136.694673 -282.283218) (xy 136.682896 -282.235434)
			(xy 136.678936 -282.18638) (xy 136.360408 -282.18638) (xy 136.359896 -282.211826) (xy 136.351732 -282.26206)
			(xy 136.335616 -282.310334) (xy 136.311965 -282.355397) (xy 136.281392 -282.396083) (xy 136.244688 -282.431338)
			(xy 136.202804 -282.460248) (xy 136.156825 -282.482065) (xy 136.107941 -282.496225) (xy 136.05742 -282.502359)
			(xy 136.006568 -282.50031) (xy 135.956704 -282.49013) (xy 135.909118 -282.472083) (xy 135.865044 -282.446637)
			(xy 135.825622 -282.41445) (xy 135.791874 -282.376356) (xy 135.764673 -282.333342) (xy 135.744725 -282.286522)
			(xy 135.732546 -282.237108) (xy 135.728451 -282.18638) (xy 135.420354 -282.18638) (xy 135.419842 -282.211826)
			(xy 135.411678 -282.26206) (xy 135.395562 -282.310334) (xy 135.371911 -282.355397) (xy 135.341338 -282.396083)
			(xy 135.304634 -282.431338) (xy 135.26275 -282.460248) (xy 135.216771 -282.482065) (xy 135.167887 -282.496225)
			(xy 135.117366 -282.502359) (xy 135.066514 -282.50031) (xy 135.01665 -282.49013) (xy 134.969064 -282.472083)
			(xy 134.92499 -282.446637) (xy 134.885568 -282.41445) (xy 134.85182 -282.376356) (xy 134.824619 -282.333342)
			(xy 134.804671 -282.286522) (xy 134.792492 -282.237108) (xy 134.788397 -282.18638) (xy 134.47014 -282.18638)
			(xy 134.469645 -282.210987) (xy 134.46175 -282.259564) (xy 134.446166 -282.306245) (xy 134.423295 -282.349822)
			(xy 134.39373 -282.389166) (xy 134.358237 -282.423258) (xy 134.317734 -282.451214) (xy 134.273272 -282.472312)
			(xy 134.226001 -282.486004) (xy 134.177146 -282.491936) (xy 134.127971 -282.489955) (xy 134.079752 -282.480111)
			(xy 134.033736 -282.462659) (xy 133.991115 -282.438052) (xy 133.952994 -282.406927) (xy 133.920359 -282.37009)
			(xy 133.894056 -282.328494) (xy 133.874765 -282.283218) (xy 133.862988 -282.235434) (xy 133.859028 -282.18638)
			(xy 133.5405 -282.18638) (xy 133.539988 -282.211826) (xy 133.531824 -282.26206) (xy 133.515708 -282.310334)
			(xy 133.492057 -282.355397) (xy 133.461484 -282.396083) (xy 133.42478 -282.431338) (xy 133.382896 -282.460248)
			(xy 133.336917 -282.482065) (xy 133.288033 -282.496225) (xy 133.237512 -282.502359) (xy 133.18666 -282.50031)
			(xy 133.136796 -282.49013) (xy 133.08921 -282.472083) (xy 133.045136 -282.446637) (xy 133.005714 -282.41445)
			(xy 132.971966 -282.376356) (xy 132.944765 -282.333342) (xy 132.924817 -282.286522) (xy 132.912638 -282.237108)
			(xy 132.908543 -282.18638) (xy 132.590032 -282.18638) (xy 132.589537 -282.210987) (xy 132.581642 -282.259564)
			(xy 132.566058 -282.306245) (xy 132.543187 -282.349822) (xy 132.513622 -282.389166) (xy 132.478129 -282.423258)
			(xy 132.437626 -282.451214) (xy 132.393164 -282.472312) (xy 132.345893 -282.486004) (xy 132.297038 -282.491936)
			(xy 132.247863 -282.489955) (xy 132.199644 -282.480111) (xy 132.153628 -282.462659) (xy 132.111007 -282.438052)
			(xy 132.072886 -282.406927) (xy 132.040251 -282.37009) (xy 132.013948 -282.328494) (xy 131.994657 -282.283218)
			(xy 131.98288 -282.235434) (xy 131.97892 -282.18638) (xy 131.660392 -282.18638) (xy 131.65988 -282.211826)
			(xy 131.651716 -282.26206) (xy 131.6356 -282.310334) (xy 131.611949 -282.355397) (xy 131.581376 -282.396083)
			(xy 131.544672 -282.431338) (xy 131.502788 -282.460248) (xy 131.456809 -282.482065) (xy 131.407925 -282.496225)
			(xy 131.357404 -282.502359) (xy 131.306552 -282.50031) (xy 131.256688 -282.49013) (xy 131.209102 -282.472083)
			(xy 131.165028 -282.446637) (xy 131.125606 -282.41445) (xy 131.091858 -282.376356) (xy 131.064657 -282.333342)
			(xy 131.044709 -282.286522) (xy 131.03253 -282.237108) (xy 131.028435 -282.18638) (xy 130.710178 -282.18638)
			(xy 130.709683 -282.210987) (xy 130.701788 -282.259564) (xy 130.686204 -282.306245) (xy 130.663333 -282.349822)
			(xy 130.633768 -282.389166) (xy 130.598275 -282.423258) (xy 130.557772 -282.451214) (xy 130.51331 -282.472312)
			(xy 130.466039 -282.486004) (xy 130.417184 -282.491936) (xy 130.368009 -282.489955) (xy 130.31979 -282.480111)
			(xy 130.273774 -282.462659) (xy 130.231153 -282.438052) (xy 130.193032 -282.406927) (xy 130.160397 -282.37009)
			(xy 130.134094 -282.328494) (xy 130.114803 -282.283218) (xy 130.103026 -282.235434) (xy 130.099066 -282.18638)
			(xy 129.780538 -282.18638) (xy 129.780026 -282.211826) (xy 129.771862 -282.26206) (xy 129.755746 -282.310334)
			(xy 129.732095 -282.355397) (xy 129.701522 -282.396083) (xy 129.664818 -282.431338) (xy 129.622934 -282.460248)
			(xy 129.576955 -282.482065) (xy 129.528071 -282.496225) (xy 129.47755 -282.502359) (xy 129.426698 -282.50031)
			(xy 129.376834 -282.49013) (xy 129.329248 -282.472083) (xy 129.285174 -282.446637) (xy 129.245752 -282.41445)
			(xy 129.212004 -282.376356) (xy 129.184803 -282.333342) (xy 129.164855 -282.286522) (xy 129.152676 -282.237108)
			(xy 129.148581 -282.18638) (xy 128.840484 -282.18638) (xy 128.839972 -282.211826) (xy 128.831808 -282.26206)
			(xy 128.815692 -282.310334) (xy 128.792041 -282.355397) (xy 128.761468 -282.396083) (xy 128.724764 -282.431338)
			(xy 128.68288 -282.460248) (xy 128.636901 -282.482065) (xy 128.588017 -282.496225) (xy 128.537496 -282.502359)
			(xy 128.486644 -282.50031) (xy 128.43678 -282.49013) (xy 128.389194 -282.472083) (xy 128.34512 -282.446637)
			(xy 128.305698 -282.41445) (xy 128.27195 -282.376356) (xy 128.244749 -282.333342) (xy 128.224801 -282.286522)
			(xy 128.212622 -282.237108) (xy 128.208527 -282.18638) (xy 127.20574 -282.18638) (xy 127.20574 -282.684982)
			(xy 127.22225 -282.710128) (xy 127.23622 -282.716224) (xy 127.259288 -282.726767) (xy 127.30185 -282.754344)
			(xy 127.339271 -282.788574) (xy 127.370522 -282.828516) (xy 127.394745 -282.873073) (xy 127.411273 -282.921019)
			(xy 127.419653 -282.971037) (xy 127.419653 -282.996386) (xy 127.738627 -282.996386) (xy 127.742722 -282.945658)
			(xy 127.754901 -282.896244) (xy 127.774849 -282.849424) (xy 127.80205 -282.80641) (xy 127.835798 -282.768316)
			(xy 127.87522 -282.736129) (xy 127.919294 -282.710683) (xy 127.96688 -282.692636) (xy 128.016744 -282.682456)
			(xy 128.067596 -282.680407) (xy 128.118117 -282.686541) (xy 128.167001 -282.700701) (xy 128.21298 -282.722518)
			(xy 128.254864 -282.751428) (xy 128.291568 -282.786683) (xy 128.322141 -282.827369) (xy 128.345792 -282.872432)
			(xy 128.361908 -282.920706) (xy 128.370072 -282.97094) (xy 128.370584 -282.996386) (xy 128.688858 -282.996386)
			(xy 128.692818 -282.947332) (xy 128.704595 -282.899548) (xy 128.723886 -282.854272) (xy 128.750189 -282.812676)
			(xy 128.782824 -282.775839) (xy 128.820945 -282.744714) (xy 128.863566 -282.720107) (xy 128.909582 -282.702655)
			(xy 128.957801 -282.692811) (xy 129.006976 -282.69083) (xy 129.055831 -282.696762) (xy 129.103102 -282.710454)
			(xy 129.147564 -282.731552) (xy 129.188067 -282.759508) (xy 129.22356 -282.7936) (xy 129.253125 -282.832944)
			(xy 129.275996 -282.876521) (xy 129.29158 -282.923202) (xy 129.299475 -282.971779) (xy 129.29997 -282.996386)
			(xy 129.618481 -282.996386) (xy 129.622576 -282.945658) (xy 129.634755 -282.896244) (xy 129.654703 -282.849424)
			(xy 129.681904 -282.80641) (xy 129.715652 -282.768316) (xy 129.755074 -282.736129) (xy 129.799148 -282.710683)
			(xy 129.846734 -282.692636) (xy 129.896598 -282.682456) (xy 129.94745 -282.680407) (xy 129.997971 -282.686541)
			(xy 130.046855 -282.700701) (xy 130.092834 -282.722518) (xy 130.134718 -282.751428) (xy 130.171422 -282.786683)
			(xy 130.201995 -282.827369) (xy 130.225646 -282.872432) (xy 130.241762 -282.920706) (xy 130.249926 -282.97094)
			(xy 130.250438 -282.996386) (xy 131.498589 -282.996386) (xy 131.502684 -282.945658) (xy 131.514863 -282.896244)
			(xy 131.534811 -282.849424) (xy 131.562012 -282.80641) (xy 131.59576 -282.768316) (xy 131.635182 -282.736129)
			(xy 131.679256 -282.710683) (xy 131.726842 -282.692636) (xy 131.776706 -282.682456) (xy 131.827558 -282.680407)
			(xy 131.878079 -282.686541) (xy 131.926963 -282.700701) (xy 131.972942 -282.722518) (xy 132.014826 -282.751428)
			(xy 132.05153 -282.786683) (xy 132.082103 -282.827369) (xy 132.105754 -282.872432) (xy 132.12187 -282.920706)
			(xy 132.130034 -282.97094) (xy 132.130546 -282.996386) (xy 132.438643 -282.996386) (xy 132.442738 -282.945658)
			(xy 132.454917 -282.896244) (xy 132.474865 -282.849424) (xy 132.502066 -282.80641) (xy 132.535814 -282.768316)
			(xy 132.575236 -282.736129) (xy 132.61931 -282.710683) (xy 132.666896 -282.692636) (xy 132.71676 -282.682456)
			(xy 132.767612 -282.680407) (xy 132.818133 -282.686541) (xy 132.867017 -282.700701) (xy 132.912996 -282.722518)
			(xy 132.95488 -282.751428) (xy 132.991584 -282.786683) (xy 133.022157 -282.827369) (xy 133.045808 -282.872432)
			(xy 133.061924 -282.920706) (xy 133.070088 -282.97094) (xy 133.0706 -282.996386) (xy 133.388874 -282.996386)
			(xy 133.392834 -282.947332) (xy 133.404611 -282.899548) (xy 133.423902 -282.854272) (xy 133.450205 -282.812676)
			(xy 133.48284 -282.775839) (xy 133.520961 -282.744714) (xy 133.563582 -282.720107) (xy 133.609598 -282.702655)
			(xy 133.657817 -282.692811) (xy 133.706992 -282.69083) (xy 133.755847 -282.696762) (xy 133.803118 -282.710454)
			(xy 133.84758 -282.731552) (xy 133.888083 -282.759508) (xy 133.923576 -282.7936) (xy 133.953141 -282.832944)
			(xy 133.976012 -282.876521) (xy 133.991596 -282.923202) (xy 133.999491 -282.971779) (xy 133.999986 -282.996386)
			(xy 134.318497 -282.996386) (xy 134.322592 -282.945658) (xy 134.334771 -282.896244) (xy 134.354719 -282.849424)
			(xy 134.38192 -282.80641) (xy 134.415668 -282.768316) (xy 134.45509 -282.736129) (xy 134.499164 -282.710683)
			(xy 134.54675 -282.692636) (xy 134.596614 -282.682456) (xy 134.647466 -282.680407) (xy 134.697987 -282.686541)
			(xy 134.746871 -282.700701) (xy 134.79285 -282.722518) (xy 134.834734 -282.751428) (xy 134.871438 -282.786683)
			(xy 134.902011 -282.827369) (xy 134.925662 -282.872432) (xy 134.941778 -282.920706) (xy 134.949942 -282.97094)
			(xy 134.950454 -282.996386) (xy 135.268982 -282.996386) (xy 135.272942 -282.947332) (xy 135.284719 -282.899548)
			(xy 135.30401 -282.854272) (xy 135.330313 -282.812676) (xy 135.362948 -282.775839) (xy 135.401069 -282.744714)
			(xy 135.44369 -282.720107) (xy 135.489706 -282.702655) (xy 135.537925 -282.692811) (xy 135.5871 -282.69083)
			(xy 135.635955 -282.696762) (xy 135.683226 -282.710454) (xy 135.727688 -282.731552) (xy 135.768191 -282.759508)
			(xy 135.803684 -282.7936) (xy 135.833249 -282.832944) (xy 135.85612 -282.876521) (xy 135.871704 -282.923202)
			(xy 135.879599 -282.971779) (xy 135.880094 -282.996386) (xy 136.198605 -282.996386) (xy 136.2027 -282.945658)
			(xy 136.214879 -282.896244) (xy 136.234827 -282.849424) (xy 136.262028 -282.80641) (xy 136.295776 -282.768316)
			(xy 136.335198 -282.736129) (xy 136.379272 -282.710683) (xy 136.426858 -282.692636) (xy 136.476722 -282.682456)
			(xy 136.527574 -282.680407) (xy 136.578095 -282.686541) (xy 136.626979 -282.700701) (xy 136.672958 -282.722518)
			(xy 136.714842 -282.751428) (xy 136.751546 -282.786683) (xy 136.782119 -282.827369) (xy 136.80577 -282.872432)
			(xy 136.821886 -282.920706) (xy 136.83005 -282.97094) (xy 136.830562 -282.996386) (xy 138.078459 -282.996386)
			(xy 138.082554 -282.945658) (xy 138.094733 -282.896244) (xy 138.114681 -282.849424) (xy 138.141882 -282.80641)
			(xy 138.17563 -282.768316) (xy 138.215052 -282.736129) (xy 138.259126 -282.710683) (xy 138.306712 -282.692636)
			(xy 138.356576 -282.682456) (xy 138.407428 -282.680407) (xy 138.457949 -282.686541) (xy 138.506833 -282.700701)
			(xy 138.552812 -282.722518) (xy 138.594696 -282.751428) (xy 138.6314 -282.786683) (xy 138.661973 -282.827369)
			(xy 138.685624 -282.872432) (xy 138.70174 -282.920706) (xy 138.709904 -282.97094) (xy 138.710416 -282.996386)
			(xy 139.018513 -282.996386) (xy 139.022608 -282.945658) (xy 139.034787 -282.896244) (xy 139.054735 -282.849424)
			(xy 139.081936 -282.80641) (xy 139.115684 -282.768316) (xy 139.155106 -282.736129) (xy 139.19918 -282.710683)
			(xy 139.246766 -282.692636) (xy 139.29663 -282.682456) (xy 139.347482 -282.680407) (xy 139.398003 -282.686541)
			(xy 139.446887 -282.700701) (xy 139.492866 -282.722518) (xy 139.53475 -282.751428) (xy 139.571454 -282.786683)
			(xy 139.602027 -282.827369) (xy 139.625678 -282.872432) (xy 139.641794 -282.920706) (xy 139.649958 -282.97094)
			(xy 139.65047 -282.996386) (xy 139.968998 -282.996386) (xy 139.972958 -282.947332) (xy 139.984735 -282.899548)
			(xy 140.004026 -282.854272) (xy 140.030329 -282.812676) (xy 140.062964 -282.775839) (xy 140.101085 -282.744714)
			(xy 140.143706 -282.720107) (xy 140.189722 -282.702655) (xy 140.237941 -282.692811) (xy 140.287116 -282.69083)
			(xy 140.335971 -282.696762) (xy 140.383242 -282.710454) (xy 140.427704 -282.731552) (xy 140.468207 -282.759508)
			(xy 140.5037 -282.7936) (xy 140.533265 -282.832944) (xy 140.556136 -282.876521) (xy 140.57172 -282.923202)
			(xy 140.579615 -282.971779) (xy 140.58011 -282.996386) (xy 140.898621 -282.996386) (xy 140.902716 -282.945658)
			(xy 140.914895 -282.896244) (xy 140.934843 -282.849424) (xy 140.962044 -282.80641) (xy 140.995792 -282.768316)
			(xy 141.035214 -282.736129) (xy 141.079288 -282.710683) (xy 141.126874 -282.692636) (xy 141.176738 -282.682456)
			(xy 141.22759 -282.680407) (xy 141.278111 -282.686541) (xy 141.326995 -282.700701) (xy 141.372974 -282.722518)
			(xy 141.414858 -282.751428) (xy 141.451562 -282.786683) (xy 141.482135 -282.827369) (xy 141.505786 -282.872432)
			(xy 141.521902 -282.920706) (xy 141.530066 -282.97094) (xy 141.530578 -282.996386) (xy 141.848852 -282.996386)
			(xy 141.852812 -282.947332) (xy 141.864589 -282.899548) (xy 141.88388 -282.854272) (xy 141.910183 -282.812676)
			(xy 141.942818 -282.775839) (xy 141.980939 -282.744714) (xy 142.02356 -282.720107) (xy 142.069576 -282.702655)
			(xy 142.117795 -282.692811) (xy 142.16697 -282.69083) (xy 142.215825 -282.696762) (xy 142.263096 -282.710454)
			(xy 142.307558 -282.731552) (xy 142.348061 -282.759508) (xy 142.383554 -282.7936) (xy 142.413119 -282.832944)
			(xy 142.43599 -282.876521) (xy 142.451574 -282.923202) (xy 142.459469 -282.971779) (xy 142.459964 -282.996386)
			(xy 142.778475 -282.996386) (xy 142.78257 -282.945658) (xy 142.794749 -282.896244) (xy 142.814697 -282.849424)
			(xy 142.841898 -282.80641) (xy 142.875646 -282.768316) (xy 142.915068 -282.736129) (xy 142.959142 -282.710683)
			(xy 143.006728 -282.692636) (xy 143.056592 -282.682456) (xy 143.107444 -282.680407) (xy 143.157965 -282.686541)
			(xy 143.206849 -282.700701) (xy 143.252828 -282.722518) (xy 143.264317 -282.730448) (xy 146.737082 -282.730448)
			(xy 146.741042 -282.681394) (xy 146.752819 -282.63361) (xy 146.77211 -282.588334) (xy 146.798413 -282.546738)
			(xy 146.831048 -282.509901) (xy 146.869169 -282.478776) (xy 146.91179 -282.454169) (xy 146.957806 -282.436717)
			(xy 147.006025 -282.426873) (xy 147.0552 -282.424892) (xy 147.104055 -282.430824) (xy 147.151326 -282.444516)
			(xy 147.195788 -282.465614) (xy 147.236291 -282.49357) (xy 147.271784 -282.527662) (xy 147.301349 -282.567006)
			(xy 147.32422 -282.610583) (xy 147.339804 -282.657264) (xy 147.347699 -282.705841) (xy 147.348194 -282.730448)
			(xy 147.347699 -282.755055) (xy 147.339804 -282.803632) (xy 147.32422 -282.850313) (xy 147.301349 -282.89389)
			(xy 147.271784 -282.933234) (xy 147.236291 -282.967326) (xy 147.195788 -282.995282) (xy 147.151326 -283.01638)
			(xy 147.104055 -283.030072) (xy 147.0552 -283.036004) (xy 147.006025 -283.034023) (xy 146.957806 -283.024179)
			(xy 146.91179 -283.006727) (xy 146.869169 -282.98212) (xy 146.831048 -282.950995) (xy 146.798413 -282.914158)
			(xy 146.77211 -282.872562) (xy 146.752819 -282.827286) (xy 146.741042 -282.779502) (xy 146.737082 -282.730448)
			(xy 143.264317 -282.730448) (xy 143.294712 -282.751428) (xy 143.331416 -282.786683) (xy 143.361989 -282.827369)
			(xy 143.38564 -282.872432) (xy 143.401756 -282.920706) (xy 143.40992 -282.97094) (xy 143.410432 -282.996386)
			(xy 143.40992 -283.021832) (xy 143.401756 -283.072066) (xy 143.38564 -283.12034) (xy 143.361989 -283.165403)
			(xy 143.346991 -283.185362) (xy 164.058615 -283.185362) (xy 164.06255 -283.131591) (xy 164.074273 -283.078967)
			(xy 164.093533 -283.02861) (xy 164.119919 -282.981593) (xy 164.152871 -282.93892) (xy 164.191684 -282.901499)
			(xy 164.235532 -282.870129) (xy 164.28348 -282.845477) (xy 164.334507 -282.828069) (xy 164.387525 -282.818276)
			(xy 164.441404 -282.816307) (xy 164.494995 -282.822204) (xy 164.547156 -282.83584) (xy 164.596776 -282.856927)
			(xy 164.642797 -282.885013) (xy 164.684239 -282.919501) (xy 164.720217 -282.959655) (xy 164.749965 -283.004619)
			(xy 164.77285 -283.053436) (xy 164.788382 -283.105065) (xy 164.796232 -283.158405) (xy 164.796724 -283.185362)
			(xy 164.796232 -283.212319) (xy 164.788382 -283.265659) (xy 164.77285 -283.317288) (xy 164.749965 -283.366105)
			(xy 164.720217 -283.411069) (xy 164.684239 -283.451223) (xy 164.642797 -283.485711) (xy 164.596776 -283.513797)
			(xy 164.547156 -283.534884) (xy 164.494995 -283.54852) (xy 164.441404 -283.554417) (xy 164.387525 -283.552448)
			(xy 164.334507 -283.542655) (xy 164.28348 -283.525247) (xy 164.235532 -283.500595) (xy 164.191684 -283.469225)
			(xy 164.152871 -283.431804) (xy 164.119919 -283.389131) (xy 164.093533 -283.342114) (xy 164.074273 -283.291757)
			(xy 164.06255 -283.239133) (xy 164.058615 -283.185362) (xy 143.346991 -283.185362) (xy 143.331416 -283.206089)
			(xy 143.294712 -283.241344) (xy 143.252828 -283.270254) (xy 143.206849 -283.292071) (xy 143.157965 -283.306231)
			(xy 143.107444 -283.312365) (xy 143.056592 -283.310316) (xy 143.006728 -283.300136) (xy 142.959142 -283.282089)
			(xy 142.915068 -283.256643) (xy 142.875646 -283.224456) (xy 142.841898 -283.186362) (xy 142.814697 -283.143348)
			(xy 142.794749 -283.096528) (xy 142.78257 -283.047114) (xy 142.778475 -282.996386) (xy 142.459964 -282.996386)
			(xy 142.459469 -283.020993) (xy 142.451574 -283.06957) (xy 142.43599 -283.116251) (xy 142.413119 -283.159828)
			(xy 142.383554 -283.199172) (xy 142.348061 -283.233264) (xy 142.307558 -283.26122) (xy 142.263096 -283.282318)
			(xy 142.215825 -283.29601) (xy 142.16697 -283.301942) (xy 142.117795 -283.299961) (xy 142.069576 -283.290117)
			(xy 142.02356 -283.272665) (xy 141.980939 -283.248058) (xy 141.942818 -283.216933) (xy 141.910183 -283.180096)
			(xy 141.88388 -283.1385) (xy 141.864589 -283.093224) (xy 141.852812 -283.04544) (xy 141.848852 -282.996386)
			(xy 141.530578 -282.996386) (xy 141.530066 -283.021832) (xy 141.521902 -283.072066) (xy 141.505786 -283.12034)
			(xy 141.482135 -283.165403) (xy 141.451562 -283.206089) (xy 141.414858 -283.241344) (xy 141.372974 -283.270254)
			(xy 141.326995 -283.292071) (xy 141.278111 -283.306231) (xy 141.22759 -283.312365) (xy 141.176738 -283.310316)
			(xy 141.126874 -283.300136) (xy 141.079288 -283.282089) (xy 141.035214 -283.256643) (xy 140.995792 -283.224456)
			(xy 140.962044 -283.186362) (xy 140.934843 -283.143348) (xy 140.914895 -283.096528) (xy 140.902716 -283.047114)
			(xy 140.898621 -282.996386) (xy 140.58011 -282.996386) (xy 140.579615 -283.020993) (xy 140.57172 -283.06957)
			(xy 140.556136 -283.116251) (xy 140.533265 -283.159828) (xy 140.5037 -283.199172) (xy 140.468207 -283.233264)
			(xy 140.427704 -283.26122) (xy 140.383242 -283.282318) (xy 140.335971 -283.29601) (xy 140.287116 -283.301942)
			(xy 140.237941 -283.299961) (xy 140.189722 -283.290117) (xy 140.143706 -283.272665) (xy 140.101085 -283.248058)
			(xy 140.062964 -283.216933) (xy 140.030329 -283.180096) (xy 140.004026 -283.1385) (xy 139.984735 -283.093224)
			(xy 139.972958 -283.04544) (xy 139.968998 -282.996386) (xy 139.65047 -282.996386) (xy 139.649958 -283.021832)
			(xy 139.641794 -283.072066) (xy 139.625678 -283.12034) (xy 139.602027 -283.165403) (xy 139.571454 -283.206089)
			(xy 139.53475 -283.241344) (xy 139.492866 -283.270254) (xy 139.446887 -283.292071) (xy 139.398003 -283.306231)
			(xy 139.347482 -283.312365) (xy 139.29663 -283.310316) (xy 139.246766 -283.300136) (xy 139.19918 -283.282089)
			(xy 139.155106 -283.256643) (xy 139.115684 -283.224456) (xy 139.081936 -283.186362) (xy 139.054735 -283.143348)
			(xy 139.034787 -283.096528) (xy 139.022608 -283.047114) (xy 139.018513 -282.996386) (xy 138.710416 -282.996386)
			(xy 138.709904 -283.021832) (xy 138.70174 -283.072066) (xy 138.685624 -283.12034) (xy 138.661973 -283.165403)
			(xy 138.6314 -283.206089) (xy 138.594696 -283.241344) (xy 138.552812 -283.270254) (xy 138.506833 -283.292071)
			(xy 138.457949 -283.306231) (xy 138.407428 -283.312365) (xy 138.356576 -283.310316) (xy 138.306712 -283.300136)
			(xy 138.259126 -283.282089) (xy 138.215052 -283.256643) (xy 138.17563 -283.224456) (xy 138.141882 -283.186362)
			(xy 138.114681 -283.143348) (xy 138.094733 -283.096528) (xy 138.082554 -283.047114) (xy 138.078459 -282.996386)
			(xy 136.830562 -282.996386) (xy 136.83005 -283.021832) (xy 136.821886 -283.072066) (xy 136.80577 -283.12034)
			(xy 136.782119 -283.165403) (xy 136.751546 -283.206089) (xy 136.714842 -283.241344) (xy 136.672958 -283.270254)
			(xy 136.626979 -283.292071) (xy 136.578095 -283.306231) (xy 136.527574 -283.312365) (xy 136.476722 -283.310316)
			(xy 136.426858 -283.300136) (xy 136.379272 -283.282089) (xy 136.335198 -283.256643) (xy 136.295776 -283.224456)
			(xy 136.262028 -283.186362) (xy 136.234827 -283.143348) (xy 136.214879 -283.096528) (xy 136.2027 -283.047114)
			(xy 136.198605 -282.996386) (xy 135.880094 -282.996386) (xy 135.879599 -283.020993) (xy 135.871704 -283.06957)
			(xy 135.85612 -283.116251) (xy 135.833249 -283.159828) (xy 135.803684 -283.199172) (xy 135.768191 -283.233264)
			(xy 135.727688 -283.26122) (xy 135.683226 -283.282318) (xy 135.635955 -283.29601) (xy 135.5871 -283.301942)
			(xy 135.537925 -283.299961) (xy 135.489706 -283.290117) (xy 135.44369 -283.272665) (xy 135.401069 -283.248058)
			(xy 135.362948 -283.216933) (xy 135.330313 -283.180096) (xy 135.30401 -283.1385) (xy 135.284719 -283.093224)
			(xy 135.272942 -283.04544) (xy 135.268982 -282.996386) (xy 134.950454 -282.996386) (xy 134.949942 -283.021832)
			(xy 134.941778 -283.072066) (xy 134.925662 -283.12034) (xy 134.902011 -283.165403) (xy 134.871438 -283.206089)
			(xy 134.834734 -283.241344) (xy 134.79285 -283.270254) (xy 134.746871 -283.292071) (xy 134.697987 -283.306231)
			(xy 134.647466 -283.312365) (xy 134.596614 -283.310316) (xy 134.54675 -283.300136) (xy 134.499164 -283.282089)
			(xy 134.45509 -283.256643) (xy 134.415668 -283.224456) (xy 134.38192 -283.186362) (xy 134.354719 -283.143348)
			(xy 134.334771 -283.096528) (xy 134.322592 -283.047114) (xy 134.318497 -282.996386) (xy 133.999986 -282.996386)
			(xy 133.999491 -283.020993) (xy 133.991596 -283.06957) (xy 133.976012 -283.116251) (xy 133.953141 -283.159828)
			(xy 133.923576 -283.199172) (xy 133.888083 -283.233264) (xy 133.84758 -283.26122) (xy 133.803118 -283.282318)
			(xy 133.755847 -283.29601) (xy 133.706992 -283.301942) (xy 133.657817 -283.299961) (xy 133.609598 -283.290117)
			(xy 133.563582 -283.272665) (xy 133.520961 -283.248058) (xy 133.48284 -283.216933) (xy 133.450205 -283.180096)
			(xy 133.423902 -283.1385) (xy 133.404611 -283.093224) (xy 133.392834 -283.04544) (xy 133.388874 -282.996386)
			(xy 133.0706 -282.996386) (xy 133.070088 -283.021832) (xy 133.061924 -283.072066) (xy 133.045808 -283.12034)
			(xy 133.022157 -283.165403) (xy 132.991584 -283.206089) (xy 132.95488 -283.241344) (xy 132.912996 -283.270254)
			(xy 132.867017 -283.292071) (xy 132.818133 -283.306231) (xy 132.767612 -283.312365) (xy 132.71676 -283.310316)
			(xy 132.666896 -283.300136) (xy 132.61931 -283.282089) (xy 132.575236 -283.256643) (xy 132.535814 -283.224456)
			(xy 132.502066 -283.186362) (xy 132.474865 -283.143348) (xy 132.454917 -283.096528) (xy 132.442738 -283.047114)
			(xy 132.438643 -282.996386) (xy 132.130546 -282.996386) (xy 132.130034 -283.021832) (xy 132.12187 -283.072066)
			(xy 132.105754 -283.12034) (xy 132.082103 -283.165403) (xy 132.05153 -283.206089) (xy 132.014826 -283.241344)
			(xy 131.972942 -283.270254) (xy 131.926963 -283.292071) (xy 131.878079 -283.306231) (xy 131.827558 -283.312365)
			(xy 131.776706 -283.310316) (xy 131.726842 -283.300136) (xy 131.679256 -283.282089) (xy 131.635182 -283.256643)
			(xy 131.59576 -283.224456) (xy 131.562012 -283.186362) (xy 131.534811 -283.143348) (xy 131.514863 -283.096528)
			(xy 131.502684 -283.047114) (xy 131.498589 -282.996386) (xy 130.250438 -282.996386) (xy 130.249926 -283.021832)
			(xy 130.241762 -283.072066) (xy 130.225646 -283.12034) (xy 130.201995 -283.165403) (xy 130.171422 -283.206089)
			(xy 130.134718 -283.241344) (xy 130.092834 -283.270254) (xy 130.046855 -283.292071) (xy 129.997971 -283.306231)
			(xy 129.94745 -283.312365) (xy 129.896598 -283.310316) (xy 129.846734 -283.300136) (xy 129.799148 -283.282089)
			(xy 129.755074 -283.256643) (xy 129.715652 -283.224456) (xy 129.681904 -283.186362) (xy 129.654703 -283.143348)
			(xy 129.634755 -283.096528) (xy 129.622576 -283.047114) (xy 129.618481 -282.996386) (xy 129.29997 -282.996386)
			(xy 129.299475 -283.020993) (xy 129.29158 -283.06957) (xy 129.275996 -283.116251) (xy 129.253125 -283.159828)
			(xy 129.22356 -283.199172) (xy 129.188067 -283.233264) (xy 129.147564 -283.26122) (xy 129.103102 -283.282318)
			(xy 129.055831 -283.29601) (xy 129.006976 -283.301942) (xy 128.957801 -283.299961) (xy 128.909582 -283.290117)
			(xy 128.863566 -283.272665) (xy 128.820945 -283.248058) (xy 128.782824 -283.216933) (xy 128.750189 -283.180096)
			(xy 128.723886 -283.1385) (xy 128.704595 -283.093224) (xy 128.692818 -283.04544) (xy 128.688858 -282.996386)
			(xy 128.370584 -282.996386) (xy 128.370072 -283.021832) (xy 128.361908 -283.072066) (xy 128.345792 -283.12034)
			(xy 128.322141 -283.165403) (xy 128.291568 -283.206089) (xy 128.254864 -283.241344) (xy 128.21298 -283.270254)
			(xy 128.167001 -283.292071) (xy 128.118117 -283.306231) (xy 128.067596 -283.312365) (xy 128.016744 -283.310316)
			(xy 127.96688 -283.300136) (xy 127.919294 -283.282089) (xy 127.87522 -283.256643) (xy 127.835798 -283.224456)
			(xy 127.80205 -283.186362) (xy 127.774849 -283.143348) (xy 127.754901 -283.096528) (xy 127.742722 -283.047114)
			(xy 127.738627 -282.996386) (xy 127.419653 -282.996386) (xy 127.419654 -283.021752) (xy 127.411276 -283.07177)
			(xy 127.394749 -283.119717) (xy 127.370528 -283.164275) (xy 127.339278 -283.204218) (xy 127.301858 -283.238449)
			(xy 127.259297 -283.266028) (xy 127.23622 -283.276548) (xy 127.22225 -283.282644) (xy 127.20574 -283.30779)
			(xy 127.20574 -283.508704) (xy 127.206184 -283.518549) (xy 127.213599 -283.536787) (xy 127.227364 -283.550864)
			(xy 127.23622 -283.555186) (xy 127.335534 -283.59862) (xy 127.365252 -283.59354) (xy 127.376682 -283.583126)
			(xy 127.393709 -283.567795) (xy 127.431501 -283.54189) (xy 127.472741 -283.521927) (xy 127.516501 -283.508353)
			(xy 127.561799 -283.501475) (xy 127.584708 -283.501084) (xy 127.609964 -283.501606) (xy 127.659786 -283.509921)
			(xy 127.70756 -283.526323) (xy 127.751982 -283.550365) (xy 127.791842 -283.58139) (xy 127.826052 -283.618552)
			(xy 127.853679 -283.660839) (xy 127.873968 -283.707096) (xy 127.886368 -283.756061) (xy 127.890538 -283.806392)
			(xy 128.208527 -283.806392) (xy 128.212622 -283.755664) (xy 128.224801 -283.70625) (xy 128.244749 -283.65943)
			(xy 128.27195 -283.616416) (xy 128.305698 -283.578322) (xy 128.34512 -283.546135) (xy 128.389194 -283.520689)
			(xy 128.43678 -283.502642) (xy 128.486644 -283.492462) (xy 128.537496 -283.490413) (xy 128.588017 -283.496547)
			(xy 128.636901 -283.510707) (xy 128.68288 -283.532524) (xy 128.724764 -283.561434) (xy 128.761468 -283.596689)
			(xy 128.792041 -283.637375) (xy 128.815692 -283.682438) (xy 128.831808 -283.730712) (xy 128.839972 -283.780946)
			(xy 128.840484 -283.806392) (xy 129.148581 -283.806392) (xy 129.152676 -283.755664) (xy 129.164855 -283.70625)
			(xy 129.184803 -283.65943) (xy 129.212004 -283.616416) (xy 129.245752 -283.578322) (xy 129.285174 -283.546135)
			(xy 129.329248 -283.520689) (xy 129.376834 -283.502642) (xy 129.426698 -283.492462) (xy 129.47755 -283.490413)
			(xy 129.528071 -283.496547) (xy 129.576955 -283.510707) (xy 129.622934 -283.532524) (xy 129.664818 -283.561434)
			(xy 129.701522 -283.596689) (xy 129.732095 -283.637375) (xy 129.755746 -283.682438) (xy 129.771862 -283.730712)
			(xy 129.780026 -283.780946) (xy 129.780538 -283.806392) (xy 130.099066 -283.806392) (xy 130.103026 -283.757338)
			(xy 130.114803 -283.709554) (xy 130.134094 -283.664278) (xy 130.160397 -283.622682) (xy 130.193032 -283.585845)
			(xy 130.231153 -283.55472) (xy 130.273774 -283.530113) (xy 130.31979 -283.512661) (xy 130.368009 -283.502817)
			(xy 130.417184 -283.500836) (xy 130.466039 -283.506768) (xy 130.51331 -283.52046) (xy 130.557772 -283.541558)
			(xy 130.598275 -283.569514) (xy 130.633768 -283.603606) (xy 130.663333 -283.64295) (xy 130.686204 -283.686527)
			(xy 130.701788 -283.733208) (xy 130.709683 -283.781785) (xy 130.710178 -283.806392) (xy 131.028435 -283.806392)
			(xy 131.03253 -283.755664) (xy 131.044709 -283.70625) (xy 131.064657 -283.65943) (xy 131.091858 -283.616416)
			(xy 131.125606 -283.578322) (xy 131.165028 -283.546135) (xy 131.209102 -283.520689) (xy 131.256688 -283.502642)
			(xy 131.306552 -283.492462) (xy 131.357404 -283.490413) (xy 131.407925 -283.496547) (xy 131.456809 -283.510707)
			(xy 131.502788 -283.532524) (xy 131.544672 -283.561434) (xy 131.581376 -283.596689) (xy 131.611949 -283.637375)
			(xy 131.6356 -283.682438) (xy 131.651716 -283.730712) (xy 131.65988 -283.780946) (xy 131.660392 -283.806392)
			(xy 131.97892 -283.806392) (xy 131.98288 -283.757338) (xy 131.994657 -283.709554) (xy 132.013948 -283.664278)
			(xy 132.040251 -283.622682) (xy 132.072886 -283.585845) (xy 132.111007 -283.55472) (xy 132.153628 -283.530113)
			(xy 132.199644 -283.512661) (xy 132.247863 -283.502817) (xy 132.297038 -283.500836) (xy 132.345893 -283.506768)
			(xy 132.393164 -283.52046) (xy 132.437626 -283.541558) (xy 132.478129 -283.569514) (xy 132.513622 -283.603606)
			(xy 132.543187 -283.64295) (xy 132.566058 -283.686527) (xy 132.581642 -283.733208) (xy 132.589537 -283.781785)
			(xy 132.590032 -283.806392) (xy 132.908543 -283.806392) (xy 132.912638 -283.755664) (xy 132.924817 -283.70625)
			(xy 132.944765 -283.65943) (xy 132.971966 -283.616416) (xy 133.005714 -283.578322) (xy 133.045136 -283.546135)
			(xy 133.08921 -283.520689) (xy 133.136796 -283.502642) (xy 133.18666 -283.492462) (xy 133.237512 -283.490413)
			(xy 133.288033 -283.496547) (xy 133.336917 -283.510707) (xy 133.382896 -283.532524) (xy 133.42478 -283.561434)
			(xy 133.461484 -283.596689) (xy 133.492057 -283.637375) (xy 133.515708 -283.682438) (xy 133.531824 -283.730712)
			(xy 133.539988 -283.780946) (xy 133.5405 -283.806392) (xy 133.859028 -283.806392) (xy 133.862988 -283.757338)
			(xy 133.874765 -283.709554) (xy 133.894056 -283.664278) (xy 133.920359 -283.622682) (xy 133.952994 -283.585845)
			(xy 133.991115 -283.55472) (xy 134.033736 -283.530113) (xy 134.079752 -283.512661) (xy 134.127971 -283.502817)
			(xy 134.177146 -283.500836) (xy 134.226001 -283.506768) (xy 134.273272 -283.52046) (xy 134.317734 -283.541558)
			(xy 134.358237 -283.569514) (xy 134.39373 -283.603606) (xy 134.423295 -283.64295) (xy 134.446166 -283.686527)
			(xy 134.46175 -283.733208) (xy 134.469645 -283.781785) (xy 134.47014 -283.806392) (xy 134.788397 -283.806392)
			(xy 134.792492 -283.755664) (xy 134.804671 -283.70625) (xy 134.824619 -283.65943) (xy 134.85182 -283.616416)
			(xy 134.885568 -283.578322) (xy 134.92499 -283.546135) (xy 134.969064 -283.520689) (xy 135.01665 -283.502642)
			(xy 135.066514 -283.492462) (xy 135.117366 -283.490413) (xy 135.167887 -283.496547) (xy 135.216771 -283.510707)
			(xy 135.26275 -283.532524) (xy 135.304634 -283.561434) (xy 135.341338 -283.596689) (xy 135.371911 -283.637375)
			(xy 135.395562 -283.682438) (xy 135.411678 -283.730712) (xy 135.419842 -283.780946) (xy 135.420354 -283.806392)
			(xy 135.728451 -283.806392) (xy 135.732546 -283.755664) (xy 135.744725 -283.70625) (xy 135.764673 -283.65943)
			(xy 135.791874 -283.616416) (xy 135.825622 -283.578322) (xy 135.865044 -283.546135) (xy 135.909118 -283.520689)
			(xy 135.956704 -283.502642) (xy 136.006568 -283.492462) (xy 136.05742 -283.490413) (xy 136.107941 -283.496547)
			(xy 136.156825 -283.510707) (xy 136.202804 -283.532524) (xy 136.244688 -283.561434) (xy 136.281392 -283.596689)
			(xy 136.311965 -283.637375) (xy 136.335616 -283.682438) (xy 136.351732 -283.730712) (xy 136.359896 -283.780946)
			(xy 136.360408 -283.806392) (xy 136.678936 -283.806392) (xy 136.682896 -283.757338) (xy 136.694673 -283.709554)
			(xy 136.713964 -283.664278) (xy 136.740267 -283.622682) (xy 136.772902 -283.585845) (xy 136.811023 -283.55472)
			(xy 136.853644 -283.530113) (xy 136.89966 -283.512661) (xy 136.947879 -283.502817) (xy 136.997054 -283.500836)
			(xy 137.045909 -283.506768) (xy 137.09318 -283.52046) (xy 137.137642 -283.541558) (xy 137.178145 -283.569514)
			(xy 137.213638 -283.603606) (xy 137.243203 -283.64295) (xy 137.266074 -283.686527) (xy 137.281658 -283.733208)
			(xy 137.289553 -283.781785) (xy 137.290048 -283.806392) (xy 137.608559 -283.806392) (xy 137.612654 -283.755664)
			(xy 137.624833 -283.70625) (xy 137.644781 -283.65943) (xy 137.671982 -283.616416) (xy 137.70573 -283.578322)
			(xy 137.745152 -283.546135) (xy 137.789226 -283.520689) (xy 137.836812 -283.502642) (xy 137.886676 -283.492462)
			(xy 137.937528 -283.490413) (xy 137.988049 -283.496547) (xy 138.036933 -283.510707) (xy 138.082912 -283.532524)
			(xy 138.124796 -283.561434) (xy 138.1615 -283.596689) (xy 138.192073 -283.637375) (xy 138.215724 -283.682438)
			(xy 138.23184 -283.730712) (xy 138.240004 -283.780946) (xy 138.240516 -283.806392) (xy 138.559044 -283.806392)
			(xy 138.563004 -283.757338) (xy 138.574781 -283.709554) (xy 138.594072 -283.664278) (xy 138.620375 -283.622682)
			(xy 138.65301 -283.585845) (xy 138.691131 -283.55472) (xy 138.733752 -283.530113) (xy 138.779768 -283.512661)
			(xy 138.827987 -283.502817) (xy 138.877162 -283.500836) (xy 138.926017 -283.506768) (xy 138.973288 -283.52046)
			(xy 139.01775 -283.541558) (xy 139.058253 -283.569514) (xy 139.093746 -283.603606) (xy 139.123311 -283.64295)
			(xy 139.146182 -283.686527) (xy 139.161766 -283.733208) (xy 139.169661 -283.781785) (xy 139.170156 -283.806392)
			(xy 139.488413 -283.806392) (xy 139.492508 -283.755664) (xy 139.504687 -283.70625) (xy 139.524635 -283.65943)
			(xy 139.551836 -283.616416) (xy 139.585584 -283.578322) (xy 139.625006 -283.546135) (xy 139.66908 -283.520689)
			(xy 139.716666 -283.502642) (xy 139.76653 -283.492462) (xy 139.817382 -283.490413) (xy 139.867903 -283.496547)
			(xy 139.916787 -283.510707) (xy 139.962766 -283.532524) (xy 140.00465 -283.561434) (xy 140.041354 -283.596689)
			(xy 140.071927 -283.637375) (xy 140.095578 -283.682438) (xy 140.111694 -283.730712) (xy 140.119858 -283.780946)
			(xy 140.12037 -283.806392) (xy 140.438898 -283.806392) (xy 140.442858 -283.757338) (xy 140.454635 -283.709554)
			(xy 140.473926 -283.664278) (xy 140.500229 -283.622682) (xy 140.532864 -283.585845) (xy 140.570985 -283.55472)
			(xy 140.613606 -283.530113) (xy 140.659622 -283.512661) (xy 140.707841 -283.502817) (xy 140.757016 -283.500836)
			(xy 140.805871 -283.506768) (xy 140.853142 -283.52046) (xy 140.897604 -283.541558) (xy 140.938107 -283.569514)
			(xy 140.9736 -283.603606) (xy 141.003165 -283.64295) (xy 141.026036 -283.686527) (xy 141.04162 -283.733208)
			(xy 141.049515 -283.781785) (xy 141.05001 -283.806392) (xy 141.368521 -283.806392) (xy 141.372616 -283.755664)
			(xy 141.384795 -283.70625) (xy 141.404743 -283.65943) (xy 141.431944 -283.616416) (xy 141.465692 -283.578322)
			(xy 141.505114 -283.546135) (xy 141.549188 -283.520689) (xy 141.596774 -283.502642) (xy 141.646638 -283.492462)
			(xy 141.69749 -283.490413) (xy 141.748011 -283.496547) (xy 141.796895 -283.510707) (xy 141.842874 -283.532524)
			(xy 141.884758 -283.561434) (xy 141.921462 -283.596689) (xy 141.952035 -283.637375) (xy 141.975686 -283.682438)
			(xy 141.991802 -283.730712) (xy 141.999966 -283.780946) (xy 142.000478 -283.806392) (xy 142.308575 -283.806392)
			(xy 142.31267 -283.755664) (xy 142.324849 -283.70625) (xy 142.344797 -283.65943) (xy 142.371998 -283.616416)
			(xy 142.405746 -283.578322) (xy 142.445168 -283.546135) (xy 142.489242 -283.520689) (xy 142.536828 -283.502642)
			(xy 142.586692 -283.492462) (xy 142.637544 -283.490413) (xy 142.688065 -283.496547) (xy 142.736949 -283.510707)
			(xy 142.782928 -283.532524) (xy 142.824812 -283.561434) (xy 142.861516 -283.596689) (xy 142.892089 -283.637375)
			(xy 142.91574 -283.682438) (xy 142.931856 -283.730712) (xy 142.94002 -283.780946) (xy 142.940532 -283.806392)
			(xy 143.258806 -283.806392) (xy 143.262766 -283.757338) (xy 143.274543 -283.709554) (xy 143.293834 -283.664278)
			(xy 143.320137 -283.622682) (xy 143.352772 -283.585845) (xy 143.390893 -283.55472) (xy 143.433514 -283.530113)
			(xy 143.47953 -283.512661) (xy 143.527749 -283.502817) (xy 143.576924 -283.500836) (xy 143.625779 -283.506768)
			(xy 143.67305 -283.52046) (xy 143.717512 -283.541558) (xy 143.758015 -283.569514) (xy 143.793508 -283.603606)
			(xy 143.823073 -283.64295) (xy 143.845944 -283.686527) (xy 143.861528 -283.733208) (xy 143.869423 -283.781785)
			(xy 143.869918 -283.806392) (xy 145.138914 -283.806392) (xy 145.142874 -283.757338) (xy 145.154651 -283.709554)
			(xy 145.173942 -283.664278) (xy 145.200245 -283.622682) (xy 145.23288 -283.585845) (xy 145.271001 -283.55472)
			(xy 145.313622 -283.530113) (xy 145.359638 -283.512661) (xy 145.407857 -283.502817) (xy 145.457032 -283.500836)
			(xy 145.505887 -283.506768) (xy 145.553158 -283.52046) (xy 145.59762 -283.541558) (xy 145.638123 -283.569514)
			(xy 145.673616 -283.603606) (xy 145.703181 -283.64295) (xy 145.726052 -283.686527) (xy 145.741636 -283.733208)
			(xy 145.749531 -283.781785) (xy 145.750026 -283.806392) (xy 145.749531 -283.830999) (xy 145.741636 -283.879576)
			(xy 145.726052 -283.926257) (xy 145.703181 -283.969834) (xy 145.673616 -284.009178) (xy 145.646477 -284.035246)
			(xy 166.774383 -284.035246) (xy 166.778318 -283.981475) (xy 166.790041 -283.928851) (xy 166.809301 -283.878494)
			(xy 166.835687 -283.831477) (xy 166.868639 -283.788804) (xy 166.907452 -283.751383) (xy 166.9513 -283.720013)
			(xy 166.999248 -283.695361) (xy 167.050275 -283.677953) (xy 167.103293 -283.66816) (xy 167.157172 -283.666191)
			(xy 167.210763 -283.672088) (xy 167.262924 -283.685724) (xy 167.312544 -283.706811) (xy 167.358565 -283.734897)
			(xy 167.400007 -283.769385) (xy 167.435985 -283.809539) (xy 167.465733 -283.854503) (xy 167.488618 -283.90332)
			(xy 167.50415 -283.954949) (xy 167.512 -284.008289) (xy 167.512492 -284.035246) (xy 171.476162 -284.035246)
			(xy 171.476652 -284.00405) (xy 171.484468 -283.942149) (xy 171.499994 -283.881719) (xy 171.522986 -283.823717)
			(xy 171.553078 -283.769061) (xy 171.589794 -283.718616) (xy 171.632554 -283.673181) (xy 171.680681 -283.633474)
			(xy 171.706794 -283.6164) (xy 171.716954 -283.609796) (xy 171.729146 -283.589984) (xy 171.738544 -283.485844)
			(xy 171.730162 -283.464254) (xy 171.721272 -283.455872) (xy 171.702969 -283.438375) (xy 171.670892 -283.399194)
			(xy 171.644476 -283.355993) (xy 171.624218 -283.309585) (xy 171.6105 -283.260842) (xy 171.603578 -283.21068)
			(xy 171.603162 -283.185362) (xy 171.60358 -283.160014) (xy 171.610517 -283.109795) (xy 171.624268 -283.060999)
			(xy 171.644574 -283.014547) (xy 171.671052 -282.971316) (xy 171.703203 -282.932119) (xy 171.721526 -282.914598)
			(xy 171.730416 -282.90647) (xy 171.738798 -282.884626) (xy 171.729146 -282.780486) (xy 171.716954 -282.760674)
			(xy 171.706794 -282.754324) (xy 171.680685 -282.737221) (xy 171.632563 -282.697469) (xy 171.589808 -282.651995)
			(xy 171.553093 -282.601518) (xy 171.523 -282.546835) (xy 171.500003 -282.488809) (xy 171.484466 -282.428356)
			(xy 171.476635 -282.366433) (xy 171.476162 -282.335224) (xy 171.476635 -282.304027) (xy 171.484454 -282.242126)
			(xy 171.499983 -282.181696) (xy 171.522976 -282.123694) (xy 171.553071 -282.069038) (xy 171.589789 -282.018593)
			(xy 171.632551 -281.973158) (xy 171.68068 -281.933452) (xy 171.706794 -281.916378) (xy 171.716954 -281.909774)
			(xy 171.729146 -281.889962) (xy 171.738544 -281.785822) (xy 171.730162 -281.764232) (xy 171.721272 -281.75585)
			(xy 171.703006 -281.738315) (xy 171.670926 -281.699142) (xy 171.644505 -281.655949) (xy 171.624241 -281.609549)
			(xy 171.610514 -281.560812) (xy 171.603583 -281.510656) (xy 171.603162 -281.48534) (xy 171.603566 -281.459991)
			(xy 171.610505 -281.409772) (xy 171.624259 -281.360976) (xy 171.644568 -281.314524) (xy 171.671049 -281.271293)
			(xy 171.703202 -281.232096) (xy 171.721526 -281.214576) (xy 171.730416 -281.206448) (xy 171.738798 -281.184604)
			(xy 171.729146 -281.080464) (xy 171.716954 -281.060652) (xy 171.706794 -281.054302) (xy 171.680675 -281.037213)
			(xy 171.632553 -280.99746) (xy 171.589798 -280.951984) (xy 171.553085 -280.901505) (xy 171.522993 -280.846819)
			(xy 171.499998 -280.788791) (xy 171.484463 -280.728337) (xy 171.476633 -280.666411) (xy 171.476162 -280.635202)
			(xy 171.476618 -280.604005) (xy 171.484439 -280.542102) (xy 171.499971 -280.481672) (xy 171.522967 -280.42367)
			(xy 171.553064 -280.369014) (xy 171.589785 -280.31857) (xy 171.632549 -280.273135) (xy 171.680679 -280.233429)
			(xy 171.706794 -280.216356) (xy 171.716954 -280.209752) (xy 171.729146 -280.18994) (xy 171.738544 -280.0858)
			(xy 171.730162 -280.06421) (xy 171.721272 -280.055828) (xy 171.701366 -280.036673) (xy 171.666904 -279.9935)
			(xy 171.639265 -279.94567) (xy 171.619069 -279.894253) (xy 171.606767 -279.840399) (xy 171.602634 -279.785312)
			(xy 171.606763 -279.730226) (xy 171.619062 -279.676371) (xy 171.639254 -279.624952) (xy 171.66689 -279.577121)
			(xy 171.701349 -279.533945) (xy 171.721272 -279.514808) (xy 171.730162 -279.506426) (xy 171.738544 -279.484836)
			(xy 171.729146 -279.380696) (xy 171.716954 -279.360884) (xy 171.706794 -279.35428) (xy 171.680678 -279.337211)
			(xy 171.632561 -279.297494) (xy 171.589809 -279.252053) (xy 171.553096 -279.201606) (xy 171.523003 -279.146952)
			(xy 171.500006 -279.088953) (xy 171.484468 -279.028527) (xy 171.476635 -278.96663) (xy 171.476162 -278.935434)
			(xy 171.476651 -278.904271) (xy 171.484463 -278.842437) (xy 171.499963 -278.782069) (xy 171.522906 -278.724121)
			(xy 171.552932 -278.669504) (xy 171.589566 -278.619082) (xy 171.632231 -278.573648) (xy 171.680253 -278.53392)
			(xy 171.732877 -278.500525) (xy 171.789271 -278.473988) (xy 171.848546 -278.454728) (xy 171.909767 -278.443049)
			(xy 171.97197 -278.439136) (xy 172.034173 -278.443049) (xy 172.095394 -278.454728) (xy 172.154669 -278.473988)
			(xy 172.211063 -278.500525) (xy 172.263687 -278.53392) (xy 172.311709 -278.573648) (xy 172.354374 -278.619082)
			(xy 172.391008 -278.669504) (xy 172.421034 -278.724121) (xy 172.443977 -278.782069) (xy 172.459477 -278.842437)
			(xy 172.467289 -278.904271) (xy 172.467778 -278.935434) (xy 172.4673 -278.966631) (xy 172.459486 -279.028533)
			(xy 172.443959 -279.088964) (xy 172.420967 -279.146967) (xy 172.390874 -279.201624) (xy 172.354155 -279.252069)
			(xy 172.311391 -279.297503) (xy 172.263261 -279.337208) (xy 172.237146 -279.35428) (xy 172.226986 -279.360884)
			(xy 172.214794 -279.380696) (xy 172.205396 -279.484836) (xy 172.213778 -279.506426) (xy 172.222668 -279.514808)
			(xy 172.242613 -279.533926) (xy 172.27708 -279.577102) (xy 172.304722 -279.624937) (xy 172.32492 -279.67636)
			(xy 172.337221 -279.73022) (xy 172.341351 -279.785312) (xy 172.337217 -279.840404) (xy 172.324912 -279.894264)
			(xy 172.304711 -279.945685) (xy 172.277066 -279.993518) (xy 172.242596 -280.036692) (xy 172.222668 -280.055828)
			(xy 172.213778 -280.06421) (xy 172.205396 -280.0858) (xy 172.214794 -280.18994) (xy 172.226986 -280.209752)
			(xy 172.237146 -280.216356) (xy 172.263265 -280.233421) (xy 172.311384 -280.273137) (xy 172.354138 -280.318578)
			(xy 172.390852 -280.369024) (xy 172.420945 -280.42368) (xy 172.443942 -280.48168) (xy 172.459477 -280.542107)
			(xy 172.467307 -280.604006) (xy 172.467778 -280.635202) (xy 172.46729 -280.666411) (xy 172.45947 -280.728337)
			(xy 172.443942 -280.788793) (xy 172.42095 -280.846822) (xy 172.39086 -280.901508) (xy 172.354145 -280.951986)
			(xy 172.311386 -280.997459) (xy 172.26326 -281.037206) (xy 172.237146 -281.054302) (xy 172.226986 -281.060652)
			(xy 172.214794 -281.080464) (xy 172.205142 -281.184604) (xy 172.213524 -281.206448) (xy 172.222414 -281.214576)
			(xy 172.240725 -281.232108) (xy 172.272868 -281.271308) (xy 172.299342 -281.314539) (xy 172.319649 -281.360987)
			(xy 172.333406 -281.409778) (xy 172.340354 -281.459993) (xy 172.340778 -281.48534) (xy 172.340337 -281.510657)
			(xy 172.333417 -281.560815) (xy 172.3197 -281.609555) (xy 172.299443 -281.65596) (xy 172.273028 -281.699157)
			(xy 172.240951 -281.738333) (xy 172.222668 -281.75585) (xy 172.213778 -281.764232) (xy 172.205396 -281.785822)
			(xy 172.214794 -281.889962) (xy 172.226986 -281.909774) (xy 172.237146 -281.916378) (xy 172.263229 -281.933495)
			(xy 172.311348 -281.973204) (xy 172.354104 -282.018637) (xy 172.390822 -282.069076) (xy 172.420919 -282.123724)
			(xy 172.443921 -282.181716) (xy 172.459464 -282.242137) (xy 172.467302 -282.30403) (xy 172.467778 -282.335224)
			(xy 172.467307 -282.366434) (xy 172.459484 -282.428361) (xy 172.443953 -282.488817) (xy 172.42096 -282.546846)
			(xy 172.390867 -282.601532) (xy 172.35415 -282.65201) (xy 172.311389 -282.697481) (xy 172.263261 -282.737229)
			(xy 172.237146 -282.754324) (xy 172.226986 -282.760674) (xy 172.214794 -282.780486) (xy 172.205142 -282.884626)
			(xy 172.213524 -282.90647) (xy 172.222414 -282.914598) (xy 172.240735 -282.932119) (xy 172.272878 -282.971321)
			(xy 172.29935 -283.014555) (xy 172.319655 -283.061005) (xy 172.33341 -283.109798) (xy 172.340355 -283.160015)
			(xy 172.340778 -283.185362) (xy 175.57623 -283.185362) (xy 175.576687 -283.154152) (xy 175.584511 -283.092224)
			(xy 175.600044 -283.031768) (xy 175.623039 -282.973738) (xy 175.653135 -282.919052) (xy 175.689854 -282.868575)
			(xy 175.732616 -282.823103) (xy 175.780746 -282.783357) (xy 175.806862 -282.766262) (xy 175.817022 -282.759912)
			(xy 175.829214 -282.7401) (xy 175.838866 -282.63596) (xy 175.830484 -282.614116) (xy 175.821594 -282.605988)
			(xy 175.803267 -282.588472) (xy 175.771125 -282.549269) (xy 175.744653 -282.506035) (xy 175.724349 -282.459583)
			(xy 175.710596 -282.410789) (xy 175.703652 -282.360572) (xy 175.70323 -282.335224) (xy 175.703644 -282.309906)
			(xy 175.710569 -282.259747) (xy 175.724291 -282.211006) (xy 175.744553 -282.164601) (xy 175.770973 -282.121405)
			(xy 175.803055 -282.08223) (xy 175.82134 -282.064714) (xy 175.83023 -282.056332) (xy 175.838612 -282.034742)
			(xy 175.829214 -281.930602) (xy 175.817022 -281.91079) (xy 175.806862 -281.904186) (xy 175.780741 -281.887124)
			(xy 175.732626 -281.847405) (xy 175.689875 -281.801962) (xy 175.653163 -281.751514) (xy 175.623071 -281.696859)
			(xy 175.600074 -281.63886) (xy 175.584537 -281.578434) (xy 175.576703 -281.516536) (xy 175.57623 -281.48534)
			(xy 175.576669 -281.454129) (xy 175.584496 -281.392201) (xy 175.600032 -281.331744) (xy 175.62303 -281.273714)
			(xy 175.653128 -281.219028) (xy 175.689849 -281.168551) (xy 175.732613 -281.12308) (xy 175.780745 -281.083335)
			(xy 175.806862 -281.06624) (xy 175.817022 -281.05989) (xy 175.829214 -281.040078) (xy 175.838866 -280.935938)
			(xy 175.830484 -280.914094) (xy 175.821594 -280.905966) (xy 175.803257 -280.888461) (xy 175.771116 -280.849255)
			(xy 175.744645 -280.806019) (xy 175.724342 -280.759565) (xy 175.710591 -280.710769) (xy 175.70365 -280.66055)
			(xy 175.70323 -280.635202) (xy 175.70363 -280.609884) (xy 175.710557 -280.559724) (xy 175.724282 -280.510983)
			(xy 175.744547 -280.464578) (xy 175.770969 -280.421382) (xy 175.803053 -280.382207) (xy 175.82134 -280.364692)
			(xy 175.83023 -280.35631) (xy 175.838612 -280.33472) (xy 175.829214 -280.23058) (xy 175.817022 -280.210768)
			(xy 175.806862 -280.204164) (xy 175.780766 -280.187063) (xy 175.732639 -280.147356) (xy 175.689877 -280.101922)
			(xy 175.653156 -280.051481) (xy 175.623057 -279.996829) (xy 175.600055 -279.938831) (xy 175.584515 -279.878405)
			(xy 175.576683 -279.816506) (xy 175.576682 -279.754113) (xy 175.584512 -279.692214) (xy 175.600049 -279.631787)
			(xy 175.623049 -279.573789) (xy 175.653146 -279.519136) (xy 175.689865 -279.468692) (xy 175.732625 -279.423257)
			(xy 175.78075 -279.383548) (xy 175.806862 -279.366472) (xy 175.817022 -279.359868) (xy 175.829214 -279.340056)
			(xy 175.838612 -279.235916) (xy 175.83023 -279.214326) (xy 175.82134 -279.205944) (xy 175.803065 -279.188418)
			(xy 175.770987 -279.149242) (xy 175.744568 -279.106048) (xy 175.724306 -279.059645) (xy 175.710581 -279.010908)
			(xy 175.703651 -278.960751) (xy 175.70323 -278.935434) (xy 175.703608 -278.910084) (xy 175.71055 -278.859862)
			(xy 175.724307 -278.811065) (xy 175.744621 -278.764613) (xy 175.771107 -278.721383) (xy 175.803267 -278.682188)
			(xy 175.821594 -278.66467) (xy 175.830484 -278.656542) (xy 175.838866 -278.634698) (xy 175.829214 -278.530558)
			(xy 175.817022 -278.510746) (xy 175.806862 -278.504396) (xy 175.780733 -278.487323) (xy 175.732612 -278.447566)
			(xy 175.689859 -278.402087) (xy 175.653147 -278.351605) (xy 175.623056 -278.296918) (xy 175.600062 -278.238888)
			(xy 175.584529 -278.178432) (xy 175.5767 -278.116506) (xy 175.57623 -278.085296) (xy 175.576719 -278.054133)
			(xy 175.584531 -277.992299) (xy 175.600031 -277.931931) (xy 175.622974 -277.873983) (xy 175.653 -277.819366)
			(xy 175.689634 -277.768944) (xy 175.732299 -277.72351) (xy 175.780321 -277.683782) (xy 175.832945 -277.650387)
			(xy 175.889339 -277.62385) (xy 175.948614 -277.60459) (xy 176.009835 -277.592911) (xy 176.072038 -277.588998)
			(xy 176.134241 -277.592911) (xy 176.195462 -277.60459) (xy 176.254737 -277.62385) (xy 176.311131 -277.650387)
			(xy 176.363755 -277.683782) (xy 176.411777 -277.72351) (xy 176.454442 -277.768944) (xy 176.491076 -277.819366)
			(xy 176.521102 -277.873983) (xy 176.544045 -277.931931) (xy 176.559545 -277.992299) (xy 176.567357 -278.054133)
			(xy 176.567846 -278.085296) (xy 180.531023 -278.085296) (xy 180.534958 -278.031525) (xy 180.546681 -277.978901)
			(xy 180.565941 -277.928544) (xy 180.592327 -277.881527) (xy 180.625279 -277.838854) (xy 180.664092 -277.801433)
			(xy 180.70794 -277.770063) (xy 180.755888 -277.745411) (xy 180.806915 -277.728003) (xy 180.859933 -277.71821)
			(xy 180.913812 -277.716241) (xy 180.967403 -277.722138) (xy 181.019564 -277.735774) (xy 181.069184 -277.756861)
			(xy 181.115205 -277.784947) (xy 181.156647 -277.819435) (xy 181.192625 -277.859589) (xy 181.222373 -277.904553)
			(xy 181.245258 -277.95337) (xy 181.26079 -278.004999) (xy 181.26864 -278.058339) (xy 181.269132 -278.085296)
			(xy 181.26864 -278.112253) (xy 181.26079 -278.165593) (xy 181.245258 -278.217222) (xy 181.222373 -278.266039)
			(xy 181.192625 -278.311003) (xy 181.156647 -278.351157) (xy 181.115205 -278.385645) (xy 181.069184 -278.413731)
			(xy 181.019564 -278.434818) (xy 180.967403 -278.448454) (xy 180.913812 -278.454351) (xy 180.859933 -278.452382)
			(xy 180.806915 -278.442589) (xy 180.755888 -278.425181) (xy 180.70794 -278.400529) (xy 180.664092 -278.369159)
			(xy 180.625279 -278.331738) (xy 180.592327 -278.289065) (xy 180.565941 -278.242048) (xy 180.546681 -278.191691)
			(xy 180.534958 -278.139067) (xy 180.531023 -278.085296) (xy 176.567846 -278.085296) (xy 176.567321 -278.116504)
			(xy 176.559504 -278.178427) (xy 176.543979 -278.238881) (xy 176.520992 -278.296909) (xy 176.490906 -278.351594)
			(xy 176.454197 -278.402073) (xy 176.411445 -278.447547) (xy 176.363325 -278.487298) (xy 176.337214 -278.504396)
			(xy 176.327054 -278.510746) (xy 176.314862 -278.530558) (xy 176.30521 -278.634698) (xy 176.313592 -278.656542)
			(xy 176.322482 -278.66467) (xy 176.340784 -278.682211) (xy 176.372929 -278.721408) (xy 176.399405 -278.764637)
			(xy 176.419714 -278.811084) (xy 176.433472 -278.859874) (xy 176.440421 -278.910088) (xy 176.440846 -278.935434)
			(xy 176.440411 -278.960751) (xy 176.433491 -279.01091) (xy 176.419774 -279.05965) (xy 176.399516 -279.106055)
			(xy 176.373099 -279.149252) (xy 176.34102 -279.188428) (xy 176.322736 -279.205944) (xy 176.313846 -279.214326)
			(xy 176.305464 -279.235916) (xy 176.314862 -279.340056) (xy 176.327054 -279.359868) (xy 176.337214 -279.366472)
			(xy 176.363345 -279.383523) (xy 176.411475 -279.423233) (xy 176.45424 -279.46867) (xy 176.490963 -279.519117)
			(xy 176.521064 -279.573773) (xy 176.544065 -279.631776) (xy 176.559605 -279.692207) (xy 176.567436 -279.754111)
			(xy 176.567435 -279.816508) (xy 176.559601 -279.878412) (xy 176.544059 -279.938842) (xy 176.521055 -279.996844)
			(xy 176.490953 -280.0515) (xy 176.454227 -280.101944) (xy 176.411461 -280.14738) (xy 176.363329 -280.187089)
			(xy 176.337214 -280.204164) (xy 176.327054 -280.210768) (xy 176.314862 -280.23058) (xy 176.305464 -280.33472)
			(xy 176.313846 -280.35631) (xy 176.322736 -280.364692) (xy 176.341023 -280.382205) (xy 176.373102 -280.421383)
			(xy 176.399519 -280.46458) (xy 176.41978 -280.510985) (xy 176.433502 -280.559725) (xy 176.440428 -280.609885)
			(xy 176.440846 -280.635202) (xy 176.440401 -280.660549) (xy 176.43347 -280.710767) (xy 176.419724 -280.759562)
			(xy 176.399423 -280.806014) (xy 176.372949 -280.849246) (xy 176.340803 -280.888444) (xy 176.322482 -280.905966)
			(xy 176.313592 -280.914094) (xy 176.30521 -280.935938) (xy 176.314862 -281.040078) (xy 176.327054 -281.05989)
			(xy 176.337214 -281.06624) (xy 176.363308 -281.083365) (xy 176.41143 -281.123114) (xy 176.454186 -281.168584)
			(xy 176.490901 -281.219058) (xy 176.520996 -281.273738) (xy 176.543995 -281.331762) (xy 176.559536 -281.392211)
			(xy 176.567371 -281.454132) (xy 176.567846 -281.48534) (xy 176.567341 -281.516536) (xy 176.559527 -281.578436)
			(xy 176.544003 -281.638865) (xy 176.521014 -281.696867) (xy 176.490924 -281.751523) (xy 176.454209 -281.801968)
			(xy 176.411451 -281.847404) (xy 176.363326 -281.887112) (xy 176.337214 -281.904186) (xy 176.327054 -281.91079)
			(xy 176.314862 -281.930602) (xy 176.305464 -282.034742) (xy 176.313846 -282.056332) (xy 176.322736 -282.064714)
			(xy 176.341034 -282.082217) (xy 176.373111 -282.121397) (xy 176.399527 -282.164596) (xy 176.419786 -282.211003)
			(xy 176.433506 -282.259745) (xy 176.440429 -282.309906) (xy 176.440846 -282.335224) (xy 176.440416 -282.360572)
			(xy 176.433481 -282.41079) (xy 176.419732 -282.459585) (xy 176.399429 -282.506037) (xy 176.372953 -282.549269)
			(xy 176.340804 -282.588467) (xy 176.322482 -282.605988) (xy 176.313592 -282.614116) (xy 176.30521 -282.63596)
			(xy 176.314862 -282.7401) (xy 176.327054 -282.759912) (xy 176.337214 -282.766262) (xy 176.363318 -282.783372)
			(xy 176.41144 -282.823123) (xy 176.454195 -282.868596) (xy 176.49091 -282.919072) (xy 176.521004 -282.973754)
			(xy 176.544001 -283.03178) (xy 176.559539 -283.092231) (xy 176.567373 -283.154154) (xy 176.567846 -283.185362)
			(xy 176.567357 -283.216525) (xy 176.559545 -283.278359) (xy 176.544045 -283.338727) (xy 176.521102 -283.396675)
			(xy 176.491076 -283.451292) (xy 176.454442 -283.501714) (xy 176.411777 -283.547148) (xy 176.363755 -283.586876)
			(xy 176.311131 -283.620271) (xy 176.254737 -283.646808) (xy 176.195462 -283.666068) (xy 176.134241 -283.677747)
			(xy 176.072038 -283.68166) (xy 176.009835 -283.677747) (xy 175.948614 -283.666068) (xy 175.889339 -283.646808)
			(xy 175.832945 -283.620271) (xy 175.780321 -283.586876) (xy 175.732299 -283.547148) (xy 175.689634 -283.501714)
			(xy 175.653 -283.451292) (xy 175.622974 -283.396675) (xy 175.600031 -283.338727) (xy 175.584531 -283.278359)
			(xy 175.576719 -283.216525) (xy 175.57623 -283.185362) (xy 172.340778 -283.185362) (xy 172.340351 -283.210679)
			(xy 172.333429 -283.260838) (xy 172.319709 -283.309578) (xy 172.299449 -283.355983) (xy 172.273031 -283.39918)
			(xy 172.240952 -283.438355) (xy 172.222668 -283.455872) (xy 172.213778 -283.464254) (xy 172.205396 -283.485844)
			(xy 172.214794 -283.589984) (xy 172.226986 -283.609796) (xy 172.237146 -283.6164) (xy 172.263239 -283.633503)
			(xy 172.311358 -283.673213) (xy 172.354114 -283.718648) (xy 172.39083 -283.76909) (xy 172.420926 -283.823739)
			(xy 172.443927 -283.881734) (xy 172.459468 -283.942157) (xy 172.467304 -284.004052) (xy 172.467778 -284.035246)
			(xy 174.318437 -284.035246) (xy 174.322372 -283.981475) (xy 174.334095 -283.928851) (xy 174.353355 -283.878494)
			(xy 174.379741 -283.831477) (xy 174.412693 -283.788804) (xy 174.451506 -283.751383) (xy 174.495354 -283.720013)
			(xy 174.543302 -283.695361) (xy 174.594329 -283.677953) (xy 174.647347 -283.66816) (xy 174.701226 -283.666191)
			(xy 174.754817 -283.672088) (xy 174.806978 -283.685724) (xy 174.856598 -283.706811) (xy 174.902619 -283.734897)
			(xy 174.944061 -283.769385) (xy 174.980039 -283.809539) (xy 175.009787 -283.854503) (xy 175.032672 -283.90332)
			(xy 175.048204 -283.954949) (xy 175.056054 -284.008289) (xy 175.056546 -284.035246) (xy 179.020216 -284.035246)
			(xy 179.020681 -284.004049) (xy 179.028498 -283.942146) (xy 179.044026 -283.881715) (xy 179.06702 -283.823712)
			(xy 179.097116 -283.769055) (xy 179.133836 -283.718611) (xy 179.176601 -283.673177) (xy 179.224732 -283.633472)
			(xy 179.250848 -283.6164) (xy 179.261008 -283.609796) (xy 179.2732 -283.589984) (xy 179.282598 -283.485844)
			(xy 179.274216 -283.464254) (xy 179.265326 -283.455872) (xy 179.247014 -283.438384) (xy 179.214939 -283.3992)
			(xy 179.188526 -283.355997) (xy 179.16827 -283.309587) (xy 179.154553 -283.260843) (xy 179.147632 -283.210681)
			(xy 179.147216 -283.185362) (xy 179.147617 -283.160013) (xy 179.154555 -283.109792) (xy 179.168308 -283.060996)
			(xy 179.188617 -283.014544) (xy 179.215099 -282.971313) (xy 179.247255 -282.932117) (xy 179.26558 -282.914598)
			(xy 179.27447 -282.90647) (xy 179.282852 -282.884626) (xy 179.2732 -282.780486) (xy 179.261008 -282.760674)
			(xy 179.250848 -282.754324) (xy 179.224728 -282.737237) (xy 179.176609 -282.697481) (xy 179.133855 -282.652005)
			(xy 179.097142 -282.601525) (xy 179.067051 -282.546839) (xy 179.044055 -282.488811) (xy 179.028519 -282.428358)
			(xy 179.020688 -282.366433) (xy 179.020216 -282.335224) (xy 179.020664 -282.304026) (xy 179.028483 -282.242123)
			(xy 179.044014 -282.181691) (xy 179.067011 -282.123688) (xy 179.097109 -282.069032) (xy 179.133832 -282.018587)
			(xy 179.176598 -281.973154) (xy 179.224731 -281.93345) (xy 179.250848 -281.916378) (xy 179.261008 -281.909774)
			(xy 179.2732 -281.889962) (xy 179.282598 -281.785822) (xy 179.274216 -281.764232) (xy 179.265326 -281.75585)
			(xy 179.247052 -281.738324) (xy 179.214974 -281.699148) (xy 179.188555 -281.655953) (xy 179.168293 -281.609551)
			(xy 179.154568 -281.560813) (xy 179.147637 -281.510657) (xy 179.147216 -281.48534) (xy 179.147602 -281.459991)
			(xy 179.154543 -281.409769) (xy 179.168299 -281.360973) (xy 179.188611 -281.314521) (xy 179.215096 -281.27129)
			(xy 179.247254 -281.232095) (xy 179.26558 -281.214576) (xy 179.27447 -281.206448) (xy 179.282852 -281.184604)
			(xy 179.2732 -281.080464) (xy 179.261008 -281.060652) (xy 179.250848 -281.054302) (xy 179.224718 -281.037229)
			(xy 179.176599 -280.997472) (xy 179.133845 -280.951993) (xy 179.097134 -280.901511) (xy 179.067043 -280.846823)
			(xy 179.04405 -280.788794) (xy 179.028516 -280.728338) (xy 179.020687 -280.666412) (xy 179.020216 -280.635202)
			(xy 179.020647 -280.604004) (xy 179.028469 -280.542099) (xy 179.044003 -280.481667) (xy 179.067002 -280.423664)
			(xy 179.097102 -280.369008) (xy 179.133827 -280.318564) (xy 179.176596 -280.273131) (xy 179.224731 -280.233428)
			(xy 179.250848 -280.216356) (xy 179.261008 -280.209752) (xy 179.2732 -280.18994) (xy 179.282598 -280.0858)
			(xy 179.274216 -280.06421) (xy 179.265326 -280.055828) (xy 179.245418 -280.036674) (xy 179.21095 -279.993503)
			(xy 179.183308 -279.945673) (xy 179.163108 -279.894256) (xy 179.150804 -279.8404) (xy 179.146671 -279.785312)
			(xy 179.150801 -279.730224) (xy 179.163101 -279.676368) (xy 179.183297 -279.624949) (xy 179.210936 -279.577117)
			(xy 179.245401 -279.533944) (xy 179.265326 -279.514808) (xy 179.274216 -279.506426) (xy 179.282598 -279.484836)
			(xy 179.2732 -279.380696) (xy 179.261008 -279.360884) (xy 179.250848 -279.35428) (xy 179.224744 -279.337193)
			(xy 179.176625 -279.29748) (xy 179.13387 -279.252042) (xy 179.097155 -279.201599) (xy 179.06706 -279.146947)
			(xy 179.044062 -279.08895) (xy 179.028523 -279.028526) (xy 179.020689 -278.966629) (xy 179.020216 -278.935434)
			(xy 179.020705 -278.904271) (xy 179.028517 -278.842437) (xy 179.044017 -278.782069) (xy 179.06696 -278.724121)
			(xy 179.096986 -278.669504) (xy 179.13362 -278.619082) (xy 179.176285 -278.573648) (xy 179.224307 -278.53392)
			(xy 179.276931 -278.500525) (xy 179.333325 -278.473988) (xy 179.3926 -278.454728) (xy 179.453821 -278.443049)
			(xy 179.516024 -278.439136) (xy 179.578227 -278.443049) (xy 179.639448 -278.454728) (xy 179.698723 -278.473988)
			(xy 179.755117 -278.500525) (xy 179.807741 -278.53392) (xy 179.855763 -278.573648) (xy 179.898428 -278.619082)
			(xy 179.935062 -278.669504) (xy 179.965088 -278.724121) (xy 179.988031 -278.782069) (xy 180.003531 -278.842437)
			(xy 180.011343 -278.904271) (xy 180.011832 -278.935434) (xy 180.011329 -278.96663) (xy 180.003515 -279.02853)
			(xy 179.987991 -279.08896) (xy 179.965002 -279.146962) (xy 179.934912 -279.201618) (xy 179.898197 -279.252063)
			(xy 179.855438 -279.297499) (xy 179.807313 -279.337206) (xy 179.7812 -279.35428) (xy 179.77104 -279.360884)
			(xy 179.758848 -279.380696) (xy 179.74945 -279.484836) (xy 179.757832 -279.506426) (xy 179.766722 -279.514808)
			(xy 179.786664 -279.533927) (xy 179.821127 -279.577105) (xy 179.848765 -279.624941) (xy 179.868959 -279.676363)
			(xy 179.881258 -279.730221) (xy 179.885388 -279.785312) (xy 179.881255 -279.840403) (xy 179.868952 -279.894261)
			(xy 179.848754 -279.945682) (xy 179.821113 -279.993515) (xy 179.786647 -280.036691) (xy 179.766722 -280.055828)
			(xy 179.757832 -280.06421) (xy 179.74945 -280.0858) (xy 179.758848 -280.18994) (xy 179.77104 -280.209752)
			(xy 179.7812 -280.216356) (xy 179.807331 -280.233403) (xy 179.855448 -280.273123) (xy 179.8982 -280.318567)
			(xy 179.934912 -280.369017) (xy 179.965003 -280.423675) (xy 179.987997 -280.481676) (xy 180.003532 -280.542105)
			(xy 180.011361 -280.604005) (xy 180.011832 -280.635202) (xy 180.011319 -280.66641) (xy 180.0035 -280.728334)
			(xy 179.987974 -280.788788) (xy 179.964985 -280.846817) (xy 179.934898 -280.901502) (xy 179.898187 -280.951981)
			(xy 179.855433 -280.997454) (xy 179.807312 -281.037205) (xy 179.7812 -281.054302) (xy 179.77104 -281.060652)
			(xy 179.758848 -281.080464) (xy 179.749196 -281.184604) (xy 179.757578 -281.206448) (xy 179.766468 -281.214576)
			(xy 179.78477 -281.232117) (xy 179.816916 -281.271314) (xy 179.843392 -281.314543) (xy 179.863701 -281.360989)
			(xy 179.877459 -281.409779) (xy 179.884408 -281.459994) (xy 179.884832 -281.48534) (xy 179.884405 -281.510657)
			(xy 179.877485 -281.560817) (xy 179.863766 -281.609558) (xy 179.843506 -281.655963) (xy 179.817088 -281.699159)
			(xy 179.785007 -281.738334) (xy 179.766722 -281.75585) (xy 179.757832 -281.764232) (xy 179.74945 -281.785822)
			(xy 179.758848 -281.889962) (xy 179.77104 -281.909774) (xy 179.7812 -281.916378) (xy 179.807295 -281.933477)
			(xy 179.855412 -281.97319) (xy 179.898166 -282.018626) (xy 179.934881 -282.069069) (xy 179.964976 -282.123719)
			(xy 179.987977 -282.181713) (xy 180.003519 -282.242135) (xy 180.011356 -282.30403) (xy 180.011832 -282.335224)
			(xy 180.011336 -282.366433) (xy 180.003514 -282.428358) (xy 179.987985 -282.488812) (xy 179.964994 -282.54684)
			(xy 179.934905 -282.601526) (xy 179.898192 -282.652004) (xy 179.855436 -282.697477) (xy 179.807313 -282.737227)
			(xy 179.7812 -282.754324) (xy 179.77104 -282.760674) (xy 179.758848 -282.780486) (xy 179.749196 -282.884626)
			(xy 179.757578 -282.90647) (xy 179.766468 -282.914598) (xy 179.784781 -282.932128) (xy 179.816925 -282.971327)
			(xy 179.843401 -283.014558) (xy 179.863707 -283.061007) (xy 179.877463 -283.109799) (xy 179.884409 -283.160015)
			(xy 179.884832 -283.185362) (xy 183.120284 -283.185362) (xy 183.120762 -283.154153) (xy 183.128585 -283.092227)
			(xy 183.144117 -283.031772) (xy 183.16711 -282.973743) (xy 183.197202 -282.919057) (xy 183.233918 -282.868579)
			(xy 183.276676 -282.823107) (xy 183.324802 -282.783358) (xy 183.350916 -282.766262) (xy 183.361076 -282.759912)
			(xy 183.373268 -282.7401) (xy 183.38292 -282.63596) (xy 183.374538 -282.614116) (xy 183.365648 -282.605988)
			(xy 183.347332 -282.588462) (xy 183.315187 -282.549262) (xy 183.288712 -282.50603) (xy 183.268405 -282.45958)
			(xy 183.25465 -282.410788) (xy 183.247706 -282.360571) (xy 183.247284 -282.335224) (xy 183.247713 -282.309907)
			(xy 183.254637 -282.259749) (xy 183.268357 -282.211009) (xy 183.288616 -282.164604) (xy 183.315033 -282.121408)
			(xy 183.347111 -282.082231) (xy 183.365394 -282.064714) (xy 183.374284 -282.056332) (xy 183.382666 -282.034742)
			(xy 183.373268 -281.930602) (xy 183.361076 -281.91079) (xy 183.350916 -281.904186) (xy 183.324808 -281.887106)
			(xy 183.27669 -281.847391) (xy 183.233937 -281.801952) (xy 183.197222 -281.751507) (xy 183.167128 -281.696854)
			(xy 183.14413 -281.638857) (xy 183.128591 -281.578432) (xy 183.120758 -281.516535) (xy 183.120284 -281.48534)
			(xy 183.120745 -281.45413) (xy 183.128571 -281.392204) (xy 183.144105 -281.331748) (xy 183.167101 -281.273719)
			(xy 183.197195 -281.219034) (xy 183.233913 -281.168556) (xy 183.276673 -281.123084) (xy 183.324801 -281.083336)
			(xy 183.350916 -281.06624) (xy 183.361076 -281.05989) (xy 183.373268 -281.040078) (xy 183.38292 -280.935938)
			(xy 183.374538 -280.914094) (xy 183.365648 -280.905966) (xy 183.347321 -280.88845) (xy 183.315177 -280.849248)
			(xy 183.288703 -280.806014) (xy 183.268399 -280.759562) (xy 183.254646 -280.710768) (xy 183.247704 -280.66055)
			(xy 183.247284 -280.635202) (xy 183.247698 -280.609884) (xy 183.254625 -280.559725) (xy 183.268348 -280.510985)
			(xy 183.28861 -280.464581) (xy 183.315029 -280.421385) (xy 183.347109 -280.382209) (xy 183.365394 -280.364692)
			(xy 183.374284 -280.35631) (xy 183.382666 -280.33472) (xy 183.373268 -280.23058) (xy 183.361076 -280.210768)
			(xy 183.350916 -280.204164) (xy 183.324817 -280.187065) (xy 183.276686 -280.147361) (xy 183.233919 -280.101928)
			(xy 183.197194 -280.051487) (xy 183.167091 -279.996834) (xy 183.144087 -279.938835) (xy 183.128545 -279.878408)
			(xy 183.120712 -279.816507) (xy 183.120711 -279.754112) (xy 183.128542 -279.692211) (xy 183.144081 -279.631783)
			(xy 183.167083 -279.573783) (xy 183.197184 -279.519129) (xy 183.233907 -279.468687) (xy 183.276672 -279.423253)
			(xy 183.324802 -279.383546) (xy 183.350916 -279.366472) (xy 183.361076 -279.359868) (xy 183.373268 -279.340056)
			(xy 183.382666 -279.235916) (xy 183.374284 -279.214326) (xy 183.365394 -279.205944) (xy 183.34713 -279.188407)
			(xy 183.315048 -279.149235) (xy 183.288627 -279.106043) (xy 183.268362 -279.059643) (xy 183.254636 -279.010906)
			(xy 183.247705 -278.96075) (xy 183.247284 -278.935434) (xy 183.247677 -278.910085) (xy 183.254618 -278.859864)
			(xy 183.268373 -278.811068) (xy 183.288684 -278.764616) (xy 183.315167 -278.721385) (xy 183.347323 -278.68219)
			(xy 183.365648 -278.66467) (xy 183.374538 -278.656542) (xy 183.38292 -278.634698) (xy 183.373268 -278.530558)
			(xy 183.361076 -278.510746) (xy 183.350916 -278.504396) (xy 183.324799 -278.487304) (xy 183.276677 -278.447551)
			(xy 183.233921 -278.402077) (xy 183.197206 -278.351598) (xy 183.167114 -278.296913) (xy 183.144119 -278.238885)
			(xy 183.128584 -278.17843) (xy 183.120755 -278.116505) (xy 183.120284 -278.085296) (xy 183.120773 -278.054133)
			(xy 183.128585 -277.992299) (xy 183.144085 -277.931931) (xy 183.167028 -277.873983) (xy 183.197054 -277.819366)
			(xy 183.233688 -277.768944) (xy 183.276353 -277.72351) (xy 183.324375 -277.683782) (xy 183.376999 -277.650387)
			(xy 183.433393 -277.62385) (xy 183.492668 -277.60459) (xy 183.553889 -277.592911) (xy 183.616092 -277.588998)
			(xy 183.678295 -277.592911) (xy 183.739516 -277.60459) (xy 183.798791 -277.62385) (xy 183.855185 -277.650387)
			(xy 183.907809 -277.683782) (xy 183.955831 -277.72351) (xy 183.998496 -277.768944) (xy 184.03513 -277.819366)
			(xy 184.065156 -277.873983) (xy 184.088099 -277.931931) (xy 184.103599 -277.992299) (xy 184.111411 -278.054133)
			(xy 184.1119 -278.085296) (xy 184.111397 -278.116505) (xy 184.103578 -278.17843) (xy 184.088051 -278.238885)
			(xy 184.065062 -278.296913) (xy 184.034973 -278.351599) (xy 183.998261 -278.402078) (xy 183.955505 -278.447551)
			(xy 183.907381 -278.487299) (xy 183.881268 -278.504396) (xy 183.871108 -278.510746) (xy 183.858916 -278.530558)
			(xy 183.849264 -278.634698) (xy 183.857646 -278.656542) (xy 183.866536 -278.66467) (xy 183.884829 -278.68222)
			(xy 183.916977 -278.721414) (xy 183.943455 -278.764641) (xy 183.963766 -278.811086) (xy 183.977525 -278.859875)
			(xy 183.984475 -278.910088) (xy 183.9849 -278.935434) (xy 183.984448 -278.96075) (xy 183.977529 -279.010908)
			(xy 183.963814 -279.059647) (xy 183.943559 -279.106052) (xy 183.917146 -279.149249) (xy 183.885072 -279.188426)
			(xy 183.86679 -279.205944) (xy 183.8579 -279.214326) (xy 183.849518 -279.235916) (xy 183.858916 -279.340056)
			(xy 183.871108 -279.359868) (xy 183.881268 -279.366472) (xy 183.907397 -279.383524) (xy 183.955522 -279.423237)
			(xy 183.998282 -279.468676) (xy 184.035001 -279.519123) (xy 184.065098 -279.573779) (xy 184.088097 -279.631781)
			(xy 184.103635 -279.69221) (xy 184.111465 -279.754112) (xy 184.111464 -279.816507) (xy 184.103631 -279.878409)
			(xy 184.088091 -279.938838) (xy 184.06509 -279.996838) (xy 184.034991 -280.051493) (xy 183.99827 -280.101939)
			(xy 183.955508 -280.147376) (xy 183.907381 -280.187087) (xy 183.881268 -280.204164) (xy 183.871108 -280.210768)
			(xy 183.858916 -280.23058) (xy 183.849518 -280.33472) (xy 183.8579 -280.35631) (xy 183.86679 -280.364692)
			(xy 183.885088 -280.382195) (xy 183.917163 -280.421376) (xy 183.943578 -280.464576) (xy 183.963836 -280.510983)
			(xy 183.977557 -280.559724) (xy 183.984482 -280.609884) (xy 183.9849 -280.635202) (xy 183.98447 -280.66055)
			(xy 183.977537 -280.710769) (xy 183.96379 -280.759565) (xy 183.943486 -280.806017) (xy 183.917009 -280.849249)
			(xy 183.884859 -280.888446) (xy 183.866536 -280.905966) (xy 183.857646 -280.914094) (xy 183.849264 -280.935938)
			(xy 183.858916 -281.040078) (xy 183.871108 -281.05989) (xy 183.881268 -281.06624) (xy 183.907352 -281.083381)
			(xy 183.955475 -281.123126) (xy 183.998233 -281.168593) (xy 184.034951 -281.219064) (xy 184.065047 -281.273743)
			(xy 184.088048 -281.331764) (xy 184.103589 -281.392213) (xy 184.111425 -281.454133) (xy 184.1119 -281.48534)
			(xy 184.111416 -281.516537) (xy 184.103602 -281.578439) (xy 184.088076 -281.638869) (xy 184.065084 -281.696872)
			(xy 184.034991 -281.751528) (xy 183.998273 -281.801973) (xy 183.955511 -281.847408) (xy 183.907382 -281.887113)
			(xy 183.881268 -281.904186) (xy 183.871108 -281.91079) (xy 183.858916 -281.930602) (xy 183.849518 -282.034742)
			(xy 183.8579 -282.056332) (xy 183.86679 -282.064714) (xy 183.885098 -282.082206) (xy 183.917173 -282.12139)
			(xy 183.943586 -282.164592) (xy 183.963842 -282.211001) (xy 183.977561 -282.259744) (xy 183.984483 -282.309905)
			(xy 183.9849 -282.335224) (xy 183.984484 -282.360572) (xy 183.977549 -282.410792) (xy 183.963798 -282.459588)
			(xy 183.943492 -282.50604) (xy 183.917013 -282.549272) (xy 183.88486 -282.588468) (xy 183.866536 -282.605988)
			(xy 183.857646 -282.614116) (xy 183.849264 -282.63596) (xy 183.858916 -282.7401) (xy 183.871108 -282.759912)
			(xy 183.881268 -282.766262) (xy 183.907362 -282.783388) (xy 183.955485 -282.823135) (xy 183.998243 -282.868604)
			(xy 184.034959 -282.919078) (xy 184.065055 -282.973759) (xy 184.088054 -283.031782) (xy 184.103593 -283.092232)
			(xy 184.111427 -283.154154) (xy 184.1119 -283.185362) (xy 184.111411 -283.216525) (xy 184.103599 -283.278359)
			(xy 184.088099 -283.338727) (xy 184.065156 -283.396675) (xy 184.03513 -283.451292) (xy 183.998496 -283.501714)
			(xy 183.955831 -283.547148) (xy 183.907809 -283.586876) (xy 183.855185 -283.620271) (xy 183.798791 -283.646808)
			(xy 183.739516 -283.666068) (xy 183.678295 -283.677747) (xy 183.616092 -283.68166) (xy 183.553889 -283.677747)
			(xy 183.492668 -283.666068) (xy 183.433393 -283.646808) (xy 183.376999 -283.620271) (xy 183.324375 -283.586876)
			(xy 183.276353 -283.547148) (xy 183.233688 -283.501714) (xy 183.197054 -283.451292) (xy 183.167028 -283.396675)
			(xy 183.144085 -283.338727) (xy 183.128585 -283.278359) (xy 183.120773 -283.216525) (xy 183.120284 -283.185362)
			(xy 179.884832 -283.185362) (xy 179.88442 -283.21068) (xy 179.877496 -283.26084) (xy 179.863775 -283.309581)
			(xy 179.843512 -283.355986) (xy 179.817091 -283.399182) (xy 179.785008 -283.438357) (xy 179.766722 -283.455872)
			(xy 179.757832 -283.464254) (xy 179.74945 -283.485844) (xy 179.758848 -283.589984) (xy 179.77104 -283.609796)
			(xy 179.7812 -283.6164) (xy 179.807305 -283.633484) (xy 179.855422 -283.673199) (xy 179.898176 -283.718638)
			(xy 179.93489 -283.769082) (xy 179.964984 -283.823734) (xy 179.987983 -283.881731) (xy 180.003522 -283.942155)
			(xy 180.011358 -284.004051) (xy 180.011832 -284.035246) (xy 181.862491 -284.035246) (xy 181.866426 -283.981475)
			(xy 181.878149 -283.928851) (xy 181.897409 -283.878494) (xy 181.923795 -283.831477) (xy 181.956747 -283.788804)
			(xy 181.99556 -283.751383) (xy 182.039408 -283.720013) (xy 182.087356 -283.695361) (xy 182.138383 -283.677953)
			(xy 182.191401 -283.66816) (xy 182.24528 -283.666191) (xy 182.298871 -283.672088) (xy 182.351032 -283.685724)
			(xy 182.400652 -283.706811) (xy 182.446673 -283.734897) (xy 182.488115 -283.769385) (xy 182.524093 -283.809539)
			(xy 182.553841 -283.854503) (xy 182.576726 -283.90332) (xy 182.592258 -283.954949) (xy 182.600108 -284.008289)
			(xy 182.6006 -284.035246) (xy 182.600108 -284.062203) (xy 182.592258 -284.115543) (xy 182.576726 -284.167172)
			(xy 182.553841 -284.215989) (xy 182.524093 -284.260953) (xy 182.488115 -284.301107) (xy 182.446673 -284.335595)
			(xy 182.400652 -284.363681) (xy 182.351032 -284.384768) (xy 182.298871 -284.398404) (xy 182.24528 -284.404301)
			(xy 182.191401 -284.402332) (xy 182.138383 -284.392539) (xy 182.087356 -284.375131) (xy 182.039408 -284.350479)
			(xy 181.99556 -284.319109) (xy 181.956747 -284.281688) (xy 181.923795 -284.239015) (xy 181.897409 -284.191998)
			(xy 181.878149 -284.141641) (xy 181.866426 -284.089017) (xy 181.862491 -284.035246) (xy 180.011832 -284.035246)
			(xy 180.011343 -284.066409) (xy 180.003531 -284.128243) (xy 179.988031 -284.188611) (xy 179.965088 -284.246559)
			(xy 179.935062 -284.301176) (xy 179.898428 -284.351598) (xy 179.855763 -284.397032) (xy 179.807741 -284.43676)
			(xy 179.755117 -284.470155) (xy 179.698723 -284.496692) (xy 179.639448 -284.515952) (xy 179.578227 -284.527631)
			(xy 179.516024 -284.531544) (xy 179.453821 -284.527631) (xy 179.3926 -284.515952) (xy 179.333325 -284.496692)
			(xy 179.276931 -284.470155) (xy 179.224307 -284.43676) (xy 179.176285 -284.397032) (xy 179.13362 -284.351598)
			(xy 179.096986 -284.301176) (xy 179.06696 -284.246559) (xy 179.044017 -284.188611) (xy 179.028517 -284.128243)
			(xy 179.020705 -284.066409) (xy 179.020216 -284.035246) (xy 175.056546 -284.035246) (xy 175.056054 -284.062203)
			(xy 175.048204 -284.115543) (xy 175.032672 -284.167172) (xy 175.009787 -284.215989) (xy 174.980039 -284.260953)
			(xy 174.944061 -284.301107) (xy 174.902619 -284.335595) (xy 174.856598 -284.363681) (xy 174.806978 -284.384768)
			(xy 174.754817 -284.398404) (xy 174.701226 -284.404301) (xy 174.647347 -284.402332) (xy 174.594329 -284.392539)
			(xy 174.543302 -284.375131) (xy 174.495354 -284.350479) (xy 174.451506 -284.319109) (xy 174.412693 -284.281688)
			(xy 174.379741 -284.239015) (xy 174.353355 -284.191998) (xy 174.334095 -284.141641) (xy 174.322372 -284.089017)
			(xy 174.318437 -284.035246) (xy 172.467778 -284.035246) (xy 172.467289 -284.066409) (xy 172.459477 -284.128243)
			(xy 172.443977 -284.188611) (xy 172.421034 -284.246559) (xy 172.391008 -284.301176) (xy 172.354374 -284.351598)
			(xy 172.311709 -284.397032) (xy 172.263687 -284.43676) (xy 172.211063 -284.470155) (xy 172.154669 -284.496692)
			(xy 172.095394 -284.515952) (xy 172.034173 -284.527631) (xy 171.97197 -284.531544) (xy 171.909767 -284.527631)
			(xy 171.848546 -284.515952) (xy 171.789271 -284.496692) (xy 171.732877 -284.470155) (xy 171.680253 -284.43676)
			(xy 171.632231 -284.397032) (xy 171.589566 -284.351598) (xy 171.552932 -284.301176) (xy 171.522906 -284.246559)
			(xy 171.499963 -284.188611) (xy 171.484463 -284.128243) (xy 171.476651 -284.066409) (xy 171.476162 -284.035246)
			(xy 167.512492 -284.035246) (xy 167.512 -284.062203) (xy 167.50415 -284.115543) (xy 167.488618 -284.167172)
			(xy 167.465733 -284.215989) (xy 167.435985 -284.260953) (xy 167.400007 -284.301107) (xy 167.358565 -284.335595)
			(xy 167.312544 -284.363681) (xy 167.262924 -284.384768) (xy 167.210763 -284.398404) (xy 167.157172 -284.404301)
			(xy 167.103293 -284.402332) (xy 167.050275 -284.392539) (xy 166.999248 -284.375131) (xy 166.9513 -284.350479)
			(xy 166.907452 -284.319109) (xy 166.868639 -284.281688) (xy 166.835687 -284.239015) (xy 166.809301 -284.191998)
			(xy 166.790041 -284.141641) (xy 166.778318 -284.089017) (xy 166.774383 -284.035246) (xy 145.646477 -284.035246)
			(xy 145.638123 -284.04327) (xy 145.59762 -284.071226) (xy 145.553158 -284.092324) (xy 145.505887 -284.106016)
			(xy 145.457032 -284.111948) (xy 145.407857 -284.109967) (xy 145.359638 -284.100123) (xy 145.313622 -284.082671)
			(xy 145.271001 -284.058064) (xy 145.23288 -284.026939) (xy 145.200245 -283.990102) (xy 145.173942 -283.948506)
			(xy 145.154651 -283.90323) (xy 145.142874 -283.855446) (xy 145.138914 -283.806392) (xy 143.869918 -283.806392)
			(xy 143.869423 -283.830999) (xy 143.861528 -283.879576) (xy 143.845944 -283.926257) (xy 143.823073 -283.969834)
			(xy 143.793508 -284.009178) (xy 143.758015 -284.04327) (xy 143.717512 -284.071226) (xy 143.67305 -284.092324)
			(xy 143.625779 -284.106016) (xy 143.576924 -284.111948) (xy 143.527749 -284.109967) (xy 143.47953 -284.100123)
			(xy 143.433514 -284.082671) (xy 143.390893 -284.058064) (xy 143.352772 -284.026939) (xy 143.320137 -283.990102)
			(xy 143.293834 -283.948506) (xy 143.274543 -283.90323) (xy 143.262766 -283.855446) (xy 143.258806 -283.806392)
			(xy 142.940532 -283.806392) (xy 142.94002 -283.831838) (xy 142.931856 -283.882072) (xy 142.91574 -283.930346)
			(xy 142.892089 -283.975409) (xy 142.861516 -284.016095) (xy 142.824812 -284.05135) (xy 142.782928 -284.08026)
			(xy 142.736949 -284.102077) (xy 142.688065 -284.116237) (xy 142.637544 -284.122371) (xy 142.586692 -284.120322)
			(xy 142.536828 -284.110142) (xy 142.489242 -284.092095) (xy 142.445168 -284.066649) (xy 142.405746 -284.034462)
			(xy 142.371998 -283.996368) (xy 142.344797 -283.953354) (xy 142.324849 -283.906534) (xy 142.31267 -283.85712)
			(xy 142.308575 -283.806392) (xy 142.000478 -283.806392) (xy 141.999966 -283.831838) (xy 141.991802 -283.882072)
			(xy 141.975686 -283.930346) (xy 141.952035 -283.975409) (xy 141.921462 -284.016095) (xy 141.884758 -284.05135)
			(xy 141.842874 -284.08026) (xy 141.796895 -284.102077) (xy 141.748011 -284.116237) (xy 141.69749 -284.122371)
			(xy 141.646638 -284.120322) (xy 141.596774 -284.110142) (xy 141.549188 -284.092095) (xy 141.505114 -284.066649)
			(xy 141.465692 -284.034462) (xy 141.431944 -283.996368) (xy 141.404743 -283.953354) (xy 141.384795 -283.906534)
			(xy 141.372616 -283.85712) (xy 141.368521 -283.806392) (xy 141.05001 -283.806392) (xy 141.049515 -283.830999)
			(xy 141.04162 -283.879576) (xy 141.026036 -283.926257) (xy 141.003165 -283.969834) (xy 140.9736 -284.009178)
			(xy 140.938107 -284.04327) (xy 140.897604 -284.071226) (xy 140.853142 -284.092324) (xy 140.805871 -284.106016)
			(xy 140.757016 -284.111948) (xy 140.707841 -284.109967) (xy 140.659622 -284.100123) (xy 140.613606 -284.082671)
			(xy 140.570985 -284.058064) (xy 140.532864 -284.026939) (xy 140.500229 -283.990102) (xy 140.473926 -283.948506)
			(xy 140.454635 -283.90323) (xy 140.442858 -283.855446) (xy 140.438898 -283.806392) (xy 140.12037 -283.806392)
			(xy 140.119858 -283.831838) (xy 140.111694 -283.882072) (xy 140.095578 -283.930346) (xy 140.071927 -283.975409)
			(xy 140.041354 -284.016095) (xy 140.00465 -284.05135) (xy 139.962766 -284.08026) (xy 139.916787 -284.102077)
			(xy 139.867903 -284.116237) (xy 139.817382 -284.122371) (xy 139.76653 -284.120322) (xy 139.716666 -284.110142)
			(xy 139.66908 -284.092095) (xy 139.625006 -284.066649) (xy 139.585584 -284.034462) (xy 139.551836 -283.996368)
			(xy 139.524635 -283.953354) (xy 139.504687 -283.906534) (xy 139.492508 -283.85712) (xy 139.488413 -283.806392)
			(xy 139.170156 -283.806392) (xy 139.169661 -283.830999) (xy 139.161766 -283.879576) (xy 139.146182 -283.926257)
			(xy 139.123311 -283.969834) (xy 139.093746 -284.009178) (xy 139.058253 -284.04327) (xy 139.01775 -284.071226)
			(xy 138.973288 -284.092324) (xy 138.926017 -284.106016) (xy 138.877162 -284.111948) (xy 138.827987 -284.109967)
			(xy 138.779768 -284.100123) (xy 138.733752 -284.082671) (xy 138.691131 -284.058064) (xy 138.65301 -284.026939)
			(xy 138.620375 -283.990102) (xy 138.594072 -283.948506) (xy 138.574781 -283.90323) (xy 138.563004 -283.855446)
			(xy 138.559044 -283.806392) (xy 138.240516 -283.806392) (xy 138.240004 -283.831838) (xy 138.23184 -283.882072)
			(xy 138.215724 -283.930346) (xy 138.192073 -283.975409) (xy 138.1615 -284.016095) (xy 138.124796 -284.05135)
			(xy 138.082912 -284.08026) (xy 138.036933 -284.102077) (xy 137.988049 -284.116237) (xy 137.937528 -284.122371)
			(xy 137.886676 -284.120322) (xy 137.836812 -284.110142) (xy 137.789226 -284.092095) (xy 137.745152 -284.066649)
			(xy 137.70573 -284.034462) (xy 137.671982 -283.996368) (xy 137.644781 -283.953354) (xy 137.624833 -283.906534)
			(xy 137.612654 -283.85712) (xy 137.608559 -283.806392) (xy 137.290048 -283.806392) (xy 137.289553 -283.830999)
			(xy 137.281658 -283.879576) (xy 137.266074 -283.926257) (xy 137.243203 -283.969834) (xy 137.213638 -284.009178)
			(xy 137.178145 -284.04327) (xy 137.137642 -284.071226) (xy 137.09318 -284.092324) (xy 137.045909 -284.106016)
			(xy 136.997054 -284.111948) (xy 136.947879 -284.109967) (xy 136.89966 -284.100123) (xy 136.853644 -284.082671)
			(xy 136.811023 -284.058064) (xy 136.772902 -284.026939) (xy 136.740267 -283.990102) (xy 136.713964 -283.948506)
			(xy 136.694673 -283.90323) (xy 136.682896 -283.855446) (xy 136.678936 -283.806392) (xy 136.360408 -283.806392)
			(xy 136.359896 -283.831838) (xy 136.351732 -283.882072) (xy 136.335616 -283.930346) (xy 136.311965 -283.975409)
			(xy 136.281392 -284.016095) (xy 136.244688 -284.05135) (xy 136.202804 -284.08026) (xy 136.156825 -284.102077)
			(xy 136.107941 -284.116237) (xy 136.05742 -284.122371) (xy 136.006568 -284.120322) (xy 135.956704 -284.110142)
			(xy 135.909118 -284.092095) (xy 135.865044 -284.066649) (xy 135.825622 -284.034462) (xy 135.791874 -283.996368)
			(xy 135.764673 -283.953354) (xy 135.744725 -283.906534) (xy 135.732546 -283.85712) (xy 135.728451 -283.806392)
			(xy 135.420354 -283.806392) (xy 135.419842 -283.831838) (xy 135.411678 -283.882072) (xy 135.395562 -283.930346)
			(xy 135.371911 -283.975409) (xy 135.341338 -284.016095) (xy 135.304634 -284.05135) (xy 135.26275 -284.08026)
			(xy 135.216771 -284.102077) (xy 135.167887 -284.116237) (xy 135.117366 -284.122371) (xy 135.066514 -284.120322)
			(xy 135.01665 -284.110142) (xy 134.969064 -284.092095) (xy 134.92499 -284.066649) (xy 134.885568 -284.034462)
			(xy 134.85182 -283.996368) (xy 134.824619 -283.953354) (xy 134.804671 -283.906534) (xy 134.792492 -283.85712)
			(xy 134.788397 -283.806392) (xy 134.47014 -283.806392) (xy 134.469645 -283.830999) (xy 134.46175 -283.879576)
			(xy 134.446166 -283.926257) (xy 134.423295 -283.969834) (xy 134.39373 -284.009178) (xy 134.358237 -284.04327)
			(xy 134.317734 -284.071226) (xy 134.273272 -284.092324) (xy 134.226001 -284.106016) (xy 134.177146 -284.111948)
			(xy 134.127971 -284.109967) (xy 134.079752 -284.100123) (xy 134.033736 -284.082671) (xy 133.991115 -284.058064)
			(xy 133.952994 -284.026939) (xy 133.920359 -283.990102) (xy 133.894056 -283.948506) (xy 133.874765 -283.90323)
			(xy 133.862988 -283.855446) (xy 133.859028 -283.806392) (xy 133.5405 -283.806392) (xy 133.539988 -283.831838)
			(xy 133.531824 -283.882072) (xy 133.515708 -283.930346) (xy 133.492057 -283.975409) (xy 133.461484 -284.016095)
			(xy 133.42478 -284.05135) (xy 133.382896 -284.08026) (xy 133.336917 -284.102077) (xy 133.288033 -284.116237)
			(xy 133.237512 -284.122371) (xy 133.18666 -284.120322) (xy 133.136796 -284.110142) (xy 133.08921 -284.092095)
			(xy 133.045136 -284.066649) (xy 133.005714 -284.034462) (xy 132.971966 -283.996368) (xy 132.944765 -283.953354)
			(xy 132.924817 -283.906534) (xy 132.912638 -283.85712) (xy 132.908543 -283.806392) (xy 132.590032 -283.806392)
			(xy 132.589537 -283.830999) (xy 132.581642 -283.879576) (xy 132.566058 -283.926257) (xy 132.543187 -283.969834)
			(xy 132.513622 -284.009178) (xy 132.478129 -284.04327) (xy 132.437626 -284.071226) (xy 132.393164 -284.092324)
			(xy 132.345893 -284.106016) (xy 132.297038 -284.111948) (xy 132.247863 -284.109967) (xy 132.199644 -284.100123)
			(xy 132.153628 -284.082671) (xy 132.111007 -284.058064) (xy 132.072886 -284.026939) (xy 132.040251 -283.990102)
			(xy 132.013948 -283.948506) (xy 131.994657 -283.90323) (xy 131.98288 -283.855446) (xy 131.97892 -283.806392)
			(xy 131.660392 -283.806392) (xy 131.65988 -283.831838) (xy 131.651716 -283.882072) (xy 131.6356 -283.930346)
			(xy 131.611949 -283.975409) (xy 131.581376 -284.016095) (xy 131.544672 -284.05135) (xy 131.502788 -284.08026)
			(xy 131.456809 -284.102077) (xy 131.407925 -284.116237) (xy 131.357404 -284.122371) (xy 131.306552 -284.120322)
			(xy 131.256688 -284.110142) (xy 131.209102 -284.092095) (xy 131.165028 -284.066649) (xy 131.125606 -284.034462)
			(xy 131.091858 -283.996368) (xy 131.064657 -283.953354) (xy 131.044709 -283.906534) (xy 131.03253 -283.85712)
			(xy 131.028435 -283.806392) (xy 130.710178 -283.806392) (xy 130.709683 -283.830999) (xy 130.701788 -283.879576)
			(xy 130.686204 -283.926257) (xy 130.663333 -283.969834) (xy 130.633768 -284.009178) (xy 130.598275 -284.04327)
			(xy 130.557772 -284.071226) (xy 130.51331 -284.092324) (xy 130.466039 -284.106016) (xy 130.417184 -284.111948)
			(xy 130.368009 -284.109967) (xy 130.31979 -284.100123) (xy 130.273774 -284.082671) (xy 130.231153 -284.058064)
			(xy 130.193032 -284.026939) (xy 130.160397 -283.990102) (xy 130.134094 -283.948506) (xy 130.114803 -283.90323)
			(xy 130.103026 -283.855446) (xy 130.099066 -283.806392) (xy 129.780538 -283.806392) (xy 129.780026 -283.831838)
			(xy 129.771862 -283.882072) (xy 129.755746 -283.930346) (xy 129.732095 -283.975409) (xy 129.701522 -284.016095)
			(xy 129.664818 -284.05135) (xy 129.622934 -284.08026) (xy 129.576955 -284.102077) (xy 129.528071 -284.116237)
			(xy 129.47755 -284.122371) (xy 129.426698 -284.120322) (xy 129.376834 -284.110142) (xy 129.329248 -284.092095)
			(xy 129.285174 -284.066649) (xy 129.245752 -284.034462) (xy 129.212004 -283.996368) (xy 129.184803 -283.953354)
			(xy 129.164855 -283.906534) (xy 129.152676 -283.85712) (xy 129.148581 -283.806392) (xy 128.840484 -283.806392)
			(xy 128.839972 -283.831838) (xy 128.831808 -283.882072) (xy 128.815692 -283.930346) (xy 128.792041 -283.975409)
			(xy 128.761468 -284.016095) (xy 128.724764 -284.05135) (xy 128.68288 -284.08026) (xy 128.636901 -284.102077)
			(xy 128.588017 -284.116237) (xy 128.537496 -284.122371) (xy 128.486644 -284.120322) (xy 128.43678 -284.110142)
			(xy 128.389194 -284.092095) (xy 128.34512 -284.066649) (xy 128.305698 -284.034462) (xy 128.27195 -283.996368)
			(xy 128.244749 -283.953354) (xy 128.224801 -283.906534) (xy 128.212622 -283.85712) (xy 128.208527 -283.806392)
			(xy 127.890538 -283.806392) (xy 127.890539 -283.8064) (xy 127.886368 -283.856739) (xy 127.873968 -283.905704)
			(xy 127.853679 -283.951961) (xy 127.826052 -283.994248) (xy 127.791842 -284.03141) (xy 127.751982 -284.062435)
			(xy 127.70756 -284.086477) (xy 127.659786 -284.102879) (xy 127.609964 -284.111194) (xy 127.584708 -284.1117)
			(xy 127.561802 -284.111269) (xy 127.51651 -284.104385) (xy 127.472753 -284.090815) (xy 127.431514 -284.070864)
			(xy 127.393715 -284.044979) (xy 127.376682 -284.029658) (xy 127.365252 -284.019244) (xy 127.335534 -284.014164)
			(xy 127.23622 -284.057598) (xy 127.227392 -284.061959) (xy 127.213653 -284.07604) (xy 127.206196 -284.094245)
			(xy 127.20574 -284.10408) (xy 127.20574 -284.304994) (xy 127.22225 -284.33014) (xy 127.23622 -284.336236)
			(xy 127.259287 -284.346779) (xy 127.301847 -284.374355) (xy 127.339266 -284.408585) (xy 127.370516 -284.448526)
			(xy 127.394737 -284.493081) (xy 127.411264 -284.541026) (xy 127.419643 -284.591043) (xy 127.419643 -284.616398)
			(xy 127.738627 -284.616398) (xy 127.742722 -284.56567) (xy 127.754901 -284.516256) (xy 127.774849 -284.469436)
			(xy 127.80205 -284.426422) (xy 127.835798 -284.388328) (xy 127.87522 -284.356141) (xy 127.919294 -284.330695)
			(xy 127.96688 -284.312648) (xy 128.016744 -284.302468) (xy 128.067596 -284.300419) (xy 128.118117 -284.306553)
			(xy 128.167001 -284.320713) (xy 128.21298 -284.34253) (xy 128.254864 -284.37144) (xy 128.291568 -284.406695)
			(xy 128.322141 -284.447381) (xy 128.345792 -284.492444) (xy 128.361908 -284.540718) (xy 128.370072 -284.590952)
			(xy 128.370584 -284.616398) (xy 128.688858 -284.616398) (xy 128.692818 -284.567344) (xy 128.704595 -284.51956)
			(xy 128.723886 -284.474284) (xy 128.750189 -284.432688) (xy 128.782824 -284.395851) (xy 128.820945 -284.364726)
			(xy 128.863566 -284.340119) (xy 128.909582 -284.322667) (xy 128.957801 -284.312823) (xy 129.006976 -284.310842)
			(xy 129.055831 -284.316774) (xy 129.103102 -284.330466) (xy 129.147564 -284.351564) (xy 129.188067 -284.37952)
			(xy 129.22356 -284.413612) (xy 129.253125 -284.452956) (xy 129.275996 -284.496533) (xy 129.29158 -284.543214)
			(xy 129.299475 -284.591791) (xy 129.29997 -284.616398) (xy 129.618481 -284.616398) (xy 129.622576 -284.56567)
			(xy 129.634755 -284.516256) (xy 129.654703 -284.469436) (xy 129.681904 -284.426422) (xy 129.715652 -284.388328)
			(xy 129.755074 -284.356141) (xy 129.799148 -284.330695) (xy 129.846734 -284.312648) (xy 129.896598 -284.302468)
			(xy 129.94745 -284.300419) (xy 129.997971 -284.306553) (xy 130.046855 -284.320713) (xy 130.092834 -284.34253)
			(xy 130.134718 -284.37144) (xy 130.171422 -284.406695) (xy 130.201995 -284.447381) (xy 130.225646 -284.492444)
			(xy 130.241762 -284.540718) (xy 130.249926 -284.590952) (xy 130.250438 -284.616398) (xy 130.568966 -284.616398)
			(xy 130.572926 -284.567344) (xy 130.584703 -284.51956) (xy 130.603994 -284.474284) (xy 130.630297 -284.432688)
			(xy 130.662932 -284.395851) (xy 130.701053 -284.364726) (xy 130.743674 -284.340119) (xy 130.78969 -284.322667)
			(xy 130.837909 -284.312823) (xy 130.887084 -284.310842) (xy 130.935939 -284.316774) (xy 130.98321 -284.330466)
			(xy 131.027672 -284.351564) (xy 131.068175 -284.37952) (xy 131.103668 -284.413612) (xy 131.133233 -284.452956)
			(xy 131.156104 -284.496533) (xy 131.171688 -284.543214) (xy 131.179583 -284.591791) (xy 131.180078 -284.616398)
			(xy 131.498589 -284.616398) (xy 131.502684 -284.56567) (xy 131.514863 -284.516256) (xy 131.534811 -284.469436)
			(xy 131.562012 -284.426422) (xy 131.59576 -284.388328) (xy 131.635182 -284.356141) (xy 131.679256 -284.330695)
			(xy 131.726842 -284.312648) (xy 131.776706 -284.302468) (xy 131.827558 -284.300419) (xy 131.878079 -284.306553)
			(xy 131.926963 -284.320713) (xy 131.972942 -284.34253) (xy 132.014826 -284.37144) (xy 132.05153 -284.406695)
			(xy 132.082103 -284.447381) (xy 132.105754 -284.492444) (xy 132.12187 -284.540718) (xy 132.130034 -284.590952)
			(xy 132.130546 -284.616398) (xy 132.438643 -284.616398) (xy 132.442738 -284.56567) (xy 132.454917 -284.516256)
			(xy 132.474865 -284.469436) (xy 132.502066 -284.426422) (xy 132.535814 -284.388328) (xy 132.575236 -284.356141)
			(xy 132.61931 -284.330695) (xy 132.666896 -284.312648) (xy 132.71676 -284.302468) (xy 132.767612 -284.300419)
			(xy 132.818133 -284.306553) (xy 132.867017 -284.320713) (xy 132.912996 -284.34253) (xy 132.95488 -284.37144)
			(xy 132.991584 -284.406695) (xy 133.022157 -284.447381) (xy 133.045808 -284.492444) (xy 133.061924 -284.540718)
			(xy 133.070088 -284.590952) (xy 133.0706 -284.616398) (xy 133.388874 -284.616398) (xy 133.392834 -284.567344)
			(xy 133.404611 -284.51956) (xy 133.423902 -284.474284) (xy 133.450205 -284.432688) (xy 133.48284 -284.395851)
			(xy 133.520961 -284.364726) (xy 133.563582 -284.340119) (xy 133.609598 -284.322667) (xy 133.657817 -284.312823)
			(xy 133.706992 -284.310842) (xy 133.755847 -284.316774) (xy 133.803118 -284.330466) (xy 133.84758 -284.351564)
			(xy 133.888083 -284.37952) (xy 133.923576 -284.413612) (xy 133.953141 -284.452956) (xy 133.976012 -284.496533)
			(xy 133.991596 -284.543214) (xy 133.999491 -284.591791) (xy 133.999986 -284.616398) (xy 134.318497 -284.616398)
			(xy 134.322592 -284.56567) (xy 134.334771 -284.516256) (xy 134.354719 -284.469436) (xy 134.38192 -284.426422)
			(xy 134.415668 -284.388328) (xy 134.45509 -284.356141) (xy 134.499164 -284.330695) (xy 134.54675 -284.312648)
			(xy 134.596614 -284.302468) (xy 134.647466 -284.300419) (xy 134.697987 -284.306553) (xy 134.746871 -284.320713)
			(xy 134.79285 -284.34253) (xy 134.834734 -284.37144) (xy 134.871438 -284.406695) (xy 134.902011 -284.447381)
			(xy 134.925662 -284.492444) (xy 134.941778 -284.540718) (xy 134.949942 -284.590952) (xy 134.950454 -284.616398)
			(xy 135.268982 -284.616398) (xy 135.272942 -284.567344) (xy 135.284719 -284.51956) (xy 135.30401 -284.474284)
			(xy 135.330313 -284.432688) (xy 135.362948 -284.395851) (xy 135.401069 -284.364726) (xy 135.44369 -284.340119)
			(xy 135.489706 -284.322667) (xy 135.537925 -284.312823) (xy 135.5871 -284.310842) (xy 135.635955 -284.316774)
			(xy 135.683226 -284.330466) (xy 135.727688 -284.351564) (xy 135.768191 -284.37952) (xy 135.803684 -284.413612)
			(xy 135.833249 -284.452956) (xy 135.85612 -284.496533) (xy 135.871704 -284.543214) (xy 135.879599 -284.591791)
			(xy 135.880094 -284.616398) (xy 136.198605 -284.616398) (xy 136.2027 -284.56567) (xy 136.214879 -284.516256)
			(xy 136.234827 -284.469436) (xy 136.262028 -284.426422) (xy 136.295776 -284.388328) (xy 136.335198 -284.356141)
			(xy 136.379272 -284.330695) (xy 136.426858 -284.312648) (xy 136.476722 -284.302468) (xy 136.527574 -284.300419)
			(xy 136.578095 -284.306553) (xy 136.626979 -284.320713) (xy 136.672958 -284.34253) (xy 136.714842 -284.37144)
			(xy 136.751546 -284.406695) (xy 136.782119 -284.447381) (xy 136.80577 -284.492444) (xy 136.821886 -284.540718)
			(xy 136.83005 -284.590952) (xy 136.830562 -284.616398) (xy 137.148836 -284.616398) (xy 137.152796 -284.567344)
			(xy 137.164573 -284.51956) (xy 137.183864 -284.474284) (xy 137.210167 -284.432688) (xy 137.242802 -284.395851)
			(xy 137.280923 -284.364726) (xy 137.323544 -284.340119) (xy 137.36956 -284.322667) (xy 137.417779 -284.312823)
			(xy 137.466954 -284.310842) (xy 137.515809 -284.316774) (xy 137.56308 -284.330466) (xy 137.607542 -284.351564)
			(xy 137.648045 -284.37952) (xy 137.683538 -284.413612) (xy 137.713103 -284.452956) (xy 137.735974 -284.496533)
			(xy 137.751558 -284.543214) (xy 137.759453 -284.591791) (xy 137.759948 -284.616398) (xy 138.078459 -284.616398)
			(xy 138.082554 -284.56567) (xy 138.094733 -284.516256) (xy 138.114681 -284.469436) (xy 138.141882 -284.426422)
			(xy 138.17563 -284.388328) (xy 138.215052 -284.356141) (xy 138.259126 -284.330695) (xy 138.306712 -284.312648)
			(xy 138.356576 -284.302468) (xy 138.407428 -284.300419) (xy 138.457949 -284.306553) (xy 138.506833 -284.320713)
			(xy 138.552812 -284.34253) (xy 138.594696 -284.37144) (xy 138.6314 -284.406695) (xy 138.661973 -284.447381)
			(xy 138.685624 -284.492444) (xy 138.70174 -284.540718) (xy 138.709904 -284.590952) (xy 138.710416 -284.616398)
			(xy 139.018513 -284.616398) (xy 139.022608 -284.56567) (xy 139.034787 -284.516256) (xy 139.054735 -284.469436)
			(xy 139.081936 -284.426422) (xy 139.115684 -284.388328) (xy 139.155106 -284.356141) (xy 139.19918 -284.330695)
			(xy 139.246766 -284.312648) (xy 139.29663 -284.302468) (xy 139.347482 -284.300419) (xy 139.398003 -284.306553)
			(xy 139.446887 -284.320713) (xy 139.492866 -284.34253) (xy 139.53475 -284.37144) (xy 139.571454 -284.406695)
			(xy 139.602027 -284.447381) (xy 139.625678 -284.492444) (xy 139.641794 -284.540718) (xy 139.649958 -284.590952)
			(xy 139.65047 -284.616398) (xy 139.968998 -284.616398) (xy 139.972958 -284.567344) (xy 139.984735 -284.51956)
			(xy 140.004026 -284.474284) (xy 140.030329 -284.432688) (xy 140.062964 -284.395851) (xy 140.101085 -284.364726)
			(xy 140.143706 -284.340119) (xy 140.189722 -284.322667) (xy 140.237941 -284.312823) (xy 140.287116 -284.310842)
			(xy 140.335971 -284.316774) (xy 140.383242 -284.330466) (xy 140.427704 -284.351564) (xy 140.468207 -284.37952)
			(xy 140.5037 -284.413612) (xy 140.533265 -284.452956) (xy 140.556136 -284.496533) (xy 140.57172 -284.543214)
			(xy 140.579615 -284.591791) (xy 140.58011 -284.616398) (xy 140.898621 -284.616398) (xy 140.902716 -284.56567)
			(xy 140.914895 -284.516256) (xy 140.934843 -284.469436) (xy 140.962044 -284.426422) (xy 140.995792 -284.388328)
			(xy 141.035214 -284.356141) (xy 141.079288 -284.330695) (xy 141.126874 -284.312648) (xy 141.176738 -284.302468)
			(xy 141.22759 -284.300419) (xy 141.278111 -284.306553) (xy 141.326995 -284.320713) (xy 141.372974 -284.34253)
			(xy 141.414858 -284.37144) (xy 141.451562 -284.406695) (xy 141.482135 -284.447381) (xy 141.505786 -284.492444)
			(xy 141.521902 -284.540718) (xy 141.530066 -284.590952) (xy 141.530578 -284.616398) (xy 141.848852 -284.616398)
			(xy 141.852812 -284.567344) (xy 141.864589 -284.51956) (xy 141.88388 -284.474284) (xy 141.910183 -284.432688)
			(xy 141.942818 -284.395851) (xy 141.980939 -284.364726) (xy 142.02356 -284.340119) (xy 142.069576 -284.322667)
			(xy 142.117795 -284.312823) (xy 142.16697 -284.310842) (xy 142.215825 -284.316774) (xy 142.263096 -284.330466)
			(xy 142.307558 -284.351564) (xy 142.348061 -284.37952) (xy 142.383554 -284.413612) (xy 142.413119 -284.452956)
			(xy 142.43599 -284.496533) (xy 142.451574 -284.543214) (xy 142.459469 -284.591791) (xy 142.459964 -284.616398)
			(xy 142.778475 -284.616398) (xy 142.78257 -284.56567) (xy 142.794749 -284.516256) (xy 142.814697 -284.469436)
			(xy 142.841898 -284.426422) (xy 142.875646 -284.388328) (xy 142.915068 -284.356141) (xy 142.959142 -284.330695)
			(xy 143.006728 -284.312648) (xy 143.056592 -284.302468) (xy 143.107444 -284.300419) (xy 143.157965 -284.306553)
			(xy 143.206849 -284.320713) (xy 143.252828 -284.34253) (xy 143.294712 -284.37144) (xy 143.331416 -284.406695)
			(xy 143.361989 -284.447381) (xy 143.38564 -284.492444) (xy 143.401756 -284.540718) (xy 143.40992 -284.590952)
			(xy 143.410432 -284.616398) (xy 143.72896 -284.616398) (xy 143.73292 -284.567344) (xy 143.744697 -284.51956)
			(xy 143.763988 -284.474284) (xy 143.790291 -284.432688) (xy 143.822926 -284.395851) (xy 143.861047 -284.364726)
			(xy 143.903668 -284.340119) (xy 143.949684 -284.322667) (xy 143.997903 -284.312823) (xy 144.047078 -284.310842)
			(xy 144.095933 -284.316774) (xy 144.143204 -284.330466) (xy 144.185339 -284.35046) (xy 146.737082 -284.35046)
			(xy 146.741042 -284.301406) (xy 146.752819 -284.253622) (xy 146.77211 -284.208346) (xy 146.798413 -284.16675)
			(xy 146.831048 -284.129913) (xy 146.869169 -284.098788) (xy 146.91179 -284.074181) (xy 146.957806 -284.056729)
			(xy 147.006025 -284.046885) (xy 147.0552 -284.044904) (xy 147.104055 -284.050836) (xy 147.151326 -284.064528)
			(xy 147.195788 -284.085626) (xy 147.236291 -284.113582) (xy 147.271784 -284.147674) (xy 147.301349 -284.187018)
			(xy 147.32422 -284.230595) (xy 147.339804 -284.277276) (xy 147.347699 -284.325853) (xy 147.348194 -284.35046)
			(xy 147.347699 -284.375067) (xy 147.339804 -284.423644) (xy 147.32422 -284.470325) (xy 147.301349 -284.513902)
			(xy 147.271784 -284.553246) (xy 147.236291 -284.587338) (xy 147.195788 -284.615294) (xy 147.151326 -284.636392)
			(xy 147.104055 -284.650084) (xy 147.0552 -284.656016) (xy 147.006025 -284.654035) (xy 146.957806 -284.644191)
			(xy 146.91179 -284.626739) (xy 146.869169 -284.602132) (xy 146.831048 -284.571007) (xy 146.798413 -284.53417)
			(xy 146.77211 -284.492574) (xy 146.752819 -284.447298) (xy 146.741042 -284.399514) (xy 146.737082 -284.35046)
			(xy 144.185339 -284.35046) (xy 144.187666 -284.351564) (xy 144.228169 -284.37952) (xy 144.263662 -284.413612)
			(xy 144.293227 -284.452956) (xy 144.316098 -284.496533) (xy 144.331682 -284.543214) (xy 144.339577 -284.591791)
			(xy 144.340072 -284.616398) (xy 144.339577 -284.641005) (xy 144.331682 -284.689582) (xy 144.316098 -284.736263)
			(xy 144.293227 -284.77984) (xy 144.263662 -284.819184) (xy 144.228169 -284.853276) (xy 144.187666 -284.881232)
			(xy 144.178916 -284.885384) (xy 165.442915 -284.885384) (xy 165.44685 -284.831613) (xy 165.458573 -284.778989)
			(xy 165.477833 -284.728632) (xy 165.504219 -284.681615) (xy 165.537171 -284.638942) (xy 165.575984 -284.601521)
			(xy 165.619832 -284.570151) (xy 165.66778 -284.545499) (xy 165.718807 -284.528091) (xy 165.771825 -284.518298)
			(xy 165.825704 -284.516329) (xy 165.879295 -284.522226) (xy 165.931456 -284.535862) (xy 165.981076 -284.556949)
			(xy 166.027097 -284.585035) (xy 166.068539 -284.619523) (xy 166.104517 -284.659677) (xy 166.134265 -284.704641)
			(xy 166.15715 -284.753458) (xy 166.172682 -284.805087) (xy 166.180532 -284.858427) (xy 166.181024 -284.885384)
			(xy 172.986969 -284.885384) (xy 172.990904 -284.831613) (xy 173.002627 -284.778989) (xy 173.021887 -284.728632)
			(xy 173.048273 -284.681615) (xy 173.081225 -284.638942) (xy 173.120038 -284.601521) (xy 173.163886 -284.570151)
			(xy 173.211834 -284.545499) (xy 173.262861 -284.528091) (xy 173.315879 -284.518298) (xy 173.369758 -284.516329)
			(xy 173.423349 -284.522226) (xy 173.47551 -284.535862) (xy 173.52513 -284.556949) (xy 173.571151 -284.585035)
			(xy 173.612593 -284.619523) (xy 173.648571 -284.659677) (xy 173.678319 -284.704641) (xy 173.701204 -284.753458)
			(xy 173.716736 -284.805087) (xy 173.724586 -284.858427) (xy 173.725078 -284.885384) (xy 173.724586 -284.912341)
			(xy 173.716736 -284.965681) (xy 173.701204 -285.01731) (xy 173.678319 -285.066127) (xy 173.648571 -285.111091)
			(xy 173.612593 -285.151245) (xy 173.571151 -285.185733) (xy 173.52513 -285.213819) (xy 173.47551 -285.234906)
			(xy 173.423349 -285.248542) (xy 173.369758 -285.254439) (xy 173.315879 -285.25247) (xy 173.262861 -285.242677)
			(xy 173.211834 -285.225269) (xy 173.163886 -285.200617) (xy 173.120038 -285.169247) (xy 173.081225 -285.131826)
			(xy 173.048273 -285.089153) (xy 173.021887 -285.042136) (xy 173.002627 -284.991779) (xy 172.990904 -284.939155)
			(xy 172.986969 -284.885384) (xy 166.181024 -284.885384) (xy 166.180532 -284.912341) (xy 166.172682 -284.965681)
			(xy 166.15715 -285.01731) (xy 166.134265 -285.066127) (xy 166.104517 -285.111091) (xy 166.068539 -285.151245)
			(xy 166.027097 -285.185733) (xy 165.981076 -285.213819) (xy 165.931456 -285.234906) (xy 165.879295 -285.248542)
			(xy 165.825704 -285.254439) (xy 165.771825 -285.25247) (xy 165.718807 -285.242677) (xy 165.66778 -285.225269)
			(xy 165.619832 -285.200617) (xy 165.575984 -285.169247) (xy 165.537171 -285.131826) (xy 165.504219 -285.089153)
			(xy 165.477833 -285.042136) (xy 165.458573 -284.991779) (xy 165.44685 -284.939155) (xy 165.442915 -284.885384)
			(xy 144.178916 -284.885384) (xy 144.143204 -284.90233) (xy 144.095933 -284.916022) (xy 144.047078 -284.921954)
			(xy 143.997903 -284.919973) (xy 143.949684 -284.910129) (xy 143.903668 -284.892677) (xy 143.861047 -284.86807)
			(xy 143.822926 -284.836945) (xy 143.790291 -284.800108) (xy 143.763988 -284.758512) (xy 143.744697 -284.713236)
			(xy 143.73292 -284.665452) (xy 143.72896 -284.616398) (xy 143.410432 -284.616398) (xy 143.40992 -284.641844)
			(xy 143.401756 -284.692078) (xy 143.38564 -284.740352) (xy 143.361989 -284.785415) (xy 143.331416 -284.826101)
			(xy 143.294712 -284.861356) (xy 143.252828 -284.890266) (xy 143.206849 -284.912083) (xy 143.157965 -284.926243)
			(xy 143.107444 -284.932377) (xy 143.056592 -284.930328) (xy 143.006728 -284.920148) (xy 142.959142 -284.902101)
			(xy 142.915068 -284.876655) (xy 142.875646 -284.844468) (xy 142.841898 -284.806374) (xy 142.814697 -284.76336)
			(xy 142.794749 -284.71654) (xy 142.78257 -284.667126) (xy 142.778475 -284.616398) (xy 142.459964 -284.616398)
			(xy 142.459469 -284.641005) (xy 142.451574 -284.689582) (xy 142.43599 -284.736263) (xy 142.413119 -284.77984)
			(xy 142.383554 -284.819184) (xy 142.348061 -284.853276) (xy 142.307558 -284.881232) (xy 142.263096 -284.90233)
			(xy 142.215825 -284.916022) (xy 142.16697 -284.921954) (xy 142.117795 -284.919973) (xy 142.069576 -284.910129)
			(xy 142.02356 -284.892677) (xy 141.980939 -284.86807) (xy 141.942818 -284.836945) (xy 141.910183 -284.800108)
			(xy 141.88388 -284.758512) (xy 141.864589 -284.713236) (xy 141.852812 -284.665452) (xy 141.848852 -284.616398)
			(xy 141.530578 -284.616398) (xy 141.530066 -284.641844) (xy 141.521902 -284.692078) (xy 141.505786 -284.740352)
			(xy 141.482135 -284.785415) (xy 141.451562 -284.826101) (xy 141.414858 -284.861356) (xy 141.372974 -284.890266)
			(xy 141.326995 -284.912083) (xy 141.278111 -284.926243) (xy 141.22759 -284.932377) (xy 141.176738 -284.930328)
			(xy 141.126874 -284.920148) (xy 141.079288 -284.902101) (xy 141.035214 -284.876655) (xy 140.995792 -284.844468)
			(xy 140.962044 -284.806374) (xy 140.934843 -284.76336) (xy 140.914895 -284.71654) (xy 140.902716 -284.667126)
			(xy 140.898621 -284.616398) (xy 140.58011 -284.616398) (xy 140.579615 -284.641005) (xy 140.57172 -284.689582)
			(xy 140.556136 -284.736263) (xy 140.533265 -284.77984) (xy 140.5037 -284.819184) (xy 140.468207 -284.853276)
			(xy 140.427704 -284.881232) (xy 140.383242 -284.90233) (xy 140.335971 -284.916022) (xy 140.287116 -284.921954)
			(xy 140.237941 -284.919973) (xy 140.189722 -284.910129) (xy 140.143706 -284.892677) (xy 140.101085 -284.86807)
			(xy 140.062964 -284.836945) (xy 140.030329 -284.800108) (xy 140.004026 -284.758512) (xy 139.984735 -284.713236)
			(xy 139.972958 -284.665452) (xy 139.968998 -284.616398) (xy 139.65047 -284.616398) (xy 139.649958 -284.641844)
			(xy 139.641794 -284.692078) (xy 139.625678 -284.740352) (xy 139.602027 -284.785415) (xy 139.571454 -284.826101)
			(xy 139.53475 -284.861356) (xy 139.492866 -284.890266) (xy 139.446887 -284.912083) (xy 139.398003 -284.926243)
			(xy 139.347482 -284.932377) (xy 139.29663 -284.930328) (xy 139.246766 -284.920148) (xy 139.19918 -284.902101)
			(xy 139.155106 -284.876655) (xy 139.115684 -284.844468) (xy 139.081936 -284.806374) (xy 139.054735 -284.76336)
			(xy 139.034787 -284.71654) (xy 139.022608 -284.667126) (xy 139.018513 -284.616398) (xy 138.710416 -284.616398)
			(xy 138.709904 -284.641844) (xy 138.70174 -284.692078) (xy 138.685624 -284.740352) (xy 138.661973 -284.785415)
			(xy 138.6314 -284.826101) (xy 138.594696 -284.861356) (xy 138.552812 -284.890266) (xy 138.506833 -284.912083)
			(xy 138.457949 -284.926243) (xy 138.407428 -284.932377) (xy 138.356576 -284.930328) (xy 138.306712 -284.920148)
			(xy 138.259126 -284.902101) (xy 138.215052 -284.876655) (xy 138.17563 -284.844468) (xy 138.141882 -284.806374)
			(xy 138.114681 -284.76336) (xy 138.094733 -284.71654) (xy 138.082554 -284.667126) (xy 138.078459 -284.616398)
			(xy 137.759948 -284.616398) (xy 137.759453 -284.641005) (xy 137.751558 -284.689582) (xy 137.735974 -284.736263)
			(xy 137.713103 -284.77984) (xy 137.683538 -284.819184) (xy 137.648045 -284.853276) (xy 137.607542 -284.881232)
			(xy 137.56308 -284.90233) (xy 137.515809 -284.916022) (xy 137.466954 -284.921954) (xy 137.417779 -284.919973)
			(xy 137.36956 -284.910129) (xy 137.323544 -284.892677) (xy 137.280923 -284.86807) (xy 137.242802 -284.836945)
			(xy 137.210167 -284.800108) (xy 137.183864 -284.758512) (xy 137.164573 -284.713236) (xy 137.152796 -284.665452)
			(xy 137.148836 -284.616398) (xy 136.830562 -284.616398) (xy 136.83005 -284.641844) (xy 136.821886 -284.692078)
			(xy 136.80577 -284.740352) (xy 136.782119 -284.785415) (xy 136.751546 -284.826101) (xy 136.714842 -284.861356)
			(xy 136.672958 -284.890266) (xy 136.626979 -284.912083) (xy 136.578095 -284.926243) (xy 136.527574 -284.932377)
			(xy 136.476722 -284.930328) (xy 136.426858 -284.920148) (xy 136.379272 -284.902101) (xy 136.335198 -284.876655)
			(xy 136.295776 -284.844468) (xy 136.262028 -284.806374) (xy 136.234827 -284.76336) (xy 136.214879 -284.71654)
			(xy 136.2027 -284.667126) (xy 136.198605 -284.616398) (xy 135.880094 -284.616398) (xy 135.879599 -284.641005)
			(xy 135.871704 -284.689582) (xy 135.85612 -284.736263) (xy 135.833249 -284.77984) (xy 135.803684 -284.819184)
			(xy 135.768191 -284.853276) (xy 135.727688 -284.881232) (xy 135.683226 -284.90233) (xy 135.635955 -284.916022)
			(xy 135.5871 -284.921954) (xy 135.537925 -284.919973) (xy 135.489706 -284.910129) (xy 135.44369 -284.892677)
			(xy 135.401069 -284.86807) (xy 135.362948 -284.836945) (xy 135.330313 -284.800108) (xy 135.30401 -284.758512)
			(xy 135.284719 -284.713236) (xy 135.272942 -284.665452) (xy 135.268982 -284.616398) (xy 134.950454 -284.616398)
			(xy 134.949942 -284.641844) (xy 134.941778 -284.692078) (xy 134.925662 -284.740352) (xy 134.902011 -284.785415)
			(xy 134.871438 -284.826101) (xy 134.834734 -284.861356) (xy 134.79285 -284.890266) (xy 134.746871 -284.912083)
			(xy 134.697987 -284.926243) (xy 134.647466 -284.932377) (xy 134.596614 -284.930328) (xy 134.54675 -284.920148)
			(xy 134.499164 -284.902101) (xy 134.45509 -284.876655) (xy 134.415668 -284.844468) (xy 134.38192 -284.806374)
			(xy 134.354719 -284.76336) (xy 134.334771 -284.71654) (xy 134.322592 -284.667126) (xy 134.318497 -284.616398)
			(xy 133.999986 -284.616398) (xy 133.999491 -284.641005) (xy 133.991596 -284.689582) (xy 133.976012 -284.736263)
			(xy 133.953141 -284.77984) (xy 133.923576 -284.819184) (xy 133.888083 -284.853276) (xy 133.84758 -284.881232)
			(xy 133.803118 -284.90233) (xy 133.755847 -284.916022) (xy 133.706992 -284.921954) (xy 133.657817 -284.919973)
			(xy 133.609598 -284.910129) (xy 133.563582 -284.892677) (xy 133.520961 -284.86807) (xy 133.48284 -284.836945)
			(xy 133.450205 -284.800108) (xy 133.423902 -284.758512) (xy 133.404611 -284.713236) (xy 133.392834 -284.665452)
			(xy 133.388874 -284.616398) (xy 133.0706 -284.616398) (xy 133.070088 -284.641844) (xy 133.061924 -284.692078)
			(xy 133.045808 -284.740352) (xy 133.022157 -284.785415) (xy 132.991584 -284.826101) (xy 132.95488 -284.861356)
			(xy 132.912996 -284.890266) (xy 132.867017 -284.912083) (xy 132.818133 -284.926243) (xy 132.767612 -284.932377)
			(xy 132.71676 -284.930328) (xy 132.666896 -284.920148) (xy 132.61931 -284.902101) (xy 132.575236 -284.876655)
			(xy 132.535814 -284.844468) (xy 132.502066 -284.806374) (xy 132.474865 -284.76336) (xy 132.454917 -284.71654)
			(xy 132.442738 -284.667126) (xy 132.438643 -284.616398) (xy 132.130546 -284.616398) (xy 132.130034 -284.641844)
			(xy 132.12187 -284.692078) (xy 132.105754 -284.740352) (xy 132.082103 -284.785415) (xy 132.05153 -284.826101)
			(xy 132.014826 -284.861356) (xy 131.972942 -284.890266) (xy 131.926963 -284.912083) (xy 131.878079 -284.926243)
			(xy 131.827558 -284.932377) (xy 131.776706 -284.930328) (xy 131.726842 -284.920148) (xy 131.679256 -284.902101)
			(xy 131.635182 -284.876655) (xy 131.59576 -284.844468) (xy 131.562012 -284.806374) (xy 131.534811 -284.76336)
			(xy 131.514863 -284.71654) (xy 131.502684 -284.667126) (xy 131.498589 -284.616398) (xy 131.180078 -284.616398)
			(xy 131.179583 -284.641005) (xy 131.171688 -284.689582) (xy 131.156104 -284.736263) (xy 131.133233 -284.77984)
			(xy 131.103668 -284.819184) (xy 131.068175 -284.853276) (xy 131.027672 -284.881232) (xy 130.98321 -284.90233)
			(xy 130.935939 -284.916022) (xy 130.887084 -284.921954) (xy 130.837909 -284.919973) (xy 130.78969 -284.910129)
			(xy 130.743674 -284.892677) (xy 130.701053 -284.86807) (xy 130.662932 -284.836945) (xy 130.630297 -284.800108)
			(xy 130.603994 -284.758512) (xy 130.584703 -284.713236) (xy 130.572926 -284.665452) (xy 130.568966 -284.616398)
			(xy 130.250438 -284.616398) (xy 130.249926 -284.641844) (xy 130.241762 -284.692078) (xy 130.225646 -284.740352)
			(xy 130.201995 -284.785415) (xy 130.171422 -284.826101) (xy 130.134718 -284.861356) (xy 130.092834 -284.890266)
			(xy 130.046855 -284.912083) (xy 129.997971 -284.926243) (xy 129.94745 -284.932377) (xy 129.896598 -284.930328)
			(xy 129.846734 -284.920148) (xy 129.799148 -284.902101) (xy 129.755074 -284.876655) (xy 129.715652 -284.844468)
			(xy 129.681904 -284.806374) (xy 129.654703 -284.76336) (xy 129.634755 -284.71654) (xy 129.622576 -284.667126)
			(xy 129.618481 -284.616398) (xy 129.29997 -284.616398) (xy 129.299475 -284.641005) (xy 129.29158 -284.689582)
			(xy 129.275996 -284.736263) (xy 129.253125 -284.77984) (xy 129.22356 -284.819184) (xy 129.188067 -284.853276)
			(xy 129.147564 -284.881232) (xy 129.103102 -284.90233) (xy 129.055831 -284.916022) (xy 129.006976 -284.921954)
			(xy 128.957801 -284.919973) (xy 128.909582 -284.910129) (xy 128.863566 -284.892677) (xy 128.820945 -284.86807)
			(xy 128.782824 -284.836945) (xy 128.750189 -284.800108) (xy 128.723886 -284.758512) (xy 128.704595 -284.713236)
			(xy 128.692818 -284.665452) (xy 128.688858 -284.616398) (xy 128.370584 -284.616398) (xy 128.370072 -284.641844)
			(xy 128.361908 -284.692078) (xy 128.345792 -284.740352) (xy 128.322141 -284.785415) (xy 128.291568 -284.826101)
			(xy 128.254864 -284.861356) (xy 128.21298 -284.890266) (xy 128.167001 -284.912083) (xy 128.118117 -284.926243)
			(xy 128.067596 -284.932377) (xy 128.016744 -284.930328) (xy 127.96688 -284.920148) (xy 127.919294 -284.902101)
			(xy 127.87522 -284.876655) (xy 127.835798 -284.844468) (xy 127.80205 -284.806374) (xy 127.774849 -284.76336)
			(xy 127.754901 -284.71654) (xy 127.742722 -284.667126) (xy 127.738627 -284.616398) (xy 127.419643 -284.616398)
			(xy 127.419643 -284.641756) (xy 127.411264 -284.691772) (xy 127.394737 -284.739717) (xy 127.370516 -284.784273)
			(xy 127.339267 -284.824214) (xy 127.301848 -284.858444) (xy 127.259288 -284.886021) (xy 127.23622 -284.89656)
			(xy 127.22225 -284.902656) (xy 127.20574 -284.927802) (xy 127.20574 -285.426404) (xy 128.208527 -285.426404)
			(xy 128.212622 -285.375676) (xy 128.224801 -285.326262) (xy 128.244749 -285.279442) (xy 128.27195 -285.236428)
			(xy 128.305698 -285.198334) (xy 128.34512 -285.166147) (xy 128.389194 -285.140701) (xy 128.43678 -285.122654)
			(xy 128.486644 -285.112474) (xy 128.537496 -285.110425) (xy 128.588017 -285.116559) (xy 128.636901 -285.130719)
			(xy 128.68288 -285.152536) (xy 128.724764 -285.181446) (xy 128.761468 -285.216701) (xy 128.792041 -285.257387)
			(xy 128.815692 -285.30245) (xy 128.831808 -285.350724) (xy 128.839972 -285.400958) (xy 128.840484 -285.426404)
			(xy 129.148581 -285.426404) (xy 129.152676 -285.375676) (xy 129.164855 -285.326262) (xy 129.184803 -285.279442)
			(xy 129.212004 -285.236428) (xy 129.245752 -285.198334) (xy 129.285174 -285.166147) (xy 129.329248 -285.140701)
			(xy 129.376834 -285.122654) (xy 129.426698 -285.112474) (xy 129.47755 -285.110425) (xy 129.528071 -285.116559)
			(xy 129.576955 -285.130719) (xy 129.622934 -285.152536) (xy 129.664818 -285.181446) (xy 129.701522 -285.216701)
			(xy 129.732095 -285.257387) (xy 129.755746 -285.30245) (xy 129.771862 -285.350724) (xy 129.780026 -285.400958)
			(xy 129.780538 -285.426404) (xy 131.028435 -285.426404) (xy 131.03253 -285.375676) (xy 131.044709 -285.326262)
			(xy 131.064657 -285.279442) (xy 131.091858 -285.236428) (xy 131.125606 -285.198334) (xy 131.165028 -285.166147)
			(xy 131.209102 -285.140701) (xy 131.256688 -285.122654) (xy 131.306552 -285.112474) (xy 131.357404 -285.110425)
			(xy 131.407925 -285.116559) (xy 131.456809 -285.130719) (xy 131.502788 -285.152536) (xy 131.544672 -285.181446)
			(xy 131.581376 -285.216701) (xy 131.611949 -285.257387) (xy 131.6356 -285.30245) (xy 131.651716 -285.350724)
			(xy 131.65988 -285.400958) (xy 131.660392 -285.426404) (xy 131.97892 -285.426404) (xy 131.98288 -285.37735)
			(xy 131.994657 -285.329566) (xy 132.013948 -285.28429) (xy 132.040251 -285.242694) (xy 132.072886 -285.205857)
			(xy 132.111007 -285.174732) (xy 132.153628 -285.150125) (xy 132.199644 -285.132673) (xy 132.247863 -285.122829)
			(xy 132.297038 -285.120848) (xy 132.345893 -285.12678) (xy 132.393164 -285.140472) (xy 132.437626 -285.16157)
			(xy 132.478129 -285.189526) (xy 132.513622 -285.223618) (xy 132.543187 -285.262962) (xy 132.566058 -285.306539)
			(xy 132.581642 -285.35322) (xy 132.589537 -285.401797) (xy 132.590032 -285.426404) (xy 132.908543 -285.426404)
			(xy 132.912638 -285.375676) (xy 132.924817 -285.326262) (xy 132.944765 -285.279442) (xy 132.971966 -285.236428)
			(xy 133.005714 -285.198334) (xy 133.045136 -285.166147) (xy 133.08921 -285.140701) (xy 133.136796 -285.122654)
			(xy 133.18666 -285.112474) (xy 133.237512 -285.110425) (xy 133.288033 -285.116559) (xy 133.336917 -285.130719)
			(xy 133.382896 -285.152536) (xy 133.42478 -285.181446) (xy 133.461484 -285.216701) (xy 133.492057 -285.257387)
			(xy 133.515708 -285.30245) (xy 133.531824 -285.350724) (xy 133.539988 -285.400958) (xy 133.5405 -285.426404)
			(xy 133.859028 -285.426404) (xy 133.862988 -285.37735) (xy 133.874765 -285.329566) (xy 133.894056 -285.28429)
			(xy 133.920359 -285.242694) (xy 133.952994 -285.205857) (xy 133.991115 -285.174732) (xy 134.033736 -285.150125)
			(xy 134.079752 -285.132673) (xy 134.127971 -285.122829) (xy 134.177146 -285.120848) (xy 134.226001 -285.12678)
			(xy 134.273272 -285.140472) (xy 134.317734 -285.16157) (xy 134.358237 -285.189526) (xy 134.39373 -285.223618)
			(xy 134.423295 -285.262962) (xy 134.446166 -285.306539) (xy 134.46175 -285.35322) (xy 134.469645 -285.401797)
			(xy 134.47014 -285.426404) (xy 134.788397 -285.426404) (xy 134.792492 -285.375676) (xy 134.804671 -285.326262)
			(xy 134.824619 -285.279442) (xy 134.85182 -285.236428) (xy 134.885568 -285.198334) (xy 134.92499 -285.166147)
			(xy 134.969064 -285.140701) (xy 135.01665 -285.122654) (xy 135.066514 -285.112474) (xy 135.117366 -285.110425)
			(xy 135.167887 -285.116559) (xy 135.216771 -285.130719) (xy 135.26275 -285.152536) (xy 135.304634 -285.181446)
			(xy 135.341338 -285.216701) (xy 135.371911 -285.257387) (xy 135.395562 -285.30245) (xy 135.411678 -285.350724)
			(xy 135.419842 -285.400958) (xy 135.420354 -285.426404) (xy 135.728451 -285.426404) (xy 135.732546 -285.375676)
			(xy 135.744725 -285.326262) (xy 135.764673 -285.279442) (xy 135.791874 -285.236428) (xy 135.825622 -285.198334)
			(xy 135.865044 -285.166147) (xy 135.909118 -285.140701) (xy 135.956704 -285.122654) (xy 136.006568 -285.112474)
			(xy 136.05742 -285.110425) (xy 136.107941 -285.116559) (xy 136.156825 -285.130719) (xy 136.202804 -285.152536)
			(xy 136.244688 -285.181446) (xy 136.281392 -285.216701) (xy 136.311965 -285.257387) (xy 136.335616 -285.30245)
			(xy 136.351732 -285.350724) (xy 136.359896 -285.400958) (xy 136.360408 -285.426404) (xy 137.608559 -285.426404)
			(xy 137.612654 -285.375676) (xy 137.624833 -285.326262) (xy 137.644781 -285.279442) (xy 137.671982 -285.236428)
			(xy 137.70573 -285.198334) (xy 137.745152 -285.166147) (xy 137.789226 -285.140701) (xy 137.836812 -285.122654)
			(xy 137.886676 -285.112474) (xy 137.937528 -285.110425) (xy 137.988049 -285.116559) (xy 138.036933 -285.130719)
			(xy 138.082912 -285.152536) (xy 138.124796 -285.181446) (xy 138.1615 -285.216701) (xy 138.192073 -285.257387)
			(xy 138.215724 -285.30245) (xy 138.23184 -285.350724) (xy 138.240004 -285.400958) (xy 138.240516 -285.426404)
			(xy 138.559044 -285.426404) (xy 138.563004 -285.37735) (xy 138.574781 -285.329566) (xy 138.594072 -285.28429)
			(xy 138.620375 -285.242694) (xy 138.65301 -285.205857) (xy 138.691131 -285.174732) (xy 138.733752 -285.150125)
			(xy 138.779768 -285.132673) (xy 138.827987 -285.122829) (xy 138.877162 -285.120848) (xy 138.926017 -285.12678)
			(xy 138.973288 -285.140472) (xy 139.01775 -285.16157) (xy 139.058253 -285.189526) (xy 139.093746 -285.223618)
			(xy 139.123311 -285.262962) (xy 139.146182 -285.306539) (xy 139.161766 -285.35322) (xy 139.169661 -285.401797)
			(xy 139.170156 -285.426404) (xy 139.488413 -285.426404) (xy 139.492508 -285.375676) (xy 139.504687 -285.326262)
			(xy 139.524635 -285.279442) (xy 139.551836 -285.236428) (xy 139.585584 -285.198334) (xy 139.625006 -285.166147)
			(xy 139.66908 -285.140701) (xy 139.716666 -285.122654) (xy 139.76653 -285.112474) (xy 139.817382 -285.110425)
			(xy 139.867903 -285.116559) (xy 139.916787 -285.130719) (xy 139.962766 -285.152536) (xy 140.00465 -285.181446)
			(xy 140.041354 -285.216701) (xy 140.071927 -285.257387) (xy 140.095578 -285.30245) (xy 140.111694 -285.350724)
			(xy 140.119858 -285.400958) (xy 140.12037 -285.426404) (xy 140.438898 -285.426404) (xy 140.442858 -285.37735)
			(xy 140.454635 -285.329566) (xy 140.473926 -285.28429) (xy 140.500229 -285.242694) (xy 140.532864 -285.205857)
			(xy 140.570985 -285.174732) (xy 140.613606 -285.150125) (xy 140.659622 -285.132673) (xy 140.707841 -285.122829)
			(xy 140.757016 -285.120848) (xy 140.805871 -285.12678) (xy 140.853142 -285.140472) (xy 140.897604 -285.16157)
			(xy 140.938107 -285.189526) (xy 140.9736 -285.223618) (xy 141.003165 -285.262962) (xy 141.026036 -285.306539)
			(xy 141.04162 -285.35322) (xy 141.049515 -285.401797) (xy 141.05001 -285.426404) (xy 141.368521 -285.426404)
			(xy 141.372616 -285.375676) (xy 141.384795 -285.326262) (xy 141.404743 -285.279442) (xy 141.431944 -285.236428)
			(xy 141.465692 -285.198334) (xy 141.505114 -285.166147) (xy 141.549188 -285.140701) (xy 141.596774 -285.122654)
			(xy 141.646638 -285.112474) (xy 141.69749 -285.110425) (xy 141.748011 -285.116559) (xy 141.796895 -285.130719)
			(xy 141.842874 -285.152536) (xy 141.884758 -285.181446) (xy 141.921462 -285.216701) (xy 141.952035 -285.257387)
			(xy 141.975686 -285.30245) (xy 141.991802 -285.350724) (xy 141.999966 -285.400958) (xy 142.000478 -285.426404)
			(xy 142.308575 -285.426404) (xy 142.31267 -285.375676) (xy 142.324849 -285.326262) (xy 142.344797 -285.279442)
			(xy 142.371998 -285.236428) (xy 142.405746 -285.198334) (xy 142.445168 -285.166147) (xy 142.489242 -285.140701)
			(xy 142.536828 -285.122654) (xy 142.586692 -285.112474) (xy 142.637544 -285.110425) (xy 142.688065 -285.116559)
			(xy 142.736949 -285.130719) (xy 142.782928 -285.152536) (xy 142.824812 -285.181446) (xy 142.861516 -285.216701)
			(xy 142.892089 -285.257387) (xy 142.91574 -285.30245) (xy 142.931856 -285.350724) (xy 142.94002 -285.400958)
			(xy 142.940532 -285.426404) (xy 145.138914 -285.426404) (xy 145.142874 -285.37735) (xy 145.154651 -285.329566)
			(xy 145.173942 -285.28429) (xy 145.200245 -285.242694) (xy 145.23288 -285.205857) (xy 145.271001 -285.174732)
			(xy 145.313622 -285.150125) (xy 145.359638 -285.132673) (xy 145.407857 -285.122829) (xy 145.457032 -285.120848)
			(xy 145.505887 -285.12678) (xy 145.553158 -285.140472) (xy 145.59762 -285.16157) (xy 145.638123 -285.189526)
			(xy 145.673616 -285.223618) (xy 145.703181 -285.262962) (xy 145.726052 -285.306539) (xy 145.727316 -285.310326)
			(xy 169.276283 -285.310326) (xy 169.280218 -285.256555) (xy 169.291941 -285.203931) (xy 169.311201 -285.153574)
			(xy 169.337587 -285.106557) (xy 169.370539 -285.063884) (xy 169.409352 -285.026463) (xy 169.4532 -284.995093)
			(xy 169.501148 -284.970441) (xy 169.552175 -284.953033) (xy 169.605193 -284.94324) (xy 169.659072 -284.941271)
			(xy 169.712663 -284.947168) (xy 169.764824 -284.960804) (xy 169.814444 -284.981891) (xy 169.860465 -285.009977)
			(xy 169.901907 -285.044465) (xy 169.937885 -285.084619) (xy 169.967633 -285.129583) (xy 169.990518 -285.1784)
			(xy 170.00605 -285.230029) (xy 170.0139 -285.283369) (xy 170.014392 -285.310326) (xy 170.0139 -285.337283)
			(xy 170.00605 -285.390623) (xy 169.990518 -285.442252) (xy 169.967633 -285.491069) (xy 169.937885 -285.536033)
			(xy 169.901907 -285.576187) (xy 169.860465 -285.610675) (xy 169.814444 -285.638761) (xy 169.764824 -285.659848)
			(xy 169.712663 -285.673484) (xy 169.659072 -285.679381) (xy 169.605193 -285.677412) (xy 169.552175 -285.667619)
			(xy 169.501148 -285.650211) (xy 169.4532 -285.625559) (xy 169.409352 -285.594189) (xy 169.370539 -285.556768)
			(xy 169.337587 -285.514095) (xy 169.311201 -285.467078) (xy 169.291941 -285.416721) (xy 169.280218 -285.364097)
			(xy 169.276283 -285.310326) (xy 145.727316 -285.310326) (xy 145.741636 -285.35322) (xy 145.749531 -285.401797)
			(xy 145.750026 -285.426404) (xy 145.749531 -285.451011) (xy 145.741636 -285.499588) (xy 145.726052 -285.546269)
			(xy 145.703181 -285.589846) (xy 145.673616 -285.62919) (xy 145.638123 -285.663282) (xy 145.59762 -285.691238)
			(xy 145.553158 -285.712336) (xy 145.505887 -285.726028) (xy 145.457032 -285.73196) (xy 145.407857 -285.729979)
			(xy 145.359638 -285.720135) (xy 145.313622 -285.702683) (xy 145.271001 -285.678076) (xy 145.23288 -285.646951)
			(xy 145.200245 -285.610114) (xy 145.173942 -285.568518) (xy 145.154651 -285.523242) (xy 145.142874 -285.475458)
			(xy 145.138914 -285.426404) (xy 142.940532 -285.426404) (xy 142.94002 -285.45185) (xy 142.931856 -285.502084)
			(xy 142.91574 -285.550358) (xy 142.892089 -285.595421) (xy 142.861516 -285.636107) (xy 142.824812 -285.671362)
			(xy 142.782928 -285.700272) (xy 142.736949 -285.722089) (xy 142.688065 -285.736249) (xy 142.637544 -285.742383)
			(xy 142.586692 -285.740334) (xy 142.536828 -285.730154) (xy 142.489242 -285.712107) (xy 142.445168 -285.686661)
			(xy 142.405746 -285.654474) (xy 142.371998 -285.61638) (xy 142.344797 -285.573366) (xy 142.324849 -285.526546)
			(xy 142.31267 -285.477132) (xy 142.308575 -285.426404) (xy 142.000478 -285.426404) (xy 141.999966 -285.45185)
			(xy 141.991802 -285.502084) (xy 141.975686 -285.550358) (xy 141.952035 -285.595421) (xy 141.921462 -285.636107)
			(xy 141.884758 -285.671362) (xy 141.842874 -285.700272) (xy 141.796895 -285.722089) (xy 141.748011 -285.736249)
			(xy 141.69749 -285.742383) (xy 141.646638 -285.740334) (xy 141.596774 -285.730154) (xy 141.549188 -285.712107)
			(xy 141.505114 -285.686661) (xy 141.465692 -285.654474) (xy 141.431944 -285.61638) (xy 141.404743 -285.573366)
			(xy 141.384795 -285.526546) (xy 141.372616 -285.477132) (xy 141.368521 -285.426404) (xy 141.05001 -285.426404)
			(xy 141.049515 -285.451011) (xy 141.04162 -285.499588) (xy 141.026036 -285.546269) (xy 141.003165 -285.589846)
			(xy 140.9736 -285.62919) (xy 140.938107 -285.663282) (xy 140.897604 -285.691238) (xy 140.853142 -285.712336)
			(xy 140.805871 -285.726028) (xy 140.757016 -285.73196) (xy 140.707841 -285.729979) (xy 140.659622 -285.720135)
			(xy 140.613606 -285.702683) (xy 140.570985 -285.678076) (xy 140.532864 -285.646951) (xy 140.500229 -285.610114)
			(xy 140.473926 -285.568518) (xy 140.454635 -285.523242) (xy 140.442858 -285.475458) (xy 140.438898 -285.426404)
			(xy 140.12037 -285.426404) (xy 140.119858 -285.45185) (xy 140.111694 -285.502084) (xy 140.095578 -285.550358)
			(xy 140.071927 -285.595421) (xy 140.041354 -285.636107) (xy 140.00465 -285.671362) (xy 139.962766 -285.700272)
			(xy 139.916787 -285.722089) (xy 139.867903 -285.736249) (xy 139.817382 -285.742383) (xy 139.76653 -285.740334)
			(xy 139.716666 -285.730154) (xy 139.66908 -285.712107) (xy 139.625006 -285.686661) (xy 139.585584 -285.654474)
			(xy 139.551836 -285.61638) (xy 139.524635 -285.573366) (xy 139.504687 -285.526546) (xy 139.492508 -285.477132)
			(xy 139.488413 -285.426404) (xy 139.170156 -285.426404) (xy 139.169661 -285.451011) (xy 139.161766 -285.499588)
			(xy 139.146182 -285.546269) (xy 139.123311 -285.589846) (xy 139.093746 -285.62919) (xy 139.058253 -285.663282)
			(xy 139.01775 -285.691238) (xy 138.973288 -285.712336) (xy 138.926017 -285.726028) (xy 138.877162 -285.73196)
			(xy 138.827987 -285.729979) (xy 138.779768 -285.720135) (xy 138.733752 -285.702683) (xy 138.691131 -285.678076)
			(xy 138.65301 -285.646951) (xy 138.620375 -285.610114) (xy 138.594072 -285.568518) (xy 138.574781 -285.523242)
			(xy 138.563004 -285.475458) (xy 138.559044 -285.426404) (xy 138.240516 -285.426404) (xy 138.240004 -285.45185)
			(xy 138.23184 -285.502084) (xy 138.215724 -285.550358) (xy 138.192073 -285.595421) (xy 138.1615 -285.636107)
			(xy 138.124796 -285.671362) (xy 138.082912 -285.700272) (xy 138.036933 -285.722089) (xy 137.988049 -285.736249)
			(xy 137.937528 -285.742383) (xy 137.886676 -285.740334) (xy 137.836812 -285.730154) (xy 137.789226 -285.712107)
			(xy 137.745152 -285.686661) (xy 137.70573 -285.654474) (xy 137.671982 -285.61638) (xy 137.644781 -285.573366)
			(xy 137.624833 -285.526546) (xy 137.612654 -285.477132) (xy 137.608559 -285.426404) (xy 136.360408 -285.426404)
			(xy 136.359896 -285.45185) (xy 136.351732 -285.502084) (xy 136.335616 -285.550358) (xy 136.311965 -285.595421)
			(xy 136.281392 -285.636107) (xy 136.244688 -285.671362) (xy 136.202804 -285.700272) (xy 136.156825 -285.722089)
			(xy 136.107941 -285.736249) (xy 136.05742 -285.742383) (xy 136.006568 -285.740334) (xy 135.956704 -285.730154)
			(xy 135.909118 -285.712107) (xy 135.865044 -285.686661) (xy 135.825622 -285.654474) (xy 135.791874 -285.61638)
			(xy 135.764673 -285.573366) (xy 135.744725 -285.526546) (xy 135.732546 -285.477132) (xy 135.728451 -285.426404)
			(xy 135.420354 -285.426404) (xy 135.419842 -285.45185) (xy 135.411678 -285.502084) (xy 135.395562 -285.550358)
			(xy 135.371911 -285.595421) (xy 135.341338 -285.636107) (xy 135.304634 -285.671362) (xy 135.26275 -285.700272)
			(xy 135.216771 -285.722089) (xy 135.167887 -285.736249) (xy 135.117366 -285.742383) (xy 135.066514 -285.740334)
			(xy 135.01665 -285.730154) (xy 134.969064 -285.712107) (xy 134.92499 -285.686661) (xy 134.885568 -285.654474)
			(xy 134.85182 -285.61638) (xy 134.824619 -285.573366) (xy 134.804671 -285.526546) (xy 134.792492 -285.477132)
			(xy 134.788397 -285.426404) (xy 134.47014 -285.426404) (xy 134.469645 -285.451011) (xy 134.46175 -285.499588)
			(xy 134.446166 -285.546269) (xy 134.423295 -285.589846) (xy 134.39373 -285.62919) (xy 134.358237 -285.663282)
			(xy 134.317734 -285.691238) (xy 134.273272 -285.712336) (xy 134.226001 -285.726028) (xy 134.177146 -285.73196)
			(xy 134.127971 -285.729979) (xy 134.079752 -285.720135) (xy 134.033736 -285.702683) (xy 133.991115 -285.678076)
			(xy 133.952994 -285.646951) (xy 133.920359 -285.610114) (xy 133.894056 -285.568518) (xy 133.874765 -285.523242)
			(xy 133.862988 -285.475458) (xy 133.859028 -285.426404) (xy 133.5405 -285.426404) (xy 133.539988 -285.45185)
			(xy 133.531824 -285.502084) (xy 133.515708 -285.550358) (xy 133.492057 -285.595421) (xy 133.461484 -285.636107)
			(xy 133.42478 -285.671362) (xy 133.382896 -285.700272) (xy 133.336917 -285.722089) (xy 133.288033 -285.736249)
			(xy 133.237512 -285.742383) (xy 133.18666 -285.740334) (xy 133.136796 -285.730154) (xy 133.08921 -285.712107)
			(xy 133.045136 -285.686661) (xy 133.005714 -285.654474) (xy 132.971966 -285.61638) (xy 132.944765 -285.573366)
			(xy 132.924817 -285.526546) (xy 132.912638 -285.477132) (xy 132.908543 -285.426404) (xy 132.590032 -285.426404)
			(xy 132.589537 -285.451011) (xy 132.581642 -285.499588) (xy 132.566058 -285.546269) (xy 132.543187 -285.589846)
			(xy 132.513622 -285.62919) (xy 132.478129 -285.663282) (xy 132.437626 -285.691238) (xy 132.393164 -285.712336)
			(xy 132.345893 -285.726028) (xy 132.297038 -285.73196) (xy 132.247863 -285.729979) (xy 132.199644 -285.720135)
			(xy 132.153628 -285.702683) (xy 132.111007 -285.678076) (xy 132.072886 -285.646951) (xy 132.040251 -285.610114)
			(xy 132.013948 -285.568518) (xy 131.994657 -285.523242) (xy 131.98288 -285.475458) (xy 131.97892 -285.426404)
			(xy 131.660392 -285.426404) (xy 131.65988 -285.45185) (xy 131.651716 -285.502084) (xy 131.6356 -285.550358)
			(xy 131.611949 -285.595421) (xy 131.581376 -285.636107) (xy 131.544672 -285.671362) (xy 131.502788 -285.700272)
			(xy 131.456809 -285.722089) (xy 131.407925 -285.736249) (xy 131.357404 -285.742383) (xy 131.306552 -285.740334)
			(xy 131.256688 -285.730154) (xy 131.209102 -285.712107) (xy 131.165028 -285.686661) (xy 131.125606 -285.654474)
			(xy 131.091858 -285.61638) (xy 131.064657 -285.573366) (xy 131.044709 -285.526546) (xy 131.03253 -285.477132)
			(xy 131.028435 -285.426404) (xy 129.780538 -285.426404) (xy 129.780026 -285.45185) (xy 129.771862 -285.502084)
			(xy 129.755746 -285.550358) (xy 129.732095 -285.595421) (xy 129.701522 -285.636107) (xy 129.664818 -285.671362)
			(xy 129.622934 -285.700272) (xy 129.576955 -285.722089) (xy 129.528071 -285.736249) (xy 129.47755 -285.742383)
			(xy 129.426698 -285.740334) (xy 129.376834 -285.730154) (xy 129.329248 -285.712107) (xy 129.285174 -285.686661)
			(xy 129.245752 -285.654474) (xy 129.212004 -285.61638) (xy 129.184803 -285.573366) (xy 129.164855 -285.526546)
			(xy 129.152676 -285.477132) (xy 129.148581 -285.426404) (xy 128.840484 -285.426404) (xy 128.839972 -285.45185)
			(xy 128.831808 -285.502084) (xy 128.815692 -285.550358) (xy 128.792041 -285.595421) (xy 128.761468 -285.636107)
			(xy 128.724764 -285.671362) (xy 128.68288 -285.700272) (xy 128.636901 -285.722089) (xy 128.588017 -285.736249)
			(xy 128.537496 -285.742383) (xy 128.486644 -285.740334) (xy 128.43678 -285.730154) (xy 128.389194 -285.712107)
			(xy 128.34512 -285.686661) (xy 128.305698 -285.654474) (xy 128.27195 -285.61638) (xy 128.244749 -285.573366)
			(xy 128.224801 -285.526546) (xy 128.212622 -285.477132) (xy 128.208527 -285.426404) (xy 127.20574 -285.426404)
			(xy 127.20574 -285.925006) (xy 127.22225 -285.950152) (xy 127.23622 -285.956248) (xy 127.259286 -285.966791)
			(xy 127.301844 -285.994367) (xy 127.339261 -286.028596) (xy 127.370509 -286.068536) (xy 127.394729 -286.11309)
			(xy 127.411254 -286.161033) (xy 127.419632 -286.211048) (xy 127.419631 -286.23641) (xy 127.738627 -286.23641)
			(xy 127.742722 -286.185682) (xy 127.754901 -286.136268) (xy 127.774849 -286.089448) (xy 127.80205 -286.046434)
			(xy 127.835798 -286.00834) (xy 127.87522 -285.976153) (xy 127.919294 -285.950707) (xy 127.96688 -285.93266)
			(xy 128.016744 -285.92248) (xy 128.067596 -285.920431) (xy 128.118117 -285.926565) (xy 128.167001 -285.940725)
			(xy 128.21298 -285.962542) (xy 128.254864 -285.991452) (xy 128.291568 -286.026707) (xy 128.322141 -286.067393)
			(xy 128.345792 -286.112456) (xy 128.361908 -286.16073) (xy 128.370072 -286.210964) (xy 128.370584 -286.23641)
			(xy 128.688858 -286.23641) (xy 128.692818 -286.187356) (xy 128.704595 -286.139572) (xy 128.723886 -286.094296)
			(xy 128.750189 -286.0527) (xy 128.782824 -286.015863) (xy 128.820945 -285.984738) (xy 128.863566 -285.960131)
			(xy 128.909582 -285.942679) (xy 128.957801 -285.932835) (xy 129.006976 -285.930854) (xy 129.055831 -285.936786)
			(xy 129.103102 -285.950478) (xy 129.147564 -285.971576) (xy 129.188067 -285.999532) (xy 129.22356 -286.033624)
			(xy 129.253125 -286.072968) (xy 129.275996 -286.116545) (xy 129.29158 -286.163226) (xy 129.299475 -286.211803)
			(xy 129.29997 -286.23641) (xy 129.618481 -286.23641) (xy 129.622576 -286.185682) (xy 129.634755 -286.136268)
			(xy 129.654703 -286.089448) (xy 129.681904 -286.046434) (xy 129.715652 -286.00834) (xy 129.755074 -285.976153)
			(xy 129.799148 -285.950707) (xy 129.846734 -285.93266) (xy 129.896598 -285.92248) (xy 129.94745 -285.920431)
			(xy 129.997971 -285.926565) (xy 130.046855 -285.940725) (xy 130.092834 -285.962542) (xy 130.134718 -285.991452)
			(xy 130.171422 -286.026707) (xy 130.201995 -286.067393) (xy 130.225646 -286.112456) (xy 130.241762 -286.16073)
			(xy 130.249926 -286.210964) (xy 130.250438 -286.23641) (xy 130.568966 -286.23641) (xy 130.572926 -286.187356)
			(xy 130.584703 -286.139572) (xy 130.603994 -286.094296) (xy 130.630297 -286.0527) (xy 130.662932 -286.015863)
			(xy 130.701053 -285.984738) (xy 130.743674 -285.960131) (xy 130.78969 -285.942679) (xy 130.837909 -285.932835)
			(xy 130.887084 -285.930854) (xy 130.935939 -285.936786) (xy 130.98321 -285.950478) (xy 131.027672 -285.971576)
			(xy 131.068175 -285.999532) (xy 131.103668 -286.033624) (xy 131.133233 -286.072968) (xy 131.156104 -286.116545)
			(xy 131.171688 -286.163226) (xy 131.179583 -286.211803) (xy 131.180078 -286.23641) (xy 131.498589 -286.23641)
			(xy 131.502684 -286.185682) (xy 131.514863 -286.136268) (xy 131.534811 -286.089448) (xy 131.562012 -286.046434)
			(xy 131.59576 -286.00834) (xy 131.635182 -285.976153) (xy 131.679256 -285.950707) (xy 131.726842 -285.93266)
			(xy 131.776706 -285.92248) (xy 131.827558 -285.920431) (xy 131.878079 -285.926565) (xy 131.926963 -285.940725)
			(xy 131.972942 -285.962542) (xy 132.014826 -285.991452) (xy 132.05153 -286.026707) (xy 132.082103 -286.067393)
			(xy 132.105754 -286.112456) (xy 132.12187 -286.16073) (xy 132.130034 -286.210964) (xy 132.130546 -286.23641)
			(xy 132.438643 -286.23641) (xy 132.442738 -286.185682) (xy 132.454917 -286.136268) (xy 132.474865 -286.089448)
			(xy 132.502066 -286.046434) (xy 132.535814 -286.00834) (xy 132.575236 -285.976153) (xy 132.61931 -285.950707)
			(xy 132.666896 -285.93266) (xy 132.71676 -285.92248) (xy 132.767612 -285.920431) (xy 132.818133 -285.926565)
			(xy 132.867017 -285.940725) (xy 132.912996 -285.962542) (xy 132.95488 -285.991452) (xy 132.991584 -286.026707)
			(xy 133.022157 -286.067393) (xy 133.045808 -286.112456) (xy 133.061924 -286.16073) (xy 133.070088 -286.210964)
			(xy 133.0706 -286.23641) (xy 133.388874 -286.23641) (xy 133.392834 -286.187356) (xy 133.404611 -286.139572)
			(xy 133.423902 -286.094296) (xy 133.450205 -286.0527) (xy 133.48284 -286.015863) (xy 133.520961 -285.984738)
			(xy 133.563582 -285.960131) (xy 133.609598 -285.942679) (xy 133.657817 -285.932835) (xy 133.706992 -285.930854)
			(xy 133.755847 -285.936786) (xy 133.803118 -285.950478) (xy 133.84758 -285.971576) (xy 133.888083 -285.999532)
			(xy 133.923576 -286.033624) (xy 133.953141 -286.072968) (xy 133.976012 -286.116545) (xy 133.991596 -286.163226)
			(xy 133.999491 -286.211803) (xy 133.999986 -286.23641) (xy 134.318497 -286.23641) (xy 134.322592 -286.185682)
			(xy 134.334771 -286.136268) (xy 134.354719 -286.089448) (xy 134.38192 -286.046434) (xy 134.415668 -286.00834)
			(xy 134.45509 -285.976153) (xy 134.499164 -285.950707) (xy 134.54675 -285.93266) (xy 134.596614 -285.92248)
			(xy 134.647466 -285.920431) (xy 134.697987 -285.926565) (xy 134.746871 -285.940725) (xy 134.79285 -285.962542)
			(xy 134.834734 -285.991452) (xy 134.871438 -286.026707) (xy 134.902011 -286.067393) (xy 134.925662 -286.112456)
			(xy 134.941778 -286.16073) (xy 134.949942 -286.210964) (xy 134.950454 -286.23641) (xy 135.268982 -286.23641)
			(xy 135.272942 -286.187356) (xy 135.284719 -286.139572) (xy 135.30401 -286.094296) (xy 135.330313 -286.0527)
			(xy 135.362948 -286.015863) (xy 135.401069 -285.984738) (xy 135.44369 -285.960131) (xy 135.489706 -285.942679)
			(xy 135.537925 -285.932835) (xy 135.5871 -285.930854) (xy 135.635955 -285.936786) (xy 135.683226 -285.950478)
			(xy 135.727688 -285.971576) (xy 135.768191 -285.999532) (xy 135.803684 -286.033624) (xy 135.833249 -286.072968)
			(xy 135.85612 -286.116545) (xy 135.871704 -286.163226) (xy 135.879599 -286.211803) (xy 135.880094 -286.23641)
			(xy 136.198605 -286.23641) (xy 136.2027 -286.185682) (xy 136.214879 -286.136268) (xy 136.234827 -286.089448)
			(xy 136.262028 -286.046434) (xy 136.295776 -286.00834) (xy 136.335198 -285.976153) (xy 136.379272 -285.950707)
			(xy 136.426858 -285.93266) (xy 136.476722 -285.92248) (xy 136.527574 -285.920431) (xy 136.578095 -285.926565)
			(xy 136.626979 -285.940725) (xy 136.672958 -285.962542) (xy 136.714842 -285.991452) (xy 136.751546 -286.026707)
			(xy 136.782119 -286.067393) (xy 136.80577 -286.112456) (xy 136.821886 -286.16073) (xy 136.83005 -286.210964)
			(xy 136.830562 -286.23641) (xy 137.148836 -286.23641) (xy 137.152796 -286.187356) (xy 137.164573 -286.139572)
			(xy 137.183864 -286.094296) (xy 137.210167 -286.0527) (xy 137.242802 -286.015863) (xy 137.280923 -285.984738)
			(xy 137.323544 -285.960131) (xy 137.36956 -285.942679) (xy 137.417779 -285.932835) (xy 137.466954 -285.930854)
			(xy 137.515809 -285.936786) (xy 137.56308 -285.950478) (xy 137.607542 -285.971576) (xy 137.648045 -285.999532)
			(xy 137.683538 -286.033624) (xy 137.713103 -286.072968) (xy 137.735974 -286.116545) (xy 137.751558 -286.163226)
			(xy 137.759453 -286.211803) (xy 137.759948 -286.23641) (xy 138.078459 -286.23641) (xy 138.082554 -286.185682)
			(xy 138.094733 -286.136268) (xy 138.114681 -286.089448) (xy 138.141882 -286.046434) (xy 138.17563 -286.00834)
			(xy 138.215052 -285.976153) (xy 138.259126 -285.950707) (xy 138.306712 -285.93266) (xy 138.356576 -285.92248)
			(xy 138.407428 -285.920431) (xy 138.457949 -285.926565) (xy 138.506833 -285.940725) (xy 138.552812 -285.962542)
			(xy 138.594696 -285.991452) (xy 138.6314 -286.026707) (xy 138.661973 -286.067393) (xy 138.685624 -286.112456)
			(xy 138.70174 -286.16073) (xy 138.709904 -286.210964) (xy 138.710416 -286.23641) (xy 139.018513 -286.23641)
			(xy 139.022608 -286.185682) (xy 139.034787 -286.136268) (xy 139.054735 -286.089448) (xy 139.081936 -286.046434)
			(xy 139.115684 -286.00834) (xy 139.155106 -285.976153) (xy 139.19918 -285.950707) (xy 139.246766 -285.93266)
			(xy 139.29663 -285.92248) (xy 139.347482 -285.920431) (xy 139.398003 -285.926565) (xy 139.446887 -285.940725)
			(xy 139.492866 -285.962542) (xy 139.53475 -285.991452) (xy 139.571454 -286.026707) (xy 139.602027 -286.067393)
			(xy 139.625678 -286.112456) (xy 139.641794 -286.16073) (xy 139.649958 -286.210964) (xy 139.65047 -286.23641)
			(xy 139.968998 -286.23641) (xy 139.972958 -286.187356) (xy 139.984735 -286.139572) (xy 140.004026 -286.094296)
			(xy 140.030329 -286.0527) (xy 140.062964 -286.015863) (xy 140.101085 -285.984738) (xy 140.143706 -285.960131)
			(xy 140.189722 -285.942679) (xy 140.237941 -285.932835) (xy 140.287116 -285.930854) (xy 140.335971 -285.936786)
			(xy 140.383242 -285.950478) (xy 140.427704 -285.971576) (xy 140.468207 -285.999532) (xy 140.5037 -286.033624)
			(xy 140.533265 -286.072968) (xy 140.556136 -286.116545) (xy 140.57172 -286.163226) (xy 140.579615 -286.211803)
			(xy 140.58011 -286.23641) (xy 140.898621 -286.23641) (xy 140.902716 -286.185682) (xy 140.914895 -286.136268)
			(xy 140.934843 -286.089448) (xy 140.962044 -286.046434) (xy 140.995792 -286.00834) (xy 141.035214 -285.976153)
			(xy 141.079288 -285.950707) (xy 141.126874 -285.93266) (xy 141.176738 -285.92248) (xy 141.22759 -285.920431)
			(xy 141.278111 -285.926565) (xy 141.326995 -285.940725) (xy 141.372974 -285.962542) (xy 141.414858 -285.991452)
			(xy 141.451562 -286.026707) (xy 141.482135 -286.067393) (xy 141.505786 -286.112456) (xy 141.521902 -286.16073)
			(xy 141.530066 -286.210964) (xy 141.530578 -286.23641) (xy 141.848852 -286.23641) (xy 141.852812 -286.187356)
			(xy 141.864589 -286.139572) (xy 141.88388 -286.094296) (xy 141.910183 -286.0527) (xy 141.942818 -286.015863)
			(xy 141.980939 -285.984738) (xy 142.02356 -285.960131) (xy 142.069576 -285.942679) (xy 142.117795 -285.932835)
			(xy 142.16697 -285.930854) (xy 142.215825 -285.936786) (xy 142.263096 -285.950478) (xy 142.307558 -285.971576)
			(xy 142.348061 -285.999532) (xy 142.383554 -286.033624) (xy 142.413119 -286.072968) (xy 142.43599 -286.116545)
			(xy 142.451574 -286.163226) (xy 142.459469 -286.211803) (xy 142.459964 -286.23641) (xy 142.778475 -286.23641)
			(xy 142.78257 -286.185682) (xy 142.794749 -286.136268) (xy 142.814697 -286.089448) (xy 142.841898 -286.046434)
			(xy 142.875646 -286.00834) (xy 142.915068 -285.976153) (xy 142.959142 -285.950707) (xy 143.006728 -285.93266)
			(xy 143.056592 -285.92248) (xy 143.107444 -285.920431) (xy 143.157965 -285.926565) (xy 143.206849 -285.940725)
			(xy 143.252828 -285.962542) (xy 143.294712 -285.991452) (xy 143.331416 -286.026707) (xy 143.361989 -286.067393)
			(xy 143.38564 -286.112456) (xy 143.401756 -286.16073) (xy 143.40992 -286.210964) (xy 143.410432 -286.23641)
			(xy 143.72896 -286.23641) (xy 143.73292 -286.187356) (xy 143.744697 -286.139572) (xy 143.763988 -286.094296)
			(xy 143.790291 -286.0527) (xy 143.822926 -286.015863) (xy 143.861047 -285.984738) (xy 143.903668 -285.960131)
			(xy 143.949684 -285.942679) (xy 143.997903 -285.932835) (xy 144.047078 -285.930854) (xy 144.095933 -285.936786)
			(xy 144.143204 -285.950478) (xy 144.185339 -285.970472) (xy 146.737082 -285.970472) (xy 146.741042 -285.921418)
			(xy 146.752819 -285.873634) (xy 146.77211 -285.828358) (xy 146.798413 -285.786762) (xy 146.831048 -285.749925)
			(xy 146.869169 -285.7188) (xy 146.91179 -285.694193) (xy 146.957806 -285.676741) (xy 147.006025 -285.666897)
			(xy 147.0552 -285.664916) (xy 147.104055 -285.670848) (xy 147.151326 -285.68454) (xy 147.195788 -285.705638)
			(xy 147.236291 -285.733594) (xy 147.271784 -285.767686) (xy 147.301349 -285.80703) (xy 147.32422 -285.850607)
			(xy 147.339804 -285.897288) (xy 147.347699 -285.945865) (xy 147.348194 -285.970472) (xy 147.347699 -285.995079)
			(xy 147.339804 -286.043656) (xy 147.32422 -286.090337) (xy 147.301349 -286.133914) (xy 147.281398 -286.160464)
			(xy 165.176215 -286.160464) (xy 165.18015 -286.106693) (xy 165.191873 -286.054069) (xy 165.211133 -286.003712)
			(xy 165.237519 -285.956695) (xy 165.270471 -285.914022) (xy 165.309284 -285.876601) (xy 165.353132 -285.845231)
			(xy 165.40108 -285.820579) (xy 165.452107 -285.803171) (xy 165.505125 -285.793378) (xy 165.559004 -285.791409)
			(xy 165.612595 -285.797306) (xy 165.664756 -285.810942) (xy 165.714376 -285.832029) (xy 165.760397 -285.860115)
			(xy 165.801839 -285.894603) (xy 165.837817 -285.934757) (xy 165.867565 -285.979721) (xy 165.89045 -286.028538)
			(xy 165.905982 -286.080167) (xy 165.913832 -286.133507) (xy 165.914324 -286.160464) (xy 165.913832 -286.187421)
			(xy 165.905982 -286.240761) (xy 165.89045 -286.29239) (xy 165.867565 -286.341207) (xy 165.837817 -286.386171)
			(xy 165.801839 -286.426325) (xy 165.760397 -286.460813) (xy 165.714376 -286.488899) (xy 165.664756 -286.509986)
			(xy 165.612595 -286.523622) (xy 165.559004 -286.529519) (xy 165.505125 -286.52755) (xy 165.452107 -286.517757)
			(xy 165.40108 -286.500349) (xy 165.353132 -286.475697) (xy 165.309284 -286.444327) (xy 165.270471 -286.406906)
			(xy 165.237519 -286.364233) (xy 165.211133 -286.317216) (xy 165.191873 -286.266859) (xy 165.18015 -286.214235)
			(xy 165.176215 -286.160464) (xy 147.281398 -286.160464) (xy 147.271784 -286.173258) (xy 147.236291 -286.20735)
			(xy 147.195788 -286.235306) (xy 147.151326 -286.256404) (xy 147.104055 -286.270096) (xy 147.0552 -286.276028)
			(xy 147.006025 -286.274047) (xy 146.957806 -286.264203) (xy 146.91179 -286.246751) (xy 146.869169 -286.222144)
			(xy 146.831048 -286.191019) (xy 146.798413 -286.154182) (xy 146.77211 -286.112586) (xy 146.752819 -286.06731)
			(xy 146.741042 -286.019526) (xy 146.737082 -285.970472) (xy 144.185339 -285.970472) (xy 144.187666 -285.971576)
			(xy 144.228169 -285.999532) (xy 144.263662 -286.033624) (xy 144.293227 -286.072968) (xy 144.316098 -286.116545)
			(xy 144.331682 -286.163226) (xy 144.339577 -286.211803) (xy 144.340072 -286.23641) (xy 144.339577 -286.261017)
			(xy 144.331682 -286.309594) (xy 144.316098 -286.356275) (xy 144.293227 -286.399852) (xy 144.263662 -286.439196)
			(xy 144.228169 -286.473288) (xy 144.187666 -286.501244) (xy 144.143204 -286.522342) (xy 144.095933 -286.536034)
			(xy 144.047078 -286.541966) (xy 143.997903 -286.539985) (xy 143.949684 -286.530141) (xy 143.903668 -286.512689)
			(xy 143.861047 -286.488082) (xy 143.822926 -286.456957) (xy 143.790291 -286.42012) (xy 143.763988 -286.378524)
			(xy 143.744697 -286.333248) (xy 143.73292 -286.285464) (xy 143.72896 -286.23641) (xy 143.410432 -286.23641)
			(xy 143.40992 -286.261856) (xy 143.401756 -286.31209) (xy 143.38564 -286.360364) (xy 143.361989 -286.405427)
			(xy 143.331416 -286.446113) (xy 143.294712 -286.481368) (xy 143.252828 -286.510278) (xy 143.206849 -286.532095)
			(xy 143.157965 -286.546255) (xy 143.107444 -286.552389) (xy 143.056592 -286.55034) (xy 143.006728 -286.54016)
			(xy 142.959142 -286.522113) (xy 142.915068 -286.496667) (xy 142.875646 -286.46448) (xy 142.841898 -286.426386)
			(xy 142.814697 -286.383372) (xy 142.794749 -286.336552) (xy 142.78257 -286.287138) (xy 142.778475 -286.23641)
			(xy 142.459964 -286.23641) (xy 142.459469 -286.261017) (xy 142.451574 -286.309594) (xy 142.43599 -286.356275)
			(xy 142.413119 -286.399852) (xy 142.383554 -286.439196) (xy 142.348061 -286.473288) (xy 142.307558 -286.501244)
			(xy 142.263096 -286.522342) (xy 142.215825 -286.536034) (xy 142.16697 -286.541966) (xy 142.117795 -286.539985)
			(xy 142.069576 -286.530141) (xy 142.02356 -286.512689) (xy 141.980939 -286.488082) (xy 141.942818 -286.456957)
			(xy 141.910183 -286.42012) (xy 141.88388 -286.378524) (xy 141.864589 -286.333248) (xy 141.852812 -286.285464)
			(xy 141.848852 -286.23641) (xy 141.530578 -286.23641) (xy 141.530066 -286.261856) (xy 141.521902 -286.31209)
			(xy 141.505786 -286.360364) (xy 141.482135 -286.405427) (xy 141.451562 -286.446113) (xy 141.414858 -286.481368)
			(xy 141.372974 -286.510278) (xy 141.326995 -286.532095) (xy 141.278111 -286.546255) (xy 141.22759 -286.552389)
			(xy 141.176738 -286.55034) (xy 141.126874 -286.54016) (xy 141.079288 -286.522113) (xy 141.035214 -286.496667)
			(xy 140.995792 -286.46448) (xy 140.962044 -286.426386) (xy 140.934843 -286.383372) (xy 140.914895 -286.336552)
			(xy 140.902716 -286.287138) (xy 140.898621 -286.23641) (xy 140.58011 -286.23641) (xy 140.579615 -286.261017)
			(xy 140.57172 -286.309594) (xy 140.556136 -286.356275) (xy 140.533265 -286.399852) (xy 140.5037 -286.439196)
			(xy 140.468207 -286.473288) (xy 140.427704 -286.501244) (xy 140.383242 -286.522342) (xy 140.335971 -286.536034)
			(xy 140.287116 -286.541966) (xy 140.237941 -286.539985) (xy 140.189722 -286.530141) (xy 140.143706 -286.512689)
			(xy 140.101085 -286.488082) (xy 140.062964 -286.456957) (xy 140.030329 -286.42012) (xy 140.004026 -286.378524)
			(xy 139.984735 -286.333248) (xy 139.972958 -286.285464) (xy 139.968998 -286.23641) (xy 139.65047 -286.23641)
			(xy 139.649958 -286.261856) (xy 139.641794 -286.31209) (xy 139.625678 -286.360364) (xy 139.602027 -286.405427)
			(xy 139.571454 -286.446113) (xy 139.53475 -286.481368) (xy 139.492866 -286.510278) (xy 139.446887 -286.532095)
			(xy 139.398003 -286.546255) (xy 139.347482 -286.552389) (xy 139.29663 -286.55034) (xy 139.246766 -286.54016)
			(xy 139.19918 -286.522113) (xy 139.155106 -286.496667) (xy 139.115684 -286.46448) (xy 139.081936 -286.426386)
			(xy 139.054735 -286.383372) (xy 139.034787 -286.336552) (xy 139.022608 -286.287138) (xy 139.018513 -286.23641)
			(xy 138.710416 -286.23641) (xy 138.709904 -286.261856) (xy 138.70174 -286.31209) (xy 138.685624 -286.360364)
			(xy 138.661973 -286.405427) (xy 138.6314 -286.446113) (xy 138.594696 -286.481368) (xy 138.552812 -286.510278)
			(xy 138.506833 -286.532095) (xy 138.457949 -286.546255) (xy 138.407428 -286.552389) (xy 138.356576 -286.55034)
			(xy 138.306712 -286.54016) (xy 138.259126 -286.522113) (xy 138.215052 -286.496667) (xy 138.17563 -286.46448)
			(xy 138.141882 -286.426386) (xy 138.114681 -286.383372) (xy 138.094733 -286.336552) (xy 138.082554 -286.287138)
			(xy 138.078459 -286.23641) (xy 137.759948 -286.23641) (xy 137.759453 -286.261017) (xy 137.751558 -286.309594)
			(xy 137.735974 -286.356275) (xy 137.713103 -286.399852) (xy 137.683538 -286.439196) (xy 137.648045 -286.473288)
			(xy 137.607542 -286.501244) (xy 137.56308 -286.522342) (xy 137.515809 -286.536034) (xy 137.466954 -286.541966)
			(xy 137.417779 -286.539985) (xy 137.36956 -286.530141) (xy 137.323544 -286.512689) (xy 137.280923 -286.488082)
			(xy 137.242802 -286.456957) (xy 137.210167 -286.42012) (xy 137.183864 -286.378524) (xy 137.164573 -286.333248)
			(xy 137.152796 -286.285464) (xy 137.148836 -286.23641) (xy 136.830562 -286.23641) (xy 136.83005 -286.261856)
			(xy 136.821886 -286.31209) (xy 136.80577 -286.360364) (xy 136.782119 -286.405427) (xy 136.751546 -286.446113)
			(xy 136.714842 -286.481368) (xy 136.672958 -286.510278) (xy 136.626979 -286.532095) (xy 136.578095 -286.546255)
			(xy 136.527574 -286.552389) (xy 136.476722 -286.55034) (xy 136.426858 -286.54016) (xy 136.379272 -286.522113)
			(xy 136.335198 -286.496667) (xy 136.295776 -286.46448) (xy 136.262028 -286.426386) (xy 136.234827 -286.383372)
			(xy 136.214879 -286.336552) (xy 136.2027 -286.287138) (xy 136.198605 -286.23641) (xy 135.880094 -286.23641)
			(xy 135.879599 -286.261017) (xy 135.871704 -286.309594) (xy 135.85612 -286.356275) (xy 135.833249 -286.399852)
			(xy 135.803684 -286.439196) (xy 135.768191 -286.473288) (xy 135.727688 -286.501244) (xy 135.683226 -286.522342)
			(xy 135.635955 -286.536034) (xy 135.5871 -286.541966) (xy 135.537925 -286.539985) (xy 135.489706 -286.530141)
			(xy 135.44369 -286.512689) (xy 135.401069 -286.488082) (xy 135.362948 -286.456957) (xy 135.330313 -286.42012)
			(xy 135.30401 -286.378524) (xy 135.284719 -286.333248) (xy 135.272942 -286.285464) (xy 135.268982 -286.23641)
			(xy 134.950454 -286.23641) (xy 134.949942 -286.261856) (xy 134.941778 -286.31209) (xy 134.925662 -286.360364)
			(xy 134.902011 -286.405427) (xy 134.871438 -286.446113) (xy 134.834734 -286.481368) (xy 134.79285 -286.510278)
			(xy 134.746871 -286.532095) (xy 134.697987 -286.546255) (xy 134.647466 -286.552389) (xy 134.596614 -286.55034)
			(xy 134.54675 -286.54016) (xy 134.499164 -286.522113) (xy 134.45509 -286.496667) (xy 134.415668 -286.46448)
			(xy 134.38192 -286.426386) (xy 134.354719 -286.383372) (xy 134.334771 -286.336552) (xy 134.322592 -286.287138)
			(xy 134.318497 -286.23641) (xy 133.999986 -286.23641) (xy 133.999491 -286.261017) (xy 133.991596 -286.309594)
			(xy 133.976012 -286.356275) (xy 133.953141 -286.399852) (xy 133.923576 -286.439196) (xy 133.888083 -286.473288)
			(xy 133.84758 -286.501244) (xy 133.803118 -286.522342) (xy 133.755847 -286.536034) (xy 133.706992 -286.541966)
			(xy 133.657817 -286.539985) (xy 133.609598 -286.530141) (xy 133.563582 -286.512689) (xy 133.520961 -286.488082)
			(xy 133.48284 -286.456957) (xy 133.450205 -286.42012) (xy 133.423902 -286.378524) (xy 133.404611 -286.333248)
			(xy 133.392834 -286.285464) (xy 133.388874 -286.23641) (xy 133.0706 -286.23641) (xy 133.070088 -286.261856)
			(xy 133.061924 -286.31209) (xy 133.045808 -286.360364) (xy 133.022157 -286.405427) (xy 132.991584 -286.446113)
			(xy 132.95488 -286.481368) (xy 132.912996 -286.510278) (xy 132.867017 -286.532095) (xy 132.818133 -286.546255)
			(xy 132.767612 -286.552389) (xy 132.71676 -286.55034) (xy 132.666896 -286.54016) (xy 132.61931 -286.522113)
			(xy 132.575236 -286.496667) (xy 132.535814 -286.46448) (xy 132.502066 -286.426386) (xy 132.474865 -286.383372)
			(xy 132.454917 -286.336552) (xy 132.442738 -286.287138) (xy 132.438643 -286.23641) (xy 132.130546 -286.23641)
			(xy 132.130034 -286.261856) (xy 132.12187 -286.31209) (xy 132.105754 -286.360364) (xy 132.082103 -286.405427)
			(xy 132.05153 -286.446113) (xy 132.014826 -286.481368) (xy 131.972942 -286.510278) (xy 131.926963 -286.532095)
			(xy 131.878079 -286.546255) (xy 131.827558 -286.552389) (xy 131.776706 -286.55034) (xy 131.726842 -286.54016)
			(xy 131.679256 -286.522113) (xy 131.635182 -286.496667) (xy 131.59576 -286.46448) (xy 131.562012 -286.426386)
			(xy 131.534811 -286.383372) (xy 131.514863 -286.336552) (xy 131.502684 -286.287138) (xy 131.498589 -286.23641)
			(xy 131.180078 -286.23641) (xy 131.179583 -286.261017) (xy 131.171688 -286.309594) (xy 131.156104 -286.356275)
			(xy 131.133233 -286.399852) (xy 131.103668 -286.439196) (xy 131.068175 -286.473288) (xy 131.027672 -286.501244)
			(xy 130.98321 -286.522342) (xy 130.935939 -286.536034) (xy 130.887084 -286.541966) (xy 130.837909 -286.539985)
			(xy 130.78969 -286.530141) (xy 130.743674 -286.512689) (xy 130.701053 -286.488082) (xy 130.662932 -286.456957)
			(xy 130.630297 -286.42012) (xy 130.603994 -286.378524) (xy 130.584703 -286.333248) (xy 130.572926 -286.285464)
			(xy 130.568966 -286.23641) (xy 130.250438 -286.23641) (xy 130.249926 -286.261856) (xy 130.241762 -286.31209)
			(xy 130.225646 -286.360364) (xy 130.201995 -286.405427) (xy 130.171422 -286.446113) (xy 130.134718 -286.481368)
			(xy 130.092834 -286.510278) (xy 130.046855 -286.532095) (xy 129.997971 -286.546255) (xy 129.94745 -286.552389)
			(xy 129.896598 -286.55034) (xy 129.846734 -286.54016) (xy 129.799148 -286.522113) (xy 129.755074 -286.496667)
			(xy 129.715652 -286.46448) (xy 129.681904 -286.426386) (xy 129.654703 -286.383372) (xy 129.634755 -286.336552)
			(xy 129.622576 -286.287138) (xy 129.618481 -286.23641) (xy 129.29997 -286.23641) (xy 129.299475 -286.261017)
			(xy 129.29158 -286.309594) (xy 129.275996 -286.356275) (xy 129.253125 -286.399852) (xy 129.22356 -286.439196)
			(xy 129.188067 -286.473288) (xy 129.147564 -286.501244) (xy 129.103102 -286.522342) (xy 129.055831 -286.536034)
			(xy 129.006976 -286.541966) (xy 128.957801 -286.539985) (xy 128.909582 -286.530141) (xy 128.863566 -286.512689)
			(xy 128.820945 -286.488082) (xy 128.782824 -286.456957) (xy 128.750189 -286.42012) (xy 128.723886 -286.378524)
			(xy 128.704595 -286.333248) (xy 128.692818 -286.285464) (xy 128.688858 -286.23641) (xy 128.370584 -286.23641)
			(xy 128.370072 -286.261856) (xy 128.361908 -286.31209) (xy 128.345792 -286.360364) (xy 128.322141 -286.405427)
			(xy 128.291568 -286.446113) (xy 128.254864 -286.481368) (xy 128.21298 -286.510278) (xy 128.167001 -286.532095)
			(xy 128.118117 -286.546255) (xy 128.067596 -286.552389) (xy 128.016744 -286.55034) (xy 127.96688 -286.54016)
			(xy 127.919294 -286.522113) (xy 127.87522 -286.496667) (xy 127.835798 -286.46448) (xy 127.80205 -286.426386)
			(xy 127.774849 -286.383372) (xy 127.754901 -286.336552) (xy 127.742722 -286.287138) (xy 127.738627 -286.23641)
			(xy 127.419631 -286.23641) (xy 127.419631 -286.26176) (xy 127.411252 -286.311774) (xy 127.394725 -286.359717)
			(xy 127.370505 -286.404271) (xy 127.339256 -286.44421) (xy 127.301837 -286.478438) (xy 127.259279 -286.506013)
			(xy 127.23622 -286.516572) (xy 127.22225 -286.522668) (xy 127.20574 -286.547814) (xy 127.20574 -286.585406)
			(xy 166.774383 -286.585406) (xy 166.778318 -286.531635) (xy 166.790041 -286.479011) (xy 166.809301 -286.428654)
			(xy 166.835687 -286.381637) (xy 166.868639 -286.338964) (xy 166.907452 -286.301543) (xy 166.9513 -286.270173)
			(xy 166.999248 -286.245521) (xy 167.050275 -286.228113) (xy 167.103293 -286.21832) (xy 167.157172 -286.216351)
			(xy 167.210763 -286.222248) (xy 167.262924 -286.235884) (xy 167.312544 -286.256971) (xy 167.358565 -286.285057)
			(xy 167.400007 -286.319545) (xy 167.435985 -286.359699) (xy 167.465733 -286.404663) (xy 167.488618 -286.45348)
			(xy 167.50415 -286.505109) (xy 167.512 -286.558449) (xy 167.512492 -286.585406) (xy 171.476162 -286.585406)
			(xy 171.476702 -286.552686) (xy 171.485295 -286.487813) (xy 171.502346 -286.424634) (xy 171.527558 -286.364246)
			(xy 171.560493 -286.307699) (xy 171.60058 -286.255974) (xy 171.623482 -286.2326) (xy 171.630848 -286.225488)
			(xy 171.638722 -286.206692) (xy 171.638722 -286.113982) (xy 171.630848 -286.095186) (xy 171.623482 -286.088074)
			(xy 171.600611 -286.064671) (xy 171.560525 -286.01295) (xy 171.527585 -285.956408) (xy 171.502365 -285.896027)
			(xy 171.485301 -285.832854) (xy 171.47669 -285.767986) (xy 171.476162 -285.735268) (xy 171.476651 -285.704105)
			(xy 171.484463 -285.642271) (xy 171.499963 -285.581903) (xy 171.522906 -285.523955) (xy 171.552932 -285.469338)
			(xy 171.589566 -285.418916) (xy 171.632231 -285.373482) (xy 171.680253 -285.333754) (xy 171.732877 -285.300359)
			(xy 171.789271 -285.273822) (xy 171.848546 -285.254562) (xy 171.909767 -285.242883) (xy 171.97197 -285.23897)
			(xy 172.034173 -285.242883) (xy 172.095394 -285.254562) (xy 172.154669 -285.273822) (xy 172.211063 -285.300359)
			(xy 172.263687 -285.333754) (xy 172.311709 -285.373482) (xy 172.354374 -285.418916) (xy 172.391008 -285.469338)
			(xy 172.421034 -285.523955) (xy 172.443977 -285.581903) (xy 172.459477 -285.642271) (xy 172.467289 -285.704105)
			(xy 172.467778 -285.735268) (xy 175.57623 -285.735268) (xy 175.576782 -285.702569) (xy 175.585387 -285.637738)
			(xy 175.602443 -285.574602) (xy 175.627655 -285.514258) (xy 175.660583 -285.457754) (xy 175.700657 -285.406071)
			(xy 175.72355 -285.382716) (xy 175.730916 -285.37535) (xy 175.738536 -285.356808) (xy 175.738536 -285.263844)
			(xy 175.730916 -285.245302) (xy 175.72355 -285.237936) (xy 175.700651 -285.214585) (xy 175.660567 -285.162906)
			(xy 175.62763 -285.106403) (xy 175.602414 -285.046058) (xy 175.585356 -284.982919) (xy 175.576754 -284.918085)
			(xy 175.57623 -284.885384) (xy 175.576719 -284.854221) (xy 175.584531 -284.792387) (xy 175.600031 -284.732019)
			(xy 175.622974 -284.674071) (xy 175.653 -284.619454) (xy 175.689634 -284.569032) (xy 175.732299 -284.523598)
			(xy 175.780321 -284.48387) (xy 175.832945 -284.450475) (xy 175.889339 -284.423938) (xy 175.948614 -284.404678)
			(xy 176.009835 -284.392999) (xy 176.072038 -284.389086) (xy 176.134241 -284.392999) (xy 176.195462 -284.404678)
			(xy 176.254737 -284.423938) (xy 176.311131 -284.450475) (xy 176.363755 -284.48387) (xy 176.411777 -284.523598)
			(xy 176.454442 -284.569032) (xy 176.491076 -284.619454) (xy 176.521102 -284.674071) (xy 176.544045 -284.732019)
			(xy 176.559545 -284.792387) (xy 176.567357 -284.854221) (xy 176.567846 -284.885384) (xy 180.531023 -284.885384)
			(xy 180.534958 -284.831613) (xy 180.546681 -284.778989) (xy 180.565941 -284.728632) (xy 180.592327 -284.681615)
			(xy 180.625279 -284.638942) (xy 180.664092 -284.601521) (xy 180.70794 -284.570151) (xy 180.755888 -284.545499)
			(xy 180.806915 -284.528091) (xy 180.859933 -284.518298) (xy 180.913812 -284.516329) (xy 180.967403 -284.522226)
			(xy 181.019564 -284.535862) (xy 181.069184 -284.556949) (xy 181.115205 -284.585035) (xy 181.156647 -284.619523)
			(xy 181.192625 -284.659677) (xy 181.222373 -284.704641) (xy 181.245258 -284.753458) (xy 181.26079 -284.805087)
			(xy 181.26864 -284.858427) (xy 181.269132 -284.885384) (xy 181.26864 -284.912341) (xy 181.26079 -284.965681)
			(xy 181.245258 -285.01731) (xy 181.222373 -285.066127) (xy 181.192625 -285.111091) (xy 181.156647 -285.151245)
			(xy 181.115205 -285.185733) (xy 181.069184 -285.213819) (xy 181.019564 -285.234906) (xy 180.967403 -285.248542)
			(xy 180.913812 -285.254439) (xy 180.859933 -285.25247) (xy 180.806915 -285.242677) (xy 180.755888 -285.225269)
			(xy 180.70794 -285.200617) (xy 180.664092 -285.169247) (xy 180.625279 -285.131826) (xy 180.592327 -285.089153)
			(xy 180.565941 -285.042136) (xy 180.546681 -284.991779) (xy 180.534958 -284.939155) (xy 180.531023 -284.885384)
			(xy 176.567846 -284.885384) (xy 176.567335 -284.918085) (xy 176.558722 -284.982917) (xy 176.541659 -285.046054)
			(xy 176.51644 -285.106398) (xy 176.483503 -285.162902) (xy 176.443422 -285.214583) (xy 176.420526 -285.237936)
			(xy 176.41316 -285.245302) (xy 176.40554 -285.263844) (xy 176.40554 -285.310326) (xy 176.820337 -285.310326)
			(xy 176.824272 -285.256555) (xy 176.835995 -285.203931) (xy 176.855255 -285.153574) (xy 176.881641 -285.106557)
			(xy 176.914593 -285.063884) (xy 176.953406 -285.026463) (xy 176.997254 -284.995093) (xy 177.045202 -284.970441)
			(xy 177.096229 -284.953033) (xy 177.149247 -284.94324) (xy 177.203126 -284.941271) (xy 177.256717 -284.947168)
			(xy 177.308878 -284.960804) (xy 177.358498 -284.981891) (xy 177.404519 -285.009977) (xy 177.445961 -285.044465)
			(xy 177.481939 -285.084619) (xy 177.511687 -285.129583) (xy 177.534572 -285.1784) (xy 177.550104 -285.230029)
			(xy 177.557954 -285.283369) (xy 177.558446 -285.310326) (xy 177.557954 -285.337283) (xy 177.550104 -285.390623)
			(xy 177.534572 -285.442252) (xy 177.511687 -285.491069) (xy 177.481939 -285.536033) (xy 177.445961 -285.576187)
			(xy 177.404519 -285.610675) (xy 177.358498 -285.638761) (xy 177.308878 -285.659848) (xy 177.256717 -285.673484)
			(xy 177.203126 -285.679381) (xy 177.149247 -285.677412) (xy 177.096229 -285.667619) (xy 177.045202 -285.650211)
			(xy 176.997254 -285.625559) (xy 176.953406 -285.594189) (xy 176.914593 -285.556768) (xy 176.881641 -285.514095)
			(xy 176.855255 -285.467078) (xy 176.835995 -285.416721) (xy 176.824272 -285.364097) (xy 176.820337 -285.310326)
			(xy 176.40554 -285.310326) (xy 176.40554 -285.356808) (xy 176.41316 -285.37535) (xy 176.420526 -285.382716)
			(xy 176.443446 -285.406047) (xy 176.483529 -285.45773) (xy 176.516463 -285.514237) (xy 176.541676 -285.574587)
			(xy 176.558729 -285.637729) (xy 176.567326 -285.702566) (xy 176.567846 -285.735268) (xy 176.567357 -285.766431)
			(xy 176.559545 -285.828265) (xy 176.544045 -285.888633) (xy 176.521102 -285.946581) (xy 176.491076 -286.001198)
			(xy 176.454442 -286.05162) (xy 176.411777 -286.097054) (xy 176.363755 -286.136782) (xy 176.311131 -286.170177)
			(xy 176.254737 -286.196714) (xy 176.195462 -286.215974) (xy 176.134241 -286.227653) (xy 176.072038 -286.231566)
			(xy 176.009835 -286.227653) (xy 175.948614 -286.215974) (xy 175.889339 -286.196714) (xy 175.832945 -286.170177)
			(xy 175.780321 -286.136782) (xy 175.732299 -286.097054) (xy 175.689634 -286.05162) (xy 175.653 -286.001198)
			(xy 175.622974 -285.946581) (xy 175.600031 -285.888633) (xy 175.584531 -285.828265) (xy 175.576719 -285.766431)
			(xy 175.57623 -285.735268) (xy 172.467778 -285.735268) (xy 172.467274 -285.767989) (xy 172.458672 -285.832863)
			(xy 172.441613 -285.896043) (xy 172.416395 -285.95643) (xy 172.383453 -286.012977) (xy 172.343362 -286.0647)
			(xy 172.320458 -286.088074) (xy 172.313092 -286.095186) (xy 172.305218 -286.113982) (xy 172.305218 -286.160464)
			(xy 172.720269 -286.160464) (xy 172.724204 -286.106693) (xy 172.735927 -286.054069) (xy 172.755187 -286.003712)
			(xy 172.781573 -285.956695) (xy 172.814525 -285.914022) (xy 172.853338 -285.876601) (xy 172.897186 -285.845231)
			(xy 172.945134 -285.820579) (xy 172.996161 -285.803171) (xy 173.049179 -285.793378) (xy 173.103058 -285.791409)
			(xy 173.156649 -285.797306) (xy 173.20881 -285.810942) (xy 173.25843 -285.832029) (xy 173.304451 -285.860115)
			(xy 173.345893 -285.894603) (xy 173.381871 -285.934757) (xy 173.411619 -285.979721) (xy 173.434504 -286.028538)
			(xy 173.450036 -286.080167) (xy 173.457886 -286.133507) (xy 173.458378 -286.160464) (xy 173.457886 -286.187421)
			(xy 173.450036 -286.240761) (xy 173.434504 -286.29239) (xy 173.411619 -286.341207) (xy 173.381871 -286.386171)
			(xy 173.345893 -286.426325) (xy 173.304451 -286.460813) (xy 173.25843 -286.488899) (xy 173.20881 -286.509986)
			(xy 173.156649 -286.523622) (xy 173.103058 -286.529519) (xy 173.049179 -286.52755) (xy 172.996161 -286.517757)
			(xy 172.945134 -286.500349) (xy 172.897186 -286.475697) (xy 172.853338 -286.444327) (xy 172.814525 -286.406906)
			(xy 172.781573 -286.364233) (xy 172.755187 -286.317216) (xy 172.735927 -286.266859) (xy 172.724204 -286.214235)
			(xy 172.720269 -286.160464) (xy 172.305218 -286.160464) (xy 172.305218 -286.206692) (xy 172.313092 -286.225488)
			(xy 172.320458 -286.2326) (xy 172.343373 -286.255962) (xy 172.383453 -286.307693) (xy 172.416385 -286.364244)
			(xy 172.441598 -286.424633) (xy 172.458653 -286.487812) (xy 172.467255 -286.552686) (xy 172.467778 -286.585406)
			(xy 174.318437 -286.585406) (xy 174.322372 -286.531635) (xy 174.334095 -286.479011) (xy 174.353355 -286.428654)
			(xy 174.379741 -286.381637) (xy 174.412693 -286.338964) (xy 174.451506 -286.301543) (xy 174.495354 -286.270173)
			(xy 174.543302 -286.245521) (xy 174.594329 -286.228113) (xy 174.647347 -286.21832) (xy 174.701226 -286.216351)
			(xy 174.754817 -286.222248) (xy 174.806978 -286.235884) (xy 174.856598 -286.256971) (xy 174.902619 -286.285057)
			(xy 174.944061 -286.319545) (xy 174.980039 -286.359699) (xy 175.009787 -286.404663) (xy 175.032672 -286.45348)
			(xy 175.048204 -286.505109) (xy 175.056054 -286.558449) (xy 175.056546 -286.585406) (xy 179.020216 -286.585406)
			(xy 179.02077 -286.552687) (xy 179.029362 -286.487815) (xy 179.046411 -286.424636) (xy 179.07162 -286.364249)
			(xy 179.104553 -286.307701) (xy 179.144636 -286.255975) (xy 179.167536 -286.2326) (xy 179.174902 -286.225488)
			(xy 179.182776 -286.206692) (xy 179.182776 -286.113982) (xy 179.174902 -286.095186) (xy 179.167536 -286.088074)
			(xy 179.144656 -286.064679) (xy 179.104572 -286.012955) (xy 179.071635 -285.956411) (xy 179.046417 -285.896029)
			(xy 179.029354 -285.832855) (xy 179.020744 -285.767987) (xy 179.020216 -285.735268) (xy 179.020705 -285.704105)
			(xy 179.028517 -285.642271) (xy 179.044017 -285.581903) (xy 179.06696 -285.523955) (xy 179.096986 -285.469338)
			(xy 179.13362 -285.418916) (xy 179.176285 -285.373482) (xy 179.224307 -285.333754) (xy 179.276931 -285.300359)
			(xy 179.333325 -285.273822) (xy 179.3926 -285.254562) (xy 179.453821 -285.242883) (xy 179.516024 -285.23897)
			(xy 179.578227 -285.242883) (xy 179.639448 -285.254562) (xy 179.698723 -285.273822) (xy 179.755117 -285.300359)
			(xy 179.807741 -285.333754) (xy 179.855763 -285.373482) (xy 179.898428 -285.418916) (xy 179.935062 -285.469338)
			(xy 179.965088 -285.523955) (xy 179.988031 -285.581903) (xy 180.003531 -285.642271) (xy 180.011343 -285.704105)
			(xy 180.011832 -285.735268) (xy 183.120284 -285.735268) (xy 183.12082 -285.702568) (xy 183.129426 -285.637736)
			(xy 183.146485 -285.5746) (xy 183.171699 -285.514255) (xy 183.204631 -285.457751) (xy 183.244709 -285.40607)
			(xy 183.267604 -285.382716) (xy 183.27497 -285.37535) (xy 183.28259 -285.356808) (xy 183.28259 -285.263844)
			(xy 183.27497 -285.245302) (xy 183.267604 -285.237936) (xy 183.244715 -285.214576) (xy 183.204628 -285.1629)
			(xy 183.171689 -285.106399) (xy 183.14647 -285.046055) (xy 183.129411 -284.982918) (xy 183.120808 -284.918085)
			(xy 183.120284 -284.885384) (xy 183.120773 -284.854221) (xy 183.128585 -284.792387) (xy 183.144085 -284.732019)
			(xy 183.167028 -284.674071) (xy 183.197054 -284.619454) (xy 183.233688 -284.569032) (xy 183.276353 -284.523598)
			(xy 183.324375 -284.48387) (xy 183.376999 -284.450475) (xy 183.433393 -284.423938) (xy 183.492668 -284.404678)
			(xy 183.553889 -284.392999) (xy 183.616092 -284.389086) (xy 183.678295 -284.392999) (xy 183.739516 -284.404678)
			(xy 183.798791 -284.423938) (xy 183.855185 -284.450475) (xy 183.907809 -284.48387) (xy 183.955831 -284.523598)
			(xy 183.998496 -284.569032) (xy 184.03513 -284.619454) (xy 184.065156 -284.674071) (xy 184.088099 -284.732019)
			(xy 184.103599 -284.792387) (xy 184.111411 -284.854221) (xy 184.1119 -284.885384) (xy 184.111402 -284.918085)
			(xy 184.102789 -284.982919) (xy 184.085724 -285.046056) (xy 184.060502 -285.106401) (xy 184.027563 -285.162904)
			(xy 183.987478 -285.214584) (xy 183.96458 -285.237936) (xy 183.957214 -285.245302) (xy 183.949594 -285.263844)
			(xy 183.949594 -285.310326) (xy 184.364391 -285.310326) (xy 184.368326 -285.256555) (xy 184.380049 -285.203931)
			(xy 184.399309 -285.153574) (xy 184.425695 -285.106557) (xy 184.458647 -285.063884) (xy 184.49746 -285.026463)
			(xy 184.541308 -284.995093) (xy 184.589256 -284.970441) (xy 184.640283 -284.953033) (xy 184.693301 -284.94324)
			(xy 184.74718 -284.941271) (xy 184.800771 -284.947168) (xy 184.852932 -284.960804) (xy 184.902552 -284.981891)
			(xy 184.948573 -285.009977) (xy 184.990015 -285.044465) (xy 185.025993 -285.084619) (xy 185.055741 -285.129583)
			(xy 185.078626 -285.1784) (xy 185.094158 -285.230029) (xy 185.102008 -285.283369) (xy 185.1025 -285.310326)
			(xy 185.102008 -285.337283) (xy 185.094158 -285.390623) (xy 185.078626 -285.442252) (xy 185.055741 -285.491069)
			(xy 185.025993 -285.536033) (xy 184.990015 -285.576187) (xy 184.948573 -285.610675) (xy 184.902552 -285.638761)
			(xy 184.852932 -285.659848) (xy 184.800771 -285.673484) (xy 184.74718 -285.679381) (xy 184.693301 -285.677412)
			(xy 184.640283 -285.667619) (xy 184.589256 -285.650211) (xy 184.541308 -285.625559) (xy 184.49746 -285.594189)
			(xy 184.458647 -285.556768) (xy 184.425695 -285.514095) (xy 184.399309 -285.467078) (xy 184.380049 -285.416721)
			(xy 184.368326 -285.364097) (xy 184.364391 -285.310326) (xy 183.949594 -285.310326) (xy 183.949594 -285.356808)
			(xy 183.957214 -285.37535) (xy 183.96458 -285.382716) (xy 183.98751 -285.406038) (xy 184.02759 -285.457724)
			(xy 184.060521 -285.514233) (xy 184.085732 -285.574584) (xy 184.102784 -285.637728) (xy 184.11138 -285.702565)
			(xy 184.1119 -285.735268) (xy 184.111411 -285.766431) (xy 184.103599 -285.828265) (xy 184.088099 -285.888633)
			(xy 184.065156 -285.946581) (xy 184.03513 -286.001198) (xy 183.998496 -286.05162) (xy 183.955831 -286.097054)
			(xy 183.907809 -286.136782) (xy 183.855185 -286.170177) (xy 183.798791 -286.196714) (xy 183.739516 -286.215974)
			(xy 183.678295 -286.227653) (xy 183.616092 -286.231566) (xy 183.553889 -286.227653) (xy 183.492668 -286.215974)
			(xy 183.433393 -286.196714) (xy 183.376999 -286.170177) (xy 183.324375 -286.136782) (xy 183.276353 -286.097054)
			(xy 183.233688 -286.05162) (xy 183.197054 -286.001198) (xy 183.167028 -285.946581) (xy 183.144085 -285.888633)
			(xy 183.128585 -285.828265) (xy 183.120773 -285.766431) (xy 183.120284 -285.735268) (xy 180.011832 -285.735268)
			(xy 180.011341 -285.76799) (xy 180.002739 -285.832865) (xy 179.985678 -285.896045) (xy 179.960457 -285.956433)
			(xy 179.927513 -286.012979) (xy 179.887418 -286.064701) (xy 179.864512 -286.088074) (xy 179.857146 -286.095186)
			(xy 179.849272 -286.113982) (xy 179.849272 -286.160464) (xy 180.264323 -286.160464) (xy 180.268258 -286.106693)
			(xy 180.279981 -286.054069) (xy 180.299241 -286.003712) (xy 180.325627 -285.956695) (xy 180.358579 -285.914022)
			(xy 180.397392 -285.876601) (xy 180.44124 -285.845231) (xy 180.489188 -285.820579) (xy 180.540215 -285.803171)
			(xy 180.593233 -285.793378) (xy 180.647112 -285.791409) (xy 180.700703 -285.797306) (xy 180.752864 -285.810942)
			(xy 180.802484 -285.832029) (xy 180.848505 -285.860115) (xy 180.889947 -285.894603) (xy 180.925925 -285.934757)
			(xy 180.955673 -285.979721) (xy 180.978558 -286.028538) (xy 180.99409 -286.080167) (xy 181.00194 -286.133507)
			(xy 181.002432 -286.160464) (xy 181.00194 -286.187421) (xy 180.99409 -286.240761) (xy 180.978558 -286.29239)
			(xy 180.955673 -286.341207) (xy 180.925925 -286.386171) (xy 180.889947 -286.426325) (xy 180.848505 -286.460813)
			(xy 180.802484 -286.488899) (xy 180.752864 -286.509986) (xy 180.700703 -286.523622) (xy 180.647112 -286.529519)
			(xy 180.593233 -286.52755) (xy 180.540215 -286.517757) (xy 180.489188 -286.500349) (xy 180.44124 -286.475697)
			(xy 180.397392 -286.444327) (xy 180.358579 -286.406906) (xy 180.325627 -286.364233) (xy 180.299241 -286.317216)
			(xy 180.279981 -286.266859) (xy 180.268258 -286.214235) (xy 180.264323 -286.160464) (xy 179.849272 -286.160464)
			(xy 179.849272 -286.206692) (xy 179.857146 -286.225488) (xy 179.864512 -286.2326) (xy 179.887418 -286.255971)
			(xy 179.927501 -286.307699) (xy 179.960435 -286.364247) (xy 179.98565 -286.424635) (xy 180.002706 -286.487813)
			(xy 180.011308 -286.552686) (xy 180.011832 -286.585406) (xy 181.862491 -286.585406) (xy 181.866426 -286.531635)
			(xy 181.878149 -286.479011) (xy 181.897409 -286.428654) (xy 181.923795 -286.381637) (xy 181.956747 -286.338964)
			(xy 181.99556 -286.301543) (xy 182.039408 -286.270173) (xy 182.087356 -286.245521) (xy 182.138383 -286.228113)
			(xy 182.191401 -286.21832) (xy 182.24528 -286.216351) (xy 182.298871 -286.222248) (xy 182.351032 -286.235884)
			(xy 182.400652 -286.256971) (xy 182.446673 -286.285057) (xy 182.488115 -286.319545) (xy 182.524093 -286.359699)
			(xy 182.553841 -286.404663) (xy 182.576726 -286.45348) (xy 182.592258 -286.505109) (xy 182.600108 -286.558449)
			(xy 182.6006 -286.585406) (xy 182.600108 -286.612363) (xy 182.592258 -286.665703) (xy 182.576726 -286.717332)
			(xy 182.553841 -286.766149) (xy 182.524093 -286.811113) (xy 182.488115 -286.851267) (xy 182.446673 -286.885755)
			(xy 182.400652 -286.913841) (xy 182.351032 -286.934928) (xy 182.298871 -286.948564) (xy 182.24528 -286.954461)
			(xy 182.191401 -286.952492) (xy 182.138383 -286.942699) (xy 182.087356 -286.925291) (xy 182.039408 -286.900639)
			(xy 181.99556 -286.869269) (xy 181.956747 -286.831848) (xy 181.923795 -286.789175) (xy 181.897409 -286.742158)
			(xy 181.878149 -286.691801) (xy 181.866426 -286.639177) (xy 181.862491 -286.585406) (xy 180.011832 -286.585406)
			(xy 180.011343 -286.616569) (xy 180.003531 -286.678403) (xy 179.988031 -286.738771) (xy 179.965088 -286.796719)
			(xy 179.935062 -286.851336) (xy 179.898428 -286.901758) (xy 179.855763 -286.947192) (xy 179.807741 -286.98692)
			(xy 179.755117 -287.020315) (xy 179.698723 -287.046852) (xy 179.639448 -287.066112) (xy 179.578227 -287.077791)
			(xy 179.516024 -287.081704) (xy 179.453821 -287.077791) (xy 179.3926 -287.066112) (xy 179.333325 -287.046852)
			(xy 179.276931 -287.020315) (xy 179.224307 -286.98692) (xy 179.176285 -286.947192) (xy 179.13362 -286.901758)
			(xy 179.096986 -286.851336) (xy 179.06696 -286.796719) (xy 179.044017 -286.738771) (xy 179.028517 -286.678403)
			(xy 179.020705 -286.616569) (xy 179.020216 -286.585406) (xy 175.056546 -286.585406) (xy 175.056054 -286.612363)
			(xy 175.048204 -286.665703) (xy 175.032672 -286.717332) (xy 175.009787 -286.766149) (xy 174.980039 -286.811113)
			(xy 174.944061 -286.851267) (xy 174.902619 -286.885755) (xy 174.856598 -286.913841) (xy 174.806978 -286.934928)
			(xy 174.754817 -286.948564) (xy 174.701226 -286.954461) (xy 174.647347 -286.952492) (xy 174.594329 -286.942699)
			(xy 174.543302 -286.925291) (xy 174.495354 -286.900639) (xy 174.451506 -286.869269) (xy 174.412693 -286.831848)
			(xy 174.379741 -286.789175) (xy 174.353355 -286.742158) (xy 174.334095 -286.691801) (xy 174.322372 -286.639177)
			(xy 174.318437 -286.585406) (xy 172.467778 -286.585406) (xy 172.467289 -286.616569) (xy 172.459477 -286.678403)
			(xy 172.443977 -286.738771) (xy 172.421034 -286.796719) (xy 172.391008 -286.851336) (xy 172.354374 -286.901758)
			(xy 172.311709 -286.947192) (xy 172.263687 -286.98692) (xy 172.211063 -287.020315) (xy 172.154669 -287.046852)
			(xy 172.095394 -287.066112) (xy 172.034173 -287.077791) (xy 171.97197 -287.081704) (xy 171.909767 -287.077791)
			(xy 171.848546 -287.066112) (xy 171.789271 -287.046852) (xy 171.732877 -287.020315) (xy 171.680253 -286.98692)
			(xy 171.632231 -286.947192) (xy 171.589566 -286.901758) (xy 171.552932 -286.851336) (xy 171.522906 -286.796719)
			(xy 171.499963 -286.738771) (xy 171.484463 -286.678403) (xy 171.476651 -286.616569) (xy 171.476162 -286.585406)
			(xy 167.512492 -286.585406) (xy 167.512 -286.612363) (xy 167.50415 -286.665703) (xy 167.488618 -286.717332)
			(xy 167.465733 -286.766149) (xy 167.435985 -286.811113) (xy 167.400007 -286.851267) (xy 167.358565 -286.885755)
			(xy 167.312544 -286.913841) (xy 167.262924 -286.934928) (xy 167.210763 -286.948564) (xy 167.157172 -286.954461)
			(xy 167.103293 -286.952492) (xy 167.050275 -286.942699) (xy 166.999248 -286.925291) (xy 166.9513 -286.900639)
			(xy 166.907452 -286.869269) (xy 166.868639 -286.831848) (xy 166.835687 -286.789175) (xy 166.809301 -286.742158)
			(xy 166.790041 -286.691801) (xy 166.778318 -286.639177) (xy 166.774383 -286.585406) (xy 127.20574 -286.585406)
			(xy 127.20574 -286.748474) (xy 127.206196 -286.758311) (xy 127.213626 -286.776529) (xy 127.227393 -286.790584)
			(xy 127.23622 -286.794956) (xy 127.335534 -286.83839) (xy 127.365252 -286.83331) (xy 127.376682 -286.822896)
			(xy 127.39371 -286.807566) (xy 127.431502 -286.781664) (xy 127.472742 -286.761703) (xy 127.516502 -286.748131)
			(xy 127.5618 -286.741253) (xy 127.584708 -286.740854) (xy 127.609966 -286.741376) (xy 127.659793 -286.749692)
			(xy 127.707572 -286.766096) (xy 127.751999 -286.790139) (xy 127.791863 -286.821168) (xy 127.826076 -286.858334)
			(xy 127.853705 -286.900625) (xy 127.873997 -286.946886) (xy 127.886397 -286.995856) (xy 127.890566 -287.046162)
			(xy 128.208527 -287.046162) (xy 128.212622 -286.995434) (xy 128.224801 -286.94602) (xy 128.244749 -286.8992)
			(xy 128.27195 -286.856186) (xy 128.305698 -286.818092) (xy 128.34512 -286.785905) (xy 128.389194 -286.760459)
			(xy 128.43678 -286.742412) (xy 128.486644 -286.732232) (xy 128.537496 -286.730183) (xy 128.588017 -286.736317)
			(xy 128.636901 -286.750477) (xy 128.68288 -286.772294) (xy 128.724764 -286.801204) (xy 128.761468 -286.836459)
			(xy 128.792041 -286.877145) (xy 128.815692 -286.922208) (xy 128.831808 -286.970482) (xy 128.839972 -287.020716)
			(xy 128.840484 -287.046162) (xy 129.148581 -287.046162) (xy 129.152676 -286.995434) (xy 129.164855 -286.94602)
			(xy 129.184803 -286.8992) (xy 129.212004 -286.856186) (xy 129.245752 -286.818092) (xy 129.285174 -286.785905)
			(xy 129.329248 -286.760459) (xy 129.376834 -286.742412) (xy 129.426698 -286.732232) (xy 129.47755 -286.730183)
			(xy 129.528071 -286.736317) (xy 129.576955 -286.750477) (xy 129.622934 -286.772294) (xy 129.664818 -286.801204)
			(xy 129.701522 -286.836459) (xy 129.732095 -286.877145) (xy 129.755746 -286.922208) (xy 129.771862 -286.970482)
			(xy 129.780026 -287.020716) (xy 129.780538 -287.046162) (xy 129.780533 -287.046416) (xy 130.099066 -287.046416)
			(xy 130.103026 -286.997362) (xy 130.114803 -286.949578) (xy 130.134094 -286.904302) (xy 130.160397 -286.862706)
			(xy 130.193032 -286.825869) (xy 130.231153 -286.794744) (xy 130.273774 -286.770137) (xy 130.31979 -286.752685)
			(xy 130.368009 -286.742841) (xy 130.417184 -286.74086) (xy 130.466039 -286.746792) (xy 130.51331 -286.760484)
			(xy 130.557772 -286.781582) (xy 130.598275 -286.809538) (xy 130.633768 -286.84363) (xy 130.663333 -286.882974)
			(xy 130.686204 -286.926551) (xy 130.701788 -286.973232) (xy 130.709683 -287.021809) (xy 130.710173 -287.046162)
			(xy 131.028435 -287.046162) (xy 131.03253 -286.995434) (xy 131.044709 -286.94602) (xy 131.064657 -286.8992)
			(xy 131.091858 -286.856186) (xy 131.125606 -286.818092) (xy 131.165028 -286.785905) (xy 131.209102 -286.760459)
			(xy 131.256688 -286.742412) (xy 131.306552 -286.732232) (xy 131.357404 -286.730183) (xy 131.407925 -286.736317)
			(xy 131.456809 -286.750477) (xy 131.502788 -286.772294) (xy 131.544672 -286.801204) (xy 131.581376 -286.836459)
			(xy 131.611949 -286.877145) (xy 131.6356 -286.922208) (xy 131.651716 -286.970482) (xy 131.65988 -287.020716)
			(xy 131.660392 -287.046162) (xy 131.97892 -287.046162) (xy 131.98288 -286.997108) (xy 131.994657 -286.949324)
			(xy 132.013948 -286.904048) (xy 132.040251 -286.862452) (xy 132.072886 -286.825615) (xy 132.111007 -286.79449)
			(xy 132.153628 -286.769883) (xy 132.199644 -286.752431) (xy 132.247863 -286.742587) (xy 132.297038 -286.740606)
			(xy 132.345893 -286.746538) (xy 132.393164 -286.76023) (xy 132.437626 -286.781328) (xy 132.478129 -286.809284)
			(xy 132.513622 -286.843376) (xy 132.543187 -286.88272) (xy 132.566058 -286.926297) (xy 132.581642 -286.972978)
			(xy 132.589537 -287.021555) (xy 132.590032 -287.046162) (xy 132.908543 -287.046162) (xy 132.912638 -286.995434)
			(xy 132.924817 -286.94602) (xy 132.944765 -286.8992) (xy 132.971966 -286.856186) (xy 133.005714 -286.818092)
			(xy 133.045136 -286.785905) (xy 133.08921 -286.760459) (xy 133.136796 -286.742412) (xy 133.18666 -286.732232)
			(xy 133.237512 -286.730183) (xy 133.288033 -286.736317) (xy 133.336917 -286.750477) (xy 133.382896 -286.772294)
			(xy 133.42478 -286.801204) (xy 133.461484 -286.836459) (xy 133.492057 -286.877145) (xy 133.515708 -286.922208)
			(xy 133.531824 -286.970482) (xy 133.539988 -287.020716) (xy 133.5405 -287.046162) (xy 133.540495 -287.046416)
			(xy 133.859028 -287.046416) (xy 133.862988 -286.997362) (xy 133.874765 -286.949578) (xy 133.894056 -286.904302)
			(xy 133.920359 -286.862706) (xy 133.952994 -286.825869) (xy 133.991115 -286.794744) (xy 134.033736 -286.770137)
			(xy 134.079752 -286.752685) (xy 134.127971 -286.742841) (xy 134.177146 -286.74086) (xy 134.226001 -286.746792)
			(xy 134.273272 -286.760484) (xy 134.317734 -286.781582) (xy 134.358237 -286.809538) (xy 134.39373 -286.84363)
			(xy 134.423295 -286.882974) (xy 134.446166 -286.926551) (xy 134.46175 -286.973232) (xy 134.469645 -287.021809)
			(xy 134.470135 -287.046162) (xy 134.788397 -287.046162) (xy 134.792492 -286.995434) (xy 134.804671 -286.94602)
			(xy 134.824619 -286.8992) (xy 134.85182 -286.856186) (xy 134.885568 -286.818092) (xy 134.92499 -286.785905)
			(xy 134.969064 -286.760459) (xy 135.01665 -286.742412) (xy 135.066514 -286.732232) (xy 135.117366 -286.730183)
			(xy 135.167887 -286.736317) (xy 135.216771 -286.750477) (xy 135.26275 -286.772294) (xy 135.304634 -286.801204)
			(xy 135.341338 -286.836459) (xy 135.371911 -286.877145) (xy 135.395562 -286.922208) (xy 135.411678 -286.970482)
			(xy 135.419842 -287.020716) (xy 135.420354 -287.046162) (xy 135.728451 -287.046162) (xy 135.732546 -286.995434)
			(xy 135.744725 -286.94602) (xy 135.764673 -286.8992) (xy 135.791874 -286.856186) (xy 135.825622 -286.818092)
			(xy 135.865044 -286.785905) (xy 135.909118 -286.760459) (xy 135.956704 -286.742412) (xy 136.006568 -286.732232)
			(xy 136.05742 -286.730183) (xy 136.107941 -286.736317) (xy 136.156825 -286.750477) (xy 136.202804 -286.772294)
			(xy 136.244688 -286.801204) (xy 136.281392 -286.836459) (xy 136.311965 -286.877145) (xy 136.335616 -286.922208)
			(xy 136.351732 -286.970482) (xy 136.359896 -287.020716) (xy 136.360408 -287.046162) (xy 136.678936 -287.046162)
			(xy 136.682896 -286.997108) (xy 136.694673 -286.949324) (xy 136.713964 -286.904048) (xy 136.740267 -286.862452)
			(xy 136.772902 -286.825615) (xy 136.811023 -286.79449) (xy 136.853644 -286.769883) (xy 136.89966 -286.752431)
			(xy 136.947879 -286.742587) (xy 136.997054 -286.740606) (xy 137.045909 -286.746538) (xy 137.09318 -286.76023)
			(xy 137.137642 -286.781328) (xy 137.178145 -286.809284) (xy 137.213638 -286.843376) (xy 137.243203 -286.88272)
			(xy 137.266074 -286.926297) (xy 137.281658 -286.972978) (xy 137.289553 -287.021555) (xy 137.290048 -287.046162)
			(xy 137.608559 -287.046162) (xy 137.612654 -286.995434) (xy 137.624833 -286.94602) (xy 137.644781 -286.8992)
			(xy 137.671982 -286.856186) (xy 137.70573 -286.818092) (xy 137.745152 -286.785905) (xy 137.789226 -286.760459)
			(xy 137.836812 -286.742412) (xy 137.886676 -286.732232) (xy 137.937528 -286.730183) (xy 137.988049 -286.736317)
			(xy 138.036933 -286.750477) (xy 138.082912 -286.772294) (xy 138.124796 -286.801204) (xy 138.1615 -286.836459)
			(xy 138.192073 -286.877145) (xy 138.215724 -286.922208) (xy 138.23184 -286.970482) (xy 138.240004 -287.020716)
			(xy 138.240516 -287.046162) (xy 138.240511 -287.046416) (xy 138.559044 -287.046416) (xy 138.563004 -286.997362)
			(xy 138.574781 -286.949578) (xy 138.594072 -286.904302) (xy 138.620375 -286.862706) (xy 138.65301 -286.825869)
			(xy 138.691131 -286.794744) (xy 138.733752 -286.770137) (xy 138.779768 -286.752685) (xy 138.827987 -286.742841)
			(xy 138.877162 -286.74086) (xy 138.926017 -286.746792) (xy 138.973288 -286.760484) (xy 139.01775 -286.781582)
			(xy 139.058253 -286.809538) (xy 139.093746 -286.84363) (xy 139.123311 -286.882974) (xy 139.146182 -286.926551)
			(xy 139.161766 -286.973232) (xy 139.169661 -287.021809) (xy 139.170151 -287.046162) (xy 139.488413 -287.046162)
			(xy 139.492508 -286.995434) (xy 139.504687 -286.94602) (xy 139.524635 -286.8992) (xy 139.551836 -286.856186)
			(xy 139.585584 -286.818092) (xy 139.625006 -286.785905) (xy 139.66908 -286.760459) (xy 139.716666 -286.742412)
			(xy 139.76653 -286.732232) (xy 139.817382 -286.730183) (xy 139.867903 -286.736317) (xy 139.916787 -286.750477)
			(xy 139.962766 -286.772294) (xy 140.00465 -286.801204) (xy 140.041354 -286.836459) (xy 140.071927 -286.877145)
			(xy 140.095578 -286.922208) (xy 140.111694 -286.970482) (xy 140.119858 -287.020716) (xy 140.12037 -287.046162)
			(xy 140.438898 -287.046162) (xy 140.442858 -286.997108) (xy 140.454635 -286.949324) (xy 140.473926 -286.904048)
			(xy 140.500229 -286.862452) (xy 140.532864 -286.825615) (xy 140.570985 -286.79449) (xy 140.613606 -286.769883)
			(xy 140.659622 -286.752431) (xy 140.707841 -286.742587) (xy 140.757016 -286.740606) (xy 140.805871 -286.746538)
			(xy 140.853142 -286.76023) (xy 140.897604 -286.781328) (xy 140.938107 -286.809284) (xy 140.9736 -286.843376)
			(xy 141.003165 -286.88272) (xy 141.026036 -286.926297) (xy 141.04162 -286.972978) (xy 141.049515 -287.021555)
			(xy 141.05001 -287.046162) (xy 141.368521 -287.046162) (xy 141.372616 -286.995434) (xy 141.384795 -286.94602)
			(xy 141.404743 -286.8992) (xy 141.431944 -286.856186) (xy 141.465692 -286.818092) (xy 141.505114 -286.785905)
			(xy 141.549188 -286.760459) (xy 141.596774 -286.742412) (xy 141.646638 -286.732232) (xy 141.69749 -286.730183)
			(xy 141.748011 -286.736317) (xy 141.796895 -286.750477) (xy 141.842874 -286.772294) (xy 141.884758 -286.801204)
			(xy 141.921462 -286.836459) (xy 141.952035 -286.877145) (xy 141.975686 -286.922208) (xy 141.991802 -286.970482)
			(xy 141.999966 -287.020716) (xy 142.000478 -287.046162) (xy 142.308575 -287.046162) (xy 142.31267 -286.995434)
			(xy 142.324849 -286.94602) (xy 142.344797 -286.8992) (xy 142.371998 -286.856186) (xy 142.405746 -286.818092)
			(xy 142.445168 -286.785905) (xy 142.489242 -286.760459) (xy 142.536828 -286.742412) (xy 142.586692 -286.732232)
			(xy 142.637544 -286.730183) (xy 142.688065 -286.736317) (xy 142.736949 -286.750477) (xy 142.782928 -286.772294)
			(xy 142.824812 -286.801204) (xy 142.861516 -286.836459) (xy 142.892089 -286.877145) (xy 142.91574 -286.922208)
			(xy 142.931856 -286.970482) (xy 142.94002 -287.020716) (xy 142.940532 -287.046162) (xy 143.258806 -287.046162)
			(xy 143.262766 -286.997108) (xy 143.274543 -286.949324) (xy 143.293834 -286.904048) (xy 143.320137 -286.862452)
			(xy 143.352772 -286.825615) (xy 143.390893 -286.79449) (xy 143.433514 -286.769883) (xy 143.47953 -286.752431)
			(xy 143.527749 -286.742587) (xy 143.576924 -286.740606) (xy 143.625779 -286.746538) (xy 143.67305 -286.76023)
			(xy 143.717512 -286.781328) (xy 143.758015 -286.809284) (xy 143.793508 -286.843376) (xy 143.823073 -286.88272)
			(xy 143.845944 -286.926297) (xy 143.861528 -286.972978) (xy 143.869423 -287.021555) (xy 143.869918 -287.046162)
			(xy 145.138914 -287.046162) (xy 145.142874 -286.997108) (xy 145.154651 -286.949324) (xy 145.173942 -286.904048)
			(xy 145.200245 -286.862452) (xy 145.23288 -286.825615) (xy 145.271001 -286.79449) (xy 145.313622 -286.769883)
			(xy 145.359638 -286.752431) (xy 145.407857 -286.742587) (xy 145.457032 -286.740606) (xy 145.505887 -286.746538)
			(xy 145.553158 -286.76023) (xy 145.59762 -286.781328) (xy 145.638123 -286.809284) (xy 145.673616 -286.843376)
			(xy 145.703181 -286.88272) (xy 145.726052 -286.926297) (xy 145.741636 -286.972978) (xy 145.749531 -287.021555)
			(xy 145.750026 -287.046162) (xy 145.749531 -287.070769) (xy 145.741636 -287.119346) (xy 145.726052 -287.166027)
			(xy 145.703181 -287.209604) (xy 145.673616 -287.248948) (xy 145.638123 -287.28304) (xy 145.59762 -287.310996)
			(xy 145.553158 -287.332094) (xy 145.505887 -287.345786) (xy 145.457032 -287.351718) (xy 145.407857 -287.349737)
			(xy 145.359638 -287.339893) (xy 145.313622 -287.322441) (xy 145.271001 -287.297834) (xy 145.23288 -287.266709)
			(xy 145.200245 -287.229872) (xy 145.173942 -287.188276) (xy 145.154651 -287.143) (xy 145.142874 -287.095216)
			(xy 145.138914 -287.046162) (xy 143.869918 -287.046162) (xy 143.869423 -287.070769) (xy 143.861528 -287.119346)
			(xy 143.845944 -287.166027) (xy 143.823073 -287.209604) (xy 143.793508 -287.248948) (xy 143.758015 -287.28304)
			(xy 143.717512 -287.310996) (xy 143.67305 -287.332094) (xy 143.625779 -287.345786) (xy 143.576924 -287.351718)
			(xy 143.527749 -287.349737) (xy 143.47953 -287.339893) (xy 143.433514 -287.322441) (xy 143.390893 -287.297834)
			(xy 143.352772 -287.266709) (xy 143.320137 -287.229872) (xy 143.293834 -287.188276) (xy 143.274543 -287.143)
			(xy 143.262766 -287.095216) (xy 143.258806 -287.046162) (xy 142.940532 -287.046162) (xy 142.94002 -287.071608)
			(xy 142.931856 -287.121842) (xy 142.91574 -287.170116) (xy 142.892089 -287.215179) (xy 142.861516 -287.255865)
			(xy 142.824812 -287.29112) (xy 142.782928 -287.32003) (xy 142.736949 -287.341847) (xy 142.688065 -287.356007)
			(xy 142.637544 -287.362141) (xy 142.586692 -287.360092) (xy 142.536828 -287.349912) (xy 142.489242 -287.331865)
			(xy 142.445168 -287.306419) (xy 142.405746 -287.274232) (xy 142.371998 -287.236138) (xy 142.344797 -287.193124)
			(xy 142.324849 -287.146304) (xy 142.31267 -287.09689) (xy 142.308575 -287.046162) (xy 142.000478 -287.046162)
			(xy 141.999966 -287.071608) (xy 141.991802 -287.121842) (xy 141.975686 -287.170116) (xy 141.952035 -287.215179)
			(xy 141.921462 -287.255865) (xy 141.884758 -287.29112) (xy 141.842874 -287.32003) (xy 141.796895 -287.341847)
			(xy 141.748011 -287.356007) (xy 141.69749 -287.362141) (xy 141.646638 -287.360092) (xy 141.596774 -287.349912)
			(xy 141.549188 -287.331865) (xy 141.505114 -287.306419) (xy 141.465692 -287.274232) (xy 141.431944 -287.236138)
			(xy 141.404743 -287.193124) (xy 141.384795 -287.146304) (xy 141.372616 -287.09689) (xy 141.368521 -287.046162)
			(xy 141.05001 -287.046162) (xy 141.049515 -287.070769) (xy 141.04162 -287.119346) (xy 141.026036 -287.166027)
			(xy 141.003165 -287.209604) (xy 140.9736 -287.248948) (xy 140.938107 -287.28304) (xy 140.897604 -287.310996)
			(xy 140.853142 -287.332094) (xy 140.805871 -287.345786) (xy 140.757016 -287.351718) (xy 140.707841 -287.349737)
			(xy 140.659622 -287.339893) (xy 140.613606 -287.322441) (xy 140.570985 -287.297834) (xy 140.532864 -287.266709)
			(xy 140.500229 -287.229872) (xy 140.473926 -287.188276) (xy 140.454635 -287.143) (xy 140.442858 -287.095216)
			(xy 140.438898 -287.046162) (xy 140.12037 -287.046162) (xy 140.119858 -287.071608) (xy 140.111694 -287.121842)
			(xy 140.095578 -287.170116) (xy 140.071927 -287.215179) (xy 140.041354 -287.255865) (xy 140.00465 -287.29112)
			(xy 139.962766 -287.32003) (xy 139.916787 -287.341847) (xy 139.867903 -287.356007) (xy 139.817382 -287.362141)
			(xy 139.76653 -287.360092) (xy 139.716666 -287.349912) (xy 139.66908 -287.331865) (xy 139.625006 -287.306419)
			(xy 139.585584 -287.274232) (xy 139.551836 -287.236138) (xy 139.524635 -287.193124) (xy 139.504687 -287.146304)
			(xy 139.492508 -287.09689) (xy 139.488413 -287.046162) (xy 139.170151 -287.046162) (xy 139.170156 -287.046416)
			(xy 139.169661 -287.071023) (xy 139.161766 -287.1196) (xy 139.146182 -287.166281) (xy 139.123311 -287.209858)
			(xy 139.093746 -287.249202) (xy 139.058253 -287.283294) (xy 139.01775 -287.31125) (xy 138.973288 -287.332348)
			(xy 138.926017 -287.34604) (xy 138.877162 -287.351972) (xy 138.827987 -287.349991) (xy 138.779768 -287.340147)
			(xy 138.733752 -287.322695) (xy 138.691131 -287.298088) (xy 138.65301 -287.266963) (xy 138.620375 -287.230126)
			(xy 138.594072 -287.18853) (xy 138.574781 -287.143254) (xy 138.563004 -287.09547) (xy 138.559044 -287.046416)
			(xy 138.240511 -287.046416) (xy 138.240004 -287.071608) (xy 138.23184 -287.121842) (xy 138.215724 -287.170116)
			(xy 138.192073 -287.215179) (xy 138.1615 -287.255865) (xy 138.124796 -287.29112) (xy 138.082912 -287.32003)
			(xy 138.036933 -287.341847) (xy 137.988049 -287.356007) (xy 137.937528 -287.362141) (xy 137.886676 -287.360092)
			(xy 137.836812 -287.349912) (xy 137.789226 -287.331865) (xy 137.745152 -287.306419) (xy 137.70573 -287.274232)
			(xy 137.671982 -287.236138) (xy 137.644781 -287.193124) (xy 137.624833 -287.146304) (xy 137.612654 -287.09689)
			(xy 137.608559 -287.046162) (xy 137.290048 -287.046162) (xy 137.289553 -287.070769) (xy 137.281658 -287.119346)
			(xy 137.266074 -287.166027) (xy 137.243203 -287.209604) (xy 137.213638 -287.248948) (xy 137.178145 -287.28304)
			(xy 137.137642 -287.310996) (xy 137.09318 -287.332094) (xy 137.045909 -287.345786) (xy 136.997054 -287.351718)
			(xy 136.947879 -287.349737) (xy 136.89966 -287.339893) (xy 136.853644 -287.322441) (xy 136.811023 -287.297834)
			(xy 136.772902 -287.266709) (xy 136.740267 -287.229872) (xy 136.713964 -287.188276) (xy 136.694673 -287.143)
			(xy 136.682896 -287.095216) (xy 136.678936 -287.046162) (xy 136.360408 -287.046162) (xy 136.359896 -287.071608)
			(xy 136.351732 -287.121842) (xy 136.335616 -287.170116) (xy 136.311965 -287.215179) (xy 136.281392 -287.255865)
			(xy 136.244688 -287.29112) (xy 136.202804 -287.32003) (xy 136.156825 -287.341847) (xy 136.107941 -287.356007)
			(xy 136.05742 -287.362141) (xy 136.006568 -287.360092) (xy 135.956704 -287.349912) (xy 135.909118 -287.331865)
			(xy 135.865044 -287.306419) (xy 135.825622 -287.274232) (xy 135.791874 -287.236138) (xy 135.764673 -287.193124)
			(xy 135.744725 -287.146304) (xy 135.732546 -287.09689) (xy 135.728451 -287.046162) (xy 135.420354 -287.046162)
			(xy 135.419842 -287.071608) (xy 135.411678 -287.121842) (xy 135.395562 -287.170116) (xy 135.371911 -287.215179)
			(xy 135.341338 -287.255865) (xy 135.304634 -287.29112) (xy 135.26275 -287.32003) (xy 135.216771 -287.341847)
			(xy 135.167887 -287.356007) (xy 135.117366 -287.362141) (xy 135.066514 -287.360092) (xy 135.01665 -287.349912)
			(xy 134.969064 -287.331865) (xy 134.92499 -287.306419) (xy 134.885568 -287.274232) (xy 134.85182 -287.236138)
			(xy 134.824619 -287.193124) (xy 134.804671 -287.146304) (xy 134.792492 -287.09689) (xy 134.788397 -287.046162)
			(xy 134.470135 -287.046162) (xy 134.47014 -287.046416) (xy 134.469645 -287.071023) (xy 134.46175 -287.1196)
			(xy 134.446166 -287.166281) (xy 134.423295 -287.209858) (xy 134.39373 -287.249202) (xy 134.358237 -287.283294)
			(xy 134.317734 -287.31125) (xy 134.273272 -287.332348) (xy 134.226001 -287.34604) (xy 134.177146 -287.351972)
			(xy 134.127971 -287.349991) (xy 134.079752 -287.340147) (xy 134.033736 -287.322695) (xy 133.991115 -287.298088)
			(xy 133.952994 -287.266963) (xy 133.920359 -287.230126) (xy 133.894056 -287.18853) (xy 133.874765 -287.143254)
			(xy 133.862988 -287.09547) (xy 133.859028 -287.046416) (xy 133.540495 -287.046416) (xy 133.539988 -287.071608)
			(xy 133.531824 -287.121842) (xy 133.515708 -287.170116) (xy 133.492057 -287.215179) (xy 133.461484 -287.255865)
			(xy 133.42478 -287.29112) (xy 133.382896 -287.32003) (xy 133.336917 -287.341847) (xy 133.288033 -287.356007)
			(xy 133.237512 -287.362141) (xy 133.18666 -287.360092) (xy 133.136796 -287.349912) (xy 133.08921 -287.331865)
			(xy 133.045136 -287.306419) (xy 133.005714 -287.274232) (xy 132.971966 -287.236138) (xy 132.944765 -287.193124)
			(xy 132.924817 -287.146304) (xy 132.912638 -287.09689) (xy 132.908543 -287.046162) (xy 132.590032 -287.046162)
			(xy 132.589537 -287.070769) (xy 132.581642 -287.119346) (xy 132.566058 -287.166027) (xy 132.543187 -287.209604)
			(xy 132.513622 -287.248948) (xy 132.478129 -287.28304) (xy 132.437626 -287.310996) (xy 132.393164 -287.332094)
			(xy 132.345893 -287.345786) (xy 132.297038 -287.351718) (xy 132.247863 -287.349737) (xy 132.199644 -287.339893)
			(xy 132.153628 -287.322441) (xy 132.111007 -287.297834) (xy 132.072886 -287.266709) (xy 132.040251 -287.229872)
			(xy 132.013948 -287.188276) (xy 131.994657 -287.143) (xy 131.98288 -287.095216) (xy 131.97892 -287.046162)
			(xy 131.660392 -287.046162) (xy 131.65988 -287.071608) (xy 131.651716 -287.121842) (xy 131.6356 -287.170116)
			(xy 131.611949 -287.215179) (xy 131.581376 -287.255865) (xy 131.544672 -287.29112) (xy 131.502788 -287.32003)
			(xy 131.456809 -287.341847) (xy 131.407925 -287.356007) (xy 131.357404 -287.362141) (xy 131.306552 -287.360092)
			(xy 131.256688 -287.349912) (xy 131.209102 -287.331865) (xy 131.165028 -287.306419) (xy 131.125606 -287.274232)
			(xy 131.091858 -287.236138) (xy 131.064657 -287.193124) (xy 131.044709 -287.146304) (xy 131.03253 -287.09689)
			(xy 131.028435 -287.046162) (xy 130.710173 -287.046162) (xy 130.710178 -287.046416) (xy 130.709683 -287.071023)
			(xy 130.701788 -287.1196) (xy 130.686204 -287.166281) (xy 130.663333 -287.209858) (xy 130.633768 -287.249202)
			(xy 130.598275 -287.283294) (xy 130.557772 -287.31125) (xy 130.51331 -287.332348) (xy 130.466039 -287.34604)
			(xy 130.417184 -287.351972) (xy 130.368009 -287.349991) (xy 130.31979 -287.340147) (xy 130.273774 -287.322695)
			(xy 130.231153 -287.298088) (xy 130.193032 -287.266963) (xy 130.160397 -287.230126) (xy 130.134094 -287.18853)
			(xy 130.114803 -287.143254) (xy 130.103026 -287.09547) (xy 130.099066 -287.046416) (xy 129.780533 -287.046416)
			(xy 129.780026 -287.071608) (xy 129.771862 -287.121842) (xy 129.755746 -287.170116) (xy 129.732095 -287.215179)
			(xy 129.701522 -287.255865) (xy 129.664818 -287.29112) (xy 129.622934 -287.32003) (xy 129.576955 -287.341847)
			(xy 129.528071 -287.356007) (xy 129.47755 -287.362141) (xy 129.426698 -287.360092) (xy 129.376834 -287.349912)
			(xy 129.329248 -287.331865) (xy 129.285174 -287.306419) (xy 129.245752 -287.274232) (xy 129.212004 -287.236138)
			(xy 129.184803 -287.193124) (xy 129.164855 -287.146304) (xy 129.152676 -287.09689) (xy 129.148581 -287.046162)
			(xy 128.840484 -287.046162) (xy 128.839972 -287.071608) (xy 128.831808 -287.121842) (xy 128.815692 -287.170116)
			(xy 128.792041 -287.215179) (xy 128.761468 -287.255865) (xy 128.724764 -287.29112) (xy 128.68288 -287.32003)
			(xy 128.636901 -287.341847) (xy 128.588017 -287.356007) (xy 128.537496 -287.362141) (xy 128.486644 -287.360092)
			(xy 128.43678 -287.349912) (xy 128.389194 -287.331865) (xy 128.34512 -287.306419) (xy 128.305698 -287.274232)
			(xy 128.27195 -287.236138) (xy 128.244749 -287.193124) (xy 128.224801 -287.146304) (xy 128.212622 -287.09689)
			(xy 128.208527 -287.046162) (xy 127.890566 -287.046162) (xy 127.890569 -287.0462) (xy 127.886397 -287.096544)
			(xy 127.873997 -287.145514) (xy 127.853705 -287.191775) (xy 127.826076 -287.234066) (xy 127.791863 -287.271232)
			(xy 127.751999 -287.302261) (xy 127.707572 -287.326304) (xy 127.659793 -287.342708) (xy 127.609966 -287.351024)
			(xy 127.584708 -287.35147) (xy 127.561802 -287.351039) (xy 127.516511 -287.344154) (xy 127.472755 -287.330584)
			(xy 127.431516 -287.310631) (xy 127.39372 -287.284744) (xy 127.376682 -287.269428) (xy 127.365252 -287.259014)
			(xy 127.335534 -287.253934) (xy 127.23622 -287.297368) (xy 127.227399 -287.301733) (xy 127.21368 -287.315817)
			(xy 127.206247 -287.33402) (xy 127.20574 -287.34385) (xy 127.20574 -287.545018) (xy 127.22225 -287.570164)
			(xy 127.23622 -287.57626) (xy 127.259285 -287.586802) (xy 127.301841 -287.614379) (xy 127.339256 -287.648607)
			(xy 127.370502 -287.688546) (xy 127.39472 -287.733099) (xy 127.411245 -287.781041) (xy 127.419622 -287.831054)
			(xy 127.419621 -287.856422) (xy 127.738627 -287.856422) (xy 127.742722 -287.805694) (xy 127.754901 -287.75628)
			(xy 127.774849 -287.70946) (xy 127.80205 -287.666446) (xy 127.835798 -287.628352) (xy 127.87522 -287.596165)
			(xy 127.919294 -287.570719) (xy 127.96688 -287.552672) (xy 128.016744 -287.542492) (xy 128.067596 -287.540443)
			(xy 128.118117 -287.546577) (xy 128.167001 -287.560737) (xy 128.21298 -287.582554) (xy 128.254864 -287.611464)
			(xy 128.291568 -287.646719) (xy 128.322141 -287.687405) (xy 128.345792 -287.732468) (xy 128.361908 -287.780742)
			(xy 128.370072 -287.830976) (xy 128.370584 -287.856422) (xy 128.688858 -287.856422) (xy 128.692818 -287.807368)
			(xy 128.704595 -287.759584) (xy 128.723886 -287.714308) (xy 128.750189 -287.672712) (xy 128.782824 -287.635875)
			(xy 128.820945 -287.60475) (xy 128.863566 -287.580143) (xy 128.909582 -287.562691) (xy 128.957801 -287.552847)
			(xy 129.006976 -287.550866) (xy 129.055831 -287.556798) (xy 129.103102 -287.57049) (xy 129.147564 -287.591588)
			(xy 129.188067 -287.619544) (xy 129.22356 -287.653636) (xy 129.253125 -287.69298) (xy 129.275996 -287.736557)
			(xy 129.29158 -287.783238) (xy 129.299475 -287.831815) (xy 129.29997 -287.856422) (xy 129.618481 -287.856422)
			(xy 129.622576 -287.805694) (xy 129.634755 -287.75628) (xy 129.654703 -287.70946) (xy 129.681904 -287.666446)
			(xy 129.715652 -287.628352) (xy 129.755074 -287.596165) (xy 129.799148 -287.570719) (xy 129.846734 -287.552672)
			(xy 129.896598 -287.542492) (xy 129.94745 -287.540443) (xy 129.997971 -287.546577) (xy 130.046855 -287.560737)
			(xy 130.092834 -287.582554) (xy 130.134718 -287.611464) (xy 130.171422 -287.646719) (xy 130.201995 -287.687405)
			(xy 130.225646 -287.732468) (xy 130.241762 -287.780742) (xy 130.249926 -287.830976) (xy 130.250438 -287.856422)
			(xy 131.498589 -287.856422) (xy 131.502684 -287.805694) (xy 131.514863 -287.75628) (xy 131.534811 -287.70946)
			(xy 131.562012 -287.666446) (xy 131.59576 -287.628352) (xy 131.635182 -287.596165) (xy 131.679256 -287.570719)
			(xy 131.726842 -287.552672) (xy 131.776706 -287.542492) (xy 131.827558 -287.540443) (xy 131.878079 -287.546577)
			(xy 131.926963 -287.560737) (xy 131.972942 -287.582554) (xy 132.014826 -287.611464) (xy 132.05153 -287.646719)
			(xy 132.082103 -287.687405) (xy 132.105754 -287.732468) (xy 132.12187 -287.780742) (xy 132.130034 -287.830976)
			(xy 132.130546 -287.856422) (xy 132.438643 -287.856422) (xy 132.442738 -287.805694) (xy 132.454917 -287.75628)
			(xy 132.474865 -287.70946) (xy 132.502066 -287.666446) (xy 132.535814 -287.628352) (xy 132.575236 -287.596165)
			(xy 132.61931 -287.570719) (xy 132.666896 -287.552672) (xy 132.71676 -287.542492) (xy 132.767612 -287.540443)
			(xy 132.818133 -287.546577) (xy 132.867017 -287.560737) (xy 132.912996 -287.582554) (xy 132.95488 -287.611464)
			(xy 132.991584 -287.646719) (xy 133.022157 -287.687405) (xy 133.045808 -287.732468) (xy 133.061924 -287.780742)
			(xy 133.070088 -287.830976) (xy 133.0706 -287.856422) (xy 133.388874 -287.856422) (xy 133.392834 -287.807368)
			(xy 133.404611 -287.759584) (xy 133.423902 -287.714308) (xy 133.450205 -287.672712) (xy 133.48284 -287.635875)
			(xy 133.520961 -287.60475) (xy 133.563582 -287.580143) (xy 133.609598 -287.562691) (xy 133.657817 -287.552847)
			(xy 133.706992 -287.550866) (xy 133.755847 -287.556798) (xy 133.803118 -287.57049) (xy 133.84758 -287.591588)
			(xy 133.888083 -287.619544) (xy 133.923576 -287.653636) (xy 133.953141 -287.69298) (xy 133.976012 -287.736557)
			(xy 133.991596 -287.783238) (xy 133.999491 -287.831815) (xy 133.999986 -287.856422) (xy 134.318497 -287.856422)
			(xy 134.322592 -287.805694) (xy 134.334771 -287.75628) (xy 134.354719 -287.70946) (xy 134.38192 -287.666446)
			(xy 134.415668 -287.628352) (xy 134.45509 -287.596165) (xy 134.499164 -287.570719) (xy 134.54675 -287.552672)
			(xy 134.596614 -287.542492) (xy 134.647466 -287.540443) (xy 134.697987 -287.546577) (xy 134.746871 -287.560737)
			(xy 134.79285 -287.582554) (xy 134.834734 -287.611464) (xy 134.871438 -287.646719) (xy 134.902011 -287.687405)
			(xy 134.925662 -287.732468) (xy 134.941778 -287.780742) (xy 134.949942 -287.830976) (xy 134.950454 -287.856422)
			(xy 135.268982 -287.856422) (xy 135.272942 -287.807368) (xy 135.284719 -287.759584) (xy 135.30401 -287.714308)
			(xy 135.330313 -287.672712) (xy 135.362948 -287.635875) (xy 135.401069 -287.60475) (xy 135.44369 -287.580143)
			(xy 135.489706 -287.562691) (xy 135.537925 -287.552847) (xy 135.5871 -287.550866) (xy 135.635955 -287.556798)
			(xy 135.683226 -287.57049) (xy 135.727688 -287.591588) (xy 135.768191 -287.619544) (xy 135.803684 -287.653636)
			(xy 135.833249 -287.69298) (xy 135.85612 -287.736557) (xy 135.871704 -287.783238) (xy 135.879599 -287.831815)
			(xy 135.880094 -287.856422) (xy 136.198605 -287.856422) (xy 136.2027 -287.805694) (xy 136.214879 -287.75628)
			(xy 136.234827 -287.70946) (xy 136.262028 -287.666446) (xy 136.295776 -287.628352) (xy 136.335198 -287.596165)
			(xy 136.379272 -287.570719) (xy 136.426858 -287.552672) (xy 136.476722 -287.542492) (xy 136.527574 -287.540443)
			(xy 136.578095 -287.546577) (xy 136.626979 -287.560737) (xy 136.672958 -287.582554) (xy 136.714842 -287.611464)
			(xy 136.751546 -287.646719) (xy 136.782119 -287.687405) (xy 136.80577 -287.732468) (xy 136.821886 -287.780742)
			(xy 136.83005 -287.830976) (xy 136.830562 -287.856422) (xy 138.078459 -287.856422) (xy 138.082554 -287.805694)
			(xy 138.094733 -287.75628) (xy 138.114681 -287.70946) (xy 138.141882 -287.666446) (xy 138.17563 -287.628352)
			(xy 138.215052 -287.596165) (xy 138.259126 -287.570719) (xy 138.306712 -287.552672) (xy 138.356576 -287.542492)
			(xy 138.407428 -287.540443) (xy 138.457949 -287.546577) (xy 138.506833 -287.560737) (xy 138.552812 -287.582554)
			(xy 138.594696 -287.611464) (xy 138.6314 -287.646719) (xy 138.661973 -287.687405) (xy 138.685624 -287.732468)
			(xy 138.70174 -287.780742) (xy 138.709904 -287.830976) (xy 138.710416 -287.856422) (xy 139.018513 -287.856422)
			(xy 139.022608 -287.805694) (xy 139.034787 -287.75628) (xy 139.054735 -287.70946) (xy 139.081936 -287.666446)
			(xy 139.115684 -287.628352) (xy 139.155106 -287.596165) (xy 139.19918 -287.570719) (xy 139.246766 -287.552672)
			(xy 139.29663 -287.542492) (xy 139.347482 -287.540443) (xy 139.398003 -287.546577) (xy 139.446887 -287.560737)
			(xy 139.492866 -287.582554) (xy 139.53475 -287.611464) (xy 139.571454 -287.646719) (xy 139.602027 -287.687405)
			(xy 139.625678 -287.732468) (xy 139.641794 -287.780742) (xy 139.649958 -287.830976) (xy 139.65047 -287.856422)
			(xy 139.968998 -287.856422) (xy 139.972958 -287.807368) (xy 139.984735 -287.759584) (xy 140.004026 -287.714308)
			(xy 140.030329 -287.672712) (xy 140.062964 -287.635875) (xy 140.101085 -287.60475) (xy 140.143706 -287.580143)
			(xy 140.189722 -287.562691) (xy 140.237941 -287.552847) (xy 140.287116 -287.550866) (xy 140.335971 -287.556798)
			(xy 140.383242 -287.57049) (xy 140.427704 -287.591588) (xy 140.468207 -287.619544) (xy 140.5037 -287.653636)
			(xy 140.533265 -287.69298) (xy 140.556136 -287.736557) (xy 140.57172 -287.783238) (xy 140.579615 -287.831815)
			(xy 140.58011 -287.856422) (xy 140.898621 -287.856422) (xy 140.902716 -287.805694) (xy 140.914895 -287.75628)
			(xy 140.934843 -287.70946) (xy 140.962044 -287.666446) (xy 140.995792 -287.628352) (xy 141.035214 -287.596165)
			(xy 141.079288 -287.570719) (xy 141.126874 -287.552672) (xy 141.176738 -287.542492) (xy 141.22759 -287.540443)
			(xy 141.278111 -287.546577) (xy 141.326995 -287.560737) (xy 141.372974 -287.582554) (xy 141.414858 -287.611464)
			(xy 141.451562 -287.646719) (xy 141.482135 -287.687405) (xy 141.505786 -287.732468) (xy 141.521902 -287.780742)
			(xy 141.530066 -287.830976) (xy 141.530578 -287.856422) (xy 141.848852 -287.856422) (xy 141.852812 -287.807368)
			(xy 141.864589 -287.759584) (xy 141.88388 -287.714308) (xy 141.910183 -287.672712) (xy 141.942818 -287.635875)
			(xy 141.980939 -287.60475) (xy 142.02356 -287.580143) (xy 142.069576 -287.562691) (xy 142.117795 -287.552847)
			(xy 142.16697 -287.550866) (xy 142.215825 -287.556798) (xy 142.263096 -287.57049) (xy 142.307558 -287.591588)
			(xy 142.348061 -287.619544) (xy 142.383554 -287.653636) (xy 142.413119 -287.69298) (xy 142.43599 -287.736557)
			(xy 142.451574 -287.783238) (xy 142.459469 -287.831815) (xy 142.459964 -287.856422) (xy 142.778475 -287.856422)
			(xy 142.78257 -287.805694) (xy 142.794749 -287.75628) (xy 142.814697 -287.70946) (xy 142.841898 -287.666446)
			(xy 142.875646 -287.628352) (xy 142.915068 -287.596165) (xy 142.959142 -287.570719) (xy 143.006728 -287.552672)
			(xy 143.056592 -287.542492) (xy 143.107444 -287.540443) (xy 143.157965 -287.546577) (xy 143.206849 -287.560737)
			(xy 143.252828 -287.582554) (xy 143.264317 -287.590484) (xy 146.737082 -287.590484) (xy 146.741042 -287.54143)
			(xy 146.752819 -287.493646) (xy 146.77211 -287.44837) (xy 146.798413 -287.406774) (xy 146.831048 -287.369937)
			(xy 146.869169 -287.338812) (xy 146.91179 -287.314205) (xy 146.957806 -287.296753) (xy 147.006025 -287.286909)
			(xy 147.0552 -287.284928) (xy 147.104055 -287.29086) (xy 147.151326 -287.304552) (xy 147.195788 -287.32565)
			(xy 147.236291 -287.353606) (xy 147.271784 -287.387698) (xy 147.301349 -287.427042) (xy 147.305678 -287.43529)
			(xy 165.442915 -287.43529) (xy 165.44685 -287.381519) (xy 165.458573 -287.328895) (xy 165.477833 -287.278538)
			(xy 165.504219 -287.231521) (xy 165.537171 -287.188848) (xy 165.575984 -287.151427) (xy 165.619832 -287.120057)
			(xy 165.66778 -287.095405) (xy 165.718807 -287.077997) (xy 165.771825 -287.068204) (xy 165.825704 -287.066235)
			(xy 165.879295 -287.072132) (xy 165.931456 -287.085768) (xy 165.981076 -287.106855) (xy 166.027097 -287.134941)
			(xy 166.068539 -287.169429) (xy 166.104517 -287.209583) (xy 166.134265 -287.254547) (xy 166.15715 -287.303364)
			(xy 166.172682 -287.354993) (xy 166.180532 -287.408333) (xy 166.181024 -287.43529) (xy 172.986969 -287.43529)
			(xy 172.990904 -287.381519) (xy 173.002627 -287.328895) (xy 173.021887 -287.278538) (xy 173.048273 -287.231521)
			(xy 173.081225 -287.188848) (xy 173.120038 -287.151427) (xy 173.163886 -287.120057) (xy 173.211834 -287.095405)
			(xy 173.262861 -287.077997) (xy 173.315879 -287.068204) (xy 173.369758 -287.066235) (xy 173.423349 -287.072132)
			(xy 173.47551 -287.085768) (xy 173.52513 -287.106855) (xy 173.571151 -287.134941) (xy 173.612593 -287.169429)
			(xy 173.648571 -287.209583) (xy 173.678319 -287.254547) (xy 173.701204 -287.303364) (xy 173.716736 -287.354993)
			(xy 173.724586 -287.408333) (xy 173.725078 -287.43529) (xy 173.724586 -287.462247) (xy 173.716736 -287.515587)
			(xy 173.701204 -287.567216) (xy 173.678319 -287.616033) (xy 173.648571 -287.660997) (xy 173.612593 -287.701151)
			(xy 173.571151 -287.735639) (xy 173.52513 -287.763725) (xy 173.47551 -287.784812) (xy 173.423349 -287.798448)
			(xy 173.369758 -287.804345) (xy 173.315879 -287.802376) (xy 173.262861 -287.792583) (xy 173.211834 -287.775175)
			(xy 173.163886 -287.750523) (xy 173.120038 -287.719153) (xy 173.081225 -287.681732) (xy 173.048273 -287.639059)
			(xy 173.021887 -287.592042) (xy 173.002627 -287.541685) (xy 172.990904 -287.489061) (xy 172.986969 -287.43529)
			(xy 166.181024 -287.43529) (xy 166.180532 -287.462247) (xy 166.172682 -287.515587) (xy 166.15715 -287.567216)
			(xy 166.134265 -287.616033) (xy 166.104517 -287.660997) (xy 166.068539 -287.701151) (xy 166.027097 -287.735639)
			(xy 165.981076 -287.763725) (xy 165.931456 -287.784812) (xy 165.879295 -287.798448) (xy 165.825704 -287.804345)
			(xy 165.771825 -287.802376) (xy 165.718807 -287.792583) (xy 165.66778 -287.775175) (xy 165.619832 -287.750523)
			(xy 165.575984 -287.719153) (xy 165.537171 -287.681732) (xy 165.504219 -287.639059) (xy 165.477833 -287.592042)
			(xy 165.458573 -287.541685) (xy 165.44685 -287.489061) (xy 165.442915 -287.43529) (xy 147.305678 -287.43529)
			(xy 147.32422 -287.470619) (xy 147.339804 -287.5173) (xy 147.347699 -287.565877) (xy 147.348194 -287.590484)
			(xy 147.347699 -287.615091) (xy 147.339804 -287.663668) (xy 147.32422 -287.710349) (xy 147.301349 -287.753926)
			(xy 147.271784 -287.79327) (xy 147.236291 -287.827362) (xy 147.195788 -287.855318) (xy 147.151326 -287.876416)
			(xy 147.104055 -287.890108) (xy 147.0552 -287.89604) (xy 147.006025 -287.894059) (xy 146.957806 -287.884215)
			(xy 146.91179 -287.866763) (xy 146.869169 -287.842156) (xy 146.831048 -287.811031) (xy 146.798413 -287.774194)
			(xy 146.77211 -287.732598) (xy 146.752819 -287.687322) (xy 146.741042 -287.639538) (xy 146.737082 -287.590484)
			(xy 143.264317 -287.590484) (xy 143.294712 -287.611464) (xy 143.331416 -287.646719) (xy 143.361989 -287.687405)
			(xy 143.38564 -287.732468) (xy 143.401756 -287.780742) (xy 143.40992 -287.830976) (xy 143.410432 -287.856422)
			(xy 143.40992 -287.881868) (xy 143.401756 -287.932102) (xy 143.38564 -287.980376) (xy 143.361989 -288.025439)
			(xy 143.331416 -288.066125) (xy 143.294712 -288.10138) (xy 143.252828 -288.13029) (xy 143.206849 -288.152107)
			(xy 143.157965 -288.166267) (xy 143.107444 -288.172401) (xy 143.056592 -288.170352) (xy 143.006728 -288.160172)
			(xy 142.959142 -288.142125) (xy 142.915068 -288.116679) (xy 142.875646 -288.084492) (xy 142.841898 -288.046398)
			(xy 142.814697 -288.003384) (xy 142.794749 -287.956564) (xy 142.78257 -287.90715) (xy 142.778475 -287.856422)
			(xy 142.459964 -287.856422) (xy 142.459469 -287.881029) (xy 142.451574 -287.929606) (xy 142.43599 -287.976287)
			(xy 142.413119 -288.019864) (xy 142.383554 -288.059208) (xy 142.348061 -288.0933) (xy 142.307558 -288.121256)
			(xy 142.263096 -288.142354) (xy 142.215825 -288.156046) (xy 142.16697 -288.161978) (xy 142.117795 -288.159997)
			(xy 142.069576 -288.150153) (xy 142.02356 -288.132701) (xy 141.980939 -288.108094) (xy 141.942818 -288.076969)
			(xy 141.910183 -288.040132) (xy 141.88388 -287.998536) (xy 141.864589 -287.95326) (xy 141.852812 -287.905476)
			(xy 141.848852 -287.856422) (xy 141.530578 -287.856422) (xy 141.530066 -287.881868) (xy 141.521902 -287.932102)
			(xy 141.505786 -287.980376) (xy 141.482135 -288.025439) (xy 141.451562 -288.066125) (xy 141.414858 -288.10138)
			(xy 141.372974 -288.13029) (xy 141.326995 -288.152107) (xy 141.278111 -288.166267) (xy 141.22759 -288.172401)
			(xy 141.176738 -288.170352) (xy 141.126874 -288.160172) (xy 141.079288 -288.142125) (xy 141.035214 -288.116679)
			(xy 140.995792 -288.084492) (xy 140.962044 -288.046398) (xy 140.934843 -288.003384) (xy 140.914895 -287.956564)
			(xy 140.902716 -287.90715) (xy 140.898621 -287.856422) (xy 140.58011 -287.856422) (xy 140.579615 -287.881029)
			(xy 140.57172 -287.929606) (xy 140.556136 -287.976287) (xy 140.533265 -288.019864) (xy 140.5037 -288.059208)
			(xy 140.468207 -288.0933) (xy 140.427704 -288.121256) (xy 140.383242 -288.142354) (xy 140.335971 -288.156046)
			(xy 140.287116 -288.161978) (xy 140.237941 -288.159997) (xy 140.189722 -288.150153) (xy 140.143706 -288.132701)
			(xy 140.101085 -288.108094) (xy 140.062964 -288.076969) (xy 140.030329 -288.040132) (xy 140.004026 -287.998536)
			(xy 139.984735 -287.95326) (xy 139.972958 -287.905476) (xy 139.968998 -287.856422) (xy 139.65047 -287.856422)
			(xy 139.649958 -287.881868) (xy 139.641794 -287.932102) (xy 139.625678 -287.980376) (xy 139.602027 -288.025439)
			(xy 139.571454 -288.066125) (xy 139.53475 -288.10138) (xy 139.492866 -288.13029) (xy 139.446887 -288.152107)
			(xy 139.398003 -288.166267) (xy 139.347482 -288.172401) (xy 139.29663 -288.170352) (xy 139.246766 -288.160172)
			(xy 139.19918 -288.142125) (xy 139.155106 -288.116679) (xy 139.115684 -288.084492) (xy 139.081936 -288.046398)
			(xy 139.054735 -288.003384) (xy 139.034787 -287.956564) (xy 139.022608 -287.90715) (xy 139.018513 -287.856422)
			(xy 138.710416 -287.856422) (xy 138.709904 -287.881868) (xy 138.70174 -287.932102) (xy 138.685624 -287.980376)
			(xy 138.661973 -288.025439) (xy 138.6314 -288.066125) (xy 138.594696 -288.10138) (xy 138.552812 -288.13029)
			(xy 138.506833 -288.152107) (xy 138.457949 -288.166267) (xy 138.407428 -288.172401) (xy 138.356576 -288.170352)
			(xy 138.306712 -288.160172) (xy 138.259126 -288.142125) (xy 138.215052 -288.116679) (xy 138.17563 -288.084492)
			(xy 138.141882 -288.046398) (xy 138.114681 -288.003384) (xy 138.094733 -287.956564) (xy 138.082554 -287.90715)
			(xy 138.078459 -287.856422) (xy 136.830562 -287.856422) (xy 136.83005 -287.881868) (xy 136.821886 -287.932102)
			(xy 136.80577 -287.980376) (xy 136.782119 -288.025439) (xy 136.751546 -288.066125) (xy 136.714842 -288.10138)
			(xy 136.672958 -288.13029) (xy 136.626979 -288.152107) (xy 136.578095 -288.166267) (xy 136.527574 -288.172401)
			(xy 136.476722 -288.170352) (xy 136.426858 -288.160172) (xy 136.379272 -288.142125) (xy 136.335198 -288.116679)
			(xy 136.295776 -288.084492) (xy 136.262028 -288.046398) (xy 136.234827 -288.003384) (xy 136.214879 -287.956564)
			(xy 136.2027 -287.90715) (xy 136.198605 -287.856422) (xy 135.880094 -287.856422) (xy 135.879599 -287.881029)
			(xy 135.871704 -287.929606) (xy 135.85612 -287.976287) (xy 135.833249 -288.019864) (xy 135.803684 -288.059208)
			(xy 135.768191 -288.0933) (xy 135.727688 -288.121256) (xy 135.683226 -288.142354) (xy 135.635955 -288.156046)
			(xy 135.5871 -288.161978) (xy 135.537925 -288.159997) (xy 135.489706 -288.150153) (xy 135.44369 -288.132701)
			(xy 135.401069 -288.108094) (xy 135.362948 -288.076969) (xy 135.330313 -288.040132) (xy 135.30401 -287.998536)
			(xy 135.284719 -287.95326) (xy 135.272942 -287.905476) (xy 135.268982 -287.856422) (xy 134.950454 -287.856422)
			(xy 134.949942 -287.881868) (xy 134.941778 -287.932102) (xy 134.925662 -287.980376) (xy 134.902011 -288.025439)
			(xy 134.871438 -288.066125) (xy 134.834734 -288.10138) (xy 134.79285 -288.13029) (xy 134.746871 -288.152107)
			(xy 134.697987 -288.166267) (xy 134.647466 -288.172401) (xy 134.596614 -288.170352) (xy 134.54675 -288.160172)
			(xy 134.499164 -288.142125) (xy 134.45509 -288.116679) (xy 134.415668 -288.084492) (xy 134.38192 -288.046398)
			(xy 134.354719 -288.003384) (xy 134.334771 -287.956564) (xy 134.322592 -287.90715) (xy 134.318497 -287.856422)
			(xy 133.999986 -287.856422) (xy 133.999491 -287.881029) (xy 133.991596 -287.929606) (xy 133.976012 -287.976287)
			(xy 133.953141 -288.019864) (xy 133.923576 -288.059208) (xy 133.888083 -288.0933) (xy 133.84758 -288.121256)
			(xy 133.803118 -288.142354) (xy 133.755847 -288.156046) (xy 133.706992 -288.161978) (xy 133.657817 -288.159997)
			(xy 133.609598 -288.150153) (xy 133.563582 -288.132701) (xy 133.520961 -288.108094) (xy 133.48284 -288.076969)
			(xy 133.450205 -288.040132) (xy 133.423902 -287.998536) (xy 133.404611 -287.95326) (xy 133.392834 -287.905476)
			(xy 133.388874 -287.856422) (xy 133.0706 -287.856422) (xy 133.070088 -287.881868) (xy 133.061924 -287.932102)
			(xy 133.045808 -287.980376) (xy 133.022157 -288.025439) (xy 132.991584 -288.066125) (xy 132.95488 -288.10138)
			(xy 132.912996 -288.13029) (xy 132.867017 -288.152107) (xy 132.818133 -288.166267) (xy 132.767612 -288.172401)
			(xy 132.71676 -288.170352) (xy 132.666896 -288.160172) (xy 132.61931 -288.142125) (xy 132.575236 -288.116679)
			(xy 132.535814 -288.084492) (xy 132.502066 -288.046398) (xy 132.474865 -288.003384) (xy 132.454917 -287.956564)
			(xy 132.442738 -287.90715) (xy 132.438643 -287.856422) (xy 132.130546 -287.856422) (xy 132.130034 -287.881868)
			(xy 132.12187 -287.932102) (xy 132.105754 -287.980376) (xy 132.082103 -288.025439) (xy 132.05153 -288.066125)
			(xy 132.014826 -288.10138) (xy 131.972942 -288.13029) (xy 131.926963 -288.152107) (xy 131.878079 -288.166267)
			(xy 131.827558 -288.172401) (xy 131.776706 -288.170352) (xy 131.726842 -288.160172) (xy 131.679256 -288.142125)
			(xy 131.635182 -288.116679) (xy 131.59576 -288.084492) (xy 131.562012 -288.046398) (xy 131.534811 -288.003384)
			(xy 131.514863 -287.956564) (xy 131.502684 -287.90715) (xy 131.498589 -287.856422) (xy 130.250438 -287.856422)
			(xy 130.249926 -287.881868) (xy 130.241762 -287.932102) (xy 130.225646 -287.980376) (xy 130.201995 -288.025439)
			(xy 130.171422 -288.066125) (xy 130.134718 -288.10138) (xy 130.092834 -288.13029) (xy 130.046855 -288.152107)
			(xy 129.997971 -288.166267) (xy 129.94745 -288.172401) (xy 129.896598 -288.170352) (xy 129.846734 -288.160172)
			(xy 129.799148 -288.142125) (xy 129.755074 -288.116679) (xy 129.715652 -288.084492) (xy 129.681904 -288.046398)
			(xy 129.654703 -288.003384) (xy 129.634755 -287.956564) (xy 129.622576 -287.90715) (xy 129.618481 -287.856422)
			(xy 129.29997 -287.856422) (xy 129.299475 -287.881029) (xy 129.29158 -287.929606) (xy 129.275996 -287.976287)
			(xy 129.253125 -288.019864) (xy 129.22356 -288.059208) (xy 129.188067 -288.0933) (xy 129.147564 -288.121256)
			(xy 129.103102 -288.142354) (xy 129.055831 -288.156046) (xy 129.006976 -288.161978) (xy 128.957801 -288.159997)
			(xy 128.909582 -288.150153) (xy 128.863566 -288.132701) (xy 128.820945 -288.108094) (xy 128.782824 -288.076969)
			(xy 128.750189 -288.040132) (xy 128.723886 -287.998536) (xy 128.704595 -287.95326) (xy 128.692818 -287.905476)
			(xy 128.688858 -287.856422) (xy 128.370584 -287.856422) (xy 128.370072 -287.881868) (xy 128.361908 -287.932102)
			(xy 128.345792 -287.980376) (xy 128.322141 -288.025439) (xy 128.291568 -288.066125) (xy 128.254864 -288.10138)
			(xy 128.21298 -288.13029) (xy 128.167001 -288.152107) (xy 128.118117 -288.166267) (xy 128.067596 -288.172401)
			(xy 128.016744 -288.170352) (xy 127.96688 -288.160172) (xy 127.919294 -288.142125) (xy 127.87522 -288.116679)
			(xy 127.835798 -288.084492) (xy 127.80205 -288.046398) (xy 127.774849 -288.003384) (xy 127.754901 -287.956564)
			(xy 127.742722 -287.90715) (xy 127.738627 -287.856422) (xy 127.419621 -287.856422) (xy 127.41962 -287.881764)
			(xy 127.411241 -287.931776) (xy 127.394713 -287.979717) (xy 127.370493 -288.024269) (xy 127.339244 -288.064206)
			(xy 127.301827 -288.098432) (xy 127.259269 -288.126006) (xy 127.23622 -288.136584) (xy 127.22225 -288.14268)
			(xy 127.20574 -288.167826) (xy 127.20574 -288.285428) (xy 168.158683 -288.285428) (xy 168.162618 -288.231657)
			(xy 168.174341 -288.179033) (xy 168.193601 -288.128676) (xy 168.219987 -288.081659) (xy 168.252939 -288.038986)
			(xy 168.291752 -288.001565) (xy 168.3356 -287.970195) (xy 168.383548 -287.945543) (xy 168.434575 -287.928135)
			(xy 168.487593 -287.918342) (xy 168.541472 -287.916373) (xy 168.595063 -287.92227) (xy 168.647224 -287.935906)
			(xy 168.696844 -287.956993) (xy 168.742865 -287.985079) (xy 168.784307 -288.019567) (xy 168.820285 -288.059721)
			(xy 168.850033 -288.104685) (xy 168.872918 -288.153502) (xy 168.88845 -288.205131) (xy 168.8963 -288.258471)
			(xy 168.896792 -288.285428) (xy 168.8963 -288.312385) (xy 168.88845 -288.365725) (xy 168.872918 -288.417354)
			(xy 168.850033 -288.466171) (xy 168.820285 -288.511135) (xy 168.784307 -288.551289) (xy 168.742865 -288.585777)
			(xy 168.696844 -288.613863) (xy 168.647224 -288.63495) (xy 168.595063 -288.648586) (xy 168.541472 -288.654483)
			(xy 168.487593 -288.652514) (xy 168.434575 -288.642721) (xy 168.383548 -288.625313) (xy 168.3356 -288.600661)
			(xy 168.291752 -288.569291) (xy 168.252939 -288.53187) (xy 168.219987 -288.489197) (xy 168.193601 -288.44218)
			(xy 168.174341 -288.391823) (xy 168.162618 -288.339199) (xy 168.158683 -288.285428) (xy 127.20574 -288.285428)
			(xy 127.20574 -288.666174) (xy 128.208527 -288.666174) (xy 128.212622 -288.615446) (xy 128.224801 -288.566032)
			(xy 128.244749 -288.519212) (xy 128.27195 -288.476198) (xy 128.305698 -288.438104) (xy 128.34512 -288.405917)
			(xy 128.389194 -288.380471) (xy 128.43678 -288.362424) (xy 128.486644 -288.352244) (xy 128.537496 -288.350195)
			(xy 128.588017 -288.356329) (xy 128.636901 -288.370489) (xy 128.68288 -288.392306) (xy 128.724764 -288.421216)
			(xy 128.761468 -288.456471) (xy 128.792041 -288.497157) (xy 128.815692 -288.54222) (xy 128.831808 -288.590494)
			(xy 128.839972 -288.640728) (xy 128.840484 -288.666174) (xy 129.148581 -288.666174) (xy 129.152676 -288.615446)
			(xy 129.164855 -288.566032) (xy 129.184803 -288.519212) (xy 129.212004 -288.476198) (xy 129.245752 -288.438104)
			(xy 129.285174 -288.405917) (xy 129.329248 -288.380471) (xy 129.376834 -288.362424) (xy 129.426698 -288.352244)
			(xy 129.47755 -288.350195) (xy 129.528071 -288.356329) (xy 129.576955 -288.370489) (xy 129.622934 -288.392306)
			(xy 129.664818 -288.421216) (xy 129.701522 -288.456471) (xy 129.732095 -288.497157) (xy 129.755746 -288.54222)
			(xy 129.771862 -288.590494) (xy 129.780026 -288.640728) (xy 129.780538 -288.666174) (xy 130.099066 -288.666174)
			(xy 130.103026 -288.61712) (xy 130.114803 -288.569336) (xy 130.134094 -288.52406) (xy 130.160397 -288.482464)
			(xy 130.193032 -288.445627) (xy 130.231153 -288.414502) (xy 130.273774 -288.389895) (xy 130.31979 -288.372443)
			(xy 130.368009 -288.362599) (xy 130.417184 -288.360618) (xy 130.466039 -288.36655) (xy 130.51331 -288.380242)
			(xy 130.557772 -288.40134) (xy 130.598275 -288.429296) (xy 130.633768 -288.463388) (xy 130.663333 -288.502732)
			(xy 130.686204 -288.546309) (xy 130.701788 -288.59299) (xy 130.709683 -288.641567) (xy 130.710178 -288.666174)
			(xy 131.028435 -288.666174) (xy 131.03253 -288.615446) (xy 131.044709 -288.566032) (xy 131.064657 -288.519212)
			(xy 131.091858 -288.476198) (xy 131.125606 -288.438104) (xy 131.165028 -288.405917) (xy 131.209102 -288.380471)
			(xy 131.256688 -288.362424) (xy 131.306552 -288.352244) (xy 131.357404 -288.350195) (xy 131.407925 -288.356329)
			(xy 131.456809 -288.370489) (xy 131.502788 -288.392306) (xy 131.544672 -288.421216) (xy 131.581376 -288.456471)
			(xy 131.611949 -288.497157) (xy 131.6356 -288.54222) (xy 131.651716 -288.590494) (xy 131.65988 -288.640728)
			(xy 131.660392 -288.666174) (xy 131.97892 -288.666174) (xy 131.98288 -288.61712) (xy 131.994657 -288.569336)
			(xy 132.013948 -288.52406) (xy 132.040251 -288.482464) (xy 132.072886 -288.445627) (xy 132.111007 -288.414502)
			(xy 132.153628 -288.389895) (xy 132.199644 -288.372443) (xy 132.247863 -288.362599) (xy 132.297038 -288.360618)
			(xy 132.345893 -288.36655) (xy 132.393164 -288.380242) (xy 132.437626 -288.40134) (xy 132.478129 -288.429296)
			(xy 132.513622 -288.463388) (xy 132.543187 -288.502732) (xy 132.566058 -288.546309) (xy 132.581642 -288.59299)
			(xy 132.589537 -288.641567) (xy 132.590032 -288.666174) (xy 132.908543 -288.666174) (xy 132.912638 -288.615446)
			(xy 132.924817 -288.566032) (xy 132.944765 -288.519212) (xy 132.971966 -288.476198) (xy 133.005714 -288.438104)
			(xy 133.045136 -288.405917) (xy 133.08921 -288.380471) (xy 133.136796 -288.362424) (xy 133.18666 -288.352244)
			(xy 133.237512 -288.350195) (xy 133.288033 -288.356329) (xy 133.336917 -288.370489) (xy 133.382896 -288.392306)
			(xy 133.42478 -288.421216) (xy 133.461484 -288.456471) (xy 133.492057 -288.497157) (xy 133.515708 -288.54222)
			(xy 133.531824 -288.590494) (xy 133.539988 -288.640728) (xy 133.5405 -288.666174) (xy 133.859028 -288.666174)
			(xy 133.862988 -288.61712) (xy 133.874765 -288.569336) (xy 133.894056 -288.52406) (xy 133.920359 -288.482464)
			(xy 133.952994 -288.445627) (xy 133.991115 -288.414502) (xy 134.033736 -288.389895) (xy 134.079752 -288.372443)
			(xy 134.127971 -288.362599) (xy 134.177146 -288.360618) (xy 134.226001 -288.36655) (xy 134.273272 -288.380242)
			(xy 134.317734 -288.40134) (xy 134.358237 -288.429296) (xy 134.39373 -288.463388) (xy 134.423295 -288.502732)
			(xy 134.446166 -288.546309) (xy 134.46175 -288.59299) (xy 134.469645 -288.641567) (xy 134.47014 -288.666174)
			(xy 134.788397 -288.666174) (xy 134.792492 -288.615446) (xy 134.804671 -288.566032) (xy 134.824619 -288.519212)
			(xy 134.85182 -288.476198) (xy 134.885568 -288.438104) (xy 134.92499 -288.405917) (xy 134.969064 -288.380471)
			(xy 135.01665 -288.362424) (xy 135.066514 -288.352244) (xy 135.117366 -288.350195) (xy 135.167887 -288.356329)
			(xy 135.216771 -288.370489) (xy 135.26275 -288.392306) (xy 135.304634 -288.421216) (xy 135.341338 -288.456471)
			(xy 135.371911 -288.497157) (xy 135.395562 -288.54222) (xy 135.411678 -288.590494) (xy 135.419842 -288.640728)
			(xy 135.420354 -288.666174) (xy 135.728451 -288.666174) (xy 135.732546 -288.615446) (xy 135.744725 -288.566032)
			(xy 135.764673 -288.519212) (xy 135.791874 -288.476198) (xy 135.825622 -288.438104) (xy 135.865044 -288.405917)
			(xy 135.909118 -288.380471) (xy 135.956704 -288.362424) (xy 136.006568 -288.352244) (xy 136.05742 -288.350195)
			(xy 136.107941 -288.356329) (xy 136.156825 -288.370489) (xy 136.202804 -288.392306) (xy 136.244688 -288.421216)
			(xy 136.281392 -288.456471) (xy 136.311965 -288.497157) (xy 136.335616 -288.54222) (xy 136.351732 -288.590494)
			(xy 136.359896 -288.640728) (xy 136.360408 -288.666174) (xy 136.678936 -288.666174) (xy 136.682896 -288.61712)
			(xy 136.694673 -288.569336) (xy 136.713964 -288.52406) (xy 136.740267 -288.482464) (xy 136.772902 -288.445627)
			(xy 136.811023 -288.414502) (xy 136.853644 -288.389895) (xy 136.89966 -288.372443) (xy 136.947879 -288.362599)
			(xy 136.997054 -288.360618) (xy 137.045909 -288.36655) (xy 137.09318 -288.380242) (xy 137.137642 -288.40134)
			(xy 137.178145 -288.429296) (xy 137.213638 -288.463388) (xy 137.243203 -288.502732) (xy 137.266074 -288.546309)
			(xy 137.281658 -288.59299) (xy 137.289553 -288.641567) (xy 137.290048 -288.666174) (xy 137.608559 -288.666174)
			(xy 137.612654 -288.615446) (xy 137.624833 -288.566032) (xy 137.644781 -288.519212) (xy 137.671982 -288.476198)
			(xy 137.70573 -288.438104) (xy 137.745152 -288.405917) (xy 137.789226 -288.380471) (xy 137.836812 -288.362424)
			(xy 137.886676 -288.352244) (xy 137.937528 -288.350195) (xy 137.988049 -288.356329) (xy 138.036933 -288.370489)
			(xy 138.082912 -288.392306) (xy 138.124796 -288.421216) (xy 138.1615 -288.456471) (xy 138.192073 -288.497157)
			(xy 138.215724 -288.54222) (xy 138.23184 -288.590494) (xy 138.240004 -288.640728) (xy 138.240516 -288.666174)
			(xy 138.559044 -288.666174) (xy 138.563004 -288.61712) (xy 138.574781 -288.569336) (xy 138.594072 -288.52406)
			(xy 138.620375 -288.482464) (xy 138.65301 -288.445627) (xy 138.691131 -288.414502) (xy 138.733752 -288.389895)
			(xy 138.779768 -288.372443) (xy 138.827987 -288.362599) (xy 138.877162 -288.360618) (xy 138.926017 -288.36655)
			(xy 138.973288 -288.380242) (xy 139.01775 -288.40134) (xy 139.058253 -288.429296) (xy 139.093746 -288.463388)
			(xy 139.123311 -288.502732) (xy 139.146182 -288.546309) (xy 139.161766 -288.59299) (xy 139.169661 -288.641567)
			(xy 139.170156 -288.666174) (xy 139.488413 -288.666174) (xy 139.492508 -288.615446) (xy 139.504687 -288.566032)
			(xy 139.524635 -288.519212) (xy 139.551836 -288.476198) (xy 139.585584 -288.438104) (xy 139.625006 -288.405917)
			(xy 139.66908 -288.380471) (xy 139.716666 -288.362424) (xy 139.76653 -288.352244) (xy 139.817382 -288.350195)
			(xy 139.867903 -288.356329) (xy 139.916787 -288.370489) (xy 139.962766 -288.392306) (xy 140.00465 -288.421216)
			(xy 140.041354 -288.456471) (xy 140.071927 -288.497157) (xy 140.095578 -288.54222) (xy 140.111694 -288.590494)
			(xy 140.119858 -288.640728) (xy 140.12037 -288.666174) (xy 140.438898 -288.666174) (xy 140.442858 -288.61712)
			(xy 140.454635 -288.569336) (xy 140.473926 -288.52406) (xy 140.500229 -288.482464) (xy 140.532864 -288.445627)
			(xy 140.570985 -288.414502) (xy 140.613606 -288.389895) (xy 140.659622 -288.372443) (xy 140.707841 -288.362599)
			(xy 140.757016 -288.360618) (xy 140.805871 -288.36655) (xy 140.853142 -288.380242) (xy 140.897604 -288.40134)
			(xy 140.938107 -288.429296) (xy 140.9736 -288.463388) (xy 141.003165 -288.502732) (xy 141.026036 -288.546309)
			(xy 141.04162 -288.59299) (xy 141.049515 -288.641567) (xy 141.05001 -288.666174) (xy 141.368521 -288.666174)
			(xy 141.372616 -288.615446) (xy 141.384795 -288.566032) (xy 141.404743 -288.519212) (xy 141.431944 -288.476198)
			(xy 141.465692 -288.438104) (xy 141.505114 -288.405917) (xy 141.549188 -288.380471) (xy 141.596774 -288.362424)
			(xy 141.646638 -288.352244) (xy 141.69749 -288.350195) (xy 141.748011 -288.356329) (xy 141.796895 -288.370489)
			(xy 141.842874 -288.392306) (xy 141.884758 -288.421216) (xy 141.921462 -288.456471) (xy 141.952035 -288.497157)
			(xy 141.975686 -288.54222) (xy 141.991802 -288.590494) (xy 141.999966 -288.640728) (xy 142.000478 -288.666174)
			(xy 142.308575 -288.666174) (xy 142.31267 -288.615446) (xy 142.324849 -288.566032) (xy 142.344797 -288.519212)
			(xy 142.371998 -288.476198) (xy 142.405746 -288.438104) (xy 142.445168 -288.405917) (xy 142.489242 -288.380471)
			(xy 142.536828 -288.362424) (xy 142.586692 -288.352244) (xy 142.637544 -288.350195) (xy 142.688065 -288.356329)
			(xy 142.736949 -288.370489) (xy 142.782928 -288.392306) (xy 142.824812 -288.421216) (xy 142.861516 -288.456471)
			(xy 142.892089 -288.497157) (xy 142.91574 -288.54222) (xy 142.931856 -288.590494) (xy 142.94002 -288.640728)
			(xy 142.940532 -288.666174) (xy 143.258806 -288.666174) (xy 143.262766 -288.61712) (xy 143.274543 -288.569336)
			(xy 143.293834 -288.52406) (xy 143.320137 -288.482464) (xy 143.352772 -288.445627) (xy 143.390893 -288.414502)
			(xy 143.433514 -288.389895) (xy 143.47953 -288.372443) (xy 143.527749 -288.362599) (xy 143.576924 -288.360618)
			(xy 143.625779 -288.36655) (xy 143.67305 -288.380242) (xy 143.717512 -288.40134) (xy 143.758015 -288.429296)
			(xy 143.793508 -288.463388) (xy 143.823073 -288.502732) (xy 143.845944 -288.546309) (xy 143.861528 -288.59299)
			(xy 143.869423 -288.641567) (xy 143.869918 -288.666174) (xy 145.138914 -288.666174) (xy 145.142874 -288.61712)
			(xy 145.154651 -288.569336) (xy 145.173942 -288.52406) (xy 145.200245 -288.482464) (xy 145.23288 -288.445627)
			(xy 145.271001 -288.414502) (xy 145.313622 -288.389895) (xy 145.359638 -288.372443) (xy 145.407857 -288.362599)
			(xy 145.457032 -288.360618) (xy 145.505887 -288.36655) (xy 145.553158 -288.380242) (xy 145.59762 -288.40134)
			(xy 145.638123 -288.429296) (xy 145.673616 -288.463388) (xy 145.703181 -288.502732) (xy 145.726052 -288.546309)
			(xy 145.741636 -288.59299) (xy 145.749531 -288.641567) (xy 145.750026 -288.666174) (xy 145.749531 -288.690781)
			(xy 145.741636 -288.739358) (xy 145.726052 -288.786039) (xy 145.703181 -288.829616) (xy 145.673616 -288.86896)
			(xy 145.638123 -288.903052) (xy 145.59762 -288.931008) (xy 145.553158 -288.952106) (xy 145.505887 -288.965798)
			(xy 145.457032 -288.97173) (xy 145.407857 -288.969749) (xy 145.359638 -288.959905) (xy 145.313622 -288.942453)
			(xy 145.271001 -288.917846) (xy 145.23288 -288.886721) (xy 145.200245 -288.849884) (xy 145.173942 -288.808288)
			(xy 145.154651 -288.763012) (xy 145.142874 -288.715228) (xy 145.138914 -288.666174) (xy 143.869918 -288.666174)
			(xy 143.869423 -288.690781) (xy 143.861528 -288.739358) (xy 143.845944 -288.786039) (xy 143.823073 -288.829616)
			(xy 143.793508 -288.86896) (xy 143.758015 -288.903052) (xy 143.717512 -288.931008) (xy 143.67305 -288.952106)
			(xy 143.625779 -288.965798) (xy 143.576924 -288.97173) (xy 143.527749 -288.969749) (xy 143.47953 -288.959905)
			(xy 143.433514 -288.942453) (xy 143.390893 -288.917846) (xy 143.352772 -288.886721) (xy 143.320137 -288.849884)
			(xy 143.293834 -288.808288) (xy 143.274543 -288.763012) (xy 143.262766 -288.715228) (xy 143.258806 -288.666174)
			(xy 142.940532 -288.666174) (xy 142.94002 -288.69162) (xy 142.931856 -288.741854) (xy 142.91574 -288.790128)
			(xy 142.892089 -288.835191) (xy 142.861516 -288.875877) (xy 142.824812 -288.911132) (xy 142.782928 -288.940042)
			(xy 142.736949 -288.961859) (xy 142.688065 -288.976019) (xy 142.637544 -288.982153) (xy 142.586692 -288.980104)
			(xy 142.536828 -288.969924) (xy 142.489242 -288.951877) (xy 142.445168 -288.926431) (xy 142.405746 -288.894244)
			(xy 142.371998 -288.85615) (xy 142.344797 -288.813136) (xy 142.324849 -288.766316) (xy 142.31267 -288.716902)
			(xy 142.308575 -288.666174) (xy 142.000478 -288.666174) (xy 141.999966 -288.69162) (xy 141.991802 -288.741854)
			(xy 141.975686 -288.790128) (xy 141.952035 -288.835191) (xy 141.921462 -288.875877) (xy 141.884758 -288.911132)
			(xy 141.842874 -288.940042) (xy 141.796895 -288.961859) (xy 141.748011 -288.976019) (xy 141.69749 -288.982153)
			(xy 141.646638 -288.980104) (xy 141.596774 -288.969924) (xy 141.549188 -288.951877) (xy 141.505114 -288.926431)
			(xy 141.465692 -288.894244) (xy 141.431944 -288.85615) (xy 141.404743 -288.813136) (xy 141.384795 -288.766316)
			(xy 141.372616 -288.716902) (xy 141.368521 -288.666174) (xy 141.05001 -288.666174) (xy 141.049515 -288.690781)
			(xy 141.04162 -288.739358) (xy 141.026036 -288.786039) (xy 141.003165 -288.829616) (xy 140.9736 -288.86896)
			(xy 140.938107 -288.903052) (xy 140.897604 -288.931008) (xy 140.853142 -288.952106) (xy 140.805871 -288.965798)
			(xy 140.757016 -288.97173) (xy 140.707841 -288.969749) (xy 140.659622 -288.959905) (xy 140.613606 -288.942453)
			(xy 140.570985 -288.917846) (xy 140.532864 -288.886721) (xy 140.500229 -288.849884) (xy 140.473926 -288.808288)
			(xy 140.454635 -288.763012) (xy 140.442858 -288.715228) (xy 140.438898 -288.666174) (xy 140.12037 -288.666174)
			(xy 140.119858 -288.69162) (xy 140.111694 -288.741854) (xy 140.095578 -288.790128) (xy 140.071927 -288.835191)
			(xy 140.041354 -288.875877) (xy 140.00465 -288.911132) (xy 139.962766 -288.940042) (xy 139.916787 -288.961859)
			(xy 139.867903 -288.976019) (xy 139.817382 -288.982153) (xy 139.76653 -288.980104) (xy 139.716666 -288.969924)
			(xy 139.66908 -288.951877) (xy 139.625006 -288.926431) (xy 139.585584 -288.894244) (xy 139.551836 -288.85615)
			(xy 139.524635 -288.813136) (xy 139.504687 -288.766316) (xy 139.492508 -288.716902) (xy 139.488413 -288.666174)
			(xy 139.170156 -288.666174) (xy 139.169661 -288.690781) (xy 139.161766 -288.739358) (xy 139.146182 -288.786039)
			(xy 139.123311 -288.829616) (xy 139.093746 -288.86896) (xy 139.058253 -288.903052) (xy 139.01775 -288.931008)
			(xy 138.973288 -288.952106) (xy 138.926017 -288.965798) (xy 138.877162 -288.97173) (xy 138.827987 -288.969749)
			(xy 138.779768 -288.959905) (xy 138.733752 -288.942453) (xy 138.691131 -288.917846) (xy 138.65301 -288.886721)
			(xy 138.620375 -288.849884) (xy 138.594072 -288.808288) (xy 138.574781 -288.763012) (xy 138.563004 -288.715228)
			(xy 138.559044 -288.666174) (xy 138.240516 -288.666174) (xy 138.240004 -288.69162) (xy 138.23184 -288.741854)
			(xy 138.215724 -288.790128) (xy 138.192073 -288.835191) (xy 138.1615 -288.875877) (xy 138.124796 -288.911132)
			(xy 138.082912 -288.940042) (xy 138.036933 -288.961859) (xy 137.988049 -288.976019) (xy 137.937528 -288.982153)
			(xy 137.886676 -288.980104) (xy 137.836812 -288.969924) (xy 137.789226 -288.951877) (xy 137.745152 -288.926431)
			(xy 137.70573 -288.894244) (xy 137.671982 -288.85615) (xy 137.644781 -288.813136) (xy 137.624833 -288.766316)
			(xy 137.612654 -288.716902) (xy 137.608559 -288.666174) (xy 137.290048 -288.666174) (xy 137.289553 -288.690781)
			(xy 137.281658 -288.739358) (xy 137.266074 -288.786039) (xy 137.243203 -288.829616) (xy 137.213638 -288.86896)
			(xy 137.178145 -288.903052) (xy 137.137642 -288.931008) (xy 137.09318 -288.952106) (xy 137.045909 -288.965798)
			(xy 136.997054 -288.97173) (xy 136.947879 -288.969749) (xy 136.89966 -288.959905) (xy 136.853644 -288.942453)
			(xy 136.811023 -288.917846) (xy 136.772902 -288.886721) (xy 136.740267 -288.849884) (xy 136.713964 -288.808288)
			(xy 136.694673 -288.763012) (xy 136.682896 -288.715228) (xy 136.678936 -288.666174) (xy 136.360408 -288.666174)
			(xy 136.359896 -288.69162) (xy 136.351732 -288.741854) (xy 136.335616 -288.790128) (xy 136.311965 -288.835191)
			(xy 136.281392 -288.875877) (xy 136.244688 -288.911132) (xy 136.202804 -288.940042) (xy 136.156825 -288.961859)
			(xy 136.107941 -288.976019) (xy 136.05742 -288.982153) (xy 136.006568 -288.980104) (xy 135.956704 -288.969924)
			(xy 135.909118 -288.951877) (xy 135.865044 -288.926431) (xy 135.825622 -288.894244) (xy 135.791874 -288.85615)
			(xy 135.764673 -288.813136) (xy 135.744725 -288.766316) (xy 135.732546 -288.716902) (xy 135.728451 -288.666174)
			(xy 135.420354 -288.666174) (xy 135.419842 -288.69162) (xy 135.411678 -288.741854) (xy 135.395562 -288.790128)
			(xy 135.371911 -288.835191) (xy 135.341338 -288.875877) (xy 135.304634 -288.911132) (xy 135.26275 -288.940042)
			(xy 135.216771 -288.961859) (xy 135.167887 -288.976019) (xy 135.117366 -288.982153) (xy 135.066514 -288.980104)
			(xy 135.01665 -288.969924) (xy 134.969064 -288.951877) (xy 134.92499 -288.926431) (xy 134.885568 -288.894244)
			(xy 134.85182 -288.85615) (xy 134.824619 -288.813136) (xy 134.804671 -288.766316) (xy 134.792492 -288.716902)
			(xy 134.788397 -288.666174) (xy 134.47014 -288.666174) (xy 134.469645 -288.690781) (xy 134.46175 -288.739358)
			(xy 134.446166 -288.786039) (xy 134.423295 -288.829616) (xy 134.39373 -288.86896) (xy 134.358237 -288.903052)
			(xy 134.317734 -288.931008) (xy 134.273272 -288.952106) (xy 134.226001 -288.965798) (xy 134.177146 -288.97173)
			(xy 134.127971 -288.969749) (xy 134.079752 -288.959905) (xy 134.033736 -288.942453) (xy 133.991115 -288.917846)
			(xy 133.952994 -288.886721) (xy 133.920359 -288.849884) (xy 133.894056 -288.808288) (xy 133.874765 -288.763012)
			(xy 133.862988 -288.715228) (xy 133.859028 -288.666174) (xy 133.5405 -288.666174) (xy 133.539988 -288.69162)
			(xy 133.531824 -288.741854) (xy 133.515708 -288.790128) (xy 133.492057 -288.835191) (xy 133.461484 -288.875877)
			(xy 133.42478 -288.911132) (xy 133.382896 -288.940042) (xy 133.336917 -288.961859) (xy 133.288033 -288.976019)
			(xy 133.237512 -288.982153) (xy 133.18666 -288.980104) (xy 133.136796 -288.969924) (xy 133.08921 -288.951877)
			(xy 133.045136 -288.926431) (xy 133.005714 -288.894244) (xy 132.971966 -288.85615) (xy 132.944765 -288.813136)
			(xy 132.924817 -288.766316) (xy 132.912638 -288.716902) (xy 132.908543 -288.666174) (xy 132.590032 -288.666174)
			(xy 132.589537 -288.690781) (xy 132.581642 -288.739358) (xy 132.566058 -288.786039) (xy 132.543187 -288.829616)
			(xy 132.513622 -288.86896) (xy 132.478129 -288.903052) (xy 132.437626 -288.931008) (xy 132.393164 -288.952106)
			(xy 132.345893 -288.965798) (xy 132.297038 -288.97173) (xy 132.247863 -288.969749) (xy 132.199644 -288.959905)
			(xy 132.153628 -288.942453) (xy 132.111007 -288.917846) (xy 132.072886 -288.886721) (xy 132.040251 -288.849884)
			(xy 132.013948 -288.808288) (xy 131.994657 -288.763012) (xy 131.98288 -288.715228) (xy 131.97892 -288.666174)
			(xy 131.660392 -288.666174) (xy 131.65988 -288.69162) (xy 131.651716 -288.741854) (xy 131.6356 -288.790128)
			(xy 131.611949 -288.835191) (xy 131.581376 -288.875877) (xy 131.544672 -288.911132) (xy 131.502788 -288.940042)
			(xy 131.456809 -288.961859) (xy 131.407925 -288.976019) (xy 131.357404 -288.982153) (xy 131.306552 -288.980104)
			(xy 131.256688 -288.969924) (xy 131.209102 -288.951877) (xy 131.165028 -288.926431) (xy 131.125606 -288.894244)
			(xy 131.091858 -288.85615) (xy 131.064657 -288.813136) (xy 131.044709 -288.766316) (xy 131.03253 -288.716902)
			(xy 131.028435 -288.666174) (xy 130.710178 -288.666174) (xy 130.709683 -288.690781) (xy 130.701788 -288.739358)
			(xy 130.686204 -288.786039) (xy 130.663333 -288.829616) (xy 130.633768 -288.86896) (xy 130.598275 -288.903052)
			(xy 130.557772 -288.931008) (xy 130.51331 -288.952106) (xy 130.466039 -288.965798) (xy 130.417184 -288.97173)
			(xy 130.368009 -288.969749) (xy 130.31979 -288.959905) (xy 130.273774 -288.942453) (xy 130.231153 -288.917846)
			(xy 130.193032 -288.886721) (xy 130.160397 -288.849884) (xy 130.134094 -288.808288) (xy 130.114803 -288.763012)
			(xy 130.103026 -288.715228) (xy 130.099066 -288.666174) (xy 129.780538 -288.666174) (xy 129.780026 -288.69162)
			(xy 129.771862 -288.741854) (xy 129.755746 -288.790128) (xy 129.732095 -288.835191) (xy 129.701522 -288.875877)
			(xy 129.664818 -288.911132) (xy 129.622934 -288.940042) (xy 129.576955 -288.961859) (xy 129.528071 -288.976019)
			(xy 129.47755 -288.982153) (xy 129.426698 -288.980104) (xy 129.376834 -288.969924) (xy 129.329248 -288.951877)
			(xy 129.285174 -288.926431) (xy 129.245752 -288.894244) (xy 129.212004 -288.85615) (xy 129.184803 -288.813136)
			(xy 129.164855 -288.766316) (xy 129.152676 -288.716902) (xy 129.148581 -288.666174) (xy 128.840484 -288.666174)
			(xy 128.839972 -288.69162) (xy 128.831808 -288.741854) (xy 128.815692 -288.790128) (xy 128.792041 -288.835191)
			(xy 128.761468 -288.875877) (xy 128.724764 -288.911132) (xy 128.68288 -288.940042) (xy 128.636901 -288.961859)
			(xy 128.588017 -288.976019) (xy 128.537496 -288.982153) (xy 128.486644 -288.980104) (xy 128.43678 -288.969924)
			(xy 128.389194 -288.951877) (xy 128.34512 -288.926431) (xy 128.305698 -288.894244) (xy 128.27195 -288.85615)
			(xy 128.244749 -288.813136) (xy 128.224801 -288.766316) (xy 128.212622 -288.716902) (xy 128.208527 -288.666174)
			(xy 127.20574 -288.666174) (xy 127.20574 -288.990278) (xy 127.206209 -289.000152) (xy 127.213661 -289.01844)
			(xy 127.220218 -289.025838) (xy 127.220472 -289.026092) (xy 127.59817 -289.40379) (xy 127.60071 -289.40633)
			(xy 127.600964 -289.40633) (xy 127.610324 -289.413727) (xy 127.633388 -289.419693) (xy 127.64516 -289.41776)
			(xy 127.734314 -289.398202) (xy 127.753618 -289.381184) (xy 127.75819 -289.368738) (xy 127.766839 -289.346202)
			(xy 127.789996 -289.303851) (xy 127.819338 -289.265524) (xy 127.854177 -289.232116) (xy 127.8937 -289.204408)
			(xy 127.936985 -289.183046) (xy 127.983019 -289.16853) (xy 128.030727 -289.161199) (xy 128.054862 -289.160712)
			(xy 128.07966 -289.161195) (xy 128.128646 -289.168945) (xy 128.175818 -289.184259) (xy 128.220015 -289.206762)
			(xy 128.260149 -289.2359) (xy 128.295232 -289.270955) (xy 128.324403 -289.311065) (xy 128.346942 -289.355243)
			(xy 128.362295 -289.402403) (xy 128.370085 -289.451383) (xy 128.370584 -289.47618) (xy 128.688858 -289.47618)
			(xy 128.692818 -289.427126) (xy 128.704595 -289.379342) (xy 128.723886 -289.334066) (xy 128.750189 -289.29247)
			(xy 128.782824 -289.255633) (xy 128.820945 -289.224508) (xy 128.863566 -289.199901) (xy 128.909582 -289.182449)
			(xy 128.957801 -289.172605) (xy 129.006976 -289.170624) (xy 129.055831 -289.176556) (xy 129.103102 -289.190248)
			(xy 129.147564 -289.211346) (xy 129.188067 -289.239302) (xy 129.22356 -289.273394) (xy 129.253125 -289.312738)
			(xy 129.275996 -289.356315) (xy 129.29158 -289.402996) (xy 129.299475 -289.451573) (xy 129.29997 -289.47618)
			(xy 129.618481 -289.47618) (xy 129.622576 -289.425452) (xy 129.634755 -289.376038) (xy 129.654703 -289.329218)
			(xy 129.681904 -289.286204) (xy 129.715652 -289.24811) (xy 129.755074 -289.215923) (xy 129.799148 -289.190477)
			(xy 129.846734 -289.17243) (xy 129.896598 -289.16225) (xy 129.94745 -289.160201) (xy 129.997971 -289.166335)
			(xy 130.046855 -289.180495) (xy 130.092834 -289.202312) (xy 130.134718 -289.231222) (xy 130.171422 -289.266477)
			(xy 130.201995 -289.307163) (xy 130.225646 -289.352226) (xy 130.241762 -289.4005) (xy 130.249926 -289.450734)
			(xy 130.250438 -289.47618) (xy 130.568966 -289.47618) (xy 130.572926 -289.427126) (xy 130.584703 -289.379342)
			(xy 130.603994 -289.334066) (xy 130.630297 -289.29247) (xy 130.662932 -289.255633) (xy 130.701053 -289.224508)
			(xy 130.743674 -289.199901) (xy 130.78969 -289.182449) (xy 130.837909 -289.172605) (xy 130.887084 -289.170624)
			(xy 130.935939 -289.176556) (xy 130.98321 -289.190248) (xy 131.027672 -289.211346) (xy 131.068175 -289.239302)
			(xy 131.103668 -289.273394) (xy 131.133233 -289.312738) (xy 131.156104 -289.356315) (xy 131.171688 -289.402996)
			(xy 131.179583 -289.451573) (xy 131.180078 -289.47618) (xy 131.498589 -289.47618) (xy 131.502684 -289.425452)
			(xy 131.514863 -289.376038) (xy 131.534811 -289.329218) (xy 131.562012 -289.286204) (xy 131.59576 -289.24811)
			(xy 131.635182 -289.215923) (xy 131.679256 -289.190477) (xy 131.726842 -289.17243) (xy 131.776706 -289.16225)
			(xy 131.827558 -289.160201) (xy 131.878079 -289.166335) (xy 131.926963 -289.180495) (xy 131.972942 -289.202312)
			(xy 132.014826 -289.231222) (xy 132.05153 -289.266477) (xy 132.082103 -289.307163) (xy 132.105754 -289.352226)
			(xy 132.12187 -289.4005) (xy 132.130034 -289.450734) (xy 132.130546 -289.47618) (xy 132.438643 -289.47618)
			(xy 132.442738 -289.425452) (xy 132.454917 -289.376038) (xy 132.474865 -289.329218) (xy 132.502066 -289.286204)
			(xy 132.535814 -289.24811) (xy 132.575236 -289.215923) (xy 132.61931 -289.190477) (xy 132.666896 -289.17243)
			(xy 132.71676 -289.16225) (xy 132.767612 -289.160201) (xy 132.818133 -289.166335) (xy 132.867017 -289.180495)
			(xy 132.912996 -289.202312) (xy 132.95488 -289.231222) (xy 132.991584 -289.266477) (xy 133.022157 -289.307163)
			(xy 133.045808 -289.352226) (xy 133.061924 -289.4005) (xy 133.070088 -289.450734) (xy 133.0706 -289.47618)
			(xy 133.388874 -289.47618) (xy 133.392834 -289.427126) (xy 133.404611 -289.379342) (xy 133.423902 -289.334066)
			(xy 133.450205 -289.29247) (xy 133.48284 -289.255633) (xy 133.520961 -289.224508) (xy 133.563582 -289.199901)
			(xy 133.609598 -289.182449) (xy 133.657817 -289.172605) (xy 133.706992 -289.170624) (xy 133.755847 -289.176556)
			(xy 133.803118 -289.190248) (xy 133.84758 -289.211346) (xy 133.888083 -289.239302) (xy 133.923576 -289.273394)
			(xy 133.953141 -289.312738) (xy 133.976012 -289.356315) (xy 133.991596 -289.402996) (xy 133.999491 -289.451573)
			(xy 133.999986 -289.47618) (xy 134.318497 -289.47618) (xy 134.322592 -289.425452) (xy 134.334771 -289.376038)
			(xy 134.354719 -289.329218) (xy 134.38192 -289.286204) (xy 134.415668 -289.24811) (xy 134.45509 -289.215923)
			(xy 134.499164 -289.190477) (xy 134.54675 -289.17243) (xy 134.596614 -289.16225) (xy 134.647466 -289.160201)
			(xy 134.697987 -289.166335) (xy 134.746871 -289.180495) (xy 134.79285 -289.202312) (xy 134.834734 -289.231222)
			(xy 134.871438 -289.266477) (xy 134.902011 -289.307163) (xy 134.925662 -289.352226) (xy 134.941778 -289.4005)
			(xy 134.949942 -289.450734) (xy 134.950454 -289.47618) (xy 135.268982 -289.47618) (xy 135.272942 -289.427126)
			(xy 135.284719 -289.379342) (xy 135.30401 -289.334066) (xy 135.330313 -289.29247) (xy 135.362948 -289.255633)
			(xy 135.401069 -289.224508) (xy 135.44369 -289.199901) (xy 135.489706 -289.182449) (xy 135.537925 -289.172605)
			(xy 135.5871 -289.170624) (xy 135.635955 -289.176556) (xy 135.683226 -289.190248) (xy 135.727688 -289.211346)
			(xy 135.768191 -289.239302) (xy 135.803684 -289.273394) (xy 135.833249 -289.312738) (xy 135.85612 -289.356315)
			(xy 135.871704 -289.402996) (xy 135.879599 -289.451573) (xy 135.880094 -289.47618) (xy 136.198605 -289.47618)
			(xy 136.2027 -289.425452) (xy 136.214879 -289.376038) (xy 136.234827 -289.329218) (xy 136.262028 -289.286204)
			(xy 136.295776 -289.24811) (xy 136.335198 -289.215923) (xy 136.379272 -289.190477) (xy 136.426858 -289.17243)
			(xy 136.476722 -289.16225) (xy 136.527574 -289.160201) (xy 136.578095 -289.166335) (xy 136.626979 -289.180495)
			(xy 136.672958 -289.202312) (xy 136.714842 -289.231222) (xy 136.751546 -289.266477) (xy 136.782119 -289.307163)
			(xy 136.80577 -289.352226) (xy 136.821886 -289.4005) (xy 136.83005 -289.450734) (xy 136.830562 -289.47618)
			(xy 137.148836 -289.47618) (xy 137.152796 -289.427126) (xy 137.164573 -289.379342) (xy 137.183864 -289.334066)
			(xy 137.210167 -289.29247) (xy 137.242802 -289.255633) (xy 137.280923 -289.224508) (xy 137.323544 -289.199901)
			(xy 137.36956 -289.182449) (xy 137.417779 -289.172605) (xy 137.466954 -289.170624) (xy 137.515809 -289.176556)
			(xy 137.56308 -289.190248) (xy 137.607542 -289.211346) (xy 137.648045 -289.239302) (xy 137.683538 -289.273394)
			(xy 137.713103 -289.312738) (xy 137.735974 -289.356315) (xy 137.751558 -289.402996) (xy 137.759453 -289.451573)
			(xy 137.759948 -289.47618) (xy 138.078459 -289.47618) (xy 138.082554 -289.425452) (xy 138.094733 -289.376038)
			(xy 138.114681 -289.329218) (xy 138.141882 -289.286204) (xy 138.17563 -289.24811) (xy 138.215052 -289.215923)
			(xy 138.259126 -289.190477) (xy 138.306712 -289.17243) (xy 138.356576 -289.16225) (xy 138.407428 -289.160201)
			(xy 138.457949 -289.166335) (xy 138.506833 -289.180495) (xy 138.552812 -289.202312) (xy 138.594696 -289.231222)
			(xy 138.6314 -289.266477) (xy 138.661973 -289.307163) (xy 138.685624 -289.352226) (xy 138.70174 -289.4005)
			(xy 138.709904 -289.450734) (xy 138.710416 -289.47618) (xy 139.018513 -289.47618) (xy 139.022608 -289.425452)
			(xy 139.034787 -289.376038) (xy 139.054735 -289.329218) (xy 139.081936 -289.286204) (xy 139.115684 -289.24811)
			(xy 139.155106 -289.215923) (xy 139.19918 -289.190477) (xy 139.246766 -289.17243) (xy 139.29663 -289.16225)
			(xy 139.347482 -289.160201) (xy 139.398003 -289.166335) (xy 139.446887 -289.180495) (xy 139.492866 -289.202312)
			(xy 139.53475 -289.231222) (xy 139.571454 -289.266477) (xy 139.602027 -289.307163) (xy 139.625678 -289.352226)
			(xy 139.641794 -289.4005) (xy 139.649958 -289.450734) (xy 139.65047 -289.47618) (xy 139.968998 -289.47618)
			(xy 139.972958 -289.427126) (xy 139.984735 -289.379342) (xy 140.004026 -289.334066) (xy 140.030329 -289.29247)
			(xy 140.062964 -289.255633) (xy 140.101085 -289.224508) (xy 140.143706 -289.199901) (xy 140.189722 -289.182449)
			(xy 140.237941 -289.172605) (xy 140.287116 -289.170624) (xy 140.335971 -289.176556) (xy 140.383242 -289.190248)
			(xy 140.427704 -289.211346) (xy 140.468207 -289.239302) (xy 140.5037 -289.273394) (xy 140.533265 -289.312738)
			(xy 140.556136 -289.356315) (xy 140.57172 -289.402996) (xy 140.579615 -289.451573) (xy 140.58011 -289.47618)
			(xy 140.898621 -289.47618) (xy 140.902716 -289.425452) (xy 140.914895 -289.376038) (xy 140.934843 -289.329218)
			(xy 140.962044 -289.286204) (xy 140.995792 -289.24811) (xy 141.035214 -289.215923) (xy 141.079288 -289.190477)
			(xy 141.126874 -289.17243) (xy 141.176738 -289.16225) (xy 141.22759 -289.160201) (xy 141.278111 -289.166335)
			(xy 141.326995 -289.180495) (xy 141.372974 -289.202312) (xy 141.414858 -289.231222) (xy 141.451562 -289.266477)
			(xy 141.482135 -289.307163) (xy 141.505786 -289.352226) (xy 141.521902 -289.4005) (xy 141.530066 -289.450734)
			(xy 141.530578 -289.47618) (xy 141.848852 -289.47618) (xy 141.852812 -289.427126) (xy 141.864589 -289.379342)
			(xy 141.88388 -289.334066) (xy 141.910183 -289.29247) (xy 141.942818 -289.255633) (xy 141.980939 -289.224508)
			(xy 142.02356 -289.199901) (xy 142.069576 -289.182449) (xy 142.117795 -289.172605) (xy 142.16697 -289.170624)
			(xy 142.215825 -289.176556) (xy 142.263096 -289.190248) (xy 142.307558 -289.211346) (xy 142.348061 -289.239302)
			(xy 142.383554 -289.273394) (xy 142.413119 -289.312738) (xy 142.43599 -289.356315) (xy 142.451574 -289.402996)
			(xy 142.459469 -289.451573) (xy 142.459964 -289.47618) (xy 142.778475 -289.47618) (xy 142.78257 -289.425452)
			(xy 142.794749 -289.376038) (xy 142.814697 -289.329218) (xy 142.841898 -289.286204) (xy 142.875646 -289.24811)
			(xy 142.915068 -289.215923) (xy 142.959142 -289.190477) (xy 143.006728 -289.17243) (xy 143.056592 -289.16225)
			(xy 143.107444 -289.160201) (xy 143.157965 -289.166335) (xy 143.206849 -289.180495) (xy 143.252828 -289.202312)
			(xy 143.294712 -289.231222) (xy 143.331416 -289.266477) (xy 143.361989 -289.307163) (xy 143.38564 -289.352226)
			(xy 143.401756 -289.4005) (xy 143.40992 -289.450734) (xy 143.410432 -289.47618) (xy 143.72896 -289.47618)
			(xy 143.73292 -289.427126) (xy 143.744697 -289.379342) (xy 143.763988 -289.334066) (xy 143.790291 -289.29247)
			(xy 143.822926 -289.255633) (xy 143.861047 -289.224508) (xy 143.903668 -289.199901) (xy 143.949684 -289.182449)
			(xy 143.997903 -289.172605) (xy 144.047078 -289.170624) (xy 144.095933 -289.176556) (xy 144.143204 -289.190248)
			(xy 144.185339 -289.210242) (xy 146.737082 -289.210242) (xy 146.741042 -289.161188) (xy 146.752819 -289.113404)
			(xy 146.77211 -289.068128) (xy 146.798413 -289.026532) (xy 146.831048 -288.989695) (xy 146.869169 -288.95857)
			(xy 146.91179 -288.933963) (xy 146.957806 -288.916511) (xy 147.006025 -288.906667) (xy 147.0552 -288.904686)
			(xy 147.104055 -288.910618) (xy 147.151326 -288.92431) (xy 147.195788 -288.945408) (xy 147.236291 -288.973364)
			(xy 147.271784 -289.007456) (xy 147.301349 -289.0468) (xy 147.32422 -289.090377) (xy 147.339221 -289.135312)
			(xy 164.058615 -289.135312) (xy 164.06255 -289.081541) (xy 164.074273 -289.028917) (xy 164.093533 -288.97856)
			(xy 164.119919 -288.931543) (xy 164.152871 -288.88887) (xy 164.191684 -288.851449) (xy 164.235532 -288.820079)
			(xy 164.28348 -288.795427) (xy 164.334507 -288.778019) (xy 164.387525 -288.768226) (xy 164.441404 -288.766257)
			(xy 164.494995 -288.772154) (xy 164.547156 -288.78579) (xy 164.596776 -288.806877) (xy 164.642797 -288.834963)
			(xy 164.684239 -288.869451) (xy 164.720217 -288.909605) (xy 164.749965 -288.954569) (xy 164.77285 -289.003386)
			(xy 164.788382 -289.055015) (xy 164.796232 -289.108355) (xy 164.796724 -289.135312) (xy 164.796232 -289.162269)
			(xy 164.788382 -289.215609) (xy 164.77285 -289.267238) (xy 164.749965 -289.316055) (xy 164.720217 -289.361019)
			(xy 164.684239 -289.401173) (xy 164.642797 -289.435661) (xy 164.596776 -289.463747) (xy 164.547156 -289.484834)
			(xy 164.494995 -289.49847) (xy 164.441404 -289.504367) (xy 164.387525 -289.502398) (xy 164.334507 -289.492605)
			(xy 164.28348 -289.475197) (xy 164.235532 -289.450545) (xy 164.191684 -289.419175) (xy 164.152871 -289.381754)
			(xy 164.119919 -289.339081) (xy 164.093533 -289.292064) (xy 164.074273 -289.241707) (xy 164.06255 -289.189083)
			(xy 164.058615 -289.135312) (xy 147.339221 -289.135312) (xy 147.339804 -289.137058) (xy 147.347699 -289.185635)
			(xy 147.348194 -289.210242) (xy 147.347699 -289.234849) (xy 147.339804 -289.283426) (xy 147.32422 -289.330107)
			(xy 147.301349 -289.373684) (xy 147.271784 -289.413028) (xy 147.236291 -289.44712) (xy 147.195788 -289.475076)
			(xy 147.151326 -289.496174) (xy 147.104055 -289.509866) (xy 147.0552 -289.515798) (xy 147.006025 -289.513817)
			(xy 146.957806 -289.503973) (xy 146.91179 -289.486521) (xy 146.869169 -289.461914) (xy 146.831048 -289.430789)
			(xy 146.798413 -289.393952) (xy 146.77211 -289.352356) (xy 146.752819 -289.30708) (xy 146.741042 -289.259296)
			(xy 146.737082 -289.210242) (xy 144.185339 -289.210242) (xy 144.187666 -289.211346) (xy 144.228169 -289.239302)
			(xy 144.263662 -289.273394) (xy 144.293227 -289.312738) (xy 144.316098 -289.356315) (xy 144.331682 -289.402996)
			(xy 144.339577 -289.451573) (xy 144.340072 -289.47618) (xy 144.339577 -289.500787) (xy 144.331682 -289.549364)
			(xy 144.316098 -289.596045) (xy 144.293227 -289.639622) (xy 144.263662 -289.678966) (xy 144.228169 -289.713058)
			(xy 144.187666 -289.741014) (xy 144.143204 -289.762112) (xy 144.095933 -289.775804) (xy 144.047078 -289.781736)
			(xy 143.997903 -289.779755) (xy 143.949684 -289.769911) (xy 143.903668 -289.752459) (xy 143.861047 -289.727852)
			(xy 143.822926 -289.696727) (xy 143.790291 -289.65989) (xy 143.763988 -289.618294) (xy 143.744697 -289.573018)
			(xy 143.73292 -289.525234) (xy 143.72896 -289.47618) (xy 143.410432 -289.47618) (xy 143.40992 -289.501626)
			(xy 143.401756 -289.55186) (xy 143.38564 -289.600134) (xy 143.361989 -289.645197) (xy 143.331416 -289.685883)
			(xy 143.294712 -289.721138) (xy 143.252828 -289.750048) (xy 143.206849 -289.771865) (xy 143.157965 -289.786025)
			(xy 143.107444 -289.792159) (xy 143.056592 -289.79011) (xy 143.006728 -289.77993) (xy 142.959142 -289.761883)
			(xy 142.915068 -289.736437) (xy 142.875646 -289.70425) (xy 142.841898 -289.666156) (xy 142.814697 -289.623142)
			(xy 142.794749 -289.576322) (xy 142.78257 -289.526908) (xy 142.778475 -289.47618) (xy 142.459964 -289.47618)
			(xy 142.459469 -289.500787) (xy 142.451574 -289.549364) (xy 142.43599 -289.596045) (xy 142.413119 -289.639622)
			(xy 142.383554 -289.678966) (xy 142.348061 -289.713058) (xy 142.307558 -289.741014) (xy 142.263096 -289.762112)
			(xy 142.215825 -289.775804) (xy 142.16697 -289.781736) (xy 142.117795 -289.779755) (xy 142.069576 -289.769911)
			(xy 142.02356 -289.752459) (xy 141.980939 -289.727852) (xy 141.942818 -289.696727) (xy 141.910183 -289.65989)
			(xy 141.88388 -289.618294) (xy 141.864589 -289.573018) (xy 141.852812 -289.525234) (xy 141.848852 -289.47618)
			(xy 141.530578 -289.47618) (xy 141.530066 -289.501626) (xy 141.521902 -289.55186) (xy 141.505786 -289.600134)
			(xy 141.482135 -289.645197) (xy 141.451562 -289.685883) (xy 141.414858 -289.721138) (xy 141.372974 -289.750048)
			(xy 141.326995 -289.771865) (xy 141.278111 -289.786025) (xy 141.22759 -289.792159) (xy 141.176738 -289.79011)
			(xy 141.126874 -289.77993) (xy 141.079288 -289.761883) (xy 141.035214 -289.736437) (xy 140.995792 -289.70425)
			(xy 140.962044 -289.666156) (xy 140.934843 -289.623142) (xy 140.914895 -289.576322) (xy 140.902716 -289.526908)
			(xy 140.898621 -289.47618) (xy 140.58011 -289.47618) (xy 140.579615 -289.500787) (xy 140.57172 -289.549364)
			(xy 140.556136 -289.596045) (xy 140.533265 -289.639622) (xy 140.5037 -289.678966) (xy 140.468207 -289.713058)
			(xy 140.427704 -289.741014) (xy 140.383242 -289.762112) (xy 140.335971 -289.775804) (xy 140.287116 -289.781736)
			(xy 140.237941 -289.779755) (xy 140.189722 -289.769911) (xy 140.143706 -289.752459) (xy 140.101085 -289.727852)
			(xy 140.062964 -289.696727) (xy 140.030329 -289.65989) (xy 140.004026 -289.618294) (xy 139.984735 -289.573018)
			(xy 139.972958 -289.525234) (xy 139.968998 -289.47618) (xy 139.65047 -289.47618) (xy 139.649958 -289.501626)
			(xy 139.641794 -289.55186) (xy 139.625678 -289.600134) (xy 139.602027 -289.645197) (xy 139.571454 -289.685883)
			(xy 139.53475 -289.721138) (xy 139.492866 -289.750048) (xy 139.446887 -289.771865) (xy 139.398003 -289.786025)
			(xy 139.347482 -289.792159) (xy 139.29663 -289.79011) (xy 139.246766 -289.77993) (xy 139.19918 -289.761883)
			(xy 139.155106 -289.736437) (xy 139.115684 -289.70425) (xy 139.081936 -289.666156) (xy 139.054735 -289.623142)
			(xy 139.034787 -289.576322) (xy 139.022608 -289.526908) (xy 139.018513 -289.47618) (xy 138.710416 -289.47618)
			(xy 138.709904 -289.501626) (xy 138.70174 -289.55186) (xy 138.685624 -289.600134) (xy 138.661973 -289.645197)
			(xy 138.6314 -289.685883) (xy 138.594696 -289.721138) (xy 138.552812 -289.750048) (xy 138.506833 -289.771865)
			(xy 138.457949 -289.786025) (xy 138.407428 -289.792159) (xy 138.356576 -289.79011) (xy 138.306712 -289.77993)
			(xy 138.259126 -289.761883) (xy 138.215052 -289.736437) (xy 138.17563 -289.70425) (xy 138.141882 -289.666156)
			(xy 138.114681 -289.623142) (xy 138.094733 -289.576322) (xy 138.082554 -289.526908) (xy 138.078459 -289.47618)
			(xy 137.759948 -289.47618) (xy 137.759453 -289.500787) (xy 137.751558 -289.549364) (xy 137.735974 -289.596045)
			(xy 137.713103 -289.639622) (xy 137.683538 -289.678966) (xy 137.648045 -289.713058) (xy 137.607542 -289.741014)
			(xy 137.56308 -289.762112) (xy 137.515809 -289.775804) (xy 137.466954 -289.781736) (xy 137.417779 -289.779755)
			(xy 137.36956 -289.769911) (xy 137.323544 -289.752459) (xy 137.280923 -289.727852) (xy 137.242802 -289.696727)
			(xy 137.210167 -289.65989) (xy 137.183864 -289.618294) (xy 137.164573 -289.573018) (xy 137.152796 -289.525234)
			(xy 137.148836 -289.47618) (xy 136.830562 -289.47618) (xy 136.83005 -289.501626) (xy 136.821886 -289.55186)
			(xy 136.80577 -289.600134) (xy 136.782119 -289.645197) (xy 136.751546 -289.685883) (xy 136.714842 -289.721138)
			(xy 136.672958 -289.750048) (xy 136.626979 -289.771865) (xy 136.578095 -289.786025) (xy 136.527574 -289.792159)
			(xy 136.476722 -289.79011) (xy 136.426858 -289.77993) (xy 136.379272 -289.761883) (xy 136.335198 -289.736437)
			(xy 136.295776 -289.70425) (xy 136.262028 -289.666156) (xy 136.234827 -289.623142) (xy 136.214879 -289.576322)
			(xy 136.2027 -289.526908) (xy 136.198605 -289.47618) (xy 135.880094 -289.47618) (xy 135.879599 -289.500787)
			(xy 135.871704 -289.549364) (xy 135.85612 -289.596045) (xy 135.833249 -289.639622) (xy 135.803684 -289.678966)
			(xy 135.768191 -289.713058) (xy 135.727688 -289.741014) (xy 135.683226 -289.762112) (xy 135.635955 -289.775804)
			(xy 135.5871 -289.781736) (xy 135.537925 -289.779755) (xy 135.489706 -289.769911) (xy 135.44369 -289.752459)
			(xy 135.401069 -289.727852) (xy 135.362948 -289.696727) (xy 135.330313 -289.65989) (xy 135.30401 -289.618294)
			(xy 135.284719 -289.573018) (xy 135.272942 -289.525234) (xy 135.268982 -289.47618) (xy 134.950454 -289.47618)
			(xy 134.949942 -289.501626) (xy 134.941778 -289.55186) (xy 134.925662 -289.600134) (xy 134.902011 -289.645197)
			(xy 134.871438 -289.685883) (xy 134.834734 -289.721138) (xy 134.79285 -289.750048) (xy 134.746871 -289.771865)
			(xy 134.697987 -289.786025) (xy 134.647466 -289.792159) (xy 134.596614 -289.79011) (xy 134.54675 -289.77993)
			(xy 134.499164 -289.761883) (xy 134.45509 -289.736437) (xy 134.415668 -289.70425) (xy 134.38192 -289.666156)
			(xy 134.354719 -289.623142) (xy 134.334771 -289.576322) (xy 134.322592 -289.526908) (xy 134.318497 -289.47618)
			(xy 133.999986 -289.47618) (xy 133.999491 -289.500787) (xy 133.991596 -289.549364) (xy 133.976012 -289.596045)
			(xy 133.953141 -289.639622) (xy 133.923576 -289.678966) (xy 133.888083 -289.713058) (xy 133.84758 -289.741014)
			(xy 133.803118 -289.762112) (xy 133.755847 -289.775804) (xy 133.706992 -289.781736) (xy 133.657817 -289.779755)
			(xy 133.609598 -289.769911) (xy 133.563582 -289.752459) (xy 133.520961 -289.727852) (xy 133.48284 -289.696727)
			(xy 133.450205 -289.65989) (xy 133.423902 -289.618294) (xy 133.404611 -289.573018) (xy 133.392834 -289.525234)
			(xy 133.388874 -289.47618) (xy 133.0706 -289.47618) (xy 133.070088 -289.501626) (xy 133.061924 -289.55186)
			(xy 133.045808 -289.600134) (xy 133.022157 -289.645197) (xy 132.991584 -289.685883) (xy 132.95488 -289.721138)
			(xy 132.912996 -289.750048) (xy 132.867017 -289.771865) (xy 132.818133 -289.786025) (xy 132.767612 -289.792159)
			(xy 132.71676 -289.79011) (xy 132.666896 -289.77993) (xy 132.61931 -289.761883) (xy 132.575236 -289.736437)
			(xy 132.535814 -289.70425) (xy 132.502066 -289.666156) (xy 132.474865 -289.623142) (xy 132.454917 -289.576322)
			(xy 132.442738 -289.526908) (xy 132.438643 -289.47618) (xy 132.130546 -289.47618) (xy 132.130034 -289.501626)
			(xy 132.12187 -289.55186) (xy 132.105754 -289.600134) (xy 132.082103 -289.645197) (xy 132.05153 -289.685883)
			(xy 132.014826 -289.721138) (xy 131.972942 -289.750048) (xy 131.926963 -289.771865) (xy 131.878079 -289.786025)
			(xy 131.827558 -289.792159) (xy 131.776706 -289.79011) (xy 131.726842 -289.77993) (xy 131.679256 -289.761883)
			(xy 131.635182 -289.736437) (xy 131.59576 -289.70425) (xy 131.562012 -289.666156) (xy 131.534811 -289.623142)
			(xy 131.514863 -289.576322) (xy 131.502684 -289.526908) (xy 131.498589 -289.47618) (xy 131.180078 -289.47618)
			(xy 131.179583 -289.500787) (xy 131.171688 -289.549364) (xy 131.156104 -289.596045) (xy 131.133233 -289.639622)
			(xy 131.103668 -289.678966) (xy 131.068175 -289.713058) (xy 131.027672 -289.741014) (xy 130.98321 -289.762112)
			(xy 130.935939 -289.775804) (xy 130.887084 -289.781736) (xy 130.837909 -289.779755) (xy 130.78969 -289.769911)
			(xy 130.743674 -289.752459) (xy 130.701053 -289.727852) (xy 130.662932 -289.696727) (xy 130.630297 -289.65989)
			(xy 130.603994 -289.618294) (xy 130.584703 -289.573018) (xy 130.572926 -289.525234) (xy 130.568966 -289.47618)
			(xy 130.250438 -289.47618) (xy 130.249926 -289.501626) (xy 130.241762 -289.55186) (xy 130.225646 -289.600134)
			(xy 130.201995 -289.645197) (xy 130.171422 -289.685883) (xy 130.134718 -289.721138) (xy 130.092834 -289.750048)
			(xy 130.046855 -289.771865) (xy 129.997971 -289.786025) (xy 129.94745 -289.792159) (xy 129.896598 -289.79011)
			(xy 129.846734 -289.77993) (xy 129.799148 -289.761883) (xy 129.755074 -289.736437) (xy 129.715652 -289.70425)
			(xy 129.681904 -289.666156) (xy 129.654703 -289.623142) (xy 129.634755 -289.576322) (xy 129.622576 -289.526908)
			(xy 129.618481 -289.47618) (xy 129.29997 -289.47618) (xy 129.299475 -289.500787) (xy 129.29158 -289.549364)
			(xy 129.275996 -289.596045) (xy 129.253125 -289.639622) (xy 129.22356 -289.678966) (xy 129.188067 -289.713058)
			(xy 129.147564 -289.741014) (xy 129.103102 -289.762112) (xy 129.055831 -289.775804) (xy 129.006976 -289.781736)
			(xy 128.957801 -289.779755) (xy 128.909582 -289.769911) (xy 128.863566 -289.752459) (xy 128.820945 -289.727852)
			(xy 128.782824 -289.696727) (xy 128.750189 -289.65989) (xy 128.723886 -289.618294) (xy 128.704595 -289.573018)
			(xy 128.692818 -289.525234) (xy 128.688858 -289.47618) (xy 128.370584 -289.47618) (xy 128.370125 -289.500326)
			(xy 128.362766 -289.548055) (xy 128.348216 -289.594104) (xy 128.326817 -289.637396) (xy 128.299067 -289.67692)
			(xy 128.265617 -289.711752) (xy 128.227247 -289.741077) (xy 128.184856 -289.764209) (xy 128.162304 -289.772852)
			(xy 128.149858 -289.777424) (xy 128.13284 -289.796728) (xy 128.113282 -289.885882) (xy 128.111414 -289.897647)
			(xy 128.117391 -289.920678) (xy 128.124712 -289.930078) (xy 128.125982 -289.931602) (xy 128.248664 -290.054284)
			(xy 128.255809 -290.060787) (xy 128.273569 -290.068353) (xy 128.283208 -290.069016) (xy 128.2954 -290.06927)
			(xy 128.313421 -290.050954) (xy 128.354307 -290.019836) (xy 128.399689 -289.995745) (xy 128.448372 -289.979314)
			(xy 128.499072 -289.970978) (xy 128.524762 -289.970464) (xy 128.549576 -289.970922) (xy 128.598593 -289.97868)
			(xy 128.645794 -289.994011) (xy 128.690015 -290.016537) (xy 128.730167 -290.045704) (xy 128.765262 -290.080793)
			(xy 128.794435 -290.120941) (xy 128.816969 -290.165158) (xy 128.832307 -290.212356) (xy 128.840073 -290.261372)
			(xy 128.840484 -290.286186) (xy 129.148581 -290.286186) (xy 129.152676 -290.235458) (xy 129.164855 -290.186044)
			(xy 129.184803 -290.139224) (xy 129.212004 -290.09621) (xy 129.245752 -290.058116) (xy 129.285174 -290.025929)
			(xy 129.329248 -290.000483) (xy 129.376834 -289.982436) (xy 129.426698 -289.972256) (xy 129.47755 -289.970207)
			(xy 129.528071 -289.976341) (xy 129.576955 -289.990501) (xy 129.622934 -290.012318) (xy 129.664818 -290.041228)
			(xy 129.701522 -290.076483) (xy 129.732095 -290.117169) (xy 129.755746 -290.162232) (xy 129.771862 -290.210506)
			(xy 129.780026 -290.26074) (xy 129.780538 -290.286186) (xy 131.028435 -290.286186) (xy 131.03253 -290.235458)
			(xy 131.044709 -290.186044) (xy 131.064657 -290.139224) (xy 131.091858 -290.09621) (xy 131.125606 -290.058116)
			(xy 131.165028 -290.025929) (xy 131.209102 -290.000483) (xy 131.256688 -289.982436) (xy 131.306552 -289.972256)
			(xy 131.357404 -289.970207) (xy 131.407925 -289.976341) (xy 131.456809 -289.990501) (xy 131.502788 -290.012318)
			(xy 131.544672 -290.041228) (xy 131.581376 -290.076483) (xy 131.611949 -290.117169) (xy 131.6356 -290.162232)
			(xy 131.651716 -290.210506) (xy 131.65988 -290.26074) (xy 131.660392 -290.286186) (xy 131.97892 -290.286186)
			(xy 131.98288 -290.237132) (xy 131.994657 -290.189348) (xy 132.013948 -290.144072) (xy 132.040251 -290.102476)
			(xy 132.072886 -290.065639) (xy 132.111007 -290.034514) (xy 132.153628 -290.009907) (xy 132.199644 -289.992455)
			(xy 132.247863 -289.982611) (xy 132.297038 -289.98063) (xy 132.345893 -289.986562) (xy 132.393164 -290.000254)
			(xy 132.437626 -290.021352) (xy 132.478129 -290.049308) (xy 132.513622 -290.0834) (xy 132.543187 -290.122744)
			(xy 132.566058 -290.166321) (xy 132.581642 -290.213002) (xy 132.589537 -290.261579) (xy 132.590032 -290.286186)
			(xy 132.908543 -290.286186) (xy 132.912638 -290.235458) (xy 132.924817 -290.186044) (xy 132.944765 -290.139224)
			(xy 132.971966 -290.09621) (xy 133.005714 -290.058116) (xy 133.045136 -290.025929) (xy 133.08921 -290.000483)
			(xy 133.136796 -289.982436) (xy 133.18666 -289.972256) (xy 133.237512 -289.970207) (xy 133.288033 -289.976341)
			(xy 133.336917 -289.990501) (xy 133.382896 -290.012318) (xy 133.42478 -290.041228) (xy 133.461484 -290.076483)
			(xy 133.492057 -290.117169) (xy 133.515708 -290.162232) (xy 133.531824 -290.210506) (xy 133.539988 -290.26074)
			(xy 133.5405 -290.286186) (xy 133.859028 -290.286186) (xy 133.862988 -290.237132) (xy 133.874765 -290.189348)
			(xy 133.894056 -290.144072) (xy 133.920359 -290.102476) (xy 133.952994 -290.065639) (xy 133.991115 -290.034514)
			(xy 134.033736 -290.009907) (xy 134.079752 -289.992455) (xy 134.127971 -289.982611) (xy 134.177146 -289.98063)
			(xy 134.226001 -289.986562) (xy 134.273272 -290.000254) (xy 134.317734 -290.021352) (xy 134.358237 -290.049308)
			(xy 134.39373 -290.0834) (xy 134.423295 -290.122744) (xy 134.446166 -290.166321) (xy 134.46175 -290.213002)
			(xy 134.469645 -290.261579) (xy 134.47014 -290.286186) (xy 134.788397 -290.286186) (xy 134.792492 -290.235458)
			(xy 134.804671 -290.186044) (xy 134.824619 -290.139224) (xy 134.85182 -290.09621) (xy 134.885568 -290.058116)
			(xy 134.92499 -290.025929) (xy 134.969064 -290.000483) (xy 135.01665 -289.982436) (xy 135.066514 -289.972256)
			(xy 135.117366 -289.970207) (xy 135.167887 -289.976341) (xy 135.216771 -289.990501) (xy 135.26275 -290.012318)
			(xy 135.304634 -290.041228) (xy 135.341338 -290.076483) (xy 135.371911 -290.117169) (xy 135.395562 -290.162232)
			(xy 135.411678 -290.210506) (xy 135.419842 -290.26074) (xy 135.420354 -290.286186) (xy 135.728451 -290.286186)
			(xy 135.732546 -290.235458) (xy 135.744725 -290.186044) (xy 135.764673 -290.139224) (xy 135.791874 -290.09621)
			(xy 135.825622 -290.058116) (xy 135.865044 -290.025929) (xy 135.909118 -290.000483) (xy 135.956704 -289.982436)
			(xy 136.006568 -289.972256) (xy 136.05742 -289.970207) (xy 136.107941 -289.976341) (xy 136.156825 -289.990501)
			(xy 136.202804 -290.012318) (xy 136.244688 -290.041228) (xy 136.281392 -290.076483) (xy 136.311965 -290.117169)
			(xy 136.335616 -290.162232) (xy 136.351732 -290.210506) (xy 136.359896 -290.26074) (xy 136.360408 -290.286186)
			(xy 137.608559 -290.286186) (xy 137.612654 -290.235458) (xy 137.624833 -290.186044) (xy 137.644781 -290.139224)
			(xy 137.671982 -290.09621) (xy 137.70573 -290.058116) (xy 137.745152 -290.025929) (xy 137.789226 -290.000483)
			(xy 137.836812 -289.982436) (xy 137.886676 -289.972256) (xy 137.937528 -289.970207) (xy 137.988049 -289.976341)
			(xy 138.036933 -289.990501) (xy 138.082912 -290.012318) (xy 138.124796 -290.041228) (xy 138.1615 -290.076483)
			(xy 138.192073 -290.117169) (xy 138.215724 -290.162232) (xy 138.23184 -290.210506) (xy 138.240004 -290.26074)
			(xy 138.240516 -290.286186) (xy 138.559044 -290.286186) (xy 138.563004 -290.237132) (xy 138.574781 -290.189348)
			(xy 138.594072 -290.144072) (xy 138.620375 -290.102476) (xy 138.65301 -290.065639) (xy 138.691131 -290.034514)
			(xy 138.733752 -290.009907) (xy 138.779768 -289.992455) (xy 138.827987 -289.982611) (xy 138.877162 -289.98063)
			(xy 138.926017 -289.986562) (xy 138.973288 -290.000254) (xy 139.01775 -290.021352) (xy 139.058253 -290.049308)
			(xy 139.093746 -290.0834) (xy 139.123311 -290.122744) (xy 139.146182 -290.166321) (xy 139.161766 -290.213002)
			(xy 139.169661 -290.261579) (xy 139.170156 -290.286186) (xy 139.488413 -290.286186) (xy 139.492508 -290.235458)
			(xy 139.504687 -290.186044) (xy 139.524635 -290.139224) (xy 139.551836 -290.09621) (xy 139.585584 -290.058116)
			(xy 139.625006 -290.025929) (xy 139.66908 -290.000483) (xy 139.716666 -289.982436) (xy 139.76653 -289.972256)
			(xy 139.817382 -289.970207) (xy 139.867903 -289.976341) (xy 139.916787 -289.990501) (xy 139.962766 -290.012318)
			(xy 140.00465 -290.041228) (xy 140.041354 -290.076483) (xy 140.071927 -290.117169) (xy 140.095578 -290.162232)
			(xy 140.111694 -290.210506) (xy 140.119858 -290.26074) (xy 140.12037 -290.286186) (xy 140.438898 -290.286186)
			(xy 140.442858 -290.237132) (xy 140.454635 -290.189348) (xy 140.473926 -290.144072) (xy 140.500229 -290.102476)
			(xy 140.532864 -290.065639) (xy 140.570985 -290.034514) (xy 140.613606 -290.009907) (xy 140.659622 -289.992455)
			(xy 140.707841 -289.982611) (xy 140.757016 -289.98063) (xy 140.805871 -289.986562) (xy 140.853142 -290.000254)
			(xy 140.897604 -290.021352) (xy 140.938107 -290.049308) (xy 140.9736 -290.0834) (xy 141.003165 -290.122744)
			(xy 141.026036 -290.166321) (xy 141.04162 -290.213002) (xy 141.049515 -290.261579) (xy 141.05001 -290.286186)
			(xy 141.368521 -290.286186) (xy 141.372616 -290.235458) (xy 141.384795 -290.186044) (xy 141.404743 -290.139224)
			(xy 141.431944 -290.09621) (xy 141.465692 -290.058116) (xy 141.505114 -290.025929) (xy 141.549188 -290.000483)
			(xy 141.596774 -289.982436) (xy 141.646638 -289.972256) (xy 141.69749 -289.970207) (xy 141.748011 -289.976341)
			(xy 141.796895 -289.990501) (xy 141.842874 -290.012318) (xy 141.884758 -290.041228) (xy 141.921462 -290.076483)
			(xy 141.952035 -290.117169) (xy 141.975686 -290.162232) (xy 141.991802 -290.210506) (xy 141.999966 -290.26074)
			(xy 142.000478 -290.286186) (xy 142.308575 -290.286186) (xy 142.31267 -290.235458) (xy 142.324849 -290.186044)
			(xy 142.344797 -290.139224) (xy 142.371998 -290.09621) (xy 142.405746 -290.058116) (xy 142.445168 -290.025929)
			(xy 142.489242 -290.000483) (xy 142.536828 -289.982436) (xy 142.586692 -289.972256) (xy 142.637544 -289.970207)
			(xy 142.688065 -289.976341) (xy 142.736949 -289.990501) (xy 142.782928 -290.012318) (xy 142.824812 -290.041228)
			(xy 142.861516 -290.076483) (xy 142.892089 -290.117169) (xy 142.91574 -290.162232) (xy 142.931856 -290.210506)
			(xy 142.94002 -290.26074) (xy 142.940532 -290.286186) (xy 145.138914 -290.286186) (xy 145.142874 -290.237132)
			(xy 145.154651 -290.189348) (xy 145.173942 -290.144072) (xy 145.200245 -290.102476) (xy 145.23288 -290.065639)
			(xy 145.271001 -290.034514) (xy 145.313622 -290.009907) (xy 145.359638 -289.992455) (xy 145.407857 -289.982611)
			(xy 145.457032 -289.98063) (xy 145.496729 -289.98545) (xy 168.158683 -289.98545) (xy 168.162618 -289.931679)
			(xy 168.174341 -289.879055) (xy 168.193601 -289.828698) (xy 168.219987 -289.781681) (xy 168.252939 -289.739008)
			(xy 168.291752 -289.701587) (xy 168.3356 -289.670217) (xy 168.383548 -289.645565) (xy 168.434575 -289.628157)
			(xy 168.487593 -289.618364) (xy 168.541472 -289.616395) (xy 168.595063 -289.622292) (xy 168.647224 -289.635928)
			(xy 168.696844 -289.657015) (xy 168.742865 -289.685101) (xy 168.784307 -289.719589) (xy 168.820285 -289.759743)
			(xy 168.850033 -289.804707) (xy 168.872918 -289.853524) (xy 168.88845 -289.905153) (xy 168.8963 -289.958493)
			(xy 168.896792 -289.98545) (xy 168.8963 -290.012407) (xy 168.88845 -290.065747) (xy 168.872918 -290.117376)
			(xy 168.850033 -290.166193) (xy 168.820285 -290.211157) (xy 168.784307 -290.251311) (xy 168.742865 -290.285799)
			(xy 168.696844 -290.313885) (xy 168.647224 -290.334972) (xy 168.595063 -290.348608) (xy 168.541472 -290.354505)
			(xy 168.487593 -290.352536) (xy 168.434575 -290.342743) (xy 168.383548 -290.325335) (xy 168.3356 -290.300683)
			(xy 168.291752 -290.269313) (xy 168.252939 -290.231892) (xy 168.219987 -290.189219) (xy 168.193601 -290.142202)
			(xy 168.174341 -290.091845) (xy 168.162618 -290.039221) (xy 168.158683 -289.98545) (xy 145.496729 -289.98545)
			(xy 145.505887 -289.986562) (xy 145.553158 -290.000254) (xy 145.59762 -290.021352) (xy 145.638123 -290.049308)
			(xy 145.673616 -290.0834) (xy 145.703181 -290.122744) (xy 145.726052 -290.166321) (xy 145.741636 -290.213002)
			(xy 145.749531 -290.261579) (xy 145.750026 -290.286186) (xy 145.749531 -290.310793) (xy 145.741636 -290.35937)
			(xy 145.726052 -290.406051) (xy 145.703181 -290.449628) (xy 145.673616 -290.488972) (xy 145.638123 -290.523064)
			(xy 145.59762 -290.55102) (xy 145.553158 -290.572118) (xy 145.505887 -290.58581) (xy 145.457032 -290.591742)
			(xy 145.407857 -290.589761) (xy 145.359638 -290.579917) (xy 145.313622 -290.562465) (xy 145.271001 -290.537858)
			(xy 145.23288 -290.506733) (xy 145.200245 -290.469896) (xy 145.173942 -290.4283) (xy 145.154651 -290.383024)
			(xy 145.142874 -290.33524) (xy 145.138914 -290.286186) (xy 142.940532 -290.286186) (xy 142.94002 -290.311632)
			(xy 142.931856 -290.361866) (xy 142.91574 -290.41014) (xy 142.892089 -290.455203) (xy 142.861516 -290.495889)
			(xy 142.824812 -290.531144) (xy 142.782928 -290.560054) (xy 142.736949 -290.581871) (xy 142.688065 -290.596031)
			(xy 142.637544 -290.602165) (xy 142.586692 -290.600116) (xy 142.536828 -290.589936) (xy 142.489242 -290.571889)
			(xy 142.445168 -290.546443) (xy 142.405746 -290.514256) (xy 142.371998 -290.476162) (xy 142.344797 -290.433148)
			(xy 142.324849 -290.386328) (xy 142.31267 -290.336914) (xy 142.308575 -290.286186) (xy 142.000478 -290.286186)
			(xy 141.999966 -290.311632) (xy 141.991802 -290.361866) (xy 141.975686 -290.41014) (xy 141.952035 -290.455203)
			(xy 141.921462 -290.495889) (xy 141.884758 -290.531144) (xy 141.842874 -290.560054) (xy 141.796895 -290.581871)
			(xy 141.748011 -290.596031) (xy 141.69749 -290.602165) (xy 141.646638 -290.600116) (xy 141.596774 -290.589936)
			(xy 141.549188 -290.571889) (xy 141.505114 -290.546443) (xy 141.465692 -290.514256) (xy 141.431944 -290.476162)
			(xy 141.404743 -290.433148) (xy 141.384795 -290.386328) (xy 141.372616 -290.336914) (xy 141.368521 -290.286186)
			(xy 141.05001 -290.286186) (xy 141.049515 -290.310793) (xy 141.04162 -290.35937) (xy 141.026036 -290.406051)
			(xy 141.003165 -290.449628) (xy 140.9736 -290.488972) (xy 140.938107 -290.523064) (xy 140.897604 -290.55102)
			(xy 140.853142 -290.572118) (xy 140.805871 -290.58581) (xy 140.757016 -290.591742) (xy 140.707841 -290.589761)
			(xy 140.659622 -290.579917) (xy 140.613606 -290.562465) (xy 140.570985 -290.537858) (xy 140.532864 -290.506733)
			(xy 140.500229 -290.469896) (xy 140.473926 -290.4283) (xy 140.454635 -290.383024) (xy 140.442858 -290.33524)
			(xy 140.438898 -290.286186) (xy 140.12037 -290.286186) (xy 140.119858 -290.311632) (xy 140.111694 -290.361866)
			(xy 140.095578 -290.41014) (xy 140.071927 -290.455203) (xy 140.041354 -290.495889) (xy 140.00465 -290.531144)
			(xy 139.962766 -290.560054) (xy 139.916787 -290.581871) (xy 139.867903 -290.596031) (xy 139.817382 -290.602165)
			(xy 139.76653 -290.600116) (xy 139.716666 -290.589936) (xy 139.66908 -290.571889) (xy 139.625006 -290.546443)
			(xy 139.585584 -290.514256) (xy 139.551836 -290.476162) (xy 139.524635 -290.433148) (xy 139.504687 -290.386328)
			(xy 139.492508 -290.336914) (xy 139.488413 -290.286186) (xy 139.170156 -290.286186) (xy 139.169661 -290.310793)
			(xy 139.161766 -290.35937) (xy 139.146182 -290.406051) (xy 139.123311 -290.449628) (xy 139.093746 -290.488972)
			(xy 139.058253 -290.523064) (xy 139.01775 -290.55102) (xy 138.973288 -290.572118) (xy 138.926017 -290.58581)
			(xy 138.877162 -290.591742) (xy 138.827987 -290.589761) (xy 138.779768 -290.579917) (xy 138.733752 -290.562465)
			(xy 138.691131 -290.537858) (xy 138.65301 -290.506733) (xy 138.620375 -290.469896) (xy 138.594072 -290.4283)
			(xy 138.574781 -290.383024) (xy 138.563004 -290.33524) (xy 138.559044 -290.286186) (xy 138.240516 -290.286186)
			(xy 138.240004 -290.311632) (xy 138.23184 -290.361866) (xy 138.215724 -290.41014) (xy 138.192073 -290.455203)
			(xy 138.1615 -290.495889) (xy 138.124796 -290.531144) (xy 138.082912 -290.560054) (xy 138.036933 -290.581871)
			(xy 137.988049 -290.596031) (xy 137.937528 -290.602165) (xy 137.886676 -290.600116) (xy 137.836812 -290.589936)
			(xy 137.789226 -290.571889) (xy 137.745152 -290.546443) (xy 137.70573 -290.514256) (xy 137.671982 -290.476162)
			(xy 137.644781 -290.433148) (xy 137.624833 -290.386328) (xy 137.612654 -290.336914) (xy 137.608559 -290.286186)
			(xy 136.360408 -290.286186) (xy 136.359896 -290.311632) (xy 136.351732 -290.361866) (xy 136.335616 -290.41014)
			(xy 136.311965 -290.455203) (xy 136.281392 -290.495889) (xy 136.244688 -290.531144) (xy 136.202804 -290.560054)
			(xy 136.156825 -290.581871) (xy 136.107941 -290.596031) (xy 136.05742 -290.602165) (xy 136.006568 -290.600116)
			(xy 135.956704 -290.589936) (xy 135.909118 -290.571889) (xy 135.865044 -290.546443) (xy 135.825622 -290.514256)
			(xy 135.791874 -290.476162) (xy 135.764673 -290.433148) (xy 135.744725 -290.386328) (xy 135.732546 -290.336914)
			(xy 135.728451 -290.286186) (xy 135.420354 -290.286186) (xy 135.419842 -290.311632) (xy 135.411678 -290.361866)
			(xy 135.395562 -290.41014) (xy 135.371911 -290.455203) (xy 135.341338 -290.495889) (xy 135.304634 -290.531144)
			(xy 135.26275 -290.560054) (xy 135.216771 -290.581871) (xy 135.167887 -290.596031) (xy 135.117366 -290.602165)
			(xy 135.066514 -290.600116) (xy 135.01665 -290.589936) (xy 134.969064 -290.571889) (xy 134.92499 -290.546443)
			(xy 134.885568 -290.514256) (xy 134.85182 -290.476162) (xy 134.824619 -290.433148) (xy 134.804671 -290.386328)
			(xy 134.792492 -290.336914) (xy 134.788397 -290.286186) (xy 134.47014 -290.286186) (xy 134.469645 -290.310793)
			(xy 134.46175 -290.35937) (xy 134.446166 -290.406051) (xy 134.423295 -290.449628) (xy 134.39373 -290.488972)
			(xy 134.358237 -290.523064) (xy 134.317734 -290.55102) (xy 134.273272 -290.572118) (xy 134.226001 -290.58581)
			(xy 134.177146 -290.591742) (xy 134.127971 -290.589761) (xy 134.079752 -290.579917) (xy 134.033736 -290.562465)
			(xy 133.991115 -290.537858) (xy 133.952994 -290.506733) (xy 133.920359 -290.469896) (xy 133.894056 -290.4283)
			(xy 133.874765 -290.383024) (xy 133.862988 -290.33524) (xy 133.859028 -290.286186) (xy 133.5405 -290.286186)
			(xy 133.539988 -290.311632) (xy 133.531824 -290.361866) (xy 133.515708 -290.41014) (xy 133.492057 -290.455203)
			(xy 133.461484 -290.495889) (xy 133.42478 -290.531144) (xy 133.382896 -290.560054) (xy 133.336917 -290.581871)
			(xy 133.288033 -290.596031) (xy 133.237512 -290.602165) (xy 133.18666 -290.600116) (xy 133.136796 -290.589936)
			(xy 133.08921 -290.571889) (xy 133.045136 -290.546443) (xy 133.005714 -290.514256) (xy 132.971966 -290.476162)
			(xy 132.944765 -290.433148) (xy 132.924817 -290.386328) (xy 132.912638 -290.336914) (xy 132.908543 -290.286186)
			(xy 132.590032 -290.286186) (xy 132.589537 -290.310793) (xy 132.581642 -290.35937) (xy 132.566058 -290.406051)
			(xy 132.543187 -290.449628) (xy 132.513622 -290.488972) (xy 132.478129 -290.523064) (xy 132.437626 -290.55102)
			(xy 132.393164 -290.572118) (xy 132.345893 -290.58581) (xy 132.297038 -290.591742) (xy 132.247863 -290.589761)
			(xy 132.199644 -290.579917) (xy 132.153628 -290.562465) (xy 132.111007 -290.537858) (xy 132.072886 -290.506733)
			(xy 132.040251 -290.469896) (xy 132.013948 -290.4283) (xy 131.994657 -290.383024) (xy 131.98288 -290.33524)
			(xy 131.97892 -290.286186) (xy 131.660392 -290.286186) (xy 131.65988 -290.311632) (xy 131.651716 -290.361866)
			(xy 131.6356 -290.41014) (xy 131.611949 -290.455203) (xy 131.581376 -290.495889) (xy 131.544672 -290.531144)
			(xy 131.502788 -290.560054) (xy 131.456809 -290.581871) (xy 131.407925 -290.596031) (xy 131.357404 -290.602165)
			(xy 131.306552 -290.600116) (xy 131.256688 -290.589936) (xy 131.209102 -290.571889) (xy 131.165028 -290.546443)
			(xy 131.125606 -290.514256) (xy 131.091858 -290.476162) (xy 131.064657 -290.433148) (xy 131.044709 -290.386328)
			(xy 131.03253 -290.336914) (xy 131.028435 -290.286186) (xy 129.780538 -290.286186) (xy 129.780026 -290.311632)
			(xy 129.771862 -290.361866) (xy 129.755746 -290.41014) (xy 129.732095 -290.455203) (xy 129.701522 -290.495889)
			(xy 129.664818 -290.531144) (xy 129.622934 -290.560054) (xy 129.576955 -290.581871) (xy 129.528071 -290.596031)
			(xy 129.47755 -290.602165) (xy 129.426698 -290.600116) (xy 129.376834 -290.589936) (xy 129.329248 -290.571889)
			(xy 129.285174 -290.546443) (xy 129.245752 -290.514256) (xy 129.212004 -290.476162) (xy 129.184803 -290.433148)
			(xy 129.164855 -290.386328) (xy 129.152676 -290.336914) (xy 129.148581 -290.286186) (xy 128.840484 -290.286186)
			(xy 128.840038 -290.310471) (xy 128.832597 -290.358468) (xy 128.817887 -290.404757) (xy 128.796256 -290.448245)
			(xy 128.768216 -290.487904) (xy 128.734429 -290.522796) (xy 128.695693 -290.552099) (xy 128.652924 -290.575118)
			(xy 128.630172 -290.58362) (xy 128.614932 -290.589208) (xy 128.59639 -290.615116) (xy 128.59639 -290.817808)
			(xy 128.59639 -290.81857) (xy 128.596888 -290.827288) (xy 128.602993 -290.843635) (xy 128.614205 -290.857005)
			(xy 128.621536 -290.86175) (xy 128.628648 -290.865052) (xy 128.73101 -290.905438) (xy 128.76149 -290.89858)
			(xy 128.772158 -290.88715) (xy 128.789599 -290.869308) (xy 128.829216 -290.838981) (xy 128.873237 -290.815499)
			(xy 128.920489 -290.799486) (xy 128.969716 -290.791368) (xy 128.994662 -290.790884) (xy 129.019922 -290.791374)
			(xy 129.069755 -290.799684) (xy 129.11754 -290.816083) (xy 129.161974 -290.840124) (xy 129.201844 -290.871152)
			(xy 129.236063 -290.908319) (xy 129.263697 -290.950612) (xy 129.283993 -290.996877) (xy 129.296396 -291.045852)
			(xy 129.300567 -291.096192) (xy 129.618481 -291.096192) (xy 129.622576 -291.045464) (xy 129.634755 -290.99605)
			(xy 129.654703 -290.94923) (xy 129.681904 -290.906216) (xy 129.715652 -290.868122) (xy 129.755074 -290.835935)
			(xy 129.799148 -290.810489) (xy 129.846734 -290.792442) (xy 129.896598 -290.782262) (xy 129.94745 -290.780213)
			(xy 129.997971 -290.786347) (xy 130.046855 -290.800507) (xy 130.092834 -290.822324) (xy 130.134718 -290.851234)
			(xy 130.171422 -290.886489) (xy 130.201995 -290.927175) (xy 130.225646 -290.972238) (xy 130.241762 -291.020512)
			(xy 130.249926 -291.070746) (xy 130.250438 -291.096192) (xy 130.568966 -291.096192) (xy 130.572926 -291.047138)
			(xy 130.584703 -290.999354) (xy 130.603994 -290.954078) (xy 130.630297 -290.912482) (xy 130.662932 -290.875645)
			(xy 130.701053 -290.84452) (xy 130.743674 -290.819913) (xy 130.78969 -290.802461) (xy 130.837909 -290.792617)
			(xy 130.887084 -290.790636) (xy 130.935939 -290.796568) (xy 130.98321 -290.81026) (xy 131.027672 -290.831358)
			(xy 131.068175 -290.859314) (xy 131.103668 -290.893406) (xy 131.133233 -290.93275) (xy 131.156104 -290.976327)
			(xy 131.171688 -291.023008) (xy 131.179583 -291.071585) (xy 131.180078 -291.096192) (xy 131.498589 -291.096192)
			(xy 131.502684 -291.045464) (xy 131.514863 -290.99605) (xy 131.534811 -290.94923) (xy 131.562012 -290.906216)
			(xy 131.59576 -290.868122) (xy 131.635182 -290.835935) (xy 131.679256 -290.810489) (xy 131.726842 -290.792442)
			(xy 131.776706 -290.782262) (xy 131.827558 -290.780213) (xy 131.878079 -290.786347) (xy 131.926963 -290.800507)
			(xy 131.972942 -290.822324) (xy 132.014826 -290.851234) (xy 132.05153 -290.886489) (xy 132.082103 -290.927175)
			(xy 132.105754 -290.972238) (xy 132.12187 -291.020512) (xy 132.130034 -291.070746) (xy 132.130546 -291.096192)
			(xy 132.438643 -291.096192) (xy 132.442738 -291.045464) (xy 132.454917 -290.99605) (xy 132.474865 -290.94923)
			(xy 132.502066 -290.906216) (xy 132.535814 -290.868122) (xy 132.575236 -290.835935) (xy 132.61931 -290.810489)
			(xy 132.666896 -290.792442) (xy 132.71676 -290.782262) (xy 132.767612 -290.780213) (xy 132.818133 -290.786347)
			(xy 132.867017 -290.800507) (xy 132.912996 -290.822324) (xy 132.95488 -290.851234) (xy 132.991584 -290.886489)
			(xy 133.022157 -290.927175) (xy 133.045808 -290.972238) (xy 133.061924 -291.020512) (xy 133.070088 -291.070746)
			(xy 133.0706 -291.096192) (xy 133.388874 -291.096192) (xy 133.392834 -291.047138) (xy 133.404611 -290.999354)
			(xy 133.423902 -290.954078) (xy 133.450205 -290.912482) (xy 133.48284 -290.875645) (xy 133.520961 -290.84452)
			(xy 133.563582 -290.819913) (xy 133.609598 -290.802461) (xy 133.657817 -290.792617) (xy 133.706992 -290.790636)
			(xy 133.755847 -290.796568) (xy 133.803118 -290.81026) (xy 133.84758 -290.831358) (xy 133.888083 -290.859314)
			(xy 133.923576 -290.893406) (xy 133.953141 -290.93275) (xy 133.976012 -290.976327) (xy 133.991596 -291.023008)
			(xy 133.999491 -291.071585) (xy 133.999986 -291.096192) (xy 134.318497 -291.096192) (xy 134.322592 -291.045464)
			(xy 134.334771 -290.99605) (xy 134.354719 -290.94923) (xy 134.38192 -290.906216) (xy 134.415668 -290.868122)
			(xy 134.45509 -290.835935) (xy 134.499164 -290.810489) (xy 134.54675 -290.792442) (xy 134.596614 -290.782262)
			(xy 134.647466 -290.780213) (xy 134.697987 -290.786347) (xy 134.746871 -290.800507) (xy 134.79285 -290.822324)
			(xy 134.834734 -290.851234) (xy 134.871438 -290.886489) (xy 134.902011 -290.927175) (xy 134.925662 -290.972238)
			(xy 134.941778 -291.020512) (xy 134.949942 -291.070746) (xy 134.950454 -291.096192) (xy 135.268982 -291.096192)
			(xy 135.272942 -291.047138) (xy 135.284719 -290.999354) (xy 135.30401 -290.954078) (xy 135.330313 -290.912482)
			(xy 135.362948 -290.875645) (xy 135.401069 -290.84452) (xy 135.44369 -290.819913) (xy 135.489706 -290.802461)
			(xy 135.537925 -290.792617) (xy 135.5871 -290.790636) (xy 135.635955 -290.796568) (xy 135.683226 -290.81026)
			(xy 135.727688 -290.831358) (xy 135.768191 -290.859314) (xy 135.803684 -290.893406) (xy 135.833249 -290.93275)
			(xy 135.85612 -290.976327) (xy 135.871704 -291.023008) (xy 135.879599 -291.071585) (xy 135.880094 -291.096192)
			(xy 136.198605 -291.096192) (xy 136.2027 -291.045464) (xy 136.214879 -290.99605) (xy 136.234827 -290.94923)
			(xy 136.262028 -290.906216) (xy 136.295776 -290.868122) (xy 136.335198 -290.835935) (xy 136.379272 -290.810489)
			(xy 136.426858 -290.792442) (xy 136.476722 -290.782262) (xy 136.527574 -290.780213) (xy 136.578095 -290.786347)
			(xy 136.626979 -290.800507) (xy 136.672958 -290.822324) (xy 136.714842 -290.851234) (xy 136.751546 -290.886489)
			(xy 136.782119 -290.927175) (xy 136.80577 -290.972238) (xy 136.821886 -291.020512) (xy 136.83005 -291.070746)
			(xy 136.830562 -291.096192) (xy 137.148836 -291.096192) (xy 137.152796 -291.047138) (xy 137.164573 -290.999354)
			(xy 137.183864 -290.954078) (xy 137.210167 -290.912482) (xy 137.242802 -290.875645) (xy 137.280923 -290.84452)
			(xy 137.323544 -290.819913) (xy 137.36956 -290.802461) (xy 137.417779 -290.792617) (xy 137.466954 -290.790636)
			(xy 137.515809 -290.796568) (xy 137.56308 -290.81026) (xy 137.607542 -290.831358) (xy 137.648045 -290.859314)
			(xy 137.683538 -290.893406) (xy 137.713103 -290.93275) (xy 137.735974 -290.976327) (xy 137.751558 -291.023008)
			(xy 137.759453 -291.071585) (xy 137.759948 -291.096192) (xy 138.078459 -291.096192) (xy 138.082554 -291.045464)
			(xy 138.094733 -290.99605) (xy 138.114681 -290.94923) (xy 138.141882 -290.906216) (xy 138.17563 -290.868122)
			(xy 138.215052 -290.835935) (xy 138.259126 -290.810489) (xy 138.306712 -290.792442) (xy 138.356576 -290.782262)
			(xy 138.407428 -290.780213) (xy 138.457949 -290.786347) (xy 138.506833 -290.800507) (xy 138.552812 -290.822324)
			(xy 138.594696 -290.851234) (xy 138.6314 -290.886489) (xy 138.661973 -290.927175) (xy 138.685624 -290.972238)
			(xy 138.70174 -291.020512) (xy 138.709904 -291.070746) (xy 138.710416 -291.096192) (xy 139.018513 -291.096192)
			(xy 139.022608 -291.045464) (xy 139.034787 -290.99605) (xy 139.054735 -290.94923) (xy 139.081936 -290.906216)
			(xy 139.115684 -290.868122) (xy 139.155106 -290.835935) (xy 139.19918 -290.810489) (xy 139.246766 -290.792442)
			(xy 139.29663 -290.782262) (xy 139.347482 -290.780213) (xy 139.398003 -290.786347) (xy 139.446887 -290.800507)
			(xy 139.492866 -290.822324) (xy 139.53475 -290.851234) (xy 139.571454 -290.886489) (xy 139.602027 -290.927175)
			(xy 139.625678 -290.972238) (xy 139.641794 -291.020512) (xy 139.649958 -291.070746) (xy 139.65047 -291.096192)
			(xy 139.968998 -291.096192) (xy 139.972958 -291.047138) (xy 139.984735 -290.999354) (xy 140.004026 -290.954078)
			(xy 140.030329 -290.912482) (xy 140.062964 -290.875645) (xy 140.101085 -290.84452) (xy 140.143706 -290.819913)
			(xy 140.189722 -290.802461) (xy 140.237941 -290.792617) (xy 140.287116 -290.790636) (xy 140.335971 -290.796568)
			(xy 140.383242 -290.81026) (xy 140.427704 -290.831358) (xy 140.468207 -290.859314) (xy 140.5037 -290.893406)
			(xy 140.533265 -290.93275) (xy 140.556136 -290.976327) (xy 140.57172 -291.023008) (xy 140.579615 -291.071585)
			(xy 140.58011 -291.096192) (xy 140.898621 -291.096192) (xy 140.902716 -291.045464) (xy 140.914895 -290.99605)
			(xy 140.934843 -290.94923) (xy 140.962044 -290.906216) (xy 140.995792 -290.868122) (xy 141.035214 -290.835935)
			(xy 141.079288 -290.810489) (xy 141.126874 -290.792442) (xy 141.176738 -290.782262) (xy 141.22759 -290.780213)
			(xy 141.278111 -290.786347) (xy 141.326995 -290.800507) (xy 141.372974 -290.822324) (xy 141.414858 -290.851234)
			(xy 141.451562 -290.886489) (xy 141.482135 -290.927175) (xy 141.505786 -290.972238) (xy 141.521902 -291.020512)
			(xy 141.530066 -291.070746) (xy 141.530578 -291.096192) (xy 141.848852 -291.096192) (xy 141.852812 -291.047138)
			(xy 141.864589 -290.999354) (xy 141.88388 -290.954078) (xy 141.910183 -290.912482) (xy 141.942818 -290.875645)
			(xy 141.980939 -290.84452) (xy 142.02356 -290.819913) (xy 142.069576 -290.802461) (xy 142.117795 -290.792617)
			(xy 142.16697 -290.790636) (xy 142.215825 -290.796568) (xy 142.263096 -290.81026) (xy 142.307558 -290.831358)
			(xy 142.348061 -290.859314) (xy 142.383554 -290.893406) (xy 142.413119 -290.93275) (xy 142.43599 -290.976327)
			(xy 142.451574 -291.023008) (xy 142.459469 -291.071585) (xy 142.459964 -291.096192) (xy 142.778475 -291.096192)
			(xy 142.78257 -291.045464) (xy 142.794749 -290.99605) (xy 142.814697 -290.94923) (xy 142.841898 -290.906216)
			(xy 142.875646 -290.868122) (xy 142.915068 -290.835935) (xy 142.959142 -290.810489) (xy 143.006728 -290.792442)
			(xy 143.056592 -290.782262) (xy 143.107444 -290.780213) (xy 143.157965 -290.786347) (xy 143.206849 -290.800507)
			(xy 143.252828 -290.822324) (xy 143.294712 -290.851234) (xy 143.331416 -290.886489) (xy 143.361989 -290.927175)
			(xy 143.38564 -290.972238) (xy 143.401756 -291.020512) (xy 143.40992 -291.070746) (xy 143.410432 -291.096192)
			(xy 143.72896 -291.096192) (xy 143.73292 -291.047138) (xy 143.744697 -290.999354) (xy 143.763988 -290.954078)
			(xy 143.790291 -290.912482) (xy 143.822926 -290.875645) (xy 143.861047 -290.84452) (xy 143.903668 -290.819913)
			(xy 143.949684 -290.802461) (xy 143.997903 -290.792617) (xy 144.047078 -290.790636) (xy 144.095933 -290.796568)
			(xy 144.143204 -290.81026) (xy 144.185339 -290.830254) (xy 146.737082 -290.830254) (xy 146.741042 -290.7812)
			(xy 146.752819 -290.733416) (xy 146.77211 -290.68814) (xy 146.798413 -290.646544) (xy 146.831048 -290.609707)
			(xy 146.869169 -290.578582) (xy 146.91179 -290.553975) (xy 146.957806 -290.536523) (xy 147.006025 -290.526679)
			(xy 147.0552 -290.524698) (xy 147.104055 -290.53063) (xy 147.151326 -290.544322) (xy 147.195788 -290.56542)
			(xy 147.236291 -290.593376) (xy 147.271784 -290.627468) (xy 147.301349 -290.666812) (xy 147.32422 -290.710389)
			(xy 147.339804 -290.75707) (xy 147.347699 -290.805647) (xy 147.348194 -290.830254) (xy 147.348092 -290.835334)
			(xy 164.058615 -290.835334) (xy 164.06255 -290.781563) (xy 164.074273 -290.728939) (xy 164.093533 -290.678582)
			(xy 164.119919 -290.631565) (xy 164.152871 -290.588892) (xy 164.191684 -290.551471) (xy 164.235532 -290.520101)
			(xy 164.28348 -290.495449) (xy 164.334507 -290.478041) (xy 164.387525 -290.468248) (xy 164.441404 -290.466279)
			(xy 164.494995 -290.472176) (xy 164.547156 -290.485812) (xy 164.596776 -290.506899) (xy 164.642797 -290.534985)
			(xy 164.684239 -290.569473) (xy 164.720217 -290.609627) (xy 164.749965 -290.654591) (xy 164.77285 -290.703408)
			(xy 164.788382 -290.755037) (xy 164.796232 -290.808377) (xy 164.796724 -290.835334) (xy 164.796232 -290.862291)
			(xy 164.788382 -290.915631) (xy 164.77285 -290.96726) (xy 164.749965 -291.016077) (xy 164.720217 -291.061041)
			(xy 164.684239 -291.101195) (xy 164.642797 -291.135683) (xy 164.596776 -291.163769) (xy 164.547156 -291.184856)
			(xy 164.494995 -291.198492) (xy 164.441404 -291.204389) (xy 164.387525 -291.20242) (xy 164.334507 -291.192627)
			(xy 164.28348 -291.175219) (xy 164.235532 -291.150567) (xy 164.191684 -291.119197) (xy 164.152871 -291.081776)
			(xy 164.119919 -291.039103) (xy 164.093533 -290.992086) (xy 164.074273 -290.941729) (xy 164.06255 -290.889105)
			(xy 164.058615 -290.835334) (xy 147.348092 -290.835334) (xy 147.347699 -290.854861) (xy 147.339804 -290.903438)
			(xy 147.32422 -290.950119) (xy 147.301349 -290.993696) (xy 147.271784 -291.03304) (xy 147.236291 -291.067132)
			(xy 147.195788 -291.095088) (xy 147.151326 -291.116186) (xy 147.104055 -291.129878) (xy 147.0552 -291.13581)
			(xy 147.006025 -291.133829) (xy 146.957806 -291.123985) (xy 146.91179 -291.106533) (xy 146.869169 -291.081926)
			(xy 146.831048 -291.050801) (xy 146.798413 -291.013964) (xy 146.77211 -290.972368) (xy 146.752819 -290.927092)
			(xy 146.741042 -290.879308) (xy 146.737082 -290.830254) (xy 144.185339 -290.830254) (xy 144.187666 -290.831358)
			(xy 144.228169 -290.859314) (xy 144.263662 -290.893406) (xy 144.293227 -290.93275) (xy 144.316098 -290.976327)
			(xy 144.331682 -291.023008) (xy 144.339577 -291.071585) (xy 144.340072 -291.096192) (xy 144.339577 -291.120799)
			(xy 144.331682 -291.169376) (xy 144.316098 -291.216057) (xy 144.293227 -291.259634) (xy 144.263662 -291.298978)
			(xy 144.228169 -291.33307) (xy 144.187666 -291.361026) (xy 144.143204 -291.382124) (xy 144.095933 -291.395816)
			(xy 144.047078 -291.401748) (xy 143.997903 -291.399767) (xy 143.949684 -291.389923) (xy 143.903668 -291.372471)
			(xy 143.861047 -291.347864) (xy 143.822926 -291.316739) (xy 143.790291 -291.279902) (xy 143.763988 -291.238306)
			(xy 143.744697 -291.19303) (xy 143.73292 -291.145246) (xy 143.72896 -291.096192) (xy 143.410432 -291.096192)
			(xy 143.40992 -291.121638) (xy 143.401756 -291.171872) (xy 143.38564 -291.220146) (xy 143.361989 -291.265209)
			(xy 143.331416 -291.305895) (xy 143.294712 -291.34115) (xy 143.252828 -291.37006) (xy 143.206849 -291.391877)
			(xy 143.157965 -291.406037) (xy 143.107444 -291.412171) (xy 143.056592 -291.410122) (xy 143.006728 -291.399942)
			(xy 142.959142 -291.381895) (xy 142.915068 -291.356449) (xy 142.875646 -291.324262) (xy 142.841898 -291.286168)
			(xy 142.814697 -291.243154) (xy 142.794749 -291.196334) (xy 142.78257 -291.14692) (xy 142.778475 -291.096192)
			(xy 142.459964 -291.096192) (xy 142.459469 -291.120799) (xy 142.451574 -291.169376) (xy 142.43599 -291.216057)
			(xy 142.413119 -291.259634) (xy 142.383554 -291.298978) (xy 142.348061 -291.33307) (xy 142.307558 -291.361026)
			(xy 142.263096 -291.382124) (xy 142.215825 -291.395816) (xy 142.16697 -291.401748) (xy 142.117795 -291.399767)
			(xy 142.069576 -291.389923) (xy 142.02356 -291.372471) (xy 141.980939 -291.347864) (xy 141.942818 -291.316739)
			(xy 141.910183 -291.279902) (xy 141.88388 -291.238306) (xy 141.864589 -291.19303) (xy 141.852812 -291.145246)
			(xy 141.848852 -291.096192) (xy 141.530578 -291.096192) (xy 141.530066 -291.121638) (xy 141.521902 -291.171872)
			(xy 141.505786 -291.220146) (xy 141.482135 -291.265209) (xy 141.451562 -291.305895) (xy 141.414858 -291.34115)
			(xy 141.372974 -291.37006) (xy 141.326995 -291.391877) (xy 141.278111 -291.406037) (xy 141.22759 -291.412171)
			(xy 141.176738 -291.410122) (xy 141.126874 -291.399942) (xy 141.079288 -291.381895) (xy 141.035214 -291.356449)
			(xy 140.995792 -291.324262) (xy 140.962044 -291.286168) (xy 140.934843 -291.243154) (xy 140.914895 -291.196334)
			(xy 140.902716 -291.14692) (xy 140.898621 -291.096192) (xy 140.58011 -291.096192) (xy 140.579615 -291.120799)
			(xy 140.57172 -291.169376) (xy 140.556136 -291.216057) (xy 140.533265 -291.259634) (xy 140.5037 -291.298978)
			(xy 140.468207 -291.33307) (xy 140.427704 -291.361026) (xy 140.383242 -291.382124) (xy 140.335971 -291.395816)
			(xy 140.287116 -291.401748) (xy 140.237941 -291.399767) (xy 140.189722 -291.389923) (xy 140.143706 -291.372471)
			(xy 140.101085 -291.347864) (xy 140.062964 -291.316739) (xy 140.030329 -291.279902) (xy 140.004026 -291.238306)
			(xy 139.984735 -291.19303) (xy 139.972958 -291.145246) (xy 139.968998 -291.096192) (xy 139.65047 -291.096192)
			(xy 139.649958 -291.121638) (xy 139.641794 -291.171872) (xy 139.625678 -291.220146) (xy 139.602027 -291.265209)
			(xy 139.571454 -291.305895) (xy 139.53475 -291.34115) (xy 139.492866 -291.37006) (xy 139.446887 -291.391877)
			(xy 139.398003 -291.406037) (xy 139.347482 -291.412171) (xy 139.29663 -291.410122) (xy 139.246766 -291.399942)
			(xy 139.19918 -291.381895) (xy 139.155106 -291.356449) (xy 139.115684 -291.324262) (xy 139.081936 -291.286168)
			(xy 139.054735 -291.243154) (xy 139.034787 -291.196334) (xy 139.022608 -291.14692) (xy 139.018513 -291.096192)
			(xy 138.710416 -291.096192) (xy 138.709904 -291.121638) (xy 138.70174 -291.171872) (xy 138.685624 -291.220146)
			(xy 138.661973 -291.265209) (xy 138.6314 -291.305895) (xy 138.594696 -291.34115) (xy 138.552812 -291.37006)
			(xy 138.506833 -291.391877) (xy 138.457949 -291.406037) (xy 138.407428 -291.412171) (xy 138.356576 -291.410122)
			(xy 138.306712 -291.399942) (xy 138.259126 -291.381895) (xy 138.215052 -291.356449) (xy 138.17563 -291.324262)
			(xy 138.141882 -291.286168) (xy 138.114681 -291.243154) (xy 138.094733 -291.196334) (xy 138.082554 -291.14692)
			(xy 138.078459 -291.096192) (xy 137.759948 -291.096192) (xy 137.759453 -291.120799) (xy 137.751558 -291.169376)
			(xy 137.735974 -291.216057) (xy 137.713103 -291.259634) (xy 137.683538 -291.298978) (xy 137.648045 -291.33307)
			(xy 137.607542 -291.361026) (xy 137.56308 -291.382124) (xy 137.515809 -291.395816) (xy 137.466954 -291.401748)
			(xy 137.417779 -291.399767) (xy 137.36956 -291.389923) (xy 137.323544 -291.372471) (xy 137.280923 -291.347864)
			(xy 137.242802 -291.316739) (xy 137.210167 -291.279902) (xy 137.183864 -291.238306) (xy 137.164573 -291.19303)
			(xy 137.152796 -291.145246) (xy 137.148836 -291.096192) (xy 136.830562 -291.096192) (xy 136.83005 -291.121638)
			(xy 136.821886 -291.171872) (xy 136.80577 -291.220146) (xy 136.782119 -291.265209) (xy 136.751546 -291.305895)
			(xy 136.714842 -291.34115) (xy 136.672958 -291.37006) (xy 136.626979 -291.391877) (xy 136.578095 -291.406037)
			(xy 136.527574 -291.412171) (xy 136.476722 -291.410122) (xy 136.426858 -291.399942) (xy 136.379272 -291.381895)
			(xy 136.335198 -291.356449) (xy 136.295776 -291.324262) (xy 136.262028 -291.286168) (xy 136.234827 -291.243154)
			(xy 136.214879 -291.196334) (xy 136.2027 -291.14692) (xy 136.198605 -291.096192) (xy 135.880094 -291.096192)
			(xy 135.879599 -291.120799) (xy 135.871704 -291.169376) (xy 135.85612 -291.216057) (xy 135.833249 -291.259634)
			(xy 135.803684 -291.298978) (xy 135.768191 -291.33307) (xy 135.727688 -291.361026) (xy 135.683226 -291.382124)
			(xy 135.635955 -291.395816) (xy 135.5871 -291.401748) (xy 135.537925 -291.399767) (xy 135.489706 -291.389923)
			(xy 135.44369 -291.372471) (xy 135.401069 -291.347864) (xy 135.362948 -291.316739) (xy 135.330313 -291.279902)
			(xy 135.30401 -291.238306) (xy 135.284719 -291.19303) (xy 135.272942 -291.145246) (xy 135.268982 -291.096192)
			(xy 134.950454 -291.096192) (xy 134.949942 -291.121638) (xy 134.941778 -291.171872) (xy 134.925662 -291.220146)
			(xy 134.902011 -291.265209) (xy 134.871438 -291.305895) (xy 134.834734 -291.34115) (xy 134.79285 -291.37006)
			(xy 134.746871 -291.391877) (xy 134.697987 -291.406037) (xy 134.647466 -291.412171) (xy 134.596614 -291.410122)
			(xy 134.54675 -291.399942) (xy 134.499164 -291.381895) (xy 134.45509 -291.356449) (xy 134.415668 -291.324262)
			(xy 134.38192 -291.286168) (xy 134.354719 -291.243154) (xy 134.334771 -291.196334) (xy 134.322592 -291.14692)
			(xy 134.318497 -291.096192) (xy 133.999986 -291.096192) (xy 133.999491 -291.120799) (xy 133.991596 -291.169376)
			(xy 133.976012 -291.216057) (xy 133.953141 -291.259634) (xy 133.923576 -291.298978) (xy 133.888083 -291.33307)
			(xy 133.84758 -291.361026) (xy 133.803118 -291.382124) (xy 133.755847 -291.395816) (xy 133.706992 -291.401748)
			(xy 133.657817 -291.399767) (xy 133.609598 -291.389923) (xy 133.563582 -291.372471) (xy 133.520961 -291.347864)
			(xy 133.48284 -291.316739) (xy 133.450205 -291.279902) (xy 133.423902 -291.238306) (xy 133.404611 -291.19303)
			(xy 133.392834 -291.145246) (xy 133.388874 -291.096192) (xy 133.0706 -291.096192) (xy 133.070088 -291.121638)
			(xy 133.061924 -291.171872) (xy 133.045808 -291.220146) (xy 133.022157 -291.265209) (xy 132.991584 -291.305895)
			(xy 132.95488 -291.34115) (xy 132.912996 -291.37006) (xy 132.867017 -291.391877) (xy 132.818133 -291.406037)
			(xy 132.767612 -291.412171) (xy 132.71676 -291.410122) (xy 132.666896 -291.399942) (xy 132.61931 -291.381895)
			(xy 132.575236 -291.356449) (xy 132.535814 -291.324262) (xy 132.502066 -291.286168) (xy 132.474865 -291.243154)
			(xy 132.454917 -291.196334) (xy 132.442738 -291.14692) (xy 132.438643 -291.096192) (xy 132.130546 -291.096192)
			(xy 132.130034 -291.121638) (xy 132.12187 -291.171872) (xy 132.105754 -291.220146) (xy 132.082103 -291.265209)
			(xy 132.05153 -291.305895) (xy 132.014826 -291.34115) (xy 131.972942 -291.37006) (xy 131.926963 -291.391877)
			(xy 131.878079 -291.406037) (xy 131.827558 -291.412171) (xy 131.776706 -291.410122) (xy 131.726842 -291.399942)
			(xy 131.679256 -291.381895) (xy 131.635182 -291.356449) (xy 131.59576 -291.324262) (xy 131.562012 -291.286168)
			(xy 131.534811 -291.243154) (xy 131.514863 -291.196334) (xy 131.502684 -291.14692) (xy 131.498589 -291.096192)
			(xy 131.180078 -291.096192) (xy 131.179583 -291.120799) (xy 131.171688 -291.169376) (xy 131.156104 -291.216057)
			(xy 131.133233 -291.259634) (xy 131.103668 -291.298978) (xy 131.068175 -291.33307) (xy 131.027672 -291.361026)
			(xy 130.98321 -291.382124) (xy 130.935939 -291.395816) (xy 130.887084 -291.401748) (xy 130.837909 -291.399767)
			(xy 130.78969 -291.389923) (xy 130.743674 -291.372471) (xy 130.701053 -291.347864) (xy 130.662932 -291.316739)
			(xy 130.630297 -291.279902) (xy 130.603994 -291.238306) (xy 130.584703 -291.19303) (xy 130.572926 -291.145246)
			(xy 130.568966 -291.096192) (xy 130.250438 -291.096192) (xy 130.249926 -291.121638) (xy 130.241762 -291.171872)
			(xy 130.225646 -291.220146) (xy 130.201995 -291.265209) (xy 130.171422 -291.305895) (xy 130.134718 -291.34115)
			(xy 130.092834 -291.37006) (xy 130.046855 -291.391877) (xy 129.997971 -291.406037) (xy 129.94745 -291.412171)
			(xy 129.896598 -291.410122) (xy 129.846734 -291.399942) (xy 129.799148 -291.381895) (xy 129.755074 -291.356449)
			(xy 129.715652 -291.324262) (xy 129.681904 -291.286168) (xy 129.654703 -291.243154) (xy 129.634755 -291.196334)
			(xy 129.622576 -291.14692) (xy 129.618481 -291.096192) (xy 129.300567 -291.096192) (xy 129.300568 -291.0962)
			(xy 129.296396 -291.146548) (xy 129.283993 -291.195523) (xy 129.263697 -291.241788) (xy 129.236063 -291.284081)
			(xy 129.201844 -291.321248) (xy 129.161974 -291.352276) (xy 129.11754 -291.376317) (xy 129.069755 -291.392716)
			(xy 129.019922 -291.401026) (xy 128.994662 -291.4015) (xy 128.969715 -291.401009) (xy 128.920484 -291.392903)
			(xy 128.873227 -291.376898) (xy 128.829203 -291.353419) (xy 128.789584 -291.323092) (xy 128.772158 -291.305234)
			(xy 128.76149 -291.293804) (xy 128.73101 -291.286946) (xy 128.628648 -291.327332) (xy 128.621536 -291.330634)
			(xy 128.614168 -291.335341) (xy 128.602916 -291.348706) (xy 128.596833 -291.365083) (xy 128.59639 -291.373814)
			(xy 128.59639 -291.56787) (xy 128.596692 -291.575534) (xy 128.601357 -291.590138) (xy 128.605534 -291.596572)
			(xy 128.60909 -291.60216) (xy 128.633692 -291.609487) (xy 128.680297 -291.630999) (xy 128.722805 -291.659773)
			(xy 128.760092 -291.69505) (xy 128.791177 -291.735898) (xy 128.815238 -291.78124) (xy 128.83164 -291.82988)
			(xy 128.839951 -291.880533) (xy 128.840484 -291.906198) (xy 129.148581 -291.906198) (xy 129.152676 -291.85547)
			(xy 129.164855 -291.806056) (xy 129.184803 -291.759236) (xy 129.212004 -291.716222) (xy 129.245752 -291.678128)
			(xy 129.285174 -291.645941) (xy 129.329248 -291.620495) (xy 129.376834 -291.602448) (xy 129.426698 -291.592268)
			(xy 129.47755 -291.590219) (xy 129.528071 -291.596353) (xy 129.576955 -291.610513) (xy 129.622934 -291.63233)
			(xy 129.664818 -291.66124) (xy 129.701522 -291.696495) (xy 129.732095 -291.737181) (xy 129.755746 -291.782244)
			(xy 129.771862 -291.830518) (xy 129.780026 -291.880752) (xy 129.780538 -291.906198) (xy 130.099066 -291.906198)
			(xy 130.103026 -291.857144) (xy 130.114803 -291.80936) (xy 130.134094 -291.764084) (xy 130.160397 -291.722488)
			(xy 130.193032 -291.685651) (xy 130.231153 -291.654526) (xy 130.273774 -291.629919) (xy 130.31979 -291.612467)
			(xy 130.368009 -291.602623) (xy 130.417184 -291.600642) (xy 130.466039 -291.606574) (xy 130.51331 -291.620266)
			(xy 130.557772 -291.641364) (xy 130.598275 -291.66932) (xy 130.633768 -291.703412) (xy 130.663333 -291.742756)
			(xy 130.686204 -291.786333) (xy 130.701788 -291.833014) (xy 130.709683 -291.881591) (xy 130.710178 -291.906198)
			(xy 131.028435 -291.906198) (xy 131.03253 -291.85547) (xy 131.044709 -291.806056) (xy 131.064657 -291.759236)
			(xy 131.091858 -291.716222) (xy 131.125606 -291.678128) (xy 131.165028 -291.645941) (xy 131.209102 -291.620495)
			(xy 131.256688 -291.602448) (xy 131.306552 -291.592268) (xy 131.357404 -291.590219) (xy 131.407925 -291.596353)
			(xy 131.456809 -291.610513) (xy 131.502788 -291.63233) (xy 131.544672 -291.66124) (xy 131.581376 -291.696495)
			(xy 131.611949 -291.737181) (xy 131.6356 -291.782244) (xy 131.651716 -291.830518) (xy 131.65988 -291.880752)
			(xy 131.660392 -291.906198) (xy 131.97892 -291.906198) (xy 131.98288 -291.857144) (xy 131.994657 -291.80936)
			(xy 132.013948 -291.764084) (xy 132.040251 -291.722488) (xy 132.072886 -291.685651) (xy 132.111007 -291.654526)
			(xy 132.153628 -291.629919) (xy 132.199644 -291.612467) (xy 132.247863 -291.602623) (xy 132.297038 -291.600642)
			(xy 132.345893 -291.606574) (xy 132.393164 -291.620266) (xy 132.437626 -291.641364) (xy 132.478129 -291.66932)
			(xy 132.513622 -291.703412) (xy 132.543187 -291.742756) (xy 132.566058 -291.786333) (xy 132.581642 -291.833014)
			(xy 132.589537 -291.881591) (xy 132.590032 -291.906198) (xy 132.908543 -291.906198) (xy 132.912638 -291.85547)
			(xy 132.924817 -291.806056) (xy 132.944765 -291.759236) (xy 132.971966 -291.716222) (xy 133.005714 -291.678128)
			(xy 133.045136 -291.645941) (xy 133.08921 -291.620495) (xy 133.136796 -291.602448) (xy 133.18666 -291.592268)
			(xy 133.237512 -291.590219) (xy 133.288033 -291.596353) (xy 133.336917 -291.610513) (xy 133.382896 -291.63233)
			(xy 133.42478 -291.66124) (xy 133.461484 -291.696495) (xy 133.492057 -291.737181) (xy 133.515708 -291.782244)
			(xy 133.531824 -291.830518) (xy 133.539988 -291.880752) (xy 133.5405 -291.906198) (xy 133.859028 -291.906198)
			(xy 133.862988 -291.857144) (xy 133.874765 -291.80936) (xy 133.894056 -291.764084) (xy 133.920359 -291.722488)
			(xy 133.952994 -291.685651) (xy 133.991115 -291.654526) (xy 134.033736 -291.629919) (xy 134.079752 -291.612467)
			(xy 134.127971 -291.602623) (xy 134.177146 -291.600642) (xy 134.226001 -291.606574) (xy 134.273272 -291.620266)
			(xy 134.317734 -291.641364) (xy 134.358237 -291.66932) (xy 134.39373 -291.703412) (xy 134.423295 -291.742756)
			(xy 134.446166 -291.786333) (xy 134.46175 -291.833014) (xy 134.469645 -291.881591) (xy 134.47014 -291.906198)
			(xy 134.788397 -291.906198) (xy 134.792492 -291.85547) (xy 134.804671 -291.806056) (xy 134.824619 -291.759236)
			(xy 134.85182 -291.716222) (xy 134.885568 -291.678128) (xy 134.92499 -291.645941) (xy 134.969064 -291.620495)
			(xy 135.01665 -291.602448) (xy 135.066514 -291.592268) (xy 135.117366 -291.590219) (xy 135.167887 -291.596353)
			(xy 135.216771 -291.610513) (xy 135.26275 -291.63233) (xy 135.304634 -291.66124) (xy 135.341338 -291.696495)
			(xy 135.371911 -291.737181) (xy 135.395562 -291.782244) (xy 135.411678 -291.830518) (xy 135.419842 -291.880752)
			(xy 135.420354 -291.906198) (xy 135.728451 -291.906198) (xy 135.732546 -291.85547) (xy 135.744725 -291.806056)
			(xy 135.764673 -291.759236) (xy 135.791874 -291.716222) (xy 135.825622 -291.678128) (xy 135.865044 -291.645941)
			(xy 135.909118 -291.620495) (xy 135.956704 -291.602448) (xy 136.006568 -291.592268) (xy 136.05742 -291.590219)
			(xy 136.107941 -291.596353) (xy 136.156825 -291.610513) (xy 136.202804 -291.63233) (xy 136.244688 -291.66124)
			(xy 136.281392 -291.696495) (xy 136.311965 -291.737181) (xy 136.335616 -291.782244) (xy 136.351732 -291.830518)
			(xy 136.359896 -291.880752) (xy 136.360408 -291.906198) (xy 136.678936 -291.906198) (xy 136.682896 -291.857144)
			(xy 136.694673 -291.80936) (xy 136.713964 -291.764084) (xy 136.740267 -291.722488) (xy 136.772902 -291.685651)
			(xy 136.811023 -291.654526) (xy 136.853644 -291.629919) (xy 136.89966 -291.612467) (xy 136.947879 -291.602623)
			(xy 136.997054 -291.600642) (xy 137.045909 -291.606574) (xy 137.09318 -291.620266) (xy 137.137642 -291.641364)
			(xy 137.178145 -291.66932) (xy 137.213638 -291.703412) (xy 137.243203 -291.742756) (xy 137.266074 -291.786333)
			(xy 137.281658 -291.833014) (xy 137.289553 -291.881591) (xy 137.290048 -291.906198) (xy 137.608559 -291.906198)
			(xy 137.612654 -291.85547) (xy 137.624833 -291.806056) (xy 137.644781 -291.759236) (xy 137.671982 -291.716222)
			(xy 137.70573 -291.678128) (xy 137.745152 -291.645941) (xy 137.789226 -291.620495) (xy 137.836812 -291.602448)
			(xy 137.886676 -291.592268) (xy 137.937528 -291.590219) (xy 137.988049 -291.596353) (xy 138.036933 -291.610513)
			(xy 138.082912 -291.63233) (xy 138.124796 -291.66124) (xy 138.1615 -291.696495) (xy 138.192073 -291.737181)
			(xy 138.215724 -291.782244) (xy 138.23184 -291.830518) (xy 138.240004 -291.880752) (xy 138.240516 -291.906198)
			(xy 138.559044 -291.906198) (xy 138.563004 -291.857144) (xy 138.574781 -291.80936) (xy 138.594072 -291.764084)
			(xy 138.620375 -291.722488) (xy 138.65301 -291.685651) (xy 138.691131 -291.654526) (xy 138.733752 -291.629919)
			(xy 138.779768 -291.612467) (xy 138.827987 -291.602623) (xy 138.877162 -291.600642) (xy 138.926017 -291.606574)
			(xy 138.973288 -291.620266) (xy 139.01775 -291.641364) (xy 139.058253 -291.66932) (xy 139.093746 -291.703412)
			(xy 139.123311 -291.742756) (xy 139.146182 -291.786333) (xy 139.161766 -291.833014) (xy 139.169661 -291.881591)
			(xy 139.170156 -291.906198) (xy 139.488413 -291.906198) (xy 139.492508 -291.85547) (xy 139.504687 -291.806056)
			(xy 139.524635 -291.759236) (xy 139.551836 -291.716222) (xy 139.585584 -291.678128) (xy 139.625006 -291.645941)
			(xy 139.66908 -291.620495) (xy 139.716666 -291.602448) (xy 139.76653 -291.592268) (xy 139.817382 -291.590219)
			(xy 139.867903 -291.596353) (xy 139.916787 -291.610513) (xy 139.962766 -291.63233) (xy 140.00465 -291.66124)
			(xy 140.041354 -291.696495) (xy 140.071927 -291.737181) (xy 140.095578 -291.782244) (xy 140.111694 -291.830518)
			(xy 140.119858 -291.880752) (xy 140.12037 -291.906198) (xy 140.438898 -291.906198) (xy 140.442858 -291.857144)
			(xy 140.454635 -291.80936) (xy 140.473926 -291.764084) (xy 140.500229 -291.722488) (xy 140.532864 -291.685651)
			(xy 140.570985 -291.654526) (xy 140.613606 -291.629919) (xy 140.659622 -291.612467) (xy 140.707841 -291.602623)
			(xy 140.757016 -291.600642) (xy 140.805871 -291.606574) (xy 140.853142 -291.620266) (xy 140.897604 -291.641364)
			(xy 140.938107 -291.66932) (xy 140.9736 -291.703412) (xy 141.003165 -291.742756) (xy 141.026036 -291.786333)
			(xy 141.04162 -291.833014) (xy 141.049515 -291.881591) (xy 141.05001 -291.906198) (xy 141.368521 -291.906198)
			(xy 141.372616 -291.85547) (xy 141.384795 -291.806056) (xy 141.404743 -291.759236) (xy 141.431944 -291.716222)
			(xy 141.465692 -291.678128) (xy 141.505114 -291.645941) (xy 141.549188 -291.620495) (xy 141.596774 -291.602448)
			(xy 141.646638 -291.592268) (xy 141.69749 -291.590219) (xy 141.748011 -291.596353) (xy 141.796895 -291.610513)
			(xy 141.842874 -291.63233) (xy 141.884758 -291.66124) (xy 141.921462 -291.696495) (xy 141.952035 -291.737181)
			(xy 141.975686 -291.782244) (xy 141.991802 -291.830518) (xy 141.999966 -291.880752) (xy 142.000478 -291.906198)
			(xy 142.308575 -291.906198) (xy 142.31267 -291.85547) (xy 142.324849 -291.806056) (xy 142.344797 -291.759236)
			(xy 142.371998 -291.716222) (xy 142.405746 -291.678128) (xy 142.445168 -291.645941) (xy 142.489242 -291.620495)
			(xy 142.536828 -291.602448) (xy 142.586692 -291.592268) (xy 142.637544 -291.590219) (xy 142.688065 -291.596353)
			(xy 142.736949 -291.610513) (xy 142.782928 -291.63233) (xy 142.824812 -291.66124) (xy 142.861516 -291.696495)
			(xy 142.892089 -291.737181) (xy 142.91574 -291.782244) (xy 142.931856 -291.830518) (xy 142.94002 -291.880752)
			(xy 142.940532 -291.906198) (xy 143.258806 -291.906198) (xy 143.262766 -291.857144) (xy 143.274543 -291.80936)
			(xy 143.293834 -291.764084) (xy 143.320137 -291.722488) (xy 143.352772 -291.685651) (xy 143.390893 -291.654526)
			(xy 143.433514 -291.629919) (xy 143.47953 -291.612467) (xy 143.527749 -291.602623) (xy 143.576924 -291.600642)
			(xy 143.625779 -291.606574) (xy 143.67305 -291.620266) (xy 143.717512 -291.641364) (xy 143.758015 -291.66932)
			(xy 143.793508 -291.703412) (xy 143.823073 -291.742756) (xy 143.845944 -291.786333) (xy 143.861528 -291.833014)
			(xy 143.869423 -291.881591) (xy 143.869918 -291.906198) (xy 145.138914 -291.906198) (xy 145.142874 -291.857144)
			(xy 145.154651 -291.80936) (xy 145.173942 -291.764084) (xy 145.200245 -291.722488) (xy 145.23288 -291.685651)
			(xy 145.271001 -291.654526) (xy 145.313622 -291.629919) (xy 145.359638 -291.612467) (xy 145.407857 -291.602623)
			(xy 145.457032 -291.600642) (xy 145.505887 -291.606574) (xy 145.553158 -291.620266) (xy 145.59762 -291.641364)
			(xy 145.638123 -291.66932) (xy 145.654674 -291.685218) (xy 168.158683 -291.685218) (xy 168.162618 -291.631447)
			(xy 168.174341 -291.578823) (xy 168.193601 -291.528466) (xy 168.219987 -291.481449) (xy 168.252939 -291.438776)
			(xy 168.291752 -291.401355) (xy 168.3356 -291.369985) (xy 168.383548 -291.345333) (xy 168.434575 -291.327925)
			(xy 168.487593 -291.318132) (xy 168.541472 -291.316163) (xy 168.595063 -291.32206) (xy 168.647224 -291.335696)
			(xy 168.696844 -291.356783) (xy 168.742865 -291.384869) (xy 168.784307 -291.419357) (xy 168.820285 -291.459511)
			(xy 168.850033 -291.504475) (xy 168.872918 -291.553292) (xy 168.88845 -291.604921) (xy 168.8963 -291.658261)
			(xy 168.896792 -291.685218) (xy 168.8963 -291.712175) (xy 168.88845 -291.765515) (xy 168.872918 -291.817144)
			(xy 168.850033 -291.865961) (xy 168.820285 -291.910925) (xy 168.784307 -291.951079) (xy 168.742865 -291.985567)
			(xy 168.696844 -292.013653) (xy 168.647224 -292.03474) (xy 168.595063 -292.048376) (xy 168.541472 -292.054273)
			(xy 168.487593 -292.052304) (xy 168.434575 -292.042511) (xy 168.383548 -292.025103) (xy 168.3356 -292.000451)
			(xy 168.291752 -291.969081) (xy 168.252939 -291.93166) (xy 168.219987 -291.888987) (xy 168.193601 -291.84197)
			(xy 168.174341 -291.791613) (xy 168.162618 -291.738989) (xy 168.158683 -291.685218) (xy 145.654674 -291.685218)
			(xy 145.673616 -291.703412) (xy 145.703181 -291.742756) (xy 145.726052 -291.786333) (xy 145.741636 -291.833014)
			(xy 145.749531 -291.881591) (xy 145.750026 -291.906198) (xy 145.749531 -291.930805) (xy 145.741636 -291.979382)
			(xy 145.726052 -292.026063) (xy 145.703181 -292.06964) (xy 145.673616 -292.108984) (xy 145.638123 -292.143076)
			(xy 145.59762 -292.171032) (xy 145.553158 -292.19213) (xy 145.505887 -292.205822) (xy 145.457032 -292.211754)
			(xy 145.407857 -292.209773) (xy 145.359638 -292.199929) (xy 145.313622 -292.182477) (xy 145.271001 -292.15787)
			(xy 145.23288 -292.126745) (xy 145.200245 -292.089908) (xy 145.173942 -292.048312) (xy 145.154651 -292.003036)
			(xy 145.142874 -291.955252) (xy 145.138914 -291.906198) (xy 143.869918 -291.906198) (xy 143.869423 -291.930805)
			(xy 143.861528 -291.979382) (xy 143.845944 -292.026063) (xy 143.823073 -292.06964) (xy 143.793508 -292.108984)
			(xy 143.758015 -292.143076) (xy 143.717512 -292.171032) (xy 143.67305 -292.19213) (xy 143.625779 -292.205822)
			(xy 143.576924 -292.211754) (xy 143.527749 -292.209773) (xy 143.47953 -292.199929) (xy 143.433514 -292.182477)
			(xy 143.390893 -292.15787) (xy 143.352772 -292.126745) (xy 143.320137 -292.089908) (xy 143.293834 -292.048312)
			(xy 143.274543 -292.003036) (xy 143.262766 -291.955252) (xy 143.258806 -291.906198) (xy 142.940532 -291.906198)
			(xy 142.94002 -291.931644) (xy 142.931856 -291.981878) (xy 142.91574 -292.030152) (xy 142.892089 -292.075215)
			(xy 142.861516 -292.115901) (xy 142.824812 -292.151156) (xy 142.782928 -292.180066) (xy 142.736949 -292.201883)
			(xy 142.688065 -292.216043) (xy 142.637544 -292.222177) (xy 142.586692 -292.220128) (xy 142.536828 -292.209948)
			(xy 142.489242 -292.191901) (xy 142.445168 -292.166455) (xy 142.405746 -292.134268) (xy 142.371998 -292.096174)
			(xy 142.344797 -292.05316) (xy 142.324849 -292.00634) (xy 142.31267 -291.956926) (xy 142.308575 -291.906198)
			(xy 142.000478 -291.906198) (xy 141.999966 -291.931644) (xy 141.991802 -291.981878) (xy 141.975686 -292.030152)
			(xy 141.952035 -292.075215) (xy 141.921462 -292.115901) (xy 141.884758 -292.151156) (xy 141.842874 -292.180066)
			(xy 141.796895 -292.201883) (xy 141.748011 -292.216043) (xy 141.69749 -292.222177) (xy 141.646638 -292.220128)
			(xy 141.596774 -292.209948) (xy 141.549188 -292.191901) (xy 141.505114 -292.166455) (xy 141.465692 -292.134268)
			(xy 141.431944 -292.096174) (xy 141.404743 -292.05316) (xy 141.384795 -292.00634) (xy 141.372616 -291.956926)
			(xy 141.368521 -291.906198) (xy 141.05001 -291.906198) (xy 141.049515 -291.930805) (xy 141.04162 -291.979382)
			(xy 141.026036 -292.026063) (xy 141.003165 -292.06964) (xy 140.9736 -292.108984) (xy 140.938107 -292.143076)
			(xy 140.897604 -292.171032) (xy 140.853142 -292.19213) (xy 140.805871 -292.205822) (xy 140.757016 -292.211754)
			(xy 140.707841 -292.209773) (xy 140.659622 -292.199929) (xy 140.613606 -292.182477) (xy 140.570985 -292.15787)
			(xy 140.532864 -292.126745) (xy 140.500229 -292.089908) (xy 140.473926 -292.048312) (xy 140.454635 -292.003036)
			(xy 140.442858 -291.955252) (xy 140.438898 -291.906198) (xy 140.12037 -291.906198) (xy 140.119858 -291.931644)
			(xy 140.111694 -291.981878) (xy 140.095578 -292.030152) (xy 140.071927 -292.075215) (xy 140.041354 -292.115901)
			(xy 140.00465 -292.151156) (xy 139.962766 -292.180066) (xy 139.916787 -292.201883) (xy 139.867903 -292.216043)
			(xy 139.817382 -292.222177) (xy 139.76653 -292.220128) (xy 139.716666 -292.209948) (xy 139.66908 -292.191901)
			(xy 139.625006 -292.166455) (xy 139.585584 -292.134268) (xy 139.551836 -292.096174) (xy 139.524635 -292.05316)
			(xy 139.504687 -292.00634) (xy 139.492508 -291.956926) (xy 139.488413 -291.906198) (xy 139.170156 -291.906198)
			(xy 139.169661 -291.930805) (xy 139.161766 -291.979382) (xy 139.146182 -292.026063) (xy 139.123311 -292.06964)
			(xy 139.093746 -292.108984) (xy 139.058253 -292.143076) (xy 139.01775 -292.171032) (xy 138.973288 -292.19213)
			(xy 138.926017 -292.205822) (xy 138.877162 -292.211754) (xy 138.827987 -292.209773) (xy 138.779768 -292.199929)
			(xy 138.733752 -292.182477) (xy 138.691131 -292.15787) (xy 138.65301 -292.126745) (xy 138.620375 -292.089908)
			(xy 138.594072 -292.048312) (xy 138.574781 -292.003036) (xy 138.563004 -291.955252) (xy 138.559044 -291.906198)
			(xy 138.240516 -291.906198) (xy 138.240004 -291.931644) (xy 138.23184 -291.981878) (xy 138.215724 -292.030152)
			(xy 138.192073 -292.075215) (xy 138.1615 -292.115901) (xy 138.124796 -292.151156) (xy 138.082912 -292.180066)
			(xy 138.036933 -292.201883) (xy 137.988049 -292.216043) (xy 137.937528 -292.222177) (xy 137.886676 -292.220128)
			(xy 137.836812 -292.209948) (xy 137.789226 -292.191901) (xy 137.745152 -292.166455) (xy 137.70573 -292.134268)
			(xy 137.671982 -292.096174) (xy 137.644781 -292.05316) (xy 137.624833 -292.00634) (xy 137.612654 -291.956926)
			(xy 137.608559 -291.906198) (xy 137.290048 -291.906198) (xy 137.289553 -291.930805) (xy 137.281658 -291.979382)
			(xy 137.266074 -292.026063) (xy 137.243203 -292.06964) (xy 137.213638 -292.108984) (xy 137.178145 -292.143076)
			(xy 137.137642 -292.171032) (xy 137.09318 -292.19213) (xy 137.045909 -292.205822) (xy 136.997054 -292.211754)
			(xy 136.947879 -292.209773) (xy 136.89966 -292.199929) (xy 136.853644 -292.182477) (xy 136.811023 -292.15787)
			(xy 136.772902 -292.126745) (xy 136.740267 -292.089908) (xy 136.713964 -292.048312) (xy 136.694673 -292.003036)
			(xy 136.682896 -291.955252) (xy 136.678936 -291.906198) (xy 136.360408 -291.906198) (xy 136.359896 -291.931644)
			(xy 136.351732 -291.981878) (xy 136.335616 -292.030152) (xy 136.311965 -292.075215) (xy 136.281392 -292.115901)
			(xy 136.244688 -292.151156) (xy 136.202804 -292.180066) (xy 136.156825 -292.201883) (xy 136.107941 -292.216043)
			(xy 136.05742 -292.222177) (xy 136.006568 -292.220128) (xy 135.956704 -292.209948) (xy 135.909118 -292.191901)
			(xy 135.865044 -292.166455) (xy 135.825622 -292.134268) (xy 135.791874 -292.096174) (xy 135.764673 -292.05316)
			(xy 135.744725 -292.00634) (xy 135.732546 -291.956926) (xy 135.728451 -291.906198) (xy 135.420354 -291.906198)
			(xy 135.419842 -291.931644) (xy 135.411678 -291.981878) (xy 135.395562 -292.030152) (xy 135.371911 -292.075215)
			(xy 135.341338 -292.115901) (xy 135.304634 -292.151156) (xy 135.26275 -292.180066) (xy 135.216771 -292.201883)
			(xy 135.167887 -292.216043) (xy 135.117366 -292.222177) (xy 135.066514 -292.220128) (xy 135.01665 -292.209948)
			(xy 134.969064 -292.191901) (xy 134.92499 -292.166455) (xy 134.885568 -292.134268) (xy 134.85182 -292.096174)
			(xy 134.824619 -292.05316) (xy 134.804671 -292.00634) (xy 134.792492 -291.956926) (xy 134.788397 -291.906198)
			(xy 134.47014 -291.906198) (xy 134.469645 -291.930805) (xy 134.46175 -291.979382) (xy 134.446166 -292.026063)
			(xy 134.423295 -292.06964) (xy 134.39373 -292.108984) (xy 134.358237 -292.143076) (xy 134.317734 -292.171032)
			(xy 134.273272 -292.19213) (xy 134.226001 -292.205822) (xy 134.177146 -292.211754) (xy 134.127971 -292.209773)
			(xy 134.079752 -292.199929) (xy 134.033736 -292.182477) (xy 133.991115 -292.15787) (xy 133.952994 -292.126745)
			(xy 133.920359 -292.089908) (xy 133.894056 -292.048312) (xy 133.874765 -292.003036) (xy 133.862988 -291.955252)
			(xy 133.859028 -291.906198) (xy 133.5405 -291.906198) (xy 133.539988 -291.931644) (xy 133.531824 -291.981878)
			(xy 133.515708 -292.030152) (xy 133.492057 -292.075215) (xy 133.461484 -292.115901) (xy 133.42478 -292.151156)
			(xy 133.382896 -292.180066) (xy 133.336917 -292.201883) (xy 133.288033 -292.216043) (xy 133.237512 -292.222177)
			(xy 133.18666 -292.220128) (xy 133.136796 -292.209948) (xy 133.08921 -292.191901) (xy 133.045136 -292.166455)
			(xy 133.005714 -292.134268) (xy 132.971966 -292.096174) (xy 132.944765 -292.05316) (xy 132.924817 -292.00634)
			(xy 132.912638 -291.956926) (xy 132.908543 -291.906198) (xy 132.590032 -291.906198) (xy 132.589537 -291.930805)
			(xy 132.581642 -291.979382) (xy 132.566058 -292.026063) (xy 132.543187 -292.06964) (xy 132.513622 -292.108984)
			(xy 132.478129 -292.143076) (xy 132.437626 -292.171032) (xy 132.393164 -292.19213) (xy 132.345893 -292.205822)
			(xy 132.297038 -292.211754) (xy 132.247863 -292.209773) (xy 132.199644 -292.199929) (xy 132.153628 -292.182477)
			(xy 132.111007 -292.15787) (xy 132.072886 -292.126745) (xy 132.040251 -292.089908) (xy 132.013948 -292.048312)
			(xy 131.994657 -292.003036) (xy 131.98288 -291.955252) (xy 131.97892 -291.906198) (xy 131.660392 -291.906198)
			(xy 131.65988 -291.931644) (xy 131.651716 -291.981878) (xy 131.6356 -292.030152) (xy 131.611949 -292.075215)
			(xy 131.581376 -292.115901) (xy 131.544672 -292.151156) (xy 131.502788 -292.180066) (xy 131.456809 -292.201883)
			(xy 131.407925 -292.216043) (xy 131.357404 -292.222177) (xy 131.306552 -292.220128) (xy 131.256688 -292.209948)
			(xy 131.209102 -292.191901) (xy 131.165028 -292.166455) (xy 131.125606 -292.134268) (xy 131.091858 -292.096174)
			(xy 131.064657 -292.05316) (xy 131.044709 -292.00634) (xy 131.03253 -291.956926) (xy 131.028435 -291.906198)
			(xy 130.710178 -291.906198) (xy 130.709683 -291.930805) (xy 130.701788 -291.979382) (xy 130.686204 -292.026063)
			(xy 130.663333 -292.06964) (xy 130.633768 -292.108984) (xy 130.598275 -292.143076) (xy 130.557772 -292.171032)
			(xy 130.51331 -292.19213) (xy 130.466039 -292.205822) (xy 130.417184 -292.211754) (xy 130.368009 -292.209773)
			(xy 130.31979 -292.199929) (xy 130.273774 -292.182477) (xy 130.231153 -292.15787) (xy 130.193032 -292.126745)
			(xy 130.160397 -292.089908) (xy 130.134094 -292.048312) (xy 130.114803 -292.003036) (xy 130.103026 -291.955252)
			(xy 130.099066 -291.906198) (xy 129.780538 -291.906198) (xy 129.780026 -291.931644) (xy 129.771862 -291.981878)
			(xy 129.755746 -292.030152) (xy 129.732095 -292.075215) (xy 129.701522 -292.115901) (xy 129.664818 -292.151156)
			(xy 129.622934 -292.180066) (xy 129.576955 -292.201883) (xy 129.528071 -292.216043) (xy 129.47755 -292.222177)
			(xy 129.426698 -292.220128) (xy 129.376834 -292.209948) (xy 129.329248 -292.191901) (xy 129.285174 -292.166455)
			(xy 129.245752 -292.134268) (xy 129.212004 -292.096174) (xy 129.184803 -292.05316) (xy 129.164855 -292.00634)
			(xy 129.152676 -291.956926) (xy 129.148581 -291.906198) (xy 128.840484 -291.906198) (xy 128.840038 -291.930483)
			(xy 128.832594 -291.978478) (xy 128.817883 -292.024766) (xy 128.796252 -292.068252) (xy 128.768211 -292.107909)
			(xy 128.734424 -292.142801) (xy 128.695689 -292.172102) (xy 128.65292 -292.19512) (xy 128.630172 -292.203632)
			(xy 128.614932 -292.20922) (xy 128.59639 -292.235128) (xy 128.59639 -292.43782) (xy 128.59639 -292.438582)
			(xy 128.59689 -292.447299) (xy 128.602997 -292.463642) (xy 128.61421 -292.47701) (xy 128.621536 -292.481762)
			(xy 128.628648 -292.485064) (xy 128.73101 -292.52545) (xy 128.76149 -292.518592) (xy 128.772158 -292.507162)
			(xy 128.789601 -292.489324) (xy 128.829221 -292.459006) (xy 128.873242 -292.43553) (xy 128.920493 -292.419522)
			(xy 128.969718 -292.411407) (xy 128.994662 -292.410896) (xy 129.019921 -292.411386) (xy 129.069752 -292.419695)
			(xy 129.117535 -292.436094) (xy 129.161967 -292.460134) (xy 129.201836 -292.491161) (xy 129.236054 -292.528327)
			(xy 129.263687 -292.570618) (xy 129.283981 -292.616881) (xy 129.296384 -292.665854) (xy 129.300556 -292.7162)
			(xy 129.300556 -292.716204) (xy 129.618481 -292.716204) (xy 129.622576 -292.665476) (xy 129.634755 -292.616062)
			(xy 129.654703 -292.569242) (xy 129.681904 -292.526228) (xy 129.715652 -292.488134) (xy 129.755074 -292.455947)
			(xy 129.799148 -292.430501) (xy 129.846734 -292.412454) (xy 129.896598 -292.402274) (xy 129.94745 -292.400225)
			(xy 129.997971 -292.406359) (xy 130.046855 -292.420519) (xy 130.092834 -292.442336) (xy 130.134718 -292.471246)
			(xy 130.171422 -292.506501) (xy 130.201995 -292.547187) (xy 130.225646 -292.59225) (xy 130.241762 -292.640524)
			(xy 130.249926 -292.690758) (xy 130.250438 -292.716204) (xy 131.498589 -292.716204) (xy 131.502684 -292.665476)
			(xy 131.514863 -292.616062) (xy 131.534811 -292.569242) (xy 131.562012 -292.526228) (xy 131.59576 -292.488134)
			(xy 131.635182 -292.455947) (xy 131.679256 -292.430501) (xy 131.726842 -292.412454) (xy 131.776706 -292.402274)
			(xy 131.827558 -292.400225) (xy 131.878079 -292.406359) (xy 131.926963 -292.420519) (xy 131.972942 -292.442336)
			(xy 132.014826 -292.471246) (xy 132.05153 -292.506501) (xy 132.082103 -292.547187) (xy 132.105754 -292.59225)
			(xy 132.12187 -292.640524) (xy 132.130034 -292.690758) (xy 132.130546 -292.716204) (xy 132.438643 -292.716204)
			(xy 132.442738 -292.665476) (xy 132.454917 -292.616062) (xy 132.474865 -292.569242) (xy 132.502066 -292.526228)
			(xy 132.535814 -292.488134) (xy 132.575236 -292.455947) (xy 132.61931 -292.430501) (xy 132.666896 -292.412454)
			(xy 132.71676 -292.402274) (xy 132.767612 -292.400225) (xy 132.818133 -292.406359) (xy 132.867017 -292.420519)
			(xy 132.912996 -292.442336) (xy 132.95488 -292.471246) (xy 132.991584 -292.506501) (xy 133.022157 -292.547187)
			(xy 133.045808 -292.59225) (xy 133.061924 -292.640524) (xy 133.070088 -292.690758) (xy 133.0706 -292.716204)
			(xy 133.388874 -292.716204) (xy 133.392834 -292.66715) (xy 133.404611 -292.619366) (xy 133.423902 -292.57409)
			(xy 133.450205 -292.532494) (xy 133.48284 -292.495657) (xy 133.520961 -292.464532) (xy 133.563582 -292.439925)
			(xy 133.609598 -292.422473) (xy 133.657817 -292.412629) (xy 133.706992 -292.410648) (xy 133.755847 -292.41658)
			(xy 133.803118 -292.430272) (xy 133.84758 -292.45137) (xy 133.888083 -292.479326) (xy 133.923576 -292.513418)
			(xy 133.953141 -292.552762) (xy 133.976012 -292.596339) (xy 133.991596 -292.64302) (xy 133.999491 -292.691597)
			(xy 133.999986 -292.716204) (xy 134.318497 -292.716204) (xy 134.322592 -292.665476) (xy 134.334771 -292.616062)
			(xy 134.354719 -292.569242) (xy 134.38192 -292.526228) (xy 134.415668 -292.488134) (xy 134.45509 -292.455947)
			(xy 134.499164 -292.430501) (xy 134.54675 -292.412454) (xy 134.596614 -292.402274) (xy 134.647466 -292.400225)
			(xy 134.697987 -292.406359) (xy 134.746871 -292.420519) (xy 134.79285 -292.442336) (xy 134.834734 -292.471246)
			(xy 134.871438 -292.506501) (xy 134.902011 -292.547187) (xy 134.925662 -292.59225) (xy 134.941778 -292.640524)
			(xy 134.949942 -292.690758) (xy 134.950454 -292.716204) (xy 135.268982 -292.716204) (xy 135.272942 -292.66715)
			(xy 135.284719 -292.619366) (xy 135.30401 -292.57409) (xy 135.330313 -292.532494) (xy 135.362948 -292.495657)
			(xy 135.401069 -292.464532) (xy 135.44369 -292.439925) (xy 135.489706 -292.422473) (xy 135.537925 -292.412629)
			(xy 135.5871 -292.410648) (xy 135.635955 -292.41658) (xy 135.683226 -292.430272) (xy 135.727688 -292.45137)
			(xy 135.768191 -292.479326) (xy 135.803684 -292.513418) (xy 135.833249 -292.552762) (xy 135.85612 -292.596339)
			(xy 135.871704 -292.64302) (xy 135.879599 -292.691597) (xy 135.880094 -292.716204) (xy 136.198605 -292.716204)
			(xy 136.2027 -292.665476) (xy 136.214879 -292.616062) (xy 136.234827 -292.569242) (xy 136.262028 -292.526228)
			(xy 136.295776 -292.488134) (xy 136.335198 -292.455947) (xy 136.379272 -292.430501) (xy 136.426858 -292.412454)
			(xy 136.476722 -292.402274) (xy 136.527574 -292.400225) (xy 136.578095 -292.406359) (xy 136.626979 -292.420519)
			(xy 136.672958 -292.442336) (xy 136.714842 -292.471246) (xy 136.751546 -292.506501) (xy 136.782119 -292.547187)
			(xy 136.80577 -292.59225) (xy 136.821886 -292.640524) (xy 136.83005 -292.690758) (xy 136.830562 -292.716204)
			(xy 138.078459 -292.716204) (xy 138.082554 -292.665476) (xy 138.094733 -292.616062) (xy 138.114681 -292.569242)
			(xy 138.141882 -292.526228) (xy 138.17563 -292.488134) (xy 138.215052 -292.455947) (xy 138.259126 -292.430501)
			(xy 138.306712 -292.412454) (xy 138.356576 -292.402274) (xy 138.407428 -292.400225) (xy 138.457949 -292.406359)
			(xy 138.506833 -292.420519) (xy 138.552812 -292.442336) (xy 138.594696 -292.471246) (xy 138.6314 -292.506501)
			(xy 138.661973 -292.547187) (xy 138.685624 -292.59225) (xy 138.70174 -292.640524) (xy 138.709904 -292.690758)
			(xy 138.710416 -292.716204) (xy 139.018513 -292.716204) (xy 139.022608 -292.665476) (xy 139.034787 -292.616062)
			(xy 139.054735 -292.569242) (xy 139.081936 -292.526228) (xy 139.115684 -292.488134) (xy 139.155106 -292.455947)
			(xy 139.19918 -292.430501) (xy 139.246766 -292.412454) (xy 139.29663 -292.402274) (xy 139.347482 -292.400225)
			(xy 139.398003 -292.406359) (xy 139.446887 -292.420519) (xy 139.492866 -292.442336) (xy 139.53475 -292.471246)
			(xy 139.571454 -292.506501) (xy 139.602027 -292.547187) (xy 139.625678 -292.59225) (xy 139.641794 -292.640524)
			(xy 139.649958 -292.690758) (xy 139.65047 -292.716204) (xy 139.968998 -292.716204) (xy 139.972958 -292.66715)
			(xy 139.984735 -292.619366) (xy 140.004026 -292.57409) (xy 140.030329 -292.532494) (xy 140.062964 -292.495657)
			(xy 140.101085 -292.464532) (xy 140.143706 -292.439925) (xy 140.189722 -292.422473) (xy 140.237941 -292.412629)
			(xy 140.287116 -292.410648) (xy 140.335971 -292.41658) (xy 140.383242 -292.430272) (xy 140.427704 -292.45137)
			(xy 140.468207 -292.479326) (xy 140.5037 -292.513418) (xy 140.533265 -292.552762) (xy 140.556136 -292.596339)
			(xy 140.57172 -292.64302) (xy 140.579615 -292.691597) (xy 140.58011 -292.716204) (xy 140.898621 -292.716204)
			(xy 140.902716 -292.665476) (xy 140.914895 -292.616062) (xy 140.934843 -292.569242) (xy 140.962044 -292.526228)
			(xy 140.995792 -292.488134) (xy 141.035214 -292.455947) (xy 141.079288 -292.430501) (xy 141.126874 -292.412454)
			(xy 141.176738 -292.402274) (xy 141.22759 -292.400225) (xy 141.278111 -292.406359) (xy 141.326995 -292.420519)
			(xy 141.372974 -292.442336) (xy 141.414858 -292.471246) (xy 141.451562 -292.506501) (xy 141.482135 -292.547187)
			(xy 141.505786 -292.59225) (xy 141.521902 -292.640524) (xy 141.530066 -292.690758) (xy 141.530578 -292.716204)
			(xy 141.848852 -292.716204) (xy 141.852812 -292.66715) (xy 141.864589 -292.619366) (xy 141.88388 -292.57409)
			(xy 141.910183 -292.532494) (xy 141.942818 -292.495657) (xy 141.980939 -292.464532) (xy 142.02356 -292.439925)
			(xy 142.069576 -292.422473) (xy 142.117795 -292.412629) (xy 142.16697 -292.410648) (xy 142.215825 -292.41658)
			(xy 142.263096 -292.430272) (xy 142.307558 -292.45137) (xy 142.348061 -292.479326) (xy 142.383554 -292.513418)
			(xy 142.413119 -292.552762) (xy 142.43599 -292.596339) (xy 142.451574 -292.64302) (xy 142.459469 -292.691597)
			(xy 142.459964 -292.716204) (xy 142.778475 -292.716204) (xy 142.78257 -292.665476) (xy 142.794749 -292.616062)
			(xy 142.814697 -292.569242) (xy 142.841898 -292.526228) (xy 142.875646 -292.488134) (xy 142.915068 -292.455947)
			(xy 142.959142 -292.430501) (xy 143.006728 -292.412454) (xy 143.056592 -292.402274) (xy 143.107444 -292.400225)
			(xy 143.157965 -292.406359) (xy 143.206849 -292.420519) (xy 143.252828 -292.442336) (xy 143.264317 -292.450266)
			(xy 146.737082 -292.450266) (xy 146.741042 -292.401212) (xy 146.752819 -292.353428) (xy 146.77211 -292.308152)
			(xy 146.798413 -292.266556) (xy 146.831048 -292.229719) (xy 146.869169 -292.198594) (xy 146.91179 -292.173987)
			(xy 146.957806 -292.156535) (xy 147.006025 -292.146691) (xy 147.0552 -292.14471) (xy 147.104055 -292.150642)
			(xy 147.151326 -292.164334) (xy 147.195788 -292.185432) (xy 147.236291 -292.213388) (xy 147.271784 -292.24748)
			(xy 147.301349 -292.286824) (xy 147.32422 -292.330401) (xy 147.339804 -292.377082) (xy 147.347699 -292.425659)
			(xy 147.348194 -292.450266) (xy 147.347699 -292.474873) (xy 147.339804 -292.52345) (xy 147.335829 -292.535356)
			(xy 164.058615 -292.535356) (xy 164.06255 -292.481585) (xy 164.074273 -292.428961) (xy 164.093533 -292.378604)
			(xy 164.119919 -292.331587) (xy 164.152871 -292.288914) (xy 164.191684 -292.251493) (xy 164.235532 -292.220123)
			(xy 164.28348 -292.195471) (xy 164.334507 -292.178063) (xy 164.387525 -292.16827) (xy 164.441404 -292.166301)
			(xy 164.494995 -292.172198) (xy 164.547156 -292.185834) (xy 164.596776 -292.206921) (xy 164.642797 -292.235007)
			(xy 164.684239 -292.269495) (xy 164.720217 -292.309649) (xy 164.749965 -292.354613) (xy 164.77285 -292.40343)
			(xy 164.788382 -292.455059) (xy 164.796232 -292.508399) (xy 164.796724 -292.535356) (xy 164.796232 -292.562313)
			(xy 164.788382 -292.615653) (xy 164.77285 -292.667282) (xy 164.749965 -292.716099) (xy 164.720217 -292.761063)
			(xy 164.684239 -292.801217) (xy 164.642797 -292.835705) (xy 164.596776 -292.863791) (xy 164.547156 -292.884878)
			(xy 164.494995 -292.898514) (xy 164.441404 -292.904411) (xy 164.387525 -292.902442) (xy 164.334507 -292.892649)
			(xy 164.28348 -292.875241) (xy 164.235532 -292.850589) (xy 164.191684 -292.819219) (xy 164.152871 -292.781798)
			(xy 164.119919 -292.739125) (xy 164.093533 -292.692108) (xy 164.074273 -292.641751) (xy 164.06255 -292.589127)
			(xy 164.058615 -292.535356) (xy 147.335829 -292.535356) (xy 147.32422 -292.570131) (xy 147.301349 -292.613708)
			(xy 147.271784 -292.653052) (xy 147.236291 -292.687144) (xy 147.195788 -292.7151) (xy 147.151326 -292.736198)
			(xy 147.104055 -292.74989) (xy 147.0552 -292.755822) (xy 147.006025 -292.753841) (xy 146.957806 -292.743997)
			(xy 146.91179 -292.726545) (xy 146.869169 -292.701938) (xy 146.831048 -292.670813) (xy 146.798413 -292.633976)
			(xy 146.77211 -292.59238) (xy 146.752819 -292.547104) (xy 146.741042 -292.49932) (xy 146.737082 -292.450266)
			(xy 143.264317 -292.450266) (xy 143.294712 -292.471246) (xy 143.331416 -292.506501) (xy 143.361989 -292.547187)
			(xy 143.38564 -292.59225) (xy 143.401756 -292.640524) (xy 143.40992 -292.690758) (xy 143.410432 -292.716204)
			(xy 143.40992 -292.74165) (xy 143.401756 -292.791884) (xy 143.38564 -292.840158) (xy 143.361989 -292.885221)
			(xy 143.331416 -292.925907) (xy 143.294712 -292.961162) (xy 143.252828 -292.990072) (xy 143.206849 -293.011889)
			(xy 143.157965 -293.026049) (xy 143.107444 -293.032183) (xy 143.056592 -293.030134) (xy 143.006728 -293.019954)
			(xy 142.959142 -293.001907) (xy 142.915068 -292.976461) (xy 142.875646 -292.944274) (xy 142.841898 -292.90618)
			(xy 142.814697 -292.863166) (xy 142.794749 -292.816346) (xy 142.78257 -292.766932) (xy 142.778475 -292.716204)
			(xy 142.459964 -292.716204) (xy 142.459469 -292.740811) (xy 142.451574 -292.789388) (xy 142.43599 -292.836069)
			(xy 142.413119 -292.879646) (xy 142.383554 -292.91899) (xy 142.348061 -292.953082) (xy 142.307558 -292.981038)
			(xy 142.263096 -293.002136) (xy 142.215825 -293.015828) (xy 142.16697 -293.02176) (xy 142.117795 -293.019779)
			(xy 142.069576 -293.009935) (xy 142.02356 -292.992483) (xy 141.980939 -292.967876) (xy 141.942818 -292.936751)
			(xy 141.910183 -292.899914) (xy 141.88388 -292.858318) (xy 141.864589 -292.813042) (xy 141.852812 -292.765258)
			(xy 141.848852 -292.716204) (xy 141.530578 -292.716204) (xy 141.530066 -292.74165) (xy 141.521902 -292.791884)
			(xy 141.505786 -292.840158) (xy 141.482135 -292.885221) (xy 141.451562 -292.925907) (xy 141.414858 -292.961162)
			(xy 141.372974 -292.990072) (xy 141.326995 -293.011889) (xy 141.278111 -293.026049) (xy 141.22759 -293.032183)
			(xy 141.176738 -293.030134) (xy 141.126874 -293.019954) (xy 141.079288 -293.001907) (xy 141.035214 -292.976461)
			(xy 140.995792 -292.944274) (xy 140.962044 -292.90618) (xy 140.934843 -292.863166) (xy 140.914895 -292.816346)
			(xy 140.902716 -292.766932) (xy 140.898621 -292.716204) (xy 140.58011 -292.716204) (xy 140.579615 -292.740811)
			(xy 140.57172 -292.789388) (xy 140.556136 -292.836069) (xy 140.533265 -292.879646) (xy 140.5037 -292.91899)
			(xy 140.468207 -292.953082) (xy 140.427704 -292.981038) (xy 140.383242 -293.002136) (xy 140.335971 -293.015828)
			(xy 140.287116 -293.02176) (xy 140.237941 -293.019779) (xy 140.189722 -293.009935) (xy 140.143706 -292.992483)
			(xy 140.101085 -292.967876) (xy 140.062964 -292.936751) (xy 140.030329 -292.899914) (xy 140.004026 -292.858318)
			(xy 139.984735 -292.813042) (xy 139.972958 -292.765258) (xy 139.968998 -292.716204) (xy 139.65047 -292.716204)
			(xy 139.649958 -292.74165) (xy 139.641794 -292.791884) (xy 139.625678 -292.840158) (xy 139.602027 -292.885221)
			(xy 139.571454 -292.925907) (xy 139.53475 -292.961162) (xy 139.492866 -292.990072) (xy 139.446887 -293.011889)
			(xy 139.398003 -293.026049) (xy 139.347482 -293.032183) (xy 139.29663 -293.030134) (xy 139.246766 -293.019954)
			(xy 139.19918 -293.001907) (xy 139.155106 -292.976461) (xy 139.115684 -292.944274) (xy 139.081936 -292.90618)
			(xy 139.054735 -292.863166) (xy 139.034787 -292.816346) (xy 139.022608 -292.766932) (xy 139.018513 -292.716204)
			(xy 138.710416 -292.716204) (xy 138.709904 -292.74165) (xy 138.70174 -292.791884) (xy 138.685624 -292.840158)
			(xy 138.661973 -292.885221) (xy 138.6314 -292.925907) (xy 138.594696 -292.961162) (xy 138.552812 -292.990072)
			(xy 138.506833 -293.011889) (xy 138.457949 -293.026049) (xy 138.407428 -293.032183) (xy 138.356576 -293.030134)
			(xy 138.306712 -293.019954) (xy 138.259126 -293.001907) (xy 138.215052 -292.976461) (xy 138.17563 -292.944274)
			(xy 138.141882 -292.90618) (xy 138.114681 -292.863166) (xy 138.094733 -292.816346) (xy 138.082554 -292.766932)
			(xy 138.078459 -292.716204) (xy 136.830562 -292.716204) (xy 136.83005 -292.74165) (xy 136.821886 -292.791884)
			(xy 136.80577 -292.840158) (xy 136.782119 -292.885221) (xy 136.751546 -292.925907) (xy 136.714842 -292.961162)
			(xy 136.672958 -292.990072) (xy 136.626979 -293.011889) (xy 136.578095 -293.026049) (xy 136.527574 -293.032183)
			(xy 136.476722 -293.030134) (xy 136.426858 -293.019954) (xy 136.379272 -293.001907) (xy 136.335198 -292.976461)
			(xy 136.295776 -292.944274) (xy 136.262028 -292.90618) (xy 136.234827 -292.863166) (xy 136.214879 -292.816346)
			(xy 136.2027 -292.766932) (xy 136.198605 -292.716204) (xy 135.880094 -292.716204) (xy 135.879599 -292.740811)
			(xy 135.871704 -292.789388) (xy 135.85612 -292.836069) (xy 135.833249 -292.879646) (xy 135.803684 -292.91899)
			(xy 135.768191 -292.953082) (xy 135.727688 -292.981038) (xy 135.683226 -293.002136) (xy 135.635955 -293.015828)
			(xy 135.5871 -293.02176) (xy 135.537925 -293.019779) (xy 135.489706 -293.009935) (xy 135.44369 -292.992483)
			(xy 135.401069 -292.967876) (xy 135.362948 -292.936751) (xy 135.330313 -292.899914) (xy 135.30401 -292.858318)
			(xy 135.284719 -292.813042) (xy 135.272942 -292.765258) (xy 135.268982 -292.716204) (xy 134.950454 -292.716204)
			(xy 134.949942 -292.74165) (xy 134.941778 -292.791884) (xy 134.925662 -292.840158) (xy 134.902011 -292.885221)
			(xy 134.871438 -292.925907) (xy 134.834734 -292.961162) (xy 134.79285 -292.990072) (xy 134.746871 -293.011889)
			(xy 134.697987 -293.026049) (xy 134.647466 -293.032183) (xy 134.596614 -293.030134) (xy 134.54675 -293.019954)
			(xy 134.499164 -293.001907) (xy 134.45509 -292.976461) (xy 134.415668 -292.944274) (xy 134.38192 -292.90618)
			(xy 134.354719 -292.863166) (xy 134.334771 -292.816346) (xy 134.322592 -292.766932) (xy 134.318497 -292.716204)
			(xy 133.999986 -292.716204) (xy 133.999491 -292.740811) (xy 133.991596 -292.789388) (xy 133.976012 -292.836069)
			(xy 133.953141 -292.879646) (xy 133.923576 -292.91899) (xy 133.888083 -292.953082) (xy 133.84758 -292.981038)
			(xy 133.803118 -293.002136) (xy 133.755847 -293.015828) (xy 133.706992 -293.02176) (xy 133.657817 -293.019779)
			(xy 133.609598 -293.009935) (xy 133.563582 -292.992483) (xy 133.520961 -292.967876) (xy 133.48284 -292.936751)
			(xy 133.450205 -292.899914) (xy 133.423902 -292.858318) (xy 133.404611 -292.813042) (xy 133.392834 -292.765258)
			(xy 133.388874 -292.716204) (xy 133.0706 -292.716204) (xy 133.070088 -292.74165) (xy 133.061924 -292.791884)
			(xy 133.045808 -292.840158) (xy 133.022157 -292.885221) (xy 132.991584 -292.925907) (xy 132.95488 -292.961162)
			(xy 132.912996 -292.990072) (xy 132.867017 -293.011889) (xy 132.818133 -293.026049) (xy 132.767612 -293.032183)
			(xy 132.71676 -293.030134) (xy 132.666896 -293.019954) (xy 132.61931 -293.001907) (xy 132.575236 -292.976461)
			(xy 132.535814 -292.944274) (xy 132.502066 -292.90618) (xy 132.474865 -292.863166) (xy 132.454917 -292.816346)
			(xy 132.442738 -292.766932) (xy 132.438643 -292.716204) (xy 132.130546 -292.716204) (xy 132.130034 -292.74165)
			(xy 132.12187 -292.791884) (xy 132.105754 -292.840158) (xy 132.082103 -292.885221) (xy 132.05153 -292.925907)
			(xy 132.014826 -292.961162) (xy 131.972942 -292.990072) (xy 131.926963 -293.011889) (xy 131.878079 -293.026049)
			(xy 131.827558 -293.032183) (xy 131.776706 -293.030134) (xy 131.726842 -293.019954) (xy 131.679256 -293.001907)
			(xy 131.635182 -292.976461) (xy 131.59576 -292.944274) (xy 131.562012 -292.90618) (xy 131.534811 -292.863166)
			(xy 131.514863 -292.816346) (xy 131.502684 -292.766932) (xy 131.498589 -292.716204) (xy 130.250438 -292.716204)
			(xy 130.249926 -292.74165) (xy 130.241762 -292.791884) (xy 130.225646 -292.840158) (xy 130.201995 -292.885221)
			(xy 130.171422 -292.925907) (xy 130.134718 -292.961162) (xy 130.092834 -292.990072) (xy 130.046855 -293.011889)
			(xy 129.997971 -293.026049) (xy 129.94745 -293.032183) (xy 129.896598 -293.030134) (xy 129.846734 -293.019954)
			(xy 129.799148 -293.001907) (xy 129.755074 -292.976461) (xy 129.715652 -292.944274) (xy 129.681904 -292.90618)
			(xy 129.654703 -292.863166) (xy 129.634755 -292.816346) (xy 129.622576 -292.766932) (xy 129.618481 -292.716204)
			(xy 129.300556 -292.716204) (xy 129.296384 -292.766546) (xy 129.283981 -292.815519) (xy 129.263687 -292.861782)
			(xy 129.236054 -292.904073) (xy 129.201836 -292.941239) (xy 129.161967 -292.972266) (xy 129.117535 -292.996306)
			(xy 129.069752 -293.012705) (xy 129.019921 -293.021014) (xy 128.994662 -293.021512) (xy 128.969715 -293.021021)
			(xy 128.920484 -293.012915) (xy 128.873226 -292.996911) (xy 128.829201 -292.973433) (xy 128.789581 -292.943107)
			(xy 128.772158 -292.925246) (xy 128.76149 -292.913816) (xy 128.73101 -292.906958) (xy 128.628648 -292.947344)
			(xy 128.621536 -292.950646) (xy 128.614169 -292.955353) (xy 128.602921 -292.968719) (xy 128.596841 -292.985096)
			(xy 128.59639 -292.993826) (xy 128.59639 -293.187882) (xy 128.596694 -293.195546) (xy 128.601362 -293.210147)
			(xy 128.605534 -293.216584) (xy 128.60909 -293.222172) (xy 128.633696 -293.229498) (xy 128.680308 -293.251008)
			(xy 128.722824 -293.27978) (xy 128.760121 -293.315055) (xy 128.791216 -293.355902) (xy 128.815289 -293.401244)
			(xy 128.831704 -293.449885) (xy 128.840028 -293.500542) (xy 128.840484 -293.52621) (xy 129.159012 -293.52621)
			(xy 129.162972 -293.477156) (xy 129.174749 -293.429372) (xy 129.19404 -293.384096) (xy 129.220343 -293.3425)
			(xy 129.252978 -293.305663) (xy 129.291099 -293.274538) (xy 129.33372 -293.249931) (xy 129.379736 -293.232479)
			(xy 129.427955 -293.222635) (xy 129.47713 -293.220654) (xy 129.525985 -293.226586) (xy 129.573256 -293.240278)
			(xy 129.617718 -293.261376) (xy 129.658221 -293.289332) (xy 129.693714 -293.323424) (xy 129.723279 -293.362768)
			(xy 129.74615 -293.406345) (xy 129.761734 -293.453026) (xy 129.769629 -293.501603) (xy 129.770124 -293.52621)
			(xy 130.099066 -293.52621) (xy 130.103026 -293.477156) (xy 130.114803 -293.429372) (xy 130.134094 -293.384096)
			(xy 130.160397 -293.3425) (xy 130.193032 -293.305663) (xy 130.231153 -293.274538) (xy 130.273774 -293.249931)
			(xy 130.31979 -293.232479) (xy 130.368009 -293.222635) (xy 130.417184 -293.220654) (xy 130.466039 -293.226586)
			(xy 130.51331 -293.240278) (xy 130.557772 -293.261376) (xy 130.598275 -293.289332) (xy 130.633768 -293.323424)
			(xy 130.663333 -293.362768) (xy 130.686204 -293.406345) (xy 130.701788 -293.453026) (xy 130.709683 -293.501603)
			(xy 130.710178 -293.52621) (xy 131.038866 -293.52621) (xy 131.042826 -293.477156) (xy 131.054603 -293.429372)
			(xy 131.073894 -293.384096) (xy 131.100197 -293.3425) (xy 131.132832 -293.305663) (xy 131.170953 -293.274538)
			(xy 131.213574 -293.249931) (xy 131.25959 -293.232479) (xy 131.307809 -293.222635) (xy 131.356984 -293.220654)
			(xy 131.405839 -293.226586) (xy 131.45311 -293.240278) (xy 131.497572 -293.261376) (xy 131.538075 -293.289332)
			(xy 131.573568 -293.323424) (xy 131.603133 -293.362768) (xy 131.626004 -293.406345) (xy 131.641588 -293.453026)
			(xy 131.649483 -293.501603) (xy 131.649978 -293.52621) (xy 131.97892 -293.52621) (xy 131.98288 -293.477156)
			(xy 131.994657 -293.429372) (xy 132.013948 -293.384096) (xy 132.040251 -293.3425) (xy 132.072886 -293.305663)
			(xy 132.111007 -293.274538) (xy 132.153628 -293.249931) (xy 132.199644 -293.232479) (xy 132.247863 -293.222635)
			(xy 132.297038 -293.220654) (xy 132.345893 -293.226586) (xy 132.393164 -293.240278) (xy 132.437626 -293.261376)
			(xy 132.478129 -293.289332) (xy 132.513622 -293.323424) (xy 132.543187 -293.362768) (xy 132.566058 -293.406345)
			(xy 132.581642 -293.453026) (xy 132.589537 -293.501603) (xy 132.590032 -293.52621) (xy 132.908543 -293.52621)
			(xy 132.912638 -293.475482) (xy 132.924817 -293.426068) (xy 132.944765 -293.379248) (xy 132.971966 -293.336234)
			(xy 133.005714 -293.29814) (xy 133.045136 -293.265953) (xy 133.08921 -293.240507) (xy 133.136796 -293.22246)
			(xy 133.18666 -293.21228) (xy 133.237512 -293.210231) (xy 133.288033 -293.216365) (xy 133.336917 -293.230525)
			(xy 133.382896 -293.252342) (xy 133.42478 -293.281252) (xy 133.461484 -293.316507) (xy 133.492057 -293.357193)
			(xy 133.515708 -293.402256) (xy 133.531824 -293.45053) (xy 133.539988 -293.500764) (xy 133.5405 -293.52621)
			(xy 133.859028 -293.52621) (xy 133.862988 -293.477156) (xy 133.874765 -293.429372) (xy 133.894056 -293.384096)
			(xy 133.920359 -293.3425) (xy 133.952994 -293.305663) (xy 133.991115 -293.274538) (xy 134.033736 -293.249931)
			(xy 134.079752 -293.232479) (xy 134.127971 -293.222635) (xy 134.177146 -293.220654) (xy 134.226001 -293.226586)
			(xy 134.273272 -293.240278) (xy 134.317734 -293.261376) (xy 134.358237 -293.289332) (xy 134.39373 -293.323424)
			(xy 134.423295 -293.362768) (xy 134.446166 -293.406345) (xy 134.46175 -293.453026) (xy 134.469645 -293.501603)
			(xy 134.47014 -293.52621) (xy 134.788397 -293.52621) (xy 134.792492 -293.475482) (xy 134.804671 -293.426068)
			(xy 134.824619 -293.379248) (xy 134.85182 -293.336234) (xy 134.885568 -293.29814) (xy 134.92499 -293.265953)
			(xy 134.969064 -293.240507) (xy 135.01665 -293.22246) (xy 135.066514 -293.21228) (xy 135.117366 -293.210231)
			(xy 135.167887 -293.216365) (xy 135.216771 -293.230525) (xy 135.26275 -293.252342) (xy 135.304634 -293.281252)
			(xy 135.341338 -293.316507) (xy 135.371911 -293.357193) (xy 135.395562 -293.402256) (xy 135.411678 -293.45053)
			(xy 135.419842 -293.500764) (xy 135.420354 -293.52621) (xy 135.738882 -293.52621) (xy 135.742842 -293.477156)
			(xy 135.754619 -293.429372) (xy 135.77391 -293.384096) (xy 135.800213 -293.3425) (xy 135.832848 -293.305663)
			(xy 135.870969 -293.274538) (xy 135.91359 -293.249931) (xy 135.959606 -293.232479) (xy 136.007825 -293.222635)
			(xy 136.057 -293.220654) (xy 136.105855 -293.226586) (xy 136.153126 -293.240278) (xy 136.197588 -293.261376)
			(xy 136.238091 -293.289332) (xy 136.273584 -293.323424) (xy 136.303149 -293.362768) (xy 136.32602 -293.406345)
			(xy 136.341604 -293.453026) (xy 136.349499 -293.501603) (xy 136.349994 -293.52621) (xy 136.678936 -293.52621)
			(xy 136.682896 -293.477156) (xy 136.694673 -293.429372) (xy 136.713964 -293.384096) (xy 136.740267 -293.3425)
			(xy 136.772902 -293.305663) (xy 136.811023 -293.274538) (xy 136.853644 -293.249931) (xy 136.89966 -293.232479)
			(xy 136.947879 -293.222635) (xy 136.997054 -293.220654) (xy 137.045909 -293.226586) (xy 137.09318 -293.240278)
			(xy 137.137642 -293.261376) (xy 137.178145 -293.289332) (xy 137.213638 -293.323424) (xy 137.243203 -293.362768)
			(xy 137.266074 -293.406345) (xy 137.281658 -293.453026) (xy 137.289553 -293.501603) (xy 137.290048 -293.52621)
			(xy 137.61899 -293.52621) (xy 137.62295 -293.477156) (xy 137.634727 -293.429372) (xy 137.654018 -293.384096)
			(xy 137.680321 -293.3425) (xy 137.712956 -293.305663) (xy 137.751077 -293.274538) (xy 137.793698 -293.249931)
			(xy 137.839714 -293.232479) (xy 137.887933 -293.222635) (xy 137.937108 -293.220654) (xy 137.985963 -293.226586)
			(xy 138.033234 -293.240278) (xy 138.077696 -293.261376) (xy 138.118199 -293.289332) (xy 138.153692 -293.323424)
			(xy 138.183257 -293.362768) (xy 138.206128 -293.406345) (xy 138.221712 -293.453026) (xy 138.229607 -293.501603)
			(xy 138.230102 -293.52621) (xy 138.559044 -293.52621) (xy 138.563004 -293.477156) (xy 138.574781 -293.429372)
			(xy 138.594072 -293.384096) (xy 138.620375 -293.3425) (xy 138.65301 -293.305663) (xy 138.691131 -293.274538)
			(xy 138.733752 -293.249931) (xy 138.779768 -293.232479) (xy 138.827987 -293.222635) (xy 138.877162 -293.220654)
			(xy 138.926017 -293.226586) (xy 138.973288 -293.240278) (xy 139.01775 -293.261376) (xy 139.058253 -293.289332)
			(xy 139.093746 -293.323424) (xy 139.123311 -293.362768) (xy 139.146182 -293.406345) (xy 139.161766 -293.453026)
			(xy 139.169661 -293.501603) (xy 139.170156 -293.52621) (xy 139.488413 -293.52621) (xy 139.492508 -293.475482)
			(xy 139.504687 -293.426068) (xy 139.524635 -293.379248) (xy 139.551836 -293.336234) (xy 139.585584 -293.29814)
			(xy 139.625006 -293.265953) (xy 139.66908 -293.240507) (xy 139.716666 -293.22246) (xy 139.76653 -293.21228)
			(xy 139.817382 -293.210231) (xy 139.867903 -293.216365) (xy 139.916787 -293.230525) (xy 139.962766 -293.252342)
			(xy 140.00465 -293.281252) (xy 140.041354 -293.316507) (xy 140.071927 -293.357193) (xy 140.095578 -293.402256)
			(xy 140.111694 -293.45053) (xy 140.119858 -293.500764) (xy 140.12037 -293.52621) (xy 140.438898 -293.52621)
			(xy 140.442858 -293.477156) (xy 140.454635 -293.429372) (xy 140.473926 -293.384096) (xy 140.500229 -293.3425)
			(xy 140.532864 -293.305663) (xy 140.570985 -293.274538) (xy 140.613606 -293.249931) (xy 140.659622 -293.232479)
			(xy 140.707841 -293.222635) (xy 140.757016 -293.220654) (xy 140.805871 -293.226586) (xy 140.853142 -293.240278)
			(xy 140.897604 -293.261376) (xy 140.938107 -293.289332) (xy 140.9736 -293.323424) (xy 141.003165 -293.362768)
			(xy 141.026036 -293.406345) (xy 141.04162 -293.453026) (xy 141.049515 -293.501603) (xy 141.05001 -293.52621)
			(xy 141.368521 -293.52621) (xy 141.372616 -293.475482) (xy 141.384795 -293.426068) (xy 141.404743 -293.379248)
			(xy 141.431944 -293.336234) (xy 141.465692 -293.29814) (xy 141.505114 -293.265953) (xy 141.549188 -293.240507)
			(xy 141.596774 -293.22246) (xy 141.646638 -293.21228) (xy 141.69749 -293.210231) (xy 141.748011 -293.216365)
			(xy 141.796895 -293.230525) (xy 141.842874 -293.252342) (xy 141.884758 -293.281252) (xy 141.921462 -293.316507)
			(xy 141.952035 -293.357193) (xy 141.975686 -293.402256) (xy 141.991802 -293.45053) (xy 141.999966 -293.500764)
			(xy 142.000478 -293.52621) (xy 142.319006 -293.52621) (xy 142.322966 -293.477156) (xy 142.334743 -293.429372)
			(xy 142.354034 -293.384096) (xy 142.380337 -293.3425) (xy 142.412972 -293.305663) (xy 142.451093 -293.274538)
			(xy 142.493714 -293.249931) (xy 142.53973 -293.232479) (xy 142.587949 -293.222635) (xy 142.637124 -293.220654)
			(xy 142.685979 -293.226586) (xy 142.73325 -293.240278) (xy 142.777712 -293.261376) (xy 142.818215 -293.289332)
			(xy 142.853708 -293.323424) (xy 142.883273 -293.362768) (xy 142.906144 -293.406345) (xy 142.921728 -293.453026)
			(xy 142.929623 -293.501603) (xy 142.930118 -293.52621) (xy 143.258806 -293.52621) (xy 143.262766 -293.477156)
			(xy 143.274543 -293.429372) (xy 143.293834 -293.384096) (xy 143.320137 -293.3425) (xy 143.352772 -293.305663)
			(xy 143.390893 -293.274538) (xy 143.433514 -293.249931) (xy 143.47953 -293.232479) (xy 143.527749 -293.222635)
			(xy 143.576924 -293.220654) (xy 143.625779 -293.226586) (xy 143.67305 -293.240278) (xy 143.717512 -293.261376)
			(xy 143.758015 -293.289332) (xy 143.793508 -293.323424) (xy 143.823073 -293.362768) (xy 143.845944 -293.406345)
			(xy 143.861528 -293.453026) (xy 143.869423 -293.501603) (xy 143.869918 -293.52621) (xy 144.19886 -293.52621)
			(xy 144.20282 -293.477156) (xy 144.214597 -293.429372) (xy 144.233888 -293.384096) (xy 144.260191 -293.3425)
			(xy 144.292826 -293.305663) (xy 144.330947 -293.274538) (xy 144.373568 -293.249931) (xy 144.419584 -293.232479)
			(xy 144.467803 -293.222635) (xy 144.516978 -293.220654) (xy 144.565833 -293.226586) (xy 144.613104 -293.240278)
			(xy 144.657566 -293.261376) (xy 144.698069 -293.289332) (xy 144.733562 -293.323424) (xy 144.763127 -293.362768)
			(xy 144.785998 -293.406345) (xy 144.801582 -293.453026) (xy 144.809477 -293.501603) (xy 144.809972 -293.52621)
			(xy 145.138914 -293.52621) (xy 145.142874 -293.477156) (xy 145.154651 -293.429372) (xy 145.173942 -293.384096)
			(xy 145.200245 -293.3425) (xy 145.23288 -293.305663) (xy 145.271001 -293.274538) (xy 145.313622 -293.249931)
			(xy 145.359638 -293.232479) (xy 145.407857 -293.222635) (xy 145.457032 -293.220654) (xy 145.505887 -293.226586)
			(xy 145.553158 -293.240278) (xy 145.59762 -293.261376) (xy 145.638123 -293.289332) (xy 145.673616 -293.323424)
			(xy 145.703181 -293.362768) (xy 145.714975 -293.38524) (xy 166.774383 -293.38524) (xy 166.778318 -293.331469)
			(xy 166.790041 -293.278845) (xy 166.809301 -293.228488) (xy 166.835687 -293.181471) (xy 166.868639 -293.138798)
			(xy 166.907452 -293.101377) (xy 166.9513 -293.070007) (xy 166.999248 -293.045355) (xy 167.050275 -293.027947)
			(xy 167.103293 -293.018154) (xy 167.157172 -293.016185) (xy 167.210763 -293.022082) (xy 167.262924 -293.035718)
			(xy 167.312544 -293.056805) (xy 167.358565 -293.084891) (xy 167.400007 -293.119379) (xy 167.435985 -293.159533)
			(xy 167.465733 -293.204497) (xy 167.488618 -293.253314) (xy 167.50415 -293.304943) (xy 167.512 -293.358283)
			(xy 167.512492 -293.38524) (xy 171.476162 -293.38524) (xy 171.476647 -293.354044) (xy 171.484464 -293.292142)
			(xy 171.499991 -293.231713) (xy 171.522983 -293.173711) (xy 171.553076 -293.119055) (xy 171.589793 -293.06861)
			(xy 171.632553 -293.023175) (xy 171.68068 -292.983468) (xy 171.706794 -292.966394) (xy 171.716954 -292.95979)
			(xy 171.729146 -292.939978) (xy 171.738544 -292.835838) (xy 171.730162 -292.814248) (xy 171.721272 -292.805866)
			(xy 171.703014 -292.788323) (xy 171.670933 -292.749152) (xy 171.644511 -292.705961) (xy 171.624246 -292.659562)
			(xy 171.610517 -292.610827) (xy 171.603584 -292.560672) (xy 171.603162 -292.535356) (xy 171.603576 -292.510008)
			(xy 171.610514 -292.459788) (xy 171.624266 -292.410993) (xy 171.644572 -292.364541) (xy 171.671051 -292.321309)
			(xy 171.703203 -292.282113) (xy 171.721526 -292.264592) (xy 171.730416 -292.256464) (xy 171.738798 -292.23462)
			(xy 171.729146 -292.13048) (xy 171.716954 -292.110668) (xy 171.706794 -292.104318) (xy 171.680682 -292.087219)
			(xy 171.632561 -292.047466) (xy 171.589805 -292.001992) (xy 171.553091 -291.951515) (xy 171.522998 -291.896831)
			(xy 171.500002 -291.838804) (xy 171.484465 -291.778351) (xy 171.476634 -291.716427) (xy 171.476162 -291.685218)
			(xy 171.47663 -291.654021) (xy 171.48445 -291.592119) (xy 171.499979 -291.531689) (xy 171.522974 -291.473687)
			(xy 171.553069 -291.419031) (xy 171.589788 -291.368587) (xy 171.632551 -291.323152) (xy 171.68068 -291.283446)
			(xy 171.706794 -291.266372) (xy 171.716954 -291.259768) (xy 171.729146 -291.239956) (xy 171.738544 -291.135816)
			(xy 171.730162 -291.114226) (xy 171.721272 -291.105844) (xy 171.701382 -291.086673) (xy 171.666919 -291.043502)
			(xy 171.63928 -290.995674) (xy 171.619083 -290.94426) (xy 171.60678 -290.890408) (xy 171.602646 -290.835323)
			(xy 171.606773 -290.780238) (xy 171.61907 -290.726385) (xy 171.63926 -290.674967) (xy 171.666893 -290.627136)
			(xy 171.701351 -290.583961) (xy 171.721272 -290.564824) (xy 171.730162 -290.556442) (xy 171.738544 -290.534852)
			(xy 171.729146 -290.430712) (xy 171.716954 -290.4109) (xy 171.706794 -290.404296) (xy 171.680685 -290.387217)
			(xy 171.632569 -290.347501) (xy 171.589816 -290.302061) (xy 171.553102 -290.251616) (xy 171.523008 -290.196963)
			(xy 171.50001 -290.138966) (xy 171.484471 -290.078542) (xy 171.476636 -290.016645) (xy 171.476162 -289.98545)
			(xy 171.476641 -289.954241) (xy 171.484465 -289.892315) (xy 171.499997 -289.831861) (xy 171.522991 -289.773832)
			(xy 171.553083 -289.719147) (xy 171.589798 -289.668669) (xy 171.632556 -289.623196) (xy 171.68068 -289.583447)
			(xy 171.706794 -289.56635) (xy 171.716954 -289.56) (xy 171.729146 -289.540188) (xy 171.738798 -289.436048)
			(xy 171.730416 -289.414204) (xy 171.721526 -289.406076) (xy 171.7032 -289.38856) (xy 171.671056 -289.349357)
			(xy 171.644583 -289.306123) (xy 171.624279 -289.259672) (xy 171.610526 -289.210877) (xy 171.603583 -289.16066)
			(xy 171.603162 -289.135312) (xy 171.603559 -289.109994) (xy 171.610486 -289.059833) (xy 171.624211 -289.011092)
			(xy 171.644476 -288.964687) (xy 171.670899 -288.921491) (xy 171.702985 -288.882317) (xy 171.721272 -288.864802)
			(xy 171.730162 -288.85642) (xy 171.738544 -288.83483) (xy 171.729146 -288.73069) (xy 171.716954 -288.710878)
			(xy 171.706794 -288.704274) (xy 171.680675 -288.687209) (xy 171.632559 -288.647491) (xy 171.589806 -288.602049)
			(xy 171.553094 -288.551602) (xy 171.523001 -288.496947) (xy 171.500004 -288.438948) (xy 171.484467 -288.378522)
			(xy 171.476635 -288.316624) (xy 171.476162 -288.285428) (xy 171.476651 -288.254265) (xy 171.484463 -288.192431)
			(xy 171.499963 -288.132063) (xy 171.522906 -288.074115) (xy 171.552932 -288.019498) (xy 171.589566 -287.969076)
			(xy 171.632231 -287.923642) (xy 171.680253 -287.883914) (xy 171.732877 -287.850519) (xy 171.789271 -287.823982)
			(xy 171.848546 -287.804722) (xy 171.909767 -287.793043) (xy 171.97197 -287.78913) (xy 172.034173 -287.793043)
			(xy 172.095394 -287.804722) (xy 172.154669 -287.823982) (xy 172.211063 -287.850519) (xy 172.263687 -287.883914)
			(xy 172.311709 -287.923642) (xy 172.354374 -287.969076) (xy 172.391008 -288.019498) (xy 172.421034 -288.074115)
			(xy 172.443977 -288.132063) (xy 172.459477 -288.192431) (xy 172.467289 -288.254265) (xy 172.467778 -288.285428)
			(xy 172.467374 -288.316627) (xy 172.459547 -288.378533) (xy 172.44401 -288.438965) (xy 172.421007 -288.496969)
			(xy 172.390903 -288.551625) (xy 172.354175 -288.602069) (xy 172.311403 -288.647501) (xy 172.263265 -288.687203)
			(xy 172.237146 -288.704274) (xy 172.226986 -288.710878) (xy 172.214794 -288.73069) (xy 172.205396 -288.83483)
			(xy 172.213778 -288.85642) (xy 172.222668 -288.864802) (xy 172.240966 -288.882304) (xy 172.273042 -288.921485)
			(xy 172.299458 -288.964685) (xy 172.319716 -289.011092) (xy 172.333436 -289.059834) (xy 172.340361 -289.109994)
			(xy 172.340778 -289.135312) (xy 172.340361 -289.16066) (xy 172.333427 -289.21088) (xy 172.319677 -289.259677)
			(xy 172.299371 -289.306129) (xy 172.272891 -289.349361) (xy 172.240738 -289.388556) (xy 172.222414 -289.406076)
			(xy 172.213524 -289.414204) (xy 172.205142 -289.436048) (xy 172.214794 -289.540188) (xy 172.226986 -289.56)
			(xy 172.237146 -289.56635) (xy 172.263252 -289.583457) (xy 172.311372 -289.623209) (xy 172.354127 -289.668683)
			(xy 172.390841 -289.71916) (xy 172.420934 -289.773843) (xy 172.443932 -289.831868) (xy 172.45947 -289.892319)
			(xy 172.467304 -289.954242) (xy 172.467778 -289.98545) (xy 172.467313 -290.016647) (xy 172.459496 -290.07855)
			(xy 172.443968 -290.138982) (xy 172.420974 -290.196985) (xy 172.390879 -290.251641) (xy 172.354158 -290.302086)
			(xy 172.311393 -290.34752) (xy 172.263262 -290.387224) (xy 172.237146 -290.404296) (xy 172.226986 -290.4109)
			(xy 172.214794 -290.430712) (xy 172.205396 -290.534852) (xy 172.213778 -290.556442) (xy 172.222668 -290.564824)
			(xy 172.242629 -290.583926) (xy 172.277096 -290.627105) (xy 172.304737 -290.674942) (xy 172.324934 -290.726367)
			(xy 172.337234 -290.780229) (xy 172.341363 -290.835323) (xy 172.337227 -290.890417) (xy 172.32492 -290.944278)
			(xy 172.304717 -290.9957) (xy 172.27707 -291.043534) (xy 172.242597 -291.086708) (xy 172.222668 -291.105844)
			(xy 172.213778 -291.114226) (xy 172.205396 -291.135816) (xy 172.214794 -291.239956) (xy 172.226986 -291.259768)
			(xy 172.237146 -291.266372) (xy 172.263226 -291.283493) (xy 172.311346 -291.323201) (xy 172.354102 -291.368634)
			(xy 172.390819 -291.419072) (xy 172.420917 -291.473719) (xy 172.443919 -291.531711) (xy 172.459463 -291.592131)
			(xy 172.467302 -291.654024) (xy 172.467778 -291.685218) (xy 172.467302 -291.716427) (xy 172.45948 -291.778354)
			(xy 172.44395 -291.83881) (xy 172.420957 -291.89684) (xy 172.390865 -291.951525) (xy 172.354148 -292.002003)
			(xy 172.311388 -292.047475) (xy 172.263261 -292.087223) (xy 172.237146 -292.104318) (xy 172.226986 -292.110668)
			(xy 172.214794 -292.13048) (xy 172.205142 -292.23462) (xy 172.213524 -292.256464) (xy 172.222414 -292.264592)
			(xy 172.240732 -292.282116) (xy 172.272875 -292.321318) (xy 172.299348 -292.36455) (xy 172.319654 -292.411)
			(xy 172.333409 -292.459793) (xy 172.340355 -292.510009) (xy 172.340778 -292.535356) (xy 175.57623 -292.535356)
			(xy 175.576682 -292.504146) (xy 175.584507 -292.442218) (xy 175.60004 -292.381761) (xy 175.623037 -292.323731)
			(xy 175.653133 -292.269046) (xy 175.689852 -292.218568) (xy 175.732615 -292.173097) (xy 175.780746 -292.133351)
			(xy 175.806862 -292.116256) (xy 175.817022 -292.109906) (xy 175.829214 -292.090094) (xy 175.838866 -291.985954)
			(xy 175.830484 -291.96411) (xy 175.821594 -291.955982) (xy 175.803265 -291.938469) (xy 175.771123 -291.899265)
			(xy 175.744651 -291.85603) (xy 175.724347 -291.809578) (xy 175.710594 -291.760784) (xy 175.703651 -291.710566)
			(xy 175.70323 -291.685218) (xy 175.70364 -291.6599) (xy 175.710566 -291.60974) (xy 175.724289 -291.561)
			(xy 175.744551 -291.514595) (xy 175.770972 -291.471399) (xy 175.803054 -291.432224) (xy 175.82134 -291.414708)
			(xy 175.83023 -291.406326) (xy 175.838612 -291.384736) (xy 175.829214 -291.280596) (xy 175.817022 -291.260784)
			(xy 175.806862 -291.25418) (xy 175.78078 -291.237057) (xy 175.732655 -291.197352) (xy 175.689893 -291.15192)
			(xy 175.653172 -291.101481) (xy 175.623073 -291.046831) (xy 175.600071 -290.988835) (xy 175.58453 -290.928411)
			(xy 175.576697 -290.866514) (xy 175.576695 -290.804123) (xy 175.584523 -290.742225) (xy 175.60006 -290.6818)
			(xy 175.623057 -290.623802) (xy 175.653153 -290.56915) (xy 175.68987 -290.518708) (xy 175.732628 -290.473273)
			(xy 175.780751 -290.433564) (xy 175.806862 -290.416488) (xy 175.817022 -290.409884) (xy 175.829214 -290.390072)
			(xy 175.838612 -290.285932) (xy 175.83023 -290.264342) (xy 175.82134 -290.25596) (xy 175.803073 -290.238426)
			(xy 175.770994 -290.199252) (xy 175.744574 -290.156059) (xy 175.724311 -290.109658) (xy 175.710584 -290.060922)
			(xy 175.703652 -290.010766) (xy 175.70323 -289.98545) (xy 175.703619 -289.960101) (xy 175.710558 -289.909879)
			(xy 175.724314 -289.861082) (xy 175.744625 -289.81463) (xy 175.77111 -289.771399) (xy 175.803268 -289.732205)
			(xy 175.821594 -289.714686) (xy 175.830484 -289.706558) (xy 175.838866 -289.684714) (xy 175.829214 -289.580574)
			(xy 175.817022 -289.560762) (xy 175.806862 -289.554412) (xy 175.78074 -289.537328) (xy 175.73262 -289.497573)
			(xy 175.689866 -289.452096) (xy 175.653153 -289.401615) (xy 175.623062 -289.346929) (xy 175.600067 -289.288901)
			(xy 175.584531 -289.228447) (xy 175.576701 -289.166521) (xy 175.57623 -289.135312) (xy 175.576708 -289.104116)
			(xy 175.584528 -289.042215) (xy 175.600057 -288.981785) (xy 175.623051 -288.923784) (xy 175.653144 -288.869129)
			(xy 175.689862 -288.818684) (xy 175.732622 -288.773248) (xy 175.780749 -288.73354) (xy 175.806862 -288.716466)
			(xy 175.817022 -288.709862) (xy 175.829214 -288.69005) (xy 175.838612 -288.58591) (xy 175.83023 -288.56432)
			(xy 175.82134 -288.555938) (xy 175.803063 -288.538415) (xy 175.770984 -288.499239) (xy 175.744566 -288.456043)
			(xy 175.724304 -288.40964) (xy 175.71058 -288.360902) (xy 175.70365 -288.310745) (xy 175.70323 -288.285428)
			(xy 175.703671 -288.26008) (xy 175.7106 -288.209861) (xy 175.724345 -288.161065) (xy 175.744646 -288.114613)
			(xy 175.771122 -288.071381) (xy 175.803271 -288.032184) (xy 175.821594 -288.014664) (xy 175.830484 -288.006536)
			(xy 175.838866 -287.984692) (xy 175.829214 -287.880552) (xy 175.817022 -287.86074) (xy 175.806862 -287.85439)
			(xy 175.78073 -287.837321) (xy 175.73261 -287.797563) (xy 175.689856 -287.752084) (xy 175.653144 -287.701602)
			(xy 175.623054 -287.646913) (xy 175.600061 -287.588883) (xy 175.584528 -287.528427) (xy 175.5767 -287.4665)
			(xy 175.57623 -287.43529) (xy 175.576719 -287.404127) (xy 175.584531 -287.342293) (xy 175.600031 -287.281925)
			(xy 175.622974 -287.223977) (xy 175.653 -287.16936) (xy 175.689634 -287.118938) (xy 175.732299 -287.073504)
			(xy 175.780321 -287.033776) (xy 175.832945 -287.000381) (xy 175.889339 -286.973844) (xy 175.948614 -286.954584)
			(xy 176.009835 -286.942905) (xy 176.072038 -286.938992) (xy 176.134241 -286.942905) (xy 176.195462 -286.954584)
			(xy 176.254737 -286.973844) (xy 176.311131 -287.000381) (xy 176.363755 -287.033776) (xy 176.411777 -287.073504)
			(xy 176.454442 -287.118938) (xy 176.491076 -287.16936) (xy 176.521102 -287.223977) (xy 176.544045 -287.281925)
			(xy 176.559545 -287.342293) (xy 176.567357 -287.404127) (xy 176.567846 -287.43529) (xy 180.531023 -287.43529)
			(xy 180.534958 -287.381519) (xy 180.546681 -287.328895) (xy 180.565941 -287.278538) (xy 180.592327 -287.231521)
			(xy 180.625279 -287.188848) (xy 180.664092 -287.151427) (xy 180.70794 -287.120057) (xy 180.755888 -287.095405)
			(xy 180.806915 -287.077997) (xy 180.859933 -287.068204) (xy 180.913812 -287.066235) (xy 180.967403 -287.072132)
			(xy 181.019564 -287.085768) (xy 181.069184 -287.106855) (xy 181.115205 -287.134941) (xy 181.156647 -287.169429)
			(xy 181.192625 -287.209583) (xy 181.222373 -287.254547) (xy 181.245258 -287.303364) (xy 181.26079 -287.354993)
			(xy 181.26864 -287.408333) (xy 181.269132 -287.43529) (xy 181.26864 -287.462247) (xy 181.26079 -287.515587)
			(xy 181.245258 -287.567216) (xy 181.222373 -287.616033) (xy 181.192625 -287.660997) (xy 181.156647 -287.701151)
			(xy 181.115205 -287.735639) (xy 181.069184 -287.763725) (xy 181.019564 -287.784812) (xy 180.967403 -287.798448)
			(xy 180.913812 -287.804345) (xy 180.859933 -287.802376) (xy 180.806915 -287.792583) (xy 180.755888 -287.775175)
			(xy 180.70794 -287.750523) (xy 180.664092 -287.719153) (xy 180.625279 -287.681732) (xy 180.592327 -287.639059)
			(xy 180.565941 -287.592042) (xy 180.546681 -287.541685) (xy 180.534958 -287.489061) (xy 180.531023 -287.43529)
			(xy 176.567846 -287.43529) (xy 176.567395 -287.4665) (xy 176.559566 -287.528426) (xy 176.544029 -287.588882)
			(xy 176.521031 -287.64691) (xy 176.490936 -287.701595) (xy 176.454217 -287.752073) (xy 176.411456 -287.797545)
			(xy 176.363329 -287.837293) (xy 176.337214 -287.85439) (xy 176.327054 -287.86074) (xy 176.314862 -287.880552)
			(xy 176.30521 -287.984692) (xy 176.313592 -288.006536) (xy 176.322482 -288.014664) (xy 176.340781 -288.032208)
			(xy 176.372926 -288.071404) (xy 176.399403 -288.114633) (xy 176.419712 -288.161079) (xy 176.433471 -288.209868)
			(xy 176.440421 -288.260082) (xy 176.440846 -288.285428) (xy 176.440407 -288.310745) (xy 176.433488 -288.360904)
			(xy 176.419771 -288.409644) (xy 176.399514 -288.456049) (xy 176.373098 -288.499246) (xy 176.34102 -288.538422)
			(xy 176.322736 -288.555938) (xy 176.313846 -288.56432) (xy 176.305464 -288.58591) (xy 176.314862 -288.69005)
			(xy 176.327054 -288.709862) (xy 176.337214 -288.716466) (xy 176.363307 -288.733568) (xy 176.411423 -288.773281)
			(xy 176.454177 -288.818718) (xy 176.490891 -288.869159) (xy 176.520987 -288.923809) (xy 176.543988 -288.981802)
			(xy 176.559531 -289.042224) (xy 176.56737 -289.104118) (xy 176.567846 -289.135312) (xy 176.567334 -289.16652)
			(xy 176.559514 -289.228444) (xy 176.543987 -289.288898) (xy 176.520998 -289.346926) (xy 176.490911 -289.401611)
			(xy 176.4542 -289.45209) (xy 176.411447 -289.497564) (xy 176.363326 -289.537314) (xy 176.337214 -289.554412)
			(xy 176.327054 -289.560762) (xy 176.314862 -289.580574) (xy 176.30521 -289.684714) (xy 176.313592 -289.706558)
			(xy 176.322482 -289.714686) (xy 176.340791 -289.732219) (xy 176.372936 -289.771418) (xy 176.399411 -289.814649)
			(xy 176.419718 -289.861097) (xy 176.433475 -289.909888) (xy 176.440422 -289.960103) (xy 176.440846 -289.98545)
			(xy 176.440421 -290.010767) (xy 176.4335 -290.060927) (xy 176.41978 -290.109667) (xy 176.39952 -290.156072)
			(xy 176.373102 -290.199269) (xy 176.341021 -290.238444) (xy 176.322736 -290.25596) (xy 176.313846 -290.264342)
			(xy 176.305464 -290.285932) (xy 176.314862 -290.390072) (xy 176.327054 -290.409884) (xy 176.337214 -290.416488)
			(xy 176.36336 -290.433517) (xy 176.41149 -290.473229) (xy 176.454256 -290.518668) (xy 176.490979 -290.569117)
			(xy 176.521079 -290.623775) (xy 176.544081 -290.68178) (xy 176.55962 -290.742213) (xy 176.56745 -290.804119)
			(xy 176.567448 -290.866518) (xy 176.559613 -290.928423) (xy 176.54407 -290.988855) (xy 176.521064 -291.046858)
			(xy 176.490959 -291.101514) (xy 176.454232 -291.15196) (xy 176.411464 -291.197396) (xy 176.36333 -291.237105)
			(xy 176.337214 -291.25418) (xy 176.327054 -291.260784) (xy 176.314862 -291.280596) (xy 176.305464 -291.384736)
			(xy 176.313846 -291.406326) (xy 176.322736 -291.414708) (xy 176.341031 -291.432214) (xy 176.373109 -291.471393)
			(xy 176.399525 -291.514592) (xy 176.419784 -291.560998) (xy 176.433505 -291.60974) (xy 176.440429 -291.6599)
			(xy 176.440846 -291.685218) (xy 176.440412 -291.710566) (xy 176.433478 -291.760784) (xy 176.41973 -291.809579)
			(xy 176.399427 -291.856031) (xy 176.372952 -291.899263) (xy 176.340803 -291.938461) (xy 176.322482 -291.955982)
			(xy 176.313592 -291.96411) (xy 176.30521 -291.985954) (xy 176.314862 -292.090094) (xy 176.327054 -292.109906)
			(xy 176.337214 -292.116256) (xy 176.363316 -292.13337) (xy 176.411437 -292.17312) (xy 176.454193 -292.218592)
			(xy 176.490908 -292.269068) (xy 176.521002 -292.32375) (xy 176.544 -292.381775) (xy 176.559538 -292.442226)
			(xy 176.567372 -292.504148) (xy 176.567846 -292.535356) (xy 176.567357 -292.566519) (xy 176.559545 -292.628353)
			(xy 176.544045 -292.688721) (xy 176.521102 -292.746669) (xy 176.491076 -292.801286) (xy 176.454442 -292.851708)
			(xy 176.411777 -292.897142) (xy 176.363755 -292.93687) (xy 176.311131 -292.970265) (xy 176.254737 -292.996802)
			(xy 176.195462 -293.016062) (xy 176.134241 -293.027741) (xy 176.072038 -293.031654) (xy 176.009835 -293.027741)
			(xy 175.948614 -293.016062) (xy 175.889339 -292.996802) (xy 175.832945 -292.970265) (xy 175.780321 -292.93687)
			(xy 175.732299 -292.897142) (xy 175.689634 -292.851708) (xy 175.653 -292.801286) (xy 175.622974 -292.746669)
			(xy 175.600031 -292.688721) (xy 175.584531 -292.628353) (xy 175.576719 -292.566519) (xy 175.57623 -292.535356)
			(xy 172.340778 -292.535356) (xy 172.340347 -292.560673) (xy 172.333426 -292.610832) (xy 172.319706 -292.659572)
			(xy 172.299448 -292.705977) (xy 172.273031 -292.749173) (xy 172.240952 -292.788349) (xy 172.222668 -292.805866)
			(xy 172.213778 -292.814248) (xy 172.205396 -292.835838) (xy 172.214794 -292.939978) (xy 172.226986 -292.95979)
			(xy 172.237146 -292.966394) (xy 172.263236 -292.983501) (xy 172.311356 -293.023211) (xy 172.354111 -293.068645)
			(xy 172.390828 -293.119086) (xy 172.420924 -293.173735) (xy 172.443925 -293.231729) (xy 172.459467 -293.292151)
			(xy 172.467303 -293.354046) (xy 172.467778 -293.38524) (xy 174.318437 -293.38524) (xy 174.322372 -293.331469)
			(xy 174.334095 -293.278845) (xy 174.353355 -293.228488) (xy 174.379741 -293.181471) (xy 174.412693 -293.138798)
			(xy 174.451506 -293.101377) (xy 174.495354 -293.070007) (xy 174.543302 -293.045355) (xy 174.594329 -293.027947)
			(xy 174.647347 -293.018154) (xy 174.701226 -293.016185) (xy 174.754817 -293.022082) (xy 174.806978 -293.035718)
			(xy 174.856598 -293.056805) (xy 174.902619 -293.084891) (xy 174.944061 -293.119379) (xy 174.980039 -293.159533)
			(xy 175.009787 -293.204497) (xy 175.032672 -293.253314) (xy 175.048204 -293.304943) (xy 175.056054 -293.358283)
			(xy 175.056546 -293.38524) (xy 179.020216 -293.38524) (xy 179.020676 -293.354043) (xy 179.028494 -293.292139)
			(xy 179.044023 -293.231708) (xy 179.067018 -293.173705) (xy 179.097114 -293.119049) (xy 179.133835 -293.068604)
			(xy 179.1766 -293.02317) (xy 179.224732 -292.983466) (xy 179.250848 -292.966394) (xy 179.261008 -292.95979)
			(xy 179.2732 -292.939978) (xy 179.282598 -292.835838) (xy 179.274216 -292.814248) (xy 179.265326 -292.805866)
			(xy 179.247059 -292.788332) (xy 179.214981 -292.749158) (xy 179.188561 -292.705965) (xy 179.168298 -292.659564)
			(xy 179.154571 -292.610828) (xy 179.147638 -292.560672) (xy 179.147216 -292.535356) (xy 179.147613 -292.510007)
			(xy 179.154552 -292.459786) (xy 179.168306 -292.41099) (xy 179.188615 -292.364538) (xy 179.215098 -292.321306)
			(xy 179.247255 -292.282111) (xy 179.26558 -292.264592) (xy 179.27447 -292.256464) (xy 179.282852 -292.23462)
			(xy 179.2732 -292.13048) (xy 179.261008 -292.110668) (xy 179.250848 -292.104318) (xy 179.224726 -292.087235)
			(xy 179.176606 -292.047479) (xy 179.133852 -292.002001) (xy 179.09714 -291.951521) (xy 179.067049 -291.896835)
			(xy 179.044054 -291.838807) (xy 179.028518 -291.778352) (xy 179.020688 -291.716427) (xy 179.020216 -291.685218)
			(xy 179.020659 -291.65402) (xy 179.02848 -291.592116) (xy 179.044011 -291.531684) (xy 179.067008 -291.473681)
			(xy 179.097107 -291.419025) (xy 179.13383 -291.368581) (xy 179.176598 -291.323147) (xy 179.224731 -291.283444)
			(xy 179.250848 -291.266372) (xy 179.261008 -291.259768) (xy 179.2732 -291.239956) (xy 179.282598 -291.135816)
			(xy 179.274216 -291.114226) (xy 179.265326 -291.105844) (xy 179.245434 -291.086674) (xy 179.210966 -291.043505)
			(xy 179.183323 -290.995678) (xy 179.163123 -290.944263) (xy 179.150818 -290.890409) (xy 179.146683 -290.835323)
			(xy 179.150811 -290.780236) (xy 179.163109 -290.726382) (xy 179.183303 -290.674964) (xy 179.21094 -290.627133)
			(xy 179.245402 -290.58396) (xy 179.265326 -290.564824) (xy 179.274216 -290.556442) (xy 179.282598 -290.534852)
			(xy 179.2732 -290.430712) (xy 179.261008 -290.4109) (xy 179.250848 -290.404296) (xy 179.224752 -290.387198)
			(xy 179.176633 -290.347487) (xy 179.133877 -290.302051) (xy 179.097162 -290.251609) (xy 179.067066 -290.196958)
			(xy 179.044066 -290.138963) (xy 179.028525 -290.07854) (xy 179.02069 -290.016645) (xy 179.020216 -289.98545)
			(xy 179.02067 -289.95424) (xy 179.028495 -289.892312) (xy 179.044029 -289.831856) (xy 179.067025 -289.773826)
			(xy 179.097121 -289.719141) (xy 179.13384 -289.668663) (xy 179.176602 -289.623192) (xy 179.224732 -289.583445)
			(xy 179.250848 -289.56635) (xy 179.261008 -289.56) (xy 179.2732 -289.540188) (xy 179.282852 -289.436048)
			(xy 179.27447 -289.414204) (xy 179.26558 -289.406076) (xy 179.247245 -289.388569) (xy 179.215104 -289.349363)
			(xy 179.188633 -289.306127) (xy 179.168331 -289.259674) (xy 179.154579 -289.210879) (xy 179.147637 -289.16066)
			(xy 179.147216 -289.135312) (xy 179.147627 -289.109994) (xy 179.154553 -289.059835) (xy 179.168276 -289.011094)
			(xy 179.188538 -288.96469) (xy 179.214959 -288.921493) (xy 179.247041 -288.882318) (xy 179.265326 -288.864802)
			(xy 179.274216 -288.85642) (xy 179.282598 -288.83483) (xy 179.2732 -288.73069) (xy 179.261008 -288.710878)
			(xy 179.250848 -288.704274) (xy 179.224742 -288.687191) (xy 179.176623 -288.647477) (xy 179.133868 -288.602039)
			(xy 179.097153 -288.551595) (xy 179.067058 -288.496942) (xy 179.04406 -288.438945) (xy 179.028522 -288.37852)
			(xy 179.020689 -288.316623) (xy 179.020216 -288.285428) (xy 179.020705 -288.254265) (xy 179.028517 -288.192431)
			(xy 179.044017 -288.132063) (xy 179.06696 -288.074115) (xy 179.096986 -288.019498) (xy 179.13362 -287.969076)
			(xy 179.176285 -287.923642) (xy 179.224307 -287.883914) (xy 179.276931 -287.850519) (xy 179.333325 -287.823982)
			(xy 179.3926 -287.804722) (xy 179.453821 -287.793043) (xy 179.516024 -287.78913) (xy 179.578227 -287.793043)
			(xy 179.639448 -287.804722) (xy 179.698723 -287.823982) (xy 179.755117 -287.850519) (xy 179.807741 -287.883914)
			(xy 179.855763 -287.923642) (xy 179.898428 -287.969076) (xy 179.935062 -288.019498) (xy 179.965088 -288.074115)
			(xy 179.988031 -288.132063) (xy 180.003531 -288.192431) (xy 180.011343 -288.254265) (xy 180.011832 -288.285428)
			(xy 180.011403 -288.316626) (xy 180.003577 -288.37853) (xy 179.988042 -288.438961) (xy 179.965042 -288.496963)
			(xy 179.934942 -288.551619) (xy 179.898217 -288.602063) (xy 179.85545 -288.647497) (xy 179.807316 -288.687201)
			(xy 179.7812 -288.704274) (xy 179.77104 -288.710878) (xy 179.758848 -288.73069) (xy 179.74945 -288.83483)
			(xy 179.757832 -288.85642) (xy 179.766722 -288.864802) (xy 179.785012 -288.882313) (xy 179.81709 -288.921491)
			(xy 179.843508 -288.964689) (xy 179.863768 -289.011094) (xy 179.877489 -289.059835) (xy 179.884414 -289.109994)
			(xy 179.884832 -289.135312) (xy 179.884398 -289.16066) (xy 179.877465 -289.210878) (xy 179.863717 -289.259674)
			(xy 179.843414 -289.306125) (xy 179.816939 -289.349358) (xy 179.78479 -289.388555) (xy 179.766468 -289.406076)
			(xy 179.757578 -289.414204) (xy 179.749196 -289.436048) (xy 179.758848 -289.540188) (xy 179.77104 -289.56)
			(xy 179.7812 -289.56635) (xy 179.807296 -289.583473) (xy 179.855418 -289.623222) (xy 179.898174 -289.668692)
			(xy 179.93489 -289.719166) (xy 179.964985 -289.773847) (xy 179.987984 -289.831871) (xy 180.003523 -289.892321)
			(xy 180.011358 -289.954242) (xy 180.011832 -289.98545) (xy 180.011341 -290.016646) (xy 180.003526 -290.078547)
			(xy 179.988 -290.138977) (xy 179.965009 -290.196979) (xy 179.934917 -290.251635) (xy 179.8982 -290.30208)
			(xy 179.85544 -290.347515) (xy 179.807313 -290.387222) (xy 179.7812 -290.404296) (xy 179.77104 -290.4109)
			(xy 179.758848 -290.430712) (xy 179.74945 -290.534852) (xy 179.757832 -290.556442) (xy 179.766722 -290.564824)
			(xy 179.78668 -290.583927) (xy 179.821143 -290.627108) (xy 179.84878 -290.674945) (xy 179.868973 -290.72637)
			(xy 179.881272 -290.78023) (xy 179.8854 -290.835323) (xy 179.881265 -290.890415) (xy 179.86896 -290.944275)
			(xy 179.84876 -290.995696) (xy 179.821117 -291.04353) (xy 179.786649 -291.086707) (xy 179.766722 -291.105844)
			(xy 179.757832 -291.114226) (xy 179.74945 -291.135816) (xy 179.758848 -291.239956) (xy 179.77104 -291.259768)
			(xy 179.7812 -291.266372) (xy 179.807293 -291.283475) (xy 179.85541 -291.323187) (xy 179.898163 -291.368623)
			(xy 179.934878 -291.419065) (xy 179.964974 -291.473714) (xy 179.987975 -291.531708) (xy 180.003518 -291.59213)
			(xy 180.011356 -291.654024) (xy 180.011832 -291.685218) (xy 180.011331 -291.716426) (xy 180.00351 -291.778351)
			(xy 179.987982 -291.838806) (xy 179.964992 -291.896834) (xy 179.934903 -291.951519) (xy 179.898191 -292.001998)
			(xy 179.855435 -292.047471) (xy 179.807313 -292.087221) (xy 179.7812 -292.104318) (xy 179.77104 -292.110668)
			(xy 179.758848 -292.13048) (xy 179.749196 -292.23462) (xy 179.757578 -292.256464) (xy 179.766468 -292.264592)
			(xy 179.784778 -292.282125) (xy 179.816923 -292.321324) (xy 179.843398 -292.364554) (xy 179.863706 -292.411003)
			(xy 179.877462 -292.459794) (xy 179.884409 -292.510009) (xy 179.884832 -292.535356) (xy 183.120284 -292.535356)
			(xy 183.120757 -292.504147) (xy 183.128581 -292.44222) (xy 183.144113 -292.381765) (xy 183.167107 -292.323736)
			(xy 183.1972 -292.269051) (xy 183.233916 -292.218573) (xy 183.276675 -292.173101) (xy 183.324802 -292.133352)
			(xy 183.350916 -292.116256) (xy 183.361076 -292.109906) (xy 183.373268 -292.090094) (xy 183.38292 -291.985954)
			(xy 183.374538 -291.96411) (xy 183.365648 -291.955982) (xy 183.347329 -291.938459) (xy 183.315184 -291.899258)
			(xy 183.288709 -291.856026) (xy 183.268404 -291.809575) (xy 183.254649 -291.760782) (xy 183.247705 -291.710565)
			(xy 183.247284 -291.685218) (xy 183.247709 -291.659901) (xy 183.254633 -291.609742) (xy 183.268355 -291.561002)
			(xy 183.288614 -291.514598) (xy 183.315032 -291.471401) (xy 183.34711 -291.432225) (xy 183.365394 -291.414708)
			(xy 183.374284 -291.406326) (xy 183.382666 -291.384736) (xy 183.373268 -291.280596) (xy 183.361076 -291.260784)
			(xy 183.350916 -291.25418) (xy 183.324832 -291.237059) (xy 183.276701 -291.197356) (xy 183.233935 -291.151926)
			(xy 183.19721 -291.101487) (xy 183.167107 -291.046836) (xy 183.144103 -290.988839) (xy 183.12856 -290.928414)
			(xy 183.120726 -290.866515) (xy 183.120724 -290.804122) (xy 183.128553 -290.742222) (xy 183.144091 -290.681795)
			(xy 183.167092 -290.623797) (xy 183.197191 -290.569144) (xy 183.233912 -290.518702) (xy 183.276675 -290.473268)
			(xy 183.324803 -290.433562) (xy 183.350916 -290.416488) (xy 183.361076 -290.409884) (xy 183.373268 -290.390072)
			(xy 183.382666 -290.285932) (xy 183.374284 -290.264342) (xy 183.365394 -290.25596) (xy 183.347137 -290.238416)
			(xy 183.315055 -290.199245) (xy 183.288633 -290.156055) (xy 183.268367 -290.109656) (xy 183.254639 -290.060921)
			(xy 183.247706 -290.010766) (xy 183.247284 -289.98545) (xy 183.247687 -289.960101) (xy 183.254626 -289.909881)
			(xy 183.268379 -289.861085) (xy 183.288688 -289.814633) (xy 183.315169 -289.771402) (xy 183.347324 -289.732206)
			(xy 183.365648 -289.714686) (xy 183.374538 -289.706558) (xy 183.38292 -289.684714) (xy 183.373268 -289.580574)
			(xy 183.361076 -289.560762) (xy 183.350916 -289.554412) (xy 183.324807 -289.537309) (xy 183.276684 -289.497558)
			(xy 183.233928 -289.452085) (xy 183.197213 -289.401608) (xy 183.167119 -289.346924) (xy 183.144123 -289.288898)
			(xy 183.128587 -289.228445) (xy 183.120756 -289.166521) (xy 183.120284 -289.135312) (xy 183.120737 -289.104114)
			(xy 183.128558 -289.042212) (xy 183.144089 -288.981781) (xy 183.167085 -288.923778) (xy 183.197182 -288.869122)
			(xy 183.233904 -288.818678) (xy 183.276669 -288.773244) (xy 183.3248 -288.733539) (xy 183.350916 -288.716466)
			(xy 183.361076 -288.709862) (xy 183.373268 -288.69005) (xy 183.382666 -288.58591) (xy 183.374284 -288.56432)
			(xy 183.365394 -288.555938) (xy 183.347127 -288.538404) (xy 183.315046 -288.499232) (xy 183.288625 -288.456039)
			(xy 183.268361 -288.409638) (xy 183.254634 -288.360901) (xy 183.247704 -288.310744) (xy 183.247284 -288.285428)
			(xy 183.247739 -288.260081) (xy 183.254667 -288.209863) (xy 183.268411 -288.161068) (xy 183.28871 -288.114616)
			(xy 183.315182 -288.071383) (xy 183.347327 -288.032185) (xy 183.365648 -288.014664) (xy 183.374538 -288.006536)
			(xy 183.38292 -287.984692) (xy 183.373268 -287.880552) (xy 183.361076 -287.86074) (xy 183.350916 -287.85439)
			(xy 183.324797 -287.837302) (xy 183.276674 -287.797549) (xy 183.233918 -287.752073) (xy 183.197204 -287.701594)
			(xy 183.167112 -287.646908) (xy 183.144117 -287.58888) (xy 183.128583 -287.528425) (xy 183.120754 -287.466499)
			(xy 183.120284 -287.43529) (xy 183.120773 -287.404127) (xy 183.128585 -287.342293) (xy 183.144085 -287.281925)
			(xy 183.167028 -287.223977) (xy 183.197054 -287.16936) (xy 183.233688 -287.118938) (xy 183.276353 -287.073504)
			(xy 183.324375 -287.033776) (xy 183.376999 -287.000381) (xy 183.433393 -286.973844) (xy 183.492668 -286.954584)
			(xy 183.553889 -286.942905) (xy 183.616092 -286.938992) (xy 183.678295 -286.942905) (xy 183.739516 -286.954584)
			(xy 183.798791 -286.973844) (xy 183.855185 -287.000381) (xy 183.907809 -287.033776) (xy 183.955831 -287.073504)
			(xy 183.998496 -287.118938) (xy 184.03513 -287.16936) (xy 184.065156 -287.223977) (xy 184.088099 -287.281925)
			(xy 184.103599 -287.342293) (xy 184.111411 -287.404127) (xy 184.1119 -287.43529) (xy 184.11147 -287.466501)
			(xy 184.10364 -287.528429) (xy 184.088102 -287.588886) (xy 184.065102 -287.646915) (xy 184.035003 -287.701601)
			(xy 183.998281 -287.752078) (xy 183.955516 -287.797549) (xy 183.907385 -287.837295) (xy 183.881268 -287.85439)
			(xy 183.871108 -287.86074) (xy 183.858916 -287.880552) (xy 183.849264 -287.984692) (xy 183.857646 -288.006536)
			(xy 183.866536 -288.014664) (xy 183.884826 -288.032217) (xy 183.916974 -288.07141) (xy 183.943453 -288.114637)
			(xy 183.963764 -288.161081) (xy 183.977524 -288.209869) (xy 183.984475 -288.260082) (xy 183.9849 -288.285428)
			(xy 183.984444 -288.310744) (xy 183.977526 -288.360902) (xy 183.963812 -288.409641) (xy 183.943558 -288.456046)
			(xy 183.917145 -288.499243) (xy 183.885071 -288.53842) (xy 183.86679 -288.555938) (xy 183.8579 -288.56432)
			(xy 183.849518 -288.58591) (xy 183.858916 -288.69005) (xy 183.871108 -288.709862) (xy 183.881268 -288.716466)
			(xy 183.907351 -288.733584) (xy 183.955469 -288.773293) (xy 183.998224 -288.818726) (xy 184.034941 -288.869165)
			(xy 184.065038 -288.923813) (xy 184.088041 -288.981805) (xy 184.103584 -289.042225) (xy 184.111424 -289.104118)
			(xy 184.1119 -289.135312) (xy 184.111409 -289.166521) (xy 184.103589 -289.228447) (xy 184.08806 -289.288902)
			(xy 184.065069 -289.346931) (xy 184.034978 -289.401616) (xy 183.998264 -289.452095) (xy 183.955507 -289.497567)
			(xy 183.907382 -289.537316) (xy 183.881268 -289.554412) (xy 183.871108 -289.560762) (xy 183.858916 -289.580574)
			(xy 183.849264 -289.684714) (xy 183.857646 -289.706558) (xy 183.866536 -289.714686) (xy 183.884837 -289.732228)
			(xy 183.916984 -289.771424) (xy 183.943461 -289.814652) (xy 183.96377 -289.861099) (xy 183.977528 -289.909889)
			(xy 183.984476 -289.960104) (xy 183.9849 -289.98545) (xy 183.984459 -290.010767) (xy 183.977538 -290.060925)
			(xy 183.963821 -290.109664) (xy 183.943564 -290.156069) (xy 183.917149 -290.199266) (xy 183.885073 -290.238443)
			(xy 183.86679 -290.25596) (xy 183.8579 -290.264342) (xy 183.849518 -290.285932) (xy 183.858916 -290.390072)
			(xy 183.871108 -290.409884) (xy 183.881268 -290.416488) (xy 183.907411 -290.433518) (xy 183.955537 -290.473233)
			(xy 183.998298 -290.518674) (xy 184.035017 -290.569123) (xy 184.065114 -290.623781) (xy 184.088113 -290.681785)
			(xy 184.10365 -290.742216) (xy 184.111479 -290.80412) (xy 184.111477 -290.866517) (xy 184.103643 -290.92842)
			(xy 184.088102 -290.98885) (xy 184.065099 -291.046852) (xy 184.034998 -291.101508) (xy 183.998275 -291.151954)
			(xy 183.955511 -291.197392) (xy 183.907382 -291.237103) (xy 183.881268 -291.25418) (xy 183.871108 -291.260784)
			(xy 183.858916 -291.280596) (xy 183.849518 -291.384736) (xy 183.8579 -291.406326) (xy 183.86679 -291.414708)
			(xy 183.885095 -291.432203) (xy 183.91717 -291.471386) (xy 183.943584 -291.514587) (xy 183.963841 -291.560996)
			(xy 183.97756 -291.609739) (xy 183.984483 -291.6599) (xy 183.9849 -291.685218) (xy 183.98448 -291.710566)
			(xy 183.977546 -291.760786) (xy 183.963796 -291.809582) (xy 183.94349 -291.856034) (xy 183.917012 -291.899266)
			(xy 183.88486 -291.938462) (xy 183.866536 -291.955982) (xy 183.857646 -291.96411) (xy 183.849264 -291.985954)
			(xy 183.858916 -292.090094) (xy 183.871108 -292.109906) (xy 183.881268 -292.116256) (xy 183.907359 -292.133386)
			(xy 183.955482 -292.173132) (xy 183.99824 -292.218601) (xy 184.034957 -292.269074) (xy 184.065053 -292.323754)
			(xy 184.088052 -292.381777) (xy 184.103592 -292.442227) (xy 184.111426 -292.504148) (xy 184.1119 -292.535356)
			(xy 184.111411 -292.566519) (xy 184.103599 -292.628353) (xy 184.088099 -292.688721) (xy 184.065156 -292.746669)
			(xy 184.03513 -292.801286) (xy 183.998496 -292.851708) (xy 183.955831 -292.897142) (xy 183.907809 -292.93687)
			(xy 183.855185 -292.970265) (xy 183.798791 -292.996802) (xy 183.739516 -293.016062) (xy 183.678295 -293.027741)
			(xy 183.616092 -293.031654) (xy 183.553889 -293.027741) (xy 183.492668 -293.016062) (xy 183.433393 -292.996802)
			(xy 183.376999 -292.970265) (xy 183.324375 -292.93687) (xy 183.276353 -292.897142) (xy 183.233688 -292.851708)
			(xy 183.197054 -292.801286) (xy 183.167028 -292.746669) (xy 183.144085 -292.688721) (xy 183.128585 -292.628353)
			(xy 183.120773 -292.566519) (xy 183.120284 -292.535356) (xy 179.884832 -292.535356) (xy 179.884416 -292.560674)
			(xy 179.877493 -292.610834) (xy 179.863772 -292.659575) (xy 179.843511 -292.70598) (xy 179.81709 -292.749176)
			(xy 179.785008 -292.78835) (xy 179.766722 -292.805866) (xy 179.757832 -292.814248) (xy 179.74945 -292.835838)
			(xy 179.758848 -292.939978) (xy 179.77104 -292.95979) (xy 179.7812 -292.966394) (xy 179.807303 -292.983482)
			(xy 179.85542 -293.023197) (xy 179.898173 -293.068635) (xy 179.934887 -293.119078) (xy 179.964982 -293.17373)
			(xy 179.987981 -293.231726) (xy 180.003521 -293.292149) (xy 180.011357 -293.354045) (xy 180.011832 -293.38524)
			(xy 181.862491 -293.38524) (xy 181.866426 -293.331469) (xy 181.878149 -293.278845) (xy 181.897409 -293.228488)
			(xy 181.923795 -293.181471) (xy 181.956747 -293.138798) (xy 181.99556 -293.101377) (xy 182.039408 -293.070007)
			(xy 182.087356 -293.045355) (xy 182.138383 -293.027947) (xy 182.191401 -293.018154) (xy 182.24528 -293.016185)
			(xy 182.298871 -293.022082) (xy 182.351032 -293.035718) (xy 182.400652 -293.056805) (xy 182.446673 -293.084891)
			(xy 182.488115 -293.119379) (xy 182.524093 -293.159533) (xy 182.553841 -293.204497) (xy 182.576726 -293.253314)
			(xy 182.592258 -293.304943) (xy 182.600108 -293.358283) (xy 182.6006 -293.38524) (xy 182.600108 -293.412197)
			(xy 182.592258 -293.465537) (xy 182.576726 -293.517166) (xy 182.553841 -293.565983) (xy 182.524093 -293.610947)
			(xy 182.488115 -293.651101) (xy 182.446673 -293.685589) (xy 182.400652 -293.713675) (xy 182.351032 -293.734762)
			(xy 182.298871 -293.748398) (xy 182.24528 -293.754295) (xy 182.191401 -293.752326) (xy 182.138383 -293.742533)
			(xy 182.087356 -293.725125) (xy 182.039408 -293.700473) (xy 181.99556 -293.669103) (xy 181.956747 -293.631682)
			(xy 181.923795 -293.589009) (xy 181.897409 -293.541992) (xy 181.878149 -293.491635) (xy 181.866426 -293.439011)
			(xy 181.862491 -293.38524) (xy 180.011832 -293.38524) (xy 180.011343 -293.416403) (xy 180.003531 -293.478237)
			(xy 179.988031 -293.538605) (xy 179.965088 -293.596553) (xy 179.935062 -293.65117) (xy 179.898428 -293.701592)
			(xy 179.855763 -293.747026) (xy 179.807741 -293.786754) (xy 179.755117 -293.820149) (xy 179.698723 -293.846686)
			(xy 179.639448 -293.865946) (xy 179.578227 -293.877625) (xy 179.516024 -293.881538) (xy 179.453821 -293.877625)
			(xy 179.3926 -293.865946) (xy 179.333325 -293.846686) (xy 179.276931 -293.820149) (xy 179.224307 -293.786754)
			(xy 179.176285 -293.747026) (xy 179.13362 -293.701592) (xy 179.096986 -293.65117) (xy 179.06696 -293.596553)
			(xy 179.044017 -293.538605) (xy 179.028517 -293.478237) (xy 179.020705 -293.416403) (xy 179.020216 -293.38524)
			(xy 175.056546 -293.38524) (xy 175.056054 -293.412197) (xy 175.048204 -293.465537) (xy 175.032672 -293.517166)
			(xy 175.009787 -293.565983) (xy 174.980039 -293.610947) (xy 174.944061 -293.651101) (xy 174.902619 -293.685589)
			(xy 174.856598 -293.713675) (xy 174.806978 -293.734762) (xy 174.754817 -293.748398) (xy 174.701226 -293.754295)
			(xy 174.647347 -293.752326) (xy 174.594329 -293.742533) (xy 174.543302 -293.725125) (xy 174.495354 -293.700473)
			(xy 174.451506 -293.669103) (xy 174.412693 -293.631682) (xy 174.379741 -293.589009) (xy 174.353355 -293.541992)
			(xy 174.334095 -293.491635) (xy 174.322372 -293.439011) (xy 174.318437 -293.38524) (xy 172.467778 -293.38524)
			(xy 172.467289 -293.416403) (xy 172.459477 -293.478237) (xy 172.443977 -293.538605) (xy 172.421034 -293.596553)
			(xy 172.391008 -293.65117) (xy 172.354374 -293.701592) (xy 172.311709 -293.747026) (xy 172.263687 -293.786754)
			(xy 172.211063 -293.820149) (xy 172.154669 -293.846686) (xy 172.095394 -293.865946) (xy 172.034173 -293.877625)
			(xy 171.97197 -293.881538) (xy 171.909767 -293.877625) (xy 171.848546 -293.865946) (xy 171.789271 -293.846686)
			(xy 171.732877 -293.820149) (xy 171.680253 -293.786754) (xy 171.632231 -293.747026) (xy 171.589566 -293.701592)
			(xy 171.552932 -293.65117) (xy 171.522906 -293.596553) (xy 171.499963 -293.538605) (xy 171.484463 -293.478237)
			(xy 171.476651 -293.416403) (xy 171.476162 -293.38524) (xy 167.512492 -293.38524) (xy 167.512 -293.412197)
			(xy 167.50415 -293.465537) (xy 167.488618 -293.517166) (xy 167.465733 -293.565983) (xy 167.435985 -293.610947)
			(xy 167.400007 -293.651101) (xy 167.358565 -293.685589) (xy 167.312544 -293.713675) (xy 167.262924 -293.734762)
			(xy 167.210763 -293.748398) (xy 167.157172 -293.754295) (xy 167.103293 -293.752326) (xy 167.050275 -293.742533)
			(xy 166.999248 -293.725125) (xy 166.9513 -293.700473) (xy 166.907452 -293.669103) (xy 166.868639 -293.631682)
			(xy 166.835687 -293.589009) (xy 166.809301 -293.541992) (xy 166.790041 -293.491635) (xy 166.778318 -293.439011)
			(xy 166.774383 -293.38524) (xy 145.714975 -293.38524) (xy 145.726052 -293.406345) (xy 145.741636 -293.453026)
			(xy 145.749531 -293.501603) (xy 145.750026 -293.52621) (xy 145.749531 -293.550817) (xy 145.741636 -293.599394)
			(xy 145.726052 -293.646075) (xy 145.703181 -293.689652) (xy 145.673616 -293.728996) (xy 145.638123 -293.763088)
			(xy 145.59762 -293.791044) (xy 145.553158 -293.812142) (xy 145.505887 -293.825834) (xy 145.457032 -293.831766)
			(xy 145.407857 -293.829785) (xy 145.359638 -293.819941) (xy 145.313622 -293.802489) (xy 145.271001 -293.777882)
			(xy 145.23288 -293.746757) (xy 145.200245 -293.70992) (xy 145.173942 -293.668324) (xy 145.154651 -293.623048)
			(xy 145.142874 -293.575264) (xy 145.138914 -293.52621) (xy 144.809972 -293.52621) (xy 144.809477 -293.550817)
			(xy 144.801582 -293.599394) (xy 144.785998 -293.646075) (xy 144.763127 -293.689652) (xy 144.733562 -293.728996)
			(xy 144.698069 -293.763088) (xy 144.657566 -293.791044) (xy 144.613104 -293.812142) (xy 144.565833 -293.825834)
			(xy 144.516978 -293.831766) (xy 144.467803 -293.829785) (xy 144.419584 -293.819941) (xy 144.373568 -293.802489)
			(xy 144.330947 -293.777882) (xy 144.292826 -293.746757) (xy 144.260191 -293.70992) (xy 144.233888 -293.668324)
			(xy 144.214597 -293.623048) (xy 144.20282 -293.575264) (xy 144.19886 -293.52621) (xy 143.869918 -293.52621)
			(xy 143.869423 -293.550817) (xy 143.861528 -293.599394) (xy 143.845944 -293.646075) (xy 143.823073 -293.689652)
			(xy 143.793508 -293.728996) (xy 143.758015 -293.763088) (xy 143.717512 -293.791044) (xy 143.67305 -293.812142)
			(xy 143.625779 -293.825834) (xy 143.576924 -293.831766) (xy 143.527749 -293.829785) (xy 143.47953 -293.819941)
			(xy 143.433514 -293.802489) (xy 143.390893 -293.777882) (xy 143.352772 -293.746757) (xy 143.320137 -293.70992)
			(xy 143.293834 -293.668324) (xy 143.274543 -293.623048) (xy 143.262766 -293.575264) (xy 143.258806 -293.52621)
			(xy 142.930118 -293.52621) (xy 142.929623 -293.550817) (xy 142.921728 -293.599394) (xy 142.906144 -293.646075)
			(xy 142.883273 -293.689652) (xy 142.853708 -293.728996) (xy 142.818215 -293.763088) (xy 142.777712 -293.791044)
			(xy 142.73325 -293.812142) (xy 142.685979 -293.825834) (xy 142.637124 -293.831766) (xy 142.587949 -293.829785)
			(xy 142.53973 -293.819941) (xy 142.493714 -293.802489) (xy 142.451093 -293.777882) (xy 142.412972 -293.746757)
			(xy 142.380337 -293.70992) (xy 142.354034 -293.668324) (xy 142.334743 -293.623048) (xy 142.322966 -293.575264)
			(xy 142.319006 -293.52621) (xy 142.000478 -293.52621) (xy 141.999966 -293.551656) (xy 141.991802 -293.60189)
			(xy 141.975686 -293.650164) (xy 141.952035 -293.695227) (xy 141.921462 -293.735913) (xy 141.884758 -293.771168)
			(xy 141.842874 -293.800078) (xy 141.796895 -293.821895) (xy 141.748011 -293.836055) (xy 141.69749 -293.842189)
			(xy 141.646638 -293.84014) (xy 141.596774 -293.82996) (xy 141.549188 -293.811913) (xy 141.505114 -293.786467)
			(xy 141.465692 -293.75428) (xy 141.431944 -293.716186) (xy 141.404743 -293.673172) (xy 141.384795 -293.626352)
			(xy 141.372616 -293.576938) (xy 141.368521 -293.52621) (xy 141.05001 -293.52621) (xy 141.049515 -293.550817)
			(xy 141.04162 -293.599394) (xy 141.026036 -293.646075) (xy 141.003165 -293.689652) (xy 140.9736 -293.728996)
			(xy 140.938107 -293.763088) (xy 140.897604 -293.791044) (xy 140.853142 -293.812142) (xy 140.805871 -293.825834)
			(xy 140.757016 -293.831766) (xy 140.707841 -293.829785) (xy 140.659622 -293.819941) (xy 140.613606 -293.802489)
			(xy 140.570985 -293.777882) (xy 140.532864 -293.746757) (xy 140.500229 -293.70992) (xy 140.473926 -293.668324)
			(xy 140.454635 -293.623048) (xy 140.442858 -293.575264) (xy 140.438898 -293.52621) (xy 140.12037 -293.52621)
			(xy 140.119858 -293.551656) (xy 140.111694 -293.60189) (xy 140.095578 -293.650164) (xy 140.071927 -293.695227)
			(xy 140.041354 -293.735913) (xy 140.00465 -293.771168) (xy 139.962766 -293.800078) (xy 139.916787 -293.821895)
			(xy 139.867903 -293.836055) (xy 139.817382 -293.842189) (xy 139.76653 -293.84014) (xy 139.716666 -293.82996)
			(xy 139.66908 -293.811913) (xy 139.625006 -293.786467) (xy 139.585584 -293.75428) (xy 139.551836 -293.716186)
			(xy 139.524635 -293.673172) (xy 139.504687 -293.626352) (xy 139.492508 -293.576938) (xy 139.488413 -293.52621)
			(xy 139.170156 -293.52621) (xy 139.169661 -293.550817) (xy 139.161766 -293.599394) (xy 139.146182 -293.646075)
			(xy 139.123311 -293.689652) (xy 139.093746 -293.728996) (xy 139.058253 -293.763088) (xy 139.01775 -293.791044)
			(xy 138.973288 -293.812142) (xy 138.926017 -293.825834) (xy 138.877162 -293.831766) (xy 138.827987 -293.829785)
			(xy 138.779768 -293.819941) (xy 138.733752 -293.802489) (xy 138.691131 -293.777882) (xy 138.65301 -293.746757)
			(xy 138.620375 -293.70992) (xy 138.594072 -293.668324) (xy 138.574781 -293.623048) (xy 138.563004 -293.575264)
			(xy 138.559044 -293.52621) (xy 138.230102 -293.52621) (xy 138.229607 -293.550817) (xy 138.221712 -293.599394)
			(xy 138.206128 -293.646075) (xy 138.183257 -293.689652) (xy 138.153692 -293.728996) (xy 138.118199 -293.763088)
			(xy 138.077696 -293.791044) (xy 138.033234 -293.812142) (xy 137.985963 -293.825834) (xy 137.937108 -293.831766)
			(xy 137.887933 -293.829785) (xy 137.839714 -293.819941) (xy 137.793698 -293.802489) (xy 137.751077 -293.777882)
			(xy 137.712956 -293.746757) (xy 137.680321 -293.70992) (xy 137.654018 -293.668324) (xy 137.634727 -293.623048)
			(xy 137.62295 -293.575264) (xy 137.61899 -293.52621) (xy 137.290048 -293.52621) (xy 137.289553 -293.550817)
			(xy 137.281658 -293.599394) (xy 137.266074 -293.646075) (xy 137.243203 -293.689652) (xy 137.213638 -293.728996)
			(xy 137.178145 -293.763088) (xy 137.137642 -293.791044) (xy 137.09318 -293.812142) (xy 137.045909 -293.825834)
			(xy 136.997054 -293.831766) (xy 136.947879 -293.829785) (xy 136.89966 -293.819941) (xy 136.853644 -293.802489)
			(xy 136.811023 -293.777882) (xy 136.772902 -293.746757) (xy 136.740267 -293.70992) (xy 136.713964 -293.668324)
			(xy 136.694673 -293.623048) (xy 136.682896 -293.575264) (xy 136.678936 -293.52621) (xy 136.349994 -293.52621)
			(xy 136.349499 -293.550817) (xy 136.341604 -293.599394) (xy 136.32602 -293.646075) (xy 136.303149 -293.689652)
			(xy 136.273584 -293.728996) (xy 136.238091 -293.763088) (xy 136.197588 -293.791044) (xy 136.153126 -293.812142)
			(xy 136.105855 -293.825834) (xy 136.057 -293.831766) (xy 136.007825 -293.829785) (xy 135.959606 -293.819941)
			(xy 135.91359 -293.802489) (xy 135.870969 -293.777882) (xy 135.832848 -293.746757) (xy 135.800213 -293.70992)
			(xy 135.77391 -293.668324) (xy 135.754619 -293.623048) (xy 135.742842 -293.575264) (xy 135.738882 -293.52621)
			(xy 135.420354 -293.52621) (xy 135.419842 -293.551656) (xy 135.411678 -293.60189) (xy 135.395562 -293.650164)
			(xy 135.371911 -293.695227) (xy 135.341338 -293.735913) (xy 135.304634 -293.771168) (xy 135.26275 -293.800078)
			(xy 135.216771 -293.821895) (xy 135.167887 -293.836055) (xy 135.117366 -293.842189) (xy 135.066514 -293.84014)
			(xy 135.01665 -293.82996) (xy 134.969064 -293.811913) (xy 134.92499 -293.786467) (xy 134.885568 -293.75428)
			(xy 134.85182 -293.716186) (xy 134.824619 -293.673172) (xy 134.804671 -293.626352) (xy 134.792492 -293.576938)
			(xy 134.788397 -293.52621) (xy 134.47014 -293.52621) (xy 134.469645 -293.550817) (xy 134.46175 -293.599394)
			(xy 134.446166 -293.646075) (xy 134.423295 -293.689652) (xy 134.39373 -293.728996) (xy 134.358237 -293.763088)
			(xy 134.317734 -293.791044) (xy 134.273272 -293.812142) (xy 134.226001 -293.825834) (xy 134.177146 -293.831766)
			(xy 134.127971 -293.829785) (xy 134.079752 -293.819941) (xy 134.033736 -293.802489) (xy 133.991115 -293.777882)
			(xy 133.952994 -293.746757) (xy 133.920359 -293.70992) (xy 133.894056 -293.668324) (xy 133.874765 -293.623048)
			(xy 133.862988 -293.575264) (xy 133.859028 -293.52621) (xy 133.5405 -293.52621) (xy 133.539988 -293.551656)
			(xy 133.531824 -293.60189) (xy 133.515708 -293.650164) (xy 133.492057 -293.695227) (xy 133.461484 -293.735913)
			(xy 133.42478 -293.771168) (xy 133.382896 -293.800078) (xy 133.336917 -293.821895) (xy 133.288033 -293.836055)
			(xy 133.237512 -293.842189) (xy 133.18666 -293.84014) (xy 133.136796 -293.82996) (xy 133.08921 -293.811913)
			(xy 133.045136 -293.786467) (xy 133.005714 -293.75428) (xy 132.971966 -293.716186) (xy 132.944765 -293.673172)
			(xy 132.924817 -293.626352) (xy 132.912638 -293.576938) (xy 132.908543 -293.52621) (xy 132.590032 -293.52621)
			(xy 132.589537 -293.550817) (xy 132.581642 -293.599394) (xy 132.566058 -293.646075) (xy 132.543187 -293.689652)
			(xy 132.513622 -293.728996) (xy 132.478129 -293.763088) (xy 132.437626 -293.791044) (xy 132.393164 -293.812142)
			(xy 132.345893 -293.825834) (xy 132.297038 -293.831766) (xy 132.247863 -293.829785) (xy 132.199644 -293.819941)
			(xy 132.153628 -293.802489) (xy 132.111007 -293.777882) (xy 132.072886 -293.746757) (xy 132.040251 -293.70992)
			(xy 132.013948 -293.668324) (xy 131.994657 -293.623048) (xy 131.98288 -293.575264) (xy 131.97892 -293.52621)
			(xy 131.649978 -293.52621) (xy 131.649483 -293.550817) (xy 131.641588 -293.599394) (xy 131.626004 -293.646075)
			(xy 131.603133 -293.689652) (xy 131.573568 -293.728996) (xy 131.538075 -293.763088) (xy 131.497572 -293.791044)
			(xy 131.45311 -293.812142) (xy 131.405839 -293.825834) (xy 131.356984 -293.831766) (xy 131.307809 -293.829785)
			(xy 131.25959 -293.819941) (xy 131.213574 -293.802489) (xy 131.170953 -293.777882) (xy 131.132832 -293.746757)
			(xy 131.100197 -293.70992) (xy 131.073894 -293.668324) (xy 131.054603 -293.623048) (xy 131.042826 -293.575264)
			(xy 131.038866 -293.52621) (xy 130.710178 -293.52621) (xy 130.709683 -293.550817) (xy 130.701788 -293.599394)
			(xy 130.686204 -293.646075) (xy 130.663333 -293.689652) (xy 130.633768 -293.728996) (xy 130.598275 -293.763088)
			(xy 130.557772 -293.791044) (xy 130.51331 -293.812142) (xy 130.466039 -293.825834) (xy 130.417184 -293.831766)
			(xy 130.368009 -293.829785) (xy 130.31979 -293.819941) (xy 130.273774 -293.802489) (xy 130.231153 -293.777882)
			(xy 130.193032 -293.746757) (xy 130.160397 -293.70992) (xy 130.134094 -293.668324) (xy 130.114803 -293.623048)
			(xy 130.103026 -293.575264) (xy 130.099066 -293.52621) (xy 129.770124 -293.52621) (xy 129.769629 -293.550817)
			(xy 129.761734 -293.599394) (xy 129.74615 -293.646075) (xy 129.723279 -293.689652) (xy 129.693714 -293.728996)
			(xy 129.658221 -293.763088) (xy 129.617718 -293.791044) (xy 129.573256 -293.812142) (xy 129.525985 -293.825834)
			(xy 129.47713 -293.831766) (xy 129.427955 -293.829785) (xy 129.379736 -293.819941) (xy 129.33372 -293.802489)
			(xy 129.291099 -293.777882) (xy 129.252978 -293.746757) (xy 129.220343 -293.70992) (xy 129.19404 -293.668324)
			(xy 129.174749 -293.623048) (xy 129.162972 -293.575264) (xy 129.159012 -293.52621) (xy 128.840484 -293.52621)
			(xy 128.840037 -293.550494) (xy 128.832592 -293.598488) (xy 128.817879 -293.644775) (xy 128.796247 -293.688259)
			(xy 128.768206 -293.727915) (xy 128.734419 -293.762805) (xy 128.695684 -293.792105) (xy 128.652916 -293.815122)
			(xy 128.630172 -293.823644) (xy 128.614932 -293.829232) (xy 128.59639 -293.85514) (xy 128.59639 -294.057832)
			(xy 128.59639 -294.058594) (xy 128.596892 -294.067309) (xy 128.603002 -294.08365) (xy 128.614216 -294.097015)
			(xy 128.621536 -294.101774) (xy 128.628648 -294.105076) (xy 128.73101 -294.145462) (xy 128.76149 -294.138604)
			(xy 128.772158 -294.127174) (xy 128.789601 -294.109335) (xy 128.82922 -294.079016) (xy 128.873241 -294.05554)
			(xy 128.920492 -294.039531) (xy 128.969717 -294.031416) (xy 128.994662 -294.030908) (xy 129.01992 -294.031398)
			(xy 129.069749 -294.039707) (xy 129.11753 -294.056105) (xy 129.161961 -294.080145) (xy 129.201828 -294.11117)
			(xy 129.236044 -294.148334) (xy 129.263676 -294.190624) (xy 129.28397 -294.236885) (xy 129.296372 -294.285856)
			(xy 129.300544 -294.3362) (xy 129.300543 -294.336216) (xy 129.628912 -294.336216) (xy 129.632872 -294.287162)
			(xy 129.644649 -294.239378) (xy 129.66394 -294.194102) (xy 129.690243 -294.152506) (xy 129.722878 -294.115669)
			(xy 129.760999 -294.084544) (xy 129.80362 -294.059937) (xy 129.849636 -294.042485) (xy 129.897855 -294.032641)
			(xy 129.94703 -294.03066) (xy 129.995885 -294.036592) (xy 130.043156 -294.050284) (xy 130.087618 -294.071382)
			(xy 130.128121 -294.099338) (xy 130.163614 -294.13343) (xy 130.193179 -294.172774) (xy 130.21605 -294.216351)
			(xy 130.231634 -294.263032) (xy 130.239529 -294.311609) (xy 130.240024 -294.336216) (xy 130.568966 -294.336216)
			(xy 130.572926 -294.287162) (xy 130.584703 -294.239378) (xy 130.603994 -294.194102) (xy 130.630297 -294.152506)
			(xy 130.662932 -294.115669) (xy 130.701053 -294.084544) (xy 130.743674 -294.059937) (xy 130.78969 -294.042485)
			(xy 130.837909 -294.032641) (xy 130.887084 -294.03066) (xy 130.935939 -294.036592) (xy 130.98321 -294.050284)
			(xy 131.027672 -294.071382) (xy 131.068175 -294.099338) (xy 131.103668 -294.13343) (xy 131.133233 -294.172774)
			(xy 131.156104 -294.216351) (xy 131.171688 -294.263032) (xy 131.179583 -294.311609) (xy 131.180078 -294.336216)
			(xy 131.50902 -294.336216) (xy 131.51298 -294.287162) (xy 131.524757 -294.239378) (xy 131.544048 -294.194102)
			(xy 131.570351 -294.152506) (xy 131.602986 -294.115669) (xy 131.641107 -294.084544) (xy 131.683728 -294.059937)
			(xy 131.729744 -294.042485) (xy 131.777963 -294.032641) (xy 131.827138 -294.03066) (xy 131.875993 -294.036592)
			(xy 131.923264 -294.050284) (xy 131.967726 -294.071382) (xy 132.008229 -294.099338) (xy 132.043722 -294.13343)
			(xy 132.073287 -294.172774) (xy 132.096158 -294.216351) (xy 132.111742 -294.263032) (xy 132.119637 -294.311609)
			(xy 132.120132 -294.336216) (xy 132.449074 -294.336216) (xy 132.453034 -294.287162) (xy 132.464811 -294.239378)
			(xy 132.484102 -294.194102) (xy 132.510405 -294.152506) (xy 132.54304 -294.115669) (xy 132.581161 -294.084544)
			(xy 132.623782 -294.059937) (xy 132.669798 -294.042485) (xy 132.718017 -294.032641) (xy 132.767192 -294.03066)
			(xy 132.816047 -294.036592) (xy 132.863318 -294.050284) (xy 132.90778 -294.071382) (xy 132.948283 -294.099338)
			(xy 132.983776 -294.13343) (xy 133.013341 -294.172774) (xy 133.036212 -294.216351) (xy 133.051796 -294.263032)
			(xy 133.059691 -294.311609) (xy 133.060186 -294.336216) (xy 133.388874 -294.336216) (xy 133.392834 -294.287162)
			(xy 133.404611 -294.239378) (xy 133.423902 -294.194102) (xy 133.450205 -294.152506) (xy 133.48284 -294.115669)
			(xy 133.520961 -294.084544) (xy 133.563582 -294.059937) (xy 133.609598 -294.042485) (xy 133.657817 -294.032641)
			(xy 133.706992 -294.03066) (xy 133.755847 -294.036592) (xy 133.803118 -294.050284) (xy 133.84758 -294.071382)
			(xy 133.888083 -294.099338) (xy 133.923576 -294.13343) (xy 133.953141 -294.172774) (xy 133.976012 -294.216351)
			(xy 133.991596 -294.263032) (xy 133.999491 -294.311609) (xy 133.999986 -294.336216) (xy 134.328928 -294.336216)
			(xy 134.332888 -294.287162) (xy 134.344665 -294.239378) (xy 134.363956 -294.194102) (xy 134.390259 -294.152506)
			(xy 134.422894 -294.115669) (xy 134.461015 -294.084544) (xy 134.503636 -294.059937) (xy 134.549652 -294.042485)
			(xy 134.597871 -294.032641) (xy 134.647046 -294.03066) (xy 134.695901 -294.036592) (xy 134.743172 -294.050284)
			(xy 134.787634 -294.071382) (xy 134.828137 -294.099338) (xy 134.86363 -294.13343) (xy 134.893195 -294.172774)
			(xy 134.916066 -294.216351) (xy 134.93165 -294.263032) (xy 134.939545 -294.311609) (xy 134.94004 -294.336216)
			(xy 135.268982 -294.336216) (xy 135.272942 -294.287162) (xy 135.284719 -294.239378) (xy 135.30401 -294.194102)
			(xy 135.330313 -294.152506) (xy 135.362948 -294.115669) (xy 135.401069 -294.084544) (xy 135.44369 -294.059937)
			(xy 135.489706 -294.042485) (xy 135.537925 -294.032641) (xy 135.5871 -294.03066) (xy 135.635955 -294.036592)
			(xy 135.683226 -294.050284) (xy 135.727688 -294.071382) (xy 135.768191 -294.099338) (xy 135.803684 -294.13343)
			(xy 135.833249 -294.172774) (xy 135.85612 -294.216351) (xy 135.871704 -294.263032) (xy 135.879599 -294.311609)
			(xy 135.880094 -294.336216) (xy 136.209036 -294.336216) (xy 136.212996 -294.287162) (xy 136.224773 -294.239378)
			(xy 136.244064 -294.194102) (xy 136.270367 -294.152506) (xy 136.303002 -294.115669) (xy 136.341123 -294.084544)
			(xy 136.383744 -294.059937) (xy 136.42976 -294.042485) (xy 136.477979 -294.032641) (xy 136.527154 -294.03066)
			(xy 136.576009 -294.036592) (xy 136.62328 -294.050284) (xy 136.667742 -294.071382) (xy 136.708245 -294.099338)
			(xy 136.743738 -294.13343) (xy 136.773303 -294.172774) (xy 136.796174 -294.216351) (xy 136.811758 -294.263032)
			(xy 136.819653 -294.311609) (xy 136.820148 -294.336216) (xy 137.148836 -294.336216) (xy 137.152796 -294.287162)
			(xy 137.164573 -294.239378) (xy 137.183864 -294.194102) (xy 137.210167 -294.152506) (xy 137.242802 -294.115669)
			(xy 137.280923 -294.084544) (xy 137.323544 -294.059937) (xy 137.36956 -294.042485) (xy 137.417779 -294.032641)
			(xy 137.466954 -294.03066) (xy 137.515809 -294.036592) (xy 137.56308 -294.050284) (xy 137.607542 -294.071382)
			(xy 137.648045 -294.099338) (xy 137.683538 -294.13343) (xy 137.713103 -294.172774) (xy 137.735974 -294.216351)
			(xy 137.751558 -294.263032) (xy 137.759453 -294.311609) (xy 137.759948 -294.336216) (xy 138.08889 -294.336216)
			(xy 138.09285 -294.287162) (xy 138.104627 -294.239378) (xy 138.123918 -294.194102) (xy 138.150221 -294.152506)
			(xy 138.182856 -294.115669) (xy 138.220977 -294.084544) (xy 138.263598 -294.059937) (xy 138.309614 -294.042485)
			(xy 138.357833 -294.032641) (xy 138.407008 -294.03066) (xy 138.455863 -294.036592) (xy 138.503134 -294.050284)
			(xy 138.547596 -294.071382) (xy 138.588099 -294.099338) (xy 138.623592 -294.13343) (xy 138.653157 -294.172774)
			(xy 138.676028 -294.216351) (xy 138.691612 -294.263032) (xy 138.699507 -294.311609) (xy 138.700002 -294.336216)
			(xy 139.028944 -294.336216) (xy 139.032904 -294.287162) (xy 139.044681 -294.239378) (xy 139.063972 -294.194102)
			(xy 139.090275 -294.152506) (xy 139.12291 -294.115669) (xy 139.161031 -294.084544) (xy 139.203652 -294.059937)
			(xy 139.249668 -294.042485) (xy 139.297887 -294.032641) (xy 139.347062 -294.03066) (xy 139.395917 -294.036592)
			(xy 139.443188 -294.050284) (xy 139.48765 -294.071382) (xy 139.528153 -294.099338) (xy 139.563646 -294.13343)
			(xy 139.593211 -294.172774) (xy 139.616082 -294.216351) (xy 139.631666 -294.263032) (xy 139.639561 -294.311609)
			(xy 139.640056 -294.336216) (xy 139.968998 -294.336216) (xy 139.972958 -294.287162) (xy 139.984735 -294.239378)
			(xy 140.004026 -294.194102) (xy 140.030329 -294.152506) (xy 140.062964 -294.115669) (xy 140.101085 -294.084544)
			(xy 140.143706 -294.059937) (xy 140.189722 -294.042485) (xy 140.237941 -294.032641) (xy 140.287116 -294.03066)
			(xy 140.335971 -294.036592) (xy 140.383242 -294.050284) (xy 140.427704 -294.071382) (xy 140.468207 -294.099338)
			(xy 140.5037 -294.13343) (xy 140.533265 -294.172774) (xy 140.556136 -294.216351) (xy 140.57172 -294.263032)
			(xy 140.579615 -294.311609) (xy 140.58011 -294.336216) (xy 140.909052 -294.336216) (xy 140.913012 -294.287162)
			(xy 140.924789 -294.239378) (xy 140.94408 -294.194102) (xy 140.970383 -294.152506) (xy 141.003018 -294.115669)
			(xy 141.041139 -294.084544) (xy 141.08376 -294.059937) (xy 141.129776 -294.042485) (xy 141.177995 -294.032641)
			(xy 141.22717 -294.03066) (xy 141.276025 -294.036592) (xy 141.323296 -294.050284) (xy 141.367758 -294.071382)
			(xy 141.408261 -294.099338) (xy 141.443754 -294.13343) (xy 141.473319 -294.172774) (xy 141.49619 -294.216351)
			(xy 141.511774 -294.263032) (xy 141.519669 -294.311609) (xy 141.520164 -294.336216) (xy 141.848852 -294.336216)
			(xy 141.852812 -294.287162) (xy 141.864589 -294.239378) (xy 141.88388 -294.194102) (xy 141.910183 -294.152506)
			(xy 141.942818 -294.115669) (xy 141.980939 -294.084544) (xy 142.02356 -294.059937) (xy 142.069576 -294.042485)
			(xy 142.117795 -294.032641) (xy 142.16697 -294.03066) (xy 142.215825 -294.036592) (xy 142.263096 -294.050284)
			(xy 142.307558 -294.071382) (xy 142.348061 -294.099338) (xy 142.383554 -294.13343) (xy 142.413119 -294.172774)
			(xy 142.43599 -294.216351) (xy 142.451574 -294.263032) (xy 142.459469 -294.311609) (xy 142.459964 -294.336216)
			(xy 143.72896 -294.336216) (xy 143.73292 -294.287162) (xy 143.744697 -294.239378) (xy 143.763988 -294.194102)
			(xy 143.790291 -294.152506) (xy 143.822926 -294.115669) (xy 143.861047 -294.084544) (xy 143.903668 -294.059937)
			(xy 143.949684 -294.042485) (xy 143.997903 -294.032641) (xy 144.047078 -294.03066) (xy 144.095933 -294.036592)
			(xy 144.143204 -294.050284) (xy 144.187666 -294.071382) (xy 144.228169 -294.099338) (xy 144.263662 -294.13343)
			(xy 144.293227 -294.172774) (xy 144.316098 -294.216351) (xy 144.331682 -294.263032) (xy 144.339577 -294.311609)
			(xy 144.340072 -294.336216) (xy 145.608814 -294.336216) (xy 145.612774 -294.287162) (xy 145.624551 -294.239378)
			(xy 145.643842 -294.194102) (xy 145.670145 -294.152506) (xy 145.70278 -294.115669) (xy 145.740901 -294.084544)
			(xy 145.783522 -294.059937) (xy 145.829538 -294.042485) (xy 145.877757 -294.032641) (xy 145.926932 -294.03066)
			(xy 145.975787 -294.036592) (xy 146.023058 -294.050284) (xy 146.06752 -294.071382) (xy 146.108023 -294.099338)
			(xy 146.143516 -294.13343) (xy 146.173081 -294.172774) (xy 146.195952 -294.216351) (xy 146.211536 -294.263032)
			(xy 146.219431 -294.311609) (xy 146.219926 -294.336216) (xy 146.548868 -294.336216) (xy 146.552828 -294.287162)
			(xy 146.564605 -294.239378) (xy 146.583896 -294.194102) (xy 146.610199 -294.152506) (xy 146.642834 -294.115669)
			(xy 146.680955 -294.084544) (xy 146.723576 -294.059937) (xy 146.769592 -294.042485) (xy 146.817811 -294.032641)
			(xy 146.866986 -294.03066) (xy 146.915841 -294.036592) (xy 146.963112 -294.050284) (xy 147.007574 -294.071382)
			(xy 147.048077 -294.099338) (xy 147.08357 -294.13343) (xy 147.113135 -294.172774) (xy 147.136006 -294.216351)
			(xy 147.142358 -294.235378) (xy 165.442915 -294.235378) (xy 165.44685 -294.181607) (xy 165.458573 -294.128983)
			(xy 165.477833 -294.078626) (xy 165.504219 -294.031609) (xy 165.537171 -293.988936) (xy 165.575984 -293.951515)
			(xy 165.619832 -293.920145) (xy 165.66778 -293.895493) (xy 165.718807 -293.878085) (xy 165.771825 -293.868292)
			(xy 165.825704 -293.866323) (xy 165.879295 -293.87222) (xy 165.931456 -293.885856) (xy 165.981076 -293.906943)
			(xy 166.027097 -293.935029) (xy 166.068539 -293.969517) (xy 166.104517 -294.009671) (xy 166.134265 -294.054635)
			(xy 166.15715 -294.103452) (xy 166.172682 -294.155081) (xy 166.180532 -294.208421) (xy 166.181024 -294.235378)
			(xy 172.986969 -294.235378) (xy 172.990904 -294.181607) (xy 173.002627 -294.128983) (xy 173.021887 -294.078626)
			(xy 173.048273 -294.031609) (xy 173.081225 -293.988936) (xy 173.120038 -293.951515) (xy 173.163886 -293.920145)
			(xy 173.211834 -293.895493) (xy 173.262861 -293.878085) (xy 173.315879 -293.868292) (xy 173.369758 -293.866323)
			(xy 173.423349 -293.87222) (xy 173.47551 -293.885856) (xy 173.52513 -293.906943) (xy 173.571151 -293.935029)
			(xy 173.612593 -293.969517) (xy 173.648571 -294.009671) (xy 173.678319 -294.054635) (xy 173.701204 -294.103452)
			(xy 173.716736 -294.155081) (xy 173.724586 -294.208421) (xy 173.725078 -294.235378) (xy 173.724586 -294.262335)
			(xy 173.716736 -294.315675) (xy 173.701204 -294.367304) (xy 173.678319 -294.416121) (xy 173.648571 -294.461085)
			(xy 173.612593 -294.501239) (xy 173.571151 -294.535727) (xy 173.52513 -294.563813) (xy 173.47551 -294.5849)
			(xy 173.423349 -294.598536) (xy 173.369758 -294.604433) (xy 173.315879 -294.602464) (xy 173.262861 -294.592671)
			(xy 173.211834 -294.575263) (xy 173.163886 -294.550611) (xy 173.120038 -294.519241) (xy 173.081225 -294.48182)
			(xy 173.048273 -294.439147) (xy 173.021887 -294.39213) (xy 173.002627 -294.341773) (xy 172.990904 -294.289149)
			(xy 172.986969 -294.235378) (xy 166.181024 -294.235378) (xy 166.180532 -294.262335) (xy 166.172682 -294.315675)
			(xy 166.15715 -294.367304) (xy 166.134265 -294.416121) (xy 166.104517 -294.461085) (xy 166.068539 -294.501239)
			(xy 166.027097 -294.535727) (xy 165.981076 -294.563813) (xy 165.931456 -294.5849) (xy 165.879295 -294.598536)
			(xy 165.825704 -294.604433) (xy 165.771825 -294.602464) (xy 165.718807 -294.592671) (xy 165.66778 -294.575263)
			(xy 165.619832 -294.550611) (xy 165.575984 -294.519241) (xy 165.537171 -294.48182) (xy 165.504219 -294.439147)
			(xy 165.477833 -294.39213) (xy 165.458573 -294.341773) (xy 165.44685 -294.289149) (xy 165.442915 -294.235378)
			(xy 147.142358 -294.235378) (xy 147.15159 -294.263032) (xy 147.159485 -294.311609) (xy 147.15998 -294.336216)
			(xy 147.159485 -294.360823) (xy 147.15159 -294.4094) (xy 147.136006 -294.456081) (xy 147.113135 -294.499658)
			(xy 147.08357 -294.539002) (xy 147.048077 -294.573094) (xy 147.007574 -294.60105) (xy 146.963112 -294.622148)
			(xy 146.915841 -294.63584) (xy 146.866986 -294.641772) (xy 146.817811 -294.639791) (xy 146.769592 -294.629947)
			(xy 146.723576 -294.612495) (xy 146.680955 -294.587888) (xy 146.642834 -294.556763) (xy 146.610199 -294.519926)
			(xy 146.583896 -294.47833) (xy 146.564605 -294.433054) (xy 146.552828 -294.38527) (xy 146.548868 -294.336216)
			(xy 146.219926 -294.336216) (xy 146.219431 -294.360823) (xy 146.211536 -294.4094) (xy 146.195952 -294.456081)
			(xy 146.173081 -294.499658) (xy 146.143516 -294.539002) (xy 146.108023 -294.573094) (xy 146.06752 -294.60105)
			(xy 146.023058 -294.622148) (xy 145.975787 -294.63584) (xy 145.926932 -294.641772) (xy 145.877757 -294.639791)
			(xy 145.829538 -294.629947) (xy 145.783522 -294.612495) (xy 145.740901 -294.587888) (xy 145.70278 -294.556763)
			(xy 145.670145 -294.519926) (xy 145.643842 -294.47833) (xy 145.624551 -294.433054) (xy 145.612774 -294.38527)
			(xy 145.608814 -294.336216) (xy 144.340072 -294.336216) (xy 144.339577 -294.360823) (xy 144.331682 -294.4094)
			(xy 144.316098 -294.456081) (xy 144.293227 -294.499658) (xy 144.263662 -294.539002) (xy 144.228169 -294.573094)
			(xy 144.187666 -294.60105) (xy 144.143204 -294.622148) (xy 144.095933 -294.63584) (xy 144.047078 -294.641772)
			(xy 143.997903 -294.639791) (xy 143.949684 -294.629947) (xy 143.903668 -294.612495) (xy 143.861047 -294.587888)
			(xy 143.822926 -294.556763) (xy 143.790291 -294.519926) (xy 143.763988 -294.47833) (xy 143.744697 -294.433054)
			(xy 143.73292 -294.38527) (xy 143.72896 -294.336216) (xy 142.459964 -294.336216) (xy 142.459469 -294.360823)
			(xy 142.451574 -294.4094) (xy 142.43599 -294.456081) (xy 142.413119 -294.499658) (xy 142.383554 -294.539002)
			(xy 142.348061 -294.573094) (xy 142.307558 -294.60105) (xy 142.263096 -294.622148) (xy 142.215825 -294.63584)
			(xy 142.16697 -294.641772) (xy 142.117795 -294.639791) (xy 142.069576 -294.629947) (xy 142.02356 -294.612495)
			(xy 141.980939 -294.587888) (xy 141.942818 -294.556763) (xy 141.910183 -294.519926) (xy 141.88388 -294.47833)
			(xy 141.864589 -294.433054) (xy 141.852812 -294.38527) (xy 141.848852 -294.336216) (xy 141.520164 -294.336216)
			(xy 141.519669 -294.360823) (xy 141.511774 -294.4094) (xy 141.49619 -294.456081) (xy 141.473319 -294.499658)
			(xy 141.443754 -294.539002) (xy 141.408261 -294.573094) (xy 141.367758 -294.60105) (xy 141.323296 -294.622148)
			(xy 141.276025 -294.63584) (xy 141.22717 -294.641772) (xy 141.177995 -294.639791) (xy 141.129776 -294.629947)
			(xy 141.08376 -294.612495) (xy 141.041139 -294.587888) (xy 141.003018 -294.556763) (xy 140.970383 -294.519926)
			(xy 140.94408 -294.47833) (xy 140.924789 -294.433054) (xy 140.913012 -294.38527) (xy 140.909052 -294.336216)
			(xy 140.58011 -294.336216) (xy 140.579615 -294.360823) (xy 140.57172 -294.4094) (xy 140.556136 -294.456081)
			(xy 140.533265 -294.499658) (xy 140.5037 -294.539002) (xy 140.468207 -294.573094) (xy 140.427704 -294.60105)
			(xy 140.383242 -294.622148) (xy 140.335971 -294.63584) (xy 140.287116 -294.641772) (xy 140.237941 -294.639791)
			(xy 140.189722 -294.629947) (xy 140.143706 -294.612495) (xy 140.101085 -294.587888) (xy 140.062964 -294.556763)
			(xy 140.030329 -294.519926) (xy 140.004026 -294.47833) (xy 139.984735 -294.433054) (xy 139.972958 -294.38527)
			(xy 139.968998 -294.336216) (xy 139.640056 -294.336216) (xy 139.639561 -294.360823) (xy 139.631666 -294.4094)
			(xy 139.616082 -294.456081) (xy 139.593211 -294.499658) (xy 139.563646 -294.539002) (xy 139.528153 -294.573094)
			(xy 139.48765 -294.60105) (xy 139.443188 -294.622148) (xy 139.395917 -294.63584) (xy 139.347062 -294.641772)
			(xy 139.297887 -294.639791) (xy 139.249668 -294.629947) (xy 139.203652 -294.612495) (xy 139.161031 -294.587888)
			(xy 139.12291 -294.556763) (xy 139.090275 -294.519926) (xy 139.063972 -294.47833) (xy 139.044681 -294.433054)
			(xy 139.032904 -294.38527) (xy 139.028944 -294.336216) (xy 138.700002 -294.336216) (xy 138.699507 -294.360823)
			(xy 138.691612 -294.4094) (xy 138.676028 -294.456081) (xy 138.653157 -294.499658) (xy 138.623592 -294.539002)
			(xy 138.588099 -294.573094) (xy 138.547596 -294.60105) (xy 138.503134 -294.622148) (xy 138.455863 -294.63584)
			(xy 138.407008 -294.641772) (xy 138.357833 -294.639791) (xy 138.309614 -294.629947) (xy 138.263598 -294.612495)
			(xy 138.220977 -294.587888) (xy 138.182856 -294.556763) (xy 138.150221 -294.519926) (xy 138.123918 -294.47833)
			(xy 138.104627 -294.433054) (xy 138.09285 -294.38527) (xy 138.08889 -294.336216) (xy 137.759948 -294.336216)
			(xy 137.759453 -294.360823) (xy 137.751558 -294.4094) (xy 137.735974 -294.456081) (xy 137.713103 -294.499658)
			(xy 137.683538 -294.539002) (xy 137.648045 -294.573094) (xy 137.607542 -294.60105) (xy 137.56308 -294.622148)
			(xy 137.515809 -294.63584) (xy 137.466954 -294.641772) (xy 137.417779 -294.639791) (xy 137.36956 -294.629947)
			(xy 137.323544 -294.612495) (xy 137.280923 -294.587888) (xy 137.242802 -294.556763) (xy 137.210167 -294.519926)
			(xy 137.183864 -294.47833) (xy 137.164573 -294.433054) (xy 137.152796 -294.38527) (xy 137.148836 -294.336216)
			(xy 136.820148 -294.336216) (xy 136.819653 -294.360823) (xy 136.811758 -294.4094) (xy 136.796174 -294.456081)
			(xy 136.773303 -294.499658) (xy 136.743738 -294.539002) (xy 136.708245 -294.573094) (xy 136.667742 -294.60105)
			(xy 136.62328 -294.622148) (xy 136.576009 -294.63584) (xy 136.527154 -294.641772) (xy 136.477979 -294.639791)
			(xy 136.42976 -294.629947) (xy 136.383744 -294.612495) (xy 136.341123 -294.587888) (xy 136.303002 -294.556763)
			(xy 136.270367 -294.519926) (xy 136.244064 -294.47833) (xy 136.224773 -294.433054) (xy 136.212996 -294.38527)
			(xy 136.209036 -294.336216) (xy 135.880094 -294.336216) (xy 135.879599 -294.360823) (xy 135.871704 -294.4094)
			(xy 135.85612 -294.456081) (xy 135.833249 -294.499658) (xy 135.803684 -294.539002) (xy 135.768191 -294.573094)
			(xy 135.727688 -294.60105) (xy 135.683226 -294.622148) (xy 135.635955 -294.63584) (xy 135.5871 -294.641772)
			(xy 135.537925 -294.639791) (xy 135.489706 -294.629947) (xy 135.44369 -294.612495) (xy 135.401069 -294.587888)
			(xy 135.362948 -294.556763) (xy 135.330313 -294.519926) (xy 135.30401 -294.47833) (xy 135.284719 -294.433054)
			(xy 135.272942 -294.38527) (xy 135.268982 -294.336216) (xy 134.94004 -294.336216) (xy 134.939545 -294.360823)
			(xy 134.93165 -294.4094) (xy 134.916066 -294.456081) (xy 134.893195 -294.499658) (xy 134.86363 -294.539002)
			(xy 134.828137 -294.573094) (xy 134.787634 -294.60105) (xy 134.743172 -294.622148) (xy 134.695901 -294.63584)
			(xy 134.647046 -294.641772) (xy 134.597871 -294.639791) (xy 134.549652 -294.629947) (xy 134.503636 -294.612495)
			(xy 134.461015 -294.587888) (xy 134.422894 -294.556763) (xy 134.390259 -294.519926) (xy 134.363956 -294.47833)
			(xy 134.344665 -294.433054) (xy 134.332888 -294.38527) (xy 134.328928 -294.336216) (xy 133.999986 -294.336216)
			(xy 133.999491 -294.360823) (xy 133.991596 -294.4094) (xy 133.976012 -294.456081) (xy 133.953141 -294.499658)
			(xy 133.923576 -294.539002) (xy 133.888083 -294.573094) (xy 133.84758 -294.60105) (xy 133.803118 -294.622148)
			(xy 133.755847 -294.63584) (xy 133.706992 -294.641772) (xy 133.657817 -294.639791) (xy 133.609598 -294.629947)
			(xy 133.563582 -294.612495) (xy 133.520961 -294.587888) (xy 133.48284 -294.556763) (xy 133.450205 -294.519926)
			(xy 133.423902 -294.47833) (xy 133.404611 -294.433054) (xy 133.392834 -294.38527) (xy 133.388874 -294.336216)
			(xy 133.060186 -294.336216) (xy 133.059691 -294.360823) (xy 133.051796 -294.4094) (xy 133.036212 -294.456081)
			(xy 133.013341 -294.499658) (xy 132.983776 -294.539002) (xy 132.948283 -294.573094) (xy 132.90778 -294.60105)
			(xy 132.863318 -294.622148) (xy 132.816047 -294.63584) (xy 132.767192 -294.641772) (xy 132.718017 -294.639791)
			(xy 132.669798 -294.629947) (xy 132.623782 -294.612495) (xy 132.581161 -294.587888) (xy 132.54304 -294.556763)
			(xy 132.510405 -294.519926) (xy 132.484102 -294.47833) (xy 132.464811 -294.433054) (xy 132.453034 -294.38527)
			(xy 132.449074 -294.336216) (xy 132.120132 -294.336216) (xy 132.119637 -294.360823) (xy 132.111742 -294.4094)
			(xy 132.096158 -294.456081) (xy 132.073287 -294.499658) (xy 132.043722 -294.539002) (xy 132.008229 -294.573094)
			(xy 131.967726 -294.60105) (xy 131.923264 -294.622148) (xy 131.875993 -294.63584) (xy 131.827138 -294.641772)
			(xy 131.777963 -294.639791) (xy 131.729744 -294.629947) (xy 131.683728 -294.612495) (xy 131.641107 -294.587888)
			(xy 131.602986 -294.556763) (xy 131.570351 -294.519926) (xy 131.544048 -294.47833) (xy 131.524757 -294.433054)
			(xy 131.51298 -294.38527) (xy 131.50902 -294.336216) (xy 131.180078 -294.336216) (xy 131.179583 -294.360823)
			(xy 131.171688 -294.4094) (xy 131.156104 -294.456081) (xy 131.133233 -294.499658) (xy 131.103668 -294.539002)
			(xy 131.068175 -294.573094) (xy 131.027672 -294.60105) (xy 130.98321 -294.622148) (xy 130.935939 -294.63584)
			(xy 130.887084 -294.641772) (xy 130.837909 -294.639791) (xy 130.78969 -294.629947) (xy 130.743674 -294.612495)
			(xy 130.701053 -294.587888) (xy 130.662932 -294.556763) (xy 130.630297 -294.519926) (xy 130.603994 -294.47833)
			(xy 130.584703 -294.433054) (xy 130.572926 -294.38527) (xy 130.568966 -294.336216) (xy 130.240024 -294.336216)
			(xy 130.239529 -294.360823) (xy 130.231634 -294.4094) (xy 130.21605 -294.456081) (xy 130.193179 -294.499658)
			(xy 130.163614 -294.539002) (xy 130.128121 -294.573094) (xy 130.087618 -294.60105) (xy 130.043156 -294.622148)
			(xy 129.995885 -294.63584) (xy 129.94703 -294.641772) (xy 129.897855 -294.639791) (xy 129.849636 -294.629947)
			(xy 129.80362 -294.612495) (xy 129.760999 -294.587888) (xy 129.722878 -294.556763) (xy 129.690243 -294.519926)
			(xy 129.66394 -294.47833) (xy 129.644649 -294.433054) (xy 129.632872 -294.38527) (xy 129.628912 -294.336216)
			(xy 129.300543 -294.336216) (xy 129.296372 -294.386544) (xy 129.28397 -294.435515) (xy 129.263676 -294.481776)
			(xy 129.236044 -294.524066) (xy 129.201828 -294.56123) (xy 129.161961 -294.592255) (xy 129.11753 -294.616295)
			(xy 129.069749 -294.632693) (xy 129.01992 -294.641002) (xy 128.994662 -294.641524) (xy 128.969715 -294.641033)
			(xy 128.920483 -294.632928) (xy 128.873226 -294.616923) (xy 128.8292 -294.593446) (xy 128.789579 -294.563121)
			(xy 128.772158 -294.545258) (xy 128.76149 -294.533828) (xy 128.73101 -294.52697) (xy 128.628648 -294.567356)
			(xy 128.621536 -294.570658) (xy 128.614171 -294.575366) (xy 128.602925 -294.588732) (xy 128.596849 -294.605109)
			(xy 128.59639 -294.613838) (xy 128.59639 -294.66032) (xy 169.276283 -294.66032) (xy 169.280218 -294.606549)
			(xy 169.291941 -294.553925) (xy 169.311201 -294.503568) (xy 169.337587 -294.456551) (xy 169.370539 -294.413878)
			(xy 169.409352 -294.376457) (xy 169.4532 -294.345087) (xy 169.501148 -294.320435) (xy 169.552175 -294.303027)
			(xy 169.605193 -294.293234) (xy 169.659072 -294.291265) (xy 169.712663 -294.297162) (xy 169.764824 -294.310798)
			(xy 169.814444 -294.331885) (xy 169.860465 -294.359971) (xy 169.901907 -294.394459) (xy 169.937885 -294.434613)
			(xy 169.967633 -294.479577) (xy 169.990518 -294.528394) (xy 170.00605 -294.580023) (xy 170.0139 -294.633363)
			(xy 170.014392 -294.66032) (xy 170.0139 -294.687277) (xy 170.00605 -294.740617) (xy 169.990518 -294.792246)
			(xy 169.967633 -294.841063) (xy 169.937885 -294.886027) (xy 169.901907 -294.926181) (xy 169.860465 -294.960669)
			(xy 169.814444 -294.988755) (xy 169.764824 -295.009842) (xy 169.712663 -295.023478) (xy 169.659072 -295.029375)
			(xy 169.605193 -295.027406) (xy 169.552175 -295.017613) (xy 169.501148 -295.000205) (xy 169.4532 -294.975553)
			(xy 169.409352 -294.944183) (xy 169.370539 -294.906762) (xy 169.337587 -294.864089) (xy 169.311201 -294.817072)
			(xy 169.291941 -294.766715) (xy 169.280218 -294.714091) (xy 169.276283 -294.66032) (xy 128.59639 -294.66032)
			(xy 128.59639 -294.82796) (xy 128.614424 -294.853868) (xy 128.629664 -294.859456) (xy 128.652837 -294.86845)
			(xy 128.696136 -294.892858) (xy 128.734909 -294.923956) (xy 128.768133 -294.960924) (xy 128.794931 -295.002786)
			(xy 128.814594 -295.048436) (xy 128.826603 -295.096668) (xy 128.83064 -295.146208) (xy 128.830639 -295.146222)
			(xy 129.159012 -295.146222) (xy 129.162972 -295.097168) (xy 129.174749 -295.049384) (xy 129.19404 -295.004108)
			(xy 129.220343 -294.962512) (xy 129.252978 -294.925675) (xy 129.291099 -294.89455) (xy 129.33372 -294.869943)
			(xy 129.379736 -294.852491) (xy 129.427955 -294.842647) (xy 129.47713 -294.840666) (xy 129.525985 -294.846598)
			(xy 129.573256 -294.86029) (xy 129.617718 -294.881388) (xy 129.658221 -294.909344) (xy 129.693714 -294.943436)
			(xy 129.723279 -294.98278) (xy 129.74615 -295.026357) (xy 129.761734 -295.073038) (xy 129.769629 -295.121615)
			(xy 129.770124 -295.146222) (xy 130.099066 -295.146222) (xy 130.103026 -295.097168) (xy 130.114803 -295.049384)
			(xy 130.134094 -295.004108) (xy 130.160397 -294.962512) (xy 130.193032 -294.925675) (xy 130.231153 -294.89455)
			(xy 130.273774 -294.869943) (xy 130.31979 -294.852491) (xy 130.368009 -294.842647) (xy 130.417184 -294.840666)
			(xy 130.466039 -294.846598) (xy 130.51331 -294.86029) (xy 130.557772 -294.881388) (xy 130.598275 -294.909344)
			(xy 130.633768 -294.943436) (xy 130.663333 -294.98278) (xy 130.686204 -295.026357) (xy 130.701788 -295.073038)
			(xy 130.709683 -295.121615) (xy 130.710178 -295.146222) (xy 131.038866 -295.146222) (xy 131.042826 -295.097168)
			(xy 131.054603 -295.049384) (xy 131.073894 -295.004108) (xy 131.100197 -294.962512) (xy 131.132832 -294.925675)
			(xy 131.170953 -294.89455) (xy 131.213574 -294.869943) (xy 131.25959 -294.852491) (xy 131.307809 -294.842647)
			(xy 131.356984 -294.840666) (xy 131.405839 -294.846598) (xy 131.45311 -294.86029) (xy 131.497572 -294.881388)
			(xy 131.538075 -294.909344) (xy 131.573568 -294.943436) (xy 131.603133 -294.98278) (xy 131.626004 -295.026357)
			(xy 131.641588 -295.073038) (xy 131.649483 -295.121615) (xy 131.649978 -295.146222) (xy 131.97892 -295.146222)
			(xy 131.98288 -295.097168) (xy 131.994657 -295.049384) (xy 132.013948 -295.004108) (xy 132.040251 -294.962512)
			(xy 132.072886 -294.925675) (xy 132.111007 -294.89455) (xy 132.153628 -294.869943) (xy 132.199644 -294.852491)
			(xy 132.247863 -294.842647) (xy 132.297038 -294.840666) (xy 132.345893 -294.846598) (xy 132.393164 -294.86029)
			(xy 132.437626 -294.881388) (xy 132.478129 -294.909344) (xy 132.513622 -294.943436) (xy 132.543187 -294.98278)
			(xy 132.566058 -295.026357) (xy 132.581642 -295.073038) (xy 132.589537 -295.121615) (xy 132.590032 -295.146222)
			(xy 132.918974 -295.146222) (xy 132.922934 -295.097168) (xy 132.934711 -295.049384) (xy 132.954002 -295.004108)
			(xy 132.980305 -294.962512) (xy 133.01294 -294.925675) (xy 133.051061 -294.89455) (xy 133.093682 -294.869943)
			(xy 133.139698 -294.852491) (xy 133.187917 -294.842647) (xy 133.237092 -294.840666) (xy 133.285947 -294.846598)
			(xy 133.333218 -294.86029) (xy 133.37768 -294.881388) (xy 133.418183 -294.909344) (xy 133.453676 -294.943436)
			(xy 133.483241 -294.98278) (xy 133.506112 -295.026357) (xy 133.521696 -295.073038) (xy 133.529591 -295.121615)
			(xy 133.530086 -295.146222) (xy 133.859028 -295.146222) (xy 133.862988 -295.097168) (xy 133.874765 -295.049384)
			(xy 133.894056 -295.004108) (xy 133.920359 -294.962512) (xy 133.952994 -294.925675) (xy 133.991115 -294.89455)
			(xy 134.033736 -294.869943) (xy 134.079752 -294.852491) (xy 134.127971 -294.842647) (xy 134.177146 -294.840666)
			(xy 134.226001 -294.846598) (xy 134.273272 -294.86029) (xy 134.317734 -294.881388) (xy 134.358237 -294.909344)
			(xy 134.39373 -294.943436) (xy 134.423295 -294.98278) (xy 134.446166 -295.026357) (xy 134.46175 -295.073038)
			(xy 134.469645 -295.121615) (xy 134.47014 -295.146222) (xy 134.798828 -295.146222) (xy 134.802788 -295.097168)
			(xy 134.814565 -295.049384) (xy 134.833856 -295.004108) (xy 134.860159 -294.962512) (xy 134.892794 -294.925675)
			(xy 134.930915 -294.89455) (xy 134.973536 -294.869943) (xy 135.019552 -294.852491) (xy 135.067771 -294.842647)
			(xy 135.116946 -294.840666) (xy 135.165801 -294.846598) (xy 135.213072 -294.86029) (xy 135.257534 -294.881388)
			(xy 135.298037 -294.909344) (xy 135.33353 -294.943436) (xy 135.363095 -294.98278) (xy 135.385966 -295.026357)
			(xy 135.40155 -295.073038) (xy 135.409445 -295.121615) (xy 135.40994 -295.146222) (xy 135.738882 -295.146222)
			(xy 135.742842 -295.097168) (xy 135.754619 -295.049384) (xy 135.77391 -295.004108) (xy 135.800213 -294.962512)
			(xy 135.832848 -294.925675) (xy 135.870969 -294.89455) (xy 135.91359 -294.869943) (xy 135.959606 -294.852491)
			(xy 136.007825 -294.842647) (xy 136.057 -294.840666) (xy 136.105855 -294.846598) (xy 136.153126 -294.86029)
			(xy 136.197588 -294.881388) (xy 136.238091 -294.909344) (xy 136.273584 -294.943436) (xy 136.303149 -294.98278)
			(xy 136.32602 -295.026357) (xy 136.341604 -295.073038) (xy 136.349499 -295.121615) (xy 136.349994 -295.146222)
			(xy 136.678936 -295.146222) (xy 136.682896 -295.097168) (xy 136.694673 -295.049384) (xy 136.713964 -295.004108)
			(xy 136.740267 -294.962512) (xy 136.772902 -294.925675) (xy 136.811023 -294.89455) (xy 136.853644 -294.869943)
			(xy 136.89966 -294.852491) (xy 136.947879 -294.842647) (xy 136.997054 -294.840666) (xy 137.045909 -294.846598)
			(xy 137.09318 -294.86029) (xy 137.137642 -294.881388) (xy 137.178145 -294.909344) (xy 137.213638 -294.943436)
			(xy 137.243203 -294.98278) (xy 137.266074 -295.026357) (xy 137.281658 -295.073038) (xy 137.289553 -295.121615)
			(xy 137.290048 -295.146222) (xy 137.61899 -295.146222) (xy 137.62295 -295.097168) (xy 137.634727 -295.049384)
			(xy 137.654018 -295.004108) (xy 137.680321 -294.962512) (xy 137.712956 -294.925675) (xy 137.751077 -294.89455)
			(xy 137.793698 -294.869943) (xy 137.839714 -294.852491) (xy 137.887933 -294.842647) (xy 137.937108 -294.840666)
			(xy 137.985963 -294.846598) (xy 138.033234 -294.86029) (xy 138.077696 -294.881388) (xy 138.118199 -294.909344)
			(xy 138.153692 -294.943436) (xy 138.183257 -294.98278) (xy 138.206128 -295.026357) (xy 138.221712 -295.073038)
			(xy 138.229607 -295.121615) (xy 138.230102 -295.146222) (xy 138.559044 -295.146222) (xy 138.563004 -295.097168)
			(xy 138.574781 -295.049384) (xy 138.594072 -295.004108) (xy 138.620375 -294.962512) (xy 138.65301 -294.925675)
			(xy 138.691131 -294.89455) (xy 138.733752 -294.869943) (xy 138.779768 -294.852491) (xy 138.827987 -294.842647)
			(xy 138.877162 -294.840666) (xy 138.926017 -294.846598) (xy 138.973288 -294.86029) (xy 139.01775 -294.881388)
			(xy 139.058253 -294.909344) (xy 139.093746 -294.943436) (xy 139.123311 -294.98278) (xy 139.146182 -295.026357)
			(xy 139.161766 -295.073038) (xy 139.169661 -295.121615) (xy 139.170156 -295.146222) (xy 140.438898 -295.146222)
			(xy 140.442858 -295.097168) (xy 140.454635 -295.049384) (xy 140.473926 -295.004108) (xy 140.500229 -294.962512)
			(xy 140.532864 -294.925675) (xy 140.570985 -294.89455) (xy 140.613606 -294.869943) (xy 140.659622 -294.852491)
			(xy 140.707841 -294.842647) (xy 140.757016 -294.840666) (xy 140.805871 -294.846598) (xy 140.853142 -294.86029)
			(xy 140.897604 -294.881388) (xy 140.938107 -294.909344) (xy 140.9736 -294.943436) (xy 141.003165 -294.98278)
			(xy 141.026036 -295.026357) (xy 141.04162 -295.073038) (xy 141.049515 -295.121615) (xy 141.05001 -295.146222)
			(xy 141.378952 -295.146222) (xy 141.382912 -295.097168) (xy 141.394689 -295.049384) (xy 141.41398 -295.004108)
			(xy 141.440283 -294.962512) (xy 141.472918 -294.925675) (xy 141.511039 -294.89455) (xy 141.55366 -294.869943)
			(xy 141.599676 -294.852491) (xy 141.647895 -294.842647) (xy 141.69707 -294.840666) (xy 141.745925 -294.846598)
			(xy 141.793196 -294.86029) (xy 141.837658 -294.881388) (xy 141.878161 -294.909344) (xy 141.913654 -294.943436)
			(xy 141.943219 -294.98278) (xy 141.96609 -295.026357) (xy 141.981674 -295.073038) (xy 141.989569 -295.121615)
			(xy 141.990064 -295.146222) (xy 143.258806 -295.146222) (xy 143.262766 -295.097168) (xy 143.274543 -295.049384)
			(xy 143.293834 -295.004108) (xy 143.320137 -294.962512) (xy 143.352772 -294.925675) (xy 143.390893 -294.89455)
			(xy 143.433514 -294.869943) (xy 143.47953 -294.852491) (xy 143.527749 -294.842647) (xy 143.576924 -294.840666)
			(xy 143.625779 -294.846598) (xy 143.67305 -294.86029) (xy 143.717512 -294.881388) (xy 143.758015 -294.909344)
			(xy 143.793508 -294.943436) (xy 143.823073 -294.98278) (xy 143.845944 -295.026357) (xy 143.861528 -295.073038)
			(xy 143.869423 -295.121615) (xy 143.869918 -295.146222) (xy 144.19886 -295.146222) (xy 144.20282 -295.097168)
			(xy 144.214597 -295.049384) (xy 144.233888 -295.004108) (xy 144.260191 -294.962512) (xy 144.292826 -294.925675)
			(xy 144.330947 -294.89455) (xy 144.373568 -294.869943) (xy 144.419584 -294.852491) (xy 144.467803 -294.842647)
			(xy 144.516978 -294.840666) (xy 144.565833 -294.846598) (xy 144.613104 -294.86029) (xy 144.657566 -294.881388)
			(xy 144.698069 -294.909344) (xy 144.733562 -294.943436) (xy 144.763127 -294.98278) (xy 144.785998 -295.026357)
			(xy 144.801582 -295.073038) (xy 144.809477 -295.121615) (xy 144.809972 -295.146222) (xy 145.138914 -295.146222)
			(xy 145.142874 -295.097168) (xy 145.154651 -295.049384) (xy 145.173942 -295.004108) (xy 145.200245 -294.962512)
			(xy 145.23288 -294.925675) (xy 145.271001 -294.89455) (xy 145.313622 -294.869943) (xy 145.359638 -294.852491)
			(xy 145.407857 -294.842647) (xy 145.457032 -294.840666) (xy 145.505887 -294.846598) (xy 145.553158 -294.86029)
			(xy 145.59762 -294.881388) (xy 145.638123 -294.909344) (xy 145.673616 -294.943436) (xy 145.703181 -294.98278)
			(xy 145.726052 -295.026357) (xy 145.741636 -295.073038) (xy 145.749531 -295.121615) (xy 145.750026 -295.146222)
			(xy 145.749531 -295.170829) (xy 145.741636 -295.219406) (xy 145.726052 -295.266087) (xy 145.703181 -295.309664)
			(xy 145.673616 -295.349008) (xy 145.638123 -295.3831) (xy 145.59762 -295.411056) (xy 145.553158 -295.432154)
			(xy 145.505887 -295.445846) (xy 145.457032 -295.451778) (xy 145.407857 -295.449797) (xy 145.359638 -295.439953)
			(xy 145.313622 -295.422501) (xy 145.271001 -295.397894) (xy 145.23288 -295.366769) (xy 145.200245 -295.329932)
			(xy 145.173942 -295.288336) (xy 145.154651 -295.24306) (xy 145.142874 -295.195276) (xy 145.138914 -295.146222)
			(xy 144.809972 -295.146222) (xy 144.809477 -295.170829) (xy 144.801582 -295.219406) (xy 144.785998 -295.266087)
			(xy 144.763127 -295.309664) (xy 144.733562 -295.349008) (xy 144.698069 -295.3831) (xy 144.657566 -295.411056)
			(xy 144.613104 -295.432154) (xy 144.565833 -295.445846) (xy 144.516978 -295.451778) (xy 144.467803 -295.449797)
			(xy 144.419584 -295.439953) (xy 144.373568 -295.422501) (xy 144.330947 -295.397894) (xy 144.292826 -295.366769)
			(xy 144.260191 -295.329932) (xy 144.233888 -295.288336) (xy 144.214597 -295.24306) (xy 144.20282 -295.195276)
			(xy 144.19886 -295.146222) (xy 143.869918 -295.146222) (xy 143.869423 -295.170829) (xy 143.861528 -295.219406)
			(xy 143.845944 -295.266087) (xy 143.823073 -295.309664) (xy 143.793508 -295.349008) (xy 143.758015 -295.3831)
			(xy 143.717512 -295.411056) (xy 143.67305 -295.432154) (xy 143.625779 -295.445846) (xy 143.576924 -295.451778)
			(xy 143.527749 -295.449797) (xy 143.47953 -295.439953) (xy 143.433514 -295.422501) (xy 143.390893 -295.397894)
			(xy 143.352772 -295.366769) (xy 143.320137 -295.329932) (xy 143.293834 -295.288336) (xy 143.274543 -295.24306)
			(xy 143.262766 -295.195276) (xy 143.258806 -295.146222) (xy 141.990064 -295.146222) (xy 141.989569 -295.170829)
			(xy 141.981674 -295.219406) (xy 141.96609 -295.266087) (xy 141.943219 -295.309664) (xy 141.913654 -295.349008)
			(xy 141.878161 -295.3831) (xy 141.837658 -295.411056) (xy 141.793196 -295.432154) (xy 141.745925 -295.445846)
			(xy 141.69707 -295.451778) (xy 141.647895 -295.449797) (xy 141.599676 -295.439953) (xy 141.55366 -295.422501)
			(xy 141.511039 -295.397894) (xy 141.472918 -295.366769) (xy 141.440283 -295.329932) (xy 141.41398 -295.288336)
			(xy 141.394689 -295.24306) (xy 141.382912 -295.195276) (xy 141.378952 -295.146222) (xy 141.05001 -295.146222)
			(xy 141.049515 -295.170829) (xy 141.04162 -295.219406) (xy 141.026036 -295.266087) (xy 141.003165 -295.309664)
			(xy 140.9736 -295.349008) (xy 140.938107 -295.3831) (xy 140.897604 -295.411056) (xy 140.853142 -295.432154)
			(xy 140.805871 -295.445846) (xy 140.757016 -295.451778) (xy 140.707841 -295.449797) (xy 140.659622 -295.439953)
			(xy 140.613606 -295.422501) (xy 140.570985 -295.397894) (xy 140.532864 -295.366769) (xy 140.500229 -295.329932)
			(xy 140.473926 -295.288336) (xy 140.454635 -295.24306) (xy 140.442858 -295.195276) (xy 140.438898 -295.146222)
			(xy 139.170156 -295.146222) (xy 139.169661 -295.170829) (xy 139.161766 -295.219406) (xy 139.146182 -295.266087)
			(xy 139.123311 -295.309664) (xy 139.093746 -295.349008) (xy 139.058253 -295.3831) (xy 139.01775 -295.411056)
			(xy 138.973288 -295.432154) (xy 138.926017 -295.445846) (xy 138.877162 -295.451778) (xy 138.827987 -295.449797)
			(xy 138.779768 -295.439953) (xy 138.733752 -295.422501) (xy 138.691131 -295.397894) (xy 138.65301 -295.366769)
			(xy 138.620375 -295.329932) (xy 138.594072 -295.288336) (xy 138.574781 -295.24306) (xy 138.563004 -295.195276)
			(xy 138.559044 -295.146222) (xy 138.230102 -295.146222) (xy 138.229607 -295.170829) (xy 138.221712 -295.219406)
			(xy 138.206128 -295.266087) (xy 138.183257 -295.309664) (xy 138.153692 -295.349008) (xy 138.118199 -295.3831)
			(xy 138.077696 -295.411056) (xy 138.033234 -295.432154) (xy 137.985963 -295.445846) (xy 137.937108 -295.451778)
			(xy 137.887933 -295.449797) (xy 137.839714 -295.439953) (xy 137.793698 -295.422501) (xy 137.751077 -295.397894)
			(xy 137.712956 -295.366769) (xy 137.680321 -295.329932) (xy 137.654018 -295.288336) (xy 137.634727 -295.24306)
			(xy 137.62295 -295.195276) (xy 137.61899 -295.146222) (xy 137.290048 -295.146222) (xy 137.289553 -295.170829)
			(xy 137.281658 -295.219406) (xy 137.266074 -295.266087) (xy 137.243203 -295.309664) (xy 137.213638 -295.349008)
			(xy 137.178145 -295.3831) (xy 137.137642 -295.411056) (xy 137.09318 -295.432154) (xy 137.045909 -295.445846)
			(xy 136.997054 -295.451778) (xy 136.947879 -295.449797) (xy 136.89966 -295.439953) (xy 136.853644 -295.422501)
			(xy 136.811023 -295.397894) (xy 136.772902 -295.366769) (xy 136.740267 -295.329932) (xy 136.713964 -295.288336)
			(xy 136.694673 -295.24306) (xy 136.682896 -295.195276) (xy 136.678936 -295.146222) (xy 136.349994 -295.146222)
			(xy 136.349499 -295.170829) (xy 136.341604 -295.219406) (xy 136.32602 -295.266087) (xy 136.303149 -295.309664)
			(xy 136.273584 -295.349008) (xy 136.238091 -295.3831) (xy 136.197588 -295.411056) (xy 136.153126 -295.432154)
			(xy 136.105855 -295.445846) (xy 136.057 -295.451778) (xy 136.007825 -295.449797) (xy 135.959606 -295.439953)
			(xy 135.91359 -295.422501) (xy 135.870969 -295.397894) (xy 135.832848 -295.366769) (xy 135.800213 -295.329932)
			(xy 135.77391 -295.288336) (xy 135.754619 -295.24306) (xy 135.742842 -295.195276) (xy 135.738882 -295.146222)
			(xy 135.40994 -295.146222) (xy 135.409445 -295.170829) (xy 135.40155 -295.219406) (xy 135.385966 -295.266087)
			(xy 135.363095 -295.309664) (xy 135.33353 -295.349008) (xy 135.298037 -295.3831) (xy 135.257534 -295.411056)
			(xy 135.213072 -295.432154) (xy 135.165801 -295.445846) (xy 135.116946 -295.451778) (xy 135.067771 -295.449797)
			(xy 135.019552 -295.439953) (xy 134.973536 -295.422501) (xy 134.930915 -295.397894) (xy 134.892794 -295.366769)
			(xy 134.860159 -295.329932) (xy 134.833856 -295.288336) (xy 134.814565 -295.24306) (xy 134.802788 -295.195276)
			(xy 134.798828 -295.146222) (xy 134.47014 -295.146222) (xy 134.469645 -295.170829) (xy 134.46175 -295.219406)
			(xy 134.446166 -295.266087) (xy 134.423295 -295.309664) (xy 134.39373 -295.349008) (xy 134.358237 -295.3831)
			(xy 134.317734 -295.411056) (xy 134.273272 -295.432154) (xy 134.226001 -295.445846) (xy 134.177146 -295.451778)
			(xy 134.127971 -295.449797) (xy 134.079752 -295.439953) (xy 134.033736 -295.422501) (xy 133.991115 -295.397894)
			(xy 133.952994 -295.366769) (xy 133.920359 -295.329932) (xy 133.894056 -295.288336) (xy 133.874765 -295.24306)
			(xy 133.862988 -295.195276) (xy 133.859028 -295.146222) (xy 133.530086 -295.146222) (xy 133.529591 -295.170829)
			(xy 133.521696 -295.219406) (xy 133.506112 -295.266087) (xy 133.483241 -295.309664) (xy 133.453676 -295.349008)
			(xy 133.418183 -295.3831) (xy 133.37768 -295.411056) (xy 133.333218 -295.432154) (xy 133.285947 -295.445846)
			(xy 133.237092 -295.451778) (xy 133.187917 -295.449797) (xy 133.139698 -295.439953) (xy 133.093682 -295.422501)
			(xy 133.051061 -295.397894) (xy 133.01294 -295.366769) (xy 132.980305 -295.329932) (xy 132.954002 -295.288336)
			(xy 132.934711 -295.24306) (xy 132.922934 -295.195276) (xy 132.918974 -295.146222) (xy 132.590032 -295.146222)
			(xy 132.589537 -295.170829) (xy 132.581642 -295.219406) (xy 132.566058 -295.266087) (xy 132.543187 -295.309664)
			(xy 132.513622 -295.349008) (xy 132.478129 -295.3831) (xy 132.437626 -295.411056) (xy 132.393164 -295.432154)
			(xy 132.345893 -295.445846) (xy 132.297038 -295.451778) (xy 132.247863 -295.449797) (xy 132.199644 -295.439953)
			(xy 132.153628 -295.422501) (xy 132.111007 -295.397894) (xy 132.072886 -295.366769) (xy 132.040251 -295.329932)
			(xy 132.013948 -295.288336) (xy 131.994657 -295.24306) (xy 131.98288 -295.195276) (xy 131.97892 -295.146222)
			(xy 131.649978 -295.146222) (xy 131.649483 -295.170829) (xy 131.641588 -295.219406) (xy 131.626004 -295.266087)
			(xy 131.603133 -295.309664) (xy 131.573568 -295.349008) (xy 131.538075 -295.3831) (xy 131.497572 -295.411056)
			(xy 131.45311 -295.432154) (xy 131.405839 -295.445846) (xy 131.356984 -295.451778) (xy 131.307809 -295.449797)
			(xy 131.25959 -295.439953) (xy 131.213574 -295.422501) (xy 131.170953 -295.397894) (xy 131.132832 -295.366769)
			(xy 131.100197 -295.329932) (xy 131.073894 -295.288336) (xy 131.054603 -295.24306) (xy 131.042826 -295.195276)
			(xy 131.038866 -295.146222) (xy 130.710178 -295.146222) (xy 130.709683 -295.170829) (xy 130.701788 -295.219406)
			(xy 130.686204 -295.266087) (xy 130.663333 -295.309664) (xy 130.633768 -295.349008) (xy 130.598275 -295.3831)
			(xy 130.557772 -295.411056) (xy 130.51331 -295.432154) (xy 130.466039 -295.445846) (xy 130.417184 -295.451778)
			(xy 130.368009 -295.449797) (xy 130.31979 -295.439953) (xy 130.273774 -295.422501) (xy 130.231153 -295.397894)
			(xy 130.193032 -295.366769) (xy 130.160397 -295.329932) (xy 130.134094 -295.288336) (xy 130.114803 -295.24306)
			(xy 130.103026 -295.195276) (xy 130.099066 -295.146222) (xy 129.770124 -295.146222) (xy 129.769629 -295.170829)
			(xy 129.761734 -295.219406) (xy 129.74615 -295.266087) (xy 129.723279 -295.309664) (xy 129.693714 -295.349008)
			(xy 129.658221 -295.3831) (xy 129.617718 -295.411056) (xy 129.573256 -295.432154) (xy 129.525985 -295.445846)
			(xy 129.47713 -295.451778) (xy 129.427955 -295.449797) (xy 129.379736 -295.439953) (xy 129.33372 -295.422501)
			(xy 129.291099 -295.397894) (xy 129.252978 -295.366769) (xy 129.220343 -295.329932) (xy 129.19404 -295.288336)
			(xy 129.174749 -295.24306) (xy 129.162972 -295.195276) (xy 129.159012 -295.146222) (xy 128.830639 -295.146222)
			(xy 128.8266 -295.195747) (xy 128.814589 -295.243978) (xy 128.794924 -295.289627) (xy 128.768124 -295.331488)
			(xy 128.734898 -295.368454) (xy 128.696123 -295.399551) (xy 128.652823 -295.423956) (xy 128.629664 -295.432988)
			(xy 128.614424 -295.438576) (xy 128.59639 -295.464484) (xy 128.59639 -295.510458) (xy 165.176215 -295.510458)
			(xy 165.18015 -295.456687) (xy 165.191873 -295.404063) (xy 165.211133 -295.353706) (xy 165.237519 -295.306689)
			(xy 165.270471 -295.264016) (xy 165.309284 -295.226595) (xy 165.353132 -295.195225) (xy 165.40108 -295.170573)
			(xy 165.452107 -295.153165) (xy 165.505125 -295.143372) (xy 165.559004 -295.141403) (xy 165.612595 -295.1473)
			(xy 165.664756 -295.160936) (xy 165.714376 -295.182023) (xy 165.760397 -295.210109) (xy 165.801839 -295.244597)
			(xy 165.837817 -295.284751) (xy 165.867565 -295.329715) (xy 165.89045 -295.378532) (xy 165.905982 -295.430161)
			(xy 165.913832 -295.483501) (xy 165.914324 -295.510458) (xy 165.913832 -295.537415) (xy 165.905982 -295.590755)
			(xy 165.89045 -295.642384) (xy 165.867565 -295.691201) (xy 165.837817 -295.736165) (xy 165.801839 -295.776319)
			(xy 165.760397 -295.810807) (xy 165.714376 -295.838893) (xy 165.664756 -295.85998) (xy 165.612595 -295.873616)
			(xy 165.559004 -295.879513) (xy 165.505125 -295.877544) (xy 165.452107 -295.867751) (xy 165.40108 -295.850343)
			(xy 165.353132 -295.825691) (xy 165.309284 -295.794321) (xy 165.270471 -295.7569) (xy 165.237519 -295.714227)
			(xy 165.211133 -295.66721) (xy 165.191873 -295.616853) (xy 165.18015 -295.564229) (xy 165.176215 -295.510458)
			(xy 128.59639 -295.510458) (xy 128.59639 -295.677844) (xy 128.59639 -295.678606) (xy 128.596878 -295.687329)
			(xy 128.602969 -295.703692) (xy 128.614177 -295.71708) (xy 128.621536 -295.721786) (xy 128.628648 -295.725088)
			(xy 128.73101 -295.765474) (xy 128.76149 -295.758616) (xy 128.772158 -295.747186) (xy 128.789601 -295.729347)
			(xy 128.82922 -295.699026) (xy 128.87324 -295.675549) (xy 128.920492 -295.65954) (xy 128.969717 -295.651424)
			(xy 128.994662 -295.65092) (xy 129.019919 -295.65141) (xy 129.069746 -295.659719) (xy 129.117526 -295.676116)
			(xy 129.161954 -295.700155) (xy 129.20182 -295.731179) (xy 129.236035 -295.768341) (xy 129.263665 -295.810629)
			(xy 129.283959 -295.856889) (xy 129.29636 -295.905858) (xy 129.300532 -295.9562) (xy 129.30053 -295.956228)
			(xy 129.628912 -295.956228) (xy 129.632872 -295.907174) (xy 129.644649 -295.85939) (xy 129.66394 -295.814114)
			(xy 129.690243 -295.772518) (xy 129.722878 -295.735681) (xy 129.760999 -295.704556) (xy 129.80362 -295.679949)
			(xy 129.849636 -295.662497) (xy 129.897855 -295.652653) (xy 129.94703 -295.650672) (xy 129.995885 -295.656604)
			(xy 130.043156 -295.670296) (xy 130.087618 -295.691394) (xy 130.128121 -295.71935) (xy 130.163614 -295.753442)
			(xy 130.193179 -295.792786) (xy 130.21605 -295.836363) (xy 130.231634 -295.883044) (xy 130.239529 -295.931621)
			(xy 130.240024 -295.956228) (xy 130.239529 -295.980835) (xy 130.237718 -295.991975) (xy 130.572409 -295.991975)
			(xy 130.575097 -295.942413) (xy 130.585767 -295.893939) (xy 130.604139 -295.847829) (xy 130.629728 -295.805299)
			(xy 130.66186 -295.767469) (xy 130.699689 -295.735335) (xy 130.742219 -295.709744) (xy 130.788327 -295.691371)
			(xy 130.836801 -295.680699) (xy 130.886363 -295.678009) (xy 130.935707 -295.683372) (xy 130.983534 -295.696647)
			(xy 131.028583 -295.717485) (xy 131.069667 -295.745336) (xy 131.105705 -295.779467) (xy 131.135747 -295.818977)
			(xy 131.159001 -295.862828) (xy 131.174855 -295.909863) (xy 131.182891 -295.958843) (xy 131.18338 -295.98366)
			(xy 131.183198 -295.997843) (xy 131.18053 -296.026083) (xy 131.178046 -296.040048) (xy 131.17576 -296.05224)
			(xy 131.182872 -296.075608) (xy 131.258056 -296.153332) (xy 131.28117 -296.160952) (xy 131.293616 -296.15892)
			(xy 131.307122 -296.156993) (xy 131.33433 -296.154955) (xy 131.347972 -296.154856) (xy 131.361682 -296.155013)
			(xy 131.389018 -296.157171) (xy 131.402582 -296.159174) (xy 131.415028 -296.160952) (xy 131.438142 -296.153332)
			(xy 131.513326 -296.075608) (xy 131.520438 -296.05224) (xy 131.518152 -296.040048) (xy 131.515673 -296.026083)
			(xy 131.513003 -295.997843) (xy 131.512818 -295.98366) (xy 131.51334 -295.958405) (xy 131.521653 -295.908583)
			(xy 131.538054 -295.860809) (xy 131.562095 -295.816386) (xy 131.593119 -295.776526) (xy 131.630281 -295.742316)
			(xy 131.672567 -295.71469) (xy 131.718823 -295.6944) (xy 131.767788 -295.682) (xy 131.818126 -295.677829)
			(xy 131.868464 -295.682) (xy 131.917429 -295.6944) (xy 131.963685 -295.71469) (xy 132.005971 -295.742316)
			(xy 132.043133 -295.776526) (xy 132.074157 -295.816386) (xy 132.098198 -295.860809) (xy 132.114599 -295.908583)
			(xy 132.122912 -295.958405) (xy 132.123434 -295.98366) (xy 132.123249 -295.997779) (xy 132.120576 -296.025892)
			(xy 132.1181 -296.039794) (xy 132.115814 -296.05224) (xy 132.122926 -296.075608) (xy 132.19811 -296.153078)
			(xy 132.221224 -296.160952) (xy 132.233416 -296.15892) (xy 132.246922 -296.156993) (xy 132.27413 -296.154955)
			(xy 132.287772 -296.154856) (xy 132.301546 -296.154995) (xy 132.329009 -296.157158) (xy 132.342636 -296.159174)
			(xy 132.355082 -296.160952) (xy 132.378196 -296.153332) (xy 132.45338 -296.075608) (xy 132.460492 -296.05224)
			(xy 132.458206 -296.040048) (xy 132.455726 -296.026083) (xy 132.453057 -295.997843) (xy 132.452872 -295.98366)
			(xy 132.453421 -295.958843) (xy 132.461457 -295.909863) (xy 132.477312 -295.862829) (xy 132.500566 -295.818979)
			(xy 132.530609 -295.779469) (xy 132.566647 -295.74534) (xy 132.607732 -295.71749) (xy 132.652782 -295.696654)
			(xy 132.700609 -295.683381) (xy 132.749953 -295.67802) (xy 132.799514 -295.680713) (xy 132.847987 -295.691388)
			(xy 132.894095 -295.709764) (xy 132.936622 -295.735358) (xy 132.974448 -295.767494) (xy 133.006577 -295.805327)
			(xy 133.032162 -295.847859) (xy 133.05053 -295.89397) (xy 133.061195 -295.942445) (xy 133.063877 -295.991981)
			(xy 133.392301 -295.991981) (xy 133.394988 -295.942417) (xy 133.405658 -295.893941) (xy 133.42403 -295.84783)
			(xy 133.449619 -295.805298) (xy 133.481752 -295.767466) (xy 133.519582 -295.735331) (xy 133.562112 -295.709739)
			(xy 133.608222 -295.691364) (xy 133.656697 -295.680691) (xy 133.706261 -295.678001) (xy 133.755607 -295.683364)
			(xy 133.803435 -295.696639) (xy 133.848485 -295.717477) (xy 133.889571 -295.745329) (xy 133.92561 -295.77946)
			(xy 133.955653 -295.818972) (xy 133.978908 -295.862824) (xy 133.994763 -295.90986) (xy 134.002799 -295.958842)
			(xy 134.003288 -295.98366) (xy 134.003106 -295.997843) (xy 134.000438 -296.026083) (xy 133.997954 -296.040048)
			(xy 133.995668 -296.05224) (xy 134.00278 -296.075608) (xy 134.077964 -296.153332) (xy 134.101078 -296.160952)
			(xy 134.113524 -296.15892) (xy 134.12703 -296.156992) (xy 134.154238 -296.154955) (xy 134.16788 -296.154856)
			(xy 134.18159 -296.155012) (xy 134.208926 -296.157171) (xy 134.22249 -296.159174) (xy 134.234936 -296.160952)
			(xy 134.25805 -296.153332) (xy 134.333234 -296.075608) (xy 134.340346 -296.05224) (xy 134.33806 -296.040048)
			(xy 134.335581 -296.026083) (xy 134.332911 -295.997843) (xy 134.332726 -295.98366) (xy 134.333248 -295.958405)
			(xy 134.341561 -295.908583) (xy 134.357962 -295.860809) (xy 134.382003 -295.816386) (xy 134.413027 -295.776526)
			(xy 134.450189 -295.742316) (xy 134.492475 -295.71469) (xy 134.538731 -295.6944) (xy 134.587696 -295.682)
			(xy 134.638034 -295.677829) (xy 134.688372 -295.682) (xy 134.737337 -295.6944) (xy 134.783593 -295.71469)
			(xy 134.825879 -295.742316) (xy 134.863041 -295.776526) (xy 134.894065 -295.816386) (xy 134.918106 -295.860809)
			(xy 134.934507 -295.908583) (xy 134.94282 -295.958405) (xy 134.943342 -295.98366) (xy 134.943159 -295.997843)
			(xy 134.940491 -296.026083) (xy 134.938008 -296.040048) (xy 134.935722 -296.05224) (xy 134.942834 -296.075608)
			(xy 135.018018 -296.153332) (xy 135.041132 -296.160952) (xy 135.053578 -296.15892) (xy 135.067083 -296.156986)
			(xy 135.094292 -296.154953) (xy 135.107934 -296.154856) (xy 135.121644 -296.155006) (xy 135.14898 -296.157169)
			(xy 135.162544 -296.159174) (xy 135.17499 -296.160952) (xy 135.198104 -296.153332) (xy 135.273288 -296.075608)
			(xy 135.2804 -296.05224) (xy 135.278114 -296.040048) (xy 135.275634 -296.026083) (xy 135.272965 -295.997843)
			(xy 135.27278 -295.98366) (xy 135.273321 -295.958843) (xy 135.281357 -295.909864) (xy 135.297211 -295.862829)
			(xy 135.320466 -295.81898) (xy 135.350508 -295.77947) (xy 135.386546 -295.745341) (xy 135.427631 -295.717491)
			(xy 135.47268 -295.696655) (xy 135.520506 -295.683382) (xy 135.56985 -295.67802) (xy 135.619411 -295.680712)
			(xy 135.667884 -295.691387) (xy 135.713992 -295.709763) (xy 135.756519 -295.735356) (xy 135.794345 -295.767492)
			(xy 135.826475 -295.805324) (xy 135.85206 -295.847855) (xy 135.870428 -295.893966) (xy 135.881095 -295.94244)
			(xy 135.881841 -295.956228) (xy 140.909052 -295.956228) (xy 140.913012 -295.907174) (xy 140.924789 -295.85939)
			(xy 140.94408 -295.814114) (xy 140.970383 -295.772518) (xy 141.003018 -295.735681) (xy 141.041139 -295.704556)
			(xy 141.08376 -295.679949) (xy 141.129776 -295.662497) (xy 141.177995 -295.652653) (xy 141.22717 -295.650672)
			(xy 141.276025 -295.656604) (xy 141.323296 -295.670296) (xy 141.367758 -295.691394) (xy 141.408261 -295.71935)
			(xy 141.443754 -295.753442) (xy 141.473319 -295.792786) (xy 141.49619 -295.836363) (xy 141.511774 -295.883044)
			(xy 141.519669 -295.931621) (xy 141.520164 -295.956228) (xy 143.72896 -295.956228) (xy 143.73292 -295.907174)
			(xy 143.744697 -295.85939) (xy 143.763988 -295.814114) (xy 143.790291 -295.772518) (xy 143.822926 -295.735681)
			(xy 143.861047 -295.704556) (xy 143.903668 -295.679949) (xy 143.949684 -295.662497) (xy 143.997903 -295.652653)
			(xy 144.047078 -295.650672) (xy 144.095933 -295.656604) (xy 144.143204 -295.670296) (xy 144.187666 -295.691394)
			(xy 144.228169 -295.71935) (xy 144.263662 -295.753442) (xy 144.293227 -295.792786) (xy 144.316098 -295.836363)
			(xy 144.331682 -295.883044) (xy 144.339577 -295.931621) (xy 144.340072 -295.956228) (xy 144.669014 -295.956228)
			(xy 144.672974 -295.907174) (xy 144.684751 -295.85939) (xy 144.704042 -295.814114) (xy 144.730345 -295.772518)
			(xy 144.76298 -295.735681) (xy 144.801101 -295.704556) (xy 144.843722 -295.679949) (xy 144.889738 -295.662497)
			(xy 144.937957 -295.652653) (xy 144.987132 -295.650672) (xy 145.035987 -295.656604) (xy 145.083258 -295.670296)
			(xy 145.12772 -295.691394) (xy 145.168223 -295.71935) (xy 145.203716 -295.753442) (xy 145.233281 -295.792786)
			(xy 145.256152 -295.836363) (xy 145.271736 -295.883044) (xy 145.279631 -295.931621) (xy 145.279707 -295.9354)
			(xy 166.774383 -295.9354) (xy 166.778318 -295.881629) (xy 166.790041 -295.829005) (xy 166.809301 -295.778648)
			(xy 166.835687 -295.731631) (xy 166.868639 -295.688958) (xy 166.907452 -295.651537) (xy 166.9513 -295.620167)
			(xy 166.999248 -295.595515) (xy 167.050275 -295.578107) (xy 167.103293 -295.568314) (xy 167.157172 -295.566345)
			(xy 167.210763 -295.572242) (xy 167.262924 -295.585878) (xy 167.312544 -295.606965) (xy 167.358565 -295.635051)
			(xy 167.400007 -295.669539) (xy 167.435985 -295.709693) (xy 167.465733 -295.754657) (xy 167.488618 -295.803474)
			(xy 167.50415 -295.855103) (xy 167.512 -295.908443) (xy 167.512492 -295.9354) (xy 171.476162 -295.9354)
			(xy 171.476698 -295.90268) (xy 171.485292 -295.837807) (xy 171.502344 -295.774627) (xy 171.527556 -295.71424)
			(xy 171.560492 -295.657692) (xy 171.60058 -295.605968) (xy 171.623482 -295.582594) (xy 171.630848 -295.575482)
			(xy 171.638722 -295.556686) (xy 171.638722 -295.463976) (xy 171.630848 -295.44518) (xy 171.623482 -295.438068)
			(xy 171.600608 -295.414667) (xy 171.560522 -295.362946) (xy 171.527583 -295.306403) (xy 171.502363 -295.246022)
			(xy 171.4853 -295.182848) (xy 171.47669 -295.11798) (xy 171.476162 -295.085262) (xy 171.476651 -295.054099)
			(xy 171.484463 -294.992265) (xy 171.499963 -294.931897) (xy 171.522906 -294.873949) (xy 171.552932 -294.819332)
			(xy 171.589566 -294.76891) (xy 171.632231 -294.723476) (xy 171.680253 -294.683748) (xy 171.732877 -294.650353)
			(xy 171.789271 -294.623816) (xy 171.848546 -294.604556) (xy 171.909767 -294.592877) (xy 171.97197 -294.588964)
			(xy 172.034173 -294.592877) (xy 172.095394 -294.604556) (xy 172.154669 -294.623816) (xy 172.211063 -294.650353)
			(xy 172.263687 -294.683748) (xy 172.311709 -294.723476) (xy 172.354374 -294.76891) (xy 172.391008 -294.819332)
			(xy 172.421034 -294.873949) (xy 172.443977 -294.931897) (xy 172.459477 -294.992265) (xy 172.467289 -295.054099)
			(xy 172.467778 -295.085262) (xy 175.57623 -295.085262) (xy 175.576778 -295.052562) (xy 175.585384 -294.987732)
			(xy 175.602441 -294.924596) (xy 175.627653 -294.864252) (xy 175.660583 -294.807748) (xy 175.700657 -294.756065)
			(xy 175.72355 -294.73271) (xy 175.730916 -294.725344) (xy 175.738536 -294.706802) (xy 175.738536 -294.613838)
			(xy 175.730916 -294.595296) (xy 175.72355 -294.58793) (xy 175.700648 -294.564582) (xy 175.660564 -294.512902)
			(xy 175.627628 -294.456399) (xy 175.602412 -294.396053) (xy 175.585355 -294.332914) (xy 175.576753 -294.268079)
			(xy 175.57623 -294.235378) (xy 175.576719 -294.204215) (xy 175.584531 -294.142381) (xy 175.600031 -294.082013)
			(xy 175.622974 -294.024065) (xy 175.653 -293.969448) (xy 175.689634 -293.919026) (xy 175.732299 -293.873592)
			(xy 175.780321 -293.833864) (xy 175.832945 -293.800469) (xy 175.889339 -293.773932) (xy 175.948614 -293.754672)
			(xy 176.009835 -293.742993) (xy 176.072038 -293.73908) (xy 176.134241 -293.742993) (xy 176.195462 -293.754672)
			(xy 176.254737 -293.773932) (xy 176.311131 -293.800469) (xy 176.363755 -293.833864) (xy 176.411777 -293.873592)
			(xy 176.454442 -293.919026) (xy 176.491076 -293.969448) (xy 176.521102 -294.024065) (xy 176.544045 -294.082013)
			(xy 176.559545 -294.142381) (xy 176.567357 -294.204215) (xy 176.567846 -294.235378) (xy 180.531023 -294.235378)
			(xy 180.534958 -294.181607) (xy 180.546681 -294.128983) (xy 180.565941 -294.078626) (xy 180.592327 -294.031609)
			(xy 180.625279 -293.988936) (xy 180.664092 -293.951515) (xy 180.70794 -293.920145) (xy 180.755888 -293.895493)
			(xy 180.806915 -293.878085) (xy 180.859933 -293.868292) (xy 180.913812 -293.866323) (xy 180.967403 -293.87222)
			(xy 181.019564 -293.885856) (xy 181.069184 -293.906943) (xy 181.115205 -293.935029) (xy 181.156647 -293.969517)
			(xy 181.192625 -294.009671) (xy 181.222373 -294.054635) (xy 181.245258 -294.103452) (xy 181.26079 -294.155081)
			(xy 181.26864 -294.208421) (xy 181.269132 -294.235378) (xy 181.26864 -294.262335) (xy 181.26079 -294.315675)
			(xy 181.245258 -294.367304) (xy 181.222373 -294.416121) (xy 181.192625 -294.461085) (xy 181.156647 -294.501239)
			(xy 181.115205 -294.535727) (xy 181.069184 -294.563813) (xy 181.019564 -294.5849) (xy 180.967403 -294.598536)
			(xy 180.913812 -294.604433) (xy 180.859933 -294.602464) (xy 180.806915 -294.592671) (xy 180.755888 -294.575263)
			(xy 180.70794 -294.550611) (xy 180.664092 -294.519241) (xy 180.625279 -294.48182) (xy 180.592327 -294.439147)
			(xy 180.565941 -294.39213) (xy 180.546681 -294.341773) (xy 180.534958 -294.289149) (xy 180.531023 -294.235378)
			(xy 176.567846 -294.235378) (xy 176.567331 -294.268079) (xy 176.558719 -294.332911) (xy 176.541656 -294.396048)
			(xy 176.516438 -294.456392) (xy 176.483503 -294.512895) (xy 176.443422 -294.564577) (xy 176.420526 -294.58793)
			(xy 176.41316 -294.595296) (xy 176.40554 -294.613838) (xy 176.40554 -294.66032) (xy 176.820337 -294.66032)
			(xy 176.824272 -294.606549) (xy 176.835995 -294.553925) (xy 176.855255 -294.503568) (xy 176.881641 -294.456551)
			(xy 176.914593 -294.413878) (xy 176.953406 -294.376457) (xy 176.997254 -294.345087) (xy 177.045202 -294.320435)
			(xy 177.096229 -294.303027) (xy 177.149247 -294.293234) (xy 177.203126 -294.291265) (xy 177.256717 -294.297162)
			(xy 177.308878 -294.310798) (xy 177.358498 -294.331885) (xy 177.404519 -294.359971) (xy 177.445961 -294.394459)
			(xy 177.481939 -294.434613) (xy 177.511687 -294.479577) (xy 177.534572 -294.528394) (xy 177.550104 -294.580023)
			(xy 177.557954 -294.633363) (xy 177.558446 -294.66032) (xy 177.557954 -294.687277) (xy 177.550104 -294.740617)
			(xy 177.534572 -294.792246) (xy 177.511687 -294.841063) (xy 177.481939 -294.886027) (xy 177.445961 -294.926181)
			(xy 177.404519 -294.960669) (xy 177.358498 -294.988755) (xy 177.308878 -295.009842) (xy 177.256717 -295.023478)
			(xy 177.203126 -295.029375) (xy 177.149247 -295.027406) (xy 177.096229 -295.017613) (xy 177.045202 -295.000205)
			(xy 176.997254 -294.975553) (xy 176.953406 -294.944183) (xy 176.914593 -294.906762) (xy 176.881641 -294.864089)
			(xy 176.855255 -294.817072) (xy 176.835995 -294.766715) (xy 176.824272 -294.714091) (xy 176.820337 -294.66032)
			(xy 176.40554 -294.66032) (xy 176.40554 -294.706802) (xy 176.41316 -294.725344) (xy 176.420526 -294.73271)
			(xy 176.443443 -294.756044) (xy 176.483526 -294.807726) (xy 176.516461 -294.864233) (xy 176.541674 -294.924582)
			(xy 176.558728 -294.987723) (xy 176.567325 -295.05256) (xy 176.567846 -295.085262) (xy 176.567357 -295.116425)
			(xy 176.559545 -295.178259) (xy 176.544045 -295.238627) (xy 176.521102 -295.296575) (xy 176.491076 -295.351192)
			(xy 176.454442 -295.401614) (xy 176.411777 -295.447048) (xy 176.363755 -295.486776) (xy 176.311131 -295.520171)
			(xy 176.254737 -295.546708) (xy 176.195462 -295.565968) (xy 176.134241 -295.577647) (xy 176.072038 -295.58156)
			(xy 176.009835 -295.577647) (xy 175.948614 -295.565968) (xy 175.889339 -295.546708) (xy 175.832945 -295.520171)
			(xy 175.780321 -295.486776) (xy 175.732299 -295.447048) (xy 175.689634 -295.401614) (xy 175.653 -295.351192)
			(xy 175.622974 -295.296575) (xy 175.600031 -295.238627) (xy 175.584531 -295.178259) (xy 175.576719 -295.116425)
			(xy 175.57623 -295.085262) (xy 172.467778 -295.085262) (xy 172.46727 -295.117983) (xy 172.458669 -295.182857)
			(xy 172.441611 -295.246036) (xy 172.416393 -295.306424) (xy 172.383452 -295.36297) (xy 172.343362 -295.414694)
			(xy 172.320458 -295.438068) (xy 172.313092 -295.44518) (xy 172.305218 -295.463976) (xy 172.305218 -295.510458)
			(xy 172.720269 -295.510458) (xy 172.724204 -295.456687) (xy 172.735927 -295.404063) (xy 172.755187 -295.353706)
			(xy 172.781573 -295.306689) (xy 172.814525 -295.264016) (xy 172.853338 -295.226595) (xy 172.897186 -295.195225)
			(xy 172.945134 -295.170573) (xy 172.996161 -295.153165) (xy 173.049179 -295.143372) (xy 173.103058 -295.141403)
			(xy 173.156649 -295.1473) (xy 173.20881 -295.160936) (xy 173.25843 -295.182023) (xy 173.304451 -295.210109)
			(xy 173.345893 -295.244597) (xy 173.381871 -295.284751) (xy 173.411619 -295.329715) (xy 173.434504 -295.378532)
			(xy 173.450036 -295.430161) (xy 173.457886 -295.483501) (xy 173.458378 -295.510458) (xy 173.457886 -295.537415)
			(xy 173.450036 -295.590755) (xy 173.434504 -295.642384) (xy 173.411619 -295.691201) (xy 173.381871 -295.736165)
			(xy 173.345893 -295.776319) (xy 173.304451 -295.810807) (xy 173.25843 -295.838893) (xy 173.20881 -295.85998)
			(xy 173.156649 -295.873616) (xy 173.103058 -295.879513) (xy 173.049179 -295.877544) (xy 172.996161 -295.867751)
			(xy 172.945134 -295.850343) (xy 172.897186 -295.825691) (xy 172.853338 -295.794321) (xy 172.814525 -295.7569)
			(xy 172.781573 -295.714227) (xy 172.755187 -295.66721) (xy 172.735927 -295.616853) (xy 172.724204 -295.564229)
			(xy 172.720269 -295.510458) (xy 172.305218 -295.510458) (xy 172.305218 -295.556686) (xy 172.313092 -295.575482)
			(xy 172.320458 -295.582594) (xy 172.34337 -295.605959) (xy 172.383451 -295.657689) (xy 172.416383 -295.714239)
			(xy 172.441596 -295.774628) (xy 172.458652 -295.837807) (xy 172.467255 -295.90268) (xy 172.467778 -295.9354)
			(xy 174.318437 -295.9354) (xy 174.322372 -295.881629) (xy 174.334095 -295.829005) (xy 174.353355 -295.778648)
			(xy 174.379741 -295.731631) (xy 174.412693 -295.688958) (xy 174.451506 -295.651537) (xy 174.495354 -295.620167)
			(xy 174.543302 -295.595515) (xy 174.594329 -295.578107) (xy 174.647347 -295.568314) (xy 174.701226 -295.566345)
			(xy 174.754817 -295.572242) (xy 174.806978 -295.585878) (xy 174.856598 -295.606965) (xy 174.902619 -295.635051)
			(xy 174.944061 -295.669539) (xy 174.980039 -295.709693) (xy 175.009787 -295.754657) (xy 175.032672 -295.803474)
			(xy 175.048204 -295.855103) (xy 175.056054 -295.908443) (xy 175.056546 -295.9354) (xy 179.020216 -295.9354)
			(xy 179.020766 -295.902681) (xy 179.029359 -295.837808) (xy 179.046409 -295.77463) (xy 179.071619 -295.714242)
			(xy 179.104552 -295.657695) (xy 179.144636 -295.605969) (xy 179.167536 -295.582594) (xy 179.174902 -295.575482)
			(xy 179.182776 -295.556686) (xy 179.182776 -295.463976) (xy 179.174902 -295.44518) (xy 179.167536 -295.438068)
			(xy 179.144653 -295.414676) (xy 179.10457 -295.362951) (xy 179.071633 -295.306407) (xy 179.046415 -295.246024)
			(xy 179.029353 -295.18285) (xy 179.020743 -295.117981) (xy 179.020216 -295.085262) (xy 179.020705 -295.054099)
			(xy 179.028517 -294.992265) (xy 179.044017 -294.931897) (xy 179.06696 -294.873949) (xy 179.096986 -294.819332)
			(xy 179.13362 -294.76891) (xy 179.176285 -294.723476) (xy 179.224307 -294.683748) (xy 179.276931 -294.650353)
			(xy 179.333325 -294.623816) (xy 179.3926 -294.604556) (xy 179.453821 -294.592877) (xy 179.516024 -294.588964)
			(xy 179.578227 -294.592877) (xy 179.639448 -294.604556) (xy 179.698723 -294.623816) (xy 179.755117 -294.650353)
			(xy 179.807741 -294.683748) (xy 179.855763 -294.723476) (xy 179.898428 -294.76891) (xy 179.935062 -294.819332)
			(xy 179.965088 -294.873949) (xy 179.988031 -294.931897) (xy 180.003531 -294.992265) (xy 180.011343 -295.054099)
			(xy 180.011832 -295.085262) (xy 183.120284 -295.085262) (xy 183.120816 -295.052562) (xy 183.129423 -294.98773)
			(xy 183.146482 -294.924593) (xy 183.171697 -294.864249) (xy 183.20463 -294.807745) (xy 183.244709 -294.756064)
			(xy 183.267604 -294.73271) (xy 183.27497 -294.725344) (xy 183.28259 -294.706802) (xy 183.28259 -294.613838)
			(xy 183.27497 -294.595296) (xy 183.267604 -294.58793) (xy 183.244712 -294.564572) (xy 183.204625 -294.512896)
			(xy 183.171686 -294.456395) (xy 183.146468 -294.39605) (xy 183.12941 -294.332912) (xy 183.120807 -294.268079)
			(xy 183.120284 -294.235378) (xy 183.120773 -294.204215) (xy 183.128585 -294.142381) (xy 183.144085 -294.082013)
			(xy 183.167028 -294.024065) (xy 183.197054 -293.969448) (xy 183.233688 -293.919026) (xy 183.276353 -293.873592)
			(xy 183.324375 -293.833864) (xy 183.376999 -293.800469) (xy 183.433393 -293.773932) (xy 183.492668 -293.754672)
			(xy 183.553889 -293.742993) (xy 183.616092 -293.73908) (xy 183.678295 -293.742993) (xy 183.739516 -293.754672)
			(xy 183.798791 -293.773932) (xy 183.855185 -293.800469) (xy 183.907809 -293.833864) (xy 183.955831 -293.873592)
			(xy 183.998496 -293.919026) (xy 184.03513 -293.969448) (xy 184.065156 -294.024065) (xy 184.088099 -294.082013)
			(xy 184.103599 -294.142381) (xy 184.111411 -294.204215) (xy 184.1119 -294.235378) (xy 184.111398 -294.268079)
			(xy 184.102786 -294.332913) (xy 184.085721 -294.39605) (xy 184.0605 -294.456395) (xy 184.027562 -294.512898)
			(xy 183.987478 -294.564578) (xy 183.96458 -294.58793) (xy 183.957214 -294.595296) (xy 183.949594 -294.613838)
			(xy 183.949594 -294.66032) (xy 184.364391 -294.66032) (xy 184.368326 -294.606549) (xy 184.380049 -294.553925)
			(xy 184.399309 -294.503568) (xy 184.425695 -294.456551) (xy 184.458647 -294.413878) (xy 184.49746 -294.376457)
			(xy 184.541308 -294.345087) (xy 184.589256 -294.320435) (xy 184.640283 -294.303027) (xy 184.693301 -294.293234)
			(xy 184.74718 -294.291265) (xy 184.800771 -294.297162) (xy 184.852932 -294.310798) (xy 184.902552 -294.331885)
			(xy 184.948573 -294.359971) (xy 184.990015 -294.394459) (xy 185.025993 -294.434613) (xy 185.055741 -294.479577)
			(xy 185.078626 -294.528394) (xy 185.094158 -294.580023) (xy 185.102008 -294.633363) (xy 185.1025 -294.66032)
			(xy 185.102008 -294.687277) (xy 185.094158 -294.740617) (xy 185.078626 -294.792246) (xy 185.055741 -294.841063)
			(xy 185.025993 -294.886027) (xy 184.990015 -294.926181) (xy 184.948573 -294.960669) (xy 184.902552 -294.988755)
			(xy 184.852932 -295.009842) (xy 184.800771 -295.023478) (xy 184.74718 -295.029375) (xy 184.693301 -295.027406)
			(xy 184.640283 -295.017613) (xy 184.589256 -295.000205) (xy 184.541308 -294.975553) (xy 184.49746 -294.944183)
			(xy 184.458647 -294.906762) (xy 184.425695 -294.864089) (xy 184.399309 -294.817072) (xy 184.380049 -294.766715)
			(xy 184.368326 -294.714091) (xy 184.364391 -294.66032) (xy 183.949594 -294.66032) (xy 183.949594 -294.706802)
			(xy 183.957214 -294.725344) (xy 183.96458 -294.73271) (xy 183.987507 -294.756035) (xy 184.027587 -294.80772)
			(xy 184.060519 -294.864229) (xy 184.08573 -294.924579) (xy 184.102783 -294.987722) (xy 184.111379 -295.05256)
			(xy 184.1119 -295.085262) (xy 184.111411 -295.116425) (xy 184.103599 -295.178259) (xy 184.088099 -295.238627)
			(xy 184.065156 -295.296575) (xy 184.03513 -295.351192) (xy 183.998496 -295.401614) (xy 183.955831 -295.447048)
			(xy 183.907809 -295.486776) (xy 183.855185 -295.520171) (xy 183.798791 -295.546708) (xy 183.739516 -295.565968)
			(xy 183.678295 -295.577647) (xy 183.616092 -295.58156) (xy 183.553889 -295.577647) (xy 183.492668 -295.565968)
			(xy 183.433393 -295.546708) (xy 183.376999 -295.520171) (xy 183.324375 -295.486776) (xy 183.276353 -295.447048)
			(xy 183.233688 -295.401614) (xy 183.197054 -295.351192) (xy 183.167028 -295.296575) (xy 183.144085 -295.238627)
			(xy 183.128585 -295.178259) (xy 183.120773 -295.116425) (xy 183.120284 -295.085262) (xy 180.011832 -295.085262)
			(xy 180.011337 -295.117983) (xy 180.002735 -295.182858) (xy 179.985676 -295.246039) (xy 179.960455 -295.306426)
			(xy 179.927512 -295.362973) (xy 179.887418 -295.414695) (xy 179.864512 -295.438068) (xy 179.857146 -295.44518)
			(xy 179.849272 -295.463976) (xy 179.849272 -295.510458) (xy 180.264323 -295.510458) (xy 180.268258 -295.456687)
			(xy 180.279981 -295.404063) (xy 180.299241 -295.353706) (xy 180.325627 -295.306689) (xy 180.358579 -295.264016)
			(xy 180.397392 -295.226595) (xy 180.44124 -295.195225) (xy 180.489188 -295.170573) (xy 180.540215 -295.153165)
			(xy 180.593233 -295.143372) (xy 180.647112 -295.141403) (xy 180.700703 -295.1473) (xy 180.752864 -295.160936)
			(xy 180.802484 -295.182023) (xy 180.848505 -295.210109) (xy 180.889947 -295.244597) (xy 180.925925 -295.284751)
			(xy 180.955673 -295.329715) (xy 180.978558 -295.378532) (xy 180.99409 -295.430161) (xy 181.00194 -295.483501)
			(xy 181.002432 -295.510458) (xy 181.00194 -295.537415) (xy 180.99409 -295.590755) (xy 180.978558 -295.642384)
			(xy 180.955673 -295.691201) (xy 180.925925 -295.736165) (xy 180.889947 -295.776319) (xy 180.848505 -295.810807)
			(xy 180.802484 -295.838893) (xy 180.752864 -295.85998) (xy 180.700703 -295.873616) (xy 180.647112 -295.879513)
			(xy 180.593233 -295.877544) (xy 180.540215 -295.867751) (xy 180.489188 -295.850343) (xy 180.44124 -295.825691)
			(xy 180.397392 -295.794321) (xy 180.358579 -295.7569) (xy 180.325627 -295.714227) (xy 180.299241 -295.66721)
			(xy 180.279981 -295.616853) (xy 180.268258 -295.564229) (xy 180.264323 -295.510458) (xy 179.849272 -295.510458)
			(xy 179.849272 -295.556686) (xy 179.857146 -295.575482) (xy 179.864512 -295.582594) (xy 179.887415 -295.605967)
			(xy 179.927498 -295.657695) (xy 179.960433 -295.714243) (xy 179.985648 -295.77463) (xy 180.002705 -295.837808)
			(xy 180.011308 -295.90268) (xy 180.011832 -295.9354) (xy 181.862491 -295.9354) (xy 181.866426 -295.881629)
			(xy 181.878149 -295.829005) (xy 181.897409 -295.778648) (xy 181.923795 -295.731631) (xy 181.956747 -295.688958)
			(xy 181.99556 -295.651537) (xy 182.039408 -295.620167) (xy 182.087356 -295.595515) (xy 182.138383 -295.578107)
			(xy 182.191401 -295.568314) (xy 182.24528 -295.566345) (xy 182.298871 -295.572242) (xy 182.351032 -295.585878)
			(xy 182.400652 -295.606965) (xy 182.446673 -295.635051) (xy 182.488115 -295.669539) (xy 182.524093 -295.709693)
			(xy 182.553841 -295.754657) (xy 182.576726 -295.803474) (xy 182.592258 -295.855103) (xy 182.600108 -295.908443)
			(xy 182.6006 -295.9354) (xy 182.600108 -295.962357) (xy 182.592258 -296.015697) (xy 182.576726 -296.067326)
			(xy 182.553841 -296.116143) (xy 182.524093 -296.161107) (xy 182.488115 -296.201261) (xy 182.446673 -296.235749)
			(xy 182.400652 -296.263835) (xy 182.351032 -296.284922) (xy 182.298871 -296.298558) (xy 182.24528 -296.304455)
			(xy 182.191401 -296.302486) (xy 182.138383 -296.292693) (xy 182.087356 -296.275285) (xy 182.039408 -296.250633)
			(xy 181.99556 -296.219263) (xy 181.956747 -296.181842) (xy 181.923795 -296.139169) (xy 181.897409 -296.092152)
			(xy 181.878149 -296.041795) (xy 181.866426 -295.989171) (xy 181.862491 -295.9354) (xy 180.011832 -295.9354)
			(xy 180.011343 -295.966563) (xy 180.003531 -296.028397) (xy 179.988031 -296.088765) (xy 179.965088 -296.146713)
			(xy 179.935062 -296.20133) (xy 179.898428 -296.251752) (xy 179.855763 -296.297186) (xy 179.807741 -296.336914)
			(xy 179.755117 -296.370309) (xy 179.698723 -296.396846) (xy 179.639448 -296.416106) (xy 179.578227 -296.427785)
			(xy 179.516024 -296.431698) (xy 179.453821 -296.427785) (xy 179.3926 -296.416106) (xy 179.333325 -296.396846)
			(xy 179.276931 -296.370309) (xy 179.224307 -296.336914) (xy 179.176285 -296.297186) (xy 179.13362 -296.251752)
			(xy 179.096986 -296.20133) (xy 179.06696 -296.146713) (xy 179.044017 -296.088765) (xy 179.028517 -296.028397)
			(xy 179.020705 -295.966563) (xy 179.020216 -295.9354) (xy 175.056546 -295.9354) (xy 175.056054 -295.962357)
			(xy 175.048204 -296.015697) (xy 175.032672 -296.067326) (xy 175.009787 -296.116143) (xy 174.980039 -296.161107)
			(xy 174.944061 -296.201261) (xy 174.902619 -296.235749) (xy 174.856598 -296.263835) (xy 174.806978 -296.284922)
			(xy 174.754817 -296.298558) (xy 174.701226 -296.304455) (xy 174.647347 -296.302486) (xy 174.594329 -296.292693)
			(xy 174.543302 -296.275285) (xy 174.495354 -296.250633) (xy 174.451506 -296.219263) (xy 174.412693 -296.181842)
			(xy 174.379741 -296.139169) (xy 174.353355 -296.092152) (xy 174.334095 -296.041795) (xy 174.322372 -295.989171)
			(xy 174.318437 -295.9354) (xy 172.467778 -295.9354) (xy 172.467289 -295.966563) (xy 172.459477 -296.028397)
			(xy 172.443977 -296.088765) (xy 172.421034 -296.146713) (xy 172.391008 -296.20133) (xy 172.354374 -296.251752)
			(xy 172.311709 -296.297186) (xy 172.263687 -296.336914) (xy 172.211063 -296.370309) (xy 172.154669 -296.396846)
			(xy 172.095394 -296.416106) (xy 172.034173 -296.427785) (xy 171.97197 -296.431698) (xy 171.909767 -296.427785)
			(xy 171.848546 -296.416106) (xy 171.789271 -296.396846) (xy 171.732877 -296.370309) (xy 171.680253 -296.336914)
			(xy 171.632231 -296.297186) (xy 171.589566 -296.251752) (xy 171.552932 -296.20133) (xy 171.522906 -296.146713)
			(xy 171.499963 -296.088765) (xy 171.484463 -296.028397) (xy 171.476651 -295.966563) (xy 171.476162 -295.9354)
			(xy 167.512492 -295.9354) (xy 167.512 -295.962357) (xy 167.50415 -296.015697) (xy 167.488618 -296.067326)
			(xy 167.465733 -296.116143) (xy 167.435985 -296.161107) (xy 167.400007 -296.201261) (xy 167.358565 -296.235749)
			(xy 167.312544 -296.263835) (xy 167.262924 -296.284922) (xy 167.210763 -296.298558) (xy 167.157172 -296.304455)
			(xy 167.103293 -296.302486) (xy 167.050275 -296.292693) (xy 166.999248 -296.275285) (xy 166.9513 -296.250633)
			(xy 166.907452 -296.219263) (xy 166.868639 -296.181842) (xy 166.835687 -296.139169) (xy 166.809301 -296.092152)
			(xy 166.790041 -296.041795) (xy 166.778318 -295.989171) (xy 166.774383 -295.9354) (xy 145.279707 -295.9354)
			(xy 145.280126 -295.956228) (xy 145.279631 -295.980835) (xy 145.271736 -296.029412) (xy 145.256152 -296.076093)
			(xy 145.233281 -296.11967) (xy 145.203716 -296.159014) (xy 145.168223 -296.193106) (xy 145.12772 -296.221062)
			(xy 145.083258 -296.24216) (xy 145.035987 -296.255852) (xy 144.987132 -296.261784) (xy 144.937957 -296.259803)
			(xy 144.889738 -296.249959) (xy 144.843722 -296.232507) (xy 144.801101 -296.2079) (xy 144.76298 -296.176775)
			(xy 144.730345 -296.139938) (xy 144.704042 -296.098342) (xy 144.684751 -296.053066) (xy 144.672974 -296.005282)
			(xy 144.669014 -295.956228) (xy 144.340072 -295.956228) (xy 144.339577 -295.980835) (xy 144.331682 -296.029412)
			(xy 144.316098 -296.076093) (xy 144.293227 -296.11967) (xy 144.263662 -296.159014) (xy 144.228169 -296.193106)
			(xy 144.187666 -296.221062) (xy 144.143204 -296.24216) (xy 144.095933 -296.255852) (xy 144.047078 -296.261784)
			(xy 143.997903 -296.259803) (xy 143.949684 -296.249959) (xy 143.903668 -296.232507) (xy 143.861047 -296.2079)
			(xy 143.822926 -296.176775) (xy 143.790291 -296.139938) (xy 143.763988 -296.098342) (xy 143.744697 -296.053066)
			(xy 143.73292 -296.005282) (xy 143.72896 -295.956228) (xy 141.520164 -295.956228) (xy 141.519669 -295.980835)
			(xy 141.511774 -296.029412) (xy 141.49619 -296.076093) (xy 141.473319 -296.11967) (xy 141.443754 -296.159014)
			(xy 141.408261 -296.193106) (xy 141.367758 -296.221062) (xy 141.323296 -296.24216) (xy 141.276025 -296.255852)
			(xy 141.22717 -296.261784) (xy 141.177995 -296.259803) (xy 141.129776 -296.249959) (xy 141.08376 -296.232507)
			(xy 141.041139 -296.2079) (xy 141.003018 -296.176775) (xy 140.970383 -296.139938) (xy 140.94408 -296.098342)
			(xy 140.924789 -296.053066) (xy 140.913012 -296.005282) (xy 140.909052 -295.956228) (xy 135.881841 -295.956228)
			(xy 135.883778 -295.992002) (xy 135.878409 -296.041345) (xy 135.865127 -296.089169) (xy 135.844283 -296.134215)
			(xy 135.816427 -296.175295) (xy 135.782291 -296.211327) (xy 135.742776 -296.241362) (xy 135.698923 -296.264609)
			(xy 135.651886 -296.280455) (xy 135.602905 -296.288483) (xy 135.578088 -296.288968) (xy 135.556498 -296.288206)
			(xy 135.543798 -296.28719) (xy 135.521446 -296.296842) (xy 135.45312 -296.380408) (xy 135.44804 -296.404284)
			(xy 135.451342 -296.416476) (xy 135.457299 -296.439642) (xy 135.463672 -296.487048) (xy 135.464042 -296.510964)
			(xy 135.463544 -296.537613) (xy 135.455601 -296.590317) (xy 135.447413 -296.616861) (xy 139.641824 -296.616861)
			(xy 139.641824 -296.563563) (xy 139.649767 -296.510859) (xy 139.665477 -296.459929) (xy 139.688603 -296.411908)
			(xy 139.718627 -296.367871) (xy 139.754879 -296.3288) (xy 139.79655 -296.295569) (xy 139.842708 -296.26892)
			(xy 139.892322 -296.249448) (xy 139.944284 -296.237588) (xy 139.997434 -296.233605) (xy 140.050584 -296.237588)
			(xy 140.102546 -296.249448) (xy 140.15216 -296.26892) (xy 140.198318 -296.295569) (xy 140.239989 -296.3288)
			(xy 140.276241 -296.367871) (xy 140.306265 -296.411908) (xy 140.329391 -296.459929) (xy 140.345101 -296.510859)
			(xy 140.353044 -296.563563) (xy 140.353542 -296.590212) (xy 140.353044 -296.616861) (xy 140.345101 -296.669565)
			(xy 140.329391 -296.720495) (xy 140.306265 -296.768516) (xy 140.294833 -296.785284) (xy 165.442915 -296.785284)
			(xy 165.44685 -296.731513) (xy 165.458573 -296.678889) (xy 165.477833 -296.628532) (xy 165.504219 -296.581515)
			(xy 165.537171 -296.538842) (xy 165.575984 -296.501421) (xy 165.619832 -296.470051) (xy 165.66778 -296.445399)
			(xy 165.718807 -296.427991) (xy 165.771825 -296.418198) (xy 165.825704 -296.416229) (xy 165.879295 -296.422126)
			(xy 165.931456 -296.435762) (xy 165.981076 -296.456849) (xy 166.027097 -296.484935) (xy 166.068539 -296.519423)
			(xy 166.104517 -296.559577) (xy 166.134265 -296.604541) (xy 166.15715 -296.653358) (xy 166.172682 -296.704987)
			(xy 166.180532 -296.758327) (xy 166.181024 -296.785284) (xy 172.986969 -296.785284) (xy 172.990904 -296.731513)
			(xy 173.002627 -296.678889) (xy 173.021887 -296.628532) (xy 173.048273 -296.581515) (xy 173.081225 -296.538842)
			(xy 173.120038 -296.501421) (xy 173.163886 -296.470051) (xy 173.211834 -296.445399) (xy 173.262861 -296.427991)
			(xy 173.315879 -296.418198) (xy 173.369758 -296.416229) (xy 173.423349 -296.422126) (xy 173.47551 -296.435762)
			(xy 173.52513 -296.456849) (xy 173.571151 -296.484935) (xy 173.612593 -296.519423) (xy 173.648571 -296.559577)
			(xy 173.678319 -296.604541) (xy 173.701204 -296.653358) (xy 173.716736 -296.704987) (xy 173.724586 -296.758327)
			(xy 173.725078 -296.785284) (xy 173.724586 -296.812241) (xy 173.716736 -296.865581) (xy 173.701204 -296.91721)
			(xy 173.678319 -296.966027) (xy 173.648571 -297.010991) (xy 173.612593 -297.051145) (xy 173.571151 -297.085633)
			(xy 173.52513 -297.113719) (xy 173.47551 -297.134806) (xy 173.423349 -297.148442) (xy 173.369758 -297.154339)
			(xy 173.315879 -297.15237) (xy 173.262861 -297.142577) (xy 173.211834 -297.125169) (xy 173.163886 -297.100517)
			(xy 173.120038 -297.069147) (xy 173.081225 -297.031726) (xy 173.048273 -296.989053) (xy 173.021887 -296.942036)
			(xy 173.002627 -296.891679) (xy 172.990904 -296.839055) (xy 172.986969 -296.785284) (xy 166.181024 -296.785284)
			(xy 166.180532 -296.812241) (xy 166.172682 -296.865581) (xy 166.15715 -296.91721) (xy 166.134265 -296.966027)
			(xy 166.104517 -297.010991) (xy 166.068539 -297.051145) (xy 166.027097 -297.085633) (xy 165.981076 -297.113719)
			(xy 165.931456 -297.134806) (xy 165.879295 -297.148442) (xy 165.825704 -297.154339) (xy 165.771825 -297.15237)
			(xy 165.718807 -297.142577) (xy 165.66778 -297.125169) (xy 165.619832 -297.100517) (xy 165.575984 -297.069147)
			(xy 165.537171 -297.031726) (xy 165.504219 -296.989053) (xy 165.477833 -296.942036) (xy 165.458573 -296.891679)
			(xy 165.44685 -296.839055) (xy 165.442915 -296.785284) (xy 140.294833 -296.785284) (xy 140.276241 -296.812553)
			(xy 140.239989 -296.851624) (xy 140.198318 -296.884855) (xy 140.15216 -296.911504) (xy 140.102546 -296.930976)
			(xy 140.050584 -296.942836) (xy 139.997434 -296.94682) (xy 139.944284 -296.942836) (xy 139.892322 -296.930976)
			(xy 139.842708 -296.911504) (xy 139.79655 -296.884855) (xy 139.754879 -296.851624) (xy 139.718627 -296.812553)
			(xy 139.688603 -296.768516) (xy 139.665477 -296.720495) (xy 139.649767 -296.669565) (xy 139.641824 -296.616861)
			(xy 135.447413 -296.616861) (xy 135.439891 -296.641247) (xy 135.416765 -296.689268) (xy 135.386741 -296.733305)
			(xy 135.350489 -296.772376) (xy 135.308818 -296.805607) (xy 135.26266 -296.832256) (xy 135.213046 -296.851728)
			(xy 135.161084 -296.863588) (xy 135.107934 -296.867572) (xy 135.054784 -296.863588) (xy 135.002822 -296.851728)
			(xy 134.953208 -296.832256) (xy 134.90705 -296.805607) (xy 134.865379 -296.772376) (xy 134.829127 -296.733305)
			(xy 134.799103 -296.689268) (xy 134.775977 -296.641247) (xy 134.760267 -296.590317) (xy 134.752324 -296.537613)
			(xy 134.751826 -296.510964) (xy 134.752192 -296.487047) (xy 134.758568 -296.439642) (xy 134.764526 -296.416476)
			(xy 134.767828 -296.404284) (xy 134.762748 -296.380662) (xy 134.694422 -296.297096) (xy 134.67207 -296.287444)
			(xy 134.65937 -296.288206) (xy 134.638034 -296.288968) (xy 134.616444 -296.288206) (xy 134.603744 -296.28719)
			(xy 134.581392 -296.296842) (xy 134.513066 -296.380408) (xy 134.507986 -296.404284) (xy 134.511288 -296.416476)
			(xy 134.517244 -296.439642) (xy 134.523617 -296.487048) (xy 134.523988 -296.510964) (xy 134.52349 -296.537613)
			(xy 134.515547 -296.590317) (xy 134.499837 -296.641247) (xy 134.476711 -296.689268) (xy 134.446687 -296.733305)
			(xy 134.410435 -296.772376) (xy 134.368764 -296.805607) (xy 134.322606 -296.832256) (xy 134.272992 -296.851728)
			(xy 134.22103 -296.863588) (xy 134.16788 -296.867572) (xy 134.11473 -296.863588) (xy 134.062768 -296.851728)
			(xy 134.013154 -296.832256) (xy 133.966996 -296.805607) (xy 133.925325 -296.772376) (xy 133.889073 -296.733305)
			(xy 133.859049 -296.689268) (xy 133.835923 -296.641247) (xy 133.820213 -296.590317) (xy 133.81227 -296.537613)
			(xy 133.811772 -296.510964) (xy 133.812136 -296.487047) (xy 133.818514 -296.439642) (xy 133.824472 -296.416476)
			(xy 133.827774 -296.404284) (xy 133.822694 -296.380662) (xy 133.754368 -296.297096) (xy 133.732016 -296.287444)
			(xy 133.719316 -296.288206) (xy 133.69798 -296.288968) (xy 133.673162 -296.288501) (xy 133.62418 -296.280467)
			(xy 133.577143 -296.264616) (xy 133.533289 -296.241364) (xy 133.493775 -296.211324) (xy 133.459641 -296.175287)
			(xy 133.431787 -296.134203) (xy 133.410946 -296.089154) (xy 133.397668 -296.041326) (xy 133.392301 -295.991981)
			(xy 133.063877 -295.991981) (xy 133.063878 -295.992007) (xy 133.058507 -296.04135) (xy 133.045225 -296.089175)
			(xy 133.02438 -296.13422) (xy 132.996523 -296.1753) (xy 132.962386 -296.211332) (xy 132.92287 -296.241366)
			(xy 132.879016 -296.264612) (xy 132.831979 -296.280457) (xy 132.782997 -296.288484) (xy 132.75818 -296.288968)
			(xy 132.736336 -296.288206) (xy 132.72389 -296.28719) (xy 132.701284 -296.296842) (xy 132.632958 -296.380408)
			(xy 132.627878 -296.404284) (xy 132.63118 -296.416476) (xy 132.637136 -296.439642) (xy 132.643509 -296.487048)
			(xy 132.64388 -296.510964) (xy 132.643382 -296.537613) (xy 132.635439 -296.590317) (xy 132.619729 -296.641247)
			(xy 132.596603 -296.689268) (xy 132.566579 -296.733305) (xy 132.530327 -296.772376) (xy 132.488656 -296.805607)
			(xy 132.442498 -296.832256) (xy 132.392884 -296.851728) (xy 132.340922 -296.863588) (xy 132.287772 -296.867572)
			(xy 132.234622 -296.863588) (xy 132.18266 -296.851728) (xy 132.133046 -296.832256) (xy 132.086888 -296.805607)
			(xy 132.045217 -296.772376) (xy 132.008965 -296.733305) (xy 131.978941 -296.689268) (xy 131.955815 -296.641247)
			(xy 131.940105 -296.590317) (xy 131.932162 -296.537613) (xy 131.931664 -296.510964) (xy 131.932029 -296.487047)
			(xy 131.938406 -296.439642) (xy 131.944364 -296.416476) (xy 131.947666 -296.404538) (xy 131.942586 -296.380662)
			(xy 131.87426 -296.297096) (xy 131.851908 -296.287444) (xy 131.839462 -296.288206) (xy 131.818126 -296.288968)
			(xy 131.796536 -296.288206) (xy 131.783836 -296.28719) (xy 131.761484 -296.296842) (xy 131.693158 -296.380408)
			(xy 131.688078 -296.404284) (xy 131.69138 -296.416476) (xy 131.697336 -296.439642) (xy 131.703709 -296.487048)
			(xy 131.70408 -296.510964) (xy 131.703582 -296.537613) (xy 131.695639 -296.590317) (xy 131.679929 -296.641247)
			(xy 131.656803 -296.689268) (xy 131.626779 -296.733305) (xy 131.590527 -296.772376) (xy 131.548856 -296.805607)
			(xy 131.502698 -296.832256) (xy 131.453084 -296.851728) (xy 131.401122 -296.863588) (xy 131.347972 -296.867572)
			(xy 131.294822 -296.863588) (xy 131.24286 -296.851728) (xy 131.193246 -296.832256) (xy 131.147088 -296.805607)
			(xy 131.105417 -296.772376) (xy 131.069165 -296.733305) (xy 131.039141 -296.689268) (xy 131.016015 -296.641247)
			(xy 131.000305 -296.590317) (xy 130.992362 -296.537613) (xy 130.991864 -296.510964) (xy 130.992229 -296.487047)
			(xy 130.998606 -296.439642) (xy 131.004564 -296.416476) (xy 131.007866 -296.404284) (xy 131.002786 -296.380662)
			(xy 130.93446 -296.297096) (xy 130.912108 -296.287444) (xy 130.899408 -296.288206) (xy 130.878072 -296.288968)
			(xy 130.853255 -296.288492) (xy 130.804274 -296.280458) (xy 130.757239 -296.264606) (xy 130.713388 -296.241353)
			(xy 130.673875 -296.211313) (xy 130.639744 -296.175277) (xy 130.611891 -296.134193) (xy 130.591052 -296.089145)
			(xy 130.577774 -296.041319) (xy 130.572409 -295.991975) (xy 130.237718 -295.991975) (xy 130.231634 -296.029412)
			(xy 130.21605 -296.076093) (xy 130.193179 -296.11967) (xy 130.163614 -296.159014) (xy 130.128121 -296.193106)
			(xy 130.087618 -296.221062) (xy 130.043156 -296.24216) (xy 129.995885 -296.255852) (xy 129.94703 -296.261784)
			(xy 129.897855 -296.259803) (xy 129.849636 -296.249959) (xy 129.80362 -296.232507) (xy 129.760999 -296.2079)
			(xy 129.722878 -296.176775) (xy 129.690243 -296.139938) (xy 129.66394 -296.098342) (xy 129.644649 -296.053066)
			(xy 129.632872 -296.005282) (xy 129.628912 -295.956228) (xy 129.30053 -295.956228) (xy 129.29636 -296.006542)
			(xy 129.283959 -296.055511) (xy 129.263665 -296.101771) (xy 129.236035 -296.144059) (xy 129.20182 -296.181221)
			(xy 129.161954 -296.212245) (xy 129.117526 -296.236284) (xy 129.069746 -296.252681) (xy 129.019919 -296.26099)
			(xy 128.994662 -296.261536) (xy 128.969715 -296.261045) (xy 128.920483 -296.25294) (xy 128.873225 -296.236936)
			(xy 128.829199 -296.213459) (xy 128.789577 -296.183135) (xy 128.772158 -296.16527) (xy 128.76149 -296.15384)
			(xy 128.73101 -296.146982) (xy 128.628648 -296.187368) (xy 128.621536 -296.19067) (xy 128.614172 -296.195378)
			(xy 128.602929 -296.208745) (xy 128.596857 -296.225122) (xy 128.59639 -296.23385) (xy 128.59639 -297.635422)
			(xy 168.158683 -297.635422) (xy 168.162618 -297.581651) (xy 168.174341 -297.529027) (xy 168.193601 -297.47867)
			(xy 168.219987 -297.431653) (xy 168.252939 -297.38898) (xy 168.291752 -297.351559) (xy 168.3356 -297.320189)
			(xy 168.383548 -297.295537) (xy 168.434575 -297.278129) (xy 168.487593 -297.268336) (xy 168.541472 -297.266367)
			(xy 168.595063 -297.272264) (xy 168.647224 -297.2859) (xy 168.696844 -297.306987) (xy 168.742865 -297.335073)
			(xy 168.784307 -297.369561) (xy 168.820285 -297.409715) (xy 168.850033 -297.454679) (xy 168.872918 -297.503496)
			(xy 168.88845 -297.555125) (xy 168.8963 -297.608465) (xy 168.896792 -297.635422) (xy 168.8963 -297.662379)
			(xy 168.88845 -297.715719) (xy 168.872918 -297.767348) (xy 168.850033 -297.816165) (xy 168.820285 -297.861129)
			(xy 168.784307 -297.901283) (xy 168.742865 -297.935771) (xy 168.696844 -297.963857) (xy 168.647224 -297.984944)
			(xy 168.595063 -297.99858) (xy 168.541472 -298.004477) (xy 168.487593 -298.002508) (xy 168.434575 -297.992715)
			(xy 168.383548 -297.975307) (xy 168.3356 -297.950655) (xy 168.291752 -297.919285) (xy 168.252939 -297.881864)
			(xy 168.219987 -297.839191) (xy 168.193601 -297.792174) (xy 168.174341 -297.741817) (xy 168.162618 -297.689193)
			(xy 168.158683 -297.635422) (xy 128.59639 -297.635422) (xy 128.59639 -298.485306) (xy 164.058615 -298.485306)
			(xy 164.06255 -298.431535) (xy 164.074273 -298.378911) (xy 164.093533 -298.328554) (xy 164.119919 -298.281537)
			(xy 164.152871 -298.238864) (xy 164.191684 -298.201443) (xy 164.235532 -298.170073) (xy 164.28348 -298.145421)
			(xy 164.334507 -298.128013) (xy 164.387525 -298.11822) (xy 164.441404 -298.116251) (xy 164.494995 -298.122148)
			(xy 164.547156 -298.135784) (xy 164.596776 -298.156871) (xy 164.642797 -298.184957) (xy 164.684239 -298.219445)
			(xy 164.720217 -298.259599) (xy 164.749965 -298.304563) (xy 164.77285 -298.35338) (xy 164.788382 -298.405009)
			(xy 164.796232 -298.458349) (xy 164.796724 -298.485306) (xy 164.796232 -298.512263) (xy 164.788382 -298.565603)
			(xy 164.77285 -298.617232) (xy 164.749965 -298.666049) (xy 164.720217 -298.711013) (xy 164.684239 -298.751167)
			(xy 164.642797 -298.785655) (xy 164.596776 -298.813741) (xy 164.547156 -298.834828) (xy 164.494995 -298.848464)
			(xy 164.441404 -298.854361) (xy 164.387525 -298.852392) (xy 164.334507 -298.842599) (xy 164.28348 -298.825191)
			(xy 164.235532 -298.800539) (xy 164.191684 -298.769169) (xy 164.152871 -298.731748) (xy 164.119919 -298.689075)
			(xy 164.093533 -298.642058) (xy 164.074273 -298.591701) (xy 164.06255 -298.539077) (xy 164.058615 -298.485306)
			(xy 128.59639 -298.485306) (xy 128.59639 -299.335444) (xy 168.158683 -299.335444) (xy 168.162618 -299.281673)
			(xy 168.174341 -299.229049) (xy 168.193601 -299.178692) (xy 168.219987 -299.131675) (xy 168.252939 -299.089002)
			(xy 168.291752 -299.051581) (xy 168.3356 -299.020211) (xy 168.383548 -298.995559) (xy 168.434575 -298.978151)
			(xy 168.487593 -298.968358) (xy 168.541472 -298.966389) (xy 168.595063 -298.972286) (xy 168.647224 -298.985922)
			(xy 168.696844 -299.007009) (xy 168.742865 -299.035095) (xy 168.784307 -299.069583) (xy 168.820285 -299.109737)
			(xy 168.850033 -299.154701) (xy 168.872918 -299.203518) (xy 168.88845 -299.255147) (xy 168.8963 -299.308487)
			(xy 168.896792 -299.335444) (xy 168.8963 -299.362401) (xy 168.88845 -299.415741) (xy 168.872918 -299.46737)
			(xy 168.850033 -299.516187) (xy 168.820285 -299.561151) (xy 168.784307 -299.601305) (xy 168.742865 -299.635793)
			(xy 168.696844 -299.663879) (xy 168.647224 -299.684966) (xy 168.595063 -299.698602) (xy 168.541472 -299.704499)
			(xy 168.487593 -299.70253) (xy 168.434575 -299.692737) (xy 168.383548 -299.675329) (xy 168.3356 -299.650677)
			(xy 168.291752 -299.619307) (xy 168.252939 -299.581886) (xy 168.219987 -299.539213) (xy 168.193601 -299.492196)
			(xy 168.174341 -299.441839) (xy 168.162618 -299.389215) (xy 168.158683 -299.335444) (xy 128.59639 -299.335444)
			(xy 128.59639 -300.185328) (xy 164.058615 -300.185328) (xy 164.06255 -300.131557) (xy 164.074273 -300.078933)
			(xy 164.093533 -300.028576) (xy 164.119919 -299.981559) (xy 164.152871 -299.938886) (xy 164.191684 -299.901465)
			(xy 164.235532 -299.870095) (xy 164.28348 -299.845443) (xy 164.334507 -299.828035) (xy 164.387525 -299.818242)
			(xy 164.441404 -299.816273) (xy 164.494995 -299.82217) (xy 164.547156 -299.835806) (xy 164.596776 -299.856893)
			(xy 164.642797 -299.884979) (xy 164.684239 -299.919467) (xy 164.720217 -299.959621) (xy 164.749965 -300.004585)
			(xy 164.77285 -300.053402) (xy 164.788382 -300.105031) (xy 164.796232 -300.158371) (xy 164.796724 -300.185328)
			(xy 164.796232 -300.212285) (xy 164.788382 -300.265625) (xy 164.77285 -300.317254) (xy 164.749965 -300.366071)
			(xy 164.720217 -300.411035) (xy 164.684239 -300.451189) (xy 164.642797 -300.485677) (xy 164.596776 -300.513763)
			(xy 164.547156 -300.53485) (xy 164.494995 -300.548486) (xy 164.441404 -300.554383) (xy 164.387525 -300.552414)
			(xy 164.334507 -300.542621) (xy 164.28348 -300.525213) (xy 164.235532 -300.500561) (xy 164.191684 -300.469191)
			(xy 164.152871 -300.43177) (xy 164.119919 -300.389097) (xy 164.093533 -300.34208) (xy 164.074273 -300.291723)
			(xy 164.06255 -300.239099) (xy 164.058615 -300.185328) (xy 128.59639 -300.185328) (xy 128.59639 -301.035212)
			(xy 168.158683 -301.035212) (xy 168.162618 -300.981441) (xy 168.174341 -300.928817) (xy 168.193601 -300.87846)
			(xy 168.219987 -300.831443) (xy 168.252939 -300.78877) (xy 168.291752 -300.751349) (xy 168.3356 -300.719979)
			(xy 168.383548 -300.695327) (xy 168.434575 -300.677919) (xy 168.487593 -300.668126) (xy 168.541472 -300.666157)
			(xy 168.595063 -300.672054) (xy 168.647224 -300.68569) (xy 168.696844 -300.706777) (xy 168.742865 -300.734863)
			(xy 168.784307 -300.769351) (xy 168.820285 -300.809505) (xy 168.850033 -300.854469) (xy 168.872918 -300.903286)
			(xy 168.88845 -300.954915) (xy 168.8963 -301.008255) (xy 168.896792 -301.035212) (xy 168.8963 -301.062169)
			(xy 168.88845 -301.115509) (xy 168.872918 -301.167138) (xy 168.850033 -301.215955) (xy 168.820285 -301.260919)
			(xy 168.784307 -301.301073) (xy 168.742865 -301.335561) (xy 168.696844 -301.363647) (xy 168.647224 -301.384734)
			(xy 168.595063 -301.39837) (xy 168.541472 -301.404267) (xy 168.487593 -301.402298) (xy 168.434575 -301.392505)
			(xy 168.383548 -301.375097) (xy 168.3356 -301.350445) (xy 168.291752 -301.319075) (xy 168.252939 -301.281654)
			(xy 168.219987 -301.238981) (xy 168.193601 -301.191964) (xy 168.174341 -301.141607) (xy 168.162618 -301.088983)
			(xy 168.158683 -301.035212) (xy 128.59639 -301.035212) (xy 128.59639 -301.88535) (xy 164.058615 -301.88535)
			(xy 164.06255 -301.831579) (xy 164.074273 -301.778955) (xy 164.093533 -301.728598) (xy 164.119919 -301.681581)
			(xy 164.152871 -301.638908) (xy 164.191684 -301.601487) (xy 164.235532 -301.570117) (xy 164.28348 -301.545465)
			(xy 164.334507 -301.528057) (xy 164.387525 -301.518264) (xy 164.441404 -301.516295) (xy 164.494995 -301.522192)
			(xy 164.547156 -301.535828) (xy 164.596776 -301.556915) (xy 164.642797 -301.585001) (xy 164.684239 -301.619489)
			(xy 164.720217 -301.659643) (xy 164.749965 -301.704607) (xy 164.77285 -301.753424) (xy 164.788382 -301.805053)
			(xy 164.796232 -301.858393) (xy 164.796724 -301.88535) (xy 164.796232 -301.912307) (xy 164.788382 -301.965647)
			(xy 164.77285 -302.017276) (xy 164.749965 -302.066093) (xy 164.720217 -302.111057) (xy 164.684239 -302.151211)
			(xy 164.642797 -302.185699) (xy 164.596776 -302.213785) (xy 164.547156 -302.234872) (xy 164.494995 -302.248508)
			(xy 164.441404 -302.254405) (xy 164.387525 -302.252436) (xy 164.334507 -302.242643) (xy 164.28348 -302.225235)
			(xy 164.235532 -302.200583) (xy 164.191684 -302.169213) (xy 164.152871 -302.131792) (xy 164.119919 -302.089119)
			(xy 164.093533 -302.042102) (xy 164.074273 -301.991745) (xy 164.06255 -301.939121) (xy 164.058615 -301.88535)
			(xy 128.59639 -301.88535) (xy 128.59639 -304.780442) (xy 140.011662 -304.780442) (xy 140.015692 -304.638092)
			(xy 140.027769 -304.496199) (xy 140.047854 -304.355216) (xy 140.075883 -304.215595) (xy 140.111767 -304.077783)
			(xy 140.155389 -303.942222) (xy 140.206611 -303.809347) (xy 140.265269 -303.679582) (xy 140.331174 -303.553343)
			(xy 140.404115 -303.431035) (xy 140.483859 -303.31305) (xy 140.570151 -303.199765) (xy 140.662713 -303.091544)
			(xy 140.76125 -302.988732) (xy 140.865445 -302.89166) (xy 140.974966 -302.800639) (xy 141.08946 -302.715959)
			(xy 141.208562 -302.637893) (xy 141.33189 -302.566689) (xy 141.459048 -302.502577) (xy 141.58963 -302.445762)
			(xy 141.723218 -302.396425) (xy 141.859382 -302.354725) (xy 141.997688 -302.320796) (xy 142.137691 -302.294745)
			(xy 142.278945 -302.276657) (xy 142.420995 -302.266589) (xy 142.563387 -302.264574) (xy 142.705666 -302.270618)
			(xy 142.847374 -302.284701) (xy 142.988059 -302.30678) (xy 143.127269 -302.336782) (xy 143.264559 -302.374612)
			(xy 143.399489 -302.420148) (xy 143.531627 -302.473246) (xy 143.660549 -302.533733) (xy 143.785842 -302.601418)
			(xy 143.907105 -302.676083) (xy 143.992007 -302.735234) (xy 166.774383 -302.735234) (xy 166.778318 -302.681463)
			(xy 166.790041 -302.628839) (xy 166.809301 -302.578482) (xy 166.835687 -302.531465) (xy 166.868639 -302.488792)
			(xy 166.907452 -302.451371) (xy 166.9513 -302.420001) (xy 166.999248 -302.395349) (xy 167.050275 -302.377941)
			(xy 167.103293 -302.368148) (xy 167.157172 -302.366179) (xy 167.210763 -302.372076) (xy 167.262924 -302.385712)
			(xy 167.312544 -302.406799) (xy 167.358565 -302.434885) (xy 167.400007 -302.469373) (xy 167.435985 -302.509527)
			(xy 167.465733 -302.554491) (xy 167.488618 -302.603308) (xy 167.50415 -302.654937) (xy 167.512 -302.708277)
			(xy 167.512492 -302.735234) (xy 171.476162 -302.735234) (xy 171.476643 -302.704037) (xy 171.48446 -302.642136)
			(xy 171.499988 -302.581706) (xy 171.52298 -302.523704) (xy 171.553074 -302.469049) (xy 171.589792 -302.418604)
			(xy 171.632553 -302.373168) (xy 171.68068 -302.333462) (xy 171.706794 -302.316388) (xy 171.716954 -302.309784)
			(xy 171.729146 -302.289972) (xy 171.738544 -302.185832) (xy 171.730162 -302.164242) (xy 171.721272 -302.15586)
			(xy 171.703011 -302.13832) (xy 171.67093 -302.099148) (xy 171.644509 -302.055957) (xy 171.624244 -302.009557)
			(xy 171.610516 -301.960821) (xy 171.603584 -301.910666) (xy 171.603162 -301.88535) (xy 171.603572 -301.860002)
			(xy 171.610511 -301.809782) (xy 171.624263 -301.760986) (xy 171.644571 -301.714535) (xy 171.67105 -301.671303)
			(xy 171.703203 -301.632106) (xy 171.721526 -301.614586) (xy 171.730416 -301.606458) (xy 171.738798 -301.584614)
			(xy 171.729146 -301.480474) (xy 171.716954 -301.460662) (xy 171.706794 -301.454312) (xy 171.68068 -301.437217)
			(xy 171.632558 -301.397464) (xy 171.589802 -301.351989) (xy 171.553089 -301.301511) (xy 171.522996 -301.246826)
			(xy 171.5 -301.188799) (xy 171.484464 -301.128345) (xy 171.476634 -301.066421) (xy 171.476162 -301.035212)
			(xy 171.476626 -301.004015) (xy 171.484446 -300.942113) (xy 171.499976 -300.881683) (xy 171.522971 -300.823681)
			(xy 171.553067 -300.769025) (xy 171.589787 -300.71858) (xy 171.63255 -300.673145) (xy 171.680679 -300.633439)
			(xy 171.706794 -300.616366) (xy 171.716954 -300.609762) (xy 171.729146 -300.58995) (xy 171.738544 -300.48581)
			(xy 171.730162 -300.46422) (xy 171.721272 -300.455838) (xy 171.701376 -300.436673) (xy 171.666913 -300.393501)
			(xy 171.639275 -300.345673) (xy 171.619078 -300.294257) (xy 171.606775 -300.240404) (xy 171.602642 -300.185319)
			(xy 171.60677 -300.130233) (xy 171.619067 -300.076379) (xy 171.639258 -300.024962) (xy 171.666892 -299.97713)
			(xy 171.70135 -299.933955) (xy 171.721272 -299.914818) (xy 171.730162 -299.906436) (xy 171.738544 -299.884846)
			(xy 171.729146 -299.780706) (xy 171.716954 -299.760894) (xy 171.706794 -299.75429) (xy 171.680683 -299.737215)
			(xy 171.632566 -299.697498) (xy 171.589813 -299.652058) (xy 171.5531 -299.601612) (xy 171.523006 -299.546959)
			(xy 171.500009 -299.488961) (xy 171.48447 -299.428536) (xy 171.476636 -299.366639) (xy 171.476162 -299.335444)
			(xy 171.476636 -299.304235) (xy 171.484461 -299.242309) (xy 171.499994 -299.181854) (xy 171.522988 -299.123826)
			(xy 171.553081 -299.06914) (xy 171.589796 -299.018663) (xy 171.632555 -298.97319) (xy 171.68068 -298.933441)
			(xy 171.706794 -298.916344) (xy 171.716954 -298.909994) (xy 171.729146 -298.890182) (xy 171.738798 -298.786042)
			(xy 171.730416 -298.764198) (xy 171.721526 -298.75607) (xy 171.703197 -298.738557) (xy 171.671054 -298.699354)
			(xy 171.644581 -298.656119) (xy 171.624277 -298.609667) (xy 171.610525 -298.560872) (xy 171.603583 -298.510654)
			(xy 171.603162 -298.485306) (xy 171.603555 -298.459987) (xy 171.610482 -298.409827) (xy 171.624208 -298.361085)
			(xy 171.644474 -298.31468) (xy 171.670898 -298.271485) (xy 171.702985 -298.232311) (xy 171.721272 -298.214796)
			(xy 171.730162 -298.206414) (xy 171.738544 -298.184824) (xy 171.729146 -298.080684) (xy 171.716954 -298.060872)
			(xy 171.706794 -298.054268) (xy 171.680673 -298.037207) (xy 171.632556 -297.997489) (xy 171.589804 -297.952046)
			(xy 171.553091 -297.901599) (xy 171.522999 -297.846943) (xy 171.500003 -297.788943) (xy 171.484466 -297.728517)
			(xy 171.476634 -297.666618) (xy 171.476162 -297.635422) (xy 171.476651 -297.604259) (xy 171.484463 -297.542425)
			(xy 171.499963 -297.482057) (xy 171.522906 -297.424109) (xy 171.552932 -297.369492) (xy 171.589566 -297.31907)
			(xy 171.632231 -297.273636) (xy 171.680253 -297.233908) (xy 171.732877 -297.200513) (xy 171.789271 -297.173976)
			(xy 171.848546 -297.154716) (xy 171.909767 -297.143037) (xy 171.97197 -297.139124) (xy 172.034173 -297.143037)
			(xy 172.095394 -297.154716) (xy 172.154669 -297.173976) (xy 172.211063 -297.200513) (xy 172.263687 -297.233908)
			(xy 172.311709 -297.273636) (xy 172.354374 -297.31907) (xy 172.391008 -297.369492) (xy 172.421034 -297.424109)
			(xy 172.443977 -297.482057) (xy 172.459477 -297.542425) (xy 172.467289 -297.604259) (xy 172.467778 -297.635422)
			(xy 172.467369 -297.666621) (xy 172.459544 -297.728526) (xy 172.444007 -297.788959) (xy 172.421005 -297.846963)
			(xy 172.390902 -297.901619) (xy 172.354174 -297.952062) (xy 172.311402 -297.997495) (xy 172.263265 -298.037197)
			(xy 172.237146 -298.054268) (xy 172.226986 -298.060872) (xy 172.214794 -298.080684) (xy 172.205396 -298.184824)
			(xy 172.213778 -298.206414) (xy 172.222668 -298.214796) (xy 172.240963 -298.232301) (xy 172.27304 -298.271481)
			(xy 172.299455 -298.314681) (xy 172.319714 -298.361087) (xy 172.333435 -298.409828) (xy 172.34036 -298.459988)
			(xy 172.340778 -298.485306) (xy 172.340357 -298.510654) (xy 172.333424 -298.560874) (xy 172.319675 -298.60967)
			(xy 172.299369 -298.656123) (xy 172.27289 -298.699354) (xy 172.240738 -298.73855) (xy 172.222414 -298.75607)
			(xy 172.213524 -298.764198) (xy 172.205142 -298.786042) (xy 172.214794 -298.890182) (xy 172.226986 -298.909994)
			(xy 172.237146 -298.916344) (xy 172.26325 -298.933455) (xy 172.31137 -298.973207) (xy 172.354124 -299.01868)
			(xy 172.390838 -299.069156) (xy 172.420932 -299.123838) (xy 172.44393 -299.181863) (xy 172.459469 -299.242314)
			(xy 172.467304 -299.304236) (xy 172.467778 -299.335444) (xy 172.467308 -299.366641) (xy 172.459492 -299.428544)
			(xy 172.443965 -299.488975) (xy 172.420972 -299.546978) (xy 172.390877 -299.601635) (xy 172.354157 -299.652079)
			(xy 172.311393 -299.697513) (xy 172.263262 -299.737218) (xy 172.237146 -299.75429) (xy 172.226986 -299.760894)
			(xy 172.214794 -299.780706) (xy 172.205396 -299.884846) (xy 172.213778 -299.906436) (xy 172.222668 -299.914818)
			(xy 172.242623 -299.933926) (xy 172.27709 -299.977104) (xy 172.304732 -300.02494) (xy 172.324929 -300.076364)
			(xy 172.337229 -300.130225) (xy 172.341359 -300.185319) (xy 172.337224 -300.240412) (xy 172.324917 -300.294272)
			(xy 172.304715 -300.345694) (xy 172.277069 -300.393528) (xy 172.242597 -300.436702) (xy 172.222668 -300.455838)
			(xy 172.213778 -300.46422) (xy 172.205396 -300.48581) (xy 172.214794 -300.58995) (xy 172.226986 -300.609762)
			(xy 172.237146 -300.616366) (xy 172.263224 -300.633491) (xy 172.311343 -300.673199) (xy 172.354099 -300.71863)
			(xy 172.390817 -300.769068) (xy 172.420915 -300.823715) (xy 172.443918 -300.881706) (xy 172.459462 -300.942126)
			(xy 172.467301 -301.004019) (xy 172.467778 -301.035212) (xy 172.467297 -301.066421) (xy 172.459476 -301.128348)
			(xy 172.443947 -301.188804) (xy 172.420955 -301.246833) (xy 172.390863 -301.301519) (xy 172.354147 -301.351997)
			(xy 172.311388 -301.397469) (xy 172.263261 -301.437216) (xy 172.237146 -301.454312) (xy 172.226986 -301.460662)
			(xy 172.214794 -301.480474) (xy 172.205142 -301.584614) (xy 172.213524 -301.606458) (xy 172.222414 -301.614586)
			(xy 172.240729 -301.632113) (xy 172.272872 -301.671314) (xy 172.299346 -301.714546) (xy 172.319652 -301.760995)
			(xy 172.333408 -301.809787) (xy 172.340354 -301.860003) (xy 172.340778 -301.88535) (xy 175.57623 -301.88535)
			(xy 175.576677 -301.85414) (xy 175.584503 -301.792212) (xy 175.600037 -301.731755) (xy 175.623034 -301.673725)
			(xy 175.653131 -301.619039) (xy 175.689851 -301.568562) (xy 175.732615 -301.523091) (xy 175.780745 -301.483345)
			(xy 175.806862 -301.46625) (xy 175.817022 -301.4599) (xy 175.829214 -301.440088) (xy 175.838866 -301.335948)
			(xy 175.830484 -301.314104) (xy 175.821594 -301.305976) (xy 175.803262 -301.288466) (xy 175.77112 -301.249262)
			(xy 175.744648 -301.206026) (xy 175.724345 -301.159573) (xy 175.710593 -301.110778) (xy 175.703651 -301.06056)
			(xy 175.70323 -301.035212) (xy 175.703636 -301.009894) (xy 175.710563 -300.959734) (xy 175.724286 -300.910993)
			(xy 175.744549 -300.864589) (xy 175.770971 -300.821393) (xy 175.803054 -300.782218) (xy 175.82134 -300.764702)
			(xy 175.83023 -300.75632) (xy 175.838612 -300.73473) (xy 175.829214 -300.63059) (xy 175.817022 -300.610778)
			(xy 175.806862 -300.604174) (xy 175.780775 -300.58706) (xy 175.732649 -300.547354) (xy 175.689887 -300.501921)
			(xy 175.653166 -300.451481) (xy 175.623067 -300.39683) (xy 175.600065 -300.338833) (xy 175.584525 -300.278408)
			(xy 175.576692 -300.216511) (xy 175.57669 -300.154119) (xy 175.584519 -300.092221) (xy 175.600056 -300.031795)
			(xy 175.623054 -299.973797) (xy 175.65315 -299.919145) (xy 175.689868 -299.868702) (xy 175.732627 -299.823267)
			(xy 175.780751 -299.783558) (xy 175.806862 -299.766482) (xy 175.817022 -299.759878) (xy 175.829214 -299.740066)
			(xy 175.838612 -299.635926) (xy 175.83023 -299.614336) (xy 175.82134 -299.605954) (xy 175.80307 -299.588423)
			(xy 175.770991 -299.549249) (xy 175.744572 -299.506055) (xy 175.724309 -299.459653) (xy 175.710583 -299.410917)
			(xy 175.703651 -299.36076) (xy 175.70323 -299.335444) (xy 175.703615 -299.310095) (xy 175.710555 -299.259873)
			(xy 175.724311 -299.211076) (xy 175.744623 -299.164624) (xy 175.771109 -299.121393) (xy 175.803267 -299.082199)
			(xy 175.821594 -299.06468) (xy 175.830484 -299.056552) (xy 175.838866 -299.034708) (xy 175.829214 -298.930568)
			(xy 175.817022 -298.910756) (xy 175.806862 -298.904406) (xy 175.780737 -298.887326) (xy 175.732617 -298.84757)
			(xy 175.689863 -298.802092) (xy 175.653151 -298.751612) (xy 175.62306 -298.696925) (xy 175.600065 -298.638896)
			(xy 175.58453 -298.578441) (xy 175.576701 -298.516515) (xy 175.57623 -298.485306) (xy 175.576704 -298.454109)
			(xy 175.584524 -298.392208) (xy 175.600054 -298.331779) (xy 175.623048 -298.273778) (xy 175.653142 -298.219122)
			(xy 175.689861 -298.168677) (xy 175.732621 -298.123242) (xy 175.780749 -298.083534) (xy 175.806862 -298.06646)
			(xy 175.817022 -298.059856) (xy 175.829214 -298.040044) (xy 175.838612 -297.935904) (xy 175.83023 -297.914314)
			(xy 175.82134 -297.905932) (xy 175.80306 -297.888412) (xy 175.770982 -297.849235) (xy 175.744564 -297.806039)
			(xy 175.724302 -297.759635) (xy 175.710578 -297.710897) (xy 175.70365 -297.660739) (xy 175.70323 -297.635422)
			(xy 175.703667 -297.610074) (xy 175.710597 -297.559855) (xy 175.724342 -297.511059) (xy 175.744645 -297.464607)
			(xy 175.771121 -297.421375) (xy 175.803271 -297.382178) (xy 175.821594 -297.364658) (xy 175.830484 -297.35653)
			(xy 175.838866 -297.334686) (xy 175.829214 -297.230546) (xy 175.817022 -297.210734) (xy 175.806862 -297.204384)
			(xy 175.780727 -297.187319) (xy 175.732607 -297.147561) (xy 175.689853 -297.102081) (xy 175.653142 -297.051598)
			(xy 175.623052 -296.996909) (xy 175.600059 -296.938878) (xy 175.584527 -296.878421) (xy 175.5767 -296.816494)
			(xy 175.57623 -296.785284) (xy 175.576719 -296.754121) (xy 175.584531 -296.692287) (xy 175.600031 -296.631919)
			(xy 175.622974 -296.573971) (xy 175.653 -296.519354) (xy 175.689634 -296.468932) (xy 175.732299 -296.423498)
			(xy 175.780321 -296.38377) (xy 175.832945 -296.350375) (xy 175.889339 -296.323838) (xy 175.948614 -296.304578)
			(xy 176.009835 -296.292899) (xy 176.072038 -296.288986) (xy 176.134241 -296.292899) (xy 176.195462 -296.304578)
			(xy 176.254737 -296.323838) (xy 176.311131 -296.350375) (xy 176.363755 -296.38377) (xy 176.411777 -296.423498)
			(xy 176.454442 -296.468932) (xy 176.491076 -296.519354) (xy 176.521102 -296.573971) (xy 176.544045 -296.631919)
			(xy 176.559545 -296.692287) (xy 176.567357 -296.754121) (xy 176.567846 -296.785284) (xy 180.531023 -296.785284)
			(xy 180.534958 -296.731513) (xy 180.546681 -296.678889) (xy 180.565941 -296.628532) (xy 180.592327 -296.581515)
			(xy 180.625279 -296.538842) (xy 180.664092 -296.501421) (xy 180.70794 -296.470051) (xy 180.755888 -296.445399)
			(xy 180.806915 -296.427991) (xy 180.859933 -296.418198) (xy 180.913812 -296.416229) (xy 180.967403 -296.422126)
			(xy 181.019564 -296.435762) (xy 181.069184 -296.456849) (xy 181.115205 -296.484935) (xy 181.156647 -296.519423)
			(xy 181.192625 -296.559577) (xy 181.222373 -296.604541) (xy 181.245258 -296.653358) (xy 181.26079 -296.704987)
			(xy 181.26864 -296.758327) (xy 181.269132 -296.785284) (xy 181.26864 -296.812241) (xy 181.26079 -296.865581)
			(xy 181.245258 -296.91721) (xy 181.222373 -296.966027) (xy 181.192625 -297.010991) (xy 181.156647 -297.051145)
			(xy 181.115205 -297.085633) (xy 181.069184 -297.113719) (xy 181.019564 -297.134806) (xy 180.967403 -297.148442)
			(xy 180.913812 -297.154339) (xy 180.859933 -297.15237) (xy 180.806915 -297.142577) (xy 180.755888 -297.125169)
			(xy 180.70794 -297.100517) (xy 180.664092 -297.069147) (xy 180.625279 -297.031726) (xy 180.592327 -296.989053)
			(xy 180.565941 -296.942036) (xy 180.546681 -296.891679) (xy 180.534958 -296.839055) (xy 180.531023 -296.785284)
			(xy 176.567846 -296.785284) (xy 176.56739 -296.816494) (xy 176.559562 -296.87842) (xy 176.544026 -296.938875)
			(xy 176.521029 -296.996904) (xy 176.490934 -297.051589) (xy 176.454216 -297.102066) (xy 176.411456 -297.147539)
			(xy 176.363329 -297.187287) (xy 176.337214 -297.204384) (xy 176.327054 -297.210734) (xy 176.314862 -297.230546)
			(xy 176.30521 -297.334686) (xy 176.313592 -297.35653) (xy 176.322482 -297.364658) (xy 176.340826 -297.382156)
			(xy 176.372968 -297.421363) (xy 176.399438 -297.464601) (xy 176.419739 -297.511056) (xy 176.433489 -297.559853)
			(xy 176.440427 -297.610073) (xy 176.440846 -297.635422) (xy 176.440403 -297.660739) (xy 176.433485 -297.710897)
			(xy 176.419769 -297.759638) (xy 176.399513 -297.806043) (xy 176.373097 -297.84924) (xy 176.341019 -297.888416)
			(xy 176.322736 -297.905932) (xy 176.313846 -297.914314) (xy 176.305464 -297.935904) (xy 176.314862 -298.040044)
			(xy 176.327054 -298.059856) (xy 176.337214 -298.06646) (xy 176.36335 -298.083499) (xy 176.411466 -298.123221)
			(xy 176.454218 -298.168667) (xy 176.490929 -298.219118) (xy 176.521019 -298.273776) (xy 176.544013 -298.331779)
			(xy 176.559547 -298.392208) (xy 176.567375 -298.454109) (xy 176.567846 -298.485306) (xy 176.567329 -298.516514)
			(xy 176.55951 -298.578438) (xy 176.543984 -298.638891) (xy 176.520996 -298.696919) (xy 176.490909 -298.751605)
			(xy 176.454199 -298.802083) (xy 176.411446 -298.847557) (xy 176.363326 -298.887308) (xy 176.337214 -298.904406)
			(xy 176.327054 -298.910756) (xy 176.314862 -298.930568) (xy 176.30521 -299.034708) (xy 176.313592 -299.056552)
			(xy 176.322482 -299.06468) (xy 176.340788 -299.082216) (xy 176.372933 -299.121414) (xy 176.399409 -299.164644)
			(xy 176.419717 -299.211092) (xy 176.433474 -299.259883) (xy 176.440422 -299.310097) (xy 176.440846 -299.335444)
			(xy 176.440417 -299.360761) (xy 176.433497 -299.410921) (xy 176.419778 -299.459661) (xy 176.399519 -299.506066)
			(xy 176.373101 -299.549263) (xy 176.341021 -299.588438) (xy 176.322736 -299.605954) (xy 176.313846 -299.614336)
			(xy 176.305464 -299.635926) (xy 176.314862 -299.740066) (xy 176.327054 -299.759878) (xy 176.337214 -299.766482)
			(xy 176.363354 -299.783519) (xy 176.411485 -299.82323) (xy 176.45425 -299.868669) (xy 176.490973 -299.919117)
			(xy 176.521073 -299.973775) (xy 176.544075 -300.031778) (xy 176.559614 -300.092211) (xy 176.567445 -300.154116)
			(xy 176.567443 -300.216514) (xy 176.559609 -300.278419) (xy 176.544066 -300.33885) (xy 176.521061 -300.396853)
			(xy 176.490957 -300.451509) (xy 176.454231 -300.501954) (xy 176.411463 -300.54739) (xy 176.36333 -300.587099)
			(xy 176.337214 -300.604174) (xy 176.327054 -300.610778) (xy 176.314862 -300.63059) (xy 176.305464 -300.73473)
			(xy 176.313846 -300.75632) (xy 176.322736 -300.764702) (xy 176.341028 -300.78221) (xy 176.373106 -300.821389)
			(xy 176.399523 -300.864588) (xy 176.419782 -300.910993) (xy 176.433504 -300.959734) (xy 176.440428 -301.009894)
			(xy 176.440846 -301.035212) (xy 176.440408 -301.060559) (xy 176.433475 -301.110778) (xy 176.419728 -301.159573)
			(xy 176.399425 -301.206024) (xy 176.372951 -301.249257) (xy 176.340803 -301.288455) (xy 176.322482 -301.305976)
			(xy 176.313592 -301.314104) (xy 176.30521 -301.335948) (xy 176.314862 -301.440088) (xy 176.327054 -301.4599)
			(xy 176.337214 -301.46625) (xy 176.363313 -301.483368) (xy 176.411434 -301.523118) (xy 176.45419 -301.568589)
			(xy 176.490905 -301.619064) (xy 176.521 -301.673746) (xy 176.543998 -301.73177) (xy 176.559537 -301.79222)
			(xy 176.567372 -301.854142) (xy 176.567846 -301.88535) (xy 176.567357 -301.916513) (xy 176.559545 -301.978347)
			(xy 176.544045 -302.038715) (xy 176.521102 -302.096663) (xy 176.491076 -302.15128) (xy 176.454442 -302.201702)
			(xy 176.411777 -302.247136) (xy 176.363755 -302.286864) (xy 176.311131 -302.320259) (xy 176.254737 -302.346796)
			(xy 176.195462 -302.366056) (xy 176.134241 -302.377735) (xy 176.072038 -302.381648) (xy 176.009835 -302.377735)
			(xy 175.948614 -302.366056) (xy 175.889339 -302.346796) (xy 175.832945 -302.320259) (xy 175.780321 -302.286864)
			(xy 175.732299 -302.247136) (xy 175.689634 -302.201702) (xy 175.653 -302.15128) (xy 175.622974 -302.096663)
			(xy 175.600031 -302.038715) (xy 175.584531 -301.978347) (xy 175.576719 -301.916513) (xy 175.57623 -301.88535)
			(xy 172.340778 -301.88535) (xy 172.340343 -301.910667) (xy 172.333422 -301.960826) (xy 172.319704 -302.009566)
			(xy 172.299446 -302.05597) (xy 172.27303 -302.099167) (xy 172.240951 -302.138343) (xy 172.222668 -302.15586)
			(xy 172.213778 -302.164242) (xy 172.205396 -302.185832) (xy 172.214794 -302.289972) (xy 172.226986 -302.309784)
			(xy 172.237146 -302.316388) (xy 172.263234 -302.333499) (xy 172.311353 -302.373208) (xy 172.354109 -302.418642)
			(xy 172.390825 -302.469082) (xy 172.420922 -302.523731) (xy 172.443924 -302.581724) (xy 172.459466 -302.642146)
			(xy 172.467303 -302.70404) (xy 172.467778 -302.735234) (xy 174.318437 -302.735234) (xy 174.322372 -302.681463)
			(xy 174.334095 -302.628839) (xy 174.353355 -302.578482) (xy 174.379741 -302.531465) (xy 174.412693 -302.488792)
			(xy 174.451506 -302.451371) (xy 174.495354 -302.420001) (xy 174.543302 -302.395349) (xy 174.594329 -302.377941)
			(xy 174.647347 -302.368148) (xy 174.701226 -302.366179) (xy 174.754817 -302.372076) (xy 174.806978 -302.385712)
			(xy 174.856598 -302.406799) (xy 174.902619 -302.434885) (xy 174.944061 -302.469373) (xy 174.980039 -302.509527)
			(xy 175.009787 -302.554491) (xy 175.032672 -302.603308) (xy 175.048204 -302.654937) (xy 175.056054 -302.708277)
			(xy 175.056546 -302.735234) (xy 179.020216 -302.735234) (xy 179.020672 -302.704036) (xy 179.02849 -302.642133)
			(xy 179.04402 -302.581702) (xy 179.067015 -302.523699) (xy 179.097112 -302.469042) (xy 179.133834 -302.418598)
			(xy 179.1766 -302.373164) (xy 179.224732 -302.33346) (xy 179.250848 -302.316388) (xy 179.261008 -302.309784)
			(xy 179.2732 -302.289972) (xy 179.282598 -302.185832) (xy 179.274216 -302.164242) (xy 179.265326 -302.15586)
			(xy 179.247057 -302.138329) (xy 179.214978 -302.099154) (xy 179.188559 -302.05596) (xy 179.168296 -302.009559)
			(xy 179.154569 -301.960822) (xy 179.147638 -301.910666) (xy 179.147216 -301.88535) (xy 179.147609 -301.860001)
			(xy 179.154548 -301.80978) (xy 179.168303 -301.760983) (xy 179.188614 -301.714531) (xy 179.215097 -301.6713)
			(xy 179.247254 -301.632105) (xy 179.26558 -301.614586) (xy 179.27447 -301.606458) (xy 179.282852 -301.584614)
			(xy 179.2732 -301.480474) (xy 179.261008 -301.460662) (xy 179.250848 -301.454312) (xy 179.224723 -301.437233)
			(xy 179.176603 -301.397476) (xy 179.13385 -301.351998) (xy 179.097138 -301.301517) (xy 179.067047 -301.246831)
			(xy 179.044052 -301.188802) (xy 179.028517 -301.128347) (xy 179.020687 -301.066421) (xy 179.020216 -301.035212)
			(xy 179.020655 -301.004014) (xy 179.028476 -300.94211) (xy 179.044008 -300.881678) (xy 179.067006 -300.823675)
			(xy 179.097105 -300.769019) (xy 179.133829 -300.718575) (xy 179.176597 -300.673141) (xy 179.224731 -300.633438)
			(xy 179.250848 -300.616366) (xy 179.261008 -300.609762) (xy 179.2732 -300.58995) (xy 179.282598 -300.48581)
			(xy 179.274216 -300.46422) (xy 179.265326 -300.455838) (xy 179.245428 -300.436674) (xy 179.21096 -300.393504)
			(xy 179.183317 -300.345676) (xy 179.163117 -300.29426) (xy 179.150813 -300.240406) (xy 179.146678 -300.185319)
			(xy 179.150807 -300.130232) (xy 179.163106 -300.076376) (xy 179.183301 -300.024958) (xy 179.210939 -299.977127)
			(xy 179.245402 -299.933954) (xy 179.265326 -299.914818) (xy 179.274216 -299.906436) (xy 179.282598 -299.884846)
			(xy 179.2732 -299.780706) (xy 179.261008 -299.760894) (xy 179.250848 -299.75429) (xy 179.224749 -299.737196)
			(xy 179.17663 -299.697484) (xy 179.133875 -299.652048) (xy 179.097159 -299.601605) (xy 179.067064 -299.546954)
			(xy 179.044064 -299.488958) (xy 179.028524 -299.428535) (xy 179.02069 -299.366639) (xy 179.020216 -299.335444)
			(xy 179.020665 -299.304234) (xy 179.028491 -299.242306) (xy 179.044026 -299.18185) (xy 179.067023 -299.12382)
			(xy 179.097119 -299.069134) (xy 179.133839 -299.018657) (xy 179.176602 -298.973186) (xy 179.224732 -298.933439)
			(xy 179.250848 -298.916344) (xy 179.261008 -298.909994) (xy 179.2732 -298.890182) (xy 179.282852 -298.786042)
			(xy 179.27447 -298.764198) (xy 179.26558 -298.75607) (xy 179.247242 -298.738566) (xy 179.215101 -298.69936)
			(xy 179.188631 -298.656123) (xy 179.168329 -298.609669) (xy 179.154578 -298.560873) (xy 179.147637 -298.510654)
			(xy 179.147216 -298.485306) (xy 179.147623 -298.459988) (xy 179.15455 -298.409828) (xy 179.168274 -298.361088)
			(xy 179.188537 -298.314683) (xy 179.214958 -298.271487) (xy 179.24704 -298.232312) (xy 179.265326 -298.214796)
			(xy 179.274216 -298.206414) (xy 179.282598 -298.184824) (xy 179.2732 -298.080684) (xy 179.261008 -298.060872)
			(xy 179.250848 -298.054268) (xy 179.224739 -298.037189) (xy 179.17662 -297.997475) (xy 179.133865 -297.952036)
			(xy 179.09715 -297.901591) (xy 179.067056 -297.846938) (xy 179.044059 -297.78894) (xy 179.028521 -297.728515)
			(xy 179.020688 -297.666617) (xy 179.020216 -297.635422) (xy 179.020705 -297.604259) (xy 179.028517 -297.542425)
			(xy 179.044017 -297.482057) (xy 179.06696 -297.424109) (xy 179.096986 -297.369492) (xy 179.13362 -297.31907)
			(xy 179.176285 -297.273636) (xy 179.224307 -297.233908) (xy 179.276931 -297.200513) (xy 179.333325 -297.173976)
			(xy 179.3926 -297.154716) (xy 179.453821 -297.143037) (xy 179.516024 -297.139124) (xy 179.578227 -297.143037)
			(xy 179.639448 -297.154716) (xy 179.698723 -297.173976) (xy 179.755117 -297.200513) (xy 179.807741 -297.233908)
			(xy 179.855763 -297.273636) (xy 179.898428 -297.31907) (xy 179.935062 -297.369492) (xy 179.965088 -297.424109)
			(xy 179.988031 -297.482057) (xy 180.003531 -297.542425) (xy 180.011343 -297.604259) (xy 180.011832 -297.635422)
			(xy 180.011398 -297.66662) (xy 180.003573 -297.728523) (xy 179.988039 -297.788954) (xy 179.965039 -297.846957)
			(xy 179.93494 -297.901612) (xy 179.898216 -297.952056) (xy 179.855449 -297.99749) (xy 179.807316 -298.037195)
			(xy 179.7812 -298.054268) (xy 179.77104 -298.060872) (xy 179.758848 -298.080684) (xy 179.74945 -298.184824)
			(xy 179.757832 -298.206414) (xy 179.766722 -298.214796) (xy 179.785009 -298.23231) (xy 179.817088 -298.271487)
			(xy 179.843506 -298.314684) (xy 179.863766 -298.361089) (xy 179.877488 -298.409829) (xy 179.884414 -298.459989)
			(xy 179.884832 -298.485306) (xy 179.884394 -298.510653) (xy 179.877462 -298.560872) (xy 179.863715 -298.609667)
			(xy 179.843412 -298.656119) (xy 179.816938 -298.699351) (xy 179.78479 -298.738549) (xy 179.766468 -298.75607)
			(xy 179.757578 -298.764198) (xy 179.749196 -298.786042) (xy 179.758848 -298.890182) (xy 179.77104 -298.909994)
			(xy 179.7812 -298.916344) (xy 179.807293 -298.933471) (xy 179.855415 -298.973219) (xy 179.898172 -299.018689)
			(xy 179.934887 -299.069162) (xy 179.964983 -299.123843) (xy 179.987982 -299.181866) (xy 180.003522 -299.242315)
			(xy 180.011358 -299.304237) (xy 180.011832 -299.335444) (xy 180.011337 -299.36664) (xy 180.003522 -299.428541)
			(xy 179.987997 -299.488971) (xy 179.965006 -299.546972) (xy 179.934915 -299.601628) (xy 179.898199 -299.652074)
			(xy 179.855439 -299.697509) (xy 179.807313 -299.737216) (xy 179.7812 -299.75429) (xy 179.77104 -299.760894)
			(xy 179.758848 -299.780706) (xy 179.74945 -299.884846) (xy 179.757832 -299.906436) (xy 179.766722 -299.914818)
			(xy 179.786674 -299.933927) (xy 179.821137 -299.977107) (xy 179.848774 -300.024944) (xy 179.868968 -300.076367)
			(xy 179.881267 -300.130227) (xy 179.885395 -300.185319) (xy 179.881261 -300.240411) (xy 179.868957 -300.294269)
			(xy 179.848758 -300.345691) (xy 179.821115 -300.393525) (xy 179.786648 -300.436701) (xy 179.766722 -300.455838)
			(xy 179.757832 -300.46422) (xy 179.74945 -300.48581) (xy 179.758848 -300.58995) (xy 179.77104 -300.609762)
			(xy 179.7812 -300.616366) (xy 179.80729 -300.633473) (xy 179.855407 -300.673185) (xy 179.898161 -300.71862)
			(xy 179.934876 -300.769061) (xy 179.964972 -300.82371) (xy 179.987974 -300.881703) (xy 180.003517 -300.942124)
			(xy 180.011356 -301.004018) (xy 180.011832 -301.035212) (xy 180.011326 -301.06642) (xy 180.003506 -301.128345)
			(xy 179.987979 -301.188799) (xy 179.964989 -301.246827) (xy 179.934901 -301.301513) (xy 179.898189 -301.351991)
			(xy 179.855435 -301.397465) (xy 179.807312 -301.437215) (xy 179.7812 -301.454312) (xy 179.77104 -301.460662)
			(xy 179.758848 -301.480474) (xy 179.749196 -301.584614) (xy 179.757578 -301.606458) (xy 179.766468 -301.614586)
			(xy 179.784775 -301.632122) (xy 179.81692 -301.67132) (xy 179.843396 -301.71455) (xy 179.863704 -301.760998)
			(xy 179.877461 -301.809789) (xy 179.884408 -301.860003) (xy 179.884832 -301.88535) (xy 183.120284 -301.88535)
			(xy 183.120752 -301.854141) (xy 183.128577 -301.792214) (xy 183.14411 -301.731759) (xy 183.167105 -301.67373)
			(xy 183.197198 -301.619044) (xy 183.233915 -301.568567) (xy 183.276675 -301.523094) (xy 183.324801 -301.483346)
			(xy 183.350916 -301.46625) (xy 183.361076 -301.4599) (xy 183.373268 -301.440088) (xy 183.38292 -301.335948)
			(xy 183.374538 -301.314104) (xy 183.365648 -301.305976) (xy 183.347326 -301.288455) (xy 183.315181 -301.249255)
			(xy 183.288707 -301.206021) (xy 183.268402 -301.159571) (xy 183.254648 -301.110777) (xy 183.247705 -301.06056)
			(xy 183.247284 -301.035212) (xy 183.247705 -301.009895) (xy 183.25463 -300.959736) (xy 183.268352 -300.910996)
			(xy 183.288613 -300.864592) (xy 183.315031 -300.821395) (xy 183.34711 -300.782219) (xy 183.365394 -300.764702)
			(xy 183.374284 -300.75632) (xy 183.382666 -300.73473) (xy 183.373268 -300.63059) (xy 183.361076 -300.610778)
			(xy 183.350916 -300.604174) (xy 183.324827 -300.587061) (xy 183.276696 -300.547358) (xy 183.233929 -300.501927)
			(xy 183.197204 -300.451487) (xy 183.167101 -300.396836) (xy 183.144097 -300.338838) (xy 183.128555 -300.278411)
			(xy 183.120721 -300.216512) (xy 183.120719 -300.154118) (xy 183.128549 -300.092218) (xy 183.144088 -300.031791)
			(xy 183.167089 -299.973792) (xy 183.197188 -299.919139) (xy 183.23391 -299.868696) (xy 183.276674 -299.823262)
			(xy 183.324802 -299.783556) (xy 183.350916 -299.766482) (xy 183.361076 -299.759878) (xy 183.373268 -299.740066)
			(xy 183.382666 -299.635926) (xy 183.374284 -299.614336) (xy 183.365394 -299.605954) (xy 183.347135 -299.588413)
			(xy 183.315053 -299.549242) (xy 183.288631 -299.50605) (xy 183.268365 -299.459651) (xy 183.254637 -299.410915)
			(xy 183.247705 -299.36076) (xy 183.247284 -299.335444) (xy 183.247683 -299.310095) (xy 183.254623 -299.259875)
			(xy 183.268377 -299.211079) (xy 183.288687 -299.164627) (xy 183.315168 -299.121396) (xy 183.347323 -299.0822)
			(xy 183.365648 -299.06468) (xy 183.374538 -299.056552) (xy 183.38292 -299.034708) (xy 183.373268 -298.930568)
			(xy 183.361076 -298.910756) (xy 183.350916 -298.904406) (xy 183.324804 -298.887307) (xy 183.276681 -298.847556)
			(xy 183.233925 -298.802082) (xy 183.19721 -298.751604) (xy 183.167117 -298.69692) (xy 183.144121 -298.638893)
			(xy 183.128586 -298.578439) (xy 183.120755 -298.516515) (xy 183.120284 -298.485306) (xy 183.120733 -298.454108)
			(xy 183.128554 -298.392205) (xy 183.144086 -298.331774) (xy 183.167083 -298.273772) (xy 183.19718 -298.219116)
			(xy 183.233903 -298.168672) (xy 183.276668 -298.123237) (xy 183.3248 -298.083533) (xy 183.350916 -298.06646)
			(xy 183.361076 -298.059856) (xy 183.373268 -298.040044) (xy 183.382666 -297.935904) (xy 183.374284 -297.914314)
			(xy 183.365394 -297.905932) (xy 183.347124 -297.888401) (xy 183.315043 -297.849228) (xy 183.288622 -297.806035)
			(xy 183.268359 -297.759633) (xy 183.254633 -297.710895) (xy 183.247704 -297.660739) (xy 183.247284 -297.635422)
			(xy 183.247735 -297.610075) (xy 183.254664 -297.559857) (xy 183.268408 -297.511062) (xy 183.288708 -297.46461)
			(xy 183.315181 -297.421377) (xy 183.347327 -297.382179) (xy 183.365648 -297.364658) (xy 183.374538 -297.35653)
			(xy 183.38292 -297.334686) (xy 183.373268 -297.230546) (xy 183.361076 -297.210734) (xy 183.350916 -297.204384)
			(xy 183.324794 -297.1873) (xy 183.276671 -297.147546) (xy 183.233915 -297.10207) (xy 183.197202 -297.05159)
			(xy 183.16711 -296.996904) (xy 183.144115 -296.938875) (xy 183.128582 -296.87842) (xy 183.120754 -296.816493)
			(xy 183.120284 -296.785284) (xy 183.120773 -296.754121) (xy 183.128585 -296.692287) (xy 183.144085 -296.631919)
			(xy 183.167028 -296.573971) (xy 183.197054 -296.519354) (xy 183.233688 -296.468932) (xy 183.276353 -296.423498)
			(xy 183.324375 -296.38377) (xy 183.376999 -296.350375) (xy 183.433393 -296.323838) (xy 183.492668 -296.304578)
			(xy 183.553889 -296.292899) (xy 183.616092 -296.288986) (xy 183.678295 -296.292899) (xy 183.739516 -296.304578)
			(xy 183.798791 -296.323838) (xy 183.855185 -296.350375) (xy 183.907809 -296.38377) (xy 183.955831 -296.423498)
			(xy 183.998496 -296.468932) (xy 184.03513 -296.519354) (xy 184.065156 -296.573971) (xy 184.088099 -296.631919)
			(xy 184.103599 -296.692287) (xy 184.111411 -296.754121) (xy 184.1119 -296.785284) (xy 184.111466 -296.816495)
			(xy 184.103636 -296.878423) (xy 184.088099 -296.938879) (xy 184.065099 -296.996909) (xy 184.035001 -297.051594)
			(xy 183.99828 -297.102071) (xy 183.955516 -297.147542) (xy 183.907385 -297.187289) (xy 183.881268 -297.204384)
			(xy 183.871108 -297.210734) (xy 183.858916 -297.230546) (xy 183.849264 -297.334686) (xy 183.857646 -297.35653)
			(xy 183.866536 -297.364658) (xy 183.884872 -297.382165) (xy 183.917016 -297.421369) (xy 183.943488 -297.464604)
			(xy 183.963791 -297.511058) (xy 183.977542 -297.559854) (xy 183.984481 -297.610074) (xy 183.9849 -297.635422)
			(xy 183.98444 -297.660738) (xy 183.977523 -297.710895) (xy 183.963809 -297.759634) (xy 183.943556 -297.806039)
			(xy 183.917144 -297.849237) (xy 183.885071 -297.888414) (xy 183.86679 -297.905932) (xy 183.8579 -297.914314)
			(xy 183.849518 -297.935904) (xy 183.858916 -298.040044) (xy 183.871108 -298.059856) (xy 183.881268 -298.06646)
			(xy 183.907394 -298.083515) (xy 183.955512 -298.123233) (xy 183.998265 -298.168676) (xy 184.034978 -298.219124)
			(xy 184.06507 -298.273781) (xy 184.088065 -298.331782) (xy 184.1036 -298.39221) (xy 184.111429 -298.45411)
			(xy 184.1119 -298.485306) (xy 184.111405 -298.516515) (xy 184.103585 -298.57844) (xy 184.088057 -298.638895)
			(xy 184.065066 -298.696924) (xy 184.034976 -298.75161) (xy 183.998263 -298.802088) (xy 183.955506 -298.847561)
			(xy 183.907382 -298.88731) (xy 183.881268 -298.904406) (xy 183.871108 -298.910756) (xy 183.858916 -298.930568)
			(xy 183.849264 -299.034708) (xy 183.857646 -299.056552) (xy 183.866536 -299.06468) (xy 183.884834 -299.082225)
			(xy 183.916981 -299.12142) (xy 183.943459 -299.164648) (xy 183.963769 -299.211094) (xy 183.977527 -299.259884)
			(xy 183.984476 -299.310098) (xy 183.9849 -299.335444) (xy 183.984454 -299.360761) (xy 183.977535 -299.410918)
			(xy 183.963818 -299.459658) (xy 183.943562 -299.506063) (xy 183.917148 -299.54926) (xy 183.885072 -299.588437)
			(xy 183.86679 -299.605954) (xy 183.8579 -299.614336) (xy 183.849518 -299.635926) (xy 183.858916 -299.740066)
			(xy 183.871108 -299.759878) (xy 183.881268 -299.766482) (xy 183.907406 -299.783521) (xy 183.955531 -299.823235)
			(xy 183.998292 -299.868675) (xy 184.035011 -299.919123) (xy 184.065108 -299.97378) (xy 184.088107 -300.031783)
			(xy 184.103644 -300.092214) (xy 184.111474 -300.154117) (xy 184.111472 -300.216513) (xy 184.103638 -300.278416)
			(xy 184.088098 -300.338845) (xy 184.065095 -300.396847) (xy 184.034995 -300.451503) (xy 183.998273 -300.501948)
			(xy 183.95551 -300.547386) (xy 183.907382 -300.587097) (xy 183.881268 -300.604174) (xy 183.871108 -300.610778)
			(xy 183.858916 -300.63059) (xy 183.849518 -300.73473) (xy 183.8579 -300.75632) (xy 183.86679 -300.764702)
			(xy 183.885092 -300.7822) (xy 183.917167 -300.821382) (xy 183.943582 -300.864583) (xy 183.963839 -300.910991)
			(xy 183.977558 -300.959733) (xy 183.984483 -301.009894) (xy 183.9849 -301.035212) (xy 183.984476 -301.06056)
			(xy 183.977543 -301.11078) (xy 183.963794 -301.159575) (xy 183.943489 -301.206027) (xy 183.917011 -301.249259)
			(xy 183.884859 -301.288456) (xy 183.866536 -301.305976) (xy 183.857646 -301.314104) (xy 183.849264 -301.335948)
			(xy 183.858916 -301.440088) (xy 183.871108 -301.4599) (xy 183.881268 -301.46625) (xy 183.907356 -301.483384)
			(xy 183.95548 -301.52313) (xy 183.998238 -301.568598) (xy 184.034955 -301.619071) (xy 184.065051 -301.67375)
			(xy 184.088051 -301.731772) (xy 184.103591 -301.792222) (xy 184.111426 -301.854143) (xy 184.1119 -301.88535)
			(xy 184.111411 -301.916513) (xy 184.103599 -301.978347) (xy 184.088099 -302.038715) (xy 184.065156 -302.096663)
			(xy 184.03513 -302.15128) (xy 183.998496 -302.201702) (xy 183.955831 -302.247136) (xy 183.907809 -302.286864)
			(xy 183.855185 -302.320259) (xy 183.798791 -302.346796) (xy 183.739516 -302.366056) (xy 183.678295 -302.377735)
			(xy 183.616092 -302.381648) (xy 183.553889 -302.377735) (xy 183.492668 -302.366056) (xy 183.433393 -302.346796)
			(xy 183.376999 -302.320259) (xy 183.324375 -302.286864) (xy 183.276353 -302.247136) (xy 183.233688 -302.201702)
			(xy 183.197054 -302.15128) (xy 183.167028 -302.096663) (xy 183.144085 -302.038715) (xy 183.128585 -301.978347)
			(xy 183.120773 -301.916513) (xy 183.120284 -301.88535) (xy 179.884832 -301.88535) (xy 179.884412 -301.910668)
			(xy 179.87749 -301.960827) (xy 179.86377 -302.009568) (xy 179.843509 -302.055973) (xy 179.817089 -302.09917)
			(xy 179.785007 -302.138344) (xy 179.766722 -302.15586) (xy 179.757832 -302.164242) (xy 179.74945 -302.185832)
			(xy 179.758848 -302.289972) (xy 179.77104 -302.309784) (xy 179.7812 -302.316388) (xy 179.8073 -302.33348)
			(xy 179.855417 -302.373194) (xy 179.89817 -302.418632) (xy 179.934885 -302.469075) (xy 179.96498 -302.523726)
			(xy 179.987979 -302.581721) (xy 180.00352 -302.642144) (xy 180.011357 -302.704039) (xy 180.011832 -302.735234)
			(xy 181.862491 -302.735234) (xy 181.866426 -302.681463) (xy 181.878149 -302.628839) (xy 181.897409 -302.578482)
			(xy 181.923795 -302.531465) (xy 181.956747 -302.488792) (xy 181.99556 -302.451371) (xy 182.039408 -302.420001)
			(xy 182.087356 -302.395349) (xy 182.138383 -302.377941) (xy 182.191401 -302.368148) (xy 182.24528 -302.366179)
			(xy 182.298871 -302.372076) (xy 182.351032 -302.385712) (xy 182.400652 -302.406799) (xy 182.446673 -302.434885)
			(xy 182.488115 -302.469373) (xy 182.524093 -302.509527) (xy 182.553841 -302.554491) (xy 182.576726 -302.603308)
			(xy 182.592258 -302.654937) (xy 182.600108 -302.708277) (xy 182.6006 -302.735234) (xy 182.600108 -302.762191)
			(xy 182.592258 -302.815531) (xy 182.576726 -302.86716) (xy 182.553841 -302.915977) (xy 182.524093 -302.960941)
			(xy 182.488115 -303.001095) (xy 182.446673 -303.035583) (xy 182.400652 -303.063669) (xy 182.351032 -303.084756)
			(xy 182.298871 -303.098392) (xy 182.24528 -303.104289) (xy 182.191401 -303.10232) (xy 182.138383 -303.092527)
			(xy 182.087356 -303.075119) (xy 182.039408 -303.050467) (xy 181.99556 -303.019097) (xy 181.956747 -302.981676)
			(xy 181.923795 -302.939003) (xy 181.897409 -302.891986) (xy 181.878149 -302.841629) (xy 181.866426 -302.789005)
			(xy 181.862491 -302.735234) (xy 180.011832 -302.735234) (xy 180.011343 -302.766397) (xy 180.003531 -302.828231)
			(xy 179.988031 -302.888599) (xy 179.965088 -302.946547) (xy 179.935062 -303.001164) (xy 179.898428 -303.051586)
			(xy 179.855763 -303.09702) (xy 179.807741 -303.136748) (xy 179.755117 -303.170143) (xy 179.698723 -303.19668)
			(xy 179.639448 -303.21594) (xy 179.578227 -303.227619) (xy 179.516024 -303.231532) (xy 179.453821 -303.227619)
			(xy 179.3926 -303.21594) (xy 179.333325 -303.19668) (xy 179.276931 -303.170143) (xy 179.224307 -303.136748)
			(xy 179.176285 -303.09702) (xy 179.13362 -303.051586) (xy 179.096986 -303.001164) (xy 179.06696 -302.946547)
			(xy 179.044017 -302.888599) (xy 179.028517 -302.828231) (xy 179.020705 -302.766397) (xy 179.020216 -302.735234)
			(xy 175.056546 -302.735234) (xy 175.056054 -302.762191) (xy 175.048204 -302.815531) (xy 175.032672 -302.86716)
			(xy 175.009787 -302.915977) (xy 174.980039 -302.960941) (xy 174.944061 -303.001095) (xy 174.902619 -303.035583)
			(xy 174.856598 -303.063669) (xy 174.806978 -303.084756) (xy 174.754817 -303.098392) (xy 174.701226 -303.104289)
			(xy 174.647347 -303.10232) (xy 174.594329 -303.092527) (xy 174.543302 -303.075119) (xy 174.495354 -303.050467)
			(xy 174.451506 -303.019097) (xy 174.412693 -302.981676) (xy 174.379741 -302.939003) (xy 174.353355 -302.891986)
			(xy 174.334095 -302.841629) (xy 174.322372 -302.789005) (xy 174.318437 -302.735234) (xy 172.467778 -302.735234)
			(xy 172.467289 -302.766397) (xy 172.459477 -302.828231) (xy 172.443977 -302.888599) (xy 172.421034 -302.946547)
			(xy 172.391008 -303.001164) (xy 172.354374 -303.051586) (xy 172.311709 -303.09702) (xy 172.263687 -303.136748)
			(xy 172.211063 -303.170143) (xy 172.154669 -303.19668) (xy 172.095394 -303.21594) (xy 172.034173 -303.227619)
			(xy 171.97197 -303.231532) (xy 171.909767 -303.227619) (xy 171.848546 -303.21594) (xy 171.789271 -303.19668)
			(xy 171.732877 -303.170143) (xy 171.680253 -303.136748) (xy 171.632231 -303.09702) (xy 171.589566 -303.051586)
			(xy 171.552932 -303.001164) (xy 171.522906 -302.946547) (xy 171.499963 -302.888599) (xy 171.484463 -302.828231)
			(xy 171.476651 -302.766397) (xy 171.476162 -302.735234) (xy 167.512492 -302.735234) (xy 167.512 -302.762191)
			(xy 167.50415 -302.815531) (xy 167.488618 -302.86716) (xy 167.465733 -302.915977) (xy 167.435985 -302.960941)
			(xy 167.400007 -303.001095) (xy 167.358565 -303.035583) (xy 167.312544 -303.063669) (xy 167.262924 -303.084756)
			(xy 167.210763 -303.098392) (xy 167.157172 -303.104289) (xy 167.103293 -303.10232) (xy 167.050275 -303.092527)
			(xy 166.999248 -303.075119) (xy 166.9513 -303.050467) (xy 166.907452 -303.019097) (xy 166.868639 -302.981676)
			(xy 166.835687 -302.939003) (xy 166.809301 -302.891986) (xy 166.790041 -302.841629) (xy 166.778318 -302.789005)
			(xy 166.774383 -302.735234) (xy 143.992007 -302.735234) (xy 144.02395 -302.757489) (xy 144.136003 -302.845375)
			(xy 144.242903 -302.939459) (xy 144.34431 -303.039441) (xy 144.439898 -303.144999) (xy 144.529361 -303.255797)
			(xy 144.612412 -303.371478) (xy 144.688785 -303.491673) (xy 144.741128 -303.585372) (xy 165.442915 -303.585372)
			(xy 165.44685 -303.531601) (xy 165.458573 -303.478977) (xy 165.477833 -303.42862) (xy 165.504219 -303.381603)
			(xy 165.537171 -303.33893) (xy 165.575984 -303.301509) (xy 165.619832 -303.270139) (xy 165.66778 -303.245487)
			(xy 165.718807 -303.228079) (xy 165.771825 -303.218286) (xy 165.825704 -303.216317) (xy 165.879295 -303.222214)
			(xy 165.931456 -303.23585) (xy 165.981076 -303.256937) (xy 166.027097 -303.285023) (xy 166.068539 -303.319511)
			(xy 166.104517 -303.359665) (xy 166.134265 -303.404629) (xy 166.15715 -303.453446) (xy 166.172682 -303.505075)
			(xy 166.180532 -303.558415) (xy 166.181024 -303.585372) (xy 172.986969 -303.585372) (xy 172.990904 -303.531601)
			(xy 173.002627 -303.478977) (xy 173.021887 -303.42862) (xy 173.048273 -303.381603) (xy 173.081225 -303.33893)
			(xy 173.120038 -303.301509) (xy 173.163886 -303.270139) (xy 173.211834 -303.245487) (xy 173.262861 -303.228079)
			(xy 173.315879 -303.218286) (xy 173.369758 -303.216317) (xy 173.423349 -303.222214) (xy 173.47551 -303.23585)
			(xy 173.52513 -303.256937) (xy 173.571151 -303.285023) (xy 173.612593 -303.319511) (xy 173.648571 -303.359665)
			(xy 173.678319 -303.404629) (xy 173.701204 -303.453446) (xy 173.716736 -303.505075) (xy 173.724586 -303.558415)
			(xy 173.725078 -303.585372) (xy 173.724586 -303.612329) (xy 173.716736 -303.665669) (xy 173.701204 -303.717298)
			(xy 173.678319 -303.766115) (xy 173.648571 -303.811079) (xy 173.612593 -303.851233) (xy 173.571151 -303.885721)
			(xy 173.52513 -303.913807) (xy 173.47551 -303.934894) (xy 173.423349 -303.94853) (xy 173.369758 -303.954427)
			(xy 173.315879 -303.952458) (xy 173.262861 -303.942665) (xy 173.211834 -303.925257) (xy 173.163886 -303.900605)
			(xy 173.120038 -303.869235) (xy 173.081225 -303.831814) (xy 173.048273 -303.789141) (xy 173.021887 -303.742124)
			(xy 173.002627 -303.691767) (xy 172.990904 -303.639143) (xy 172.986969 -303.585372) (xy 166.181024 -303.585372)
			(xy 166.180532 -303.612329) (xy 166.172682 -303.665669) (xy 166.15715 -303.717298) (xy 166.134265 -303.766115)
			(xy 166.104517 -303.811079) (xy 166.068539 -303.851233) (xy 166.027097 -303.885721) (xy 165.981076 -303.913807)
			(xy 165.931456 -303.934894) (xy 165.879295 -303.94853) (xy 165.825704 -303.954427) (xy 165.771825 -303.952458)
			(xy 165.718807 -303.942665) (xy 165.66778 -303.925257) (xy 165.619832 -303.900605) (xy 165.575984 -303.869235)
			(xy 165.537171 -303.831814) (xy 165.504219 -303.789141) (xy 165.477833 -303.742124) (xy 165.458573 -303.691767)
			(xy 165.44685 -303.639143) (xy 165.442915 -303.585372) (xy 144.741128 -303.585372) (xy 144.758236 -303.615996)
			(xy 144.820542 -303.744049) (xy 144.875504 -303.875422) (xy 144.922945 -304.009694) (xy 144.923125 -304.010314)
			(xy 169.276283 -304.010314) (xy 169.280218 -303.956543) (xy 169.291941 -303.903919) (xy 169.311201 -303.853562)
			(xy 169.337587 -303.806545) (xy 169.370539 -303.763872) (xy 169.409352 -303.726451) (xy 169.4532 -303.695081)
			(xy 169.501148 -303.670429) (xy 169.552175 -303.653021) (xy 169.605193 -303.643228) (xy 169.659072 -303.641259)
			(xy 169.712663 -303.647156) (xy 169.764824 -303.660792) (xy 169.814444 -303.681879) (xy 169.860465 -303.709965)
			(xy 169.901907 -303.744453) (xy 169.937885 -303.784607) (xy 169.967633 -303.829571) (xy 169.990518 -303.878388)
			(xy 170.00605 -303.930017) (xy 170.0139 -303.983357) (xy 170.014392 -304.010314) (xy 170.0139 -304.037271)
			(xy 170.00605 -304.090611) (xy 169.990518 -304.14224) (xy 169.967633 -304.191057) (xy 169.937885 -304.236021)
			(xy 169.901907 -304.276175) (xy 169.860465 -304.310663) (xy 169.814444 -304.338749) (xy 169.764824 -304.359836)
			(xy 169.712663 -304.373472) (xy 169.659072 -304.379369) (xy 169.605193 -304.3774) (xy 169.552175 -304.367607)
			(xy 169.501148 -304.350199) (xy 169.4532 -304.325547) (xy 169.409352 -304.294177) (xy 169.370539 -304.256756)
			(xy 169.337587 -304.214083) (xy 169.311201 -304.167066) (xy 169.291941 -304.116709) (xy 169.280218 -304.064085)
			(xy 169.276283 -304.010314) (xy 144.923125 -304.010314) (xy 144.962714 -304.146435) (xy 144.994683 -304.285207)
			(xy 145.01875 -304.425565) (xy 145.034838 -304.56706) (xy 145.042894 -304.709239) (xy 145.043398 -304.780442)
			(xy 145.042894 -304.851645) (xy 145.042395 -304.860452) (xy 165.176215 -304.860452) (xy 165.18015 -304.806681)
			(xy 165.191873 -304.754057) (xy 165.211133 -304.7037) (xy 165.237519 -304.656683) (xy 165.270471 -304.61401)
			(xy 165.309284 -304.576589) (xy 165.353132 -304.545219) (xy 165.40108 -304.520567) (xy 165.452107 -304.503159)
			(xy 165.505125 -304.493366) (xy 165.559004 -304.491397) (xy 165.612595 -304.497294) (xy 165.664756 -304.51093)
			(xy 165.714376 -304.532017) (xy 165.760397 -304.560103) (xy 165.801839 -304.594591) (xy 165.837817 -304.634745)
			(xy 165.867565 -304.679709) (xy 165.89045 -304.728526) (xy 165.905982 -304.780155) (xy 165.913832 -304.833495)
			(xy 165.914324 -304.860452) (xy 165.913832 -304.887409) (xy 165.905982 -304.940749) (xy 165.89045 -304.992378)
			(xy 165.867565 -305.041195) (xy 165.837817 -305.086159) (xy 165.801839 -305.126313) (xy 165.760397 -305.160801)
			(xy 165.714376 -305.188887) (xy 165.664756 -305.209974) (xy 165.612595 -305.22361) (xy 165.559004 -305.229507)
			(xy 165.505125 -305.227538) (xy 165.452107 -305.217745) (xy 165.40108 -305.200337) (xy 165.353132 -305.175685)
			(xy 165.309284 -305.144315) (xy 165.270471 -305.106894) (xy 165.237519 -305.064221) (xy 165.211133 -305.017204)
			(xy 165.191873 -304.966847) (xy 165.18015 -304.914223) (xy 165.176215 -304.860452) (xy 145.042395 -304.860452)
			(xy 145.034838 -304.993824) (xy 145.01875 -305.135319) (xy 144.994683 -305.275677) (xy 144.992444 -305.285394)
			(xy 166.774383 -305.285394) (xy 166.778318 -305.231623) (xy 166.790041 -305.178999) (xy 166.809301 -305.128642)
			(xy 166.835687 -305.081625) (xy 166.868639 -305.038952) (xy 166.907452 -305.001531) (xy 166.9513 -304.970161)
			(xy 166.999248 -304.945509) (xy 167.050275 -304.928101) (xy 167.103293 -304.918308) (xy 167.157172 -304.916339)
			(xy 167.210763 -304.922236) (xy 167.262924 -304.935872) (xy 167.312544 -304.956959) (xy 167.358565 -304.985045)
			(xy 167.400007 -305.019533) (xy 167.435985 -305.059687) (xy 167.465733 -305.104651) (xy 167.488618 -305.153468)
			(xy 167.50415 -305.205097) (xy 167.512 -305.258437) (xy 167.512492 -305.285394) (xy 171.476162 -305.285394)
			(xy 171.476695 -305.252674) (xy 171.485289 -305.187801) (xy 171.502341 -305.124621) (xy 171.527555 -305.064233)
			(xy 171.560491 -305.007686) (xy 171.600579 -304.955962) (xy 171.623482 -304.932588) (xy 171.630848 -304.925476)
			(xy 171.638722 -304.90668) (xy 171.638722 -304.81397) (xy 171.630848 -304.795174) (xy 171.623482 -304.788062)
			(xy 171.600605 -304.764664) (xy 171.560519 -304.712942) (xy 171.527581 -304.656399) (xy 171.502362 -304.596017)
			(xy 171.485299 -304.532843) (xy 171.47669 -304.467975) (xy 171.476162 -304.435256) (xy 171.476651 -304.404093)
			(xy 171.484463 -304.342259) (xy 171.499963 -304.281891) (xy 171.522906 -304.223943) (xy 171.552932 -304.169326)
			(xy 171.589566 -304.118904) (xy 171.632231 -304.07347) (xy 171.680253 -304.033742) (xy 171.732877 -304.000347)
			(xy 171.789271 -303.97381) (xy 171.848546 -303.95455) (xy 171.909767 -303.942871) (xy 171.97197 -303.938958)
			(xy 172.034173 -303.942871) (xy 172.095394 -303.95455) (xy 172.154669 -303.97381) (xy 172.211063 -304.000347)
			(xy 172.263687 -304.033742) (xy 172.311709 -304.07347) (xy 172.354374 -304.118904) (xy 172.391008 -304.169326)
			(xy 172.421034 -304.223943) (xy 172.443977 -304.281891) (xy 172.459477 -304.342259) (xy 172.467289 -304.404093)
			(xy 172.467778 -304.435256) (xy 175.57623 -304.435256) (xy 175.576774 -304.402556) (xy 175.585381 -304.337725)
			(xy 175.602439 -304.27459) (xy 175.627652 -304.214246) (xy 175.660582 -304.157741) (xy 175.700656 -304.106059)
			(xy 175.72355 -304.082704) (xy 175.730916 -304.075338) (xy 175.738536 -304.056796) (xy 175.738536 -303.963832)
			(xy 175.730916 -303.94529) (xy 175.72355 -303.937924) (xy 175.700645 -303.914579) (xy 175.660562 -303.862899)
			(xy 175.627626 -303.806394) (xy 175.60241 -303.746048) (xy 175.585354 -303.682908) (xy 175.576753 -303.618073)
			(xy 175.57623 -303.585372) (xy 175.576719 -303.554209) (xy 175.584531 -303.492375) (xy 175.600031 -303.432007)
			(xy 175.622974 -303.374059) (xy 175.653 -303.319442) (xy 175.689634 -303.26902) (xy 175.732299 -303.223586)
			(xy 175.780321 -303.183858) (xy 175.832945 -303.150463) (xy 175.889339 -303.123926) (xy 175.948614 -303.104666)
			(xy 176.009835 -303.092987) (xy 176.072038 -303.089074) (xy 176.134241 -303.092987) (xy 176.195462 -303.104666)
			(xy 176.254737 -303.123926) (xy 176.311131 -303.150463) (xy 176.363755 -303.183858) (xy 176.411777 -303.223586)
			(xy 176.454442 -303.26902) (xy 176.491076 -303.319442) (xy 176.521102 -303.374059) (xy 176.544045 -303.432007)
			(xy 176.559545 -303.492375) (xy 176.567357 -303.554209) (xy 176.567846 -303.585372) (xy 180.531023 -303.585372)
			(xy 180.534958 -303.531601) (xy 180.546681 -303.478977) (xy 180.565941 -303.42862) (xy 180.592327 -303.381603)
			(xy 180.625279 -303.33893) (xy 180.664092 -303.301509) (xy 180.70794 -303.270139) (xy 180.755888 -303.245487)
			(xy 180.806915 -303.228079) (xy 180.859933 -303.218286) (xy 180.913812 -303.216317) (xy 180.967403 -303.222214)
			(xy 181.019564 -303.23585) (xy 181.069184 -303.256937) (xy 181.115205 -303.285023) (xy 181.156647 -303.319511)
			(xy 181.192625 -303.359665) (xy 181.222373 -303.404629) (xy 181.245258 -303.453446) (xy 181.26079 -303.505075)
			(xy 181.26864 -303.558415) (xy 181.269132 -303.585372) (xy 181.26864 -303.612329) (xy 181.26079 -303.665669)
			(xy 181.245258 -303.717298) (xy 181.222373 -303.766115) (xy 181.192625 -303.811079) (xy 181.156647 -303.851233)
			(xy 181.115205 -303.885721) (xy 181.069184 -303.913807) (xy 181.019564 -303.934894) (xy 180.967403 -303.94853)
			(xy 180.913812 -303.954427) (xy 180.859933 -303.952458) (xy 180.806915 -303.942665) (xy 180.755888 -303.925257)
			(xy 180.70794 -303.900605) (xy 180.664092 -303.869235) (xy 180.625279 -303.831814) (xy 180.592327 -303.789141)
			(xy 180.565941 -303.742124) (xy 180.546681 -303.691767) (xy 180.534958 -303.639143) (xy 180.531023 -303.585372)
			(xy 176.567846 -303.585372) (xy 176.567327 -303.618073) (xy 176.558716 -303.682905) (xy 176.541654 -303.746041)
			(xy 176.516436 -303.806385) (xy 176.483502 -303.862889) (xy 176.443422 -303.91457) (xy 176.420526 -303.937924)
			(xy 176.41316 -303.94529) (xy 176.40554 -303.963832) (xy 176.40554 -304.010314) (xy 176.820337 -304.010314)
			(xy 176.824272 -303.956543) (xy 176.835995 -303.903919) (xy 176.855255 -303.853562) (xy 176.881641 -303.806545)
			(xy 176.914593 -303.763872) (xy 176.953406 -303.726451) (xy 176.997254 -303.695081) (xy 177.045202 -303.670429)
			(xy 177.096229 -303.653021) (xy 177.149247 -303.643228) (xy 177.203126 -303.641259) (xy 177.256717 -303.647156)
			(xy 177.308878 -303.660792) (xy 177.358498 -303.681879) (xy 177.404519 -303.709965) (xy 177.445961 -303.744453)
			(xy 177.481939 -303.784607) (xy 177.511687 -303.829571) (xy 177.534572 -303.878388) (xy 177.550104 -303.930017)
			(xy 177.557954 -303.983357) (xy 177.558446 -304.010314) (xy 177.557954 -304.037271) (xy 177.550104 -304.090611)
			(xy 177.534572 -304.14224) (xy 177.511687 -304.191057) (xy 177.481939 -304.236021) (xy 177.445961 -304.276175)
			(xy 177.404519 -304.310663) (xy 177.358498 -304.338749) (xy 177.308878 -304.359836) (xy 177.256717 -304.373472)
			(xy 177.203126 -304.379369) (xy 177.149247 -304.3774) (xy 177.096229 -304.367607) (xy 177.045202 -304.350199)
			(xy 176.997254 -304.325547) (xy 176.953406 -304.294177) (xy 176.914593 -304.256756) (xy 176.881641 -304.214083)
			(xy 176.855255 -304.167066) (xy 176.835995 -304.116709) (xy 176.824272 -304.064085) (xy 176.820337 -304.010314)
			(xy 176.40554 -304.010314) (xy 176.40554 -304.056796) (xy 176.41316 -304.075338) (xy 176.420526 -304.082704)
			(xy 176.44344 -304.106041) (xy 176.483524 -304.157722) (xy 176.516459 -304.214228) (xy 176.541672 -304.274577)
			(xy 176.558727 -304.337718) (xy 176.567325 -304.402554) (xy 176.567846 -304.435256) (xy 176.567357 -304.466419)
			(xy 176.559545 -304.528253) (xy 176.544045 -304.588621) (xy 176.521102 -304.646569) (xy 176.491076 -304.701186)
			(xy 176.454442 -304.751608) (xy 176.411777 -304.797042) (xy 176.363755 -304.83677) (xy 176.311131 -304.870165)
			(xy 176.254737 -304.896702) (xy 176.195462 -304.915962) (xy 176.134241 -304.927641) (xy 176.072038 -304.931554)
			(xy 176.009835 -304.927641) (xy 175.948614 -304.915962) (xy 175.889339 -304.896702) (xy 175.832945 -304.870165)
			(xy 175.780321 -304.83677) (xy 175.732299 -304.797042) (xy 175.689634 -304.751608) (xy 175.653 -304.701186)
			(xy 175.622974 -304.646569) (xy 175.600031 -304.588621) (xy 175.584531 -304.528253) (xy 175.576719 -304.466419)
			(xy 175.57623 -304.435256) (xy 172.467778 -304.435256) (xy 172.467266 -304.467977) (xy 172.458666 -304.53285)
			(xy 172.441609 -304.59603) (xy 172.416391 -304.656417) (xy 172.383451 -304.712964) (xy 172.343361 -304.764688)
			(xy 172.320458 -304.788062) (xy 172.313092 -304.795174) (xy 172.305218 -304.81397) (xy 172.305218 -304.860452)
			(xy 172.720269 -304.860452) (xy 172.724204 -304.806681) (xy 172.735927 -304.754057) (xy 172.755187 -304.7037)
			(xy 172.781573 -304.656683) (xy 172.814525 -304.61401) (xy 172.853338 -304.576589) (xy 172.897186 -304.545219)
			(xy 172.945134 -304.520567) (xy 172.996161 -304.503159) (xy 173.049179 -304.493366) (xy 173.103058 -304.491397)
			(xy 173.156649 -304.497294) (xy 173.20881 -304.51093) (xy 173.25843 -304.532017) (xy 173.304451 -304.560103)
			(xy 173.345893 -304.594591) (xy 173.381871 -304.634745) (xy 173.411619 -304.679709) (xy 173.434504 -304.728526)
			(xy 173.450036 -304.780155) (xy 173.457886 -304.833495) (xy 173.458378 -304.860452) (xy 173.457886 -304.887409)
			(xy 173.450036 -304.940749) (xy 173.434504 -304.992378) (xy 173.411619 -305.041195) (xy 173.381871 -305.086159)
			(xy 173.345893 -305.126313) (xy 173.304451 -305.160801) (xy 173.25843 -305.188887) (xy 173.20881 -305.209974)
			(xy 173.156649 -305.22361) (xy 173.103058 -305.229507) (xy 173.049179 -305.227538) (xy 172.996161 -305.217745)
			(xy 172.945134 -305.200337) (xy 172.897186 -305.175685) (xy 172.853338 -305.144315) (xy 172.814525 -305.106894)
			(xy 172.781573 -305.064221) (xy 172.755187 -305.017204) (xy 172.735927 -304.966847) (xy 172.724204 -304.914223)
			(xy 172.720269 -304.860452) (xy 172.305218 -304.860452) (xy 172.305218 -304.90668) (xy 172.313092 -304.925476)
			(xy 172.320458 -304.932588) (xy 172.343367 -304.955956) (xy 172.383448 -305.007685) (xy 172.416381 -305.064235)
			(xy 172.441595 -305.124623) (xy 172.458651 -305.187801) (xy 172.467254 -305.252674) (xy 172.467778 -305.285394)
			(xy 174.318437 -305.285394) (xy 174.322372 -305.231623) (xy 174.334095 -305.178999) (xy 174.353355 -305.128642)
			(xy 174.379741 -305.081625) (xy 174.412693 -305.038952) (xy 174.451506 -305.001531) (xy 174.495354 -304.970161)
			(xy 174.543302 -304.945509) (xy 174.594329 -304.928101) (xy 174.647347 -304.918308) (xy 174.701226 -304.916339)
			(xy 174.754817 -304.922236) (xy 174.806978 -304.935872) (xy 174.856598 -304.956959) (xy 174.902619 -304.985045)
			(xy 174.944061 -305.019533) (xy 174.980039 -305.059687) (xy 175.009787 -305.104651) (xy 175.032672 -305.153468)
			(xy 175.048204 -305.205097) (xy 175.056054 -305.258437) (xy 175.056546 -305.285394) (xy 179.020216 -305.285394)
			(xy 179.020762 -305.252674) (xy 179.029356 -305.187802) (xy 179.046406 -305.124624) (xy 179.071617 -305.064236)
			(xy 179.104551 -305.007688) (xy 179.144635 -304.955963) (xy 179.167536 -304.932588) (xy 179.174902 -304.925476)
			(xy 179.182776 -304.90668) (xy 179.182776 -304.81397) (xy 179.174902 -304.795174) (xy 179.167536 -304.788062)
			(xy 179.14465 -304.764673) (xy 179.104567 -304.712948) (xy 179.071631 -304.656403) (xy 179.046413 -304.596019)
			(xy 179.029352 -304.532844) (xy 179.020743 -304.467975) (xy 179.020216 -304.435256) (xy 179.020705 -304.404093)
			(xy 179.028517 -304.342259) (xy 179.044017 -304.281891) (xy 179.06696 -304.223943) (xy 179.096986 -304.169326)
			(xy 179.13362 -304.118904) (xy 179.176285 -304.07347) (xy 179.224307 -304.033742) (xy 179.276931 -304.000347)
			(xy 179.333325 -303.97381) (xy 179.3926 -303.95455) (xy 179.453821 -303.942871) (xy 179.516024 -303.938958)
			(xy 179.578227 -303.942871) (xy 179.639448 -303.95455) (xy 179.698723 -303.97381) (xy 179.755117 -304.000347)
			(xy 179.807741 -304.033742) (xy 179.855763 -304.07347) (xy 179.898428 -304.118904) (xy 179.935062 -304.169326)
			(xy 179.965088 -304.223943) (xy 179.988031 -304.281891) (xy 180.003531 -304.342259) (xy 180.011343 -304.404093)
			(xy 180.011832 -304.435256) (xy 183.120284 -304.435256) (xy 183.120812 -304.402556) (xy 183.12942 -304.337724)
			(xy 183.14648 -304.274587) (xy 183.171696 -304.214242) (xy 183.204629 -304.157739) (xy 183.244708 -304.106057)
			(xy 183.267604 -304.082704) (xy 183.27497 -304.075338) (xy 183.28259 -304.056796) (xy 183.28259 -303.963832)
			(xy 183.27497 -303.94529) (xy 183.267604 -303.937924) (xy 183.244709 -303.914569) (xy 183.204622 -303.862892)
			(xy 183.171684 -303.80639) (xy 183.146467 -303.746045) (xy 183.129409 -303.682907) (xy 183.120807 -303.618073)
			(xy 183.120284 -303.585372) (xy 183.120773 -303.554209) (xy 183.128585 -303.492375) (xy 183.144085 -303.432007)
			(xy 183.167028 -303.374059) (xy 183.197054 -303.319442) (xy 183.233688 -303.26902) (xy 183.276353 -303.223586)
			(xy 183.324375 -303.183858) (xy 183.376999 -303.150463) (xy 183.433393 -303.123926) (xy 183.492668 -303.104666)
			(xy 183.553889 -303.092987) (xy 183.616092 -303.089074) (xy 183.678295 -303.092987) (xy 183.739516 -303.104666)
			(xy 183.798791 -303.123926) (xy 183.855185 -303.150463) (xy 183.907809 -303.183858) (xy 183.955831 -303.223586)
			(xy 183.998496 -303.26902) (xy 184.03513 -303.319442) (xy 184.065156 -303.374059) (xy 184.088099 -303.432007)
			(xy 184.103599 -303.492375) (xy 184.111411 -303.554209) (xy 184.1119 -303.585372) (xy 184.111394 -303.618073)
			(xy 184.102783 -303.682906) (xy 184.085719 -303.746044) (xy 184.060499 -303.806388) (xy 184.027561 -303.862891)
			(xy 183.987478 -303.914571) (xy 183.96458 -303.937924) (xy 183.957214 -303.94529) (xy 183.949594 -303.963832)
			(xy 183.949594 -304.010314) (xy 184.364391 -304.010314) (xy 184.368326 -303.956543) (xy 184.380049 -303.903919)
			(xy 184.399309 -303.853562) (xy 184.425695 -303.806545) (xy 184.458647 -303.763872) (xy 184.49746 -303.726451)
			(xy 184.541308 -303.695081) (xy 184.589256 -303.670429) (xy 184.640283 -303.653021) (xy 184.693301 -303.643228)
			(xy 184.74718 -303.641259) (xy 184.800771 -303.647156) (xy 184.852932 -303.660792) (xy 184.902552 -303.681879)
			(xy 184.948573 -303.709965) (xy 184.990015 -303.744453) (xy 185.025993 -303.784607) (xy 185.055741 -303.829571)
			(xy 185.078626 -303.878388) (xy 185.094158 -303.930017) (xy 185.102008 -303.983357) (xy 185.1025 -304.010314)
			(xy 185.102008 -304.037271) (xy 185.094158 -304.090611) (xy 185.078626 -304.14224) (xy 185.055741 -304.191057)
			(xy 185.025993 -304.236021) (xy 184.990015 -304.276175) (xy 184.948573 -304.310663) (xy 184.902552 -304.338749)
			(xy 184.852932 -304.359836) (xy 184.800771 -304.373472) (xy 184.74718 -304.379369) (xy 184.693301 -304.3774)
			(xy 184.640283 -304.367607) (xy 184.589256 -304.350199) (xy 184.541308 -304.325547) (xy 184.49746 -304.294177)
			(xy 184.458647 -304.256756) (xy 184.425695 -304.214083) (xy 184.399309 -304.167066) (xy 184.380049 -304.116709)
			(xy 184.368326 -304.064085) (xy 184.364391 -304.010314) (xy 183.949594 -304.010314) (xy 183.949594 -304.056796)
			(xy 183.957214 -304.075338) (xy 183.96458 -304.082704) (xy 183.987504 -304.106031) (xy 184.027585 -304.157716)
			(xy 184.060517 -304.214224) (xy 184.085729 -304.274574) (xy 184.102782 -304.337717) (xy 184.111379 -304.402554)
			(xy 184.1119 -304.435256) (xy 184.111411 -304.466419) (xy 184.103599 -304.528253) (xy 184.088099 -304.588621)
			(xy 184.065156 -304.646569) (xy 184.03513 -304.701186) (xy 183.998496 -304.751608) (xy 183.955831 -304.797042)
			(xy 183.907809 -304.83677) (xy 183.855185 -304.870165) (xy 183.798791 -304.896702) (xy 183.739516 -304.915962)
			(xy 183.678295 -304.927641) (xy 183.616092 -304.931554) (xy 183.553889 -304.927641) (xy 183.492668 -304.915962)
			(xy 183.433393 -304.896702) (xy 183.376999 -304.870165) (xy 183.324375 -304.83677) (xy 183.276353 -304.797042)
			(xy 183.233688 -304.751608) (xy 183.197054 -304.701186) (xy 183.167028 -304.646569) (xy 183.144085 -304.588621)
			(xy 183.128585 -304.528253) (xy 183.120773 -304.466419) (xy 183.120284 -304.435256) (xy 180.011832 -304.435256)
			(xy 180.011334 -304.467977) (xy 180.002732 -304.532852) (xy 179.985674 -304.596032) (xy 179.960454 -304.65642)
			(xy 179.927511 -304.712966) (xy 179.887417 -304.764689) (xy 179.864512 -304.788062) (xy 179.857146 -304.795174)
			(xy 179.849272 -304.81397) (xy 179.849272 -304.860452) (xy 180.264323 -304.860452) (xy 180.268258 -304.806681)
			(xy 180.279981 -304.754057) (xy 180.299241 -304.7037) (xy 180.325627 -304.656683) (xy 180.358579 -304.61401)
			(xy 180.397392 -304.576589) (xy 180.44124 -304.545219) (xy 180.489188 -304.520567) (xy 180.540215 -304.503159)
			(xy 180.593233 -304.493366) (xy 180.647112 -304.491397) (xy 180.700703 -304.497294) (xy 180.752864 -304.51093)
			(xy 180.802484 -304.532017) (xy 180.848505 -304.560103) (xy 180.889947 -304.594591) (xy 180.925925 -304.634745)
			(xy 180.955673 -304.679709) (xy 180.978558 -304.728526) (xy 180.99409 -304.780155) (xy 181.00194 -304.833495)
			(xy 181.002432 -304.860452) (xy 181.00194 -304.887409) (xy 180.99409 -304.940749) (xy 180.978558 -304.992378)
			(xy 180.955673 -305.041195) (xy 180.925925 -305.086159) (xy 180.889947 -305.126313) (xy 180.848505 -305.160801)
			(xy 180.802484 -305.188887) (xy 180.752864 -305.209974) (xy 180.700703 -305.22361) (xy 180.647112 -305.229507)
			(xy 180.593233 -305.227538) (xy 180.540215 -305.217745) (xy 180.489188 -305.200337) (xy 180.44124 -305.175685)
			(xy 180.397392 -305.144315) (xy 180.358579 -305.106894) (xy 180.325627 -305.064221) (xy 180.299241 -305.017204)
			(xy 180.279981 -304.966847) (xy 180.268258 -304.914223) (xy 180.264323 -304.860452) (xy 179.849272 -304.860452)
			(xy 179.849272 -304.90668) (xy 179.857146 -304.925476) (xy 179.864512 -304.932588) (xy 179.887412 -304.955964)
			(xy 179.927496 -305.007691) (xy 179.960431 -305.064239) (xy 179.985646 -305.124625) (xy 180.002704 -305.187803)
			(xy 180.011308 -305.252674) (xy 180.011832 -305.285394) (xy 181.862491 -305.285394) (xy 181.866426 -305.231623)
			(xy 181.878149 -305.178999) (xy 181.897409 -305.128642) (xy 181.923795 -305.081625) (xy 181.956747 -305.038952)
			(xy 181.99556 -305.001531) (xy 182.039408 -304.970161) (xy 182.087356 -304.945509) (xy 182.138383 -304.928101)
			(xy 182.191401 -304.918308) (xy 182.24528 -304.916339) (xy 182.298871 -304.922236) (xy 182.351032 -304.935872)
			(xy 182.400652 -304.956959) (xy 182.446673 -304.985045) (xy 182.488115 -305.019533) (xy 182.524093 -305.059687)
			(xy 182.553841 -305.104651) (xy 182.576726 -305.153468) (xy 182.592258 -305.205097) (xy 182.600108 -305.258437)
			(xy 182.6006 -305.285394) (xy 182.600108 -305.312351) (xy 182.592258 -305.365691) (xy 182.576726 -305.41732)
			(xy 182.553841 -305.466137) (xy 182.524093 -305.511101) (xy 182.488115 -305.551255) (xy 182.446673 -305.585743)
			(xy 182.400652 -305.613829) (xy 182.351032 -305.634916) (xy 182.298871 -305.648552) (xy 182.24528 -305.654449)
			(xy 182.191401 -305.65248) (xy 182.138383 -305.642687) (xy 182.087356 -305.625279) (xy 182.039408 -305.600627)
			(xy 181.99556 -305.569257) (xy 181.956747 -305.531836) (xy 181.923795 -305.489163) (xy 181.897409 -305.442146)
			(xy 181.878149 -305.391789) (xy 181.866426 -305.339165) (xy 181.862491 -305.285394) (xy 180.011832 -305.285394)
			(xy 180.011343 -305.316557) (xy 180.003531 -305.378391) (xy 179.988031 -305.438759) (xy 179.965088 -305.496707)
			(xy 179.935062 -305.551324) (xy 179.898428 -305.601746) (xy 179.855763 -305.64718) (xy 179.807741 -305.686908)
			(xy 179.755117 -305.720303) (xy 179.698723 -305.74684) (xy 179.639448 -305.7661) (xy 179.578227 -305.777779)
			(xy 179.516024 -305.781692) (xy 179.453821 -305.777779) (xy 179.3926 -305.7661) (xy 179.333325 -305.74684)
			(xy 179.276931 -305.720303) (xy 179.224307 -305.686908) (xy 179.176285 -305.64718) (xy 179.13362 -305.601746)
			(xy 179.096986 -305.551324) (xy 179.06696 -305.496707) (xy 179.044017 -305.438759) (xy 179.028517 -305.378391)
			(xy 179.020705 -305.316557) (xy 179.020216 -305.285394) (xy 175.056546 -305.285394) (xy 175.056054 -305.312351)
			(xy 175.048204 -305.365691) (xy 175.032672 -305.41732) (xy 175.009787 -305.466137) (xy 174.980039 -305.511101)
			(xy 174.944061 -305.551255) (xy 174.902619 -305.585743) (xy 174.856598 -305.613829) (xy 174.806978 -305.634916)
			(xy 174.754817 -305.648552) (xy 174.701226 -305.654449) (xy 174.647347 -305.65248) (xy 174.594329 -305.642687)
			(xy 174.543302 -305.625279) (xy 174.495354 -305.600627) (xy 174.451506 -305.569257) (xy 174.412693 -305.531836)
			(xy 174.379741 -305.489163) (xy 174.353355 -305.442146) (xy 174.334095 -305.391789) (xy 174.322372 -305.339165)
			(xy 174.318437 -305.285394) (xy 172.467778 -305.285394) (xy 172.467289 -305.316557) (xy 172.459477 -305.378391)
			(xy 172.443977 -305.438759) (xy 172.421034 -305.496707) (xy 172.391008 -305.551324) (xy 172.354374 -305.601746)
			(xy 172.311709 -305.64718) (xy 172.263687 -305.686908) (xy 172.211063 -305.720303) (xy 172.154669 -305.74684)
			(xy 172.095394 -305.7661) (xy 172.034173 -305.777779) (xy 171.97197 -305.781692) (xy 171.909767 -305.777779)
			(xy 171.848546 -305.7661) (xy 171.789271 -305.74684) (xy 171.732877 -305.720303) (xy 171.680253 -305.686908)
			(xy 171.632231 -305.64718) (xy 171.589566 -305.601746) (xy 171.552932 -305.551324) (xy 171.522906 -305.496707)
			(xy 171.499963 -305.438759) (xy 171.484463 -305.378391) (xy 171.476651 -305.316557) (xy 171.476162 -305.285394)
			(xy 167.512492 -305.285394) (xy 167.512 -305.312351) (xy 167.50415 -305.365691) (xy 167.488618 -305.41732)
			(xy 167.465733 -305.466137) (xy 167.435985 -305.511101) (xy 167.400007 -305.551255) (xy 167.358565 -305.585743)
			(xy 167.312544 -305.613829) (xy 167.262924 -305.634916) (xy 167.210763 -305.648552) (xy 167.157172 -305.654449)
			(xy 167.103293 -305.65248) (xy 167.050275 -305.642687) (xy 166.999248 -305.625279) (xy 166.9513 -305.600627)
			(xy 166.907452 -305.569257) (xy 166.868639 -305.531836) (xy 166.835687 -305.489163) (xy 166.809301 -305.442146)
			(xy 166.790041 -305.391789) (xy 166.778318 -305.339165) (xy 166.774383 -305.285394) (xy 144.992444 -305.285394)
			(xy 144.962714 -305.414449) (xy 144.922945 -305.55119) (xy 144.875504 -305.685462) (xy 144.820542 -305.816835)
			(xy 144.758236 -305.944888) (xy 144.688785 -306.069211) (xy 144.646805 -306.135278) (xy 165.442915 -306.135278)
			(xy 165.44685 -306.081507) (xy 165.458573 -306.028883) (xy 165.477833 -305.978526) (xy 165.504219 -305.931509)
			(xy 165.537171 -305.888836) (xy 165.575984 -305.851415) (xy 165.619832 -305.820045) (xy 165.66778 -305.795393)
			(xy 165.718807 -305.777985) (xy 165.771825 -305.768192) (xy 165.825704 -305.766223) (xy 165.879295 -305.77212)
			(xy 165.931456 -305.785756) (xy 165.981076 -305.806843) (xy 166.027097 -305.834929) (xy 166.068539 -305.869417)
			(xy 166.104517 -305.909571) (xy 166.134265 -305.954535) (xy 166.15715 -306.003352) (xy 166.172682 -306.054981)
			(xy 166.180532 -306.108321) (xy 166.181024 -306.135278) (xy 172.986969 -306.135278) (xy 172.990904 -306.081507)
			(xy 173.002627 -306.028883) (xy 173.021887 -305.978526) (xy 173.048273 -305.931509) (xy 173.081225 -305.888836)
			(xy 173.120038 -305.851415) (xy 173.163886 -305.820045) (xy 173.211834 -305.795393) (xy 173.262861 -305.777985)
			(xy 173.315879 -305.768192) (xy 173.369758 -305.766223) (xy 173.423349 -305.77212) (xy 173.47551 -305.785756)
			(xy 173.52513 -305.806843) (xy 173.571151 -305.834929) (xy 173.612593 -305.869417) (xy 173.648571 -305.909571)
			(xy 173.678319 -305.954535) (xy 173.701204 -306.003352) (xy 173.716736 -306.054981) (xy 173.724586 -306.108321)
			(xy 173.725078 -306.135278) (xy 173.724586 -306.162235) (xy 173.716736 -306.215575) (xy 173.701204 -306.267204)
			(xy 173.678319 -306.316021) (xy 173.648571 -306.360985) (xy 173.612593 -306.401139) (xy 173.571151 -306.435627)
			(xy 173.52513 -306.463713) (xy 173.47551 -306.4848) (xy 173.423349 -306.498436) (xy 173.369758 -306.504333)
			(xy 173.315879 -306.502364) (xy 173.262861 -306.492571) (xy 173.211834 -306.475163) (xy 173.163886 -306.450511)
			(xy 173.120038 -306.419141) (xy 173.081225 -306.38172) (xy 173.048273 -306.339047) (xy 173.021887 -306.29203)
			(xy 173.002627 -306.241673) (xy 172.990904 -306.189049) (xy 172.986969 -306.135278) (xy 166.181024 -306.135278)
			(xy 166.180532 -306.162235) (xy 166.172682 -306.215575) (xy 166.15715 -306.267204) (xy 166.134265 -306.316021)
			(xy 166.104517 -306.360985) (xy 166.068539 -306.401139) (xy 166.027097 -306.435627) (xy 165.981076 -306.463713)
			(xy 165.931456 -306.4848) (xy 165.879295 -306.498436) (xy 165.825704 -306.504333) (xy 165.771825 -306.502364)
			(xy 165.718807 -306.492571) (xy 165.66778 -306.475163) (xy 165.619832 -306.450511) (xy 165.575984 -306.419141)
			(xy 165.537171 -306.38172) (xy 165.504219 -306.339047) (xy 165.477833 -306.29203) (xy 165.458573 -306.241673)
			(xy 165.44685 -306.189049) (xy 165.442915 -306.135278) (xy 144.646805 -306.135278) (xy 144.612412 -306.189406)
			(xy 144.529361 -306.305087) (xy 144.439898 -306.415885) (xy 144.34431 -306.521443) (xy 144.242903 -306.621425)
			(xy 144.136003 -306.715509) (xy 144.02395 -306.803395) (xy 143.907105 -306.884801) (xy 143.785842 -306.959466)
			(xy 143.737805 -306.985416) (xy 168.158683 -306.985416) (xy 168.162618 -306.931645) (xy 168.174341 -306.879021)
			(xy 168.193601 -306.828664) (xy 168.219987 -306.781647) (xy 168.252939 -306.738974) (xy 168.291752 -306.701553)
			(xy 168.3356 -306.670183) (xy 168.383548 -306.645531) (xy 168.434575 -306.628123) (xy 168.487593 -306.61833)
			(xy 168.541472 -306.616361) (xy 168.595063 -306.622258) (xy 168.647224 -306.635894) (xy 168.696844 -306.656981)
			(xy 168.742865 -306.685067) (xy 168.784307 -306.719555) (xy 168.820285 -306.759709) (xy 168.850033 -306.804673)
			(xy 168.872918 -306.85349) (xy 168.88845 -306.905119) (xy 168.8963 -306.958459) (xy 168.896792 -306.985416)
			(xy 168.8963 -307.012373) (xy 168.88845 -307.065713) (xy 168.872918 -307.117342) (xy 168.850033 -307.166159)
			(xy 168.820285 -307.211123) (xy 168.784307 -307.251277) (xy 168.742865 -307.285765) (xy 168.696844 -307.313851)
			(xy 168.647224 -307.334938) (xy 168.595063 -307.348574) (xy 168.541472 -307.354471) (xy 168.487593 -307.352502)
			(xy 168.434575 -307.342709) (xy 168.383548 -307.325301) (xy 168.3356 -307.300649) (xy 168.291752 -307.269279)
			(xy 168.252939 -307.231858) (xy 168.219987 -307.189185) (xy 168.193601 -307.142168) (xy 168.174341 -307.091811)
			(xy 168.162618 -307.039187) (xy 168.158683 -306.985416) (xy 143.737805 -306.985416) (xy 143.660549 -307.027151)
			(xy 143.531627 -307.087638) (xy 143.399489 -307.140736) (xy 143.264559 -307.186272) (xy 143.127269 -307.224102)
			(xy 142.988059 -307.254104) (xy 142.847374 -307.276183) (xy 142.705666 -307.290266) (xy 142.563387 -307.29631)
			(xy 142.420995 -307.294295) (xy 142.278945 -307.284227) (xy 142.137691 -307.266139) (xy 141.997688 -307.240088)
			(xy 141.859382 -307.206159) (xy 141.723218 -307.164459) (xy 141.58963 -307.115122) (xy 141.459048 -307.058307)
			(xy 141.33189 -306.994195) (xy 141.208562 -306.922991) (xy 141.08946 -306.844925) (xy 140.974966 -306.760245)
			(xy 140.865445 -306.669224) (xy 140.76125 -306.572152) (xy 140.662713 -306.46934) (xy 140.570151 -306.361119)
			(xy 140.483859 -306.247834) (xy 140.404115 -306.129849) (xy 140.331174 -306.007541) (xy 140.265269 -305.881302)
			(xy 140.206611 -305.751537) (xy 140.155389 -305.618662) (xy 140.111767 -305.483101) (xy 140.075883 -305.345289)
			(xy 140.047854 -305.205668) (xy 140.027769 -305.064685) (xy 140.015692 -304.922792) (xy 140.011662 -304.780442)
			(xy 128.59639 -304.780442) (xy 128.59639 -307.8353) (xy 164.058615 -307.8353) (xy 164.06255 -307.781529)
			(xy 164.074273 -307.728905) (xy 164.093533 -307.678548) (xy 164.119919 -307.631531) (xy 164.152871 -307.588858)
			(xy 164.191684 -307.551437) (xy 164.235532 -307.520067) (xy 164.28348 -307.495415) (xy 164.334507 -307.478007)
			(xy 164.387525 -307.468214) (xy 164.441404 -307.466245) (xy 164.494995 -307.472142) (xy 164.547156 -307.485778)
			(xy 164.596776 -307.506865) (xy 164.642797 -307.534951) (xy 164.684239 -307.569439) (xy 164.720217 -307.609593)
			(xy 164.749965 -307.654557) (xy 164.77285 -307.703374) (xy 164.788382 -307.755003) (xy 164.796232 -307.808343)
			(xy 164.796724 -307.8353) (xy 164.796232 -307.862257) (xy 164.788382 -307.915597) (xy 164.77285 -307.967226)
			(xy 164.749965 -308.016043) (xy 164.720217 -308.061007) (xy 164.684239 -308.101161) (xy 164.642797 -308.135649)
			(xy 164.596776 -308.163735) (xy 164.547156 -308.184822) (xy 164.494995 -308.198458) (xy 164.441404 -308.204355)
			(xy 164.387525 -308.202386) (xy 164.334507 -308.192593) (xy 164.28348 -308.175185) (xy 164.235532 -308.150533)
			(xy 164.191684 -308.119163) (xy 164.152871 -308.081742) (xy 164.119919 -308.039069) (xy 164.093533 -307.992052)
			(xy 164.074273 -307.941695) (xy 164.06255 -307.889071) (xy 164.058615 -307.8353) (xy 128.59639 -307.8353)
			(xy 128.59639 -308.685438) (xy 168.158683 -308.685438) (xy 168.162618 -308.631667) (xy 168.174341 -308.579043)
			(xy 168.193601 -308.528686) (xy 168.219987 -308.481669) (xy 168.252939 -308.438996) (xy 168.291752 -308.401575)
			(xy 168.3356 -308.370205) (xy 168.383548 -308.345553) (xy 168.434575 -308.328145) (xy 168.487593 -308.318352)
			(xy 168.541472 -308.316383) (xy 168.595063 -308.32228) (xy 168.647224 -308.335916) (xy 168.696844 -308.357003)
			(xy 168.742865 -308.385089) (xy 168.784307 -308.419577) (xy 168.820285 -308.459731) (xy 168.850033 -308.504695)
			(xy 168.872918 -308.553512) (xy 168.88845 -308.605141) (xy 168.8963 -308.658481) (xy 168.896792 -308.685438)
			(xy 168.8963 -308.712395) (xy 168.88845 -308.765735) (xy 168.872918 -308.817364) (xy 168.850033 -308.866181)
			(xy 168.820285 -308.911145) (xy 168.784307 -308.951299) (xy 168.742865 -308.985787) (xy 168.696844 -309.013873)
			(xy 168.647224 -309.03496) (xy 168.595063 -309.048596) (xy 168.541472 -309.054493) (xy 168.487593 -309.052524)
			(xy 168.434575 -309.042731) (xy 168.383548 -309.025323) (xy 168.3356 -309.000671) (xy 168.291752 -308.969301)
			(xy 168.252939 -308.93188) (xy 168.219987 -308.889207) (xy 168.193601 -308.84219) (xy 168.174341 -308.791833)
			(xy 168.162618 -308.739209) (xy 168.158683 -308.685438) (xy 128.59639 -308.685438) (xy 128.59639 -309.521352)
			(xy 146.640802 -309.521352) (xy 146.644873 -309.46573) (xy 146.656999 -309.411293) (xy 146.676922 -309.359202)
			(xy 146.704218 -309.310567) (xy 146.738304 -309.266424) (xy 146.778453 -309.227715) (xy 146.823811 -309.195264)
			(xy 146.873411 -309.169763) (xy 146.926195 -309.151756) (xy 146.981038 -309.141626) (xy 147.036772 -309.139589)
			(xy 147.092209 -309.145689) (xy 147.146166 -309.159795) (xy 147.197495 -309.181607) (xy 147.245101 -309.210661)
			(xy 147.287969 -309.246336) (xy 147.325186 -309.287873) (xy 147.355959 -309.334386) (xy 147.379631 -309.384883)
			(xy 147.395699 -309.43829) (xy 147.403819 -309.493466) (xy 147.404328 -309.521352) (xy 147.404073 -309.535322)
			(xy 164.058615 -309.535322) (xy 164.06255 -309.481551) (xy 164.074273 -309.428927) (xy 164.093533 -309.37857)
			(xy 164.119919 -309.331553) (xy 164.152871 -309.28888) (xy 164.191684 -309.251459) (xy 164.235532 -309.220089)
			(xy 164.28348 -309.195437) (xy 164.334507 -309.178029) (xy 164.387525 -309.168236) (xy 164.441404 -309.166267)
			(xy 164.494995 -309.172164) (xy 164.547156 -309.1858) (xy 164.596776 -309.206887) (xy 164.642797 -309.234973)
			(xy 164.684239 -309.269461) (xy 164.720217 -309.309615) (xy 164.749965 -309.354579) (xy 164.77285 -309.403396)
			(xy 164.788382 -309.455025) (xy 164.796232 -309.508365) (xy 164.796724 -309.535322) (xy 164.796232 -309.562279)
			(xy 164.788382 -309.615619) (xy 164.77285 -309.667248) (xy 164.749965 -309.716065) (xy 164.720217 -309.761029)
			(xy 164.684239 -309.801183) (xy 164.642797 -309.835671) (xy 164.596776 -309.863757) (xy 164.547156 -309.884844)
			(xy 164.494995 -309.89848) (xy 164.441404 -309.904377) (xy 164.387525 -309.902408) (xy 164.334507 -309.892615)
			(xy 164.28348 -309.875207) (xy 164.235532 -309.850555) (xy 164.191684 -309.819185) (xy 164.152871 -309.781764)
			(xy 164.119919 -309.739091) (xy 164.093533 -309.692074) (xy 164.074273 -309.641717) (xy 164.06255 -309.589093)
			(xy 164.058615 -309.535322) (xy 147.404073 -309.535322) (xy 147.403819 -309.549238) (xy 147.395699 -309.604414)
			(xy 147.379631 -309.657821) (xy 147.355959 -309.708318) (xy 147.325186 -309.754831) (xy 147.287969 -309.796368)
			(xy 147.245101 -309.832043) (xy 147.197495 -309.861097) (xy 147.146166 -309.882909) (xy 147.092209 -309.897015)
			(xy 147.036772 -309.903115) (xy 146.981038 -309.901078) (xy 146.926195 -309.890948) (xy 146.873411 -309.872941)
			(xy 146.823811 -309.84744) (xy 146.778453 -309.814989) (xy 146.738304 -309.77628) (xy 146.704218 -309.732137)
			(xy 146.676922 -309.683502) (xy 146.656999 -309.631411) (xy 146.644873 -309.576974) (xy 146.640802 -309.521352)
			(xy 128.59639 -309.521352) (xy 128.59639 -310.054752) (xy 150.179276 -310.054752) (xy 150.183347 -309.99913)
			(xy 150.195473 -309.944693) (xy 150.215396 -309.892602) (xy 150.242692 -309.843967) (xy 150.276778 -309.799824)
			(xy 150.316927 -309.761115) (xy 150.362285 -309.728664) (xy 150.411885 -309.703163) (xy 150.464669 -309.685156)
			(xy 150.519512 -309.675026) (xy 150.575246 -309.672989) (xy 150.630683 -309.679089) (xy 150.68464 -309.693195)
			(xy 150.735969 -309.715007) (xy 150.783575 -309.744061) (xy 150.826443 -309.779736) (xy 150.86366 -309.821273)
			(xy 150.894433 -309.867786) (xy 150.918105 -309.918283) (xy 150.934173 -309.97169) (xy 150.942293 -310.026866)
			(xy 150.942802 -310.054752) (xy 150.942293 -310.082638) (xy 150.934173 -310.137814) (xy 150.918105 -310.191221)
			(xy 150.894433 -310.241718) (xy 150.86366 -310.288231) (xy 150.826443 -310.329768) (xy 150.783575 -310.365443)
			(xy 150.751193 -310.385206) (xy 168.158683 -310.385206) (xy 168.162618 -310.331435) (xy 168.174341 -310.278811)
			(xy 168.193601 -310.228454) (xy 168.219987 -310.181437) (xy 168.252939 -310.138764) (xy 168.291752 -310.101343)
			(xy 168.3356 -310.069973) (xy 168.383548 -310.045321) (xy 168.434575 -310.027913) (xy 168.487593 -310.01812)
			(xy 168.541472 -310.016151) (xy 168.595063 -310.022048) (xy 168.647224 -310.035684) (xy 168.696844 -310.056771)
			(xy 168.742865 -310.084857) (xy 168.784307 -310.119345) (xy 168.820285 -310.159499) (xy 168.850033 -310.204463)
			(xy 168.872918 -310.25328) (xy 168.88845 -310.304909) (xy 168.8963 -310.358249) (xy 168.896792 -310.385206)
			(xy 168.8963 -310.412163) (xy 168.88845 -310.465503) (xy 168.872918 -310.517132) (xy 168.850033 -310.565949)
			(xy 168.820285 -310.610913) (xy 168.784307 -310.651067) (xy 168.742865 -310.685555) (xy 168.696844 -310.713641)
			(xy 168.647224 -310.734728) (xy 168.595063 -310.748364) (xy 168.541472 -310.754261) (xy 168.487593 -310.752292)
			(xy 168.434575 -310.742499) (xy 168.383548 -310.725091) (xy 168.3356 -310.700439) (xy 168.291752 -310.669069)
			(xy 168.252939 -310.631648) (xy 168.219987 -310.588975) (xy 168.193601 -310.541958) (xy 168.174341 -310.491601)
			(xy 168.162618 -310.438977) (xy 168.158683 -310.385206) (xy 150.751193 -310.385206) (xy 150.735969 -310.394497)
			(xy 150.68464 -310.416309) (xy 150.630683 -310.430415) (xy 150.575246 -310.436515) (xy 150.519512 -310.434478)
			(xy 150.464669 -310.424348) (xy 150.411885 -310.406341) (xy 150.362285 -310.38084) (xy 150.316927 -310.348389)
			(xy 150.276778 -310.30968) (xy 150.242692 -310.265537) (xy 150.215396 -310.216902) (xy 150.195473 -310.164811)
			(xy 150.183347 -310.110374) (xy 150.179276 -310.054752) (xy 128.59639 -310.054752) (xy 128.59639 -311.452277)
			(xy 141.398437 -311.452277) (xy 141.401049 -311.389254) (xy 141.411437 -311.327038) (xy 141.42944 -311.266584)
			(xy 141.454783 -311.208822) (xy 141.487075 -311.154638) (xy 141.525822 -311.104864) (xy 141.570429 -311.060265)
			(xy 141.620209 -311.021527) (xy 141.674398 -310.989243) (xy 141.732165 -310.96391) (xy 141.792621 -310.945917)
			(xy 141.854839 -310.93554) (xy 141.917863 -310.932939) (xy 141.980724 -310.938153) (xy 142.042458 -310.951103)
			(xy 142.102116 -310.97159) (xy 142.158781 -310.999298) (xy 142.211584 -311.033803) (xy 142.259714 -311.074574)
			(xy 142.302431 -311.120985) (xy 142.339079 -311.172323) (xy 142.369096 -311.227801) (xy 142.372039 -311.235344)
			(xy 164.058615 -311.235344) (xy 164.06255 -311.181573) (xy 164.074273 -311.128949) (xy 164.093533 -311.078592)
			(xy 164.119919 -311.031575) (xy 164.152871 -310.988902) (xy 164.191684 -310.951481) (xy 164.235532 -310.920111)
			(xy 164.28348 -310.895459) (xy 164.334507 -310.878051) (xy 164.387525 -310.868258) (xy 164.441404 -310.866289)
			(xy 164.494995 -310.872186) (xy 164.547156 -310.885822) (xy 164.596776 -310.906909) (xy 164.642797 -310.934995)
			(xy 164.684239 -310.969483) (xy 164.720217 -311.009637) (xy 164.749965 -311.054601) (xy 164.77285 -311.103418)
			(xy 164.788382 -311.155047) (xy 164.796232 -311.208387) (xy 164.796724 -311.235344) (xy 164.796232 -311.262301)
			(xy 164.788382 -311.315641) (xy 164.77285 -311.36727) (xy 164.749965 -311.416087) (xy 164.720217 -311.461051)
			(xy 164.684239 -311.501205) (xy 164.642797 -311.535693) (xy 164.596776 -311.563779) (xy 164.547156 -311.584866)
			(xy 164.494995 -311.598502) (xy 164.441404 -311.604399) (xy 164.387525 -311.60243) (xy 164.334507 -311.592637)
			(xy 164.28348 -311.575229) (xy 164.235532 -311.550577) (xy 164.191684 -311.519207) (xy 164.152871 -311.481786)
			(xy 164.119919 -311.439113) (xy 164.093533 -311.392096) (xy 164.074273 -311.341739) (xy 164.06255 -311.289115)
			(xy 164.058615 -311.235344) (xy 142.372039 -311.235344) (xy 142.39202 -311.286565) (xy 142.407499 -311.347714)
			(xy 142.415295 -311.410307) (xy 142.415768 -311.441846) (xy 142.415768 -311.443878) (xy 142.415768 -311.4548)
			(xy 142.424404 -311.474358) (xy 142.496794 -311.53989) (xy 142.517114 -311.546494) (xy 142.528036 -311.545224)
			(xy 142.541459 -311.543907) (xy 142.568397 -311.542508) (xy 142.581884 -311.54243) (xy 142.612617 -311.542853)
			(xy 142.673636 -311.55026) (xy 142.733316 -311.564969) (xy 142.790789 -311.586765) (xy 142.845214 -311.61533)
			(xy 142.8958 -311.650248) (xy 142.941807 -311.691008) (xy 142.982566 -311.737017) (xy 143.017481 -311.787605)
			(xy 143.046044 -311.842032) (xy 143.067837 -311.899505) (xy 143.082544 -311.959186) (xy 143.089949 -312.020205)
			(xy 143.090392 -312.050938) (xy 143.090227 -312.067305) (xy 143.088067 -312.09997) (xy 143.086074 -312.116216)
			(xy 143.08455 -312.128662) (xy 143.093186 -312.15203) (xy 143.174212 -312.224928) (xy 143.198088 -312.231024)
			(xy 143.210534 -312.227976) (xy 143.239447 -312.221567) (xy 143.29827 -312.214691) (xy 143.327882 -312.21426)
			(xy 143.359425 -312.214749) (xy 143.422026 -312.22255) (xy 143.483182 -312.238035) (xy 143.541953 -312.260965)
			(xy 143.597435 -312.290989) (xy 143.648778 -312.327646) (xy 143.695193 -312.370371) (xy 143.735966 -312.41851)
			(xy 143.741226 -312.426561) (xy 145.338794 -312.426561) (xy 145.338794 -312.362639) (xy 145.346805 -312.299221)
			(xy 145.362702 -312.237307) (xy 145.386234 -312.177874) (xy 145.417028 -312.121859) (xy 145.454601 -312.070144)
			(xy 145.498358 -312.023547) (xy 145.547611 -311.982802) (xy 145.601582 -311.948551) (xy 145.659421 -311.921334)
			(xy 145.720214 -311.901581) (xy 145.783004 -311.889603) (xy 145.8468 -311.88559) (xy 145.910596 -311.889603)
			(xy 145.973386 -311.901581) (xy 146.034179 -311.921334) (xy 146.092018 -311.948551) (xy 146.145989 -311.982802)
			(xy 146.195242 -312.023547) (xy 146.238999 -312.070144) (xy 146.276572 -312.121859) (xy 146.307366 -312.177874)
			(xy 146.330898 -312.237307) (xy 146.346795 -312.299221) (xy 146.347164 -312.302144) (xy 148.335236 -312.302144)
			(xy 148.339307 -312.246522) (xy 148.351433 -312.192085) (xy 148.371356 -312.139994) (xy 148.398652 -312.091359)
			(xy 148.432738 -312.047216) (xy 148.472887 -312.008507) (xy 148.518245 -311.976056) (xy 148.567845 -311.950555)
			(xy 148.620629 -311.932548) (xy 148.675472 -311.922418) (xy 148.731206 -311.920381) (xy 148.786643 -311.926481)
			(xy 148.8406 -311.940587) (xy 148.891929 -311.962399) (xy 148.939535 -311.991453) (xy 148.982403 -312.027128)
			(xy 149.01962 -312.068665) (xy 149.030578 -312.085228) (xy 166.774383 -312.085228) (xy 166.778318 -312.031457)
			(xy 166.790041 -311.978833) (xy 166.809301 -311.928476) (xy 166.835687 -311.881459) (xy 166.868639 -311.838786)
			(xy 166.907452 -311.801365) (xy 166.9513 -311.769995) (xy 166.999248 -311.745343) (xy 167.050275 -311.727935)
			(xy 167.103293 -311.718142) (xy 167.157172 -311.716173) (xy 167.210763 -311.72207) (xy 167.262924 -311.735706)
			(xy 167.312544 -311.756793) (xy 167.358565 -311.784879) (xy 167.400007 -311.819367) (xy 167.435985 -311.859521)
			(xy 167.465733 -311.904485) (xy 167.488618 -311.953302) (xy 167.50415 -312.004931) (xy 167.512 -312.058271)
			(xy 167.512492 -312.085228) (xy 171.476162 -312.085228) (xy 171.476638 -312.054031) (xy 171.484456 -311.99213)
			(xy 171.499985 -311.9317) (xy 171.522978 -311.873698) (xy 171.553072 -311.819042) (xy 171.58979 -311.768597)
			(xy 171.632552 -311.723162) (xy 171.68068 -311.683456) (xy 171.706794 -311.666382) (xy 171.716954 -311.659778)
			(xy 171.729146 -311.639966) (xy 171.738544 -311.535826) (xy 171.730162 -311.514236) (xy 171.721272 -311.505854)
			(xy 171.703008 -311.488317) (xy 171.670928 -311.449145) (xy 171.644507 -311.405952) (xy 171.624242 -311.359552)
			(xy 171.610515 -311.310816) (xy 171.603583 -311.26066) (xy 171.603162 -311.235344) (xy 171.603568 -311.209995)
			(xy 171.610507 -311.159776) (xy 171.624261 -311.11098) (xy 171.644569 -311.064528) (xy 171.671049 -311.021297)
			(xy 171.703202 -310.9821) (xy 171.721526 -310.96458) (xy 171.730416 -310.956452) (xy 171.738798 -310.934608)
			(xy 171.729146 -310.830468) (xy 171.716954 -310.810656) (xy 171.706794 -310.804306) (xy 171.680677 -310.787215)
			(xy 171.632555 -310.747461) (xy 171.5898 -310.701986) (xy 171.553086 -310.651507) (xy 171.522994 -310.596822)
			(xy 171.499999 -310.538794) (xy 171.484463 -310.47834) (xy 171.476633 -310.416415) (xy 171.476162 -310.385206)
			(xy 171.476621 -310.354009) (xy 171.484442 -310.292107) (xy 171.499973 -310.231676) (xy 171.522969 -310.173674)
			(xy 171.553065 -310.119018) (xy 171.589786 -310.068574) (xy 171.632549 -310.023139) (xy 171.680679 -309.983433)
			(xy 171.706794 -309.96636) (xy 171.716954 -309.959756) (xy 171.729146 -309.939944) (xy 171.738544 -309.835804)
			(xy 171.730162 -309.814214) (xy 171.721272 -309.805832) (xy 171.70137 -309.786673) (xy 171.666908 -309.7435)
			(xy 171.639269 -309.695671) (xy 171.619073 -309.644254) (xy 171.60677 -309.590401) (xy 171.602637 -309.535315)
			(xy 171.606766 -309.480229) (xy 171.619064 -309.426374) (xy 171.639256 -309.374956) (xy 171.666891 -309.327125)
			(xy 171.70135 -309.283949) (xy 171.721272 -309.264812) (xy 171.730162 -309.25643) (xy 171.738544 -309.23484)
			(xy 171.729146 -309.1307) (xy 171.716954 -309.110888) (xy 171.706794 -309.104284) (xy 171.68068 -309.087213)
			(xy 171.632563 -309.047496) (xy 171.589811 -309.002055) (xy 171.553097 -308.951609) (xy 171.523004 -308.896955)
			(xy 171.500007 -308.838956) (xy 171.484469 -308.778531) (xy 171.476635 -308.716634) (xy 171.476162 -308.685438)
			(xy 171.476631 -308.654229) (xy 171.484457 -308.592303) (xy 171.499991 -308.531848) (xy 171.522986 -308.473819)
			(xy 171.553079 -308.419134) (xy 171.589795 -308.368656) (xy 171.632554 -308.323184) (xy 171.68068 -308.283435)
			(xy 171.706794 -308.266338) (xy 171.716954 -308.259988) (xy 171.729146 -308.240176) (xy 171.738798 -308.136036)
			(xy 171.730416 -308.114192) (xy 171.721526 -308.106064) (xy 171.703194 -308.088554) (xy 171.671051 -308.04935)
			(xy 171.644579 -308.006115) (xy 171.624275 -307.959662) (xy 171.610524 -307.910867) (xy 171.603582 -307.860648)
			(xy 171.603162 -307.8353) (xy 171.603551 -307.809981) (xy 171.610479 -307.75982) (xy 171.624206 -307.711079)
			(xy 171.644472 -307.664674) (xy 171.670897 -307.621479) (xy 171.702984 -307.582305) (xy 171.721272 -307.56479)
			(xy 171.730162 -307.556408) (xy 171.738544 -307.534818) (xy 171.729146 -307.430678) (xy 171.716954 -307.410866)
			(xy 171.706794 -307.404262) (xy 171.68067 -307.387205) (xy 171.632553 -307.347486) (xy 171.589801 -307.302043)
			(xy 171.553089 -307.251595) (xy 171.522997 -307.196939) (xy 171.500001 -307.138939) (xy 171.484465 -307.078511)
			(xy 171.476634 -307.016612) (xy 171.476162 -306.985416) (xy 171.476651 -306.954253) (xy 171.484463 -306.892419)
			(xy 171.499963 -306.832051) (xy 171.522906 -306.774103) (xy 171.552932 -306.719486) (xy 171.589566 -306.669064)
			(xy 171.632231 -306.62363) (xy 171.680253 -306.583902) (xy 171.732877 -306.550507) (xy 171.789271 -306.52397)
			(xy 171.848546 -306.50471) (xy 171.909767 -306.493031) (xy 171.97197 -306.489118) (xy 172.034173 -306.493031)
			(xy 172.095394 -306.50471) (xy 172.154669 -306.52397) (xy 172.211063 -306.550507) (xy 172.263687 -306.583902)
			(xy 172.311709 -306.62363) (xy 172.354374 -306.669064) (xy 172.391008 -306.719486) (xy 172.421034 -306.774103)
			(xy 172.443977 -306.832051) (xy 172.459477 -306.892419) (xy 172.467289 -306.954253) (xy 172.467778 -306.985416)
			(xy 172.467364 -307.016615) (xy 172.45954 -307.07852) (xy 172.444004 -307.138953) (xy 172.421002 -307.196956)
			(xy 172.3909 -307.251612) (xy 172.354172 -307.302056) (xy 172.311401 -307.347488) (xy 172.263264 -307.387191)
			(xy 172.237146 -307.404262) (xy 172.226986 -307.410866) (xy 172.214794 -307.430678) (xy 172.205396 -307.534818)
			(xy 172.213778 -307.556408) (xy 172.222668 -307.56479) (xy 172.240961 -307.582298) (xy 172.273037 -307.621478)
			(xy 172.299453 -307.664676) (xy 172.319712 -307.711082) (xy 172.333434 -307.759823) (xy 172.34036 -307.809982)
			(xy 172.340778 -307.8353) (xy 172.340353 -307.860648) (xy 172.333421 -307.910868) (xy 172.319672 -307.959664)
			(xy 172.299368 -308.006116) (xy 172.27289 -308.049348) (xy 172.240738 -308.088544) (xy 172.222414 -308.106064)
			(xy 172.213524 -308.114192) (xy 172.205142 -308.136036) (xy 172.214794 -308.240176) (xy 172.226986 -308.259988)
			(xy 172.237146 -308.266338) (xy 172.263247 -308.283453) (xy 172.311367 -308.323204) (xy 172.354122 -308.368677)
			(xy 172.390836 -308.419152) (xy 172.42093 -308.473834) (xy 172.443928 -308.531858) (xy 172.459468 -308.592308)
			(xy 172.467304 -308.65423) (xy 172.467778 -308.685438) (xy 172.467303 -308.716635) (xy 172.459488 -308.778538)
			(xy 172.443962 -308.838969) (xy 172.420969 -308.896972) (xy 172.390875 -308.951628) (xy 172.354155 -309.002073)
			(xy 172.311392 -309.047507) (xy 172.263261 -309.087212) (xy 172.237146 -309.104284) (xy 172.226986 -309.110888)
			(xy 172.214794 -309.1307) (xy 172.205396 -309.23484) (xy 172.213778 -309.25643) (xy 172.222668 -309.264812)
			(xy 172.242617 -309.283926) (xy 172.277084 -309.327103) (xy 172.304726 -309.374938) (xy 172.324923 -309.426361)
			(xy 172.337224 -309.480222) (xy 172.341354 -309.535315) (xy 172.33722 -309.590408) (xy 172.324914 -309.644267)
			(xy 172.304713 -309.695689) (xy 172.277067 -309.743522) (xy 172.242596 -309.786696) (xy 172.222668 -309.805832)
			(xy 172.213778 -309.814214) (xy 172.205396 -309.835804) (xy 172.214794 -309.939944) (xy 172.226986 -309.959756)
			(xy 172.237146 -309.96636) (xy 172.263266 -309.983423) (xy 172.311386 -310.023139) (xy 172.35414 -310.06858)
			(xy 172.390854 -310.119027) (xy 172.420947 -310.173683) (xy 172.443943 -310.231683) (xy 172.459478 -310.29211)
			(xy 172.467307 -310.35401) (xy 172.467778 -310.385206) (xy 172.467293 -310.416415) (xy 172.459472 -310.478342)
			(xy 172.443944 -310.538797) (xy 172.420952 -310.596827) (xy 172.390861 -310.651513) (xy 172.354146 -310.701991)
			(xy 172.311387 -310.747463) (xy 172.263261 -310.78721) (xy 172.237146 -310.804306) (xy 172.226986 -310.810656)
			(xy 172.214794 -310.830468) (xy 172.205142 -310.934608) (xy 172.213524 -310.956452) (xy 172.222414 -310.96458)
			(xy 172.240727 -310.98211) (xy 172.27287 -311.02131) (xy 172.299344 -311.064542) (xy 172.31965 -311.110991)
			(xy 172.333407 -311.159782) (xy 172.340354 -311.209997) (xy 172.340778 -311.235344) (xy 175.57623 -311.235344)
			(xy 175.576672 -311.204134) (xy 175.584499 -311.142205) (xy 175.600034 -311.081748) (xy 175.623032 -311.023718)
			(xy 175.653129 -310.969033) (xy 175.68985 -310.918555) (xy 175.732614 -310.873085) (xy 175.780745 -310.833339)
			(xy 175.806862 -310.816244) (xy 175.817022 -310.809894) (xy 175.829214 -310.790082) (xy 175.838866 -310.685942)
			(xy 175.830484 -310.664098) (xy 175.821594 -310.65597) (xy 175.803259 -310.638463) (xy 175.771117 -310.599258)
			(xy 175.744646 -310.556022) (xy 175.724344 -310.509568) (xy 175.710592 -310.460773) (xy 175.703651 -310.410554)
			(xy 175.70323 -310.385206) (xy 175.703632 -310.359888) (xy 175.710559 -310.309728) (xy 175.724284 -310.260987)
			(xy 175.744548 -310.214582) (xy 175.77097 -310.171386) (xy 175.803054 -310.132211) (xy 175.82134 -310.114696)
			(xy 175.83023 -310.106314) (xy 175.838612 -310.084724) (xy 175.829214 -309.980584) (xy 175.817022 -309.960772)
			(xy 175.806862 -309.954168) (xy 175.780769 -309.937062) (xy 175.732643 -309.897355) (xy 175.689881 -309.851922)
			(xy 175.65316 -309.801481) (xy 175.623061 -309.746829) (xy 175.600059 -309.688832) (xy 175.584519 -309.628406)
			(xy 175.576686 -309.566508) (xy 175.576685 -309.504116) (xy 175.584515 -309.442217) (xy 175.600052 -309.381791)
			(xy 175.623051 -309.323792) (xy 175.653148 -309.269139) (xy 175.689866 -309.218696) (xy 175.732626 -309.173261)
			(xy 175.78075 -309.133552) (xy 175.806862 -309.116476) (xy 175.817022 -309.109872) (xy 175.829214 -309.09006)
			(xy 175.838612 -308.98592) (xy 175.83023 -308.96433) (xy 175.82134 -308.955948) (xy 175.803067 -308.93842)
			(xy 175.770989 -308.899245) (xy 175.74457 -308.856051) (xy 175.724307 -308.809649) (xy 175.710581 -308.760911)
			(xy 175.703651 -308.710755) (xy 175.70323 -308.685438) (xy 175.703611 -308.660088) (xy 175.710552 -308.609867)
			(xy 175.724309 -308.56107) (xy 175.744622 -308.514618) (xy 175.771108 -308.471387) (xy 175.803267 -308.432193)
			(xy 175.821594 -308.414674) (xy 175.830484 -308.406546) (xy 175.838866 -308.384702) (xy 175.829214 -308.280562)
			(xy 175.817022 -308.26075) (xy 175.806862 -308.2544) (xy 175.780735 -308.237324) (xy 175.732614 -308.197567)
			(xy 175.68986 -308.152089) (xy 175.653148 -308.101608) (xy 175.623057 -308.046921) (xy 175.600063 -307.988891)
			(xy 175.584529 -307.928436) (xy 175.576701 -307.86651) (xy 175.57623 -307.8353) (xy 175.576699 -307.804103)
			(xy 175.58452 -307.742202) (xy 175.600051 -307.681773) (xy 175.623046 -307.623771) (xy 175.65314 -307.569116)
			(xy 175.689859 -307.518671) (xy 175.732621 -307.473236) (xy 175.780748 -307.433528) (xy 175.806862 -307.416454)
			(xy 175.817022 -307.40985) (xy 175.829214 -307.390038) (xy 175.838612 -307.285898) (xy 175.83023 -307.264308)
			(xy 175.82134 -307.255926) (xy 175.803057 -307.238409) (xy 175.770979 -307.199231) (xy 175.744562 -307.156035)
			(xy 175.724301 -307.109631) (xy 175.710577 -307.060891) (xy 175.703649 -307.010733) (xy 175.70323 -306.985416)
			(xy 175.703663 -306.960068) (xy 175.710593 -306.909849) (xy 175.72434 -306.861053) (xy 175.744643 -306.8146)
			(xy 175.77112 -306.771368) (xy 175.803271 -306.732172) (xy 175.821594 -306.714652) (xy 175.830484 -306.706524)
			(xy 175.838866 -306.68468) (xy 175.829214 -306.58054) (xy 175.817022 -306.560728) (xy 175.806862 -306.554378)
			(xy 175.780725 -306.537317) (xy 175.732604 -306.497558) (xy 175.689851 -306.452078) (xy 175.653139 -306.401594)
			(xy 175.62305 -306.346905) (xy 175.600058 -306.288873) (xy 175.584526 -306.228416) (xy 175.576699 -306.166488)
			(xy 175.57623 -306.135278) (xy 175.576719 -306.104115) (xy 175.584531 -306.042281) (xy 175.600031 -305.981913)
			(xy 175.622974 -305.923965) (xy 175.653 -305.869348) (xy 175.689634 -305.818926) (xy 175.732299 -305.773492)
			(xy 175.780321 -305.733764) (xy 175.832945 -305.700369) (xy 175.889339 -305.673832) (xy 175.948614 -305.654572)
			(xy 176.009835 -305.642893) (xy 176.072038 -305.63898) (xy 176.134241 -305.642893) (xy 176.195462 -305.654572)
			(xy 176.254737 -305.673832) (xy 176.311131 -305.700369) (xy 176.363755 -305.733764) (xy 176.411777 -305.773492)
			(xy 176.454442 -305.818926) (xy 176.491076 -305.869348) (xy 176.521102 -305.923965) (xy 176.544045 -305.981913)
			(xy 176.559545 -306.042281) (xy 176.567357 -306.104115) (xy 176.567846 -306.135278) (xy 180.531023 -306.135278)
			(xy 180.534958 -306.081507) (xy 180.546681 -306.028883) (xy 180.565941 -305.978526) (xy 180.592327 -305.931509)
			(xy 180.625279 -305.888836) (xy 180.664092 -305.851415) (xy 180.70794 -305.820045) (xy 180.755888 -305.795393)
			(xy 180.806915 -305.777985) (xy 180.859933 -305.768192) (xy 180.913812 -305.766223) (xy 180.967403 -305.77212)
			(xy 181.019564 -305.785756) (xy 181.069184 -305.806843) (xy 181.115205 -305.834929) (xy 181.156647 -305.869417)
			(xy 181.192625 -305.909571) (xy 181.222373 -305.954535) (xy 181.245258 -306.003352) (xy 181.26079 -306.054981)
			(xy 181.26864 -306.108321) (xy 181.269132 -306.135278) (xy 181.26864 -306.162235) (xy 181.26079 -306.215575)
			(xy 181.245258 -306.267204) (xy 181.222373 -306.316021) (xy 181.192625 -306.360985) (xy 181.156647 -306.401139)
			(xy 181.115205 -306.435627) (xy 181.069184 -306.463713) (xy 181.019564 -306.4848) (xy 180.967403 -306.498436)
			(xy 180.913812 -306.504333) (xy 180.859933 -306.502364) (xy 180.806915 -306.492571) (xy 180.755888 -306.475163)
			(xy 180.70794 -306.450511) (xy 180.664092 -306.419141) (xy 180.625279 -306.38172) (xy 180.592327 -306.339047)
			(xy 180.565941 -306.29203) (xy 180.546681 -306.241673) (xy 180.534958 -306.189049) (xy 180.531023 -306.135278)
			(xy 176.567846 -306.135278) (xy 176.567386 -306.166488) (xy 176.559558 -306.228414) (xy 176.544023 -306.288869)
			(xy 176.521026 -306.346897) (xy 176.490932 -306.401582) (xy 176.454215 -306.45206) (xy 176.411455 -306.497532)
			(xy 176.363328 -306.537281) (xy 176.337214 -306.554378) (xy 176.327054 -306.560728) (xy 176.314862 -306.58054)
			(xy 176.30521 -306.68468) (xy 176.313592 -306.706524) (xy 176.322482 -306.714652) (xy 176.340823 -306.732153)
			(xy 176.372965 -306.771359) (xy 176.399436 -306.814596) (xy 176.419738 -306.861051) (xy 176.433488 -306.909848)
			(xy 176.440427 -306.960067) (xy 176.440846 -306.985416) (xy 176.440466 -307.010735) (xy 176.433535 -307.060896)
			(xy 176.419807 -307.109638) (xy 176.399539 -307.156043) (xy 176.373112 -307.199238) (xy 176.341024 -307.238412)
			(xy 176.322736 -307.255926) (xy 176.313846 -307.264308) (xy 176.305464 -307.285898) (xy 176.314862 -307.390038)
			(xy 176.327054 -307.40985) (xy 176.337214 -307.416454) (xy 176.363347 -307.433497) (xy 176.411463 -307.473219)
			(xy 176.454215 -307.518664) (xy 176.490926 -307.569114) (xy 176.521017 -307.623772) (xy 176.544011 -307.681774)
			(xy 176.559546 -307.742203) (xy 176.567375 -307.804103) (xy 176.567846 -307.8353) (xy 176.567325 -307.866508)
			(xy 176.559506 -307.928431) (xy 176.543981 -307.988885) (xy 176.520993 -308.046913) (xy 176.490907 -308.101598)
			(xy 176.454198 -308.152077) (xy 176.411445 -308.197551) (xy 176.363325 -308.237302) (xy 176.337214 -308.2544)
			(xy 176.327054 -308.26075) (xy 176.314862 -308.280562) (xy 176.30521 -308.384702) (xy 176.313592 -308.406546)
			(xy 176.322482 -308.414674) (xy 176.340786 -308.432213) (xy 176.372931 -308.471411) (xy 176.399407 -308.51464)
			(xy 176.419715 -308.561087) (xy 176.433473 -308.609877) (xy 176.440422 -308.660092) (xy 176.440846 -308.685438)
			(xy 176.440413 -308.710755) (xy 176.433494 -308.760914) (xy 176.419775 -308.809655) (xy 176.399517 -308.85606)
			(xy 176.3731 -308.899256) (xy 176.34102 -308.938432) (xy 176.322736 -308.955948) (xy 176.313846 -308.96433)
			(xy 176.305464 -308.98592) (xy 176.314862 -309.09006) (xy 176.327054 -309.109872) (xy 176.337214 -309.116476)
			(xy 176.363349 -309.133521) (xy 176.411479 -309.173232) (xy 176.454244 -309.21867) (xy 176.490967 -309.269117)
			(xy 176.521068 -309.323774) (xy 176.544069 -309.381777) (xy 176.559609 -309.442209) (xy 176.567439 -309.504113)
			(xy 176.567438 -309.566511) (xy 176.559604 -309.628414) (xy 176.544062 -309.688845) (xy 176.521057 -309.746848)
			(xy 176.490954 -309.801503) (xy 176.454229 -309.851948) (xy 176.411462 -309.897384) (xy 176.36333 -309.937093)
			(xy 176.337214 -309.954168) (xy 176.327054 -309.960772) (xy 176.314862 -309.980584) (xy 176.305464 -310.084724)
			(xy 176.313846 -310.106314) (xy 176.322736 -310.114696) (xy 176.341025 -310.132207) (xy 176.373103 -310.171385)
			(xy 176.399521 -310.214583) (xy 176.419781 -310.260989) (xy 176.433502 -310.309729) (xy 176.440428 -310.359888)
			(xy 176.440846 -310.385206) (xy 176.440404 -310.410553) (xy 176.433472 -310.460771) (xy 176.419725 -310.509566)
			(xy 176.399424 -310.556018) (xy 176.37295 -310.599251) (xy 176.340803 -310.638449) (xy 176.322482 -310.65597)
			(xy 176.313592 -310.664098) (xy 176.30521 -310.685942) (xy 176.314862 -310.790082) (xy 176.327054 -310.809894)
			(xy 176.337214 -310.816244) (xy 176.36331 -310.833366) (xy 176.411432 -310.873115) (xy 176.454188 -310.918586)
			(xy 176.490903 -310.969061) (xy 176.520998 -311.023741) (xy 176.543996 -311.081765) (xy 176.559536 -311.142215)
			(xy 176.567372 -311.204136) (xy 176.567846 -311.235344) (xy 176.567357 -311.266507) (xy 176.559545 -311.328341)
			(xy 176.544045 -311.388709) (xy 176.521102 -311.446657) (xy 176.491076 -311.501274) (xy 176.454442 -311.551696)
			(xy 176.411777 -311.59713) (xy 176.363755 -311.636858) (xy 176.311131 -311.670253) (xy 176.254737 -311.69679)
			(xy 176.195462 -311.71605) (xy 176.134241 -311.727729) (xy 176.072038 -311.731642) (xy 176.009835 -311.727729)
			(xy 175.948614 -311.71605) (xy 175.889339 -311.69679) (xy 175.832945 -311.670253) (xy 175.780321 -311.636858)
			(xy 175.732299 -311.59713) (xy 175.689634 -311.551696) (xy 175.653 -311.501274) (xy 175.622974 -311.446657)
			(xy 175.600031 -311.388709) (xy 175.584531 -311.328341) (xy 175.576719 -311.266507) (xy 175.57623 -311.235344)
			(xy 172.340778 -311.235344) (xy 172.340339 -311.260661) (xy 172.333419 -311.310819) (xy 172.319702 -311.359559)
			(xy 172.299444 -311.405964) (xy 172.273029 -311.449161) (xy 172.240951 -311.488337) (xy 172.222668 -311.505854)
			(xy 172.213778 -311.514236) (xy 172.205396 -311.535826) (xy 172.214794 -311.639966) (xy 172.226986 -311.659778)
			(xy 172.237146 -311.666382) (xy 172.263231 -311.683497) (xy 172.31135 -311.723206) (xy 172.354106 -311.768639)
			(xy 172.390823 -311.819078) (xy 172.42092 -311.873726) (xy 172.443922 -311.931719) (xy 172.459465 -311.99214)
			(xy 172.467302 -312.054034) (xy 172.467778 -312.085228) (xy 174.318437 -312.085228) (xy 174.322372 -312.031457)
			(xy 174.334095 -311.978833) (xy 174.353355 -311.928476) (xy 174.379741 -311.881459) (xy 174.412693 -311.838786)
			(xy 174.451506 -311.801365) (xy 174.495354 -311.769995) (xy 174.543302 -311.745343) (xy 174.594329 -311.727935)
			(xy 174.647347 -311.718142) (xy 174.701226 -311.716173) (xy 174.754817 -311.72207) (xy 174.806978 -311.735706)
			(xy 174.856598 -311.756793) (xy 174.902619 -311.784879) (xy 174.944061 -311.819367) (xy 174.980039 -311.859521)
			(xy 175.009787 -311.904485) (xy 175.032672 -311.953302) (xy 175.048204 -312.004931) (xy 175.056054 -312.058271)
			(xy 175.056546 -312.085228) (xy 179.020216 -312.085228) (xy 179.020667 -312.05403) (xy 179.028486 -311.992127)
			(xy 179.044017 -311.931695) (xy 179.067013 -311.873692) (xy 179.09711 -311.819036) (xy 179.133833 -311.768592)
			(xy 179.176599 -311.723158) (xy 179.224732 -311.683454) (xy 179.250848 -311.666382) (xy 179.261008 -311.659778)
			(xy 179.2732 -311.639966) (xy 179.282598 -311.535826) (xy 179.274216 -311.514236) (xy 179.265326 -311.505854)
			(xy 179.247054 -311.488326) (xy 179.214976 -311.44915) (xy 179.188557 -311.405956) (xy 179.168294 -311.359554)
			(xy 179.154568 -311.310817) (xy 179.147637 -311.26066) (xy 179.147216 -311.235344) (xy 179.147605 -311.209995)
			(xy 179.154545 -311.159774) (xy 179.168301 -311.110977) (xy 179.188612 -311.064525) (xy 179.215096 -311.021294)
			(xy 179.247254 -310.982099) (xy 179.26558 -310.96458) (xy 179.27447 -310.956452) (xy 179.282852 -310.934608)
			(xy 179.2732 -310.830468) (xy 179.261008 -310.810656) (xy 179.250848 -310.804306) (xy 179.22472 -310.787231)
			(xy 179.1766 -310.747474) (xy 179.133847 -310.701995) (xy 179.097135 -310.651514) (xy 179.067045 -310.596826)
			(xy 179.044051 -310.538797) (xy 179.028516 -310.478342) (xy 179.020687 -310.416416) (xy 179.020216 -310.385206)
			(xy 179.02065 -310.354008) (xy 179.028472 -310.292104) (xy 179.044005 -310.231672) (xy 179.067003 -310.173668)
			(xy 179.097103 -310.119012) (xy 179.133828 -310.068568) (xy 179.176596 -310.023135) (xy 179.224731 -309.983432)
			(xy 179.250848 -309.96636) (xy 179.261008 -309.959756) (xy 179.2732 -309.939944) (xy 179.282598 -309.835804)
			(xy 179.274216 -309.814214) (xy 179.265326 -309.805832) (xy 179.245422 -309.786674) (xy 179.210954 -309.743503)
			(xy 179.183311 -309.695674) (xy 179.163112 -309.644257) (xy 179.150808 -309.590403) (xy 179.146674 -309.535315)
			(xy 179.150803 -309.480227) (xy 179.163103 -309.426371) (xy 179.183298 -309.374953) (xy 179.210937 -309.327121)
			(xy 179.245401 -309.283948) (xy 179.265326 -309.264812) (xy 179.274216 -309.25643) (xy 179.282598 -309.23484)
			(xy 179.2732 -309.1307) (xy 179.261008 -309.110888) (xy 179.250848 -309.104284) (xy 179.224746 -309.087194)
			(xy 179.176627 -309.047481) (xy 179.133872 -309.002044) (xy 179.097157 -308.951601) (xy 179.067062 -308.89695)
			(xy 179.044063 -308.838953) (xy 179.028523 -308.778529) (xy 179.020689 -308.716633) (xy 179.020216 -308.685438)
			(xy 179.02066 -308.654228) (xy 179.028487 -308.5923) (xy 179.044022 -308.531843) (xy 179.06702 -308.473813)
			(xy 179.097117 -308.419128) (xy 179.133837 -308.368651) (xy 179.176601 -308.323179) (xy 179.224732 -308.283433)
			(xy 179.250848 -308.266338) (xy 179.261008 -308.259988) (xy 179.2732 -308.240176) (xy 179.282852 -308.136036)
			(xy 179.27447 -308.114192) (xy 179.26558 -308.106064) (xy 179.247239 -308.088563) (xy 179.215099 -308.049356)
			(xy 179.188629 -308.006118) (xy 179.168327 -307.959664) (xy 179.154577 -307.910868) (xy 179.147636 -307.860648)
			(xy 179.147216 -307.8353) (xy 179.147619 -307.809982) (xy 179.154546 -307.759822) (xy 179.168271 -307.711081)
			(xy 179.188535 -307.664677) (xy 179.214957 -307.621481) (xy 179.24704 -307.582306) (xy 179.265326 -307.56479)
			(xy 179.274216 -307.556408) (xy 179.282598 -307.534818) (xy 179.2732 -307.430678) (xy 179.261008 -307.410866)
			(xy 179.250848 -307.404262) (xy 179.224736 -307.387187) (xy 179.176617 -307.347472) (xy 179.133863 -307.302033)
			(xy 179.097148 -307.251588) (xy 179.067054 -307.196934) (xy 179.044057 -307.138935) (xy 179.02852 -307.07851)
			(xy 179.020688 -307.016612) (xy 179.020216 -306.985416) (xy 179.020705 -306.954253) (xy 179.028517 -306.892419)
			(xy 179.044017 -306.832051) (xy 179.06696 -306.774103) (xy 179.096986 -306.719486) (xy 179.13362 -306.669064)
			(xy 179.176285 -306.62363) (xy 179.224307 -306.583902) (xy 179.276931 -306.550507) (xy 179.333325 -306.52397)
			(xy 179.3926 -306.50471) (xy 179.453821 -306.493031) (xy 179.516024 -306.489118) (xy 179.578227 -306.493031)
			(xy 179.639448 -306.50471) (xy 179.698723 -306.52397) (xy 179.755117 -306.550507) (xy 179.807741 -306.583902)
			(xy 179.855763 -306.62363) (xy 179.898428 -306.669064) (xy 179.935062 -306.719486) (xy 179.965088 -306.774103)
			(xy 179.988031 -306.832051) (xy 180.003531 -306.892419) (xy 180.011343 -306.954253) (xy 180.011832 -306.985416)
			(xy 180.011393 -307.016614) (xy 180.00357 -307.078517) (xy 179.988035 -307.138948) (xy 179.965037 -307.19695)
			(xy 179.934938 -307.251606) (xy 179.898215 -307.30205) (xy 179.855448 -307.347484) (xy 179.807316 -307.387189)
			(xy 179.7812 -307.404262) (xy 179.77104 -307.410866) (xy 179.758848 -307.430678) (xy 179.74945 -307.534818)
			(xy 179.757832 -307.556408) (xy 179.766722 -307.56479) (xy 179.785006 -307.582307) (xy 179.817085 -307.621484)
			(xy 179.843503 -307.66468) (xy 179.863764 -307.711084) (xy 179.877487 -307.759824) (xy 179.884414 -307.809983)
			(xy 179.884832 -307.8353) (xy 179.88439 -307.860647) (xy 179.877459 -307.910866) (xy 179.863712 -307.959661)
			(xy 179.843411 -308.006113) (xy 179.816937 -308.049345) (xy 179.784789 -308.088543) (xy 179.766468 -308.106064)
			(xy 179.757578 -308.114192) (xy 179.749196 -308.136036) (xy 179.758848 -308.240176) (xy 179.77104 -308.259988)
			(xy 179.7812 -308.266338) (xy 179.80729 -308.283469) (xy 179.855412 -308.323216) (xy 179.898169 -308.368686)
			(xy 179.934885 -308.419159) (xy 179.964981 -308.473838) (xy 179.98798 -308.531861) (xy 180.003521 -308.59231)
			(xy 180.011357 -308.654231) (xy 180.011832 -308.685438) (xy 180.011332 -308.716634) (xy 180.003518 -308.778535)
			(xy 179.987993 -308.838964) (xy 179.965004 -308.896966) (xy 179.934913 -308.951622) (xy 179.898198 -309.002067)
			(xy 179.855439 -309.047503) (xy 179.807313 -309.08721) (xy 179.7812 -309.104284) (xy 179.77104 -309.110888)
			(xy 179.758848 -309.1307) (xy 179.74945 -309.23484) (xy 179.757832 -309.25643) (xy 179.766722 -309.264812)
			(xy 179.786668 -309.283927) (xy 179.821131 -309.327106) (xy 179.848768 -309.374942) (xy 179.868963 -309.426364)
			(xy 179.881262 -309.480224) (xy 179.885391 -309.535315) (xy 179.881257 -309.590406) (xy 179.868954 -309.644264)
			(xy 179.848755 -309.695685) (xy 179.821114 -309.743519) (xy 179.786648 -309.786695) (xy 179.766722 -309.805832)
			(xy 179.757832 -309.814214) (xy 179.74945 -309.835804) (xy 179.758848 -309.939944) (xy 179.77104 -309.959756)
			(xy 179.7812 -309.96636) (xy 179.807333 -309.983404) (xy 179.85545 -310.023125) (xy 179.898202 -310.068569)
			(xy 179.934913 -310.11902) (xy 179.965004 -310.173678) (xy 179.987998 -310.23168) (xy 180.003533 -310.292109)
			(xy 180.011361 -310.354009) (xy 180.011832 -310.385206) (xy 180.011322 -310.416414) (xy 180.003502 -310.478339)
			(xy 179.987976 -310.538793) (xy 179.964987 -310.596821) (xy 179.934899 -310.651506) (xy 179.898188 -310.701985)
			(xy 179.855434 -310.747458) (xy 179.807312 -310.787209) (xy 179.7812 -310.804306) (xy 179.77104 -310.810656)
			(xy 179.758848 -310.830468) (xy 179.749196 -310.934608) (xy 179.757578 -310.956452) (xy 179.766468 -310.96458)
			(xy 179.784772 -310.982119) (xy 179.816917 -311.021316) (xy 179.843394 -311.064546) (xy 179.863702 -311.110993)
			(xy 179.87746 -311.159783) (xy 179.884408 -311.209998) (xy 179.884832 -311.235344) (xy 183.120284 -311.235344)
			(xy 183.120748 -311.204134) (xy 183.128574 -311.142208) (xy 183.144107 -311.081752) (xy 183.167102 -311.023723)
			(xy 183.197196 -310.969038) (xy 183.233914 -310.91856) (xy 183.276674 -310.873088) (xy 183.324801 -310.83334)
			(xy 183.350916 -310.816244) (xy 183.361076 -310.809894) (xy 183.373268 -310.790082) (xy 183.38292 -310.685942)
			(xy 183.374538 -310.664098) (xy 183.365648 -310.65597) (xy 183.347323 -310.638452) (xy 183.315179 -310.599251)
			(xy 183.288705 -310.556017) (xy 183.2684 -310.509566) (xy 183.254647 -310.460771) (xy 183.247705 -310.410554)
			(xy 183.247284 -310.385206) (xy 183.247701 -310.359889) (xy 183.254627 -310.30973) (xy 183.26835 -310.26099)
			(xy 183.288611 -310.214585) (xy 183.31503 -310.171389) (xy 183.34711 -310.132213) (xy 183.365394 -310.114696)
			(xy 183.374284 -310.106314) (xy 183.382666 -310.084724) (xy 183.373268 -309.980584) (xy 183.361076 -309.960772)
			(xy 183.350916 -309.954168) (xy 183.324821 -309.937064) (xy 183.27669 -309.89736) (xy 183.233923 -309.851928)
			(xy 183.197198 -309.801487) (xy 183.167095 -309.746835) (xy 183.144091 -309.688836) (xy 183.128549 -309.628409)
			(xy 183.120715 -309.566509) (xy 183.120714 -309.504115) (xy 183.128545 -309.442214) (xy 183.144084 -309.381786)
			(xy 183.167085 -309.323786) (xy 183.197186 -309.269133) (xy 183.233908 -309.21869) (xy 183.276673 -309.173257)
			(xy 183.324802 -309.13355) (xy 183.350916 -309.116476) (xy 183.361076 -309.109872) (xy 183.373268 -309.09006)
			(xy 183.382666 -308.98592) (xy 183.374284 -308.96433) (xy 183.365394 -308.955948) (xy 183.347132 -308.938409)
			(xy 183.31505 -308.899238) (xy 183.288628 -308.856046) (xy 183.268363 -308.809646) (xy 183.254636 -308.76091)
			(xy 183.247705 -308.710754) (xy 183.247284 -308.685438) (xy 183.247679 -308.660089) (xy 183.25462 -308.609869)
			(xy 183.268375 -308.561072) (xy 183.288685 -308.514621) (xy 183.315168 -308.471389) (xy 183.347323 -308.432194)
			(xy 183.365648 -308.414674) (xy 183.374538 -308.406546) (xy 183.38292 -308.384702) (xy 183.373268 -308.280562)
			(xy 183.361076 -308.26075) (xy 183.350916 -308.2544) (xy 183.324801 -308.237305) (xy 183.276679 -308.197553)
			(xy 183.233922 -308.152079) (xy 183.197208 -308.1016) (xy 183.167115 -308.046916) (xy 183.14412 -307.988888)
			(xy 183.128585 -307.928434) (xy 183.120755 -307.866509) (xy 183.120284 -307.8353) (xy 183.120728 -307.804102)
			(xy 183.12855 -307.742199) (xy 183.144083 -307.681768) (xy 183.16708 -307.623765) (xy 183.197179 -307.569109)
			(xy 183.233901 -307.518665) (xy 183.276668 -307.473231) (xy 183.3248 -307.433527) (xy 183.350916 -307.416454)
			(xy 183.361076 -307.40985) (xy 183.373268 -307.390038) (xy 183.382666 -307.285898) (xy 183.374284 -307.264308)
			(xy 183.365394 -307.255926) (xy 183.347121 -307.238398) (xy 183.31504 -307.199224) (xy 183.28862 -307.15603)
			(xy 183.268357 -307.109628) (xy 183.254632 -307.06089) (xy 183.247703 -307.010733) (xy 183.247284 -306.985416)
			(xy 183.247731 -306.960069) (xy 183.254661 -306.909851) (xy 183.268406 -306.861055) (xy 183.288706 -306.814603)
			(xy 183.31518 -306.771371) (xy 183.347327 -306.732173) (xy 183.365648 -306.714652) (xy 183.374538 -306.706524)
			(xy 183.38292 -306.68468) (xy 183.373268 -306.58054) (xy 183.361076 -306.560728) (xy 183.350916 -306.554378)
			(xy 183.324791 -306.537298) (xy 183.276669 -306.497544) (xy 183.233913 -306.452067) (xy 183.197199 -306.401587)
			(xy 183.167108 -306.3469) (xy 183.144114 -306.28887) (xy 183.128581 -306.228414) (xy 183.120754 -306.166488)
			(xy 183.120284 -306.135278) (xy 183.120773 -306.104115) (xy 183.128585 -306.042281) (xy 183.144085 -305.981913)
			(xy 183.167028 -305.923965) (xy 183.197054 -305.869348) (xy 183.233688 -305.818926) (xy 183.276353 -305.773492)
			(xy 183.324375 -305.733764) (xy 183.376999 -305.700369) (xy 183.433393 -305.673832) (xy 183.492668 -305.654572)
			(xy 183.553889 -305.642893) (xy 183.616092 -305.63898) (xy 183.678295 -305.642893) (xy 183.739516 -305.654572)
			(xy 183.798791 -305.673832) (xy 183.855185 -305.700369) (xy 183.907809 -305.733764) (xy 183.955831 -305.773492)
			(xy 183.998496 -305.818926) (xy 184.03513 -305.869348) (xy 184.065156 -305.923965) (xy 184.088099 -305.981913)
			(xy 184.103599 -306.042281) (xy 184.111411 -306.104115) (xy 184.1119 -306.135278) (xy 184.111461 -306.166488)
			(xy 184.103632 -306.228416) (xy 184.088096 -306.288873) (xy 184.065097 -306.346902) (xy 184.034999 -306.401588)
			(xy 183.998279 -306.452065) (xy 183.955515 -306.497536) (xy 183.907384 -306.537283) (xy 183.881268 -306.554378)
			(xy 183.871108 -306.560728) (xy 183.858916 -306.58054) (xy 183.849264 -306.68468) (xy 183.857646 -306.706524)
			(xy 183.866536 -306.714652) (xy 183.884869 -306.732162) (xy 183.917013 -306.771365) (xy 183.943486 -306.8146)
			(xy 183.96379 -306.861053) (xy 183.977541 -306.909849) (xy 183.984481 -306.960068) (xy 183.9849 -306.985416)
			(xy 183.984503 -307.010734) (xy 183.977573 -307.060894) (xy 183.963847 -307.109635) (xy 183.943582 -307.156039)
			(xy 183.91716 -307.199235) (xy 183.885076 -307.23841) (xy 183.86679 -307.255926) (xy 183.8579 -307.264308)
			(xy 183.849518 -307.285898) (xy 183.858916 -307.390038) (xy 183.871108 -307.40985) (xy 183.881268 -307.416454)
			(xy 183.907391 -307.433513) (xy 183.955509 -307.473231) (xy 183.998263 -307.518672) (xy 184.034976 -307.56912)
			(xy 184.065068 -307.623776) (xy 184.088064 -307.681777) (xy 184.103599 -307.742204) (xy 184.111429 -307.804104)
			(xy 184.1119 -307.8353) (xy 184.1114 -307.866509) (xy 184.103581 -307.928434) (xy 184.088054 -307.988889)
			(xy 184.065064 -308.046918) (xy 184.034975 -308.101604) (xy 183.998262 -308.152082) (xy 183.955505 -308.197555)
			(xy 183.907381 -308.237304) (xy 183.881268 -308.2544) (xy 183.871108 -308.26075) (xy 183.858916 -308.280562)
			(xy 183.849264 -308.384702) (xy 183.857646 -308.406546) (xy 183.866536 -308.414674) (xy 183.884831 -308.432222)
			(xy 183.916979 -308.471417) (xy 183.943457 -308.514644) (xy 183.963767 -308.561089) (xy 183.977526 -308.609878)
			(xy 183.984476 -308.660092) (xy 183.9849 -308.685438) (xy 183.98445 -308.710754) (xy 183.977531 -308.760912)
			(xy 183.963816 -308.809652) (xy 183.94356 -308.856056) (xy 183.917147 -308.899253) (xy 183.885072 -308.93843)
			(xy 183.86679 -308.955948) (xy 183.8579 -308.96433) (xy 183.849518 -308.98592) (xy 183.858916 -309.09006)
			(xy 183.871108 -309.109872) (xy 183.881268 -309.116476) (xy 183.9074 -309.133523) (xy 183.955526 -309.173236)
			(xy 183.998286 -309.218676) (xy 184.035005 -309.269123) (xy 184.065102 -309.32378) (xy 184.088101 -309.381782)
			(xy 184.103639 -309.442212) (xy 184.111468 -309.504114) (xy 184.111467 -309.56651) (xy 184.103634 -309.628411)
			(xy 184.088094 -309.688841) (xy 184.065092 -309.746842) (xy 184.034992 -309.801497) (xy 183.998271 -309.851942)
			(xy 183.955508 -309.89738) (xy 183.907381 -309.937091) (xy 183.881268 -309.954168) (xy 183.871108 -309.960772)
			(xy 183.858916 -309.980584) (xy 183.849518 -310.084724) (xy 183.8579 -310.106314) (xy 183.86679 -310.114696)
			(xy 183.88509 -310.132197) (xy 183.917165 -310.171378) (xy 183.943579 -310.214579) (xy 183.963837 -310.260986)
			(xy 183.977557 -310.309728) (xy 183.984482 -310.359888) (xy 183.9849 -310.385206) (xy 183.984472 -310.410554)
			(xy 183.977539 -310.460773) (xy 183.963791 -310.509569) (xy 183.943487 -310.556021) (xy 183.91701 -310.599253)
			(xy 183.884859 -310.63845) (xy 183.866536 -310.65597) (xy 183.857646 -310.664098) (xy 183.849264 -310.685942)
			(xy 183.858916 -310.790082) (xy 183.871108 -310.809894) (xy 183.881268 -310.816244) (xy 183.907354 -310.833382)
			(xy 183.955477 -310.873127) (xy 183.998235 -310.918595) (xy 184.034952 -310.969067) (xy 184.065049 -311.023746)
			(xy 184.088049 -311.081768) (xy 184.10359 -311.142216) (xy 184.111425 -311.204137) (xy 184.1119 -311.235344)
			(xy 184.111411 -311.266507) (xy 184.103599 -311.328341) (xy 184.088099 -311.388709) (xy 184.065156 -311.446657)
			(xy 184.03513 -311.501274) (xy 183.998496 -311.551696) (xy 183.955831 -311.59713) (xy 183.907809 -311.636858)
			(xy 183.855185 -311.670253) (xy 183.798791 -311.69679) (xy 183.739516 -311.71605) (xy 183.678295 -311.727729)
			(xy 183.616092 -311.731642) (xy 183.553889 -311.727729) (xy 183.492668 -311.71605) (xy 183.433393 -311.69679)
			(xy 183.376999 -311.670253) (xy 183.324375 -311.636858) (xy 183.276353 -311.59713) (xy 183.233688 -311.551696)
			(xy 183.197054 -311.501274) (xy 183.167028 -311.446657) (xy 183.144085 -311.388709) (xy 183.128585 -311.328341)
			(xy 183.120773 -311.266507) (xy 183.120284 -311.235344) (xy 179.884832 -311.235344) (xy 179.884408 -311.260661)
			(xy 179.877487 -311.310821) (xy 179.863767 -311.359562) (xy 179.843508 -311.405967) (xy 179.817088 -311.449163)
			(xy 179.785007 -311.488338) (xy 179.766722 -311.505854) (xy 179.757832 -311.514236) (xy 179.74945 -311.535826)
			(xy 179.758848 -311.639966) (xy 179.77104 -311.659778) (xy 179.7812 -311.666382) (xy 179.807297 -311.683478)
			(xy 179.855414 -311.723192) (xy 179.898168 -311.768629) (xy 179.934882 -311.819071) (xy 179.964978 -311.873721)
			(xy 179.987978 -311.931716) (xy 180.003519 -311.992139) (xy 180.011357 -312.054034) (xy 180.011832 -312.085228)
			(xy 181.862491 -312.085228) (xy 181.866426 -312.031457) (xy 181.878149 -311.978833) (xy 181.897409 -311.928476)
			(xy 181.923795 -311.881459) (xy 181.956747 -311.838786) (xy 181.99556 -311.801365) (xy 182.039408 -311.769995)
			(xy 182.087356 -311.745343) (xy 182.138383 -311.727935) (xy 182.191401 -311.718142) (xy 182.24528 -311.716173)
			(xy 182.298871 -311.72207) (xy 182.351032 -311.735706) (xy 182.400652 -311.756793) (xy 182.446673 -311.784879)
			(xy 182.488115 -311.819367) (xy 182.524093 -311.859521) (xy 182.553841 -311.904485) (xy 182.576726 -311.953302)
			(xy 182.592258 -312.004931) (xy 182.600108 -312.058271) (xy 182.6006 -312.085228) (xy 182.600108 -312.112185)
			(xy 182.592258 -312.165525) (xy 182.576726 -312.217154) (xy 182.553841 -312.265971) (xy 182.524093 -312.310935)
			(xy 182.488115 -312.351089) (xy 182.446673 -312.385577) (xy 182.400652 -312.413663) (xy 182.351032 -312.43475)
			(xy 182.298871 -312.448386) (xy 182.24528 -312.454283) (xy 182.191401 -312.452314) (xy 182.138383 -312.442521)
			(xy 182.087356 -312.425113) (xy 182.039408 -312.400461) (xy 181.99556 -312.369091) (xy 181.956747 -312.33167)
			(xy 181.923795 -312.288997) (xy 181.897409 -312.24198) (xy 181.878149 -312.191623) (xy 181.866426 -312.138999)
			(xy 181.862491 -312.085228) (xy 180.011832 -312.085228) (xy 180.011343 -312.116391) (xy 180.003531 -312.178225)
			(xy 179.988031 -312.238593) (xy 179.965088 -312.296541) (xy 179.935062 -312.351158) (xy 179.898428 -312.40158)
			(xy 179.855763 -312.447014) (xy 179.807741 -312.486742) (xy 179.755117 -312.520137) (xy 179.698723 -312.546674)
			(xy 179.639448 -312.565934) (xy 179.578227 -312.577613) (xy 179.516024 -312.581526) (xy 179.453821 -312.577613)
			(xy 179.3926 -312.565934) (xy 179.333325 -312.546674) (xy 179.276931 -312.520137) (xy 179.224307 -312.486742)
			(xy 179.176285 -312.447014) (xy 179.13362 -312.40158) (xy 179.096986 -312.351158) (xy 179.06696 -312.296541)
			(xy 179.044017 -312.238593) (xy 179.028517 -312.178225) (xy 179.020705 -312.116391) (xy 179.020216 -312.085228)
			(xy 175.056546 -312.085228) (xy 175.056054 -312.112185) (xy 175.048204 -312.165525) (xy 175.032672 -312.217154)
			(xy 175.009787 -312.265971) (xy 174.980039 -312.310935) (xy 174.944061 -312.351089) (xy 174.902619 -312.385577)
			(xy 174.856598 -312.413663) (xy 174.806978 -312.43475) (xy 174.754817 -312.448386) (xy 174.701226 -312.454283)
			(xy 174.647347 -312.452314) (xy 174.594329 -312.442521) (xy 174.543302 -312.425113) (xy 174.495354 -312.400461)
			(xy 174.451506 -312.369091) (xy 174.412693 -312.33167) (xy 174.379741 -312.288997) (xy 174.353355 -312.24198)
			(xy 174.334095 -312.191623) (xy 174.322372 -312.138999) (xy 174.318437 -312.085228) (xy 172.467778 -312.085228)
			(xy 172.467289 -312.116391) (xy 172.459477 -312.178225) (xy 172.443977 -312.238593) (xy 172.421034 -312.296541)
			(xy 172.391008 -312.351158) (xy 172.354374 -312.40158) (xy 172.311709 -312.447014) (xy 172.263687 -312.486742)
			(xy 172.211063 -312.520137) (xy 172.154669 -312.546674) (xy 172.095394 -312.565934) (xy 172.034173 -312.577613)
			(xy 171.97197 -312.581526) (xy 171.909767 -312.577613) (xy 171.848546 -312.565934) (xy 171.789271 -312.546674)
			(xy 171.732877 -312.520137) (xy 171.680253 -312.486742) (xy 171.632231 -312.447014) (xy 171.589566 -312.40158)
			(xy 171.552932 -312.351158) (xy 171.522906 -312.296541) (xy 171.499963 -312.238593) (xy 171.484463 -312.178225)
			(xy 171.476651 -312.116391) (xy 171.476162 -312.085228) (xy 167.512492 -312.085228) (xy 167.512 -312.112185)
			(xy 167.50415 -312.165525) (xy 167.488618 -312.217154) (xy 167.465733 -312.265971) (xy 167.435985 -312.310935)
			(xy 167.400007 -312.351089) (xy 167.358565 -312.385577) (xy 167.312544 -312.413663) (xy 167.262924 -312.43475)
			(xy 167.210763 -312.448386) (xy 167.157172 -312.454283) (xy 167.103293 -312.452314) (xy 167.050275 -312.442521)
			(xy 166.999248 -312.425113) (xy 166.9513 -312.400461) (xy 166.907452 -312.369091) (xy 166.868639 -312.33167)
			(xy 166.835687 -312.288997) (xy 166.809301 -312.24198) (xy 166.790041 -312.191623) (xy 166.778318 -312.138999)
			(xy 166.774383 -312.085228) (xy 149.030578 -312.085228) (xy 149.050393 -312.115178) (xy 149.074065 -312.165675)
			(xy 149.090133 -312.219082) (xy 149.098253 -312.274258) (xy 149.098762 -312.302144) (xy 149.098253 -312.33003)
			(xy 149.090133 -312.385206) (xy 149.074065 -312.438613) (xy 149.050393 -312.48911) (xy 149.01962 -312.535623)
			(xy 148.982403 -312.57716) (xy 148.939535 -312.612835) (xy 148.891929 -312.641889) (xy 148.8406 -312.663701)
			(xy 148.786643 -312.677807) (xy 148.731206 -312.683907) (xy 148.675472 -312.68187) (xy 148.620629 -312.67174)
			(xy 148.567845 -312.653733) (xy 148.518245 -312.628232) (xy 148.472887 -312.595781) (xy 148.432738 -312.557072)
			(xy 148.398652 -312.512929) (xy 148.371356 -312.464294) (xy 148.351433 -312.412203) (xy 148.339307 -312.357766)
			(xy 148.335236 -312.302144) (xy 146.347164 -312.302144) (xy 146.354806 -312.362639) (xy 146.355308 -312.3946)
			(xy 146.354806 -312.426561) (xy 146.346795 -312.489979) (xy 146.330898 -312.551893) (xy 146.307366 -312.611326)
			(xy 146.276572 -312.667341) (xy 146.238999 -312.719056) (xy 146.195242 -312.765653) (xy 146.145989 -312.806398)
			(xy 146.092018 -312.840649) (xy 146.034179 -312.867866) (xy 145.973386 -312.887619) (xy 145.910596 -312.899597)
			(xy 145.8468 -312.903611) (xy 145.783004 -312.899597) (xy 145.720214 -312.887619) (xy 145.659421 -312.867866)
			(xy 145.601582 -312.840649) (xy 145.547611 -312.806398) (xy 145.498358 -312.765653) (xy 145.454601 -312.719056)
			(xy 145.417028 -312.667341) (xy 145.386234 -312.611326) (xy 145.362702 -312.551893) (xy 145.346805 -312.489979)
			(xy 145.338794 -312.426561) (xy 143.741226 -312.426561) (xy 143.770471 -312.471323) (xy 143.798179 -312.527998)
			(xy 143.818663 -312.587665) (xy 143.83161 -312.649408) (xy 143.83682 -312.712278) (xy 143.834213 -312.77531)
			(xy 143.823829 -312.837535) (xy 143.805828 -312.897998) (xy 143.789437 -312.935366) (xy 165.442915 -312.935366)
			(xy 165.44685 -312.881595) (xy 165.458573 -312.828971) (xy 165.477833 -312.778614) (xy 165.504219 -312.731597)
			(xy 165.537171 -312.688924) (xy 165.575984 -312.651503) (xy 165.619832 -312.620133) (xy 165.66778 -312.595481)
			(xy 165.718807 -312.578073) (xy 165.771825 -312.56828) (xy 165.825704 -312.566311) (xy 165.879295 -312.572208)
			(xy 165.931456 -312.585844) (xy 165.981076 -312.606931) (xy 166.027097 -312.635017) (xy 166.068539 -312.669505)
			(xy 166.104517 -312.709659) (xy 166.134265 -312.754623) (xy 166.15715 -312.80344) (xy 166.172682 -312.855069)
			(xy 166.180532 -312.908409) (xy 166.181024 -312.935366) (xy 172.986969 -312.935366) (xy 172.990904 -312.881595)
			(xy 173.002627 -312.828971) (xy 173.021887 -312.778614) (xy 173.048273 -312.731597) (xy 173.081225 -312.688924)
			(xy 173.120038 -312.651503) (xy 173.163886 -312.620133) (xy 173.211834 -312.595481) (xy 173.262861 -312.578073)
			(xy 173.315879 -312.56828) (xy 173.369758 -312.566311) (xy 173.423349 -312.572208) (xy 173.47551 -312.585844)
			(xy 173.52513 -312.606931) (xy 173.571151 -312.635017) (xy 173.612593 -312.669505) (xy 173.648571 -312.709659)
			(xy 173.678319 -312.754623) (xy 173.701204 -312.80344) (xy 173.716736 -312.855069) (xy 173.724586 -312.908409)
			(xy 173.725078 -312.935366) (xy 173.724586 -312.962323) (xy 173.716736 -313.015663) (xy 173.701204 -313.067292)
			(xy 173.678319 -313.116109) (xy 173.648571 -313.161073) (xy 173.612593 -313.201227) (xy 173.571151 -313.235715)
			(xy 173.52513 -313.263801) (xy 173.47551 -313.284888) (xy 173.423349 -313.298524) (xy 173.369758 -313.304421)
			(xy 173.315879 -313.302452) (xy 173.262861 -313.292659) (xy 173.211834 -313.275251) (xy 173.163886 -313.250599)
			(xy 173.120038 -313.219229) (xy 173.081225 -313.181808) (xy 173.048273 -313.139135) (xy 173.021887 -313.092118)
			(xy 173.002627 -313.041761) (xy 172.990904 -312.989137) (xy 172.986969 -312.935366) (xy 166.181024 -312.935366)
			(xy 166.180532 -312.962323) (xy 166.172682 -313.015663) (xy 166.15715 -313.067292) (xy 166.134265 -313.116109)
			(xy 166.104517 -313.161073) (xy 166.068539 -313.201227) (xy 166.027097 -313.235715) (xy 165.981076 -313.263801)
			(xy 165.931456 -313.284888) (xy 165.879295 -313.298524) (xy 165.825704 -313.304421) (xy 165.771825 -313.302452)
			(xy 165.718807 -313.292659) (xy 165.66778 -313.275251) (xy 165.619832 -313.250599) (xy 165.575984 -313.219229)
			(xy 165.537171 -313.181808) (xy 165.504219 -313.139135) (xy 165.477833 -313.092118) (xy 165.458573 -313.041761)
			(xy 165.44685 -312.989137) (xy 165.442915 -312.935366) (xy 143.789437 -312.935366) (xy 143.780487 -312.95577)
			(xy 143.748194 -313.009964) (xy 143.709445 -313.059747) (xy 143.664836 -313.104355) (xy 143.615052 -313.143102)
			(xy 143.560858 -313.175393) (xy 143.503085 -313.200733) (xy 143.442622 -313.218732) (xy 143.380396 -313.229114)
			(xy 143.317364 -313.231719) (xy 143.254494 -313.226508) (xy 143.192752 -313.21356) (xy 143.133085 -313.193074)
			(xy 143.076411 -313.165364) (xy 143.023599 -313.130858) (xy 142.975461 -313.090083) (xy 142.932737 -313.043668)
			(xy 142.896082 -312.992324) (xy 142.866059 -312.93684) (xy 142.84313 -312.878069) (xy 142.827647 -312.816912)
			(xy 142.819848 -312.754311) (xy 142.819374 -312.722768) (xy 142.819539 -312.706401) (xy 142.821699 -312.673736)
			(xy 142.823692 -312.65749) (xy 142.825216 -312.645044) (xy 142.81658 -312.621676) (xy 142.735554 -312.548778)
			(xy 142.711678 -312.542682) (xy 142.699232 -312.54573) (xy 142.67032 -312.552145) (xy 142.611496 -312.559017)
			(xy 142.581884 -312.559446) (xy 142.551154 -312.558959) (xy 142.490143 -312.551549) (xy 142.430469 -312.53684)
			(xy 142.373003 -312.515046) (xy 142.318583 -312.486484) (xy 142.268003 -312.451572) (xy 142.221999 -312.410817)
			(xy 142.181242 -312.364815) (xy 142.146327 -312.314236) (xy 142.117763 -312.259817) (xy 142.095966 -312.202352)
			(xy 142.081255 -312.142679) (xy 142.073842 -312.081668) (xy 142.073376 -312.050938) (xy 142.073376 -312.048906)
			(xy 142.073376 -312.037984) (xy 142.06474 -312.018426) (xy 141.99235 -311.952894) (xy 141.97203 -311.94629)
			(xy 141.961108 -311.94756) (xy 141.947685 -311.948881) (xy 141.920747 -311.950278) (xy 141.90726 -311.950354)
			(xy 141.875721 -311.94979) (xy 141.813129 -311.941983) (xy 141.751983 -311.926493) (xy 141.693223 -311.90356)
			(xy 141.63775 -311.873534) (xy 141.586418 -311.836877) (xy 141.540014 -311.794152) (xy 141.499251 -311.746015)
			(xy 141.464755 -311.693207) (xy 141.437057 -311.636536) (xy 141.41658 -311.576875) (xy 141.403641 -311.515139)
			(xy 141.398437 -311.452277) (xy 128.59639 -311.452277) (xy 128.59639 -314.682378) (xy 142.917418 -314.682378)
			(xy 142.917838 -314.651847) (xy 142.925153 -314.591226) (xy 142.939675 -314.531916) (xy 142.961194 -314.474773)
			(xy 142.989402 -314.420617) (xy 143.023892 -314.37023) (xy 143.064168 -314.324335) (xy 143.109651 -314.283593)
			(xy 143.159684 -314.248592) (xy 143.186404 -314.233814) (xy 143.196056 -314.228734) (xy 143.209264 -314.211716)
			(xy 143.232886 -314.117736) (xy 143.22933 -314.096908) (xy 143.223234 -314.087764) (xy 143.207009 -314.062652)
			(xy 143.179919 -314.009351) (xy 143.159267 -313.953241) (xy 143.145337 -313.895096) (xy 143.138323 -313.835719)
			(xy 143.13789 -313.805824) (xy 143.138392 -313.773863) (xy 143.146403 -313.710445) (xy 143.1623 -313.648531)
			(xy 143.185832 -313.589098) (xy 143.216626 -313.533083) (xy 143.254199 -313.481368) (xy 143.297956 -313.434771)
			(xy 143.347209 -313.394026) (xy 143.40118 -313.359775) (xy 143.459019 -313.332558) (xy 143.519812 -313.312805)
			(xy 143.582602 -313.300827) (xy 143.646398 -313.296814) (xy 143.710194 -313.300827) (xy 143.772984 -313.312805)
			(xy 143.833777 -313.332558) (xy 143.891616 -313.359775) (xy 143.945587 -313.394026) (xy 143.99484 -313.434771)
			(xy 144.038597 -313.481368) (xy 144.07617 -313.533083) (xy 144.106964 -313.589098) (xy 144.130496 -313.648531)
			(xy 144.146393 -313.710445) (xy 144.154404 -313.773863) (xy 144.154906 -313.805824) (xy 144.154475 -313.836354)
			(xy 144.14716 -313.896975) (xy 144.132639 -313.956284) (xy 144.11112 -314.013427) (xy 144.082914 -314.067582)
			(xy 144.048425 -314.117969) (xy 144.008151 -314.163864) (xy 143.962671 -314.204607) (xy 143.912639 -314.239609)
			(xy 143.88592 -314.254388) (xy 143.876268 -314.259468) (xy 143.86306 -314.276486) (xy 143.839438 -314.370466)
			(xy 143.842994 -314.391294) (xy 143.84909 -314.400438) (xy 143.865319 -314.425548) (xy 143.888444 -314.47105)
			(xy 146.640802 -314.47105) (xy 146.644873 -314.415428) (xy 146.656999 -314.360991) (xy 146.676922 -314.3089)
			(xy 146.704218 -314.260265) (xy 146.738304 -314.216122) (xy 146.778453 -314.177413) (xy 146.823811 -314.144962)
			(xy 146.873411 -314.119461) (xy 146.926195 -314.101454) (xy 146.981038 -314.091324) (xy 147.036772 -314.089287)
			(xy 147.092209 -314.095387) (xy 147.146166 -314.109493) (xy 147.197495 -314.131305) (xy 147.245101 -314.160359)
			(xy 147.287969 -314.196034) (xy 147.325186 -314.237571) (xy 147.355959 -314.284084) (xy 147.379631 -314.334581)
			(xy 147.395699 -314.387988) (xy 147.403819 -314.443164) (xy 147.404328 -314.47105) (xy 147.403819 -314.498936)
			(xy 147.395699 -314.554112) (xy 147.379631 -314.607519) (xy 147.355959 -314.658016) (xy 147.325186 -314.704529)
			(xy 147.287969 -314.746066) (xy 147.245101 -314.781741) (xy 147.197495 -314.810795) (xy 147.146166 -314.832607)
			(xy 147.092209 -314.846713) (xy 147.036772 -314.852813) (xy 146.981038 -314.850776) (xy 146.926195 -314.840646)
			(xy 146.873411 -314.822639) (xy 146.823811 -314.797138) (xy 146.778453 -314.764687) (xy 146.738304 -314.725978)
			(xy 146.704218 -314.681835) (xy 146.676922 -314.6332) (xy 146.656999 -314.581109) (xy 146.644873 -314.526672)
			(xy 146.640802 -314.47105) (xy 143.888444 -314.47105) (xy 143.892408 -314.47885) (xy 143.913059 -314.53496)
			(xy 143.926987 -314.593106) (xy 143.934002 -314.652483) (xy 143.934434 -314.682378) (xy 143.933932 -314.714339)
			(xy 143.925921 -314.777757) (xy 143.910024 -314.839671) (xy 143.886492 -314.899104) (xy 143.855698 -314.955119)
			(xy 143.818125 -315.006834) (xy 143.774368 -315.053431) (xy 143.725115 -315.094176) (xy 143.671144 -315.128427)
			(xy 143.613305 -315.155644) (xy 143.552512 -315.175397) (xy 143.489722 -315.187375) (xy 143.425926 -315.191389)
			(xy 143.36213 -315.187375) (xy 143.29934 -315.175397) (xy 143.238547 -315.155644) (xy 143.180708 -315.128427)
			(xy 143.126737 -315.094176) (xy 143.077484 -315.053431) (xy 143.033727 -315.006834) (xy 142.996154 -314.955119)
			(xy 142.96536 -314.899104) (xy 142.941828 -314.839671) (xy 142.925931 -314.777757) (xy 142.91792 -314.714339)
			(xy 142.917418 -314.682378) (xy 128.59639 -314.682378) (xy 128.59639 -315.65596) (xy 142.259302 -315.65596)
			(xy 142.263373 -315.600338) (xy 142.275499 -315.545901) (xy 142.295422 -315.49381) (xy 142.322718 -315.445175)
			(xy 142.356804 -315.401032) (xy 142.396953 -315.362323) (xy 142.442311 -315.329872) (xy 142.491911 -315.304371)
			(xy 142.544695 -315.286364) (xy 142.599538 -315.276234) (xy 142.655272 -315.274197) (xy 142.710709 -315.280297)
			(xy 142.764666 -315.294403) (xy 142.815995 -315.316215) (xy 142.863601 -315.345269) (xy 142.906469 -315.380944)
			(xy 142.943686 -315.422481) (xy 142.974459 -315.468994) (xy 142.998131 -315.519491) (xy 143.014199 -315.572898)
			(xy 143.022319 -315.628074) (xy 143.022828 -315.65596) (xy 143.022319 -315.683846) (xy 143.014199 -315.739022)
			(xy 142.998131 -315.792429) (xy 142.974459 -315.842926) (xy 142.943686 -315.889439) (xy 142.906469 -315.930976)
			(xy 142.863601 -315.966651) (xy 142.815995 -315.995705) (xy 142.764666 -316.017517) (xy 142.710709 -316.031623)
			(xy 142.655272 -316.037723) (xy 142.599538 -316.035686) (xy 142.544695 -316.025556) (xy 142.491911 -316.007549)
			(xy 142.442311 -315.982048) (xy 142.396953 -315.949597) (xy 142.356804 -315.910888) (xy 142.322718 -315.866745)
			(xy 142.295422 -315.81811) (xy 142.275499 -315.766019) (xy 142.263373 -315.711582) (xy 142.259302 -315.65596)
			(xy 128.59639 -315.65596) (xy 128.59639 -316.08395) (xy 146.448526 -316.08395) (xy 146.449288 -316.059566)
			(xy 146.449288 -315.578998) (xy 146.449755 -315.568994) (xy 146.457469 -315.55053) (xy 146.464274 -315.543184)
			(xy 147.028662 -314.978796) (xy 147.036071 -314.972115) (xy 147.05451 -314.964542) (xy 147.064476 -314.964064)
			(xy 149.483064 -314.964064) (xy 149.512528 -314.936632) (xy 149.513798 -314.916566) (xy 149.51851 -314.853063)
			(xy 149.534997 -314.726782) (xy 149.559359 -314.601781) (xy 149.591499 -314.478551) (xy 149.631292 -314.357575)
			(xy 149.678581 -314.239328) (xy 149.733181 -314.124274) (xy 149.794877 -314.012863) (xy 149.863428 -313.905535)
			(xy 149.938564 -313.802708) (xy 150.019991 -313.704788) (xy 150.107388 -313.612158) (xy 150.200414 -313.525182)
			(xy 150.298703 -313.444201) (xy 150.40187 -313.369533) (xy 150.509509 -313.301471) (xy 150.621198 -313.240281)
			(xy 150.736499 -313.186204) (xy 150.85496 -313.139453) (xy 150.976116 -313.10021) (xy 151.099491 -313.06863)
			(xy 151.224601 -313.044836) (xy 151.350955 -313.028922) (xy 151.478058 -313.020951) (xy 151.541734 -313.020456)
			(xy 151.605592 -313.020961) (xy 151.733056 -313.028982) (xy 151.859765 -313.044991) (xy 151.985218 -313.068924)
			(xy 152.108922 -313.100687) (xy 152.230386 -313.140155) (xy 152.349133 -313.187171) (xy 152.464694 -313.241551)
			(xy 152.576612 -313.303079) (xy 152.66679 -313.360308) (xy 169.276283 -313.360308) (xy 169.280218 -313.306537)
			(xy 169.291941 -313.253913) (xy 169.311201 -313.203556) (xy 169.337587 -313.156539) (xy 169.370539 -313.113866)
			(xy 169.409352 -313.076445) (xy 169.4532 -313.045075) (xy 169.501148 -313.020423) (xy 169.552175 -313.003015)
			(xy 169.605193 -312.993222) (xy 169.659072 -312.991253) (xy 169.712663 -312.99715) (xy 169.764824 -313.010786)
			(xy 169.814444 -313.031873) (xy 169.860465 -313.059959) (xy 169.901907 -313.094447) (xy 169.937885 -313.134601)
			(xy 169.967633 -313.179565) (xy 169.990518 -313.228382) (xy 170.00605 -313.280011) (xy 170.0139 -313.333351)
			(xy 170.014392 -313.360308) (xy 170.0139 -313.387265) (xy 170.00605 -313.440605) (xy 169.990518 -313.492234)
			(xy 169.967633 -313.541051) (xy 169.937885 -313.586015) (xy 169.901907 -313.626169) (xy 169.860465 -313.660657)
			(xy 169.814444 -313.688743) (xy 169.764824 -313.70983) (xy 169.712663 -313.723466) (xy 169.659072 -313.729363)
			(xy 169.605193 -313.727394) (xy 169.552175 -313.717601) (xy 169.501148 -313.700193) (xy 169.4532 -313.675541)
			(xy 169.409352 -313.644171) (xy 169.370539 -313.60675) (xy 169.337587 -313.564077) (xy 169.311201 -313.51706)
			(xy 169.291941 -313.466703) (xy 169.280218 -313.414079) (xy 169.276283 -313.360308) (xy 152.66679 -313.360308)
			(xy 152.684446 -313.371513) (xy 152.78777 -313.446583) (xy 152.886177 -313.527993) (xy 152.979278 -313.61542)
			(xy 153.066706 -313.708521) (xy 153.148115 -313.806928) (xy 153.223186 -313.910252) (xy 153.29162 -314.018086)
			(xy 153.353148 -314.130004) (xy 153.391002 -314.210446) (xy 165.176215 -314.210446) (xy 165.18015 -314.156675)
			(xy 165.191873 -314.104051) (xy 165.211133 -314.053694) (xy 165.237519 -314.006677) (xy 165.270471 -313.964004)
			(xy 165.309284 -313.926583) (xy 165.353132 -313.895213) (xy 165.40108 -313.870561) (xy 165.452107 -313.853153)
			(xy 165.505125 -313.84336) (xy 165.559004 -313.841391) (xy 165.612595 -313.847288) (xy 165.664756 -313.860924)
			(xy 165.714376 -313.882011) (xy 165.760397 -313.910097) (xy 165.801839 -313.944585) (xy 165.837817 -313.984739)
			(xy 165.867565 -314.029703) (xy 165.89045 -314.07852) (xy 165.905982 -314.130149) (xy 165.913832 -314.183489)
			(xy 165.914324 -314.210446) (xy 165.913832 -314.237403) (xy 165.905982 -314.290743) (xy 165.89045 -314.342372)
			(xy 165.867565 -314.391189) (xy 165.837817 -314.436153) (xy 165.801839 -314.476307) (xy 165.760397 -314.510795)
			(xy 165.714376 -314.538881) (xy 165.664756 -314.559968) (xy 165.612595 -314.573604) (xy 165.559004 -314.579501)
			(xy 165.505125 -314.577532) (xy 165.452107 -314.567739) (xy 165.40108 -314.550331) (xy 165.353132 -314.525679)
			(xy 165.309284 -314.494309) (xy 165.270471 -314.456888) (xy 165.237519 -314.414215) (xy 165.211133 -314.367198)
			(xy 165.191873 -314.316841) (xy 165.18015 -314.264217) (xy 165.176215 -314.210446) (xy 153.391002 -314.210446)
			(xy 153.407528 -314.245565) (xy 153.454545 -314.364312) (xy 153.494012 -314.485776) (xy 153.525776 -314.60948)
			(xy 153.530719 -314.635388) (xy 166.774383 -314.635388) (xy 166.778318 -314.581617) (xy 166.790041 -314.528993)
			(xy 166.809301 -314.478636) (xy 166.835687 -314.431619) (xy 166.868639 -314.388946) (xy 166.907452 -314.351525)
			(xy 166.9513 -314.320155) (xy 166.999248 -314.295503) (xy 167.050275 -314.278095) (xy 167.103293 -314.268302)
			(xy 167.157172 -314.266333) (xy 167.210763 -314.27223) (xy 167.262924 -314.285866) (xy 167.312544 -314.306953)
			(xy 167.358565 -314.335039) (xy 167.400007 -314.369527) (xy 167.435985 -314.409681) (xy 167.465733 -314.454645)
			(xy 167.488618 -314.503462) (xy 167.50415 -314.555091) (xy 167.512 -314.608431) (xy 167.512492 -314.635388)
			(xy 171.476162 -314.635388) (xy 171.476691 -314.602668) (xy 171.485286 -314.537794) (xy 171.502339 -314.474615)
			(xy 171.527553 -314.414227) (xy 171.560491 -314.35768) (xy 171.600579 -314.305956) (xy 171.623482 -314.282582)
			(xy 171.630848 -314.27547) (xy 171.638722 -314.256674) (xy 171.638722 -314.163964) (xy 171.630848 -314.145168)
			(xy 171.623482 -314.138056) (xy 171.600602 -314.114661) (xy 171.560517 -314.062938) (xy 171.527579 -314.006395)
			(xy 171.50236 -313.946012) (xy 171.485298 -313.882838) (xy 171.476689 -313.817969) (xy 171.476162 -313.78525)
			(xy 171.476651 -313.754087) (xy 171.484463 -313.692253) (xy 171.499963 -313.631885) (xy 171.522906 -313.573937)
			(xy 171.552932 -313.51932) (xy 171.589566 -313.468898) (xy 171.632231 -313.423464) (xy 171.680253 -313.383736)
			(xy 171.732877 -313.350341) (xy 171.789271 -313.323804) (xy 171.848546 -313.304544) (xy 171.909767 -313.292865)
			(xy 171.97197 -313.288952) (xy 172.034173 -313.292865) (xy 172.095394 -313.304544) (xy 172.154669 -313.323804)
			(xy 172.211063 -313.350341) (xy 172.263687 -313.383736) (xy 172.311709 -313.423464) (xy 172.354374 -313.468898)
			(xy 172.391008 -313.51932) (xy 172.421034 -313.573937) (xy 172.443977 -313.631885) (xy 172.459477 -313.692253)
			(xy 172.467289 -313.754087) (xy 172.467778 -313.78525) (xy 175.57623 -313.78525) (xy 175.57677 -313.75255)
			(xy 175.585378 -313.687719) (xy 175.602436 -313.624583) (xy 175.62765 -313.564239) (xy 175.660581 -313.507735)
			(xy 175.700656 -313.456052) (xy 175.72355 -313.432698) (xy 175.730916 -313.425332) (xy 175.738536 -313.40679)
			(xy 175.738536 -313.313826) (xy 175.730916 -313.295284) (xy 175.72355 -313.287918) (xy 175.700642 -313.264575)
			(xy 175.660559 -313.212895) (xy 175.627624 -313.15639) (xy 175.602409 -313.096043) (xy 175.585353 -313.032903)
			(xy 175.576752 -312.968068) (xy 175.57623 -312.935366) (xy 175.576719 -312.904203) (xy 175.584531 -312.842369)
			(xy 175.600031 -312.782001) (xy 175.622974 -312.724053) (xy 175.653 -312.669436) (xy 175.689634 -312.619014)
			(xy 175.732299 -312.57358) (xy 175.780321 -312.533852) (xy 175.832945 -312.500457) (xy 175.889339 -312.47392)
			(xy 175.948614 -312.45466) (xy 176.009835 -312.442981) (xy 176.072038 -312.439068) (xy 176.134241 -312.442981)
			(xy 176.195462 -312.45466) (xy 176.254737 -312.47392) (xy 176.311131 -312.500457) (xy 176.363755 -312.533852)
			(xy 176.411777 -312.57358) (xy 176.454442 -312.619014) (xy 176.491076 -312.669436) (xy 176.521102 -312.724053)
			(xy 176.544045 -312.782001) (xy 176.559545 -312.842369) (xy 176.567357 -312.904203) (xy 176.567846 -312.935366)
			(xy 180.531023 -312.935366) (xy 180.534958 -312.881595) (xy 180.546681 -312.828971) (xy 180.565941 -312.778614)
			(xy 180.592327 -312.731597) (xy 180.625279 -312.688924) (xy 180.664092 -312.651503) (xy 180.70794 -312.620133)
			(xy 180.755888 -312.595481) (xy 180.806915 -312.578073) (xy 180.859933 -312.56828) (xy 180.913812 -312.566311)
			(xy 180.967403 -312.572208) (xy 181.019564 -312.585844) (xy 181.069184 -312.606931) (xy 181.115205 -312.635017)
			(xy 181.156647 -312.669505) (xy 181.192625 -312.709659) (xy 181.222373 -312.754623) (xy 181.245258 -312.80344)
			(xy 181.26079 -312.855069) (xy 181.26864 -312.908409) (xy 181.269132 -312.935366) (xy 181.26864 -312.962323)
			(xy 181.26079 -313.015663) (xy 181.245258 -313.067292) (xy 181.222373 -313.116109) (xy 181.192625 -313.161073)
			(xy 181.156647 -313.201227) (xy 181.115205 -313.235715) (xy 181.069184 -313.263801) (xy 181.019564 -313.284888)
			(xy 180.967403 -313.298524) (xy 180.913812 -313.304421) (xy 180.859933 -313.302452) (xy 180.806915 -313.292659)
			(xy 180.755888 -313.275251) (xy 180.70794 -313.250599) (xy 180.664092 -313.219229) (xy 180.625279 -313.181808)
			(xy 180.592327 -313.139135) (xy 180.565941 -313.092118) (xy 180.546681 -313.041761) (xy 180.534958 -312.989137)
			(xy 180.531023 -312.935366) (xy 176.567846 -312.935366) (xy 176.567323 -312.968067) (xy 176.558713 -313.032898)
			(xy 176.541652 -313.096035) (xy 176.516435 -313.156379) (xy 176.483501 -313.212883) (xy 176.443422 -313.264564)
			(xy 176.420526 -313.287918) (xy 176.41316 -313.295284) (xy 176.40554 -313.313826) (xy 176.40554 -313.360308)
			(xy 176.820337 -313.360308) (xy 176.824272 -313.306537) (xy 176.835995 -313.253913) (xy 176.855255 -313.203556)
			(xy 176.881641 -313.156539) (xy 176.914593 -313.113866) (xy 176.953406 -313.076445) (xy 176.997254 -313.045075)
			(xy 177.045202 -313.020423) (xy 177.096229 -313.003015) (xy 177.149247 -312.993222) (xy 177.203126 -312.991253)
			(xy 177.256717 -312.99715) (xy 177.308878 -313.010786) (xy 177.358498 -313.031873) (xy 177.404519 -313.059959)
			(xy 177.445961 -313.094447) (xy 177.481939 -313.134601) (xy 177.511687 -313.179565) (xy 177.534572 -313.228382)
			(xy 177.550104 -313.280011) (xy 177.557954 -313.333351) (xy 177.558446 -313.360308) (xy 177.557954 -313.387265)
			(xy 177.550104 -313.440605) (xy 177.534572 -313.492234) (xy 177.511687 -313.541051) (xy 177.481939 -313.586015)
			(xy 177.445961 -313.626169) (xy 177.404519 -313.660657) (xy 177.358498 -313.688743) (xy 177.308878 -313.70983)
			(xy 177.256717 -313.723466) (xy 177.203126 -313.729363) (xy 177.149247 -313.727394) (xy 177.096229 -313.717601)
			(xy 177.045202 -313.700193) (xy 176.997254 -313.675541) (xy 176.953406 -313.644171) (xy 176.914593 -313.60675)
			(xy 176.881641 -313.564077) (xy 176.855255 -313.51706) (xy 176.835995 -313.466703) (xy 176.824272 -313.414079)
			(xy 176.820337 -313.360308) (xy 176.40554 -313.360308) (xy 176.40554 -313.40679) (xy 176.41316 -313.425332)
			(xy 176.420526 -313.432698) (xy 176.443437 -313.456038) (xy 176.483521 -313.507718) (xy 176.516456 -313.564224)
			(xy 176.541671 -313.624572) (xy 176.558726 -313.687712) (xy 176.567325 -313.752548) (xy 176.567846 -313.78525)
			(xy 176.567357 -313.816413) (xy 176.559545 -313.878247) (xy 176.544045 -313.938615) (xy 176.521102 -313.996563)
			(xy 176.491076 -314.05118) (xy 176.454442 -314.101602) (xy 176.411777 -314.147036) (xy 176.363755 -314.186764)
			(xy 176.311131 -314.220159) (xy 176.254737 -314.246696) (xy 176.195462 -314.265956) (xy 176.134241 -314.277635)
			(xy 176.072038 -314.281548) (xy 176.009835 -314.277635) (xy 175.948614 -314.265956) (xy 175.889339 -314.246696)
			(xy 175.832945 -314.220159) (xy 175.780321 -314.186764) (xy 175.732299 -314.147036) (xy 175.689634 -314.101602)
			(xy 175.653 -314.05118) (xy 175.622974 -313.996563) (xy 175.600031 -313.938615) (xy 175.584531 -313.878247)
			(xy 175.576719 -313.816413) (xy 175.57623 -313.78525) (xy 172.467778 -313.78525) (xy 172.467262 -313.817971)
			(xy 172.458663 -313.882844) (xy 172.441606 -313.946023) (xy 172.41639 -314.006411) (xy 172.383451 -314.062958)
			(xy 172.343361 -314.114682) (xy 172.320458 -314.138056) (xy 172.313092 -314.145168) (xy 172.305218 -314.163964)
			(xy 172.305218 -314.210446) (xy 172.720269 -314.210446) (xy 172.724204 -314.156675) (xy 172.735927 -314.104051)
			(xy 172.755187 -314.053694) (xy 172.781573 -314.006677) (xy 172.814525 -313.964004) (xy 172.853338 -313.926583)
			(xy 172.897186 -313.895213) (xy 172.945134 -313.870561) (xy 172.996161 -313.853153) (xy 173.049179 -313.84336)
			(xy 173.103058 -313.841391) (xy 173.156649 -313.847288) (xy 173.20881 -313.860924) (xy 173.25843 -313.882011)
			(xy 173.304451 -313.910097) (xy 173.345893 -313.944585) (xy 173.381871 -313.984739) (xy 173.411619 -314.029703)
			(xy 173.434504 -314.07852) (xy 173.450036 -314.130149) (xy 173.457886 -314.183489) (xy 173.458378 -314.210446)
			(xy 173.457886 -314.237403) (xy 173.450036 -314.290743) (xy 173.434504 -314.342372) (xy 173.411619 -314.391189)
			(xy 173.381871 -314.436153) (xy 173.345893 -314.476307) (xy 173.304451 -314.510795) (xy 173.25843 -314.538881)
			(xy 173.20881 -314.559968) (xy 173.156649 -314.573604) (xy 173.103058 -314.579501) (xy 173.049179 -314.577532)
			(xy 172.996161 -314.567739) (xy 172.945134 -314.550331) (xy 172.897186 -314.525679) (xy 172.853338 -314.494309)
			(xy 172.814525 -314.456888) (xy 172.781573 -314.414215) (xy 172.755187 -314.367198) (xy 172.735927 -314.316841)
			(xy 172.724204 -314.264217) (xy 172.720269 -314.210446) (xy 172.305218 -314.210446) (xy 172.305218 -314.256674)
			(xy 172.313092 -314.27547) (xy 172.320458 -314.282582) (xy 172.343364 -314.305952) (xy 172.383445 -314.357681)
			(xy 172.416379 -314.41423) (xy 172.441593 -314.474618) (xy 172.45865 -314.537796) (xy 172.467254 -314.602668)
			(xy 172.467778 -314.635388) (xy 174.318437 -314.635388) (xy 174.322372 -314.581617) (xy 174.334095 -314.528993)
			(xy 174.353355 -314.478636) (xy 174.379741 -314.431619) (xy 174.412693 -314.388946) (xy 174.451506 -314.351525)
			(xy 174.495354 -314.320155) (xy 174.543302 -314.295503) (xy 174.594329 -314.278095) (xy 174.647347 -314.268302)
			(xy 174.701226 -314.266333) (xy 174.754817 -314.27223) (xy 174.806978 -314.285866) (xy 174.856598 -314.306953)
			(xy 174.902619 -314.335039) (xy 174.944061 -314.369527) (xy 174.980039 -314.409681) (xy 175.009787 -314.454645)
			(xy 175.032672 -314.503462) (xy 175.048204 -314.555091) (xy 175.056054 -314.608431) (xy 175.056546 -314.635388)
			(xy 179.020216 -314.635388) (xy 179.020758 -314.602668) (xy 179.029353 -314.537796) (xy 179.046404 -314.474617)
			(xy 179.071616 -314.41423) (xy 179.10455 -314.357682) (xy 179.144635 -314.305957) (xy 179.167536 -314.282582)
			(xy 179.174902 -314.27547) (xy 179.182776 -314.256674) (xy 179.182776 -314.163964) (xy 179.174902 -314.145168)
			(xy 179.167536 -314.138056) (xy 179.144647 -314.114669) (xy 179.104564 -314.062944) (xy 179.071629 -314.006398)
			(xy 179.046412 -313.946014) (xy 179.029351 -313.882839) (xy 179.020743 -313.817969) (xy 179.020216 -313.78525)
			(xy 179.020705 -313.754087) (xy 179.028517 -313.692253) (xy 179.044017 -313.631885) (xy 179.06696 -313.573937)
			(xy 179.096986 -313.51932) (xy 179.13362 -313.468898) (xy 179.176285 -313.423464) (xy 179.224307 -313.383736)
			(xy 179.276931 -313.350341) (xy 179.333325 -313.323804) (xy 179.3926 -313.304544) (xy 179.453821 -313.292865)
			(xy 179.516024 -313.288952) (xy 179.578227 -313.292865) (xy 179.639448 -313.304544) (xy 179.698723 -313.323804)
			(xy 179.755117 -313.350341) (xy 179.807741 -313.383736) (xy 179.855763 -313.423464) (xy 179.898428 -313.468898)
			(xy 179.935062 -313.51932) (xy 179.965088 -313.573937) (xy 179.988031 -313.631885) (xy 180.003531 -313.692253)
			(xy 180.011343 -313.754087) (xy 180.011832 -313.78525) (xy 183.120284 -313.78525) (xy 183.120808 -313.752549)
			(xy 183.129417 -313.687717) (xy 183.146478 -313.62458) (xy 183.171694 -313.564236) (xy 183.204628 -313.507732)
			(xy 183.244708 -313.456051) (xy 183.267604 -313.432698) (xy 183.27497 -313.425332) (xy 183.28259 -313.40679)
			(xy 183.28259 -313.313826) (xy 183.27497 -313.295284) (xy 183.267604 -313.287918) (xy 183.244706 -313.264566)
			(xy 183.20462 -313.212888) (xy 183.171682 -313.156386) (xy 183.146465 -313.09604) (xy 183.129408 -313.032901)
			(xy 183.120806 -312.968067) (xy 183.120284 -312.935366) (xy 183.120773 -312.904203) (xy 183.128585 -312.842369)
			(xy 183.144085 -312.782001) (xy 183.167028 -312.724053) (xy 183.197054 -312.669436) (xy 183.233688 -312.619014)
			(xy 183.276353 -312.57358) (xy 183.324375 -312.533852) (xy 183.376999 -312.500457) (xy 183.433393 -312.47392)
			(xy 183.492668 -312.45466) (xy 183.553889 -312.442981) (xy 183.616092 -312.439068) (xy 183.678295 -312.442981)
			(xy 183.739516 -312.45466) (xy 183.798791 -312.47392) (xy 183.855185 -312.500457) (xy 183.907809 -312.533852)
			(xy 183.955831 -312.57358) (xy 183.998496 -312.619014) (xy 184.03513 -312.669436) (xy 184.065156 -312.724053)
			(xy 184.088099 -312.782001) (xy 184.103599 -312.842369) (xy 184.111411 -312.904203) (xy 184.1119 -312.935366)
			(xy 184.111391 -312.968067) (xy 184.10278 -313.0329) (xy 184.085717 -313.096037) (xy 184.060497 -313.156382)
			(xy 184.02756 -313.212885) (xy 183.987477 -313.264565) (xy 183.96458 -313.287918) (xy 183.957214 -313.295284)
			(xy 183.949594 -313.313826) (xy 183.949594 -313.360308) (xy 184.364391 -313.360308) (xy 184.368326 -313.306537)
			(xy 184.380049 -313.253913) (xy 184.399309 -313.203556) (xy 184.425695 -313.156539) (xy 184.458647 -313.113866)
			(xy 184.49746 -313.076445) (xy 184.541308 -313.045075) (xy 184.589256 -313.020423) (xy 184.640283 -313.003015)
			(xy 184.693301 -312.993222) (xy 184.74718 -312.991253) (xy 184.800771 -312.99715) (xy 184.852932 -313.010786)
			(xy 184.902552 -313.031873) (xy 184.948573 -313.059959) (xy 184.990015 -313.094447) (xy 185.025993 -313.134601)
			(xy 185.055741 -313.179565) (xy 185.078626 -313.228382) (xy 185.094158 -313.280011) (xy 185.102008 -313.333351)
			(xy 185.1025 -313.360308) (xy 185.102008 -313.387265) (xy 185.094158 -313.440605) (xy 185.078626 -313.492234)
			(xy 185.055741 -313.541051) (xy 185.025993 -313.586015) (xy 184.990015 -313.626169) (xy 184.948573 -313.660657)
			(xy 184.902552 -313.688743) (xy 184.852932 -313.70983) (xy 184.800771 -313.723466) (xy 184.74718 -313.729363)
			(xy 184.693301 -313.727394) (xy 184.640283 -313.717601) (xy 184.589256 -313.700193) (xy 184.541308 -313.675541)
			(xy 184.49746 -313.644171) (xy 184.458647 -313.60675) (xy 184.425695 -313.564077) (xy 184.399309 -313.51706)
			(xy 184.380049 -313.466703) (xy 184.368326 -313.414079) (xy 184.364391 -313.360308) (xy 183.949594 -313.360308)
			(xy 183.949594 -313.40679) (xy 183.957214 -313.425332) (xy 183.96458 -313.432698) (xy 183.987501 -313.456028)
			(xy 184.027582 -313.507712) (xy 184.060515 -313.56422) (xy 184.085727 -313.624569) (xy 184.102781 -313.687711)
			(xy 184.111379 -313.752548) (xy 184.1119 -313.78525) (xy 184.111411 -313.816413) (xy 184.103599 -313.878247)
			(xy 184.088099 -313.938615) (xy 184.065156 -313.996563) (xy 184.03513 -314.05118) (xy 183.998496 -314.101602)
			(xy 183.955831 -314.147036) (xy 183.907809 -314.186764) (xy 183.855185 -314.220159) (xy 183.798791 -314.246696)
			(xy 183.739516 -314.265956) (xy 183.678295 -314.277635) (xy 183.616092 -314.281548) (xy 183.553889 -314.277635)
			(xy 183.492668 -314.265956) (xy 183.433393 -314.246696) (xy 183.376999 -314.220159) (xy 183.324375 -314.186764)
			(xy 183.276353 -314.147036) (xy 183.233688 -314.101602) (xy 183.197054 -314.05118) (xy 183.167028 -313.996563)
			(xy 183.144085 -313.938615) (xy 183.128585 -313.878247) (xy 183.120773 -313.816413) (xy 183.120284 -313.78525)
			(xy 180.011832 -313.78525) (xy 180.01133 -313.817971) (xy 180.002729 -313.882846) (xy 179.985671 -313.946026)
			(xy 179.960452 -314.006414) (xy 179.92751 -314.06296) (xy 179.887417 -314.114683) (xy 179.864512 -314.138056)
			(xy 179.857146 -314.145168) (xy 179.849272 -314.163964) (xy 179.849272 -314.210446) (xy 180.264323 -314.210446)
			(xy 180.268258 -314.156675) (xy 180.279981 -314.104051) (xy 180.299241 -314.053694) (xy 180.325627 -314.006677)
			(xy 180.358579 -313.964004) (xy 180.397392 -313.926583) (xy 180.44124 -313.895213) (xy 180.489188 -313.870561)
			(xy 180.540215 -313.853153) (xy 180.593233 -313.84336) (xy 180.647112 -313.841391) (xy 180.700703 -313.847288)
			(xy 180.752864 -313.860924) (xy 180.802484 -313.882011) (xy 180.848505 -313.910097) (xy 180.889947 -313.944585)
			(xy 180.925925 -313.984739) (xy 180.955673 -314.029703) (xy 180.978558 -314.07852) (xy 180.99409 -314.130149)
			(xy 181.00194 -314.183489) (xy 181.002432 -314.210446) (xy 181.00194 -314.237403) (xy 180.99409 -314.290743)
			(xy 180.978558 -314.342372) (xy 180.955673 -314.391189) (xy 180.925925 -314.436153) (xy 180.889947 -314.476307)
			(xy 180.848505 -314.510795) (xy 180.802484 -314.538881) (xy 180.752864 -314.559968) (xy 180.700703 -314.573604)
			(xy 180.647112 -314.579501) (xy 180.593233 -314.577532) (xy 180.540215 -314.567739) (xy 180.489188 -314.550331)
			(xy 180.44124 -314.525679) (xy 180.397392 -314.494309) (xy 180.358579 -314.456888) (xy 180.325627 -314.414215)
			(xy 180.299241 -314.367198) (xy 180.279981 -314.316841) (xy 180.268258 -314.264217) (xy 180.264323 -314.210446)
			(xy 179.849272 -314.210446) (xy 179.849272 -314.256674) (xy 179.857146 -314.27547) (xy 179.864512 -314.282582)
			(xy 179.887409 -314.305961) (xy 179.927493 -314.357687) (xy 179.960429 -314.414234) (xy 179.985644 -314.47462)
			(xy 180.002703 -314.537797) (xy 180.011307 -314.602668) (xy 180.011832 -314.635388) (xy 181.862491 -314.635388)
			(xy 181.866426 -314.581617) (xy 181.878149 -314.528993) (xy 181.897409 -314.478636) (xy 181.923795 -314.431619)
			(xy 181.956747 -314.388946) (xy 181.99556 -314.351525) (xy 182.039408 -314.320155) (xy 182.087356 -314.295503)
			(xy 182.138383 -314.278095) (xy 182.191401 -314.268302) (xy 182.24528 -314.266333) (xy 182.298871 -314.27223)
			(xy 182.351032 -314.285866) (xy 182.400652 -314.306953) (xy 182.446673 -314.335039) (xy 182.488115 -314.369527)
			(xy 182.524093 -314.409681) (xy 182.553841 -314.454645) (xy 182.576726 -314.503462) (xy 182.592258 -314.555091)
			(xy 182.600108 -314.608431) (xy 182.6006 -314.635388) (xy 182.600108 -314.662345) (xy 182.592258 -314.715685)
			(xy 182.576726 -314.767314) (xy 182.553841 -314.816131) (xy 182.524093 -314.861095) (xy 182.488115 -314.901249)
			(xy 182.446673 -314.935737) (xy 182.400652 -314.963823) (xy 182.351032 -314.98491) (xy 182.298871 -314.998546)
			(xy 182.24528 -315.004443) (xy 182.191401 -315.002474) (xy 182.138383 -314.992681) (xy 182.087356 -314.975273)
			(xy 182.039408 -314.950621) (xy 181.99556 -314.919251) (xy 181.956747 -314.88183) (xy 181.923795 -314.839157)
			(xy 181.897409 -314.79214) (xy 181.878149 -314.741783) (xy 181.866426 -314.689159) (xy 181.862491 -314.635388)
			(xy 180.011832 -314.635388) (xy 180.011343 -314.666551) (xy 180.003531 -314.728385) (xy 179.988031 -314.788753)
			(xy 179.965088 -314.846701) (xy 179.935062 -314.901318) (xy 179.898428 -314.95174) (xy 179.855763 -314.997174)
			(xy 179.807741 -315.036902) (xy 179.755117 -315.070297) (xy 179.698723 -315.096834) (xy 179.639448 -315.116094)
			(xy 179.578227 -315.127773) (xy 179.516024 -315.131686) (xy 179.453821 -315.127773) (xy 179.3926 -315.116094)
			(xy 179.333325 -315.096834) (xy 179.276931 -315.070297) (xy 179.224307 -315.036902) (xy 179.176285 -314.997174)
			(xy 179.13362 -314.95174) (xy 179.096986 -314.901318) (xy 179.06696 -314.846701) (xy 179.044017 -314.788753)
			(xy 179.028517 -314.728385) (xy 179.020705 -314.666551) (xy 179.020216 -314.635388) (xy 175.056546 -314.635388)
			(xy 175.056054 -314.662345) (xy 175.048204 -314.715685) (xy 175.032672 -314.767314) (xy 175.009787 -314.816131)
			(xy 174.980039 -314.861095) (xy 174.944061 -314.901249) (xy 174.902619 -314.935737) (xy 174.856598 -314.963823)
			(xy 174.806978 -314.98491) (xy 174.754817 -314.998546) (xy 174.701226 -315.004443) (xy 174.647347 -315.002474)
			(xy 174.594329 -314.992681) (xy 174.543302 -314.975273) (xy 174.495354 -314.950621) (xy 174.451506 -314.919251)
			(xy 174.412693 -314.88183) (xy 174.379741 -314.839157) (xy 174.353355 -314.79214) (xy 174.334095 -314.741783)
			(xy 174.322372 -314.689159) (xy 174.318437 -314.635388) (xy 172.467778 -314.635388) (xy 172.467289 -314.666551)
			(xy 172.459477 -314.728385) (xy 172.443977 -314.788753) (xy 172.421034 -314.846701) (xy 172.391008 -314.901318)
			(xy 172.354374 -314.95174) (xy 172.311709 -314.997174) (xy 172.263687 -315.036902) (xy 172.211063 -315.070297)
			(xy 172.154669 -315.096834) (xy 172.095394 -315.116094) (xy 172.034173 -315.127773) (xy 171.97197 -315.131686)
			(xy 171.909767 -315.127773) (xy 171.848546 -315.116094) (xy 171.789271 -315.096834) (xy 171.732877 -315.070297)
			(xy 171.680253 -315.036902) (xy 171.632231 -314.997174) (xy 171.589566 -314.95174) (xy 171.552932 -314.901318)
			(xy 171.522906 -314.846701) (xy 171.499963 -314.788753) (xy 171.484463 -314.728385) (xy 171.476651 -314.666551)
			(xy 171.476162 -314.635388) (xy 167.512492 -314.635388) (xy 167.512 -314.662345) (xy 167.50415 -314.715685)
			(xy 167.488618 -314.767314) (xy 167.465733 -314.816131) (xy 167.435985 -314.861095) (xy 167.400007 -314.901249)
			(xy 167.358565 -314.935737) (xy 167.312544 -314.963823) (xy 167.262924 -314.98491) (xy 167.210763 -314.998546)
			(xy 167.157172 -315.004443) (xy 167.103293 -315.002474) (xy 167.050275 -314.992681) (xy 166.999248 -314.975273)
			(xy 166.9513 -314.950621) (xy 166.907452 -314.919251) (xy 166.868639 -314.88183) (xy 166.835687 -314.839157)
			(xy 166.809301 -314.79214) (xy 166.790041 -314.741783) (xy 166.778318 -314.689159) (xy 166.774383 -314.635388)
			(xy 153.530719 -314.635388) (xy 153.549709 -314.734933) (xy 153.565718 -314.861642) (xy 153.573739 -314.989106)
			(xy 153.573978 -315.019436) (xy 154.344368 -315.019436) (xy 154.348439 -314.963814) (xy 154.360565 -314.909377)
			(xy 154.380488 -314.857286) (xy 154.407784 -314.808651) (xy 154.44187 -314.764508) (xy 154.482019 -314.725799)
			(xy 154.527377 -314.693348) (xy 154.576977 -314.667847) (xy 154.629761 -314.64984) (xy 154.684604 -314.63971)
			(xy 154.740338 -314.637673) (xy 154.795775 -314.643773) (xy 154.849732 -314.657879) (xy 154.901061 -314.679691)
			(xy 154.948667 -314.708745) (xy 154.991535 -314.74442) (xy 155.028752 -314.785957) (xy 155.059525 -314.83247)
			(xy 155.083197 -314.882967) (xy 155.099265 -314.936374) (xy 155.107385 -314.99155) (xy 155.107894 -315.019436)
			(xy 155.107385 -315.047322) (xy 155.099265 -315.102498) (xy 155.083197 -315.155905) (xy 155.059525 -315.206402)
			(xy 155.028752 -315.252915) (xy 154.991535 -315.294452) (xy 154.948667 -315.330127) (xy 154.901061 -315.359181)
			(xy 154.849732 -315.380993) (xy 154.795775 -315.395099) (xy 154.740338 -315.401199) (xy 154.684604 -315.399162)
			(xy 154.629761 -315.389032) (xy 154.576977 -315.371025) (xy 154.527377 -315.345524) (xy 154.482019 -315.313073)
			(xy 154.44187 -315.274364) (xy 154.407784 -315.230221) (xy 154.380488 -315.181586) (xy 154.360565 -315.129495)
			(xy 154.348439 -315.075058) (xy 154.344368 -315.019436) (xy 153.573978 -315.019436) (xy 153.574242 -315.052964)
			(xy 153.573769 -315.115907) (xy 153.565975 -315.241551) (xy 153.550421 -315.366472) (xy 153.528091 -315.485272)
			(xy 165.442915 -315.485272) (xy 165.44685 -315.431501) (xy 165.458573 -315.378877) (xy 165.477833 -315.32852)
			(xy 165.504219 -315.281503) (xy 165.537171 -315.23883) (xy 165.575984 -315.201409) (xy 165.619832 -315.170039)
			(xy 165.66778 -315.145387) (xy 165.718807 -315.127979) (xy 165.771825 -315.118186) (xy 165.825704 -315.116217)
			(xy 165.879295 -315.122114) (xy 165.931456 -315.13575) (xy 165.981076 -315.156837) (xy 166.027097 -315.184923)
			(xy 166.068539 -315.219411) (xy 166.104517 -315.259565) (xy 166.134265 -315.304529) (xy 166.15715 -315.353346)
			(xy 166.172682 -315.404975) (xy 166.180532 -315.458315) (xy 166.181024 -315.485272) (xy 172.986969 -315.485272)
			(xy 172.990904 -315.431501) (xy 173.002627 -315.378877) (xy 173.021887 -315.32852) (xy 173.048273 -315.281503)
			(xy 173.081225 -315.23883) (xy 173.120038 -315.201409) (xy 173.163886 -315.170039) (xy 173.211834 -315.145387)
			(xy 173.262861 -315.127979) (xy 173.315879 -315.118186) (xy 173.369758 -315.116217) (xy 173.423349 -315.122114)
			(xy 173.47551 -315.13575) (xy 173.52513 -315.156837) (xy 173.571151 -315.184923) (xy 173.612593 -315.219411)
			(xy 173.648571 -315.259565) (xy 173.678319 -315.304529) (xy 173.701204 -315.353346) (xy 173.716736 -315.404975)
			(xy 173.724586 -315.458315) (xy 173.725078 -315.485272) (xy 173.724586 -315.512229) (xy 173.716736 -315.565569)
			(xy 173.701204 -315.617198) (xy 173.678319 -315.666015) (xy 173.648571 -315.710979) (xy 173.612593 -315.751133)
			(xy 173.571151 -315.785621) (xy 173.52513 -315.813707) (xy 173.47551 -315.834794) (xy 173.423349 -315.84843)
			(xy 173.369758 -315.854327) (xy 173.315879 -315.852358) (xy 173.262861 -315.842565) (xy 173.211834 -315.825157)
			(xy 173.163886 -315.800505) (xy 173.120038 -315.769135) (xy 173.081225 -315.731714) (xy 173.048273 -315.689041)
			(xy 173.021887 -315.642024) (xy 173.002627 -315.591667) (xy 172.990904 -315.539043) (xy 172.986969 -315.485272)
			(xy 166.181024 -315.485272) (xy 166.180532 -315.512229) (xy 166.172682 -315.565569) (xy 166.15715 -315.617198)
			(xy 166.134265 -315.666015) (xy 166.104517 -315.710979) (xy 166.068539 -315.751133) (xy 166.027097 -315.785621)
			(xy 165.981076 -315.813707) (xy 165.931456 -315.834794) (xy 165.879295 -315.84843) (xy 165.825704 -315.854327)
			(xy 165.771825 -315.852358) (xy 165.718807 -315.842565) (xy 165.66778 -315.825157) (xy 165.619832 -315.800505)
			(xy 165.575984 -315.769135) (xy 165.537171 -315.731714) (xy 165.504219 -315.689041) (xy 165.477833 -315.642024)
			(xy 165.458573 -315.591667) (xy 165.44685 -315.539043) (xy 165.442915 -315.485272) (xy 153.528091 -315.485272)
			(xy 153.527167 -315.49019) (xy 153.496301 -315.612233) (xy 153.457943 -315.732132) (xy 153.412238 -315.849428)
			(xy 153.359363 -315.96367) (xy 153.29952 -316.074422) (xy 153.232938 -316.181258) (xy 153.196798 -316.232794)
			(xy 153.188416 -316.244732) (xy 153.186384 -316.272672) (xy 153.218522 -316.33541) (xy 168.158683 -316.33541)
			(xy 168.162618 -316.281639) (xy 168.174341 -316.229015) (xy 168.193601 -316.178658) (xy 168.219987 -316.131641)
			(xy 168.252939 -316.088968) (xy 168.291752 -316.051547) (xy 168.3356 -316.020177) (xy 168.383548 -315.995525)
			(xy 168.434575 -315.978117) (xy 168.487593 -315.968324) (xy 168.541472 -315.966355) (xy 168.595063 -315.972252)
			(xy 168.647224 -315.985888) (xy 168.696844 -316.006975) (xy 168.742865 -316.035061) (xy 168.784307 -316.069549)
			(xy 168.820285 -316.109703) (xy 168.850033 -316.154667) (xy 168.872918 -316.203484) (xy 168.88845 -316.255113)
			(xy 168.8963 -316.308453) (xy 168.896792 -316.33541) (xy 168.8963 -316.362367) (xy 168.88845 -316.415707)
			(xy 168.872918 -316.467336) (xy 168.850033 -316.516153) (xy 168.820285 -316.561117) (xy 168.784307 -316.601271)
			(xy 168.742865 -316.635759) (xy 168.696844 -316.663845) (xy 168.647224 -316.684932) (xy 168.595063 -316.698568)
			(xy 168.541472 -316.704465) (xy 168.487593 -316.702496) (xy 168.434575 -316.692703) (xy 168.383548 -316.675295)
			(xy 168.3356 -316.650643) (xy 168.291752 -316.619273) (xy 168.252939 -316.581852) (xy 168.219987 -316.539179)
			(xy 168.193601 -316.492162) (xy 168.174341 -316.441805) (xy 168.162618 -316.389181) (xy 168.158683 -316.33541)
			(xy 153.218522 -316.33541) (xy 153.234136 -316.36589) (xy 153.238743 -316.37401) (xy 153.252605 -316.38649)
			(xy 153.270021 -316.393166) (xy 153.279348 -316.393576) (xy 155.777692 -316.393576) (xy 155.787661 -316.394036)
			(xy 155.806097 -316.401622) (xy 155.813506 -316.408308) (xy 156.192474 -316.787276) (xy 156.199199 -316.794679)
			(xy 156.206919 -316.813104) (xy 156.20746 -316.82309) (xy 156.20746 -317.185294) (xy 164.058615 -317.185294)
			(xy 164.06255 -317.131523) (xy 164.074273 -317.078899) (xy 164.093533 -317.028542) (xy 164.119919 -316.981525)
			(xy 164.152871 -316.938852) (xy 164.191684 -316.901431) (xy 164.235532 -316.870061) (xy 164.28348 -316.845409)
			(xy 164.334507 -316.828001) (xy 164.387525 -316.818208) (xy 164.441404 -316.816239) (xy 164.494995 -316.822136)
			(xy 164.547156 -316.835772) (xy 164.596776 -316.856859) (xy 164.642797 -316.884945) (xy 164.684239 -316.919433)
			(xy 164.720217 -316.959587) (xy 164.749965 -317.004551) (xy 164.77285 -317.053368) (xy 164.788382 -317.104997)
			(xy 164.796232 -317.158337) (xy 164.796724 -317.185294) (xy 164.796232 -317.212251) (xy 164.788382 -317.265591)
			(xy 164.77285 -317.31722) (xy 164.749965 -317.366037) (xy 164.720217 -317.411001) (xy 164.684239 -317.451155)
			(xy 164.642797 -317.485643) (xy 164.596776 -317.513729) (xy 164.547156 -317.534816) (xy 164.494995 -317.548452)
			(xy 164.441404 -317.554349) (xy 164.387525 -317.55238) (xy 164.334507 -317.542587) (xy 164.28348 -317.525179)
			(xy 164.235532 -317.500527) (xy 164.191684 -317.469157) (xy 164.152871 -317.431736) (xy 164.119919 -317.389063)
			(xy 164.093533 -317.342046) (xy 164.074273 -317.291689) (xy 164.06255 -317.239065) (xy 164.058615 -317.185294)
			(xy 156.20746 -317.185294) (xy 156.20746 -318.035432) (xy 168.158683 -318.035432) (xy 168.162618 -317.981661)
			(xy 168.174341 -317.929037) (xy 168.193601 -317.87868) (xy 168.219987 -317.831663) (xy 168.252939 -317.78899)
			(xy 168.291752 -317.751569) (xy 168.3356 -317.720199) (xy 168.383548 -317.695547) (xy 168.434575 -317.678139)
			(xy 168.487593 -317.668346) (xy 168.541472 -317.666377) (xy 168.595063 -317.672274) (xy 168.647224 -317.68591)
			(xy 168.696844 -317.706997) (xy 168.742865 -317.735083) (xy 168.784307 -317.769571) (xy 168.820285 -317.809725)
			(xy 168.850033 -317.854689) (xy 168.872918 -317.903506) (xy 168.88845 -317.955135) (xy 168.8963 -318.008475)
			(xy 168.896792 -318.035432) (xy 171.476162 -318.035432) (xy 171.476627 -318.004223) (xy 171.484453 -317.942296)
			(xy 171.499987 -317.881841) (xy 171.522983 -317.823813) (xy 171.553077 -317.769128) (xy 171.589794 -317.71865)
			(xy 171.632553 -317.673177) (xy 171.68068 -317.633429) (xy 171.706794 -317.616332) (xy 171.716954 -317.609982)
			(xy 171.729146 -317.59017) (xy 171.738798 -317.48603) (xy 171.730416 -317.464186) (xy 171.721526 -317.456058)
			(xy 171.703191 -317.43855) (xy 171.671048 -317.399346) (xy 171.644576 -317.35611) (xy 171.624274 -317.309657)
			(xy 171.610522 -317.260861) (xy 171.603582 -317.210642) (xy 171.603162 -317.185294) (xy 171.603546 -317.159975)
			(xy 171.610476 -317.109814) (xy 171.624203 -317.061072) (xy 171.64447 -317.014667) (xy 171.670896 -316.971472)
			(xy 171.702984 -316.932298) (xy 171.721272 -316.914784) (xy 171.730162 -316.906402) (xy 171.738544 -316.884812)
			(xy 171.729146 -316.780672) (xy 171.716954 -316.76086) (xy 171.706794 -316.754256) (xy 171.680667 -316.737203)
			(xy 171.632551 -316.697484) (xy 171.589798 -316.65204) (xy 171.553086 -316.601591) (xy 171.522995 -316.546934)
			(xy 171.5 -316.488934) (xy 171.484464 -316.428506) (xy 171.476634 -316.366606) (xy 171.476162 -316.33541)
			(xy 171.476651 -316.304247) (xy 171.484463 -316.242413) (xy 171.499963 -316.182045) (xy 171.522906 -316.124097)
			(xy 171.552932 -316.06948) (xy 171.589566 -316.019058) (xy 171.632231 -315.973624) (xy 171.680253 -315.933896)
			(xy 171.732877 -315.900501) (xy 171.789271 -315.873964) (xy 171.848546 -315.854704) (xy 171.909767 -315.843025)
			(xy 171.97197 -315.839112) (xy 172.034173 -315.843025) (xy 172.095394 -315.854704) (xy 172.154669 -315.873964)
			(xy 172.211063 -315.900501) (xy 172.263687 -315.933896) (xy 172.311709 -315.973624) (xy 172.354374 -316.019058)
			(xy 172.391008 -316.06948) (xy 172.421034 -316.124097) (xy 172.443977 -316.182045) (xy 172.459477 -316.242413)
			(xy 172.467289 -316.304247) (xy 172.467778 -316.33541) (xy 172.467359 -316.366609) (xy 172.459536 -316.428514)
			(xy 172.444 -316.488946) (xy 172.421 -316.54695) (xy 172.390898 -316.601606) (xy 172.354171 -316.652049)
			(xy 172.311401 -316.697482) (xy 172.263264 -316.737185) (xy 172.237146 -316.754256) (xy 172.226986 -316.76086)
			(xy 172.214794 -316.780672) (xy 172.205396 -316.884812) (xy 172.213778 -316.906402) (xy 172.222668 -316.914784)
			(xy 172.240958 -316.932295) (xy 172.273034 -316.971474) (xy 172.299451 -317.014672) (xy 172.319711 -317.061077)
			(xy 172.333433 -317.109817) (xy 172.340359 -317.159976) (xy 172.340778 -317.185294) (xy 175.57623 -317.185294)
			(xy 175.576694 -317.154097) (xy 175.584516 -317.092196) (xy 175.600048 -317.031766) (xy 175.623043 -316.973765)
			(xy 175.653139 -316.919109) (xy 175.689858 -316.868665) (xy 175.73262 -316.823229) (xy 175.780748 -316.783522)
			(xy 175.806862 -316.766448) (xy 175.817022 -316.759844) (xy 175.829214 -316.740032) (xy 175.838612 -316.635892)
			(xy 175.83023 -316.614302) (xy 175.82134 -316.60592) (xy 175.803054 -316.588406) (xy 175.770976 -316.549228)
			(xy 175.744559 -316.50603) (xy 175.724299 -316.459626) (xy 175.710576 -316.410886) (xy 175.703649 -316.360727)
			(xy 175.70323 -316.33541) (xy 175.703659 -316.310062) (xy 175.71059 -316.259842) (xy 175.724338 -316.211046)
			(xy 175.744642 -316.164594) (xy 175.771119 -316.121362) (xy 175.803271 -316.082166) (xy 175.821594 -316.064646)
			(xy 175.830484 -316.056518) (xy 175.838866 -316.034674) (xy 175.829214 -315.930534) (xy 175.817022 -315.910722)
			(xy 175.806862 -315.904372) (xy 175.780722 -315.887315) (xy 175.732602 -315.847555) (xy 175.689848 -315.802075)
			(xy 175.653137 -315.75159) (xy 175.623048 -315.6969) (xy 175.600056 -315.638868) (xy 175.584525 -315.578411)
			(xy 175.576699 -315.516482) (xy 175.57623 -315.485272) (xy 175.576719 -315.454109) (xy 175.584531 -315.392275)
			(xy 175.600031 -315.331907) (xy 175.622974 -315.273959) (xy 175.653 -315.219342) (xy 175.689634 -315.16892)
			(xy 175.732299 -315.123486) (xy 175.780321 -315.083758) (xy 175.832945 -315.050363) (xy 175.889339 -315.023826)
			(xy 175.948614 -315.004566) (xy 176.009835 -314.992887) (xy 176.072038 -314.988974) (xy 176.134241 -314.992887)
			(xy 176.195462 -315.004566) (xy 176.254737 -315.023826) (xy 176.311131 -315.050363) (xy 176.363755 -315.083758)
			(xy 176.411777 -315.123486) (xy 176.454442 -315.16892) (xy 176.491076 -315.219342) (xy 176.521102 -315.273959)
			(xy 176.544045 -315.331907) (xy 176.559545 -315.392275) (xy 176.567357 -315.454109) (xy 176.567846 -315.485272)
			(xy 180.531023 -315.485272) (xy 180.534958 -315.431501) (xy 180.546681 -315.378877) (xy 180.565941 -315.32852)
			(xy 180.592327 -315.281503) (xy 180.625279 -315.23883) (xy 180.664092 -315.201409) (xy 180.70794 -315.170039)
			(xy 180.755888 -315.145387) (xy 180.806915 -315.127979) (xy 180.859933 -315.118186) (xy 180.913812 -315.116217)
			(xy 180.967403 -315.122114) (xy 181.019564 -315.13575) (xy 181.069184 -315.156837) (xy 181.115205 -315.184923)
			(xy 181.156647 -315.219411) (xy 181.192625 -315.259565) (xy 181.222373 -315.304529) (xy 181.245258 -315.353346)
			(xy 181.26079 -315.404975) (xy 181.26864 -315.458315) (xy 181.269132 -315.485272) (xy 181.26864 -315.512229)
			(xy 181.26079 -315.565569) (xy 181.245258 -315.617198) (xy 181.222373 -315.666015) (xy 181.192625 -315.710979)
			(xy 181.156647 -315.751133) (xy 181.115205 -315.785621) (xy 181.069184 -315.813707) (xy 181.019564 -315.834794)
			(xy 180.967403 -315.84843) (xy 180.913812 -315.854327) (xy 180.859933 -315.852358) (xy 180.806915 -315.842565)
			(xy 180.755888 -315.825157) (xy 180.70794 -315.800505) (xy 180.664092 -315.769135) (xy 180.625279 -315.731714)
			(xy 180.592327 -315.689041) (xy 180.565941 -315.642024) (xy 180.546681 -315.591667) (xy 180.534958 -315.539043)
			(xy 180.531023 -315.485272) (xy 176.567846 -315.485272) (xy 176.567381 -315.516481) (xy 176.559554 -315.578407)
			(xy 176.54402 -315.638862) (xy 176.521024 -315.696891) (xy 176.49093 -315.751576) (xy 176.454213 -315.802053)
			(xy 176.411454 -315.847526) (xy 176.363328 -315.887275) (xy 176.337214 -315.904372) (xy 176.327054 -315.910722)
			(xy 176.314862 -315.930534) (xy 176.30521 -316.034674) (xy 176.313592 -316.056518) (xy 176.322482 -316.064646)
			(xy 176.34082 -316.08215) (xy 176.372962 -316.121355) (xy 176.399434 -316.164592) (xy 176.419736 -316.211046)
			(xy 176.433487 -316.259842) (xy 176.440426 -316.310062) (xy 176.440846 -316.33541) (xy 176.440462 -316.360729)
			(xy 176.433532 -316.41089) (xy 176.419805 -316.459631) (xy 176.399537 -316.506036) (xy 176.373112 -316.549232)
			(xy 176.341024 -316.588405) (xy 176.322736 -316.60592) (xy 176.313846 -316.614302) (xy 176.305464 -316.635892)
			(xy 176.314862 -316.740032) (xy 176.327054 -316.759844) (xy 176.337214 -316.766448) (xy 176.363345 -316.783495)
			(xy 176.411461 -316.823216) (xy 176.454212 -316.868661) (xy 176.490924 -316.91911) (xy 176.521015 -316.973768)
			(xy 176.54401 -317.031769) (xy 176.559545 -317.092197) (xy 176.567375 -317.154097) (xy 176.567846 -317.185294)
			(xy 176.56732 -317.216502) (xy 176.559502 -317.278425) (xy 176.543977 -317.338879) (xy 176.520991 -317.396906)
			(xy 176.490905 -317.451592) (xy 176.454196 -317.502071) (xy 176.411444 -317.547545) (xy 176.363325 -317.587296)
			(xy 176.337214 -317.604394) (xy 176.327054 -317.610744) (xy 176.314862 -317.630556) (xy 176.30521 -317.734696)
			(xy 176.313592 -317.75654) (xy 176.322482 -317.764668) (xy 176.340783 -317.78221) (xy 176.372928 -317.821407)
			(xy 176.399404 -317.864636) (xy 176.419713 -317.911082) (xy 176.433472 -317.959872) (xy 176.440421 -318.010086)
			(xy 176.440846 -318.035432) (xy 179.020216 -318.035432) (xy 179.020656 -318.004222) (xy 179.028483 -317.942293)
			(xy 179.044019 -317.881837) (xy 179.067018 -317.823807) (xy 179.097115 -317.769121) (xy 179.133836 -317.718644)
			(xy 179.1766 -317.673173) (xy 179.224731 -317.633427) (xy 179.250848 -317.616332) (xy 179.261008 -317.609982)
			(xy 179.2732 -317.59017) (xy 179.282852 -317.48603) (xy 179.27447 -317.464186) (xy 179.26558 -317.456058)
			(xy 179.247236 -317.438559) (xy 179.215096 -317.399352) (xy 179.188626 -317.356114) (xy 179.168326 -317.309659)
			(xy 179.154576 -317.260862) (xy 179.147636 -317.210643) (xy 179.147216 -317.185294) (xy 179.147615 -317.159976)
			(xy 179.154543 -317.109816) (xy 179.168269 -317.061075) (xy 179.188533 -317.01467) (xy 179.214956 -316.971475)
			(xy 179.24704 -316.9323) (xy 179.265326 -316.914784) (xy 179.274216 -316.906402) (xy 179.282598 -316.884812)
			(xy 179.2732 -316.780672) (xy 179.261008 -316.76086) (xy 179.250848 -316.754256) (xy 179.224733 -316.737185)
			(xy 179.176615 -316.69747) (xy 179.13386 -316.65203) (xy 179.097146 -316.601584) (xy 179.067052 -316.546929)
			(xy 179.044055 -316.488931) (xy 179.028519 -316.428504) (xy 179.020688 -316.366606) (xy 179.020216 -316.33541)
			(xy 179.020705 -316.304247) (xy 179.028517 -316.242413) (xy 179.044017 -316.182045) (xy 179.06696 -316.124097)
			(xy 179.096986 -316.06948) (xy 179.13362 -316.019058) (xy 179.176285 -315.973624) (xy 179.224307 -315.933896)
			(xy 179.276931 -315.900501) (xy 179.333325 -315.873964) (xy 179.3926 -315.854704) (xy 179.453821 -315.843025)
			(xy 179.516024 -315.839112) (xy 179.578227 -315.843025) (xy 179.639448 -315.854704) (xy 179.698723 -315.873964)
			(xy 179.755117 -315.900501) (xy 179.807741 -315.933896) (xy 179.855763 -315.973624) (xy 179.898428 -316.019058)
			(xy 179.935062 -316.06948) (xy 179.965088 -316.124097) (xy 179.988031 -316.182045) (xy 180.003531 -316.242413)
			(xy 180.011343 -316.304247) (xy 180.011832 -316.33541) (xy 180.011388 -316.366608) (xy 180.003566 -316.428511)
			(xy 179.988032 -316.488941) (xy 179.965034 -316.546944) (xy 179.934936 -316.6016) (xy 179.898213 -316.652044)
			(xy 179.855448 -316.697478) (xy 179.807316 -316.737183) (xy 179.7812 -316.754256) (xy 179.77104 -316.76086)
			(xy 179.758848 -316.780672) (xy 179.74945 -316.884812) (xy 179.757832 -316.906402) (xy 179.766722 -316.914784)
			(xy 179.785003 -316.932304) (xy 179.817082 -316.97148) (xy 179.843501 -317.014676) (xy 179.863763 -317.061079)
			(xy 179.877486 -317.109819) (xy 179.884413 -317.159977) (xy 179.884832 -317.185294) (xy 183.120284 -317.185294)
			(xy 183.120723 -317.154096) (xy 183.128546 -317.092193) (xy 183.144079 -317.031761) (xy 183.167078 -316.973759)
			(xy 183.197177 -316.919103) (xy 183.2339 -316.868659) (xy 183.276667 -316.823225) (xy 183.3248 -316.78352)
			(xy 183.350916 -316.766448) (xy 183.361076 -316.759844) (xy 183.373268 -316.740032) (xy 183.382666 -316.635892)
			(xy 183.374284 -316.614302) (xy 183.365394 -316.60592) (xy 183.347118 -316.588395) (xy 183.315038 -316.549221)
			(xy 183.288618 -316.506026) (xy 183.268355 -316.459623) (xy 183.254631 -316.410885) (xy 183.247703 -316.360727)
			(xy 183.247284 -316.33541) (xy 183.247727 -316.310063) (xy 183.254658 -316.259844) (xy 183.268403 -316.211049)
			(xy 183.288705 -316.164597) (xy 183.315179 -316.121365) (xy 183.347327 -316.082167) (xy 183.365648 -316.064646)
			(xy 183.374538 -316.056518) (xy 183.38292 -316.034674) (xy 183.373268 -315.930534) (xy 183.361076 -315.910722)
			(xy 183.350916 -315.904372) (xy 183.324788 -315.887296) (xy 183.276666 -315.847541) (xy 183.23391 -315.802064)
			(xy 183.197197 -315.751583) (xy 183.167106 -315.696895) (xy 183.144112 -315.638865) (xy 183.12858 -315.578409)
			(xy 183.120753 -315.516482) (xy 183.120284 -315.485272) (xy 183.120773 -315.454109) (xy 183.128585 -315.392275)
			(xy 183.144085 -315.331907) (xy 183.167028 -315.273959) (xy 183.197054 -315.219342) (xy 183.233688 -315.16892)
			(xy 183.276353 -315.123486) (xy 183.324375 -315.083758) (xy 183.376999 -315.050363) (xy 183.433393 -315.023826)
			(xy 183.492668 -315.004566) (xy 183.553889 -314.992887) (xy 183.616092 -314.988974) (xy 183.678295 -314.992887)
			(xy 183.739516 -315.004566) (xy 183.798791 -315.023826) (xy 183.855185 -315.050363) (xy 183.907809 -315.083758)
			(xy 183.955831 -315.123486) (xy 183.998496 -315.16892) (xy 184.03513 -315.219342) (xy 184.065156 -315.273959)
			(xy 184.088099 -315.331907) (xy 184.103599 -315.392275) (xy 184.111411 -315.454109) (xy 184.1119 -315.485272)
			(xy 184.111456 -315.516482) (xy 184.103628 -315.57841) (xy 184.088092 -315.638866) (xy 184.065094 -315.696896)
			(xy 184.034997 -315.751581) (xy 183.998277 -315.802058) (xy 183.955514 -315.84753) (xy 183.907384 -315.887277)
			(xy 183.881268 -315.904372) (xy 183.871108 -315.910722) (xy 183.858916 -315.930534) (xy 183.849264 -316.034674)
			(xy 183.857646 -316.056518) (xy 183.866536 -316.064646) (xy 183.884866 -316.082159) (xy 183.91701 -316.121361)
			(xy 183.943484 -316.164596) (xy 183.963788 -316.211048) (xy 183.97754 -316.259843) (xy 183.98448 -316.310062)
			(xy 183.9849 -316.33541) (xy 183.984499 -316.360728) (xy 183.97757 -316.410888) (xy 183.963845 -316.459628)
			(xy 183.943581 -316.506033) (xy 183.917159 -316.549229) (xy 183.885076 -316.588404) (xy 183.86679 -316.60592)
			(xy 183.8579 -316.614302) (xy 183.849518 -316.635892) (xy 183.858916 -316.740032) (xy 183.871108 -316.759844)
			(xy 183.881268 -316.766448) (xy 183.907388 -316.783511) (xy 183.955506 -316.823228) (xy 183.99826 -316.868669)
			(xy 184.034973 -316.919116) (xy 184.065066 -316.973772) (xy 184.088062 -317.031772) (xy 184.103598 -317.092199)
			(xy 184.111429 -317.154098) (xy 184.1119 -317.185294) (xy 184.111395 -317.216502) (xy 184.103577 -317.278428)
			(xy 184.08805 -317.338882) (xy 184.065061 -317.396911) (xy 184.034973 -317.451597) (xy 183.99826 -317.502075)
			(xy 183.955505 -317.547548) (xy 183.907381 -317.587297) (xy 183.881268 -317.604394) (xy 183.871108 -317.610744)
			(xy 183.858916 -317.630556) (xy 183.849264 -317.734696) (xy 183.857646 -317.75654) (xy 183.866536 -317.764668)
			(xy 183.884828 -317.782219) (xy 183.916976 -317.821413) (xy 183.943455 -317.864639) (xy 183.963765 -317.911085)
			(xy 183.977525 -317.959873) (xy 183.984475 -318.010086) (xy 183.9849 -318.035432) (xy 183.984384 -318.063032)
			(xy 183.976157 -318.117615) (xy 183.959887 -318.170362) (xy 183.935937 -318.220095) (xy 183.904842 -318.265702)
			(xy 183.867297 -318.306166) (xy 183.82414 -318.340583) (xy 183.776336 -318.368182) (xy 183.724952 -318.388349)
			(xy 183.671137 -318.400632) (xy 183.616092 -318.404757) (xy 183.561047 -318.400632) (xy 183.507232 -318.388349)
			(xy 183.455848 -318.368182) (xy 183.408044 -318.340583) (xy 183.364887 -318.306166) (xy 183.327342 -318.265702)
			(xy 183.296247 -318.220095) (xy 183.272297 -318.170362) (xy 183.256027 -318.117615) (xy 183.2478 -318.063032)
			(xy 183.247284 -318.035432) (xy 183.247675 -318.010083) (xy 183.254616 -317.959862) (xy 183.268372 -317.911066)
			(xy 183.288683 -317.864614) (xy 183.315167 -317.821383) (xy 183.347323 -317.782188) (xy 183.365648 -317.764668)
			(xy 183.374538 -317.75654) (xy 183.38292 -317.734696) (xy 183.373268 -317.630556) (xy 183.361076 -317.610744)
			(xy 183.350916 -317.604394) (xy 183.324798 -317.587303) (xy 183.276676 -317.54755) (xy 183.23392 -317.502076)
			(xy 183.197206 -317.451597) (xy 183.167113 -317.396911) (xy 183.144118 -317.338883) (xy 183.128583 -317.278429)
			(xy 183.120755 -317.216503) (xy 183.120284 -317.185294) (xy 179.884832 -317.185294) (xy 179.884386 -317.210641)
			(xy 179.877456 -317.260859) (xy 179.86371 -317.309654) (xy 179.843409 -317.356106) (xy 179.816936 -317.399339)
			(xy 179.784789 -317.438537) (xy 179.766468 -317.456058) (xy 179.757578 -317.464186) (xy 179.749196 -317.48603)
			(xy 179.758848 -317.59017) (xy 179.77104 -317.609982) (xy 179.7812 -317.616332) (xy 179.807287 -317.633467)
			(xy 179.855409 -317.673214) (xy 179.898166 -317.718683) (xy 179.934883 -317.769155) (xy 179.964979 -317.823834)
			(xy 179.987979 -317.881856) (xy 180.00352 -317.942304) (xy 180.011357 -318.004225) (xy 180.011832 -318.035432)
			(xy 180.011327 -318.066628) (xy 180.003514 -318.128528) (xy 179.98799 -318.188958) (xy 179.965001 -318.246959)
			(xy 179.934911 -318.301616) (xy 179.898196 -318.352061) (xy 179.855438 -318.397497) (xy 179.807313 -318.437204)
			(xy 179.7812 -318.454278) (xy 179.77104 -318.460882) (xy 179.758848 -318.480694) (xy 179.74945 -318.584834)
			(xy 179.757832 -318.606424) (xy 179.766722 -318.614806) (xy 179.785014 -318.632315) (xy 179.817092 -318.671493)
			(xy 179.843509 -318.714692) (xy 179.863769 -318.761097) (xy 179.87749 -318.809838) (xy 179.884415 -318.859998)
			(xy 179.884832 -318.885316) (xy 179.884316 -318.912916) (xy 179.876089 -318.967499) (xy 179.859819 -319.020246)
			(xy 179.835869 -319.069979) (xy 179.804774 -319.115586) (xy 179.767229 -319.15605) (xy 179.724072 -319.190467)
			(xy 179.676268 -319.218066) (xy 179.624884 -319.238233) (xy 179.571069 -319.250516) (xy 179.516024 -319.254641)
			(xy 179.460979 -319.250516) (xy 179.407164 -319.238233) (xy 179.35578 -319.218066) (xy 179.307976 -319.190467)
			(xy 179.264819 -319.15605) (xy 179.227274 -319.115586) (xy 179.196179 -319.069979) (xy 179.172229 -319.020246)
			(xy 179.155959 -318.967499) (xy 179.147732 -318.912916) (xy 179.147216 -318.885316) (xy 179.14763 -318.859998)
			(xy 179.154555 -318.809839) (xy 179.168278 -318.761098) (xy 179.188539 -318.714694) (xy 179.214959 -318.671498)
			(xy 179.247041 -318.632322) (xy 179.265326 -318.614806) (xy 179.274216 -318.606424) (xy 179.282598 -318.584834)
			(xy 179.2732 -318.480694) (xy 179.261008 -318.460882) (xy 179.250848 -318.454278) (xy 179.224744 -318.437192)
			(xy 179.176625 -318.397479) (xy 179.13387 -318.352041) (xy 179.097154 -318.301598) (xy 179.06706 -318.246945)
			(xy 179.044061 -318.188948) (xy 179.028522 -318.128524) (xy 179.020689 -318.066627) (xy 179.020216 -318.035432)
			(xy 176.440846 -318.035432) (xy 176.44033 -318.063032) (xy 176.432103 -318.117615) (xy 176.415833 -318.170362)
			(xy 176.391883 -318.220095) (xy 176.360788 -318.265702) (xy 176.323243 -318.306166) (xy 176.280086 -318.340583)
			(xy 176.232282 -318.368182) (xy 176.180898 -318.388349) (xy 176.127083 -318.400632) (xy 176.072038 -318.404757)
			(xy 176.016993 -318.400632) (xy 175.963178 -318.388349) (xy 175.911794 -318.368182) (xy 175.86399 -318.340583)
			(xy 175.820833 -318.306166) (xy 175.783288 -318.265702) (xy 175.752193 -318.220095) (xy 175.728243 -318.170362)
			(xy 175.711973 -318.117615) (xy 175.703746 -318.063032) (xy 175.70323 -318.035432) (xy 175.703607 -318.010082)
			(xy 175.710549 -317.95986) (xy 175.724306 -317.911063) (xy 175.74462 -317.864611) (xy 175.771107 -317.82138)
			(xy 175.803267 -317.782186) (xy 175.821594 -317.764668) (xy 175.830484 -317.75654) (xy 175.838866 -317.734696)
			(xy 175.829214 -317.630556) (xy 175.817022 -317.610744) (xy 175.806862 -317.604394) (xy 175.780732 -317.587322)
			(xy 175.732612 -317.547565) (xy 175.689858 -317.502086) (xy 175.653146 -317.451604) (xy 175.623055 -317.396916)
			(xy 175.600062 -317.338886) (xy 175.584528 -317.27843) (xy 175.5767 -317.216504) (xy 175.57623 -317.185294)
			(xy 172.340778 -317.185294) (xy 172.340349 -317.210642) (xy 172.333418 -317.260862) (xy 172.31967 -317.309658)
			(xy 172.299366 -317.35611) (xy 172.272889 -317.399342) (xy 172.240737 -317.438538) (xy 172.222414 -317.456058)
			(xy 172.213524 -317.464186) (xy 172.205142 -317.48603) (xy 172.214794 -317.59017) (xy 172.226986 -317.609982)
			(xy 172.237146 -317.616332) (xy 172.263244 -317.633451) (xy 172.311364 -317.673202) (xy 172.354119 -317.718674)
			(xy 172.390834 -317.769149) (xy 172.420928 -317.82383) (xy 172.443927 -317.881853) (xy 172.459467 -317.942303)
			(xy 172.467303 -318.004224) (xy 172.467778 -318.035432) (xy 172.467298 -318.066629) (xy 172.459484 -318.128531)
			(xy 172.443958 -318.188962) (xy 172.420967 -318.246965) (xy 172.390873 -318.301622) (xy 172.354154 -318.352067)
			(xy 172.311391 -318.397501) (xy 172.263261 -318.437206) (xy 172.237146 -318.454278) (xy 172.226986 -318.460882)
			(xy 172.214794 -318.480694) (xy 172.205396 -318.584834) (xy 172.213778 -318.606424) (xy 172.222668 -318.614806)
			(xy 172.240968 -318.632306) (xy 172.273044 -318.671488) (xy 172.299459 -318.714688) (xy 172.319717 -318.761095)
			(xy 172.333437 -318.809837) (xy 172.340361 -318.859998) (xy 172.340778 -318.885316) (xy 172.340262 -318.912916)
			(xy 172.332035 -318.967499) (xy 172.315765 -319.020246) (xy 172.291815 -319.069979) (xy 172.26072 -319.115586)
			(xy 172.223175 -319.15605) (xy 172.180018 -319.190467) (xy 172.132214 -319.218066) (xy 172.08083 -319.238233)
			(xy 172.027015 -319.250516) (xy 171.97197 -319.254641) (xy 171.916925 -319.250516) (xy 171.86311 -319.238233)
			(xy 171.811726 -319.218066) (xy 171.763922 -319.190467) (xy 171.720765 -319.15605) (xy 171.68322 -319.115586)
			(xy 171.652125 -319.069979) (xy 171.628175 -319.020246) (xy 171.611905 -318.967499) (xy 171.603678 -318.912916)
			(xy 171.603162 -318.885316) (xy 171.603561 -318.859998) (xy 171.610488 -318.809837) (xy 171.624212 -318.761096)
			(xy 171.644477 -318.714691) (xy 171.6709 -318.671495) (xy 171.702985 -318.632321) (xy 171.721272 -318.614806)
			(xy 171.730162 -318.606424) (xy 171.738544 -318.584834) (xy 171.729146 -318.480694) (xy 171.716954 -318.460882)
			(xy 171.706794 -318.454278) (xy 171.680677 -318.437211) (xy 171.632561 -318.397493) (xy 171.589808 -318.352052)
			(xy 171.553095 -318.301605) (xy 171.523002 -318.24695) (xy 171.500005 -318.188952) (xy 171.484468 -318.128526)
			(xy 171.476635 -318.066628) (xy 171.476162 -318.035432) (xy 168.896792 -318.035432) (xy 168.8963 -318.062389)
			(xy 168.88845 -318.115729) (xy 168.872918 -318.167358) (xy 168.850033 -318.216175) (xy 168.820285 -318.261139)
			(xy 168.784307 -318.301293) (xy 168.742865 -318.335781) (xy 168.696844 -318.363867) (xy 168.647224 -318.384954)
			(xy 168.595063 -318.39859) (xy 168.541472 -318.404487) (xy 168.487593 -318.402518) (xy 168.434575 -318.392725)
			(xy 168.383548 -318.375317) (xy 168.3356 -318.350665) (xy 168.291752 -318.319295) (xy 168.252939 -318.281874)
			(xy 168.219987 -318.239201) (xy 168.193601 -318.192184) (xy 168.174341 -318.141827) (xy 168.162618 -318.089203)
			(xy 168.158683 -318.035432) (xy 156.20746 -318.035432) (xy 156.20746 -318.885316) (xy 164.058615 -318.885316)
			(xy 164.06255 -318.831545) (xy 164.074273 -318.778921) (xy 164.093533 -318.728564) (xy 164.119919 -318.681547)
			(xy 164.152871 -318.638874) (xy 164.191684 -318.601453) (xy 164.235532 -318.570083) (xy 164.28348 -318.545431)
			(xy 164.334507 -318.528023) (xy 164.387525 -318.51823) (xy 164.441404 -318.516261) (xy 164.494995 -318.522158)
			(xy 164.547156 -318.535794) (xy 164.596776 -318.556881) (xy 164.642797 -318.584967) (xy 164.684239 -318.619455)
			(xy 164.720217 -318.659609) (xy 164.749965 -318.704573) (xy 164.77285 -318.75339) (xy 164.788382 -318.805019)
			(xy 164.796232 -318.858359) (xy 164.796724 -318.885316) (xy 164.796232 -318.912273) (xy 164.788382 -318.965613)
			(xy 164.77285 -319.017242) (xy 164.749965 -319.066059) (xy 164.720217 -319.111023) (xy 164.684239 -319.151177)
			(xy 164.642797 -319.185665) (xy 164.596776 -319.213751) (xy 164.547156 -319.234838) (xy 164.494995 -319.248474)
			(xy 164.441404 -319.254371) (xy 164.387525 -319.252402) (xy 164.334507 -319.242609) (xy 164.28348 -319.225201)
			(xy 164.235532 -319.200549) (xy 164.191684 -319.169179) (xy 164.152871 -319.131758) (xy 164.119919 -319.089085)
			(xy 164.093533 -319.042068) (xy 164.074273 -318.991711) (xy 164.06255 -318.939087) (xy 164.058615 -318.885316)
			(xy 156.20746 -318.885316) (xy 156.20746 -319.905126) (xy 156.206993 -319.91513) (xy 156.199278 -319.933593)
			(xy 156.192474 -319.94094) (xy 155.936442 -320.196972) (xy 155.929028 -320.203647) (xy 155.910593 -320.211225)
			(xy 155.900628 -320.211704) (xy 155.44927 -320.211704) (xy 155.438676 -320.212274) (xy 155.419317 -320.220896)
			(xy 155.4051 -320.23661) (xy 155.401264 -320.246502) (xy 155.365196 -320.353182) (xy 155.374848 -320.384424)
			(xy 155.387802 -320.39433) (xy 155.414075 -320.415026) (xy 155.461552 -320.462133) (xy 155.50244 -320.515059)
			(xy 155.536033 -320.572892) (xy 155.561751 -320.63463) (xy 155.57915 -320.699209) (xy 155.587928 -320.765511)
			(xy 155.588462 -320.798952) (xy 155.587936 -320.831536) (xy 155.579597 -320.89617) (xy 155.563073 -320.959209)
			(xy 155.538637 -321.019623) (xy 155.506687 -321.076423) (xy 155.467747 -321.128678) (xy 155.422453 -321.175535)
			(xy 155.371549 -321.216225) (xy 155.315865 -321.250083) (xy 155.256315 -321.276554) (xy 155.225242 -321.286378)
			(xy 155.21559 -321.289172) (xy 155.199842 -321.301872) (xy 155.156154 -321.383406) (xy 155.154122 -321.403472)
			(xy 155.15717 -321.413378) (xy 155.167485 -321.449592) (xy 155.178584 -321.524066) (xy 155.179268 -321.561714)
			(xy 155.178705 -321.596273) (xy 155.169359 -321.664756) (xy 155.150829 -321.731343) (xy 155.123454 -321.794809)
			(xy 155.092008 -321.846913) (xy 156.657288 -321.846913) (xy 156.657288 -321.782991) (xy 156.665299 -321.719573)
			(xy 156.681196 -321.657659) (xy 156.704728 -321.598226) (xy 156.735522 -321.542211) (xy 156.773095 -321.490496)
			(xy 156.816852 -321.443899) (xy 156.866105 -321.403154) (xy 156.920076 -321.368903) (xy 156.977915 -321.341686)
			(xy 157.038708 -321.321933) (xy 157.101498 -321.309955) (xy 157.165294 -321.305942) (xy 157.22909 -321.309955)
			(xy 157.29188 -321.321933) (xy 157.352673 -321.341686) (xy 157.410512 -321.368903) (xy 157.464483 -321.403154)
			(xy 157.513736 -321.443899) (xy 157.557493 -321.490496) (xy 157.595066 -321.542211) (xy 157.62586 -321.598226)
			(xy 157.649392 -321.657659) (xy 157.665289 -321.719573) (xy 157.6733 -321.782991) (xy 157.673802 -321.814952)
			(xy 157.6733 -321.846913) (xy 157.665289 -321.910331) (xy 157.649392 -321.972245) (xy 157.62586 -322.031678)
			(xy 157.595066 -322.087693) (xy 157.557493 -322.139408) (xy 157.513736 -322.186005) (xy 157.464483 -322.22675)
			(xy 157.410512 -322.261001) (xy 157.352673 -322.288218) (xy 157.29188 -322.307971) (xy 157.22909 -322.319949)
			(xy 157.165294 -322.323963) (xy 157.101498 -322.319949) (xy 157.038708 -322.307971) (xy 156.977915 -322.288218)
			(xy 156.920076 -322.261001) (xy 156.866105 -322.22675) (xy 156.816852 -322.186005) (xy 156.773095 -322.139408)
			(xy 156.735522 -322.087693) (xy 156.704728 -322.031678) (xy 156.681196 -321.972245) (xy 156.665299 -321.910331)
			(xy 156.657288 -321.846913) (xy 155.092008 -321.846913) (xy 155.08774 -321.853985) (xy 155.066492 -321.881246)
			(xy 155.057602 -321.892168) (xy 155.053538 -321.919346) (xy 155.098496 -322.028058) (xy 155.120594 -322.044568)
			(xy 155.134564 -322.046092) (xy 155.165339 -322.04993) (xy 155.225736 -322.064016) (xy 155.28397 -322.085346)
			(xy 155.339176 -322.113604) (xy 155.390533 -322.148369) (xy 155.437279 -322.189124) (xy 155.478718 -322.235265)
			(xy 155.514236 -322.286105) (xy 155.543303 -322.340889) (xy 155.565489 -322.398803) (xy 155.580462 -322.458985)
			(xy 155.588002 -322.520543) (xy 155.588462 -322.551552) (xy 155.58796 -322.583513) (xy 155.579949 -322.646931)
			(xy 155.564052 -322.708845) (xy 155.54052 -322.768278) (xy 155.509726 -322.824293) (xy 155.472153 -322.876008)
			(xy 155.428396 -322.922605) (xy 155.379143 -322.96335) (xy 155.325172 -322.997601) (xy 155.267333 -323.024818)
			(xy 155.20654 -323.044571) (xy 155.14375 -323.056549) (xy 155.079954 -323.060563) (xy 155.016158 -323.056549)
			(xy 154.953368 -323.044571) (xy 154.892575 -323.024818) (xy 154.834736 -322.997601) (xy 154.780765 -322.96335)
			(xy 154.731512 -322.922605) (xy 154.687755 -322.876008) (xy 154.650182 -322.824293) (xy 154.619388 -322.768278)
			(xy 154.595856 -322.708845) (xy 154.579959 -322.646931) (xy 154.571948 -322.583513) (xy 154.571446 -322.551552)
			(xy 154.572009 -322.516993) (xy 154.581357 -322.448511) (xy 154.599889 -322.381924) (xy 154.627263 -322.318459)
			(xy 154.662976 -322.259282) (xy 154.684222 -322.23202) (xy 154.693112 -322.221098) (xy 154.697176 -322.19392)
			(xy 154.652218 -322.085208) (xy 154.63012 -322.068698) (xy 154.61615 -322.067174) (xy 154.582097 -322.06296)
			(xy 154.515484 -322.046506) (xy 154.451693 -322.021231) (xy 154.391888 -321.987593) (xy 154.364182 -321.967352)
			(xy 154.355038 -321.960494) (xy 154.332686 -321.955922) (xy 154.233626 -321.980306) (xy 154.215846 -321.994784)
			(xy 154.21102 -322.005198) (xy 154.199131 -322.029428) (xy 154.169527 -322.074556) (xy 154.133855 -322.115058)
			(xy 154.092829 -322.150126) (xy 154.047267 -322.179057) (xy 153.998081 -322.201275) (xy 153.946253 -322.216335)
			(xy 153.89282 -322.223937) (xy 153.865834 -322.2244) (xy 153.838579 -322.223955) (xy 153.784623 -322.216202)
			(xy 153.73232 -322.200848) (xy 153.682735 -322.178207) (xy 153.636876 -322.14874) (xy 153.595679 -322.113045)
			(xy 153.559981 -322.071851) (xy 153.530509 -322.025995) (xy 153.507864 -321.976412) (xy 153.492505 -321.92411)
			(xy 153.484747 -321.870155) (xy 153.484747 -321.815645) (xy 153.492505 -321.76169) (xy 153.507864 -321.709388)
			(xy 153.530509 -321.659805) (xy 153.559981 -321.613949) (xy 153.595679 -321.572755) (xy 153.636876 -321.53706)
			(xy 153.682735 -321.507593) (xy 153.73232 -321.484952) (xy 153.784623 -321.469598) (xy 153.838579 -321.461845)
			(xy 153.865834 -321.461384) (xy 153.895013 -321.461893) (xy 153.952695 -321.470747) (xy 154.008349 -321.488305)
			(xy 154.034744 -321.500754) (xy 154.045158 -321.506088) (xy 154.068018 -321.506342) (xy 154.160728 -321.463924)
			(xy 154.17546 -321.446144) (xy 154.178254 -321.434968) (xy 154.181048 -321.4243) (xy 154.185112 -321.41033)
			(xy 154.177238 -321.382898) (xy 154.088846 -321.302126) (xy 154.060652 -321.296792) (xy 154.04719 -321.301872)
			(xy 154.018149 -321.312495) (xy 153.958134 -321.327405) (xy 153.896754 -321.33493) (xy 153.865834 -321.3354)
			(xy 153.83429 -321.334968) (xy 153.771687 -321.327169) (xy 153.71053 -321.311686) (xy 153.651757 -321.288757)
			(xy 153.596272 -321.258734) (xy 153.544927 -321.222079) (xy 153.49851 -321.179354) (xy 153.457734 -321.131216)
			(xy 153.423225 -321.078404) (xy 153.395515 -321.021728) (xy 153.375027 -320.962061) (xy 153.362078 -320.900317)
			(xy 153.356865 -320.837446) (xy 153.359469 -320.774413) (xy 153.369849 -320.712186) (xy 153.387848 -320.65172)
			(xy 153.413187 -320.593946) (xy 153.445478 -320.539749) (xy 153.484224 -320.489963) (xy 153.528832 -320.445352)
			(xy 153.578615 -320.406601) (xy 153.632809 -320.374306) (xy 153.690581 -320.348962) (xy 153.751045 -320.330959)
			(xy 153.813271 -320.320573) (xy 153.876304 -320.317964) (xy 153.939175 -320.323172) (xy 154.00092 -320.336116)
			(xy 154.060589 -320.356599) (xy 154.117267 -320.384305) (xy 154.170082 -320.418809) (xy 154.218224 -320.45958)
			(xy 154.260953 -320.505994) (xy 154.297612 -320.557336) (xy 154.327639 -320.612819) (xy 154.350573 -320.67159)
			(xy 154.366061 -320.732746) (xy 154.373866 -320.795349) (xy 154.374342 -320.826892) (xy 154.373767 -320.861687)
			(xy 154.364338 -320.930635) (xy 154.355546 -320.964306) (xy 154.351482 -320.978276) (xy 154.359356 -321.005708)
			(xy 154.447748 -321.08648) (xy 154.475942 -321.091814) (xy 154.489404 -321.086734) (xy 154.525472 -321.074288)
			(xy 154.535124 -321.071494) (xy 154.550872 -321.058794) (xy 154.59456 -320.97726) (xy 154.596592 -320.957194)
			(xy 154.593544 -320.947288) (xy 154.58322 -320.911076) (xy 154.572127 -320.836601) (xy 154.571446 -320.798952)
			(xy 154.572005 -320.765511) (xy 154.580771 -320.699205) (xy 154.598159 -320.634622) (xy 154.623867 -320.572878)
			(xy 154.657453 -320.51504) (xy 154.698335 -320.462107) (xy 154.745807 -320.414993) (xy 154.772106 -320.39433)
			(xy 154.78506 -320.384424) (xy 154.794712 -320.353182) (xy 154.758644 -320.246502) (xy 154.754742 -320.236646)
			(xy 154.740537 -320.220954) (xy 154.721218 -320.212306) (xy 154.710638 -320.211704) (xy 151.722074 -320.211704)
			(xy 151.71234 -320.212183) (xy 151.694293 -320.219494) (xy 151.680251 -320.232983) (xy 151.675846 -320.241676)
			(xy 151.63165 -320.339974) (xy 151.635968 -320.369438) (xy 151.645874 -320.380614) (xy 151.665565 -320.403503)
			(xy 151.699973 -320.453121) (xy 151.728254 -320.506469) (xy 151.750008 -320.562795) (xy 151.757888 -320.591942)
			(xy 151.760618 -320.600987) (xy 151.771578 -320.616361) (xy 151.779224 -320.621914) (xy 151.804878 -320.638678)
			(xy 151.812965 -320.643493) (xy 151.831331 -320.647531) (xy 151.840692 -320.646552) (xy 151.860497 -320.643583)
			(xy 151.900422 -320.640404) (xy 151.920448 -320.640202) (xy 151.952408 -320.640687) (xy 152.015822 -320.648704)
			(xy 152.077733 -320.664605) (xy 152.137162 -320.688139) (xy 152.193173 -320.718936) (xy 152.244883 -320.75651)
			(xy 152.291476 -320.800268) (xy 152.332218 -320.849521) (xy 152.366465 -320.903491) (xy 152.39368 -320.961328)
			(xy 152.413431 -321.022119) (xy 152.425407 -321.084907) (xy 152.429421 -321.1487) (xy 152.425407 -321.212493)
			(xy 152.413431 -321.275281) (xy 152.39368 -321.336072) (xy 152.366465 -321.393909) (xy 152.332218 -321.447879)
			(xy 152.291476 -321.497132) (xy 152.244883 -321.54089) (xy 152.193173 -321.578464) (xy 152.137162 -321.609261)
			(xy 152.077733 -321.632795) (xy 152.015822 -321.648696) (xy 151.952408 -321.656713) (xy 151.920448 -321.657218)
			(xy 151.896099 -321.65691) (xy 151.847628 -321.652199) (xy 151.823674 -321.64782) (xy 151.812244 -321.645788)
			(xy 151.790908 -321.651122) (xy 151.712676 -321.714114) (xy 151.703024 -321.733926) (xy 151.702516 -321.745356)
			(xy 151.701468 -321.773766) (xy 151.693866 -321.830109) (xy 151.680036 -321.885254) (xy 151.66015 -321.938515)
			(xy 151.647652 -321.96405) (xy 151.642064 -321.974718) (xy 151.642064 -321.99834) (xy 151.688546 -322.093082)
			(xy 151.707342 -322.10756) (xy 151.71928 -322.109846) (xy 151.750578 -322.116289) (xy 151.811352 -322.136042)
			(xy 151.86917 -322.163257) (xy 151.92312 -322.197504) (xy 151.972353 -322.238243) (xy 152.016091 -322.284833)
			(xy 152.053644 -322.336537) (xy 152.08442 -322.39254) (xy 152.107933 -322.45196) (xy 152.123814 -322.513858)
			(xy 152.13181 -322.577259) (xy 152.132284 -322.60921) (xy 152.131782 -322.641171) (xy 152.123771 -322.704589)
			(xy 152.107874 -322.766503) (xy 152.084342 -322.825936) (xy 152.053548 -322.881951) (xy 152.015975 -322.933666)
			(xy 151.972218 -322.980263) (xy 151.922965 -323.021008) (xy 151.868994 -323.055259) (xy 151.811155 -323.082476)
			(xy 151.750362 -323.102229) (xy 151.687572 -323.114207) (xy 151.623776 -323.118221) (xy 151.55998 -323.114207)
			(xy 151.49719 -323.102229) (xy 151.436397 -323.082476) (xy 151.378558 -323.055259) (xy 151.324587 -323.021008)
			(xy 151.275334 -322.980263) (xy 151.231577 -322.933666) (xy 151.194004 -322.881951) (xy 151.16321 -322.825936)
			(xy 151.139678 -322.766503) (xy 151.123781 -322.704589) (xy 151.11577 -322.641171) (xy 151.115268 -322.60921)
			(xy 151.115663 -322.579315) (xy 151.122652 -322.519934) (xy 151.136569 -322.461786) (xy 151.157222 -322.405676)
			(xy 151.170386 -322.378832) (xy 151.175974 -322.368164) (xy 151.175974 -322.344542) (xy 151.129492 -322.2498)
			(xy 151.110696 -322.235322) (xy 151.098758 -322.233036) (xy 151.067473 -322.226541) (xy 151.006707 -322.206786)
			(xy 150.948896 -322.179572) (xy 150.894951 -322.145327) (xy 150.845723 -322.104592) (xy 150.801989 -322.058008)
			(xy 150.764437 -322.006311) (xy 150.73366 -321.950315) (xy 150.710144 -321.890903) (xy 150.694258 -321.829013)
			(xy 150.686254 -321.76562) (xy 150.685754 -321.733672) (xy 150.68633 -321.700062) (xy 150.695186 -321.633426)
			(xy 150.712738 -321.568537) (xy 150.738682 -321.506525) (xy 150.772566 -321.448469) (xy 150.8138 -321.39538)
			(xy 150.861665 -321.348182) (xy 150.915328 -321.307699) (xy 150.944326 -321.290696) (xy 150.955502 -321.284346)
			(xy 150.969218 -321.26301) (xy 150.976838 -321.15252) (xy 150.966424 -321.129406) (xy 150.956264 -321.121532)
			(xy 150.930103 -321.10084) (xy 150.882861 -321.053753) (xy 150.842183 -321.000893) (xy 150.808767 -320.943166)
			(xy 150.783186 -320.881566) (xy 150.765882 -320.817149) (xy 150.75715 -320.751022) (xy 150.75662 -320.717672)
			(xy 150.757043 -320.686291) (xy 150.764752 -320.624006) (xy 150.780073 -320.563143) (xy 150.802773 -320.504631)
			(xy 150.832507 -320.449361) (xy 150.868821 -320.398173) (xy 150.911164 -320.351847) (xy 150.958889 -320.311089)
			(xy 151.011271 -320.27652) (xy 151.067512 -320.248665) (xy 151.09698 -320.237866) (xy 151.10968 -320.233294)
			(xy 151.126698 -320.21399) (xy 151.148796 -320.117216) (xy 151.150419 -320.108793) (xy 151.148541 -320.091751)
			(xy 151.141144 -320.076284) (xy 151.135334 -320.069972) (xy 151.055578 -319.990216) (xy 151.048843 -319.982822)
			(xy 151.04113 -319.964389) (xy 151.040592 -319.954402) (xy 151.040592 -319.876678) (xy 151.037798 -319.86474)
			(xy 151.03475 -319.858898) (xy 151.020393 -319.830935) (xy 151.000032 -319.771472) (xy 150.989691 -319.709476)
			(xy 150.98903 -319.67805) (xy 150.989685 -319.646624) (xy 151.000029 -319.584628) (xy 151.020395 -319.525166)
			(xy 151.03475 -319.497202) (xy 151.037798 -319.49136) (xy 151.040592 -319.479422) (xy 151.040592 -319.434972)
			(xy 151.040214 -319.424928) (xy 151.032631 -319.406332) (xy 151.02586 -319.398904) (xy 150.87473 -319.247774)
			(xy 150.867317 -319.240951) (xy 150.848727 -319.233222) (xy 150.838662 -319.232788) (xy 147.124928 -319.232788)
			(xy 147.114963 -319.2323) (xy 147.096527 -319.224732) (xy 147.089114 -319.218056) (xy 146.464274 -318.593216)
			(xy 146.457538 -318.585822) (xy 146.449826 -318.56739) (xy 146.449288 -318.557402) (xy 146.449288 -316.108334)
			(xy 146.448526 -316.08395) (xy 128.59639 -316.08395) (xy 128.59639 -317.382144) (xy 143.66824 -317.382144)
			(xy 143.672311 -317.326522) (xy 143.684437 -317.272085) (xy 143.70436 -317.219994) (xy 143.731656 -317.171359)
			(xy 143.765742 -317.127216) (xy 143.805891 -317.088507) (xy 143.851249 -317.056056) (xy 143.900849 -317.030555)
			(xy 143.953633 -317.012548) (xy 144.008476 -317.002418) (xy 144.06421 -317.000381) (xy 144.119647 -317.006481)
			(xy 144.173604 -317.020587) (xy 144.224933 -317.042399) (xy 144.272539 -317.071453) (xy 144.315407 -317.107128)
			(xy 144.352624 -317.148665) (xy 144.383397 -317.195178) (xy 144.407069 -317.245675) (xy 144.423137 -317.299082)
			(xy 144.431257 -317.354258) (xy 144.431766 -317.382144) (xy 144.431257 -317.41003) (xy 144.423137 -317.465206)
			(xy 144.407069 -317.518613) (xy 144.383397 -317.56911) (xy 144.352624 -317.615623) (xy 144.315407 -317.65716)
			(xy 144.272539 -317.692835) (xy 144.224933 -317.721889) (xy 144.173604 -317.743701) (xy 144.119647 -317.757807)
			(xy 144.06421 -317.763907) (xy 144.008476 -317.76187) (xy 143.953633 -317.75174) (xy 143.900849 -317.733733)
			(xy 143.851249 -317.708232) (xy 143.805891 -317.675781) (xy 143.765742 -317.637072) (xy 143.731656 -317.592929)
			(xy 143.70436 -317.544294) (xy 143.684437 -317.492203) (xy 143.672311 -317.437766) (xy 143.66824 -317.382144)
			(xy 128.59639 -317.382144) (xy 128.59639 -320.804032) (xy 144.468342 -320.804032) (xy 144.468895 -320.770483)
			(xy 144.47772 -320.703967) (xy 144.495221 -320.639191) (xy 144.521094 -320.577281) (xy 144.554888 -320.519314)
			(xy 144.596015 -320.466298) (xy 144.643762 -320.419154) (xy 144.697296 -320.378704) (xy 144.755688 -320.345649)
			(xy 144.786604 -320.332608) (xy 144.79946 -320.326889) (xy 144.821654 -320.309612) (xy 144.838297 -320.286938)
			(xy 144.848126 -320.260585) (xy 144.850396 -320.232551) (xy 144.844936 -320.20496) (xy 144.832159 -320.179903)
			(xy 144.822926 -320.169286) (xy 144.803964 -320.147972) (xy 144.77187 -320.100811) (xy 144.74715 -320.0494)
			(xy 144.730356 -319.994883) (xy 144.72186 -319.938474) (xy 144.721326 -319.909952) (xy 144.721812 -319.882701)
			(xy 144.729568 -319.828753) (xy 144.744923 -319.776458) (xy 144.767565 -319.726881) (xy 144.797031 -319.681031)
			(xy 144.832722 -319.63984) (xy 144.873913 -319.604149) (xy 144.919763 -319.574683) (xy 144.96934 -319.552041)
			(xy 145.021635 -319.536686) (xy 145.075583 -319.52893) (xy 145.130085 -319.52893) (xy 145.184033 -319.536686)
			(xy 145.236328 -319.552041) (xy 145.285905 -319.574683) (xy 145.331755 -319.604149) (xy 145.372946 -319.63984)
			(xy 145.408637 -319.681031) (xy 145.438103 -319.726881) (xy 145.460745 -319.776458) (xy 145.4761 -319.828753)
			(xy 145.483856 -319.882701) (xy 145.484342 -319.909952) (xy 145.483827 -319.937963) (xy 145.475646 -319.993385)
			(xy 145.459452 -320.047015) (xy 145.435592 -320.097703) (xy 145.40458 -320.144359) (xy 145.367082 -320.185981)
			(xy 145.323903 -320.221675) (xy 145.300192 -320.236596) (xy 145.288354 -320.244195) (xy 145.269148 -320.264741)
			(xy 145.256279 -320.289748) (xy 145.250724 -320.317318) (xy 145.252905 -320.345357) (xy 145.262655 -320.371737)
			(xy 145.279235 -320.394454) (xy 145.290032 -320.403474) (xy 145.315666 -320.424202) (xy 145.361924 -320.471172)
			(xy 145.401723 -320.523726) (xy 145.434397 -320.580983) (xy 145.459396 -320.641982) (xy 145.476302 -320.705701)
			(xy 145.484831 -320.77107) (xy 145.485358 -320.804032) (xy 145.484856 -320.835993) (xy 145.476845 -320.899411)
			(xy 145.460948 -320.961325) (xy 145.437416 -321.020758) (xy 145.406622 -321.076773) (xy 145.400708 -321.084913)
			(xy 147.896828 -321.084913) (xy 147.896828 -321.020991) (xy 147.904839 -320.957573) (xy 147.920736 -320.895659)
			(xy 147.944268 -320.836226) (xy 147.975062 -320.780211) (xy 148.012635 -320.728496) (xy 148.056392 -320.681899)
			(xy 148.105645 -320.641154) (xy 148.159616 -320.606903) (xy 148.217455 -320.579686) (xy 148.278248 -320.559933)
			(xy 148.341038 -320.547955) (xy 148.404834 -320.543942) (xy 148.46863 -320.547955) (xy 148.53142 -320.559933)
			(xy 148.592213 -320.579686) (xy 148.650052 -320.606903) (xy 148.704023 -320.641154) (xy 148.753276 -320.681899)
			(xy 148.797033 -320.728496) (xy 148.834606 -320.780211) (xy 148.8654 -320.836226) (xy 148.888932 -320.895659)
			(xy 148.904829 -320.957573) (xy 148.91284 -321.020991) (xy 148.913342 -321.052952) (xy 148.91284 -321.084913)
			(xy 148.904829 -321.148331) (xy 148.888932 -321.210245) (xy 148.8654 -321.269678) (xy 148.834606 -321.325693)
			(xy 148.797033 -321.377408) (xy 148.753276 -321.424005) (xy 148.704023 -321.46475) (xy 148.650052 -321.499001)
			(xy 148.592213 -321.526218) (xy 148.53142 -321.545971) (xy 148.46863 -321.557949) (xy 148.404834 -321.561963)
			(xy 148.341038 -321.557949) (xy 148.278248 -321.545971) (xy 148.217455 -321.526218) (xy 148.159616 -321.499001)
			(xy 148.105645 -321.46475) (xy 148.056392 -321.424005) (xy 148.012635 -321.377408) (xy 147.975062 -321.325693)
			(xy 147.944268 -321.269678) (xy 147.920736 -321.210245) (xy 147.904839 -321.148331) (xy 147.896828 -321.084913)
			(xy 145.400708 -321.084913) (xy 145.369049 -321.128488) (xy 145.325292 -321.175085) (xy 145.276039 -321.21583)
			(xy 145.222068 -321.250081) (xy 145.164229 -321.277298) (xy 145.103436 -321.297051) (xy 145.040646 -321.309029)
			(xy 144.97685 -321.313043) (xy 144.913054 -321.309029) (xy 144.850264 -321.297051) (xy 144.789471 -321.277298)
			(xy 144.731632 -321.250081) (xy 144.677661 -321.21583) (xy 144.628408 -321.175085) (xy 144.584651 -321.128488)
			(xy 144.547078 -321.076773) (xy 144.516284 -321.020758) (xy 144.492752 -320.961325) (xy 144.476855 -320.899411)
			(xy 144.468844 -320.835993) (xy 144.468342 -320.804032) (xy 128.59639 -320.804032) (xy 128.59639 -324.720669)
			(xy 153.57322 -324.720669) (xy 153.57322 -324.656747) (xy 153.581231 -324.593329) (xy 153.597128 -324.531415)
			(xy 153.62066 -324.471982) (xy 153.651454 -324.415967) (xy 153.689027 -324.364252) (xy 153.732784 -324.317655)
			(xy 153.782037 -324.27691) (xy 153.836008 -324.242659) (xy 153.893847 -324.215442) (xy 153.95464 -324.195689)
			(xy 154.01743 -324.183711) (xy 154.081226 -324.179698) (xy 154.145022 -324.183711) (xy 154.207812 -324.195689)
			(xy 154.268605 -324.215442) (xy 154.326444 -324.242659) (xy 154.380415 -324.27691) (xy 154.429668 -324.317655)
			(xy 154.473425 -324.364252) (xy 154.510998 -324.415967) (xy 154.541792 -324.471982) (xy 154.565324 -324.531415)
			(xy 154.581221 -324.593329) (xy 154.589232 -324.656747) (xy 154.589734 -324.688708) (xy 154.589232 -324.720669)
			(xy 154.581221 -324.784087) (xy 154.573635 -324.813633) (xy 156.657288 -324.813633) (xy 156.657288 -324.749711)
			(xy 156.665299 -324.686293) (xy 156.681196 -324.624379) (xy 156.704728 -324.564946) (xy 156.735522 -324.508931)
			(xy 156.773095 -324.457216) (xy 156.816852 -324.410619) (xy 156.866105 -324.369874) (xy 156.920076 -324.335623)
			(xy 156.977915 -324.308406) (xy 157.038708 -324.288653) (xy 157.101498 -324.276675) (xy 157.165294 -324.272662)
			(xy 157.22909 -324.276675) (xy 157.29188 -324.288653) (xy 157.352673 -324.308406) (xy 157.410512 -324.335623)
			(xy 157.464483 -324.369874) (xy 157.513736 -324.410619) (xy 157.518666 -324.415869) (xy 160.805362 -324.415869)
			(xy 160.805362 -324.351947) (xy 160.813373 -324.288529) (xy 160.82927 -324.226615) (xy 160.852802 -324.167182)
			(xy 160.883596 -324.111167) (xy 160.921169 -324.059452) (xy 160.964926 -324.012855) (xy 161.014179 -323.97211)
			(xy 161.06815 -323.937859) (xy 161.125989 -323.910642) (xy 161.186782 -323.890889) (xy 161.249572 -323.878911)
			(xy 161.313368 -323.874898) (xy 161.377164 -323.878911) (xy 161.439954 -323.890889) (xy 161.500747 -323.910642)
			(xy 161.558586 -323.937859) (xy 161.612557 -323.97211) (xy 161.66181 -324.012855) (xy 161.705567 -324.059452)
			(xy 161.74314 -324.111167) (xy 161.773934 -324.167182) (xy 161.797466 -324.226615) (xy 161.813363 -324.288529)
			(xy 161.821374 -324.351947) (xy 161.821876 -324.383908) (xy 161.821374 -324.415869) (xy 161.813363 -324.479287)
			(xy 161.798981 -324.5353) (xy 164.610084 -324.5353) (xy 164.614076 -324.446415) (xy 164.626019 -324.358246)
			(xy 164.645817 -324.271502) (xy 164.673311 -324.186882) (xy 164.708279 -324.105067) (xy 164.75044 -324.026716)
			(xy 164.799454 -323.952459) (xy 164.854928 -323.882895) (xy 164.916413 -323.818583) (xy 164.983415 -323.760042)
			(xy 165.055396 -323.707742) (xy 165.131774 -323.662104) (xy 165.211936 -323.623497) (xy 165.295236 -323.59223)
			(xy 165.381003 -323.568556) (xy 165.468547 -323.552665) (xy 165.557163 -323.544685) (xy 165.60165 -323.544184)
			(xy 167.35425 -323.544184) (xy 167.39874 -323.544682) (xy 167.487362 -323.552654) (xy 167.574913 -323.568538)
			(xy 167.660688 -323.592207) (xy 167.743995 -323.623469) (xy 167.824165 -323.662073) (xy 167.900551 -323.707708)
			(xy 167.972539 -323.760007) (xy 168.039549 -323.818549) (xy 168.101041 -323.882862) (xy 168.156521 -323.952428)
			(xy 168.205541 -324.026687) (xy 168.247707 -324.105042) (xy 168.28268 -324.186861) (xy 168.310177 -324.271486)
			(xy 168.329977 -324.358235) (xy 168.341922 -324.44641) (xy 168.345914 -324.5353) (xy 172.15407 -324.5353)
			(xy 172.158062 -324.446411) (xy 172.170006 -324.358237) (xy 172.189806 -324.271489) (xy 172.217302 -324.186865)
			(xy 172.252273 -324.105047) (xy 172.294437 -324.026693) (xy 172.343455 -323.952433) (xy 172.398933 -323.882867)
			(xy 172.460423 -323.818554) (xy 172.527431 -323.760011) (xy 172.599416 -323.707711) (xy 172.6758 -323.662074)
			(xy 172.755967 -323.623468) (xy 172.839273 -323.592203) (xy 172.925045 -323.568531) (xy 173.012594 -323.552644)
			(xy 173.101215 -323.544668) (xy 173.145704 -323.544184) (xy 174.898304 -323.544184) (xy 174.942792 -323.544699)
			(xy 175.031409 -323.552675) (xy 175.118955 -323.568563) (xy 175.204724 -323.592234) (xy 175.288026 -323.623498)
			(xy 175.36819 -323.662103) (xy 175.444571 -323.707739) (xy 175.516554 -323.760038) (xy 175.583559 -323.818578)
			(xy 175.645046 -323.88289) (xy 175.700522 -323.952454) (xy 175.749538 -324.026711) (xy 175.791701 -324.105062)
			(xy 175.82667 -324.186878) (xy 175.854165 -324.271499) (xy 175.873964 -324.358244) (xy 175.885908 -324.446414)
			(xy 175.8899 -324.5353) (xy 179.698184 -324.5353) (xy 179.702176 -324.446415) (xy 179.714119 -324.358245)
			(xy 179.733918 -324.271501) (xy 179.761412 -324.18688) (xy 179.79638 -324.105065) (xy 179.838541 -324.026713)
			(xy 179.887556 -323.952457) (xy 179.94303 -323.882892) (xy 180.004516 -323.81858) (xy 180.071519 -323.760039)
			(xy 180.1435 -323.707739) (xy 180.219879 -323.662101) (xy 180.300042 -323.623494) (xy 180.383342 -323.592228)
			(xy 180.46911 -323.568554) (xy 180.556654 -323.552664) (xy 180.645271 -323.544685) (xy 180.689758 -323.544184)
			(xy 182.442358 -323.544184) (xy 182.486848 -323.544683) (xy 182.57547 -323.552655) (xy 182.66302 -323.56854)
			(xy 182.748794 -323.592209) (xy 182.8321 -323.623471) (xy 182.912269 -323.662075) (xy 182.988655 -323.707711)
			(xy 183.060642 -323.76001) (xy 183.127652 -323.818552) (xy 183.189144 -323.882864) (xy 183.244623 -323.95243)
			(xy 183.293642 -324.02669) (xy 183.335808 -324.105044) (xy 183.37078 -324.186863) (xy 183.398277 -324.271487)
			(xy 183.418077 -324.358236) (xy 183.430022 -324.44641) (xy 183.434014 -324.5353) (xy 187.24217 -324.5353)
			(xy 187.246162 -324.44641) (xy 187.258106 -324.358236) (xy 187.277906 -324.271488) (xy 187.305402 -324.186864)
			(xy 187.340374 -324.105045) (xy 187.382539 -324.02669) (xy 187.431557 -323.952431) (xy 187.487035 -323.882864)
			(xy 187.548526 -323.818551) (xy 187.615534 -323.760008) (xy 187.68752 -323.707708) (xy 187.763905 -323.662071)
			(xy 187.844073 -323.623465) (xy 187.927379 -323.592201) (xy 188.013152 -323.56853) (xy 188.100701 -323.552643)
			(xy 188.189322 -323.544668) (xy 188.233812 -323.544184) (xy 189.986412 -323.544184) (xy 190.0309 -323.544699)
			(xy 190.119517 -323.552676) (xy 190.207062 -323.568564) (xy 190.29283 -323.592236) (xy 190.376132 -323.6235)
			(xy 190.456295 -323.662106) (xy 190.532675 -323.707742) (xy 190.604658 -323.760041) (xy 190.671662 -323.818581)
			(xy 190.733149 -323.882892) (xy 190.788624 -323.952456) (xy 190.83764 -324.026713) (xy 190.879802 -324.105064)
			(xy 190.914771 -324.186879) (xy 190.942266 -324.2715) (xy 190.962064 -324.358244) (xy 190.974008 -324.446414)
			(xy 190.978 -324.5353) (xy 190.974008 -324.624186) (xy 190.962064 -324.712356) (xy 190.942266 -324.7991)
			(xy 190.914771 -324.883721) (xy 190.879802 -324.965536) (xy 190.83764 -325.043887) (xy 190.788624 -325.118144)
			(xy 190.733149 -325.187708) (xy 190.671662 -325.252019) (xy 190.604658 -325.310559) (xy 190.532675 -325.362858)
			(xy 190.456295 -325.408494) (xy 190.376132 -325.4471) (xy 190.29283 -325.478364) (xy 190.207062 -325.502036)
			(xy 190.119517 -325.517924) (xy 190.0309 -325.525901) (xy 189.986412 -325.5264) (xy 188.233812 -325.5264)
			(xy 188.189322 -325.525932) (xy 188.100701 -325.517957) (xy 188.013152 -325.50207) (xy 187.927379 -325.478399)
			(xy 187.844073 -325.447135) (xy 187.763905 -325.408529) (xy 187.68752 -325.362892) (xy 187.615534 -325.310592)
			(xy 187.548526 -325.252049) (xy 187.487035 -325.187736) (xy 187.431557 -325.118169) (xy 187.382539 -325.04391)
			(xy 187.340374 -324.965555) (xy 187.305402 -324.883736) (xy 187.277906 -324.799112) (xy 187.258106 -324.712364)
			(xy 187.246162 -324.62419) (xy 187.24217 -324.5353) (xy 183.434014 -324.5353) (xy 183.430022 -324.62419)
			(xy 183.418077 -324.712364) (xy 183.398277 -324.799113) (xy 183.37078 -324.883737) (xy 183.335808 -324.965556)
			(xy 183.293642 -325.04391) (xy 183.244623 -325.11817) (xy 183.189144 -325.187736) (xy 183.127652 -325.252048)
			(xy 183.060642 -325.31059) (xy 182.988655 -325.362889) (xy 182.912269 -325.408525) (xy 182.8321 -325.447129)
			(xy 182.748794 -325.478391) (xy 182.66302 -325.50206) (xy 182.57547 -325.517945) (xy 182.486848 -325.525917)
			(xy 182.442358 -325.5264) (xy 180.689758 -325.5264) (xy 180.645271 -325.525915) (xy 180.556654 -325.517936)
			(xy 180.46911 -325.502046) (xy 180.383342 -325.478372) (xy 180.300042 -325.447106) (xy 180.219879 -325.408499)
			(xy 180.1435 -325.362861) (xy 180.071519 -325.310561) (xy 180.004516 -325.25202) (xy 179.94303 -325.187708)
			(xy 179.887556 -325.118143) (xy 179.838541 -325.043887) (xy 179.79638 -324.965535) (xy 179.761412 -324.88372)
			(xy 179.733918 -324.799099) (xy 179.714119 -324.712355) (xy 179.702176 -324.624185) (xy 179.698184 -324.5353)
			(xy 175.8899 -324.5353) (xy 175.885908 -324.624186) (xy 175.873964 -324.712356) (xy 175.854165 -324.799101)
			(xy 175.82667 -324.883722) (xy 175.791701 -324.965538) (xy 175.749538 -325.043889) (xy 175.700522 -325.118146)
			(xy 175.645046 -325.18771) (xy 175.583559 -325.252022) (xy 175.516554 -325.310562) (xy 175.444571 -325.362861)
			(xy 175.36819 -325.408497) (xy 175.288026 -325.447102) (xy 175.204724 -325.478366) (xy 175.118955 -325.502037)
			(xy 175.031409 -325.517925) (xy 174.942792 -325.525901) (xy 174.898304 -325.5264) (xy 173.145704 -325.5264)
			(xy 173.101215 -325.525932) (xy 173.012594 -325.517956) (xy 172.925045 -325.502069) (xy 172.839273 -325.478397)
			(xy 172.755967 -325.447132) (xy 172.6758 -325.408526) (xy 172.599416 -325.362889) (xy 172.527431 -325.310589)
			(xy 172.460423 -325.252046) (xy 172.398933 -325.187733) (xy 172.343455 -325.118167) (xy 172.294437 -325.043907)
			(xy 172.252273 -324.965553) (xy 172.217302 -324.883735) (xy 172.189806 -324.799111) (xy 172.170006 -324.712363)
			(xy 172.158062 -324.624189) (xy 172.15407 -324.5353) (xy 168.345914 -324.5353) (xy 168.341922 -324.62419)
			(xy 168.329977 -324.712365) (xy 168.310177 -324.799114) (xy 168.28268 -324.883739) (xy 168.247707 -324.965558)
			(xy 168.205541 -325.043913) (xy 168.156521 -325.118172) (xy 168.101041 -325.187738) (xy 168.039549 -325.252051)
			(xy 167.972539 -325.310593) (xy 167.900551 -325.362892) (xy 167.824165 -325.408527) (xy 167.743995 -325.447131)
			(xy 167.660688 -325.478393) (xy 167.574913 -325.502062) (xy 167.487362 -325.517946) (xy 167.39874 -325.525918)
			(xy 167.35425 -325.5264) (xy 165.60165 -325.5264) (xy 165.557163 -325.525915) (xy 165.468547 -325.517935)
			(xy 165.381003 -325.502044) (xy 165.295236 -325.47837) (xy 165.211936 -325.447103) (xy 165.131774 -325.408496)
			(xy 165.055396 -325.362858) (xy 164.983415 -325.310558) (xy 164.916413 -325.252017) (xy 164.854928 -325.187705)
			(xy 164.799454 -325.118141) (xy 164.75044 -325.043884) (xy 164.708279 -324.965533) (xy 164.673311 -324.883718)
			(xy 164.645817 -324.799098) (xy 164.626019 -324.712354) (xy 164.614076 -324.624185) (xy 164.610084 -324.5353)
			(xy 161.798981 -324.5353) (xy 161.797466 -324.541201) (xy 161.773934 -324.600634) (xy 161.74314 -324.656649)
			(xy 161.705567 -324.708364) (xy 161.66181 -324.754961) (xy 161.612557 -324.795706) (xy 161.558586 -324.829957)
			(xy 161.500747 -324.857174) (xy 161.439954 -324.876927) (xy 161.377164 -324.888905) (xy 161.313368 -324.892919)
			(xy 161.249572 -324.888905) (xy 161.186782 -324.876927) (xy 161.125989 -324.857174) (xy 161.06815 -324.829957)
			(xy 161.014179 -324.795706) (xy 160.964926 -324.754961) (xy 160.921169 -324.708364) (xy 160.883596 -324.656649)
			(xy 160.852802 -324.600634) (xy 160.82927 -324.541201) (xy 160.813373 -324.479287) (xy 160.805362 -324.415869)
			(xy 157.518666 -324.415869) (xy 157.557493 -324.457216) (xy 157.595066 -324.508931) (xy 157.62586 -324.564946)
			(xy 157.649392 -324.624379) (xy 157.665289 -324.686293) (xy 157.6733 -324.749711) (xy 157.673802 -324.781672)
			(xy 157.6733 -324.813633) (xy 157.665289 -324.877051) (xy 157.649392 -324.938965) (xy 157.62586 -324.998398)
			(xy 157.595066 -325.054413) (xy 157.557493 -325.106128) (xy 157.513736 -325.152725) (xy 157.464483 -325.19347)
			(xy 157.410512 -325.227721) (xy 157.352673 -325.254938) (xy 157.29188 -325.274691) (xy 157.22909 -325.286669)
			(xy 157.165294 -325.290683) (xy 157.101498 -325.286669) (xy 157.038708 -325.274691) (xy 156.977915 -325.254938)
			(xy 156.920076 -325.227721) (xy 156.866105 -325.19347) (xy 156.816852 -325.152725) (xy 156.773095 -325.106128)
			(xy 156.735522 -325.054413) (xy 156.704728 -324.998398) (xy 156.681196 -324.938965) (xy 156.665299 -324.877051)
			(xy 156.657288 -324.813633) (xy 154.573635 -324.813633) (xy 154.565324 -324.846001) (xy 154.541792 -324.905434)
			(xy 154.510998 -324.961449) (xy 154.473425 -325.013164) (xy 154.429668 -325.059761) (xy 154.380415 -325.100506)
			(xy 154.326444 -325.134757) (xy 154.268605 -325.161974) (xy 154.207812 -325.181727) (xy 154.145022 -325.193705)
			(xy 154.081226 -325.197719) (xy 154.01743 -325.193705) (xy 153.95464 -325.181727) (xy 153.893847 -325.161974)
			(xy 153.836008 -325.134757) (xy 153.782037 -325.100506) (xy 153.732784 -325.059761) (xy 153.689027 -325.013164)
			(xy 153.651454 -324.961449) (xy 153.62066 -324.905434) (xy 153.597128 -324.846001) (xy 153.581231 -324.784087)
			(xy 153.57322 -324.720669) (xy 128.59639 -324.720669) (xy 128.59639 -325.669613) (xy 155.852108 -325.669613)
			(xy 155.852108 -325.605691) (xy 155.860119 -325.542273) (xy 155.876016 -325.480359) (xy 155.899548 -325.420926)
			(xy 155.930342 -325.364911) (xy 155.967915 -325.313196) (xy 156.011672 -325.266599) (xy 156.060925 -325.225854)
			(xy 156.114896 -325.191603) (xy 156.172735 -325.164386) (xy 156.233528 -325.144633) (xy 156.296318 -325.132655)
			(xy 156.360114 -325.128642) (xy 156.42391 -325.132655) (xy 156.4867 -325.144633) (xy 156.547493 -325.164386)
			(xy 156.605332 -325.191603) (xy 156.659303 -325.225854) (xy 156.708556 -325.266599) (xy 156.752313 -325.313196)
			(xy 156.789886 -325.364911) (xy 156.82068 -325.420926) (xy 156.844212 -325.480359) (xy 156.860109 -325.542273)
			(xy 156.86812 -325.605691) (xy 156.868622 -325.637652) (xy 156.86812 -325.669613) (xy 156.860109 -325.733031)
			(xy 156.844212 -325.794945) (xy 156.82068 -325.854378) (xy 156.789886 -325.910393) (xy 156.752313 -325.962108)
			(xy 156.708556 -326.008705) (xy 156.659303 -326.04945) (xy 156.605332 -326.083701) (xy 156.547493 -326.110918)
			(xy 156.4867 -326.130671) (xy 156.42391 -326.142649) (xy 156.360114 -326.146663) (xy 156.296318 -326.142649)
			(xy 156.233528 -326.130671) (xy 156.172735 -326.110918) (xy 156.114896 -326.083701) (xy 156.060925 -326.04945)
			(xy 156.011672 -326.008705) (xy 155.967915 -325.962108) (xy 155.930342 -325.910393) (xy 155.899548 -325.854378)
			(xy 155.876016 -325.794945) (xy 155.860119 -325.733031) (xy 155.852108 -325.669613) (xy 128.59639 -325.669613)
			(xy 128.59639 -327.553828) (xy 150.365206 -327.553828) (xy 150.365667 -327.517078) (xy 150.372769 -327.443921)
			(xy 150.386872 -327.371785) (xy 150.407844 -327.30134) (xy 150.435492 -327.233237) (xy 150.469559 -327.168107)
			(xy 150.50973 -327.106555) (xy 150.532338 -327.077578) (xy 150.538967 -327.06819) (xy 150.54408 -327.045822)
			(xy 150.538986 -327.02345) (xy 150.532338 -327.014078) (xy 150.509698 -326.985122) (xy 150.469494 -326.923583)
			(xy 150.435406 -326.858457) (xy 150.40775 -326.79035) (xy 150.386785 -326.719896) (xy 150.372704 -326.647749)
			(xy 150.365639 -326.574582) (xy 150.365206 -326.537828) (xy 150.365695 -326.499183) (xy 150.373515 -326.422289)
			(xy 150.389073 -326.346581) (xy 150.412211 -326.272835) (xy 150.442691 -326.201808) (xy 150.4802 -326.13423)
			(xy 150.524354 -326.070792) (xy 150.574699 -326.012148) (xy 150.630718 -325.958897) (xy 150.691837 -325.911587)
			(xy 150.75743 -325.870703) (xy 150.826821 -325.836665) (xy 150.899301 -325.809822) (xy 150.974124 -325.790449)
			(xy 151.050523 -325.778745) (xy 151.127714 -325.77483) (xy 151.204905 -325.778745) (xy 151.281304 -325.790449)
			(xy 151.356127 -325.809822) (xy 151.428607 -325.836665) (xy 151.497998 -325.870703) (xy 151.563591 -325.911587)
			(xy 151.62471 -325.958897) (xy 151.680729 -326.012148) (xy 151.731074 -326.070792) (xy 151.775228 -326.13423)
			(xy 151.812737 -326.201808) (xy 151.843217 -326.272835) (xy 151.866355 -326.346581) (xy 151.881913 -326.422289)
			(xy 151.889733 -326.499183) (xy 151.890222 -326.537828) (xy 151.889787 -326.574579) (xy 151.88268 -326.647737)
			(xy 151.868573 -326.719873) (xy 151.847596 -326.790318) (xy 151.819944 -326.858421) (xy 151.785874 -326.92355)
			(xy 151.7457 -326.985102) (xy 151.72309 -327.014078) (xy 151.716418 -327.023437) (xy 151.711328 -327.045822)
			(xy 151.716437 -327.068203) (xy 151.72309 -327.077578) (xy 151.745714 -327.106546) (xy 151.785918 -327.168083)
			(xy 151.820008 -327.233207) (xy 151.847666 -327.301312) (xy 151.868634 -327.371764) (xy 151.882718 -327.443909)
			(xy 151.889787 -327.517075) (xy 151.890222 -327.553828) (xy 151.889733 -327.592473) (xy 151.881913 -327.669367)
			(xy 151.866355 -327.745075) (xy 151.843217 -327.818821) (xy 151.812737 -327.889848) (xy 151.775228 -327.957426)
			(xy 151.731074 -328.020864) (xy 151.680729 -328.079508) (xy 151.62471 -328.132759) (xy 151.563591 -328.180069)
			(xy 151.497998 -328.220953) (xy 151.428607 -328.254991) (xy 151.356127 -328.281834) (xy 151.281304 -328.301207)
			(xy 151.204905 -328.312911) (xy 151.127714 -328.316826) (xy 151.050523 -328.312911) (xy 150.974124 -328.301207)
			(xy 150.899301 -328.281834) (xy 150.826821 -328.254991) (xy 150.75743 -328.220953) (xy 150.691837 -328.180069)
			(xy 150.630718 -328.132759) (xy 150.574699 -328.079508) (xy 150.524354 -328.020864) (xy 150.4802 -327.957426)
			(xy 150.442691 -327.889848) (xy 150.412211 -327.818821) (xy 150.389073 -327.745075) (xy 150.373515 -327.669367)
			(xy 150.365695 -327.592473) (xy 150.365206 -327.553828) (xy 128.59639 -327.553828) (xy 128.59639 -331.522324)
			(xy 174.389796 -331.522324) (xy 174.390335 -331.493586) (xy 174.398954 -331.436759) (xy 174.416001 -331.381869)
			(xy 174.441089 -331.330157) (xy 174.473651 -331.282793) (xy 174.49292 -331.261466) (xy 174.499524 -331.254354)
			(xy 174.506636 -331.236828) (xy 174.506636 -331.14742) (xy 174.499524 -331.129894) (xy 174.49292 -331.122782)
			(xy 174.473673 -331.101435) (xy 174.441107 -331.054075) (xy 174.416015 -331.002367) (xy 174.398963 -330.94748)
			(xy 174.390338 -330.890655) (xy 174.390336 -330.83318) (xy 174.398955 -330.776355) (xy 174.416002 -330.721466)
			(xy 174.44109 -330.669755) (xy 174.473651 -330.622393) (xy 174.49292 -330.601066) (xy 174.499524 -330.593954)
			(xy 174.506636 -330.576428) (xy 174.506636 -330.48702) (xy 174.499524 -330.469494) (xy 174.49292 -330.462382)
			(xy 174.473658 -330.441048) (xy 174.441091 -330.393687) (xy 174.415997 -330.341978) (xy 174.398944 -330.287088)
			(xy 174.390319 -330.230262) (xy 174.389796 -330.201524) (xy 174.390277 -330.174154) (xy 174.398091 -330.119976)
			(xy 174.413577 -330.067473) (xy 174.436415 -330.017726) (xy 174.466136 -329.971758) (xy 174.483776 -329.950826)
			(xy 174.489872 -329.943714) (xy 174.496222 -329.926696) (xy 174.496222 -329.841352) (xy 174.489872 -329.824334)
			(xy 174.483776 -329.817222) (xy 174.46613 -329.796296) (xy 174.43642 -329.750321) (xy 174.413586 -329.700572)
			(xy 174.398096 -329.64807) (xy 174.390269 -329.593893) (xy 174.389796 -329.566524) (xy 174.390282 -329.539273)
			(xy 174.398038 -329.485325) (xy 174.413393 -329.43303) (xy 174.436035 -329.383453) (xy 174.465501 -329.337603)
			(xy 174.501192 -329.296412) (xy 174.542383 -329.260721) (xy 174.588233 -329.231255) (xy 174.63781 -329.208613)
			(xy 174.690105 -329.193258) (xy 174.744053 -329.185502) (xy 174.798555 -329.185502) (xy 174.852503 -329.193258)
			(xy 174.904798 -329.208613) (xy 174.954375 -329.231255) (xy 175.000225 -329.260721) (xy 175.041416 -329.296412)
			(xy 175.077107 -329.337603) (xy 175.106573 -329.383453) (xy 175.129215 -329.43303) (xy 175.14457 -329.485325)
			(xy 175.152326 -329.539273) (xy 175.152812 -329.566524) (xy 175.152357 -329.593895) (xy 175.144536 -329.648074)
			(xy 175.129044 -329.700577) (xy 175.1062 -329.750324) (xy 175.076474 -329.79629) (xy 175.058832 -329.817222)
			(xy 175.052736 -329.824334) (xy 175.046386 -329.841352) (xy 175.046386 -329.926696) (xy 175.052736 -329.943714)
			(xy 175.058832 -329.950826) (xy 175.076455 -329.971771) (xy 175.106168 -330.017741) (xy 175.129007 -330.067485)
			(xy 175.144502 -330.119983) (xy 175.152335 -330.174156) (xy 175.152812 -330.201524) (xy 175.1523 -330.230263)
			(xy 175.143674 -330.287091) (xy 175.126621 -330.341982) (xy 175.101527 -330.393693) (xy 175.06896 -330.441055)
			(xy 175.049688 -330.462382) (xy 175.043084 -330.469494) (xy 175.035972 -330.48702) (xy 175.035972 -330.576428)
			(xy 175.043084 -330.593954) (xy 175.049688 -330.601066) (xy 175.068982 -330.622372) (xy 175.101546 -330.669739)
			(xy 175.126635 -330.721454) (xy 175.143683 -330.776348) (xy 175.152303 -330.833178) (xy 175.1523 -330.890657)
			(xy 175.143675 -330.947487) (xy 175.126622 -331.002379) (xy 175.101528 -331.054092) (xy 175.06896 -331.101455)
			(xy 175.049688 -331.122782) (xy 175.043084 -331.129894) (xy 175.035972 -331.14742) (xy 175.035972 -331.236828)
			(xy 175.043084 -331.254354) (xy 175.049688 -331.261466) (xy 175.068974 -331.282779) (xy 175.101538 -331.330146)
			(xy 175.126627 -331.381861) (xy 175.143674 -331.436754) (xy 175.152293 -331.493584) (xy 175.152812 -331.522324)
			(xy 176.779174 -331.522324) (xy 176.779719 -331.493586) (xy 176.788338 -331.43676) (xy 176.805383 -331.38187)
			(xy 176.83047 -331.330158) (xy 176.86303 -331.282794) (xy 176.882298 -331.261466) (xy 176.888902 -331.254354)
			(xy 176.896014 -331.236828) (xy 176.896014 -331.14742) (xy 176.888902 -331.129894) (xy 176.882298 -331.122782)
			(xy 176.863052 -331.101434) (xy 176.830488 -331.054074) (xy 176.805397 -331.002366) (xy 176.788347 -330.947479)
			(xy 176.779722 -330.890655) (xy 176.77972 -330.83318) (xy 176.788339 -330.776355) (xy 176.805384 -330.721467)
			(xy 176.830471 -330.669756) (xy 176.86303 -330.622393) (xy 176.882298 -330.601066) (xy 176.888902 -330.593954)
			(xy 176.896014 -330.576428) (xy 176.896014 -330.48702) (xy 176.888902 -330.469494) (xy 176.882298 -330.462382)
			(xy 176.863049 -330.441036) (xy 176.830478 -330.39368) (xy 176.80538 -330.341974) (xy 176.788325 -330.287087)
			(xy 176.779697 -330.230262) (xy 176.779174 -330.201524) (xy 176.779636 -330.174153) (xy 176.787452 -330.119973)
			(xy 176.802941 -330.06747) (xy 176.825784 -330.017723) (xy 176.855511 -329.971757) (xy 176.873154 -329.950826)
			(xy 176.87925 -329.943714) (xy 176.8856 -329.926696) (xy 176.8856 -329.841352) (xy 176.87925 -329.824334)
			(xy 176.873154 -329.817222) (xy 176.85552 -329.796286) (xy 176.825806 -329.750315) (xy 176.802968 -329.700568)
			(xy 176.787476 -329.648068) (xy 176.779648 -329.593893) (xy 176.779174 -329.566524) (xy 176.77966 -329.539273)
			(xy 176.787416 -329.485325) (xy 176.802771 -329.43303) (xy 176.825413 -329.383453) (xy 176.854879 -329.337603)
			(xy 176.89057 -329.296412) (xy 176.931761 -329.260721) (xy 176.977611 -329.231255) (xy 177.027188 -329.208613)
			(xy 177.079483 -329.193258) (xy 177.133431 -329.185502) (xy 177.187933 -329.185502) (xy 177.241881 -329.193258)
			(xy 177.294176 -329.208613) (xy 177.343753 -329.231255) (xy 177.389603 -329.260721) (xy 177.430794 -329.296412)
			(xy 177.466485 -329.337603) (xy 177.495951 -329.383453) (xy 177.518593 -329.43303) (xy 177.533948 -329.485325)
			(xy 177.541704 -329.539273) (xy 177.54219 -329.566524) (xy 177.54174 -329.593895) (xy 177.533919 -329.648075)
			(xy 177.518426 -329.700578) (xy 177.495581 -329.750325) (xy 177.465853 -329.796291) (xy 177.44821 -329.817222)
			(xy 177.442114 -329.824334) (xy 177.435764 -329.841352) (xy 177.435764 -329.926696) (xy 177.442114 -329.943714)
			(xy 177.44821 -329.950826) (xy 177.465829 -329.971774) (xy 177.495544 -330.017742) (xy 177.518383 -330.067486)
			(xy 177.533879 -330.119983) (xy 177.541713 -330.174156) (xy 177.54219 -330.201524) (xy 177.541684 -330.230264)
			(xy 177.533057 -330.287092) (xy 177.516003 -330.341983) (xy 177.490908 -330.393694) (xy 177.458339 -330.441056)
			(xy 177.439066 -330.462382) (xy 177.432462 -330.469494) (xy 177.42535 -330.48702) (xy 177.42535 -330.576428)
			(xy 177.432462 -330.593954) (xy 177.439066 -330.601066) (xy 177.458361 -330.622372) (xy 177.490926 -330.669738)
			(xy 177.516017 -330.721453) (xy 177.533066 -330.776347) (xy 177.541687 -330.833177) (xy 177.541684 -330.890658)
			(xy 177.533058 -330.947487) (xy 177.516004 -331.00238) (xy 177.490909 -331.054093) (xy 177.458339 -331.101455)
			(xy 177.439066 -331.122782) (xy 177.432462 -331.129894) (xy 177.42535 -331.14742) (xy 177.42535 -331.236828)
			(xy 177.432462 -331.254354) (xy 177.439066 -331.261466) (xy 177.458349 -331.282783) (xy 177.490913 -331.330148)
			(xy 177.516003 -331.381862) (xy 177.533051 -331.436755) (xy 177.541671 -331.493584) (xy 177.54219 -331.522324)
			(xy 177.542009 -331.532484) (xy 180.454808 -331.532484) (xy 180.45532 -331.503745) (xy 180.463945 -331.446917)
			(xy 180.480998 -331.392026) (xy 180.506092 -331.340314) (xy 180.53866 -331.292952) (xy 180.557932 -331.271626)
			(xy 180.564536 -331.264514) (xy 180.571648 -331.246988) (xy 180.571648 -331.15758) (xy 180.564536 -331.140054)
			(xy 180.557932 -331.132942) (xy 180.538645 -331.111629) (xy 180.50608 -331.064265) (xy 180.480988 -331.012551)
			(xy 180.463939 -330.957658) (xy 180.455318 -330.900828) (xy 180.45532 -330.843349) (xy 180.463944 -330.78652)
			(xy 180.480997 -330.731628) (xy 180.506091 -330.679915) (xy 180.53866 -330.632553) (xy 180.557932 -330.611226)
			(xy 180.564536 -330.604114) (xy 180.571648 -330.586588) (xy 180.571648 -330.49718) (xy 180.564536 -330.479654)
			(xy 180.557932 -330.472542) (xy 180.538653 -330.451222) (xy 180.506088 -330.403858) (xy 180.480997 -330.352145)
			(xy 180.463948 -330.297252) (xy 180.455328 -330.240424) (xy 180.454808 -330.211684) (xy 180.455263 -330.184313)
			(xy 180.463083 -330.130134) (xy 180.478575 -330.07763) (xy 180.501419 -330.027884) (xy 180.531146 -329.981917)
			(xy 180.548788 -329.960986) (xy 180.554884 -329.953874) (xy 180.561234 -329.936856) (xy 180.561234 -329.851512)
			(xy 180.554884 -329.834494) (xy 180.548788 -329.827382) (xy 180.531172 -329.806431) (xy 180.501457 -329.760463)
			(xy 180.478617 -329.710721) (xy 180.46312 -329.658224) (xy 180.455286 -329.604052) (xy 180.454808 -329.576684)
			(xy 180.455294 -329.549433) (xy 180.46305 -329.495485) (xy 180.478405 -329.44319) (xy 180.501047 -329.393613)
			(xy 180.530513 -329.347763) (xy 180.566204 -329.306572) (xy 180.607395 -329.270881) (xy 180.653245 -329.241415)
			(xy 180.702822 -329.218773) (xy 180.755117 -329.203418) (xy 180.809065 -329.195662) (xy 180.863567 -329.195662)
			(xy 180.917515 -329.203418) (xy 180.96981 -329.218773) (xy 181.019387 -329.241415) (xy 181.065237 -329.270881)
			(xy 181.106428 -329.306572) (xy 181.142119 -329.347763) (xy 181.171585 -329.393613) (xy 181.194227 -329.44319)
			(xy 181.209582 -329.495485) (xy 181.217338 -329.549433) (xy 181.217824 -329.576684) (xy 181.217367 -329.604055)
			(xy 181.20955 -329.658235) (xy 181.19406 -329.710739) (xy 181.171215 -329.760486) (xy 181.141487 -329.806451)
			(xy 181.123844 -329.827382) (xy 181.117748 -329.834494) (xy 181.111398 -329.851512) (xy 181.111398 -329.936856)
			(xy 181.117748 -329.953874) (xy 181.123844 -329.960986) (xy 181.141497 -329.981907) (xy 181.171206 -330.027883)
			(xy 181.194038 -330.077634) (xy 181.209526 -330.130137) (xy 181.217352 -330.184314) (xy 181.217824 -330.211684)
			(xy 181.217284 -330.240422) (xy 181.208664 -330.297249) (xy 181.191618 -330.352139) (xy 181.16653 -330.403851)
			(xy 181.133969 -330.451214) (xy 181.1147 -330.472542) (xy 181.108096 -330.479654) (xy 181.100984 -330.49718)
			(xy 181.100984 -330.586588) (xy 181.108096 -330.604114) (xy 181.1147 -330.611226) (xy 181.133954 -330.632567)
			(xy 181.166518 -330.679928) (xy 181.191608 -330.731637) (xy 181.208659 -330.786526) (xy 181.217282 -330.843351)
			(xy 181.217284 -330.900826) (xy 181.208664 -330.957652) (xy 181.191617 -331.012541) (xy 181.166529 -331.064252)
			(xy 181.133969 -331.111615) (xy 181.1147 -331.132942) (xy 181.108096 -331.140054) (xy 181.100984 -331.15758)
			(xy 181.100984 -331.246988) (xy 181.108096 -331.264514) (xy 181.1147 -331.271626) (xy 181.133952 -331.292969)
			(xy 181.166524 -331.340326) (xy 181.19162 -331.392033) (xy 181.208675 -331.446921) (xy 181.217301 -331.503746)
			(xy 181.217824 -331.532484) (xy 182.844186 -331.532484) (xy 182.844704 -331.503745) (xy 182.853328 -331.446917)
			(xy 182.87038 -331.392027) (xy 182.895473 -331.340315) (xy 182.928039 -331.292953) (xy 182.94731 -331.271626)
			(xy 182.953914 -331.264514) (xy 182.961026 -331.246988) (xy 182.961026 -331.15758) (xy 182.953914 -331.140054)
			(xy 182.94731 -331.132942) (xy 182.928024 -331.111629) (xy 182.89546 -331.064264) (xy 182.870371 -331.012549)
			(xy 182.853322 -330.957657) (xy 182.844702 -330.900828) (xy 182.844703 -330.843349) (xy 182.853328 -330.78652)
			(xy 182.870379 -330.731629) (xy 182.895472 -330.679916) (xy 182.928039 -330.632553) (xy 182.94731 -330.611226)
			(xy 182.953914 -330.604114) (xy 182.961026 -330.586588) (xy 182.961026 -330.49718) (xy 182.953914 -330.479654)
			(xy 182.94731 -330.472542) (xy 182.928027 -330.451226) (xy 182.895464 -330.40386) (xy 182.870374 -330.352146)
			(xy 182.853326 -330.297253) (xy 182.844706 -330.240424) (xy 182.844186 -330.211684) (xy 182.844646 -330.184314)
			(xy 182.852466 -330.130134) (xy 182.867957 -330.077631) (xy 182.890799 -330.027885) (xy 182.920525 -329.981918)
			(xy 182.938166 -329.960986) (xy 182.944262 -329.953874) (xy 182.950612 -329.936856) (xy 182.950612 -329.851512)
			(xy 182.944262 -329.834494) (xy 182.938166 -329.827382) (xy 182.920547 -329.806434) (xy 182.890833 -329.760465)
			(xy 182.867994 -329.710722) (xy 182.852498 -329.658225) (xy 182.844664 -329.604052) (xy 182.844186 -329.576684)
			(xy 182.844672 -329.549433) (xy 182.852428 -329.495485) (xy 182.867783 -329.44319) (xy 182.890425 -329.393613)
			(xy 182.919891 -329.347763) (xy 182.955582 -329.306572) (xy 182.996773 -329.270881) (xy 183.042623 -329.241415)
			(xy 183.0922 -329.218773) (xy 183.144495 -329.203418) (xy 183.198443 -329.195662) (xy 183.252945 -329.195662)
			(xy 183.306893 -329.203418) (xy 183.359188 -329.218773) (xy 183.408765 -329.241415) (xy 183.454615 -329.270881)
			(xy 183.495806 -329.306572) (xy 183.531497 -329.347763) (xy 183.560963 -329.393613) (xy 183.583605 -329.44319)
			(xy 183.59896 -329.495485) (xy 183.606716 -329.549433) (xy 183.607202 -329.576684) (xy 183.606726 -329.604054)
			(xy 183.598911 -329.658233) (xy 183.583424 -329.710736) (xy 183.560584 -329.760483) (xy 183.530862 -329.80645)
			(xy 183.513222 -329.827382) (xy 183.507126 -329.834494) (xy 183.500776 -329.851512) (xy 183.500776 -329.936856)
			(xy 183.507126 -329.953874) (xy 183.513222 -329.960986) (xy 183.530871 -329.98191) (xy 183.560581 -330.027885)
			(xy 183.583415 -330.077635) (xy 183.598903 -330.130137) (xy 183.606729 -330.184314) (xy 183.607202 -330.211684)
			(xy 183.606668 -330.240423) (xy 183.598048 -330.297249) (xy 183.581 -330.35214) (xy 183.555911 -330.403852)
			(xy 183.523348 -330.451215) (xy 183.504078 -330.472542) (xy 183.497474 -330.479654) (xy 183.490362 -330.49718)
			(xy 183.490362 -330.586588) (xy 183.497474 -330.604114) (xy 183.504078 -330.611226) (xy 183.523333 -330.632567)
			(xy 183.555898 -330.679927) (xy 183.580991 -330.731636) (xy 183.598042 -330.786525) (xy 183.606666 -330.84335)
			(xy 183.606668 -330.900826) (xy 183.598047 -330.957652) (xy 183.580999 -331.012542) (xy 183.55591 -331.064253)
			(xy 183.523348 -331.111615) (xy 183.504078 -331.132942) (xy 183.497474 -331.140054) (xy 183.490362 -331.15758)
			(xy 183.490362 -331.246988) (xy 183.497474 -331.264514) (xy 183.504078 -331.271626) (xy 183.523344 -331.292957)
			(xy 183.55591 -331.340318) (xy 183.581003 -331.392029) (xy 183.598055 -331.446919) (xy 183.60668 -331.503745)
			(xy 183.607202 -331.532484) (xy 186.550808 -331.532484) (xy 186.55132 -331.503745) (xy 186.559945 -331.446917)
			(xy 186.576998 -331.392026) (xy 186.602092 -331.340314) (xy 186.63466 -331.292952) (xy 186.653932 -331.271626)
			(xy 186.660536 -331.264514) (xy 186.667648 -331.246988) (xy 186.667648 -331.15758) (xy 186.660536 -331.140054)
			(xy 186.653932 -331.132942) (xy 186.634645 -331.111629) (xy 186.60208 -331.064265) (xy 186.576988 -331.012551)
			(xy 186.559939 -330.957658) (xy 186.551318 -330.900828) (xy 186.55132 -330.843349) (xy 186.559944 -330.78652)
			(xy 186.576997 -330.731628) (xy 186.602091 -330.679915) (xy 186.63466 -330.632553) (xy 186.653932 -330.611226)
			(xy 186.660536 -330.604114) (xy 186.667648 -330.586588) (xy 186.667648 -330.49718) (xy 186.660536 -330.479654)
			(xy 186.653932 -330.472542) (xy 186.634653 -330.451222) (xy 186.602088 -330.403858) (xy 186.576997 -330.352145)
			(xy 186.559948 -330.297252) (xy 186.551328 -330.240424) (xy 186.550808 -330.211684) (xy 186.551263 -330.184313)
			(xy 186.559083 -330.130134) (xy 186.574575 -330.07763) (xy 186.597419 -330.027884) (xy 186.627146 -329.981917)
			(xy 186.644788 -329.960986) (xy 186.650884 -329.953874) (xy 186.657234 -329.936856) (xy 186.657234 -329.851512)
			(xy 186.650884 -329.834494) (xy 186.644788 -329.827382) (xy 186.627172 -329.806431) (xy 186.597457 -329.760463)
			(xy 186.574617 -329.710721) (xy 186.55912 -329.658224) (xy 186.551286 -329.604052) (xy 186.550808 -329.576684)
			(xy 186.551294 -329.549433) (xy 186.55905 -329.495485) (xy 186.574405 -329.44319) (xy 186.597047 -329.393613)
			(xy 186.626513 -329.347763) (xy 186.662204 -329.306572) (xy 186.703395 -329.270881) (xy 186.749245 -329.241415)
			(xy 186.798822 -329.218773) (xy 186.851117 -329.203418) (xy 186.905065 -329.195662) (xy 186.959567 -329.195662)
			(xy 187.013515 -329.203418) (xy 187.06581 -329.218773) (xy 187.115387 -329.241415) (xy 187.161237 -329.270881)
			(xy 187.202428 -329.306572) (xy 187.238119 -329.347763) (xy 187.267585 -329.393613) (xy 187.290227 -329.44319)
			(xy 187.305582 -329.495485) (xy 187.313338 -329.549433) (xy 187.313824 -329.576684) (xy 187.313367 -329.604055)
			(xy 187.30555 -329.658235) (xy 187.29006 -329.710739) (xy 187.267215 -329.760486) (xy 187.237487 -329.806451)
			(xy 187.219844 -329.827382) (xy 187.213748 -329.834494) (xy 187.207398 -329.851512) (xy 187.207398 -329.936856)
			(xy 187.213748 -329.953874) (xy 187.219844 -329.960986) (xy 187.237497 -329.981907) (xy 187.267206 -330.027883)
			(xy 187.290038 -330.077634) (xy 187.305526 -330.130137) (xy 187.313352 -330.184314) (xy 187.313824 -330.211684)
			(xy 187.313284 -330.240422) (xy 187.304664 -330.297249) (xy 187.287618 -330.352139) (xy 187.26253 -330.403851)
			(xy 187.229969 -330.451214) (xy 187.2107 -330.472542) (xy 187.204096 -330.479654) (xy 187.196984 -330.49718)
			(xy 187.196984 -330.586588) (xy 187.204096 -330.604114) (xy 187.2107 -330.611226) (xy 187.229954 -330.632567)
			(xy 187.262518 -330.679928) (xy 187.287608 -330.731637) (xy 187.304659 -330.786526) (xy 187.313282 -330.843351)
			(xy 187.313284 -330.900826) (xy 187.304664 -330.957652) (xy 187.287617 -331.012541) (xy 187.262529 -331.064252)
			(xy 187.229969 -331.111615) (xy 187.2107 -331.132942) (xy 187.204096 -331.140054) (xy 187.196984 -331.15758)
			(xy 187.196984 -331.246988) (xy 187.204096 -331.264514) (xy 187.2107 -331.271626) (xy 187.229952 -331.292969)
			(xy 187.262524 -331.340326) (xy 187.28762 -331.392033) (xy 187.304675 -331.446921) (xy 187.306096 -331.456284)
			(xy 188.969142 -331.456284) (xy 188.969672 -331.427546) (xy 188.978295 -331.370719) (xy 188.995345 -331.315829)
			(xy 189.020434 -331.264117) (xy 189.052997 -331.216754) (xy 189.072266 -331.195426) (xy 189.07887 -331.188314)
			(xy 189.085982 -331.170788) (xy 189.085982 -331.08138) (xy 189.07887 -331.063854) (xy 189.072266 -331.056742)
			(xy 189.052982 -331.035428) (xy 189.020422 -330.988061) (xy 188.995335 -330.936347) (xy 188.978289 -330.881455)
			(xy 188.969669 -330.824627) (xy 188.969671 -330.767149) (xy 188.978294 -330.710322) (xy 188.995344 -330.655431)
			(xy 189.020434 -330.603718) (xy 189.052997 -330.556354) (xy 189.072266 -330.535026) (xy 189.07887 -330.527914)
			(xy 189.085982 -330.510388) (xy 189.085982 -330.42098) (xy 189.07887 -330.403454) (xy 189.072266 -330.396342)
			(xy 189.052992 -330.375017) (xy 189.020425 -330.327655) (xy 188.995333 -330.275943) (xy 188.978283 -330.221052)
			(xy 188.969662 -330.164223) (xy 188.969142 -330.135484) (xy 188.969588 -330.108113) (xy 188.977409 -330.053933)
			(xy 188.992903 -330.001429) (xy 189.015749 -329.951682) (xy 189.045478 -329.905717) (xy 189.063122 -329.884786)
			(xy 189.069218 -329.877674) (xy 189.075568 -329.860656) (xy 189.075568 -329.775312) (xy 189.069218 -329.758294)
			(xy 189.063122 -329.751182) (xy 189.045511 -329.730227) (xy 189.015794 -329.684261) (xy 188.992953 -329.634519)
			(xy 188.977455 -329.582023) (xy 188.96962 -329.527852) (xy 188.969142 -329.500484) (xy 188.969628 -329.473233)
			(xy 188.977384 -329.419285) (xy 188.992739 -329.36699) (xy 189.015381 -329.317413) (xy 189.044847 -329.271563)
			(xy 189.080538 -329.230372) (xy 189.121729 -329.194681) (xy 189.167579 -329.165215) (xy 189.217156 -329.142573)
			(xy 189.269451 -329.127218) (xy 189.323399 -329.119462) (xy 189.377901 -329.119462) (xy 189.431849 -329.127218)
			(xy 189.484144 -329.142573) (xy 189.533721 -329.165215) (xy 189.579571 -329.194681) (xy 189.620762 -329.230372)
			(xy 189.656453 -329.271563) (xy 189.685919 -329.317413) (xy 189.708561 -329.36699) (xy 189.723916 -329.419285)
			(xy 189.731672 -329.473233) (xy 189.732158 -329.500484) (xy 189.731693 -329.527854) (xy 189.723876 -329.582034)
			(xy 189.708388 -329.634537) (xy 189.685545 -329.684284) (xy 189.65582 -329.730251) (xy 189.638178 -329.751182)
			(xy 189.632082 -329.758294) (xy 189.625732 -329.775312) (xy 189.625732 -329.860656) (xy 189.632082 -329.877674)
			(xy 189.638178 -329.884786) (xy 189.655821 -329.905715) (xy 189.685533 -329.951689) (xy 189.708368 -330.001437)
			(xy 189.723858 -330.053938) (xy 189.731685 -330.108115) (xy 189.732158 -330.135484) (xy 189.731609 -330.164222)
			(xy 189.72299 -330.221047) (xy 189.705945 -330.275937) (xy 189.68086 -330.327649) (xy 189.648301 -330.375014)
			(xy 189.629034 -330.396342) (xy 189.62243 -330.403454) (xy 189.615318 -330.42098) (xy 189.615318 -330.510388)
			(xy 189.62243 -330.527914) (xy 189.629034 -330.535026) (xy 189.648286 -330.556368) (xy 189.680847 -330.603729)
			(xy 189.705936 -330.655439) (xy 189.722984 -330.710327) (xy 189.731607 -330.767151) (xy 189.731609 -330.824626)
			(xy 189.72299 -330.88145) (xy 189.705944 -330.936339) (xy 189.680859 -330.98805) (xy 189.648301 -331.035414)
			(xy 189.629034 -331.056742) (xy 189.62243 -331.063854) (xy 189.615318 -331.08138) (xy 189.615318 -331.170788)
			(xy 189.62243 -331.188314) (xy 189.629034 -331.195426) (xy 189.648292 -331.216764) (xy 189.680862 -331.264122)
			(xy 189.705957 -331.315831) (xy 189.72301 -331.37072) (xy 189.731636 -331.427546) (xy 189.732158 -331.456284)
			(xy 192.621408 -331.456284) (xy 192.62192 -331.427545) (xy 192.630545 -331.370717) (xy 192.647598 -331.315826)
			(xy 192.672692 -331.264114) (xy 192.70526 -331.216752) (xy 192.724532 -331.195426) (xy 192.731136 -331.188314)
			(xy 192.738248 -331.170788) (xy 192.738248 -331.08138) (xy 192.731136 -331.063854) (xy 192.724532 -331.056742)
			(xy 192.705245 -331.035429) (xy 192.67268 -330.988065) (xy 192.647588 -330.936351) (xy 192.630539 -330.881458)
			(xy 192.621918 -330.824628) (xy 192.62192 -330.767149) (xy 192.630544 -330.71032) (xy 192.647597 -330.655428)
			(xy 192.672691 -330.603715) (xy 192.70526 -330.556353) (xy 192.724532 -330.535026) (xy 192.731136 -330.527914)
			(xy 192.738248 -330.510388) (xy 192.738248 -330.42098) (xy 192.731136 -330.403454) (xy 192.724532 -330.396342)
			(xy 192.705253 -330.375022) (xy 192.672688 -330.327658) (xy 192.647597 -330.275945) (xy 192.630548 -330.221052)
			(xy 192.621928 -330.164224) (xy 192.621408 -330.135484) (xy 192.621863 -330.108113) (xy 192.629683 -330.053934)
			(xy 192.645175 -330.00143) (xy 192.668019 -329.951684) (xy 192.697746 -329.905717) (xy 192.715388 -329.884786)
			(xy 192.721484 -329.877674) (xy 192.727834 -329.860656) (xy 192.727834 -329.775312) (xy 192.721484 -329.758294)
			(xy 192.715388 -329.751182) (xy 192.697772 -329.730231) (xy 192.668057 -329.684263) (xy 192.645217 -329.634521)
			(xy 192.62972 -329.582024) (xy 192.621886 -329.527852) (xy 192.621408 -329.500484) (xy 192.621894 -329.473233)
			(xy 192.62965 -329.419285) (xy 192.645005 -329.36699) (xy 192.667647 -329.317413) (xy 192.697113 -329.271563)
			(xy 192.732804 -329.230372) (xy 192.773995 -329.194681) (xy 192.819845 -329.165215) (xy 192.869422 -329.142573)
			(xy 192.921717 -329.127218) (xy 192.975665 -329.119462) (xy 193.030167 -329.119462) (xy 193.084115 -329.127218)
			(xy 193.13641 -329.142573) (xy 193.185987 -329.165215) (xy 193.231837 -329.194681) (xy 193.273028 -329.230372)
			(xy 193.308719 -329.271563) (xy 193.338185 -329.317413) (xy 193.360827 -329.36699) (xy 193.376182 -329.419285)
			(xy 193.383938 -329.473233) (xy 193.384424 -329.500484) (xy 193.383967 -329.527855) (xy 193.37615 -329.582035)
			(xy 193.36066 -329.634539) (xy 193.337815 -329.684286) (xy 193.308087 -329.730251) (xy 193.290444 -329.751182)
			(xy 193.284348 -329.758294) (xy 193.277998 -329.775312) (xy 193.277998 -329.860656) (xy 193.284348 -329.877674)
			(xy 193.290444 -329.884786) (xy 193.308097 -329.905707) (xy 193.337806 -329.951683) (xy 193.360638 -330.001434)
			(xy 193.376126 -330.053937) (xy 193.383952 -330.108114) (xy 193.384424 -330.135484) (xy 193.383884 -330.164222)
			(xy 193.375264 -330.221049) (xy 193.358218 -330.275939) (xy 193.33313 -330.327651) (xy 193.300569 -330.375014)
			(xy 193.2813 -330.396342) (xy 193.274696 -330.403454) (xy 193.267584 -330.42098) (xy 193.267584 -330.510388)
			(xy 193.274696 -330.527914) (xy 193.2813 -330.535026) (xy 193.300554 -330.556367) (xy 193.333118 -330.603728)
			(xy 193.358208 -330.655437) (xy 193.375259 -330.710326) (xy 193.383882 -330.767151) (xy 193.383884 -330.824626)
			(xy 193.375264 -330.881452) (xy 193.358217 -330.936341) (xy 193.333129 -330.988052) (xy 193.300569 -331.035415)
			(xy 193.2813 -331.056742) (xy 193.274696 -331.063854) (xy 193.267584 -331.08138) (xy 193.267584 -331.170788)
			(xy 193.274696 -331.188314) (xy 193.2813 -331.195426) (xy 193.300552 -331.216769) (xy 193.333124 -331.264126)
			(xy 193.35822 -331.315833) (xy 193.375275 -331.370721) (xy 193.383901 -331.427546) (xy 193.384207 -331.444346)
			(xy 195.076826 -331.444346) (xy 195.077337 -331.415607) (xy 195.085965 -331.35878) (xy 195.10302 -331.30389)
			(xy 195.128114 -331.252178) (xy 195.160679 -331.204815) (xy 195.17995 -331.183488) (xy 195.186554 -331.176376)
			(xy 195.193666 -331.15885) (xy 195.193666 -331.069442) (xy 195.186554 -331.051916) (xy 195.17995 -331.044804)
			(xy 195.160724 -331.023438) (xy 195.128155 -330.976083) (xy 195.103059 -330.924378) (xy 195.086004 -330.869493)
			(xy 195.077377 -330.81267) (xy 195.077372 -330.755197) (xy 195.085989 -330.698373) (xy 195.103034 -330.643485)
			(xy 195.128121 -330.591775) (xy 195.160681 -330.544414) (xy 195.17995 -330.523088) (xy 195.186554 -330.515976)
			(xy 195.193666 -330.49845) (xy 195.193666 -330.409042) (xy 195.186554 -330.391516) (xy 195.17995 -330.384404)
			(xy 195.160656 -330.363097) (xy 195.128092 -330.31573) (xy 195.103004 -330.264013) (xy 195.085959 -330.209118)
			(xy 195.077343 -330.152286) (xy 195.076826 -330.123546) (xy 195.077313 -330.096176) (xy 195.085125 -330.041998)
			(xy 195.100608 -329.989495) (xy 195.123446 -329.939748) (xy 195.153166 -329.89378) (xy 195.170806 -329.872848)
			(xy 195.176902 -329.865736) (xy 195.183252 -329.848718) (xy 195.183252 -329.763374) (xy 195.176902 -329.746356)
			(xy 195.170806 -329.739244) (xy 195.153175 -329.718305) (xy 195.123462 -329.672334) (xy 195.100624 -329.622589)
			(xy 195.085131 -329.570089) (xy 195.077301 -329.515915) (xy 195.076826 -329.488546) (xy 195.077312 -329.461295)
			(xy 195.085068 -329.407347) (xy 195.100423 -329.355052) (xy 195.123065 -329.305475) (xy 195.152531 -329.259625)
			(xy 195.188222 -329.218434) (xy 195.229413 -329.182743) (xy 195.275263 -329.153277) (xy 195.32484 -329.130635)
			(xy 195.377135 -329.11528) (xy 195.431083 -329.107524) (xy 195.485585 -329.107524) (xy 195.539533 -329.11528)
			(xy 195.591828 -329.130635) (xy 195.641405 -329.153277) (xy 195.687255 -329.182743) (xy 195.728446 -329.218434)
			(xy 195.764137 -329.259625) (xy 195.793603 -329.305475) (xy 195.816245 -329.355052) (xy 195.8316 -329.407347)
			(xy 195.839356 -329.461295) (xy 195.839842 -329.488546) (xy 195.839358 -329.515916) (xy 195.831547 -329.570095)
			(xy 195.816063 -329.622598) (xy 195.793225 -329.672345) (xy 195.763502 -329.718312) (xy 195.745862 -329.739244)
			(xy 195.739766 -329.746356) (xy 195.733416 -329.763374) (xy 195.733416 -329.848718) (xy 195.739766 -329.865736)
			(xy 195.745862 -329.872848) (xy 195.763484 -329.893794) (xy 195.7932 -329.939762) (xy 195.81604 -329.989506)
			(xy 195.831535 -330.042004) (xy 195.839366 -330.096178) (xy 195.839842 -330.123546) (xy 195.839335 -330.152285)
			(xy 195.830707 -330.209113) (xy 195.813652 -330.264003) (xy 195.788557 -330.315715) (xy 195.75599 -330.363077)
			(xy 195.736718 -330.384404) (xy 195.730114 -330.391516) (xy 195.723002 -330.409042) (xy 195.723002 -330.49845)
			(xy 195.730114 -330.515976) (xy 195.736718 -330.523088) (xy 195.756032 -330.544376) (xy 195.788593 -330.591746)
			(xy 195.813679 -330.643465) (xy 195.830724 -330.698361) (xy 195.839341 -330.755193) (xy 195.839336 -330.812674)
			(xy 195.830709 -330.869505) (xy 195.813654 -330.924398) (xy 195.788559 -330.976112) (xy 195.75599 -331.023476)
			(xy 195.736718 -331.044804) (xy 195.730114 -331.051916) (xy 195.723002 -331.069442) (xy 195.723002 -331.15885)
			(xy 195.730114 -331.176376) (xy 195.736718 -331.183488) (xy 195.756003 -331.204803) (xy 195.788569 -331.252167)
			(xy 195.81366 -331.303882) (xy 195.830707 -331.358776) (xy 195.839324 -331.415606) (xy 195.839842 -331.444346)
			(xy 195.839356 -331.471597) (xy 195.8316 -331.525545) (xy 195.816245 -331.57784) (xy 195.793603 -331.627417)
			(xy 195.764137 -331.673267) (xy 195.728446 -331.714458) (xy 195.687255 -331.750149) (xy 195.641405 -331.779615)
			(xy 195.591828 -331.802257) (xy 195.539533 -331.817612) (xy 195.485585 -331.825368) (xy 195.431083 -331.825368)
			(xy 195.377135 -331.817612) (xy 195.32484 -331.802257) (xy 195.275263 -331.779615) (xy 195.229413 -331.750149)
			(xy 195.188222 -331.714458) (xy 195.152531 -331.673267) (xy 195.123065 -331.627417) (xy 195.100423 -331.57784)
			(xy 195.085068 -331.525545) (xy 195.077312 -331.471597) (xy 195.076826 -331.444346) (xy 193.384207 -331.444346)
			(xy 193.384424 -331.456284) (xy 193.383938 -331.483535) (xy 193.376182 -331.537483) (xy 193.360827 -331.589778)
			(xy 193.338185 -331.639355) (xy 193.308719 -331.685205) (xy 193.273028 -331.726396) (xy 193.231837 -331.762087)
			(xy 193.185987 -331.791553) (xy 193.13641 -331.814195) (xy 193.084115 -331.82955) (xy 193.030167 -331.837306)
			(xy 192.975665 -331.837306) (xy 192.921717 -331.82955) (xy 192.869422 -331.814195) (xy 192.819845 -331.791553)
			(xy 192.773995 -331.762087) (xy 192.732804 -331.726396) (xy 192.697113 -331.685205) (xy 192.667647 -331.639355)
			(xy 192.645005 -331.589778) (xy 192.62965 -331.537483) (xy 192.621894 -331.483535) (xy 192.621408 -331.456284)
			(xy 189.732158 -331.456284) (xy 189.731672 -331.483535) (xy 189.723916 -331.537483) (xy 189.708561 -331.589778)
			(xy 189.685919 -331.639355) (xy 189.656453 -331.685205) (xy 189.620762 -331.726396) (xy 189.579571 -331.762087)
			(xy 189.533721 -331.791553) (xy 189.484144 -331.814195) (xy 189.431849 -331.82955) (xy 189.377901 -331.837306)
			(xy 189.323399 -331.837306) (xy 189.269451 -331.82955) (xy 189.217156 -331.814195) (xy 189.167579 -331.791553)
			(xy 189.121729 -331.762087) (xy 189.080538 -331.726396) (xy 189.044847 -331.685205) (xy 189.015381 -331.639355)
			(xy 188.992739 -331.589778) (xy 188.977384 -331.537483) (xy 188.969628 -331.483535) (xy 188.969142 -331.456284)
			(xy 187.306096 -331.456284) (xy 187.313301 -331.503746) (xy 187.313824 -331.532484) (xy 187.313338 -331.559735)
			(xy 187.305582 -331.613683) (xy 187.290227 -331.665978) (xy 187.267585 -331.715555) (xy 187.238119 -331.761405)
			(xy 187.202428 -331.802596) (xy 187.161237 -331.838287) (xy 187.115387 -331.867753) (xy 187.06581 -331.890395)
			(xy 187.013515 -331.90575) (xy 186.959567 -331.913506) (xy 186.905065 -331.913506) (xy 186.851117 -331.90575)
			(xy 186.798822 -331.890395) (xy 186.749245 -331.867753) (xy 186.703395 -331.838287) (xy 186.662204 -331.802596)
			(xy 186.626513 -331.761405) (xy 186.597047 -331.715555) (xy 186.574405 -331.665978) (xy 186.55905 -331.613683)
			(xy 186.551294 -331.559735) (xy 186.550808 -331.532484) (xy 183.607202 -331.532484) (xy 183.606716 -331.559735)
			(xy 183.59896 -331.613683) (xy 183.583605 -331.665978) (xy 183.560963 -331.715555) (xy 183.531497 -331.761405)
			(xy 183.495806 -331.802596) (xy 183.454615 -331.838287) (xy 183.408765 -331.867753) (xy 183.359188 -331.890395)
			(xy 183.306893 -331.90575) (xy 183.252945 -331.913506) (xy 183.198443 -331.913506) (xy 183.144495 -331.90575)
			(xy 183.0922 -331.890395) (xy 183.042623 -331.867753) (xy 182.996773 -331.838287) (xy 182.955582 -331.802596)
			(xy 182.919891 -331.761405) (xy 182.890425 -331.715555) (xy 182.867783 -331.665978) (xy 182.852428 -331.613683)
			(xy 182.844672 -331.559735) (xy 182.844186 -331.532484) (xy 181.217824 -331.532484) (xy 181.217338 -331.559735)
			(xy 181.209582 -331.613683) (xy 181.194227 -331.665978) (xy 181.171585 -331.715555) (xy 181.142119 -331.761405)
			(xy 181.106428 -331.802596) (xy 181.065237 -331.838287) (xy 181.019387 -331.867753) (xy 180.96981 -331.890395)
			(xy 180.917515 -331.90575) (xy 180.863567 -331.913506) (xy 180.809065 -331.913506) (xy 180.755117 -331.90575)
			(xy 180.702822 -331.890395) (xy 180.653245 -331.867753) (xy 180.607395 -331.838287) (xy 180.566204 -331.802596)
			(xy 180.530513 -331.761405) (xy 180.501047 -331.715555) (xy 180.478405 -331.665978) (xy 180.46305 -331.613683)
			(xy 180.455294 -331.559735) (xy 180.454808 -331.532484) (xy 177.542009 -331.532484) (xy 177.541704 -331.549575)
			(xy 177.533948 -331.603523) (xy 177.518593 -331.655818) (xy 177.495951 -331.705395) (xy 177.466485 -331.751245)
			(xy 177.430794 -331.792436) (xy 177.389603 -331.828127) (xy 177.343753 -331.857593) (xy 177.294176 -331.880235)
			(xy 177.241881 -331.89559) (xy 177.187933 -331.903346) (xy 177.133431 -331.903346) (xy 177.079483 -331.89559)
			(xy 177.027188 -331.880235) (xy 176.977611 -331.857593) (xy 176.931761 -331.828127) (xy 176.89057 -331.792436)
			(xy 176.854879 -331.751245) (xy 176.825413 -331.705395) (xy 176.802771 -331.655818) (xy 176.787416 -331.603523)
			(xy 176.77966 -331.549575) (xy 176.779174 -331.522324) (xy 175.152812 -331.522324) (xy 175.152326 -331.549575)
			(xy 175.14457 -331.603523) (xy 175.129215 -331.655818) (xy 175.106573 -331.705395) (xy 175.077107 -331.751245)
			(xy 175.041416 -331.792436) (xy 175.000225 -331.828127) (xy 174.954375 -331.857593) (xy 174.904798 -331.880235)
			(xy 174.852503 -331.89559) (xy 174.798555 -331.903346) (xy 174.744053 -331.903346) (xy 174.690105 -331.89559)
			(xy 174.63781 -331.880235) (xy 174.588233 -331.857593) (xy 174.542383 -331.828127) (xy 174.501192 -331.792436)
			(xy 174.465501 -331.751245) (xy 174.436035 -331.705395) (xy 174.413393 -331.655818) (xy 174.398038 -331.603523)
			(xy 174.390282 -331.549575) (xy 174.389796 -331.522324) (xy 128.59639 -331.522324) (xy 128.59639 -331.641958)
			(xy 128.596823 -331.652024) (xy 128.604551 -331.670614) (xy 128.611376 -331.678026) (xy 130.054858 -333.121508)
			(xy 167.537892 -333.121508) (xy 167.53833 -333.08433) (xy 167.545581 -333.010329) (xy 167.560006 -332.937387)
			(xy 167.581466 -332.866196) (xy 167.609759 -332.797433) (xy 167.626792 -332.764384) (xy 167.632093 -332.753025)
			(xy 167.632097 -332.727989) (xy 167.626792 -332.716632) (xy 167.609761 -332.683583) (xy 167.581488 -332.614815)
			(xy 167.560038 -332.543623) (xy 167.545614 -332.470682) (xy 167.538353 -332.396684) (xy 167.537892 -332.359508)
			(xy 167.538381 -332.320863) (xy 167.546201 -332.243969) (xy 167.561759 -332.168261) (xy 167.584897 -332.094515)
			(xy 167.615377 -332.023488) (xy 167.652886 -331.95591) (xy 167.69704 -331.892472) (xy 167.747385 -331.833828)
			(xy 167.803404 -331.780577) (xy 167.864523 -331.733267) (xy 167.930116 -331.692383) (xy 167.999507 -331.658345)
			(xy 168.071987 -331.631502) (xy 168.14681 -331.612129) (xy 168.223209 -331.600425) (xy 168.3004 -331.59651)
			(xy 168.377591 -331.600425) (xy 168.45399 -331.612129) (xy 168.528813 -331.631502) (xy 168.601293 -331.658345)
			(xy 168.670684 -331.692383) (xy 168.736277 -331.733267) (xy 168.797396 -331.780577) (xy 168.853415 -331.833828)
			(xy 168.90376 -331.892472) (xy 168.947914 -331.95591) (xy 168.985423 -332.023488) (xy 169.015903 -332.094515)
			(xy 169.039041 -332.168261) (xy 169.054599 -332.243969) (xy 169.062419 -332.320863) (xy 169.062908 -332.359508)
			(xy 169.062477 -332.396686) (xy 169.055224 -332.470687) (xy 169.040798 -332.54363) (xy 169.019336 -332.614821)
			(xy 168.991041 -332.683583) (xy 168.974008 -332.716632) (xy 168.968696 -332.727987) (xy 168.968699 -332.753027)
			(xy 168.974008 -332.764384) (xy 168.991045 -332.79743) (xy 169.019317 -332.866199) (xy 169.040765 -332.937392)
			(xy 169.055188 -333.010333) (xy 169.062448 -333.084331) (xy 169.062908 -333.121508) (xy 169.062419 -333.160153)
			(xy 169.054599 -333.237047) (xy 169.039041 -333.312755) (xy 169.015903 -333.386501) (xy 168.985423 -333.457528)
			(xy 168.947914 -333.525106) (xy 168.90376 -333.588544) (xy 168.853415 -333.647188) (xy 168.797396 -333.700439)
			(xy 168.736277 -333.747749) (xy 168.670684 -333.788633) (xy 168.601293 -333.822671) (xy 168.528813 -333.849514)
			(xy 168.45399 -333.868887) (xy 168.377591 -333.880591) (xy 168.3004 -333.884506) (xy 168.223209 -333.880591)
			(xy 168.14681 -333.868887) (xy 168.071987 -333.849514) (xy 167.999507 -333.822671) (xy 167.930116 -333.788633)
			(xy 167.864523 -333.747749) (xy 167.803404 -333.700439) (xy 167.747385 -333.647188) (xy 167.69704 -333.588544)
			(xy 167.652886 -333.525106) (xy 167.615377 -333.457528) (xy 167.584897 -333.386501) (xy 167.561759 -333.312755)
			(xy 167.546201 -333.237047) (xy 167.538381 -333.160153) (xy 167.537892 -333.121508) (xy 130.054858 -333.121508)
			(xy 132.163058 -335.229708) (xy 132.165563 -335.232287) (xy 132.169893 -335.238026) (xy 132.171694 -335.241138)
			(xy 132.178298 -335.253584) (xy 132.180096 -335.256697) (xy 132.184431 -335.262433) (xy 132.186934 -335.265014)
			(xy 139.052554 -342.130634) (xy 139.053062 -342.131142) (xy 139.060443 -342.137724) (xy 139.078742 -342.145173)
			(xy 139.088622 -342.14562)
		)
		(stroke
			(width 0)
			(type solid)
		)
		(fill yes)
		(layer "In15.Cu")
		(net "PVDD11_S3_P1")
	)
	(gr_poly
		(pts
			(xy 64.86906 -335.162652) (xy 64.873145 -335.162569) (xy 64.881193 -335.161168) (xy 64.885062 -335.159858)
			(xy 64.902334 -335.153508) (xy 64.90462 -335.151476) (xy 67.961002 -332.095094) (xy 67.965991 -332.089596)
			(xy 67.97284 -332.07643) (xy 67.974464 -332.069186) (xy 67.97548 -332.059534) (xy 67.97548 -328.062082)
			(xy 67.975906 -328.052013) (xy 67.983623 -328.033411) (xy 67.990466 -328.026014) (xy 68.577714 -327.438766)
			(xy 68.58511 -327.431915) (xy 68.603709 -327.424175) (xy 68.613782 -327.42378) (xy 98.281998 -327.42378)
			(xy 98.292069 -327.424202) (xy 98.310676 -327.431914) (xy 98.318066 -327.438766) (xy 99.028504 -328.14895)
			(xy 99.0359 -328.155801) (xy 99.054499 -328.163542) (xy 99.064572 -328.163936) (xy 107.800648 -328.163936)
			(xy 107.810713 -328.163502) (xy 107.829299 -328.155769) (xy 107.836716 -328.14895) (xy 110.766606 -325.219314)
			(xy 110.771803 -325.213637) (xy 110.778789 -325.199932) (xy 110.780322 -325.19239) (xy 110.780322 -325.191882)
			(xy 110.781084 -325.183754) (xy 110.781084 -323.949568) (xy 110.781512 -323.9395) (xy 110.789233 -323.920902)
			(xy 110.79607 -323.9135) (xy 111.064294 -323.645276) (xy 111.071137 -323.637876) (xy 111.078864 -323.619278)
			(xy 111.07928 -323.609208) (xy 111.07928 -320.593466) (xy 111.079709 -320.583398) (xy 111.08743 -320.564801)
			(xy 111.094266 -320.557398) (xy 111.102648 -320.549016) (xy 111.108744 -320.51879) (xy 103.174038 -301.673768)
			(xy 103.172028 -301.669263) (xy 103.166528 -301.661075) (xy 103.163116 -301.657512) (xy 102.964742 -301.459138)
			(xy 102.957901 -301.451738) (xy 102.950182 -301.433139) (xy 102.949756 -301.42307) (xy 102.949756 -295.43248)
			(xy 102.949262 -295.421638) (xy 102.940321 -295.401886) (xy 102.932484 -295.39438) (xy 102.913655 -295.377141)
			(xy 102.881012 -295.337895) (xy 102.854783 -295.294101) (xy 102.83559 -295.246799) (xy 102.823887 -295.197111)
			(xy 102.819954 -295.146215) (xy 102.823883 -295.095318) (xy 102.835581 -295.045629) (xy 102.85477 -294.998325)
			(xy 102.880995 -294.954529) (xy 102.913635 -294.91528) (xy 102.932484 -294.898064) (xy 102.940279 -294.890527)
			(xy 102.949218 -294.870794) (xy 102.949756 -294.859964) (xy 102.949756 -294.718486) (xy 102.949077 -294.705846)
			(xy 102.937074 -294.683597) (xy 102.926896 -294.676068) (xy 102.855522 -294.629332) (xy 102.844565 -294.622994)
			(xy 102.819376 -294.62085) (xy 102.807516 -294.625268) (xy 102.787532 -294.633625) (xy 102.745844 -294.64539)
			(xy 102.702936 -294.65132) (xy 102.681278 -294.651684) (xy 102.681024 -294.651684) (xy 102.65623 -294.651225)
			(xy 102.607252 -294.643471) (xy 102.56009 -294.62815) (xy 102.515905 -294.60564) (xy 102.475786 -294.576495)
			(xy 102.440721 -294.541432) (xy 102.411573 -294.501315) (xy 102.389059 -294.457132) (xy 102.373735 -294.409972)
			(xy 102.365977 -294.360994) (xy 102.365977 -294.311406) (xy 102.373735 -294.262428) (xy 102.389059 -294.215268)
			(xy 102.411573 -294.171085) (xy 102.440721 -294.130968) (xy 102.475786 -294.095905) (xy 102.515905 -294.06676)
			(xy 102.56009 -294.04425) (xy 102.607252 -294.028929) (xy 102.65623 -294.021175) (xy 102.681024 -294.020748)
			(xy 102.681278 -294.020748) (xy 102.702934 -294.021128) (xy 102.745835 -294.027082) (xy 102.787525 -294.038829)
			(xy 102.807516 -294.047164) (xy 102.819454 -294.052244) (xy 102.844854 -294.050212) (xy 102.926896 -293.996364)
			(xy 102.937082 -293.988845) (xy 102.94908 -293.966588) (xy 102.949756 -293.953946) (xy 102.949756 -293.777416)
			(xy 102.949265 -293.767456) (xy 102.941668 -293.749041) (xy 102.935024 -293.741602) (xy 102.918453 -293.724332)
			(xy 102.890355 -293.685589) (xy 102.868655 -293.642932) (xy 102.853885 -293.597408) (xy 102.846408 -293.550137)
			(xy 102.846407 -293.502277) (xy 102.853882 -293.455005) (xy 102.86865 -293.409481) (xy 102.890348 -293.366823)
			(xy 102.918443 -293.328078) (xy 102.935024 -293.310818) (xy 102.941708 -293.303408) (xy 102.949293 -293.284972)
			(xy 102.949756 -293.275004) (xy 102.949756 -292.157404) (xy 102.949281 -292.147437) (xy 102.941707 -292.128999)
			(xy 102.935024 -292.12159) (xy 102.918454 -292.10432) (xy 102.890358 -292.065577) (xy 102.86866 -292.022921)
			(xy 102.853892 -291.977398) (xy 102.846416 -291.930128) (xy 102.846416 -291.88227) (xy 102.853892 -291.834999)
			(xy 102.868661 -291.789477) (xy 102.89036 -291.74682) (xy 102.918455 -291.708077) (xy 102.935024 -291.690806)
			(xy 102.941706 -291.683396) (xy 102.949287 -291.66496) (xy 102.949756 -291.654992) (xy 102.949756 -291.467286)
			(xy 102.949045 -291.454559) (xy 102.936901 -291.432184) (xy 102.926642 -291.424614) (xy 102.844092 -291.371274)
			(xy 102.818184 -291.369242) (xy 102.8065 -291.374576) (xy 102.786733 -291.383083) (xy 102.745402 -291.395072)
			(xy 102.702795 -291.401118) (xy 102.681278 -291.4015) (xy 102.681024 -291.4015) (xy 102.655766 -291.401009)
			(xy 102.605937 -291.392698) (xy 102.558157 -291.376298) (xy 102.513728 -291.352257) (xy 102.473861 -291.321231)
			(xy 102.439646 -291.284066) (xy 102.412015 -291.241776) (xy 102.391722 -291.195515) (xy 102.37932 -291.146544)
			(xy 102.375148 -291.0962) (xy 102.37932 -291.045856) (xy 102.391722 -290.996885) (xy 102.412015 -290.950624)
			(xy 102.439646 -290.908334) (xy 102.473861 -290.871169) (xy 102.513728 -290.840143) (xy 102.558157 -290.816102)
			(xy 102.605937 -290.799702) (xy 102.655766 -290.791391) (xy 102.681024 -290.790884) (xy 102.681278 -290.790884)
			(xy 102.702793 -290.791274) (xy 102.745394 -290.797347) (xy 102.786726 -290.809321) (xy 102.8065 -290.817808)
			(xy 102.818184 -290.823142) (xy 102.844092 -290.82111) (xy 102.926642 -290.76777) (xy 102.933577 -290.76291)
			(xy 102.944 -290.749575) (xy 102.94948 -290.733562) (xy 102.949756 -290.725098) (xy 102.949756 -290.572444)
			(xy 102.949255 -290.561606) (xy 102.940305 -290.541864) (xy 102.932484 -290.534344) (xy 102.913658 -290.517105)
			(xy 102.881021 -290.47786) (xy 102.854796 -290.434068) (xy 102.835608 -290.386768) (xy 102.82391 -290.337083)
			(xy 102.819981 -290.286191) (xy 102.823913 -290.235299) (xy 102.835614 -290.185614) (xy 102.854805 -290.138316)
			(xy 102.881031 -290.094525) (xy 102.913671 -290.055281) (xy 102.932484 -290.038028) (xy 102.940273 -290.030489)
			(xy 102.949198 -290.010756) (xy 102.949756 -289.999928) (xy 102.949756 -289.847274) (xy 102.949064 -289.834536)
			(xy 102.936941 -289.812128) (xy 102.926642 -289.804602) (xy 102.844092 -289.751262) (xy 102.818184 -289.74923)
			(xy 102.8065 -289.754564) (xy 102.786733 -289.763071) (xy 102.745402 -289.775061) (xy 102.702795 -289.781107)
			(xy 102.681278 -289.781488) (xy 102.681024 -289.781488) (xy 102.655767 -289.780997) (xy 102.60594 -289.772686)
			(xy 102.558162 -289.756287) (xy 102.513734 -289.732247) (xy 102.47387 -289.701222) (xy 102.439655 -289.664059)
			(xy 102.412025 -289.62177) (xy 102.391733 -289.575511) (xy 102.379332 -289.526542) (xy 102.37516 -289.4762)
			(xy 102.379332 -289.425858) (xy 102.391733 -289.376889) (xy 102.412025 -289.33063) (xy 102.439655 -289.288341)
			(xy 102.47387 -289.251178) (xy 102.513734 -289.220153) (xy 102.558162 -289.196113) (xy 102.60594 -289.179714)
			(xy 102.655767 -289.171403) (xy 102.681024 -289.170872) (xy 102.681278 -289.170872) (xy 102.702793 -289.171262)
			(xy 102.745394 -289.177335) (xy 102.786726 -289.189308) (xy 102.8065 -289.197796) (xy 102.818184 -289.20313)
			(xy 102.844092 -289.201098) (xy 102.926642 -289.147758) (xy 102.933576 -289.142898) (xy 102.943996 -289.129562)
			(xy 102.949472 -289.113549) (xy 102.949756 -289.105086) (xy 102.949756 -288.91738) (xy 102.949277 -288.907415)
			(xy 102.941696 -288.888983) (xy 102.935024 -288.881566) (xy 102.918455 -288.864297) (xy 102.890364 -288.825554)
			(xy 102.868669 -288.782898) (xy 102.853904 -288.737378) (xy 102.846431 -288.690109) (xy 102.846434 -288.642254)
			(xy 102.853913 -288.594986) (xy 102.868683 -288.549468) (xy 102.890383 -288.506815) (xy 102.918479 -288.468075)
			(xy 102.935024 -288.450782) (xy 102.941703 -288.44337) (xy 102.949275 -288.424934) (xy 102.949756 -288.414968)
			(xy 102.949756 -288.227516) (xy 102.949051 -288.214785) (xy 102.936915 -288.192399) (xy 102.926642 -288.184844)
			(xy 102.844092 -288.131504) (xy 102.818184 -288.129472) (xy 102.8065 -288.134806) (xy 102.786732 -288.143312)
			(xy 102.745402 -288.1553) (xy 102.702795 -288.161346) (xy 102.681278 -288.16173) (xy 102.681024 -288.16173)
			(xy 102.655763 -288.161239) (xy 102.60593 -288.152927) (xy 102.558145 -288.136526) (xy 102.513711 -288.112482)
			(xy 102.473841 -288.081453) (xy 102.439622 -288.044285) (xy 102.411988 -288.00199) (xy 102.391693 -287.955725)
			(xy 102.37929 -287.906749) (xy 102.375118 -287.8564) (xy 102.37929 -287.806051) (xy 102.391693 -287.757075)
			(xy 102.411988 -287.71081) (xy 102.439622 -287.668515) (xy 102.473841 -287.631347) (xy 102.513711 -287.600318)
			(xy 102.558145 -287.576274) (xy 102.60593 -287.559873) (xy 102.655763 -287.551561) (xy 102.681024 -287.551114)
			(xy 102.681278 -287.551114) (xy 102.702793 -287.551504) (xy 102.745393 -287.557578) (xy 102.786725 -287.569553)
			(xy 102.8065 -287.578038) (xy 102.818184 -287.583372) (xy 102.844092 -287.58134) (xy 102.926642 -287.528)
			(xy 102.933581 -287.523142) (xy 102.944011 -287.509808) (xy 102.949501 -287.493793) (xy 102.949756 -287.485328)
			(xy 102.949756 -287.33242) (xy 102.949251 -287.321584) (xy 102.940294 -287.30185) (xy 102.932484 -287.29432)
			(xy 102.91366 -287.277081) (xy 102.881026 -287.237836) (xy 102.854806 -287.194045) (xy 102.83562 -287.146747)
			(xy 102.823926 -287.097064) (xy 102.819999 -287.046175) (xy 102.823934 -286.995286) (xy 102.835636 -286.945605)
			(xy 102.854828 -286.89831) (xy 102.881055 -286.854523) (xy 102.913695 -286.815283) (xy 102.932484 -286.798004)
			(xy 102.940285 -286.790469) (xy 102.949239 -286.770737) (xy 102.949756 -286.759904) (xy 102.949756 -286.607504)
			(xy 102.949049 -286.594774) (xy 102.936909 -286.572393) (xy 102.926642 -286.564832) (xy 102.844092 -286.511492)
			(xy 102.818184 -286.50946) (xy 102.8065 -286.514794) (xy 102.786732 -286.523301) (xy 102.745402 -286.535289)
			(xy 102.702795 -286.541335) (xy 102.681278 -286.541718) (xy 102.681024 -286.541718) (xy 102.655764 -286.541227)
			(xy 102.605933 -286.532915) (xy 102.55815 -286.516515) (xy 102.513718 -286.492472) (xy 102.473849 -286.461444)
			(xy 102.439632 -286.424277) (xy 102.411999 -286.381985) (xy 102.391705 -286.335721) (xy 102.379302 -286.286747)
			(xy 102.37513 -286.2364) (xy 102.379302 -286.186053) (xy 102.391705 -286.137079) (xy 102.411999 -286.090815)
			(xy 102.439632 -286.048523) (xy 102.473849 -286.011356) (xy 102.513718 -285.980328) (xy 102.55815 -285.956285)
			(xy 102.605933 -285.939885) (xy 102.655764 -285.931573) (xy 102.681024 -285.931102) (xy 102.681278 -285.931102)
			(xy 102.702793 -285.931492) (xy 102.745394 -285.937566) (xy 102.786725 -285.94954) (xy 102.8065 -285.958026)
			(xy 102.818184 -285.96336) (xy 102.844092 -285.961328) (xy 102.926642 -285.907988) (xy 102.933579 -285.903129)
			(xy 102.944007 -285.889795) (xy 102.949492 -285.873781) (xy 102.949756 -285.865316) (xy 102.949756 -285.67761)
			(xy 102.949282 -285.667643) (xy 102.941709 -285.649203) (xy 102.935024 -285.641796) (xy 102.918453 -285.624526)
			(xy 102.890357 -285.585783) (xy 102.868658 -285.543126) (xy 102.853889 -285.497603) (xy 102.846412 -285.450332)
			(xy 102.846412 -285.402473) (xy 102.853887 -285.355202) (xy 102.868656 -285.309679) (xy 102.890354 -285.267022)
			(xy 102.918449 -285.228278) (xy 102.935024 -285.211012) (xy 102.941707 -285.203602) (xy 102.94929 -285.185166)
			(xy 102.949756 -285.175198) (xy 102.949756 -284.987492) (xy 102.949046 -284.974764) (xy 102.936904 -284.952387)
			(xy 102.926642 -284.94482) (xy 102.844092 -284.89148) (xy 102.818184 -284.889448) (xy 102.8065 -284.894782)
			(xy 102.786733 -284.903289) (xy 102.745402 -284.915278) (xy 102.702795 -284.921324) (xy 102.681278 -284.921706)
			(xy 102.681024 -284.921706) (xy 102.655765 -284.921215) (xy 102.605936 -284.912904) (xy 102.558154 -284.896504)
			(xy 102.513724 -284.872462) (xy 102.473857 -284.841436) (xy 102.439641 -284.80427) (xy 102.41201 -284.761979)
			(xy 102.391716 -284.715717) (xy 102.379314 -284.666745) (xy 102.375142 -284.6164) (xy 102.379314 -284.566055)
			(xy 102.391716 -284.517083) (xy 102.41201 -284.470821) (xy 102.439641 -284.42853) (xy 102.473857 -284.391364)
			(xy 102.513724 -284.360338) (xy 102.558154 -284.336296) (xy 102.605936 -284.319896) (xy 102.655765 -284.311585)
			(xy 102.681024 -284.31109) (xy 102.681278 -284.31109) (xy 102.702793 -284.31148) (xy 102.745394 -284.317554)
			(xy 102.786725 -284.329527) (xy 102.8065 -284.338014) (xy 102.818184 -284.343348) (xy 102.844092 -284.341316)
			(xy 102.926642 -284.287976) (xy 102.933578 -284.283117) (xy 102.944003 -284.269782) (xy 102.949484 -284.253768)
			(xy 102.949756 -284.245304) (xy 102.949756 -284.09265) (xy 102.949257 -284.081811) (xy 102.940308 -284.062068)
			(xy 102.932484 -284.05455) (xy 102.913658 -284.037311) (xy 102.881019 -283.998065) (xy 102.854794 -283.954273)
			(xy 102.835605 -283.906973) (xy 102.823907 -283.857287) (xy 102.819977 -283.806395) (xy 102.823908 -283.755502)
			(xy 102.835608 -283.705817) (xy 102.854799 -283.658517) (xy 102.881025 -283.614726) (xy 102.913665 -283.575481)
			(xy 102.932484 -283.558234) (xy 102.940274 -283.550695) (xy 102.949202 -283.530962) (xy 102.949756 -283.520134)
			(xy 102.949756 -283.36748) (xy 102.949066 -283.354741) (xy 102.936944 -283.332331) (xy 102.926642 -283.324808)
			(xy 102.844092 -283.271468) (xy 102.818184 -283.269436) (xy 102.8065 -283.27477) (xy 102.786733 -283.283277)
			(xy 102.745402 -283.295266) (xy 102.702795 -283.301313) (xy 102.681278 -283.301694) (xy 102.681024 -283.301694)
			(xy 102.655766 -283.301203) (xy 102.605939 -283.292892) (xy 102.558159 -283.276493) (xy 102.513731 -283.252452)
			(xy 102.473865 -283.221427) (xy 102.439651 -283.184262) (xy 102.41202 -283.141973) (xy 102.391727 -283.095713)
			(xy 102.379326 -283.046743) (xy 102.375154 -282.9964) (xy 102.379326 -282.946057) (xy 102.391727 -282.897087)
			(xy 102.41202 -282.850827) (xy 102.439651 -282.808538) (xy 102.473865 -282.771373) (xy 102.513731 -282.740348)
			(xy 102.558159 -282.716307) (xy 102.605939 -282.699908) (xy 102.655766 -282.691597) (xy 102.681024 -282.691078)
			(xy 102.681278 -282.691078) (xy 102.702793 -282.691468) (xy 102.745394 -282.697541) (xy 102.786726 -282.709515)
			(xy 102.8065 -282.718002) (xy 102.818184 -282.723336) (xy 102.844092 -282.721304) (xy 102.926642 -282.667964)
			(xy 102.933577 -282.663104) (xy 102.943998 -282.649769) (xy 102.949476 -282.633755) (xy 102.949756 -282.625292)
			(xy 102.949756 -282.437586) (xy 102.949278 -282.427621) (xy 102.941699 -282.409187) (xy 102.935024 -282.401772)
			(xy 102.918455 -282.384503) (xy 102.890362 -282.34576) (xy 102.868667 -282.303104) (xy 102.853901 -282.257583)
			(xy 102.846428 -282.210314) (xy 102.84643 -282.162458) (xy 102.853908 -282.11519) (xy 102.868678 -282.06967)
			(xy 102.890377 -282.027016) (xy 102.918473 -281.988276) (xy 102.935024 -281.970988) (xy 102.941704 -281.963577)
			(xy 102.949278 -281.945141) (xy 102.949756 -281.935174) (xy 102.949756 -281.747468) (xy 102.949063 -281.73473)
			(xy 102.936938 -281.712325) (xy 102.926642 -281.704796) (xy 102.844092 -281.651456) (xy 102.818184 -281.649424)
			(xy 102.8065 -281.654758) (xy 102.786733 -281.663265) (xy 102.745402 -281.675255) (xy 102.702795 -281.681302)
			(xy 102.681278 -281.681682) (xy 102.681024 -281.681682) (xy 102.655767 -281.681191) (xy 102.605942 -281.672881)
			(xy 102.558164 -281.656482) (xy 102.513737 -281.632442) (xy 102.473874 -281.601418) (xy 102.43966 -281.564255)
			(xy 102.412031 -281.521968) (xy 102.391739 -281.475709) (xy 102.379338 -281.426741) (xy 102.375166 -281.3764)
			(xy 102.379338 -281.326059) (xy 102.391739 -281.277091) (xy 102.412031 -281.230832) (xy 102.43966 -281.188545)
			(xy 102.473874 -281.151382) (xy 102.513737 -281.120358) (xy 102.558164 -281.096318) (xy 102.605942 -281.079919)
			(xy 102.655767 -281.071609) (xy 102.681024 -281.071066) (xy 102.681278 -281.071066) (xy 102.702793 -281.071456)
			(xy 102.745394 -281.077529) (xy 102.786726 -281.089502) (xy 102.8065 -281.09799) (xy 102.818184 -281.103324)
			(xy 102.844092 -281.101292) (xy 102.926642 -281.047952) (xy 102.933576 -281.043092) (xy 102.943994 -281.029756)
			(xy 102.949468 -281.013743) (xy 102.949756 -281.00528) (xy 102.949756 -280.817574) (xy 102.949276 -280.80761)
			(xy 102.941694 -280.789179) (xy 102.935024 -280.78176) (xy 102.918456 -280.764491) (xy 102.890365 -280.725748)
			(xy 102.868671 -280.683093) (xy 102.853907 -280.637573) (xy 102.846435 -280.590305) (xy 102.846439 -280.54245)
			(xy 102.853918 -280.495183) (xy 102.868689 -280.449665) (xy 102.890389 -280.407013) (xy 102.918485 -280.368275)
			(xy 102.935024 -280.350976) (xy 102.941702 -280.343564) (xy 102.949272 -280.325128) (xy 102.949756 -280.315162)
			(xy 102.949756 -280.127456) (xy 102.94906 -280.11472) (xy 102.936933 -280.092319) (xy 102.926642 -280.084784)
			(xy 102.844092 -280.031444) (xy 102.818184 -280.029412) (xy 102.8065 -280.034746) (xy 102.786733 -280.043254)
			(xy 102.745403 -280.055244) (xy 102.702795 -280.061291) (xy 102.681278 -280.06167) (xy 102.681024 -280.06167)
			(xy 102.655768 -280.061179) (xy 102.605945 -280.052869) (xy 102.558169 -280.036471) (xy 102.513744 -280.012432)
			(xy 102.473882 -279.981409) (xy 102.43967 -279.944248) (xy 102.412041 -279.901962) (xy 102.39175 -279.855705)
			(xy 102.379349 -279.806739) (xy 102.375178 -279.7564) (xy 102.379349 -279.706061) (xy 102.39175 -279.657095)
			(xy 102.412041 -279.610838) (xy 102.43967 -279.568552) (xy 102.473882 -279.531391) (xy 102.513744 -279.500368)
			(xy 102.558169 -279.476329) (xy 102.605945 -279.459931) (xy 102.655768 -279.451621) (xy 102.681024 -279.451054)
			(xy 102.681278 -279.451054) (xy 102.702793 -279.451445) (xy 102.745393 -279.457519) (xy 102.786724 -279.469495)
			(xy 102.8065 -279.477978) (xy 102.818184 -279.483312) (xy 102.844092 -279.48128) (xy 102.926642 -279.42794)
			(xy 102.933574 -279.423079) (xy 102.943989 -279.409743) (xy 102.94946 -279.39373) (xy 102.949756 -279.385268)
			(xy 102.949756 -279.232614) (xy 102.949249 -279.221779) (xy 102.940292 -279.202046) (xy 102.932484 -279.194514)
			(xy 102.91366 -279.177275) (xy 102.881027 -279.13803) (xy 102.854808 -279.09424) (xy 102.835623 -279.046942)
			(xy 102.82393 -278.99726) (xy 102.820004 -278.946371) (xy 102.823939 -278.895483) (xy 102.835641 -278.845802)
			(xy 102.854834 -278.798508) (xy 102.881061 -278.754722) (xy 102.913701 -278.715483) (xy 102.932484 -278.698198)
			(xy 102.940284 -278.690663) (xy 102.949236 -278.67093) (xy 102.949756 -278.660098) (xy 102.949756 -278.507444)
			(xy 102.949058 -278.494709) (xy 102.936927 -278.472313) (xy 102.926642 -278.464772) (xy 102.844092 -278.411432)
			(xy 102.818184 -278.4094) (xy 102.8065 -278.414734) (xy 102.786733 -278.423242) (xy 102.745403 -278.435233)
			(xy 102.702795 -278.44128) (xy 102.681278 -278.441658) (xy 102.681024 -278.441658) (xy 102.655761 -278.441167)
			(xy 102.605923 -278.432854) (xy 102.558134 -278.416451) (xy 102.513696 -278.392406) (xy 102.473822 -278.361374)
			(xy 102.4396 -278.324202) (xy 102.411964 -278.281904) (xy 102.391667 -278.235634) (xy 102.379263 -278.186654)
			(xy 102.37509 -278.1363) (xy 102.379263 -278.085946) (xy 102.391667 -278.036966) (xy 102.411964 -277.990696)
			(xy 102.4396 -277.948398) (xy 102.473822 -277.911226) (xy 102.513696 -277.880194) (xy 102.558134 -277.856149)
			(xy 102.605923 -277.839746) (xy 102.655761 -277.831433) (xy 102.681024 -277.831042) (xy 102.681278 -277.831042)
			(xy 102.702793 -277.831433) (xy 102.745393 -277.837507) (xy 102.786724 -277.849482) (xy 102.8065 -277.857966)
			(xy 102.818184 -277.8633) (xy 102.844092 -277.861268) (xy 102.926642 -277.807928) (xy 102.933584 -277.803071)
			(xy 102.944022 -277.789738) (xy 102.94952 -277.773723) (xy 102.949756 -277.765256) (xy 102.949756 -277.57755)
			(xy 102.949271 -277.567587) (xy 102.941683 -277.549163) (xy 102.935024 -277.541736) (xy 102.91845 -277.524466)
			(xy 102.890348 -277.485722) (xy 102.868642 -277.443063) (xy 102.853868 -277.397537) (xy 102.846386 -277.350263)
			(xy 102.846381 -277.3024) (xy 102.853853 -277.255123) (xy 102.868619 -277.209595) (xy 102.890315 -277.166931)
			(xy 102.918409 -277.128181) (xy 102.935024 -277.110952) (xy 102.941714 -277.103544) (xy 102.949311 -277.085108)
			(xy 102.949756 -277.075138) (xy 102.949756 -276.887432) (xy 102.949055 -276.874699) (xy 102.936922 -276.852307)
			(xy 102.926642 -276.84476) (xy 102.844092 -276.79142) (xy 102.818184 -276.789388) (xy 102.8065 -276.794722)
			(xy 102.786733 -276.80323) (xy 102.745403 -276.815222) (xy 102.702795 -276.821269) (xy 102.681278 -276.821646)
			(xy 102.681024 -276.821646) (xy 102.655762 -276.821155) (xy 102.605926 -276.812843) (xy 102.558138 -276.79644)
			(xy 102.513702 -276.772396) (xy 102.47383 -276.741365) (xy 102.43961 -276.704194) (xy 102.411974 -276.661898)
			(xy 102.391678 -276.61563) (xy 102.379274 -276.566652) (xy 102.375102 -276.5163) (xy 102.379274 -276.465948)
			(xy 102.391678 -276.41697) (xy 102.411974 -276.370702) (xy 102.43961 -276.328406) (xy 102.47383 -276.291235)
			(xy 102.513702 -276.260204) (xy 102.558138 -276.23616) (xy 102.605926 -276.219757) (xy 102.655762 -276.211445)
			(xy 102.681024 -276.21103) (xy 102.681278 -276.21103) (xy 102.702793 -276.211421) (xy 102.745393 -276.217494)
			(xy 102.786725 -276.22947) (xy 102.8065 -276.237954) (xy 102.818184 -276.243288) (xy 102.844092 -276.241256)
			(xy 102.926642 -276.187916) (xy 102.933583 -276.183059) (xy 102.944018 -276.169725) (xy 102.949512 -276.15371)
			(xy 102.949756 -276.145244) (xy 102.949756 -275.99259) (xy 102.949264 -275.981747) (xy 102.940326 -275.961992)
			(xy 102.932484 -275.95449) (xy 102.913655 -275.937251) (xy 102.88101 -275.898004) (xy 102.854779 -275.85421)
			(xy 102.835584 -275.806907) (xy 102.823881 -275.757218) (xy 102.819947 -275.706321) (xy 102.823875 -275.655424)
			(xy 102.835572 -275.605733) (xy 102.85476 -275.558428) (xy 102.880985 -275.51463) (xy 102.913625 -275.475379)
			(xy 102.932484 -275.458174) (xy 102.94028 -275.450637) (xy 102.949223 -275.430905) (xy 102.949756 -275.420074)
			(xy 102.949756 -275.26742) (xy 102.949052 -275.254688) (xy 102.936917 -275.232301) (xy 102.926642 -275.224748)
			(xy 102.844092 -275.171408) (xy 102.818184 -275.169376) (xy 102.8065 -275.17471) (xy 102.786733 -275.183219)
			(xy 102.745403 -275.19521) (xy 102.702795 -275.201258) (xy 102.681278 -275.201634) (xy 102.681024 -275.201634)
			(xy 102.655763 -275.201143) (xy 102.605929 -275.192831) (xy 102.558143 -275.176429) (xy 102.513709 -275.152386)
			(xy 102.473838 -275.121356) (xy 102.439619 -275.084187) (xy 102.411985 -275.041892) (xy 102.391689 -274.995626)
			(xy 102.379286 -274.94665) (xy 102.375114 -274.8963) (xy 102.379286 -274.84595) (xy 102.391689 -274.796974)
			(xy 102.411985 -274.750708) (xy 102.439619 -274.708413) (xy 102.473838 -274.671244) (xy 102.513709 -274.640214)
			(xy 102.558143 -274.616171) (xy 102.605929 -274.599769) (xy 102.655763 -274.591457) (xy 102.681024 -274.591018)
			(xy 102.681278 -274.591018) (xy 102.702793 -274.591408) (xy 102.745393 -274.597482) (xy 102.786725 -274.609457)
			(xy 102.8065 -274.617942) (xy 102.818184 -274.623276) (xy 102.844092 -274.621244) (xy 102.926642 -274.567904)
			(xy 102.933581 -274.563046) (xy 102.944013 -274.549712) (xy 102.949503 -274.533698) (xy 102.949756 -274.525232)
			(xy 102.949756 -274.337526) (xy 102.949267 -274.327565) (xy 102.941673 -274.309147) (xy 102.935024 -274.301712)
			(xy 102.918452 -274.284442) (xy 102.890353 -274.245699) (xy 102.868652 -274.203041) (xy 102.85388 -274.157517)
			(xy 102.846402 -274.110244) (xy 102.846399 -274.062384) (xy 102.853874 -274.015111) (xy 102.868641 -273.969585)
			(xy 102.890338 -273.926926) (xy 102.918433 -273.888179) (xy 102.935024 -273.870928) (xy 102.94171 -273.863519)
			(xy 102.949299 -273.845083) (xy 102.949756 -273.835114) (xy 102.949756 -273.647408) (xy 102.94905 -273.634678)
			(xy 102.936911 -273.612295) (xy 102.926642 -273.604736) (xy 102.844092 -273.551396) (xy 102.818184 -273.549364)
			(xy 102.8065 -273.554698) (xy 102.786732 -273.563204) (xy 102.745402 -273.575193) (xy 102.702795 -273.581238)
			(xy 102.681278 -273.581622) (xy 102.681024 -273.581622) (xy 102.655764 -273.581131) (xy 102.605932 -273.572819)
			(xy 102.558148 -273.556418) (xy 102.513715 -273.532376) (xy 102.473846 -273.501347) (xy 102.439629 -273.46418)
			(xy 102.411995 -273.421887) (xy 102.391701 -273.375622) (xy 102.379298 -273.326648) (xy 102.375126 -273.2763)
			(xy 102.379298 -273.225952) (xy 102.391701 -273.176978) (xy 102.411995 -273.130713) (xy 102.439629 -273.08842)
			(xy 102.473846 -273.051253) (xy 102.513715 -273.020224) (xy 102.558148 -272.996182) (xy 102.605932 -272.979781)
			(xy 102.655764 -272.971469) (xy 102.681024 -272.971006) (xy 102.681278 -272.971006) (xy 102.702793 -272.971396)
			(xy 102.745394 -272.97747) (xy 102.786725 -272.989444) (xy 102.8065 -272.99793) (xy 102.818184 -273.003264)
			(xy 102.844092 -273.001232) (xy 102.926642 -272.947892) (xy 102.93358 -272.943033) (xy 102.944008 -272.929699)
			(xy 102.949495 -272.913685) (xy 102.949756 -272.90522) (xy 102.949756 -272.752566) (xy 102.94926 -272.741726)
			(xy 102.940315 -272.721977) (xy 102.932484 -272.714466) (xy 102.913656 -272.697227) (xy 102.881016 -272.657981)
			(xy 102.854788 -272.614188) (xy 102.835597 -272.566887) (xy 102.823896 -272.5172) (xy 102.819965 -272.466305)
			(xy 102.823895 -272.415411) (xy 102.835594 -272.365723) (xy 102.854783 -272.318422) (xy 102.881009 -272.274628)
			(xy 102.913649 -272.23538) (xy 102.932484 -272.21815) (xy 102.940276 -272.210612) (xy 102.94921 -272.190879)
			(xy 102.949756 -272.18005) (xy 102.949756 -272.027396) (xy 102.949047 -272.014667) (xy 102.936906 -271.992289)
			(xy 102.926642 -271.984724) (xy 102.844092 -271.931384) (xy 102.818184 -271.929352) (xy 102.8065 -271.934686)
			(xy 102.786733 -271.943193) (xy 102.745402 -271.955181) (xy 102.702795 -271.961227) (xy 102.681278 -271.96161)
			(xy 102.681024 -271.96161) (xy 102.655765 -271.961119) (xy 102.605935 -271.952808) (xy 102.558153 -271.936407)
			(xy 102.513722 -271.912366) (xy 102.473855 -271.881339) (xy 102.439638 -271.844172) (xy 102.412006 -271.801881)
			(xy 102.391712 -271.755618) (xy 102.37931 -271.706646) (xy 102.375138 -271.6563) (xy 102.37931 -271.605954)
			(xy 102.391712 -271.556982) (xy 102.412006 -271.510719) (xy 102.439638 -271.468428) (xy 102.473855 -271.431261)
			(xy 102.513722 -271.400234) (xy 102.558153 -271.376193) (xy 102.605935 -271.359792) (xy 102.655765 -271.351481)
			(xy 102.681024 -271.350994) (xy 102.681278 -271.350994) (xy 102.702793 -271.351384) (xy 102.745394 -271.357458)
			(xy 102.786725 -271.369432) (xy 102.8065 -271.377918) (xy 102.818184 -271.383252) (xy 102.844092 -271.38122)
			(xy 102.926642 -271.32788) (xy 102.933579 -271.323021) (xy 102.944004 -271.309686) (xy 102.949487 -271.293672)
			(xy 102.949756 -271.285208) (xy 102.949756 -271.097502) (xy 102.949281 -271.087535) (xy 102.941706 -271.069097)
			(xy 102.935024 -271.061688) (xy 102.918454 -271.044418) (xy 102.890359 -271.005675) (xy 102.868661 -270.963019)
			(xy 102.853893 -270.917496) (xy 102.846417 -270.870226) (xy 102.846418 -270.822368) (xy 102.853894 -270.775098)
			(xy 102.868663 -270.729576) (xy 102.890362 -270.68692) (xy 102.918457 -270.648177) (xy 102.935024 -270.630904)
			(xy 102.941706 -270.623493) (xy 102.949286 -270.605058) (xy 102.949756 -270.59509) (xy 102.949756 -270.407384)
			(xy 102.949044 -270.394657) (xy 102.9369 -270.372283) (xy 102.926642 -270.364712) (xy 102.844092 -270.311372)
			(xy 102.818184 -270.30934) (xy 102.8065 -270.314674) (xy 102.786733 -270.323181) (xy 102.745402 -270.33517)
			(xy 102.702795 -270.341216) (xy 102.681278 -270.341598) (xy 102.681024 -270.341598) (xy 102.655766 -270.341107)
			(xy 102.605938 -270.332796) (xy 102.558158 -270.316396) (xy 102.513729 -270.292356) (xy 102.473863 -270.26133)
			(xy 102.439648 -270.224165) (xy 102.412017 -270.181875) (xy 102.391723 -270.135614) (xy 102.379322 -270.086644)
			(xy 102.37515 -270.0363) (xy 102.379322 -269.985956) (xy 102.391723 -269.936986) (xy 102.412017 -269.890725)
			(xy 102.439648 -269.848435) (xy 102.473863 -269.81127) (xy 102.513729 -269.780244) (xy 102.558158 -269.756204)
			(xy 102.605938 -269.739804) (xy 102.655766 -269.731493) (xy 102.681024 -269.730982) (xy 102.704167 -269.731413)
			(xy 102.749922 -269.73841) (xy 102.794094 -269.75224) (xy 102.835669 -269.772585) (xy 102.873694 -269.798978)
			(xy 102.907293 -269.830814) (xy 102.921816 -269.848838) (xy 102.922324 -269.849346) (xy 102.927601 -269.855551)
			(xy 102.941204 -269.864494) (xy 102.948994 -269.866872) (xy 102.949756 -269.867126) (xy 102.956868 -269.868396)
			(xy 102.969822 -269.868396) (xy 103.056182 -269.856204) (xy 103.062278 -269.854934) (xy 103.06685 -269.85341)
			(xy 103.067104 -269.85341) (xy 103.070851 -269.85193) (xy 103.077871 -269.847978) (xy 103.081074 -269.845536)
			(xy 103.09606 -269.825978) (xy 103.096568 -269.824708) (xy 103.109566 -269.793727) (xy 103.141879 -269.73482)
			(xy 103.180947 -269.680159) (xy 103.226219 -269.630515) (xy 103.277057 -269.586587) (xy 103.332743 -269.548996)
			(xy 103.392493 -269.51827) (xy 103.455464 -269.494844) (xy 103.520768 -269.479048) (xy 103.587484 -269.471105)
			(xy 103.621078 -269.470632) (xy 103.91902 -269.470632) (xy 103.952948 -269.471147) (xy 104.020314 -269.479295)
			(xy 104.053386 -269.486888) (xy 104.080056 -269.494) (xy 104.086372 -269.495218) (xy 104.099226 -269.494839)
			(xy 104.105456 -269.493238) (xy 104.14404 -269.482717) (xy 104.223204 -269.471374) (xy 104.26319 -269.470632)
			(xy 104.56164 -269.470632) (xy 104.580109 -269.470779) (xy 104.616969 -269.473195) (xy 104.6353 -269.475458)
			(xy 104.638602 -269.475966) (xy 104.638856 -269.475966) (xy 104.651535 -269.476925) (xy 104.675256 -269.46786)
			(xy 104.684068 -269.458694) (xy 104.708706 -269.427452) (xy 104.739694 -269.388082) (xy 104.74365 -269.382726)
			(xy 104.748927 -269.370505) (xy 104.750108 -269.363952) (xy 104.751886 -269.350744) (xy 104.74706 -269.338298)
			(xy 104.74706 -269.338044) (xy 104.73716 -269.311169) (xy 104.726422 -269.254917) (xy 104.725724 -269.226284)
			(xy 104.726246 -269.201029) (xy 104.734559 -269.151207) (xy 104.75096 -269.103433) (xy 104.775001 -269.05901)
			(xy 104.806025 -269.01915) (xy 104.843187 -268.98494) (xy 104.885473 -268.957314) (xy 104.931729 -268.937024)
			(xy 104.980694 -268.924624) (xy 105.031032 -268.920453) (xy 105.08137 -268.924624) (xy 105.130335 -268.937024)
			(xy 105.176591 -268.957314) (xy 105.218877 -268.98494) (xy 105.256039 -269.01915) (xy 105.287063 -269.05901)
			(xy 105.311104 -269.103433) (xy 105.327505 -269.151207) (xy 105.335818 -269.201029) (xy 105.33634 -269.226284)
			(xy 105.33634 -269.226792) (xy 105.336221 -269.238396) (xy 105.334438 -269.261534) (xy 105.332784 -269.27302)
			(xy 105.332276 -269.276068) (xy 105.332276 -269.277084) (xy 105.327837 -269.300735) (xy 105.312503 -269.346348)
			(xy 105.290205 -269.38899) (xy 105.261493 -269.427606) (xy 105.22708 -269.461241) (xy 105.187816 -269.48906)
			(xy 105.144674 -269.510376) (xy 105.098723 -269.524661) (xy 105.074974 -269.528544) (xy 105.071672 -269.529052)
			(xy 105.059565 -269.532306) (xy 105.040402 -269.548426) (xy 105.035096 -269.559786) (xy 105.0036 -269.637256)
			(xy 105.000044 -269.650718) (xy 104.999637 -269.655648) (xy 105.000541 -269.665498) (xy 105.001822 -269.670276)
			(xy 105.008934 -269.69085) (xy 105.01376 -269.6972) (xy 105.028492 -269.717774) (xy 105.05186 -269.755112)
			(xy 105.061333 -269.771928) (xy 105.078239 -269.806629) (xy 105.085642 -269.824454) (xy 105.088287 -269.830579)
			(xy 105.096264 -269.841267) (xy 105.10139 -269.845536) (xy 105.106724 -269.8496) (xy 105.112566 -269.85214)
			(xy 105.125774 -269.85595) (xy 105.203752 -269.866618) (xy 105.208986 -269.86721) (xy 105.219489 -269.866443)
			(xy 105.22458 -269.865094) (xy 105.225088 -269.865094) (xy 105.233216 -269.862046) (xy 105.254806 -269.851378)
			(xy 105.262934 -269.845028) (xy 105.26649 -269.84071) (xy 105.281134 -269.823774) (xy 105.314528 -269.793953)
			(xy 105.351914 -269.769322) (xy 105.392494 -269.750406) (xy 105.435398 -269.737612) (xy 105.457498 -269.73403)
			(xy 105.469182 -269.732506) (xy 105.500932 -269.730728) (xy 105.524155 -269.731162) (xy 105.570066 -269.738191)
			(xy 105.614386 -269.752083) (xy 105.656095 -269.772518) (xy 105.694234 -269.799026) (xy 105.727925 -269.830996)
			(xy 105.742486 -269.849092) (xy 105.747058 -269.854934) (xy 105.75671 -269.8623) (xy 105.762552 -269.86484)
			(xy 105.774236 -269.868142) (xy 105.777958 -269.868702) (xy 105.785484 -269.868834) (xy 105.789222 -269.868396)
			(xy 105.87609 -269.856204) (xy 105.882186 -269.854934) (xy 105.886758 -269.85341) (xy 105.887012 -269.85341)
			(xy 105.890758 -269.851929) (xy 105.897778 -269.847977) (xy 105.900982 -269.845536) (xy 105.915968 -269.825978)
			(xy 105.916476 -269.824708) (xy 105.929474 -269.793727) (xy 105.961787 -269.734821) (xy 106.000855 -269.680161)
			(xy 106.046127 -269.630517) (xy 106.096965 -269.58659) (xy 106.152652 -269.548999) (xy 106.212402 -269.518274)
			(xy 106.275373 -269.494849) (xy 106.340677 -269.479054) (xy 106.407392 -269.471112) (xy 106.440986 -269.470632)
			(xy 106.738928 -269.470632) (xy 106.772856 -269.471147) (xy 106.840222 -269.479297) (xy 106.873294 -269.486888)
			(xy 106.899964 -269.494) (xy 106.90628 -269.495217) (xy 106.919134 -269.494836) (xy 106.925364 -269.493238)
			(xy 106.963948 -269.482718) (xy 107.043112 -269.471376) (xy 107.083098 -269.470632) (xy 107.381548 -269.470632)
			(xy 107.400017 -269.470779) (xy 107.436877 -269.473196) (xy 107.455208 -269.475458) (xy 107.45851 -269.475966)
			(xy 107.458764 -269.475966) (xy 107.471442 -269.476923) (xy 107.49516 -269.467856) (xy 107.503976 -269.458694)
			(xy 107.528614 -269.427452) (xy 107.559602 -269.388082) (xy 107.563558 -269.382725) (xy 107.568833 -269.370505)
			(xy 107.570016 -269.363952) (xy 107.571794 -269.350744) (xy 107.566968 -269.338298) (xy 107.566968 -269.338044)
			(xy 107.557067 -269.311169) (xy 107.54633 -269.254917) (xy 107.545632 -269.226284) (xy 107.546079 -269.202293)
			(xy 107.553588 -269.154902) (xy 107.568419 -269.109269) (xy 107.590206 -269.066518) (xy 107.618412 -269.027701)
			(xy 107.652344 -268.993776) (xy 107.691165 -268.965576) (xy 107.73392 -268.943797) (xy 107.779556 -268.928975)
			(xy 107.826949 -268.921475) (xy 107.85094 -268.920976) (xy 107.87413 -268.92141) (xy 107.919978 -268.928426)
			(xy 107.964238 -268.942292) (xy 108.005893 -268.962688) (xy 108.043988 -268.989146) (xy 108.077645 -269.021058)
			(xy 108.09224 -269.039086) (xy 108.096304 -269.04442) (xy 108.106718 -269.052294) (xy 108.11256 -269.054834)
			(xy 108.124244 -269.058136) (xy 108.127966 -269.058696) (xy 108.135492 -269.058827) (xy 108.13923 -269.05839)
			(xy 108.226098 -269.046198) (xy 108.232194 -269.044928) (xy 108.232448 -269.044928) (xy 108.237168 -269.043535)
			(xy 108.245991 -269.039183) (xy 108.249974 -269.036292) (xy 108.251244 -269.035276) (xy 108.255674 -269.031529)
			(xy 108.262865 -269.022427) (xy 108.265468 -269.017242) (xy 108.266484 -269.014702) (xy 108.269786 -269.006828)
			(xy 108.269786 -269.006066) (xy 108.273342 -268.997938) (xy 108.273342 -268.997684) (xy 108.288139 -268.965556)
			(xy 108.324577 -268.904929) (xy 108.368289 -268.849317) (xy 108.418593 -268.799588) (xy 108.474703 -268.756517)
			(xy 108.535745 -268.720778) (xy 108.600766 -268.692926) (xy 108.668751 -268.673398) (xy 108.738641 -268.662497)
			(xy 108.773976 -268.66088) (xy 108.880402 -268.66088) (xy 108.88345 -268.660626) (xy 108.884466 -268.660626)
			(xy 108.893552 -268.65951) (xy 108.910089 -268.651693) (xy 108.916724 -268.645386) (xy 108.917232 -268.644878)
			(xy 108.922058 -268.63929) (xy 108.966762 -268.574012) (xy 108.968794 -268.57071) (xy 108.974128 -268.557502)
			(xy 108.975398 -268.54658) (xy 108.975398 -268.53261) (xy 108.973366 -268.520164) (xy 108.971334 -268.512544)
			(xy 108.964102 -268.489138) (xy 108.956323 -268.440772) (xy 108.95584 -268.416278) (xy 108.956362 -268.391023)
			(xy 108.964675 -268.341201) (xy 108.981076 -268.293427) (xy 109.005117 -268.249004) (xy 109.036141 -268.209144)
			(xy 109.073303 -268.174934) (xy 109.115589 -268.147308) (xy 109.161845 -268.127018) (xy 109.21081 -268.114618)
			(xy 109.261148 -268.110447) (xy 109.311486 -268.114618) (xy 109.360451 -268.127018) (xy 109.406707 -268.147308)
			(xy 109.448993 -268.174934) (xy 109.486155 -268.209144) (xy 109.517179 -268.249004) (xy 109.54122 -268.293427)
			(xy 109.557621 -268.341201) (xy 109.565934 -268.391023) (xy 109.566456 -268.416278) (xy 113.64901 -268.416278)
			(xy 113.65297 -268.367224) (xy 113.664747 -268.31944) (xy 113.684038 -268.274164) (xy 113.710341 -268.232568)
			(xy 113.742976 -268.195731) (xy 113.781097 -268.164606) (xy 113.823718 -268.139999) (xy 113.869734 -268.122547)
			(xy 113.917953 -268.112703) (xy 113.967128 -268.110722) (xy 114.015983 -268.116654) (xy 114.063254 -268.130346)
			(xy 114.107716 -268.151444) (xy 114.148219 -268.1794) (xy 114.183712 -268.213492) (xy 114.213277 -268.252836)
			(xy 114.236148 -268.296413) (xy 114.251732 -268.343094) (xy 114.259627 -268.391671) (xy 114.260122 -268.416278)
			(xy 115.528864 -268.416278) (xy 115.532824 -268.367224) (xy 115.544601 -268.31944) (xy 115.563892 -268.274164)
			(xy 115.590195 -268.232568) (xy 115.62283 -268.195731) (xy 115.660951 -268.164606) (xy 115.703572 -268.139999)
			(xy 115.749588 -268.122547) (xy 115.797807 -268.112703) (xy 115.846982 -268.110722) (xy 115.895837 -268.116654)
			(xy 115.943108 -268.130346) (xy 115.98757 -268.151444) (xy 116.028073 -268.1794) (xy 116.063566 -268.213492)
			(xy 116.093131 -268.252836) (xy 116.116002 -268.296413) (xy 116.131586 -268.343094) (xy 116.139481 -268.391671)
			(xy 116.139976 -268.416278) (xy 117.408972 -268.416278) (xy 117.412932 -268.367224) (xy 117.424709 -268.31944)
			(xy 117.444 -268.274164) (xy 117.470303 -268.232568) (xy 117.502938 -268.195731) (xy 117.541059 -268.164606)
			(xy 117.58368 -268.139999) (xy 117.629696 -268.122547) (xy 117.677915 -268.112703) (xy 117.72709 -268.110722)
			(xy 117.775945 -268.116654) (xy 117.823216 -268.130346) (xy 117.867678 -268.151444) (xy 117.908181 -268.1794)
			(xy 117.943674 -268.213492) (xy 117.973239 -268.252836) (xy 117.99611 -268.296413) (xy 118.011694 -268.343094)
			(xy 118.019589 -268.391671) (xy 118.020084 -268.416278) (xy 119.288826 -268.416278) (xy 119.292786 -268.367224)
			(xy 119.304563 -268.31944) (xy 119.323854 -268.274164) (xy 119.350157 -268.232568) (xy 119.382792 -268.195731)
			(xy 119.420913 -268.164606) (xy 119.463534 -268.139999) (xy 119.50955 -268.122547) (xy 119.557769 -268.112703)
			(xy 119.606944 -268.110722) (xy 119.655799 -268.116654) (xy 119.70307 -268.130346) (xy 119.747532 -268.151444)
			(xy 119.788035 -268.1794) (xy 119.823528 -268.213492) (xy 119.853093 -268.252836) (xy 119.875964 -268.296413)
			(xy 119.891548 -268.343094) (xy 119.899443 -268.391671) (xy 119.899938 -268.416278) (xy 121.168934 -268.416278)
			(xy 121.172894 -268.367224) (xy 121.184671 -268.31944) (xy 121.203962 -268.274164) (xy 121.230265 -268.232568)
			(xy 121.2629 -268.195731) (xy 121.301021 -268.164606) (xy 121.343642 -268.139999) (xy 121.389658 -268.122547)
			(xy 121.437877 -268.112703) (xy 121.487052 -268.110722) (xy 121.535907 -268.116654) (xy 121.583178 -268.130346)
			(xy 121.62764 -268.151444) (xy 121.668143 -268.1794) (xy 121.703636 -268.213492) (xy 121.733201 -268.252836)
			(xy 121.756072 -268.296413) (xy 121.771656 -268.343094) (xy 121.779551 -268.391671) (xy 121.780046 -268.416278)
			(xy 123.049042 -268.416278) (xy 123.053002 -268.367224) (xy 123.064779 -268.31944) (xy 123.08407 -268.274164)
			(xy 123.110373 -268.232568) (xy 123.143008 -268.195731) (xy 123.181129 -268.164606) (xy 123.22375 -268.139999)
			(xy 123.269766 -268.122547) (xy 123.317985 -268.112703) (xy 123.36716 -268.110722) (xy 123.416015 -268.116654)
			(xy 123.463286 -268.130346) (xy 123.507748 -268.151444) (xy 123.548251 -268.1794) (xy 123.583744 -268.213492)
			(xy 123.613309 -268.252836) (xy 123.63618 -268.296413) (xy 123.651764 -268.343094) (xy 123.659659 -268.391671)
			(xy 123.660154 -268.416278) (xy 124.928896 -268.416278) (xy 124.932856 -268.367224) (xy 124.944633 -268.31944)
			(xy 124.963924 -268.274164) (xy 124.990227 -268.232568) (xy 125.022862 -268.195731) (xy 125.060983 -268.164606)
			(xy 125.103604 -268.139999) (xy 125.14962 -268.122547) (xy 125.197839 -268.112703) (xy 125.247014 -268.110722)
			(xy 125.295869 -268.116654) (xy 125.34314 -268.130346) (xy 125.387602 -268.151444) (xy 125.428105 -268.1794)
			(xy 125.463598 -268.213492) (xy 125.493163 -268.252836) (xy 125.516034 -268.296413) (xy 125.531618 -268.343094)
			(xy 125.539513 -268.391671) (xy 125.540008 -268.416278) (xy 125.539513 -268.440885) (xy 125.531618 -268.489462)
			(xy 125.516034 -268.536143) (xy 125.493163 -268.57972) (xy 125.463598 -268.619064) (xy 125.428105 -268.653156)
			(xy 125.387602 -268.681112) (xy 125.34314 -268.70221) (xy 125.295869 -268.715902) (xy 125.247014 -268.721834)
			(xy 125.197839 -268.719853) (xy 125.14962 -268.710009) (xy 125.103604 -268.692557) (xy 125.060983 -268.66795)
			(xy 125.022862 -268.636825) (xy 124.990227 -268.599988) (xy 124.963924 -268.558392) (xy 124.944633 -268.513116)
			(xy 124.932856 -268.465332) (xy 124.928896 -268.416278) (xy 123.660154 -268.416278) (xy 123.659659 -268.440885)
			(xy 123.651764 -268.489462) (xy 123.63618 -268.536143) (xy 123.613309 -268.57972) (xy 123.583744 -268.619064)
			(xy 123.548251 -268.653156) (xy 123.507748 -268.681112) (xy 123.463286 -268.70221) (xy 123.416015 -268.715902)
			(xy 123.36716 -268.721834) (xy 123.317985 -268.719853) (xy 123.269766 -268.710009) (xy 123.22375 -268.692557)
			(xy 123.181129 -268.66795) (xy 123.143008 -268.636825) (xy 123.110373 -268.599988) (xy 123.08407 -268.558392)
			(xy 123.064779 -268.513116) (xy 123.053002 -268.465332) (xy 123.049042 -268.416278) (xy 121.780046 -268.416278)
			(xy 121.779551 -268.440885) (xy 121.771656 -268.489462) (xy 121.756072 -268.536143) (xy 121.733201 -268.57972)
			(xy 121.703636 -268.619064) (xy 121.668143 -268.653156) (xy 121.62764 -268.681112) (xy 121.583178 -268.70221)
			(xy 121.535907 -268.715902) (xy 121.487052 -268.721834) (xy 121.437877 -268.719853) (xy 121.389658 -268.710009)
			(xy 121.343642 -268.692557) (xy 121.301021 -268.66795) (xy 121.2629 -268.636825) (xy 121.230265 -268.599988)
			(xy 121.203962 -268.558392) (xy 121.184671 -268.513116) (xy 121.172894 -268.465332) (xy 121.168934 -268.416278)
			(xy 119.899938 -268.416278) (xy 119.899443 -268.440885) (xy 119.891548 -268.489462) (xy 119.875964 -268.536143)
			(xy 119.853093 -268.57972) (xy 119.823528 -268.619064) (xy 119.788035 -268.653156) (xy 119.747532 -268.681112)
			(xy 119.70307 -268.70221) (xy 119.655799 -268.715902) (xy 119.606944 -268.721834) (xy 119.557769 -268.719853)
			(xy 119.50955 -268.710009) (xy 119.463534 -268.692557) (xy 119.420913 -268.66795) (xy 119.382792 -268.636825)
			(xy 119.350157 -268.599988) (xy 119.323854 -268.558392) (xy 119.304563 -268.513116) (xy 119.292786 -268.465332)
			(xy 119.288826 -268.416278) (xy 118.020084 -268.416278) (xy 118.019589 -268.440885) (xy 118.011694 -268.489462)
			(xy 117.99611 -268.536143) (xy 117.973239 -268.57972) (xy 117.943674 -268.619064) (xy 117.908181 -268.653156)
			(xy 117.867678 -268.681112) (xy 117.823216 -268.70221) (xy 117.775945 -268.715902) (xy 117.72709 -268.721834)
			(xy 117.677915 -268.719853) (xy 117.629696 -268.710009) (xy 117.58368 -268.692557) (xy 117.541059 -268.66795)
			(xy 117.502938 -268.636825) (xy 117.470303 -268.599988) (xy 117.444 -268.558392) (xy 117.424709 -268.513116)
			(xy 117.412932 -268.465332) (xy 117.408972 -268.416278) (xy 116.139976 -268.416278) (xy 116.139481 -268.440885)
			(xy 116.131586 -268.489462) (xy 116.116002 -268.536143) (xy 116.093131 -268.57972) (xy 116.063566 -268.619064)
			(xy 116.028073 -268.653156) (xy 115.98757 -268.681112) (xy 115.943108 -268.70221) (xy 115.895837 -268.715902)
			(xy 115.846982 -268.721834) (xy 115.797807 -268.719853) (xy 115.749588 -268.710009) (xy 115.703572 -268.692557)
			(xy 115.660951 -268.66795) (xy 115.62283 -268.636825) (xy 115.590195 -268.599988) (xy 115.563892 -268.558392)
			(xy 115.544601 -268.513116) (xy 115.532824 -268.465332) (xy 115.528864 -268.416278) (xy 114.260122 -268.416278)
			(xy 114.259627 -268.440885) (xy 114.251732 -268.489462) (xy 114.236148 -268.536143) (xy 114.213277 -268.57972)
			(xy 114.183712 -268.619064) (xy 114.148219 -268.653156) (xy 114.107716 -268.681112) (xy 114.063254 -268.70221)
			(xy 114.015983 -268.715902) (xy 113.967128 -268.721834) (xy 113.917953 -268.719853) (xy 113.869734 -268.710009)
			(xy 113.823718 -268.692557) (xy 113.781097 -268.66795) (xy 113.742976 -268.636825) (xy 113.710341 -268.599988)
			(xy 113.684038 -268.558392) (xy 113.664747 -268.513116) (xy 113.65297 -268.465332) (xy 113.64901 -268.416278)
			(xy 109.566456 -268.416278) (xy 109.566456 -268.41704) (xy 109.565811 -268.44424) (xy 109.556095 -268.497769)
			(xy 109.547152 -268.523466) (xy 109.546644 -268.525244) (xy 109.544854 -268.530771) (xy 109.543581 -268.542317)
			(xy 109.544104 -268.548104) (xy 109.545628 -268.559534) (xy 109.600492 -268.63929) (xy 109.605318 -268.645132)
			(xy 109.605572 -268.645386) (xy 109.60608 -268.645894) (xy 109.612667 -268.651984) (xy 109.628926 -268.659539)
			(xy 109.63783 -268.660626) (xy 109.638846 -268.660626) (xy 109.641894 -268.66088) (xy 109.744002 -268.66088)
			(xy 109.77694 -268.662104) (xy 109.842214 -268.671273) (xy 109.905981 -268.687961) (xy 109.967379 -268.711942)
			(xy 110.025576 -268.742892) (xy 110.079784 -268.780391) (xy 110.129271 -268.823933) (xy 110.173365 -268.872927)
			(xy 110.211471 -268.926712) (xy 110.243072 -268.984558) (xy 110.255812 -269.014956) (xy 110.257844 -269.019528)
			(xy 110.260386 -269.024101) (xy 110.267038 -269.032175) (xy 110.271052 -269.03553) (xy 110.275965 -269.039234)
			(xy 110.287138 -269.044381) (xy 110.29315 -269.04569) (xy 110.30712 -269.047722) (xy 110.307628 -269.047722)
			(xy 110.383066 -269.058136) (xy 110.389837 -269.058906) (xy 110.403355 -269.057226) (xy 110.409736 -269.054834)
			(xy 110.415324 -269.052294) (xy 110.425484 -269.044674) (xy 110.429802 -269.039086) (xy 110.444372 -269.021039)
			(xy 110.478039 -268.989137) (xy 110.51614 -268.96269) (xy 110.557801 -268.942304) (xy 110.602063 -268.928447)
			(xy 110.647912 -268.921439) (xy 110.671102 -268.920976) (xy 110.696359 -268.921498) (xy 110.746183 -268.929812)
			(xy 110.793959 -268.946214) (xy 110.838384 -268.970256) (xy 110.878245 -269.001282) (xy 110.912457 -269.038446)
			(xy 110.940085 -269.080733) (xy 110.960376 -269.126992) (xy 110.972776 -269.175959) (xy 110.976946 -269.226284)
			(xy 113.178856 -269.226284) (xy 113.182816 -269.17723) (xy 113.194593 -269.129446) (xy 113.213884 -269.08417)
			(xy 113.240187 -269.042574) (xy 113.272822 -269.005737) (xy 113.310943 -268.974612) (xy 113.353564 -268.950005)
			(xy 113.39958 -268.932553) (xy 113.447799 -268.922709) (xy 113.496974 -268.920728) (xy 113.545829 -268.92666)
			(xy 113.5931 -268.940352) (xy 113.637562 -268.96145) (xy 113.678065 -268.989406) (xy 113.713558 -269.023498)
			(xy 113.743123 -269.062842) (xy 113.765994 -269.106419) (xy 113.781578 -269.1531) (xy 113.789473 -269.201677)
			(xy 113.789968 -269.226284) (xy 114.108479 -269.226284) (xy 114.112574 -269.175556) (xy 114.124753 -269.126142)
			(xy 114.144701 -269.079322) (xy 114.171902 -269.036308) (xy 114.20565 -268.998214) (xy 114.245072 -268.966027)
			(xy 114.289146 -268.940581) (xy 114.336732 -268.922534) (xy 114.386596 -268.912354) (xy 114.437448 -268.910305)
			(xy 114.487969 -268.916439) (xy 114.536853 -268.930599) (xy 114.582832 -268.952416) (xy 114.624716 -268.981326)
			(xy 114.66142 -269.016581) (xy 114.691993 -269.057267) (xy 114.715644 -269.10233) (xy 114.73176 -269.150604)
			(xy 114.739924 -269.200838) (xy 114.740436 -269.226284) (xy 115.048533 -269.226284) (xy 115.052628 -269.175556)
			(xy 115.064807 -269.126142) (xy 115.084755 -269.079322) (xy 115.111956 -269.036308) (xy 115.145704 -268.998214)
			(xy 115.185126 -268.966027) (xy 115.2292 -268.940581) (xy 115.276786 -268.922534) (xy 115.32665 -268.912354)
			(xy 115.377502 -268.910305) (xy 115.428023 -268.916439) (xy 115.476907 -268.930599) (xy 115.522886 -268.952416)
			(xy 115.56477 -268.981326) (xy 115.601474 -269.016581) (xy 115.632047 -269.057267) (xy 115.655698 -269.10233)
			(xy 115.671814 -269.150604) (xy 115.679978 -269.200838) (xy 115.68049 -269.226284) (xy 115.999018 -269.226284)
			(xy 116.002978 -269.17723) (xy 116.014755 -269.129446) (xy 116.034046 -269.08417) (xy 116.060349 -269.042574)
			(xy 116.092984 -269.005737) (xy 116.131105 -268.974612) (xy 116.173726 -268.950005) (xy 116.219742 -268.932553)
			(xy 116.267961 -268.922709) (xy 116.317136 -268.920728) (xy 116.365991 -268.92666) (xy 116.413262 -268.940352)
			(xy 116.457724 -268.96145) (xy 116.498227 -268.989406) (xy 116.53372 -269.023498) (xy 116.563285 -269.062842)
			(xy 116.586156 -269.106419) (xy 116.60174 -269.1531) (xy 116.609635 -269.201677) (xy 116.61013 -269.226284)
			(xy 118.818926 -269.226284) (xy 118.822886 -269.17723) (xy 118.834663 -269.129446) (xy 118.853954 -269.08417)
			(xy 118.880257 -269.042574) (xy 118.912892 -269.005737) (xy 118.951013 -268.974612) (xy 118.993634 -268.950005)
			(xy 119.03965 -268.932553) (xy 119.087869 -268.922709) (xy 119.137044 -268.920728) (xy 119.185899 -268.92666)
			(xy 119.23317 -268.940352) (xy 119.277632 -268.96145) (xy 119.318135 -268.989406) (xy 119.353628 -269.023498)
			(xy 119.383193 -269.062842) (xy 119.406064 -269.106419) (xy 119.421648 -269.1531) (xy 119.429543 -269.201677)
			(xy 119.430038 -269.226284) (xy 121.638834 -269.226284) (xy 121.642794 -269.17723) (xy 121.654571 -269.129446)
			(xy 121.673862 -269.08417) (xy 121.700165 -269.042574) (xy 121.7328 -269.005737) (xy 121.770921 -268.974612)
			(xy 121.813542 -268.950005) (xy 121.859558 -268.932553) (xy 121.907777 -268.922709) (xy 121.956952 -268.920728)
			(xy 122.005807 -268.92666) (xy 122.053078 -268.940352) (xy 122.09754 -268.96145) (xy 122.138043 -268.989406)
			(xy 122.173536 -269.023498) (xy 122.203101 -269.062842) (xy 122.225972 -269.106419) (xy 122.241556 -269.1531)
			(xy 122.249451 -269.201677) (xy 122.249946 -269.226284) (xy 124.458996 -269.226284) (xy 124.462956 -269.17723)
			(xy 124.474733 -269.129446) (xy 124.494024 -269.08417) (xy 124.520327 -269.042574) (xy 124.552962 -269.005737)
			(xy 124.591083 -268.974612) (xy 124.633704 -268.950005) (xy 124.67972 -268.932553) (xy 124.727939 -268.922709)
			(xy 124.777114 -268.920728) (xy 124.825969 -268.92666) (xy 124.87324 -268.940352) (xy 124.917702 -268.96145)
			(xy 124.958205 -268.989406) (xy 124.993698 -269.023498) (xy 125.023263 -269.062842) (xy 125.046134 -269.106419)
			(xy 125.061718 -269.1531) (xy 125.069613 -269.201677) (xy 125.070108 -269.226284) (xy 125.069613 -269.250891)
			(xy 125.061718 -269.299468) (xy 125.046134 -269.346149) (xy 125.023263 -269.389726) (xy 124.993698 -269.42907)
			(xy 124.958205 -269.463162) (xy 124.917702 -269.491118) (xy 124.87324 -269.512216) (xy 124.825969 -269.525908)
			(xy 124.777114 -269.53184) (xy 124.727939 -269.529859) (xy 124.67972 -269.520015) (xy 124.633704 -269.502563)
			(xy 124.591083 -269.477956) (xy 124.552962 -269.446831) (xy 124.520327 -269.409994) (xy 124.494024 -269.368398)
			(xy 124.474733 -269.323122) (xy 124.462956 -269.275338) (xy 124.458996 -269.226284) (xy 122.249946 -269.226284)
			(xy 122.249451 -269.250891) (xy 122.241556 -269.299468) (xy 122.225972 -269.346149) (xy 122.203101 -269.389726)
			(xy 122.173536 -269.42907) (xy 122.138043 -269.463162) (xy 122.09754 -269.491118) (xy 122.053078 -269.512216)
			(xy 122.005807 -269.525908) (xy 121.956952 -269.53184) (xy 121.907777 -269.529859) (xy 121.859558 -269.520015)
			(xy 121.813542 -269.502563) (xy 121.770921 -269.477956) (xy 121.7328 -269.446831) (xy 121.700165 -269.409994)
			(xy 121.673862 -269.368398) (xy 121.654571 -269.323122) (xy 121.642794 -269.275338) (xy 121.638834 -269.226284)
			(xy 119.430038 -269.226284) (xy 119.429543 -269.250891) (xy 119.421648 -269.299468) (xy 119.406064 -269.346149)
			(xy 119.383193 -269.389726) (xy 119.353628 -269.42907) (xy 119.318135 -269.463162) (xy 119.277632 -269.491118)
			(xy 119.23317 -269.512216) (xy 119.185899 -269.525908) (xy 119.137044 -269.53184) (xy 119.087869 -269.529859)
			(xy 119.03965 -269.520015) (xy 118.993634 -269.502563) (xy 118.951013 -269.477956) (xy 118.912892 -269.446831)
			(xy 118.880257 -269.409994) (xy 118.853954 -269.368398) (xy 118.834663 -269.323122) (xy 118.822886 -269.275338)
			(xy 118.818926 -269.226284) (xy 116.61013 -269.226284) (xy 116.609635 -269.250891) (xy 116.60174 -269.299468)
			(xy 116.586156 -269.346149) (xy 116.563285 -269.389726) (xy 116.53372 -269.42907) (xy 116.498227 -269.463162)
			(xy 116.457724 -269.491118) (xy 116.413262 -269.512216) (xy 116.365991 -269.525908) (xy 116.317136 -269.53184)
			(xy 116.267961 -269.529859) (xy 116.219742 -269.520015) (xy 116.173726 -269.502563) (xy 116.131105 -269.477956)
			(xy 116.092984 -269.446831) (xy 116.060349 -269.409994) (xy 116.034046 -269.368398) (xy 116.014755 -269.323122)
			(xy 116.002978 -269.275338) (xy 115.999018 -269.226284) (xy 115.68049 -269.226284) (xy 115.679978 -269.25173)
			(xy 115.671814 -269.301964) (xy 115.655698 -269.350238) (xy 115.632047 -269.395301) (xy 115.601474 -269.435987)
			(xy 115.56477 -269.471242) (xy 115.522886 -269.500152) (xy 115.476907 -269.521969) (xy 115.428023 -269.536129)
			(xy 115.377502 -269.542263) (xy 115.32665 -269.540214) (xy 115.276786 -269.530034) (xy 115.2292 -269.511987)
			(xy 115.185126 -269.486541) (xy 115.145704 -269.454354) (xy 115.111956 -269.41626) (xy 115.084755 -269.373246)
			(xy 115.064807 -269.326426) (xy 115.052628 -269.277012) (xy 115.048533 -269.226284) (xy 114.740436 -269.226284)
			(xy 114.739924 -269.25173) (xy 114.73176 -269.301964) (xy 114.715644 -269.350238) (xy 114.691993 -269.395301)
			(xy 114.66142 -269.435987) (xy 114.624716 -269.471242) (xy 114.582832 -269.500152) (xy 114.536853 -269.521969)
			(xy 114.487969 -269.536129) (xy 114.437448 -269.542263) (xy 114.386596 -269.540214) (xy 114.336732 -269.530034)
			(xy 114.289146 -269.511987) (xy 114.245072 -269.486541) (xy 114.20565 -269.454354) (xy 114.171902 -269.41626)
			(xy 114.144701 -269.373246) (xy 114.124753 -269.326426) (xy 114.112574 -269.277012) (xy 114.108479 -269.226284)
			(xy 113.789968 -269.226284) (xy 113.789473 -269.250891) (xy 113.781578 -269.299468) (xy 113.765994 -269.346149)
			(xy 113.743123 -269.389726) (xy 113.713558 -269.42907) (xy 113.678065 -269.463162) (xy 113.637562 -269.491118)
			(xy 113.5931 -269.512216) (xy 113.545829 -269.525908) (xy 113.496974 -269.53184) (xy 113.447799 -269.529859)
			(xy 113.39958 -269.520015) (xy 113.353564 -269.502563) (xy 113.310943 -269.477956) (xy 113.272822 -269.446831)
			(xy 113.240187 -269.409994) (xy 113.213884 -269.368398) (xy 113.194593 -269.323122) (xy 113.182816 -269.275338)
			(xy 113.178856 -269.226284) (xy 110.976946 -269.226284) (xy 110.976947 -269.2263) (xy 110.972776 -269.276641)
			(xy 110.960376 -269.325608) (xy 110.940085 -269.371867) (xy 110.912457 -269.414154) (xy 110.878245 -269.451318)
			(xy 110.838384 -269.482344) (xy 110.793959 -269.506386) (xy 110.746183 -269.522788) (xy 110.696359 -269.531102)
			(xy 110.671102 -269.531592) (xy 110.65834 -269.531439) (xy 110.632907 -269.529279) (xy 110.620302 -269.527274)
			(xy 110.620302 -269.527528) (xy 110.597972 -269.523332) (xy 110.554787 -269.509215) (xy 110.514164 -269.488866)
			(xy 110.476998 -269.462733) (xy 110.444106 -269.43139) (xy 110.429802 -269.413736) (xy 110.424976 -269.40764)
			(xy 110.415324 -269.400274) (xy 110.409482 -269.397734) (xy 110.404016 -269.395639) (xy 110.392472 -269.393721)
			(xy 110.386622 -269.393924) (xy 110.292896 -269.406878) (xy 110.288243 -269.4079) (xy 110.279415 -269.411475)
			(xy 110.27537 -269.41399) (xy 110.270036 -269.418054) (xy 110.265965 -269.421652) (xy 110.259312 -269.430239)
			(xy 110.256828 -269.435072) (xy 110.255558 -269.437866) (xy 110.25505 -269.439136) (xy 110.253272 -269.443708)
			(xy 110.252764 -269.44701) (xy 110.25124 -269.455392) (xy 110.250874 -269.459203) (xy 110.251128 -269.466854)
			(xy 110.251748 -269.470632) (xy 110.25378 -269.479014) (xy 110.256066 -269.48765) (xy 110.258352 -269.492222)
			(xy 110.259368 -269.493746) (xy 110.279923 -269.531492) (xy 110.315905 -269.609555) (xy 110.33125 -269.649702)
			(xy 110.340934 -269.676241) (xy 110.357959 -269.730114) (xy 110.365286 -269.757398) (xy 110.366302 -269.761208)
			(xy 110.367572 -269.76578) (xy 110.385352 -269.792704) (xy 110.38967 -269.79626) (xy 110.391956 -269.798038)
			(xy 110.411104 -269.81403) (xy 110.444437 -269.851145) (xy 110.471308 -269.893176) (xy 110.481618 -269.915894)
			(xy 110.489521 -269.93523) (xy 110.500606 -269.975502) (xy 110.503716 -269.996158) (xy 110.503716 -269.996412)
			(xy 110.50397 -269.997936) (xy 110.504986 -270.004794) (xy 110.519718 -270.035782) (xy 110.520248 -270.03629)
			(xy 113.64901 -270.03629) (xy 113.65297 -269.987236) (xy 113.664747 -269.939452) (xy 113.684038 -269.894176)
			(xy 113.710341 -269.85258) (xy 113.742976 -269.815743) (xy 113.781097 -269.784618) (xy 113.823718 -269.760011)
			(xy 113.869734 -269.742559) (xy 113.917953 -269.732715) (xy 113.967128 -269.730734) (xy 114.015983 -269.736666)
			(xy 114.063254 -269.750358) (xy 114.107716 -269.771456) (xy 114.148219 -269.799412) (xy 114.183712 -269.833504)
			(xy 114.213277 -269.872848) (xy 114.236148 -269.916425) (xy 114.251732 -269.963106) (xy 114.259627 -270.011683)
			(xy 114.260122 -270.03629) (xy 114.58881 -270.03629) (xy 114.59277 -269.987236) (xy 114.604547 -269.939452)
			(xy 114.623838 -269.894176) (xy 114.650141 -269.85258) (xy 114.682776 -269.815743) (xy 114.720897 -269.784618)
			(xy 114.763518 -269.760011) (xy 114.809534 -269.742559) (xy 114.857753 -269.732715) (xy 114.906928 -269.730734)
			(xy 114.955783 -269.736666) (xy 115.003054 -269.750358) (xy 115.047516 -269.771456) (xy 115.088019 -269.799412)
			(xy 115.123512 -269.833504) (xy 115.153077 -269.872848) (xy 115.175948 -269.916425) (xy 115.191532 -269.963106)
			(xy 115.199427 -270.011683) (xy 115.199922 -270.03629) (xy 115.528864 -270.03629) (xy 115.532824 -269.987236)
			(xy 115.544601 -269.939452) (xy 115.563892 -269.894176) (xy 115.590195 -269.85258) (xy 115.62283 -269.815743)
			(xy 115.660951 -269.784618) (xy 115.703572 -269.760011) (xy 115.749588 -269.742559) (xy 115.797807 -269.732715)
			(xy 115.846982 -269.730734) (xy 115.895837 -269.736666) (xy 115.943108 -269.750358) (xy 115.98757 -269.771456)
			(xy 116.028073 -269.799412) (xy 116.063566 -269.833504) (xy 116.093131 -269.872848) (xy 116.116002 -269.916425)
			(xy 116.131586 -269.963106) (xy 116.139481 -270.011683) (xy 116.139976 -270.03629) (xy 116.458487 -270.03629)
			(xy 116.462582 -269.985562) (xy 116.474761 -269.936148) (xy 116.494709 -269.889328) (xy 116.52191 -269.846314)
			(xy 116.555658 -269.80822) (xy 116.59508 -269.776033) (xy 116.639154 -269.750587) (xy 116.68674 -269.73254)
			(xy 116.736604 -269.72236) (xy 116.787456 -269.720311) (xy 116.837977 -269.726445) (xy 116.886861 -269.740605)
			(xy 116.93284 -269.762422) (xy 116.974724 -269.791332) (xy 117.011428 -269.826587) (xy 117.042001 -269.867273)
			(xy 117.065652 -269.912336) (xy 117.081768 -269.96061) (xy 117.089932 -270.010844) (xy 117.090444 -270.03629)
			(xy 117.398541 -270.03629) (xy 117.402636 -269.985562) (xy 117.414815 -269.936148) (xy 117.434763 -269.889328)
			(xy 117.461964 -269.846314) (xy 117.495712 -269.80822) (xy 117.535134 -269.776033) (xy 117.579208 -269.750587)
			(xy 117.626794 -269.73254) (xy 117.676658 -269.72236) (xy 117.72751 -269.720311) (xy 117.778031 -269.726445)
			(xy 117.826915 -269.740605) (xy 117.872894 -269.762422) (xy 117.914778 -269.791332) (xy 117.951482 -269.826587)
			(xy 117.982055 -269.867273) (xy 118.005706 -269.912336) (xy 118.021822 -269.96061) (xy 118.029986 -270.010844)
			(xy 118.030498 -270.03629) (xy 118.349026 -270.03629) (xy 118.352986 -269.987236) (xy 118.364763 -269.939452)
			(xy 118.384054 -269.894176) (xy 118.410357 -269.85258) (xy 118.442992 -269.815743) (xy 118.481113 -269.784618)
			(xy 118.523734 -269.760011) (xy 118.56975 -269.742559) (xy 118.617969 -269.732715) (xy 118.667144 -269.730734)
			(xy 118.715999 -269.736666) (xy 118.76327 -269.750358) (xy 118.807732 -269.771456) (xy 118.848235 -269.799412)
			(xy 118.883728 -269.833504) (xy 118.913293 -269.872848) (xy 118.936164 -269.916425) (xy 118.951748 -269.963106)
			(xy 118.959643 -270.011683) (xy 118.960138 -270.03629) (xy 119.278395 -270.03629) (xy 119.28249 -269.985562)
			(xy 119.294669 -269.936148) (xy 119.314617 -269.889328) (xy 119.341818 -269.846314) (xy 119.375566 -269.80822)
			(xy 119.414988 -269.776033) (xy 119.459062 -269.750587) (xy 119.506648 -269.73254) (xy 119.556512 -269.72236)
			(xy 119.607364 -269.720311) (xy 119.657885 -269.726445) (xy 119.706769 -269.740605) (xy 119.752748 -269.762422)
			(xy 119.794632 -269.791332) (xy 119.831336 -269.826587) (xy 119.861909 -269.867273) (xy 119.88556 -269.912336)
			(xy 119.901676 -269.96061) (xy 119.90984 -270.010844) (xy 119.910352 -270.03629) (xy 120.218449 -270.03629)
			(xy 120.222544 -269.985562) (xy 120.234723 -269.936148) (xy 120.254671 -269.889328) (xy 120.281872 -269.846314)
			(xy 120.31562 -269.80822) (xy 120.355042 -269.776033) (xy 120.399116 -269.750587) (xy 120.446702 -269.73254)
			(xy 120.496566 -269.72236) (xy 120.547418 -269.720311) (xy 120.597939 -269.726445) (xy 120.646823 -269.740605)
			(xy 120.692802 -269.762422) (xy 120.734686 -269.791332) (xy 120.77139 -269.826587) (xy 120.801963 -269.867273)
			(xy 120.825614 -269.912336) (xy 120.84173 -269.96061) (xy 120.849894 -270.010844) (xy 120.850406 -270.03629)
			(xy 121.168934 -270.03629) (xy 121.172894 -269.987236) (xy 121.184671 -269.939452) (xy 121.203962 -269.894176)
			(xy 121.230265 -269.85258) (xy 121.2629 -269.815743) (xy 121.301021 -269.784618) (xy 121.343642 -269.760011)
			(xy 121.389658 -269.742559) (xy 121.437877 -269.732715) (xy 121.487052 -269.730734) (xy 121.535907 -269.736666)
			(xy 121.583178 -269.750358) (xy 121.62764 -269.771456) (xy 121.668143 -269.799412) (xy 121.703636 -269.833504)
			(xy 121.733201 -269.872848) (xy 121.756072 -269.916425) (xy 121.771656 -269.963106) (xy 121.779551 -270.011683)
			(xy 121.780046 -270.03629) (xy 122.098557 -270.03629) (xy 122.102652 -269.985562) (xy 122.114831 -269.936148)
			(xy 122.134779 -269.889328) (xy 122.16198 -269.846314) (xy 122.195728 -269.80822) (xy 122.23515 -269.776033)
			(xy 122.279224 -269.750587) (xy 122.32681 -269.73254) (xy 122.376674 -269.72236) (xy 122.427526 -269.720311)
			(xy 122.478047 -269.726445) (xy 122.526931 -269.740605) (xy 122.57291 -269.762422) (xy 122.614794 -269.791332)
			(xy 122.651498 -269.826587) (xy 122.682071 -269.867273) (xy 122.705722 -269.912336) (xy 122.721838 -269.96061)
			(xy 122.730002 -270.010844) (xy 122.730514 -270.03629) (xy 123.038611 -270.03629) (xy 123.042706 -269.985562)
			(xy 123.054885 -269.936148) (xy 123.074833 -269.889328) (xy 123.102034 -269.846314) (xy 123.135782 -269.80822)
			(xy 123.175204 -269.776033) (xy 123.219278 -269.750587) (xy 123.266864 -269.73254) (xy 123.316728 -269.72236)
			(xy 123.36758 -269.720311) (xy 123.418101 -269.726445) (xy 123.466985 -269.740605) (xy 123.512964 -269.762422)
			(xy 123.554848 -269.791332) (xy 123.591552 -269.826587) (xy 123.622125 -269.867273) (xy 123.645776 -269.912336)
			(xy 123.661892 -269.96061) (xy 123.670056 -270.010844) (xy 123.670568 -270.03629) (xy 123.988842 -270.03629)
			(xy 123.992802 -269.987236) (xy 124.004579 -269.939452) (xy 124.02387 -269.894176) (xy 124.050173 -269.85258)
			(xy 124.082808 -269.815743) (xy 124.120929 -269.784618) (xy 124.16355 -269.760011) (xy 124.209566 -269.742559)
			(xy 124.257785 -269.732715) (xy 124.30696 -269.730734) (xy 124.355815 -269.736666) (xy 124.403086 -269.750358)
			(xy 124.447548 -269.771456) (xy 124.488051 -269.799412) (xy 124.523544 -269.833504) (xy 124.553109 -269.872848)
			(xy 124.57598 -269.916425) (xy 124.591564 -269.963106) (xy 124.599459 -270.011683) (xy 124.599954 -270.03629)
			(xy 124.918465 -270.03629) (xy 124.92256 -269.985562) (xy 124.934739 -269.936148) (xy 124.954687 -269.889328)
			(xy 124.981888 -269.846314) (xy 125.015636 -269.80822) (xy 125.055058 -269.776033) (xy 125.099132 -269.750587)
			(xy 125.146718 -269.73254) (xy 125.196582 -269.72236) (xy 125.247434 -269.720311) (xy 125.297955 -269.726445)
			(xy 125.346839 -269.740605) (xy 125.392818 -269.762422) (xy 125.434702 -269.791332) (xy 125.471406 -269.826587)
			(xy 125.501979 -269.867273) (xy 125.52563 -269.912336) (xy 125.541746 -269.96061) (xy 125.54991 -270.010844)
			(xy 125.550422 -270.03629) (xy 125.858519 -270.03629) (xy 125.862614 -269.985562) (xy 125.874793 -269.936148)
			(xy 125.894741 -269.889328) (xy 125.921942 -269.846314) (xy 125.95569 -269.80822) (xy 125.995112 -269.776033)
			(xy 126.039186 -269.750587) (xy 126.086772 -269.73254) (xy 126.136636 -269.72236) (xy 126.187488 -269.720311)
			(xy 126.238009 -269.726445) (xy 126.286893 -269.740605) (xy 126.332872 -269.762422) (xy 126.374756 -269.791332)
			(xy 126.41146 -269.826587) (xy 126.442033 -269.867273) (xy 126.465684 -269.912336) (xy 126.4818 -269.96061)
			(xy 126.489964 -270.010844) (xy 126.490476 -270.03629) (xy 126.489964 -270.061736) (xy 126.4818 -270.11197)
			(xy 126.465684 -270.160244) (xy 126.442033 -270.205307) (xy 126.41146 -270.245993) (xy 126.374756 -270.281248)
			(xy 126.332872 -270.310158) (xy 126.286893 -270.331975) (xy 126.238009 -270.346135) (xy 126.187488 -270.352269)
			(xy 126.136636 -270.35022) (xy 126.086772 -270.34004) (xy 126.039186 -270.321993) (xy 125.995112 -270.296547)
			(xy 125.95569 -270.26436) (xy 125.921942 -270.226266) (xy 125.894741 -270.183252) (xy 125.874793 -270.136432)
			(xy 125.862614 -270.087018) (xy 125.858519 -270.03629) (xy 125.550422 -270.03629) (xy 125.54991 -270.061736)
			(xy 125.541746 -270.11197) (xy 125.52563 -270.160244) (xy 125.501979 -270.205307) (xy 125.471406 -270.245993)
			(xy 125.434702 -270.281248) (xy 125.392818 -270.310158) (xy 125.346839 -270.331975) (xy 125.297955 -270.346135)
			(xy 125.247434 -270.352269) (xy 125.196582 -270.35022) (xy 125.146718 -270.34004) (xy 125.099132 -270.321993)
			(xy 125.055058 -270.296547) (xy 125.015636 -270.26436) (xy 124.981888 -270.226266) (xy 124.954687 -270.183252)
			(xy 124.934739 -270.136432) (xy 124.92256 -270.087018) (xy 124.918465 -270.03629) (xy 124.599954 -270.03629)
			(xy 124.599459 -270.060897) (xy 124.591564 -270.109474) (xy 124.57598 -270.156155) (xy 124.553109 -270.199732)
			(xy 124.523544 -270.239076) (xy 124.488051 -270.273168) (xy 124.447548 -270.301124) (xy 124.403086 -270.322222)
			(xy 124.355815 -270.335914) (xy 124.30696 -270.341846) (xy 124.257785 -270.339865) (xy 124.209566 -270.330021)
			(xy 124.16355 -270.312569) (xy 124.120929 -270.287962) (xy 124.082808 -270.256837) (xy 124.050173 -270.22)
			(xy 124.02387 -270.178404) (xy 124.004579 -270.133128) (xy 123.992802 -270.085344) (xy 123.988842 -270.03629)
			(xy 123.670568 -270.03629) (xy 123.670056 -270.061736) (xy 123.661892 -270.11197) (xy 123.645776 -270.160244)
			(xy 123.622125 -270.205307) (xy 123.591552 -270.245993) (xy 123.554848 -270.281248) (xy 123.512964 -270.310158)
			(xy 123.466985 -270.331975) (xy 123.418101 -270.346135) (xy 123.36758 -270.352269) (xy 123.316728 -270.35022)
			(xy 123.266864 -270.34004) (xy 123.219278 -270.321993) (xy 123.175204 -270.296547) (xy 123.135782 -270.26436)
			(xy 123.102034 -270.226266) (xy 123.074833 -270.183252) (xy 123.054885 -270.136432) (xy 123.042706 -270.087018)
			(xy 123.038611 -270.03629) (xy 122.730514 -270.03629) (xy 122.730002 -270.061736) (xy 122.721838 -270.11197)
			(xy 122.705722 -270.160244) (xy 122.682071 -270.205307) (xy 122.651498 -270.245993) (xy 122.614794 -270.281248)
			(xy 122.57291 -270.310158) (xy 122.526931 -270.331975) (xy 122.478047 -270.346135) (xy 122.427526 -270.352269)
			(xy 122.376674 -270.35022) (xy 122.32681 -270.34004) (xy 122.279224 -270.321993) (xy 122.23515 -270.296547)
			(xy 122.195728 -270.26436) (xy 122.16198 -270.226266) (xy 122.134779 -270.183252) (xy 122.114831 -270.136432)
			(xy 122.102652 -270.087018) (xy 122.098557 -270.03629) (xy 121.780046 -270.03629) (xy 121.779551 -270.060897)
			(xy 121.771656 -270.109474) (xy 121.756072 -270.156155) (xy 121.733201 -270.199732) (xy 121.703636 -270.239076)
			(xy 121.668143 -270.273168) (xy 121.62764 -270.301124) (xy 121.583178 -270.322222) (xy 121.535907 -270.335914)
			(xy 121.487052 -270.341846) (xy 121.437877 -270.339865) (xy 121.389658 -270.330021) (xy 121.343642 -270.312569)
			(xy 121.301021 -270.287962) (xy 121.2629 -270.256837) (xy 121.230265 -270.22) (xy 121.203962 -270.178404)
			(xy 121.184671 -270.133128) (xy 121.172894 -270.085344) (xy 121.168934 -270.03629) (xy 120.850406 -270.03629)
			(xy 120.849894 -270.061736) (xy 120.84173 -270.11197) (xy 120.825614 -270.160244) (xy 120.801963 -270.205307)
			(xy 120.77139 -270.245993) (xy 120.734686 -270.281248) (xy 120.692802 -270.310158) (xy 120.646823 -270.331975)
			(xy 120.597939 -270.346135) (xy 120.547418 -270.352269) (xy 120.496566 -270.35022) (xy 120.446702 -270.34004)
			(xy 120.399116 -270.321993) (xy 120.355042 -270.296547) (xy 120.31562 -270.26436) (xy 120.281872 -270.226266)
			(xy 120.254671 -270.183252) (xy 120.234723 -270.136432) (xy 120.222544 -270.087018) (xy 120.218449 -270.03629)
			(xy 119.910352 -270.03629) (xy 119.90984 -270.061736) (xy 119.901676 -270.11197) (xy 119.88556 -270.160244)
			(xy 119.861909 -270.205307) (xy 119.831336 -270.245993) (xy 119.794632 -270.281248) (xy 119.752748 -270.310158)
			(xy 119.706769 -270.331975) (xy 119.657885 -270.346135) (xy 119.607364 -270.352269) (xy 119.556512 -270.35022)
			(xy 119.506648 -270.34004) (xy 119.459062 -270.321993) (xy 119.414988 -270.296547) (xy 119.375566 -270.26436)
			(xy 119.341818 -270.226266) (xy 119.314617 -270.183252) (xy 119.294669 -270.136432) (xy 119.28249 -270.087018)
			(xy 119.278395 -270.03629) (xy 118.960138 -270.03629) (xy 118.959643 -270.060897) (xy 118.951748 -270.109474)
			(xy 118.936164 -270.156155) (xy 118.913293 -270.199732) (xy 118.883728 -270.239076) (xy 118.848235 -270.273168)
			(xy 118.807732 -270.301124) (xy 118.76327 -270.322222) (xy 118.715999 -270.335914) (xy 118.667144 -270.341846)
			(xy 118.617969 -270.339865) (xy 118.56975 -270.330021) (xy 118.523734 -270.312569) (xy 118.481113 -270.287962)
			(xy 118.442992 -270.256837) (xy 118.410357 -270.22) (xy 118.384054 -270.178404) (xy 118.364763 -270.133128)
			(xy 118.352986 -270.085344) (xy 118.349026 -270.03629) (xy 118.030498 -270.03629) (xy 118.029986 -270.061736)
			(xy 118.021822 -270.11197) (xy 118.005706 -270.160244) (xy 117.982055 -270.205307) (xy 117.951482 -270.245993)
			(xy 117.914778 -270.281248) (xy 117.872894 -270.310158) (xy 117.826915 -270.331975) (xy 117.778031 -270.346135)
			(xy 117.72751 -270.352269) (xy 117.676658 -270.35022) (xy 117.626794 -270.34004) (xy 117.579208 -270.321993)
			(xy 117.535134 -270.296547) (xy 117.495712 -270.26436) (xy 117.461964 -270.226266) (xy 117.434763 -270.183252)
			(xy 117.414815 -270.136432) (xy 117.402636 -270.087018) (xy 117.398541 -270.03629) (xy 117.090444 -270.03629)
			(xy 117.089932 -270.061736) (xy 117.081768 -270.11197) (xy 117.065652 -270.160244) (xy 117.042001 -270.205307)
			(xy 117.011428 -270.245993) (xy 116.974724 -270.281248) (xy 116.93284 -270.310158) (xy 116.886861 -270.331975)
			(xy 116.837977 -270.346135) (xy 116.787456 -270.352269) (xy 116.736604 -270.35022) (xy 116.68674 -270.34004)
			(xy 116.639154 -270.321993) (xy 116.59508 -270.296547) (xy 116.555658 -270.26436) (xy 116.52191 -270.226266)
			(xy 116.494709 -270.183252) (xy 116.474761 -270.136432) (xy 116.462582 -270.087018) (xy 116.458487 -270.03629)
			(xy 116.139976 -270.03629) (xy 116.139481 -270.060897) (xy 116.131586 -270.109474) (xy 116.116002 -270.156155)
			(xy 116.093131 -270.199732) (xy 116.063566 -270.239076) (xy 116.028073 -270.273168) (xy 115.98757 -270.301124)
			(xy 115.943108 -270.322222) (xy 115.895837 -270.335914) (xy 115.846982 -270.341846) (xy 115.797807 -270.339865)
			(xy 115.749588 -270.330021) (xy 115.703572 -270.312569) (xy 115.660951 -270.287962) (xy 115.62283 -270.256837)
			(xy 115.590195 -270.22) (xy 115.563892 -270.178404) (xy 115.544601 -270.133128) (xy 115.532824 -270.085344)
			(xy 115.528864 -270.03629) (xy 115.199922 -270.03629) (xy 115.199427 -270.060897) (xy 115.191532 -270.109474)
			(xy 115.175948 -270.156155) (xy 115.153077 -270.199732) (xy 115.123512 -270.239076) (xy 115.088019 -270.273168)
			(xy 115.047516 -270.301124) (xy 115.003054 -270.322222) (xy 114.955783 -270.335914) (xy 114.906928 -270.341846)
			(xy 114.857753 -270.339865) (xy 114.809534 -270.330021) (xy 114.763518 -270.312569) (xy 114.720897 -270.287962)
			(xy 114.682776 -270.256837) (xy 114.650141 -270.22) (xy 114.623838 -270.178404) (xy 114.604547 -270.133128)
			(xy 114.59277 -270.085344) (xy 114.58881 -270.03629) (xy 114.260122 -270.03629) (xy 114.259627 -270.060897)
			(xy 114.251732 -270.109474) (xy 114.236148 -270.156155) (xy 114.213277 -270.199732) (xy 114.183712 -270.239076)
			(xy 114.148219 -270.273168) (xy 114.107716 -270.301124) (xy 114.063254 -270.322222) (xy 114.015983 -270.335914)
			(xy 113.967128 -270.341846) (xy 113.917953 -270.339865) (xy 113.869734 -270.330021) (xy 113.823718 -270.312569)
			(xy 113.781097 -270.287962) (xy 113.742976 -270.256837) (xy 113.710341 -270.22) (xy 113.684038 -270.178404)
			(xy 113.664747 -270.133128) (xy 113.65297 -270.085344) (xy 113.64901 -270.03629) (xy 110.520248 -270.03629)
			(xy 110.525814 -270.041624) (xy 110.556294 -270.072866) (xy 110.588438 -270.10787) (xy 110.647392 -270.18242)
			(xy 110.699884 -270.261653) (xy 110.745543 -270.34501) (xy 110.784048 -270.431904) (xy 110.815127 -270.521723)
			(xy 110.827312 -270.567658) (xy 110.827312 -270.567912) (xy 110.828905 -270.573603) (xy 110.834301 -270.584114)
			(xy 110.83798 -270.58874) (xy 110.845092 -270.595344) (xy 110.866979 -270.611216) (xy 110.905291 -270.649355)
			(xy 110.93628 -270.693651) (xy 110.958974 -270.742716) (xy 110.972663 -270.795014) (xy 110.975394 -270.821912)
			(xy 110.976156 -270.831056) (xy 110.979712 -270.83893) (xy 110.981692 -270.842912) (xy 110.984066 -270.846296)
			(xy 113.178856 -270.846296) (xy 113.182816 -270.797242) (xy 113.194593 -270.749458) (xy 113.213884 -270.704182)
			(xy 113.240187 -270.662586) (xy 113.272822 -270.625749) (xy 113.310943 -270.594624) (xy 113.353564 -270.570017)
			(xy 113.39958 -270.552565) (xy 113.447799 -270.542721) (xy 113.496974 -270.54074) (xy 113.545829 -270.546672)
			(xy 113.5931 -270.560364) (xy 113.637562 -270.581462) (xy 113.678065 -270.609418) (xy 113.713558 -270.64351)
			(xy 113.743123 -270.682854) (xy 113.765994 -270.726431) (xy 113.781578 -270.773112) (xy 113.789473 -270.821689)
			(xy 113.789968 -270.846296) (xy 114.108479 -270.846296) (xy 114.112574 -270.795568) (xy 114.124753 -270.746154)
			(xy 114.144701 -270.699334) (xy 114.171902 -270.65632) (xy 114.20565 -270.618226) (xy 114.245072 -270.586039)
			(xy 114.289146 -270.560593) (xy 114.336732 -270.542546) (xy 114.386596 -270.532366) (xy 114.437448 -270.530317)
			(xy 114.487969 -270.536451) (xy 114.536853 -270.550611) (xy 114.582832 -270.572428) (xy 114.624716 -270.601338)
			(xy 114.66142 -270.636593) (xy 114.691993 -270.677279) (xy 114.715644 -270.722342) (xy 114.73176 -270.770616)
			(xy 114.739924 -270.82085) (xy 114.740436 -270.846296) (xy 115.048533 -270.846296) (xy 115.052628 -270.795568)
			(xy 115.064807 -270.746154) (xy 115.084755 -270.699334) (xy 115.111956 -270.65632) (xy 115.145704 -270.618226)
			(xy 115.185126 -270.586039) (xy 115.2292 -270.560593) (xy 115.276786 -270.542546) (xy 115.32665 -270.532366)
			(xy 115.377502 -270.530317) (xy 115.428023 -270.536451) (xy 115.476907 -270.550611) (xy 115.522886 -270.572428)
			(xy 115.56477 -270.601338) (xy 115.601474 -270.636593) (xy 115.632047 -270.677279) (xy 115.655698 -270.722342)
			(xy 115.671814 -270.770616) (xy 115.679978 -270.82085) (xy 115.68049 -270.846296) (xy 115.999018 -270.846296)
			(xy 116.002978 -270.797242) (xy 116.014755 -270.749458) (xy 116.034046 -270.704182) (xy 116.060349 -270.662586)
			(xy 116.092984 -270.625749) (xy 116.131105 -270.594624) (xy 116.173726 -270.570017) (xy 116.219742 -270.552565)
			(xy 116.267961 -270.542721) (xy 116.317136 -270.54074) (xy 116.365991 -270.546672) (xy 116.413262 -270.560364)
			(xy 116.457724 -270.581462) (xy 116.498227 -270.609418) (xy 116.53372 -270.64351) (xy 116.563285 -270.682854)
			(xy 116.586156 -270.726431) (xy 116.60174 -270.773112) (xy 116.609635 -270.821689) (xy 116.61013 -270.846296)
			(xy 116.938818 -270.846296) (xy 116.942778 -270.797242) (xy 116.954555 -270.749458) (xy 116.973846 -270.704182)
			(xy 117.000149 -270.662586) (xy 117.032784 -270.625749) (xy 117.070905 -270.594624) (xy 117.113526 -270.570017)
			(xy 117.159542 -270.552565) (xy 117.207761 -270.542721) (xy 117.256936 -270.54074) (xy 117.305791 -270.546672)
			(xy 117.353062 -270.560364) (xy 117.397524 -270.581462) (xy 117.438027 -270.609418) (xy 117.47352 -270.64351)
			(xy 117.503085 -270.682854) (xy 117.525956 -270.726431) (xy 117.54154 -270.773112) (xy 117.549435 -270.821689)
			(xy 117.54993 -270.846296) (xy 117.878872 -270.846296) (xy 117.882832 -270.797242) (xy 117.894609 -270.749458)
			(xy 117.9139 -270.704182) (xy 117.940203 -270.662586) (xy 117.972838 -270.625749) (xy 118.010959 -270.594624)
			(xy 118.05358 -270.570017) (xy 118.099596 -270.552565) (xy 118.147815 -270.542721) (xy 118.19699 -270.54074)
			(xy 118.245845 -270.546672) (xy 118.293116 -270.560364) (xy 118.337578 -270.581462) (xy 118.378081 -270.609418)
			(xy 118.413574 -270.64351) (xy 118.443139 -270.682854) (xy 118.46601 -270.726431) (xy 118.481594 -270.773112)
			(xy 118.489489 -270.821689) (xy 118.489984 -270.846296) (xy 118.818926 -270.846296) (xy 118.822886 -270.797242)
			(xy 118.834663 -270.749458) (xy 118.853954 -270.704182) (xy 118.880257 -270.662586) (xy 118.912892 -270.625749)
			(xy 118.951013 -270.594624) (xy 118.993634 -270.570017) (xy 119.03965 -270.552565) (xy 119.087869 -270.542721)
			(xy 119.137044 -270.54074) (xy 119.185899 -270.546672) (xy 119.23317 -270.560364) (xy 119.277632 -270.581462)
			(xy 119.318135 -270.609418) (xy 119.353628 -270.64351) (xy 119.383193 -270.682854) (xy 119.406064 -270.726431)
			(xy 119.421648 -270.773112) (xy 119.429543 -270.821689) (xy 119.430038 -270.846296) (xy 119.75898 -270.846296)
			(xy 119.76294 -270.797242) (xy 119.774717 -270.749458) (xy 119.794008 -270.704182) (xy 119.820311 -270.662586)
			(xy 119.852946 -270.625749) (xy 119.891067 -270.594624) (xy 119.933688 -270.570017) (xy 119.979704 -270.552565)
			(xy 120.027923 -270.542721) (xy 120.077098 -270.54074) (xy 120.125953 -270.546672) (xy 120.173224 -270.560364)
			(xy 120.217686 -270.581462) (xy 120.258189 -270.609418) (xy 120.293682 -270.64351) (xy 120.323247 -270.682854)
			(xy 120.346118 -270.726431) (xy 120.361702 -270.773112) (xy 120.369597 -270.821689) (xy 120.370092 -270.846296)
			(xy 120.699034 -270.846296) (xy 120.702994 -270.797242) (xy 120.714771 -270.749458) (xy 120.734062 -270.704182)
			(xy 120.760365 -270.662586) (xy 120.793 -270.625749) (xy 120.831121 -270.594624) (xy 120.873742 -270.570017)
			(xy 120.919758 -270.552565) (xy 120.967977 -270.542721) (xy 121.017152 -270.54074) (xy 121.066007 -270.546672)
			(xy 121.113278 -270.560364) (xy 121.15774 -270.581462) (xy 121.198243 -270.609418) (xy 121.233736 -270.64351)
			(xy 121.263301 -270.682854) (xy 121.286172 -270.726431) (xy 121.301756 -270.773112) (xy 121.309651 -270.821689)
			(xy 121.310146 -270.846296) (xy 121.638834 -270.846296) (xy 121.642794 -270.797242) (xy 121.654571 -270.749458)
			(xy 121.673862 -270.704182) (xy 121.700165 -270.662586) (xy 121.7328 -270.625749) (xy 121.770921 -270.594624)
			(xy 121.813542 -270.570017) (xy 121.859558 -270.552565) (xy 121.907777 -270.542721) (xy 121.956952 -270.54074)
			(xy 122.005807 -270.546672) (xy 122.053078 -270.560364) (xy 122.09754 -270.581462) (xy 122.138043 -270.609418)
			(xy 122.173536 -270.64351) (xy 122.203101 -270.682854) (xy 122.225972 -270.726431) (xy 122.241556 -270.773112)
			(xy 122.249451 -270.821689) (xy 122.249946 -270.846296) (xy 122.578888 -270.846296) (xy 122.582848 -270.797242)
			(xy 122.594625 -270.749458) (xy 122.613916 -270.704182) (xy 122.640219 -270.662586) (xy 122.672854 -270.625749)
			(xy 122.710975 -270.594624) (xy 122.753596 -270.570017) (xy 122.799612 -270.552565) (xy 122.847831 -270.542721)
			(xy 122.897006 -270.54074) (xy 122.945861 -270.546672) (xy 122.993132 -270.560364) (xy 123.037594 -270.581462)
			(xy 123.078097 -270.609418) (xy 123.11359 -270.64351) (xy 123.143155 -270.682854) (xy 123.166026 -270.726431)
			(xy 123.18161 -270.773112) (xy 123.189505 -270.821689) (xy 123.19 -270.846296) (xy 123.518942 -270.846296)
			(xy 123.522902 -270.797242) (xy 123.534679 -270.749458) (xy 123.55397 -270.704182) (xy 123.580273 -270.662586)
			(xy 123.612908 -270.625749) (xy 123.651029 -270.594624) (xy 123.69365 -270.570017) (xy 123.739666 -270.552565)
			(xy 123.787885 -270.542721) (xy 123.83706 -270.54074) (xy 123.885915 -270.546672) (xy 123.933186 -270.560364)
			(xy 123.977648 -270.581462) (xy 124.018151 -270.609418) (xy 124.053644 -270.64351) (xy 124.083209 -270.682854)
			(xy 124.10608 -270.726431) (xy 124.121664 -270.773112) (xy 124.129559 -270.821689) (xy 124.130054 -270.846296)
			(xy 124.458996 -270.846296) (xy 124.462956 -270.797242) (xy 124.474733 -270.749458) (xy 124.494024 -270.704182)
			(xy 124.520327 -270.662586) (xy 124.552962 -270.625749) (xy 124.591083 -270.594624) (xy 124.633704 -270.570017)
			(xy 124.67972 -270.552565) (xy 124.727939 -270.542721) (xy 124.777114 -270.54074) (xy 124.825969 -270.546672)
			(xy 124.87324 -270.560364) (xy 124.917702 -270.581462) (xy 124.958205 -270.609418) (xy 124.993698 -270.64351)
			(xy 125.023263 -270.682854) (xy 125.046134 -270.726431) (xy 125.061718 -270.773112) (xy 125.069613 -270.821689)
			(xy 125.070108 -270.846296) (xy 125.39905 -270.846296) (xy 125.40301 -270.797242) (xy 125.414787 -270.749458)
			(xy 125.434078 -270.704182) (xy 125.460381 -270.662586) (xy 125.493016 -270.625749) (xy 125.531137 -270.594624)
			(xy 125.573758 -270.570017) (xy 125.619774 -270.552565) (xy 125.667993 -270.542721) (xy 125.717168 -270.54074)
			(xy 125.766023 -270.546672) (xy 125.813294 -270.560364) (xy 125.857756 -270.581462) (xy 125.898259 -270.609418)
			(xy 125.933752 -270.64351) (xy 125.963317 -270.682854) (xy 125.986188 -270.726431) (xy 126.001772 -270.773112)
			(xy 126.009667 -270.821689) (xy 126.010162 -270.846296) (xy 126.009667 -270.870903) (xy 126.001772 -270.91948)
			(xy 125.986188 -270.966161) (xy 125.963317 -271.009738) (xy 125.933752 -271.049082) (xy 125.898259 -271.083174)
			(xy 125.857756 -271.11113) (xy 125.813294 -271.132228) (xy 125.766023 -271.14592) (xy 125.717168 -271.151852)
			(xy 125.667993 -271.149871) (xy 125.619774 -271.140027) (xy 125.573758 -271.122575) (xy 125.531137 -271.097968)
			(xy 125.493016 -271.066843) (xy 125.460381 -271.030006) (xy 125.434078 -270.98841) (xy 125.414787 -270.943134)
			(xy 125.40301 -270.89535) (xy 125.39905 -270.846296) (xy 125.070108 -270.846296) (xy 125.069613 -270.870903)
			(xy 125.061718 -270.91948) (xy 125.046134 -270.966161) (xy 125.023263 -271.009738) (xy 124.993698 -271.049082)
			(xy 124.958205 -271.083174) (xy 124.917702 -271.11113) (xy 124.87324 -271.132228) (xy 124.825969 -271.14592)
			(xy 124.777114 -271.151852) (xy 124.727939 -271.149871) (xy 124.67972 -271.140027) (xy 124.633704 -271.122575)
			(xy 124.591083 -271.097968) (xy 124.552962 -271.066843) (xy 124.520327 -271.030006) (xy 124.494024 -270.98841)
			(xy 124.474733 -270.943134) (xy 124.462956 -270.89535) (xy 124.458996 -270.846296) (xy 124.130054 -270.846296)
			(xy 124.129559 -270.870903) (xy 124.121664 -270.91948) (xy 124.10608 -270.966161) (xy 124.083209 -271.009738)
			(xy 124.053644 -271.049082) (xy 124.018151 -271.083174) (xy 123.977648 -271.11113) (xy 123.933186 -271.132228)
			(xy 123.885915 -271.14592) (xy 123.83706 -271.151852) (xy 123.787885 -271.149871) (xy 123.739666 -271.140027)
			(xy 123.69365 -271.122575) (xy 123.651029 -271.097968) (xy 123.612908 -271.066843) (xy 123.580273 -271.030006)
			(xy 123.55397 -270.98841) (xy 123.534679 -270.943134) (xy 123.522902 -270.89535) (xy 123.518942 -270.846296)
			(xy 123.19 -270.846296) (xy 123.189505 -270.870903) (xy 123.18161 -270.91948) (xy 123.166026 -270.966161)
			(xy 123.143155 -271.009738) (xy 123.11359 -271.049082) (xy 123.078097 -271.083174) (xy 123.037594 -271.11113)
			(xy 122.993132 -271.132228) (xy 122.945861 -271.14592) (xy 122.897006 -271.151852) (xy 122.847831 -271.149871)
			(xy 122.799612 -271.140027) (xy 122.753596 -271.122575) (xy 122.710975 -271.097968) (xy 122.672854 -271.066843)
			(xy 122.640219 -271.030006) (xy 122.613916 -270.98841) (xy 122.594625 -270.943134) (xy 122.582848 -270.89535)
			(xy 122.578888 -270.846296) (xy 122.249946 -270.846296) (xy 122.249451 -270.870903) (xy 122.241556 -270.91948)
			(xy 122.225972 -270.966161) (xy 122.203101 -271.009738) (xy 122.173536 -271.049082) (xy 122.138043 -271.083174)
			(xy 122.09754 -271.11113) (xy 122.053078 -271.132228) (xy 122.005807 -271.14592) (xy 121.956952 -271.151852)
			(xy 121.907777 -271.149871) (xy 121.859558 -271.140027) (xy 121.813542 -271.122575) (xy 121.770921 -271.097968)
			(xy 121.7328 -271.066843) (xy 121.700165 -271.030006) (xy 121.673862 -270.98841) (xy 121.654571 -270.943134)
			(xy 121.642794 -270.89535) (xy 121.638834 -270.846296) (xy 121.310146 -270.846296) (xy 121.309651 -270.870903)
			(xy 121.301756 -270.91948) (xy 121.286172 -270.966161) (xy 121.263301 -271.009738) (xy 121.233736 -271.049082)
			(xy 121.198243 -271.083174) (xy 121.15774 -271.11113) (xy 121.113278 -271.132228) (xy 121.066007 -271.14592)
			(xy 121.017152 -271.151852) (xy 120.967977 -271.149871) (xy 120.919758 -271.140027) (xy 120.873742 -271.122575)
			(xy 120.831121 -271.097968) (xy 120.793 -271.066843) (xy 120.760365 -271.030006) (xy 120.734062 -270.98841)
			(xy 120.714771 -270.943134) (xy 120.702994 -270.89535) (xy 120.699034 -270.846296) (xy 120.370092 -270.846296)
			(xy 120.369597 -270.870903) (xy 120.361702 -270.91948) (xy 120.346118 -270.966161) (xy 120.323247 -271.009738)
			(xy 120.293682 -271.049082) (xy 120.258189 -271.083174) (xy 120.217686 -271.11113) (xy 120.173224 -271.132228)
			(xy 120.125953 -271.14592) (xy 120.077098 -271.151852) (xy 120.027923 -271.149871) (xy 119.979704 -271.140027)
			(xy 119.933688 -271.122575) (xy 119.891067 -271.097968) (xy 119.852946 -271.066843) (xy 119.820311 -271.030006)
			(xy 119.794008 -270.98841) (xy 119.774717 -270.943134) (xy 119.76294 -270.89535) (xy 119.75898 -270.846296)
			(xy 119.430038 -270.846296) (xy 119.429543 -270.870903) (xy 119.421648 -270.91948) (xy 119.406064 -270.966161)
			(xy 119.383193 -271.009738) (xy 119.353628 -271.049082) (xy 119.318135 -271.083174) (xy 119.277632 -271.11113)
			(xy 119.23317 -271.132228) (xy 119.185899 -271.14592) (xy 119.137044 -271.151852) (xy 119.087869 -271.149871)
			(xy 119.03965 -271.140027) (xy 118.993634 -271.122575) (xy 118.951013 -271.097968) (xy 118.912892 -271.066843)
			(xy 118.880257 -271.030006) (xy 118.853954 -270.98841) (xy 118.834663 -270.943134) (xy 118.822886 -270.89535)
			(xy 118.818926 -270.846296) (xy 118.489984 -270.846296) (xy 118.489489 -270.870903) (xy 118.481594 -270.91948)
			(xy 118.46601 -270.966161) (xy 118.443139 -271.009738) (xy 118.413574 -271.049082) (xy 118.378081 -271.083174)
			(xy 118.337578 -271.11113) (xy 118.293116 -271.132228) (xy 118.245845 -271.14592) (xy 118.19699 -271.151852)
			(xy 118.147815 -271.149871) (xy 118.099596 -271.140027) (xy 118.05358 -271.122575) (xy 118.010959 -271.097968)
			(xy 117.972838 -271.066843) (xy 117.940203 -271.030006) (xy 117.9139 -270.98841) (xy 117.894609 -270.943134)
			(xy 117.882832 -270.89535) (xy 117.878872 -270.846296) (xy 117.54993 -270.846296) (xy 117.549435 -270.870903)
			(xy 117.54154 -270.91948) (xy 117.525956 -270.966161) (xy 117.503085 -271.009738) (xy 117.47352 -271.049082)
			(xy 117.438027 -271.083174) (xy 117.397524 -271.11113) (xy 117.353062 -271.132228) (xy 117.305791 -271.14592)
			(xy 117.256936 -271.151852) (xy 117.207761 -271.149871) (xy 117.159542 -271.140027) (xy 117.113526 -271.122575)
			(xy 117.070905 -271.097968) (xy 117.032784 -271.066843) (xy 117.000149 -271.030006) (xy 116.973846 -270.98841)
			(xy 116.954555 -270.943134) (xy 116.942778 -270.89535) (xy 116.938818 -270.846296) (xy 116.61013 -270.846296)
			(xy 116.609635 -270.870903) (xy 116.60174 -270.91948) (xy 116.586156 -270.966161) (xy 116.563285 -271.009738)
			(xy 116.53372 -271.049082) (xy 116.498227 -271.083174) (xy 116.457724 -271.11113) (xy 116.413262 -271.132228)
			(xy 116.365991 -271.14592) (xy 116.317136 -271.151852) (xy 116.267961 -271.149871) (xy 116.219742 -271.140027)
			(xy 116.173726 -271.122575) (xy 116.131105 -271.097968) (xy 116.092984 -271.066843) (xy 116.060349 -271.030006)
			(xy 116.034046 -270.98841) (xy 116.014755 -270.943134) (xy 116.002978 -270.89535) (xy 115.999018 -270.846296)
			(xy 115.68049 -270.846296) (xy 115.679978 -270.871742) (xy 115.671814 -270.921976) (xy 115.655698 -270.97025)
			(xy 115.632047 -271.015313) (xy 115.601474 -271.055999) (xy 115.56477 -271.091254) (xy 115.522886 -271.120164)
			(xy 115.476907 -271.141981) (xy 115.428023 -271.156141) (xy 115.377502 -271.162275) (xy 115.32665 -271.160226)
			(xy 115.276786 -271.150046) (xy 115.2292 -271.131999) (xy 115.185126 -271.106553) (xy 115.145704 -271.074366)
			(xy 115.111956 -271.036272) (xy 115.084755 -270.993258) (xy 115.064807 -270.946438) (xy 115.052628 -270.897024)
			(xy 115.048533 -270.846296) (xy 114.740436 -270.846296) (xy 114.739924 -270.871742) (xy 114.73176 -270.921976)
			(xy 114.715644 -270.97025) (xy 114.691993 -271.015313) (xy 114.66142 -271.055999) (xy 114.624716 -271.091254)
			(xy 114.582832 -271.120164) (xy 114.536853 -271.141981) (xy 114.487969 -271.156141) (xy 114.437448 -271.162275)
			(xy 114.386596 -271.160226) (xy 114.336732 -271.150046) (xy 114.289146 -271.131999) (xy 114.245072 -271.106553)
			(xy 114.20565 -271.074366) (xy 114.171902 -271.036272) (xy 114.144701 -270.993258) (xy 114.124753 -270.946438)
			(xy 114.112574 -270.897024) (xy 114.108479 -270.846296) (xy 113.789968 -270.846296) (xy 113.789473 -270.870903)
			(xy 113.781578 -270.91948) (xy 113.765994 -270.966161) (xy 113.743123 -271.009738) (xy 113.713558 -271.049082)
			(xy 113.678065 -271.083174) (xy 113.637562 -271.11113) (xy 113.5931 -271.132228) (xy 113.545829 -271.14592)
			(xy 113.496974 -271.151852) (xy 113.447799 -271.149871) (xy 113.39958 -271.140027) (xy 113.353564 -271.122575)
			(xy 113.310943 -271.097968) (xy 113.272822 -271.066843) (xy 113.240187 -271.030006) (xy 113.213884 -270.98841)
			(xy 113.194593 -270.943134) (xy 113.182816 -270.89535) (xy 113.178856 -270.846296) (xy 110.984066 -270.846296)
			(xy 110.986799 -270.850193) (xy 110.989872 -270.853408) (xy 111.34725 -271.210786) (xy 111.357918 -271.214596)
			(xy 111.387563 -271.22582) (xy 111.444424 -271.253841) (xy 111.497887 -271.287902) (xy 111.547311 -271.327597)
			(xy 111.570008 -271.349724) (xy 111.876586 -271.656302) (xy 115.528864 -271.656302) (xy 115.532824 -271.607248)
			(xy 115.544601 -271.559464) (xy 115.563892 -271.514188) (xy 115.590195 -271.472592) (xy 115.62283 -271.435755)
			(xy 115.660951 -271.40463) (xy 115.703572 -271.380023) (xy 115.749588 -271.362571) (xy 115.797807 -271.352727)
			(xy 115.846982 -271.350746) (xy 115.895837 -271.356678) (xy 115.943108 -271.37037) (xy 115.98757 -271.391468)
			(xy 116.028073 -271.419424) (xy 116.063566 -271.453516) (xy 116.093131 -271.49286) (xy 116.116002 -271.536437)
			(xy 116.131586 -271.583118) (xy 116.139481 -271.631695) (xy 116.139976 -271.656302) (xy 116.458487 -271.656302)
			(xy 116.462582 -271.605574) (xy 116.474761 -271.55616) (xy 116.494709 -271.50934) (xy 116.52191 -271.466326)
			(xy 116.555658 -271.428232) (xy 116.59508 -271.396045) (xy 116.639154 -271.370599) (xy 116.68674 -271.352552)
			(xy 116.736604 -271.342372) (xy 116.787456 -271.340323) (xy 116.837977 -271.346457) (xy 116.886861 -271.360617)
			(xy 116.93284 -271.382434) (xy 116.974724 -271.411344) (xy 117.011428 -271.446599) (xy 117.042001 -271.487285)
			(xy 117.065652 -271.532348) (xy 117.081768 -271.580622) (xy 117.089932 -271.630856) (xy 117.090444 -271.656302)
			(xy 117.398541 -271.656302) (xy 117.402636 -271.605574) (xy 117.414815 -271.55616) (xy 117.434763 -271.50934)
			(xy 117.461964 -271.466326) (xy 117.495712 -271.428232) (xy 117.535134 -271.396045) (xy 117.579208 -271.370599)
			(xy 117.626794 -271.352552) (xy 117.676658 -271.342372) (xy 117.72751 -271.340323) (xy 117.778031 -271.346457)
			(xy 117.826915 -271.360617) (xy 117.872894 -271.382434) (xy 117.914778 -271.411344) (xy 117.951482 -271.446599)
			(xy 117.982055 -271.487285) (xy 118.005706 -271.532348) (xy 118.021822 -271.580622) (xy 118.029986 -271.630856)
			(xy 118.030498 -271.656302) (xy 118.349026 -271.656302) (xy 118.352986 -271.607248) (xy 118.364763 -271.559464)
			(xy 118.384054 -271.514188) (xy 118.410357 -271.472592) (xy 118.442992 -271.435755) (xy 118.481113 -271.40463)
			(xy 118.523734 -271.380023) (xy 118.56975 -271.362571) (xy 118.617969 -271.352727) (xy 118.667144 -271.350746)
			(xy 118.715999 -271.356678) (xy 118.76327 -271.37037) (xy 118.807732 -271.391468) (xy 118.848235 -271.419424)
			(xy 118.883728 -271.453516) (xy 118.913293 -271.49286) (xy 118.936164 -271.536437) (xy 118.951748 -271.583118)
			(xy 118.959643 -271.631695) (xy 118.960138 -271.656302) (xy 119.278395 -271.656302) (xy 119.28249 -271.605574)
			(xy 119.294669 -271.55616) (xy 119.314617 -271.50934) (xy 119.341818 -271.466326) (xy 119.375566 -271.428232)
			(xy 119.414988 -271.396045) (xy 119.459062 -271.370599) (xy 119.506648 -271.352552) (xy 119.556512 -271.342372)
			(xy 119.607364 -271.340323) (xy 119.657885 -271.346457) (xy 119.706769 -271.360617) (xy 119.752748 -271.382434)
			(xy 119.794632 -271.411344) (xy 119.831336 -271.446599) (xy 119.861909 -271.487285) (xy 119.88556 -271.532348)
			(xy 119.901676 -271.580622) (xy 119.90984 -271.630856) (xy 119.910352 -271.656302) (xy 120.218449 -271.656302)
			(xy 120.222544 -271.605574) (xy 120.234723 -271.55616) (xy 120.254671 -271.50934) (xy 120.281872 -271.466326)
			(xy 120.31562 -271.428232) (xy 120.355042 -271.396045) (xy 120.399116 -271.370599) (xy 120.446702 -271.352552)
			(xy 120.496566 -271.342372) (xy 120.547418 -271.340323) (xy 120.597939 -271.346457) (xy 120.646823 -271.360617)
			(xy 120.692802 -271.382434) (xy 120.734686 -271.411344) (xy 120.77139 -271.446599) (xy 120.801963 -271.487285)
			(xy 120.825614 -271.532348) (xy 120.84173 -271.580622) (xy 120.849894 -271.630856) (xy 120.850406 -271.656302)
			(xy 121.168934 -271.656302) (xy 121.172894 -271.607248) (xy 121.184671 -271.559464) (xy 121.203962 -271.514188)
			(xy 121.230265 -271.472592) (xy 121.2629 -271.435755) (xy 121.301021 -271.40463) (xy 121.343642 -271.380023)
			(xy 121.389658 -271.362571) (xy 121.437877 -271.352727) (xy 121.487052 -271.350746) (xy 121.535907 -271.356678)
			(xy 121.583178 -271.37037) (xy 121.62764 -271.391468) (xy 121.668143 -271.419424) (xy 121.703636 -271.453516)
			(xy 121.733201 -271.49286) (xy 121.756072 -271.536437) (xy 121.771656 -271.583118) (xy 121.779551 -271.631695)
			(xy 121.780046 -271.656302) (xy 122.098557 -271.656302) (xy 122.102652 -271.605574) (xy 122.114831 -271.55616)
			(xy 122.134779 -271.50934) (xy 122.16198 -271.466326) (xy 122.195728 -271.428232) (xy 122.23515 -271.396045)
			(xy 122.279224 -271.370599) (xy 122.32681 -271.352552) (xy 122.376674 -271.342372) (xy 122.427526 -271.340323)
			(xy 122.478047 -271.346457) (xy 122.526931 -271.360617) (xy 122.57291 -271.382434) (xy 122.614794 -271.411344)
			(xy 122.651498 -271.446599) (xy 122.682071 -271.487285) (xy 122.705722 -271.532348) (xy 122.721838 -271.580622)
			(xy 122.730002 -271.630856) (xy 122.730514 -271.656302) (xy 123.038611 -271.656302) (xy 123.042706 -271.605574)
			(xy 123.054885 -271.55616) (xy 123.074833 -271.50934) (xy 123.102034 -271.466326) (xy 123.135782 -271.428232)
			(xy 123.175204 -271.396045) (xy 123.219278 -271.370599) (xy 123.266864 -271.352552) (xy 123.316728 -271.342372)
			(xy 123.36758 -271.340323) (xy 123.418101 -271.346457) (xy 123.466985 -271.360617) (xy 123.512964 -271.382434)
			(xy 123.554848 -271.411344) (xy 123.591552 -271.446599) (xy 123.622125 -271.487285) (xy 123.645776 -271.532348)
			(xy 123.661892 -271.580622) (xy 123.670056 -271.630856) (xy 123.670568 -271.656302) (xy 123.988842 -271.656302)
			(xy 123.992802 -271.607248) (xy 124.004579 -271.559464) (xy 124.02387 -271.514188) (xy 124.050173 -271.472592)
			(xy 124.082808 -271.435755) (xy 124.120929 -271.40463) (xy 124.16355 -271.380023) (xy 124.209566 -271.362571)
			(xy 124.257785 -271.352727) (xy 124.30696 -271.350746) (xy 124.355815 -271.356678) (xy 124.403086 -271.37037)
			(xy 124.447548 -271.391468) (xy 124.488051 -271.419424) (xy 124.523544 -271.453516) (xy 124.553109 -271.49286)
			(xy 124.57598 -271.536437) (xy 124.591564 -271.583118) (xy 124.599459 -271.631695) (xy 124.599954 -271.656302)
			(xy 124.918465 -271.656302) (xy 124.92256 -271.605574) (xy 124.934739 -271.55616) (xy 124.954687 -271.50934)
			(xy 124.981888 -271.466326) (xy 125.015636 -271.428232) (xy 125.055058 -271.396045) (xy 125.099132 -271.370599)
			(xy 125.146718 -271.352552) (xy 125.196582 -271.342372) (xy 125.247434 -271.340323) (xy 125.297955 -271.346457)
			(xy 125.346839 -271.360617) (xy 125.392818 -271.382434) (xy 125.434702 -271.411344) (xy 125.471406 -271.446599)
			(xy 125.501979 -271.487285) (xy 125.52563 -271.532348) (xy 125.541746 -271.580622) (xy 125.54991 -271.630856)
			(xy 125.550422 -271.656302) (xy 125.858519 -271.656302) (xy 125.862614 -271.605574) (xy 125.874793 -271.55616)
			(xy 125.894741 -271.50934) (xy 125.921942 -271.466326) (xy 125.95569 -271.428232) (xy 125.995112 -271.396045)
			(xy 126.039186 -271.370599) (xy 126.086772 -271.352552) (xy 126.136636 -271.342372) (xy 126.187488 -271.340323)
			(xy 126.238009 -271.346457) (xy 126.286893 -271.360617) (xy 126.332872 -271.382434) (xy 126.374756 -271.411344)
			(xy 126.41146 -271.446599) (xy 126.442033 -271.487285) (xy 126.465684 -271.532348) (xy 126.4818 -271.580622)
			(xy 126.489964 -271.630856) (xy 126.490476 -271.656302) (xy 126.489964 -271.681748) (xy 126.4818 -271.731982)
			(xy 126.465684 -271.780256) (xy 126.442033 -271.825319) (xy 126.41146 -271.866005) (xy 126.374756 -271.90126)
			(xy 126.332872 -271.93017) (xy 126.286893 -271.951987) (xy 126.238009 -271.966147) (xy 126.187488 -271.972281)
			(xy 126.136636 -271.970232) (xy 126.086772 -271.960052) (xy 126.039186 -271.942005) (xy 125.995112 -271.916559)
			(xy 125.95569 -271.884372) (xy 125.921942 -271.846278) (xy 125.894741 -271.803264) (xy 125.874793 -271.756444)
			(xy 125.862614 -271.70703) (xy 125.858519 -271.656302) (xy 125.550422 -271.656302) (xy 125.54991 -271.681748)
			(xy 125.541746 -271.731982) (xy 125.52563 -271.780256) (xy 125.501979 -271.825319) (xy 125.471406 -271.866005)
			(xy 125.434702 -271.90126) (xy 125.392818 -271.93017) (xy 125.346839 -271.951987) (xy 125.297955 -271.966147)
			(xy 125.247434 -271.972281) (xy 125.196582 -271.970232) (xy 125.146718 -271.960052) (xy 125.099132 -271.942005)
			(xy 125.055058 -271.916559) (xy 125.015636 -271.884372) (xy 124.981888 -271.846278) (xy 124.954687 -271.803264)
			(xy 124.934739 -271.756444) (xy 124.92256 -271.70703) (xy 124.918465 -271.656302) (xy 124.599954 -271.656302)
			(xy 124.599459 -271.680909) (xy 124.591564 -271.729486) (xy 124.57598 -271.776167) (xy 124.553109 -271.819744)
			(xy 124.523544 -271.859088) (xy 124.488051 -271.89318) (xy 124.447548 -271.921136) (xy 124.403086 -271.942234)
			(xy 124.355815 -271.955926) (xy 124.30696 -271.961858) (xy 124.257785 -271.959877) (xy 124.209566 -271.950033)
			(xy 124.16355 -271.932581) (xy 124.120929 -271.907974) (xy 124.082808 -271.876849) (xy 124.050173 -271.840012)
			(xy 124.02387 -271.798416) (xy 124.004579 -271.75314) (xy 123.992802 -271.705356) (xy 123.988842 -271.656302)
			(xy 123.670568 -271.656302) (xy 123.670056 -271.681748) (xy 123.661892 -271.731982) (xy 123.645776 -271.780256)
			(xy 123.622125 -271.825319) (xy 123.591552 -271.866005) (xy 123.554848 -271.90126) (xy 123.512964 -271.93017)
			(xy 123.466985 -271.951987) (xy 123.418101 -271.966147) (xy 123.36758 -271.972281) (xy 123.316728 -271.970232)
			(xy 123.266864 -271.960052) (xy 123.219278 -271.942005) (xy 123.175204 -271.916559) (xy 123.135782 -271.884372)
			(xy 123.102034 -271.846278) (xy 123.074833 -271.803264) (xy 123.054885 -271.756444) (xy 123.042706 -271.70703)
			(xy 123.038611 -271.656302) (xy 122.730514 -271.656302) (xy 122.730002 -271.681748) (xy 122.721838 -271.731982)
			(xy 122.705722 -271.780256) (xy 122.682071 -271.825319) (xy 122.651498 -271.866005) (xy 122.614794 -271.90126)
			(xy 122.57291 -271.93017) (xy 122.526931 -271.951987) (xy 122.478047 -271.966147) (xy 122.427526 -271.972281)
			(xy 122.376674 -271.970232) (xy 122.32681 -271.960052) (xy 122.279224 -271.942005) (xy 122.23515 -271.916559)
			(xy 122.195728 -271.884372) (xy 122.16198 -271.846278) (xy 122.134779 -271.803264) (xy 122.114831 -271.756444)
			(xy 122.102652 -271.70703) (xy 122.098557 -271.656302) (xy 121.780046 -271.656302) (xy 121.779551 -271.680909)
			(xy 121.771656 -271.729486) (xy 121.756072 -271.776167) (xy 121.733201 -271.819744) (xy 121.703636 -271.859088)
			(xy 121.668143 -271.89318) (xy 121.62764 -271.921136) (xy 121.583178 -271.942234) (xy 121.535907 -271.955926)
			(xy 121.487052 -271.961858) (xy 121.437877 -271.959877) (xy 121.389658 -271.950033) (xy 121.343642 -271.932581)
			(xy 121.301021 -271.907974) (xy 121.2629 -271.876849) (xy 121.230265 -271.840012) (xy 121.203962 -271.798416)
			(xy 121.184671 -271.75314) (xy 121.172894 -271.705356) (xy 121.168934 -271.656302) (xy 120.850406 -271.656302)
			(xy 120.849894 -271.681748) (xy 120.84173 -271.731982) (xy 120.825614 -271.780256) (xy 120.801963 -271.825319)
			(xy 120.77139 -271.866005) (xy 120.734686 -271.90126) (xy 120.692802 -271.93017) (xy 120.646823 -271.951987)
			(xy 120.597939 -271.966147) (xy 120.547418 -271.972281) (xy 120.496566 -271.970232) (xy 120.446702 -271.960052)
			(xy 120.399116 -271.942005) (xy 120.355042 -271.916559) (xy 120.31562 -271.884372) (xy 120.281872 -271.846278)
			(xy 120.254671 -271.803264) (xy 120.234723 -271.756444) (xy 120.222544 -271.70703) (xy 120.218449 -271.656302)
			(xy 119.910352 -271.656302) (xy 119.90984 -271.681748) (xy 119.901676 -271.731982) (xy 119.88556 -271.780256)
			(xy 119.861909 -271.825319) (xy 119.831336 -271.866005) (xy 119.794632 -271.90126) (xy 119.752748 -271.93017)
			(xy 119.706769 -271.951987) (xy 119.657885 -271.966147) (xy 119.607364 -271.972281) (xy 119.556512 -271.970232)
			(xy 119.506648 -271.960052) (xy 119.459062 -271.942005) (xy 119.414988 -271.916559) (xy 119.375566 -271.884372)
			(xy 119.341818 -271.846278) (xy 119.314617 -271.803264) (xy 119.294669 -271.756444) (xy 119.28249 -271.70703)
			(xy 119.278395 -271.656302) (xy 118.960138 -271.656302) (xy 118.959643 -271.680909) (xy 118.951748 -271.729486)
			(xy 118.936164 -271.776167) (xy 118.913293 -271.819744) (xy 118.883728 -271.859088) (xy 118.848235 -271.89318)
			(xy 118.807732 -271.921136) (xy 118.76327 -271.942234) (xy 118.715999 -271.955926) (xy 118.667144 -271.961858)
			(xy 118.617969 -271.959877) (xy 118.56975 -271.950033) (xy 118.523734 -271.932581) (xy 118.481113 -271.907974)
			(xy 118.442992 -271.876849) (xy 118.410357 -271.840012) (xy 118.384054 -271.798416) (xy 118.364763 -271.75314)
			(xy 118.352986 -271.705356) (xy 118.349026 -271.656302) (xy 118.030498 -271.656302) (xy 118.029986 -271.681748)
			(xy 118.021822 -271.731982) (xy 118.005706 -271.780256) (xy 117.982055 -271.825319) (xy 117.951482 -271.866005)
			(xy 117.914778 -271.90126) (xy 117.872894 -271.93017) (xy 117.826915 -271.951987) (xy 117.778031 -271.966147)
			(xy 117.72751 -271.972281) (xy 117.676658 -271.970232) (xy 117.626794 -271.960052) (xy 117.579208 -271.942005)
			(xy 117.535134 -271.916559) (xy 117.495712 -271.884372) (xy 117.461964 -271.846278) (xy 117.434763 -271.803264)
			(xy 117.414815 -271.756444) (xy 117.402636 -271.70703) (xy 117.398541 -271.656302) (xy 117.090444 -271.656302)
			(xy 117.089932 -271.681748) (xy 117.081768 -271.731982) (xy 117.065652 -271.780256) (xy 117.042001 -271.825319)
			(xy 117.011428 -271.866005) (xy 116.974724 -271.90126) (xy 116.93284 -271.93017) (xy 116.886861 -271.951987)
			(xy 116.837977 -271.966147) (xy 116.787456 -271.972281) (xy 116.736604 -271.970232) (xy 116.68674 -271.960052)
			(xy 116.639154 -271.942005) (xy 116.59508 -271.916559) (xy 116.555658 -271.884372) (xy 116.52191 -271.846278)
			(xy 116.494709 -271.803264) (xy 116.474761 -271.756444) (xy 116.462582 -271.70703) (xy 116.458487 -271.656302)
			(xy 116.139976 -271.656302) (xy 116.139481 -271.680909) (xy 116.131586 -271.729486) (xy 116.116002 -271.776167)
			(xy 116.093131 -271.819744) (xy 116.063566 -271.859088) (xy 116.028073 -271.89318) (xy 115.98757 -271.921136)
			(xy 115.943108 -271.942234) (xy 115.895837 -271.955926) (xy 115.846982 -271.961858) (xy 115.797807 -271.959877)
			(xy 115.749588 -271.950033) (xy 115.703572 -271.932581) (xy 115.660951 -271.907974) (xy 115.62283 -271.876849)
			(xy 115.590195 -271.840012) (xy 115.563892 -271.798416) (xy 115.544601 -271.75314) (xy 115.532824 -271.705356)
			(xy 115.528864 -271.656302) (xy 111.876586 -271.656302) (xy 112.136936 -271.916652) (xy 112.159616 -271.939953)
			(xy 112.200157 -271.990793) (xy 112.23475 -272.045854) (xy 112.262957 -272.104444) (xy 112.284425 -272.165824)
			(xy 112.298883 -272.229222) (xy 112.306149 -272.293841) (xy 112.306608 -272.326354) (xy 112.306608 -272.466308)
			(xy 113.178856 -272.466308) (xy 113.182816 -272.417254) (xy 113.194593 -272.36947) (xy 113.213884 -272.324194)
			(xy 113.240187 -272.282598) (xy 113.272822 -272.245761) (xy 113.310943 -272.214636) (xy 113.353564 -272.190029)
			(xy 113.39958 -272.172577) (xy 113.447799 -272.162733) (xy 113.496974 -272.160752) (xy 113.545829 -272.166684)
			(xy 113.5931 -272.180376) (xy 113.637562 -272.201474) (xy 113.678065 -272.22943) (xy 113.713558 -272.263522)
			(xy 113.743123 -272.302866) (xy 113.765994 -272.346443) (xy 113.781578 -272.393124) (xy 113.789473 -272.441701)
			(xy 113.789968 -272.466308) (xy 114.108479 -272.466308) (xy 114.112574 -272.41558) (xy 114.124753 -272.366166)
			(xy 114.144701 -272.319346) (xy 114.171902 -272.276332) (xy 114.20565 -272.238238) (xy 114.245072 -272.206051)
			(xy 114.289146 -272.180605) (xy 114.336732 -272.162558) (xy 114.386596 -272.152378) (xy 114.437448 -272.150329)
			(xy 114.487969 -272.156463) (xy 114.536853 -272.170623) (xy 114.582832 -272.19244) (xy 114.624716 -272.22135)
			(xy 114.66142 -272.256605) (xy 114.691993 -272.297291) (xy 114.715644 -272.342354) (xy 114.73176 -272.390628)
			(xy 114.739924 -272.440862) (xy 114.740436 -272.466308) (xy 115.048533 -272.466308) (xy 115.052628 -272.41558)
			(xy 115.064807 -272.366166) (xy 115.084755 -272.319346) (xy 115.111956 -272.276332) (xy 115.145704 -272.238238)
			(xy 115.185126 -272.206051) (xy 115.2292 -272.180605) (xy 115.276786 -272.162558) (xy 115.32665 -272.152378)
			(xy 115.377502 -272.150329) (xy 115.428023 -272.156463) (xy 115.476907 -272.170623) (xy 115.522886 -272.19244)
			(xy 115.56477 -272.22135) (xy 115.601474 -272.256605) (xy 115.632047 -272.297291) (xy 115.655698 -272.342354)
			(xy 115.671814 -272.390628) (xy 115.679978 -272.440862) (xy 115.68049 -272.466308) (xy 115.999018 -272.466308)
			(xy 116.002978 -272.417254) (xy 116.014755 -272.36947) (xy 116.034046 -272.324194) (xy 116.060349 -272.282598)
			(xy 116.092984 -272.245761) (xy 116.131105 -272.214636) (xy 116.173726 -272.190029) (xy 116.219742 -272.172577)
			(xy 116.267961 -272.162733) (xy 116.317136 -272.160752) (xy 116.365991 -272.166684) (xy 116.413262 -272.180376)
			(xy 116.457724 -272.201474) (xy 116.498227 -272.22943) (xy 116.53372 -272.263522) (xy 116.563285 -272.302866)
			(xy 116.586156 -272.346443) (xy 116.60174 -272.393124) (xy 116.609635 -272.441701) (xy 116.61013 -272.466308)
			(xy 118.818926 -272.466308) (xy 118.822886 -272.417254) (xy 118.834663 -272.36947) (xy 118.853954 -272.324194)
			(xy 118.880257 -272.282598) (xy 118.912892 -272.245761) (xy 118.951013 -272.214636) (xy 118.993634 -272.190029)
			(xy 119.03965 -272.172577) (xy 119.087869 -272.162733) (xy 119.137044 -272.160752) (xy 119.185899 -272.166684)
			(xy 119.23317 -272.180376) (xy 119.277632 -272.201474) (xy 119.318135 -272.22943) (xy 119.353628 -272.263522)
			(xy 119.383193 -272.302866) (xy 119.406064 -272.346443) (xy 119.421648 -272.393124) (xy 119.429543 -272.441701)
			(xy 119.430038 -272.466308) (xy 121.638834 -272.466308) (xy 121.642794 -272.417254) (xy 121.654571 -272.36947)
			(xy 121.673862 -272.324194) (xy 121.700165 -272.282598) (xy 121.7328 -272.245761) (xy 121.770921 -272.214636)
			(xy 121.813542 -272.190029) (xy 121.859558 -272.172577) (xy 121.907777 -272.162733) (xy 121.956952 -272.160752)
			(xy 122.005807 -272.166684) (xy 122.053078 -272.180376) (xy 122.09754 -272.201474) (xy 122.138043 -272.22943)
			(xy 122.173536 -272.263522) (xy 122.203101 -272.302866) (xy 122.225972 -272.346443) (xy 122.241556 -272.393124)
			(xy 122.249451 -272.441701) (xy 122.249946 -272.466308) (xy 124.458996 -272.466308) (xy 124.462956 -272.417254)
			(xy 124.474733 -272.36947) (xy 124.494024 -272.324194) (xy 124.520327 -272.282598) (xy 124.552962 -272.245761)
			(xy 124.591083 -272.214636) (xy 124.633704 -272.190029) (xy 124.67972 -272.172577) (xy 124.727939 -272.162733)
			(xy 124.777114 -272.160752) (xy 124.825969 -272.166684) (xy 124.87324 -272.180376) (xy 124.917702 -272.201474)
			(xy 124.958205 -272.22943) (xy 124.993698 -272.263522) (xy 125.023263 -272.302866) (xy 125.046134 -272.346443)
			(xy 125.061718 -272.393124) (xy 125.069613 -272.441701) (xy 125.070108 -272.466308) (xy 125.069613 -272.490915)
			(xy 125.061718 -272.539492) (xy 125.046134 -272.586173) (xy 125.023263 -272.62975) (xy 124.993698 -272.669094)
			(xy 124.958205 -272.703186) (xy 124.917702 -272.731142) (xy 124.87324 -272.75224) (xy 124.825969 -272.765932)
			(xy 124.777114 -272.771864) (xy 124.727939 -272.769883) (xy 124.67972 -272.760039) (xy 124.633704 -272.742587)
			(xy 124.591083 -272.71798) (xy 124.552962 -272.686855) (xy 124.520327 -272.650018) (xy 124.494024 -272.608422)
			(xy 124.474733 -272.563146) (xy 124.462956 -272.515362) (xy 124.458996 -272.466308) (xy 122.249946 -272.466308)
			(xy 122.249451 -272.490915) (xy 122.241556 -272.539492) (xy 122.225972 -272.586173) (xy 122.203101 -272.62975)
			(xy 122.173536 -272.669094) (xy 122.138043 -272.703186) (xy 122.09754 -272.731142) (xy 122.053078 -272.75224)
			(xy 122.005807 -272.765932) (xy 121.956952 -272.771864) (xy 121.907777 -272.769883) (xy 121.859558 -272.760039)
			(xy 121.813542 -272.742587) (xy 121.770921 -272.71798) (xy 121.7328 -272.686855) (xy 121.700165 -272.650018)
			(xy 121.673862 -272.608422) (xy 121.654571 -272.563146) (xy 121.642794 -272.515362) (xy 121.638834 -272.466308)
			(xy 119.430038 -272.466308) (xy 119.429543 -272.490915) (xy 119.421648 -272.539492) (xy 119.406064 -272.586173)
			(xy 119.383193 -272.62975) (xy 119.353628 -272.669094) (xy 119.318135 -272.703186) (xy 119.277632 -272.731142)
			(xy 119.23317 -272.75224) (xy 119.185899 -272.765932) (xy 119.137044 -272.771864) (xy 119.087869 -272.769883)
			(xy 119.03965 -272.760039) (xy 118.993634 -272.742587) (xy 118.951013 -272.71798) (xy 118.912892 -272.686855)
			(xy 118.880257 -272.650018) (xy 118.853954 -272.608422) (xy 118.834663 -272.563146) (xy 118.822886 -272.515362)
			(xy 118.818926 -272.466308) (xy 116.61013 -272.466308) (xy 116.609635 -272.490915) (xy 116.60174 -272.539492)
			(xy 116.586156 -272.586173) (xy 116.563285 -272.62975) (xy 116.53372 -272.669094) (xy 116.498227 -272.703186)
			(xy 116.457724 -272.731142) (xy 116.413262 -272.75224) (xy 116.365991 -272.765932) (xy 116.317136 -272.771864)
			(xy 116.267961 -272.769883) (xy 116.219742 -272.760039) (xy 116.173726 -272.742587) (xy 116.131105 -272.71798)
			(xy 116.092984 -272.686855) (xy 116.060349 -272.650018) (xy 116.034046 -272.608422) (xy 116.014755 -272.563146)
			(xy 116.002978 -272.515362) (xy 115.999018 -272.466308) (xy 115.68049 -272.466308) (xy 115.679978 -272.491754)
			(xy 115.671814 -272.541988) (xy 115.655698 -272.590262) (xy 115.632047 -272.635325) (xy 115.601474 -272.676011)
			(xy 115.56477 -272.711266) (xy 115.522886 -272.740176) (xy 115.476907 -272.761993) (xy 115.428023 -272.776153)
			(xy 115.377502 -272.782287) (xy 115.32665 -272.780238) (xy 115.276786 -272.770058) (xy 115.2292 -272.752011)
			(xy 115.185126 -272.726565) (xy 115.145704 -272.694378) (xy 115.111956 -272.656284) (xy 115.084755 -272.61327)
			(xy 115.064807 -272.56645) (xy 115.052628 -272.517036) (xy 115.048533 -272.466308) (xy 114.740436 -272.466308)
			(xy 114.739924 -272.491754) (xy 114.73176 -272.541988) (xy 114.715644 -272.590262) (xy 114.691993 -272.635325)
			(xy 114.66142 -272.676011) (xy 114.624716 -272.711266) (xy 114.582832 -272.740176) (xy 114.536853 -272.761993)
			(xy 114.487969 -272.776153) (xy 114.437448 -272.782287) (xy 114.386596 -272.780238) (xy 114.336732 -272.770058)
			(xy 114.289146 -272.752011) (xy 114.245072 -272.726565) (xy 114.20565 -272.694378) (xy 114.171902 -272.656284)
			(xy 114.144701 -272.61327) (xy 114.124753 -272.56645) (xy 114.112574 -272.517036) (xy 114.108479 -272.466308)
			(xy 113.789968 -272.466308) (xy 113.789473 -272.490915) (xy 113.781578 -272.539492) (xy 113.765994 -272.586173)
			(xy 113.743123 -272.62975) (xy 113.713558 -272.669094) (xy 113.678065 -272.703186) (xy 113.637562 -272.731142)
			(xy 113.5931 -272.75224) (xy 113.545829 -272.765932) (xy 113.496974 -272.771864) (xy 113.447799 -272.769883)
			(xy 113.39958 -272.760039) (xy 113.353564 -272.742587) (xy 113.310943 -272.71798) (xy 113.272822 -272.686855)
			(xy 113.240187 -272.650018) (xy 113.213884 -272.608422) (xy 113.194593 -272.563146) (xy 113.182816 -272.515362)
			(xy 113.178856 -272.466308) (xy 112.306608 -272.466308) (xy 112.306608 -273.276314) (xy 113.64901 -273.276314)
			(xy 113.65297 -273.22726) (xy 113.664747 -273.179476) (xy 113.684038 -273.1342) (xy 113.710341 -273.092604)
			(xy 113.742976 -273.055767) (xy 113.781097 -273.024642) (xy 113.823718 -273.000035) (xy 113.869734 -272.982583)
			(xy 113.917953 -272.972739) (xy 113.967128 -272.970758) (xy 114.015983 -272.97669) (xy 114.063254 -272.990382)
			(xy 114.107716 -273.01148) (xy 114.148219 -273.039436) (xy 114.183712 -273.073528) (xy 114.213277 -273.112872)
			(xy 114.236148 -273.156449) (xy 114.251732 -273.20313) (xy 114.259627 -273.251707) (xy 114.260122 -273.276314)
			(xy 114.58881 -273.276314) (xy 114.59277 -273.22726) (xy 114.604547 -273.179476) (xy 114.623838 -273.1342)
			(xy 114.650141 -273.092604) (xy 114.682776 -273.055767) (xy 114.720897 -273.024642) (xy 114.763518 -273.000035)
			(xy 114.809534 -272.982583) (xy 114.857753 -272.972739) (xy 114.906928 -272.970758) (xy 114.955783 -272.97669)
			(xy 115.003054 -272.990382) (xy 115.047516 -273.01148) (xy 115.088019 -273.039436) (xy 115.123512 -273.073528)
			(xy 115.153077 -273.112872) (xy 115.175948 -273.156449) (xy 115.191532 -273.20313) (xy 115.199427 -273.251707)
			(xy 115.199922 -273.276314) (xy 115.528864 -273.276314) (xy 115.532824 -273.22726) (xy 115.544601 -273.179476)
			(xy 115.563892 -273.1342) (xy 115.590195 -273.092604) (xy 115.62283 -273.055767) (xy 115.660951 -273.024642)
			(xy 115.703572 -273.000035) (xy 115.749588 -272.982583) (xy 115.797807 -272.972739) (xy 115.846982 -272.970758)
			(xy 115.895837 -272.97669) (xy 115.943108 -272.990382) (xy 115.98757 -273.01148) (xy 116.028073 -273.039436)
			(xy 116.063566 -273.073528) (xy 116.093131 -273.112872) (xy 116.116002 -273.156449) (xy 116.131586 -273.20313)
			(xy 116.139481 -273.251707) (xy 116.139976 -273.276314) (xy 116.458487 -273.276314) (xy 116.462582 -273.225586)
			(xy 116.474761 -273.176172) (xy 116.494709 -273.129352) (xy 116.52191 -273.086338) (xy 116.555658 -273.048244)
			(xy 116.59508 -273.016057) (xy 116.639154 -272.990611) (xy 116.68674 -272.972564) (xy 116.736604 -272.962384)
			(xy 116.787456 -272.960335) (xy 116.837977 -272.966469) (xy 116.886861 -272.980629) (xy 116.93284 -273.002446)
			(xy 116.974724 -273.031356) (xy 117.011428 -273.066611) (xy 117.042001 -273.107297) (xy 117.065652 -273.15236)
			(xy 117.081768 -273.200634) (xy 117.089932 -273.250868) (xy 117.090444 -273.276314) (xy 117.398541 -273.276314)
			(xy 117.402636 -273.225586) (xy 117.414815 -273.176172) (xy 117.434763 -273.129352) (xy 117.461964 -273.086338)
			(xy 117.495712 -273.048244) (xy 117.535134 -273.016057) (xy 117.579208 -272.990611) (xy 117.626794 -272.972564)
			(xy 117.676658 -272.962384) (xy 117.72751 -272.960335) (xy 117.778031 -272.966469) (xy 117.826915 -272.980629)
			(xy 117.872894 -273.002446) (xy 117.914778 -273.031356) (xy 117.951482 -273.066611) (xy 117.982055 -273.107297)
			(xy 118.005706 -273.15236) (xy 118.021822 -273.200634) (xy 118.029986 -273.250868) (xy 118.030498 -273.276314)
			(xy 118.349026 -273.276314) (xy 118.352986 -273.22726) (xy 118.364763 -273.179476) (xy 118.384054 -273.1342)
			(xy 118.410357 -273.092604) (xy 118.442992 -273.055767) (xy 118.481113 -273.024642) (xy 118.523734 -273.000035)
			(xy 118.56975 -272.982583) (xy 118.617969 -272.972739) (xy 118.667144 -272.970758) (xy 118.715999 -272.97669)
			(xy 118.76327 -272.990382) (xy 118.807732 -273.01148) (xy 118.848235 -273.039436) (xy 118.883728 -273.073528)
			(xy 118.913293 -273.112872) (xy 118.936164 -273.156449) (xy 118.951748 -273.20313) (xy 118.959643 -273.251707)
			(xy 118.960138 -273.276314) (xy 119.278395 -273.276314) (xy 119.28249 -273.225586) (xy 119.294669 -273.176172)
			(xy 119.314617 -273.129352) (xy 119.341818 -273.086338) (xy 119.375566 -273.048244) (xy 119.414988 -273.016057)
			(xy 119.459062 -272.990611) (xy 119.506648 -272.972564) (xy 119.556512 -272.962384) (xy 119.607364 -272.960335)
			(xy 119.657885 -272.966469) (xy 119.706769 -272.980629) (xy 119.752748 -273.002446) (xy 119.794632 -273.031356)
			(xy 119.831336 -273.066611) (xy 119.861909 -273.107297) (xy 119.88556 -273.15236) (xy 119.901676 -273.200634)
			(xy 119.90984 -273.250868) (xy 119.910352 -273.276314) (xy 120.218449 -273.276314) (xy 120.222544 -273.225586)
			(xy 120.234723 -273.176172) (xy 120.254671 -273.129352) (xy 120.281872 -273.086338) (xy 120.31562 -273.048244)
			(xy 120.355042 -273.016057) (xy 120.399116 -272.990611) (xy 120.446702 -272.972564) (xy 120.496566 -272.962384)
			(xy 120.547418 -272.960335) (xy 120.597939 -272.966469) (xy 120.646823 -272.980629) (xy 120.692802 -273.002446)
			(xy 120.734686 -273.031356) (xy 120.77139 -273.066611) (xy 120.801963 -273.107297) (xy 120.825614 -273.15236)
			(xy 120.84173 -273.200634) (xy 120.849894 -273.250868) (xy 120.850406 -273.276314) (xy 121.168934 -273.276314)
			(xy 121.172894 -273.22726) (xy 121.184671 -273.179476) (xy 121.203962 -273.1342) (xy 121.230265 -273.092604)
			(xy 121.2629 -273.055767) (xy 121.301021 -273.024642) (xy 121.343642 -273.000035) (xy 121.389658 -272.982583)
			(xy 121.437877 -272.972739) (xy 121.487052 -272.970758) (xy 121.535907 -272.97669) (xy 121.583178 -272.990382)
			(xy 121.62764 -273.01148) (xy 121.668143 -273.039436) (xy 121.703636 -273.073528) (xy 121.733201 -273.112872)
			(xy 121.756072 -273.156449) (xy 121.771656 -273.20313) (xy 121.779551 -273.251707) (xy 121.780046 -273.276314)
			(xy 122.098557 -273.276314) (xy 122.102652 -273.225586) (xy 122.114831 -273.176172) (xy 122.134779 -273.129352)
			(xy 122.16198 -273.086338) (xy 122.195728 -273.048244) (xy 122.23515 -273.016057) (xy 122.279224 -272.990611)
			(xy 122.32681 -272.972564) (xy 122.376674 -272.962384) (xy 122.427526 -272.960335) (xy 122.478047 -272.966469)
			(xy 122.526931 -272.980629) (xy 122.57291 -273.002446) (xy 122.614794 -273.031356) (xy 122.651498 -273.066611)
			(xy 122.682071 -273.107297) (xy 122.705722 -273.15236) (xy 122.721838 -273.200634) (xy 122.730002 -273.250868)
			(xy 122.730514 -273.276314) (xy 123.038611 -273.276314) (xy 123.042706 -273.225586) (xy 123.054885 -273.176172)
			(xy 123.074833 -273.129352) (xy 123.102034 -273.086338) (xy 123.135782 -273.048244) (xy 123.175204 -273.016057)
			(xy 123.219278 -272.990611) (xy 123.266864 -272.972564) (xy 123.316728 -272.962384) (xy 123.36758 -272.960335)
			(xy 123.418101 -272.966469) (xy 123.466985 -272.980629) (xy 123.512964 -273.002446) (xy 123.554848 -273.031356)
			(xy 123.591552 -273.066611) (xy 123.622125 -273.107297) (xy 123.645776 -273.15236) (xy 123.661892 -273.200634)
			(xy 123.670056 -273.250868) (xy 123.670568 -273.276314) (xy 123.988842 -273.276314) (xy 123.992802 -273.22726)
			(xy 124.004579 -273.179476) (xy 124.02387 -273.1342) (xy 124.050173 -273.092604) (xy 124.082808 -273.055767)
			(xy 124.120929 -273.024642) (xy 124.16355 -273.000035) (xy 124.209566 -272.982583) (xy 124.257785 -272.972739)
			(xy 124.30696 -272.970758) (xy 124.355815 -272.97669) (xy 124.403086 -272.990382) (xy 124.447548 -273.01148)
			(xy 124.488051 -273.039436) (xy 124.523544 -273.073528) (xy 124.553109 -273.112872) (xy 124.57598 -273.156449)
			(xy 124.591564 -273.20313) (xy 124.599459 -273.251707) (xy 124.599954 -273.276314) (xy 124.918465 -273.276314)
			(xy 124.92256 -273.225586) (xy 124.934739 -273.176172) (xy 124.954687 -273.129352) (xy 124.981888 -273.086338)
			(xy 125.015636 -273.048244) (xy 125.055058 -273.016057) (xy 125.099132 -272.990611) (xy 125.146718 -272.972564)
			(xy 125.196582 -272.962384) (xy 125.247434 -272.960335) (xy 125.297955 -272.966469) (xy 125.346839 -272.980629)
			(xy 125.392818 -273.002446) (xy 125.434702 -273.031356) (xy 125.471406 -273.066611) (xy 125.501979 -273.107297)
			(xy 125.52563 -273.15236) (xy 125.541746 -273.200634) (xy 125.54991 -273.250868) (xy 125.550422 -273.276314)
			(xy 125.858519 -273.276314) (xy 125.862614 -273.225586) (xy 125.874793 -273.176172) (xy 125.894741 -273.129352)
			(xy 125.921942 -273.086338) (xy 125.95569 -273.048244) (xy 125.995112 -273.016057) (xy 126.039186 -272.990611)
			(xy 126.086772 -272.972564) (xy 126.136636 -272.962384) (xy 126.187488 -272.960335) (xy 126.238009 -272.966469)
			(xy 126.286893 -272.980629) (xy 126.332872 -273.002446) (xy 126.374756 -273.031356) (xy 126.41146 -273.066611)
			(xy 126.442033 -273.107297) (xy 126.465684 -273.15236) (xy 126.4818 -273.200634) (xy 126.489964 -273.250868)
			(xy 126.490476 -273.276314) (xy 126.489964 -273.30176) (xy 126.4818 -273.351994) (xy 126.465684 -273.400268)
			(xy 126.442033 -273.445331) (xy 126.41146 -273.486017) (xy 126.374756 -273.521272) (xy 126.332872 -273.550182)
			(xy 126.286893 -273.571999) (xy 126.238009 -273.586159) (xy 126.187488 -273.592293) (xy 126.136636 -273.590244)
			(xy 126.086772 -273.580064) (xy 126.039186 -273.562017) (xy 125.995112 -273.536571) (xy 125.95569 -273.504384)
			(xy 125.921942 -273.46629) (xy 125.894741 -273.423276) (xy 125.874793 -273.376456) (xy 125.862614 -273.327042)
			(xy 125.858519 -273.276314) (xy 125.550422 -273.276314) (xy 125.54991 -273.30176) (xy 125.541746 -273.351994)
			(xy 125.52563 -273.400268) (xy 125.501979 -273.445331) (xy 125.471406 -273.486017) (xy 125.434702 -273.521272)
			(xy 125.392818 -273.550182) (xy 125.346839 -273.571999) (xy 125.297955 -273.586159) (xy 125.247434 -273.592293)
			(xy 125.196582 -273.590244) (xy 125.146718 -273.580064) (xy 125.099132 -273.562017) (xy 125.055058 -273.536571)
			(xy 125.015636 -273.504384) (xy 124.981888 -273.46629) (xy 124.954687 -273.423276) (xy 124.934739 -273.376456)
			(xy 124.92256 -273.327042) (xy 124.918465 -273.276314) (xy 124.599954 -273.276314) (xy 124.599459 -273.300921)
			(xy 124.591564 -273.349498) (xy 124.57598 -273.396179) (xy 124.553109 -273.439756) (xy 124.523544 -273.4791)
			(xy 124.488051 -273.513192) (xy 124.447548 -273.541148) (xy 124.403086 -273.562246) (xy 124.355815 -273.575938)
			(xy 124.30696 -273.58187) (xy 124.257785 -273.579889) (xy 124.209566 -273.570045) (xy 124.16355 -273.552593)
			(xy 124.120929 -273.527986) (xy 124.082808 -273.496861) (xy 124.050173 -273.460024) (xy 124.02387 -273.418428)
			(xy 124.004579 -273.373152) (xy 123.992802 -273.325368) (xy 123.988842 -273.276314) (xy 123.670568 -273.276314)
			(xy 123.670056 -273.30176) (xy 123.661892 -273.351994) (xy 123.645776 -273.400268) (xy 123.622125 -273.445331)
			(xy 123.591552 -273.486017) (xy 123.554848 -273.521272) (xy 123.512964 -273.550182) (xy 123.466985 -273.571999)
			(xy 123.418101 -273.586159) (xy 123.36758 -273.592293) (xy 123.316728 -273.590244) (xy 123.266864 -273.580064)
			(xy 123.219278 -273.562017) (xy 123.175204 -273.536571) (xy 123.135782 -273.504384) (xy 123.102034 -273.46629)
			(xy 123.074833 -273.423276) (xy 123.054885 -273.376456) (xy 123.042706 -273.327042) (xy 123.038611 -273.276314)
			(xy 122.730514 -273.276314) (xy 122.730002 -273.30176) (xy 122.721838 -273.351994) (xy 122.705722 -273.400268)
			(xy 122.682071 -273.445331) (xy 122.651498 -273.486017) (xy 122.614794 -273.521272) (xy 122.57291 -273.550182)
			(xy 122.526931 -273.571999) (xy 122.478047 -273.586159) (xy 122.427526 -273.592293) (xy 122.376674 -273.590244)
			(xy 122.32681 -273.580064) (xy 122.279224 -273.562017) (xy 122.23515 -273.536571) (xy 122.195728 -273.504384)
			(xy 122.16198 -273.46629) (xy 122.134779 -273.423276) (xy 122.114831 -273.376456) (xy 122.102652 -273.327042)
			(xy 122.098557 -273.276314) (xy 121.780046 -273.276314) (xy 121.779551 -273.300921) (xy 121.771656 -273.349498)
			(xy 121.756072 -273.396179) (xy 121.733201 -273.439756) (xy 121.703636 -273.4791) (xy 121.668143 -273.513192)
			(xy 121.62764 -273.541148) (xy 121.583178 -273.562246) (xy 121.535907 -273.575938) (xy 121.487052 -273.58187)
			(xy 121.437877 -273.579889) (xy 121.389658 -273.570045) (xy 121.343642 -273.552593) (xy 121.301021 -273.527986)
			(xy 121.2629 -273.496861) (xy 121.230265 -273.460024) (xy 121.203962 -273.418428) (xy 121.184671 -273.373152)
			(xy 121.172894 -273.325368) (xy 121.168934 -273.276314) (xy 120.850406 -273.276314) (xy 120.849894 -273.30176)
			(xy 120.84173 -273.351994) (xy 120.825614 -273.400268) (xy 120.801963 -273.445331) (xy 120.77139 -273.486017)
			(xy 120.734686 -273.521272) (xy 120.692802 -273.550182) (xy 120.646823 -273.571999) (xy 120.597939 -273.586159)
			(xy 120.547418 -273.592293) (xy 120.496566 -273.590244) (xy 120.446702 -273.580064) (xy 120.399116 -273.562017)
			(xy 120.355042 -273.536571) (xy 120.31562 -273.504384) (xy 120.281872 -273.46629) (xy 120.254671 -273.423276)
			(xy 120.234723 -273.376456) (xy 120.222544 -273.327042) (xy 120.218449 -273.276314) (xy 119.910352 -273.276314)
			(xy 119.90984 -273.30176) (xy 119.901676 -273.351994) (xy 119.88556 -273.400268) (xy 119.861909 -273.445331)
			(xy 119.831336 -273.486017) (xy 119.794632 -273.521272) (xy 119.752748 -273.550182) (xy 119.706769 -273.571999)
			(xy 119.657885 -273.586159) (xy 119.607364 -273.592293) (xy 119.556512 -273.590244) (xy 119.506648 -273.580064)
			(xy 119.459062 -273.562017) (xy 119.414988 -273.536571) (xy 119.375566 -273.504384) (xy 119.341818 -273.46629)
			(xy 119.314617 -273.423276) (xy 119.294669 -273.376456) (xy 119.28249 -273.327042) (xy 119.278395 -273.276314)
			(xy 118.960138 -273.276314) (xy 118.959643 -273.300921) (xy 118.951748 -273.349498) (xy 118.936164 -273.396179)
			(xy 118.913293 -273.439756) (xy 118.883728 -273.4791) (xy 118.848235 -273.513192) (xy 118.807732 -273.541148)
			(xy 118.76327 -273.562246) (xy 118.715999 -273.575938) (xy 118.667144 -273.58187) (xy 118.617969 -273.579889)
			(xy 118.56975 -273.570045) (xy 118.523734 -273.552593) (xy 118.481113 -273.527986) (xy 118.442992 -273.496861)
			(xy 118.410357 -273.460024) (xy 118.384054 -273.418428) (xy 118.364763 -273.373152) (xy 118.352986 -273.325368)
			(xy 118.349026 -273.276314) (xy 118.030498 -273.276314) (xy 118.029986 -273.30176) (xy 118.021822 -273.351994)
			(xy 118.005706 -273.400268) (xy 117.982055 -273.445331) (xy 117.951482 -273.486017) (xy 117.914778 -273.521272)
			(xy 117.872894 -273.550182) (xy 117.826915 -273.571999) (xy 117.778031 -273.586159) (xy 117.72751 -273.592293)
			(xy 117.676658 -273.590244) (xy 117.626794 -273.580064) (xy 117.579208 -273.562017) (xy 117.535134 -273.536571)
			(xy 117.495712 -273.504384) (xy 117.461964 -273.46629) (xy 117.434763 -273.423276) (xy 117.414815 -273.376456)
			(xy 117.402636 -273.327042) (xy 117.398541 -273.276314) (xy 117.090444 -273.276314) (xy 117.089932 -273.30176)
			(xy 117.081768 -273.351994) (xy 117.065652 -273.400268) (xy 117.042001 -273.445331) (xy 117.011428 -273.486017)
			(xy 116.974724 -273.521272) (xy 116.93284 -273.550182) (xy 116.886861 -273.571999) (xy 116.837977 -273.586159)
			(xy 116.787456 -273.592293) (xy 116.736604 -273.590244) (xy 116.68674 -273.580064) (xy 116.639154 -273.562017)
			(xy 116.59508 -273.536571) (xy 116.555658 -273.504384) (xy 116.52191 -273.46629) (xy 116.494709 -273.423276)
			(xy 116.474761 -273.376456) (xy 116.462582 -273.327042) (xy 116.458487 -273.276314) (xy 116.139976 -273.276314)
			(xy 116.139481 -273.300921) (xy 116.131586 -273.349498) (xy 116.116002 -273.396179) (xy 116.093131 -273.439756)
			(xy 116.063566 -273.4791) (xy 116.028073 -273.513192) (xy 115.98757 -273.541148) (xy 115.943108 -273.562246)
			(xy 115.895837 -273.575938) (xy 115.846982 -273.58187) (xy 115.797807 -273.579889) (xy 115.749588 -273.570045)
			(xy 115.703572 -273.552593) (xy 115.660951 -273.527986) (xy 115.62283 -273.496861) (xy 115.590195 -273.460024)
			(xy 115.563892 -273.418428) (xy 115.544601 -273.373152) (xy 115.532824 -273.325368) (xy 115.528864 -273.276314)
			(xy 115.199922 -273.276314) (xy 115.199427 -273.300921) (xy 115.191532 -273.349498) (xy 115.175948 -273.396179)
			(xy 115.153077 -273.439756) (xy 115.123512 -273.4791) (xy 115.088019 -273.513192) (xy 115.047516 -273.541148)
			(xy 115.003054 -273.562246) (xy 114.955783 -273.575938) (xy 114.906928 -273.58187) (xy 114.857753 -273.579889)
			(xy 114.809534 -273.570045) (xy 114.763518 -273.552593) (xy 114.720897 -273.527986) (xy 114.682776 -273.496861)
			(xy 114.650141 -273.460024) (xy 114.623838 -273.418428) (xy 114.604547 -273.373152) (xy 114.59277 -273.325368)
			(xy 114.58881 -273.276314) (xy 114.260122 -273.276314) (xy 114.259627 -273.300921) (xy 114.251732 -273.349498)
			(xy 114.236148 -273.396179) (xy 114.213277 -273.439756) (xy 114.183712 -273.4791) (xy 114.148219 -273.513192)
			(xy 114.107716 -273.541148) (xy 114.063254 -273.562246) (xy 114.015983 -273.575938) (xy 113.967128 -273.58187)
			(xy 113.917953 -273.579889) (xy 113.869734 -273.570045) (xy 113.823718 -273.552593) (xy 113.781097 -273.527986)
			(xy 113.742976 -273.496861) (xy 113.710341 -273.460024) (xy 113.684038 -273.418428) (xy 113.664747 -273.373152)
			(xy 113.65297 -273.325368) (xy 113.64901 -273.276314) (xy 112.306608 -273.276314) (xy 112.306608 -274.08632)
			(xy 113.178856 -274.08632) (xy 113.182816 -274.037266) (xy 113.194593 -273.989482) (xy 113.213884 -273.944206)
			(xy 113.240187 -273.90261) (xy 113.272822 -273.865773) (xy 113.310943 -273.834648) (xy 113.353564 -273.810041)
			(xy 113.39958 -273.792589) (xy 113.447799 -273.782745) (xy 113.496974 -273.780764) (xy 113.545829 -273.786696)
			(xy 113.5931 -273.800388) (xy 113.637562 -273.821486) (xy 113.678065 -273.849442) (xy 113.713558 -273.883534)
			(xy 113.743123 -273.922878) (xy 113.765994 -273.966455) (xy 113.781578 -274.013136) (xy 113.789473 -274.061713)
			(xy 113.789968 -274.08632) (xy 114.108479 -274.08632) (xy 114.112574 -274.035592) (xy 114.124753 -273.986178)
			(xy 114.144701 -273.939358) (xy 114.171902 -273.896344) (xy 114.20565 -273.85825) (xy 114.245072 -273.826063)
			(xy 114.289146 -273.800617) (xy 114.336732 -273.78257) (xy 114.386596 -273.77239) (xy 114.437448 -273.770341)
			(xy 114.487969 -273.776475) (xy 114.536853 -273.790635) (xy 114.582832 -273.812452) (xy 114.624716 -273.841362)
			(xy 114.66142 -273.876617) (xy 114.691993 -273.917303) (xy 114.715644 -273.962366) (xy 114.73176 -274.01064)
			(xy 114.739924 -274.060874) (xy 114.740436 -274.08632) (xy 115.048533 -274.08632) (xy 115.052628 -274.035592)
			(xy 115.064807 -273.986178) (xy 115.084755 -273.939358) (xy 115.111956 -273.896344) (xy 115.145704 -273.85825)
			(xy 115.185126 -273.826063) (xy 115.2292 -273.800617) (xy 115.276786 -273.78257) (xy 115.32665 -273.77239)
			(xy 115.377502 -273.770341) (xy 115.428023 -273.776475) (xy 115.476907 -273.790635) (xy 115.522886 -273.812452)
			(xy 115.56477 -273.841362) (xy 115.601474 -273.876617) (xy 115.632047 -273.917303) (xy 115.655698 -273.962366)
			(xy 115.671814 -274.01064) (xy 115.679978 -274.060874) (xy 115.68049 -274.08632) (xy 115.999018 -274.08632)
			(xy 116.002978 -274.037266) (xy 116.014755 -273.989482) (xy 116.034046 -273.944206) (xy 116.060349 -273.90261)
			(xy 116.092984 -273.865773) (xy 116.131105 -273.834648) (xy 116.173726 -273.810041) (xy 116.219742 -273.792589)
			(xy 116.267961 -273.782745) (xy 116.317136 -273.780764) (xy 116.365991 -273.786696) (xy 116.413262 -273.800388)
			(xy 116.457724 -273.821486) (xy 116.498227 -273.849442) (xy 116.53372 -273.883534) (xy 116.563285 -273.922878)
			(xy 116.586156 -273.966455) (xy 116.60174 -274.013136) (xy 116.609635 -274.061713) (xy 116.61013 -274.08632)
			(xy 116.938818 -274.08632) (xy 116.942778 -274.037266) (xy 116.954555 -273.989482) (xy 116.973846 -273.944206)
			(xy 117.000149 -273.90261) (xy 117.032784 -273.865773) (xy 117.070905 -273.834648) (xy 117.113526 -273.810041)
			(xy 117.159542 -273.792589) (xy 117.207761 -273.782745) (xy 117.256936 -273.780764) (xy 117.305791 -273.786696)
			(xy 117.353062 -273.800388) (xy 117.397524 -273.821486) (xy 117.438027 -273.849442) (xy 117.47352 -273.883534)
			(xy 117.503085 -273.922878) (xy 117.525956 -273.966455) (xy 117.54154 -274.013136) (xy 117.549435 -274.061713)
			(xy 117.54993 -274.08632) (xy 117.878872 -274.08632) (xy 117.882832 -274.037266) (xy 117.894609 -273.989482)
			(xy 117.9139 -273.944206) (xy 117.940203 -273.90261) (xy 117.972838 -273.865773) (xy 118.010959 -273.834648)
			(xy 118.05358 -273.810041) (xy 118.099596 -273.792589) (xy 118.147815 -273.782745) (xy 118.19699 -273.780764)
			(xy 118.245845 -273.786696) (xy 118.293116 -273.800388) (xy 118.337578 -273.821486) (xy 118.378081 -273.849442)
			(xy 118.413574 -273.883534) (xy 118.443139 -273.922878) (xy 118.46601 -273.966455) (xy 118.481594 -274.013136)
			(xy 118.489489 -274.061713) (xy 118.489984 -274.08632) (xy 118.818926 -274.08632) (xy 118.822886 -274.037266)
			(xy 118.834663 -273.989482) (xy 118.853954 -273.944206) (xy 118.880257 -273.90261) (xy 118.912892 -273.865773)
			(xy 118.951013 -273.834648) (xy 118.993634 -273.810041) (xy 119.03965 -273.792589) (xy 119.087869 -273.782745)
			(xy 119.137044 -273.780764) (xy 119.185899 -273.786696) (xy 119.23317 -273.800388) (xy 119.277632 -273.821486)
			(xy 119.318135 -273.849442) (xy 119.353628 -273.883534) (xy 119.383193 -273.922878) (xy 119.406064 -273.966455)
			(xy 119.421648 -274.013136) (xy 119.429543 -274.061713) (xy 119.430038 -274.08632) (xy 119.75898 -274.08632)
			(xy 119.76294 -274.037266) (xy 119.774717 -273.989482) (xy 119.794008 -273.944206) (xy 119.820311 -273.90261)
			(xy 119.852946 -273.865773) (xy 119.891067 -273.834648) (xy 119.933688 -273.810041) (xy 119.979704 -273.792589)
			(xy 120.027923 -273.782745) (xy 120.077098 -273.780764) (xy 120.125953 -273.786696) (xy 120.173224 -273.800388)
			(xy 120.217686 -273.821486) (xy 120.258189 -273.849442) (xy 120.293682 -273.883534) (xy 120.323247 -273.922878)
			(xy 120.346118 -273.966455) (xy 120.361702 -274.013136) (xy 120.369597 -274.061713) (xy 120.370092 -274.08632)
			(xy 120.699034 -274.08632) (xy 120.702994 -274.037266) (xy 120.714771 -273.989482) (xy 120.734062 -273.944206)
			(xy 120.760365 -273.90261) (xy 120.793 -273.865773) (xy 120.831121 -273.834648) (xy 120.873742 -273.810041)
			(xy 120.919758 -273.792589) (xy 120.967977 -273.782745) (xy 121.017152 -273.780764) (xy 121.066007 -273.786696)
			(xy 121.113278 -273.800388) (xy 121.15774 -273.821486) (xy 121.198243 -273.849442) (xy 121.233736 -273.883534)
			(xy 121.263301 -273.922878) (xy 121.286172 -273.966455) (xy 121.301756 -274.013136) (xy 121.309651 -274.061713)
			(xy 121.310146 -274.08632) (xy 121.638834 -274.08632) (xy 121.642794 -274.037266) (xy 121.654571 -273.989482)
			(xy 121.673862 -273.944206) (xy 121.700165 -273.90261) (xy 121.7328 -273.865773) (xy 121.770921 -273.834648)
			(xy 121.813542 -273.810041) (xy 121.859558 -273.792589) (xy 121.907777 -273.782745) (xy 121.956952 -273.780764)
			(xy 122.005807 -273.786696) (xy 122.053078 -273.800388) (xy 122.09754 -273.821486) (xy 122.138043 -273.849442)
			(xy 122.173536 -273.883534) (xy 122.203101 -273.922878) (xy 122.225972 -273.966455) (xy 122.241556 -274.013136)
			(xy 122.249451 -274.061713) (xy 122.249946 -274.08632) (xy 122.578888 -274.08632) (xy 122.582848 -274.037266)
			(xy 122.594625 -273.989482) (xy 122.613916 -273.944206) (xy 122.640219 -273.90261) (xy 122.672854 -273.865773)
			(xy 122.710975 -273.834648) (xy 122.753596 -273.810041) (xy 122.799612 -273.792589) (xy 122.847831 -273.782745)
			(xy 122.897006 -273.780764) (xy 122.945861 -273.786696) (xy 122.993132 -273.800388) (xy 123.037594 -273.821486)
			(xy 123.078097 -273.849442) (xy 123.11359 -273.883534) (xy 123.143155 -273.922878) (xy 123.166026 -273.966455)
			(xy 123.18161 -274.013136) (xy 123.189505 -274.061713) (xy 123.19 -274.08632) (xy 123.518942 -274.08632)
			(xy 123.522902 -274.037266) (xy 123.534679 -273.989482) (xy 123.55397 -273.944206) (xy 123.580273 -273.90261)
			(xy 123.612908 -273.865773) (xy 123.651029 -273.834648) (xy 123.69365 -273.810041) (xy 123.739666 -273.792589)
			(xy 123.787885 -273.782745) (xy 123.83706 -273.780764) (xy 123.885915 -273.786696) (xy 123.933186 -273.800388)
			(xy 123.977648 -273.821486) (xy 124.018151 -273.849442) (xy 124.053644 -273.883534) (xy 124.083209 -273.922878)
			(xy 124.10608 -273.966455) (xy 124.121664 -274.013136) (xy 124.129559 -274.061713) (xy 124.130054 -274.08632)
			(xy 124.458996 -274.08632) (xy 124.462956 -274.037266) (xy 124.474733 -273.989482) (xy 124.494024 -273.944206)
			(xy 124.520327 -273.90261) (xy 124.552962 -273.865773) (xy 124.591083 -273.834648) (xy 124.633704 -273.810041)
			(xy 124.67972 -273.792589) (xy 124.727939 -273.782745) (xy 124.777114 -273.780764) (xy 124.825969 -273.786696)
			(xy 124.87324 -273.800388) (xy 124.917702 -273.821486) (xy 124.958205 -273.849442) (xy 124.993698 -273.883534)
			(xy 125.023263 -273.922878) (xy 125.046134 -273.966455) (xy 125.061718 -274.013136) (xy 125.069613 -274.061713)
			(xy 125.070108 -274.08632) (xy 125.39905 -274.08632) (xy 125.40301 -274.037266) (xy 125.414787 -273.989482)
			(xy 125.434078 -273.944206) (xy 125.460381 -273.90261) (xy 125.493016 -273.865773) (xy 125.531137 -273.834648)
			(xy 125.573758 -273.810041) (xy 125.619774 -273.792589) (xy 125.667993 -273.782745) (xy 125.717168 -273.780764)
			(xy 125.766023 -273.786696) (xy 125.813294 -273.800388) (xy 125.857756 -273.821486) (xy 125.898259 -273.849442)
			(xy 125.933752 -273.883534) (xy 125.963317 -273.922878) (xy 125.986188 -273.966455) (xy 126.001772 -274.013136)
			(xy 126.009667 -274.061713) (xy 126.010162 -274.08632) (xy 126.009667 -274.110927) (xy 126.001772 -274.159504)
			(xy 125.986188 -274.206185) (xy 125.963317 -274.249762) (xy 125.933752 -274.289106) (xy 125.898259 -274.323198)
			(xy 125.857756 -274.351154) (xy 125.813294 -274.372252) (xy 125.766023 -274.385944) (xy 125.717168 -274.391876)
			(xy 125.667993 -274.389895) (xy 125.619774 -274.380051) (xy 125.573758 -274.362599) (xy 125.531137 -274.337992)
			(xy 125.493016 -274.306867) (xy 125.460381 -274.27003) (xy 125.434078 -274.228434) (xy 125.414787 -274.183158)
			(xy 125.40301 -274.135374) (xy 125.39905 -274.08632) (xy 125.070108 -274.08632) (xy 125.069613 -274.110927)
			(xy 125.061718 -274.159504) (xy 125.046134 -274.206185) (xy 125.023263 -274.249762) (xy 124.993698 -274.289106)
			(xy 124.958205 -274.323198) (xy 124.917702 -274.351154) (xy 124.87324 -274.372252) (xy 124.825969 -274.385944)
			(xy 124.777114 -274.391876) (xy 124.727939 -274.389895) (xy 124.67972 -274.380051) (xy 124.633704 -274.362599)
			(xy 124.591083 -274.337992) (xy 124.552962 -274.306867) (xy 124.520327 -274.27003) (xy 124.494024 -274.228434)
			(xy 124.474733 -274.183158) (xy 124.462956 -274.135374) (xy 124.458996 -274.08632) (xy 124.130054 -274.08632)
			(xy 124.129559 -274.110927) (xy 124.121664 -274.159504) (xy 124.10608 -274.206185) (xy 124.083209 -274.249762)
			(xy 124.053644 -274.289106) (xy 124.018151 -274.323198) (xy 123.977648 -274.351154) (xy 123.933186 -274.372252)
			(xy 123.885915 -274.385944) (xy 123.83706 -274.391876) (xy 123.787885 -274.389895) (xy 123.739666 -274.380051)
			(xy 123.69365 -274.362599) (xy 123.651029 -274.337992) (xy 123.612908 -274.306867) (xy 123.580273 -274.27003)
			(xy 123.55397 -274.228434) (xy 123.534679 -274.183158) (xy 123.522902 -274.135374) (xy 123.518942 -274.08632)
			(xy 123.19 -274.08632) (xy 123.189505 -274.110927) (xy 123.18161 -274.159504) (xy 123.166026 -274.206185)
			(xy 123.143155 -274.249762) (xy 123.11359 -274.289106) (xy 123.078097 -274.323198) (xy 123.037594 -274.351154)
			(xy 122.993132 -274.372252) (xy 122.945861 -274.385944) (xy 122.897006 -274.391876) (xy 122.847831 -274.389895)
			(xy 122.799612 -274.380051) (xy 122.753596 -274.362599) (xy 122.710975 -274.337992) (xy 122.672854 -274.306867)
			(xy 122.640219 -274.27003) (xy 122.613916 -274.228434) (xy 122.594625 -274.183158) (xy 122.582848 -274.135374)
			(xy 122.578888 -274.08632) (xy 122.249946 -274.08632) (xy 122.249451 -274.110927) (xy 122.241556 -274.159504)
			(xy 122.225972 -274.206185) (xy 122.203101 -274.249762) (xy 122.173536 -274.289106) (xy 122.138043 -274.323198)
			(xy 122.09754 -274.351154) (xy 122.053078 -274.372252) (xy 122.005807 -274.385944) (xy 121.956952 -274.391876)
			(xy 121.907777 -274.389895) (xy 121.859558 -274.380051) (xy 121.813542 -274.362599) (xy 121.770921 -274.337992)
			(xy 121.7328 -274.306867) (xy 121.700165 -274.27003) (xy 121.673862 -274.228434) (xy 121.654571 -274.183158)
			(xy 121.642794 -274.135374) (xy 121.638834 -274.08632) (xy 121.310146 -274.08632) (xy 121.309651 -274.110927)
			(xy 121.301756 -274.159504) (xy 121.286172 -274.206185) (xy 121.263301 -274.249762) (xy 121.233736 -274.289106)
			(xy 121.198243 -274.323198) (xy 121.15774 -274.351154) (xy 121.113278 -274.372252) (xy 121.066007 -274.385944)
			(xy 121.017152 -274.391876) (xy 120.967977 -274.389895) (xy 120.919758 -274.380051) (xy 120.873742 -274.362599)
			(xy 120.831121 -274.337992) (xy 120.793 -274.306867) (xy 120.760365 -274.27003) (xy 120.734062 -274.228434)
			(xy 120.714771 -274.183158) (xy 120.702994 -274.135374) (xy 120.699034 -274.08632) (xy 120.370092 -274.08632)
			(xy 120.369597 -274.110927) (xy 120.361702 -274.159504) (xy 120.346118 -274.206185) (xy 120.323247 -274.249762)
			(xy 120.293682 -274.289106) (xy 120.258189 -274.323198) (xy 120.217686 -274.351154) (xy 120.173224 -274.372252)
			(xy 120.125953 -274.385944) (xy 120.077098 -274.391876) (xy 120.027923 -274.389895) (xy 119.979704 -274.380051)
			(xy 119.933688 -274.362599) (xy 119.891067 -274.337992) (xy 119.852946 -274.306867) (xy 119.820311 -274.27003)
			(xy 119.794008 -274.228434) (xy 119.774717 -274.183158) (xy 119.76294 -274.135374) (xy 119.75898 -274.08632)
			(xy 119.430038 -274.08632) (xy 119.429543 -274.110927) (xy 119.421648 -274.159504) (xy 119.406064 -274.206185)
			(xy 119.383193 -274.249762) (xy 119.353628 -274.289106) (xy 119.318135 -274.323198) (xy 119.277632 -274.351154)
			(xy 119.23317 -274.372252) (xy 119.185899 -274.385944) (xy 119.137044 -274.391876) (xy 119.087869 -274.389895)
			(xy 119.03965 -274.380051) (xy 118.993634 -274.362599) (xy 118.951013 -274.337992) (xy 118.912892 -274.306867)
			(xy 118.880257 -274.27003) (xy 118.853954 -274.228434) (xy 118.834663 -274.183158) (xy 118.822886 -274.135374)
			(xy 118.818926 -274.08632) (xy 118.489984 -274.08632) (xy 118.489489 -274.110927) (xy 118.481594 -274.159504)
			(xy 118.46601 -274.206185) (xy 118.443139 -274.249762) (xy 118.413574 -274.289106) (xy 118.378081 -274.323198)
			(xy 118.337578 -274.351154) (xy 118.293116 -274.372252) (xy 118.245845 -274.385944) (xy 118.19699 -274.391876)
			(xy 118.147815 -274.389895) (xy 118.099596 -274.380051) (xy 118.05358 -274.362599) (xy 118.010959 -274.337992)
			(xy 117.972838 -274.306867) (xy 117.940203 -274.27003) (xy 117.9139 -274.228434) (xy 117.894609 -274.183158)
			(xy 117.882832 -274.135374) (xy 117.878872 -274.08632) (xy 117.54993 -274.08632) (xy 117.549435 -274.110927)
			(xy 117.54154 -274.159504) (xy 117.525956 -274.206185) (xy 117.503085 -274.249762) (xy 117.47352 -274.289106)
			(xy 117.438027 -274.323198) (xy 117.397524 -274.351154) (xy 117.353062 -274.372252) (xy 117.305791 -274.385944)
			(xy 117.256936 -274.391876) (xy 117.207761 -274.389895) (xy 117.159542 -274.380051) (xy 117.113526 -274.362599)
			(xy 117.070905 -274.337992) (xy 117.032784 -274.306867) (xy 117.000149 -274.27003) (xy 116.973846 -274.228434)
			(xy 116.954555 -274.183158) (xy 116.942778 -274.135374) (xy 116.938818 -274.08632) (xy 116.61013 -274.08632)
			(xy 116.609635 -274.110927) (xy 116.60174 -274.159504) (xy 116.586156 -274.206185) (xy 116.563285 -274.249762)
			(xy 116.53372 -274.289106) (xy 116.498227 -274.323198) (xy 116.457724 -274.351154) (xy 116.413262 -274.372252)
			(xy 116.365991 -274.385944) (xy 116.317136 -274.391876) (xy 116.267961 -274.389895) (xy 116.219742 -274.380051)
			(xy 116.173726 -274.362599) (xy 116.131105 -274.337992) (xy 116.092984 -274.306867) (xy 116.060349 -274.27003)
			(xy 116.034046 -274.228434) (xy 116.014755 -274.183158) (xy 116.002978 -274.135374) (xy 115.999018 -274.08632)
			(xy 115.68049 -274.08632) (xy 115.679978 -274.111766) (xy 115.671814 -274.162) (xy 115.655698 -274.210274)
			(xy 115.632047 -274.255337) (xy 115.601474 -274.296023) (xy 115.56477 -274.331278) (xy 115.522886 -274.360188)
			(xy 115.476907 -274.382005) (xy 115.428023 -274.396165) (xy 115.377502 -274.402299) (xy 115.32665 -274.40025)
			(xy 115.276786 -274.39007) (xy 115.2292 -274.372023) (xy 115.185126 -274.346577) (xy 115.145704 -274.31439)
			(xy 115.111956 -274.276296) (xy 115.084755 -274.233282) (xy 115.064807 -274.186462) (xy 115.052628 -274.137048)
			(xy 115.048533 -274.08632) (xy 114.740436 -274.08632) (xy 114.739924 -274.111766) (xy 114.73176 -274.162)
			(xy 114.715644 -274.210274) (xy 114.691993 -274.255337) (xy 114.66142 -274.296023) (xy 114.624716 -274.331278)
			(xy 114.582832 -274.360188) (xy 114.536853 -274.382005) (xy 114.487969 -274.396165) (xy 114.437448 -274.402299)
			(xy 114.386596 -274.40025) (xy 114.336732 -274.39007) (xy 114.289146 -274.372023) (xy 114.245072 -274.346577)
			(xy 114.20565 -274.31439) (xy 114.171902 -274.276296) (xy 114.144701 -274.233282) (xy 114.124753 -274.186462)
			(xy 114.112574 -274.137048) (xy 114.108479 -274.08632) (xy 113.789968 -274.08632) (xy 113.789473 -274.110927)
			(xy 113.781578 -274.159504) (xy 113.765994 -274.206185) (xy 113.743123 -274.249762) (xy 113.713558 -274.289106)
			(xy 113.678065 -274.323198) (xy 113.637562 -274.351154) (xy 113.5931 -274.372252) (xy 113.545829 -274.385944)
			(xy 113.496974 -274.391876) (xy 113.447799 -274.389895) (xy 113.39958 -274.380051) (xy 113.353564 -274.362599)
			(xy 113.310943 -274.337992) (xy 113.272822 -274.306867) (xy 113.240187 -274.27003) (xy 113.213884 -274.228434)
			(xy 113.194593 -274.183158) (xy 113.182816 -274.135374) (xy 113.178856 -274.08632) (xy 112.306608 -274.08632)
			(xy 112.306608 -274.801838) (xy 112.306608 -274.802854) (xy 112.308122 -274.896326) (xy 115.528864 -274.896326)
			(xy 115.532824 -274.847272) (xy 115.544601 -274.799488) (xy 115.563892 -274.754212) (xy 115.590195 -274.712616)
			(xy 115.62283 -274.675779) (xy 115.660951 -274.644654) (xy 115.703572 -274.620047) (xy 115.749588 -274.602595)
			(xy 115.797807 -274.592751) (xy 115.846982 -274.59077) (xy 115.895837 -274.596702) (xy 115.943108 -274.610394)
			(xy 115.98757 -274.631492) (xy 116.028073 -274.659448) (xy 116.063566 -274.69354) (xy 116.093131 -274.732884)
			(xy 116.116002 -274.776461) (xy 116.131586 -274.823142) (xy 116.139481 -274.871719) (xy 116.139976 -274.896326)
			(xy 116.458487 -274.896326) (xy 116.462582 -274.845598) (xy 116.474761 -274.796184) (xy 116.494709 -274.749364)
			(xy 116.52191 -274.70635) (xy 116.555658 -274.668256) (xy 116.59508 -274.636069) (xy 116.639154 -274.610623)
			(xy 116.68674 -274.592576) (xy 116.736604 -274.582396) (xy 116.787456 -274.580347) (xy 116.837977 -274.586481)
			(xy 116.886861 -274.600641) (xy 116.93284 -274.622458) (xy 116.974724 -274.651368) (xy 117.011428 -274.686623)
			(xy 117.042001 -274.727309) (xy 117.065652 -274.772372) (xy 117.081768 -274.820646) (xy 117.089932 -274.87088)
			(xy 117.090444 -274.896326) (xy 117.398541 -274.896326) (xy 117.402636 -274.845598) (xy 117.414815 -274.796184)
			(xy 117.434763 -274.749364) (xy 117.461964 -274.70635) (xy 117.495712 -274.668256) (xy 117.535134 -274.636069)
			(xy 117.579208 -274.610623) (xy 117.626794 -274.592576) (xy 117.676658 -274.582396) (xy 117.72751 -274.580347)
			(xy 117.778031 -274.586481) (xy 117.826915 -274.600641) (xy 117.872894 -274.622458) (xy 117.914778 -274.651368)
			(xy 117.951482 -274.686623) (xy 117.982055 -274.727309) (xy 118.005706 -274.772372) (xy 118.021822 -274.820646)
			(xy 118.029986 -274.87088) (xy 118.030498 -274.896326) (xy 118.349026 -274.896326) (xy 118.352986 -274.847272)
			(xy 118.364763 -274.799488) (xy 118.384054 -274.754212) (xy 118.410357 -274.712616) (xy 118.442992 -274.675779)
			(xy 118.481113 -274.644654) (xy 118.523734 -274.620047) (xy 118.56975 -274.602595) (xy 118.617969 -274.592751)
			(xy 118.667144 -274.59077) (xy 118.715999 -274.596702) (xy 118.76327 -274.610394) (xy 118.807732 -274.631492)
			(xy 118.848235 -274.659448) (xy 118.883728 -274.69354) (xy 118.913293 -274.732884) (xy 118.936164 -274.776461)
			(xy 118.951748 -274.823142) (xy 118.959643 -274.871719) (xy 118.960138 -274.896326) (xy 119.278395 -274.896326)
			(xy 119.28249 -274.845598) (xy 119.294669 -274.796184) (xy 119.314617 -274.749364) (xy 119.341818 -274.70635)
			(xy 119.375566 -274.668256) (xy 119.414988 -274.636069) (xy 119.459062 -274.610623) (xy 119.506648 -274.592576)
			(xy 119.556512 -274.582396) (xy 119.607364 -274.580347) (xy 119.657885 -274.586481) (xy 119.706769 -274.600641)
			(xy 119.752748 -274.622458) (xy 119.794632 -274.651368) (xy 119.831336 -274.686623) (xy 119.861909 -274.727309)
			(xy 119.88556 -274.772372) (xy 119.901676 -274.820646) (xy 119.90984 -274.87088) (xy 119.910352 -274.896326)
			(xy 120.218449 -274.896326) (xy 120.222544 -274.845598) (xy 120.234723 -274.796184) (xy 120.254671 -274.749364)
			(xy 120.281872 -274.70635) (xy 120.31562 -274.668256) (xy 120.355042 -274.636069) (xy 120.399116 -274.610623)
			(xy 120.446702 -274.592576) (xy 120.496566 -274.582396) (xy 120.547418 -274.580347) (xy 120.597939 -274.586481)
			(xy 120.646823 -274.600641) (xy 120.692802 -274.622458) (xy 120.734686 -274.651368) (xy 120.77139 -274.686623)
			(xy 120.801963 -274.727309) (xy 120.825614 -274.772372) (xy 120.84173 -274.820646) (xy 120.849894 -274.87088)
			(xy 120.850406 -274.896326) (xy 121.168934 -274.896326) (xy 121.172894 -274.847272) (xy 121.184671 -274.799488)
			(xy 121.203962 -274.754212) (xy 121.230265 -274.712616) (xy 121.2629 -274.675779) (xy 121.301021 -274.644654)
			(xy 121.343642 -274.620047) (xy 121.389658 -274.602595) (xy 121.437877 -274.592751) (xy 121.487052 -274.59077)
			(xy 121.535907 -274.596702) (xy 121.583178 -274.610394) (xy 121.62764 -274.631492) (xy 121.668143 -274.659448)
			(xy 121.703636 -274.69354) (xy 121.733201 -274.732884) (xy 121.756072 -274.776461) (xy 121.771656 -274.823142)
			(xy 121.779551 -274.871719) (xy 121.780046 -274.896326) (xy 122.098557 -274.896326) (xy 122.102652 -274.845598)
			(xy 122.114831 -274.796184) (xy 122.134779 -274.749364) (xy 122.16198 -274.70635) (xy 122.195728 -274.668256)
			(xy 122.23515 -274.636069) (xy 122.279224 -274.610623) (xy 122.32681 -274.592576) (xy 122.376674 -274.582396)
			(xy 122.427526 -274.580347) (xy 122.478047 -274.586481) (xy 122.526931 -274.600641) (xy 122.57291 -274.622458)
			(xy 122.614794 -274.651368) (xy 122.651498 -274.686623) (xy 122.682071 -274.727309) (xy 122.705722 -274.772372)
			(xy 122.721838 -274.820646) (xy 122.730002 -274.87088) (xy 122.730514 -274.896326) (xy 123.038611 -274.896326)
			(xy 123.042706 -274.845598) (xy 123.054885 -274.796184) (xy 123.074833 -274.749364) (xy 123.102034 -274.70635)
			(xy 123.135782 -274.668256) (xy 123.175204 -274.636069) (xy 123.219278 -274.610623) (xy 123.266864 -274.592576)
			(xy 123.316728 -274.582396) (xy 123.36758 -274.580347) (xy 123.418101 -274.586481) (xy 123.466985 -274.600641)
			(xy 123.512964 -274.622458) (xy 123.554848 -274.651368) (xy 123.591552 -274.686623) (xy 123.622125 -274.727309)
			(xy 123.645776 -274.772372) (xy 123.661892 -274.820646) (xy 123.670056 -274.87088) (xy 123.670568 -274.896326)
			(xy 123.988842 -274.896326) (xy 123.992802 -274.847272) (xy 124.004579 -274.799488) (xy 124.02387 -274.754212)
			(xy 124.050173 -274.712616) (xy 124.082808 -274.675779) (xy 124.120929 -274.644654) (xy 124.16355 -274.620047)
			(xy 124.209566 -274.602595) (xy 124.257785 -274.592751) (xy 124.30696 -274.59077) (xy 124.355815 -274.596702)
			(xy 124.403086 -274.610394) (xy 124.447548 -274.631492) (xy 124.488051 -274.659448) (xy 124.523544 -274.69354)
			(xy 124.553109 -274.732884) (xy 124.57598 -274.776461) (xy 124.591564 -274.823142) (xy 124.599459 -274.871719)
			(xy 124.599954 -274.896326) (xy 124.918465 -274.896326) (xy 124.92256 -274.845598) (xy 124.934739 -274.796184)
			(xy 124.954687 -274.749364) (xy 124.981888 -274.70635) (xy 125.015636 -274.668256) (xy 125.055058 -274.636069)
			(xy 125.099132 -274.610623) (xy 125.146718 -274.592576) (xy 125.196582 -274.582396) (xy 125.247434 -274.580347)
			(xy 125.297955 -274.586481) (xy 125.346839 -274.600641) (xy 125.392818 -274.622458) (xy 125.434702 -274.651368)
			(xy 125.471406 -274.686623) (xy 125.501979 -274.727309) (xy 125.52563 -274.772372) (xy 125.541746 -274.820646)
			(xy 125.54991 -274.87088) (xy 125.550422 -274.896326) (xy 125.858519 -274.896326) (xy 125.862614 -274.845598)
			(xy 125.874793 -274.796184) (xy 125.894741 -274.749364) (xy 125.921942 -274.70635) (xy 125.95569 -274.668256)
			(xy 125.995112 -274.636069) (xy 126.039186 -274.610623) (xy 126.086772 -274.592576) (xy 126.136636 -274.582396)
			(xy 126.187488 -274.580347) (xy 126.238009 -274.586481) (xy 126.286893 -274.600641) (xy 126.332872 -274.622458)
			(xy 126.374756 -274.651368) (xy 126.41146 -274.686623) (xy 126.442033 -274.727309) (xy 126.465684 -274.772372)
			(xy 126.4818 -274.820646) (xy 126.489964 -274.87088) (xy 126.490476 -274.896326) (xy 126.489964 -274.921772)
			(xy 126.4818 -274.972006) (xy 126.465684 -275.02028) (xy 126.442033 -275.065343) (xy 126.41146 -275.106029)
			(xy 126.374756 -275.141284) (xy 126.332872 -275.170194) (xy 126.286893 -275.192011) (xy 126.238009 -275.206171)
			(xy 126.187488 -275.212305) (xy 126.136636 -275.210256) (xy 126.086772 -275.200076) (xy 126.039186 -275.182029)
			(xy 125.995112 -275.156583) (xy 125.95569 -275.124396) (xy 125.921942 -275.086302) (xy 125.894741 -275.043288)
			(xy 125.874793 -274.996468) (xy 125.862614 -274.947054) (xy 125.858519 -274.896326) (xy 125.550422 -274.896326)
			(xy 125.54991 -274.921772) (xy 125.541746 -274.972006) (xy 125.52563 -275.02028) (xy 125.501979 -275.065343)
			(xy 125.471406 -275.106029) (xy 125.434702 -275.141284) (xy 125.392818 -275.170194) (xy 125.346839 -275.192011)
			(xy 125.297955 -275.206171) (xy 125.247434 -275.212305) (xy 125.196582 -275.210256) (xy 125.146718 -275.200076)
			(xy 125.099132 -275.182029) (xy 125.055058 -275.156583) (xy 125.015636 -275.124396) (xy 124.981888 -275.086302)
			(xy 124.954687 -275.043288) (xy 124.934739 -274.996468) (xy 124.92256 -274.947054) (xy 124.918465 -274.896326)
			(xy 124.599954 -274.896326) (xy 124.599459 -274.920933) (xy 124.591564 -274.96951) (xy 124.57598 -275.016191)
			(xy 124.553109 -275.059768) (xy 124.523544 -275.099112) (xy 124.488051 -275.133204) (xy 124.447548 -275.16116)
			(xy 124.403086 -275.182258) (xy 124.355815 -275.19595) (xy 124.30696 -275.201882) (xy 124.257785 -275.199901)
			(xy 124.209566 -275.190057) (xy 124.16355 -275.172605) (xy 124.120929 -275.147998) (xy 124.082808 -275.116873)
			(xy 124.050173 -275.080036) (xy 124.02387 -275.03844) (xy 124.004579 -274.993164) (xy 123.992802 -274.94538)
			(xy 123.988842 -274.896326) (xy 123.670568 -274.896326) (xy 123.670056 -274.921772) (xy 123.661892 -274.972006)
			(xy 123.645776 -275.02028) (xy 123.622125 -275.065343) (xy 123.591552 -275.106029) (xy 123.554848 -275.141284)
			(xy 123.512964 -275.170194) (xy 123.466985 -275.192011) (xy 123.418101 -275.206171) (xy 123.36758 -275.212305)
			(xy 123.316728 -275.210256) (xy 123.266864 -275.200076) (xy 123.219278 -275.182029) (xy 123.175204 -275.156583)
			(xy 123.135782 -275.124396) (xy 123.102034 -275.086302) (xy 123.074833 -275.043288) (xy 123.054885 -274.996468)
			(xy 123.042706 -274.947054) (xy 123.038611 -274.896326) (xy 122.730514 -274.896326) (xy 122.730002 -274.921772)
			(xy 122.721838 -274.972006) (xy 122.705722 -275.02028) (xy 122.682071 -275.065343) (xy 122.651498 -275.106029)
			(xy 122.614794 -275.141284) (xy 122.57291 -275.170194) (xy 122.526931 -275.192011) (xy 122.478047 -275.206171)
			(xy 122.427526 -275.212305) (xy 122.376674 -275.210256) (xy 122.32681 -275.200076) (xy 122.279224 -275.182029)
			(xy 122.23515 -275.156583) (xy 122.195728 -275.124396) (xy 122.16198 -275.086302) (xy 122.134779 -275.043288)
			(xy 122.114831 -274.996468) (xy 122.102652 -274.947054) (xy 122.098557 -274.896326) (xy 121.780046 -274.896326)
			(xy 121.779551 -274.920933) (xy 121.771656 -274.96951) (xy 121.756072 -275.016191) (xy 121.733201 -275.059768)
			(xy 121.703636 -275.099112) (xy 121.668143 -275.133204) (xy 121.62764 -275.16116) (xy 121.583178 -275.182258)
			(xy 121.535907 -275.19595) (xy 121.487052 -275.201882) (xy 121.437877 -275.199901) (xy 121.389658 -275.190057)
			(xy 121.343642 -275.172605) (xy 121.301021 -275.147998) (xy 121.2629 -275.116873) (xy 121.230265 -275.080036)
			(xy 121.203962 -275.03844) (xy 121.184671 -274.993164) (xy 121.172894 -274.94538) (xy 121.168934 -274.896326)
			(xy 120.850406 -274.896326) (xy 120.849894 -274.921772) (xy 120.84173 -274.972006) (xy 120.825614 -275.02028)
			(xy 120.801963 -275.065343) (xy 120.77139 -275.106029) (xy 120.734686 -275.141284) (xy 120.692802 -275.170194)
			(xy 120.646823 -275.192011) (xy 120.597939 -275.206171) (xy 120.547418 -275.212305) (xy 120.496566 -275.210256)
			(xy 120.446702 -275.200076) (xy 120.399116 -275.182029) (xy 120.355042 -275.156583) (xy 120.31562 -275.124396)
			(xy 120.281872 -275.086302) (xy 120.254671 -275.043288) (xy 120.234723 -274.996468) (xy 120.222544 -274.947054)
			(xy 120.218449 -274.896326) (xy 119.910352 -274.896326) (xy 119.90984 -274.921772) (xy 119.901676 -274.972006)
			(xy 119.88556 -275.02028) (xy 119.861909 -275.065343) (xy 119.831336 -275.106029) (xy 119.794632 -275.141284)
			(xy 119.752748 -275.170194) (xy 119.706769 -275.192011) (xy 119.657885 -275.206171) (xy 119.607364 -275.212305)
			(xy 119.556512 -275.210256) (xy 119.506648 -275.200076) (xy 119.459062 -275.182029) (xy 119.414988 -275.156583)
			(xy 119.375566 -275.124396) (xy 119.341818 -275.086302) (xy 119.314617 -275.043288) (xy 119.294669 -274.996468)
			(xy 119.28249 -274.947054) (xy 119.278395 -274.896326) (xy 118.960138 -274.896326) (xy 118.959643 -274.920933)
			(xy 118.951748 -274.96951) (xy 118.936164 -275.016191) (xy 118.913293 -275.059768) (xy 118.883728 -275.099112)
			(xy 118.848235 -275.133204) (xy 118.807732 -275.16116) (xy 118.76327 -275.182258) (xy 118.715999 -275.19595)
			(xy 118.667144 -275.201882) (xy 118.617969 -275.199901) (xy 118.56975 -275.190057) (xy 118.523734 -275.172605)
			(xy 118.481113 -275.147998) (xy 118.442992 -275.116873) (xy 118.410357 -275.080036) (xy 118.384054 -275.03844)
			(xy 118.364763 -274.993164) (xy 118.352986 -274.94538) (xy 118.349026 -274.896326) (xy 118.030498 -274.896326)
			(xy 118.029986 -274.921772) (xy 118.021822 -274.972006) (xy 118.005706 -275.02028) (xy 117.982055 -275.065343)
			(xy 117.951482 -275.106029) (xy 117.914778 -275.141284) (xy 117.872894 -275.170194) (xy 117.826915 -275.192011)
			(xy 117.778031 -275.206171) (xy 117.72751 -275.212305) (xy 117.676658 -275.210256) (xy 117.626794 -275.200076)
			(xy 117.579208 -275.182029) (xy 117.535134 -275.156583) (xy 117.495712 -275.124396) (xy 117.461964 -275.086302)
			(xy 117.434763 -275.043288) (xy 117.414815 -274.996468) (xy 117.402636 -274.947054) (xy 117.398541 -274.896326)
			(xy 117.090444 -274.896326) (xy 117.089932 -274.921772) (xy 117.081768 -274.972006) (xy 117.065652 -275.02028)
			(xy 117.042001 -275.065343) (xy 117.011428 -275.106029) (xy 116.974724 -275.141284) (xy 116.93284 -275.170194)
			(xy 116.886861 -275.192011) (xy 116.837977 -275.206171) (xy 116.787456 -275.212305) (xy 116.736604 -275.210256)
			(xy 116.68674 -275.200076) (xy 116.639154 -275.182029) (xy 116.59508 -275.156583) (xy 116.555658 -275.124396)
			(xy 116.52191 -275.086302) (xy 116.494709 -275.043288) (xy 116.474761 -274.996468) (xy 116.462582 -274.947054)
			(xy 116.458487 -274.896326) (xy 116.139976 -274.896326) (xy 116.139481 -274.920933) (xy 116.131586 -274.96951)
			(xy 116.116002 -275.016191) (xy 116.093131 -275.059768) (xy 116.063566 -275.099112) (xy 116.028073 -275.133204)
			(xy 115.98757 -275.16116) (xy 115.943108 -275.182258) (xy 115.895837 -275.19595) (xy 115.846982 -275.201882)
			(xy 115.797807 -275.199901) (xy 115.749588 -275.190057) (xy 115.703572 -275.172605) (xy 115.660951 -275.147998)
			(xy 115.62283 -275.116873) (xy 115.590195 -275.080036) (xy 115.563892 -275.03844) (xy 115.544601 -274.993164)
			(xy 115.532824 -274.94538) (xy 115.528864 -274.896326) (xy 112.308122 -274.896326) (xy 112.321238 -275.706332)
			(xy 113.178856 -275.706332) (xy 113.182816 -275.657278) (xy 113.194593 -275.609494) (xy 113.213884 -275.564218)
			(xy 113.240187 -275.522622) (xy 113.272822 -275.485785) (xy 113.310943 -275.45466) (xy 113.353564 -275.430053)
			(xy 113.39958 -275.412601) (xy 113.447799 -275.402757) (xy 113.496974 -275.400776) (xy 113.545829 -275.406708)
			(xy 113.5931 -275.4204) (xy 113.637562 -275.441498) (xy 113.678065 -275.469454) (xy 113.713558 -275.503546)
			(xy 113.743123 -275.54289) (xy 113.765994 -275.586467) (xy 113.781578 -275.633148) (xy 113.789473 -275.681725)
			(xy 113.789968 -275.706332) (xy 114.108479 -275.706332) (xy 114.112574 -275.655604) (xy 114.124753 -275.60619)
			(xy 114.144701 -275.55937) (xy 114.171902 -275.516356) (xy 114.20565 -275.478262) (xy 114.245072 -275.446075)
			(xy 114.289146 -275.420629) (xy 114.336732 -275.402582) (xy 114.386596 -275.392402) (xy 114.437448 -275.390353)
			(xy 114.487969 -275.396487) (xy 114.536853 -275.410647) (xy 114.582832 -275.432464) (xy 114.624716 -275.461374)
			(xy 114.66142 -275.496629) (xy 114.691993 -275.537315) (xy 114.715644 -275.582378) (xy 114.73176 -275.630652)
			(xy 114.739924 -275.680886) (xy 114.740436 -275.706332) (xy 115.048533 -275.706332) (xy 115.052628 -275.655604)
			(xy 115.064807 -275.60619) (xy 115.084755 -275.55937) (xy 115.111956 -275.516356) (xy 115.145704 -275.478262)
			(xy 115.185126 -275.446075) (xy 115.2292 -275.420629) (xy 115.276786 -275.402582) (xy 115.32665 -275.392402)
			(xy 115.377502 -275.390353) (xy 115.428023 -275.396487) (xy 115.476907 -275.410647) (xy 115.522886 -275.432464)
			(xy 115.56477 -275.461374) (xy 115.601474 -275.496629) (xy 115.632047 -275.537315) (xy 115.655698 -275.582378)
			(xy 115.671814 -275.630652) (xy 115.679978 -275.680886) (xy 115.68049 -275.706332) (xy 115.999018 -275.706332)
			(xy 116.002978 -275.657278) (xy 116.014755 -275.609494) (xy 116.034046 -275.564218) (xy 116.060349 -275.522622)
			(xy 116.092984 -275.485785) (xy 116.131105 -275.45466) (xy 116.173726 -275.430053) (xy 116.219742 -275.412601)
			(xy 116.267961 -275.402757) (xy 116.317136 -275.400776) (xy 116.365991 -275.406708) (xy 116.413262 -275.4204)
			(xy 116.457724 -275.441498) (xy 116.498227 -275.469454) (xy 116.53372 -275.503546) (xy 116.563285 -275.54289)
			(xy 116.586156 -275.586467) (xy 116.60174 -275.633148) (xy 116.609635 -275.681725) (xy 116.61013 -275.706332)
			(xy 118.818926 -275.706332) (xy 118.822886 -275.657278) (xy 118.834663 -275.609494) (xy 118.853954 -275.564218)
			(xy 118.880257 -275.522622) (xy 118.912892 -275.485785) (xy 118.951013 -275.45466) (xy 118.993634 -275.430053)
			(xy 119.03965 -275.412601) (xy 119.087869 -275.402757) (xy 119.137044 -275.400776) (xy 119.185899 -275.406708)
			(xy 119.23317 -275.4204) (xy 119.277632 -275.441498) (xy 119.318135 -275.469454) (xy 119.353628 -275.503546)
			(xy 119.383193 -275.54289) (xy 119.406064 -275.586467) (xy 119.421648 -275.633148) (xy 119.429543 -275.681725)
			(xy 119.430038 -275.706332) (xy 121.638834 -275.706332) (xy 121.642794 -275.657278) (xy 121.654571 -275.609494)
			(xy 121.673862 -275.564218) (xy 121.700165 -275.522622) (xy 121.7328 -275.485785) (xy 121.770921 -275.45466)
			(xy 121.813542 -275.430053) (xy 121.859558 -275.412601) (xy 121.907777 -275.402757) (xy 121.956952 -275.400776)
			(xy 122.005807 -275.406708) (xy 122.053078 -275.4204) (xy 122.09754 -275.441498) (xy 122.138043 -275.469454)
			(xy 122.173536 -275.503546) (xy 122.203101 -275.54289) (xy 122.225972 -275.586467) (xy 122.241556 -275.633148)
			(xy 122.249451 -275.681725) (xy 122.249946 -275.706332) (xy 124.458996 -275.706332) (xy 124.462956 -275.657278)
			(xy 124.474733 -275.609494) (xy 124.494024 -275.564218) (xy 124.520327 -275.522622) (xy 124.552962 -275.485785)
			(xy 124.591083 -275.45466) (xy 124.633704 -275.430053) (xy 124.67972 -275.412601) (xy 124.727939 -275.402757)
			(xy 124.777114 -275.400776) (xy 124.825969 -275.406708) (xy 124.87324 -275.4204) (xy 124.917702 -275.441498)
			(xy 124.958205 -275.469454) (xy 124.993698 -275.503546) (xy 125.023263 -275.54289) (xy 125.046134 -275.586467)
			(xy 125.061718 -275.633148) (xy 125.069613 -275.681725) (xy 125.070108 -275.706332) (xy 125.069613 -275.730939)
			(xy 125.061718 -275.779516) (xy 125.046134 -275.826197) (xy 125.023263 -275.869774) (xy 124.993698 -275.909118)
			(xy 124.958205 -275.94321) (xy 124.917702 -275.971166) (xy 124.87324 -275.992264) (xy 124.825969 -276.005956)
			(xy 124.777114 -276.011888) (xy 124.727939 -276.009907) (xy 124.67972 -276.000063) (xy 124.633704 -275.982611)
			(xy 124.591083 -275.958004) (xy 124.552962 -275.926879) (xy 124.520327 -275.890042) (xy 124.494024 -275.848446)
			(xy 124.474733 -275.80317) (xy 124.462956 -275.755386) (xy 124.458996 -275.706332) (xy 122.249946 -275.706332)
			(xy 122.249451 -275.730939) (xy 122.241556 -275.779516) (xy 122.225972 -275.826197) (xy 122.203101 -275.869774)
			(xy 122.173536 -275.909118) (xy 122.138043 -275.94321) (xy 122.09754 -275.971166) (xy 122.053078 -275.992264)
			(xy 122.005807 -276.005956) (xy 121.956952 -276.011888) (xy 121.907777 -276.009907) (xy 121.859558 -276.000063)
			(xy 121.813542 -275.982611) (xy 121.770921 -275.958004) (xy 121.7328 -275.926879) (xy 121.700165 -275.890042)
			(xy 121.673862 -275.848446) (xy 121.654571 -275.80317) (xy 121.642794 -275.755386) (xy 121.638834 -275.706332)
			(xy 119.430038 -275.706332) (xy 119.429543 -275.730939) (xy 119.421648 -275.779516) (xy 119.406064 -275.826197)
			(xy 119.383193 -275.869774) (xy 119.353628 -275.909118) (xy 119.318135 -275.94321) (xy 119.277632 -275.971166)
			(xy 119.23317 -275.992264) (xy 119.185899 -276.005956) (xy 119.137044 -276.011888) (xy 119.087869 -276.009907)
			(xy 119.03965 -276.000063) (xy 118.993634 -275.982611) (xy 118.951013 -275.958004) (xy 118.912892 -275.926879)
			(xy 118.880257 -275.890042) (xy 118.853954 -275.848446) (xy 118.834663 -275.80317) (xy 118.822886 -275.755386)
			(xy 118.818926 -275.706332) (xy 116.61013 -275.706332) (xy 116.609635 -275.730939) (xy 116.60174 -275.779516)
			(xy 116.586156 -275.826197) (xy 116.563285 -275.869774) (xy 116.53372 -275.909118) (xy 116.498227 -275.94321)
			(xy 116.457724 -275.971166) (xy 116.413262 -275.992264) (xy 116.365991 -276.005956) (xy 116.317136 -276.011888)
			(xy 116.267961 -276.009907) (xy 116.219742 -276.000063) (xy 116.173726 -275.982611) (xy 116.131105 -275.958004)
			(xy 116.092984 -275.926879) (xy 116.060349 -275.890042) (xy 116.034046 -275.848446) (xy 116.014755 -275.80317)
			(xy 116.002978 -275.755386) (xy 115.999018 -275.706332) (xy 115.68049 -275.706332) (xy 115.679978 -275.731778)
			(xy 115.671814 -275.782012) (xy 115.655698 -275.830286) (xy 115.632047 -275.875349) (xy 115.601474 -275.916035)
			(xy 115.56477 -275.95129) (xy 115.522886 -275.9802) (xy 115.476907 -276.002017) (xy 115.428023 -276.016177)
			(xy 115.377502 -276.022311) (xy 115.32665 -276.020262) (xy 115.276786 -276.010082) (xy 115.2292 -275.992035)
			(xy 115.185126 -275.966589) (xy 115.145704 -275.934402) (xy 115.111956 -275.896308) (xy 115.084755 -275.853294)
			(xy 115.064807 -275.806474) (xy 115.052628 -275.75706) (xy 115.048533 -275.706332) (xy 114.740436 -275.706332)
			(xy 114.739924 -275.731778) (xy 114.73176 -275.782012) (xy 114.715644 -275.830286) (xy 114.691993 -275.875349)
			(xy 114.66142 -275.916035) (xy 114.624716 -275.95129) (xy 114.582832 -275.9802) (xy 114.536853 -276.002017)
			(xy 114.487969 -276.016177) (xy 114.437448 -276.022311) (xy 114.386596 -276.020262) (xy 114.336732 -276.010082)
			(xy 114.289146 -275.992035) (xy 114.245072 -275.966589) (xy 114.20565 -275.934402) (xy 114.171902 -275.896308)
			(xy 114.144701 -275.853294) (xy 114.124753 -275.806474) (xy 114.112574 -275.75706) (xy 114.108479 -275.706332)
			(xy 113.789968 -275.706332) (xy 113.789473 -275.730939) (xy 113.781578 -275.779516) (xy 113.765994 -275.826197)
			(xy 113.743123 -275.869774) (xy 113.713558 -275.909118) (xy 113.678065 -275.94321) (xy 113.637562 -275.971166)
			(xy 113.5931 -275.992264) (xy 113.545829 -276.005956) (xy 113.496974 -276.011888) (xy 113.447799 -276.009907)
			(xy 113.39958 -276.000063) (xy 113.353564 -275.982611) (xy 113.310943 -275.958004) (xy 113.272822 -275.926879)
			(xy 113.240187 -275.890042) (xy 113.213884 -275.848446) (xy 113.194593 -275.80317) (xy 113.182816 -275.755386)
			(xy 113.178856 -275.706332) (xy 112.321238 -275.706332) (xy 112.334354 -276.516338) (xy 113.64901 -276.516338)
			(xy 113.65297 -276.467284) (xy 113.664747 -276.4195) (xy 113.684038 -276.374224) (xy 113.710341 -276.332628)
			(xy 113.742976 -276.295791) (xy 113.781097 -276.264666) (xy 113.823718 -276.240059) (xy 113.869734 -276.222607)
			(xy 113.917953 -276.212763) (xy 113.967128 -276.210782) (xy 114.015983 -276.216714) (xy 114.063254 -276.230406)
			(xy 114.107716 -276.251504) (xy 114.148219 -276.27946) (xy 114.183712 -276.313552) (xy 114.213277 -276.352896)
			(xy 114.236148 -276.396473) (xy 114.251732 -276.443154) (xy 114.259627 -276.491731) (xy 114.260122 -276.516338)
			(xy 114.58881 -276.516338) (xy 114.59277 -276.467284) (xy 114.604547 -276.4195) (xy 114.623838 -276.374224)
			(xy 114.650141 -276.332628) (xy 114.682776 -276.295791) (xy 114.720897 -276.264666) (xy 114.763518 -276.240059)
			(xy 114.809534 -276.222607) (xy 114.857753 -276.212763) (xy 114.906928 -276.210782) (xy 114.955783 -276.216714)
			(xy 115.003054 -276.230406) (xy 115.047516 -276.251504) (xy 115.088019 -276.27946) (xy 115.123512 -276.313552)
			(xy 115.153077 -276.352896) (xy 115.175948 -276.396473) (xy 115.191532 -276.443154) (xy 115.199427 -276.491731)
			(xy 115.199922 -276.516338) (xy 115.528864 -276.516338) (xy 115.532824 -276.467284) (xy 115.544601 -276.4195)
			(xy 115.563892 -276.374224) (xy 115.590195 -276.332628) (xy 115.62283 -276.295791) (xy 115.660951 -276.264666)
			(xy 115.703572 -276.240059) (xy 115.749588 -276.222607) (xy 115.797807 -276.212763) (xy 115.846982 -276.210782)
			(xy 115.895837 -276.216714) (xy 115.943108 -276.230406) (xy 115.98757 -276.251504) (xy 116.028073 -276.27946)
			(xy 116.063566 -276.313552) (xy 116.093131 -276.352896) (xy 116.116002 -276.396473) (xy 116.131586 -276.443154)
			(xy 116.139481 -276.491731) (xy 116.139976 -276.516338) (xy 116.458487 -276.516338) (xy 116.462582 -276.46561)
			(xy 116.474761 -276.416196) (xy 116.494709 -276.369376) (xy 116.52191 -276.326362) (xy 116.555658 -276.288268)
			(xy 116.59508 -276.256081) (xy 116.639154 -276.230635) (xy 116.68674 -276.212588) (xy 116.736604 -276.202408)
			(xy 116.787456 -276.200359) (xy 116.837977 -276.206493) (xy 116.886861 -276.220653) (xy 116.93284 -276.24247)
			(xy 116.974724 -276.27138) (xy 117.011428 -276.306635) (xy 117.042001 -276.347321) (xy 117.065652 -276.392384)
			(xy 117.081768 -276.440658) (xy 117.089932 -276.490892) (xy 117.090444 -276.516338) (xy 117.398541 -276.516338)
			(xy 117.402636 -276.46561) (xy 117.414815 -276.416196) (xy 117.434763 -276.369376) (xy 117.461964 -276.326362)
			(xy 117.495712 -276.288268) (xy 117.535134 -276.256081) (xy 117.579208 -276.230635) (xy 117.626794 -276.212588)
			(xy 117.676658 -276.202408) (xy 117.72751 -276.200359) (xy 117.778031 -276.206493) (xy 117.826915 -276.220653)
			(xy 117.872894 -276.24247) (xy 117.914778 -276.27138) (xy 117.951482 -276.306635) (xy 117.982055 -276.347321)
			(xy 118.005706 -276.392384) (xy 118.021822 -276.440658) (xy 118.029986 -276.490892) (xy 118.030498 -276.516338)
			(xy 118.349026 -276.516338) (xy 118.352986 -276.467284) (xy 118.364763 -276.4195) (xy 118.384054 -276.374224)
			(xy 118.410357 -276.332628) (xy 118.442992 -276.295791) (xy 118.481113 -276.264666) (xy 118.523734 -276.240059)
			(xy 118.56975 -276.222607) (xy 118.617969 -276.212763) (xy 118.667144 -276.210782) (xy 118.715999 -276.216714)
			(xy 118.76327 -276.230406) (xy 118.807732 -276.251504) (xy 118.848235 -276.27946) (xy 118.883728 -276.313552)
			(xy 118.913293 -276.352896) (xy 118.936164 -276.396473) (xy 118.951748 -276.443154) (xy 118.959643 -276.491731)
			(xy 118.960138 -276.516338) (xy 119.278395 -276.516338) (xy 119.28249 -276.46561) (xy 119.294669 -276.416196)
			(xy 119.314617 -276.369376) (xy 119.341818 -276.326362) (xy 119.375566 -276.288268) (xy 119.414988 -276.256081)
			(xy 119.459062 -276.230635) (xy 119.506648 -276.212588) (xy 119.556512 -276.202408) (xy 119.607364 -276.200359)
			(xy 119.657885 -276.206493) (xy 119.706769 -276.220653) (xy 119.752748 -276.24247) (xy 119.794632 -276.27138)
			(xy 119.831336 -276.306635) (xy 119.861909 -276.347321) (xy 119.88556 -276.392384) (xy 119.901676 -276.440658)
			(xy 119.90984 -276.490892) (xy 119.910352 -276.516338) (xy 120.218449 -276.516338) (xy 120.222544 -276.46561)
			(xy 120.234723 -276.416196) (xy 120.254671 -276.369376) (xy 120.281872 -276.326362) (xy 120.31562 -276.288268)
			(xy 120.355042 -276.256081) (xy 120.399116 -276.230635) (xy 120.446702 -276.212588) (xy 120.496566 -276.202408)
			(xy 120.547418 -276.200359) (xy 120.597939 -276.206493) (xy 120.646823 -276.220653) (xy 120.692802 -276.24247)
			(xy 120.734686 -276.27138) (xy 120.77139 -276.306635) (xy 120.801963 -276.347321) (xy 120.825614 -276.392384)
			(xy 120.84173 -276.440658) (xy 120.849894 -276.490892) (xy 120.850406 -276.516338) (xy 121.168934 -276.516338)
			(xy 121.172894 -276.467284) (xy 121.184671 -276.4195) (xy 121.203962 -276.374224) (xy 121.230265 -276.332628)
			(xy 121.2629 -276.295791) (xy 121.301021 -276.264666) (xy 121.343642 -276.240059) (xy 121.389658 -276.222607)
			(xy 121.437877 -276.212763) (xy 121.487052 -276.210782) (xy 121.535907 -276.216714) (xy 121.583178 -276.230406)
			(xy 121.62764 -276.251504) (xy 121.668143 -276.27946) (xy 121.703636 -276.313552) (xy 121.733201 -276.352896)
			(xy 121.756072 -276.396473) (xy 121.771656 -276.443154) (xy 121.779551 -276.491731) (xy 121.780046 -276.516338)
			(xy 122.098557 -276.516338) (xy 122.102652 -276.46561) (xy 122.114831 -276.416196) (xy 122.134779 -276.369376)
			(xy 122.16198 -276.326362) (xy 122.195728 -276.288268) (xy 122.23515 -276.256081) (xy 122.279224 -276.230635)
			(xy 122.32681 -276.212588) (xy 122.376674 -276.202408) (xy 122.427526 -276.200359) (xy 122.478047 -276.206493)
			(xy 122.526931 -276.220653) (xy 122.57291 -276.24247) (xy 122.614794 -276.27138) (xy 122.651498 -276.306635)
			(xy 122.682071 -276.347321) (xy 122.705722 -276.392384) (xy 122.721838 -276.440658) (xy 122.730002 -276.490892)
			(xy 122.730514 -276.516338) (xy 123.038611 -276.516338) (xy 123.042706 -276.46561) (xy 123.054885 -276.416196)
			(xy 123.074833 -276.369376) (xy 123.102034 -276.326362) (xy 123.135782 -276.288268) (xy 123.175204 -276.256081)
			(xy 123.219278 -276.230635) (xy 123.266864 -276.212588) (xy 123.316728 -276.202408) (xy 123.36758 -276.200359)
			(xy 123.418101 -276.206493) (xy 123.466985 -276.220653) (xy 123.512964 -276.24247) (xy 123.554848 -276.27138)
			(xy 123.591552 -276.306635) (xy 123.622125 -276.347321) (xy 123.645776 -276.392384) (xy 123.661892 -276.440658)
			(xy 123.670056 -276.490892) (xy 123.670568 -276.516338) (xy 123.988842 -276.516338) (xy 123.992802 -276.467284)
			(xy 124.004579 -276.4195) (xy 124.02387 -276.374224) (xy 124.050173 -276.332628) (xy 124.082808 -276.295791)
			(xy 124.120929 -276.264666) (xy 124.16355 -276.240059) (xy 124.209566 -276.222607) (xy 124.257785 -276.212763)
			(xy 124.30696 -276.210782) (xy 124.355815 -276.216714) (xy 124.403086 -276.230406) (xy 124.447548 -276.251504)
			(xy 124.488051 -276.27946) (xy 124.523544 -276.313552) (xy 124.553109 -276.352896) (xy 124.57598 -276.396473)
			(xy 124.591564 -276.443154) (xy 124.599459 -276.491731) (xy 124.599954 -276.516338) (xy 124.918465 -276.516338)
			(xy 124.92256 -276.46561) (xy 124.934739 -276.416196) (xy 124.954687 -276.369376) (xy 124.981888 -276.326362)
			(xy 125.015636 -276.288268) (xy 125.055058 -276.256081) (xy 125.099132 -276.230635) (xy 125.146718 -276.212588)
			(xy 125.196582 -276.202408) (xy 125.247434 -276.200359) (xy 125.297955 -276.206493) (xy 125.346839 -276.220653)
			(xy 125.392818 -276.24247) (xy 125.434702 -276.27138) (xy 125.471406 -276.306635) (xy 125.501979 -276.347321)
			(xy 125.52563 -276.392384) (xy 125.541746 -276.440658) (xy 125.54991 -276.490892) (xy 125.550422 -276.516338)
			(xy 125.858519 -276.516338) (xy 125.862614 -276.46561) (xy 125.874793 -276.416196) (xy 125.894741 -276.369376)
			(xy 125.921942 -276.326362) (xy 125.95569 -276.288268) (xy 125.995112 -276.256081) (xy 126.039186 -276.230635)
			(xy 126.086772 -276.212588) (xy 126.136636 -276.202408) (xy 126.187488 -276.200359) (xy 126.238009 -276.206493)
			(xy 126.286893 -276.220653) (xy 126.332872 -276.24247) (xy 126.374756 -276.27138) (xy 126.41146 -276.306635)
			(xy 126.442033 -276.347321) (xy 126.465684 -276.392384) (xy 126.4818 -276.440658) (xy 126.489964 -276.490892)
			(xy 126.490476 -276.516338) (xy 126.489964 -276.541784) (xy 126.4818 -276.592018) (xy 126.465684 -276.640292)
			(xy 126.442033 -276.685355) (xy 126.41146 -276.726041) (xy 126.374756 -276.761296) (xy 126.332872 -276.790206)
			(xy 126.286893 -276.812023) (xy 126.238009 -276.826183) (xy 126.187488 -276.832317) (xy 126.136636 -276.830268)
			(xy 126.086772 -276.820088) (xy 126.039186 -276.802041) (xy 125.995112 -276.776595) (xy 125.95569 -276.744408)
			(xy 125.921942 -276.706314) (xy 125.894741 -276.6633) (xy 125.874793 -276.61648) (xy 125.862614 -276.567066)
			(xy 125.858519 -276.516338) (xy 125.550422 -276.516338) (xy 125.54991 -276.541784) (xy 125.541746 -276.592018)
			(xy 125.52563 -276.640292) (xy 125.501979 -276.685355) (xy 125.471406 -276.726041) (xy 125.434702 -276.761296)
			(xy 125.392818 -276.790206) (xy 125.346839 -276.812023) (xy 125.297955 -276.826183) (xy 125.247434 -276.832317)
			(xy 125.196582 -276.830268) (xy 125.146718 -276.820088) (xy 125.099132 -276.802041) (xy 125.055058 -276.776595)
			(xy 125.015636 -276.744408) (xy 124.981888 -276.706314) (xy 124.954687 -276.6633) (xy 124.934739 -276.61648)
			(xy 124.92256 -276.567066) (xy 124.918465 -276.516338) (xy 124.599954 -276.516338) (xy 124.599459 -276.540945)
			(xy 124.591564 -276.589522) (xy 124.57598 -276.636203) (xy 124.553109 -276.67978) (xy 124.523544 -276.719124)
			(xy 124.488051 -276.753216) (xy 124.447548 -276.781172) (xy 124.403086 -276.80227) (xy 124.355815 -276.815962)
			(xy 124.30696 -276.821894) (xy 124.257785 -276.819913) (xy 124.209566 -276.810069) (xy 124.16355 -276.792617)
			(xy 124.120929 -276.76801) (xy 124.082808 -276.736885) (xy 124.050173 -276.700048) (xy 124.02387 -276.658452)
			(xy 124.004579 -276.613176) (xy 123.992802 -276.565392) (xy 123.988842 -276.516338) (xy 123.670568 -276.516338)
			(xy 123.670056 -276.541784) (xy 123.661892 -276.592018) (xy 123.645776 -276.640292) (xy 123.622125 -276.685355)
			(xy 123.591552 -276.726041) (xy 123.554848 -276.761296) (xy 123.512964 -276.790206) (xy 123.466985 -276.812023)
			(xy 123.418101 -276.826183) (xy 123.36758 -276.832317) (xy 123.316728 -276.830268) (xy 123.266864 -276.820088)
			(xy 123.219278 -276.802041) (xy 123.175204 -276.776595) (xy 123.135782 -276.744408) (xy 123.102034 -276.706314)
			(xy 123.074833 -276.6633) (xy 123.054885 -276.61648) (xy 123.042706 -276.567066) (xy 123.038611 -276.516338)
			(xy 122.730514 -276.516338) (xy 122.730002 -276.541784) (xy 122.721838 -276.592018) (xy 122.705722 -276.640292)
			(xy 122.682071 -276.685355) (xy 122.651498 -276.726041) (xy 122.614794 -276.761296) (xy 122.57291 -276.790206)
			(xy 122.526931 -276.812023) (xy 122.478047 -276.826183) (xy 122.427526 -276.832317) (xy 122.376674 -276.830268)
			(xy 122.32681 -276.820088) (xy 122.279224 -276.802041) (xy 122.23515 -276.776595) (xy 122.195728 -276.744408)
			(xy 122.16198 -276.706314) (xy 122.134779 -276.6633) (xy 122.114831 -276.61648) (xy 122.102652 -276.567066)
			(xy 122.098557 -276.516338) (xy 121.780046 -276.516338) (xy 121.779551 -276.540945) (xy 121.771656 -276.589522)
			(xy 121.756072 -276.636203) (xy 121.733201 -276.67978) (xy 121.703636 -276.719124) (xy 121.668143 -276.753216)
			(xy 121.62764 -276.781172) (xy 121.583178 -276.80227) (xy 121.535907 -276.815962) (xy 121.487052 -276.821894)
			(xy 121.437877 -276.819913) (xy 121.389658 -276.810069) (xy 121.343642 -276.792617) (xy 121.301021 -276.76801)
			(xy 121.2629 -276.736885) (xy 121.230265 -276.700048) (xy 121.203962 -276.658452) (xy 121.184671 -276.613176)
			(xy 121.172894 -276.565392) (xy 121.168934 -276.516338) (xy 120.850406 -276.516338) (xy 120.849894 -276.541784)
			(xy 120.84173 -276.592018) (xy 120.825614 -276.640292) (xy 120.801963 -276.685355) (xy 120.77139 -276.726041)
			(xy 120.734686 -276.761296) (xy 120.692802 -276.790206) (xy 120.646823 -276.812023) (xy 120.597939 -276.826183)
			(xy 120.547418 -276.832317) (xy 120.496566 -276.830268) (xy 120.446702 -276.820088) (xy 120.399116 -276.802041)
			(xy 120.355042 -276.776595) (xy 120.31562 -276.744408) (xy 120.281872 -276.706314) (xy 120.254671 -276.6633)
			(xy 120.234723 -276.61648) (xy 120.222544 -276.567066) (xy 120.218449 -276.516338) (xy 119.910352 -276.516338)
			(xy 119.90984 -276.541784) (xy 119.901676 -276.592018) (xy 119.88556 -276.640292) (xy 119.861909 -276.685355)
			(xy 119.831336 -276.726041) (xy 119.794632 -276.761296) (xy 119.752748 -276.790206) (xy 119.706769 -276.812023)
			(xy 119.657885 -276.826183) (xy 119.607364 -276.832317) (xy 119.556512 -276.830268) (xy 119.506648 -276.820088)
			(xy 119.459062 -276.802041) (xy 119.414988 -276.776595) (xy 119.375566 -276.744408) (xy 119.341818 -276.706314)
			(xy 119.314617 -276.6633) (xy 119.294669 -276.61648) (xy 119.28249 -276.567066) (xy 119.278395 -276.516338)
			(xy 118.960138 -276.516338) (xy 118.959643 -276.540945) (xy 118.951748 -276.589522) (xy 118.936164 -276.636203)
			(xy 118.913293 -276.67978) (xy 118.883728 -276.719124) (xy 118.848235 -276.753216) (xy 118.807732 -276.781172)
			(xy 118.76327 -276.80227) (xy 118.715999 -276.815962) (xy 118.667144 -276.821894) (xy 118.617969 -276.819913)
			(xy 118.56975 -276.810069) (xy 118.523734 -276.792617) (xy 118.481113 -276.76801) (xy 118.442992 -276.736885)
			(xy 118.410357 -276.700048) (xy 118.384054 -276.658452) (xy 118.364763 -276.613176) (xy 118.352986 -276.565392)
			(xy 118.349026 -276.516338) (xy 118.030498 -276.516338) (xy 118.029986 -276.541784) (xy 118.021822 -276.592018)
			(xy 118.005706 -276.640292) (xy 117.982055 -276.685355) (xy 117.951482 -276.726041) (xy 117.914778 -276.761296)
			(xy 117.872894 -276.790206) (xy 117.826915 -276.812023) (xy 117.778031 -276.826183) (xy 117.72751 -276.832317)
			(xy 117.676658 -276.830268) (xy 117.626794 -276.820088) (xy 117.579208 -276.802041) (xy 117.535134 -276.776595)
			(xy 117.495712 -276.744408) (xy 117.461964 -276.706314) (xy 117.434763 -276.6633) (xy 117.414815 -276.61648)
			(xy 117.402636 -276.567066) (xy 117.398541 -276.516338) (xy 117.090444 -276.516338) (xy 117.089932 -276.541784)
			(xy 117.081768 -276.592018) (xy 117.065652 -276.640292) (xy 117.042001 -276.685355) (xy 117.011428 -276.726041)
			(xy 116.974724 -276.761296) (xy 116.93284 -276.790206) (xy 116.886861 -276.812023) (xy 116.837977 -276.826183)
			(xy 116.787456 -276.832317) (xy 116.736604 -276.830268) (xy 116.68674 -276.820088) (xy 116.639154 -276.802041)
			(xy 116.59508 -276.776595) (xy 116.555658 -276.744408) (xy 116.52191 -276.706314) (xy 116.494709 -276.6633)
			(xy 116.474761 -276.61648) (xy 116.462582 -276.567066) (xy 116.458487 -276.516338) (xy 116.139976 -276.516338)
			(xy 116.139481 -276.540945) (xy 116.131586 -276.589522) (xy 116.116002 -276.636203) (xy 116.093131 -276.67978)
			(xy 116.063566 -276.719124) (xy 116.028073 -276.753216) (xy 115.98757 -276.781172) (xy 115.943108 -276.80227)
			(xy 115.895837 -276.815962) (xy 115.846982 -276.821894) (xy 115.797807 -276.819913) (xy 115.749588 -276.810069)
			(xy 115.703572 -276.792617) (xy 115.660951 -276.76801) (xy 115.62283 -276.736885) (xy 115.590195 -276.700048)
			(xy 115.563892 -276.658452) (xy 115.544601 -276.613176) (xy 115.532824 -276.565392) (xy 115.528864 -276.516338)
			(xy 115.199922 -276.516338) (xy 115.199427 -276.540945) (xy 115.191532 -276.589522) (xy 115.175948 -276.636203)
			(xy 115.153077 -276.67978) (xy 115.123512 -276.719124) (xy 115.088019 -276.753216) (xy 115.047516 -276.781172)
			(xy 115.003054 -276.80227) (xy 114.955783 -276.815962) (xy 114.906928 -276.821894) (xy 114.857753 -276.819913)
			(xy 114.809534 -276.810069) (xy 114.763518 -276.792617) (xy 114.720897 -276.76801) (xy 114.682776 -276.736885)
			(xy 114.650141 -276.700048) (xy 114.623838 -276.658452) (xy 114.604547 -276.613176) (xy 114.59277 -276.565392)
			(xy 114.58881 -276.516338) (xy 114.260122 -276.516338) (xy 114.259627 -276.540945) (xy 114.251732 -276.589522)
			(xy 114.236148 -276.636203) (xy 114.213277 -276.67978) (xy 114.183712 -276.719124) (xy 114.148219 -276.753216)
			(xy 114.107716 -276.781172) (xy 114.063254 -276.80227) (xy 114.015983 -276.815962) (xy 113.967128 -276.821894)
			(xy 113.917953 -276.819913) (xy 113.869734 -276.810069) (xy 113.823718 -276.792617) (xy 113.781097 -276.76801)
			(xy 113.742976 -276.736885) (xy 113.710341 -276.700048) (xy 113.684038 -276.658452) (xy 113.664747 -276.613176)
			(xy 113.65297 -276.565392) (xy 113.64901 -276.516338) (xy 112.334354 -276.516338) (xy 112.34747 -277.326344)
			(xy 113.178856 -277.326344) (xy 113.182816 -277.27729) (xy 113.194593 -277.229506) (xy 113.213884 -277.18423)
			(xy 113.240187 -277.142634) (xy 113.272822 -277.105797) (xy 113.310943 -277.074672) (xy 113.353564 -277.050065)
			(xy 113.39958 -277.032613) (xy 113.447799 -277.022769) (xy 113.496974 -277.020788) (xy 113.545829 -277.02672)
			(xy 113.5931 -277.040412) (xy 113.637562 -277.06151) (xy 113.678065 -277.089466) (xy 113.713558 -277.123558)
			(xy 113.743123 -277.162902) (xy 113.765994 -277.206479) (xy 113.781578 -277.25316) (xy 113.789473 -277.301737)
			(xy 113.789968 -277.326344) (xy 114.108479 -277.326344) (xy 114.112574 -277.275616) (xy 114.124753 -277.226202)
			(xy 114.144701 -277.179382) (xy 114.171902 -277.136368) (xy 114.20565 -277.098274) (xy 114.245072 -277.066087)
			(xy 114.289146 -277.040641) (xy 114.336732 -277.022594) (xy 114.386596 -277.012414) (xy 114.437448 -277.010365)
			(xy 114.487969 -277.016499) (xy 114.536853 -277.030659) (xy 114.582832 -277.052476) (xy 114.624716 -277.081386)
			(xy 114.66142 -277.116641) (xy 114.691993 -277.157327) (xy 114.715644 -277.20239) (xy 114.73176 -277.250664)
			(xy 114.739924 -277.300898) (xy 114.740436 -277.326344) (xy 115.048533 -277.326344) (xy 115.052628 -277.275616)
			(xy 115.064807 -277.226202) (xy 115.084755 -277.179382) (xy 115.111956 -277.136368) (xy 115.145704 -277.098274)
			(xy 115.185126 -277.066087) (xy 115.2292 -277.040641) (xy 115.276786 -277.022594) (xy 115.32665 -277.012414)
			(xy 115.377502 -277.010365) (xy 115.428023 -277.016499) (xy 115.476907 -277.030659) (xy 115.522886 -277.052476)
			(xy 115.56477 -277.081386) (xy 115.601474 -277.116641) (xy 115.632047 -277.157327) (xy 115.655698 -277.20239)
			(xy 115.671814 -277.250664) (xy 115.679978 -277.300898) (xy 115.68049 -277.326344) (xy 115.999018 -277.326344)
			(xy 116.002978 -277.27729) (xy 116.014755 -277.229506) (xy 116.034046 -277.18423) (xy 116.060349 -277.142634)
			(xy 116.092984 -277.105797) (xy 116.131105 -277.074672) (xy 116.173726 -277.050065) (xy 116.219742 -277.032613)
			(xy 116.267961 -277.022769) (xy 116.317136 -277.020788) (xy 116.365991 -277.02672) (xy 116.413262 -277.040412)
			(xy 116.457724 -277.06151) (xy 116.498227 -277.089466) (xy 116.53372 -277.123558) (xy 116.563285 -277.162902)
			(xy 116.586156 -277.206479) (xy 116.60174 -277.25316) (xy 116.609635 -277.301737) (xy 116.61013 -277.326344)
			(xy 116.938818 -277.326344) (xy 116.942778 -277.27729) (xy 116.954555 -277.229506) (xy 116.973846 -277.18423)
			(xy 117.000149 -277.142634) (xy 117.032784 -277.105797) (xy 117.070905 -277.074672) (xy 117.113526 -277.050065)
			(xy 117.159542 -277.032613) (xy 117.207761 -277.022769) (xy 117.256936 -277.020788) (xy 117.305791 -277.02672)
			(xy 117.353062 -277.040412) (xy 117.397524 -277.06151) (xy 117.438027 -277.089466) (xy 117.47352 -277.123558)
			(xy 117.503085 -277.162902) (xy 117.525956 -277.206479) (xy 117.54154 -277.25316) (xy 117.549435 -277.301737)
			(xy 117.54993 -277.326344) (xy 117.878872 -277.326344) (xy 117.882832 -277.27729) (xy 117.894609 -277.229506)
			(xy 117.9139 -277.18423) (xy 117.940203 -277.142634) (xy 117.972838 -277.105797) (xy 118.010959 -277.074672)
			(xy 118.05358 -277.050065) (xy 118.099596 -277.032613) (xy 118.147815 -277.022769) (xy 118.19699 -277.020788)
			(xy 118.245845 -277.02672) (xy 118.293116 -277.040412) (xy 118.337578 -277.06151) (xy 118.378081 -277.089466)
			(xy 118.413574 -277.123558) (xy 118.443139 -277.162902) (xy 118.46601 -277.206479) (xy 118.481594 -277.25316)
			(xy 118.489489 -277.301737) (xy 118.489984 -277.326344) (xy 118.818926 -277.326344) (xy 118.822886 -277.27729)
			(xy 118.834663 -277.229506) (xy 118.853954 -277.18423) (xy 118.880257 -277.142634) (xy 118.912892 -277.105797)
			(xy 118.951013 -277.074672) (xy 118.993634 -277.050065) (xy 119.03965 -277.032613) (xy 119.087869 -277.022769)
			(xy 119.137044 -277.020788) (xy 119.185899 -277.02672) (xy 119.23317 -277.040412) (xy 119.277632 -277.06151)
			(xy 119.318135 -277.089466) (xy 119.353628 -277.123558) (xy 119.383193 -277.162902) (xy 119.406064 -277.206479)
			(xy 119.421648 -277.25316) (xy 119.429543 -277.301737) (xy 119.430038 -277.326344) (xy 119.75898 -277.326344)
			(xy 119.76294 -277.27729) (xy 119.774717 -277.229506) (xy 119.794008 -277.18423) (xy 119.820311 -277.142634)
			(xy 119.852946 -277.105797) (xy 119.891067 -277.074672) (xy 119.933688 -277.050065) (xy 119.979704 -277.032613)
			(xy 120.027923 -277.022769) (xy 120.077098 -277.020788) (xy 120.125953 -277.02672) (xy 120.173224 -277.040412)
			(xy 120.217686 -277.06151) (xy 120.258189 -277.089466) (xy 120.293682 -277.123558) (xy 120.323247 -277.162902)
			(xy 120.346118 -277.206479) (xy 120.361702 -277.25316) (xy 120.369597 -277.301737) (xy 120.370092 -277.326344)
			(xy 120.699034 -277.326344) (xy 120.702994 -277.27729) (xy 120.714771 -277.229506) (xy 120.734062 -277.18423)
			(xy 120.760365 -277.142634) (xy 120.793 -277.105797) (xy 120.831121 -277.074672) (xy 120.873742 -277.050065)
			(xy 120.919758 -277.032613) (xy 120.967977 -277.022769) (xy 121.017152 -277.020788) (xy 121.066007 -277.02672)
			(xy 121.113278 -277.040412) (xy 121.15774 -277.06151) (xy 121.198243 -277.089466) (xy 121.233736 -277.123558)
			(xy 121.263301 -277.162902) (xy 121.286172 -277.206479) (xy 121.301756 -277.25316) (xy 121.309651 -277.301737)
			(xy 121.310146 -277.326344) (xy 121.638834 -277.326344) (xy 121.642794 -277.27729) (xy 121.654571 -277.229506)
			(xy 121.673862 -277.18423) (xy 121.700165 -277.142634) (xy 121.7328 -277.105797) (xy 121.770921 -277.074672)
			(xy 121.813542 -277.050065) (xy 121.859558 -277.032613) (xy 121.907777 -277.022769) (xy 121.956952 -277.020788)
			(xy 122.005807 -277.02672) (xy 122.053078 -277.040412) (xy 122.09754 -277.06151) (xy 122.138043 -277.089466)
			(xy 122.173536 -277.123558) (xy 122.203101 -277.162902) (xy 122.225972 -277.206479) (xy 122.241556 -277.25316)
			(xy 122.249451 -277.301737) (xy 122.249946 -277.326344) (xy 122.578888 -277.326344) (xy 122.582848 -277.27729)
			(xy 122.594625 -277.229506) (xy 122.613916 -277.18423) (xy 122.640219 -277.142634) (xy 122.672854 -277.105797)
			(xy 122.710975 -277.074672) (xy 122.753596 -277.050065) (xy 122.799612 -277.032613) (xy 122.847831 -277.022769)
			(xy 122.897006 -277.020788) (xy 122.945861 -277.02672) (xy 122.993132 -277.040412) (xy 123.037594 -277.06151)
			(xy 123.078097 -277.089466) (xy 123.11359 -277.123558) (xy 123.143155 -277.162902) (xy 123.166026 -277.206479)
			(xy 123.18161 -277.25316) (xy 123.189505 -277.301737) (xy 123.19 -277.326344) (xy 123.518942 -277.326344)
			(xy 123.522902 -277.27729) (xy 123.534679 -277.229506) (xy 123.55397 -277.18423) (xy 123.580273 -277.142634)
			(xy 123.612908 -277.105797) (xy 123.651029 -277.074672) (xy 123.69365 -277.050065) (xy 123.739666 -277.032613)
			(xy 123.787885 -277.022769) (xy 123.83706 -277.020788) (xy 123.885915 -277.02672) (xy 123.933186 -277.040412)
			(xy 123.977648 -277.06151) (xy 124.018151 -277.089466) (xy 124.053644 -277.123558) (xy 124.083209 -277.162902)
			(xy 124.10608 -277.206479) (xy 124.121664 -277.25316) (xy 124.129559 -277.301737) (xy 124.130054 -277.326344)
			(xy 124.458996 -277.326344) (xy 124.462956 -277.27729) (xy 124.474733 -277.229506) (xy 124.494024 -277.18423)
			(xy 124.520327 -277.142634) (xy 124.552962 -277.105797) (xy 124.591083 -277.074672) (xy 124.633704 -277.050065)
			(xy 124.67972 -277.032613) (xy 124.727939 -277.022769) (xy 124.777114 -277.020788) (xy 124.825969 -277.02672)
			(xy 124.87324 -277.040412) (xy 124.917702 -277.06151) (xy 124.958205 -277.089466) (xy 124.993698 -277.123558)
			(xy 125.023263 -277.162902) (xy 125.046134 -277.206479) (xy 125.061718 -277.25316) (xy 125.069613 -277.301737)
			(xy 125.070108 -277.326344) (xy 125.39905 -277.326344) (xy 125.40301 -277.27729) (xy 125.414787 -277.229506)
			(xy 125.434078 -277.18423) (xy 125.460381 -277.142634) (xy 125.493016 -277.105797) (xy 125.531137 -277.074672)
			(xy 125.573758 -277.050065) (xy 125.619774 -277.032613) (xy 125.667993 -277.022769) (xy 125.717168 -277.020788)
			(xy 125.766023 -277.02672) (xy 125.813294 -277.040412) (xy 125.857756 -277.06151) (xy 125.898259 -277.089466)
			(xy 125.933752 -277.123558) (xy 125.963317 -277.162902) (xy 125.986188 -277.206479) (xy 126.001772 -277.25316)
			(xy 126.009667 -277.301737) (xy 126.010162 -277.326344) (xy 126.009667 -277.350951) (xy 126.001772 -277.399528)
			(xy 125.986188 -277.446209) (xy 125.963317 -277.489786) (xy 125.933752 -277.52913) (xy 125.898259 -277.563222)
			(xy 125.857756 -277.591178) (xy 125.813294 -277.612276) (xy 125.766023 -277.625968) (xy 125.717168 -277.6319)
			(xy 125.667993 -277.629919) (xy 125.619774 -277.620075) (xy 125.573758 -277.602623) (xy 125.531137 -277.578016)
			(xy 125.493016 -277.546891) (xy 125.460381 -277.510054) (xy 125.434078 -277.468458) (xy 125.414787 -277.423182)
			(xy 125.40301 -277.375398) (xy 125.39905 -277.326344) (xy 125.070108 -277.326344) (xy 125.069613 -277.350951)
			(xy 125.061718 -277.399528) (xy 125.046134 -277.446209) (xy 125.023263 -277.489786) (xy 124.993698 -277.52913)
			(xy 124.958205 -277.563222) (xy 124.917702 -277.591178) (xy 124.87324 -277.612276) (xy 124.825969 -277.625968)
			(xy 124.777114 -277.6319) (xy 124.727939 -277.629919) (xy 124.67972 -277.620075) (xy 124.633704 -277.602623)
			(xy 124.591083 -277.578016) (xy 124.552962 -277.546891) (xy 124.520327 -277.510054) (xy 124.494024 -277.468458)
			(xy 124.474733 -277.423182) (xy 124.462956 -277.375398) (xy 124.458996 -277.326344) (xy 124.130054 -277.326344)
			(xy 124.129559 -277.350951) (xy 124.121664 -277.399528) (xy 124.10608 -277.446209) (xy 124.083209 -277.489786)
			(xy 124.053644 -277.52913) (xy 124.018151 -277.563222) (xy 123.977648 -277.591178) (xy 123.933186 -277.612276)
			(xy 123.885915 -277.625968) (xy 123.83706 -277.6319) (xy 123.787885 -277.629919) (xy 123.739666 -277.620075)
			(xy 123.69365 -277.602623) (xy 123.651029 -277.578016) (xy 123.612908 -277.546891) (xy 123.580273 -277.510054)
			(xy 123.55397 -277.468458) (xy 123.534679 -277.423182) (xy 123.522902 -277.375398) (xy 123.518942 -277.326344)
			(xy 123.19 -277.326344) (xy 123.189505 -277.350951) (xy 123.18161 -277.399528) (xy 123.166026 -277.446209)
			(xy 123.143155 -277.489786) (xy 123.11359 -277.52913) (xy 123.078097 -277.563222) (xy 123.037594 -277.591178)
			(xy 122.993132 -277.612276) (xy 122.945861 -277.625968) (xy 122.897006 -277.6319) (xy 122.847831 -277.629919)
			(xy 122.799612 -277.620075) (xy 122.753596 -277.602623) (xy 122.710975 -277.578016) (xy 122.672854 -277.546891)
			(xy 122.640219 -277.510054) (xy 122.613916 -277.468458) (xy 122.594625 -277.423182) (xy 122.582848 -277.375398)
			(xy 122.578888 -277.326344) (xy 122.249946 -277.326344) (xy 122.249451 -277.350951) (xy 122.241556 -277.399528)
			(xy 122.225972 -277.446209) (xy 122.203101 -277.489786) (xy 122.173536 -277.52913) (xy 122.138043 -277.563222)
			(xy 122.09754 -277.591178) (xy 122.053078 -277.612276) (xy 122.005807 -277.625968) (xy 121.956952 -277.6319)
			(xy 121.907777 -277.629919) (xy 121.859558 -277.620075) (xy 121.813542 -277.602623) (xy 121.770921 -277.578016)
			(xy 121.7328 -277.546891) (xy 121.700165 -277.510054) (xy 121.673862 -277.468458) (xy 121.654571 -277.423182)
			(xy 121.642794 -277.375398) (xy 121.638834 -277.326344) (xy 121.310146 -277.326344) (xy 121.309651 -277.350951)
			(xy 121.301756 -277.399528) (xy 121.286172 -277.446209) (xy 121.263301 -277.489786) (xy 121.233736 -277.52913)
			(xy 121.198243 -277.563222) (xy 121.15774 -277.591178) (xy 121.113278 -277.612276) (xy 121.066007 -277.625968)
			(xy 121.017152 -277.6319) (xy 120.967977 -277.629919) (xy 120.919758 -277.620075) (xy 120.873742 -277.602623)
			(xy 120.831121 -277.578016) (xy 120.793 -277.546891) (xy 120.760365 -277.510054) (xy 120.734062 -277.468458)
			(xy 120.714771 -277.423182) (xy 120.702994 -277.375398) (xy 120.699034 -277.326344) (xy 120.370092 -277.326344)
			(xy 120.369597 -277.350951) (xy 120.361702 -277.399528) (xy 120.346118 -277.446209) (xy 120.323247 -277.489786)
			(xy 120.293682 -277.52913) (xy 120.258189 -277.563222) (xy 120.217686 -277.591178) (xy 120.173224 -277.612276)
			(xy 120.125953 -277.625968) (xy 120.077098 -277.6319) (xy 120.027923 -277.629919) (xy 119.979704 -277.620075)
			(xy 119.933688 -277.602623) (xy 119.891067 -277.578016) (xy 119.852946 -277.546891) (xy 119.820311 -277.510054)
			(xy 119.794008 -277.468458) (xy 119.774717 -277.423182) (xy 119.76294 -277.375398) (xy 119.75898 -277.326344)
			(xy 119.430038 -277.326344) (xy 119.429543 -277.350951) (xy 119.421648 -277.399528) (xy 119.406064 -277.446209)
			(xy 119.383193 -277.489786) (xy 119.353628 -277.52913) (xy 119.318135 -277.563222) (xy 119.277632 -277.591178)
			(xy 119.23317 -277.612276) (xy 119.185899 -277.625968) (xy 119.137044 -277.6319) (xy 119.087869 -277.629919)
			(xy 119.03965 -277.620075) (xy 118.993634 -277.602623) (xy 118.951013 -277.578016) (xy 118.912892 -277.546891)
			(xy 118.880257 -277.510054) (xy 118.853954 -277.468458) (xy 118.834663 -277.423182) (xy 118.822886 -277.375398)
			(xy 118.818926 -277.326344) (xy 118.489984 -277.326344) (xy 118.489489 -277.350951) (xy 118.481594 -277.399528)
			(xy 118.46601 -277.446209) (xy 118.443139 -277.489786) (xy 118.413574 -277.52913) (xy 118.378081 -277.563222)
			(xy 118.337578 -277.591178) (xy 118.293116 -277.612276) (xy 118.245845 -277.625968) (xy 118.19699 -277.6319)
			(xy 118.147815 -277.629919) (xy 118.099596 -277.620075) (xy 118.05358 -277.602623) (xy 118.010959 -277.578016)
			(xy 117.972838 -277.546891) (xy 117.940203 -277.510054) (xy 117.9139 -277.468458) (xy 117.894609 -277.423182)
			(xy 117.882832 -277.375398) (xy 117.878872 -277.326344) (xy 117.54993 -277.326344) (xy 117.549435 -277.350951)
			(xy 117.54154 -277.399528) (xy 117.525956 -277.446209) (xy 117.503085 -277.489786) (xy 117.47352 -277.52913)
			(xy 117.438027 -277.563222) (xy 117.397524 -277.591178) (xy 117.353062 -277.612276) (xy 117.305791 -277.625968)
			(xy 117.256936 -277.6319) (xy 117.207761 -277.629919) (xy 117.159542 -277.620075) (xy 117.113526 -277.602623)
			(xy 117.070905 -277.578016) (xy 117.032784 -277.546891) (xy 117.000149 -277.510054) (xy 116.973846 -277.468458)
			(xy 116.954555 -277.423182) (xy 116.942778 -277.375398) (xy 116.938818 -277.326344) (xy 116.61013 -277.326344)
			(xy 116.609635 -277.350951) (xy 116.60174 -277.399528) (xy 116.586156 -277.446209) (xy 116.563285 -277.489786)
			(xy 116.53372 -277.52913) (xy 116.498227 -277.563222) (xy 116.457724 -277.591178) (xy 116.413262 -277.612276)
			(xy 116.365991 -277.625968) (xy 116.317136 -277.6319) (xy 116.267961 -277.629919) (xy 116.219742 -277.620075)
			(xy 116.173726 -277.602623) (xy 116.131105 -277.578016) (xy 116.092984 -277.546891) (xy 116.060349 -277.510054)
			(xy 116.034046 -277.468458) (xy 116.014755 -277.423182) (xy 116.002978 -277.375398) (xy 115.999018 -277.326344)
			(xy 115.68049 -277.326344) (xy 115.679978 -277.35179) (xy 115.671814 -277.402024) (xy 115.655698 -277.450298)
			(xy 115.632047 -277.495361) (xy 115.601474 -277.536047) (xy 115.56477 -277.571302) (xy 115.522886 -277.600212)
			(xy 115.476907 -277.622029) (xy 115.428023 -277.636189) (xy 115.377502 -277.642323) (xy 115.32665 -277.640274)
			(xy 115.276786 -277.630094) (xy 115.2292 -277.612047) (xy 115.185126 -277.586601) (xy 115.145704 -277.554414)
			(xy 115.111956 -277.51632) (xy 115.084755 -277.473306) (xy 115.064807 -277.426486) (xy 115.052628 -277.377072)
			(xy 115.048533 -277.326344) (xy 114.740436 -277.326344) (xy 114.739924 -277.35179) (xy 114.73176 -277.402024)
			(xy 114.715644 -277.450298) (xy 114.691993 -277.495361) (xy 114.66142 -277.536047) (xy 114.624716 -277.571302)
			(xy 114.582832 -277.600212) (xy 114.536853 -277.622029) (xy 114.487969 -277.636189) (xy 114.437448 -277.642323)
			(xy 114.386596 -277.640274) (xy 114.336732 -277.630094) (xy 114.289146 -277.612047) (xy 114.245072 -277.586601)
			(xy 114.20565 -277.554414) (xy 114.171902 -277.51632) (xy 114.144701 -277.473306) (xy 114.124753 -277.426486)
			(xy 114.112574 -277.377072) (xy 114.108479 -277.326344) (xy 113.789968 -277.326344) (xy 113.789473 -277.350951)
			(xy 113.781578 -277.399528) (xy 113.765994 -277.446209) (xy 113.743123 -277.489786) (xy 113.713558 -277.52913)
			(xy 113.678065 -277.563222) (xy 113.637562 -277.591178) (xy 113.5931 -277.612276) (xy 113.545829 -277.625968)
			(xy 113.496974 -277.6319) (xy 113.447799 -277.629919) (xy 113.39958 -277.620075) (xy 113.353564 -277.602623)
			(xy 113.310943 -277.578016) (xy 113.272822 -277.546891) (xy 113.240187 -277.510054) (xy 113.213884 -277.468458)
			(xy 113.194593 -277.423182) (xy 113.182816 -277.375398) (xy 113.178856 -277.326344) (xy 112.34747 -277.326344)
			(xy 112.360586 -278.13635) (xy 115.528864 -278.13635) (xy 115.532824 -278.087296) (xy 115.544601 -278.039512)
			(xy 115.563892 -277.994236) (xy 115.590195 -277.95264) (xy 115.62283 -277.915803) (xy 115.660951 -277.884678)
			(xy 115.703572 -277.860071) (xy 115.749588 -277.842619) (xy 115.797807 -277.832775) (xy 115.846982 -277.830794)
			(xy 115.895837 -277.836726) (xy 115.943108 -277.850418) (xy 115.98757 -277.871516) (xy 116.028073 -277.899472)
			(xy 116.063566 -277.933564) (xy 116.093131 -277.972908) (xy 116.116002 -278.016485) (xy 116.131586 -278.063166)
			(xy 116.139481 -278.111743) (xy 116.139976 -278.13635) (xy 116.458487 -278.13635) (xy 116.462582 -278.085622)
			(xy 116.474761 -278.036208) (xy 116.494709 -277.989388) (xy 116.52191 -277.946374) (xy 116.555658 -277.90828)
			(xy 116.59508 -277.876093) (xy 116.639154 -277.850647) (xy 116.68674 -277.8326) (xy 116.736604 -277.82242)
			(xy 116.787456 -277.820371) (xy 116.837977 -277.826505) (xy 116.886861 -277.840665) (xy 116.93284 -277.862482)
			(xy 116.974724 -277.891392) (xy 117.011428 -277.926647) (xy 117.042001 -277.967333) (xy 117.065652 -278.012396)
			(xy 117.081768 -278.06067) (xy 117.089932 -278.110904) (xy 117.090444 -278.13635) (xy 117.398541 -278.13635)
			(xy 117.402636 -278.085622) (xy 117.414815 -278.036208) (xy 117.434763 -277.989388) (xy 117.461964 -277.946374)
			(xy 117.495712 -277.90828) (xy 117.535134 -277.876093) (xy 117.579208 -277.850647) (xy 117.626794 -277.8326)
			(xy 117.676658 -277.82242) (xy 117.72751 -277.820371) (xy 117.778031 -277.826505) (xy 117.826915 -277.840665)
			(xy 117.872894 -277.862482) (xy 117.914778 -277.891392) (xy 117.951482 -277.926647) (xy 117.982055 -277.967333)
			(xy 118.005706 -278.012396) (xy 118.021822 -278.06067) (xy 118.029986 -278.110904) (xy 118.030498 -278.13635)
			(xy 118.349026 -278.13635) (xy 118.352986 -278.087296) (xy 118.364763 -278.039512) (xy 118.384054 -277.994236)
			(xy 118.410357 -277.95264) (xy 118.442992 -277.915803) (xy 118.481113 -277.884678) (xy 118.523734 -277.860071)
			(xy 118.56975 -277.842619) (xy 118.617969 -277.832775) (xy 118.667144 -277.830794) (xy 118.715999 -277.836726)
			(xy 118.76327 -277.850418) (xy 118.807732 -277.871516) (xy 118.848235 -277.899472) (xy 118.883728 -277.933564)
			(xy 118.913293 -277.972908) (xy 118.936164 -278.016485) (xy 118.951748 -278.063166) (xy 118.959643 -278.111743)
			(xy 118.960138 -278.13635) (xy 119.278395 -278.13635) (xy 119.28249 -278.085622) (xy 119.294669 -278.036208)
			(xy 119.314617 -277.989388) (xy 119.341818 -277.946374) (xy 119.375566 -277.90828) (xy 119.414988 -277.876093)
			(xy 119.459062 -277.850647) (xy 119.506648 -277.8326) (xy 119.556512 -277.82242) (xy 119.607364 -277.820371)
			(xy 119.657885 -277.826505) (xy 119.706769 -277.840665) (xy 119.752748 -277.862482) (xy 119.794632 -277.891392)
			(xy 119.831336 -277.926647) (xy 119.861909 -277.967333) (xy 119.88556 -278.012396) (xy 119.901676 -278.06067)
			(xy 119.90984 -278.110904) (xy 119.910352 -278.13635) (xy 120.218449 -278.13635) (xy 120.222544 -278.085622)
			(xy 120.234723 -278.036208) (xy 120.254671 -277.989388) (xy 120.281872 -277.946374) (xy 120.31562 -277.90828)
			(xy 120.355042 -277.876093) (xy 120.399116 -277.850647) (xy 120.446702 -277.8326) (xy 120.496566 -277.82242)
			(xy 120.547418 -277.820371) (xy 120.597939 -277.826505) (xy 120.646823 -277.840665) (xy 120.692802 -277.862482)
			(xy 120.734686 -277.891392) (xy 120.77139 -277.926647) (xy 120.801963 -277.967333) (xy 120.825614 -278.012396)
			(xy 120.84173 -278.06067) (xy 120.849894 -278.110904) (xy 120.850406 -278.13635) (xy 121.168934 -278.13635)
			(xy 121.172894 -278.087296) (xy 121.184671 -278.039512) (xy 121.203962 -277.994236) (xy 121.230265 -277.95264)
			(xy 121.2629 -277.915803) (xy 121.301021 -277.884678) (xy 121.343642 -277.860071) (xy 121.389658 -277.842619)
			(xy 121.437877 -277.832775) (xy 121.487052 -277.830794) (xy 121.535907 -277.836726) (xy 121.583178 -277.850418)
			(xy 121.62764 -277.871516) (xy 121.668143 -277.899472) (xy 121.703636 -277.933564) (xy 121.733201 -277.972908)
			(xy 121.756072 -278.016485) (xy 121.771656 -278.063166) (xy 121.779551 -278.111743) (xy 121.780046 -278.13635)
			(xy 122.098557 -278.13635) (xy 122.102652 -278.085622) (xy 122.114831 -278.036208) (xy 122.134779 -277.989388)
			(xy 122.16198 -277.946374) (xy 122.195728 -277.90828) (xy 122.23515 -277.876093) (xy 122.279224 -277.850647)
			(xy 122.32681 -277.8326) (xy 122.376674 -277.82242) (xy 122.427526 -277.820371) (xy 122.478047 -277.826505)
			(xy 122.526931 -277.840665) (xy 122.57291 -277.862482) (xy 122.614794 -277.891392) (xy 122.651498 -277.926647)
			(xy 122.682071 -277.967333) (xy 122.705722 -278.012396) (xy 122.721838 -278.06067) (xy 122.730002 -278.110904)
			(xy 122.730514 -278.13635) (xy 123.038611 -278.13635) (xy 123.042706 -278.085622) (xy 123.054885 -278.036208)
			(xy 123.074833 -277.989388) (xy 123.102034 -277.946374) (xy 123.135782 -277.90828) (xy 123.175204 -277.876093)
			(xy 123.219278 -277.850647) (xy 123.266864 -277.8326) (xy 123.316728 -277.82242) (xy 123.36758 -277.820371)
			(xy 123.418101 -277.826505) (xy 123.466985 -277.840665) (xy 123.512964 -277.862482) (xy 123.554848 -277.891392)
			(xy 123.591552 -277.926647) (xy 123.622125 -277.967333) (xy 123.645776 -278.012396) (xy 123.661892 -278.06067)
			(xy 123.670056 -278.110904) (xy 123.670568 -278.13635) (xy 123.988842 -278.13635) (xy 123.992802 -278.087296)
			(xy 124.004579 -278.039512) (xy 124.02387 -277.994236) (xy 124.050173 -277.95264) (xy 124.082808 -277.915803)
			(xy 124.120929 -277.884678) (xy 124.16355 -277.860071) (xy 124.209566 -277.842619) (xy 124.257785 -277.832775)
			(xy 124.30696 -277.830794) (xy 124.355815 -277.836726) (xy 124.403086 -277.850418) (xy 124.447548 -277.871516)
			(xy 124.488051 -277.899472) (xy 124.523544 -277.933564) (xy 124.553109 -277.972908) (xy 124.57598 -278.016485)
			(xy 124.591564 -278.063166) (xy 124.599459 -278.111743) (xy 124.599954 -278.13635) (xy 124.918465 -278.13635)
			(xy 124.92256 -278.085622) (xy 124.934739 -278.036208) (xy 124.954687 -277.989388) (xy 124.981888 -277.946374)
			(xy 125.015636 -277.90828) (xy 125.055058 -277.876093) (xy 125.099132 -277.850647) (xy 125.146718 -277.8326)
			(xy 125.196582 -277.82242) (xy 125.247434 -277.820371) (xy 125.297955 -277.826505) (xy 125.346839 -277.840665)
			(xy 125.392818 -277.862482) (xy 125.434702 -277.891392) (xy 125.471406 -277.926647) (xy 125.501979 -277.967333)
			(xy 125.52563 -278.012396) (xy 125.541746 -278.06067) (xy 125.54991 -278.110904) (xy 125.550422 -278.13635)
			(xy 125.858519 -278.13635) (xy 125.862614 -278.085622) (xy 125.874793 -278.036208) (xy 125.894741 -277.989388)
			(xy 125.921942 -277.946374) (xy 125.95569 -277.90828) (xy 125.995112 -277.876093) (xy 126.039186 -277.850647)
			(xy 126.086772 -277.8326) (xy 126.136636 -277.82242) (xy 126.187488 -277.820371) (xy 126.238009 -277.826505)
			(xy 126.286893 -277.840665) (xy 126.332872 -277.862482) (xy 126.374756 -277.891392) (xy 126.41146 -277.926647)
			(xy 126.442033 -277.967333) (xy 126.465684 -278.012396) (xy 126.4818 -278.06067) (xy 126.489964 -278.110904)
			(xy 126.490476 -278.13635) (xy 126.489964 -278.161796) (xy 126.4818 -278.21203) (xy 126.465684 -278.260304)
			(xy 126.442033 -278.305367) (xy 126.41146 -278.346053) (xy 126.374756 -278.381308) (xy 126.332872 -278.410218)
			(xy 126.286893 -278.432035) (xy 126.238009 -278.446195) (xy 126.187488 -278.452329) (xy 126.136636 -278.45028)
			(xy 126.086772 -278.4401) (xy 126.039186 -278.422053) (xy 125.995112 -278.396607) (xy 125.95569 -278.36442)
			(xy 125.921942 -278.326326) (xy 125.894741 -278.283312) (xy 125.874793 -278.236492) (xy 125.862614 -278.187078)
			(xy 125.858519 -278.13635) (xy 125.550422 -278.13635) (xy 125.54991 -278.161796) (xy 125.541746 -278.21203)
			(xy 125.52563 -278.260304) (xy 125.501979 -278.305367) (xy 125.471406 -278.346053) (xy 125.434702 -278.381308)
			(xy 125.392818 -278.410218) (xy 125.346839 -278.432035) (xy 125.297955 -278.446195) (xy 125.247434 -278.452329)
			(xy 125.196582 -278.45028) (xy 125.146718 -278.4401) (xy 125.099132 -278.422053) (xy 125.055058 -278.396607)
			(xy 125.015636 -278.36442) (xy 124.981888 -278.326326) (xy 124.954687 -278.283312) (xy 124.934739 -278.236492)
			(xy 124.92256 -278.187078) (xy 124.918465 -278.13635) (xy 124.599954 -278.13635) (xy 124.599459 -278.160957)
			(xy 124.591564 -278.209534) (xy 124.57598 -278.256215) (xy 124.553109 -278.299792) (xy 124.523544 -278.339136)
			(xy 124.488051 -278.373228) (xy 124.447548 -278.401184) (xy 124.403086 -278.422282) (xy 124.355815 -278.435974)
			(xy 124.30696 -278.441906) (xy 124.257785 -278.439925) (xy 124.209566 -278.430081) (xy 124.16355 -278.412629)
			(xy 124.120929 -278.388022) (xy 124.082808 -278.356897) (xy 124.050173 -278.32006) (xy 124.02387 -278.278464)
			(xy 124.004579 -278.233188) (xy 123.992802 -278.185404) (xy 123.988842 -278.13635) (xy 123.670568 -278.13635)
			(xy 123.670056 -278.161796) (xy 123.661892 -278.21203) (xy 123.645776 -278.260304) (xy 123.622125 -278.305367)
			(xy 123.591552 -278.346053) (xy 123.554848 -278.381308) (xy 123.512964 -278.410218) (xy 123.466985 -278.432035)
			(xy 123.418101 -278.446195) (xy 123.36758 -278.452329) (xy 123.316728 -278.45028) (xy 123.266864 -278.4401)
			(xy 123.219278 -278.422053) (xy 123.175204 -278.396607) (xy 123.135782 -278.36442) (xy 123.102034 -278.326326)
			(xy 123.074833 -278.283312) (xy 123.054885 -278.236492) (xy 123.042706 -278.187078) (xy 123.038611 -278.13635)
			(xy 122.730514 -278.13635) (xy 122.730002 -278.161796) (xy 122.721838 -278.21203) (xy 122.705722 -278.260304)
			(xy 122.682071 -278.305367) (xy 122.651498 -278.346053) (xy 122.614794 -278.381308) (xy 122.57291 -278.410218)
			(xy 122.526931 -278.432035) (xy 122.478047 -278.446195) (xy 122.427526 -278.452329) (xy 122.376674 -278.45028)
			(xy 122.32681 -278.4401) (xy 122.279224 -278.422053) (xy 122.23515 -278.396607) (xy 122.195728 -278.36442)
			(xy 122.16198 -278.326326) (xy 122.134779 -278.283312) (xy 122.114831 -278.236492) (xy 122.102652 -278.187078)
			(xy 122.098557 -278.13635) (xy 121.780046 -278.13635) (xy 121.779551 -278.160957) (xy 121.771656 -278.209534)
			(xy 121.756072 -278.256215) (xy 121.733201 -278.299792) (xy 121.703636 -278.339136) (xy 121.668143 -278.373228)
			(xy 121.62764 -278.401184) (xy 121.583178 -278.422282) (xy 121.535907 -278.435974) (xy 121.487052 -278.441906)
			(xy 121.437877 -278.439925) (xy 121.389658 -278.430081) (xy 121.343642 -278.412629) (xy 121.301021 -278.388022)
			(xy 121.2629 -278.356897) (xy 121.230265 -278.32006) (xy 121.203962 -278.278464) (xy 121.184671 -278.233188)
			(xy 121.172894 -278.185404) (xy 121.168934 -278.13635) (xy 120.850406 -278.13635) (xy 120.849894 -278.161796)
			(xy 120.84173 -278.21203) (xy 120.825614 -278.260304) (xy 120.801963 -278.305367) (xy 120.77139 -278.346053)
			(xy 120.734686 -278.381308) (xy 120.692802 -278.410218) (xy 120.646823 -278.432035) (xy 120.597939 -278.446195)
			(xy 120.547418 -278.452329) (xy 120.496566 -278.45028) (xy 120.446702 -278.4401) (xy 120.399116 -278.422053)
			(xy 120.355042 -278.396607) (xy 120.31562 -278.36442) (xy 120.281872 -278.326326) (xy 120.254671 -278.283312)
			(xy 120.234723 -278.236492) (xy 120.222544 -278.187078) (xy 120.218449 -278.13635) (xy 119.910352 -278.13635)
			(xy 119.90984 -278.161796) (xy 119.901676 -278.21203) (xy 119.88556 -278.260304) (xy 119.861909 -278.305367)
			(xy 119.831336 -278.346053) (xy 119.794632 -278.381308) (xy 119.752748 -278.410218) (xy 119.706769 -278.432035)
			(xy 119.657885 -278.446195) (xy 119.607364 -278.452329) (xy 119.556512 -278.45028) (xy 119.506648 -278.4401)
			(xy 119.459062 -278.422053) (xy 119.414988 -278.396607) (xy 119.375566 -278.36442) (xy 119.341818 -278.326326)
			(xy 119.314617 -278.283312) (xy 119.294669 -278.236492) (xy 119.28249 -278.187078) (xy 119.278395 -278.13635)
			(xy 118.960138 -278.13635) (xy 118.959643 -278.160957) (xy 118.951748 -278.209534) (xy 118.936164 -278.256215)
			(xy 118.913293 -278.299792) (xy 118.883728 -278.339136) (xy 118.848235 -278.373228) (xy 118.807732 -278.401184)
			(xy 118.76327 -278.422282) (xy 118.715999 -278.435974) (xy 118.667144 -278.441906) (xy 118.617969 -278.439925)
			(xy 118.56975 -278.430081) (xy 118.523734 -278.412629) (xy 118.481113 -278.388022) (xy 118.442992 -278.356897)
			(xy 118.410357 -278.32006) (xy 118.384054 -278.278464) (xy 118.364763 -278.233188) (xy 118.352986 -278.185404)
			(xy 118.349026 -278.13635) (xy 118.030498 -278.13635) (xy 118.029986 -278.161796) (xy 118.021822 -278.21203)
			(xy 118.005706 -278.260304) (xy 117.982055 -278.305367) (xy 117.951482 -278.346053) (xy 117.914778 -278.381308)
			(xy 117.872894 -278.410218) (xy 117.826915 -278.432035) (xy 117.778031 -278.446195) (xy 117.72751 -278.452329)
			(xy 117.676658 -278.45028) (xy 117.626794 -278.4401) (xy 117.579208 -278.422053) (xy 117.535134 -278.396607)
			(xy 117.495712 -278.36442) (xy 117.461964 -278.326326) (xy 117.434763 -278.283312) (xy 117.414815 -278.236492)
			(xy 117.402636 -278.187078) (xy 117.398541 -278.13635) (xy 117.090444 -278.13635) (xy 117.089932 -278.161796)
			(xy 117.081768 -278.21203) (xy 117.065652 -278.260304) (xy 117.042001 -278.305367) (xy 117.011428 -278.346053)
			(xy 116.974724 -278.381308) (xy 116.93284 -278.410218) (xy 116.886861 -278.432035) (xy 116.837977 -278.446195)
			(xy 116.787456 -278.452329) (xy 116.736604 -278.45028) (xy 116.68674 -278.4401) (xy 116.639154 -278.422053)
			(xy 116.59508 -278.396607) (xy 116.555658 -278.36442) (xy 116.52191 -278.326326) (xy 116.494709 -278.283312)
			(xy 116.474761 -278.236492) (xy 116.462582 -278.187078) (xy 116.458487 -278.13635) (xy 116.139976 -278.13635)
			(xy 116.139481 -278.160957) (xy 116.131586 -278.209534) (xy 116.116002 -278.256215) (xy 116.093131 -278.299792)
			(xy 116.063566 -278.339136) (xy 116.028073 -278.373228) (xy 115.98757 -278.401184) (xy 115.943108 -278.422282)
			(xy 115.895837 -278.435974) (xy 115.846982 -278.441906) (xy 115.797807 -278.439925) (xy 115.749588 -278.430081)
			(xy 115.703572 -278.412629) (xy 115.660951 -278.388022) (xy 115.62283 -278.356897) (xy 115.590195 -278.32006)
			(xy 115.563892 -278.278464) (xy 115.544601 -278.233188) (xy 115.532824 -278.185404) (xy 115.528864 -278.13635)
			(xy 112.360586 -278.13635) (xy 112.373702 -278.946356) (xy 113.178856 -278.946356) (xy 113.182816 -278.897302)
			(xy 113.194593 -278.849518) (xy 113.213884 -278.804242) (xy 113.240187 -278.762646) (xy 113.272822 -278.725809)
			(xy 113.310943 -278.694684) (xy 113.353564 -278.670077) (xy 113.39958 -278.652625) (xy 113.447799 -278.642781)
			(xy 113.496974 -278.6408) (xy 113.545829 -278.646732) (xy 113.5931 -278.660424) (xy 113.637562 -278.681522)
			(xy 113.678065 -278.709478) (xy 113.713558 -278.74357) (xy 113.743123 -278.782914) (xy 113.765994 -278.826491)
			(xy 113.781578 -278.873172) (xy 113.789473 -278.921749) (xy 113.789968 -278.946356) (xy 114.108479 -278.946356)
			(xy 114.112574 -278.895628) (xy 114.124753 -278.846214) (xy 114.144701 -278.799394) (xy 114.171902 -278.75638)
			(xy 114.20565 -278.718286) (xy 114.245072 -278.686099) (xy 114.289146 -278.660653) (xy 114.336732 -278.642606)
			(xy 114.386596 -278.632426) (xy 114.437448 -278.630377) (xy 114.487969 -278.636511) (xy 114.536853 -278.650671)
			(xy 114.582832 -278.672488) (xy 114.624716 -278.701398) (xy 114.66142 -278.736653) (xy 114.691993 -278.777339)
			(xy 114.715644 -278.822402) (xy 114.73176 -278.870676) (xy 114.739924 -278.92091) (xy 114.740436 -278.946356)
			(xy 115.048533 -278.946356) (xy 115.052628 -278.895628) (xy 115.064807 -278.846214) (xy 115.084755 -278.799394)
			(xy 115.111956 -278.75638) (xy 115.145704 -278.718286) (xy 115.185126 -278.686099) (xy 115.2292 -278.660653)
			(xy 115.276786 -278.642606) (xy 115.32665 -278.632426) (xy 115.377502 -278.630377) (xy 115.428023 -278.636511)
			(xy 115.476907 -278.650671) (xy 115.522886 -278.672488) (xy 115.56477 -278.701398) (xy 115.601474 -278.736653)
			(xy 115.632047 -278.777339) (xy 115.655698 -278.822402) (xy 115.671814 -278.870676) (xy 115.679978 -278.92091)
			(xy 115.68049 -278.946356) (xy 115.999018 -278.946356) (xy 116.002978 -278.897302) (xy 116.014755 -278.849518)
			(xy 116.034046 -278.804242) (xy 116.060349 -278.762646) (xy 116.092984 -278.725809) (xy 116.131105 -278.694684)
			(xy 116.173726 -278.670077) (xy 116.219742 -278.652625) (xy 116.267961 -278.642781) (xy 116.317136 -278.6408)
			(xy 116.365991 -278.646732) (xy 116.413262 -278.660424) (xy 116.457724 -278.681522) (xy 116.498227 -278.709478)
			(xy 116.53372 -278.74357) (xy 116.563285 -278.782914) (xy 116.586156 -278.826491) (xy 116.60174 -278.873172)
			(xy 116.609635 -278.921749) (xy 116.61013 -278.946356) (xy 118.818926 -278.946356) (xy 118.822886 -278.897302)
			(xy 118.834663 -278.849518) (xy 118.853954 -278.804242) (xy 118.880257 -278.762646) (xy 118.912892 -278.725809)
			(xy 118.951013 -278.694684) (xy 118.993634 -278.670077) (xy 119.03965 -278.652625) (xy 119.087869 -278.642781)
			(xy 119.137044 -278.6408) (xy 119.185899 -278.646732) (xy 119.23317 -278.660424) (xy 119.277632 -278.681522)
			(xy 119.318135 -278.709478) (xy 119.353628 -278.74357) (xy 119.383193 -278.782914) (xy 119.406064 -278.826491)
			(xy 119.421648 -278.873172) (xy 119.429543 -278.921749) (xy 119.430038 -278.946356) (xy 121.638834 -278.946356)
			(xy 121.642794 -278.897302) (xy 121.654571 -278.849518) (xy 121.673862 -278.804242) (xy 121.700165 -278.762646)
			(xy 121.7328 -278.725809) (xy 121.770921 -278.694684) (xy 121.813542 -278.670077) (xy 121.859558 -278.652625)
			(xy 121.907777 -278.642781) (xy 121.956952 -278.6408) (xy 122.005807 -278.646732) (xy 122.053078 -278.660424)
			(xy 122.09754 -278.681522) (xy 122.138043 -278.709478) (xy 122.173536 -278.74357) (xy 122.203101 -278.782914)
			(xy 122.225972 -278.826491) (xy 122.241556 -278.873172) (xy 122.249451 -278.921749) (xy 122.249946 -278.946356)
			(xy 124.458996 -278.946356) (xy 124.462956 -278.897302) (xy 124.474733 -278.849518) (xy 124.494024 -278.804242)
			(xy 124.520327 -278.762646) (xy 124.552962 -278.725809) (xy 124.591083 -278.694684) (xy 124.633704 -278.670077)
			(xy 124.67972 -278.652625) (xy 124.727939 -278.642781) (xy 124.777114 -278.6408) (xy 124.825969 -278.646732)
			(xy 124.87324 -278.660424) (xy 124.917702 -278.681522) (xy 124.958205 -278.709478) (xy 124.993698 -278.74357)
			(xy 125.023263 -278.782914) (xy 125.046134 -278.826491) (xy 125.061718 -278.873172) (xy 125.069613 -278.921749)
			(xy 125.070108 -278.946356) (xy 125.069613 -278.970963) (xy 125.061718 -279.01954) (xy 125.046134 -279.066221)
			(xy 125.023263 -279.109798) (xy 124.993698 -279.149142) (xy 124.958205 -279.183234) (xy 124.917702 -279.21119)
			(xy 124.87324 -279.232288) (xy 124.825969 -279.24598) (xy 124.777114 -279.251912) (xy 124.727939 -279.249931)
			(xy 124.67972 -279.240087) (xy 124.633704 -279.222635) (xy 124.591083 -279.198028) (xy 124.552962 -279.166903)
			(xy 124.520327 -279.130066) (xy 124.494024 -279.08847) (xy 124.474733 -279.043194) (xy 124.462956 -278.99541)
			(xy 124.458996 -278.946356) (xy 122.249946 -278.946356) (xy 122.249451 -278.970963) (xy 122.241556 -279.01954)
			(xy 122.225972 -279.066221) (xy 122.203101 -279.109798) (xy 122.173536 -279.149142) (xy 122.138043 -279.183234)
			(xy 122.09754 -279.21119) (xy 122.053078 -279.232288) (xy 122.005807 -279.24598) (xy 121.956952 -279.251912)
			(xy 121.907777 -279.249931) (xy 121.859558 -279.240087) (xy 121.813542 -279.222635) (xy 121.770921 -279.198028)
			(xy 121.7328 -279.166903) (xy 121.700165 -279.130066) (xy 121.673862 -279.08847) (xy 121.654571 -279.043194)
			(xy 121.642794 -278.99541) (xy 121.638834 -278.946356) (xy 119.430038 -278.946356) (xy 119.429543 -278.970963)
			(xy 119.421648 -279.01954) (xy 119.406064 -279.066221) (xy 119.383193 -279.109798) (xy 119.353628 -279.149142)
			(xy 119.318135 -279.183234) (xy 119.277632 -279.21119) (xy 119.23317 -279.232288) (xy 119.185899 -279.24598)
			(xy 119.137044 -279.251912) (xy 119.087869 -279.249931) (xy 119.03965 -279.240087) (xy 118.993634 -279.222635)
			(xy 118.951013 -279.198028) (xy 118.912892 -279.166903) (xy 118.880257 -279.130066) (xy 118.853954 -279.08847)
			(xy 118.834663 -279.043194) (xy 118.822886 -278.99541) (xy 118.818926 -278.946356) (xy 116.61013 -278.946356)
			(xy 116.609635 -278.970963) (xy 116.60174 -279.01954) (xy 116.586156 -279.066221) (xy 116.563285 -279.109798)
			(xy 116.53372 -279.149142) (xy 116.498227 -279.183234) (xy 116.457724 -279.21119) (xy 116.413262 -279.232288)
			(xy 116.365991 -279.24598) (xy 116.317136 -279.251912) (xy 116.267961 -279.249931) (xy 116.219742 -279.240087)
			(xy 116.173726 -279.222635) (xy 116.131105 -279.198028) (xy 116.092984 -279.166903) (xy 116.060349 -279.130066)
			(xy 116.034046 -279.08847) (xy 116.014755 -279.043194) (xy 116.002978 -278.99541) (xy 115.999018 -278.946356)
			(xy 115.68049 -278.946356) (xy 115.679978 -278.971802) (xy 115.671814 -279.022036) (xy 115.655698 -279.07031)
			(xy 115.632047 -279.115373) (xy 115.601474 -279.156059) (xy 115.56477 -279.191314) (xy 115.522886 -279.220224)
			(xy 115.476907 -279.242041) (xy 115.428023 -279.256201) (xy 115.377502 -279.262335) (xy 115.32665 -279.260286)
			(xy 115.276786 -279.250106) (xy 115.2292 -279.232059) (xy 115.185126 -279.206613) (xy 115.145704 -279.174426)
			(xy 115.111956 -279.136332) (xy 115.084755 -279.093318) (xy 115.064807 -279.046498) (xy 115.052628 -278.997084)
			(xy 115.048533 -278.946356) (xy 114.740436 -278.946356) (xy 114.739924 -278.971802) (xy 114.73176 -279.022036)
			(xy 114.715644 -279.07031) (xy 114.691993 -279.115373) (xy 114.66142 -279.156059) (xy 114.624716 -279.191314)
			(xy 114.582832 -279.220224) (xy 114.536853 -279.242041) (xy 114.487969 -279.256201) (xy 114.437448 -279.262335)
			(xy 114.386596 -279.260286) (xy 114.336732 -279.250106) (xy 114.289146 -279.232059) (xy 114.245072 -279.206613)
			(xy 114.20565 -279.174426) (xy 114.171902 -279.136332) (xy 114.144701 -279.093318) (xy 114.124753 -279.046498)
			(xy 114.112574 -278.997084) (xy 114.108479 -278.946356) (xy 113.789968 -278.946356) (xy 113.789473 -278.970963)
			(xy 113.781578 -279.01954) (xy 113.765994 -279.066221) (xy 113.743123 -279.109798) (xy 113.713558 -279.149142)
			(xy 113.678065 -279.183234) (xy 113.637562 -279.21119) (xy 113.5931 -279.232288) (xy 113.545829 -279.24598)
			(xy 113.496974 -279.251912) (xy 113.447799 -279.249931) (xy 113.39958 -279.240087) (xy 113.353564 -279.222635)
			(xy 113.310943 -279.198028) (xy 113.272822 -279.166903) (xy 113.240187 -279.130066) (xy 113.213884 -279.08847)
			(xy 113.194593 -279.043194) (xy 113.182816 -278.99541) (xy 113.178856 -278.946356) (xy 112.373702 -278.946356)
			(xy 112.386818 -279.756362) (xy 113.64901 -279.756362) (xy 113.65297 -279.707308) (xy 113.664747 -279.659524)
			(xy 113.684038 -279.614248) (xy 113.710341 -279.572652) (xy 113.742976 -279.535815) (xy 113.781097 -279.50469)
			(xy 113.823718 -279.480083) (xy 113.869734 -279.462631) (xy 113.917953 -279.452787) (xy 113.967128 -279.450806)
			(xy 114.015983 -279.456738) (xy 114.063254 -279.47043) (xy 114.107716 -279.491528) (xy 114.148219 -279.519484)
			(xy 114.183712 -279.553576) (xy 114.213277 -279.59292) (xy 114.236148 -279.636497) (xy 114.251732 -279.683178)
			(xy 114.259627 -279.731755) (xy 114.260122 -279.756362) (xy 114.58881 -279.756362) (xy 114.59277 -279.707308)
			(xy 114.604547 -279.659524) (xy 114.623838 -279.614248) (xy 114.650141 -279.572652) (xy 114.682776 -279.535815)
			(xy 114.720897 -279.50469) (xy 114.763518 -279.480083) (xy 114.809534 -279.462631) (xy 114.857753 -279.452787)
			(xy 114.906928 -279.450806) (xy 114.955783 -279.456738) (xy 115.003054 -279.47043) (xy 115.047516 -279.491528)
			(xy 115.088019 -279.519484) (xy 115.123512 -279.553576) (xy 115.153077 -279.59292) (xy 115.175948 -279.636497)
			(xy 115.191532 -279.683178) (xy 115.199427 -279.731755) (xy 115.199922 -279.756362) (xy 115.528864 -279.756362)
			(xy 115.532824 -279.707308) (xy 115.544601 -279.659524) (xy 115.563892 -279.614248) (xy 115.590195 -279.572652)
			(xy 115.62283 -279.535815) (xy 115.660951 -279.50469) (xy 115.703572 -279.480083) (xy 115.749588 -279.462631)
			(xy 115.797807 -279.452787) (xy 115.846982 -279.450806) (xy 115.895837 -279.456738) (xy 115.943108 -279.47043)
			(xy 115.98757 -279.491528) (xy 116.028073 -279.519484) (xy 116.063566 -279.553576) (xy 116.093131 -279.59292)
			(xy 116.116002 -279.636497) (xy 116.131586 -279.683178) (xy 116.139481 -279.731755) (xy 116.139976 -279.756362)
			(xy 116.458487 -279.756362) (xy 116.462582 -279.705634) (xy 116.474761 -279.65622) (xy 116.494709 -279.6094)
			(xy 116.52191 -279.566386) (xy 116.555658 -279.528292) (xy 116.59508 -279.496105) (xy 116.639154 -279.470659)
			(xy 116.68674 -279.452612) (xy 116.736604 -279.442432) (xy 116.787456 -279.440383) (xy 116.837977 -279.446517)
			(xy 116.886861 -279.460677) (xy 116.93284 -279.482494) (xy 116.974724 -279.511404) (xy 117.011428 -279.546659)
			(xy 117.042001 -279.587345) (xy 117.065652 -279.632408) (xy 117.081768 -279.680682) (xy 117.089932 -279.730916)
			(xy 117.090444 -279.756362) (xy 117.398541 -279.756362) (xy 117.402636 -279.705634) (xy 117.414815 -279.65622)
			(xy 117.434763 -279.6094) (xy 117.461964 -279.566386) (xy 117.495712 -279.528292) (xy 117.535134 -279.496105)
			(xy 117.579208 -279.470659) (xy 117.626794 -279.452612) (xy 117.676658 -279.442432) (xy 117.72751 -279.440383)
			(xy 117.778031 -279.446517) (xy 117.826915 -279.460677) (xy 117.872894 -279.482494) (xy 117.914778 -279.511404)
			(xy 117.951482 -279.546659) (xy 117.982055 -279.587345) (xy 118.005706 -279.632408) (xy 118.021822 -279.680682)
			(xy 118.029986 -279.730916) (xy 118.030498 -279.756362) (xy 118.349026 -279.756362) (xy 118.352986 -279.707308)
			(xy 118.364763 -279.659524) (xy 118.384054 -279.614248) (xy 118.410357 -279.572652) (xy 118.442992 -279.535815)
			(xy 118.481113 -279.50469) (xy 118.523734 -279.480083) (xy 118.56975 -279.462631) (xy 118.617969 -279.452787)
			(xy 118.667144 -279.450806) (xy 118.715999 -279.456738) (xy 118.76327 -279.47043) (xy 118.807732 -279.491528)
			(xy 118.848235 -279.519484) (xy 118.883728 -279.553576) (xy 118.913293 -279.59292) (xy 118.936164 -279.636497)
			(xy 118.951748 -279.683178) (xy 118.959643 -279.731755) (xy 118.960138 -279.756362) (xy 119.288826 -279.756362)
			(xy 119.292786 -279.707308) (xy 119.304563 -279.659524) (xy 119.323854 -279.614248) (xy 119.350157 -279.572652)
			(xy 119.382792 -279.535815) (xy 119.420913 -279.50469) (xy 119.463534 -279.480083) (xy 119.50955 -279.462631)
			(xy 119.557769 -279.452787) (xy 119.606944 -279.450806) (xy 119.655799 -279.456738) (xy 119.70307 -279.47043)
			(xy 119.747532 -279.491528) (xy 119.788035 -279.519484) (xy 119.823528 -279.553576) (xy 119.853093 -279.59292)
			(xy 119.875964 -279.636497) (xy 119.891548 -279.683178) (xy 119.899443 -279.731755) (xy 119.899938 -279.756362)
			(xy 120.22888 -279.756362) (xy 120.23284 -279.707308) (xy 120.244617 -279.659524) (xy 120.263908 -279.614248)
			(xy 120.290211 -279.572652) (xy 120.322846 -279.535815) (xy 120.360967 -279.50469) (xy 120.403588 -279.480083)
			(xy 120.449604 -279.462631) (xy 120.497823 -279.452787) (xy 120.546998 -279.450806) (xy 120.595853 -279.456738)
			(xy 120.643124 -279.47043) (xy 120.687586 -279.491528) (xy 120.728089 -279.519484) (xy 120.763582 -279.553576)
			(xy 120.793147 -279.59292) (xy 120.816018 -279.636497) (xy 120.831602 -279.683178) (xy 120.839497 -279.731755)
			(xy 120.839992 -279.756362) (xy 121.168934 -279.756362) (xy 121.172894 -279.707308) (xy 121.184671 -279.659524)
			(xy 121.203962 -279.614248) (xy 121.230265 -279.572652) (xy 121.2629 -279.535815) (xy 121.301021 -279.50469)
			(xy 121.343642 -279.480083) (xy 121.389658 -279.462631) (xy 121.437877 -279.452787) (xy 121.487052 -279.450806)
			(xy 121.535907 -279.456738) (xy 121.583178 -279.47043) (xy 121.62764 -279.491528) (xy 121.668143 -279.519484)
			(xy 121.703636 -279.553576) (xy 121.733201 -279.59292) (xy 121.756072 -279.636497) (xy 121.771656 -279.683178)
			(xy 121.779551 -279.731755) (xy 121.780046 -279.756362) (xy 122.108988 -279.756362) (xy 122.112948 -279.707308)
			(xy 122.124725 -279.659524) (xy 122.144016 -279.614248) (xy 122.170319 -279.572652) (xy 122.202954 -279.535815)
			(xy 122.241075 -279.50469) (xy 122.283696 -279.480083) (xy 122.329712 -279.462631) (xy 122.377931 -279.452787)
			(xy 122.427106 -279.450806) (xy 122.475961 -279.456738) (xy 122.523232 -279.47043) (xy 122.567694 -279.491528)
			(xy 122.608197 -279.519484) (xy 122.64369 -279.553576) (xy 122.673255 -279.59292) (xy 122.696126 -279.636497)
			(xy 122.71171 -279.683178) (xy 122.719605 -279.731755) (xy 122.7201 -279.756362) (xy 123.049042 -279.756362)
			(xy 123.053002 -279.707308) (xy 123.064779 -279.659524) (xy 123.08407 -279.614248) (xy 123.110373 -279.572652)
			(xy 123.143008 -279.535815) (xy 123.181129 -279.50469) (xy 123.22375 -279.480083) (xy 123.269766 -279.462631)
			(xy 123.317985 -279.452787) (xy 123.36716 -279.450806) (xy 123.416015 -279.456738) (xy 123.463286 -279.47043)
			(xy 123.507748 -279.491528) (xy 123.548251 -279.519484) (xy 123.583744 -279.553576) (xy 123.613309 -279.59292)
			(xy 123.63618 -279.636497) (xy 123.651764 -279.683178) (xy 123.659659 -279.731755) (xy 123.660154 -279.756362)
			(xy 123.988842 -279.756362) (xy 123.992802 -279.707308) (xy 124.004579 -279.659524) (xy 124.02387 -279.614248)
			(xy 124.050173 -279.572652) (xy 124.082808 -279.535815) (xy 124.120929 -279.50469) (xy 124.16355 -279.480083)
			(xy 124.209566 -279.462631) (xy 124.257785 -279.452787) (xy 124.30696 -279.450806) (xy 124.355815 -279.456738)
			(xy 124.403086 -279.47043) (xy 124.447548 -279.491528) (xy 124.488051 -279.519484) (xy 124.523544 -279.553576)
			(xy 124.553109 -279.59292) (xy 124.57598 -279.636497) (xy 124.591564 -279.683178) (xy 124.599459 -279.731755)
			(xy 124.599954 -279.756362) (xy 124.928896 -279.756362) (xy 124.932856 -279.707308) (xy 124.944633 -279.659524)
			(xy 124.963924 -279.614248) (xy 124.990227 -279.572652) (xy 125.022862 -279.535815) (xy 125.060983 -279.50469)
			(xy 125.103604 -279.480083) (xy 125.14962 -279.462631) (xy 125.197839 -279.452787) (xy 125.247014 -279.450806)
			(xy 125.295869 -279.456738) (xy 125.34314 -279.47043) (xy 125.387602 -279.491528) (xy 125.428105 -279.519484)
			(xy 125.463598 -279.553576) (xy 125.493163 -279.59292) (xy 125.516034 -279.636497) (xy 125.531618 -279.683178)
			(xy 125.539513 -279.731755) (xy 125.540008 -279.756362) (xy 125.86895 -279.756362) (xy 125.87291 -279.707308)
			(xy 125.884687 -279.659524) (xy 125.903978 -279.614248) (xy 125.930281 -279.572652) (xy 125.962916 -279.535815)
			(xy 126.001037 -279.50469) (xy 126.043658 -279.480083) (xy 126.089674 -279.462631) (xy 126.137893 -279.452787)
			(xy 126.187068 -279.450806) (xy 126.235923 -279.456738) (xy 126.283194 -279.47043) (xy 126.327656 -279.491528)
			(xy 126.368159 -279.519484) (xy 126.403652 -279.553576) (xy 126.433217 -279.59292) (xy 126.456088 -279.636497)
			(xy 126.471672 -279.683178) (xy 126.479567 -279.731755) (xy 126.480062 -279.756362) (xy 126.479567 -279.780969)
			(xy 126.471672 -279.829546) (xy 126.456088 -279.876227) (xy 126.433217 -279.919804) (xy 126.403652 -279.959148)
			(xy 126.368159 -279.99324) (xy 126.327656 -280.021196) (xy 126.283194 -280.042294) (xy 126.235923 -280.055986)
			(xy 126.187068 -280.061918) (xy 126.137893 -280.059937) (xy 126.089674 -280.050093) (xy 126.043658 -280.032641)
			(xy 126.001037 -280.008034) (xy 125.962916 -279.976909) (xy 125.930281 -279.940072) (xy 125.903978 -279.898476)
			(xy 125.884687 -279.8532) (xy 125.87291 -279.805416) (xy 125.86895 -279.756362) (xy 125.540008 -279.756362)
			(xy 125.539513 -279.780969) (xy 125.531618 -279.829546) (xy 125.516034 -279.876227) (xy 125.493163 -279.919804)
			(xy 125.463598 -279.959148) (xy 125.428105 -279.99324) (xy 125.387602 -280.021196) (xy 125.34314 -280.042294)
			(xy 125.295869 -280.055986) (xy 125.247014 -280.061918) (xy 125.197839 -280.059937) (xy 125.14962 -280.050093)
			(xy 125.103604 -280.032641) (xy 125.060983 -280.008034) (xy 125.022862 -279.976909) (xy 124.990227 -279.940072)
			(xy 124.963924 -279.898476) (xy 124.944633 -279.8532) (xy 124.932856 -279.805416) (xy 124.928896 -279.756362)
			(xy 124.599954 -279.756362) (xy 124.599459 -279.780969) (xy 124.591564 -279.829546) (xy 124.57598 -279.876227)
			(xy 124.553109 -279.919804) (xy 124.523544 -279.959148) (xy 124.488051 -279.99324) (xy 124.447548 -280.021196)
			(xy 124.403086 -280.042294) (xy 124.355815 -280.055986) (xy 124.30696 -280.061918) (xy 124.257785 -280.059937)
			(xy 124.209566 -280.050093) (xy 124.16355 -280.032641) (xy 124.120929 -280.008034) (xy 124.082808 -279.976909)
			(xy 124.050173 -279.940072) (xy 124.02387 -279.898476) (xy 124.004579 -279.8532) (xy 123.992802 -279.805416)
			(xy 123.988842 -279.756362) (xy 123.660154 -279.756362) (xy 123.659659 -279.780969) (xy 123.651764 -279.829546)
			(xy 123.63618 -279.876227) (xy 123.613309 -279.919804) (xy 123.583744 -279.959148) (xy 123.548251 -279.99324)
			(xy 123.507748 -280.021196) (xy 123.463286 -280.042294) (xy 123.416015 -280.055986) (xy 123.36716 -280.061918)
			(xy 123.317985 -280.059937) (xy 123.269766 -280.050093) (xy 123.22375 -280.032641) (xy 123.181129 -280.008034)
			(xy 123.143008 -279.976909) (xy 123.110373 -279.940072) (xy 123.08407 -279.898476) (xy 123.064779 -279.8532)
			(xy 123.053002 -279.805416) (xy 123.049042 -279.756362) (xy 122.7201 -279.756362) (xy 122.719605 -279.780969)
			(xy 122.71171 -279.829546) (xy 122.696126 -279.876227) (xy 122.673255 -279.919804) (xy 122.64369 -279.959148)
			(xy 122.608197 -279.99324) (xy 122.567694 -280.021196) (xy 122.523232 -280.042294) (xy 122.475961 -280.055986)
			(xy 122.427106 -280.061918) (xy 122.377931 -280.059937) (xy 122.329712 -280.050093) (xy 122.283696 -280.032641)
			(xy 122.241075 -280.008034) (xy 122.202954 -279.976909) (xy 122.170319 -279.940072) (xy 122.144016 -279.898476)
			(xy 122.124725 -279.8532) (xy 122.112948 -279.805416) (xy 122.108988 -279.756362) (xy 121.780046 -279.756362)
			(xy 121.779551 -279.780969) (xy 121.771656 -279.829546) (xy 121.756072 -279.876227) (xy 121.733201 -279.919804)
			(xy 121.703636 -279.959148) (xy 121.668143 -279.99324) (xy 121.62764 -280.021196) (xy 121.583178 -280.042294)
			(xy 121.535907 -280.055986) (xy 121.487052 -280.061918) (xy 121.437877 -280.059937) (xy 121.389658 -280.050093)
			(xy 121.343642 -280.032641) (xy 121.301021 -280.008034) (xy 121.2629 -279.976909) (xy 121.230265 -279.940072)
			(xy 121.203962 -279.898476) (xy 121.184671 -279.8532) (xy 121.172894 -279.805416) (xy 121.168934 -279.756362)
			(xy 120.839992 -279.756362) (xy 120.839497 -279.780969) (xy 120.831602 -279.829546) (xy 120.816018 -279.876227)
			(xy 120.793147 -279.919804) (xy 120.763582 -279.959148) (xy 120.728089 -279.99324) (xy 120.687586 -280.021196)
			(xy 120.643124 -280.042294) (xy 120.595853 -280.055986) (xy 120.546998 -280.061918) (xy 120.497823 -280.059937)
			(xy 120.449604 -280.050093) (xy 120.403588 -280.032641) (xy 120.360967 -280.008034) (xy 120.322846 -279.976909)
			(xy 120.290211 -279.940072) (xy 120.263908 -279.898476) (xy 120.244617 -279.8532) (xy 120.23284 -279.805416)
			(xy 120.22888 -279.756362) (xy 119.899938 -279.756362) (xy 119.899443 -279.780969) (xy 119.891548 -279.829546)
			(xy 119.875964 -279.876227) (xy 119.853093 -279.919804) (xy 119.823528 -279.959148) (xy 119.788035 -279.99324)
			(xy 119.747532 -280.021196) (xy 119.70307 -280.042294) (xy 119.655799 -280.055986) (xy 119.606944 -280.061918)
			(xy 119.557769 -280.059937) (xy 119.50955 -280.050093) (xy 119.463534 -280.032641) (xy 119.420913 -280.008034)
			(xy 119.382792 -279.976909) (xy 119.350157 -279.940072) (xy 119.323854 -279.898476) (xy 119.304563 -279.8532)
			(xy 119.292786 -279.805416) (xy 119.288826 -279.756362) (xy 118.960138 -279.756362) (xy 118.959643 -279.780969)
			(xy 118.951748 -279.829546) (xy 118.936164 -279.876227) (xy 118.913293 -279.919804) (xy 118.883728 -279.959148)
			(xy 118.848235 -279.99324) (xy 118.807732 -280.021196) (xy 118.76327 -280.042294) (xy 118.715999 -280.055986)
			(xy 118.667144 -280.061918) (xy 118.617969 -280.059937) (xy 118.56975 -280.050093) (xy 118.523734 -280.032641)
			(xy 118.481113 -280.008034) (xy 118.442992 -279.976909) (xy 118.410357 -279.940072) (xy 118.384054 -279.898476)
			(xy 118.364763 -279.8532) (xy 118.352986 -279.805416) (xy 118.349026 -279.756362) (xy 118.030498 -279.756362)
			(xy 118.029986 -279.781808) (xy 118.021822 -279.832042) (xy 118.005706 -279.880316) (xy 117.982055 -279.925379)
			(xy 117.951482 -279.966065) (xy 117.914778 -280.00132) (xy 117.872894 -280.03023) (xy 117.826915 -280.052047)
			(xy 117.778031 -280.066207) (xy 117.72751 -280.072341) (xy 117.676658 -280.070292) (xy 117.626794 -280.060112)
			(xy 117.579208 -280.042065) (xy 117.535134 -280.016619) (xy 117.495712 -279.984432) (xy 117.461964 -279.946338)
			(xy 117.434763 -279.903324) (xy 117.414815 -279.856504) (xy 117.402636 -279.80709) (xy 117.398541 -279.756362)
			(xy 117.090444 -279.756362) (xy 117.089932 -279.781808) (xy 117.081768 -279.832042) (xy 117.065652 -279.880316)
			(xy 117.042001 -279.925379) (xy 117.011428 -279.966065) (xy 116.974724 -280.00132) (xy 116.93284 -280.03023)
			(xy 116.886861 -280.052047) (xy 116.837977 -280.066207) (xy 116.787456 -280.072341) (xy 116.736604 -280.070292)
			(xy 116.68674 -280.060112) (xy 116.639154 -280.042065) (xy 116.59508 -280.016619) (xy 116.555658 -279.984432)
			(xy 116.52191 -279.946338) (xy 116.494709 -279.903324) (xy 116.474761 -279.856504) (xy 116.462582 -279.80709)
			(xy 116.458487 -279.756362) (xy 116.139976 -279.756362) (xy 116.139481 -279.780969) (xy 116.131586 -279.829546)
			(xy 116.116002 -279.876227) (xy 116.093131 -279.919804) (xy 116.063566 -279.959148) (xy 116.028073 -279.99324)
			(xy 115.98757 -280.021196) (xy 115.943108 -280.042294) (xy 115.895837 -280.055986) (xy 115.846982 -280.061918)
			(xy 115.797807 -280.059937) (xy 115.749588 -280.050093) (xy 115.703572 -280.032641) (xy 115.660951 -280.008034)
			(xy 115.62283 -279.976909) (xy 115.590195 -279.940072) (xy 115.563892 -279.898476) (xy 115.544601 -279.8532)
			(xy 115.532824 -279.805416) (xy 115.528864 -279.756362) (xy 115.199922 -279.756362) (xy 115.199427 -279.780969)
			(xy 115.191532 -279.829546) (xy 115.175948 -279.876227) (xy 115.153077 -279.919804) (xy 115.123512 -279.959148)
			(xy 115.088019 -279.99324) (xy 115.047516 -280.021196) (xy 115.003054 -280.042294) (xy 114.955783 -280.055986)
			(xy 114.906928 -280.061918) (xy 114.857753 -280.059937) (xy 114.809534 -280.050093) (xy 114.763518 -280.032641)
			(xy 114.720897 -280.008034) (xy 114.682776 -279.976909) (xy 114.650141 -279.940072) (xy 114.623838 -279.898476)
			(xy 114.604547 -279.8532) (xy 114.59277 -279.805416) (xy 114.58881 -279.756362) (xy 114.260122 -279.756362)
			(xy 114.259627 -279.780969) (xy 114.251732 -279.829546) (xy 114.236148 -279.876227) (xy 114.213277 -279.919804)
			(xy 114.183712 -279.959148) (xy 114.148219 -279.99324) (xy 114.107716 -280.021196) (xy 114.063254 -280.042294)
			(xy 114.015983 -280.055986) (xy 113.967128 -280.061918) (xy 113.917953 -280.059937) (xy 113.869734 -280.050093)
			(xy 113.823718 -280.032641) (xy 113.781097 -280.008034) (xy 113.742976 -279.976909) (xy 113.710341 -279.940072)
			(xy 113.684038 -279.898476) (xy 113.664747 -279.8532) (xy 113.65297 -279.805416) (xy 113.64901 -279.756362)
			(xy 112.386818 -279.756362) (xy 112.399934 -280.566368) (xy 113.178856 -280.566368) (xy 113.182816 -280.517314)
			(xy 113.194593 -280.46953) (xy 113.213884 -280.424254) (xy 113.240187 -280.382658) (xy 113.272822 -280.345821)
			(xy 113.310943 -280.314696) (xy 113.353564 -280.290089) (xy 113.39958 -280.272637) (xy 113.447799 -280.262793)
			(xy 113.496974 -280.260812) (xy 113.545829 -280.266744) (xy 113.5931 -280.280436) (xy 113.637562 -280.301534)
			(xy 113.678065 -280.32949) (xy 113.713558 -280.363582) (xy 113.743123 -280.402926) (xy 113.765994 -280.446503)
			(xy 113.781578 -280.493184) (xy 113.789473 -280.541761) (xy 113.789968 -280.566368) (xy 115.999018 -280.566368)
			(xy 116.002978 -280.517314) (xy 116.014755 -280.46953) (xy 116.034046 -280.424254) (xy 116.060349 -280.382658)
			(xy 116.092984 -280.345821) (xy 116.131105 -280.314696) (xy 116.173726 -280.290089) (xy 116.219742 -280.272637)
			(xy 116.267961 -280.262793) (xy 116.317136 -280.260812) (xy 116.365991 -280.266744) (xy 116.413262 -280.280436)
			(xy 116.457724 -280.301534) (xy 116.498227 -280.32949) (xy 116.53372 -280.363582) (xy 116.563285 -280.402926)
			(xy 116.586156 -280.446503) (xy 116.60174 -280.493184) (xy 116.609635 -280.541761) (xy 116.61013 -280.566368)
			(xy 116.938818 -280.566368) (xy 116.942778 -280.517314) (xy 116.954555 -280.46953) (xy 116.973846 -280.424254)
			(xy 117.000149 -280.382658) (xy 117.032784 -280.345821) (xy 117.070905 -280.314696) (xy 117.113526 -280.290089)
			(xy 117.159542 -280.272637) (xy 117.207761 -280.262793) (xy 117.256936 -280.260812) (xy 117.305791 -280.266744)
			(xy 117.353062 -280.280436) (xy 117.397524 -280.301534) (xy 117.438027 -280.32949) (xy 117.47352 -280.363582)
			(xy 117.503085 -280.402926) (xy 117.525956 -280.446503) (xy 117.54154 -280.493184) (xy 117.549435 -280.541761)
			(xy 117.54993 -280.566368) (xy 117.878872 -280.566368) (xy 117.882832 -280.517314) (xy 117.894609 -280.46953)
			(xy 117.9139 -280.424254) (xy 117.940203 -280.382658) (xy 117.972838 -280.345821) (xy 118.010959 -280.314696)
			(xy 118.05358 -280.290089) (xy 118.099596 -280.272637) (xy 118.147815 -280.262793) (xy 118.19699 -280.260812)
			(xy 118.245845 -280.266744) (xy 118.293116 -280.280436) (xy 118.337578 -280.301534) (xy 118.378081 -280.32949)
			(xy 118.413574 -280.363582) (xy 118.443139 -280.402926) (xy 118.46601 -280.446503) (xy 118.481594 -280.493184)
			(xy 118.489489 -280.541761) (xy 118.489984 -280.566368) (xy 118.818926 -280.566368) (xy 118.822886 -280.517314)
			(xy 118.834663 -280.46953) (xy 118.853954 -280.424254) (xy 118.880257 -280.382658) (xy 118.912892 -280.345821)
			(xy 118.951013 -280.314696) (xy 118.993634 -280.290089) (xy 119.03965 -280.272637) (xy 119.087869 -280.262793)
			(xy 119.137044 -280.260812) (xy 119.185899 -280.266744) (xy 119.23317 -280.280436) (xy 119.277632 -280.301534)
			(xy 119.318135 -280.32949) (xy 119.353628 -280.363582) (xy 119.383193 -280.402926) (xy 119.406064 -280.446503)
			(xy 119.421648 -280.493184) (xy 119.429543 -280.541761) (xy 119.430038 -280.566368) (xy 119.75898 -280.566368)
			(xy 119.76294 -280.517314) (xy 119.774717 -280.46953) (xy 119.794008 -280.424254) (xy 119.820311 -280.382658)
			(xy 119.852946 -280.345821) (xy 119.891067 -280.314696) (xy 119.933688 -280.290089) (xy 119.979704 -280.272637)
			(xy 120.027923 -280.262793) (xy 120.077098 -280.260812) (xy 120.125953 -280.266744) (xy 120.173224 -280.280436)
			(xy 120.217686 -280.301534) (xy 120.258189 -280.32949) (xy 120.293682 -280.363582) (xy 120.323247 -280.402926)
			(xy 120.346118 -280.446503) (xy 120.361702 -280.493184) (xy 120.369597 -280.541761) (xy 120.370092 -280.566368)
			(xy 120.699034 -280.566368) (xy 120.702994 -280.517314) (xy 120.714771 -280.46953) (xy 120.734062 -280.424254)
			(xy 120.760365 -280.382658) (xy 120.793 -280.345821) (xy 120.831121 -280.314696) (xy 120.873742 -280.290089)
			(xy 120.919758 -280.272637) (xy 120.967977 -280.262793) (xy 121.017152 -280.260812) (xy 121.066007 -280.266744)
			(xy 121.113278 -280.280436) (xy 121.15774 -280.301534) (xy 121.198243 -280.32949) (xy 121.233736 -280.363582)
			(xy 121.263301 -280.402926) (xy 121.286172 -280.446503) (xy 121.301756 -280.493184) (xy 121.309651 -280.541761)
			(xy 121.310146 -280.566368) (xy 121.638834 -280.566368) (xy 121.642794 -280.517314) (xy 121.654571 -280.46953)
			(xy 121.673862 -280.424254) (xy 121.700165 -280.382658) (xy 121.7328 -280.345821) (xy 121.770921 -280.314696)
			(xy 121.813542 -280.290089) (xy 121.859558 -280.272637) (xy 121.907777 -280.262793) (xy 121.956952 -280.260812)
			(xy 122.005807 -280.266744) (xy 122.053078 -280.280436) (xy 122.09754 -280.301534) (xy 122.138043 -280.32949)
			(xy 122.173536 -280.363582) (xy 122.203101 -280.402926) (xy 122.225972 -280.446503) (xy 122.241556 -280.493184)
			(xy 122.249451 -280.541761) (xy 122.249946 -280.566368) (xy 122.578888 -280.566368) (xy 122.582848 -280.517314)
			(xy 122.594625 -280.46953) (xy 122.613916 -280.424254) (xy 122.640219 -280.382658) (xy 122.672854 -280.345821)
			(xy 122.710975 -280.314696) (xy 122.753596 -280.290089) (xy 122.799612 -280.272637) (xy 122.847831 -280.262793)
			(xy 122.897006 -280.260812) (xy 122.945861 -280.266744) (xy 122.993132 -280.280436) (xy 123.037594 -280.301534)
			(xy 123.078097 -280.32949) (xy 123.11359 -280.363582) (xy 123.143155 -280.402926) (xy 123.166026 -280.446503)
			(xy 123.18161 -280.493184) (xy 123.189505 -280.541761) (xy 123.19 -280.566368) (xy 123.518942 -280.566368)
			(xy 123.522902 -280.517314) (xy 123.534679 -280.46953) (xy 123.55397 -280.424254) (xy 123.580273 -280.382658)
			(xy 123.612908 -280.345821) (xy 123.651029 -280.314696) (xy 123.69365 -280.290089) (xy 123.739666 -280.272637)
			(xy 123.787885 -280.262793) (xy 123.83706 -280.260812) (xy 123.885915 -280.266744) (xy 123.933186 -280.280436)
			(xy 123.977648 -280.301534) (xy 124.018151 -280.32949) (xy 124.053644 -280.363582) (xy 124.083209 -280.402926)
			(xy 124.10608 -280.446503) (xy 124.121664 -280.493184) (xy 124.129559 -280.541761) (xy 124.130054 -280.566368)
			(xy 124.458996 -280.566368) (xy 124.462956 -280.517314) (xy 124.474733 -280.46953) (xy 124.494024 -280.424254)
			(xy 124.520327 -280.382658) (xy 124.552962 -280.345821) (xy 124.591083 -280.314696) (xy 124.633704 -280.290089)
			(xy 124.67972 -280.272637) (xy 124.727939 -280.262793) (xy 124.777114 -280.260812) (xy 124.825969 -280.266744)
			(xy 124.87324 -280.280436) (xy 124.917702 -280.301534) (xy 124.958205 -280.32949) (xy 124.993698 -280.363582)
			(xy 125.023263 -280.402926) (xy 125.046134 -280.446503) (xy 125.061718 -280.493184) (xy 125.069613 -280.541761)
			(xy 125.070108 -280.566368) (xy 125.39905 -280.566368) (xy 125.40301 -280.517314) (xy 125.414787 -280.46953)
			(xy 125.434078 -280.424254) (xy 125.460381 -280.382658) (xy 125.493016 -280.345821) (xy 125.531137 -280.314696)
			(xy 125.573758 -280.290089) (xy 125.619774 -280.272637) (xy 125.667993 -280.262793) (xy 125.717168 -280.260812)
			(xy 125.766023 -280.266744) (xy 125.813294 -280.280436) (xy 125.857756 -280.301534) (xy 125.898259 -280.32949)
			(xy 125.933752 -280.363582) (xy 125.963317 -280.402926) (xy 125.986188 -280.446503) (xy 126.001772 -280.493184)
			(xy 126.009667 -280.541761) (xy 126.010162 -280.566368) (xy 126.009667 -280.590975) (xy 126.001772 -280.639552)
			(xy 125.986188 -280.686233) (xy 125.963317 -280.72981) (xy 125.933752 -280.769154) (xy 125.898259 -280.803246)
			(xy 125.857756 -280.831202) (xy 125.813294 -280.8523) (xy 125.766023 -280.865992) (xy 125.717168 -280.871924)
			(xy 125.667993 -280.869943) (xy 125.619774 -280.860099) (xy 125.573758 -280.842647) (xy 125.531137 -280.81804)
			(xy 125.493016 -280.786915) (xy 125.460381 -280.750078) (xy 125.434078 -280.708482) (xy 125.414787 -280.663206)
			(xy 125.40301 -280.615422) (xy 125.39905 -280.566368) (xy 125.070108 -280.566368) (xy 125.069613 -280.590975)
			(xy 125.061718 -280.639552) (xy 125.046134 -280.686233) (xy 125.023263 -280.72981) (xy 124.993698 -280.769154)
			(xy 124.958205 -280.803246) (xy 124.917702 -280.831202) (xy 124.87324 -280.8523) (xy 124.825969 -280.865992)
			(xy 124.777114 -280.871924) (xy 124.727939 -280.869943) (xy 124.67972 -280.860099) (xy 124.633704 -280.842647)
			(xy 124.591083 -280.81804) (xy 124.552962 -280.786915) (xy 124.520327 -280.750078) (xy 124.494024 -280.708482)
			(xy 124.474733 -280.663206) (xy 124.462956 -280.615422) (xy 124.458996 -280.566368) (xy 124.130054 -280.566368)
			(xy 124.129559 -280.590975) (xy 124.121664 -280.639552) (xy 124.10608 -280.686233) (xy 124.083209 -280.72981)
			(xy 124.053644 -280.769154) (xy 124.018151 -280.803246) (xy 123.977648 -280.831202) (xy 123.933186 -280.8523)
			(xy 123.885915 -280.865992) (xy 123.83706 -280.871924) (xy 123.787885 -280.869943) (xy 123.739666 -280.860099)
			(xy 123.69365 -280.842647) (xy 123.651029 -280.81804) (xy 123.612908 -280.786915) (xy 123.580273 -280.750078)
			(xy 123.55397 -280.708482) (xy 123.534679 -280.663206) (xy 123.522902 -280.615422) (xy 123.518942 -280.566368)
			(xy 123.19 -280.566368) (xy 123.189505 -280.590975) (xy 123.18161 -280.639552) (xy 123.166026 -280.686233)
			(xy 123.143155 -280.72981) (xy 123.11359 -280.769154) (xy 123.078097 -280.803246) (xy 123.037594 -280.831202)
			(xy 122.993132 -280.8523) (xy 122.945861 -280.865992) (xy 122.897006 -280.871924) (xy 122.847831 -280.869943)
			(xy 122.799612 -280.860099) (xy 122.753596 -280.842647) (xy 122.710975 -280.81804) (xy 122.672854 -280.786915)
			(xy 122.640219 -280.750078) (xy 122.613916 -280.708482) (xy 122.594625 -280.663206) (xy 122.582848 -280.615422)
			(xy 122.578888 -280.566368) (xy 122.249946 -280.566368) (xy 122.249451 -280.590975) (xy 122.241556 -280.639552)
			(xy 122.225972 -280.686233) (xy 122.203101 -280.72981) (xy 122.173536 -280.769154) (xy 122.138043 -280.803246)
			(xy 122.09754 -280.831202) (xy 122.053078 -280.8523) (xy 122.005807 -280.865992) (xy 121.956952 -280.871924)
			(xy 121.907777 -280.869943) (xy 121.859558 -280.860099) (xy 121.813542 -280.842647) (xy 121.770921 -280.81804)
			(xy 121.7328 -280.786915) (xy 121.700165 -280.750078) (xy 121.673862 -280.708482) (xy 121.654571 -280.663206)
			(xy 121.642794 -280.615422) (xy 121.638834 -280.566368) (xy 121.310146 -280.566368) (xy 121.309651 -280.590975)
			(xy 121.301756 -280.639552) (xy 121.286172 -280.686233) (xy 121.263301 -280.72981) (xy 121.233736 -280.769154)
			(xy 121.198243 -280.803246) (xy 121.15774 -280.831202) (xy 121.113278 -280.8523) (xy 121.066007 -280.865992)
			(xy 121.017152 -280.871924) (xy 120.967977 -280.869943) (xy 120.919758 -280.860099) (xy 120.873742 -280.842647)
			(xy 120.831121 -280.81804) (xy 120.793 -280.786915) (xy 120.760365 -280.750078) (xy 120.734062 -280.708482)
			(xy 120.714771 -280.663206) (xy 120.702994 -280.615422) (xy 120.699034 -280.566368) (xy 120.370092 -280.566368)
			(xy 120.369597 -280.590975) (xy 120.361702 -280.639552) (xy 120.346118 -280.686233) (xy 120.323247 -280.72981)
			(xy 120.293682 -280.769154) (xy 120.258189 -280.803246) (xy 120.217686 -280.831202) (xy 120.173224 -280.8523)
			(xy 120.125953 -280.865992) (xy 120.077098 -280.871924) (xy 120.027923 -280.869943) (xy 119.979704 -280.860099)
			(xy 119.933688 -280.842647) (xy 119.891067 -280.81804) (xy 119.852946 -280.786915) (xy 119.820311 -280.750078)
			(xy 119.794008 -280.708482) (xy 119.774717 -280.663206) (xy 119.76294 -280.615422) (xy 119.75898 -280.566368)
			(xy 119.430038 -280.566368) (xy 119.429543 -280.590975) (xy 119.421648 -280.639552) (xy 119.406064 -280.686233)
			(xy 119.383193 -280.72981) (xy 119.353628 -280.769154) (xy 119.318135 -280.803246) (xy 119.277632 -280.831202)
			(xy 119.23317 -280.8523) (xy 119.185899 -280.865992) (xy 119.137044 -280.871924) (xy 119.087869 -280.869943)
			(xy 119.03965 -280.860099) (xy 118.993634 -280.842647) (xy 118.951013 -280.81804) (xy 118.912892 -280.786915)
			(xy 118.880257 -280.750078) (xy 118.853954 -280.708482) (xy 118.834663 -280.663206) (xy 118.822886 -280.615422)
			(xy 118.818926 -280.566368) (xy 118.489984 -280.566368) (xy 118.489489 -280.590975) (xy 118.481594 -280.639552)
			(xy 118.46601 -280.686233) (xy 118.443139 -280.72981) (xy 118.413574 -280.769154) (xy 118.378081 -280.803246)
			(xy 118.337578 -280.831202) (xy 118.293116 -280.8523) (xy 118.245845 -280.865992) (xy 118.19699 -280.871924)
			(xy 118.147815 -280.869943) (xy 118.099596 -280.860099) (xy 118.05358 -280.842647) (xy 118.010959 -280.81804)
			(xy 117.972838 -280.786915) (xy 117.940203 -280.750078) (xy 117.9139 -280.708482) (xy 117.894609 -280.663206)
			(xy 117.882832 -280.615422) (xy 117.878872 -280.566368) (xy 117.54993 -280.566368) (xy 117.549435 -280.590975)
			(xy 117.54154 -280.639552) (xy 117.525956 -280.686233) (xy 117.503085 -280.72981) (xy 117.47352 -280.769154)
			(xy 117.438027 -280.803246) (xy 117.397524 -280.831202) (xy 117.353062 -280.8523) (xy 117.305791 -280.865992)
			(xy 117.256936 -280.871924) (xy 117.207761 -280.869943) (xy 117.159542 -280.860099) (xy 117.113526 -280.842647)
			(xy 117.070905 -280.81804) (xy 117.032784 -280.786915) (xy 117.000149 -280.750078) (xy 116.973846 -280.708482)
			(xy 116.954555 -280.663206) (xy 116.942778 -280.615422) (xy 116.938818 -280.566368) (xy 116.61013 -280.566368)
			(xy 116.609635 -280.590975) (xy 116.60174 -280.639552) (xy 116.586156 -280.686233) (xy 116.563285 -280.72981)
			(xy 116.53372 -280.769154) (xy 116.498227 -280.803246) (xy 116.457724 -280.831202) (xy 116.413262 -280.8523)
			(xy 116.365991 -280.865992) (xy 116.317136 -280.871924) (xy 116.267961 -280.869943) (xy 116.219742 -280.860099)
			(xy 116.173726 -280.842647) (xy 116.131105 -280.81804) (xy 116.092984 -280.786915) (xy 116.060349 -280.750078)
			(xy 116.034046 -280.708482) (xy 116.014755 -280.663206) (xy 116.002978 -280.615422) (xy 115.999018 -280.566368)
			(xy 113.789968 -280.566368) (xy 113.789473 -280.590975) (xy 113.781578 -280.639552) (xy 113.765994 -280.686233)
			(xy 113.743123 -280.72981) (xy 113.713558 -280.769154) (xy 113.678065 -280.803246) (xy 113.637562 -280.831202)
			(xy 113.5931 -280.8523) (xy 113.545829 -280.865992) (xy 113.496974 -280.871924) (xy 113.447799 -280.869943)
			(xy 113.39958 -280.860099) (xy 113.353564 -280.842647) (xy 113.310943 -280.81804) (xy 113.272822 -280.786915)
			(xy 113.240187 -280.750078) (xy 113.213884 -280.708482) (xy 113.194593 -280.663206) (xy 113.182816 -280.615422)
			(xy 113.178856 -280.566368) (xy 112.399934 -280.566368) (xy 112.41305 -281.376374) (xy 113.64901 -281.376374)
			(xy 113.65297 -281.32732) (xy 113.664747 -281.279536) (xy 113.684038 -281.23426) (xy 113.710341 -281.192664)
			(xy 113.742976 -281.155827) (xy 113.781097 -281.124702) (xy 113.823718 -281.100095) (xy 113.869734 -281.082643)
			(xy 113.917953 -281.072799) (xy 113.967128 -281.070818) (xy 114.015983 -281.07675) (xy 114.063254 -281.090442)
			(xy 114.107716 -281.11154) (xy 114.148219 -281.139496) (xy 114.183712 -281.173588) (xy 114.213277 -281.212932)
			(xy 114.236148 -281.256509) (xy 114.251732 -281.30319) (xy 114.259627 -281.351767) (xy 114.260122 -281.376374)
			(xy 114.58881 -281.376374) (xy 114.59277 -281.32732) (xy 114.604547 -281.279536) (xy 114.623838 -281.23426)
			(xy 114.650141 -281.192664) (xy 114.682776 -281.155827) (xy 114.720897 -281.124702) (xy 114.763518 -281.100095)
			(xy 114.809534 -281.082643) (xy 114.857753 -281.072799) (xy 114.906928 -281.070818) (xy 114.955783 -281.07675)
			(xy 115.003054 -281.090442) (xy 115.047516 -281.11154) (xy 115.088019 -281.139496) (xy 115.123512 -281.173588)
			(xy 115.153077 -281.212932) (xy 115.175948 -281.256509) (xy 115.191532 -281.30319) (xy 115.199427 -281.351767)
			(xy 115.199922 -281.376374) (xy 115.528864 -281.376374) (xy 115.532824 -281.32732) (xy 115.544601 -281.279536)
			(xy 115.563892 -281.23426) (xy 115.590195 -281.192664) (xy 115.62283 -281.155827) (xy 115.660951 -281.124702)
			(xy 115.703572 -281.100095) (xy 115.749588 -281.082643) (xy 115.797807 -281.072799) (xy 115.846982 -281.070818)
			(xy 115.895837 -281.07675) (xy 115.943108 -281.090442) (xy 115.98757 -281.11154) (xy 116.028073 -281.139496)
			(xy 116.063566 -281.173588) (xy 116.093131 -281.212932) (xy 116.116002 -281.256509) (xy 116.131586 -281.30319)
			(xy 116.139481 -281.351767) (xy 116.139976 -281.376374) (xy 118.349026 -281.376374) (xy 118.352986 -281.32732)
			(xy 118.364763 -281.279536) (xy 118.384054 -281.23426) (xy 118.410357 -281.192664) (xy 118.442992 -281.155827)
			(xy 118.481113 -281.124702) (xy 118.523734 -281.100095) (xy 118.56975 -281.082643) (xy 118.617969 -281.072799)
			(xy 118.667144 -281.070818) (xy 118.715999 -281.07675) (xy 118.76327 -281.090442) (xy 118.807732 -281.11154)
			(xy 118.848235 -281.139496) (xy 118.883728 -281.173588) (xy 118.913293 -281.212932) (xy 118.936164 -281.256509)
			(xy 118.951748 -281.30319) (xy 118.959643 -281.351767) (xy 118.960138 -281.376374) (xy 121.168934 -281.376374)
			(xy 121.172894 -281.32732) (xy 121.184671 -281.279536) (xy 121.203962 -281.23426) (xy 121.230265 -281.192664)
			(xy 121.2629 -281.155827) (xy 121.301021 -281.124702) (xy 121.343642 -281.100095) (xy 121.389658 -281.082643)
			(xy 121.437877 -281.072799) (xy 121.487052 -281.070818) (xy 121.535907 -281.07675) (xy 121.583178 -281.090442)
			(xy 121.62764 -281.11154) (xy 121.668143 -281.139496) (xy 121.703636 -281.173588) (xy 121.733201 -281.212932)
			(xy 121.756072 -281.256509) (xy 121.771656 -281.30319) (xy 121.779551 -281.351767) (xy 121.780046 -281.376374)
			(xy 122.098557 -281.376374) (xy 122.102652 -281.325646) (xy 122.114831 -281.276232) (xy 122.134779 -281.229412)
			(xy 122.16198 -281.186398) (xy 122.195728 -281.148304) (xy 122.23515 -281.116117) (xy 122.279224 -281.090671)
			(xy 122.32681 -281.072624) (xy 122.376674 -281.062444) (xy 122.427526 -281.060395) (xy 122.478047 -281.066529)
			(xy 122.526931 -281.080689) (xy 122.57291 -281.102506) (xy 122.614794 -281.131416) (xy 122.651498 -281.166671)
			(xy 122.682071 -281.207357) (xy 122.705722 -281.25242) (xy 122.721838 -281.300694) (xy 122.730002 -281.350928)
			(xy 122.730514 -281.376374) (xy 123.038611 -281.376374) (xy 123.042706 -281.325646) (xy 123.054885 -281.276232)
			(xy 123.074833 -281.229412) (xy 123.102034 -281.186398) (xy 123.135782 -281.148304) (xy 123.175204 -281.116117)
			(xy 123.219278 -281.090671) (xy 123.266864 -281.072624) (xy 123.316728 -281.062444) (xy 123.36758 -281.060395)
			(xy 123.418101 -281.066529) (xy 123.466985 -281.080689) (xy 123.512964 -281.102506) (xy 123.554848 -281.131416)
			(xy 123.591552 -281.166671) (xy 123.622125 -281.207357) (xy 123.645776 -281.25242) (xy 123.661892 -281.300694)
			(xy 123.670056 -281.350928) (xy 123.670568 -281.376374) (xy 123.988842 -281.376374) (xy 123.992802 -281.32732)
			(xy 124.004579 -281.279536) (xy 124.02387 -281.23426) (xy 124.050173 -281.192664) (xy 124.082808 -281.155827)
			(xy 124.120929 -281.124702) (xy 124.16355 -281.100095) (xy 124.209566 -281.082643) (xy 124.257785 -281.072799)
			(xy 124.30696 -281.070818) (xy 124.355815 -281.07675) (xy 124.403086 -281.090442) (xy 124.447548 -281.11154)
			(xy 124.488051 -281.139496) (xy 124.523544 -281.173588) (xy 124.553109 -281.212932) (xy 124.57598 -281.256509)
			(xy 124.591564 -281.30319) (xy 124.599459 -281.351767) (xy 124.599954 -281.376374) (xy 124.918465 -281.376374)
			(xy 124.92256 -281.325646) (xy 124.934739 -281.276232) (xy 124.954687 -281.229412) (xy 124.981888 -281.186398)
			(xy 125.015636 -281.148304) (xy 125.055058 -281.116117) (xy 125.099132 -281.090671) (xy 125.146718 -281.072624)
			(xy 125.196582 -281.062444) (xy 125.247434 -281.060395) (xy 125.297955 -281.066529) (xy 125.346839 -281.080689)
			(xy 125.392818 -281.102506) (xy 125.434702 -281.131416) (xy 125.471406 -281.166671) (xy 125.501979 -281.207357)
			(xy 125.52563 -281.25242) (xy 125.541746 -281.300694) (xy 125.54991 -281.350928) (xy 125.550422 -281.376374)
			(xy 125.858519 -281.376374) (xy 125.862614 -281.325646) (xy 125.874793 -281.276232) (xy 125.894741 -281.229412)
			(xy 125.921942 -281.186398) (xy 125.95569 -281.148304) (xy 125.995112 -281.116117) (xy 126.039186 -281.090671)
			(xy 126.086772 -281.072624) (xy 126.136636 -281.062444) (xy 126.187488 -281.060395) (xy 126.238009 -281.066529)
			(xy 126.286893 -281.080689) (xy 126.332872 -281.102506) (xy 126.374756 -281.131416) (xy 126.41146 -281.166671)
			(xy 126.442033 -281.207357) (xy 126.465684 -281.25242) (xy 126.4818 -281.300694) (xy 126.489964 -281.350928)
			(xy 126.490476 -281.376374) (xy 126.489964 -281.40182) (xy 126.4818 -281.452054) (xy 126.465684 -281.500328)
			(xy 126.442033 -281.545391) (xy 126.41146 -281.586077) (xy 126.374756 -281.621332) (xy 126.332872 -281.650242)
			(xy 126.286893 -281.672059) (xy 126.238009 -281.686219) (xy 126.187488 -281.692353) (xy 126.136636 -281.690304)
			(xy 126.086772 -281.680124) (xy 126.039186 -281.662077) (xy 125.995112 -281.636631) (xy 125.95569 -281.604444)
			(xy 125.921942 -281.56635) (xy 125.894741 -281.523336) (xy 125.874793 -281.476516) (xy 125.862614 -281.427102)
			(xy 125.858519 -281.376374) (xy 125.550422 -281.376374) (xy 125.54991 -281.40182) (xy 125.541746 -281.452054)
			(xy 125.52563 -281.500328) (xy 125.501979 -281.545391) (xy 125.471406 -281.586077) (xy 125.434702 -281.621332)
			(xy 125.392818 -281.650242) (xy 125.346839 -281.672059) (xy 125.297955 -281.686219) (xy 125.247434 -281.692353)
			(xy 125.196582 -281.690304) (xy 125.146718 -281.680124) (xy 125.099132 -281.662077) (xy 125.055058 -281.636631)
			(xy 125.015636 -281.604444) (xy 124.981888 -281.56635) (xy 124.954687 -281.523336) (xy 124.934739 -281.476516)
			(xy 124.92256 -281.427102) (xy 124.918465 -281.376374) (xy 124.599954 -281.376374) (xy 124.599459 -281.400981)
			(xy 124.591564 -281.449558) (xy 124.57598 -281.496239) (xy 124.553109 -281.539816) (xy 124.523544 -281.57916)
			(xy 124.488051 -281.613252) (xy 124.447548 -281.641208) (xy 124.403086 -281.662306) (xy 124.355815 -281.675998)
			(xy 124.30696 -281.68193) (xy 124.257785 -281.679949) (xy 124.209566 -281.670105) (xy 124.16355 -281.652653)
			(xy 124.120929 -281.628046) (xy 124.082808 -281.596921) (xy 124.050173 -281.560084) (xy 124.02387 -281.518488)
			(xy 124.004579 -281.473212) (xy 123.992802 -281.425428) (xy 123.988842 -281.376374) (xy 123.670568 -281.376374)
			(xy 123.670056 -281.40182) (xy 123.661892 -281.452054) (xy 123.645776 -281.500328) (xy 123.622125 -281.545391)
			(xy 123.591552 -281.586077) (xy 123.554848 -281.621332) (xy 123.512964 -281.650242) (xy 123.466985 -281.672059)
			(xy 123.418101 -281.686219) (xy 123.36758 -281.692353) (xy 123.316728 -281.690304) (xy 123.266864 -281.680124)
			(xy 123.219278 -281.662077) (xy 123.175204 -281.636631) (xy 123.135782 -281.604444) (xy 123.102034 -281.56635)
			(xy 123.074833 -281.523336) (xy 123.054885 -281.476516) (xy 123.042706 -281.427102) (xy 123.038611 -281.376374)
			(xy 122.730514 -281.376374) (xy 122.730002 -281.40182) (xy 122.721838 -281.452054) (xy 122.705722 -281.500328)
			(xy 122.682071 -281.545391) (xy 122.651498 -281.586077) (xy 122.614794 -281.621332) (xy 122.57291 -281.650242)
			(xy 122.526931 -281.672059) (xy 122.478047 -281.686219) (xy 122.427526 -281.692353) (xy 122.376674 -281.690304)
			(xy 122.32681 -281.680124) (xy 122.279224 -281.662077) (xy 122.23515 -281.636631) (xy 122.195728 -281.604444)
			(xy 122.16198 -281.56635) (xy 122.134779 -281.523336) (xy 122.114831 -281.476516) (xy 122.102652 -281.427102)
			(xy 122.098557 -281.376374) (xy 121.780046 -281.376374) (xy 121.779551 -281.400981) (xy 121.771656 -281.449558)
			(xy 121.756072 -281.496239) (xy 121.733201 -281.539816) (xy 121.703636 -281.57916) (xy 121.668143 -281.613252)
			(xy 121.62764 -281.641208) (xy 121.583178 -281.662306) (xy 121.535907 -281.675998) (xy 121.487052 -281.68193)
			(xy 121.437877 -281.679949) (xy 121.389658 -281.670105) (xy 121.343642 -281.652653) (xy 121.301021 -281.628046)
			(xy 121.2629 -281.596921) (xy 121.230265 -281.560084) (xy 121.203962 -281.518488) (xy 121.184671 -281.473212)
			(xy 121.172894 -281.425428) (xy 121.168934 -281.376374) (xy 118.960138 -281.376374) (xy 118.959643 -281.400981)
			(xy 118.951748 -281.449558) (xy 118.936164 -281.496239) (xy 118.913293 -281.539816) (xy 118.883728 -281.57916)
			(xy 118.848235 -281.613252) (xy 118.807732 -281.641208) (xy 118.76327 -281.662306) (xy 118.715999 -281.675998)
			(xy 118.667144 -281.68193) (xy 118.617969 -281.679949) (xy 118.56975 -281.670105) (xy 118.523734 -281.652653)
			(xy 118.481113 -281.628046) (xy 118.442992 -281.596921) (xy 118.410357 -281.560084) (xy 118.384054 -281.518488)
			(xy 118.364763 -281.473212) (xy 118.352986 -281.425428) (xy 118.349026 -281.376374) (xy 116.139976 -281.376374)
			(xy 116.139481 -281.400981) (xy 116.131586 -281.449558) (xy 116.116002 -281.496239) (xy 116.093131 -281.539816)
			(xy 116.063566 -281.57916) (xy 116.028073 -281.613252) (xy 115.98757 -281.641208) (xy 115.943108 -281.662306)
			(xy 115.895837 -281.675998) (xy 115.846982 -281.68193) (xy 115.797807 -281.679949) (xy 115.749588 -281.670105)
			(xy 115.703572 -281.652653) (xy 115.660951 -281.628046) (xy 115.62283 -281.596921) (xy 115.590195 -281.560084)
			(xy 115.563892 -281.518488) (xy 115.544601 -281.473212) (xy 115.532824 -281.425428) (xy 115.528864 -281.376374)
			(xy 115.199922 -281.376374) (xy 115.199427 -281.400981) (xy 115.191532 -281.449558) (xy 115.175948 -281.496239)
			(xy 115.153077 -281.539816) (xy 115.123512 -281.57916) (xy 115.088019 -281.613252) (xy 115.047516 -281.641208)
			(xy 115.003054 -281.662306) (xy 114.955783 -281.675998) (xy 114.906928 -281.68193) (xy 114.857753 -281.679949)
			(xy 114.809534 -281.670105) (xy 114.763518 -281.652653) (xy 114.720897 -281.628046) (xy 114.682776 -281.596921)
			(xy 114.650141 -281.560084) (xy 114.623838 -281.518488) (xy 114.604547 -281.473212) (xy 114.59277 -281.425428)
			(xy 114.58881 -281.376374) (xy 114.260122 -281.376374) (xy 114.259627 -281.400981) (xy 114.251732 -281.449558)
			(xy 114.236148 -281.496239) (xy 114.213277 -281.539816) (xy 114.183712 -281.57916) (xy 114.148219 -281.613252)
			(xy 114.107716 -281.641208) (xy 114.063254 -281.662306) (xy 114.015983 -281.675998) (xy 113.967128 -281.68193)
			(xy 113.917953 -281.679949) (xy 113.869734 -281.670105) (xy 113.823718 -281.652653) (xy 113.781097 -281.628046)
			(xy 113.742976 -281.596921) (xy 113.710341 -281.560084) (xy 113.684038 -281.518488) (xy 113.664747 -281.473212)
			(xy 113.65297 -281.425428) (xy 113.64901 -281.376374) (xy 112.41305 -281.376374) (xy 112.426166 -282.18638)
			(xy 113.178856 -282.18638) (xy 113.182816 -282.137326) (xy 113.194593 -282.089542) (xy 113.213884 -282.044266)
			(xy 113.240187 -282.00267) (xy 113.272822 -281.965833) (xy 113.310943 -281.934708) (xy 113.353564 -281.910101)
			(xy 113.39958 -281.892649) (xy 113.447799 -281.882805) (xy 113.496974 -281.880824) (xy 113.545829 -281.886756)
			(xy 113.5931 -281.900448) (xy 113.637562 -281.921546) (xy 113.678065 -281.949502) (xy 113.713558 -281.983594)
			(xy 113.743123 -282.022938) (xy 113.765994 -282.066515) (xy 113.781578 -282.113196) (xy 113.789473 -282.161773)
			(xy 113.789968 -282.18638) (xy 114.108479 -282.18638) (xy 114.112574 -282.135652) (xy 114.124753 -282.086238)
			(xy 114.144701 -282.039418) (xy 114.171902 -281.996404) (xy 114.20565 -281.95831) (xy 114.245072 -281.926123)
			(xy 114.289146 -281.900677) (xy 114.336732 -281.88263) (xy 114.386596 -281.87245) (xy 114.437448 -281.870401)
			(xy 114.487969 -281.876535) (xy 114.536853 -281.890695) (xy 114.582832 -281.912512) (xy 114.624716 -281.941422)
			(xy 114.66142 -281.976677) (xy 114.691993 -282.017363) (xy 114.715644 -282.062426) (xy 114.73176 -282.1107)
			(xy 114.739924 -282.160934) (xy 114.740436 -282.18638) (xy 115.048533 -282.18638) (xy 115.052628 -282.135652)
			(xy 115.064807 -282.086238) (xy 115.084755 -282.039418) (xy 115.111956 -281.996404) (xy 115.145704 -281.95831)
			(xy 115.185126 -281.926123) (xy 115.2292 -281.900677) (xy 115.276786 -281.88263) (xy 115.32665 -281.87245)
			(xy 115.377502 -281.870401) (xy 115.428023 -281.876535) (xy 115.476907 -281.890695) (xy 115.522886 -281.912512)
			(xy 115.56477 -281.941422) (xy 115.601474 -281.976677) (xy 115.632047 -282.017363) (xy 115.655698 -282.062426)
			(xy 115.671814 -282.1107) (xy 115.679978 -282.160934) (xy 115.68049 -282.18638) (xy 115.999018 -282.18638)
			(xy 116.002978 -282.137326) (xy 116.014755 -282.089542) (xy 116.034046 -282.044266) (xy 116.060349 -282.00267)
			(xy 116.092984 -281.965833) (xy 116.131105 -281.934708) (xy 116.173726 -281.910101) (xy 116.219742 -281.892649)
			(xy 116.267961 -281.882805) (xy 116.317136 -281.880824) (xy 116.365991 -281.886756) (xy 116.413262 -281.900448)
			(xy 116.457724 -281.921546) (xy 116.498227 -281.949502) (xy 116.53372 -281.983594) (xy 116.563285 -282.022938)
			(xy 116.586156 -282.066515) (xy 116.60174 -282.113196) (xy 116.609635 -282.161773) (xy 116.61013 -282.18638)
			(xy 116.938818 -282.18638) (xy 116.942778 -282.137326) (xy 116.954555 -282.089542) (xy 116.973846 -282.044266)
			(xy 117.000149 -282.00267) (xy 117.032784 -281.965833) (xy 117.070905 -281.934708) (xy 117.113526 -281.910101)
			(xy 117.159542 -281.892649) (xy 117.207761 -281.882805) (xy 117.256936 -281.880824) (xy 117.305791 -281.886756)
			(xy 117.353062 -281.900448) (xy 117.397524 -281.921546) (xy 117.438027 -281.949502) (xy 117.47352 -281.983594)
			(xy 117.503085 -282.022938) (xy 117.525956 -282.066515) (xy 117.54154 -282.113196) (xy 117.549435 -282.161773)
			(xy 117.54993 -282.18638) (xy 117.878872 -282.18638) (xy 117.882832 -282.137326) (xy 117.894609 -282.089542)
			(xy 117.9139 -282.044266) (xy 117.940203 -282.00267) (xy 117.972838 -281.965833) (xy 118.010959 -281.934708)
			(xy 118.05358 -281.910101) (xy 118.099596 -281.892649) (xy 118.147815 -281.882805) (xy 118.19699 -281.880824)
			(xy 118.245845 -281.886756) (xy 118.293116 -281.900448) (xy 118.337578 -281.921546) (xy 118.378081 -281.949502)
			(xy 118.413574 -281.983594) (xy 118.443139 -282.022938) (xy 118.46601 -282.066515) (xy 118.481594 -282.113196)
			(xy 118.489489 -282.161773) (xy 118.489984 -282.18638) (xy 118.818926 -282.18638) (xy 118.822886 -282.137326)
			(xy 118.834663 -282.089542) (xy 118.853954 -282.044266) (xy 118.880257 -282.00267) (xy 118.912892 -281.965833)
			(xy 118.951013 -281.934708) (xy 118.993634 -281.910101) (xy 119.03965 -281.892649) (xy 119.087869 -281.882805)
			(xy 119.137044 -281.880824) (xy 119.185899 -281.886756) (xy 119.23317 -281.900448) (xy 119.277632 -281.921546)
			(xy 119.318135 -281.949502) (xy 119.353628 -281.983594) (xy 119.383193 -282.022938) (xy 119.406064 -282.066515)
			(xy 119.421648 -282.113196) (xy 119.429543 -282.161773) (xy 119.430038 -282.18638) (xy 119.75898 -282.18638)
			(xy 119.76294 -282.137326) (xy 119.774717 -282.089542) (xy 119.794008 -282.044266) (xy 119.820311 -282.00267)
			(xy 119.852946 -281.965833) (xy 119.891067 -281.934708) (xy 119.933688 -281.910101) (xy 119.979704 -281.892649)
			(xy 120.027923 -281.882805) (xy 120.077098 -281.880824) (xy 120.125953 -281.886756) (xy 120.173224 -281.900448)
			(xy 120.217686 -281.921546) (xy 120.258189 -281.949502) (xy 120.293682 -281.983594) (xy 120.323247 -282.022938)
			(xy 120.346118 -282.066515) (xy 120.361702 -282.113196) (xy 120.369597 -282.161773) (xy 120.370092 -282.18638)
			(xy 120.699034 -282.18638) (xy 120.702994 -282.137326) (xy 120.714771 -282.089542) (xy 120.734062 -282.044266)
			(xy 120.760365 -282.00267) (xy 120.793 -281.965833) (xy 120.831121 -281.934708) (xy 120.873742 -281.910101)
			(xy 120.919758 -281.892649) (xy 120.967977 -281.882805) (xy 121.017152 -281.880824) (xy 121.066007 -281.886756)
			(xy 121.113278 -281.900448) (xy 121.15774 -281.921546) (xy 121.198243 -281.949502) (xy 121.233736 -281.983594)
			(xy 121.263301 -282.022938) (xy 121.286172 -282.066515) (xy 121.301756 -282.113196) (xy 121.309651 -282.161773)
			(xy 121.310146 -282.18638) (xy 121.638834 -282.18638) (xy 121.642794 -282.137326) (xy 121.654571 -282.089542)
			(xy 121.673862 -282.044266) (xy 121.700165 -282.00267) (xy 121.7328 -281.965833) (xy 121.770921 -281.934708)
			(xy 121.813542 -281.910101) (xy 121.859558 -281.892649) (xy 121.907777 -281.882805) (xy 121.956952 -281.880824)
			(xy 122.005807 -281.886756) (xy 122.053078 -281.900448) (xy 122.09754 -281.921546) (xy 122.138043 -281.949502)
			(xy 122.173536 -281.983594) (xy 122.203101 -282.022938) (xy 122.225972 -282.066515) (xy 122.241556 -282.113196)
			(xy 122.249451 -282.161773) (xy 122.249946 -282.18638) (xy 122.578888 -282.18638) (xy 122.582848 -282.137326)
			(xy 122.594625 -282.089542) (xy 122.613916 -282.044266) (xy 122.640219 -282.00267) (xy 122.672854 -281.965833)
			(xy 122.710975 -281.934708) (xy 122.753596 -281.910101) (xy 122.799612 -281.892649) (xy 122.847831 -281.882805)
			(xy 122.897006 -281.880824) (xy 122.945861 -281.886756) (xy 122.993132 -281.900448) (xy 123.037594 -281.921546)
			(xy 123.078097 -281.949502) (xy 123.11359 -281.983594) (xy 123.143155 -282.022938) (xy 123.166026 -282.066515)
			(xy 123.18161 -282.113196) (xy 123.189505 -282.161773) (xy 123.19 -282.18638) (xy 123.518942 -282.18638)
			(xy 123.522902 -282.137326) (xy 123.534679 -282.089542) (xy 123.55397 -282.044266) (xy 123.580273 -282.00267)
			(xy 123.612908 -281.965833) (xy 123.651029 -281.934708) (xy 123.69365 -281.910101) (xy 123.739666 -281.892649)
			(xy 123.787885 -281.882805) (xy 123.83706 -281.880824) (xy 123.885915 -281.886756) (xy 123.933186 -281.900448)
			(xy 123.977648 -281.921546) (xy 124.018151 -281.949502) (xy 124.053644 -281.983594) (xy 124.083209 -282.022938)
			(xy 124.10608 -282.066515) (xy 124.121664 -282.113196) (xy 124.129559 -282.161773) (xy 124.130054 -282.18638)
			(xy 124.458996 -282.18638) (xy 124.462956 -282.137326) (xy 124.474733 -282.089542) (xy 124.494024 -282.044266)
			(xy 124.520327 -282.00267) (xy 124.552962 -281.965833) (xy 124.591083 -281.934708) (xy 124.633704 -281.910101)
			(xy 124.67972 -281.892649) (xy 124.727939 -281.882805) (xy 124.777114 -281.880824) (xy 124.825969 -281.886756)
			(xy 124.87324 -281.900448) (xy 124.917702 -281.921546) (xy 124.958205 -281.949502) (xy 124.993698 -281.983594)
			(xy 125.023263 -282.022938) (xy 125.046134 -282.066515) (xy 125.061718 -282.113196) (xy 125.069613 -282.161773)
			(xy 125.070108 -282.18638) (xy 125.39905 -282.18638) (xy 125.40301 -282.137326) (xy 125.414787 -282.089542)
			(xy 125.434078 -282.044266) (xy 125.460381 -282.00267) (xy 125.493016 -281.965833) (xy 125.531137 -281.934708)
			(xy 125.573758 -281.910101) (xy 125.619774 -281.892649) (xy 125.667993 -281.882805) (xy 125.717168 -281.880824)
			(xy 125.766023 -281.886756) (xy 125.813294 -281.900448) (xy 125.857756 -281.921546) (xy 125.898259 -281.949502)
			(xy 125.933752 -281.983594) (xy 125.963317 -282.022938) (xy 125.986188 -282.066515) (xy 126.001772 -282.113196)
			(xy 126.009667 -282.161773) (xy 126.010162 -282.18638) (xy 126.009667 -282.210987) (xy 126.001772 -282.259564)
			(xy 125.986188 -282.306245) (xy 125.963317 -282.349822) (xy 125.933752 -282.389166) (xy 125.898259 -282.423258)
			(xy 125.857756 -282.451214) (xy 125.813294 -282.472312) (xy 125.766023 -282.486004) (xy 125.717168 -282.491936)
			(xy 125.667993 -282.489955) (xy 125.619774 -282.480111) (xy 125.573758 -282.462659) (xy 125.531137 -282.438052)
			(xy 125.493016 -282.406927) (xy 125.460381 -282.37009) (xy 125.434078 -282.328494) (xy 125.414787 -282.283218)
			(xy 125.40301 -282.235434) (xy 125.39905 -282.18638) (xy 125.070108 -282.18638) (xy 125.069613 -282.210987)
			(xy 125.061718 -282.259564) (xy 125.046134 -282.306245) (xy 125.023263 -282.349822) (xy 124.993698 -282.389166)
			(xy 124.958205 -282.423258) (xy 124.917702 -282.451214) (xy 124.87324 -282.472312) (xy 124.825969 -282.486004)
			(xy 124.777114 -282.491936) (xy 124.727939 -282.489955) (xy 124.67972 -282.480111) (xy 124.633704 -282.462659)
			(xy 124.591083 -282.438052) (xy 124.552962 -282.406927) (xy 124.520327 -282.37009) (xy 124.494024 -282.328494)
			(xy 124.474733 -282.283218) (xy 124.462956 -282.235434) (xy 124.458996 -282.18638) (xy 124.130054 -282.18638)
			(xy 124.129559 -282.210987) (xy 124.121664 -282.259564) (xy 124.10608 -282.306245) (xy 124.083209 -282.349822)
			(xy 124.053644 -282.389166) (xy 124.018151 -282.423258) (xy 123.977648 -282.451214) (xy 123.933186 -282.472312)
			(xy 123.885915 -282.486004) (xy 123.83706 -282.491936) (xy 123.787885 -282.489955) (xy 123.739666 -282.480111)
			(xy 123.69365 -282.462659) (xy 123.651029 -282.438052) (xy 123.612908 -282.406927) (xy 123.580273 -282.37009)
			(xy 123.55397 -282.328494) (xy 123.534679 -282.283218) (xy 123.522902 -282.235434) (xy 123.518942 -282.18638)
			(xy 123.19 -282.18638) (xy 123.189505 -282.210987) (xy 123.18161 -282.259564) (xy 123.166026 -282.306245)
			(xy 123.143155 -282.349822) (xy 123.11359 -282.389166) (xy 123.078097 -282.423258) (xy 123.037594 -282.451214)
			(xy 122.993132 -282.472312) (xy 122.945861 -282.486004) (xy 122.897006 -282.491936) (xy 122.847831 -282.489955)
			(xy 122.799612 -282.480111) (xy 122.753596 -282.462659) (xy 122.710975 -282.438052) (xy 122.672854 -282.406927)
			(xy 122.640219 -282.37009) (xy 122.613916 -282.328494) (xy 122.594625 -282.283218) (xy 122.582848 -282.235434)
			(xy 122.578888 -282.18638) (xy 122.249946 -282.18638) (xy 122.249451 -282.210987) (xy 122.241556 -282.259564)
			(xy 122.225972 -282.306245) (xy 122.203101 -282.349822) (xy 122.173536 -282.389166) (xy 122.138043 -282.423258)
			(xy 122.09754 -282.451214) (xy 122.053078 -282.472312) (xy 122.005807 -282.486004) (xy 121.956952 -282.491936)
			(xy 121.907777 -282.489955) (xy 121.859558 -282.480111) (xy 121.813542 -282.462659) (xy 121.770921 -282.438052)
			(xy 121.7328 -282.406927) (xy 121.700165 -282.37009) (xy 121.673862 -282.328494) (xy 121.654571 -282.283218)
			(xy 121.642794 -282.235434) (xy 121.638834 -282.18638) (xy 121.310146 -282.18638) (xy 121.309651 -282.210987)
			(xy 121.301756 -282.259564) (xy 121.286172 -282.306245) (xy 121.263301 -282.349822) (xy 121.233736 -282.389166)
			(xy 121.198243 -282.423258) (xy 121.15774 -282.451214) (xy 121.113278 -282.472312) (xy 121.066007 -282.486004)
			(xy 121.017152 -282.491936) (xy 120.967977 -282.489955) (xy 120.919758 -282.480111) (xy 120.873742 -282.462659)
			(xy 120.831121 -282.438052) (xy 120.793 -282.406927) (xy 120.760365 -282.37009) (xy 120.734062 -282.328494)
			(xy 120.714771 -282.283218) (xy 120.702994 -282.235434) (xy 120.699034 -282.18638) (xy 120.370092 -282.18638)
			(xy 120.369597 -282.210987) (xy 120.361702 -282.259564) (xy 120.346118 -282.306245) (xy 120.323247 -282.349822)
			(xy 120.293682 -282.389166) (xy 120.258189 -282.423258) (xy 120.217686 -282.451214) (xy 120.173224 -282.472312)
			(xy 120.125953 -282.486004) (xy 120.077098 -282.491936) (xy 120.027923 -282.489955) (xy 119.979704 -282.480111)
			(xy 119.933688 -282.462659) (xy 119.891067 -282.438052) (xy 119.852946 -282.406927) (xy 119.820311 -282.37009)
			(xy 119.794008 -282.328494) (xy 119.774717 -282.283218) (xy 119.76294 -282.235434) (xy 119.75898 -282.18638)
			(xy 119.430038 -282.18638) (xy 119.429543 -282.210987) (xy 119.421648 -282.259564) (xy 119.406064 -282.306245)
			(xy 119.383193 -282.349822) (xy 119.353628 -282.389166) (xy 119.318135 -282.423258) (xy 119.277632 -282.451214)
			(xy 119.23317 -282.472312) (xy 119.185899 -282.486004) (xy 119.137044 -282.491936) (xy 119.087869 -282.489955)
			(xy 119.03965 -282.480111) (xy 118.993634 -282.462659) (xy 118.951013 -282.438052) (xy 118.912892 -282.406927)
			(xy 118.880257 -282.37009) (xy 118.853954 -282.328494) (xy 118.834663 -282.283218) (xy 118.822886 -282.235434)
			(xy 118.818926 -282.18638) (xy 118.489984 -282.18638) (xy 118.489489 -282.210987) (xy 118.481594 -282.259564)
			(xy 118.46601 -282.306245) (xy 118.443139 -282.349822) (xy 118.413574 -282.389166) (xy 118.378081 -282.423258)
			(xy 118.337578 -282.451214) (xy 118.293116 -282.472312) (xy 118.245845 -282.486004) (xy 118.19699 -282.491936)
			(xy 118.147815 -282.489955) (xy 118.099596 -282.480111) (xy 118.05358 -282.462659) (xy 118.010959 -282.438052)
			(xy 117.972838 -282.406927) (xy 117.940203 -282.37009) (xy 117.9139 -282.328494) (xy 117.894609 -282.283218)
			(xy 117.882832 -282.235434) (xy 117.878872 -282.18638) (xy 117.54993 -282.18638) (xy 117.549435 -282.210987)
			(xy 117.54154 -282.259564) (xy 117.525956 -282.306245) (xy 117.503085 -282.349822) (xy 117.47352 -282.389166)
			(xy 117.438027 -282.423258) (xy 117.397524 -282.451214) (xy 117.353062 -282.472312) (xy 117.305791 -282.486004)
			(xy 117.256936 -282.491936) (xy 117.207761 -282.489955) (xy 117.159542 -282.480111) (xy 117.113526 -282.462659)
			(xy 117.070905 -282.438052) (xy 117.032784 -282.406927) (xy 117.000149 -282.37009) (xy 116.973846 -282.328494)
			(xy 116.954555 -282.283218) (xy 116.942778 -282.235434) (xy 116.938818 -282.18638) (xy 116.61013 -282.18638)
			(xy 116.609635 -282.210987) (xy 116.60174 -282.259564) (xy 116.586156 -282.306245) (xy 116.563285 -282.349822)
			(xy 116.53372 -282.389166) (xy 116.498227 -282.423258) (xy 116.457724 -282.451214) (xy 116.413262 -282.472312)
			(xy 116.365991 -282.486004) (xy 116.317136 -282.491936) (xy 116.267961 -282.489955) (xy 116.219742 -282.480111)
			(xy 116.173726 -282.462659) (xy 116.131105 -282.438052) (xy 116.092984 -282.406927) (xy 116.060349 -282.37009)
			(xy 116.034046 -282.328494) (xy 116.014755 -282.283218) (xy 116.002978 -282.235434) (xy 115.999018 -282.18638)
			(xy 115.68049 -282.18638) (xy 115.679978 -282.211826) (xy 115.671814 -282.26206) (xy 115.655698 -282.310334)
			(xy 115.632047 -282.355397) (xy 115.601474 -282.396083) (xy 115.56477 -282.431338) (xy 115.522886 -282.460248)
			(xy 115.476907 -282.482065) (xy 115.428023 -282.496225) (xy 115.377502 -282.502359) (xy 115.32665 -282.50031)
			(xy 115.276786 -282.49013) (xy 115.2292 -282.472083) (xy 115.185126 -282.446637) (xy 115.145704 -282.41445)
			(xy 115.111956 -282.376356) (xy 115.084755 -282.333342) (xy 115.064807 -282.286522) (xy 115.052628 -282.237108)
			(xy 115.048533 -282.18638) (xy 114.740436 -282.18638) (xy 114.739924 -282.211826) (xy 114.73176 -282.26206)
			(xy 114.715644 -282.310334) (xy 114.691993 -282.355397) (xy 114.66142 -282.396083) (xy 114.624716 -282.431338)
			(xy 114.582832 -282.460248) (xy 114.536853 -282.482065) (xy 114.487969 -282.496225) (xy 114.437448 -282.502359)
			(xy 114.386596 -282.50031) (xy 114.336732 -282.49013) (xy 114.289146 -282.472083) (xy 114.245072 -282.446637)
			(xy 114.20565 -282.41445) (xy 114.171902 -282.376356) (xy 114.144701 -282.333342) (xy 114.124753 -282.286522)
			(xy 114.112574 -282.237108) (xy 114.108479 -282.18638) (xy 113.789968 -282.18638) (xy 113.789473 -282.210987)
			(xy 113.781578 -282.259564) (xy 113.765994 -282.306245) (xy 113.743123 -282.349822) (xy 113.713558 -282.389166)
			(xy 113.678065 -282.423258) (xy 113.637562 -282.451214) (xy 113.5931 -282.472312) (xy 113.545829 -282.486004)
			(xy 113.496974 -282.491936) (xy 113.447799 -282.489955) (xy 113.39958 -282.480111) (xy 113.353564 -282.462659)
			(xy 113.310943 -282.438052) (xy 113.272822 -282.406927) (xy 113.240187 -282.37009) (xy 113.213884 -282.328494)
			(xy 113.194593 -282.283218) (xy 113.182816 -282.235434) (xy 113.178856 -282.18638) (xy 112.426166 -282.18638)
			(xy 112.439282 -282.996386) (xy 115.528864 -282.996386) (xy 115.532824 -282.947332) (xy 115.544601 -282.899548)
			(xy 115.563892 -282.854272) (xy 115.590195 -282.812676) (xy 115.62283 -282.775839) (xy 115.660951 -282.744714)
			(xy 115.703572 -282.720107) (xy 115.749588 -282.702655) (xy 115.797807 -282.692811) (xy 115.846982 -282.69083)
			(xy 115.895837 -282.696762) (xy 115.943108 -282.710454) (xy 115.98757 -282.731552) (xy 116.028073 -282.759508)
			(xy 116.063566 -282.7936) (xy 116.093131 -282.832944) (xy 116.116002 -282.876521) (xy 116.131586 -282.923202)
			(xy 116.139481 -282.971779) (xy 116.139976 -282.996386) (xy 116.458487 -282.996386) (xy 116.462582 -282.945658)
			(xy 116.474761 -282.896244) (xy 116.494709 -282.849424) (xy 116.52191 -282.80641) (xy 116.555658 -282.768316)
			(xy 116.59508 -282.736129) (xy 116.639154 -282.710683) (xy 116.68674 -282.692636) (xy 116.736604 -282.682456)
			(xy 116.787456 -282.680407) (xy 116.837977 -282.686541) (xy 116.886861 -282.700701) (xy 116.93284 -282.722518)
			(xy 116.974724 -282.751428) (xy 117.011428 -282.786683) (xy 117.042001 -282.827369) (xy 117.065652 -282.872432)
			(xy 117.081768 -282.920706) (xy 117.089932 -282.97094) (xy 117.090444 -282.996386) (xy 117.398541 -282.996386)
			(xy 117.402636 -282.945658) (xy 117.414815 -282.896244) (xy 117.434763 -282.849424) (xy 117.461964 -282.80641)
			(xy 117.495712 -282.768316) (xy 117.535134 -282.736129) (xy 117.579208 -282.710683) (xy 117.626794 -282.692636)
			(xy 117.676658 -282.682456) (xy 117.72751 -282.680407) (xy 117.778031 -282.686541) (xy 117.826915 -282.700701)
			(xy 117.872894 -282.722518) (xy 117.914778 -282.751428) (xy 117.951482 -282.786683) (xy 117.982055 -282.827369)
			(xy 118.005706 -282.872432) (xy 118.021822 -282.920706) (xy 118.029986 -282.97094) (xy 118.030498 -282.996386)
			(xy 118.349026 -282.996386) (xy 118.352986 -282.947332) (xy 118.364763 -282.899548) (xy 118.384054 -282.854272)
			(xy 118.410357 -282.812676) (xy 118.442992 -282.775839) (xy 118.481113 -282.744714) (xy 118.523734 -282.720107)
			(xy 118.56975 -282.702655) (xy 118.617969 -282.692811) (xy 118.667144 -282.69083) (xy 118.715999 -282.696762)
			(xy 118.76327 -282.710454) (xy 118.807732 -282.731552) (xy 118.848235 -282.759508) (xy 118.883728 -282.7936)
			(xy 118.913293 -282.832944) (xy 118.936164 -282.876521) (xy 118.951748 -282.923202) (xy 118.959643 -282.971779)
			(xy 118.960138 -282.996386) (xy 119.278395 -282.996386) (xy 119.28249 -282.945658) (xy 119.294669 -282.896244)
			(xy 119.314617 -282.849424) (xy 119.341818 -282.80641) (xy 119.375566 -282.768316) (xy 119.414988 -282.736129)
			(xy 119.459062 -282.710683) (xy 119.506648 -282.692636) (xy 119.556512 -282.682456) (xy 119.607364 -282.680407)
			(xy 119.657885 -282.686541) (xy 119.706769 -282.700701) (xy 119.752748 -282.722518) (xy 119.794632 -282.751428)
			(xy 119.831336 -282.786683) (xy 119.861909 -282.827369) (xy 119.88556 -282.872432) (xy 119.901676 -282.920706)
			(xy 119.90984 -282.97094) (xy 119.910352 -282.996386) (xy 120.218449 -282.996386) (xy 120.222544 -282.945658)
			(xy 120.234723 -282.896244) (xy 120.254671 -282.849424) (xy 120.281872 -282.80641) (xy 120.31562 -282.768316)
			(xy 120.355042 -282.736129) (xy 120.399116 -282.710683) (xy 120.446702 -282.692636) (xy 120.496566 -282.682456)
			(xy 120.547418 -282.680407) (xy 120.597939 -282.686541) (xy 120.646823 -282.700701) (xy 120.692802 -282.722518)
			(xy 120.734686 -282.751428) (xy 120.77139 -282.786683) (xy 120.801963 -282.827369) (xy 120.825614 -282.872432)
			(xy 120.84173 -282.920706) (xy 120.849894 -282.97094) (xy 120.850406 -282.996386) (xy 121.168934 -282.996386)
			(xy 121.172894 -282.947332) (xy 121.184671 -282.899548) (xy 121.203962 -282.854272) (xy 121.230265 -282.812676)
			(xy 121.2629 -282.775839) (xy 121.301021 -282.744714) (xy 121.343642 -282.720107) (xy 121.389658 -282.702655)
			(xy 121.437877 -282.692811) (xy 121.487052 -282.69083) (xy 121.535907 -282.696762) (xy 121.583178 -282.710454)
			(xy 121.62764 -282.731552) (xy 121.668143 -282.759508) (xy 121.703636 -282.7936) (xy 121.733201 -282.832944)
			(xy 121.756072 -282.876521) (xy 121.771656 -282.923202) (xy 121.779551 -282.971779) (xy 121.780046 -282.996386)
			(xy 122.098557 -282.996386) (xy 122.102652 -282.945658) (xy 122.114831 -282.896244) (xy 122.134779 -282.849424)
			(xy 122.16198 -282.80641) (xy 122.195728 -282.768316) (xy 122.23515 -282.736129) (xy 122.279224 -282.710683)
			(xy 122.32681 -282.692636) (xy 122.376674 -282.682456) (xy 122.427526 -282.680407) (xy 122.478047 -282.686541)
			(xy 122.526931 -282.700701) (xy 122.57291 -282.722518) (xy 122.614794 -282.751428) (xy 122.651498 -282.786683)
			(xy 122.682071 -282.827369) (xy 122.705722 -282.872432) (xy 122.721838 -282.920706) (xy 122.730002 -282.97094)
			(xy 122.730514 -282.996386) (xy 123.038611 -282.996386) (xy 123.042706 -282.945658) (xy 123.054885 -282.896244)
			(xy 123.074833 -282.849424) (xy 123.102034 -282.80641) (xy 123.135782 -282.768316) (xy 123.175204 -282.736129)
			(xy 123.219278 -282.710683) (xy 123.266864 -282.692636) (xy 123.316728 -282.682456) (xy 123.36758 -282.680407)
			(xy 123.418101 -282.686541) (xy 123.466985 -282.700701) (xy 123.512964 -282.722518) (xy 123.554848 -282.751428)
			(xy 123.591552 -282.786683) (xy 123.622125 -282.827369) (xy 123.645776 -282.872432) (xy 123.661892 -282.920706)
			(xy 123.670056 -282.97094) (xy 123.670568 -282.996386) (xy 123.988842 -282.996386) (xy 123.992802 -282.947332)
			(xy 124.004579 -282.899548) (xy 124.02387 -282.854272) (xy 124.050173 -282.812676) (xy 124.082808 -282.775839)
			(xy 124.120929 -282.744714) (xy 124.16355 -282.720107) (xy 124.209566 -282.702655) (xy 124.257785 -282.692811)
			(xy 124.30696 -282.69083) (xy 124.355815 -282.696762) (xy 124.403086 -282.710454) (xy 124.447548 -282.731552)
			(xy 124.488051 -282.759508) (xy 124.523544 -282.7936) (xy 124.553109 -282.832944) (xy 124.57598 -282.876521)
			(xy 124.591564 -282.923202) (xy 124.599459 -282.971779) (xy 124.599954 -282.996386) (xy 124.918465 -282.996386)
			(xy 124.92256 -282.945658) (xy 124.934739 -282.896244) (xy 124.954687 -282.849424) (xy 124.981888 -282.80641)
			(xy 125.015636 -282.768316) (xy 125.055058 -282.736129) (xy 125.099132 -282.710683) (xy 125.146718 -282.692636)
			(xy 125.196582 -282.682456) (xy 125.247434 -282.680407) (xy 125.297955 -282.686541) (xy 125.346839 -282.700701)
			(xy 125.392818 -282.722518) (xy 125.434702 -282.751428) (xy 125.471406 -282.786683) (xy 125.501979 -282.827369)
			(xy 125.52563 -282.872432) (xy 125.541746 -282.920706) (xy 125.54991 -282.97094) (xy 125.550422 -282.996386)
			(xy 125.858519 -282.996386) (xy 125.862614 -282.945658) (xy 125.874793 -282.896244) (xy 125.894741 -282.849424)
			(xy 125.921942 -282.80641) (xy 125.95569 -282.768316) (xy 125.995112 -282.736129) (xy 126.039186 -282.710683)
			(xy 126.086772 -282.692636) (xy 126.136636 -282.682456) (xy 126.187488 -282.680407) (xy 126.238009 -282.686541)
			(xy 126.286893 -282.700701) (xy 126.332872 -282.722518) (xy 126.374756 -282.751428) (xy 126.41146 -282.786683)
			(xy 126.442033 -282.827369) (xy 126.465684 -282.872432) (xy 126.4818 -282.920706) (xy 126.489964 -282.97094)
			(xy 126.490476 -282.996386) (xy 126.489964 -283.021832) (xy 126.4818 -283.072066) (xy 126.465684 -283.12034)
			(xy 126.442033 -283.165403) (xy 126.41146 -283.206089) (xy 126.374756 -283.241344) (xy 126.332872 -283.270254)
			(xy 126.286893 -283.292071) (xy 126.238009 -283.306231) (xy 126.187488 -283.312365) (xy 126.136636 -283.310316)
			(xy 126.086772 -283.300136) (xy 126.039186 -283.282089) (xy 125.995112 -283.256643) (xy 125.95569 -283.224456)
			(xy 125.921942 -283.186362) (xy 125.894741 -283.143348) (xy 125.874793 -283.096528) (xy 125.862614 -283.047114)
			(xy 125.858519 -282.996386) (xy 125.550422 -282.996386) (xy 125.54991 -283.021832) (xy 125.541746 -283.072066)
			(xy 125.52563 -283.12034) (xy 125.501979 -283.165403) (xy 125.471406 -283.206089) (xy 125.434702 -283.241344)
			(xy 125.392818 -283.270254) (xy 125.346839 -283.292071) (xy 125.297955 -283.306231) (xy 125.247434 -283.312365)
			(xy 125.196582 -283.310316) (xy 125.146718 -283.300136) (xy 125.099132 -283.282089) (xy 125.055058 -283.256643)
			(xy 125.015636 -283.224456) (xy 124.981888 -283.186362) (xy 124.954687 -283.143348) (xy 124.934739 -283.096528)
			(xy 124.92256 -283.047114) (xy 124.918465 -282.996386) (xy 124.599954 -282.996386) (xy 124.599459 -283.020993)
			(xy 124.591564 -283.06957) (xy 124.57598 -283.116251) (xy 124.553109 -283.159828) (xy 124.523544 -283.199172)
			(xy 124.488051 -283.233264) (xy 124.447548 -283.26122) (xy 124.403086 -283.282318) (xy 124.355815 -283.29601)
			(xy 124.30696 -283.301942) (xy 124.257785 -283.299961) (xy 124.209566 -283.290117) (xy 124.16355 -283.272665)
			(xy 124.120929 -283.248058) (xy 124.082808 -283.216933) (xy 124.050173 -283.180096) (xy 124.02387 -283.1385)
			(xy 124.004579 -283.093224) (xy 123.992802 -283.04544) (xy 123.988842 -282.996386) (xy 123.670568 -282.996386)
			(xy 123.670056 -283.021832) (xy 123.661892 -283.072066) (xy 123.645776 -283.12034) (xy 123.622125 -283.165403)
			(xy 123.591552 -283.206089) (xy 123.554848 -283.241344) (xy 123.512964 -283.270254) (xy 123.466985 -283.292071)
			(xy 123.418101 -283.306231) (xy 123.36758 -283.312365) (xy 123.316728 -283.310316) (xy 123.266864 -283.300136)
			(xy 123.219278 -283.282089) (xy 123.175204 -283.256643) (xy 123.135782 -283.224456) (xy 123.102034 -283.186362)
			(xy 123.074833 -283.143348) (xy 123.054885 -283.096528) (xy 123.042706 -283.047114) (xy 123.038611 -282.996386)
			(xy 122.730514 -282.996386) (xy 122.730002 -283.021832) (xy 122.721838 -283.072066) (xy 122.705722 -283.12034)
			(xy 122.682071 -283.165403) (xy 122.651498 -283.206089) (xy 122.614794 -283.241344) (xy 122.57291 -283.270254)
			(xy 122.526931 -283.292071) (xy 122.478047 -283.306231) (xy 122.427526 -283.312365) (xy 122.376674 -283.310316)
			(xy 122.32681 -283.300136) (xy 122.279224 -283.282089) (xy 122.23515 -283.256643) (xy 122.195728 -283.224456)
			(xy 122.16198 -283.186362) (xy 122.134779 -283.143348) (xy 122.114831 -283.096528) (xy 122.102652 -283.047114)
			(xy 122.098557 -282.996386) (xy 121.780046 -282.996386) (xy 121.779551 -283.020993) (xy 121.771656 -283.06957)
			(xy 121.756072 -283.116251) (xy 121.733201 -283.159828) (xy 121.703636 -283.199172) (xy 121.668143 -283.233264)
			(xy 121.62764 -283.26122) (xy 121.583178 -283.282318) (xy 121.535907 -283.29601) (xy 121.487052 -283.301942)
			(xy 121.437877 -283.299961) (xy 121.389658 -283.290117) (xy 121.343642 -283.272665) (xy 121.301021 -283.248058)
			(xy 121.2629 -283.216933) (xy 121.230265 -283.180096) (xy 121.203962 -283.1385) (xy 121.184671 -283.093224)
			(xy 121.172894 -283.04544) (xy 121.168934 -282.996386) (xy 120.850406 -282.996386) (xy 120.849894 -283.021832)
			(xy 120.84173 -283.072066) (xy 120.825614 -283.12034) (xy 120.801963 -283.165403) (xy 120.77139 -283.206089)
			(xy 120.734686 -283.241344) (xy 120.692802 -283.270254) (xy 120.646823 -283.292071) (xy 120.597939 -283.306231)
			(xy 120.547418 -283.312365) (xy 120.496566 -283.310316) (xy 120.446702 -283.300136) (xy 120.399116 -283.282089)
			(xy 120.355042 -283.256643) (xy 120.31562 -283.224456) (xy 120.281872 -283.186362) (xy 120.254671 -283.143348)
			(xy 120.234723 -283.096528) (xy 120.222544 -283.047114) (xy 120.218449 -282.996386) (xy 119.910352 -282.996386)
			(xy 119.90984 -283.021832) (xy 119.901676 -283.072066) (xy 119.88556 -283.12034) (xy 119.861909 -283.165403)
			(xy 119.831336 -283.206089) (xy 119.794632 -283.241344) (xy 119.752748 -283.270254) (xy 119.706769 -283.292071)
			(xy 119.657885 -283.306231) (xy 119.607364 -283.312365) (xy 119.556512 -283.310316) (xy 119.506648 -283.300136)
			(xy 119.459062 -283.282089) (xy 119.414988 -283.256643) (xy 119.375566 -283.224456) (xy 119.341818 -283.186362)
			(xy 119.314617 -283.143348) (xy 119.294669 -283.096528) (xy 119.28249 -283.047114) (xy 119.278395 -282.996386)
			(xy 118.960138 -282.996386) (xy 118.959643 -283.020993) (xy 118.951748 -283.06957) (xy 118.936164 -283.116251)
			(xy 118.913293 -283.159828) (xy 118.883728 -283.199172) (xy 118.848235 -283.233264) (xy 118.807732 -283.26122)
			(xy 118.76327 -283.282318) (xy 118.715999 -283.29601) (xy 118.667144 -283.301942) (xy 118.617969 -283.299961)
			(xy 118.56975 -283.290117) (xy 118.523734 -283.272665) (xy 118.481113 -283.248058) (xy 118.442992 -283.216933)
			(xy 118.410357 -283.180096) (xy 118.384054 -283.1385) (xy 118.364763 -283.093224) (xy 118.352986 -283.04544)
			(xy 118.349026 -282.996386) (xy 118.030498 -282.996386) (xy 118.029986 -283.021832) (xy 118.021822 -283.072066)
			(xy 118.005706 -283.12034) (xy 117.982055 -283.165403) (xy 117.951482 -283.206089) (xy 117.914778 -283.241344)
			(xy 117.872894 -283.270254) (xy 117.826915 -283.292071) (xy 117.778031 -283.306231) (xy 117.72751 -283.312365)
			(xy 117.676658 -283.310316) (xy 117.626794 -283.300136) (xy 117.579208 -283.282089) (xy 117.535134 -283.256643)
			(xy 117.495712 -283.224456) (xy 117.461964 -283.186362) (xy 117.434763 -283.143348) (xy 117.414815 -283.096528)
			(xy 117.402636 -283.047114) (xy 117.398541 -282.996386) (xy 117.090444 -282.996386) (xy 117.089932 -283.021832)
			(xy 117.081768 -283.072066) (xy 117.065652 -283.12034) (xy 117.042001 -283.165403) (xy 117.011428 -283.206089)
			(xy 116.974724 -283.241344) (xy 116.93284 -283.270254) (xy 116.886861 -283.292071) (xy 116.837977 -283.306231)
			(xy 116.787456 -283.312365) (xy 116.736604 -283.310316) (xy 116.68674 -283.300136) (xy 116.639154 -283.282089)
			(xy 116.59508 -283.256643) (xy 116.555658 -283.224456) (xy 116.52191 -283.186362) (xy 116.494709 -283.143348)
			(xy 116.474761 -283.096528) (xy 116.462582 -283.047114) (xy 116.458487 -282.996386) (xy 116.139976 -282.996386)
			(xy 116.139481 -283.020993) (xy 116.131586 -283.06957) (xy 116.116002 -283.116251) (xy 116.093131 -283.159828)
			(xy 116.063566 -283.199172) (xy 116.028073 -283.233264) (xy 115.98757 -283.26122) (xy 115.943108 -283.282318)
			(xy 115.895837 -283.29601) (xy 115.846982 -283.301942) (xy 115.797807 -283.299961) (xy 115.749588 -283.290117)
			(xy 115.703572 -283.272665) (xy 115.660951 -283.248058) (xy 115.62283 -283.216933) (xy 115.590195 -283.180096)
			(xy 115.563892 -283.1385) (xy 115.544601 -283.093224) (xy 115.532824 -283.04544) (xy 115.528864 -282.996386)
			(xy 112.439282 -282.996386) (xy 112.452398 -283.806392) (xy 113.178856 -283.806392) (xy 113.182816 -283.757338)
			(xy 113.194593 -283.709554) (xy 113.213884 -283.664278) (xy 113.240187 -283.622682) (xy 113.272822 -283.585845)
			(xy 113.310943 -283.55472) (xy 113.353564 -283.530113) (xy 113.39958 -283.512661) (xy 113.447799 -283.502817)
			(xy 113.496974 -283.500836) (xy 113.545829 -283.506768) (xy 113.5931 -283.52046) (xy 113.637562 -283.541558)
			(xy 113.678065 -283.569514) (xy 113.713558 -283.603606) (xy 113.743123 -283.64295) (xy 113.765994 -283.686527)
			(xy 113.781578 -283.733208) (xy 113.789473 -283.781785) (xy 113.789968 -283.806392) (xy 114.108479 -283.806392)
			(xy 114.112574 -283.755664) (xy 114.124753 -283.70625) (xy 114.144701 -283.65943) (xy 114.171902 -283.616416)
			(xy 114.20565 -283.578322) (xy 114.245072 -283.546135) (xy 114.289146 -283.520689) (xy 114.336732 -283.502642)
			(xy 114.386596 -283.492462) (xy 114.437448 -283.490413) (xy 114.487969 -283.496547) (xy 114.536853 -283.510707)
			(xy 114.582832 -283.532524) (xy 114.624716 -283.561434) (xy 114.66142 -283.596689) (xy 114.691993 -283.637375)
			(xy 114.715644 -283.682438) (xy 114.73176 -283.730712) (xy 114.739924 -283.780946) (xy 114.740436 -283.806392)
			(xy 115.048533 -283.806392) (xy 115.052628 -283.755664) (xy 115.064807 -283.70625) (xy 115.084755 -283.65943)
			(xy 115.111956 -283.616416) (xy 115.145704 -283.578322) (xy 115.185126 -283.546135) (xy 115.2292 -283.520689)
			(xy 115.276786 -283.502642) (xy 115.32665 -283.492462) (xy 115.377502 -283.490413) (xy 115.428023 -283.496547)
			(xy 115.476907 -283.510707) (xy 115.522886 -283.532524) (xy 115.56477 -283.561434) (xy 115.601474 -283.596689)
			(xy 115.632047 -283.637375) (xy 115.655698 -283.682438) (xy 115.671814 -283.730712) (xy 115.679978 -283.780946)
			(xy 115.68049 -283.806392) (xy 115.999018 -283.806392) (xy 116.002978 -283.757338) (xy 116.014755 -283.709554)
			(xy 116.034046 -283.664278) (xy 116.060349 -283.622682) (xy 116.092984 -283.585845) (xy 116.131105 -283.55472)
			(xy 116.173726 -283.530113) (xy 116.219742 -283.512661) (xy 116.267961 -283.502817) (xy 116.317136 -283.500836)
			(xy 116.365991 -283.506768) (xy 116.413262 -283.52046) (xy 116.457724 -283.541558) (xy 116.498227 -283.569514)
			(xy 116.53372 -283.603606) (xy 116.563285 -283.64295) (xy 116.586156 -283.686527) (xy 116.60174 -283.733208)
			(xy 116.609635 -283.781785) (xy 116.61013 -283.806392) (xy 118.818926 -283.806392) (xy 118.822886 -283.757338)
			(xy 118.834663 -283.709554) (xy 118.853954 -283.664278) (xy 118.880257 -283.622682) (xy 118.912892 -283.585845)
			(xy 118.951013 -283.55472) (xy 118.993634 -283.530113) (xy 119.03965 -283.512661) (xy 119.087869 -283.502817)
			(xy 119.137044 -283.500836) (xy 119.185899 -283.506768) (xy 119.23317 -283.52046) (xy 119.277632 -283.541558)
			(xy 119.318135 -283.569514) (xy 119.353628 -283.603606) (xy 119.383193 -283.64295) (xy 119.406064 -283.686527)
			(xy 119.421648 -283.733208) (xy 119.429543 -283.781785) (xy 119.430038 -283.806392) (xy 121.638834 -283.806392)
			(xy 121.642794 -283.757338) (xy 121.654571 -283.709554) (xy 121.673862 -283.664278) (xy 121.700165 -283.622682)
			(xy 121.7328 -283.585845) (xy 121.770921 -283.55472) (xy 121.813542 -283.530113) (xy 121.859558 -283.512661)
			(xy 121.907777 -283.502817) (xy 121.956952 -283.500836) (xy 122.005807 -283.506768) (xy 122.053078 -283.52046)
			(xy 122.09754 -283.541558) (xy 122.138043 -283.569514) (xy 122.173536 -283.603606) (xy 122.203101 -283.64295)
			(xy 122.225972 -283.686527) (xy 122.241556 -283.733208) (xy 122.249451 -283.781785) (xy 122.249946 -283.806392)
			(xy 124.458996 -283.806392) (xy 124.462956 -283.757338) (xy 124.474733 -283.709554) (xy 124.494024 -283.664278)
			(xy 124.520327 -283.622682) (xy 124.552962 -283.585845) (xy 124.591083 -283.55472) (xy 124.633704 -283.530113)
			(xy 124.67972 -283.512661) (xy 124.727939 -283.502817) (xy 124.777114 -283.500836) (xy 124.825969 -283.506768)
			(xy 124.87324 -283.52046) (xy 124.917702 -283.541558) (xy 124.958205 -283.569514) (xy 124.993698 -283.603606)
			(xy 125.023263 -283.64295) (xy 125.046134 -283.686527) (xy 125.061718 -283.733208) (xy 125.069613 -283.781785)
			(xy 125.070108 -283.806392) (xy 125.069613 -283.830999) (xy 125.061718 -283.879576) (xy 125.046134 -283.926257)
			(xy 125.023263 -283.969834) (xy 124.993698 -284.009178) (xy 124.958205 -284.04327) (xy 124.917702 -284.071226)
			(xy 124.87324 -284.092324) (xy 124.825969 -284.106016) (xy 124.777114 -284.111948) (xy 124.727939 -284.109967)
			(xy 124.67972 -284.100123) (xy 124.633704 -284.082671) (xy 124.591083 -284.058064) (xy 124.552962 -284.026939)
			(xy 124.520327 -283.990102) (xy 124.494024 -283.948506) (xy 124.474733 -283.90323) (xy 124.462956 -283.855446)
			(xy 124.458996 -283.806392) (xy 122.249946 -283.806392) (xy 122.249451 -283.830999) (xy 122.241556 -283.879576)
			(xy 122.225972 -283.926257) (xy 122.203101 -283.969834) (xy 122.173536 -284.009178) (xy 122.138043 -284.04327)
			(xy 122.09754 -284.071226) (xy 122.053078 -284.092324) (xy 122.005807 -284.106016) (xy 121.956952 -284.111948)
			(xy 121.907777 -284.109967) (xy 121.859558 -284.100123) (xy 121.813542 -284.082671) (xy 121.770921 -284.058064)
			(xy 121.7328 -284.026939) (xy 121.700165 -283.990102) (xy 121.673862 -283.948506) (xy 121.654571 -283.90323)
			(xy 121.642794 -283.855446) (xy 121.638834 -283.806392) (xy 119.430038 -283.806392) (xy 119.429543 -283.830999)
			(xy 119.421648 -283.879576) (xy 119.406064 -283.926257) (xy 119.383193 -283.969834) (xy 119.353628 -284.009178)
			(xy 119.318135 -284.04327) (xy 119.277632 -284.071226) (xy 119.23317 -284.092324) (xy 119.185899 -284.106016)
			(xy 119.137044 -284.111948) (xy 119.087869 -284.109967) (xy 119.03965 -284.100123) (xy 118.993634 -284.082671)
			(xy 118.951013 -284.058064) (xy 118.912892 -284.026939) (xy 118.880257 -283.990102) (xy 118.853954 -283.948506)
			(xy 118.834663 -283.90323) (xy 118.822886 -283.855446) (xy 118.818926 -283.806392) (xy 116.61013 -283.806392)
			(xy 116.609635 -283.830999) (xy 116.60174 -283.879576) (xy 116.586156 -283.926257) (xy 116.563285 -283.969834)
			(xy 116.53372 -284.009178) (xy 116.498227 -284.04327) (xy 116.457724 -284.071226) (xy 116.413262 -284.092324)
			(xy 116.365991 -284.106016) (xy 116.317136 -284.111948) (xy 116.267961 -284.109967) (xy 116.219742 -284.100123)
			(xy 116.173726 -284.082671) (xy 116.131105 -284.058064) (xy 116.092984 -284.026939) (xy 116.060349 -283.990102)
			(xy 116.034046 -283.948506) (xy 116.014755 -283.90323) (xy 116.002978 -283.855446) (xy 115.999018 -283.806392)
			(xy 115.68049 -283.806392) (xy 115.679978 -283.831838) (xy 115.671814 -283.882072) (xy 115.655698 -283.930346)
			(xy 115.632047 -283.975409) (xy 115.601474 -284.016095) (xy 115.56477 -284.05135) (xy 115.522886 -284.08026)
			(xy 115.476907 -284.102077) (xy 115.428023 -284.116237) (xy 115.377502 -284.122371) (xy 115.32665 -284.120322)
			(xy 115.276786 -284.110142) (xy 115.2292 -284.092095) (xy 115.185126 -284.066649) (xy 115.145704 -284.034462)
			(xy 115.111956 -283.996368) (xy 115.084755 -283.953354) (xy 115.064807 -283.906534) (xy 115.052628 -283.85712)
			(xy 115.048533 -283.806392) (xy 114.740436 -283.806392) (xy 114.739924 -283.831838) (xy 114.73176 -283.882072)
			(xy 114.715644 -283.930346) (xy 114.691993 -283.975409) (xy 114.66142 -284.016095) (xy 114.624716 -284.05135)
			(xy 114.582832 -284.08026) (xy 114.536853 -284.102077) (xy 114.487969 -284.116237) (xy 114.437448 -284.122371)
			(xy 114.386596 -284.120322) (xy 114.336732 -284.110142) (xy 114.289146 -284.092095) (xy 114.245072 -284.066649)
			(xy 114.20565 -284.034462) (xy 114.171902 -283.996368) (xy 114.144701 -283.953354) (xy 114.124753 -283.906534)
			(xy 114.112574 -283.85712) (xy 114.108479 -283.806392) (xy 113.789968 -283.806392) (xy 113.789473 -283.830999)
			(xy 113.781578 -283.879576) (xy 113.765994 -283.926257) (xy 113.743123 -283.969834) (xy 113.713558 -284.009178)
			(xy 113.678065 -284.04327) (xy 113.637562 -284.071226) (xy 113.5931 -284.092324) (xy 113.545829 -284.106016)
			(xy 113.496974 -284.111948) (xy 113.447799 -284.109967) (xy 113.39958 -284.100123) (xy 113.353564 -284.082671)
			(xy 113.310943 -284.058064) (xy 113.272822 -284.026939) (xy 113.240187 -283.990102) (xy 113.213884 -283.948506)
			(xy 113.194593 -283.90323) (xy 113.182816 -283.855446) (xy 113.178856 -283.806392) (xy 112.452398 -283.806392)
			(xy 112.465514 -284.616398) (xy 113.64901 -284.616398) (xy 113.65297 -284.567344) (xy 113.664747 -284.51956)
			(xy 113.684038 -284.474284) (xy 113.710341 -284.432688) (xy 113.742976 -284.395851) (xy 113.781097 -284.364726)
			(xy 113.823718 -284.340119) (xy 113.869734 -284.322667) (xy 113.917953 -284.312823) (xy 113.967128 -284.310842)
			(xy 114.015983 -284.316774) (xy 114.063254 -284.330466) (xy 114.107716 -284.351564) (xy 114.148219 -284.37952)
			(xy 114.183712 -284.413612) (xy 114.213277 -284.452956) (xy 114.236148 -284.496533) (xy 114.251732 -284.543214)
			(xy 114.259627 -284.591791) (xy 114.260122 -284.616398) (xy 114.58881 -284.616398) (xy 114.59277 -284.567344)
			(xy 114.604547 -284.51956) (xy 114.623838 -284.474284) (xy 114.650141 -284.432688) (xy 114.682776 -284.395851)
			(xy 114.720897 -284.364726) (xy 114.763518 -284.340119) (xy 114.809534 -284.322667) (xy 114.857753 -284.312823)
			(xy 114.906928 -284.310842) (xy 114.955783 -284.316774) (xy 115.003054 -284.330466) (xy 115.047516 -284.351564)
			(xy 115.088019 -284.37952) (xy 115.123512 -284.413612) (xy 115.153077 -284.452956) (xy 115.175948 -284.496533)
			(xy 115.191532 -284.543214) (xy 115.199427 -284.591791) (xy 115.199922 -284.616398) (xy 115.528864 -284.616398)
			(xy 115.532824 -284.567344) (xy 115.544601 -284.51956) (xy 115.563892 -284.474284) (xy 115.590195 -284.432688)
			(xy 115.62283 -284.395851) (xy 115.660951 -284.364726) (xy 115.703572 -284.340119) (xy 115.749588 -284.322667)
			(xy 115.797807 -284.312823) (xy 115.846982 -284.310842) (xy 115.895837 -284.316774) (xy 115.943108 -284.330466)
			(xy 115.98757 -284.351564) (xy 116.028073 -284.37952) (xy 116.063566 -284.413612) (xy 116.093131 -284.452956)
			(xy 116.116002 -284.496533) (xy 116.131586 -284.543214) (xy 116.139481 -284.591791) (xy 116.139976 -284.616398)
			(xy 116.458487 -284.616398) (xy 116.462582 -284.56567) (xy 116.474761 -284.516256) (xy 116.494709 -284.469436)
			(xy 116.52191 -284.426422) (xy 116.555658 -284.388328) (xy 116.59508 -284.356141) (xy 116.639154 -284.330695)
			(xy 116.68674 -284.312648) (xy 116.736604 -284.302468) (xy 116.787456 -284.300419) (xy 116.837977 -284.306553)
			(xy 116.886861 -284.320713) (xy 116.93284 -284.34253) (xy 116.974724 -284.37144) (xy 117.011428 -284.406695)
			(xy 117.042001 -284.447381) (xy 117.065652 -284.492444) (xy 117.081768 -284.540718) (xy 117.089932 -284.590952)
			(xy 117.090444 -284.616398) (xy 117.398541 -284.616398) (xy 117.402636 -284.56567) (xy 117.414815 -284.516256)
			(xy 117.434763 -284.469436) (xy 117.461964 -284.426422) (xy 117.495712 -284.388328) (xy 117.535134 -284.356141)
			(xy 117.579208 -284.330695) (xy 117.626794 -284.312648) (xy 117.676658 -284.302468) (xy 117.72751 -284.300419)
			(xy 117.778031 -284.306553) (xy 117.826915 -284.320713) (xy 117.872894 -284.34253) (xy 117.914778 -284.37144)
			(xy 117.951482 -284.406695) (xy 117.982055 -284.447381) (xy 118.005706 -284.492444) (xy 118.021822 -284.540718)
			(xy 118.029986 -284.590952) (xy 118.030498 -284.616398) (xy 118.349026 -284.616398) (xy 118.352986 -284.567344)
			(xy 118.364763 -284.51956) (xy 118.384054 -284.474284) (xy 118.410357 -284.432688) (xy 118.442992 -284.395851)
			(xy 118.481113 -284.364726) (xy 118.523734 -284.340119) (xy 118.56975 -284.322667) (xy 118.617969 -284.312823)
			(xy 118.667144 -284.310842) (xy 118.715999 -284.316774) (xy 118.76327 -284.330466) (xy 118.807732 -284.351564)
			(xy 118.848235 -284.37952) (xy 118.883728 -284.413612) (xy 118.913293 -284.452956) (xy 118.936164 -284.496533)
			(xy 118.951748 -284.543214) (xy 118.959643 -284.591791) (xy 118.960138 -284.616398) (xy 119.278395 -284.616398)
			(xy 119.28249 -284.56567) (xy 119.294669 -284.516256) (xy 119.314617 -284.469436) (xy 119.341818 -284.426422)
			(xy 119.375566 -284.388328) (xy 119.414988 -284.356141) (xy 119.459062 -284.330695) (xy 119.506648 -284.312648)
			(xy 119.556512 -284.302468) (xy 119.607364 -284.300419) (xy 119.657885 -284.306553) (xy 119.706769 -284.320713)
			(xy 119.752748 -284.34253) (xy 119.794632 -284.37144) (xy 119.831336 -284.406695) (xy 119.861909 -284.447381)
			(xy 119.88556 -284.492444) (xy 119.901676 -284.540718) (xy 119.90984 -284.590952) (xy 119.910352 -284.616398)
			(xy 120.218449 -284.616398) (xy 120.222544 -284.56567) (xy 120.234723 -284.516256) (xy 120.254671 -284.469436)
			(xy 120.281872 -284.426422) (xy 120.31562 -284.388328) (xy 120.355042 -284.356141) (xy 120.399116 -284.330695)
			(xy 120.446702 -284.312648) (xy 120.496566 -284.302468) (xy 120.547418 -284.300419) (xy 120.597939 -284.306553)
			(xy 120.646823 -284.320713) (xy 120.692802 -284.34253) (xy 120.734686 -284.37144) (xy 120.77139 -284.406695)
			(xy 120.801963 -284.447381) (xy 120.825614 -284.492444) (xy 120.84173 -284.540718) (xy 120.849894 -284.590952)
			(xy 120.850406 -284.616398) (xy 121.168934 -284.616398) (xy 121.172894 -284.567344) (xy 121.184671 -284.51956)
			(xy 121.203962 -284.474284) (xy 121.230265 -284.432688) (xy 121.2629 -284.395851) (xy 121.301021 -284.364726)
			(xy 121.343642 -284.340119) (xy 121.389658 -284.322667) (xy 121.437877 -284.312823) (xy 121.487052 -284.310842)
			(xy 121.535907 -284.316774) (xy 121.583178 -284.330466) (xy 121.62764 -284.351564) (xy 121.668143 -284.37952)
			(xy 121.703636 -284.413612) (xy 121.733201 -284.452956) (xy 121.756072 -284.496533) (xy 121.771656 -284.543214)
			(xy 121.779551 -284.591791) (xy 121.780046 -284.616398) (xy 122.098557 -284.616398) (xy 122.102652 -284.56567)
			(xy 122.114831 -284.516256) (xy 122.134779 -284.469436) (xy 122.16198 -284.426422) (xy 122.195728 -284.388328)
			(xy 122.23515 -284.356141) (xy 122.279224 -284.330695) (xy 122.32681 -284.312648) (xy 122.376674 -284.302468)
			(xy 122.427526 -284.300419) (xy 122.478047 -284.306553) (xy 122.526931 -284.320713) (xy 122.57291 -284.34253)
			(xy 122.614794 -284.37144) (xy 122.651498 -284.406695) (xy 122.682071 -284.447381) (xy 122.705722 -284.492444)
			(xy 122.721838 -284.540718) (xy 122.730002 -284.590952) (xy 122.730514 -284.616398) (xy 123.038611 -284.616398)
			(xy 123.042706 -284.56567) (xy 123.054885 -284.516256) (xy 123.074833 -284.469436) (xy 123.102034 -284.426422)
			(xy 123.135782 -284.388328) (xy 123.175204 -284.356141) (xy 123.219278 -284.330695) (xy 123.266864 -284.312648)
			(xy 123.316728 -284.302468) (xy 123.36758 -284.300419) (xy 123.418101 -284.306553) (xy 123.466985 -284.320713)
			(xy 123.512964 -284.34253) (xy 123.554848 -284.37144) (xy 123.591552 -284.406695) (xy 123.622125 -284.447381)
			(xy 123.645776 -284.492444) (xy 123.661892 -284.540718) (xy 123.670056 -284.590952) (xy 123.670568 -284.616398)
			(xy 123.988842 -284.616398) (xy 123.992802 -284.567344) (xy 124.004579 -284.51956) (xy 124.02387 -284.474284)
			(xy 124.050173 -284.432688) (xy 124.082808 -284.395851) (xy 124.120929 -284.364726) (xy 124.16355 -284.340119)
			(xy 124.209566 -284.322667) (xy 124.257785 -284.312823) (xy 124.30696 -284.310842) (xy 124.355815 -284.316774)
			(xy 124.403086 -284.330466) (xy 124.447548 -284.351564) (xy 124.488051 -284.37952) (xy 124.523544 -284.413612)
			(xy 124.553109 -284.452956) (xy 124.57598 -284.496533) (xy 124.591564 -284.543214) (xy 124.599459 -284.591791)
			(xy 124.599954 -284.616398) (xy 124.918465 -284.616398) (xy 124.92256 -284.56567) (xy 124.934739 -284.516256)
			(xy 124.954687 -284.469436) (xy 124.981888 -284.426422) (xy 125.015636 -284.388328) (xy 125.055058 -284.356141)
			(xy 125.099132 -284.330695) (xy 125.146718 -284.312648) (xy 125.196582 -284.302468) (xy 125.247434 -284.300419)
			(xy 125.297955 -284.306553) (xy 125.346839 -284.320713) (xy 125.392818 -284.34253) (xy 125.434702 -284.37144)
			(xy 125.471406 -284.406695) (xy 125.501979 -284.447381) (xy 125.52563 -284.492444) (xy 125.541746 -284.540718)
			(xy 125.54991 -284.590952) (xy 125.550422 -284.616398) (xy 125.858519 -284.616398) (xy 125.862614 -284.56567)
			(xy 125.874793 -284.516256) (xy 125.894741 -284.469436) (xy 125.921942 -284.426422) (xy 125.95569 -284.388328)
			(xy 125.995112 -284.356141) (xy 126.039186 -284.330695) (xy 126.086772 -284.312648) (xy 126.136636 -284.302468)
			(xy 126.187488 -284.300419) (xy 126.238009 -284.306553) (xy 126.286893 -284.320713) (xy 126.332872 -284.34253)
			(xy 126.374756 -284.37144) (xy 126.41146 -284.406695) (xy 126.442033 -284.447381) (xy 126.465684 -284.492444)
			(xy 126.4818 -284.540718) (xy 126.489964 -284.590952) (xy 126.490476 -284.616398) (xy 126.489964 -284.641844)
			(xy 126.4818 -284.692078) (xy 126.465684 -284.740352) (xy 126.442033 -284.785415) (xy 126.41146 -284.826101)
			(xy 126.374756 -284.861356) (xy 126.332872 -284.890266) (xy 126.286893 -284.912083) (xy 126.238009 -284.926243)
			(xy 126.187488 -284.932377) (xy 126.136636 -284.930328) (xy 126.086772 -284.920148) (xy 126.039186 -284.902101)
			(xy 125.995112 -284.876655) (xy 125.95569 -284.844468) (xy 125.921942 -284.806374) (xy 125.894741 -284.76336)
			(xy 125.874793 -284.71654) (xy 125.862614 -284.667126) (xy 125.858519 -284.616398) (xy 125.550422 -284.616398)
			(xy 125.54991 -284.641844) (xy 125.541746 -284.692078) (xy 125.52563 -284.740352) (xy 125.501979 -284.785415)
			(xy 125.471406 -284.826101) (xy 125.434702 -284.861356) (xy 125.392818 -284.890266) (xy 125.346839 -284.912083)
			(xy 125.297955 -284.926243) (xy 125.247434 -284.932377) (xy 125.196582 -284.930328) (xy 125.146718 -284.920148)
			(xy 125.099132 -284.902101) (xy 125.055058 -284.876655) (xy 125.015636 -284.844468) (xy 124.981888 -284.806374)
			(xy 124.954687 -284.76336) (xy 124.934739 -284.71654) (xy 124.92256 -284.667126) (xy 124.918465 -284.616398)
			(xy 124.599954 -284.616398) (xy 124.599459 -284.641005) (xy 124.591564 -284.689582) (xy 124.57598 -284.736263)
			(xy 124.553109 -284.77984) (xy 124.523544 -284.819184) (xy 124.488051 -284.853276) (xy 124.447548 -284.881232)
			(xy 124.403086 -284.90233) (xy 124.355815 -284.916022) (xy 124.30696 -284.921954) (xy 124.257785 -284.919973)
			(xy 124.209566 -284.910129) (xy 124.16355 -284.892677) (xy 124.120929 -284.86807) (xy 124.082808 -284.836945)
			(xy 124.050173 -284.800108) (xy 124.02387 -284.758512) (xy 124.004579 -284.713236) (xy 123.992802 -284.665452)
			(xy 123.988842 -284.616398) (xy 123.670568 -284.616398) (xy 123.670056 -284.641844) (xy 123.661892 -284.692078)
			(xy 123.645776 -284.740352) (xy 123.622125 -284.785415) (xy 123.591552 -284.826101) (xy 123.554848 -284.861356)
			(xy 123.512964 -284.890266) (xy 123.466985 -284.912083) (xy 123.418101 -284.926243) (xy 123.36758 -284.932377)
			(xy 123.316728 -284.930328) (xy 123.266864 -284.920148) (xy 123.219278 -284.902101) (xy 123.175204 -284.876655)
			(xy 123.135782 -284.844468) (xy 123.102034 -284.806374) (xy 123.074833 -284.76336) (xy 123.054885 -284.71654)
			(xy 123.042706 -284.667126) (xy 123.038611 -284.616398) (xy 122.730514 -284.616398) (xy 122.730002 -284.641844)
			(xy 122.721838 -284.692078) (xy 122.705722 -284.740352) (xy 122.682071 -284.785415) (xy 122.651498 -284.826101)
			(xy 122.614794 -284.861356) (xy 122.57291 -284.890266) (xy 122.526931 -284.912083) (xy 122.478047 -284.926243)
			(xy 122.427526 -284.932377) (xy 122.376674 -284.930328) (xy 122.32681 -284.920148) (xy 122.279224 -284.902101)
			(xy 122.23515 -284.876655) (xy 122.195728 -284.844468) (xy 122.16198 -284.806374) (xy 122.134779 -284.76336)
			(xy 122.114831 -284.71654) (xy 122.102652 -284.667126) (xy 122.098557 -284.616398) (xy 121.780046 -284.616398)
			(xy 121.779551 -284.641005) (xy 121.771656 -284.689582) (xy 121.756072 -284.736263) (xy 121.733201 -284.77984)
			(xy 121.703636 -284.819184) (xy 121.668143 -284.853276) (xy 121.62764 -284.881232) (xy 121.583178 -284.90233)
			(xy 121.535907 -284.916022) (xy 121.487052 -284.921954) (xy 121.437877 -284.919973) (xy 121.389658 -284.910129)
			(xy 121.343642 -284.892677) (xy 121.301021 -284.86807) (xy 121.2629 -284.836945) (xy 121.230265 -284.800108)
			(xy 121.203962 -284.758512) (xy 121.184671 -284.713236) (xy 121.172894 -284.665452) (xy 121.168934 -284.616398)
			(xy 120.850406 -284.616398) (xy 120.849894 -284.641844) (xy 120.84173 -284.692078) (xy 120.825614 -284.740352)
			(xy 120.801963 -284.785415) (xy 120.77139 -284.826101) (xy 120.734686 -284.861356) (xy 120.692802 -284.890266)
			(xy 120.646823 -284.912083) (xy 120.597939 -284.926243) (xy 120.547418 -284.932377) (xy 120.496566 -284.930328)
			(xy 120.446702 -284.920148) (xy 120.399116 -284.902101) (xy 120.355042 -284.876655) (xy 120.31562 -284.844468)
			(xy 120.281872 -284.806374) (xy 120.254671 -284.76336) (xy 120.234723 -284.71654) (xy 120.222544 -284.667126)
			(xy 120.218449 -284.616398) (xy 119.910352 -284.616398) (xy 119.90984 -284.641844) (xy 119.901676 -284.692078)
			(xy 119.88556 -284.740352) (xy 119.861909 -284.785415) (xy 119.831336 -284.826101) (xy 119.794632 -284.861356)
			(xy 119.752748 -284.890266) (xy 119.706769 -284.912083) (xy 119.657885 -284.926243) (xy 119.607364 -284.932377)
			(xy 119.556512 -284.930328) (xy 119.506648 -284.920148) (xy 119.459062 -284.902101) (xy 119.414988 -284.876655)
			(xy 119.375566 -284.844468) (xy 119.341818 -284.806374) (xy 119.314617 -284.76336) (xy 119.294669 -284.71654)
			(xy 119.28249 -284.667126) (xy 119.278395 -284.616398) (xy 118.960138 -284.616398) (xy 118.959643 -284.641005)
			(xy 118.951748 -284.689582) (xy 118.936164 -284.736263) (xy 118.913293 -284.77984) (xy 118.883728 -284.819184)
			(xy 118.848235 -284.853276) (xy 118.807732 -284.881232) (xy 118.76327 -284.90233) (xy 118.715999 -284.916022)
			(xy 118.667144 -284.921954) (xy 118.617969 -284.919973) (xy 118.56975 -284.910129) (xy 118.523734 -284.892677)
			(xy 118.481113 -284.86807) (xy 118.442992 -284.836945) (xy 118.410357 -284.800108) (xy 118.384054 -284.758512)
			(xy 118.364763 -284.713236) (xy 118.352986 -284.665452) (xy 118.349026 -284.616398) (xy 118.030498 -284.616398)
			(xy 118.029986 -284.641844) (xy 118.021822 -284.692078) (xy 118.005706 -284.740352) (xy 117.982055 -284.785415)
			(xy 117.951482 -284.826101) (xy 117.914778 -284.861356) (xy 117.872894 -284.890266) (xy 117.826915 -284.912083)
			(xy 117.778031 -284.926243) (xy 117.72751 -284.932377) (xy 117.676658 -284.930328) (xy 117.626794 -284.920148)
			(xy 117.579208 -284.902101) (xy 117.535134 -284.876655) (xy 117.495712 -284.844468) (xy 117.461964 -284.806374)
			(xy 117.434763 -284.76336) (xy 117.414815 -284.71654) (xy 117.402636 -284.667126) (xy 117.398541 -284.616398)
			(xy 117.090444 -284.616398) (xy 117.089932 -284.641844) (xy 117.081768 -284.692078) (xy 117.065652 -284.740352)
			(xy 117.042001 -284.785415) (xy 117.011428 -284.826101) (xy 116.974724 -284.861356) (xy 116.93284 -284.890266)
			(xy 116.886861 -284.912083) (xy 116.837977 -284.926243) (xy 116.787456 -284.932377) (xy 116.736604 -284.930328)
			(xy 116.68674 -284.920148) (xy 116.639154 -284.902101) (xy 116.59508 -284.876655) (xy 116.555658 -284.844468)
			(xy 116.52191 -284.806374) (xy 116.494709 -284.76336) (xy 116.474761 -284.71654) (xy 116.462582 -284.667126)
			(xy 116.458487 -284.616398) (xy 116.139976 -284.616398) (xy 116.139481 -284.641005) (xy 116.131586 -284.689582)
			(xy 116.116002 -284.736263) (xy 116.093131 -284.77984) (xy 116.063566 -284.819184) (xy 116.028073 -284.853276)
			(xy 115.98757 -284.881232) (xy 115.943108 -284.90233) (xy 115.895837 -284.916022) (xy 115.846982 -284.921954)
			(xy 115.797807 -284.919973) (xy 115.749588 -284.910129) (xy 115.703572 -284.892677) (xy 115.660951 -284.86807)
			(xy 115.62283 -284.836945) (xy 115.590195 -284.800108) (xy 115.563892 -284.758512) (xy 115.544601 -284.713236)
			(xy 115.532824 -284.665452) (xy 115.528864 -284.616398) (xy 115.199922 -284.616398) (xy 115.199427 -284.641005)
			(xy 115.191532 -284.689582) (xy 115.175948 -284.736263) (xy 115.153077 -284.77984) (xy 115.123512 -284.819184)
			(xy 115.088019 -284.853276) (xy 115.047516 -284.881232) (xy 115.003054 -284.90233) (xy 114.955783 -284.916022)
			(xy 114.906928 -284.921954) (xy 114.857753 -284.919973) (xy 114.809534 -284.910129) (xy 114.763518 -284.892677)
			(xy 114.720897 -284.86807) (xy 114.682776 -284.836945) (xy 114.650141 -284.800108) (xy 114.623838 -284.758512)
			(xy 114.604547 -284.713236) (xy 114.59277 -284.665452) (xy 114.58881 -284.616398) (xy 114.260122 -284.616398)
			(xy 114.259627 -284.641005) (xy 114.251732 -284.689582) (xy 114.236148 -284.736263) (xy 114.213277 -284.77984)
			(xy 114.183712 -284.819184) (xy 114.148219 -284.853276) (xy 114.107716 -284.881232) (xy 114.063254 -284.90233)
			(xy 114.015983 -284.916022) (xy 113.967128 -284.921954) (xy 113.917953 -284.919973) (xy 113.869734 -284.910129)
			(xy 113.823718 -284.892677) (xy 113.781097 -284.86807) (xy 113.742976 -284.836945) (xy 113.710341 -284.800108)
			(xy 113.684038 -284.758512) (xy 113.664747 -284.713236) (xy 113.65297 -284.665452) (xy 113.64901 -284.616398)
			(xy 112.465514 -284.616398) (xy 112.47863 -285.426404) (xy 113.178856 -285.426404) (xy 113.182816 -285.37735)
			(xy 113.194593 -285.329566) (xy 113.213884 -285.28429) (xy 113.240187 -285.242694) (xy 113.272822 -285.205857)
			(xy 113.310943 -285.174732) (xy 113.353564 -285.150125) (xy 113.39958 -285.132673) (xy 113.447799 -285.122829)
			(xy 113.496974 -285.120848) (xy 113.545829 -285.12678) (xy 113.5931 -285.140472) (xy 113.637562 -285.16157)
			(xy 113.678065 -285.189526) (xy 113.713558 -285.223618) (xy 113.743123 -285.262962) (xy 113.765994 -285.306539)
			(xy 113.781578 -285.35322) (xy 113.789473 -285.401797) (xy 113.789968 -285.426404) (xy 114.108479 -285.426404)
			(xy 114.112574 -285.375676) (xy 114.124753 -285.326262) (xy 114.144701 -285.279442) (xy 114.171902 -285.236428)
			(xy 114.20565 -285.198334) (xy 114.245072 -285.166147) (xy 114.289146 -285.140701) (xy 114.336732 -285.122654)
			(xy 114.386596 -285.112474) (xy 114.437448 -285.110425) (xy 114.487969 -285.116559) (xy 114.536853 -285.130719)
			(xy 114.582832 -285.152536) (xy 114.624716 -285.181446) (xy 114.66142 -285.216701) (xy 114.691993 -285.257387)
			(xy 114.715644 -285.30245) (xy 114.73176 -285.350724) (xy 114.739924 -285.400958) (xy 114.740436 -285.426404)
			(xy 115.048533 -285.426404) (xy 115.052628 -285.375676) (xy 115.064807 -285.326262) (xy 115.084755 -285.279442)
			(xy 115.111956 -285.236428) (xy 115.145704 -285.198334) (xy 115.185126 -285.166147) (xy 115.2292 -285.140701)
			(xy 115.276786 -285.122654) (xy 115.32665 -285.112474) (xy 115.377502 -285.110425) (xy 115.428023 -285.116559)
			(xy 115.476907 -285.130719) (xy 115.522886 -285.152536) (xy 115.56477 -285.181446) (xy 115.601474 -285.216701)
			(xy 115.632047 -285.257387) (xy 115.655698 -285.30245) (xy 115.671814 -285.350724) (xy 115.679978 -285.400958)
			(xy 115.68049 -285.426404) (xy 115.999018 -285.426404) (xy 116.002978 -285.37735) (xy 116.014755 -285.329566)
			(xy 116.034046 -285.28429) (xy 116.060349 -285.242694) (xy 116.092984 -285.205857) (xy 116.131105 -285.174732)
			(xy 116.173726 -285.150125) (xy 116.219742 -285.132673) (xy 116.267961 -285.122829) (xy 116.317136 -285.120848)
			(xy 116.365991 -285.12678) (xy 116.413262 -285.140472) (xy 116.457724 -285.16157) (xy 116.498227 -285.189526)
			(xy 116.53372 -285.223618) (xy 116.563285 -285.262962) (xy 116.586156 -285.306539) (xy 116.60174 -285.35322)
			(xy 116.609635 -285.401797) (xy 116.61013 -285.426404) (xy 116.938818 -285.426404) (xy 116.942778 -285.37735)
			(xy 116.954555 -285.329566) (xy 116.973846 -285.28429) (xy 117.000149 -285.242694) (xy 117.032784 -285.205857)
			(xy 117.070905 -285.174732) (xy 117.113526 -285.150125) (xy 117.159542 -285.132673) (xy 117.207761 -285.122829)
			(xy 117.256936 -285.120848) (xy 117.305791 -285.12678) (xy 117.353062 -285.140472) (xy 117.397524 -285.16157)
			(xy 117.438027 -285.189526) (xy 117.47352 -285.223618) (xy 117.503085 -285.262962) (xy 117.525956 -285.306539)
			(xy 117.54154 -285.35322) (xy 117.549435 -285.401797) (xy 117.54993 -285.426404) (xy 117.878872 -285.426404)
			(xy 117.882832 -285.37735) (xy 117.894609 -285.329566) (xy 117.9139 -285.28429) (xy 117.940203 -285.242694)
			(xy 117.972838 -285.205857) (xy 118.010959 -285.174732) (xy 118.05358 -285.150125) (xy 118.099596 -285.132673)
			(xy 118.147815 -285.122829) (xy 118.19699 -285.120848) (xy 118.245845 -285.12678) (xy 118.293116 -285.140472)
			(xy 118.337578 -285.16157) (xy 118.378081 -285.189526) (xy 118.413574 -285.223618) (xy 118.443139 -285.262962)
			(xy 118.46601 -285.306539) (xy 118.481594 -285.35322) (xy 118.489489 -285.401797) (xy 118.489984 -285.426404)
			(xy 118.818926 -285.426404) (xy 118.822886 -285.37735) (xy 118.834663 -285.329566) (xy 118.853954 -285.28429)
			(xy 118.880257 -285.242694) (xy 118.912892 -285.205857) (xy 118.951013 -285.174732) (xy 118.993634 -285.150125)
			(xy 119.03965 -285.132673) (xy 119.087869 -285.122829) (xy 119.137044 -285.120848) (xy 119.185899 -285.12678)
			(xy 119.23317 -285.140472) (xy 119.277632 -285.16157) (xy 119.318135 -285.189526) (xy 119.353628 -285.223618)
			(xy 119.383193 -285.262962) (xy 119.406064 -285.306539) (xy 119.421648 -285.35322) (xy 119.429543 -285.401797)
			(xy 119.430038 -285.426404) (xy 119.75898 -285.426404) (xy 119.76294 -285.37735) (xy 119.774717 -285.329566)
			(xy 119.794008 -285.28429) (xy 119.820311 -285.242694) (xy 119.852946 -285.205857) (xy 119.891067 -285.174732)
			(xy 119.933688 -285.150125) (xy 119.979704 -285.132673) (xy 120.027923 -285.122829) (xy 120.077098 -285.120848)
			(xy 120.125953 -285.12678) (xy 120.173224 -285.140472) (xy 120.217686 -285.16157) (xy 120.258189 -285.189526)
			(xy 120.293682 -285.223618) (xy 120.323247 -285.262962) (xy 120.346118 -285.306539) (xy 120.361702 -285.35322)
			(xy 120.369597 -285.401797) (xy 120.370092 -285.426404) (xy 120.699034 -285.426404) (xy 120.702994 -285.37735)
			(xy 120.714771 -285.329566) (xy 120.734062 -285.28429) (xy 120.760365 -285.242694) (xy 120.793 -285.205857)
			(xy 120.831121 -285.174732) (xy 120.873742 -285.150125) (xy 120.919758 -285.132673) (xy 120.967977 -285.122829)
			(xy 121.017152 -285.120848) (xy 121.066007 -285.12678) (xy 121.113278 -285.140472) (xy 121.15774 -285.16157)
			(xy 121.198243 -285.189526) (xy 121.233736 -285.223618) (xy 121.263301 -285.262962) (xy 121.286172 -285.306539)
			(xy 121.301756 -285.35322) (xy 121.309651 -285.401797) (xy 121.310146 -285.426404) (xy 121.638834 -285.426404)
			(xy 121.642794 -285.37735) (xy 121.654571 -285.329566) (xy 121.673862 -285.28429) (xy 121.700165 -285.242694)
			(xy 121.7328 -285.205857) (xy 121.770921 -285.174732) (xy 121.813542 -285.150125) (xy 121.859558 -285.132673)
			(xy 121.907777 -285.122829) (xy 121.956952 -285.120848) (xy 122.005807 -285.12678) (xy 122.053078 -285.140472)
			(xy 122.09754 -285.16157) (xy 122.138043 -285.189526) (xy 122.173536 -285.223618) (xy 122.203101 -285.262962)
			(xy 122.225972 -285.306539) (xy 122.241556 -285.35322) (xy 122.249451 -285.401797) (xy 122.249946 -285.426404)
			(xy 122.578888 -285.426404) (xy 122.582848 -285.37735) (xy 122.594625 -285.329566) (xy 122.613916 -285.28429)
			(xy 122.640219 -285.242694) (xy 122.672854 -285.205857) (xy 122.710975 -285.174732) (xy 122.753596 -285.150125)
			(xy 122.799612 -285.132673) (xy 122.847831 -285.122829) (xy 122.897006 -285.120848) (xy 122.945861 -285.12678)
			(xy 122.993132 -285.140472) (xy 123.037594 -285.16157) (xy 123.078097 -285.189526) (xy 123.11359 -285.223618)
			(xy 123.143155 -285.262962) (xy 123.166026 -285.306539) (xy 123.18161 -285.35322) (xy 123.189505 -285.401797)
			(xy 123.19 -285.426404) (xy 123.518942 -285.426404) (xy 123.522902 -285.37735) (xy 123.534679 -285.329566)
			(xy 123.55397 -285.28429) (xy 123.580273 -285.242694) (xy 123.612908 -285.205857) (xy 123.651029 -285.174732)
			(xy 123.69365 -285.150125) (xy 123.739666 -285.132673) (xy 123.787885 -285.122829) (xy 123.83706 -285.120848)
			(xy 123.885915 -285.12678) (xy 123.933186 -285.140472) (xy 123.977648 -285.16157) (xy 124.018151 -285.189526)
			(xy 124.053644 -285.223618) (xy 124.083209 -285.262962) (xy 124.10608 -285.306539) (xy 124.121664 -285.35322)
			(xy 124.129559 -285.401797) (xy 124.130054 -285.426404) (xy 124.458996 -285.426404) (xy 124.462956 -285.37735)
			(xy 124.474733 -285.329566) (xy 124.494024 -285.28429) (xy 124.520327 -285.242694) (xy 124.552962 -285.205857)
			(xy 124.591083 -285.174732) (xy 124.633704 -285.150125) (xy 124.67972 -285.132673) (xy 124.727939 -285.122829)
			(xy 124.777114 -285.120848) (xy 124.825969 -285.12678) (xy 124.87324 -285.140472) (xy 124.917702 -285.16157)
			(xy 124.958205 -285.189526) (xy 124.993698 -285.223618) (xy 125.023263 -285.262962) (xy 125.046134 -285.306539)
			(xy 125.061718 -285.35322) (xy 125.069613 -285.401797) (xy 125.070108 -285.426404) (xy 125.39905 -285.426404)
			(xy 125.40301 -285.37735) (xy 125.414787 -285.329566) (xy 125.434078 -285.28429) (xy 125.460381 -285.242694)
			(xy 125.493016 -285.205857) (xy 125.531137 -285.174732) (xy 125.573758 -285.150125) (xy 125.619774 -285.132673)
			(xy 125.667993 -285.122829) (xy 125.717168 -285.120848) (xy 125.766023 -285.12678) (xy 125.813294 -285.140472)
			(xy 125.857756 -285.16157) (xy 125.898259 -285.189526) (xy 125.933752 -285.223618) (xy 125.963317 -285.262962)
			(xy 125.986188 -285.306539) (xy 126.001772 -285.35322) (xy 126.009667 -285.401797) (xy 126.010162 -285.426404)
			(xy 126.009667 -285.451011) (xy 126.001772 -285.499588) (xy 125.986188 -285.546269) (xy 125.963317 -285.589846)
			(xy 125.933752 -285.62919) (xy 125.898259 -285.663282) (xy 125.857756 -285.691238) (xy 125.813294 -285.712336)
			(xy 125.766023 -285.726028) (xy 125.717168 -285.73196) (xy 125.667993 -285.729979) (xy 125.619774 -285.720135)
			(xy 125.573758 -285.702683) (xy 125.531137 -285.678076) (xy 125.493016 -285.646951) (xy 125.460381 -285.610114)
			(xy 125.434078 -285.568518) (xy 125.414787 -285.523242) (xy 125.40301 -285.475458) (xy 125.39905 -285.426404)
			(xy 125.070108 -285.426404) (xy 125.069613 -285.451011) (xy 125.061718 -285.499588) (xy 125.046134 -285.546269)
			(xy 125.023263 -285.589846) (xy 124.993698 -285.62919) (xy 124.958205 -285.663282) (xy 124.917702 -285.691238)
			(xy 124.87324 -285.712336) (xy 124.825969 -285.726028) (xy 124.777114 -285.73196) (xy 124.727939 -285.729979)
			(xy 124.67972 -285.720135) (xy 124.633704 -285.702683) (xy 124.591083 -285.678076) (xy 124.552962 -285.646951)
			(xy 124.520327 -285.610114) (xy 124.494024 -285.568518) (xy 124.474733 -285.523242) (xy 124.462956 -285.475458)
			(xy 124.458996 -285.426404) (xy 124.130054 -285.426404) (xy 124.129559 -285.451011) (xy 124.121664 -285.499588)
			(xy 124.10608 -285.546269) (xy 124.083209 -285.589846) (xy 124.053644 -285.62919) (xy 124.018151 -285.663282)
			(xy 123.977648 -285.691238) (xy 123.933186 -285.712336) (xy 123.885915 -285.726028) (xy 123.83706 -285.73196)
			(xy 123.787885 -285.729979) (xy 123.739666 -285.720135) (xy 123.69365 -285.702683) (xy 123.651029 -285.678076)
			(xy 123.612908 -285.646951) (xy 123.580273 -285.610114) (xy 123.55397 -285.568518) (xy 123.534679 -285.523242)
			(xy 123.522902 -285.475458) (xy 123.518942 -285.426404) (xy 123.19 -285.426404) (xy 123.189505 -285.451011)
			(xy 123.18161 -285.499588) (xy 123.166026 -285.546269) (xy 123.143155 -285.589846) (xy 123.11359 -285.62919)
			(xy 123.078097 -285.663282) (xy 123.037594 -285.691238) (xy 122.993132 -285.712336) (xy 122.945861 -285.726028)
			(xy 122.897006 -285.73196) (xy 122.847831 -285.729979) (xy 122.799612 -285.720135) (xy 122.753596 -285.702683)
			(xy 122.710975 -285.678076) (xy 122.672854 -285.646951) (xy 122.640219 -285.610114) (xy 122.613916 -285.568518)
			(xy 122.594625 -285.523242) (xy 122.582848 -285.475458) (xy 122.578888 -285.426404) (xy 122.249946 -285.426404)
			(xy 122.249451 -285.451011) (xy 122.241556 -285.499588) (xy 122.225972 -285.546269) (xy 122.203101 -285.589846)
			(xy 122.173536 -285.62919) (xy 122.138043 -285.663282) (xy 122.09754 -285.691238) (xy 122.053078 -285.712336)
			(xy 122.005807 -285.726028) (xy 121.956952 -285.73196) (xy 121.907777 -285.729979) (xy 121.859558 -285.720135)
			(xy 121.813542 -285.702683) (xy 121.770921 -285.678076) (xy 121.7328 -285.646951) (xy 121.700165 -285.610114)
			(xy 121.673862 -285.568518) (xy 121.654571 -285.523242) (xy 121.642794 -285.475458) (xy 121.638834 -285.426404)
			(xy 121.310146 -285.426404) (xy 121.309651 -285.451011) (xy 121.301756 -285.499588) (xy 121.286172 -285.546269)
			(xy 121.263301 -285.589846) (xy 121.233736 -285.62919) (xy 121.198243 -285.663282) (xy 121.15774 -285.691238)
			(xy 121.113278 -285.712336) (xy 121.066007 -285.726028) (xy 121.017152 -285.73196) (xy 120.967977 -285.729979)
			(xy 120.919758 -285.720135) (xy 120.873742 -285.702683) (xy 120.831121 -285.678076) (xy 120.793 -285.646951)
			(xy 120.760365 -285.610114) (xy 120.734062 -285.568518) (xy 120.714771 -285.523242) (xy 120.702994 -285.475458)
			(xy 120.699034 -285.426404) (xy 120.370092 -285.426404) (xy 120.369597 -285.451011) (xy 120.361702 -285.499588)
			(xy 120.346118 -285.546269) (xy 120.323247 -285.589846) (xy 120.293682 -285.62919) (xy 120.258189 -285.663282)
			(xy 120.217686 -285.691238) (xy 120.173224 -285.712336) (xy 120.125953 -285.726028) (xy 120.077098 -285.73196)
			(xy 120.027923 -285.729979) (xy 119.979704 -285.720135) (xy 119.933688 -285.702683) (xy 119.891067 -285.678076)
			(xy 119.852946 -285.646951) (xy 119.820311 -285.610114) (xy 119.794008 -285.568518) (xy 119.774717 -285.523242)
			(xy 119.76294 -285.475458) (xy 119.75898 -285.426404) (xy 119.430038 -285.426404) (xy 119.429543 -285.451011)
			(xy 119.421648 -285.499588) (xy 119.406064 -285.546269) (xy 119.383193 -285.589846) (xy 119.353628 -285.62919)
			(xy 119.318135 -285.663282) (xy 119.277632 -285.691238) (xy 119.23317 -285.712336) (xy 119.185899 -285.726028)
			(xy 119.137044 -285.73196) (xy 119.087869 -285.729979) (xy 119.03965 -285.720135) (xy 118.993634 -285.702683)
			(xy 118.951013 -285.678076) (xy 118.912892 -285.646951) (xy 118.880257 -285.610114) (xy 118.853954 -285.568518)
			(xy 118.834663 -285.523242) (xy 118.822886 -285.475458) (xy 118.818926 -285.426404) (xy 118.489984 -285.426404)
			(xy 118.489489 -285.451011) (xy 118.481594 -285.499588) (xy 118.46601 -285.546269) (xy 118.443139 -285.589846)
			(xy 118.413574 -285.62919) (xy 118.378081 -285.663282) (xy 118.337578 -285.691238) (xy 118.293116 -285.712336)
			(xy 118.245845 -285.726028) (xy 118.19699 -285.73196) (xy 118.147815 -285.729979) (xy 118.099596 -285.720135)
			(xy 118.05358 -285.702683) (xy 118.010959 -285.678076) (xy 117.972838 -285.646951) (xy 117.940203 -285.610114)
			(xy 117.9139 -285.568518) (xy 117.894609 -285.523242) (xy 117.882832 -285.475458) (xy 117.878872 -285.426404)
			(xy 117.54993 -285.426404) (xy 117.549435 -285.451011) (xy 117.54154 -285.499588) (xy 117.525956 -285.546269)
			(xy 117.503085 -285.589846) (xy 117.47352 -285.62919) (xy 117.438027 -285.663282) (xy 117.397524 -285.691238)
			(xy 117.353062 -285.712336) (xy 117.305791 -285.726028) (xy 117.256936 -285.73196) (xy 117.207761 -285.729979)
			(xy 117.159542 -285.720135) (xy 117.113526 -285.702683) (xy 117.070905 -285.678076) (xy 117.032784 -285.646951)
			(xy 117.000149 -285.610114) (xy 116.973846 -285.568518) (xy 116.954555 -285.523242) (xy 116.942778 -285.475458)
			(xy 116.938818 -285.426404) (xy 116.61013 -285.426404) (xy 116.609635 -285.451011) (xy 116.60174 -285.499588)
			(xy 116.586156 -285.546269) (xy 116.563285 -285.589846) (xy 116.53372 -285.62919) (xy 116.498227 -285.663282)
			(xy 116.457724 -285.691238) (xy 116.413262 -285.712336) (xy 116.365991 -285.726028) (xy 116.317136 -285.73196)
			(xy 116.267961 -285.729979) (xy 116.219742 -285.720135) (xy 116.173726 -285.702683) (xy 116.131105 -285.678076)
			(xy 116.092984 -285.646951) (xy 116.060349 -285.610114) (xy 116.034046 -285.568518) (xy 116.014755 -285.523242)
			(xy 116.002978 -285.475458) (xy 115.999018 -285.426404) (xy 115.68049 -285.426404) (xy 115.679978 -285.45185)
			(xy 115.671814 -285.502084) (xy 115.655698 -285.550358) (xy 115.632047 -285.595421) (xy 115.601474 -285.636107)
			(xy 115.56477 -285.671362) (xy 115.522886 -285.700272) (xy 115.476907 -285.722089) (xy 115.428023 -285.736249)
			(xy 115.377502 -285.742383) (xy 115.32665 -285.740334) (xy 115.276786 -285.730154) (xy 115.2292 -285.712107)
			(xy 115.185126 -285.686661) (xy 115.145704 -285.654474) (xy 115.111956 -285.61638) (xy 115.084755 -285.573366)
			(xy 115.064807 -285.526546) (xy 115.052628 -285.477132) (xy 115.048533 -285.426404) (xy 114.740436 -285.426404)
			(xy 114.739924 -285.45185) (xy 114.73176 -285.502084) (xy 114.715644 -285.550358) (xy 114.691993 -285.595421)
			(xy 114.66142 -285.636107) (xy 114.624716 -285.671362) (xy 114.582832 -285.700272) (xy 114.536853 -285.722089)
			(xy 114.487969 -285.736249) (xy 114.437448 -285.742383) (xy 114.386596 -285.740334) (xy 114.336732 -285.730154)
			(xy 114.289146 -285.712107) (xy 114.245072 -285.686661) (xy 114.20565 -285.654474) (xy 114.171902 -285.61638)
			(xy 114.144701 -285.573366) (xy 114.124753 -285.526546) (xy 114.112574 -285.477132) (xy 114.108479 -285.426404)
			(xy 113.789968 -285.426404) (xy 113.789473 -285.451011) (xy 113.781578 -285.499588) (xy 113.765994 -285.546269)
			(xy 113.743123 -285.589846) (xy 113.713558 -285.62919) (xy 113.678065 -285.663282) (xy 113.637562 -285.691238)
			(xy 113.5931 -285.712336) (xy 113.545829 -285.726028) (xy 113.496974 -285.73196) (xy 113.447799 -285.729979)
			(xy 113.39958 -285.720135) (xy 113.353564 -285.702683) (xy 113.310943 -285.678076) (xy 113.272822 -285.646951)
			(xy 113.240187 -285.610114) (xy 113.213884 -285.568518) (xy 113.194593 -285.523242) (xy 113.182816 -285.475458)
			(xy 113.178856 -285.426404) (xy 112.47863 -285.426404) (xy 112.491746 -286.23641) (xy 115.528864 -286.23641)
			(xy 115.532824 -286.187356) (xy 115.544601 -286.139572) (xy 115.563892 -286.094296) (xy 115.590195 -286.0527)
			(xy 115.62283 -286.015863) (xy 115.660951 -285.984738) (xy 115.703572 -285.960131) (xy 115.749588 -285.942679)
			(xy 115.797807 -285.932835) (xy 115.846982 -285.930854) (xy 115.895837 -285.936786) (xy 115.943108 -285.950478)
			(xy 115.98757 -285.971576) (xy 116.028073 -285.999532) (xy 116.063566 -286.033624) (xy 116.093131 -286.072968)
			(xy 116.116002 -286.116545) (xy 116.131586 -286.163226) (xy 116.139481 -286.211803) (xy 116.139976 -286.23641)
			(xy 116.458487 -286.23641) (xy 116.462582 -286.185682) (xy 116.474761 -286.136268) (xy 116.494709 -286.089448)
			(xy 116.52191 -286.046434) (xy 116.555658 -286.00834) (xy 116.59508 -285.976153) (xy 116.639154 -285.950707)
			(xy 116.68674 -285.93266) (xy 116.736604 -285.92248) (xy 116.787456 -285.920431) (xy 116.837977 -285.926565)
			(xy 116.886861 -285.940725) (xy 116.93284 -285.962542) (xy 116.974724 -285.991452) (xy 117.011428 -286.026707)
			(xy 117.042001 -286.067393) (xy 117.065652 -286.112456) (xy 117.081768 -286.16073) (xy 117.089932 -286.210964)
			(xy 117.090444 -286.23641) (xy 117.398541 -286.23641) (xy 117.402636 -286.185682) (xy 117.414815 -286.136268)
			(xy 117.434763 -286.089448) (xy 117.461964 -286.046434) (xy 117.495712 -286.00834) (xy 117.535134 -285.976153)
			(xy 117.579208 -285.950707) (xy 117.626794 -285.93266) (xy 117.676658 -285.92248) (xy 117.72751 -285.920431)
			(xy 117.778031 -285.926565) (xy 117.826915 -285.940725) (xy 117.872894 -285.962542) (xy 117.914778 -285.991452)
			(xy 117.951482 -286.026707) (xy 117.982055 -286.067393) (xy 118.005706 -286.112456) (xy 118.021822 -286.16073)
			(xy 118.029986 -286.210964) (xy 118.030498 -286.23641) (xy 118.349026 -286.23641) (xy 118.352986 -286.187356)
			(xy 118.364763 -286.139572) (xy 118.384054 -286.094296) (xy 118.410357 -286.0527) (xy 118.442992 -286.015863)
			(xy 118.481113 -285.984738) (xy 118.523734 -285.960131) (xy 118.56975 -285.942679) (xy 118.617969 -285.932835)
			(xy 118.667144 -285.930854) (xy 118.715999 -285.936786) (xy 118.76327 -285.950478) (xy 118.807732 -285.971576)
			(xy 118.848235 -285.999532) (xy 118.883728 -286.033624) (xy 118.913293 -286.072968) (xy 118.936164 -286.116545)
			(xy 118.951748 -286.163226) (xy 118.959643 -286.211803) (xy 118.960138 -286.23641) (xy 119.278395 -286.23641)
			(xy 119.28249 -286.185682) (xy 119.294669 -286.136268) (xy 119.314617 -286.089448) (xy 119.341818 -286.046434)
			(xy 119.375566 -286.00834) (xy 119.414988 -285.976153) (xy 119.459062 -285.950707) (xy 119.506648 -285.93266)
			(xy 119.556512 -285.92248) (xy 119.607364 -285.920431) (xy 119.657885 -285.926565) (xy 119.706769 -285.940725)
			(xy 119.752748 -285.962542) (xy 119.794632 -285.991452) (xy 119.831336 -286.026707) (xy 119.861909 -286.067393)
			(xy 119.88556 -286.112456) (xy 119.901676 -286.16073) (xy 119.90984 -286.210964) (xy 119.910352 -286.23641)
			(xy 120.218449 -286.23641) (xy 120.222544 -286.185682) (xy 120.234723 -286.136268) (xy 120.254671 -286.089448)
			(xy 120.281872 -286.046434) (xy 120.31562 -286.00834) (xy 120.355042 -285.976153) (xy 120.399116 -285.950707)
			(xy 120.446702 -285.93266) (xy 120.496566 -285.92248) (xy 120.547418 -285.920431) (xy 120.597939 -285.926565)
			(xy 120.646823 -285.940725) (xy 120.692802 -285.962542) (xy 120.734686 -285.991452) (xy 120.77139 -286.026707)
			(xy 120.801963 -286.067393) (xy 120.825614 -286.112456) (xy 120.84173 -286.16073) (xy 120.849894 -286.210964)
			(xy 120.850406 -286.23641) (xy 121.168934 -286.23641) (xy 121.172894 -286.187356) (xy 121.184671 -286.139572)
			(xy 121.203962 -286.094296) (xy 121.230265 -286.0527) (xy 121.2629 -286.015863) (xy 121.301021 -285.984738)
			(xy 121.343642 -285.960131) (xy 121.389658 -285.942679) (xy 121.437877 -285.932835) (xy 121.487052 -285.930854)
			(xy 121.535907 -285.936786) (xy 121.583178 -285.950478) (xy 121.62764 -285.971576) (xy 121.668143 -285.999532)
			(xy 121.703636 -286.033624) (xy 121.733201 -286.072968) (xy 121.756072 -286.116545) (xy 121.771656 -286.163226)
			(xy 121.779551 -286.211803) (xy 121.780046 -286.23641) (xy 122.098557 -286.23641) (xy 122.102652 -286.185682)
			(xy 122.114831 -286.136268) (xy 122.134779 -286.089448) (xy 122.16198 -286.046434) (xy 122.195728 -286.00834)
			(xy 122.23515 -285.976153) (xy 122.279224 -285.950707) (xy 122.32681 -285.93266) (xy 122.376674 -285.92248)
			(xy 122.427526 -285.920431) (xy 122.478047 -285.926565) (xy 122.526931 -285.940725) (xy 122.57291 -285.962542)
			(xy 122.614794 -285.991452) (xy 122.651498 -286.026707) (xy 122.682071 -286.067393) (xy 122.705722 -286.112456)
			(xy 122.721838 -286.16073) (xy 122.730002 -286.210964) (xy 122.730514 -286.23641) (xy 123.038611 -286.23641)
			(xy 123.042706 -286.185682) (xy 123.054885 -286.136268) (xy 123.074833 -286.089448) (xy 123.102034 -286.046434)
			(xy 123.135782 -286.00834) (xy 123.175204 -285.976153) (xy 123.219278 -285.950707) (xy 123.266864 -285.93266)
			(xy 123.316728 -285.92248) (xy 123.36758 -285.920431) (xy 123.418101 -285.926565) (xy 123.466985 -285.940725)
			(xy 123.512964 -285.962542) (xy 123.554848 -285.991452) (xy 123.591552 -286.026707) (xy 123.622125 -286.067393)
			(xy 123.645776 -286.112456) (xy 123.661892 -286.16073) (xy 123.670056 -286.210964) (xy 123.670568 -286.23641)
			(xy 123.988842 -286.23641) (xy 123.992802 -286.187356) (xy 124.004579 -286.139572) (xy 124.02387 -286.094296)
			(xy 124.050173 -286.0527) (xy 124.082808 -286.015863) (xy 124.120929 -285.984738) (xy 124.16355 -285.960131)
			(xy 124.209566 -285.942679) (xy 124.257785 -285.932835) (xy 124.30696 -285.930854) (xy 124.355815 -285.936786)
			(xy 124.403086 -285.950478) (xy 124.447548 -285.971576) (xy 124.488051 -285.999532) (xy 124.523544 -286.033624)
			(xy 124.553109 -286.072968) (xy 124.57598 -286.116545) (xy 124.591564 -286.163226) (xy 124.599459 -286.211803)
			(xy 124.599954 -286.23641) (xy 124.918465 -286.23641) (xy 124.92256 -286.185682) (xy 124.934739 -286.136268)
			(xy 124.954687 -286.089448) (xy 124.981888 -286.046434) (xy 125.015636 -286.00834) (xy 125.055058 -285.976153)
			(xy 125.099132 -285.950707) (xy 125.146718 -285.93266) (xy 125.196582 -285.92248) (xy 125.247434 -285.920431)
			(xy 125.297955 -285.926565) (xy 125.346839 -285.940725) (xy 125.392818 -285.962542) (xy 125.434702 -285.991452)
			(xy 125.471406 -286.026707) (xy 125.501979 -286.067393) (xy 125.52563 -286.112456) (xy 125.541746 -286.16073)
			(xy 125.54991 -286.210964) (xy 125.550422 -286.23641) (xy 125.858519 -286.23641) (xy 125.862614 -286.185682)
			(xy 125.874793 -286.136268) (xy 125.894741 -286.089448) (xy 125.921942 -286.046434) (xy 125.95569 -286.00834)
			(xy 125.995112 -285.976153) (xy 126.039186 -285.950707) (xy 126.086772 -285.93266) (xy 126.136636 -285.92248)
			(xy 126.187488 -285.920431) (xy 126.238009 -285.926565) (xy 126.286893 -285.940725) (xy 126.332872 -285.962542)
			(xy 126.374756 -285.991452) (xy 126.41146 -286.026707) (xy 126.442033 -286.067393) (xy 126.465684 -286.112456)
			(xy 126.4818 -286.16073) (xy 126.489964 -286.210964) (xy 126.490476 -286.23641) (xy 126.489964 -286.261856)
			(xy 126.4818 -286.31209) (xy 126.465684 -286.360364) (xy 126.442033 -286.405427) (xy 126.41146 -286.446113)
			(xy 126.374756 -286.481368) (xy 126.332872 -286.510278) (xy 126.286893 -286.532095) (xy 126.238009 -286.546255)
			(xy 126.187488 -286.552389) (xy 126.136636 -286.55034) (xy 126.086772 -286.54016) (xy 126.039186 -286.522113)
			(xy 125.995112 -286.496667) (xy 125.95569 -286.46448) (xy 125.921942 -286.426386) (xy 125.894741 -286.383372)
			(xy 125.874793 -286.336552) (xy 125.862614 -286.287138) (xy 125.858519 -286.23641) (xy 125.550422 -286.23641)
			(xy 125.54991 -286.261856) (xy 125.541746 -286.31209) (xy 125.52563 -286.360364) (xy 125.501979 -286.405427)
			(xy 125.471406 -286.446113) (xy 125.434702 -286.481368) (xy 125.392818 -286.510278) (xy 125.346839 -286.532095)
			(xy 125.297955 -286.546255) (xy 125.247434 -286.552389) (xy 125.196582 -286.55034) (xy 125.146718 -286.54016)
			(xy 125.099132 -286.522113) (xy 125.055058 -286.496667) (xy 125.015636 -286.46448) (xy 124.981888 -286.426386)
			(xy 124.954687 -286.383372) (xy 124.934739 -286.336552) (xy 124.92256 -286.287138) (xy 124.918465 -286.23641)
			(xy 124.599954 -286.23641) (xy 124.599459 -286.261017) (xy 124.591564 -286.309594) (xy 124.57598 -286.356275)
			(xy 124.553109 -286.399852) (xy 124.523544 -286.439196) (xy 124.488051 -286.473288) (xy 124.447548 -286.501244)
			(xy 124.403086 -286.522342) (xy 124.355815 -286.536034) (xy 124.30696 -286.541966) (xy 124.257785 -286.539985)
			(xy 124.209566 -286.530141) (xy 124.16355 -286.512689) (xy 124.120929 -286.488082) (xy 124.082808 -286.456957)
			(xy 124.050173 -286.42012) (xy 124.02387 -286.378524) (xy 124.004579 -286.333248) (xy 123.992802 -286.285464)
			(xy 123.988842 -286.23641) (xy 123.670568 -286.23641) (xy 123.670056 -286.261856) (xy 123.661892 -286.31209)
			(xy 123.645776 -286.360364) (xy 123.622125 -286.405427) (xy 123.591552 -286.446113) (xy 123.554848 -286.481368)
			(xy 123.512964 -286.510278) (xy 123.466985 -286.532095) (xy 123.418101 -286.546255) (xy 123.36758 -286.552389)
			(xy 123.316728 -286.55034) (xy 123.266864 -286.54016) (xy 123.219278 -286.522113) (xy 123.175204 -286.496667)
			(xy 123.135782 -286.46448) (xy 123.102034 -286.426386) (xy 123.074833 -286.383372) (xy 123.054885 -286.336552)
			(xy 123.042706 -286.287138) (xy 123.038611 -286.23641) (xy 122.730514 -286.23641) (xy 122.730002 -286.261856)
			(xy 122.721838 -286.31209) (xy 122.705722 -286.360364) (xy 122.682071 -286.405427) (xy 122.651498 -286.446113)
			(xy 122.614794 -286.481368) (xy 122.57291 -286.510278) (xy 122.526931 -286.532095) (xy 122.478047 -286.546255)
			(xy 122.427526 -286.552389) (xy 122.376674 -286.55034) (xy 122.32681 -286.54016) (xy 122.279224 -286.522113)
			(xy 122.23515 -286.496667) (xy 122.195728 -286.46448) (xy 122.16198 -286.426386) (xy 122.134779 -286.383372)
			(xy 122.114831 -286.336552) (xy 122.102652 -286.287138) (xy 122.098557 -286.23641) (xy 121.780046 -286.23641)
			(xy 121.779551 -286.261017) (xy 121.771656 -286.309594) (xy 121.756072 -286.356275) (xy 121.733201 -286.399852)
			(xy 121.703636 -286.439196) (xy 121.668143 -286.473288) (xy 121.62764 -286.501244) (xy 121.583178 -286.522342)
			(xy 121.535907 -286.536034) (xy 121.487052 -286.541966) (xy 121.437877 -286.539985) (xy 121.389658 -286.530141)
			(xy 121.343642 -286.512689) (xy 121.301021 -286.488082) (xy 121.2629 -286.456957) (xy 121.230265 -286.42012)
			(xy 121.203962 -286.378524) (xy 121.184671 -286.333248) (xy 121.172894 -286.285464) (xy 121.168934 -286.23641)
			(xy 120.850406 -286.23641) (xy 120.849894 -286.261856) (xy 120.84173 -286.31209) (xy 120.825614 -286.360364)
			(xy 120.801963 -286.405427) (xy 120.77139 -286.446113) (xy 120.734686 -286.481368) (xy 120.692802 -286.510278)
			(xy 120.646823 -286.532095) (xy 120.597939 -286.546255) (xy 120.547418 -286.552389) (xy 120.496566 -286.55034)
			(xy 120.446702 -286.54016) (xy 120.399116 -286.522113) (xy 120.355042 -286.496667) (xy 120.31562 -286.46448)
			(xy 120.281872 -286.426386) (xy 120.254671 -286.383372) (xy 120.234723 -286.336552) (xy 120.222544 -286.287138)
			(xy 120.218449 -286.23641) (xy 119.910352 -286.23641) (xy 119.90984 -286.261856) (xy 119.901676 -286.31209)
			(xy 119.88556 -286.360364) (xy 119.861909 -286.405427) (xy 119.831336 -286.446113) (xy 119.794632 -286.481368)
			(xy 119.752748 -286.510278) (xy 119.706769 -286.532095) (xy 119.657885 -286.546255) (xy 119.607364 -286.552389)
			(xy 119.556512 -286.55034) (xy 119.506648 -286.54016) (xy 119.459062 -286.522113) (xy 119.414988 -286.496667)
			(xy 119.375566 -286.46448) (xy 119.341818 -286.426386) (xy 119.314617 -286.383372) (xy 119.294669 -286.336552)
			(xy 119.28249 -286.287138) (xy 119.278395 -286.23641) (xy 118.960138 -286.23641) (xy 118.959643 -286.261017)
			(xy 118.951748 -286.309594) (xy 118.936164 -286.356275) (xy 118.913293 -286.399852) (xy 118.883728 -286.439196)
			(xy 118.848235 -286.473288) (xy 118.807732 -286.501244) (xy 118.76327 -286.522342) (xy 118.715999 -286.536034)
			(xy 118.667144 -286.541966) (xy 118.617969 -286.539985) (xy 118.56975 -286.530141) (xy 118.523734 -286.512689)
			(xy 118.481113 -286.488082) (xy 118.442992 -286.456957) (xy 118.410357 -286.42012) (xy 118.384054 -286.378524)
			(xy 118.364763 -286.333248) (xy 118.352986 -286.285464) (xy 118.349026 -286.23641) (xy 118.030498 -286.23641)
			(xy 118.029986 -286.261856) (xy 118.021822 -286.31209) (xy 118.005706 -286.360364) (xy 117.982055 -286.405427)
			(xy 117.951482 -286.446113) (xy 117.914778 -286.481368) (xy 117.872894 -286.510278) (xy 117.826915 -286.532095)
			(xy 117.778031 -286.546255) (xy 117.72751 -286.552389) (xy 117.676658 -286.55034) (xy 117.626794 -286.54016)
			(xy 117.579208 -286.522113) (xy 117.535134 -286.496667) (xy 117.495712 -286.46448) (xy 117.461964 -286.426386)
			(xy 117.434763 -286.383372) (xy 117.414815 -286.336552) (xy 117.402636 -286.287138) (xy 117.398541 -286.23641)
			(xy 117.090444 -286.23641) (xy 117.089932 -286.261856) (xy 117.081768 -286.31209) (xy 117.065652 -286.360364)
			(xy 117.042001 -286.405427) (xy 117.011428 -286.446113) (xy 116.974724 -286.481368) (xy 116.93284 -286.510278)
			(xy 116.886861 -286.532095) (xy 116.837977 -286.546255) (xy 116.787456 -286.552389) (xy 116.736604 -286.55034)
			(xy 116.68674 -286.54016) (xy 116.639154 -286.522113) (xy 116.59508 -286.496667) (xy 116.555658 -286.46448)
			(xy 116.52191 -286.426386) (xy 116.494709 -286.383372) (xy 116.474761 -286.336552) (xy 116.462582 -286.287138)
			(xy 116.458487 -286.23641) (xy 116.139976 -286.23641) (xy 116.139481 -286.261017) (xy 116.131586 -286.309594)
			(xy 116.116002 -286.356275) (xy 116.093131 -286.399852) (xy 116.063566 -286.439196) (xy 116.028073 -286.473288)
			(xy 115.98757 -286.501244) (xy 115.943108 -286.522342) (xy 115.895837 -286.536034) (xy 115.846982 -286.541966)
			(xy 115.797807 -286.539985) (xy 115.749588 -286.530141) (xy 115.703572 -286.512689) (xy 115.660951 -286.488082)
			(xy 115.62283 -286.456957) (xy 115.590195 -286.42012) (xy 115.563892 -286.378524) (xy 115.544601 -286.333248)
			(xy 115.532824 -286.285464) (xy 115.528864 -286.23641) (xy 112.491746 -286.23641) (xy 112.504858 -287.046162)
			(xy 113.178856 -287.046162) (xy 113.182816 -286.997108) (xy 113.194593 -286.949324) (xy 113.213884 -286.904048)
			(xy 113.240187 -286.862452) (xy 113.272822 -286.825615) (xy 113.310943 -286.79449) (xy 113.353564 -286.769883)
			(xy 113.39958 -286.752431) (xy 113.447799 -286.742587) (xy 113.496974 -286.740606) (xy 113.545829 -286.746538)
			(xy 113.5931 -286.76023) (xy 113.637562 -286.781328) (xy 113.678065 -286.809284) (xy 113.713558 -286.843376)
			(xy 113.743123 -286.88272) (xy 113.765994 -286.926297) (xy 113.781578 -286.972978) (xy 113.789473 -287.021555)
			(xy 113.789968 -287.046162) (xy 114.108479 -287.046162) (xy 114.112574 -286.995434) (xy 114.124753 -286.94602)
			(xy 114.144701 -286.8992) (xy 114.171902 -286.856186) (xy 114.20565 -286.818092) (xy 114.245072 -286.785905)
			(xy 114.289146 -286.760459) (xy 114.336732 -286.742412) (xy 114.386596 -286.732232) (xy 114.437448 -286.730183)
			(xy 114.487969 -286.736317) (xy 114.536853 -286.750477) (xy 114.582832 -286.772294) (xy 114.624716 -286.801204)
			(xy 114.66142 -286.836459) (xy 114.691993 -286.877145) (xy 114.715644 -286.922208) (xy 114.73176 -286.970482)
			(xy 114.739924 -287.020716) (xy 114.740436 -287.046162) (xy 115.048533 -287.046162) (xy 115.052628 -286.995434)
			(xy 115.064807 -286.94602) (xy 115.084755 -286.8992) (xy 115.111956 -286.856186) (xy 115.145704 -286.818092)
			(xy 115.185126 -286.785905) (xy 115.2292 -286.760459) (xy 115.276786 -286.742412) (xy 115.32665 -286.732232)
			(xy 115.377502 -286.730183) (xy 115.428023 -286.736317) (xy 115.476907 -286.750477) (xy 115.522886 -286.772294)
			(xy 115.56477 -286.801204) (xy 115.601474 -286.836459) (xy 115.632047 -286.877145) (xy 115.655698 -286.922208)
			(xy 115.671814 -286.970482) (xy 115.679978 -287.020716) (xy 115.68049 -287.046162) (xy 115.680485 -287.046416)
			(xy 115.999018 -287.046416) (xy 116.002978 -286.997362) (xy 116.014755 -286.949578) (xy 116.034046 -286.904302)
			(xy 116.060349 -286.862706) (xy 116.092984 -286.825869) (xy 116.131105 -286.794744) (xy 116.173726 -286.770137)
			(xy 116.219742 -286.752685) (xy 116.267961 -286.742841) (xy 116.317136 -286.74086) (xy 116.365991 -286.746792)
			(xy 116.413262 -286.760484) (xy 116.457724 -286.781582) (xy 116.498227 -286.809538) (xy 116.53372 -286.84363)
			(xy 116.563285 -286.882974) (xy 116.586156 -286.926551) (xy 116.60174 -286.973232) (xy 116.609635 -287.021809)
			(xy 116.610125 -287.046162) (xy 118.818926 -287.046162) (xy 118.822886 -286.997108) (xy 118.834663 -286.949324)
			(xy 118.853954 -286.904048) (xy 118.880257 -286.862452) (xy 118.912892 -286.825615) (xy 118.951013 -286.79449)
			(xy 118.993634 -286.769883) (xy 119.03965 -286.752431) (xy 119.087869 -286.742587) (xy 119.137044 -286.740606)
			(xy 119.185899 -286.746538) (xy 119.23317 -286.76023) (xy 119.277632 -286.781328) (xy 119.318135 -286.809284)
			(xy 119.353628 -286.843376) (xy 119.383193 -286.88272) (xy 119.406064 -286.926297) (xy 119.421648 -286.972978)
			(xy 119.429543 -287.021555) (xy 119.430038 -287.046162) (xy 121.638834 -287.046162) (xy 121.642794 -286.997108)
			(xy 121.654571 -286.949324) (xy 121.673862 -286.904048) (xy 121.700165 -286.862452) (xy 121.7328 -286.825615)
			(xy 121.770921 -286.79449) (xy 121.813542 -286.769883) (xy 121.859558 -286.752431) (xy 121.907777 -286.742587)
			(xy 121.956952 -286.740606) (xy 122.005807 -286.746538) (xy 122.053078 -286.76023) (xy 122.09754 -286.781328)
			(xy 122.138043 -286.809284) (xy 122.173536 -286.843376) (xy 122.203101 -286.88272) (xy 122.225972 -286.926297)
			(xy 122.241556 -286.972978) (xy 122.249451 -287.021555) (xy 122.249946 -287.046162) (xy 124.458996 -287.046162)
			(xy 124.462956 -286.997108) (xy 124.474733 -286.949324) (xy 124.494024 -286.904048) (xy 124.520327 -286.862452)
			(xy 124.552962 -286.825615) (xy 124.591083 -286.79449) (xy 124.633704 -286.769883) (xy 124.67972 -286.752431)
			(xy 124.727939 -286.742587) (xy 124.777114 -286.740606) (xy 124.825969 -286.746538) (xy 124.87324 -286.76023)
			(xy 124.917702 -286.781328) (xy 124.958205 -286.809284) (xy 124.993698 -286.843376) (xy 125.023263 -286.88272)
			(xy 125.046134 -286.926297) (xy 125.061718 -286.972978) (xy 125.069613 -287.021555) (xy 125.070108 -287.046162)
			(xy 125.069613 -287.070769) (xy 125.061718 -287.119346) (xy 125.046134 -287.166027) (xy 125.023263 -287.209604)
			(xy 124.993698 -287.248948) (xy 124.958205 -287.28304) (xy 124.917702 -287.310996) (xy 124.87324 -287.332094)
			(xy 124.825969 -287.345786) (xy 124.777114 -287.351718) (xy 124.727939 -287.349737) (xy 124.67972 -287.339893)
			(xy 124.633704 -287.322441) (xy 124.591083 -287.297834) (xy 124.552962 -287.266709) (xy 124.520327 -287.229872)
			(xy 124.494024 -287.188276) (xy 124.474733 -287.143) (xy 124.462956 -287.095216) (xy 124.458996 -287.046162)
			(xy 122.249946 -287.046162) (xy 122.249451 -287.070769) (xy 122.241556 -287.119346) (xy 122.225972 -287.166027)
			(xy 122.203101 -287.209604) (xy 122.173536 -287.248948) (xy 122.138043 -287.28304) (xy 122.09754 -287.310996)
			(xy 122.053078 -287.332094) (xy 122.005807 -287.345786) (xy 121.956952 -287.351718) (xy 121.907777 -287.349737)
			(xy 121.859558 -287.339893) (xy 121.813542 -287.322441) (xy 121.770921 -287.297834) (xy 121.7328 -287.266709)
			(xy 121.700165 -287.229872) (xy 121.673862 -287.188276) (xy 121.654571 -287.143) (xy 121.642794 -287.095216)
			(xy 121.638834 -287.046162) (xy 119.430038 -287.046162) (xy 119.429543 -287.070769) (xy 119.421648 -287.119346)
			(xy 119.406064 -287.166027) (xy 119.383193 -287.209604) (xy 119.353628 -287.248948) (xy 119.318135 -287.28304)
			(xy 119.277632 -287.310996) (xy 119.23317 -287.332094) (xy 119.185899 -287.345786) (xy 119.137044 -287.351718)
			(xy 119.087869 -287.349737) (xy 119.03965 -287.339893) (xy 118.993634 -287.322441) (xy 118.951013 -287.297834)
			(xy 118.912892 -287.266709) (xy 118.880257 -287.229872) (xy 118.853954 -287.188276) (xy 118.834663 -287.143)
			(xy 118.822886 -287.095216) (xy 118.818926 -287.046162) (xy 116.610125 -287.046162) (xy 116.61013 -287.046416)
			(xy 116.609635 -287.071023) (xy 116.60174 -287.1196) (xy 116.586156 -287.166281) (xy 116.563285 -287.209858)
			(xy 116.53372 -287.249202) (xy 116.498227 -287.283294) (xy 116.457724 -287.31125) (xy 116.413262 -287.332348)
			(xy 116.365991 -287.34604) (xy 116.317136 -287.351972) (xy 116.267961 -287.349991) (xy 116.219742 -287.340147)
			(xy 116.173726 -287.322695) (xy 116.131105 -287.298088) (xy 116.092984 -287.266963) (xy 116.060349 -287.230126)
			(xy 116.034046 -287.18853) (xy 116.014755 -287.143254) (xy 116.002978 -287.09547) (xy 115.999018 -287.046416)
			(xy 115.680485 -287.046416) (xy 115.679978 -287.071608) (xy 115.671814 -287.121842) (xy 115.655698 -287.170116)
			(xy 115.632047 -287.215179) (xy 115.601474 -287.255865) (xy 115.56477 -287.29112) (xy 115.522886 -287.32003)
			(xy 115.476907 -287.341847) (xy 115.428023 -287.356007) (xy 115.377502 -287.362141) (xy 115.32665 -287.360092)
			(xy 115.276786 -287.349912) (xy 115.2292 -287.331865) (xy 115.185126 -287.306419) (xy 115.145704 -287.274232)
			(xy 115.111956 -287.236138) (xy 115.084755 -287.193124) (xy 115.064807 -287.146304) (xy 115.052628 -287.09689)
			(xy 115.048533 -287.046162) (xy 114.740436 -287.046162) (xy 114.739924 -287.071608) (xy 114.73176 -287.121842)
			(xy 114.715644 -287.170116) (xy 114.691993 -287.215179) (xy 114.66142 -287.255865) (xy 114.624716 -287.29112)
			(xy 114.582832 -287.32003) (xy 114.536853 -287.341847) (xy 114.487969 -287.356007) (xy 114.437448 -287.362141)
			(xy 114.386596 -287.360092) (xy 114.336732 -287.349912) (xy 114.289146 -287.331865) (xy 114.245072 -287.306419)
			(xy 114.20565 -287.274232) (xy 114.171902 -287.236138) (xy 114.144701 -287.193124) (xy 114.124753 -287.146304)
			(xy 114.112574 -287.09689) (xy 114.108479 -287.046162) (xy 113.789968 -287.046162) (xy 113.789473 -287.070769)
			(xy 113.781578 -287.119346) (xy 113.765994 -287.166027) (xy 113.743123 -287.209604) (xy 113.713558 -287.248948)
			(xy 113.678065 -287.28304) (xy 113.637562 -287.310996) (xy 113.5931 -287.332094) (xy 113.545829 -287.345786)
			(xy 113.496974 -287.351718) (xy 113.447799 -287.349737) (xy 113.39958 -287.339893) (xy 113.353564 -287.322441)
			(xy 113.310943 -287.297834) (xy 113.272822 -287.266709) (xy 113.240187 -287.229872) (xy 113.213884 -287.188276)
			(xy 113.194593 -287.143) (xy 113.182816 -287.095216) (xy 113.178856 -287.046162) (xy 112.504858 -287.046162)
			(xy 112.517978 -287.856422) (xy 113.64901 -287.856422) (xy 113.65297 -287.807368) (xy 113.664747 -287.759584)
			(xy 113.684038 -287.714308) (xy 113.710341 -287.672712) (xy 113.742976 -287.635875) (xy 113.781097 -287.60475)
			(xy 113.823718 -287.580143) (xy 113.869734 -287.562691) (xy 113.917953 -287.552847) (xy 113.967128 -287.550866)
			(xy 114.015983 -287.556798) (xy 114.063254 -287.57049) (xy 114.107716 -287.591588) (xy 114.148219 -287.619544)
			(xy 114.183712 -287.653636) (xy 114.213277 -287.69298) (xy 114.236148 -287.736557) (xy 114.251732 -287.783238)
			(xy 114.259627 -287.831815) (xy 114.260122 -287.856422) (xy 114.58881 -287.856422) (xy 114.59277 -287.807368)
			(xy 114.604547 -287.759584) (xy 114.623838 -287.714308) (xy 114.650141 -287.672712) (xy 114.682776 -287.635875)
			(xy 114.720897 -287.60475) (xy 114.763518 -287.580143) (xy 114.809534 -287.562691) (xy 114.857753 -287.552847)
			(xy 114.906928 -287.550866) (xy 114.955783 -287.556798) (xy 115.003054 -287.57049) (xy 115.047516 -287.591588)
			(xy 115.088019 -287.619544) (xy 115.123512 -287.653636) (xy 115.153077 -287.69298) (xy 115.175948 -287.736557)
			(xy 115.191532 -287.783238) (xy 115.199427 -287.831815) (xy 115.199922 -287.856422) (xy 115.528864 -287.856422)
			(xy 115.532824 -287.807368) (xy 115.544601 -287.759584) (xy 115.563892 -287.714308) (xy 115.590195 -287.672712)
			(xy 115.62283 -287.635875) (xy 115.660951 -287.60475) (xy 115.703572 -287.580143) (xy 115.749588 -287.562691)
			(xy 115.797807 -287.552847) (xy 115.846982 -287.550866) (xy 115.895837 -287.556798) (xy 115.943108 -287.57049)
			(xy 115.98757 -287.591588) (xy 116.028073 -287.619544) (xy 116.063566 -287.653636) (xy 116.093131 -287.69298)
			(xy 116.116002 -287.736557) (xy 116.131586 -287.783238) (xy 116.139481 -287.831815) (xy 116.139976 -287.856422)
			(xy 116.458487 -287.856422) (xy 116.462582 -287.805694) (xy 116.474761 -287.75628) (xy 116.494709 -287.70946)
			(xy 116.52191 -287.666446) (xy 116.555658 -287.628352) (xy 116.59508 -287.596165) (xy 116.639154 -287.570719)
			(xy 116.68674 -287.552672) (xy 116.736604 -287.542492) (xy 116.787456 -287.540443) (xy 116.837977 -287.546577)
			(xy 116.886861 -287.560737) (xy 116.93284 -287.582554) (xy 116.974724 -287.611464) (xy 117.011428 -287.646719)
			(xy 117.042001 -287.687405) (xy 117.065652 -287.732468) (xy 117.081768 -287.780742) (xy 117.089932 -287.830976)
			(xy 117.090444 -287.856422) (xy 117.398541 -287.856422) (xy 117.402636 -287.805694) (xy 117.414815 -287.75628)
			(xy 117.434763 -287.70946) (xy 117.461964 -287.666446) (xy 117.495712 -287.628352) (xy 117.535134 -287.596165)
			(xy 117.579208 -287.570719) (xy 117.626794 -287.552672) (xy 117.676658 -287.542492) (xy 117.72751 -287.540443)
			(xy 117.778031 -287.546577) (xy 117.826915 -287.560737) (xy 117.872894 -287.582554) (xy 117.914778 -287.611464)
			(xy 117.951482 -287.646719) (xy 117.982055 -287.687405) (xy 118.005706 -287.732468) (xy 118.021822 -287.780742)
			(xy 118.029986 -287.830976) (xy 118.030498 -287.856422) (xy 118.349026 -287.856422) (xy 118.352986 -287.807368)
			(xy 118.364763 -287.759584) (xy 118.384054 -287.714308) (xy 118.410357 -287.672712) (xy 118.442992 -287.635875)
			(xy 118.481113 -287.60475) (xy 118.523734 -287.580143) (xy 118.56975 -287.562691) (xy 118.617969 -287.552847)
			(xy 118.667144 -287.550866) (xy 118.715999 -287.556798) (xy 118.76327 -287.57049) (xy 118.807732 -287.591588)
			(xy 118.848235 -287.619544) (xy 118.883728 -287.653636) (xy 118.913293 -287.69298) (xy 118.936164 -287.736557)
			(xy 118.951748 -287.783238) (xy 118.959643 -287.831815) (xy 118.960138 -287.856422) (xy 119.278395 -287.856422)
			(xy 119.28249 -287.805694) (xy 119.294669 -287.75628) (xy 119.314617 -287.70946) (xy 119.341818 -287.666446)
			(xy 119.375566 -287.628352) (xy 119.414988 -287.596165) (xy 119.459062 -287.570719) (xy 119.506648 -287.552672)
			(xy 119.556512 -287.542492) (xy 119.607364 -287.540443) (xy 119.657885 -287.546577) (xy 119.706769 -287.560737)
			(xy 119.752748 -287.582554) (xy 119.794632 -287.611464) (xy 119.831336 -287.646719) (xy 119.861909 -287.687405)
			(xy 119.88556 -287.732468) (xy 119.901676 -287.780742) (xy 119.90984 -287.830976) (xy 119.910352 -287.856422)
			(xy 120.218449 -287.856422) (xy 120.222544 -287.805694) (xy 120.234723 -287.75628) (xy 120.254671 -287.70946)
			(xy 120.281872 -287.666446) (xy 120.31562 -287.628352) (xy 120.355042 -287.596165) (xy 120.399116 -287.570719)
			(xy 120.446702 -287.552672) (xy 120.496566 -287.542492) (xy 120.547418 -287.540443) (xy 120.597939 -287.546577)
			(xy 120.646823 -287.560737) (xy 120.692802 -287.582554) (xy 120.734686 -287.611464) (xy 120.77139 -287.646719)
			(xy 120.801963 -287.687405) (xy 120.825614 -287.732468) (xy 120.84173 -287.780742) (xy 120.849894 -287.830976)
			(xy 120.850406 -287.856422) (xy 121.168934 -287.856422) (xy 121.172894 -287.807368) (xy 121.184671 -287.759584)
			(xy 121.203962 -287.714308) (xy 121.230265 -287.672712) (xy 121.2629 -287.635875) (xy 121.301021 -287.60475)
			(xy 121.343642 -287.580143) (xy 121.389658 -287.562691) (xy 121.437877 -287.552847) (xy 121.487052 -287.550866)
			(xy 121.535907 -287.556798) (xy 121.583178 -287.57049) (xy 121.62764 -287.591588) (xy 121.668143 -287.619544)
			(xy 121.703636 -287.653636) (xy 121.733201 -287.69298) (xy 121.756072 -287.736557) (xy 121.771656 -287.783238)
			(xy 121.779551 -287.831815) (xy 121.780046 -287.856422) (xy 122.098557 -287.856422) (xy 122.102652 -287.805694)
			(xy 122.114831 -287.75628) (xy 122.134779 -287.70946) (xy 122.16198 -287.666446) (xy 122.195728 -287.628352)
			(xy 122.23515 -287.596165) (xy 122.279224 -287.570719) (xy 122.32681 -287.552672) (xy 122.376674 -287.542492)
			(xy 122.427526 -287.540443) (xy 122.478047 -287.546577) (xy 122.526931 -287.560737) (xy 122.57291 -287.582554)
			(xy 122.614794 -287.611464) (xy 122.651498 -287.646719) (xy 122.682071 -287.687405) (xy 122.705722 -287.732468)
			(xy 122.721838 -287.780742) (xy 122.730002 -287.830976) (xy 122.730514 -287.856422) (xy 123.038611 -287.856422)
			(xy 123.042706 -287.805694) (xy 123.054885 -287.75628) (xy 123.074833 -287.70946) (xy 123.102034 -287.666446)
			(xy 123.135782 -287.628352) (xy 123.175204 -287.596165) (xy 123.219278 -287.570719) (xy 123.266864 -287.552672)
			(xy 123.316728 -287.542492) (xy 123.36758 -287.540443) (xy 123.418101 -287.546577) (xy 123.466985 -287.560737)
			(xy 123.512964 -287.582554) (xy 123.554848 -287.611464) (xy 123.591552 -287.646719) (xy 123.622125 -287.687405)
			(xy 123.645776 -287.732468) (xy 123.661892 -287.780742) (xy 123.670056 -287.830976) (xy 123.670568 -287.856422)
			(xy 123.988842 -287.856422) (xy 123.992802 -287.807368) (xy 124.004579 -287.759584) (xy 124.02387 -287.714308)
			(xy 124.050173 -287.672712) (xy 124.082808 -287.635875) (xy 124.120929 -287.60475) (xy 124.16355 -287.580143)
			(xy 124.209566 -287.562691) (xy 124.257785 -287.552847) (xy 124.30696 -287.550866) (xy 124.355815 -287.556798)
			(xy 124.403086 -287.57049) (xy 124.447548 -287.591588) (xy 124.488051 -287.619544) (xy 124.523544 -287.653636)
			(xy 124.553109 -287.69298) (xy 124.57598 -287.736557) (xy 124.591564 -287.783238) (xy 124.599459 -287.831815)
			(xy 124.599954 -287.856422) (xy 124.918465 -287.856422) (xy 124.92256 -287.805694) (xy 124.934739 -287.75628)
			(xy 124.954687 -287.70946) (xy 124.981888 -287.666446) (xy 125.015636 -287.628352) (xy 125.055058 -287.596165)
			(xy 125.099132 -287.570719) (xy 125.146718 -287.552672) (xy 125.196582 -287.542492) (xy 125.247434 -287.540443)
			(xy 125.297955 -287.546577) (xy 125.346839 -287.560737) (xy 125.392818 -287.582554) (xy 125.434702 -287.611464)
			(xy 125.471406 -287.646719) (xy 125.501979 -287.687405) (xy 125.52563 -287.732468) (xy 125.541746 -287.780742)
			(xy 125.54991 -287.830976) (xy 125.550422 -287.856422) (xy 125.858519 -287.856422) (xy 125.862614 -287.805694)
			(xy 125.874793 -287.75628) (xy 125.894741 -287.70946) (xy 125.921942 -287.666446) (xy 125.95569 -287.628352)
			(xy 125.995112 -287.596165) (xy 126.039186 -287.570719) (xy 126.086772 -287.552672) (xy 126.136636 -287.542492)
			(xy 126.187488 -287.540443) (xy 126.238009 -287.546577) (xy 126.286893 -287.560737) (xy 126.332872 -287.582554)
			(xy 126.374756 -287.611464) (xy 126.41146 -287.646719) (xy 126.442033 -287.687405) (xy 126.465684 -287.732468)
			(xy 126.4818 -287.780742) (xy 126.489964 -287.830976) (xy 126.490476 -287.856422) (xy 126.489964 -287.881868)
			(xy 126.4818 -287.932102) (xy 126.465684 -287.980376) (xy 126.442033 -288.025439) (xy 126.41146 -288.066125)
			(xy 126.374756 -288.10138) (xy 126.332872 -288.13029) (xy 126.286893 -288.152107) (xy 126.238009 -288.166267)
			(xy 126.187488 -288.172401) (xy 126.136636 -288.170352) (xy 126.086772 -288.160172) (xy 126.039186 -288.142125)
			(xy 125.995112 -288.116679) (xy 125.95569 -288.084492) (xy 125.921942 -288.046398) (xy 125.894741 -288.003384)
			(xy 125.874793 -287.956564) (xy 125.862614 -287.90715) (xy 125.858519 -287.856422) (xy 125.550422 -287.856422)
			(xy 125.54991 -287.881868) (xy 125.541746 -287.932102) (xy 125.52563 -287.980376) (xy 125.501979 -288.025439)
			(xy 125.471406 -288.066125) (xy 125.434702 -288.10138) (xy 125.392818 -288.13029) (xy 125.346839 -288.152107)
			(xy 125.297955 -288.166267) (xy 125.247434 -288.172401) (xy 125.196582 -288.170352) (xy 125.146718 -288.160172)
			(xy 125.099132 -288.142125) (xy 125.055058 -288.116679) (xy 125.015636 -288.084492) (xy 124.981888 -288.046398)
			(xy 124.954687 -288.003384) (xy 124.934739 -287.956564) (xy 124.92256 -287.90715) (xy 124.918465 -287.856422)
			(xy 124.599954 -287.856422) (xy 124.599459 -287.881029) (xy 124.591564 -287.929606) (xy 124.57598 -287.976287)
			(xy 124.553109 -288.019864) (xy 124.523544 -288.059208) (xy 124.488051 -288.0933) (xy 124.447548 -288.121256)
			(xy 124.403086 -288.142354) (xy 124.355815 -288.156046) (xy 124.30696 -288.161978) (xy 124.257785 -288.159997)
			(xy 124.209566 -288.150153) (xy 124.16355 -288.132701) (xy 124.120929 -288.108094) (xy 124.082808 -288.076969)
			(xy 124.050173 -288.040132) (xy 124.02387 -287.998536) (xy 124.004579 -287.95326) (xy 123.992802 -287.905476)
			(xy 123.988842 -287.856422) (xy 123.670568 -287.856422) (xy 123.670056 -287.881868) (xy 123.661892 -287.932102)
			(xy 123.645776 -287.980376) (xy 123.622125 -288.025439) (xy 123.591552 -288.066125) (xy 123.554848 -288.10138)
			(xy 123.512964 -288.13029) (xy 123.466985 -288.152107) (xy 123.418101 -288.166267) (xy 123.36758 -288.172401)
			(xy 123.316728 -288.170352) (xy 123.266864 -288.160172) (xy 123.219278 -288.142125) (xy 123.175204 -288.116679)
			(xy 123.135782 -288.084492) (xy 123.102034 -288.046398) (xy 123.074833 -288.003384) (xy 123.054885 -287.956564)
			(xy 123.042706 -287.90715) (xy 123.038611 -287.856422) (xy 122.730514 -287.856422) (xy 122.730002 -287.881868)
			(xy 122.721838 -287.932102) (xy 122.705722 -287.980376) (xy 122.682071 -288.025439) (xy 122.651498 -288.066125)
			(xy 122.614794 -288.10138) (xy 122.57291 -288.13029) (xy 122.526931 -288.152107) (xy 122.478047 -288.166267)
			(xy 122.427526 -288.172401) (xy 122.376674 -288.170352) (xy 122.32681 -288.160172) (xy 122.279224 -288.142125)
			(xy 122.23515 -288.116679) (xy 122.195728 -288.084492) (xy 122.16198 -288.046398) (xy 122.134779 -288.003384)
			(xy 122.114831 -287.956564) (xy 122.102652 -287.90715) (xy 122.098557 -287.856422) (xy 121.780046 -287.856422)
			(xy 121.779551 -287.881029) (xy 121.771656 -287.929606) (xy 121.756072 -287.976287) (xy 121.733201 -288.019864)
			(xy 121.703636 -288.059208) (xy 121.668143 -288.0933) (xy 121.62764 -288.121256) (xy 121.583178 -288.142354)
			(xy 121.535907 -288.156046) (xy 121.487052 -288.161978) (xy 121.437877 -288.159997) (xy 121.389658 -288.150153)
			(xy 121.343642 -288.132701) (xy 121.301021 -288.108094) (xy 121.2629 -288.076969) (xy 121.230265 -288.040132)
			(xy 121.203962 -287.998536) (xy 121.184671 -287.95326) (xy 121.172894 -287.905476) (xy 121.168934 -287.856422)
			(xy 120.850406 -287.856422) (xy 120.849894 -287.881868) (xy 120.84173 -287.932102) (xy 120.825614 -287.980376)
			(xy 120.801963 -288.025439) (xy 120.77139 -288.066125) (xy 120.734686 -288.10138) (xy 120.692802 -288.13029)
			(xy 120.646823 -288.152107) (xy 120.597939 -288.166267) (xy 120.547418 -288.172401) (xy 120.496566 -288.170352)
			(xy 120.446702 -288.160172) (xy 120.399116 -288.142125) (xy 120.355042 -288.116679) (xy 120.31562 -288.084492)
			(xy 120.281872 -288.046398) (xy 120.254671 -288.003384) (xy 120.234723 -287.956564) (xy 120.222544 -287.90715)
			(xy 120.218449 -287.856422) (xy 119.910352 -287.856422) (xy 119.90984 -287.881868) (xy 119.901676 -287.932102)
			(xy 119.88556 -287.980376) (xy 119.861909 -288.025439) (xy 119.831336 -288.066125) (xy 119.794632 -288.10138)
			(xy 119.752748 -288.13029) (xy 119.706769 -288.152107) (xy 119.657885 -288.166267) (xy 119.607364 -288.172401)
			(xy 119.556512 -288.170352) (xy 119.506648 -288.160172) (xy 119.459062 -288.142125) (xy 119.414988 -288.116679)
			(xy 119.375566 -288.084492) (xy 119.341818 -288.046398) (xy 119.314617 -288.003384) (xy 119.294669 -287.956564)
			(xy 119.28249 -287.90715) (xy 119.278395 -287.856422) (xy 118.960138 -287.856422) (xy 118.959643 -287.881029)
			(xy 118.951748 -287.929606) (xy 118.936164 -287.976287) (xy 118.913293 -288.019864) (xy 118.883728 -288.059208)
			(xy 118.848235 -288.0933) (xy 118.807732 -288.121256) (xy 118.76327 -288.142354) (xy 118.715999 -288.156046)
			(xy 118.667144 -288.161978) (xy 118.617969 -288.159997) (xy 118.56975 -288.150153) (xy 118.523734 -288.132701)
			(xy 118.481113 -288.108094) (xy 118.442992 -288.076969) (xy 118.410357 -288.040132) (xy 118.384054 -287.998536)
			(xy 118.364763 -287.95326) (xy 118.352986 -287.905476) (xy 118.349026 -287.856422) (xy 118.030498 -287.856422)
			(xy 118.029986 -287.881868) (xy 118.021822 -287.932102) (xy 118.005706 -287.980376) (xy 117.982055 -288.025439)
			(xy 117.951482 -288.066125) (xy 117.914778 -288.10138) (xy 117.872894 -288.13029) (xy 117.826915 -288.152107)
			(xy 117.778031 -288.166267) (xy 117.72751 -288.172401) (xy 117.676658 -288.170352) (xy 117.626794 -288.160172)
			(xy 117.579208 -288.142125) (xy 117.535134 -288.116679) (xy 117.495712 -288.084492) (xy 117.461964 -288.046398)
			(xy 117.434763 -288.003384) (xy 117.414815 -287.956564) (xy 117.402636 -287.90715) (xy 117.398541 -287.856422)
			(xy 117.090444 -287.856422) (xy 117.089932 -287.881868) (xy 117.081768 -287.932102) (xy 117.065652 -287.980376)
			(xy 117.042001 -288.025439) (xy 117.011428 -288.066125) (xy 116.974724 -288.10138) (xy 116.93284 -288.13029)
			(xy 116.886861 -288.152107) (xy 116.837977 -288.166267) (xy 116.787456 -288.172401) (xy 116.736604 -288.170352)
			(xy 116.68674 -288.160172) (xy 116.639154 -288.142125) (xy 116.59508 -288.116679) (xy 116.555658 -288.084492)
			(xy 116.52191 -288.046398) (xy 116.494709 -288.003384) (xy 116.474761 -287.956564) (xy 116.462582 -287.90715)
			(xy 116.458487 -287.856422) (xy 116.139976 -287.856422) (xy 116.139481 -287.881029) (xy 116.131586 -287.929606)
			(xy 116.116002 -287.976287) (xy 116.093131 -288.019864) (xy 116.063566 -288.059208) (xy 116.028073 -288.0933)
			(xy 115.98757 -288.121256) (xy 115.943108 -288.142354) (xy 115.895837 -288.156046) (xy 115.846982 -288.161978)
			(xy 115.797807 -288.159997) (xy 115.749588 -288.150153) (xy 115.703572 -288.132701) (xy 115.660951 -288.108094)
			(xy 115.62283 -288.076969) (xy 115.590195 -288.040132) (xy 115.563892 -287.998536) (xy 115.544601 -287.95326)
			(xy 115.532824 -287.905476) (xy 115.528864 -287.856422) (xy 115.199922 -287.856422) (xy 115.199427 -287.881029)
			(xy 115.191532 -287.929606) (xy 115.175948 -287.976287) (xy 115.153077 -288.019864) (xy 115.123512 -288.059208)
			(xy 115.088019 -288.0933) (xy 115.047516 -288.121256) (xy 115.003054 -288.142354) (xy 114.955783 -288.156046)
			(xy 114.906928 -288.161978) (xy 114.857753 -288.159997) (xy 114.809534 -288.150153) (xy 114.763518 -288.132701)
			(xy 114.720897 -288.108094) (xy 114.682776 -288.076969) (xy 114.650141 -288.040132) (xy 114.623838 -287.998536)
			(xy 114.604547 -287.95326) (xy 114.59277 -287.905476) (xy 114.58881 -287.856422) (xy 114.260122 -287.856422)
			(xy 114.259627 -287.881029) (xy 114.251732 -287.929606) (xy 114.236148 -287.976287) (xy 114.213277 -288.019864)
			(xy 114.183712 -288.059208) (xy 114.148219 -288.0933) (xy 114.107716 -288.121256) (xy 114.063254 -288.142354)
			(xy 114.015983 -288.156046) (xy 113.967128 -288.161978) (xy 113.917953 -288.159997) (xy 113.869734 -288.150153)
			(xy 113.823718 -288.132701) (xy 113.781097 -288.108094) (xy 113.742976 -288.076969) (xy 113.710341 -288.040132)
			(xy 113.684038 -287.998536) (xy 113.664747 -287.95326) (xy 113.65297 -287.905476) (xy 113.64901 -287.856422)
			(xy 112.517978 -287.856422) (xy 112.53109 -288.666174) (xy 113.178856 -288.666174) (xy 113.182816 -288.61712)
			(xy 113.194593 -288.569336) (xy 113.213884 -288.52406) (xy 113.240187 -288.482464) (xy 113.272822 -288.445627)
			(xy 113.310943 -288.414502) (xy 113.353564 -288.389895) (xy 113.39958 -288.372443) (xy 113.447799 -288.362599)
			(xy 113.496974 -288.360618) (xy 113.545829 -288.36655) (xy 113.5931 -288.380242) (xy 113.637562 -288.40134)
			(xy 113.678065 -288.429296) (xy 113.713558 -288.463388) (xy 113.743123 -288.502732) (xy 113.765994 -288.546309)
			(xy 113.781578 -288.59299) (xy 113.789473 -288.641567) (xy 113.789968 -288.666174) (xy 114.108479 -288.666174)
			(xy 114.112574 -288.615446) (xy 114.124753 -288.566032) (xy 114.144701 -288.519212) (xy 114.171902 -288.476198)
			(xy 114.20565 -288.438104) (xy 114.245072 -288.405917) (xy 114.289146 -288.380471) (xy 114.336732 -288.362424)
			(xy 114.386596 -288.352244) (xy 114.437448 -288.350195) (xy 114.487969 -288.356329) (xy 114.536853 -288.370489)
			(xy 114.582832 -288.392306) (xy 114.624716 -288.421216) (xy 114.66142 -288.456471) (xy 114.691993 -288.497157)
			(xy 114.715644 -288.54222) (xy 114.73176 -288.590494) (xy 114.739924 -288.640728) (xy 114.740436 -288.666174)
			(xy 115.048533 -288.666174) (xy 115.052628 -288.615446) (xy 115.064807 -288.566032) (xy 115.084755 -288.519212)
			(xy 115.111956 -288.476198) (xy 115.145704 -288.438104) (xy 115.185126 -288.405917) (xy 115.2292 -288.380471)
			(xy 115.276786 -288.362424) (xy 115.32665 -288.352244) (xy 115.377502 -288.350195) (xy 115.428023 -288.356329)
			(xy 115.476907 -288.370489) (xy 115.522886 -288.392306) (xy 115.56477 -288.421216) (xy 115.601474 -288.456471)
			(xy 115.632047 -288.497157) (xy 115.655698 -288.54222) (xy 115.671814 -288.590494) (xy 115.679978 -288.640728)
			(xy 115.68049 -288.666174) (xy 115.999018 -288.666174) (xy 116.002978 -288.61712) (xy 116.014755 -288.569336)
			(xy 116.034046 -288.52406) (xy 116.060349 -288.482464) (xy 116.092984 -288.445627) (xy 116.131105 -288.414502)
			(xy 116.173726 -288.389895) (xy 116.219742 -288.372443) (xy 116.267961 -288.362599) (xy 116.317136 -288.360618)
			(xy 116.365991 -288.36655) (xy 116.413262 -288.380242) (xy 116.457724 -288.40134) (xy 116.498227 -288.429296)
			(xy 116.53372 -288.463388) (xy 116.563285 -288.502732) (xy 116.586156 -288.546309) (xy 116.60174 -288.59299)
			(xy 116.609635 -288.641567) (xy 116.61013 -288.666174) (xy 116.938818 -288.666174) (xy 116.942778 -288.61712)
			(xy 116.954555 -288.569336) (xy 116.973846 -288.52406) (xy 117.000149 -288.482464) (xy 117.032784 -288.445627)
			(xy 117.070905 -288.414502) (xy 117.113526 -288.389895) (xy 117.159542 -288.372443) (xy 117.207761 -288.362599)
			(xy 117.256936 -288.360618) (xy 117.305791 -288.36655) (xy 117.353062 -288.380242) (xy 117.397524 -288.40134)
			(xy 117.438027 -288.429296) (xy 117.47352 -288.463388) (xy 117.503085 -288.502732) (xy 117.525956 -288.546309)
			(xy 117.54154 -288.59299) (xy 117.549435 -288.641567) (xy 117.54993 -288.666174) (xy 117.878872 -288.666174)
			(xy 117.882832 -288.61712) (xy 117.894609 -288.569336) (xy 117.9139 -288.52406) (xy 117.940203 -288.482464)
			(xy 117.972838 -288.445627) (xy 118.010959 -288.414502) (xy 118.05358 -288.389895) (xy 118.099596 -288.372443)
			(xy 118.147815 -288.362599) (xy 118.19699 -288.360618) (xy 118.245845 -288.36655) (xy 118.293116 -288.380242)
			(xy 118.337578 -288.40134) (xy 118.378081 -288.429296) (xy 118.413574 -288.463388) (xy 118.443139 -288.502732)
			(xy 118.46601 -288.546309) (xy 118.481594 -288.59299) (xy 118.489489 -288.641567) (xy 118.489984 -288.666174)
			(xy 118.818926 -288.666174) (xy 118.822886 -288.61712) (xy 118.834663 -288.569336) (xy 118.853954 -288.52406)
			(xy 118.880257 -288.482464) (xy 118.912892 -288.445627) (xy 118.951013 -288.414502) (xy 118.993634 -288.389895)
			(xy 119.03965 -288.372443) (xy 119.087869 -288.362599) (xy 119.137044 -288.360618) (xy 119.185899 -288.36655)
			(xy 119.23317 -288.380242) (xy 119.277632 -288.40134) (xy 119.318135 -288.429296) (xy 119.353628 -288.463388)
			(xy 119.383193 -288.502732) (xy 119.406064 -288.546309) (xy 119.421648 -288.59299) (xy 119.429543 -288.641567)
			(xy 119.430038 -288.666174) (xy 119.75898 -288.666174) (xy 119.76294 -288.61712) (xy 119.774717 -288.569336)
			(xy 119.794008 -288.52406) (xy 119.820311 -288.482464) (xy 119.852946 -288.445627) (xy 119.891067 -288.414502)
			(xy 119.933688 -288.389895) (xy 119.979704 -288.372443) (xy 120.027923 -288.362599) (xy 120.077098 -288.360618)
			(xy 120.125953 -288.36655) (xy 120.173224 -288.380242) (xy 120.217686 -288.40134) (xy 120.258189 -288.429296)
			(xy 120.293682 -288.463388) (xy 120.323247 -288.502732) (xy 120.346118 -288.546309) (xy 120.361702 -288.59299)
			(xy 120.369597 -288.641567) (xy 120.370092 -288.666174) (xy 120.699034 -288.666174) (xy 120.702994 -288.61712)
			(xy 120.714771 -288.569336) (xy 120.734062 -288.52406) (xy 120.760365 -288.482464) (xy 120.793 -288.445627)
			(xy 120.831121 -288.414502) (xy 120.873742 -288.389895) (xy 120.919758 -288.372443) (xy 120.967977 -288.362599)
			(xy 121.017152 -288.360618) (xy 121.066007 -288.36655) (xy 121.113278 -288.380242) (xy 121.15774 -288.40134)
			(xy 121.198243 -288.429296) (xy 121.233736 -288.463388) (xy 121.263301 -288.502732) (xy 121.286172 -288.546309)
			(xy 121.301756 -288.59299) (xy 121.309651 -288.641567) (xy 121.310146 -288.666174) (xy 121.638834 -288.666174)
			(xy 121.642794 -288.61712) (xy 121.654571 -288.569336) (xy 121.673862 -288.52406) (xy 121.700165 -288.482464)
			(xy 121.7328 -288.445627) (xy 121.770921 -288.414502) (xy 121.813542 -288.389895) (xy 121.859558 -288.372443)
			(xy 121.907777 -288.362599) (xy 121.956952 -288.360618) (xy 122.005807 -288.36655) (xy 122.053078 -288.380242)
			(xy 122.09754 -288.40134) (xy 122.138043 -288.429296) (xy 122.173536 -288.463388) (xy 122.203101 -288.502732)
			(xy 122.225972 -288.546309) (xy 122.241556 -288.59299) (xy 122.249451 -288.641567) (xy 122.249946 -288.666174)
			(xy 122.578888 -288.666174) (xy 122.582848 -288.61712) (xy 122.594625 -288.569336) (xy 122.613916 -288.52406)
			(xy 122.640219 -288.482464) (xy 122.672854 -288.445627) (xy 122.710975 -288.414502) (xy 122.753596 -288.389895)
			(xy 122.799612 -288.372443) (xy 122.847831 -288.362599) (xy 122.897006 -288.360618) (xy 122.945861 -288.36655)
			(xy 122.993132 -288.380242) (xy 123.037594 -288.40134) (xy 123.078097 -288.429296) (xy 123.11359 -288.463388)
			(xy 123.143155 -288.502732) (xy 123.166026 -288.546309) (xy 123.18161 -288.59299) (xy 123.189505 -288.641567)
			(xy 123.19 -288.666174) (xy 123.518942 -288.666174) (xy 123.522902 -288.61712) (xy 123.534679 -288.569336)
			(xy 123.55397 -288.52406) (xy 123.580273 -288.482464) (xy 123.612908 -288.445627) (xy 123.651029 -288.414502)
			(xy 123.69365 -288.389895) (xy 123.739666 -288.372443) (xy 123.787885 -288.362599) (xy 123.83706 -288.360618)
			(xy 123.885915 -288.36655) (xy 123.933186 -288.380242) (xy 123.977648 -288.40134) (xy 124.018151 -288.429296)
			(xy 124.053644 -288.463388) (xy 124.083209 -288.502732) (xy 124.10608 -288.546309) (xy 124.121664 -288.59299)
			(xy 124.129559 -288.641567) (xy 124.130054 -288.666174) (xy 124.458996 -288.666174) (xy 124.462956 -288.61712)
			(xy 124.474733 -288.569336) (xy 124.494024 -288.52406) (xy 124.520327 -288.482464) (xy 124.552962 -288.445627)
			(xy 124.591083 -288.414502) (xy 124.633704 -288.389895) (xy 124.67972 -288.372443) (xy 124.727939 -288.362599)
			(xy 124.777114 -288.360618) (xy 124.825969 -288.36655) (xy 124.87324 -288.380242) (xy 124.917702 -288.40134)
			(xy 124.958205 -288.429296) (xy 124.993698 -288.463388) (xy 125.023263 -288.502732) (xy 125.046134 -288.546309)
			(xy 125.061718 -288.59299) (xy 125.069613 -288.641567) (xy 125.070108 -288.666174) (xy 125.39905 -288.666174)
			(xy 125.40301 -288.61712) (xy 125.414787 -288.569336) (xy 125.434078 -288.52406) (xy 125.460381 -288.482464)
			(xy 125.493016 -288.445627) (xy 125.531137 -288.414502) (xy 125.573758 -288.389895) (xy 125.619774 -288.372443)
			(xy 125.667993 -288.362599) (xy 125.717168 -288.360618) (xy 125.766023 -288.36655) (xy 125.813294 -288.380242)
			(xy 125.857756 -288.40134) (xy 125.898259 -288.429296) (xy 125.933752 -288.463388) (xy 125.963317 -288.502732)
			(xy 125.986188 -288.546309) (xy 126.001772 -288.59299) (xy 126.009667 -288.641567) (xy 126.010162 -288.666174)
			(xy 126.009667 -288.690781) (xy 126.001772 -288.739358) (xy 125.986188 -288.786039) (xy 125.963317 -288.829616)
			(xy 125.933752 -288.86896) (xy 125.898259 -288.903052) (xy 125.857756 -288.931008) (xy 125.813294 -288.952106)
			(xy 125.766023 -288.965798) (xy 125.717168 -288.97173) (xy 125.667993 -288.969749) (xy 125.619774 -288.959905)
			(xy 125.573758 -288.942453) (xy 125.531137 -288.917846) (xy 125.493016 -288.886721) (xy 125.460381 -288.849884)
			(xy 125.434078 -288.808288) (xy 125.414787 -288.763012) (xy 125.40301 -288.715228) (xy 125.39905 -288.666174)
			(xy 125.070108 -288.666174) (xy 125.069613 -288.690781) (xy 125.061718 -288.739358) (xy 125.046134 -288.786039)
			(xy 125.023263 -288.829616) (xy 124.993698 -288.86896) (xy 124.958205 -288.903052) (xy 124.917702 -288.931008)
			(xy 124.87324 -288.952106) (xy 124.825969 -288.965798) (xy 124.777114 -288.97173) (xy 124.727939 -288.969749)
			(xy 124.67972 -288.959905) (xy 124.633704 -288.942453) (xy 124.591083 -288.917846) (xy 124.552962 -288.886721)
			(xy 124.520327 -288.849884) (xy 124.494024 -288.808288) (xy 124.474733 -288.763012) (xy 124.462956 -288.715228)
			(xy 124.458996 -288.666174) (xy 124.130054 -288.666174) (xy 124.129559 -288.690781) (xy 124.121664 -288.739358)
			(xy 124.10608 -288.786039) (xy 124.083209 -288.829616) (xy 124.053644 -288.86896) (xy 124.018151 -288.903052)
			(xy 123.977648 -288.931008) (xy 123.933186 -288.952106) (xy 123.885915 -288.965798) (xy 123.83706 -288.97173)
			(xy 123.787885 -288.969749) (xy 123.739666 -288.959905) (xy 123.69365 -288.942453) (xy 123.651029 -288.917846)
			(xy 123.612908 -288.886721) (xy 123.580273 -288.849884) (xy 123.55397 -288.808288) (xy 123.534679 -288.763012)
			(xy 123.522902 -288.715228) (xy 123.518942 -288.666174) (xy 123.19 -288.666174) (xy 123.189505 -288.690781)
			(xy 123.18161 -288.739358) (xy 123.166026 -288.786039) (xy 123.143155 -288.829616) (xy 123.11359 -288.86896)
			(xy 123.078097 -288.903052) (xy 123.037594 -288.931008) (xy 122.993132 -288.952106) (xy 122.945861 -288.965798)
			(xy 122.897006 -288.97173) (xy 122.847831 -288.969749) (xy 122.799612 -288.959905) (xy 122.753596 -288.942453)
			(xy 122.710975 -288.917846) (xy 122.672854 -288.886721) (xy 122.640219 -288.849884) (xy 122.613916 -288.808288)
			(xy 122.594625 -288.763012) (xy 122.582848 -288.715228) (xy 122.578888 -288.666174) (xy 122.249946 -288.666174)
			(xy 122.249451 -288.690781) (xy 122.241556 -288.739358) (xy 122.225972 -288.786039) (xy 122.203101 -288.829616)
			(xy 122.173536 -288.86896) (xy 122.138043 -288.903052) (xy 122.09754 -288.931008) (xy 122.053078 -288.952106)
			(xy 122.005807 -288.965798) (xy 121.956952 -288.97173) (xy 121.907777 -288.969749) (xy 121.859558 -288.959905)
			(xy 121.813542 -288.942453) (xy 121.770921 -288.917846) (xy 121.7328 -288.886721) (xy 121.700165 -288.849884)
			(xy 121.673862 -288.808288) (xy 121.654571 -288.763012) (xy 121.642794 -288.715228) (xy 121.638834 -288.666174)
			(xy 121.310146 -288.666174) (xy 121.309651 -288.690781) (xy 121.301756 -288.739358) (xy 121.286172 -288.786039)
			(xy 121.263301 -288.829616) (xy 121.233736 -288.86896) (xy 121.198243 -288.903052) (xy 121.15774 -288.931008)
			(xy 121.113278 -288.952106) (xy 121.066007 -288.965798) (xy 121.017152 -288.97173) (xy 120.967977 -288.969749)
			(xy 120.919758 -288.959905) (xy 120.873742 -288.942453) (xy 120.831121 -288.917846) (xy 120.793 -288.886721)
			(xy 120.760365 -288.849884) (xy 120.734062 -288.808288) (xy 120.714771 -288.763012) (xy 120.702994 -288.715228)
			(xy 120.699034 -288.666174) (xy 120.370092 -288.666174) (xy 120.369597 -288.690781) (xy 120.361702 -288.739358)
			(xy 120.346118 -288.786039) (xy 120.323247 -288.829616) (xy 120.293682 -288.86896) (xy 120.258189 -288.903052)
			(xy 120.217686 -288.931008) (xy 120.173224 -288.952106) (xy 120.125953 -288.965798) (xy 120.077098 -288.97173)
			(xy 120.027923 -288.969749) (xy 119.979704 -288.959905) (xy 119.933688 -288.942453) (xy 119.891067 -288.917846)
			(xy 119.852946 -288.886721) (xy 119.820311 -288.849884) (xy 119.794008 -288.808288) (xy 119.774717 -288.763012)
			(xy 119.76294 -288.715228) (xy 119.75898 -288.666174) (xy 119.430038 -288.666174) (xy 119.429543 -288.690781)
			(xy 119.421648 -288.739358) (xy 119.406064 -288.786039) (xy 119.383193 -288.829616) (xy 119.353628 -288.86896)
			(xy 119.318135 -288.903052) (xy 119.277632 -288.931008) (xy 119.23317 -288.952106) (xy 119.185899 -288.965798)
			(xy 119.137044 -288.97173) (xy 119.087869 -288.969749) (xy 119.03965 -288.959905) (xy 118.993634 -288.942453)
			(xy 118.951013 -288.917846) (xy 118.912892 -288.886721) (xy 118.880257 -288.849884) (xy 118.853954 -288.808288)
			(xy 118.834663 -288.763012) (xy 118.822886 -288.715228) (xy 118.818926 -288.666174) (xy 118.489984 -288.666174)
			(xy 118.489489 -288.690781) (xy 118.481594 -288.739358) (xy 118.46601 -288.786039) (xy 118.443139 -288.829616)
			(xy 118.413574 -288.86896) (xy 118.378081 -288.903052) (xy 118.337578 -288.931008) (xy 118.293116 -288.952106)
			(xy 118.245845 -288.965798) (xy 118.19699 -288.97173) (xy 118.147815 -288.969749) (xy 118.099596 -288.959905)
			(xy 118.05358 -288.942453) (xy 118.010959 -288.917846) (xy 117.972838 -288.886721) (xy 117.940203 -288.849884)
			(xy 117.9139 -288.808288) (xy 117.894609 -288.763012) (xy 117.882832 -288.715228) (xy 117.878872 -288.666174)
			(xy 117.54993 -288.666174) (xy 117.549435 -288.690781) (xy 117.54154 -288.739358) (xy 117.525956 -288.786039)
			(xy 117.503085 -288.829616) (xy 117.47352 -288.86896) (xy 117.438027 -288.903052) (xy 117.397524 -288.931008)
			(xy 117.353062 -288.952106) (xy 117.305791 -288.965798) (xy 117.256936 -288.97173) (xy 117.207761 -288.969749)
			(xy 117.159542 -288.959905) (xy 117.113526 -288.942453) (xy 117.070905 -288.917846) (xy 117.032784 -288.886721)
			(xy 117.000149 -288.849884) (xy 116.973846 -288.808288) (xy 116.954555 -288.763012) (xy 116.942778 -288.715228)
			(xy 116.938818 -288.666174) (xy 116.61013 -288.666174) (xy 116.609635 -288.690781) (xy 116.60174 -288.739358)
			(xy 116.586156 -288.786039) (xy 116.563285 -288.829616) (xy 116.53372 -288.86896) (xy 116.498227 -288.903052)
			(xy 116.457724 -288.931008) (xy 116.413262 -288.952106) (xy 116.365991 -288.965798) (xy 116.317136 -288.97173)
			(xy 116.267961 -288.969749) (xy 116.219742 -288.959905) (xy 116.173726 -288.942453) (xy 116.131105 -288.917846)
			(xy 116.092984 -288.886721) (xy 116.060349 -288.849884) (xy 116.034046 -288.808288) (xy 116.014755 -288.763012)
			(xy 116.002978 -288.715228) (xy 115.999018 -288.666174) (xy 115.68049 -288.666174) (xy 115.679978 -288.69162)
			(xy 115.671814 -288.741854) (xy 115.655698 -288.790128) (xy 115.632047 -288.835191) (xy 115.601474 -288.875877)
			(xy 115.56477 -288.911132) (xy 115.522886 -288.940042) (xy 115.476907 -288.961859) (xy 115.428023 -288.976019)
			(xy 115.377502 -288.982153) (xy 115.32665 -288.980104) (xy 115.276786 -288.969924) (xy 115.2292 -288.951877)
			(xy 115.185126 -288.926431) (xy 115.145704 -288.894244) (xy 115.111956 -288.85615) (xy 115.084755 -288.813136)
			(xy 115.064807 -288.766316) (xy 115.052628 -288.716902) (xy 115.048533 -288.666174) (xy 114.740436 -288.666174)
			(xy 114.739924 -288.69162) (xy 114.73176 -288.741854) (xy 114.715644 -288.790128) (xy 114.691993 -288.835191)
			(xy 114.66142 -288.875877) (xy 114.624716 -288.911132) (xy 114.582832 -288.940042) (xy 114.536853 -288.961859)
			(xy 114.487969 -288.976019) (xy 114.437448 -288.982153) (xy 114.386596 -288.980104) (xy 114.336732 -288.969924)
			(xy 114.289146 -288.951877) (xy 114.245072 -288.926431) (xy 114.20565 -288.894244) (xy 114.171902 -288.85615)
			(xy 114.144701 -288.813136) (xy 114.124753 -288.766316) (xy 114.112574 -288.716902) (xy 114.108479 -288.666174)
			(xy 113.789968 -288.666174) (xy 113.789473 -288.690781) (xy 113.781578 -288.739358) (xy 113.765994 -288.786039)
			(xy 113.743123 -288.829616) (xy 113.713558 -288.86896) (xy 113.678065 -288.903052) (xy 113.637562 -288.931008)
			(xy 113.5931 -288.952106) (xy 113.545829 -288.965798) (xy 113.496974 -288.97173) (xy 113.447799 -288.969749)
			(xy 113.39958 -288.959905) (xy 113.353564 -288.942453) (xy 113.310943 -288.917846) (xy 113.272822 -288.886721)
			(xy 113.240187 -288.849884) (xy 113.213884 -288.808288) (xy 113.194593 -288.763012) (xy 113.182816 -288.715228)
			(xy 113.178856 -288.666174) (xy 112.53109 -288.666174) (xy 112.544206 -289.47618) (xy 115.528864 -289.47618)
			(xy 115.532824 -289.427126) (xy 115.544601 -289.379342) (xy 115.563892 -289.334066) (xy 115.590195 -289.29247)
			(xy 115.62283 -289.255633) (xy 115.660951 -289.224508) (xy 115.703572 -289.199901) (xy 115.749588 -289.182449)
			(xy 115.797807 -289.172605) (xy 115.846982 -289.170624) (xy 115.895837 -289.176556) (xy 115.943108 -289.190248)
			(xy 115.98757 -289.211346) (xy 116.028073 -289.239302) (xy 116.063566 -289.273394) (xy 116.093131 -289.312738)
			(xy 116.116002 -289.356315) (xy 116.131586 -289.402996) (xy 116.139481 -289.451573) (xy 116.139976 -289.47618)
			(xy 116.458487 -289.47618) (xy 116.462582 -289.425452) (xy 116.474761 -289.376038) (xy 116.494709 -289.329218)
			(xy 116.52191 -289.286204) (xy 116.555658 -289.24811) (xy 116.59508 -289.215923) (xy 116.639154 -289.190477)
			(xy 116.68674 -289.17243) (xy 116.736604 -289.16225) (xy 116.787456 -289.160201) (xy 116.837977 -289.166335)
			(xy 116.886861 -289.180495) (xy 116.93284 -289.202312) (xy 116.974724 -289.231222) (xy 117.011428 -289.266477)
			(xy 117.042001 -289.307163) (xy 117.065652 -289.352226) (xy 117.081768 -289.4005) (xy 117.089932 -289.450734)
			(xy 117.090444 -289.47618) (xy 117.398541 -289.47618) (xy 117.402636 -289.425452) (xy 117.414815 -289.376038)
			(xy 117.434763 -289.329218) (xy 117.461964 -289.286204) (xy 117.495712 -289.24811) (xy 117.535134 -289.215923)
			(xy 117.579208 -289.190477) (xy 117.626794 -289.17243) (xy 117.676658 -289.16225) (xy 117.72751 -289.160201)
			(xy 117.778031 -289.166335) (xy 117.826915 -289.180495) (xy 117.872894 -289.202312) (xy 117.914778 -289.231222)
			(xy 117.951482 -289.266477) (xy 117.982055 -289.307163) (xy 118.005706 -289.352226) (xy 118.021822 -289.4005)
			(xy 118.029986 -289.450734) (xy 118.030498 -289.47618) (xy 118.349026 -289.47618) (xy 118.352986 -289.427126)
			(xy 118.364763 -289.379342) (xy 118.384054 -289.334066) (xy 118.410357 -289.29247) (xy 118.442992 -289.255633)
			(xy 118.481113 -289.224508) (xy 118.523734 -289.199901) (xy 118.56975 -289.182449) (xy 118.617969 -289.172605)
			(xy 118.667144 -289.170624) (xy 118.715999 -289.176556) (xy 118.76327 -289.190248) (xy 118.807732 -289.211346)
			(xy 118.848235 -289.239302) (xy 118.883728 -289.273394) (xy 118.913293 -289.312738) (xy 118.936164 -289.356315)
			(xy 118.951748 -289.402996) (xy 118.959643 -289.451573) (xy 118.960138 -289.47618) (xy 119.278395 -289.47618)
			(xy 119.28249 -289.425452) (xy 119.294669 -289.376038) (xy 119.314617 -289.329218) (xy 119.341818 -289.286204)
			(xy 119.375566 -289.24811) (xy 119.414988 -289.215923) (xy 119.459062 -289.190477) (xy 119.506648 -289.17243)
			(xy 119.556512 -289.16225) (xy 119.607364 -289.160201) (xy 119.657885 -289.166335) (xy 119.706769 -289.180495)
			(xy 119.752748 -289.202312) (xy 119.794632 -289.231222) (xy 119.831336 -289.266477) (xy 119.861909 -289.307163)
			(xy 119.88556 -289.352226) (xy 119.901676 -289.4005) (xy 119.90984 -289.450734) (xy 119.910352 -289.47618)
			(xy 120.218449 -289.47618) (xy 120.222544 -289.425452) (xy 120.234723 -289.376038) (xy 120.254671 -289.329218)
			(xy 120.281872 -289.286204) (xy 120.31562 -289.24811) (xy 120.355042 -289.215923) (xy 120.399116 -289.190477)
			(xy 120.446702 -289.17243) (xy 120.496566 -289.16225) (xy 120.547418 -289.160201) (xy 120.597939 -289.166335)
			(xy 120.646823 -289.180495) (xy 120.692802 -289.202312) (xy 120.734686 -289.231222) (xy 120.77139 -289.266477)
			(xy 120.801963 -289.307163) (xy 120.825614 -289.352226) (xy 120.84173 -289.4005) (xy 120.849894 -289.450734)
			(xy 120.850406 -289.47618) (xy 121.168934 -289.47618) (xy 121.172894 -289.427126) (xy 121.184671 -289.379342)
			(xy 121.203962 -289.334066) (xy 121.230265 -289.29247) (xy 121.2629 -289.255633) (xy 121.301021 -289.224508)
			(xy 121.343642 -289.199901) (xy 121.389658 -289.182449) (xy 121.437877 -289.172605) (xy 121.487052 -289.170624)
			(xy 121.535907 -289.176556) (xy 121.583178 -289.190248) (xy 121.62764 -289.211346) (xy 121.668143 -289.239302)
			(xy 121.703636 -289.273394) (xy 121.733201 -289.312738) (xy 121.756072 -289.356315) (xy 121.771656 -289.402996)
			(xy 121.779551 -289.451573) (xy 121.780046 -289.47618) (xy 122.098557 -289.47618) (xy 122.102652 -289.425452)
			(xy 122.114831 -289.376038) (xy 122.134779 -289.329218) (xy 122.16198 -289.286204) (xy 122.195728 -289.24811)
			(xy 122.23515 -289.215923) (xy 122.279224 -289.190477) (xy 122.32681 -289.17243) (xy 122.376674 -289.16225)
			(xy 122.427526 -289.160201) (xy 122.478047 -289.166335) (xy 122.526931 -289.180495) (xy 122.57291 -289.202312)
			(xy 122.614794 -289.231222) (xy 122.651498 -289.266477) (xy 122.682071 -289.307163) (xy 122.705722 -289.352226)
			(xy 122.721838 -289.4005) (xy 122.730002 -289.450734) (xy 122.730514 -289.47618) (xy 123.038611 -289.47618)
			(xy 123.042706 -289.425452) (xy 123.054885 -289.376038) (xy 123.074833 -289.329218) (xy 123.102034 -289.286204)
			(xy 123.135782 -289.24811) (xy 123.175204 -289.215923) (xy 123.219278 -289.190477) (xy 123.266864 -289.17243)
			(xy 123.316728 -289.16225) (xy 123.36758 -289.160201) (xy 123.418101 -289.166335) (xy 123.466985 -289.180495)
			(xy 123.512964 -289.202312) (xy 123.554848 -289.231222) (xy 123.591552 -289.266477) (xy 123.622125 -289.307163)
			(xy 123.645776 -289.352226) (xy 123.661892 -289.4005) (xy 123.670056 -289.450734) (xy 123.670568 -289.47618)
			(xy 123.988842 -289.47618) (xy 123.992802 -289.427126) (xy 124.004579 -289.379342) (xy 124.02387 -289.334066)
			(xy 124.050173 -289.29247) (xy 124.082808 -289.255633) (xy 124.120929 -289.224508) (xy 124.16355 -289.199901)
			(xy 124.209566 -289.182449) (xy 124.257785 -289.172605) (xy 124.30696 -289.170624) (xy 124.355815 -289.176556)
			(xy 124.403086 -289.190248) (xy 124.447548 -289.211346) (xy 124.488051 -289.239302) (xy 124.523544 -289.273394)
			(xy 124.553109 -289.312738) (xy 124.57598 -289.356315) (xy 124.591564 -289.402996) (xy 124.599459 -289.451573)
			(xy 124.599954 -289.47618) (xy 124.918465 -289.47618) (xy 124.92256 -289.425452) (xy 124.934739 -289.376038)
			(xy 124.954687 -289.329218) (xy 124.981888 -289.286204) (xy 125.015636 -289.24811) (xy 125.055058 -289.215923)
			(xy 125.099132 -289.190477) (xy 125.146718 -289.17243) (xy 125.196582 -289.16225) (xy 125.247434 -289.160201)
			(xy 125.297955 -289.166335) (xy 125.346839 -289.180495) (xy 125.392818 -289.202312) (xy 125.434702 -289.231222)
			(xy 125.471406 -289.266477) (xy 125.501979 -289.307163) (xy 125.52563 -289.352226) (xy 125.541746 -289.4005)
			(xy 125.54991 -289.450734) (xy 125.550422 -289.47618) (xy 125.858519 -289.47618) (xy 125.862614 -289.425452)
			(xy 125.874793 -289.376038) (xy 125.894741 -289.329218) (xy 125.921942 -289.286204) (xy 125.95569 -289.24811)
			(xy 125.995112 -289.215923) (xy 126.039186 -289.190477) (xy 126.086772 -289.17243) (xy 126.136636 -289.16225)
			(xy 126.187488 -289.160201) (xy 126.238009 -289.166335) (xy 126.286893 -289.180495) (xy 126.332872 -289.202312)
			(xy 126.374756 -289.231222) (xy 126.41146 -289.266477) (xy 126.442033 -289.307163) (xy 126.465684 -289.352226)
			(xy 126.4818 -289.4005) (xy 126.489964 -289.450734) (xy 126.490476 -289.47618) (xy 126.489964 -289.501626)
			(xy 126.4818 -289.55186) (xy 126.465684 -289.600134) (xy 126.442033 -289.645197) (xy 126.41146 -289.685883)
			(xy 126.374756 -289.721138) (xy 126.332872 -289.750048) (xy 126.286893 -289.771865) (xy 126.238009 -289.786025)
			(xy 126.187488 -289.792159) (xy 126.136636 -289.79011) (xy 126.086772 -289.77993) (xy 126.039186 -289.761883)
			(xy 125.995112 -289.736437) (xy 125.95569 -289.70425) (xy 125.921942 -289.666156) (xy 125.894741 -289.623142)
			(xy 125.874793 -289.576322) (xy 125.862614 -289.526908) (xy 125.858519 -289.47618) (xy 125.550422 -289.47618)
			(xy 125.54991 -289.501626) (xy 125.541746 -289.55186) (xy 125.52563 -289.600134) (xy 125.501979 -289.645197)
			(xy 125.471406 -289.685883) (xy 125.434702 -289.721138) (xy 125.392818 -289.750048) (xy 125.346839 -289.771865)
			(xy 125.297955 -289.786025) (xy 125.247434 -289.792159) (xy 125.196582 -289.79011) (xy 125.146718 -289.77993)
			(xy 125.099132 -289.761883) (xy 125.055058 -289.736437) (xy 125.015636 -289.70425) (xy 124.981888 -289.666156)
			(xy 124.954687 -289.623142) (xy 124.934739 -289.576322) (xy 124.92256 -289.526908) (xy 124.918465 -289.47618)
			(xy 124.599954 -289.47618) (xy 124.599459 -289.500787) (xy 124.591564 -289.549364) (xy 124.57598 -289.596045)
			(xy 124.553109 -289.639622) (xy 124.523544 -289.678966) (xy 124.488051 -289.713058) (xy 124.447548 -289.741014)
			(xy 124.403086 -289.762112) (xy 124.355815 -289.775804) (xy 124.30696 -289.781736) (xy 124.257785 -289.779755)
			(xy 124.209566 -289.769911) (xy 124.16355 -289.752459) (xy 124.120929 -289.727852) (xy 124.082808 -289.696727)
			(xy 124.050173 -289.65989) (xy 124.02387 -289.618294) (xy 124.004579 -289.573018) (xy 123.992802 -289.525234)
			(xy 123.988842 -289.47618) (xy 123.670568 -289.47618) (xy 123.670056 -289.501626) (xy 123.661892 -289.55186)
			(xy 123.645776 -289.600134) (xy 123.622125 -289.645197) (xy 123.591552 -289.685883) (xy 123.554848 -289.721138)
			(xy 123.512964 -289.750048) (xy 123.466985 -289.771865) (xy 123.418101 -289.786025) (xy 123.36758 -289.792159)
			(xy 123.316728 -289.79011) (xy 123.266864 -289.77993) (xy 123.219278 -289.761883) (xy 123.175204 -289.736437)
			(xy 123.135782 -289.70425) (xy 123.102034 -289.666156) (xy 123.074833 -289.623142) (xy 123.054885 -289.576322)
			(xy 123.042706 -289.526908) (xy 123.038611 -289.47618) (xy 122.730514 -289.47618) (xy 122.730002 -289.501626)
			(xy 122.721838 -289.55186) (xy 122.705722 -289.600134) (xy 122.682071 -289.645197) (xy 122.651498 -289.685883)
			(xy 122.614794 -289.721138) (xy 122.57291 -289.750048) (xy 122.526931 -289.771865) (xy 122.478047 -289.786025)
			(xy 122.427526 -289.792159) (xy 122.376674 -289.79011) (xy 122.32681 -289.77993) (xy 122.279224 -289.761883)
			(xy 122.23515 -289.736437) (xy 122.195728 -289.70425) (xy 122.16198 -289.666156) (xy 122.134779 -289.623142)
			(xy 122.114831 -289.576322) (xy 122.102652 -289.526908) (xy 122.098557 -289.47618) (xy 121.780046 -289.47618)
			(xy 121.779551 -289.500787) (xy 121.771656 -289.549364) (xy 121.756072 -289.596045) (xy 121.733201 -289.639622)
			(xy 121.703636 -289.678966) (xy 121.668143 -289.713058) (xy 121.62764 -289.741014) (xy 121.583178 -289.762112)
			(xy 121.535907 -289.775804) (xy 121.487052 -289.781736) (xy 121.437877 -289.779755) (xy 121.389658 -289.769911)
			(xy 121.343642 -289.752459) (xy 121.301021 -289.727852) (xy 121.2629 -289.696727) (xy 121.230265 -289.65989)
			(xy 121.203962 -289.618294) (xy 121.184671 -289.573018) (xy 121.172894 -289.525234) (xy 121.168934 -289.47618)
			(xy 120.850406 -289.47618) (xy 120.849894 -289.501626) (xy 120.84173 -289.55186) (xy 120.825614 -289.600134)
			(xy 120.801963 -289.645197) (xy 120.77139 -289.685883) (xy 120.734686 -289.721138) (xy 120.692802 -289.750048)
			(xy 120.646823 -289.771865) (xy 120.597939 -289.786025) (xy 120.547418 -289.792159) (xy 120.496566 -289.79011)
			(xy 120.446702 -289.77993) (xy 120.399116 -289.761883) (xy 120.355042 -289.736437) (xy 120.31562 -289.70425)
			(xy 120.281872 -289.666156) (xy 120.254671 -289.623142) (xy 120.234723 -289.576322) (xy 120.222544 -289.526908)
			(xy 120.218449 -289.47618) (xy 119.910352 -289.47618) (xy 119.90984 -289.501626) (xy 119.901676 -289.55186)
			(xy 119.88556 -289.600134) (xy 119.861909 -289.645197) (xy 119.831336 -289.685883) (xy 119.794632 -289.721138)
			(xy 119.752748 -289.750048) (xy 119.706769 -289.771865) (xy 119.657885 -289.786025) (xy 119.607364 -289.792159)
			(xy 119.556512 -289.79011) (xy 119.506648 -289.77993) (xy 119.459062 -289.761883) (xy 119.414988 -289.736437)
			(xy 119.375566 -289.70425) (xy 119.341818 -289.666156) (xy 119.314617 -289.623142) (xy 119.294669 -289.576322)
			(xy 119.28249 -289.526908) (xy 119.278395 -289.47618) (xy 118.960138 -289.47618) (xy 118.959643 -289.500787)
			(xy 118.951748 -289.549364) (xy 118.936164 -289.596045) (xy 118.913293 -289.639622) (xy 118.883728 -289.678966)
			(xy 118.848235 -289.713058) (xy 118.807732 -289.741014) (xy 118.76327 -289.762112) (xy 118.715999 -289.775804)
			(xy 118.667144 -289.781736) (xy 118.617969 -289.779755) (xy 118.56975 -289.769911) (xy 118.523734 -289.752459)
			(xy 118.481113 -289.727852) (xy 118.442992 -289.696727) (xy 118.410357 -289.65989) (xy 118.384054 -289.618294)
			(xy 118.364763 -289.573018) (xy 118.352986 -289.525234) (xy 118.349026 -289.47618) (xy 118.030498 -289.47618)
			(xy 118.029986 -289.501626) (xy 118.021822 -289.55186) (xy 118.005706 -289.600134) (xy 117.982055 -289.645197)
			(xy 117.951482 -289.685883) (xy 117.914778 -289.721138) (xy 117.872894 -289.750048) (xy 117.826915 -289.771865)
			(xy 117.778031 -289.786025) (xy 117.72751 -289.792159) (xy 117.676658 -289.79011) (xy 117.626794 -289.77993)
			(xy 117.579208 -289.761883) (xy 117.535134 -289.736437) (xy 117.495712 -289.70425) (xy 117.461964 -289.666156)
			(xy 117.434763 -289.623142) (xy 117.414815 -289.576322) (xy 117.402636 -289.526908) (xy 117.398541 -289.47618)
			(xy 117.090444 -289.47618) (xy 117.089932 -289.501626) (xy 117.081768 -289.55186) (xy 117.065652 -289.600134)
			(xy 117.042001 -289.645197) (xy 117.011428 -289.685883) (xy 116.974724 -289.721138) (xy 116.93284 -289.750048)
			(xy 116.886861 -289.771865) (xy 116.837977 -289.786025) (xy 116.787456 -289.792159) (xy 116.736604 -289.79011)
			(xy 116.68674 -289.77993) (xy 116.639154 -289.761883) (xy 116.59508 -289.736437) (xy 116.555658 -289.70425)
			(xy 116.52191 -289.666156) (xy 116.494709 -289.623142) (xy 116.474761 -289.576322) (xy 116.462582 -289.526908)
			(xy 116.458487 -289.47618) (xy 116.139976 -289.47618) (xy 116.139481 -289.500787) (xy 116.131586 -289.549364)
			(xy 116.116002 -289.596045) (xy 116.093131 -289.639622) (xy 116.063566 -289.678966) (xy 116.028073 -289.713058)
			(xy 115.98757 -289.741014) (xy 115.943108 -289.762112) (xy 115.895837 -289.775804) (xy 115.846982 -289.781736)
			(xy 115.797807 -289.779755) (xy 115.749588 -289.769911) (xy 115.703572 -289.752459) (xy 115.660951 -289.727852)
			(xy 115.62283 -289.696727) (xy 115.590195 -289.65989) (xy 115.563892 -289.618294) (xy 115.544601 -289.573018)
			(xy 115.532824 -289.525234) (xy 115.528864 -289.47618) (xy 112.544206 -289.47618) (xy 112.557322 -290.286186)
			(xy 113.178856 -290.286186) (xy 113.182816 -290.237132) (xy 113.194593 -290.189348) (xy 113.213884 -290.144072)
			(xy 113.240187 -290.102476) (xy 113.272822 -290.065639) (xy 113.310943 -290.034514) (xy 113.353564 -290.009907)
			(xy 113.39958 -289.992455) (xy 113.447799 -289.982611) (xy 113.496974 -289.98063) (xy 113.545829 -289.986562)
			(xy 113.5931 -290.000254) (xy 113.637562 -290.021352) (xy 113.678065 -290.049308) (xy 113.713558 -290.0834)
			(xy 113.743123 -290.122744) (xy 113.765994 -290.166321) (xy 113.781578 -290.213002) (xy 113.789473 -290.261579)
			(xy 113.789968 -290.286186) (xy 114.108479 -290.286186) (xy 114.112574 -290.235458) (xy 114.124753 -290.186044)
			(xy 114.144701 -290.139224) (xy 114.171902 -290.09621) (xy 114.20565 -290.058116) (xy 114.245072 -290.025929)
			(xy 114.289146 -290.000483) (xy 114.336732 -289.982436) (xy 114.386596 -289.972256) (xy 114.437448 -289.970207)
			(xy 114.487969 -289.976341) (xy 114.536853 -289.990501) (xy 114.582832 -290.012318) (xy 114.624716 -290.041228)
			(xy 114.66142 -290.076483) (xy 114.691993 -290.117169) (xy 114.715644 -290.162232) (xy 114.73176 -290.210506)
			(xy 114.739924 -290.26074) (xy 114.740436 -290.286186) (xy 115.048533 -290.286186) (xy 115.052628 -290.235458)
			(xy 115.064807 -290.186044) (xy 115.084755 -290.139224) (xy 115.111956 -290.09621) (xy 115.145704 -290.058116)
			(xy 115.185126 -290.025929) (xy 115.2292 -290.000483) (xy 115.276786 -289.982436) (xy 115.32665 -289.972256)
			(xy 115.377502 -289.970207) (xy 115.428023 -289.976341) (xy 115.476907 -289.990501) (xy 115.522886 -290.012318)
			(xy 115.56477 -290.041228) (xy 115.601474 -290.076483) (xy 115.632047 -290.117169) (xy 115.655698 -290.162232)
			(xy 115.671814 -290.210506) (xy 115.679978 -290.26074) (xy 115.68049 -290.286186) (xy 115.999018 -290.286186)
			(xy 116.002978 -290.237132) (xy 116.014755 -290.189348) (xy 116.034046 -290.144072) (xy 116.060349 -290.102476)
			(xy 116.092984 -290.065639) (xy 116.131105 -290.034514) (xy 116.173726 -290.009907) (xy 116.219742 -289.992455)
			(xy 116.267961 -289.982611) (xy 116.317136 -289.98063) (xy 116.365991 -289.986562) (xy 116.413262 -290.000254)
			(xy 116.457724 -290.021352) (xy 116.498227 -290.049308) (xy 116.53372 -290.0834) (xy 116.563285 -290.122744)
			(xy 116.586156 -290.166321) (xy 116.60174 -290.213002) (xy 116.609635 -290.261579) (xy 116.61013 -290.286186)
			(xy 118.818926 -290.286186) (xy 118.822886 -290.237132) (xy 118.834663 -290.189348) (xy 118.853954 -290.144072)
			(xy 118.880257 -290.102476) (xy 118.912892 -290.065639) (xy 118.951013 -290.034514) (xy 118.993634 -290.009907)
			(xy 119.03965 -289.992455) (xy 119.087869 -289.982611) (xy 119.137044 -289.98063) (xy 119.185899 -289.986562)
			(xy 119.23317 -290.000254) (xy 119.277632 -290.021352) (xy 119.318135 -290.049308) (xy 119.353628 -290.0834)
			(xy 119.383193 -290.122744) (xy 119.406064 -290.166321) (xy 119.421648 -290.213002) (xy 119.429543 -290.261579)
			(xy 119.430038 -290.286186) (xy 121.638834 -290.286186) (xy 121.642794 -290.237132) (xy 121.654571 -290.189348)
			(xy 121.673862 -290.144072) (xy 121.700165 -290.102476) (xy 121.7328 -290.065639) (xy 121.770921 -290.034514)
			(xy 121.813542 -290.009907) (xy 121.859558 -289.992455) (xy 121.907777 -289.982611) (xy 121.956952 -289.98063)
			(xy 122.005807 -289.986562) (xy 122.053078 -290.000254) (xy 122.09754 -290.021352) (xy 122.138043 -290.049308)
			(xy 122.173536 -290.0834) (xy 122.203101 -290.122744) (xy 122.225972 -290.166321) (xy 122.241556 -290.213002)
			(xy 122.249451 -290.261579) (xy 122.249946 -290.286186) (xy 124.458996 -290.286186) (xy 124.462956 -290.237132)
			(xy 124.474733 -290.189348) (xy 124.494024 -290.144072) (xy 124.520327 -290.102476) (xy 124.552962 -290.065639)
			(xy 124.591083 -290.034514) (xy 124.633704 -290.009907) (xy 124.67972 -289.992455) (xy 124.727939 -289.982611)
			(xy 124.777114 -289.98063) (xy 124.825969 -289.986562) (xy 124.87324 -290.000254) (xy 124.917702 -290.021352)
			(xy 124.958205 -290.049308) (xy 124.993698 -290.0834) (xy 125.023263 -290.122744) (xy 125.046134 -290.166321)
			(xy 125.061718 -290.213002) (xy 125.069613 -290.261579) (xy 125.070108 -290.286186) (xy 125.069613 -290.310793)
			(xy 125.061718 -290.35937) (xy 125.046134 -290.406051) (xy 125.023263 -290.449628) (xy 124.993698 -290.488972)
			(xy 124.958205 -290.523064) (xy 124.917702 -290.55102) (xy 124.87324 -290.572118) (xy 124.825969 -290.58581)
			(xy 124.777114 -290.591742) (xy 124.727939 -290.589761) (xy 124.67972 -290.579917) (xy 124.633704 -290.562465)
			(xy 124.591083 -290.537858) (xy 124.552962 -290.506733) (xy 124.520327 -290.469896) (xy 124.494024 -290.4283)
			(xy 124.474733 -290.383024) (xy 124.462956 -290.33524) (xy 124.458996 -290.286186) (xy 122.249946 -290.286186)
			(xy 122.249451 -290.310793) (xy 122.241556 -290.35937) (xy 122.225972 -290.406051) (xy 122.203101 -290.449628)
			(xy 122.173536 -290.488972) (xy 122.138043 -290.523064) (xy 122.09754 -290.55102) (xy 122.053078 -290.572118)
			(xy 122.005807 -290.58581) (xy 121.956952 -290.591742) (xy 121.907777 -290.589761) (xy 121.859558 -290.579917)
			(xy 121.813542 -290.562465) (xy 121.770921 -290.537858) (xy 121.7328 -290.506733) (xy 121.700165 -290.469896)
			(xy 121.673862 -290.4283) (xy 121.654571 -290.383024) (xy 121.642794 -290.33524) (xy 121.638834 -290.286186)
			(xy 119.430038 -290.286186) (xy 119.429543 -290.310793) (xy 119.421648 -290.35937) (xy 119.406064 -290.406051)
			(xy 119.383193 -290.449628) (xy 119.353628 -290.488972) (xy 119.318135 -290.523064) (xy 119.277632 -290.55102)
			(xy 119.23317 -290.572118) (xy 119.185899 -290.58581) (xy 119.137044 -290.591742) (xy 119.087869 -290.589761)
			(xy 119.03965 -290.579917) (xy 118.993634 -290.562465) (xy 118.951013 -290.537858) (xy 118.912892 -290.506733)
			(xy 118.880257 -290.469896) (xy 118.853954 -290.4283) (xy 118.834663 -290.383024) (xy 118.822886 -290.33524)
			(xy 118.818926 -290.286186) (xy 116.61013 -290.286186) (xy 116.609635 -290.310793) (xy 116.60174 -290.35937)
			(xy 116.586156 -290.406051) (xy 116.563285 -290.449628) (xy 116.53372 -290.488972) (xy 116.498227 -290.523064)
			(xy 116.457724 -290.55102) (xy 116.413262 -290.572118) (xy 116.365991 -290.58581) (xy 116.317136 -290.591742)
			(xy 116.267961 -290.589761) (xy 116.219742 -290.579917) (xy 116.173726 -290.562465) (xy 116.131105 -290.537858)
			(xy 116.092984 -290.506733) (xy 116.060349 -290.469896) (xy 116.034046 -290.4283) (xy 116.014755 -290.383024)
			(xy 116.002978 -290.33524) (xy 115.999018 -290.286186) (xy 115.68049 -290.286186) (xy 115.679978 -290.311632)
			(xy 115.671814 -290.361866) (xy 115.655698 -290.41014) (xy 115.632047 -290.455203) (xy 115.601474 -290.495889)
			(xy 115.56477 -290.531144) (xy 115.522886 -290.560054) (xy 115.476907 -290.581871) (xy 115.428023 -290.596031)
			(xy 115.377502 -290.602165) (xy 115.32665 -290.600116) (xy 115.276786 -290.589936) (xy 115.2292 -290.571889)
			(xy 115.185126 -290.546443) (xy 115.145704 -290.514256) (xy 115.111956 -290.476162) (xy 115.084755 -290.433148)
			(xy 115.064807 -290.386328) (xy 115.052628 -290.336914) (xy 115.048533 -290.286186) (xy 114.740436 -290.286186)
			(xy 114.739924 -290.311632) (xy 114.73176 -290.361866) (xy 114.715644 -290.41014) (xy 114.691993 -290.455203)
			(xy 114.66142 -290.495889) (xy 114.624716 -290.531144) (xy 114.582832 -290.560054) (xy 114.536853 -290.581871)
			(xy 114.487969 -290.596031) (xy 114.437448 -290.602165) (xy 114.386596 -290.600116) (xy 114.336732 -290.589936)
			(xy 114.289146 -290.571889) (xy 114.245072 -290.546443) (xy 114.20565 -290.514256) (xy 114.171902 -290.476162)
			(xy 114.144701 -290.433148) (xy 114.124753 -290.386328) (xy 114.112574 -290.336914) (xy 114.108479 -290.286186)
			(xy 113.789968 -290.286186) (xy 113.789473 -290.310793) (xy 113.781578 -290.35937) (xy 113.765994 -290.406051)
			(xy 113.743123 -290.449628) (xy 113.713558 -290.488972) (xy 113.678065 -290.523064) (xy 113.637562 -290.55102)
			(xy 113.5931 -290.572118) (xy 113.545829 -290.58581) (xy 113.496974 -290.591742) (xy 113.447799 -290.589761)
			(xy 113.39958 -290.579917) (xy 113.353564 -290.562465) (xy 113.310943 -290.537858) (xy 113.272822 -290.506733)
			(xy 113.240187 -290.469896) (xy 113.213884 -290.4283) (xy 113.194593 -290.383024) (xy 113.182816 -290.33524)
			(xy 113.178856 -290.286186) (xy 112.557322 -290.286186) (xy 112.570438 -291.096192) (xy 115.528864 -291.096192)
			(xy 115.532824 -291.047138) (xy 115.544601 -290.999354) (xy 115.563892 -290.954078) (xy 115.590195 -290.912482)
			(xy 115.62283 -290.875645) (xy 115.660951 -290.84452) (xy 115.703572 -290.819913) (xy 115.749588 -290.802461)
			(xy 115.797807 -290.792617) (xy 115.846982 -290.790636) (xy 115.895837 -290.796568) (xy 115.943108 -290.81026)
			(xy 115.98757 -290.831358) (xy 116.028073 -290.859314) (xy 116.063566 -290.893406) (xy 116.093131 -290.93275)
			(xy 116.116002 -290.976327) (xy 116.131586 -291.023008) (xy 116.139481 -291.071585) (xy 116.139976 -291.096192)
			(xy 116.458487 -291.096192) (xy 116.462582 -291.045464) (xy 116.474761 -290.99605) (xy 116.494709 -290.94923)
			(xy 116.52191 -290.906216) (xy 116.555658 -290.868122) (xy 116.59508 -290.835935) (xy 116.639154 -290.810489)
			(xy 116.68674 -290.792442) (xy 116.736604 -290.782262) (xy 116.787456 -290.780213) (xy 116.837977 -290.786347)
			(xy 116.886861 -290.800507) (xy 116.93284 -290.822324) (xy 116.974724 -290.851234) (xy 117.011428 -290.886489)
			(xy 117.042001 -290.927175) (xy 117.065652 -290.972238) (xy 117.081768 -291.020512) (xy 117.089932 -291.070746)
			(xy 117.090444 -291.096192) (xy 117.398541 -291.096192) (xy 117.402636 -291.045464) (xy 117.414815 -290.99605)
			(xy 117.434763 -290.94923) (xy 117.461964 -290.906216) (xy 117.495712 -290.868122) (xy 117.535134 -290.835935)
			(xy 117.579208 -290.810489) (xy 117.626794 -290.792442) (xy 117.676658 -290.782262) (xy 117.72751 -290.780213)
			(xy 117.778031 -290.786347) (xy 117.826915 -290.800507) (xy 117.872894 -290.822324) (xy 117.914778 -290.851234)
			(xy 117.951482 -290.886489) (xy 117.982055 -290.927175) (xy 118.005706 -290.972238) (xy 118.021822 -291.020512)
			(xy 118.029986 -291.070746) (xy 118.030498 -291.096192) (xy 118.349026 -291.096192) (xy 118.352986 -291.047138)
			(xy 118.364763 -290.999354) (xy 118.384054 -290.954078) (xy 118.410357 -290.912482) (xy 118.442992 -290.875645)
			(xy 118.481113 -290.84452) (xy 118.523734 -290.819913) (xy 118.56975 -290.802461) (xy 118.617969 -290.792617)
			(xy 118.667144 -290.790636) (xy 118.715999 -290.796568) (xy 118.76327 -290.81026) (xy 118.807732 -290.831358)
			(xy 118.848235 -290.859314) (xy 118.883728 -290.893406) (xy 118.913293 -290.93275) (xy 118.936164 -290.976327)
			(xy 118.951748 -291.023008) (xy 118.959643 -291.071585) (xy 118.960138 -291.096192) (xy 119.278395 -291.096192)
			(xy 119.28249 -291.045464) (xy 119.294669 -290.99605) (xy 119.314617 -290.94923) (xy 119.341818 -290.906216)
			(xy 119.375566 -290.868122) (xy 119.414988 -290.835935) (xy 119.459062 -290.810489) (xy 119.506648 -290.792442)
			(xy 119.556512 -290.782262) (xy 119.607364 -290.780213) (xy 119.657885 -290.786347) (xy 119.706769 -290.800507)
			(xy 119.752748 -290.822324) (xy 119.794632 -290.851234) (xy 119.831336 -290.886489) (xy 119.861909 -290.927175)
			(xy 119.88556 -290.972238) (xy 119.901676 -291.020512) (xy 119.90984 -291.070746) (xy 119.910352 -291.096192)
			(xy 120.218449 -291.096192) (xy 120.222544 -291.045464) (xy 120.234723 -290.99605) (xy 120.254671 -290.94923)
			(xy 120.281872 -290.906216) (xy 120.31562 -290.868122) (xy 120.355042 -290.835935) (xy 120.399116 -290.810489)
			(xy 120.446702 -290.792442) (xy 120.496566 -290.782262) (xy 120.547418 -290.780213) (xy 120.597939 -290.786347)
			(xy 120.646823 -290.800507) (xy 120.692802 -290.822324) (xy 120.734686 -290.851234) (xy 120.77139 -290.886489)
			(xy 120.801963 -290.927175) (xy 120.825614 -290.972238) (xy 120.84173 -291.020512) (xy 120.849894 -291.070746)
			(xy 120.850406 -291.096192) (xy 121.168934 -291.096192) (xy 121.172894 -291.047138) (xy 121.184671 -290.999354)
			(xy 121.203962 -290.954078) (xy 121.230265 -290.912482) (xy 121.2629 -290.875645) (xy 121.301021 -290.84452)
			(xy 121.343642 -290.819913) (xy 121.389658 -290.802461) (xy 121.437877 -290.792617) (xy 121.487052 -290.790636)
			(xy 121.535907 -290.796568) (xy 121.583178 -290.81026) (xy 121.62764 -290.831358) (xy 121.668143 -290.859314)
			(xy 121.703636 -290.893406) (xy 121.733201 -290.93275) (xy 121.756072 -290.976327) (xy 121.771656 -291.023008)
			(xy 121.779551 -291.071585) (xy 121.780046 -291.096192) (xy 122.098557 -291.096192) (xy 122.102652 -291.045464)
			(xy 122.114831 -290.99605) (xy 122.134779 -290.94923) (xy 122.16198 -290.906216) (xy 122.195728 -290.868122)
			(xy 122.23515 -290.835935) (xy 122.279224 -290.810489) (xy 122.32681 -290.792442) (xy 122.376674 -290.782262)
			(xy 122.427526 -290.780213) (xy 122.478047 -290.786347) (xy 122.526931 -290.800507) (xy 122.57291 -290.822324)
			(xy 122.614794 -290.851234) (xy 122.651498 -290.886489) (xy 122.682071 -290.927175) (xy 122.705722 -290.972238)
			(xy 122.721838 -291.020512) (xy 122.730002 -291.070746) (xy 122.730514 -291.096192) (xy 123.038611 -291.096192)
			(xy 123.042706 -291.045464) (xy 123.054885 -290.99605) (xy 123.074833 -290.94923) (xy 123.102034 -290.906216)
			(xy 123.135782 -290.868122) (xy 123.175204 -290.835935) (xy 123.219278 -290.810489) (xy 123.266864 -290.792442)
			(xy 123.316728 -290.782262) (xy 123.36758 -290.780213) (xy 123.418101 -290.786347) (xy 123.466985 -290.800507)
			(xy 123.512964 -290.822324) (xy 123.554848 -290.851234) (xy 123.591552 -290.886489) (xy 123.622125 -290.927175)
			(xy 123.645776 -290.972238) (xy 123.661892 -291.020512) (xy 123.670056 -291.070746) (xy 123.670568 -291.096192)
			(xy 123.988842 -291.096192) (xy 123.992802 -291.047138) (xy 124.004579 -290.999354) (xy 124.02387 -290.954078)
			(xy 124.050173 -290.912482) (xy 124.082808 -290.875645) (xy 124.120929 -290.84452) (xy 124.16355 -290.819913)
			(xy 124.209566 -290.802461) (xy 124.257785 -290.792617) (xy 124.30696 -290.790636) (xy 124.355815 -290.796568)
			(xy 124.403086 -290.81026) (xy 124.447548 -290.831358) (xy 124.488051 -290.859314) (xy 124.523544 -290.893406)
			(xy 124.553109 -290.93275) (xy 124.57598 -290.976327) (xy 124.591564 -291.023008) (xy 124.599459 -291.071585)
			(xy 124.599954 -291.096192) (xy 124.918465 -291.096192) (xy 124.92256 -291.045464) (xy 124.934739 -290.99605)
			(xy 124.954687 -290.94923) (xy 124.981888 -290.906216) (xy 125.015636 -290.868122) (xy 125.055058 -290.835935)
			(xy 125.099132 -290.810489) (xy 125.146718 -290.792442) (xy 125.196582 -290.782262) (xy 125.247434 -290.780213)
			(xy 125.297955 -290.786347) (xy 125.346839 -290.800507) (xy 125.392818 -290.822324) (xy 125.434702 -290.851234)
			(xy 125.471406 -290.886489) (xy 125.501979 -290.927175) (xy 125.52563 -290.972238) (xy 125.541746 -291.020512)
			(xy 125.54991 -291.070746) (xy 125.550422 -291.096192) (xy 125.858519 -291.096192) (xy 125.862614 -291.045464)
			(xy 125.874793 -290.99605) (xy 125.894741 -290.94923) (xy 125.921942 -290.906216) (xy 125.95569 -290.868122)
			(xy 125.995112 -290.835935) (xy 126.039186 -290.810489) (xy 126.086772 -290.792442) (xy 126.136636 -290.782262)
			(xy 126.187488 -290.780213) (xy 126.238009 -290.786347) (xy 126.286893 -290.800507) (xy 126.332872 -290.822324)
			(xy 126.374756 -290.851234) (xy 126.41146 -290.886489) (xy 126.442033 -290.927175) (xy 126.465684 -290.972238)
			(xy 126.4818 -291.020512) (xy 126.489964 -291.070746) (xy 126.490476 -291.096192) (xy 126.809004 -291.096192)
			(xy 126.812964 -291.047138) (xy 126.824741 -290.999354) (xy 126.844032 -290.954078) (xy 126.870335 -290.912482)
			(xy 126.90297 -290.875645) (xy 126.941091 -290.84452) (xy 126.983712 -290.819913) (xy 127.029728 -290.802461)
			(xy 127.077947 -290.792617) (xy 127.127122 -290.790636) (xy 127.175977 -290.796568) (xy 127.223248 -290.81026)
			(xy 127.26771 -290.831358) (xy 127.308213 -290.859314) (xy 127.343706 -290.893406) (xy 127.373271 -290.93275)
			(xy 127.396142 -290.976327) (xy 127.411726 -291.023008) (xy 127.419621 -291.071585) (xy 127.420116 -291.096192)
			(xy 127.419621 -291.120799) (xy 127.411726 -291.169376) (xy 127.396142 -291.216057) (xy 127.373271 -291.259634)
			(xy 127.343706 -291.298978) (xy 127.308213 -291.33307) (xy 127.26771 -291.361026) (xy 127.223248 -291.382124)
			(xy 127.175977 -291.395816) (xy 127.127122 -291.401748) (xy 127.077947 -291.399767) (xy 127.029728 -291.389923)
			(xy 126.983712 -291.372471) (xy 126.941091 -291.347864) (xy 126.90297 -291.316739) (xy 126.870335 -291.279902)
			(xy 126.844032 -291.238306) (xy 126.824741 -291.19303) (xy 126.812964 -291.145246) (xy 126.809004 -291.096192)
			(xy 126.490476 -291.096192) (xy 126.489964 -291.121638) (xy 126.4818 -291.171872) (xy 126.465684 -291.220146)
			(xy 126.442033 -291.265209) (xy 126.41146 -291.305895) (xy 126.374756 -291.34115) (xy 126.332872 -291.37006)
			(xy 126.286893 -291.391877) (xy 126.238009 -291.406037) (xy 126.187488 -291.412171) (xy 126.136636 -291.410122)
			(xy 126.086772 -291.399942) (xy 126.039186 -291.381895) (xy 125.995112 -291.356449) (xy 125.95569 -291.324262)
			(xy 125.921942 -291.286168) (xy 125.894741 -291.243154) (xy 125.874793 -291.196334) (xy 125.862614 -291.14692)
			(xy 125.858519 -291.096192) (xy 125.550422 -291.096192) (xy 125.54991 -291.121638) (xy 125.541746 -291.171872)
			(xy 125.52563 -291.220146) (xy 125.501979 -291.265209) (xy 125.471406 -291.305895) (xy 125.434702 -291.34115)
			(xy 125.392818 -291.37006) (xy 125.346839 -291.391877) (xy 125.297955 -291.406037) (xy 125.247434 -291.412171)
			(xy 125.196582 -291.410122) (xy 125.146718 -291.399942) (xy 125.099132 -291.381895) (xy 125.055058 -291.356449)
			(xy 125.015636 -291.324262) (xy 124.981888 -291.286168) (xy 124.954687 -291.243154) (xy 124.934739 -291.196334)
			(xy 124.92256 -291.14692) (xy 124.918465 -291.096192) (xy 124.599954 -291.096192) (xy 124.599459 -291.120799)
			(xy 124.591564 -291.169376) (xy 124.57598 -291.216057) (xy 124.553109 -291.259634) (xy 124.523544 -291.298978)
			(xy 124.488051 -291.33307) (xy 124.447548 -291.361026) (xy 124.403086 -291.382124) (xy 124.355815 -291.395816)
			(xy 124.30696 -291.401748) (xy 124.257785 -291.399767) (xy 124.209566 -291.389923) (xy 124.16355 -291.372471)
			(xy 124.120929 -291.347864) (xy 124.082808 -291.316739) (xy 124.050173 -291.279902) (xy 124.02387 -291.238306)
			(xy 124.004579 -291.19303) (xy 123.992802 -291.145246) (xy 123.988842 -291.096192) (xy 123.670568 -291.096192)
			(xy 123.670056 -291.121638) (xy 123.661892 -291.171872) (xy 123.645776 -291.220146) (xy 123.622125 -291.265209)
			(xy 123.591552 -291.305895) (xy 123.554848 -291.34115) (xy 123.512964 -291.37006) (xy 123.466985 -291.391877)
			(xy 123.418101 -291.406037) (xy 123.36758 -291.412171) (xy 123.316728 -291.410122) (xy 123.266864 -291.399942)
			(xy 123.219278 -291.381895) (xy 123.175204 -291.356449) (xy 123.135782 -291.324262) (xy 123.102034 -291.286168)
			(xy 123.074833 -291.243154) (xy 123.054885 -291.196334) (xy 123.042706 -291.14692) (xy 123.038611 -291.096192)
			(xy 122.730514 -291.096192) (xy 122.730002 -291.121638) (xy 122.721838 -291.171872) (xy 122.705722 -291.220146)
			(xy 122.682071 -291.265209) (xy 122.651498 -291.305895) (xy 122.614794 -291.34115) (xy 122.57291 -291.37006)
			(xy 122.526931 -291.391877) (xy 122.478047 -291.406037) (xy 122.427526 -291.412171) (xy 122.376674 -291.410122)
			(xy 122.32681 -291.399942) (xy 122.279224 -291.381895) (xy 122.23515 -291.356449) (xy 122.195728 -291.324262)
			(xy 122.16198 -291.286168) (xy 122.134779 -291.243154) (xy 122.114831 -291.196334) (xy 122.102652 -291.14692)
			(xy 122.098557 -291.096192) (xy 121.780046 -291.096192) (xy 121.779551 -291.120799) (xy 121.771656 -291.169376)
			(xy 121.756072 -291.216057) (xy 121.733201 -291.259634) (xy 121.703636 -291.298978) (xy 121.668143 -291.33307)
			(xy 121.62764 -291.361026) (xy 121.583178 -291.382124) (xy 121.535907 -291.395816) (xy 121.487052 -291.401748)
			(xy 121.437877 -291.399767) (xy 121.389658 -291.389923) (xy 121.343642 -291.372471) (xy 121.301021 -291.347864)
			(xy 121.2629 -291.316739) (xy 121.230265 -291.279902) (xy 121.203962 -291.238306) (xy 121.184671 -291.19303)
			(xy 121.172894 -291.145246) (xy 121.168934 -291.096192) (xy 120.850406 -291.096192) (xy 120.849894 -291.121638)
			(xy 120.84173 -291.171872) (xy 120.825614 -291.220146) (xy 120.801963 -291.265209) (xy 120.77139 -291.305895)
			(xy 120.734686 -291.34115) (xy 120.692802 -291.37006) (xy 120.646823 -291.391877) (xy 120.597939 -291.406037)
			(xy 120.547418 -291.412171) (xy 120.496566 -291.410122) (xy 120.446702 -291.399942) (xy 120.399116 -291.381895)
			(xy 120.355042 -291.356449) (xy 120.31562 -291.324262) (xy 120.281872 -291.286168) (xy 120.254671 -291.243154)
			(xy 120.234723 -291.196334) (xy 120.222544 -291.14692) (xy 120.218449 -291.096192) (xy 119.910352 -291.096192)
			(xy 119.90984 -291.121638) (xy 119.901676 -291.171872) (xy 119.88556 -291.220146) (xy 119.861909 -291.265209)
			(xy 119.831336 -291.305895) (xy 119.794632 -291.34115) (xy 119.752748 -291.37006) (xy 119.706769 -291.391877)
			(xy 119.657885 -291.406037) (xy 119.607364 -291.412171) (xy 119.556512 -291.410122) (xy 119.506648 -291.399942)
			(xy 119.459062 -291.381895) (xy 119.414988 -291.356449) (xy 119.375566 -291.324262) (xy 119.341818 -291.286168)
			(xy 119.314617 -291.243154) (xy 119.294669 -291.196334) (xy 119.28249 -291.14692) (xy 119.278395 -291.096192)
			(xy 118.960138 -291.096192) (xy 118.959643 -291.120799) (xy 118.951748 -291.169376) (xy 118.936164 -291.216057)
			(xy 118.913293 -291.259634) (xy 118.883728 -291.298978) (xy 118.848235 -291.33307) (xy 118.807732 -291.361026)
			(xy 118.76327 -291.382124) (xy 118.715999 -291.395816) (xy 118.667144 -291.401748) (xy 118.617969 -291.399767)
			(xy 118.56975 -291.389923) (xy 118.523734 -291.372471) (xy 118.481113 -291.347864) (xy 118.442992 -291.316739)
			(xy 118.410357 -291.279902) (xy 118.384054 -291.238306) (xy 118.364763 -291.19303) (xy 118.352986 -291.145246)
			(xy 118.349026 -291.096192) (xy 118.030498 -291.096192) (xy 118.029986 -291.121638) (xy 118.021822 -291.171872)
			(xy 118.005706 -291.220146) (xy 117.982055 -291.265209) (xy 117.951482 -291.305895) (xy 117.914778 -291.34115)
			(xy 117.872894 -291.37006) (xy 117.826915 -291.391877) (xy 117.778031 -291.406037) (xy 117.72751 -291.412171)
			(xy 117.676658 -291.410122) (xy 117.626794 -291.399942) (xy 117.579208 -291.381895) (xy 117.535134 -291.356449)
			(xy 117.495712 -291.324262) (xy 117.461964 -291.286168) (xy 117.434763 -291.243154) (xy 117.414815 -291.196334)
			(xy 117.402636 -291.14692) (xy 117.398541 -291.096192) (xy 117.090444 -291.096192) (xy 117.089932 -291.121638)
			(xy 117.081768 -291.171872) (xy 117.065652 -291.220146) (xy 117.042001 -291.265209) (xy 117.011428 -291.305895)
			(xy 116.974724 -291.34115) (xy 116.93284 -291.37006) (xy 116.886861 -291.391877) (xy 116.837977 -291.406037)
			(xy 116.787456 -291.412171) (xy 116.736604 -291.410122) (xy 116.68674 -291.399942) (xy 116.639154 -291.381895)
			(xy 116.59508 -291.356449) (xy 116.555658 -291.324262) (xy 116.52191 -291.286168) (xy 116.494709 -291.243154)
			(xy 116.474761 -291.196334) (xy 116.462582 -291.14692) (xy 116.458487 -291.096192) (xy 116.139976 -291.096192)
			(xy 116.139481 -291.120799) (xy 116.131586 -291.169376) (xy 116.116002 -291.216057) (xy 116.093131 -291.259634)
			(xy 116.063566 -291.298978) (xy 116.028073 -291.33307) (xy 115.98757 -291.361026) (xy 115.943108 -291.382124)
			(xy 115.895837 -291.395816) (xy 115.846982 -291.401748) (xy 115.797807 -291.399767) (xy 115.749588 -291.389923)
			(xy 115.703572 -291.372471) (xy 115.660951 -291.347864) (xy 115.62283 -291.316739) (xy 115.590195 -291.279902)
			(xy 115.563892 -291.238306) (xy 115.544601 -291.19303) (xy 115.532824 -291.145246) (xy 115.528864 -291.096192)
			(xy 112.570438 -291.096192) (xy 112.583554 -291.906198) (xy 113.178856 -291.906198) (xy 113.182816 -291.857144)
			(xy 113.194593 -291.80936) (xy 113.213884 -291.764084) (xy 113.240187 -291.722488) (xy 113.272822 -291.685651)
			(xy 113.310943 -291.654526) (xy 113.353564 -291.629919) (xy 113.39958 -291.612467) (xy 113.447799 -291.602623)
			(xy 113.496974 -291.600642) (xy 113.545829 -291.606574) (xy 113.5931 -291.620266) (xy 113.637562 -291.641364)
			(xy 113.678065 -291.66932) (xy 113.713558 -291.703412) (xy 113.743123 -291.742756) (xy 113.765994 -291.786333)
			(xy 113.781578 -291.833014) (xy 113.789473 -291.881591) (xy 113.789968 -291.906198) (xy 114.11891 -291.906198)
			(xy 114.12287 -291.857144) (xy 114.134647 -291.80936) (xy 114.153938 -291.764084) (xy 114.180241 -291.722488)
			(xy 114.212876 -291.685651) (xy 114.250997 -291.654526) (xy 114.293618 -291.629919) (xy 114.339634 -291.612467)
			(xy 114.387853 -291.602623) (xy 114.437028 -291.600642) (xy 114.485883 -291.606574) (xy 114.533154 -291.620266)
			(xy 114.577616 -291.641364) (xy 114.618119 -291.66932) (xy 114.653612 -291.703412) (xy 114.683177 -291.742756)
			(xy 114.706048 -291.786333) (xy 114.721632 -291.833014) (xy 114.729527 -291.881591) (xy 114.730022 -291.906198)
			(xy 115.058964 -291.906198) (xy 115.062924 -291.857144) (xy 115.074701 -291.80936) (xy 115.093992 -291.764084)
			(xy 115.120295 -291.722488) (xy 115.15293 -291.685651) (xy 115.191051 -291.654526) (xy 115.233672 -291.629919)
			(xy 115.279688 -291.612467) (xy 115.327907 -291.602623) (xy 115.377082 -291.600642) (xy 115.425937 -291.606574)
			(xy 115.473208 -291.620266) (xy 115.51767 -291.641364) (xy 115.558173 -291.66932) (xy 115.593666 -291.703412)
			(xy 115.623231 -291.742756) (xy 115.646102 -291.786333) (xy 115.661686 -291.833014) (xy 115.669581 -291.881591)
			(xy 115.670076 -291.906198) (xy 116.938818 -291.906198) (xy 116.942778 -291.857144) (xy 116.954555 -291.80936)
			(xy 116.973846 -291.764084) (xy 117.000149 -291.722488) (xy 117.032784 -291.685651) (xy 117.070905 -291.654526)
			(xy 117.113526 -291.629919) (xy 117.159542 -291.612467) (xy 117.207761 -291.602623) (xy 117.256936 -291.600642)
			(xy 117.305791 -291.606574) (xy 117.353062 -291.620266) (xy 117.397524 -291.641364) (xy 117.438027 -291.66932)
			(xy 117.47352 -291.703412) (xy 117.503085 -291.742756) (xy 117.525956 -291.786333) (xy 117.54154 -291.833014)
			(xy 117.549435 -291.881591) (xy 117.54993 -291.906198) (xy 117.878872 -291.906198) (xy 117.882832 -291.857144)
			(xy 117.894609 -291.80936) (xy 117.9139 -291.764084) (xy 117.940203 -291.722488) (xy 117.972838 -291.685651)
			(xy 118.010959 -291.654526) (xy 118.05358 -291.629919) (xy 118.099596 -291.612467) (xy 118.147815 -291.602623)
			(xy 118.19699 -291.600642) (xy 118.245845 -291.606574) (xy 118.293116 -291.620266) (xy 118.337578 -291.641364)
			(xy 118.378081 -291.66932) (xy 118.413574 -291.703412) (xy 118.443139 -291.742756) (xy 118.46601 -291.786333)
			(xy 118.481594 -291.833014) (xy 118.489489 -291.881591) (xy 118.489984 -291.906198) (xy 119.75898 -291.906198)
			(xy 119.76294 -291.857144) (xy 119.774717 -291.80936) (xy 119.794008 -291.764084) (xy 119.820311 -291.722488)
			(xy 119.852946 -291.685651) (xy 119.891067 -291.654526) (xy 119.933688 -291.629919) (xy 119.979704 -291.612467)
			(xy 120.027923 -291.602623) (xy 120.077098 -291.600642) (xy 120.125953 -291.606574) (xy 120.173224 -291.620266)
			(xy 120.217686 -291.641364) (xy 120.258189 -291.66932) (xy 120.293682 -291.703412) (xy 120.323247 -291.742756)
			(xy 120.346118 -291.786333) (xy 120.361702 -291.833014) (xy 120.369597 -291.881591) (xy 120.370092 -291.906198)
			(xy 120.699034 -291.906198) (xy 120.702994 -291.857144) (xy 120.714771 -291.80936) (xy 120.734062 -291.764084)
			(xy 120.760365 -291.722488) (xy 120.793 -291.685651) (xy 120.831121 -291.654526) (xy 120.873742 -291.629919)
			(xy 120.919758 -291.612467) (xy 120.967977 -291.602623) (xy 121.017152 -291.600642) (xy 121.066007 -291.606574)
			(xy 121.113278 -291.620266) (xy 121.15774 -291.641364) (xy 121.198243 -291.66932) (xy 121.233736 -291.703412)
			(xy 121.263301 -291.742756) (xy 121.286172 -291.786333) (xy 121.301756 -291.833014) (xy 121.309651 -291.881591)
			(xy 121.310146 -291.906198) (xy 122.578888 -291.906198) (xy 122.582848 -291.857144) (xy 122.594625 -291.80936)
			(xy 122.613916 -291.764084) (xy 122.640219 -291.722488) (xy 122.672854 -291.685651) (xy 122.710975 -291.654526)
			(xy 122.753596 -291.629919) (xy 122.799612 -291.612467) (xy 122.847831 -291.602623) (xy 122.897006 -291.600642)
			(xy 122.945861 -291.606574) (xy 122.993132 -291.620266) (xy 123.037594 -291.641364) (xy 123.078097 -291.66932)
			(xy 123.11359 -291.703412) (xy 123.143155 -291.742756) (xy 123.166026 -291.786333) (xy 123.18161 -291.833014)
			(xy 123.189505 -291.881591) (xy 123.19 -291.906198) (xy 123.518942 -291.906198) (xy 123.522902 -291.857144)
			(xy 123.534679 -291.80936) (xy 123.55397 -291.764084) (xy 123.580273 -291.722488) (xy 123.612908 -291.685651)
			(xy 123.651029 -291.654526) (xy 123.69365 -291.629919) (xy 123.739666 -291.612467) (xy 123.787885 -291.602623)
			(xy 123.83706 -291.600642) (xy 123.885915 -291.606574) (xy 123.933186 -291.620266) (xy 123.977648 -291.641364)
			(xy 124.018151 -291.66932) (xy 124.053644 -291.703412) (xy 124.083209 -291.742756) (xy 124.10608 -291.786333)
			(xy 124.121664 -291.833014) (xy 124.129559 -291.881591) (xy 124.130054 -291.906198) (xy 125.39905 -291.906198)
			(xy 125.40301 -291.857144) (xy 125.414787 -291.80936) (xy 125.434078 -291.764084) (xy 125.460381 -291.722488)
			(xy 125.493016 -291.685651) (xy 125.531137 -291.654526) (xy 125.573758 -291.629919) (xy 125.619774 -291.612467)
			(xy 125.667993 -291.602623) (xy 125.717168 -291.600642) (xy 125.766023 -291.606574) (xy 125.813294 -291.620266)
			(xy 125.857756 -291.641364) (xy 125.898259 -291.66932) (xy 125.933752 -291.703412) (xy 125.963317 -291.742756)
			(xy 125.986188 -291.786333) (xy 126.001772 -291.833014) (xy 126.009667 -291.881591) (xy 126.010162 -291.906198)
			(xy 126.33885 -291.906198) (xy 126.34281 -291.857144) (xy 126.354587 -291.80936) (xy 126.373878 -291.764084)
			(xy 126.400181 -291.722488) (xy 126.432816 -291.685651) (xy 126.470937 -291.654526) (xy 126.513558 -291.629919)
			(xy 126.559574 -291.612467) (xy 126.607793 -291.602623) (xy 126.656968 -291.600642) (xy 126.705823 -291.606574)
			(xy 126.753094 -291.620266) (xy 126.797556 -291.641364) (xy 126.838059 -291.66932) (xy 126.873552 -291.703412)
			(xy 126.903117 -291.742756) (xy 126.925988 -291.786333) (xy 126.941572 -291.833014) (xy 126.949467 -291.881591)
			(xy 126.949962 -291.906198) (xy 126.949467 -291.930805) (xy 126.941572 -291.979382) (xy 126.925988 -292.026063)
			(xy 126.903117 -292.06964) (xy 126.873552 -292.108984) (xy 126.838059 -292.143076) (xy 126.797556 -292.171032)
			(xy 126.753094 -292.19213) (xy 126.705823 -292.205822) (xy 126.656968 -292.211754) (xy 126.607793 -292.209773)
			(xy 126.559574 -292.199929) (xy 126.513558 -292.182477) (xy 126.470937 -292.15787) (xy 126.432816 -292.126745)
			(xy 126.400181 -292.089908) (xy 126.373878 -292.048312) (xy 126.354587 -292.003036) (xy 126.34281 -291.955252)
			(xy 126.33885 -291.906198) (xy 126.010162 -291.906198) (xy 126.009667 -291.930805) (xy 126.001772 -291.979382)
			(xy 125.986188 -292.026063) (xy 125.963317 -292.06964) (xy 125.933752 -292.108984) (xy 125.898259 -292.143076)
			(xy 125.857756 -292.171032) (xy 125.813294 -292.19213) (xy 125.766023 -292.205822) (xy 125.717168 -292.211754)
			(xy 125.667993 -292.209773) (xy 125.619774 -292.199929) (xy 125.573758 -292.182477) (xy 125.531137 -292.15787)
			(xy 125.493016 -292.126745) (xy 125.460381 -292.089908) (xy 125.434078 -292.048312) (xy 125.414787 -292.003036)
			(xy 125.40301 -291.955252) (xy 125.39905 -291.906198) (xy 124.130054 -291.906198) (xy 124.129559 -291.930805)
			(xy 124.121664 -291.979382) (xy 124.10608 -292.026063) (xy 124.083209 -292.06964) (xy 124.053644 -292.108984)
			(xy 124.018151 -292.143076) (xy 123.977648 -292.171032) (xy 123.933186 -292.19213) (xy 123.885915 -292.205822)
			(xy 123.83706 -292.211754) (xy 123.787885 -292.209773) (xy 123.739666 -292.199929) (xy 123.69365 -292.182477)
			(xy 123.651029 -292.15787) (xy 123.612908 -292.126745) (xy 123.580273 -292.089908) (xy 123.55397 -292.048312)
			(xy 123.534679 -292.003036) (xy 123.522902 -291.955252) (xy 123.518942 -291.906198) (xy 123.19 -291.906198)
			(xy 123.189505 -291.930805) (xy 123.18161 -291.979382) (xy 123.166026 -292.026063) (xy 123.143155 -292.06964)
			(xy 123.11359 -292.108984) (xy 123.078097 -292.143076) (xy 123.037594 -292.171032) (xy 122.993132 -292.19213)
			(xy 122.945861 -292.205822) (xy 122.897006 -292.211754) (xy 122.847831 -292.209773) (xy 122.799612 -292.199929)
			(xy 122.753596 -292.182477) (xy 122.710975 -292.15787) (xy 122.672854 -292.126745) (xy 122.640219 -292.089908)
			(xy 122.613916 -292.048312) (xy 122.594625 -292.003036) (xy 122.582848 -291.955252) (xy 122.578888 -291.906198)
			(xy 121.310146 -291.906198) (xy 121.309651 -291.930805) (xy 121.301756 -291.979382) (xy 121.286172 -292.026063)
			(xy 121.263301 -292.06964) (xy 121.233736 -292.108984) (xy 121.198243 -292.143076) (xy 121.15774 -292.171032)
			(xy 121.113278 -292.19213) (xy 121.066007 -292.205822) (xy 121.017152 -292.211754) (xy 120.967977 -292.209773)
			(xy 120.919758 -292.199929) (xy 120.873742 -292.182477) (xy 120.831121 -292.15787) (xy 120.793 -292.126745)
			(xy 120.760365 -292.089908) (xy 120.734062 -292.048312) (xy 120.714771 -292.003036) (xy 120.702994 -291.955252)
			(xy 120.699034 -291.906198) (xy 120.370092 -291.906198) (xy 120.369597 -291.930805) (xy 120.361702 -291.979382)
			(xy 120.346118 -292.026063) (xy 120.323247 -292.06964) (xy 120.293682 -292.108984) (xy 120.258189 -292.143076)
			(xy 120.217686 -292.171032) (xy 120.173224 -292.19213) (xy 120.125953 -292.205822) (xy 120.077098 -292.211754)
			(xy 120.027923 -292.209773) (xy 119.979704 -292.199929) (xy 119.933688 -292.182477) (xy 119.891067 -292.15787)
			(xy 119.852946 -292.126745) (xy 119.820311 -292.089908) (xy 119.794008 -292.048312) (xy 119.774717 -292.003036)
			(xy 119.76294 -291.955252) (xy 119.75898 -291.906198) (xy 118.489984 -291.906198) (xy 118.489489 -291.930805)
			(xy 118.481594 -291.979382) (xy 118.46601 -292.026063) (xy 118.443139 -292.06964) (xy 118.413574 -292.108984)
			(xy 118.378081 -292.143076) (xy 118.337578 -292.171032) (xy 118.293116 -292.19213) (xy 118.245845 -292.205822)
			(xy 118.19699 -292.211754) (xy 118.147815 -292.209773) (xy 118.099596 -292.199929) (xy 118.05358 -292.182477)
			(xy 118.010959 -292.15787) (xy 117.972838 -292.126745) (xy 117.940203 -292.089908) (xy 117.9139 -292.048312)
			(xy 117.894609 -292.003036) (xy 117.882832 -291.955252) (xy 117.878872 -291.906198) (xy 117.54993 -291.906198)
			(xy 117.549435 -291.930805) (xy 117.54154 -291.979382) (xy 117.525956 -292.026063) (xy 117.503085 -292.06964)
			(xy 117.47352 -292.108984) (xy 117.438027 -292.143076) (xy 117.397524 -292.171032) (xy 117.353062 -292.19213)
			(xy 117.305791 -292.205822) (xy 117.256936 -292.211754) (xy 117.207761 -292.209773) (xy 117.159542 -292.199929)
			(xy 117.113526 -292.182477) (xy 117.070905 -292.15787) (xy 117.032784 -292.126745) (xy 117.000149 -292.089908)
			(xy 116.973846 -292.048312) (xy 116.954555 -292.003036) (xy 116.942778 -291.955252) (xy 116.938818 -291.906198)
			(xy 115.670076 -291.906198) (xy 115.669581 -291.930805) (xy 115.661686 -291.979382) (xy 115.646102 -292.026063)
			(xy 115.623231 -292.06964) (xy 115.593666 -292.108984) (xy 115.558173 -292.143076) (xy 115.51767 -292.171032)
			(xy 115.473208 -292.19213) (xy 115.425937 -292.205822) (xy 115.377082 -292.211754) (xy 115.327907 -292.209773)
			(xy 115.279688 -292.199929) (xy 115.233672 -292.182477) (xy 115.191051 -292.15787) (xy 115.15293 -292.126745)
			(xy 115.120295 -292.089908) (xy 115.093992 -292.048312) (xy 115.074701 -292.003036) (xy 115.062924 -291.955252)
			(xy 115.058964 -291.906198) (xy 114.730022 -291.906198) (xy 114.729527 -291.930805) (xy 114.721632 -291.979382)
			(xy 114.706048 -292.026063) (xy 114.683177 -292.06964) (xy 114.653612 -292.108984) (xy 114.618119 -292.143076)
			(xy 114.577616 -292.171032) (xy 114.533154 -292.19213) (xy 114.485883 -292.205822) (xy 114.437028 -292.211754)
			(xy 114.387853 -292.209773) (xy 114.339634 -292.199929) (xy 114.293618 -292.182477) (xy 114.250997 -292.15787)
			(xy 114.212876 -292.126745) (xy 114.180241 -292.089908) (xy 114.153938 -292.048312) (xy 114.134647 -292.003036)
			(xy 114.12287 -291.955252) (xy 114.11891 -291.906198) (xy 113.789968 -291.906198) (xy 113.789473 -291.930805)
			(xy 113.781578 -291.979382) (xy 113.765994 -292.026063) (xy 113.743123 -292.06964) (xy 113.713558 -292.108984)
			(xy 113.678065 -292.143076) (xy 113.637562 -292.171032) (xy 113.5931 -292.19213) (xy 113.545829 -292.205822)
			(xy 113.496974 -292.211754) (xy 113.447799 -292.209773) (xy 113.39958 -292.199929) (xy 113.353564 -292.182477)
			(xy 113.310943 -292.15787) (xy 113.272822 -292.126745) (xy 113.240187 -292.089908) (xy 113.213884 -292.048312)
			(xy 113.194593 -292.003036) (xy 113.182816 -291.955252) (xy 113.178856 -291.906198) (xy 112.583554 -291.906198)
			(xy 112.59667 -292.716204) (xy 116.468918 -292.716204) (xy 116.472878 -292.66715) (xy 116.484655 -292.619366)
			(xy 116.503946 -292.57409) (xy 116.530249 -292.532494) (xy 116.562884 -292.495657) (xy 116.601005 -292.464532)
			(xy 116.643626 -292.439925) (xy 116.689642 -292.422473) (xy 116.737861 -292.412629) (xy 116.787036 -292.410648)
			(xy 116.835891 -292.41658) (xy 116.883162 -292.430272) (xy 116.927624 -292.45137) (xy 116.968127 -292.479326)
			(xy 117.00362 -292.513418) (xy 117.033185 -292.552762) (xy 117.056056 -292.596339) (xy 117.07164 -292.64302)
			(xy 117.079535 -292.691597) (xy 117.08003 -292.716204) (xy 117.408972 -292.716204) (xy 117.412932 -292.66715)
			(xy 117.424709 -292.619366) (xy 117.444 -292.57409) (xy 117.470303 -292.532494) (xy 117.502938 -292.495657)
			(xy 117.541059 -292.464532) (xy 117.58368 -292.439925) (xy 117.629696 -292.422473) (xy 117.677915 -292.412629)
			(xy 117.72709 -292.410648) (xy 117.775945 -292.41658) (xy 117.823216 -292.430272) (xy 117.867678 -292.45137)
			(xy 117.908181 -292.479326) (xy 117.943674 -292.513418) (xy 117.973239 -292.552762) (xy 117.99611 -292.596339)
			(xy 118.011694 -292.64302) (xy 118.019589 -292.691597) (xy 118.020084 -292.716204) (xy 119.288826 -292.716204)
			(xy 119.292786 -292.66715) (xy 119.304563 -292.619366) (xy 119.323854 -292.57409) (xy 119.350157 -292.532494)
			(xy 119.382792 -292.495657) (xy 119.420913 -292.464532) (xy 119.463534 -292.439925) (xy 119.50955 -292.422473)
			(xy 119.557769 -292.412629) (xy 119.606944 -292.410648) (xy 119.655799 -292.41658) (xy 119.70307 -292.430272)
			(xy 119.747532 -292.45137) (xy 119.788035 -292.479326) (xy 119.823528 -292.513418) (xy 119.853093 -292.552762)
			(xy 119.875964 -292.596339) (xy 119.891548 -292.64302) (xy 119.899443 -292.691597) (xy 119.899938 -292.716204)
			(xy 120.22888 -292.716204) (xy 120.23284 -292.66715) (xy 120.244617 -292.619366) (xy 120.263908 -292.57409)
			(xy 120.290211 -292.532494) (xy 120.322846 -292.495657) (xy 120.360967 -292.464532) (xy 120.403588 -292.439925)
			(xy 120.449604 -292.422473) (xy 120.497823 -292.412629) (xy 120.546998 -292.410648) (xy 120.595853 -292.41658)
			(xy 120.643124 -292.430272) (xy 120.687586 -292.45137) (xy 120.728089 -292.479326) (xy 120.763582 -292.513418)
			(xy 120.793147 -292.552762) (xy 120.816018 -292.596339) (xy 120.831602 -292.64302) (xy 120.839497 -292.691597)
			(xy 120.839992 -292.716204) (xy 122.108988 -292.716204) (xy 122.112948 -292.66715) (xy 122.124725 -292.619366)
			(xy 122.144016 -292.57409) (xy 122.170319 -292.532494) (xy 122.202954 -292.495657) (xy 122.241075 -292.464532)
			(xy 122.283696 -292.439925) (xy 122.329712 -292.422473) (xy 122.377931 -292.412629) (xy 122.427106 -292.410648)
			(xy 122.475961 -292.41658) (xy 122.523232 -292.430272) (xy 122.567694 -292.45137) (xy 122.608197 -292.479326)
			(xy 122.64369 -292.513418) (xy 122.673255 -292.552762) (xy 122.696126 -292.596339) (xy 122.71171 -292.64302)
			(xy 122.719605 -292.691597) (xy 122.7201 -292.716204) (xy 123.049042 -292.716204) (xy 123.053002 -292.66715)
			(xy 123.064779 -292.619366) (xy 123.08407 -292.57409) (xy 123.110373 -292.532494) (xy 123.143008 -292.495657)
			(xy 123.181129 -292.464532) (xy 123.22375 -292.439925) (xy 123.269766 -292.422473) (xy 123.317985 -292.412629)
			(xy 123.36716 -292.410648) (xy 123.416015 -292.41658) (xy 123.463286 -292.430272) (xy 123.507748 -292.45137)
			(xy 123.548251 -292.479326) (xy 123.583744 -292.513418) (xy 123.613309 -292.552762) (xy 123.63618 -292.596339)
			(xy 123.651764 -292.64302) (xy 123.659659 -292.691597) (xy 123.660154 -292.716204) (xy 124.928896 -292.716204)
			(xy 124.932856 -292.66715) (xy 124.944633 -292.619366) (xy 124.963924 -292.57409) (xy 124.990227 -292.532494)
			(xy 125.022862 -292.495657) (xy 125.060983 -292.464532) (xy 125.103604 -292.439925) (xy 125.14962 -292.422473)
			(xy 125.197839 -292.412629) (xy 125.247014 -292.410648) (xy 125.295869 -292.41658) (xy 125.34314 -292.430272)
			(xy 125.387602 -292.45137) (xy 125.428105 -292.479326) (xy 125.463598 -292.513418) (xy 125.493163 -292.552762)
			(xy 125.516034 -292.596339) (xy 125.531618 -292.64302) (xy 125.539513 -292.691597) (xy 125.540008 -292.716204)
			(xy 125.86895 -292.716204) (xy 125.87291 -292.66715) (xy 125.884687 -292.619366) (xy 125.903978 -292.57409)
			(xy 125.930281 -292.532494) (xy 125.962916 -292.495657) (xy 126.001037 -292.464532) (xy 126.043658 -292.439925)
			(xy 126.089674 -292.422473) (xy 126.137893 -292.412629) (xy 126.187068 -292.410648) (xy 126.235923 -292.41658)
			(xy 126.283194 -292.430272) (xy 126.327656 -292.45137) (xy 126.368159 -292.479326) (xy 126.403652 -292.513418)
			(xy 126.433217 -292.552762) (xy 126.456088 -292.596339) (xy 126.471672 -292.64302) (xy 126.479567 -292.691597)
			(xy 126.480062 -292.716204) (xy 126.479567 -292.740811) (xy 126.471672 -292.789388) (xy 126.456088 -292.836069)
			(xy 126.433217 -292.879646) (xy 126.403652 -292.91899) (xy 126.368159 -292.953082) (xy 126.327656 -292.981038)
			(xy 126.283194 -293.002136) (xy 126.235923 -293.015828) (xy 126.187068 -293.02176) (xy 126.137893 -293.019779)
			(xy 126.089674 -293.009935) (xy 126.043658 -292.992483) (xy 126.001037 -292.967876) (xy 125.962916 -292.936751)
			(xy 125.930281 -292.899914) (xy 125.903978 -292.858318) (xy 125.884687 -292.813042) (xy 125.87291 -292.765258)
			(xy 125.86895 -292.716204) (xy 125.540008 -292.716204) (xy 125.539513 -292.740811) (xy 125.531618 -292.789388)
			(xy 125.516034 -292.836069) (xy 125.493163 -292.879646) (xy 125.463598 -292.91899) (xy 125.428105 -292.953082)
			(xy 125.387602 -292.981038) (xy 125.34314 -293.002136) (xy 125.295869 -293.015828) (xy 125.247014 -293.02176)
			(xy 125.197839 -293.019779) (xy 125.14962 -293.009935) (xy 125.103604 -292.992483) (xy 125.060983 -292.967876)
			(xy 125.022862 -292.936751) (xy 124.990227 -292.899914) (xy 124.963924 -292.858318) (xy 124.944633 -292.813042)
			(xy 124.932856 -292.765258) (xy 124.928896 -292.716204) (xy 123.660154 -292.716204) (xy 123.659659 -292.740811)
			(xy 123.651764 -292.789388) (xy 123.63618 -292.836069) (xy 123.613309 -292.879646) (xy 123.583744 -292.91899)
			(xy 123.548251 -292.953082) (xy 123.507748 -292.981038) (xy 123.463286 -293.002136) (xy 123.416015 -293.015828)
			(xy 123.36716 -293.02176) (xy 123.317985 -293.019779) (xy 123.269766 -293.009935) (xy 123.22375 -292.992483)
			(xy 123.181129 -292.967876) (xy 123.143008 -292.936751) (xy 123.110373 -292.899914) (xy 123.08407 -292.858318)
			(xy 123.064779 -292.813042) (xy 123.053002 -292.765258) (xy 123.049042 -292.716204) (xy 122.7201 -292.716204)
			(xy 122.719605 -292.740811) (xy 122.71171 -292.789388) (xy 122.696126 -292.836069) (xy 122.673255 -292.879646)
			(xy 122.64369 -292.91899) (xy 122.608197 -292.953082) (xy 122.567694 -292.981038) (xy 122.523232 -293.002136)
			(xy 122.475961 -293.015828) (xy 122.427106 -293.02176) (xy 122.377931 -293.019779) (xy 122.329712 -293.009935)
			(xy 122.283696 -292.992483) (xy 122.241075 -292.967876) (xy 122.202954 -292.936751) (xy 122.170319 -292.899914)
			(xy 122.144016 -292.858318) (xy 122.124725 -292.813042) (xy 122.112948 -292.765258) (xy 122.108988 -292.716204)
			(xy 120.839992 -292.716204) (xy 120.839497 -292.740811) (xy 120.831602 -292.789388) (xy 120.816018 -292.836069)
			(xy 120.793147 -292.879646) (xy 120.763582 -292.91899) (xy 120.728089 -292.953082) (xy 120.687586 -292.981038)
			(xy 120.643124 -293.002136) (xy 120.595853 -293.015828) (xy 120.546998 -293.02176) (xy 120.497823 -293.019779)
			(xy 120.449604 -293.009935) (xy 120.403588 -292.992483) (xy 120.360967 -292.967876) (xy 120.322846 -292.936751)
			(xy 120.290211 -292.899914) (xy 120.263908 -292.858318) (xy 120.244617 -292.813042) (xy 120.23284 -292.765258)
			(xy 120.22888 -292.716204) (xy 119.899938 -292.716204) (xy 119.899443 -292.740811) (xy 119.891548 -292.789388)
			(xy 119.875964 -292.836069) (xy 119.853093 -292.879646) (xy 119.823528 -292.91899) (xy 119.788035 -292.953082)
			(xy 119.747532 -292.981038) (xy 119.70307 -293.002136) (xy 119.655799 -293.015828) (xy 119.606944 -293.02176)
			(xy 119.557769 -293.019779) (xy 119.50955 -293.009935) (xy 119.463534 -292.992483) (xy 119.420913 -292.967876)
			(xy 119.382792 -292.936751) (xy 119.350157 -292.899914) (xy 119.323854 -292.858318) (xy 119.304563 -292.813042)
			(xy 119.292786 -292.765258) (xy 119.288826 -292.716204) (xy 118.020084 -292.716204) (xy 118.019589 -292.740811)
			(xy 118.011694 -292.789388) (xy 117.99611 -292.836069) (xy 117.973239 -292.879646) (xy 117.943674 -292.91899)
			(xy 117.908181 -292.953082) (xy 117.867678 -292.981038) (xy 117.823216 -293.002136) (xy 117.775945 -293.015828)
			(xy 117.72709 -293.02176) (xy 117.677915 -293.019779) (xy 117.629696 -293.009935) (xy 117.58368 -292.992483)
			(xy 117.541059 -292.967876) (xy 117.502938 -292.936751) (xy 117.470303 -292.899914) (xy 117.444 -292.858318)
			(xy 117.424709 -292.813042) (xy 117.412932 -292.765258) (xy 117.408972 -292.716204) (xy 117.08003 -292.716204)
			(xy 117.079535 -292.740811) (xy 117.07164 -292.789388) (xy 117.056056 -292.836069) (xy 117.033185 -292.879646)
			(xy 117.00362 -292.91899) (xy 116.968127 -292.953082) (xy 116.927624 -292.981038) (xy 116.883162 -293.002136)
			(xy 116.835891 -293.015828) (xy 116.787036 -293.02176) (xy 116.737861 -293.019779) (xy 116.689642 -293.009935)
			(xy 116.643626 -292.992483) (xy 116.601005 -292.967876) (xy 116.562884 -292.936751) (xy 116.530249 -292.899914)
			(xy 116.503946 -292.858318) (xy 116.484655 -292.813042) (xy 116.472878 -292.765258) (xy 116.468918 -292.716204)
			(xy 112.59667 -292.716204) (xy 112.609786 -293.52621) (xy 113.178856 -293.52621) (xy 113.182816 -293.477156)
			(xy 113.194593 -293.429372) (xy 113.213884 -293.384096) (xy 113.240187 -293.3425) (xy 113.272822 -293.305663)
			(xy 113.310943 -293.274538) (xy 113.353564 -293.249931) (xy 113.39958 -293.232479) (xy 113.447799 -293.222635)
			(xy 113.496974 -293.220654) (xy 113.545829 -293.226586) (xy 113.5931 -293.240278) (xy 113.637562 -293.261376)
			(xy 113.678065 -293.289332) (xy 113.713558 -293.323424) (xy 113.743123 -293.362768) (xy 113.765994 -293.406345)
			(xy 113.781578 -293.453026) (xy 113.789473 -293.501603) (xy 113.789968 -293.52621) (xy 114.11891 -293.52621)
			(xy 114.12287 -293.477156) (xy 114.134647 -293.429372) (xy 114.153938 -293.384096) (xy 114.180241 -293.3425)
			(xy 114.212876 -293.305663) (xy 114.250997 -293.274538) (xy 114.293618 -293.249931) (xy 114.339634 -293.232479)
			(xy 114.387853 -293.222635) (xy 114.437028 -293.220654) (xy 114.485883 -293.226586) (xy 114.533154 -293.240278)
			(xy 114.577616 -293.261376) (xy 114.618119 -293.289332) (xy 114.653612 -293.323424) (xy 114.683177 -293.362768)
			(xy 114.706048 -293.406345) (xy 114.721632 -293.453026) (xy 114.729527 -293.501603) (xy 114.730022 -293.52621)
			(xy 115.058964 -293.52621) (xy 115.062924 -293.477156) (xy 115.074701 -293.429372) (xy 115.093992 -293.384096)
			(xy 115.120295 -293.3425) (xy 115.15293 -293.305663) (xy 115.191051 -293.274538) (xy 115.233672 -293.249931)
			(xy 115.279688 -293.232479) (xy 115.327907 -293.222635) (xy 115.377082 -293.220654) (xy 115.425937 -293.226586)
			(xy 115.473208 -293.240278) (xy 115.51767 -293.261376) (xy 115.558173 -293.289332) (xy 115.593666 -293.323424)
			(xy 115.623231 -293.362768) (xy 115.646102 -293.406345) (xy 115.661686 -293.453026) (xy 115.669581 -293.501603)
			(xy 115.670076 -293.52621) (xy 115.999018 -293.52621) (xy 116.002978 -293.477156) (xy 116.014755 -293.429372)
			(xy 116.034046 -293.384096) (xy 116.060349 -293.3425) (xy 116.092984 -293.305663) (xy 116.131105 -293.274538)
			(xy 116.173726 -293.249931) (xy 116.219742 -293.232479) (xy 116.267961 -293.222635) (xy 116.317136 -293.220654)
			(xy 116.365991 -293.226586) (xy 116.413262 -293.240278) (xy 116.457724 -293.261376) (xy 116.498227 -293.289332)
			(xy 116.53372 -293.323424) (xy 116.563285 -293.362768) (xy 116.586156 -293.406345) (xy 116.60174 -293.453026)
			(xy 116.609635 -293.501603) (xy 116.61013 -293.52621) (xy 116.938818 -293.52621) (xy 116.942778 -293.477156)
			(xy 116.954555 -293.429372) (xy 116.973846 -293.384096) (xy 117.000149 -293.3425) (xy 117.032784 -293.305663)
			(xy 117.070905 -293.274538) (xy 117.113526 -293.249931) (xy 117.159542 -293.232479) (xy 117.207761 -293.222635)
			(xy 117.256936 -293.220654) (xy 117.305791 -293.226586) (xy 117.353062 -293.240278) (xy 117.397524 -293.261376)
			(xy 117.438027 -293.289332) (xy 117.47352 -293.323424) (xy 117.503085 -293.362768) (xy 117.525956 -293.406345)
			(xy 117.54154 -293.453026) (xy 117.549435 -293.501603) (xy 117.54993 -293.52621) (xy 117.878872 -293.52621)
			(xy 117.882832 -293.477156) (xy 117.894609 -293.429372) (xy 117.9139 -293.384096) (xy 117.940203 -293.3425)
			(xy 117.972838 -293.305663) (xy 118.010959 -293.274538) (xy 118.05358 -293.249931) (xy 118.099596 -293.232479)
			(xy 118.147815 -293.222635) (xy 118.19699 -293.220654) (xy 118.245845 -293.226586) (xy 118.293116 -293.240278)
			(xy 118.337578 -293.261376) (xy 118.378081 -293.289332) (xy 118.413574 -293.323424) (xy 118.443139 -293.362768)
			(xy 118.46601 -293.406345) (xy 118.481594 -293.453026) (xy 118.489489 -293.501603) (xy 118.489984 -293.52621)
			(xy 118.818926 -293.52621) (xy 118.822886 -293.477156) (xy 118.834663 -293.429372) (xy 118.853954 -293.384096)
			(xy 118.880257 -293.3425) (xy 118.912892 -293.305663) (xy 118.951013 -293.274538) (xy 118.993634 -293.249931)
			(xy 119.03965 -293.232479) (xy 119.087869 -293.222635) (xy 119.137044 -293.220654) (xy 119.185899 -293.226586)
			(xy 119.23317 -293.240278) (xy 119.277632 -293.261376) (xy 119.318135 -293.289332) (xy 119.353628 -293.323424)
			(xy 119.383193 -293.362768) (xy 119.406064 -293.406345) (xy 119.421648 -293.453026) (xy 119.429543 -293.501603)
			(xy 119.430038 -293.52621) (xy 119.75898 -293.52621) (xy 119.76294 -293.477156) (xy 119.774717 -293.429372)
			(xy 119.794008 -293.384096) (xy 119.820311 -293.3425) (xy 119.852946 -293.305663) (xy 119.891067 -293.274538)
			(xy 119.933688 -293.249931) (xy 119.979704 -293.232479) (xy 120.027923 -293.222635) (xy 120.077098 -293.220654)
			(xy 120.125953 -293.226586) (xy 120.173224 -293.240278) (xy 120.217686 -293.261376) (xy 120.258189 -293.289332)
			(xy 120.293682 -293.323424) (xy 120.323247 -293.362768) (xy 120.346118 -293.406345) (xy 120.361702 -293.453026)
			(xy 120.369597 -293.501603) (xy 120.370092 -293.52621) (xy 120.699034 -293.52621) (xy 120.702994 -293.477156)
			(xy 120.714771 -293.429372) (xy 120.734062 -293.384096) (xy 120.760365 -293.3425) (xy 120.793 -293.305663)
			(xy 120.831121 -293.274538) (xy 120.873742 -293.249931) (xy 120.919758 -293.232479) (xy 120.967977 -293.222635)
			(xy 121.017152 -293.220654) (xy 121.066007 -293.226586) (xy 121.113278 -293.240278) (xy 121.15774 -293.261376)
			(xy 121.198243 -293.289332) (xy 121.233736 -293.323424) (xy 121.263301 -293.362768) (xy 121.286172 -293.406345)
			(xy 121.301756 -293.453026) (xy 121.309651 -293.501603) (xy 121.310146 -293.52621) (xy 121.638834 -293.52621)
			(xy 121.642794 -293.477156) (xy 121.654571 -293.429372) (xy 121.673862 -293.384096) (xy 121.700165 -293.3425)
			(xy 121.7328 -293.305663) (xy 121.770921 -293.274538) (xy 121.813542 -293.249931) (xy 121.859558 -293.232479)
			(xy 121.907777 -293.222635) (xy 121.956952 -293.220654) (xy 122.005807 -293.226586) (xy 122.053078 -293.240278)
			(xy 122.09754 -293.261376) (xy 122.138043 -293.289332) (xy 122.173536 -293.323424) (xy 122.203101 -293.362768)
			(xy 122.225972 -293.406345) (xy 122.241556 -293.453026) (xy 122.249451 -293.501603) (xy 122.249946 -293.52621)
			(xy 122.578888 -293.52621) (xy 122.582848 -293.477156) (xy 122.594625 -293.429372) (xy 122.613916 -293.384096)
			(xy 122.640219 -293.3425) (xy 122.672854 -293.305663) (xy 122.710975 -293.274538) (xy 122.753596 -293.249931)
			(xy 122.799612 -293.232479) (xy 122.847831 -293.222635) (xy 122.897006 -293.220654) (xy 122.945861 -293.226586)
			(xy 122.993132 -293.240278) (xy 123.037594 -293.261376) (xy 123.078097 -293.289332) (xy 123.11359 -293.323424)
			(xy 123.143155 -293.362768) (xy 123.166026 -293.406345) (xy 123.18161 -293.453026) (xy 123.189505 -293.501603)
			(xy 123.19 -293.52621) (xy 123.518942 -293.52621) (xy 123.522902 -293.477156) (xy 123.534679 -293.429372)
			(xy 123.55397 -293.384096) (xy 123.580273 -293.3425) (xy 123.612908 -293.305663) (xy 123.651029 -293.274538)
			(xy 123.69365 -293.249931) (xy 123.739666 -293.232479) (xy 123.787885 -293.222635) (xy 123.83706 -293.220654)
			(xy 123.885915 -293.226586) (xy 123.933186 -293.240278) (xy 123.977648 -293.261376) (xy 124.018151 -293.289332)
			(xy 124.053644 -293.323424) (xy 124.083209 -293.362768) (xy 124.10608 -293.406345) (xy 124.121664 -293.453026)
			(xy 124.129559 -293.501603) (xy 124.130054 -293.52621) (xy 124.458996 -293.52621) (xy 124.462956 -293.477156)
			(xy 124.474733 -293.429372) (xy 124.494024 -293.384096) (xy 124.520327 -293.3425) (xy 124.552962 -293.305663)
			(xy 124.591083 -293.274538) (xy 124.633704 -293.249931) (xy 124.67972 -293.232479) (xy 124.727939 -293.222635)
			(xy 124.777114 -293.220654) (xy 124.825969 -293.226586) (xy 124.87324 -293.240278) (xy 124.917702 -293.261376)
			(xy 124.958205 -293.289332) (xy 124.993698 -293.323424) (xy 125.023263 -293.362768) (xy 125.046134 -293.406345)
			(xy 125.061718 -293.453026) (xy 125.069613 -293.501603) (xy 125.070108 -293.52621) (xy 125.39905 -293.52621)
			(xy 125.40301 -293.477156) (xy 125.414787 -293.429372) (xy 125.434078 -293.384096) (xy 125.460381 -293.3425)
			(xy 125.493016 -293.305663) (xy 125.531137 -293.274538) (xy 125.573758 -293.249931) (xy 125.619774 -293.232479)
			(xy 125.667993 -293.222635) (xy 125.717168 -293.220654) (xy 125.766023 -293.226586) (xy 125.813294 -293.240278)
			(xy 125.857756 -293.261376) (xy 125.898259 -293.289332) (xy 125.933752 -293.323424) (xy 125.963317 -293.362768)
			(xy 125.986188 -293.406345) (xy 126.001772 -293.453026) (xy 126.009667 -293.501603) (xy 126.010162 -293.52621)
			(xy 126.33885 -293.52621) (xy 126.34281 -293.477156) (xy 126.354587 -293.429372) (xy 126.373878 -293.384096)
			(xy 126.400181 -293.3425) (xy 126.432816 -293.305663) (xy 126.470937 -293.274538) (xy 126.513558 -293.249931)
			(xy 126.559574 -293.232479) (xy 126.607793 -293.222635) (xy 126.656968 -293.220654) (xy 126.705823 -293.226586)
			(xy 126.753094 -293.240278) (xy 126.797556 -293.261376) (xy 126.838059 -293.289332) (xy 126.873552 -293.323424)
			(xy 126.903117 -293.362768) (xy 126.925988 -293.406345) (xy 126.941572 -293.453026) (xy 126.949467 -293.501603)
			(xy 126.949962 -293.52621) (xy 127.278904 -293.52621) (xy 127.282864 -293.477156) (xy 127.294641 -293.429372)
			(xy 127.313932 -293.384096) (xy 127.340235 -293.3425) (xy 127.37287 -293.305663) (xy 127.410991 -293.274538)
			(xy 127.453612 -293.249931) (xy 127.499628 -293.232479) (xy 127.547847 -293.222635) (xy 127.597022 -293.220654)
			(xy 127.645877 -293.226586) (xy 127.693148 -293.240278) (xy 127.73761 -293.261376) (xy 127.778113 -293.289332)
			(xy 127.813606 -293.323424) (xy 127.843171 -293.362768) (xy 127.866042 -293.406345) (xy 127.881626 -293.453026)
			(xy 127.889521 -293.501603) (xy 127.890016 -293.52621) (xy 127.889521 -293.550817) (xy 127.881626 -293.599394)
			(xy 127.866042 -293.646075) (xy 127.843171 -293.689652) (xy 127.813606 -293.728996) (xy 127.778113 -293.763088)
			(xy 127.73761 -293.791044) (xy 127.693148 -293.812142) (xy 127.645877 -293.825834) (xy 127.597022 -293.831766)
			(xy 127.547847 -293.829785) (xy 127.499628 -293.819941) (xy 127.453612 -293.802489) (xy 127.410991 -293.777882)
			(xy 127.37287 -293.746757) (xy 127.340235 -293.70992) (xy 127.313932 -293.668324) (xy 127.294641 -293.623048)
			(xy 127.282864 -293.575264) (xy 127.278904 -293.52621) (xy 126.949962 -293.52621) (xy 126.949467 -293.550817)
			(xy 126.941572 -293.599394) (xy 126.925988 -293.646075) (xy 126.903117 -293.689652) (xy 126.873552 -293.728996)
			(xy 126.838059 -293.763088) (xy 126.797556 -293.791044) (xy 126.753094 -293.812142) (xy 126.705823 -293.825834)
			(xy 126.656968 -293.831766) (xy 126.607793 -293.829785) (xy 126.559574 -293.819941) (xy 126.513558 -293.802489)
			(xy 126.470937 -293.777882) (xy 126.432816 -293.746757) (xy 126.400181 -293.70992) (xy 126.373878 -293.668324)
			(xy 126.354587 -293.623048) (xy 126.34281 -293.575264) (xy 126.33885 -293.52621) (xy 126.010162 -293.52621)
			(xy 126.009667 -293.550817) (xy 126.001772 -293.599394) (xy 125.986188 -293.646075) (xy 125.963317 -293.689652)
			(xy 125.933752 -293.728996) (xy 125.898259 -293.763088) (xy 125.857756 -293.791044) (xy 125.813294 -293.812142)
			(xy 125.766023 -293.825834) (xy 125.717168 -293.831766) (xy 125.667993 -293.829785) (xy 125.619774 -293.819941)
			(xy 125.573758 -293.802489) (xy 125.531137 -293.777882) (xy 125.493016 -293.746757) (xy 125.460381 -293.70992)
			(xy 125.434078 -293.668324) (xy 125.414787 -293.623048) (xy 125.40301 -293.575264) (xy 125.39905 -293.52621)
			(xy 125.070108 -293.52621) (xy 125.069613 -293.550817) (xy 125.061718 -293.599394) (xy 125.046134 -293.646075)
			(xy 125.023263 -293.689652) (xy 124.993698 -293.728996) (xy 124.958205 -293.763088) (xy 124.917702 -293.791044)
			(xy 124.87324 -293.812142) (xy 124.825969 -293.825834) (xy 124.777114 -293.831766) (xy 124.727939 -293.829785)
			(xy 124.67972 -293.819941) (xy 124.633704 -293.802489) (xy 124.591083 -293.777882) (xy 124.552962 -293.746757)
			(xy 124.520327 -293.70992) (xy 124.494024 -293.668324) (xy 124.474733 -293.623048) (xy 124.462956 -293.575264)
			(xy 124.458996 -293.52621) (xy 124.130054 -293.52621) (xy 124.129559 -293.550817) (xy 124.121664 -293.599394)
			(xy 124.10608 -293.646075) (xy 124.083209 -293.689652) (xy 124.053644 -293.728996) (xy 124.018151 -293.763088)
			(xy 123.977648 -293.791044) (xy 123.933186 -293.812142) (xy 123.885915 -293.825834) (xy 123.83706 -293.831766)
			(xy 123.787885 -293.829785) (xy 123.739666 -293.819941) (xy 123.69365 -293.802489) (xy 123.651029 -293.777882)
			(xy 123.612908 -293.746757) (xy 123.580273 -293.70992) (xy 123.55397 -293.668324) (xy 123.534679 -293.623048)
			(xy 123.522902 -293.575264) (xy 123.518942 -293.52621) (xy 123.19 -293.52621) (xy 123.189505 -293.550817)
			(xy 123.18161 -293.599394) (xy 123.166026 -293.646075) (xy 123.143155 -293.689652) (xy 123.11359 -293.728996)
			(xy 123.078097 -293.763088) (xy 123.037594 -293.791044) (xy 122.993132 -293.812142) (xy 122.945861 -293.825834)
			(xy 122.897006 -293.831766) (xy 122.847831 -293.829785) (xy 122.799612 -293.819941) (xy 122.753596 -293.802489)
			(xy 122.710975 -293.777882) (xy 122.672854 -293.746757) (xy 122.640219 -293.70992) (xy 122.613916 -293.668324)
			(xy 122.594625 -293.623048) (xy 122.582848 -293.575264) (xy 122.578888 -293.52621) (xy 122.249946 -293.52621)
			(xy 122.249451 -293.550817) (xy 122.241556 -293.599394) (xy 122.225972 -293.646075) (xy 122.203101 -293.689652)
			(xy 122.173536 -293.728996) (xy 122.138043 -293.763088) (xy 122.09754 -293.791044) (xy 122.053078 -293.812142)
			(xy 122.005807 -293.825834) (xy 121.956952 -293.831766) (xy 121.907777 -293.829785) (xy 121.859558 -293.819941)
			(xy 121.813542 -293.802489) (xy 121.770921 -293.777882) (xy 121.7328 -293.746757) (xy 121.700165 -293.70992)
			(xy 121.673862 -293.668324) (xy 121.654571 -293.623048) (xy 121.642794 -293.575264) (xy 121.638834 -293.52621)
			(xy 121.310146 -293.52621) (xy 121.309651 -293.550817) (xy 121.301756 -293.599394) (xy 121.286172 -293.646075)
			(xy 121.263301 -293.689652) (xy 121.233736 -293.728996) (xy 121.198243 -293.763088) (xy 121.15774 -293.791044)
			(xy 121.113278 -293.812142) (xy 121.066007 -293.825834) (xy 121.017152 -293.831766) (xy 120.967977 -293.829785)
			(xy 120.919758 -293.819941) (xy 120.873742 -293.802489) (xy 120.831121 -293.777882) (xy 120.793 -293.746757)
			(xy 120.760365 -293.70992) (xy 120.734062 -293.668324) (xy 120.714771 -293.623048) (xy 120.702994 -293.575264)
			(xy 120.699034 -293.52621) (xy 120.370092 -293.52621) (xy 120.369597 -293.550817) (xy 120.361702 -293.599394)
			(xy 120.346118 -293.646075) (xy 120.323247 -293.689652) (xy 120.293682 -293.728996) (xy 120.258189 -293.763088)
			(xy 120.217686 -293.791044) (xy 120.173224 -293.812142) (xy 120.125953 -293.825834) (xy 120.077098 -293.831766)
			(xy 120.027923 -293.829785) (xy 119.979704 -293.819941) (xy 119.933688 -293.802489) (xy 119.891067 -293.777882)
			(xy 119.852946 -293.746757) (xy 119.820311 -293.70992) (xy 119.794008 -293.668324) (xy 119.774717 -293.623048)
			(xy 119.76294 -293.575264) (xy 119.75898 -293.52621) (xy 119.430038 -293.52621) (xy 119.429543 -293.550817)
			(xy 119.421648 -293.599394) (xy 119.406064 -293.646075) (xy 119.383193 -293.689652) (xy 119.353628 -293.728996)
			(xy 119.318135 -293.763088) (xy 119.277632 -293.791044) (xy 119.23317 -293.812142) (xy 119.185899 -293.825834)
			(xy 119.137044 -293.831766) (xy 119.087869 -293.829785) (xy 119.03965 -293.819941) (xy 118.993634 -293.802489)
			(xy 118.951013 -293.777882) (xy 118.912892 -293.746757) (xy 118.880257 -293.70992) (xy 118.853954 -293.668324)
			(xy 118.834663 -293.623048) (xy 118.822886 -293.575264) (xy 118.818926 -293.52621) (xy 118.489984 -293.52621)
			(xy 118.489489 -293.550817) (xy 118.481594 -293.599394) (xy 118.46601 -293.646075) (xy 118.443139 -293.689652)
			(xy 118.413574 -293.728996) (xy 118.378081 -293.763088) (xy 118.337578 -293.791044) (xy 118.293116 -293.812142)
			(xy 118.245845 -293.825834) (xy 118.19699 -293.831766) (xy 118.147815 -293.829785) (xy 118.099596 -293.819941)
			(xy 118.05358 -293.802489) (xy 118.010959 -293.777882) (xy 117.972838 -293.746757) (xy 117.940203 -293.70992)
			(xy 117.9139 -293.668324) (xy 117.894609 -293.623048) (xy 117.882832 -293.575264) (xy 117.878872 -293.52621)
			(xy 117.54993 -293.52621) (xy 117.549435 -293.550817) (xy 117.54154 -293.599394) (xy 117.525956 -293.646075)
			(xy 117.503085 -293.689652) (xy 117.47352 -293.728996) (xy 117.438027 -293.763088) (xy 117.397524 -293.791044)
			(xy 117.353062 -293.812142) (xy 117.305791 -293.825834) (xy 117.256936 -293.831766) (xy 117.207761 -293.829785)
			(xy 117.159542 -293.819941) (xy 117.113526 -293.802489) (xy 117.070905 -293.777882) (xy 117.032784 -293.746757)
			(xy 117.000149 -293.70992) (xy 116.973846 -293.668324) (xy 116.954555 -293.623048) (xy 116.942778 -293.575264)
			(xy 116.938818 -293.52621) (xy 116.61013 -293.52621) (xy 116.609635 -293.550817) (xy 116.60174 -293.599394)
			(xy 116.586156 -293.646075) (xy 116.563285 -293.689652) (xy 116.53372 -293.728996) (xy 116.498227 -293.763088)
			(xy 116.457724 -293.791044) (xy 116.413262 -293.812142) (xy 116.365991 -293.825834) (xy 116.317136 -293.831766)
			(xy 116.267961 -293.829785) (xy 116.219742 -293.819941) (xy 116.173726 -293.802489) (xy 116.131105 -293.777882)
			(xy 116.092984 -293.746757) (xy 116.060349 -293.70992) (xy 116.034046 -293.668324) (xy 116.014755 -293.623048)
			(xy 116.002978 -293.575264) (xy 115.999018 -293.52621) (xy 115.670076 -293.52621) (xy 115.669581 -293.550817)
			(xy 115.661686 -293.599394) (xy 115.646102 -293.646075) (xy 115.623231 -293.689652) (xy 115.593666 -293.728996)
			(xy 115.558173 -293.763088) (xy 115.51767 -293.791044) (xy 115.473208 -293.812142) (xy 115.425937 -293.825834)
			(xy 115.377082 -293.831766) (xy 115.327907 -293.829785) (xy 115.279688 -293.819941) (xy 115.233672 -293.802489)
			(xy 115.191051 -293.777882) (xy 115.15293 -293.746757) (xy 115.120295 -293.70992) (xy 115.093992 -293.668324)
			(xy 115.074701 -293.623048) (xy 115.062924 -293.575264) (xy 115.058964 -293.52621) (xy 114.730022 -293.52621)
			(xy 114.729527 -293.550817) (xy 114.721632 -293.599394) (xy 114.706048 -293.646075) (xy 114.683177 -293.689652)
			(xy 114.653612 -293.728996) (xy 114.618119 -293.763088) (xy 114.577616 -293.791044) (xy 114.533154 -293.812142)
			(xy 114.485883 -293.825834) (xy 114.437028 -293.831766) (xy 114.387853 -293.829785) (xy 114.339634 -293.819941)
			(xy 114.293618 -293.802489) (xy 114.250997 -293.777882) (xy 114.212876 -293.746757) (xy 114.180241 -293.70992)
			(xy 114.153938 -293.668324) (xy 114.134647 -293.623048) (xy 114.12287 -293.575264) (xy 114.11891 -293.52621)
			(xy 113.789968 -293.52621) (xy 113.789473 -293.550817) (xy 113.781578 -293.599394) (xy 113.765994 -293.646075)
			(xy 113.743123 -293.689652) (xy 113.713558 -293.728996) (xy 113.678065 -293.763088) (xy 113.637562 -293.791044)
			(xy 113.5931 -293.812142) (xy 113.545829 -293.825834) (xy 113.496974 -293.831766) (xy 113.447799 -293.829785)
			(xy 113.39958 -293.819941) (xy 113.353564 -293.802489) (xy 113.310943 -293.777882) (xy 113.272822 -293.746757)
			(xy 113.240187 -293.70992) (xy 113.213884 -293.668324) (xy 113.194593 -293.623048) (xy 113.182816 -293.575264)
			(xy 113.178856 -293.52621) (xy 112.609786 -293.52621) (xy 112.622902 -294.336216) (xy 113.64901 -294.336216)
			(xy 113.65297 -294.287162) (xy 113.664747 -294.239378) (xy 113.684038 -294.194102) (xy 113.710341 -294.152506)
			(xy 113.742976 -294.115669) (xy 113.781097 -294.084544) (xy 113.823718 -294.059937) (xy 113.869734 -294.042485)
			(xy 113.917953 -294.032641) (xy 113.967128 -294.03066) (xy 114.015983 -294.036592) (xy 114.063254 -294.050284)
			(xy 114.107716 -294.071382) (xy 114.148219 -294.099338) (xy 114.183712 -294.13343) (xy 114.213277 -294.172774)
			(xy 114.236148 -294.216351) (xy 114.251732 -294.263032) (xy 114.259627 -294.311609) (xy 114.260122 -294.336216)
			(xy 114.58881 -294.336216) (xy 114.59277 -294.287162) (xy 114.604547 -294.239378) (xy 114.623838 -294.194102)
			(xy 114.650141 -294.152506) (xy 114.682776 -294.115669) (xy 114.720897 -294.084544) (xy 114.763518 -294.059937)
			(xy 114.809534 -294.042485) (xy 114.857753 -294.032641) (xy 114.906928 -294.03066) (xy 114.955783 -294.036592)
			(xy 115.003054 -294.050284) (xy 115.047516 -294.071382) (xy 115.088019 -294.099338) (xy 115.123512 -294.13343)
			(xy 115.153077 -294.172774) (xy 115.175948 -294.216351) (xy 115.191532 -294.263032) (xy 115.199427 -294.311609)
			(xy 115.199922 -294.336216) (xy 115.528864 -294.336216) (xy 115.532824 -294.287162) (xy 115.544601 -294.239378)
			(xy 115.563892 -294.194102) (xy 115.590195 -294.152506) (xy 115.62283 -294.115669) (xy 115.660951 -294.084544)
			(xy 115.703572 -294.059937) (xy 115.749588 -294.042485) (xy 115.797807 -294.032641) (xy 115.846982 -294.03066)
			(xy 115.895837 -294.036592) (xy 115.943108 -294.050284) (xy 115.98757 -294.071382) (xy 116.028073 -294.099338)
			(xy 116.063566 -294.13343) (xy 116.093131 -294.172774) (xy 116.116002 -294.216351) (xy 116.131586 -294.263032)
			(xy 116.139481 -294.311609) (xy 116.139976 -294.336216) (xy 116.468918 -294.336216) (xy 116.472878 -294.287162)
			(xy 116.484655 -294.239378) (xy 116.503946 -294.194102) (xy 116.530249 -294.152506) (xy 116.562884 -294.115669)
			(xy 116.601005 -294.084544) (xy 116.643626 -294.059937) (xy 116.689642 -294.042485) (xy 116.737861 -294.032641)
			(xy 116.787036 -294.03066) (xy 116.835891 -294.036592) (xy 116.883162 -294.050284) (xy 116.927624 -294.071382)
			(xy 116.968127 -294.099338) (xy 117.00362 -294.13343) (xy 117.033185 -294.172774) (xy 117.056056 -294.216351)
			(xy 117.07164 -294.263032) (xy 117.079535 -294.311609) (xy 117.08003 -294.336216) (xy 117.408972 -294.336216)
			(xy 117.412932 -294.287162) (xy 117.424709 -294.239378) (xy 117.444 -294.194102) (xy 117.470303 -294.152506)
			(xy 117.502938 -294.115669) (xy 117.541059 -294.084544) (xy 117.58368 -294.059937) (xy 117.629696 -294.042485)
			(xy 117.677915 -294.032641) (xy 117.72709 -294.03066) (xy 117.775945 -294.036592) (xy 117.823216 -294.050284)
			(xy 117.867678 -294.071382) (xy 117.908181 -294.099338) (xy 117.943674 -294.13343) (xy 117.973239 -294.172774)
			(xy 117.99611 -294.216351) (xy 118.011694 -294.263032) (xy 118.019589 -294.311609) (xy 118.020084 -294.336216)
			(xy 118.349026 -294.336216) (xy 118.352986 -294.287162) (xy 118.364763 -294.239378) (xy 118.384054 -294.194102)
			(xy 118.410357 -294.152506) (xy 118.442992 -294.115669) (xy 118.481113 -294.084544) (xy 118.523734 -294.059937)
			(xy 118.56975 -294.042485) (xy 118.617969 -294.032641) (xy 118.667144 -294.03066) (xy 118.715999 -294.036592)
			(xy 118.76327 -294.050284) (xy 118.807732 -294.071382) (xy 118.848235 -294.099338) (xy 118.883728 -294.13343)
			(xy 118.913293 -294.172774) (xy 118.936164 -294.216351) (xy 118.951748 -294.263032) (xy 118.959643 -294.311609)
			(xy 118.960138 -294.336216) (xy 119.288826 -294.336216) (xy 119.292786 -294.287162) (xy 119.304563 -294.239378)
			(xy 119.323854 -294.194102) (xy 119.350157 -294.152506) (xy 119.382792 -294.115669) (xy 119.420913 -294.084544)
			(xy 119.463534 -294.059937) (xy 119.50955 -294.042485) (xy 119.557769 -294.032641) (xy 119.606944 -294.03066)
			(xy 119.655799 -294.036592) (xy 119.70307 -294.050284) (xy 119.747532 -294.071382) (xy 119.788035 -294.099338)
			(xy 119.823528 -294.13343) (xy 119.853093 -294.172774) (xy 119.875964 -294.216351) (xy 119.891548 -294.263032)
			(xy 119.899443 -294.311609) (xy 119.899938 -294.336216) (xy 120.22888 -294.336216) (xy 120.23284 -294.287162)
			(xy 120.244617 -294.239378) (xy 120.263908 -294.194102) (xy 120.290211 -294.152506) (xy 120.322846 -294.115669)
			(xy 120.360967 -294.084544) (xy 120.403588 -294.059937) (xy 120.449604 -294.042485) (xy 120.497823 -294.032641)
			(xy 120.546998 -294.03066) (xy 120.595853 -294.036592) (xy 120.643124 -294.050284) (xy 120.687586 -294.071382)
			(xy 120.728089 -294.099338) (xy 120.763582 -294.13343) (xy 120.793147 -294.172774) (xy 120.816018 -294.216351)
			(xy 120.831602 -294.263032) (xy 120.839497 -294.311609) (xy 120.839992 -294.336216) (xy 121.168934 -294.336216)
			(xy 121.172894 -294.287162) (xy 121.184671 -294.239378) (xy 121.203962 -294.194102) (xy 121.230265 -294.152506)
			(xy 121.2629 -294.115669) (xy 121.301021 -294.084544) (xy 121.343642 -294.059937) (xy 121.389658 -294.042485)
			(xy 121.437877 -294.032641) (xy 121.487052 -294.03066) (xy 121.535907 -294.036592) (xy 121.583178 -294.050284)
			(xy 121.62764 -294.071382) (xy 121.668143 -294.099338) (xy 121.703636 -294.13343) (xy 121.733201 -294.172774)
			(xy 121.756072 -294.216351) (xy 121.771656 -294.263032) (xy 121.779551 -294.311609) (xy 121.780046 -294.336216)
			(xy 122.108988 -294.336216) (xy 122.112948 -294.287162) (xy 122.124725 -294.239378) (xy 122.144016 -294.194102)
			(xy 122.170319 -294.152506) (xy 122.202954 -294.115669) (xy 122.241075 -294.084544) (xy 122.283696 -294.059937)
			(xy 122.329712 -294.042485) (xy 122.377931 -294.032641) (xy 122.427106 -294.03066) (xy 122.475961 -294.036592)
			(xy 122.523232 -294.050284) (xy 122.567694 -294.071382) (xy 122.608197 -294.099338) (xy 122.64369 -294.13343)
			(xy 122.673255 -294.172774) (xy 122.696126 -294.216351) (xy 122.71171 -294.263032) (xy 122.719605 -294.311609)
			(xy 122.7201 -294.336216) (xy 123.049042 -294.336216) (xy 123.053002 -294.287162) (xy 123.064779 -294.239378)
			(xy 123.08407 -294.194102) (xy 123.110373 -294.152506) (xy 123.143008 -294.115669) (xy 123.181129 -294.084544)
			(xy 123.22375 -294.059937) (xy 123.269766 -294.042485) (xy 123.317985 -294.032641) (xy 123.36716 -294.03066)
			(xy 123.416015 -294.036592) (xy 123.463286 -294.050284) (xy 123.507748 -294.071382) (xy 123.548251 -294.099338)
			(xy 123.583744 -294.13343) (xy 123.613309 -294.172774) (xy 123.63618 -294.216351) (xy 123.651764 -294.263032)
			(xy 123.659659 -294.311609) (xy 123.660154 -294.336216) (xy 123.988842 -294.336216) (xy 123.992802 -294.287162)
			(xy 124.004579 -294.239378) (xy 124.02387 -294.194102) (xy 124.050173 -294.152506) (xy 124.082808 -294.115669)
			(xy 124.120929 -294.084544) (xy 124.16355 -294.059937) (xy 124.209566 -294.042485) (xy 124.257785 -294.032641)
			(xy 124.30696 -294.03066) (xy 124.355815 -294.036592) (xy 124.403086 -294.050284) (xy 124.447548 -294.071382)
			(xy 124.488051 -294.099338) (xy 124.523544 -294.13343) (xy 124.553109 -294.172774) (xy 124.57598 -294.216351)
			(xy 124.591564 -294.263032) (xy 124.599459 -294.311609) (xy 124.599954 -294.336216) (xy 124.928896 -294.336216)
			(xy 124.932856 -294.287162) (xy 124.944633 -294.239378) (xy 124.963924 -294.194102) (xy 124.990227 -294.152506)
			(xy 125.022862 -294.115669) (xy 125.060983 -294.084544) (xy 125.103604 -294.059937) (xy 125.14962 -294.042485)
			(xy 125.197839 -294.032641) (xy 125.247014 -294.03066) (xy 125.295869 -294.036592) (xy 125.34314 -294.050284)
			(xy 125.387602 -294.071382) (xy 125.428105 -294.099338) (xy 125.463598 -294.13343) (xy 125.493163 -294.172774)
			(xy 125.516034 -294.216351) (xy 125.531618 -294.263032) (xy 125.539513 -294.311609) (xy 125.540008 -294.336216)
			(xy 125.86895 -294.336216) (xy 125.87291 -294.287162) (xy 125.884687 -294.239378) (xy 125.903978 -294.194102)
			(xy 125.930281 -294.152506) (xy 125.962916 -294.115669) (xy 126.001037 -294.084544) (xy 126.043658 -294.059937)
			(xy 126.089674 -294.042485) (xy 126.137893 -294.032641) (xy 126.187068 -294.03066) (xy 126.235923 -294.036592)
			(xy 126.283194 -294.050284) (xy 126.327656 -294.071382) (xy 126.368159 -294.099338) (xy 126.403652 -294.13343)
			(xy 126.433217 -294.172774) (xy 126.456088 -294.216351) (xy 126.471672 -294.263032) (xy 126.479567 -294.311609)
			(xy 126.480062 -294.336216) (xy 126.809004 -294.336216) (xy 126.812964 -294.287162) (xy 126.824741 -294.239378)
			(xy 126.844032 -294.194102) (xy 126.870335 -294.152506) (xy 126.90297 -294.115669) (xy 126.941091 -294.084544)
			(xy 126.983712 -294.059937) (xy 127.029728 -294.042485) (xy 127.077947 -294.032641) (xy 127.127122 -294.03066)
			(xy 127.175977 -294.036592) (xy 127.223248 -294.050284) (xy 127.26771 -294.071382) (xy 127.308213 -294.099338)
			(xy 127.343706 -294.13343) (xy 127.373271 -294.172774) (xy 127.396142 -294.216351) (xy 127.411726 -294.263032)
			(xy 127.419621 -294.311609) (xy 127.420116 -294.336216) (xy 127.419621 -294.360823) (xy 127.411726 -294.4094)
			(xy 127.396142 -294.456081) (xy 127.373271 -294.499658) (xy 127.343706 -294.539002) (xy 127.308213 -294.573094)
			(xy 127.26771 -294.60105) (xy 127.223248 -294.622148) (xy 127.175977 -294.63584) (xy 127.127122 -294.641772)
			(xy 127.077947 -294.639791) (xy 127.029728 -294.629947) (xy 126.983712 -294.612495) (xy 126.941091 -294.587888)
			(xy 126.90297 -294.556763) (xy 126.870335 -294.519926) (xy 126.844032 -294.47833) (xy 126.824741 -294.433054)
			(xy 126.812964 -294.38527) (xy 126.809004 -294.336216) (xy 126.480062 -294.336216) (xy 126.479567 -294.360823)
			(xy 126.471672 -294.4094) (xy 126.456088 -294.456081) (xy 126.433217 -294.499658) (xy 126.403652 -294.539002)
			(xy 126.368159 -294.573094) (xy 126.327656 -294.60105) (xy 126.283194 -294.622148) (xy 126.235923 -294.63584)
			(xy 126.187068 -294.641772) (xy 126.137893 -294.639791) (xy 126.089674 -294.629947) (xy 126.043658 -294.612495)
			(xy 126.001037 -294.587888) (xy 125.962916 -294.556763) (xy 125.930281 -294.519926) (xy 125.903978 -294.47833)
			(xy 125.884687 -294.433054) (xy 125.87291 -294.38527) (xy 125.86895 -294.336216) (xy 125.540008 -294.336216)
			(xy 125.539513 -294.360823) (xy 125.531618 -294.4094) (xy 125.516034 -294.456081) (xy 125.493163 -294.499658)
			(xy 125.463598 -294.539002) (xy 125.428105 -294.573094) (xy 125.387602 -294.60105) (xy 125.34314 -294.622148)
			(xy 125.295869 -294.63584) (xy 125.247014 -294.641772) (xy 125.197839 -294.639791) (xy 125.14962 -294.629947)
			(xy 125.103604 -294.612495) (xy 125.060983 -294.587888) (xy 125.022862 -294.556763) (xy 124.990227 -294.519926)
			(xy 124.963924 -294.47833) (xy 124.944633 -294.433054) (xy 124.932856 -294.38527) (xy 124.928896 -294.336216)
			(xy 124.599954 -294.336216) (xy 124.599459 -294.360823) (xy 124.591564 -294.4094) (xy 124.57598 -294.456081)
			(xy 124.553109 -294.499658) (xy 124.523544 -294.539002) (xy 124.488051 -294.573094) (xy 124.447548 -294.60105)
			(xy 124.403086 -294.622148) (xy 124.355815 -294.63584) (xy 124.30696 -294.641772) (xy 124.257785 -294.639791)
			(xy 124.209566 -294.629947) (xy 124.16355 -294.612495) (xy 124.120929 -294.587888) (xy 124.082808 -294.556763)
			(xy 124.050173 -294.519926) (xy 124.02387 -294.47833) (xy 124.004579 -294.433054) (xy 123.992802 -294.38527)
			(xy 123.988842 -294.336216) (xy 123.660154 -294.336216) (xy 123.659659 -294.360823) (xy 123.651764 -294.4094)
			(xy 123.63618 -294.456081) (xy 123.613309 -294.499658) (xy 123.583744 -294.539002) (xy 123.548251 -294.573094)
			(xy 123.507748 -294.60105) (xy 123.463286 -294.622148) (xy 123.416015 -294.63584) (xy 123.36716 -294.641772)
			(xy 123.317985 -294.639791) (xy 123.269766 -294.629947) (xy 123.22375 -294.612495) (xy 123.181129 -294.587888)
			(xy 123.143008 -294.556763) (xy 123.110373 -294.519926) (xy 123.08407 -294.47833) (xy 123.064779 -294.433054)
			(xy 123.053002 -294.38527) (xy 123.049042 -294.336216) (xy 122.7201 -294.336216) (xy 122.719605 -294.360823)
			(xy 122.71171 -294.4094) (xy 122.696126 -294.456081) (xy 122.673255 -294.499658) (xy 122.64369 -294.539002)
			(xy 122.608197 -294.573094) (xy 122.567694 -294.60105) (xy 122.523232 -294.622148) (xy 122.475961 -294.63584)
			(xy 122.427106 -294.641772) (xy 122.377931 -294.639791) (xy 122.329712 -294.629947) (xy 122.283696 -294.612495)
			(xy 122.241075 -294.587888) (xy 122.202954 -294.556763) (xy 122.170319 -294.519926) (xy 122.144016 -294.47833)
			(xy 122.124725 -294.433054) (xy 122.112948 -294.38527) (xy 122.108988 -294.336216) (xy 121.780046 -294.336216)
			(xy 121.779551 -294.360823) (xy 121.771656 -294.4094) (xy 121.756072 -294.456081) (xy 121.733201 -294.499658)
			(xy 121.703636 -294.539002) (xy 121.668143 -294.573094) (xy 121.62764 -294.60105) (xy 121.583178 -294.622148)
			(xy 121.535907 -294.63584) (xy 121.487052 -294.641772) (xy 121.437877 -294.639791) (xy 121.389658 -294.629947)
			(xy 121.343642 -294.612495) (xy 121.301021 -294.587888) (xy 121.2629 -294.556763) (xy 121.230265 -294.519926)
			(xy 121.203962 -294.47833) (xy 121.184671 -294.433054) (xy 121.172894 -294.38527) (xy 121.168934 -294.336216)
			(xy 120.839992 -294.336216) (xy 120.839497 -294.360823) (xy 120.831602 -294.4094) (xy 120.816018 -294.456081)
			(xy 120.793147 -294.499658) (xy 120.763582 -294.539002) (xy 120.728089 -294.573094) (xy 120.687586 -294.60105)
			(xy 120.643124 -294.622148) (xy 120.595853 -294.63584) (xy 120.546998 -294.641772) (xy 120.497823 -294.639791)
			(xy 120.449604 -294.629947) (xy 120.403588 -294.612495) (xy 120.360967 -294.587888) (xy 120.322846 -294.556763)
			(xy 120.290211 -294.519926) (xy 120.263908 -294.47833) (xy 120.244617 -294.433054) (xy 120.23284 -294.38527)
			(xy 120.22888 -294.336216) (xy 119.899938 -294.336216) (xy 119.899443 -294.360823) (xy 119.891548 -294.4094)
			(xy 119.875964 -294.456081) (xy 119.853093 -294.499658) (xy 119.823528 -294.539002) (xy 119.788035 -294.573094)
			(xy 119.747532 -294.60105) (xy 119.70307 -294.622148) (xy 119.655799 -294.63584) (xy 119.606944 -294.641772)
			(xy 119.557769 -294.639791) (xy 119.50955 -294.629947) (xy 119.463534 -294.612495) (xy 119.420913 -294.587888)
			(xy 119.382792 -294.556763) (xy 119.350157 -294.519926) (xy 119.323854 -294.47833) (xy 119.304563 -294.433054)
			(xy 119.292786 -294.38527) (xy 119.288826 -294.336216) (xy 118.960138 -294.336216) (xy 118.959643 -294.360823)
			(xy 118.951748 -294.4094) (xy 118.936164 -294.456081) (xy 118.913293 -294.499658) (xy 118.883728 -294.539002)
			(xy 118.848235 -294.573094) (xy 118.807732 -294.60105) (xy 118.76327 -294.622148) (xy 118.715999 -294.63584)
			(xy 118.667144 -294.641772) (xy 118.617969 -294.639791) (xy 118.56975 -294.629947) (xy 118.523734 -294.612495)
			(xy 118.481113 -294.587888) (xy 118.442992 -294.556763) (xy 118.410357 -294.519926) (xy 118.384054 -294.47833)
			(xy 118.364763 -294.433054) (xy 118.352986 -294.38527) (xy 118.349026 -294.336216) (xy 118.020084 -294.336216)
			(xy 118.019589 -294.360823) (xy 118.011694 -294.4094) (xy 117.99611 -294.456081) (xy 117.973239 -294.499658)
			(xy 117.943674 -294.539002) (xy 117.908181 -294.573094) (xy 117.867678 -294.60105) (xy 117.823216 -294.622148)
			(xy 117.775945 -294.63584) (xy 117.72709 -294.641772) (xy 117.677915 -294.639791) (xy 117.629696 -294.629947)
			(xy 117.58368 -294.612495) (xy 117.541059 -294.587888) (xy 117.502938 -294.556763) (xy 117.470303 -294.519926)
			(xy 117.444 -294.47833) (xy 117.424709 -294.433054) (xy 117.412932 -294.38527) (xy 117.408972 -294.336216)
			(xy 117.08003 -294.336216) (xy 117.079535 -294.360823) (xy 117.07164 -294.4094) (xy 117.056056 -294.456081)
			(xy 117.033185 -294.499658) (xy 117.00362 -294.539002) (xy 116.968127 -294.573094) (xy 116.927624 -294.60105)
			(xy 116.883162 -294.622148) (xy 116.835891 -294.63584) (xy 116.787036 -294.641772) (xy 116.737861 -294.639791)
			(xy 116.689642 -294.629947) (xy 116.643626 -294.612495) (xy 116.601005 -294.587888) (xy 116.562884 -294.556763)
			(xy 116.530249 -294.519926) (xy 116.503946 -294.47833) (xy 116.484655 -294.433054) (xy 116.472878 -294.38527)
			(xy 116.468918 -294.336216) (xy 116.139976 -294.336216) (xy 116.139481 -294.360823) (xy 116.131586 -294.4094)
			(xy 116.116002 -294.456081) (xy 116.093131 -294.499658) (xy 116.063566 -294.539002) (xy 116.028073 -294.573094)
			(xy 115.98757 -294.60105) (xy 115.943108 -294.622148) (xy 115.895837 -294.63584) (xy 115.846982 -294.641772)
			(xy 115.797807 -294.639791) (xy 115.749588 -294.629947) (xy 115.703572 -294.612495) (xy 115.660951 -294.587888)
			(xy 115.62283 -294.556763) (xy 115.590195 -294.519926) (xy 115.563892 -294.47833) (xy 115.544601 -294.433054)
			(xy 115.532824 -294.38527) (xy 115.528864 -294.336216) (xy 115.199922 -294.336216) (xy 115.199427 -294.360823)
			(xy 115.191532 -294.4094) (xy 115.175948 -294.456081) (xy 115.153077 -294.499658) (xy 115.123512 -294.539002)
			(xy 115.088019 -294.573094) (xy 115.047516 -294.60105) (xy 115.003054 -294.622148) (xy 114.955783 -294.63584)
			(xy 114.906928 -294.641772) (xy 114.857753 -294.639791) (xy 114.809534 -294.629947) (xy 114.763518 -294.612495)
			(xy 114.720897 -294.587888) (xy 114.682776 -294.556763) (xy 114.650141 -294.519926) (xy 114.623838 -294.47833)
			(xy 114.604547 -294.433054) (xy 114.59277 -294.38527) (xy 114.58881 -294.336216) (xy 114.260122 -294.336216)
			(xy 114.259627 -294.360823) (xy 114.251732 -294.4094) (xy 114.236148 -294.456081) (xy 114.213277 -294.499658)
			(xy 114.183712 -294.539002) (xy 114.148219 -294.573094) (xy 114.107716 -294.60105) (xy 114.063254 -294.622148)
			(xy 114.015983 -294.63584) (xy 113.967128 -294.641772) (xy 113.917953 -294.639791) (xy 113.869734 -294.629947)
			(xy 113.823718 -294.612495) (xy 113.781097 -294.587888) (xy 113.742976 -294.556763) (xy 113.710341 -294.519926)
			(xy 113.684038 -294.47833) (xy 113.664747 -294.433054) (xy 113.65297 -294.38527) (xy 113.64901 -294.336216)
			(xy 112.622902 -294.336216) (xy 112.636018 -295.146222) (xy 113.178856 -295.146222) (xy 113.182816 -295.097168)
			(xy 113.194593 -295.049384) (xy 113.213884 -295.004108) (xy 113.240187 -294.962512) (xy 113.272822 -294.925675)
			(xy 113.310943 -294.89455) (xy 113.353564 -294.869943) (xy 113.39958 -294.852491) (xy 113.447799 -294.842647)
			(xy 113.496974 -294.840666) (xy 113.545829 -294.846598) (xy 113.5931 -294.86029) (xy 113.637562 -294.881388)
			(xy 113.678065 -294.909344) (xy 113.713558 -294.943436) (xy 113.743123 -294.98278) (xy 113.765994 -295.026357)
			(xy 113.781578 -295.073038) (xy 113.789473 -295.121615) (xy 113.789968 -295.146222) (xy 114.11891 -295.146222)
			(xy 114.12287 -295.097168) (xy 114.134647 -295.049384) (xy 114.153938 -295.004108) (xy 114.180241 -294.962512)
			(xy 114.212876 -294.925675) (xy 114.250997 -294.89455) (xy 114.293618 -294.869943) (xy 114.339634 -294.852491)
			(xy 114.387853 -294.842647) (xy 114.437028 -294.840666) (xy 114.485883 -294.846598) (xy 114.533154 -294.86029)
			(xy 114.577616 -294.881388) (xy 114.618119 -294.909344) (xy 114.653612 -294.943436) (xy 114.683177 -294.98278)
			(xy 114.706048 -295.026357) (xy 114.721632 -295.073038) (xy 114.729527 -295.121615) (xy 114.730022 -295.146222)
			(xy 116.938818 -295.146222) (xy 116.942778 -295.097168) (xy 116.954555 -295.049384) (xy 116.973846 -295.004108)
			(xy 117.000149 -294.962512) (xy 117.032784 -294.925675) (xy 117.070905 -294.89455) (xy 117.113526 -294.869943)
			(xy 117.159542 -294.852491) (xy 117.207761 -294.842647) (xy 117.256936 -294.840666) (xy 117.305791 -294.846598)
			(xy 117.353062 -294.86029) (xy 117.397524 -294.881388) (xy 117.438027 -294.909344) (xy 117.47352 -294.943436)
			(xy 117.503085 -294.98278) (xy 117.525956 -295.026357) (xy 117.54154 -295.073038) (xy 117.549435 -295.121615)
			(xy 117.54993 -295.146222) (xy 119.75898 -295.146222) (xy 119.76294 -295.097168) (xy 119.774717 -295.049384)
			(xy 119.794008 -295.004108) (xy 119.820311 -294.962512) (xy 119.852946 -294.925675) (xy 119.891067 -294.89455)
			(xy 119.933688 -294.869943) (xy 119.979704 -294.852491) (xy 120.027923 -294.842647) (xy 120.077098 -294.840666)
			(xy 120.125953 -294.846598) (xy 120.173224 -294.86029) (xy 120.217686 -294.881388) (xy 120.258189 -294.909344)
			(xy 120.293682 -294.943436) (xy 120.323247 -294.98278) (xy 120.346118 -295.026357) (xy 120.361702 -295.073038)
			(xy 120.369597 -295.121615) (xy 120.370092 -295.146222) (xy 122.578888 -295.146222) (xy 122.582848 -295.097168)
			(xy 122.594625 -295.049384) (xy 122.613916 -295.004108) (xy 122.640219 -294.962512) (xy 122.672854 -294.925675)
			(xy 122.710975 -294.89455) (xy 122.753596 -294.869943) (xy 122.799612 -294.852491) (xy 122.847831 -294.842647)
			(xy 122.897006 -294.840666) (xy 122.945861 -294.846598) (xy 122.993132 -294.86029) (xy 123.037594 -294.881388)
			(xy 123.078097 -294.909344) (xy 123.11359 -294.943436) (xy 123.143155 -294.98278) (xy 123.166026 -295.026357)
			(xy 123.18161 -295.073038) (xy 123.189505 -295.121615) (xy 123.19 -295.146222) (xy 125.39905 -295.146222)
			(xy 125.40301 -295.097168) (xy 125.414787 -295.049384) (xy 125.434078 -295.004108) (xy 125.460381 -294.962512)
			(xy 125.493016 -294.925675) (xy 125.531137 -294.89455) (xy 125.573758 -294.869943) (xy 125.619774 -294.852491)
			(xy 125.667993 -294.842647) (xy 125.717168 -294.840666) (xy 125.766023 -294.846598) (xy 125.813294 -294.86029)
			(xy 125.857756 -294.881388) (xy 125.898259 -294.909344) (xy 125.933752 -294.943436) (xy 125.963317 -294.98278)
			(xy 125.986188 -295.026357) (xy 126.001772 -295.073038) (xy 126.009667 -295.121615) (xy 126.010162 -295.146222)
			(xy 126.009667 -295.170829) (xy 126.001772 -295.219406) (xy 125.986188 -295.266087) (xy 125.963317 -295.309664)
			(xy 125.933752 -295.349008) (xy 125.898259 -295.3831) (xy 125.857756 -295.411056) (xy 125.813294 -295.432154)
			(xy 125.766023 -295.445846) (xy 125.717168 -295.451778) (xy 125.667993 -295.449797) (xy 125.619774 -295.439953)
			(xy 125.573758 -295.422501) (xy 125.531137 -295.397894) (xy 125.493016 -295.366769) (xy 125.460381 -295.329932)
			(xy 125.434078 -295.288336) (xy 125.414787 -295.24306) (xy 125.40301 -295.195276) (xy 125.39905 -295.146222)
			(xy 123.19 -295.146222) (xy 123.189505 -295.170829) (xy 123.18161 -295.219406) (xy 123.166026 -295.266087)
			(xy 123.143155 -295.309664) (xy 123.11359 -295.349008) (xy 123.078097 -295.3831) (xy 123.037594 -295.411056)
			(xy 122.993132 -295.432154) (xy 122.945861 -295.445846) (xy 122.897006 -295.451778) (xy 122.847831 -295.449797)
			(xy 122.799612 -295.439953) (xy 122.753596 -295.422501) (xy 122.710975 -295.397894) (xy 122.672854 -295.366769)
			(xy 122.640219 -295.329932) (xy 122.613916 -295.288336) (xy 122.594625 -295.24306) (xy 122.582848 -295.195276)
			(xy 122.578888 -295.146222) (xy 120.370092 -295.146222) (xy 120.369597 -295.170829) (xy 120.361702 -295.219406)
			(xy 120.346118 -295.266087) (xy 120.323247 -295.309664) (xy 120.293682 -295.349008) (xy 120.258189 -295.3831)
			(xy 120.217686 -295.411056) (xy 120.173224 -295.432154) (xy 120.125953 -295.445846) (xy 120.077098 -295.451778)
			(xy 120.027923 -295.449797) (xy 119.979704 -295.439953) (xy 119.933688 -295.422501) (xy 119.891067 -295.397894)
			(xy 119.852946 -295.366769) (xy 119.820311 -295.329932) (xy 119.794008 -295.288336) (xy 119.774717 -295.24306)
			(xy 119.76294 -295.195276) (xy 119.75898 -295.146222) (xy 117.54993 -295.146222) (xy 117.549435 -295.170829)
			(xy 117.54154 -295.219406) (xy 117.525956 -295.266087) (xy 117.503085 -295.309664) (xy 117.47352 -295.349008)
			(xy 117.438027 -295.3831) (xy 117.397524 -295.411056) (xy 117.353062 -295.432154) (xy 117.305791 -295.445846)
			(xy 117.256936 -295.451778) (xy 117.207761 -295.449797) (xy 117.159542 -295.439953) (xy 117.113526 -295.422501)
			(xy 117.070905 -295.397894) (xy 117.032784 -295.366769) (xy 117.000149 -295.329932) (xy 116.973846 -295.288336)
			(xy 116.954555 -295.24306) (xy 116.942778 -295.195276) (xy 116.938818 -295.146222) (xy 114.730022 -295.146222)
			(xy 114.729527 -295.170829) (xy 114.721632 -295.219406) (xy 114.706048 -295.266087) (xy 114.683177 -295.309664)
			(xy 114.653612 -295.349008) (xy 114.618119 -295.3831) (xy 114.577616 -295.411056) (xy 114.533154 -295.432154)
			(xy 114.485883 -295.445846) (xy 114.437028 -295.451778) (xy 114.387853 -295.449797) (xy 114.339634 -295.439953)
			(xy 114.293618 -295.422501) (xy 114.250997 -295.397894) (xy 114.212876 -295.366769) (xy 114.180241 -295.329932)
			(xy 114.153938 -295.288336) (xy 114.134647 -295.24306) (xy 114.12287 -295.195276) (xy 114.11891 -295.146222)
			(xy 113.789968 -295.146222) (xy 113.789473 -295.170829) (xy 113.781578 -295.219406) (xy 113.765994 -295.266087)
			(xy 113.743123 -295.309664) (xy 113.713558 -295.349008) (xy 113.678065 -295.3831) (xy 113.637562 -295.411056)
			(xy 113.5931 -295.432154) (xy 113.545829 -295.445846) (xy 113.496974 -295.451778) (xy 113.447799 -295.449797)
			(xy 113.39958 -295.439953) (xy 113.353564 -295.422501) (xy 113.310943 -295.397894) (xy 113.272822 -295.366769)
			(xy 113.240187 -295.329932) (xy 113.213884 -295.288336) (xy 113.194593 -295.24306) (xy 113.182816 -295.195276)
			(xy 113.178856 -295.146222) (xy 112.636018 -295.146222) (xy 112.639094 -295.336214) (xy 112.639348 -295.345612)
			(xy 112.639348 -295.86555) (xy 112.639782 -295.875615) (xy 112.647514 -295.894202) (xy 112.654334 -295.901618)
			(xy 112.708926 -295.956228) (xy 114.58881 -295.956228) (xy 114.59277 -295.907174) (xy 114.604547 -295.85939)
			(xy 114.623838 -295.814114) (xy 114.650141 -295.772518) (xy 114.682776 -295.735681) (xy 114.720897 -295.704556)
			(xy 114.763518 -295.679949) (xy 114.809534 -295.662497) (xy 114.857753 -295.652653) (xy 114.906928 -295.650672)
			(xy 114.955783 -295.656604) (xy 115.003054 -295.670296) (xy 115.047516 -295.691394) (xy 115.088019 -295.71935)
			(xy 115.123512 -295.753442) (xy 115.153077 -295.792786) (xy 115.175948 -295.836363) (xy 115.191532 -295.883044)
			(xy 115.199427 -295.931621) (xy 115.199922 -295.956228) (xy 115.528864 -295.956228) (xy 115.532824 -295.907174)
			(xy 115.544601 -295.85939) (xy 115.563892 -295.814114) (xy 115.590195 -295.772518) (xy 115.62283 -295.735681)
			(xy 115.660951 -295.704556) (xy 115.703572 -295.679949) (xy 115.749588 -295.662497) (xy 115.797807 -295.652653)
			(xy 115.846982 -295.650672) (xy 115.895837 -295.656604) (xy 115.943108 -295.670296) (xy 115.98757 -295.691394)
			(xy 116.028073 -295.71935) (xy 116.063566 -295.753442) (xy 116.093131 -295.792786) (xy 116.116002 -295.836363)
			(xy 116.131586 -295.883044) (xy 116.139481 -295.931621) (xy 116.139976 -295.956228) (xy 116.468918 -295.956228)
			(xy 116.472878 -295.907174) (xy 116.484655 -295.85939) (xy 116.503946 -295.814114) (xy 116.530249 -295.772518)
			(xy 116.562884 -295.735681) (xy 116.601005 -295.704556) (xy 116.643626 -295.679949) (xy 116.689642 -295.662497)
			(xy 116.737861 -295.652653) (xy 116.787036 -295.650672) (xy 116.835891 -295.656604) (xy 116.883162 -295.670296)
			(xy 116.927624 -295.691394) (xy 116.968127 -295.71935) (xy 117.00362 -295.753442) (xy 117.033185 -295.792786)
			(xy 117.056056 -295.836363) (xy 117.07164 -295.883044) (xy 117.079535 -295.931621) (xy 117.08003 -295.956228)
			(xy 117.408972 -295.956228) (xy 117.412932 -295.907174) (xy 117.424709 -295.85939) (xy 117.444 -295.814114)
			(xy 117.470303 -295.772518) (xy 117.502938 -295.735681) (xy 117.541059 -295.704556) (xy 117.58368 -295.679949)
			(xy 117.629696 -295.662497) (xy 117.677915 -295.652653) (xy 117.72709 -295.650672) (xy 117.775945 -295.656604)
			(xy 117.823216 -295.670296) (xy 117.867678 -295.691394) (xy 117.908181 -295.71935) (xy 117.943674 -295.753442)
			(xy 117.973239 -295.792786) (xy 117.99611 -295.836363) (xy 118.011694 -295.883044) (xy 118.019589 -295.931621)
			(xy 118.020084 -295.956228) (xy 118.349026 -295.956228) (xy 118.352986 -295.907174) (xy 118.364763 -295.85939)
			(xy 118.384054 -295.814114) (xy 118.410357 -295.772518) (xy 118.442992 -295.735681) (xy 118.481113 -295.704556)
			(xy 118.523734 -295.679949) (xy 118.56975 -295.662497) (xy 118.617969 -295.652653) (xy 118.667144 -295.650672)
			(xy 118.715999 -295.656604) (xy 118.76327 -295.670296) (xy 118.807732 -295.691394) (xy 118.848235 -295.71935)
			(xy 118.883728 -295.753442) (xy 118.913293 -295.792786) (xy 118.936164 -295.836363) (xy 118.951748 -295.883044)
			(xy 118.959643 -295.931621) (xy 118.960138 -295.956228) (xy 120.22888 -295.956228) (xy 120.23284 -295.907174)
			(xy 120.244617 -295.85939) (xy 120.263908 -295.814114) (xy 120.290211 -295.772518) (xy 120.322846 -295.735681)
			(xy 120.360967 -295.704556) (xy 120.403588 -295.679949) (xy 120.449604 -295.662497) (xy 120.497823 -295.652653)
			(xy 120.546998 -295.650672) (xy 120.595853 -295.656604) (xy 120.643124 -295.670296) (xy 120.687586 -295.691394)
			(xy 120.728089 -295.71935) (xy 120.763582 -295.753442) (xy 120.793147 -295.792786) (xy 120.816018 -295.836363)
			(xy 120.831602 -295.883044) (xy 120.839497 -295.931621) (xy 120.839992 -295.956228) (xy 121.168934 -295.956228)
			(xy 121.172894 -295.907174) (xy 121.184671 -295.85939) (xy 121.203962 -295.814114) (xy 121.230265 -295.772518)
			(xy 121.2629 -295.735681) (xy 121.301021 -295.704556) (xy 121.343642 -295.679949) (xy 121.389658 -295.662497)
			(xy 121.437877 -295.652653) (xy 121.487052 -295.650672) (xy 121.535907 -295.656604) (xy 121.583178 -295.670296)
			(xy 121.62764 -295.691394) (xy 121.668143 -295.71935) (xy 121.703636 -295.753442) (xy 121.733201 -295.792786)
			(xy 121.756072 -295.836363) (xy 121.771656 -295.883044) (xy 121.779551 -295.931621) (xy 121.780046 -295.956228)
			(xy 122.108988 -295.956228) (xy 122.112948 -295.907174) (xy 122.124725 -295.85939) (xy 122.144016 -295.814114)
			(xy 122.170319 -295.772518) (xy 122.202954 -295.735681) (xy 122.241075 -295.704556) (xy 122.283696 -295.679949)
			(xy 122.329712 -295.662497) (xy 122.377931 -295.652653) (xy 122.427106 -295.650672) (xy 122.475961 -295.656604)
			(xy 122.523232 -295.670296) (xy 122.567694 -295.691394) (xy 122.608197 -295.71935) (xy 122.64369 -295.753442)
			(xy 122.673255 -295.792786) (xy 122.696126 -295.836363) (xy 122.71171 -295.883044) (xy 122.719605 -295.931621)
			(xy 122.7201 -295.956228) (xy 123.049042 -295.956228) (xy 123.053002 -295.907174) (xy 123.064779 -295.85939)
			(xy 123.08407 -295.814114) (xy 123.110373 -295.772518) (xy 123.143008 -295.735681) (xy 123.181129 -295.704556)
			(xy 123.22375 -295.679949) (xy 123.269766 -295.662497) (xy 123.317985 -295.652653) (xy 123.36716 -295.650672)
			(xy 123.416015 -295.656604) (xy 123.463286 -295.670296) (xy 123.507748 -295.691394) (xy 123.548251 -295.71935)
			(xy 123.583744 -295.753442) (xy 123.613309 -295.792786) (xy 123.63618 -295.836363) (xy 123.651764 -295.883044)
			(xy 123.659659 -295.931621) (xy 123.660154 -295.956228) (xy 123.988842 -295.956228) (xy 123.992802 -295.907174)
			(xy 124.004579 -295.85939) (xy 124.02387 -295.814114) (xy 124.050173 -295.772518) (xy 124.082808 -295.735681)
			(xy 124.120929 -295.704556) (xy 124.16355 -295.679949) (xy 124.209566 -295.662497) (xy 124.257785 -295.652653)
			(xy 124.30696 -295.650672) (xy 124.355815 -295.656604) (xy 124.403086 -295.670296) (xy 124.447548 -295.691394)
			(xy 124.488051 -295.71935) (xy 124.523544 -295.753442) (xy 124.553109 -295.792786) (xy 124.57598 -295.836363)
			(xy 124.591564 -295.883044) (xy 124.599459 -295.931621) (xy 124.599954 -295.956228) (xy 125.86895 -295.956228)
			(xy 125.87291 -295.907174) (xy 125.884687 -295.85939) (xy 125.903978 -295.814114) (xy 125.930281 -295.772518)
			(xy 125.962916 -295.735681) (xy 126.001037 -295.704556) (xy 126.043658 -295.679949) (xy 126.089674 -295.662497)
			(xy 126.137893 -295.652653) (xy 126.187068 -295.650672) (xy 126.235923 -295.656604) (xy 126.283194 -295.670296)
			(xy 126.327656 -295.691394) (xy 126.368159 -295.71935) (xy 126.403652 -295.753442) (xy 126.433217 -295.792786)
			(xy 126.456088 -295.836363) (xy 126.471672 -295.883044) (xy 126.479567 -295.931621) (xy 126.480062 -295.956228)
			(xy 126.809004 -295.956228) (xy 126.812964 -295.907174) (xy 126.824741 -295.85939) (xy 126.844032 -295.814114)
			(xy 126.870335 -295.772518) (xy 126.90297 -295.735681) (xy 126.941091 -295.704556) (xy 126.983712 -295.679949)
			(xy 127.029728 -295.662497) (xy 127.077947 -295.652653) (xy 127.127122 -295.650672) (xy 127.175977 -295.656604)
			(xy 127.223248 -295.670296) (xy 127.26771 -295.691394) (xy 127.308213 -295.71935) (xy 127.343706 -295.753442)
			(xy 127.373271 -295.792786) (xy 127.396142 -295.836363) (xy 127.411726 -295.883044) (xy 127.419621 -295.931621)
			(xy 127.420116 -295.956228) (xy 127.419621 -295.980835) (xy 127.411726 -296.029412) (xy 127.396142 -296.076093)
			(xy 127.373271 -296.11967) (xy 127.343706 -296.159014) (xy 127.308213 -296.193106) (xy 127.26771 -296.221062)
			(xy 127.223248 -296.24216) (xy 127.175977 -296.255852) (xy 127.127122 -296.261784) (xy 127.077947 -296.259803)
			(xy 127.029728 -296.249959) (xy 126.983712 -296.232507) (xy 126.941091 -296.2079) (xy 126.90297 -296.176775)
			(xy 126.870335 -296.139938) (xy 126.844032 -296.098342) (xy 126.824741 -296.053066) (xy 126.812964 -296.005282)
			(xy 126.809004 -295.956228) (xy 126.480062 -295.956228) (xy 126.479567 -295.980835) (xy 126.471672 -296.029412)
			(xy 126.456088 -296.076093) (xy 126.433217 -296.11967) (xy 126.403652 -296.159014) (xy 126.368159 -296.193106)
			(xy 126.327656 -296.221062) (xy 126.283194 -296.24216) (xy 126.235923 -296.255852) (xy 126.187068 -296.261784)
			(xy 126.137893 -296.259803) (xy 126.089674 -296.249959) (xy 126.043658 -296.232507) (xy 126.001037 -296.2079)
			(xy 125.962916 -296.176775) (xy 125.930281 -296.139938) (xy 125.903978 -296.098342) (xy 125.884687 -296.053066)
			(xy 125.87291 -296.005282) (xy 125.86895 -295.956228) (xy 124.599954 -295.956228) (xy 124.599459 -295.980835)
			(xy 124.591564 -296.029412) (xy 124.57598 -296.076093) (xy 124.553109 -296.11967) (xy 124.523544 -296.159014)
			(xy 124.488051 -296.193106) (xy 124.447548 -296.221062) (xy 124.403086 -296.24216) (xy 124.355815 -296.255852)
			(xy 124.30696 -296.261784) (xy 124.257785 -296.259803) (xy 124.209566 -296.249959) (xy 124.16355 -296.232507)
			(xy 124.120929 -296.2079) (xy 124.082808 -296.176775) (xy 124.050173 -296.139938) (xy 124.02387 -296.098342)
			(xy 124.004579 -296.053066) (xy 123.992802 -296.005282) (xy 123.988842 -295.956228) (xy 123.660154 -295.956228)
			(xy 123.659659 -295.980835) (xy 123.651764 -296.029412) (xy 123.63618 -296.076093) (xy 123.613309 -296.11967)
			(xy 123.583744 -296.159014) (xy 123.548251 -296.193106) (xy 123.507748 -296.221062) (xy 123.463286 -296.24216)
			(xy 123.416015 -296.255852) (xy 123.36716 -296.261784) (xy 123.317985 -296.259803) (xy 123.269766 -296.249959)
			(xy 123.22375 -296.232507) (xy 123.181129 -296.2079) (xy 123.143008 -296.176775) (xy 123.110373 -296.139938)
			(xy 123.08407 -296.098342) (xy 123.064779 -296.053066) (xy 123.053002 -296.005282) (xy 123.049042 -295.956228)
			(xy 122.7201 -295.956228) (xy 122.719605 -295.980835) (xy 122.71171 -296.029412) (xy 122.696126 -296.076093)
			(xy 122.673255 -296.11967) (xy 122.64369 -296.159014) (xy 122.608197 -296.193106) (xy 122.567694 -296.221062)
			(xy 122.523232 -296.24216) (xy 122.475961 -296.255852) (xy 122.427106 -296.261784) (xy 122.377931 -296.259803)
			(xy 122.329712 -296.249959) (xy 122.283696 -296.232507) (xy 122.241075 -296.2079) (xy 122.202954 -296.176775)
			(xy 122.170319 -296.139938) (xy 122.144016 -296.098342) (xy 122.124725 -296.053066) (xy 122.112948 -296.005282)
			(xy 122.108988 -295.956228) (xy 121.780046 -295.956228) (xy 121.779551 -295.980835) (xy 121.771656 -296.029412)
			(xy 121.756072 -296.076093) (xy 121.733201 -296.11967) (xy 121.703636 -296.159014) (xy 121.668143 -296.193106)
			(xy 121.62764 -296.221062) (xy 121.583178 -296.24216) (xy 121.535907 -296.255852) (xy 121.487052 -296.261784)
			(xy 121.437877 -296.259803) (xy 121.389658 -296.249959) (xy 121.343642 -296.232507) (xy 121.301021 -296.2079)
			(xy 121.2629 -296.176775) (xy 121.230265 -296.139938) (xy 121.203962 -296.098342) (xy 121.184671 -296.053066)
			(xy 121.172894 -296.005282) (xy 121.168934 -295.956228) (xy 120.839992 -295.956228) (xy 120.839497 -295.980835)
			(xy 120.831602 -296.029412) (xy 120.816018 -296.076093) (xy 120.793147 -296.11967) (xy 120.763582 -296.159014)
			(xy 120.728089 -296.193106) (xy 120.687586 -296.221062) (xy 120.643124 -296.24216) (xy 120.595853 -296.255852)
			(xy 120.546998 -296.261784) (xy 120.497823 -296.259803) (xy 120.449604 -296.249959) (xy 120.403588 -296.232507)
			(xy 120.360967 -296.2079) (xy 120.322846 -296.176775) (xy 120.290211 -296.139938) (xy 120.263908 -296.098342)
			(xy 120.244617 -296.053066) (xy 120.23284 -296.005282) (xy 120.22888 -295.956228) (xy 118.960138 -295.956228)
			(xy 118.959643 -295.980835) (xy 118.951748 -296.029412) (xy 118.936164 -296.076093) (xy 118.913293 -296.11967)
			(xy 118.883728 -296.159014) (xy 118.848235 -296.193106) (xy 118.807732 -296.221062) (xy 118.76327 -296.24216)
			(xy 118.715999 -296.255852) (xy 118.667144 -296.261784) (xy 118.617969 -296.259803) (xy 118.56975 -296.249959)
			(xy 118.523734 -296.232507) (xy 118.481113 -296.2079) (xy 118.442992 -296.176775) (xy 118.410357 -296.139938)
			(xy 118.384054 -296.098342) (xy 118.364763 -296.053066) (xy 118.352986 -296.005282) (xy 118.349026 -295.956228)
			(xy 118.020084 -295.956228) (xy 118.019589 -295.980835) (xy 118.011694 -296.029412) (xy 117.99611 -296.076093)
			(xy 117.973239 -296.11967) (xy 117.943674 -296.159014) (xy 117.908181 -296.193106) (xy 117.867678 -296.221062)
			(xy 117.823216 -296.24216) (xy 117.775945 -296.255852) (xy 117.72709 -296.261784) (xy 117.677915 -296.259803)
			(xy 117.629696 -296.249959) (xy 117.58368 -296.232507) (xy 117.541059 -296.2079) (xy 117.502938 -296.176775)
			(xy 117.470303 -296.139938) (xy 117.444 -296.098342) (xy 117.424709 -296.053066) (xy 117.412932 -296.005282)
			(xy 117.408972 -295.956228) (xy 117.08003 -295.956228) (xy 117.079535 -295.980835) (xy 117.07164 -296.029412)
			(xy 117.056056 -296.076093) (xy 117.033185 -296.11967) (xy 117.00362 -296.159014) (xy 116.968127 -296.193106)
			(xy 116.927624 -296.221062) (xy 116.883162 -296.24216) (xy 116.835891 -296.255852) (xy 116.787036 -296.261784)
			(xy 116.737861 -296.259803) (xy 116.689642 -296.249959) (xy 116.643626 -296.232507) (xy 116.601005 -296.2079)
			(xy 116.562884 -296.176775) (xy 116.530249 -296.139938) (xy 116.503946 -296.098342) (xy 116.484655 -296.053066)
			(xy 116.472878 -296.005282) (xy 116.468918 -295.956228) (xy 116.139976 -295.956228) (xy 116.139481 -295.980835)
			(xy 116.131586 -296.029412) (xy 116.116002 -296.076093) (xy 116.093131 -296.11967) (xy 116.063566 -296.159014)
			(xy 116.028073 -296.193106) (xy 115.98757 -296.221062) (xy 115.943108 -296.24216) (xy 115.895837 -296.255852)
			(xy 115.846982 -296.261784) (xy 115.797807 -296.259803) (xy 115.749588 -296.249959) (xy 115.703572 -296.232507)
			(xy 115.660951 -296.2079) (xy 115.62283 -296.176775) (xy 115.590195 -296.139938) (xy 115.563892 -296.098342)
			(xy 115.544601 -296.053066) (xy 115.532824 -296.005282) (xy 115.528864 -295.956228) (xy 115.199922 -295.956228)
			(xy 115.199427 -295.980835) (xy 115.191532 -296.029412) (xy 115.175948 -296.076093) (xy 115.153077 -296.11967)
			(xy 115.123512 -296.159014) (xy 115.088019 -296.193106) (xy 115.047516 -296.221062) (xy 115.003054 -296.24216)
			(xy 114.955783 -296.255852) (xy 114.906928 -296.261784) (xy 114.857753 -296.259803) (xy 114.809534 -296.249959)
			(xy 114.763518 -296.232507) (xy 114.720897 -296.2079) (xy 114.682776 -296.176775) (xy 114.650141 -296.139938)
			(xy 114.623838 -296.098342) (xy 114.604547 -296.053066) (xy 114.59277 -296.005282) (xy 114.58881 -295.956228)
			(xy 112.708926 -295.956228) (xy 113.420144 -296.667682) (xy 113.427544 -296.674524) (xy 113.446142 -296.682245)
			(xy 113.456212 -296.682668) (xy 128.062482 -296.682668) (xy 128.07061 -296.681906) (xy 128.071118 -296.681906)
			(xy 128.078638 -296.680307) (xy 128.092329 -296.673334) (xy 128.098042 -296.66819) (xy 128.283208 -296.483024)
			(xy 128.288405 -296.477347) (xy 128.295395 -296.463643) (xy 128.296924 -296.4561) (xy 128.296924 -296.455592)
			(xy 128.297686 -296.447464) (xy 128.297686 -296.335958) (xy 128.297432 -296.33164) (xy 128.295805 -296.32167)
			(xy 128.285858 -296.304106) (xy 128.278128 -296.297604) (xy 128.246124 -296.275506) (xy 128.206754 -296.248328)
			(xy 128.198969 -296.243631) (xy 128.181259 -296.23958) (xy 128.17221 -296.240454) (xy 128.161034 -296.242486)
			(xy 128.157478 -296.243756) (xy 128.13264 -296.252057) (xy 128.081045 -296.261004) (xy 128.054862 -296.261536)
			(xy 128.029606 -296.261011) (xy 127.979785 -296.252692) (xy 127.932012 -296.236286) (xy 127.887591 -296.212242)
			(xy 127.847733 -296.181214) (xy 127.813524 -296.14405) (xy 127.785899 -296.101762) (xy 127.765611 -296.055505)
			(xy 127.753212 -296.006539) (xy 127.749041 -295.9562) (xy 127.753212 -295.905861) (xy 127.765611 -295.856895)
			(xy 127.785899 -295.810638) (xy 127.813524 -295.76835) (xy 127.847733 -295.731186) (xy 127.887591 -295.700158)
			(xy 127.932012 -295.676114) (xy 127.979785 -295.659708) (xy 128.029606 -295.651389) (xy 128.054862 -295.65092)
			(xy 128.081991 -295.651504) (xy 128.135398 -295.661077) (xy 128.161034 -295.66997) (xy 128.163828 -295.670986)
			(xy 128.174177 -295.673535) (xy 128.195301 -295.670894) (xy 128.204722 -295.665906) (xy 128.274826 -295.617138)
			(xy 128.275842 -295.616376) (xy 128.276096 -295.616122) (xy 128.277112 -295.61536) (xy 128.279398 -295.613582)
			(xy 128.279652 -295.613582) (xy 128.279906 -295.613328) (xy 128.287765 -295.605956) (xy 128.296961 -295.586488)
			(xy 128.297686 -295.575736) (xy 128.297686 -295.368472) (xy 128.297288 -295.360502) (xy 128.292234 -295.345376)
			(xy 128.28778 -295.338754) (xy 128.271745 -295.318201) (xy 128.2462 -295.272764) (xy 128.228744 -295.223648)
			(xy 128.219887 -295.17228) (xy 128.219884 -295.120154) (xy 128.228736 -295.068786) (xy 128.246185 -295.019667)
			(xy 128.271726 -294.974227) (xy 128.28778 -294.95369) (xy 128.292305 -294.947105) (xy 128.297351 -294.931955)
			(xy 128.297686 -294.923972) (xy 128.297686 -294.715946) (xy 128.297432 -294.711628) (xy 128.295803 -294.701659)
			(xy 128.285853 -294.684099) (xy 128.278128 -294.677592) (xy 128.246124 -294.655494) (xy 128.206754 -294.628316)
			(xy 128.198969 -294.62362) (xy 128.181259 -294.61957) (xy 128.17221 -294.620442) (xy 128.161034 -294.622474)
			(xy 128.157478 -294.623744) (xy 128.13264 -294.632046) (xy 128.081045 -294.640993) (xy 128.054862 -294.641524)
			(xy 128.029607 -294.640999) (xy 127.979788 -294.63268) (xy 127.932017 -294.616275) (xy 127.887597 -294.592232)
			(xy 127.847741 -294.561205) (xy 127.813534 -294.524042) (xy 127.78591 -294.481757) (xy 127.765622 -294.435501)
			(xy 127.753224 -294.386537) (xy 127.749053 -294.3362) (xy 127.753224 -294.285863) (xy 127.765622 -294.236899)
			(xy 127.78591 -294.190643) (xy 127.813534 -294.148358) (xy 127.847741 -294.111195) (xy 127.887597 -294.080168)
			(xy 127.932017 -294.056125) (xy 127.979788 -294.03972) (xy 128.029607 -294.031401) (xy 128.054862 -294.030908)
			(xy 128.081991 -294.031492) (xy 128.135398 -294.041064) (xy 128.161034 -294.049958) (xy 128.163828 -294.050974)
			(xy 128.174177 -294.053523) (xy 128.195301 -294.050882) (xy 128.204722 -294.045894) (xy 128.274826 -293.997126)
			(xy 128.275842 -293.996364) (xy 128.276096 -293.99611) (xy 128.277112 -293.995348) (xy 128.279398 -293.99357)
			(xy 128.279652 -293.99357) (xy 128.279906 -293.993316) (xy 128.287764 -293.985943) (xy 128.296955 -293.966476)
			(xy 128.297686 -293.955724) (xy 128.297686 -293.763954) (xy 128.29759 -293.759809) (xy 128.296187 -293.751637)
			(xy 128.294892 -293.747698) (xy 128.291844 -293.739062) (xy 128.276377 -293.721526) (xy 128.250251 -293.682747)
			(xy 128.230128 -293.640541) (xy 128.216447 -293.595829) (xy 128.209508 -293.549589) (xy 128.20904 -293.52621)
			(xy 128.209478 -293.502828) (xy 128.216407 -293.456581) (xy 128.230086 -293.411862) (xy 128.250214 -293.369652)
			(xy 128.276351 -293.330875) (xy 128.291844 -293.313358) (xy 128.294892 -293.304722) (xy 128.296154 -293.300775)
			(xy 128.297555 -293.292608) (xy 128.297686 -293.288466) (xy 128.297686 -293.10203) (xy 128.297178 -293.095172)
			(xy 128.295703 -293.08689) (xy 128.288196 -293.071847) (xy 128.282446 -293.065708) (xy 128.279652 -293.063168)
			(xy 128.275842 -293.060374) (xy 128.27508 -293.059866) (xy 128.207262 -293.012622) (xy 128.202413 -293.009415)
			(xy 128.191641 -293.005051) (xy 128.185926 -293.003986) (xy 128.166622 -293.011352) (xy 128.139663 -293.020841)
			(xy 128.083436 -293.031058) (xy 128.054862 -293.031672) (xy 128.030074 -293.031183) (xy 127.981109 -293.023422)
			(xy 127.933961 -293.008098) (xy 127.88979 -292.985587) (xy 127.849684 -292.956444) (xy 127.814631 -292.921387)
			(xy 127.785493 -292.881277) (xy 127.762987 -292.837104) (xy 127.747669 -292.789954) (xy 127.739914 -292.740988)
			(xy 127.739914 -292.691412) (xy 127.747669 -292.642446) (xy 127.762987 -292.595296) (xy 127.785493 -292.551123)
			(xy 127.814631 -292.511013) (xy 127.849684 -292.475956) (xy 127.88979 -292.446813) (xy 127.933961 -292.424302)
			(xy 127.981109 -292.408978) (xy 128.030074 -292.401217) (xy 128.054862 -292.400736) (xy 128.083437 -292.401338)
			(xy 128.139666 -292.411556) (xy 128.166622 -292.421056) (xy 128.185926 -292.428422) (xy 128.191645 -292.42737)
			(xy 128.202424 -292.423012) (xy 128.207262 -292.419786) (xy 128.27508 -292.372542) (xy 128.275842 -292.372034)
			(xy 128.279652 -292.36924) (xy 128.282446 -292.3667) (xy 128.288245 -292.360594) (xy 128.295761 -292.345537)
			(xy 128.297178 -292.337236) (xy 128.297686 -292.330378) (xy 128.297686 -292.143942) (xy 128.297589 -292.139797)
			(xy 128.296184 -292.131626) (xy 128.294892 -292.127686) (xy 128.291844 -292.11905) (xy 128.276372 -292.101515)
			(xy 128.250235 -292.062739) (xy 128.2301 -292.020534) (xy 128.216407 -291.975821) (xy 128.209455 -291.929579)
			(xy 128.20904 -291.906198) (xy 128.209479 -291.882817) (xy 128.216409 -291.83657) (xy 128.230089 -291.791853)
			(xy 128.250219 -291.749644) (xy 128.276357 -291.710868) (xy 128.291844 -291.693346) (xy 128.294892 -291.68471)
			(xy 128.296153 -291.680763) (xy 128.297552 -291.672596) (xy 128.297686 -291.668454) (xy 128.297686 -291.482018)
			(xy 128.297178 -291.47516) (xy 128.295701 -291.466879) (xy 128.288192 -291.451839) (xy 128.282446 -291.445696)
			(xy 128.279652 -291.443156) (xy 128.275842 -291.440362) (xy 128.27508 -291.439854) (xy 128.207262 -291.39261)
			(xy 128.202413 -291.389403) (xy 128.19164 -291.385041) (xy 128.185926 -291.383974) (xy 128.166622 -291.39134)
			(xy 128.139663 -291.400829) (xy 128.083436 -291.411047) (xy 128.054862 -291.41166) (xy 128.030075 -291.411171)
			(xy 127.981112 -291.40341) (xy 127.933966 -291.388087) (xy 127.889797 -291.365577) (xy 127.849693 -291.336435)
			(xy 127.814641 -291.301378) (xy 127.785504 -291.261271) (xy 127.762999 -291.217099) (xy 127.747681 -291.169951)
			(xy 127.739926 -291.120987) (xy 127.739926 -291.071413) (xy 127.747681 -291.022449) (xy 127.762999 -290.975301)
			(xy 127.785504 -290.931129) (xy 127.814641 -290.891022) (xy 127.849693 -290.855965) (xy 127.889797 -290.826823)
			(xy 127.933966 -290.804313) (xy 127.981112 -290.78899) (xy 128.030075 -290.781229) (xy 128.054862 -290.780724)
			(xy 128.083502 -290.781301) (xy 128.139861 -290.791518) (xy 128.166876 -290.801044) (xy 128.185672 -290.80841)
			(xy 128.191379 -290.807422) (xy 128.20216 -290.803196) (xy 128.207008 -290.800028) (xy 128.222756 -290.789106)
			(xy 128.234608 -290.780201) (xy 128.253002 -290.756968) (xy 128.263959 -290.729435) (xy 128.266559 -290.699917)
			(xy 128.260584 -290.670892) (xy 128.246536 -290.644801) (xy 128.236472 -290.633912) (xy 128.012952 -290.410392)
			(xy 128.001775 -290.399989) (xy 127.974754 -290.385797) (xy 127.94475 -290.380203) (xy 127.91443 -290.383704)
			(xy 127.886491 -290.395989) (xy 127.863415 -290.415966) (xy 127.854964 -290.42868) (xy 127.85344 -290.43122)
			(xy 127.852932 -290.432236) (xy 127.841338 -290.452563) (xy 127.812934 -290.48975) (xy 127.779193 -290.522172)
			(xy 127.740905 -290.549073) (xy 127.698963 -290.569823) (xy 127.654349 -290.583937) (xy 127.608105 -290.591086)
			(xy 127.584708 -290.591494) (xy 127.560715 -290.591048) (xy 127.513319 -290.583543) (xy 127.467681 -290.568715)
			(xy 127.424925 -290.546929) (xy 127.386104 -290.518724) (xy 127.352172 -290.484792) (xy 127.323967 -290.44597)
			(xy 127.302183 -290.403213) (xy 127.287356 -290.357575) (xy 127.279851 -290.310179) (xy 127.2794 -290.286186)
			(xy 127.279538 -290.273423) (xy 127.281698 -290.247989) (xy 127.283718 -290.235386) (xy 127.283464 -290.235386)
			(xy 127.287718 -290.212677) (xy 127.30217 -290.168797) (xy 127.323075 -290.127598) (xy 127.349955 -290.090023)
			(xy 127.382195 -290.056933) (xy 127.419057 -290.029085) (xy 127.439166 -290.017708) (xy 127.439674 -290.017454)
			(xy 127.442214 -290.01593) (xy 127.454923 -290.00745) (xy 127.474964 -289.984408) (xy 127.487292 -289.956469)
			(xy 127.490803 -289.926133) (xy 127.485182 -289.896116) (xy 127.470932 -289.869106) (xy 127.460502 -289.857942)
			(xy 127.342646 -289.740086) (xy 127.340868 -289.738562) (xy 127.332678 -289.731799) (xy 127.312571 -289.725028)
			(xy 127.291445 -289.726968) (xy 127.28194 -289.731704) (xy 127.2794 -289.733228) (xy 127.260893 -289.744648)
			(xy 127.221327 -289.762698) (xy 127.179598 -289.774939) (xy 127.136552 -289.781123) (xy 127.114808 -289.781488)
			(xy 127.090815 -289.781042) (xy 127.04342 -289.773537) (xy 126.997782 -289.758708) (xy 126.955027 -289.736923)
			(xy 126.916205 -289.708717) (xy 126.882275 -289.674786) (xy 126.854071 -289.635963) (xy 126.832287 -289.593207)
			(xy 126.817461 -289.547569) (xy 126.809957 -289.500173) (xy 126.8095 -289.47618) (xy 126.810168 -289.447544)
			(xy 126.820905 -289.391287) (xy 126.830836 -289.36442) (xy 126.839925 -289.342449) (xy 126.863908 -289.301395)
			(xy 126.893957 -289.264549) (xy 126.911354 -289.248342) (xy 126.914402 -289.245802) (xy 126.924562 -289.233356)
			(xy 126.926966 -289.228973) (xy 126.930166 -289.219503) (xy 126.930912 -289.21456) (xy 126.930912 -289.214052)
			(xy 126.93142 -289.207956) (xy 126.93142 -289.027616) (xy 126.93142 -289.026854) (xy 126.930699 -289.0125)
			(xy 126.92227 -288.985036) (xy 126.906542 -288.960996) (xy 126.884754 -288.942274) (xy 126.85862 -288.930343)
			(xy 126.830201 -288.926145) (xy 126.801734 -288.930009) (xy 126.788418 -288.935414) (xy 126.78791 -288.935668)
			(xy 126.78537 -288.936938) (xy 126.785116 -288.937192) (xy 126.763291 -288.947984) (xy 126.717064 -288.963261)
			(xy 126.668997 -288.970993) (xy 126.644654 -288.971482) (xy 126.619403 -288.970957) (xy 126.569592 -288.962638)
			(xy 126.521828 -288.946234) (xy 126.477416 -288.922194) (xy 126.437566 -288.891172) (xy 126.403365 -288.854014)
			(xy 126.375746 -288.811734) (xy 126.355461 -288.765486) (xy 126.343065 -288.716529) (xy 126.338895 -288.6662)
			(xy 126.343065 -288.615871) (xy 126.355461 -288.566914) (xy 126.375746 -288.520666) (xy 126.403365 -288.478386)
			(xy 126.437566 -288.441228) (xy 126.477416 -288.410206) (xy 126.521828 -288.386166) (xy 126.569592 -288.369762)
			(xy 126.619403 -288.361443) (xy 126.644654 -288.360866) (xy 126.644908 -288.360866) (xy 126.669442 -288.361351)
			(xy 126.717878 -288.369198) (xy 126.76443 -288.384706) (xy 126.786386 -288.395664) (xy 126.787656 -288.396426)
			(xy 126.789688 -288.397188) (xy 126.790958 -288.397696) (xy 126.804267 -288.402692) (xy 126.832501 -288.4059)
			(xy 126.860526 -288.401204) (xy 126.886173 -288.388969) (xy 126.907456 -288.370141) (xy 126.922729 -288.346178)
			(xy 126.930808 -288.318935) (xy 126.93142 -288.304732) (xy 126.93142 -288.135568) (xy 126.931263 -288.130191)
			(xy 126.928967 -288.119684) (xy 126.926848 -288.11474) (xy 126.924054 -288.108644) (xy 126.91872 -288.096706)
			(xy 126.916749 -288.092499) (xy 126.911514 -288.084826) (xy 126.908306 -288.081466) (xy 126.906782 -288.079942)
			(xy 126.888782 -288.062502) (xy 126.85816 -288.022829) (xy 126.834429 -287.978688) (xy 126.818223 -287.931265)
			(xy 126.809979 -287.881831) (xy 126.809918 -287.831715) (xy 126.818041 -287.782262) (xy 126.83413 -287.734799)
			(xy 126.857754 -287.6906) (xy 126.888277 -287.650852) (xy 126.906274 -287.63341) (xy 126.90729 -287.632394)
			(xy 126.91491 -287.624774) (xy 126.924054 -287.6042) (xy 126.926848 -287.598104) (xy 126.928955 -287.593156)
			(xy 126.931257 -287.582652) (xy 126.93142 -287.577276) (xy 126.93142 -286.515556) (xy 126.931261 -286.510179)
			(xy 126.928963 -286.499673) (xy 126.926848 -286.494728) (xy 126.924054 -286.488632) (xy 126.91872 -286.476694)
			(xy 126.916748 -286.472488) (xy 126.911512 -286.464816) (xy 126.908306 -286.461454) (xy 126.906782 -286.45993)
			(xy 126.888783 -286.44249) (xy 126.858164 -286.402817) (xy 126.834434 -286.358677) (xy 126.81823 -286.311254)
			(xy 126.809988 -286.261822) (xy 126.809928 -286.211708) (xy 126.818052 -286.162256) (xy 126.834142 -286.114795)
			(xy 126.857766 -286.070598) (xy 126.88829 -286.030852) (xy 126.906274 -286.013398) (xy 126.90729 -286.012382)
			(xy 126.91491 -286.004762) (xy 126.924054 -285.984188) (xy 126.926848 -285.978092) (xy 126.928954 -285.973143)
			(xy 126.931253 -285.96264) (xy 126.93142 -285.957264) (xy 126.93142 -285.787846) (xy 126.93142 -285.787084)
			(xy 126.930702 -285.772727) (xy 126.922279 -285.745255) (xy 126.906552 -285.721208) (xy 126.884761 -285.702479)
			(xy 126.858623 -285.690545) (xy 126.830197 -285.686345) (xy 126.801725 -285.690212) (xy 126.788418 -285.695644)
			(xy 126.78791 -285.695898) (xy 126.78537 -285.697168) (xy 126.785116 -285.697422) (xy 126.763292 -285.708217)
			(xy 126.717065 -285.723497) (xy 126.668997 -285.731231) (xy 126.644654 -285.731712) (xy 126.619401 -285.731187)
			(xy 126.569584 -285.722867) (xy 126.521816 -285.706462) (xy 126.4774 -285.682419) (xy 126.437546 -285.651394)
			(xy 126.403341 -285.614232) (xy 126.375719 -285.571949) (xy 126.355433 -285.525695) (xy 126.343035 -285.476734)
			(xy 126.338865 -285.4264) (xy 126.343035 -285.376066) (xy 126.355433 -285.327105) (xy 126.375719 -285.280851)
			(xy 126.403341 -285.238568) (xy 126.437546 -285.201406) (xy 126.4774 -285.170381) (xy 126.521816 -285.146338)
			(xy 126.569584 -285.129933) (xy 126.619401 -285.121613) (xy 126.644654 -285.121096) (xy 126.644908 -285.121096)
			(xy 126.669442 -285.121581) (xy 126.717877 -285.129429) (xy 126.764429 -285.144938) (xy 126.786386 -285.155894)
			(xy 126.787656 -285.156656) (xy 126.789688 -285.157418) (xy 126.790958 -285.157926) (xy 126.804264 -285.162924)
			(xy 126.832493 -285.166135) (xy 126.860514 -285.161439) (xy 126.886155 -285.149202) (xy 126.90743 -285.130371)
			(xy 126.92269 -285.106406) (xy 126.930753 -285.079163) (xy 126.93142 -285.064962) (xy 126.93142 -284.895544)
			(xy 126.93126 -284.890168) (xy 126.92896 -284.879662) (xy 126.926848 -284.874716) (xy 126.924054 -284.86862)
			(xy 126.91872 -284.856682) (xy 126.916747 -284.852476) (xy 126.91151 -284.844805) (xy 126.908306 -284.841442)
			(xy 126.906782 -284.839918) (xy 126.888784 -284.822478) (xy 126.858167 -284.782806) (xy 126.834439 -284.738666)
			(xy 126.818237 -284.691244) (xy 126.809996 -284.641814) (xy 126.809937 -284.591701) (xy 126.818062 -284.542251)
			(xy 126.834153 -284.494791) (xy 126.857778 -284.450596) (xy 126.888302 -284.410852) (xy 126.906274 -284.393386)
			(xy 126.90729 -284.39237) (xy 126.91491 -284.38475) (xy 126.924054 -284.364176) (xy 126.926848 -284.35808)
			(xy 126.928953 -284.353131) (xy 126.931249 -284.342627) (xy 126.93142 -284.337252) (xy 126.93142 -283.275532)
			(xy 126.931259 -283.270156) (xy 126.928956 -283.259652) (xy 126.926848 -283.254704) (xy 126.924054 -283.248608)
			(xy 126.91872 -283.23667) (xy 126.916747 -283.232465) (xy 126.911508 -283.224795) (xy 126.908306 -283.22143)
			(xy 126.906782 -283.219906) (xy 126.888785 -283.202466) (xy 126.85817 -283.162794) (xy 126.834443 -283.118655)
			(xy 126.818243 -283.071234) (xy 126.810004 -283.021805) (xy 126.809947 -282.971693) (xy 126.818073 -282.922245)
			(xy 126.834164 -282.874787) (xy 126.857789 -282.830594) (xy 126.888314 -282.790852) (xy 126.906274 -282.773374)
			(xy 126.90729 -282.772358) (xy 126.91491 -282.764738) (xy 126.924054 -282.744164) (xy 126.926848 -282.738068)
			(xy 126.928962 -282.733121) (xy 126.931277 -282.722617) (xy 126.93142 -282.71724) (xy 126.93142 -282.547822)
			(xy 126.93142 -282.54706) (xy 126.930699 -282.532705) (xy 126.922272 -282.50524) (xy 126.906544 -282.481198)
			(xy 126.884755 -282.462475) (xy 126.858621 -282.450543) (xy 126.8302 -282.446345) (xy 126.801732 -282.45021)
			(xy 126.788418 -282.45562) (xy 126.78791 -282.455874) (xy 126.78537 -282.457144) (xy 126.785116 -282.457398)
			(xy 126.763291 -282.46819) (xy 126.717064 -282.483466) (xy 126.668997 -282.491199) (xy 126.644654 -282.491688)
			(xy 126.619403 -282.491163) (xy 126.56959 -282.482844) (xy 126.521826 -282.46644) (xy 126.477413 -282.442399)
			(xy 126.437562 -282.411376) (xy 126.40336 -282.374218) (xy 126.37574 -282.331937) (xy 126.355456 -282.285687)
			(xy 126.343059 -282.23673) (xy 126.338889 -282.1864) (xy 126.343059 -282.13607) (xy 126.355456 -282.087113)
			(xy 126.37574 -282.040863) (xy 126.40336 -281.998582) (xy 126.437562 -281.961424) (xy 126.477413 -281.930401)
			(xy 126.521826 -281.90636) (xy 126.56959 -281.889956) (xy 126.619403 -281.881637) (xy 126.644654 -281.881072)
			(xy 126.644908 -281.881072) (xy 126.669442 -281.881557) (xy 126.717878 -281.889405) (xy 126.76443 -281.904912)
			(xy 126.786386 -281.91587) (xy 126.787656 -281.916632) (xy 126.789688 -281.917394) (xy 126.790958 -281.917902)
			(xy 126.804267 -281.922898) (xy 126.832502 -281.926105) (xy 126.860527 -281.921409) (xy 126.886175 -281.909174)
			(xy 126.907459 -281.890347) (xy 126.922732 -281.866384) (xy 126.930812 -281.839141) (xy 126.93142 -281.824938)
			(xy 126.93142 -281.65552) (xy 126.931258 -281.650144) (xy 126.928953 -281.639641) (xy 126.926848 -281.634692)
			(xy 126.924054 -281.628596) (xy 126.91872 -281.616658) (xy 126.916746 -281.612453) (xy 126.911506 -281.604785)
			(xy 126.908306 -281.601418) (xy 126.906782 -281.599894) (xy 126.888786 -281.582454) (xy 126.858173 -281.542782)
			(xy 126.834448 -281.498644) (xy 126.81825 -281.451224) (xy 126.810012 -281.401796) (xy 126.809956 -281.351686)
			(xy 126.818083 -281.302239) (xy 126.834176 -281.254783) (xy 126.857801 -281.210592) (xy 126.888326 -281.170852)
			(xy 126.906274 -281.153362) (xy 126.90729 -281.152346) (xy 126.91491 -281.144726) (xy 126.924054 -281.124152)
			(xy 126.926848 -281.118056) (xy 126.928961 -281.113109) (xy 126.931273 -281.102605) (xy 126.93142 -281.097228)
			(xy 126.93142 -280.92781) (xy 126.93142 -280.927048) (xy 126.930698 -280.912694) (xy 126.922269 -280.885232)
			(xy 126.906541 -280.861194) (xy 126.884752 -280.842472) (xy 126.85862 -280.830543) (xy 126.830201 -280.826345)
			(xy 126.801736 -280.830209) (xy 126.788418 -280.835608) (xy 126.78791 -280.835862) (xy 126.78537 -280.837132)
			(xy 126.785116 -280.837386) (xy 126.763291 -280.848179) (xy 126.717064 -280.863455) (xy 126.668997 -280.871188)
			(xy 126.644654 -280.871676) (xy 126.619404 -280.871151) (xy 126.569593 -280.862832) (xy 126.521831 -280.846429)
			(xy 126.477419 -280.822389) (xy 126.43757 -280.791367) (xy 126.40337 -280.75421) (xy 126.375751 -280.711931)
			(xy 126.355467 -280.665684) (xy 126.343071 -280.616728) (xy 126.338901 -280.5664) (xy 126.343071 -280.516072)
			(xy 126.355467 -280.467116) (xy 126.375751 -280.420869) (xy 126.40337 -280.37859) (xy 126.43757 -280.341433)
			(xy 126.477419 -280.310411) (xy 126.521831 -280.286371) (xy 126.569593 -280.269968) (xy 126.619404 -280.261649)
			(xy 126.644654 -280.26106) (xy 126.644908 -280.26106) (xy 126.669442 -280.261545) (xy 126.717878 -280.269392)
			(xy 126.76443 -280.2849) (xy 126.786386 -280.295858) (xy 126.787656 -280.29662) (xy 126.789688 -280.297382)
			(xy 126.790958 -280.29789) (xy 126.804267 -280.302886) (xy 126.8325 -280.306094) (xy 126.860525 -280.301398)
			(xy 126.886172 -280.289163) (xy 126.907454 -280.270335) (xy 126.922725 -280.246372) (xy 126.930803 -280.219129)
			(xy 126.93142 -280.204926) (xy 126.93142 -280.035508) (xy 126.931257 -280.030133) (xy 126.928949 -280.01963)
			(xy 126.926848 -280.01468) (xy 126.924054 -280.008584) (xy 126.91872 -279.996646) (xy 126.916745 -279.992442)
			(xy 126.911504 -279.984775) (xy 126.908306 -279.981406) (xy 126.906782 -279.979882) (xy 126.888787 -279.962442)
			(xy 126.858175 -279.922771) (xy 126.834453 -279.878633) (xy 126.818256 -279.831214) (xy 126.81002 -279.781787)
			(xy 126.809965 -279.731678) (xy 126.818094 -279.682233) (xy 126.834187 -279.634779) (xy 126.857813 -279.59059)
			(xy 126.888338 -279.550851) (xy 126.906274 -279.53335) (xy 126.90729 -279.532334) (xy 126.91491 -279.524714)
			(xy 126.924054 -279.50414) (xy 126.926848 -279.498044) (xy 126.928959 -279.493097) (xy 126.931269 -279.482593)
			(xy 126.93142 -279.477216) (xy 126.93142 -278.415496) (xy 126.931255 -278.410121) (xy 126.928946 -278.39962)
			(xy 126.926848 -278.394668) (xy 126.924054 -278.388572) (xy 126.91872 -278.376634) (xy 126.916745 -278.37243)
			(xy 126.911502 -278.364765) (xy 126.908306 -278.361394) (xy 126.906782 -278.35987) (xy 126.888788 -278.34243)
			(xy 126.858178 -278.302759) (xy 126.834458 -278.258622) (xy 126.818263 -278.211204) (xy 126.810028 -278.161778)
			(xy 126.809975 -278.111671) (xy 126.818104 -278.062227) (xy 126.834198 -278.014775) (xy 126.857825 -277.970588)
			(xy 126.88835 -277.930851) (xy 126.906274 -277.913338) (xy 126.90729 -277.912322) (xy 126.91491 -277.904702)
			(xy 126.924054 -277.884128) (xy 126.926848 -277.878032) (xy 126.928958 -277.873084) (xy 126.931266 -277.862581)
			(xy 126.93142 -277.857204) (xy 126.93142 -277.687786) (xy 126.93142 -277.687024) (xy 126.930707 -277.672663)
			(xy 126.92229 -277.645181) (xy 126.906565 -277.621123) (xy 126.884771 -277.602386) (xy 126.858626 -277.590446)
			(xy 126.830193 -277.586246) (xy 126.801714 -277.590116) (xy 126.788418 -277.595584) (xy 126.78791 -277.595838)
			(xy 126.78537 -277.597108) (xy 126.785116 -277.597362) (xy 126.763292 -277.608155) (xy 126.717065 -277.623433)
			(xy 126.668997 -277.631167) (xy 126.644654 -277.631652) (xy 126.619397 -277.631127) (xy 126.569574 -277.622806)
			(xy 126.5218 -277.606399) (xy 126.477378 -277.582353) (xy 126.437518 -277.551323) (xy 126.403309 -277.514157)
			(xy 126.375684 -277.471868) (xy 126.355395 -277.425608) (xy 126.342995 -277.376641) (xy 126.338824 -277.3263)
			(xy 126.342995 -277.275959) (xy 126.355395 -277.226992) (xy 126.375684 -277.180732) (xy 126.403309 -277.138443)
			(xy 126.437518 -277.101277) (xy 126.477378 -277.070247) (xy 126.5218 -277.046201) (xy 126.569574 -277.029794)
			(xy 126.619397 -277.021473) (xy 126.644654 -277.021036) (xy 126.644908 -277.021036) (xy 126.669442 -277.021521)
			(xy 126.717877 -277.02937) (xy 126.764428 -277.044881) (xy 126.786386 -277.055834) (xy 126.787656 -277.056596)
			(xy 126.789688 -277.057358) (xy 126.790958 -277.057866) (xy 126.804265 -277.062863) (xy 126.832498 -277.066072)
			(xy 126.860521 -277.061376) (xy 126.886166 -277.04914) (xy 126.907445 -277.030311) (xy 126.922712 -277.006347)
			(xy 126.930784 -276.979104) (xy 126.93142 -276.964902) (xy 126.93142 -276.795484) (xy 126.931254 -276.790109)
			(xy 126.928943 -276.779609) (xy 126.926848 -276.774656) (xy 126.924054 -276.76856) (xy 126.91872 -276.756622)
			(xy 126.91675 -276.752414) (xy 126.911517 -276.744739) (xy 126.908306 -276.741382) (xy 126.906782 -276.739858)
			(xy 126.888789 -276.722418) (xy 126.858181 -276.682747) (xy 126.834463 -276.638611) (xy 126.818269 -276.591194)
			(xy 126.810036 -276.541769) (xy 126.809984 -276.491663) (xy 126.818115 -276.442221) (xy 126.83421 -276.394771)
			(xy 126.857837 -276.350585) (xy 126.888362 -276.310851) (xy 126.906274 -276.293326) (xy 126.90729 -276.29231)
			(xy 126.91491 -276.28469) (xy 126.924054 -276.264116) (xy 126.926848 -276.25802) (xy 126.928957 -276.253072)
			(xy 126.931261 -276.242568) (xy 126.93142 -276.237192) (xy 126.93142 -275.175472) (xy 126.931263 -275.170095)
			(xy 126.928968 -275.159587) (xy 126.926848 -275.154644) (xy 126.924054 -275.148548) (xy 126.91872 -275.13661)
			(xy 126.916749 -275.132403) (xy 126.911515 -275.124729) (xy 126.908306 -275.12137) (xy 126.906782 -275.119846)
			(xy 126.888781 -275.102406) (xy 126.85816 -275.062733) (xy 126.834427 -275.018592) (xy 126.818221 -274.971168)
			(xy 126.809976 -274.921734) (xy 126.809915 -274.871618) (xy 126.818037 -274.822164) (xy 126.834126 -274.7747)
			(xy 126.85775 -274.730501) (xy 126.888273 -274.690752) (xy 126.906274 -274.673314) (xy 126.90729 -274.672298)
			(xy 126.91491 -274.664678) (xy 126.924054 -274.644104) (xy 126.926848 -274.638008) (xy 126.928955 -274.63306)
			(xy 126.931258 -274.622556) (xy 126.93142 -274.61718) (xy 126.93142 -274.447762) (xy 126.93142 -274.447)
			(xy 126.930704 -274.432641) (xy 126.922283 -274.405166) (xy 126.906557 -274.381114) (xy 126.884765 -274.362382)
			(xy 126.858624 -274.350445) (xy 126.830196 -274.346246) (xy 126.80172 -274.350114) (xy 126.788418 -274.35556)
			(xy 126.78791 -274.355814) (xy 126.78537 -274.357084) (xy 126.785116 -274.357338) (xy 126.763292 -274.368132)
			(xy 126.717065 -274.383411) (xy 126.668997 -274.391145) (xy 126.644654 -274.391628) (xy 126.6194 -274.391103)
			(xy 126.56958 -274.382783) (xy 126.52181 -274.366377) (xy 126.477391 -274.342332) (xy 126.437535 -274.311305)
			(xy 126.403329 -274.274142) (xy 126.375705 -274.231856) (xy 126.355418 -274.1856) (xy 126.34302 -274.136637)
			(xy 126.338849 -274.0863) (xy 126.34302 -274.035963) (xy 126.355418 -273.987) (xy 126.375705 -273.940744)
			(xy 126.403329 -273.898458) (xy 126.437535 -273.861295) (xy 126.477391 -273.830268) (xy 126.52181 -273.806223)
			(xy 126.56958 -273.789817) (xy 126.6194 -273.781497) (xy 126.644654 -273.781012) (xy 126.644908 -273.781012)
			(xy 126.669442 -273.781497) (xy 126.717877 -273.789346) (xy 126.764429 -273.804855) (xy 126.786386 -273.81581)
			(xy 126.787656 -273.816572) (xy 126.789688 -273.817334) (xy 126.790958 -273.817842) (xy 126.804264 -273.82284)
			(xy 126.832495 -273.826049) (xy 126.860517 -273.821354) (xy 126.886159 -273.809117) (xy 126.907436 -273.790287)
			(xy 126.922699 -273.766322) (xy 126.930765 -273.739079) (xy 126.93142 -273.724878) (xy 126.93142 -273.55546)
			(xy 126.931262 -273.550083) (xy 126.928965 -273.539577) (xy 126.926848 -273.534632) (xy 126.924054 -273.528536)
			(xy 126.91872 -273.516598) (xy 126.916748 -273.512392) (xy 126.911513 -273.504719) (xy 126.908306 -273.501358)
			(xy 126.906782 -273.499834) (xy 126.888783 -273.482394) (xy 126.858163 -273.442721) (xy 126.834432 -273.398581)
			(xy 126.818228 -273.351158) (xy 126.809985 -273.301725) (xy 126.809925 -273.25161) (xy 126.818048 -273.202158)
			(xy 126.834138 -273.154696) (xy 126.857762 -273.110499) (xy 126.888286 -273.070752) (xy 126.906274 -273.053302)
			(xy 126.90729 -273.052286) (xy 126.91491 -273.044666) (xy 126.924054 -273.024092) (xy 126.926848 -273.017996)
			(xy 126.928954 -273.013048) (xy 126.931254 -273.002544) (xy 126.93142 -272.997168) (xy 126.93142 -271.935448)
			(xy 126.931261 -271.930072) (xy 126.928961 -271.919566) (xy 126.926848 -271.91462) (xy 126.924054 -271.908524)
			(xy 126.91872 -271.896586) (xy 126.916748 -271.89238) (xy 126.911511 -271.884709) (xy 126.908306 -271.881346)
			(xy 126.906782 -271.879822) (xy 126.888784 -271.862382) (xy 126.858166 -271.822709) (xy 126.834437 -271.77857)
			(xy 126.818235 -271.731148) (xy 126.809993 -271.681717) (xy 126.809934 -271.631603) (xy 126.818059 -271.582153)
			(xy 126.834149 -271.534692) (xy 126.857774 -271.490497) (xy 126.888298 -271.450752) (xy 126.906274 -271.43329)
			(xy 126.90729 -271.432274) (xy 126.91491 -271.424654) (xy 126.924054 -271.40408) (xy 126.926848 -271.397984)
			(xy 126.928953 -271.393035) (xy 126.93125 -271.382532) (xy 126.93142 -271.377156) (xy 126.93142 -271.207738)
			(xy 126.93142 -271.206976) (xy 126.930701 -271.19262) (xy 126.922277 -271.16515) (xy 126.906549 -271.141105)
			(xy 126.884759 -271.122377) (xy 126.858622 -271.110444) (xy 126.830198 -271.106245) (xy 126.801727 -271.110112)
			(xy 126.788418 -271.115536) (xy 126.78791 -271.11579) (xy 126.78537 -271.11706) (xy 126.785116 -271.117314)
			(xy 126.763292 -271.128109) (xy 126.717065 -271.143389) (xy 126.668997 -271.151124) (xy 126.644654 -271.151604)
			(xy 126.619402 -271.151079) (xy 126.569586 -271.142759) (xy 126.52182 -271.126355) (xy 126.477404 -271.102312)
			(xy 126.437551 -271.071288) (xy 126.403348 -271.034128) (xy 126.375726 -270.991845) (xy 126.35544 -270.945593)
			(xy 126.343043 -270.896633) (xy 126.338873 -270.8463) (xy 126.343043 -270.795967) (xy 126.35544 -270.747007)
			(xy 126.375726 -270.700755) (xy 126.403348 -270.658472) (xy 126.437551 -270.621312) (xy 126.477404 -270.590288)
			(xy 126.52182 -270.566245) (xy 126.569586 -270.549841) (xy 126.619402 -270.541521) (xy 126.644654 -270.540988)
			(xy 126.644908 -270.540988) (xy 126.669442 -270.541473) (xy 126.717877 -270.549321) (xy 126.764429 -270.56483)
			(xy 126.786386 -270.575786) (xy 126.787656 -270.576548) (xy 126.789688 -270.57731) (xy 126.790958 -270.577818)
			(xy 126.804263 -270.582816) (xy 126.832492 -270.586027) (xy 126.860513 -270.581332) (xy 126.886153 -270.569095)
			(xy 126.907427 -270.550264) (xy 126.922685 -270.526298) (xy 126.930746 -270.499054) (xy 126.93142 -270.484854)
			(xy 126.93142 -270.315436) (xy 126.931259 -270.31006) (xy 126.928958 -270.299555) (xy 126.926848 -270.294608)
			(xy 126.924054 -270.288512) (xy 126.91872 -270.276574) (xy 126.916747 -270.272369) (xy 126.911509 -270.264699)
			(xy 126.908306 -270.261334) (xy 126.906782 -270.25981) (xy 126.888785 -270.24237) (xy 126.858169 -270.202698)
			(xy 126.834442 -270.158559) (xy 126.818241 -270.111138) (xy 126.810001 -270.061708) (xy 126.809943 -270.011596)
			(xy 126.818069 -269.962147) (xy 126.834161 -269.914688) (xy 126.857785 -269.870495) (xy 126.88831 -269.830752)
			(xy 126.906274 -269.813278) (xy 126.90729 -269.812262) (xy 126.91491 -269.804642) (xy 126.924054 -269.784068)
			(xy 126.926848 -269.777972) (xy 126.928962 -269.773025) (xy 126.931278 -269.762521) (xy 126.93142 -269.757144)
			(xy 126.93142 -268.694662) (xy 126.931308 -268.69058) (xy 126.929911 -268.682536) (xy 126.928626 -268.67866)
			(xy 126.925578 -268.671548) (xy 126.918466 -268.66088) (xy 126.913132 -268.6558) (xy 126.892622 -268.637782)
			(xy 126.857569 -268.595936) (xy 126.83031 -268.548642) (xy 126.811671 -268.497335) (xy 126.802219 -268.443572)
			(xy 126.801626 -268.416278) (xy 126.801626 -268.41577) (xy 126.802089 -268.392229) (xy 126.809212 -268.345686)
			(xy 126.823217 -268.300733) (xy 126.833122 -268.279372) (xy 126.835916 -268.27353) (xy 126.838435 -268.266715)
			(xy 126.839987 -268.252275) (xy 126.838964 -268.245082) (xy 126.838456 -268.242796) (xy 125.879352 -267.283692)
			(xy 125.876498 -267.28099) (xy 125.870115 -267.276406) (xy 125.866652 -267.274548) (xy 125.861226 -267.271963)
			(xy 125.849546 -267.269138) (xy 125.843538 -267.26896) (xy 125.096524 -267.26896) (xy 125.085501 -267.269234)
			(xy 125.063969 -267.273973) (xy 125.053852 -267.278358) (xy 125.051312 -267.279628) (xy 125.038866 -267.286994)
			(xy 125.038358 -267.287502) (xy 125.032516 -267.29182) (xy 125.03023 -267.293852) (xy 125.028452 -267.295376)
			(xy 125.017908 -267.305507) (xy 125.00262 -267.33042) (xy 124.995034 -267.358648) (xy 124.995776 -267.387868)
			(xy 125.004783 -267.415675) (xy 125.012704 -267.427964) (xy 125.016768 -267.433806) (xy 125.029363 -267.452958)
			(xy 125.049288 -267.494238) (xy 125.062827 -267.53803) (xy 125.069675 -267.583353) (xy 125.070108 -267.606272)
			(xy 125.069586 -267.631527) (xy 125.061273 -267.681349) (xy 125.044872 -267.729123) (xy 125.020831 -267.773546)
			(xy 124.989807 -267.813406) (xy 124.952645 -267.847616) (xy 124.910359 -267.875242) (xy 124.864103 -267.895532)
			(xy 124.815138 -267.907932) (xy 124.7648 -267.912103) (xy 124.714462 -267.907932) (xy 124.665497 -267.895532)
			(xy 124.619241 -267.875242) (xy 124.576955 -267.847616) (xy 124.539793 -267.813406) (xy 124.508769 -267.773546)
			(xy 124.484728 -267.729123) (xy 124.468327 -267.681349) (xy 124.460014 -267.631527) (xy 124.459492 -267.606272)
			(xy 124.459492 -267.606018) (xy 124.460004 -267.580914) (xy 124.46821 -267.531381) (xy 124.48439 -267.483852)
			(xy 124.495814 -267.461492) (xy 124.496322 -267.460984) (xy 124.507244 -267.439648) (xy 124.516906 -267.4285)
			(xy 124.529945 -267.402052) (xy 124.534882 -267.37298) (xy 124.531305 -267.34371) (xy 124.519514 -267.316683)
			(xy 124.50049 -267.294152) (xy 124.475822 -267.277996) (xy 124.447566 -267.269564) (xy 124.432822 -267.26896)
			(xy 123.815602 -267.26896) (xy 123.805533 -267.268536) (xy 123.786931 -267.260818) (xy 123.779534 -267.253974)
			(xy 123.584716 -267.059156) (xy 123.57354 -267.050774) (xy 123.567876 -267.047835) (xy 123.555534 -267.044614)
			(xy 123.549156 -267.044424) (xy 123.52147 -267.052552) (xy 123.515628 -267.056108) (xy 123.491271 -267.070411)
			(xy 123.438602 -267.090796) (xy 123.383084 -267.10116) (xy 123.354846 -267.101828) (xy 123.330831 -267.101385)
			(xy 123.283393 -267.093877) (xy 123.237713 -267.07904) (xy 123.194918 -267.057239) (xy 123.15606 -267.02901)
			(xy 123.122098 -266.995049) (xy 123.093868 -266.956193) (xy 123.072064 -266.913398) (xy 123.057225 -266.867719)
			(xy 123.049716 -266.82028) (xy 123.049284 -266.796266) (xy 123.049799 -266.77103) (xy 123.058089 -266.721243)
			(xy 123.065794 -266.697206) (xy 123.069814 -266.683998) (xy 123.071402 -266.656446) (xy 123.065554 -266.629475)
			(xy 123.052697 -266.605055) (xy 123.03377 -266.58497) (xy 123.010156 -266.570687) (xy 122.98358 -266.563249)
			(xy 122.969782 -266.56284) (xy 121.816622 -266.56284) (xy 121.810613 -266.56301) (xy 121.798932 -266.565836)
			(xy 121.793508 -266.568428) (xy 121.790033 -266.570267) (xy 121.783654 -266.57486) (xy 121.780808 -266.577572)
			(xy 121.75744 -266.60094) (xy 121.751986 -266.606788) (xy 121.744732 -266.621029) (xy 121.743216 -266.62888)
			(xy 121.741946 -266.6365) (xy 121.744232 -266.651994) (xy 121.748042 -266.659614) (xy 121.758218 -266.680941)
			(xy 121.772599 -266.725952) (xy 121.779879 -266.77264) (xy 121.7803 -266.796266) (xy 121.779832 -266.82028)
			(xy 121.772324 -266.867718) (xy 121.757488 -266.913396) (xy 121.735688 -266.956192) (xy 121.707463 -266.995051)
			(xy 121.673506 -267.029016) (xy 121.634654 -267.057251) (xy 121.591863 -267.07906) (xy 121.546188 -267.093907)
			(xy 121.498752 -267.101426) (xy 121.474738 -267.101828) (xy 121.451112 -267.10139) (xy 121.404422 -267.094124)
			(xy 121.359407 -267.079758) (xy 121.338086 -267.06957) (xy 121.337832 -267.06957) (xy 121.337578 -267.069316)
			(xy 121.330409 -267.066114) (xy 121.31489 -267.063778) (xy 121.307098 -267.064744) (xy 121.299478 -267.066014)
			(xy 121.29262 -267.069316) (xy 121.289004 -267.071268) (xy 121.28237 -267.076116) (xy 121.279412 -267.078968)
			(xy 121.161048 -267.197332) (xy 121.150858 -267.208259) (xy 121.136744 -267.234578) (xy 121.130841 -267.263854)
			(xy 121.133653 -267.293586) (xy 121.14494 -267.321235) (xy 121.163738 -267.344442) (xy 121.17578 -267.353288)
			(xy 121.196106 -267.367612) (xy 121.23225 -267.401759) (xy 121.262381 -267.441313) (xy 121.285702 -267.485228)
			(xy 121.301597 -267.532343) (xy 121.309645 -267.58141) (xy 121.310146 -267.606272) (xy 122.578888 -267.606272)
			(xy 122.582848 -267.557218) (xy 122.594625 -267.509434) (xy 122.613916 -267.464158) (xy 122.640219 -267.422562)
			(xy 122.672854 -267.385725) (xy 122.710975 -267.3546) (xy 122.753596 -267.329993) (xy 122.799612 -267.312541)
			(xy 122.847831 -267.302697) (xy 122.897006 -267.300716) (xy 122.945861 -267.306648) (xy 122.993132 -267.32034)
			(xy 123.037594 -267.341438) (xy 123.078097 -267.369394) (xy 123.11359 -267.403486) (xy 123.143155 -267.44283)
			(xy 123.166026 -267.486407) (xy 123.18161 -267.533088) (xy 123.189505 -267.581665) (xy 123.19 -267.606272)
			(xy 123.189505 -267.630879) (xy 123.18161 -267.679456) (xy 123.166026 -267.726137) (xy 123.143155 -267.769714)
			(xy 123.11359 -267.809058) (xy 123.078097 -267.84315) (xy 123.037594 -267.871106) (xy 122.993132 -267.892204)
			(xy 122.945861 -267.905896) (xy 122.897006 -267.911828) (xy 122.847831 -267.909847) (xy 122.799612 -267.900003)
			(xy 122.753596 -267.882551) (xy 122.710975 -267.857944) (xy 122.672854 -267.826819) (xy 122.640219 -267.789982)
			(xy 122.613916 -267.748386) (xy 122.594625 -267.70311) (xy 122.582848 -267.655326) (xy 122.578888 -267.606272)
			(xy 121.310146 -267.606272) (xy 121.309624 -267.631527) (xy 121.301311 -267.681349) (xy 121.28491 -267.729123)
			(xy 121.260869 -267.773546) (xy 121.229845 -267.813406) (xy 121.192683 -267.847616) (xy 121.150397 -267.875242)
			(xy 121.104141 -267.895532) (xy 121.055176 -267.907932) (xy 121.004838 -267.912103) (xy 120.9545 -267.907932)
			(xy 120.905535 -267.895532) (xy 120.859279 -267.875242) (xy 120.816993 -267.847616) (xy 120.779831 -267.813406)
			(xy 120.748807 -267.773546) (xy 120.724766 -267.729123) (xy 120.708365 -267.681349) (xy 120.700052 -267.631527)
			(xy 120.69953 -267.606272) (xy 120.699971 -267.582692) (xy 120.707225 -267.536093) (xy 120.721558 -267.491163)
			(xy 120.742627 -267.448971) (xy 120.755918 -267.429488) (xy 120.763631 -267.4179) (xy 120.773037 -267.391711)
			(xy 120.775026 -267.363955) (xy 120.76945 -267.336692) (xy 120.756723 -267.311946) (xy 120.73779 -267.291554)
			(xy 120.714055 -267.277028) (xy 120.68728 -267.269447) (xy 120.673368 -267.26896) (xy 120.046242 -267.26896)
			(xy 120.036177 -267.268525) (xy 120.017592 -267.260791) (xy 120.010174 -267.253974) (xy 119.818912 -267.062712)
			(xy 119.812308 -267.057124) (xy 119.807018 -267.053657) (xy 119.795196 -267.049174) (xy 119.78894 -267.048234)
			(xy 119.780304 -267.047218) (xy 119.76354 -267.051028) (xy 119.756174 -267.0556) (xy 119.731748 -267.07009)
			(xy 119.678836 -267.090709) (xy 119.623024 -267.101193) (xy 119.59463 -267.101828) (xy 119.570616 -267.101384)
			(xy 119.52318 -267.093874) (xy 119.477502 -267.079036) (xy 119.434709 -267.057233) (xy 119.395854 -267.029004)
			(xy 119.361893 -266.995043) (xy 119.333665 -266.956188) (xy 119.311863 -266.913394) (xy 119.297025 -266.867716)
			(xy 119.289516 -266.82028) (xy 119.289068 -266.796266) (xy 119.289068 -266.796012) (xy 119.28952 -266.772851)
			(xy 119.296539 -266.727062) (xy 119.303038 -266.704826) (xy 119.30667 -266.691713) (xy 119.307617 -266.664529)
			(xy 119.301353 -266.638059) (xy 119.288323 -266.614183) (xy 119.269453 -266.594593) (xy 119.24608 -266.58068)
			(xy 119.219863 -266.573431) (xy 119.206264 -266.573) (xy 118.258082 -266.573) (xy 118.252071 -266.573164)
			(xy 118.240386 -266.575981) (xy 118.234968 -266.578588) (xy 118.231494 -266.580428) (xy 118.225116 -266.585022)
			(xy 118.222268 -266.587732) (xy 118.034816 -266.775184) (xy 118.03191 -266.77831) (xy 118.027059 -266.78533)
			(xy 118.025164 -266.789154) (xy 118.020592 -266.799568) (xy 118.020084 -266.808966) (xy 118.020084 -266.80922)
			(xy 118.018498 -266.834418) (xy 118.008101 -266.883822) (xy 117.989724 -266.930844) (xy 117.963868 -266.974206)
			(xy 117.931235 -267.012728) (xy 117.892715 -267.045362) (xy 117.849354 -267.07122) (xy 117.802332 -267.089598)
			(xy 117.752929 -267.099997) (xy 117.72773 -267.101574) (xy 117.727476 -267.101574) (xy 117.718078 -267.102082)
			(xy 117.707664 -267.106654) (xy 117.703827 -267.108526) (xy 117.696806 -267.113383) (xy 117.693694 -267.116306)
			(xy 117.556026 -267.253974) (xy 117.548625 -267.260812) (xy 117.530026 -267.268523) (xy 117.519958 -267.26896)
			(xy 117.49278 -267.26896) (xy 117.487556 -267.269035) (xy 117.477313 -267.271088) (xy 117.47246 -267.273024)
			(xy 117.463647 -267.277327) (xy 117.449917 -267.291306) (xy 117.44579 -267.300202) (xy 117.445282 -267.301726)
			(xy 117.43563 -267.33119) (xy 117.433839 -267.339813) (xy 117.435573 -267.357325) (xy 117.443134 -267.373216)
			(xy 117.449092 -267.379704) (xy 117.450616 -267.380974) (xy 117.468994 -267.398456) (xy 117.500258 -267.438394)
			(xy 117.524496 -267.482948) (xy 117.541042 -267.530893) (xy 117.54944 -267.580912) (xy 117.54993 -267.606272)
			(xy 118.818926 -267.606272) (xy 118.822886 -267.557218) (xy 118.834663 -267.509434) (xy 118.853954 -267.464158)
			(xy 118.880257 -267.422562) (xy 118.912892 -267.385725) (xy 118.951013 -267.3546) (xy 118.993634 -267.329993)
			(xy 119.03965 -267.312541) (xy 119.087869 -267.302697) (xy 119.137044 -267.300716) (xy 119.185899 -267.306648)
			(xy 119.23317 -267.32034) (xy 119.277632 -267.341438) (xy 119.318135 -267.369394) (xy 119.353628 -267.403486)
			(xy 119.383193 -267.44283) (xy 119.406064 -267.486407) (xy 119.421648 -267.533088) (xy 119.429543 -267.581665)
			(xy 119.430038 -267.606272) (xy 119.429543 -267.630879) (xy 119.421648 -267.679456) (xy 119.406064 -267.726137)
			(xy 119.383193 -267.769714) (xy 119.353628 -267.809058) (xy 119.318135 -267.84315) (xy 119.277632 -267.871106)
			(xy 119.23317 -267.892204) (xy 119.185899 -267.905896) (xy 119.137044 -267.911828) (xy 119.087869 -267.909847)
			(xy 119.03965 -267.900003) (xy 118.993634 -267.882551) (xy 118.951013 -267.857944) (xy 118.912892 -267.826819)
			(xy 118.880257 -267.789982) (xy 118.853954 -267.748386) (xy 118.834663 -267.70311) (xy 118.822886 -267.655326)
			(xy 118.818926 -267.606272) (xy 117.54993 -267.606272) (xy 117.549408 -267.631527) (xy 117.541095 -267.681349)
			(xy 117.524694 -267.729123) (xy 117.500653 -267.773546) (xy 117.469629 -267.813406) (xy 117.432467 -267.847616)
			(xy 117.390181 -267.875242) (xy 117.343925 -267.895532) (xy 117.29496 -267.907932) (xy 117.244622 -267.912103)
			(xy 117.194284 -267.907932) (xy 117.145319 -267.895532) (xy 117.099063 -267.875242) (xy 117.056777 -267.847616)
			(xy 117.019615 -267.813406) (xy 116.988591 -267.773546) (xy 116.96455 -267.729123) (xy 116.948149 -267.681349)
			(xy 116.939836 -267.631527) (xy 116.939314 -267.606272) (xy 116.939755 -267.582692) (xy 116.947011 -267.536094)
			(xy 116.961347 -267.491166) (xy 116.982421 -267.448978) (xy 116.995702 -267.429488) (xy 117.003416 -267.417901)
			(xy 117.012823 -267.391713) (xy 117.014813 -267.363957) (xy 117.009237 -267.336695) (xy 116.99651 -267.31195)
			(xy 116.977575 -267.291558) (xy 116.953839 -267.277035) (xy 116.927064 -267.269458) (xy 116.913152 -267.26896)
			(xy 116.256562 -267.26896) (xy 116.246496 -267.268529) (xy 116.227905 -267.2608) (xy 116.220494 -267.253974)
			(xy 116.0399 -267.07338) (xy 116.034312 -267.068554) (xy 116.029177 -267.064985) (xy 116.017612 -267.060235)
			(xy 116.011452 -267.059156) (xy 116.003832 -267.05814) (xy 115.98783 -267.060934) (xy 115.98021 -267.064998)
			(xy 115.957769 -267.076594) (xy 115.909999 -267.093007) (xy 115.860177 -267.101321) (xy 115.834922 -267.101828)
			(xy 115.834668 -267.101828) (xy 115.810658 -267.101379) (xy 115.763228 -267.093862) (xy 115.717559 -267.079018)
			(xy 115.674774 -267.057212) (xy 115.635928 -267.028982) (xy 115.601975 -266.995022) (xy 115.573753 -266.956169)
			(xy 115.551957 -266.91338) (xy 115.537123 -266.867707) (xy 115.529616 -266.820277) (xy 115.529106 -266.796266)
			(xy 115.529106 -266.796012) (xy 115.529479 -266.774377) (xy 115.535597 -266.731542) (xy 115.541298 -266.710668)
			(xy 115.544677 -266.697608) (xy 115.54519 -266.670646) (xy 115.538624 -266.644491) (xy 115.525435 -266.620969)
			(xy 115.506545 -266.601723) (xy 115.483274 -266.588097) (xy 115.457246 -266.581043) (xy 115.443762 -266.58062)
			(xy 114.34572 -266.58062) (xy 114.332237 -266.581034) (xy 114.30621 -266.588092) (xy 114.28294 -266.60172)
			(xy 114.264053 -266.620967) (xy 114.250865 -266.64449) (xy 114.244299 -266.670645) (xy 114.244812 -266.697606)
			(xy 114.248184 -266.710668) (xy 114.253862 -266.731546) (xy 114.259975 -266.774379) (xy 114.260376 -266.796012)
			(xy 114.260376 -266.796266) (xy 114.259854 -266.821542) (xy 114.251533 -266.871406) (xy 114.235119 -266.919219)
			(xy 114.211059 -266.963679) (xy 114.180008 -267.003572) (xy 114.142816 -267.03781) (xy 114.100495 -267.06546)
			(xy 114.0542 -267.085767) (xy 114.005194 -267.098177) (xy 113.954814 -267.102352) (xy 113.904434 -267.098177)
			(xy 113.855428 -267.085767) (xy 113.809133 -267.06546) (xy 113.766812 -267.03781) (xy 113.72962 -267.003572)
			(xy 113.698569 -266.963679) (xy 113.674509 -266.919219) (xy 113.658095 -266.871406) (xy 113.649774 -266.821542)
			(xy 113.649252 -266.796266) (xy 113.649252 -266.796012) (xy 113.649625 -266.774377) (xy 113.655744 -266.731542)
			(xy 113.661444 -266.710668) (xy 113.664822 -266.697606) (xy 113.665334 -266.670641) (xy 113.658768 -266.644482)
			(xy 113.64558 -266.620956) (xy 113.626692 -266.601704) (xy 113.603422 -266.588069) (xy 113.577393 -266.581005)
			(xy 113.563908 -266.58062) (xy 111.689642 -266.58062) (xy 111.683633 -266.580788) (xy 111.671952 -266.583615)
			(xy 111.666528 -266.586208) (xy 111.663052 -266.588045) (xy 111.65667 -266.592635) (xy 111.653828 -266.595352)
			(xy 110.995206 -267.253974) (xy 110.987809 -267.260824) (xy 110.969211 -267.268565) (xy 110.959138 -267.26896)
			(xy 110.062518 -267.26896) (xy 110.048604 -267.269428) (xy 110.021828 -267.277013) (xy 109.998092 -267.291542)
			(xy 109.979158 -267.311938) (xy 109.96643 -267.336687) (xy 109.960854 -267.363952) (xy 109.962842 -267.391711)
			(xy 109.972248 -267.417903) (xy 109.979968 -267.429488) (xy 109.993268 -267.448966) (xy 110.014346 -267.491157)
			(xy 110.028684 -267.536089) (xy 110.035942 -267.58269) (xy 110.036356 -267.606272) (xy 113.178856 -267.606272)
			(xy 113.182816 -267.557218) (xy 113.194593 -267.509434) (xy 113.213884 -267.464158) (xy 113.240187 -267.422562)
			(xy 113.272822 -267.385725) (xy 113.310943 -267.3546) (xy 113.353564 -267.329993) (xy 113.39958 -267.312541)
			(xy 113.447799 -267.302697) (xy 113.496974 -267.300716) (xy 113.545829 -267.306648) (xy 113.5931 -267.32034)
			(xy 113.637562 -267.341438) (xy 113.678065 -267.369394) (xy 113.713558 -267.403486) (xy 113.743123 -267.44283)
			(xy 113.765994 -267.486407) (xy 113.781578 -267.533088) (xy 113.789473 -267.581665) (xy 113.789968 -267.606272)
			(xy 115.058964 -267.606272) (xy 115.062924 -267.557218) (xy 115.074701 -267.509434) (xy 115.093992 -267.464158)
			(xy 115.120295 -267.422562) (xy 115.15293 -267.385725) (xy 115.191051 -267.3546) (xy 115.233672 -267.329993)
			(xy 115.279688 -267.312541) (xy 115.327907 -267.302697) (xy 115.377082 -267.300716) (xy 115.425937 -267.306648)
			(xy 115.473208 -267.32034) (xy 115.51767 -267.341438) (xy 115.558173 -267.369394) (xy 115.593666 -267.403486)
			(xy 115.623231 -267.44283) (xy 115.646102 -267.486407) (xy 115.661686 -267.533088) (xy 115.669581 -267.581665)
			(xy 115.670076 -267.606272) (xy 115.669581 -267.630879) (xy 115.661686 -267.679456) (xy 115.646102 -267.726137)
			(xy 115.623231 -267.769714) (xy 115.593666 -267.809058) (xy 115.558173 -267.84315) (xy 115.51767 -267.871106)
			(xy 115.473208 -267.892204) (xy 115.425937 -267.905896) (xy 115.377082 -267.911828) (xy 115.327907 -267.909847)
			(xy 115.279688 -267.900003) (xy 115.233672 -267.882551) (xy 115.191051 -267.857944) (xy 115.15293 -267.826819)
			(xy 115.120295 -267.789982) (xy 115.093992 -267.748386) (xy 115.074701 -267.70311) (xy 115.062924 -267.655326)
			(xy 115.058964 -267.606272) (xy 113.789968 -267.606272) (xy 113.789473 -267.630879) (xy 113.781578 -267.679456)
			(xy 113.765994 -267.726137) (xy 113.743123 -267.769714) (xy 113.713558 -267.809058) (xy 113.678065 -267.84315)
			(xy 113.637562 -267.871106) (xy 113.5931 -267.892204) (xy 113.545829 -267.905896) (xy 113.496974 -267.911828)
			(xy 113.447799 -267.909847) (xy 113.39958 -267.900003) (xy 113.353564 -267.882551) (xy 113.310943 -267.857944)
			(xy 113.272822 -267.826819) (xy 113.240187 -267.789982) (xy 113.213884 -267.748386) (xy 113.194593 -267.70311)
			(xy 113.182816 -267.655326) (xy 113.178856 -267.606272) (xy 110.036356 -267.606272) (xy 110.035834 -267.631527)
			(xy 110.027521 -267.681349) (xy 110.01112 -267.729123) (xy 109.987079 -267.773546) (xy 109.956055 -267.813406)
			(xy 109.918893 -267.847616) (xy 109.876607 -267.875242) (xy 109.830351 -267.895532) (xy 109.781386 -267.907932)
			(xy 109.731048 -267.912103) (xy 109.68071 -267.907932) (xy 109.631745 -267.895532) (xy 109.585489 -267.875242)
			(xy 109.543203 -267.847616) (xy 109.506041 -267.813406) (xy 109.475017 -267.773546) (xy 109.450976 -267.729123)
			(xy 109.434575 -267.681349) (xy 109.426262 -267.631527) (xy 109.42574 -267.606272) (xy 109.426276 -267.580152)
			(xy 109.435169 -267.528674) (xy 109.452689 -267.479459) (xy 109.478328 -267.433942) (xy 109.511336 -267.393451)
			(xy 109.550751 -267.359166) (xy 109.572806 -267.34516) (xy 109.585679 -267.336741) (xy 109.606051 -267.313713)
			(xy 109.618662 -267.285673) (xy 109.622374 -267.255152) (xy 109.616851 -267.224906) (xy 109.602593 -267.197667)
			(xy 109.59211 -267.18641) (xy 109.474762 -267.069062) (xy 109.468693 -267.063353) (xy 109.453771 -267.055956)
			(xy 109.445552 -267.054584) (xy 109.43717 -267.053568) (xy 109.421168 -267.056616) (xy 109.413548 -267.060934)
			(xy 109.390208 -267.073745) (xy 109.340188 -267.09197) (xy 109.287766 -267.101245) (xy 109.261148 -267.101828)
			(xy 109.237133 -267.101385) (xy 109.189695 -267.093878) (xy 109.144015 -267.079041) (xy 109.101219 -267.057239)
			(xy 109.062361 -267.02901) (xy 109.028399 -266.99505) (xy 109.000168 -266.956193) (xy 108.978365 -266.913398)
			(xy 108.963525 -266.867719) (xy 108.956016 -266.820281) (xy 108.955586 -266.796266) (xy 108.955851 -266.778055)
			(xy 108.960184 -266.74189) (xy 108.964222 -266.72413) (xy 108.967359 -266.709093) (xy 108.965465 -266.678447)
			(xy 108.954551 -266.649749) (xy 108.935603 -266.625589) (xy 108.910332 -266.60815) (xy 108.881022 -266.599007)
			(xy 108.86567 -266.5984) (xy 107.960922 -266.5984) (xy 107.954913 -266.598571) (xy 107.943234 -266.6014)
			(xy 107.937808 -266.603988) (xy 107.934333 -266.605826) (xy 107.92795 -266.610416) (xy 107.925108 -266.613132)
			(xy 107.690666 -266.847574) (xy 107.682792 -266.857734) (xy 107.68203 -266.859004) (xy 107.678982 -266.864592)
			(xy 107.677204 -266.871196) (xy 107.677204 -266.87145) (xy 107.671024 -266.894072) (xy 107.652684 -266.93723)
			(xy 107.627965 -266.97708) (xy 107.59745 -267.012686) (xy 107.561853 -267.043212) (xy 107.52201 -267.067942)
			(xy 107.478857 -267.086295) (xy 107.456224 -267.09243) (xy 107.45597 -267.09243) (xy 107.449366 -267.094208)
			(xy 107.443778 -267.097256) (xy 107.442508 -267.098018) (xy 107.432348 -267.105892) (xy 107.284266 -267.253974)
			(xy 107.276867 -267.260818) (xy 107.258269 -267.268544) (xy 107.248198 -267.26896) (xy 106.302556 -267.26896)
			(xy 106.288638 -267.269423) (xy 106.261853 -267.277002) (xy 106.238107 -267.29153) (xy 106.219165 -267.311929)
			(xy 106.206432 -267.336683) (xy 106.200853 -267.363956) (xy 106.202844 -267.391722) (xy 106.212257 -267.41792)
			(xy 106.220006 -267.429488) (xy 106.233305 -267.448967) (xy 106.25438 -267.491159) (xy 106.268717 -267.53609)
			(xy 106.275973 -267.582691) (xy 106.276394 -267.606272) (xy 107.545136 -267.606272) (xy 107.549096 -267.557218)
			(xy 107.560873 -267.509434) (xy 107.580164 -267.464158) (xy 107.606467 -267.422562) (xy 107.639102 -267.385725)
			(xy 107.677223 -267.3546) (xy 107.719844 -267.329993) (xy 107.76586 -267.312541) (xy 107.814079 -267.302697)
			(xy 107.863254 -267.300716) (xy 107.912109 -267.306648) (xy 107.95938 -267.32034) (xy 108.003842 -267.341438)
			(xy 108.044345 -267.369394) (xy 108.079838 -267.403486) (xy 108.109403 -267.44283) (xy 108.132274 -267.486407)
			(xy 108.147858 -267.533088) (xy 108.155753 -267.581665) (xy 108.156248 -267.606272) (xy 108.155753 -267.630879)
			(xy 108.147858 -267.679456) (xy 108.132274 -267.726137) (xy 108.109403 -267.769714) (xy 108.079838 -267.809058)
			(xy 108.044345 -267.84315) (xy 108.003842 -267.871106) (xy 107.95938 -267.892204) (xy 107.912109 -267.905896)
			(xy 107.863254 -267.911828) (xy 107.814079 -267.909847) (xy 107.76586 -267.900003) (xy 107.719844 -267.882551)
			(xy 107.677223 -267.857944) (xy 107.639102 -267.826819) (xy 107.606467 -267.789982) (xy 107.580164 -267.748386)
			(xy 107.560873 -267.70311) (xy 107.549096 -267.655326) (xy 107.545136 -267.606272) (xy 106.276394 -267.606272)
			(xy 106.275872 -267.631527) (xy 106.267559 -267.681349) (xy 106.251158 -267.729123) (xy 106.227117 -267.773546)
			(xy 106.196093 -267.813406) (xy 106.158931 -267.847616) (xy 106.116645 -267.875242) (xy 106.070389 -267.895532)
			(xy 106.021424 -267.907932) (xy 105.971086 -267.912103) (xy 105.920748 -267.907932) (xy 105.871783 -267.895532)
			(xy 105.825527 -267.875242) (xy 105.783241 -267.847616) (xy 105.746079 -267.813406) (xy 105.715055 -267.773546)
			(xy 105.691014 -267.729123) (xy 105.674613 -267.681349) (xy 105.6663 -267.631527) (xy 105.665778 -267.606272)
			(xy 105.666212 -267.583081) (xy 105.673234 -267.537234) (xy 105.687111 -267.492978) (xy 105.707525 -267.45133)
			(xy 105.720388 -267.432028) (xy 105.726979 -267.422742) (xy 105.741345 -267.40507) (xy 105.74909 -267.396722)
			(xy 105.765951 -267.379488) (xy 105.804107 -267.350018) (xy 105.825036 -267.338048) (xy 105.826052 -267.33754)
			(xy 105.826814 -267.337032) (xy 105.839878 -267.32873) (xy 105.860639 -267.305791) (xy 105.873568 -267.277683)
			(xy 105.877477 -267.246992) (xy 105.872004 -267.216541) (xy 105.857655 -267.189131) (xy 105.847134 -267.177774)
			(xy 105.729024 -267.059664) (xy 105.727754 -267.058394) (xy 105.726484 -267.057378) (xy 105.716832 -267.050774)
			(xy 105.69866 -267.065664) (xy 105.658925 -267.090729) (xy 105.616069 -267.109976) (xy 105.570937 -267.123025)
			(xy 105.524422 -267.129616) (xy 105.500932 -267.130022) (xy 105.474703 -267.129537) (xy 105.422889 -267.121334)
			(xy 105.372997 -267.105127) (xy 105.326255 -267.081312) (xy 105.283814 -267.050479) (xy 105.24672 -267.013384)
			(xy 105.215887 -266.970944) (xy 105.192073 -266.924201) (xy 105.175865 -266.874309) (xy 105.167663 -266.822495)
			(xy 105.167176 -266.796266) (xy 105.167551 -266.774451) (xy 105.17327 -266.731196) (xy 105.184567 -266.689054)
			(xy 105.192576 -266.668758) (xy 105.195977 -266.659393) (xy 105.196072 -266.63949) (xy 105.188558 -266.62106)
			(xy 105.181908 -266.61364) (xy 105.172195 -266.604301) (xy 105.148974 -266.590654) (xy 105.122985 -266.58358)
			(xy 105.109518 -266.58316) (xy 104.138222 -266.58316) (xy 104.132213 -266.58333) (xy 104.120533 -266.586158)
			(xy 104.115108 -266.588748) (xy 104.111634 -266.590588) (xy 104.105256 -266.595182) (xy 104.102408 -266.597892)
			(xy 103.941372 -266.758928) (xy 103.938273 -266.762192) (xy 103.933171 -266.769607) (xy 103.931212 -266.77366)
			(xy 103.92664 -266.784582) (xy 103.92664 -266.794996) (xy 103.92664 -266.796012) (xy 103.92664 -266.796266)
			(xy 103.926196 -266.82028) (xy 103.918687 -266.867718) (xy 103.903849 -266.913397) (xy 103.882047 -266.956192)
			(xy 103.853818 -266.995048) (xy 103.819858 -267.02901) (xy 103.781002 -267.057241) (xy 103.738208 -267.079044)
			(xy 103.69253 -267.093884) (xy 103.645092 -267.101395) (xy 103.621078 -267.101828) (xy 103.620824 -267.101828)
			(xy 103.619808 -267.101828) (xy 103.619554 -267.101828) (xy 103.600504 -267.105638) (xy 103.60025 -267.105638)
			(xy 103.595686 -267.107645) (xy 103.587371 -267.113144) (xy 103.58374 -267.11656) (xy 103.446326 -267.253974)
			(xy 103.438925 -267.260812) (xy 103.420326 -267.268523) (xy 103.410258 -267.26896) (xy 102.542594 -267.26896)
			(xy 102.528683 -267.269431) (xy 102.501912 -267.27702) (xy 102.478182 -267.29155) (xy 102.459253 -267.311944)
			(xy 102.446529 -267.33669) (xy 102.440954 -267.36395) (xy 102.442941 -267.391705) (xy 102.452343 -267.417893)
			(xy 102.460044 -267.429488) (xy 102.473341 -267.448967) (xy 102.494414 -267.49116) (xy 102.508749 -267.53609)
			(xy 102.516004 -267.582691) (xy 102.516432 -267.606272) (xy 103.785174 -267.606272) (xy 103.789134 -267.557218)
			(xy 103.800911 -267.509434) (xy 103.820202 -267.464158) (xy 103.846505 -267.422562) (xy 103.87914 -267.385725)
			(xy 103.917261 -267.3546) (xy 103.959882 -267.329993) (xy 104.005898 -267.312541) (xy 104.054117 -267.302697)
			(xy 104.103292 -267.300716) (xy 104.152147 -267.306648) (xy 104.199418 -267.32034) (xy 104.24388 -267.341438)
			(xy 104.284383 -267.369394) (xy 104.319876 -267.403486) (xy 104.349441 -267.44283) (xy 104.372312 -267.486407)
			(xy 104.387896 -267.533088) (xy 104.395791 -267.581665) (xy 104.396286 -267.606272) (xy 104.395791 -267.630879)
			(xy 104.387896 -267.679456) (xy 104.372312 -267.726137) (xy 104.349441 -267.769714) (xy 104.319876 -267.809058)
			(xy 104.284383 -267.84315) (xy 104.24388 -267.871106) (xy 104.199418 -267.892204) (xy 104.152147 -267.905896)
			(xy 104.103292 -267.911828) (xy 104.054117 -267.909847) (xy 104.005898 -267.900003) (xy 103.959882 -267.882551)
			(xy 103.917261 -267.857944) (xy 103.87914 -267.826819) (xy 103.846505 -267.789982) (xy 103.820202 -267.748386)
			(xy 103.800911 -267.70311) (xy 103.789134 -267.655326) (xy 103.785174 -267.606272) (xy 102.516432 -267.606272)
			(xy 102.51591 -267.631527) (xy 102.507597 -267.681349) (xy 102.491196 -267.729123) (xy 102.467155 -267.773546)
			(xy 102.436131 -267.813406) (xy 102.398969 -267.847616) (xy 102.356683 -267.875242) (xy 102.310427 -267.895532)
			(xy 102.261462 -267.907932) (xy 102.211124 -267.912103) (xy 102.160786 -267.907932) (xy 102.111821 -267.895532)
			(xy 102.065565 -267.875242) (xy 102.023279 -267.847616) (xy 101.986117 -267.813406) (xy 101.955093 -267.773546)
			(xy 101.931052 -267.729123) (xy 101.914651 -267.681349) (xy 101.906338 -267.631527) (xy 101.905816 -267.606272)
			(xy 101.906257 -267.582692) (xy 101.913513 -267.536094) (xy 101.927849 -267.491167) (xy 101.948924 -267.448978)
			(xy 101.962204 -267.429488) (xy 101.969917 -267.417901) (xy 101.979325 -267.391712) (xy 101.981315 -267.363957)
			(xy 101.975739 -267.336695) (xy 101.963011 -267.311949) (xy 101.944077 -267.291558) (xy 101.920341 -267.277034)
			(xy 101.893566 -267.269456) (xy 101.879654 -267.26896) (xy 101.702362 -267.26896) (xy 101.692296 -267.268529)
			(xy 101.673705 -267.2608) (xy 101.666294 -267.253974) (xy 100.728272 -266.315952) (xy 100.724839 -266.312334)
			(xy 100.71934 -266.304015) (xy 100.71735 -266.299442) (xy 100.71354 -266.290298) (xy 100.71354 -266.280646)
			(xy 100.713079 -266.266102) (xy 100.704891 -266.238191) (xy 100.689165 -266.213722) (xy 100.667178 -266.194678)
			(xy 100.640714 -266.182607) (xy 100.61192 -266.178487) (xy 100.583133 -266.182652) (xy 100.556688 -266.194764)
			(xy 100.545392 -266.203938) (xy 100.54082 -266.208256) (xy 100.540566 -266.20851) (xy 100.520111 -266.226979)
			(xy 100.473884 -266.256974) (xy 100.423031 -266.278204) (xy 100.369198 -266.289981) (xy 100.341684 -266.291568)
			(xy 100.332286 -266.291822) (xy 100.314506 -266.299442) (xy 100.204016 -266.409932) (xy 100.196616 -266.416773)
			(xy 100.178017 -266.424487) (xy 100.167948 -266.424918) (xy 100.165662 -266.424918) (xy 100.155918 -266.425351)
			(xy 100.137845 -266.432642) (xy 100.123829 -266.44618) (xy 100.119434 -266.45489) (xy 100.081334 -266.539218)
			(xy 100.077717 -266.548311) (xy 100.076932 -266.567847) (xy 100.083519 -266.586256) (xy 100.089716 -266.593828)
			(xy 100.107609 -266.61496) (xy 100.136229 -266.662354) (xy 100.155854 -266.714126) (xy 100.165841 -266.768583)
			(xy 100.166424 -266.796266) (xy 100.165902 -266.821521) (xy 100.157589 -266.871343) (xy 100.141188 -266.919117)
			(xy 100.117147 -266.96354) (xy 100.086123 -267.0034) (xy 100.048961 -267.03761) (xy 100.006675 -267.065236)
			(xy 99.960419 -267.085526) (xy 99.911454 -267.097926) (xy 99.861116 -267.102097) (xy 99.810778 -267.097926)
			(xy 99.761813 -267.085526) (xy 99.715557 -267.065236) (xy 99.673271 -267.03761) (xy 99.636109 -267.0034)
			(xy 99.605085 -266.96354) (xy 99.581044 -266.919117) (xy 99.564643 -266.871343) (xy 99.55633 -266.821521)
			(xy 99.555808 -266.796266) (xy 99.556403 -266.768582) (xy 99.566367 -266.714118) (xy 99.585981 -266.66234)
			(xy 99.614603 -266.614943) (xy 99.632516 -266.593828) (xy 99.638688 -266.58624) (xy 99.645279 -266.567842)
			(xy 99.644493 -266.548316) (xy 99.640898 -266.539218) (xy 99.602798 -266.45489) (xy 99.598396 -266.446191)
			(xy 99.584358 -266.432685) (xy 99.566308 -266.425357) (xy 99.55657 -266.424918) (xy 99.225608 -266.424918)
			(xy 99.215859 -266.425343) (xy 99.197773 -266.432624) (xy 99.183742 -266.446161) (xy 99.17938 -266.45489)
			(xy 99.14128 -266.539218) (xy 99.137666 -266.548312) (xy 99.136881 -266.567848) (xy 99.143463 -266.586259)
			(xy 99.149662 -266.593828) (xy 99.167558 -266.614958) (xy 99.196183 -266.662352) (xy 99.215811 -266.714124)
			(xy 99.2258 -266.768582) (xy 99.22637 -266.796266) (xy 99.225848 -266.821521) (xy 99.217535 -266.871343)
			(xy 99.201134 -266.919117) (xy 99.177093 -266.96354) (xy 99.146069 -267.0034) (xy 99.108907 -267.03761)
			(xy 99.066621 -267.065236) (xy 99.020365 -267.085526) (xy 98.9714 -267.097926) (xy 98.921062 -267.102097)
			(xy 98.870724 -267.097926) (xy 98.821759 -267.085526) (xy 98.775503 -267.065236) (xy 98.733217 -267.03761)
			(xy 98.696055 -267.0034) (xy 98.665031 -266.96354) (xy 98.64099 -266.919117) (xy 98.624589 -266.871343)
			(xy 98.616276 -266.821521) (xy 98.615754 -266.796266) (xy 98.616348 -266.768581) (xy 98.626311 -266.714116)
			(xy 98.645922 -266.662336) (xy 98.67454 -266.614936) (xy 98.692462 -266.593828) (xy 98.698639 -266.586242)
			(xy 98.705238 -266.567843) (xy 98.70445 -266.548313) (xy 98.700844 -266.539218) (xy 98.662744 -266.45489)
			(xy 98.65834 -266.446196) (xy 98.644298 -266.432706) (xy 98.62625 -266.425396) (xy 98.616516 -266.424918)
			(xy 98.285554 -266.424918) (xy 98.275811 -266.425353) (xy 98.257741 -266.432645) (xy 98.243727 -266.446184)
			(xy 98.239326 -266.45489) (xy 98.201226 -266.539218) (xy 98.197609 -266.548311) (xy 98.196824 -266.567847)
			(xy 98.20341 -266.586257) (xy 98.209608 -266.593828) (xy 98.227501 -266.614959) (xy 98.256123 -266.662354)
			(xy 98.275747 -266.714125) (xy 98.285735 -266.768583) (xy 98.286316 -266.796266) (xy 98.285794 -266.821521)
			(xy 98.277481 -266.871343) (xy 98.26108 -266.919117) (xy 98.237039 -266.96354) (xy 98.206015 -267.0034)
			(xy 98.168853 -267.03761) (xy 98.126567 -267.065236) (xy 98.080311 -267.085526) (xy 98.031346 -267.097926)
			(xy 97.981008 -267.102097) (xy 97.93067 -267.097926) (xy 97.881705 -267.085526) (xy 97.835449 -267.065236)
			(xy 97.793163 -267.03761) (xy 97.756001 -267.0034) (xy 97.724977 -266.96354) (xy 97.700936 -266.919117)
			(xy 97.684535 -266.871343) (xy 97.676222 -266.821521) (xy 97.6757 -266.796266) (xy 97.676295 -266.768582)
			(xy 97.686259 -266.714117) (xy 97.705872 -266.662339) (xy 97.734494 -266.614942) (xy 97.752408 -266.593828)
			(xy 97.758581 -266.58624) (xy 97.765173 -266.567843) (xy 97.764387 -266.548316) (xy 97.76079 -266.539218)
			(xy 97.72269 -266.45489) (xy 97.718288 -266.446192) (xy 97.704249 -266.432688) (xy 97.686199 -266.425363)
			(xy 97.676462 -266.424918) (xy 97.3455 -266.424918) (xy 97.335752 -266.425345) (xy 97.317668 -266.432627)
			(xy 97.30364 -266.446165) (xy 97.299272 -266.45489) (xy 97.261172 -266.539218) (xy 97.257558 -266.548312)
			(xy 97.256774 -266.567848) (xy 97.263354 -266.586259) (xy 97.269554 -266.593828) (xy 97.28745 -266.614958)
			(xy 97.316076 -266.662351) (xy 97.335705 -266.714123) (xy 97.345694 -266.768582) (xy 97.346262 -266.796266)
			(xy 97.34574 -266.821521) (xy 97.337427 -266.871343) (xy 97.321026 -266.919117) (xy 97.296985 -266.96354)
			(xy 97.265961 -267.0034) (xy 97.228799 -267.03761) (xy 97.186513 -267.065236) (xy 97.140257 -267.085526)
			(xy 97.091292 -267.097926) (xy 97.040954 -267.102097) (xy 96.990616 -267.097926) (xy 96.941651 -267.085526)
			(xy 96.895395 -267.065236) (xy 96.853109 -267.03761) (xy 96.815947 -267.0034) (xy 96.784923 -266.96354)
			(xy 96.760882 -266.919117) (xy 96.744481 -266.871343) (xy 96.736168 -266.821521) (xy 96.735646 -266.796266)
			(xy 96.736241 -266.768582) (xy 96.746206 -266.714119) (xy 96.765822 -266.662342) (xy 96.794446 -266.614948)
			(xy 96.812354 -266.593828) (xy 96.818532 -266.586242) (xy 96.825132 -266.567843) (xy 96.824344 -266.548313)
			(xy 96.820736 -266.539218) (xy 96.782636 -266.45489) (xy 96.778231 -266.446197) (xy 96.764189 -266.432709)
			(xy 96.746142 -266.425402) (xy 96.736408 -266.424918) (xy 96.419416 -266.424918) (xy 96.409735 -266.425347)
			(xy 96.391742 -266.432503) (xy 96.377645 -266.445779) (xy 96.373188 -266.454382) (xy 96.33458 -266.537948)
			(xy 96.330889 -266.546878) (xy 96.329817 -266.566155) (xy 96.33598 -266.584451) (xy 96.341946 -266.59205)
			(xy 96.341946 -266.592304) (xy 96.359452 -266.613842) (xy 96.3874 -266.661788) (xy 96.406539 -266.713881)
			(xy 96.416279 -266.768518) (xy 96.416876 -266.796266) (xy 96.416389 -266.821076) (xy 96.408627 -266.870084)
			(xy 96.393294 -266.917274) (xy 96.370767 -266.961485) (xy 96.341602 -267.001628) (xy 96.306516 -267.036714)
			(xy 96.266373 -267.065879) (xy 96.222162 -267.088406) (xy 96.174972 -267.103739) (xy 96.125964 -267.111501)
			(xy 96.076344 -267.111501) (xy 96.027336 -267.103739) (xy 95.980146 -267.088406) (xy 95.935935 -267.065879)
			(xy 95.895792 -267.036714) (xy 95.860706 -267.001628) (xy 95.831541 -266.961485) (xy 95.809014 -266.917274)
			(xy 95.793681 -266.870084) (xy 95.785919 -266.821076) (xy 95.785432 -266.796266) (xy 95.786034 -266.768517)
			(xy 95.795771 -266.71388) (xy 95.814905 -266.661785) (xy 95.842847 -266.613834) (xy 95.860362 -266.592304)
			(xy 95.860362 -266.59205) (xy 95.86628 -266.584422) (xy 95.872436 -266.566138) (xy 95.871405 -266.546874)
			(xy 95.867728 -266.537948) (xy 95.82912 -266.454382) (xy 95.824679 -266.445761) (xy 95.810606 -266.432444)
			(xy 95.792582 -266.425332) (xy 95.782892 -266.424918) (xy 95.465646 -266.424918) (xy 95.455903 -266.425354)
			(xy 95.437836 -266.432648) (xy 95.423824 -266.446187) (xy 95.419418 -266.45489) (xy 95.381318 -266.539218)
			(xy 95.377701 -266.548311) (xy 95.376916 -266.567848) (xy 95.383502 -266.586257) (xy 95.3897 -266.593828)
			(xy 95.407594 -266.614959) (xy 95.436216 -266.662354) (xy 95.455841 -266.714125) (xy 95.465829 -266.768583)
			(xy 95.466408 -266.796266) (xy 95.465886 -266.821521) (xy 95.457573 -266.871343) (xy 95.441172 -266.919117)
			(xy 95.417131 -266.96354) (xy 95.386107 -267.0034) (xy 95.348945 -267.03761) (xy 95.306659 -267.065236)
			(xy 95.260403 -267.085526) (xy 95.211438 -267.097926) (xy 95.1611 -267.102097) (xy 95.110762 -267.097926)
			(xy 95.061797 -267.085526) (xy 95.015541 -267.065236) (xy 94.973255 -267.03761) (xy 94.936093 -267.0034)
			(xy 94.905069 -266.96354) (xy 94.881028 -266.919117) (xy 94.864627 -266.871343) (xy 94.856314 -266.821521)
			(xy 94.855792 -266.796266) (xy 94.856387 -266.768582) (xy 94.86635 -266.714117) (xy 94.885964 -266.662339)
			(xy 94.914584 -266.614941) (xy 94.9325 -266.593828) (xy 94.938673 -266.58624) (xy 94.945266 -266.567843)
			(xy 94.94448 -266.548315) (xy 94.940882 -266.539218) (xy 94.902782 -266.45489) (xy 94.898379 -266.446192)
			(xy 94.88434 -266.432691) (xy 94.866291 -266.425369) (xy 94.856554 -266.424918) (xy 94.539308 -266.424918)
			(xy 94.529628 -266.425349) (xy 94.511637 -266.432506) (xy 94.497543 -266.445782) (xy 94.49308 -266.454382)
			(xy 94.454472 -266.537948) (xy 94.450781 -266.546878) (xy 94.449709 -266.566155) (xy 94.455872 -266.584451)
			(xy 94.461838 -266.59205) (xy 94.461838 -266.592304) (xy 94.479344 -266.613842) (xy 94.507293 -266.661788)
			(xy 94.526433 -266.713881) (xy 94.536173 -266.768518) (xy 94.536768 -266.796266) (xy 94.536281 -266.821076)
			(xy 94.528519 -266.870084) (xy 94.513186 -266.917274) (xy 94.490659 -266.961485) (xy 94.461494 -267.001628)
			(xy 94.426408 -267.036714) (xy 94.386265 -267.065879) (xy 94.342054 -267.088406) (xy 94.294864 -267.103739)
			(xy 94.245856 -267.111501) (xy 94.196236 -267.111501) (xy 94.147228 -267.103739) (xy 94.100038 -267.088406)
			(xy 94.055827 -267.065879) (xy 94.015684 -267.036714) (xy 93.980598 -267.001628) (xy 93.951433 -266.961485)
			(xy 93.928906 -266.917274) (xy 93.913573 -266.870084) (xy 93.905811 -266.821076) (xy 93.905324 -266.796266)
			(xy 93.905926 -266.768517) (xy 93.915663 -266.71388) (xy 93.934797 -266.661785) (xy 93.962738 -266.613834)
			(xy 93.980254 -266.592304) (xy 93.980254 -266.59205) (xy 93.986173 -266.584422) (xy 93.99233 -266.566139)
			(xy 93.991298 -266.546874) (xy 93.98762 -266.537948) (xy 93.949012 -266.454382) (xy 93.944571 -266.445762)
			(xy 93.930497 -266.432447) (xy 93.912474 -266.425337) (xy 93.902784 -266.424918) (xy 93.585538 -266.424918)
			(xy 93.575786 -266.425338) (xy 93.55769 -266.432612) (xy 93.543651 -266.446149) (xy 93.53931 -266.45489)
			(xy 93.50121 -266.539218) (xy 93.497594 -266.548311) (xy 93.496809 -266.567848) (xy 93.503394 -266.586258)
			(xy 93.509592 -266.593828) (xy 93.527486 -266.614959) (xy 93.556109 -266.662353) (xy 93.575735 -266.714125)
			(xy 93.585723 -266.768583) (xy 93.5863 -266.796266) (xy 93.585778 -266.821521) (xy 93.577465 -266.871343)
			(xy 93.561064 -266.919117) (xy 93.537023 -266.96354) (xy 93.505999 -267.0034) (xy 93.468837 -267.03761)
			(xy 93.426551 -267.065236) (xy 93.380295 -267.085526) (xy 93.33133 -267.097926) (xy 93.280992 -267.102097)
			(xy 93.230654 -267.097926) (xy 93.181689 -267.085526) (xy 93.135433 -267.065236) (xy 93.093147 -267.03761)
			(xy 93.055985 -267.0034) (xy 93.024961 -266.96354) (xy 93.00092 -266.919117) (xy 92.984519 -266.871343)
			(xy 92.976206 -266.821521) (xy 92.975684 -266.796266) (xy 92.976279 -266.768582) (xy 92.986242 -266.714117)
			(xy 93.005855 -266.662338) (xy 93.034475 -266.61494) (xy 93.052392 -266.593828) (xy 93.058566 -266.58624)
			(xy 93.06516 -266.567843) (xy 93.064374 -266.548315) (xy 93.060774 -266.539218) (xy 93.022674 -266.45489)
			(xy 93.018271 -266.446193) (xy 93.004231 -266.432694) (xy 92.986182 -266.425375) (xy 92.976446 -266.424918)
			(xy 92.6592 -266.424918) (xy 92.649521 -266.42535) (xy 92.631532 -266.432509) (xy 92.61744 -266.445786)
			(xy 92.612972 -266.454382) (xy 92.574364 -266.537948) (xy 92.570673 -266.546878) (xy 92.569601 -266.566155)
			(xy 92.575764 -266.584452) (xy 92.58173 -266.59205) (xy 92.58173 -266.592304) (xy 92.599236 -266.613842)
			(xy 92.627187 -266.661788) (xy 92.646326 -266.713881) (xy 92.656067 -266.768517) (xy 92.65666 -266.796266)
			(xy 92.656173 -266.821076) (xy 92.648411 -266.870084) (xy 92.633078 -266.917274) (xy 92.610551 -266.961485)
			(xy 92.581386 -267.001628) (xy 92.5463 -267.036714) (xy 92.506157 -267.065879) (xy 92.461946 -267.088406)
			(xy 92.414756 -267.103739) (xy 92.365748 -267.111501) (xy 92.316128 -267.111501) (xy 92.26712 -267.103739)
			(xy 92.21993 -267.088406) (xy 92.175719 -267.065879) (xy 92.135576 -267.036714) (xy 92.10049 -267.001628)
			(xy 92.071325 -266.961485) (xy 92.048798 -266.917274) (xy 92.033465 -266.870084) (xy 92.025703 -266.821076)
			(xy 92.025216 -266.796266) (xy 92.025818 -266.768517) (xy 92.035555 -266.71388) (xy 92.054688 -266.661784)
			(xy 92.082629 -266.613833) (xy 92.100146 -266.592304) (xy 92.100146 -266.59205) (xy 92.106066 -266.584422)
			(xy 92.112223 -266.566139) (xy 92.111192 -266.546874) (xy 92.107512 -266.537948) (xy 92.068904 -266.454382)
			(xy 92.064462 -266.445763) (xy 92.050388 -266.43245) (xy 92.032365 -266.425343) (xy 92.022676 -266.424918)
			(xy 91.7194 -266.424918) (xy 91.709721 -266.42535) (xy 91.691732 -266.432509) (xy 91.67764 -266.445786)
			(xy 91.673172 -266.454382) (xy 91.634564 -266.537948) (xy 91.630873 -266.546878) (xy 91.629801 -266.566155)
			(xy 91.635964 -266.584452) (xy 91.64193 -266.59205) (xy 91.64193 -266.592304) (xy 91.659436 -266.613842)
			(xy 91.687387 -266.661788) (xy 91.706526 -266.713881) (xy 91.716267 -266.768517) (xy 91.71686 -266.796266)
			(xy 91.716373 -266.821076) (xy 91.708611 -266.870084) (xy 91.693278 -266.917274) (xy 91.670751 -266.961485)
			(xy 91.641586 -267.001628) (xy 91.6065 -267.036714) (xy 91.566357 -267.065879) (xy 91.522146 -267.088406)
			(xy 91.474956 -267.103739) (xy 91.425948 -267.111501) (xy 91.376328 -267.111501) (xy 91.32732 -267.103739)
			(xy 91.28013 -267.088406) (xy 91.235919 -267.065879) (xy 91.195776 -267.036714) (xy 91.16069 -267.001628)
			(xy 91.131525 -266.961485) (xy 91.108998 -266.917274) (xy 91.093665 -266.870084) (xy 91.085903 -266.821076)
			(xy 91.085416 -266.796266) (xy 91.086018 -266.768517) (xy 91.095755 -266.71388) (xy 91.114888 -266.661784)
			(xy 91.142829 -266.613833) (xy 91.160346 -266.592304) (xy 91.160346 -266.59205) (xy 91.166266 -266.584422)
			(xy 91.172423 -266.566139) (xy 91.171392 -266.546874) (xy 91.167712 -266.537948) (xy 91.129104 -266.454382)
			(xy 91.124662 -266.445763) (xy 91.110588 -266.43245) (xy 91.092565 -266.425343) (xy 91.082876 -266.424918)
			(xy 90.76563 -266.424918) (xy 90.755878 -266.42534) (xy 90.737786 -266.432615) (xy 90.723749 -266.446152)
			(xy 90.719402 -266.45489) (xy 90.681302 -266.539218) (xy 90.677686 -266.548312) (xy 90.676902 -266.567848)
			(xy 90.683485 -266.586258) (xy 90.689684 -266.593828) (xy 90.707579 -266.614959) (xy 90.736202 -266.662353)
			(xy 90.755828 -266.714124) (xy 90.765817 -266.768583) (xy 90.766392 -266.796266) (xy 90.76587 -266.821521)
			(xy 90.757557 -266.871343) (xy 90.741156 -266.919117) (xy 90.717115 -266.96354) (xy 90.686091 -267.0034)
			(xy 90.648929 -267.03761) (xy 90.606643 -267.065236) (xy 90.560387 -267.085526) (xy 90.511422 -267.097926)
			(xy 90.461084 -267.102097) (xy 90.410746 -267.097926) (xy 90.361781 -267.085526) (xy 90.315525 -267.065236)
			(xy 90.273239 -267.03761) (xy 90.236077 -267.0034) (xy 90.205053 -266.96354) (xy 90.181012 -266.919117)
			(xy 90.164611 -266.871343) (xy 90.156298 -266.821521) (xy 90.155776 -266.796266) (xy 90.156371 -266.768582)
			(xy 90.166334 -266.714117) (xy 90.185946 -266.662338) (xy 90.214566 -266.614939) (xy 90.232484 -266.593828)
			(xy 90.238659 -266.586241) (xy 90.245254 -266.567843) (xy 90.244467 -266.548314) (xy 90.240866 -266.539218)
			(xy 90.202766 -266.45489) (xy 90.198363 -266.446194) (xy 90.184322 -266.432697) (xy 90.166274 -266.42538)
			(xy 90.156538 -266.424918) (xy 89.839292 -266.424918) (xy 89.829613 -266.425351) (xy 89.811627 -266.432512)
			(xy 89.797538 -266.445789) (xy 89.793064 -266.454382) (xy 89.754456 -266.537948) (xy 89.750766 -266.546878)
			(xy 89.749694 -266.566155) (xy 89.755855 -266.584452) (xy 89.761822 -266.59205) (xy 89.761822 -266.592304)
			(xy 89.779329 -266.613841) (xy 89.80728 -266.661787) (xy 89.82642 -266.713881) (xy 89.836161 -266.768517)
			(xy 89.836752 -266.796266) (xy 89.836265 -266.821076) (xy 89.828503 -266.870084) (xy 89.81317 -266.917274)
			(xy 89.790643 -266.961485) (xy 89.761478 -267.001628) (xy 89.726392 -267.036714) (xy 89.686249 -267.065879)
			(xy 89.642038 -267.088406) (xy 89.594848 -267.103739) (xy 89.54584 -267.111501) (xy 89.49622 -267.111501)
			(xy 89.447212 -267.103739) (xy 89.400022 -267.088406) (xy 89.355811 -267.065879) (xy 89.315668 -267.036714)
			(xy 89.280582 -267.001628) (xy 89.251417 -266.961485) (xy 89.22889 -266.917274) (xy 89.213557 -266.870084)
			(xy 89.205795 -266.821076) (xy 89.205308 -266.796266) (xy 89.20591 -266.768517) (xy 89.215646 -266.71388)
			(xy 89.234779 -266.661784) (xy 89.26272 -266.613832) (xy 89.280238 -266.592304) (xy 89.280238 -266.59205)
			(xy 89.286158 -266.584422) (xy 89.292317 -266.566139) (xy 89.291285 -266.546873) (xy 89.287604 -266.537948)
			(xy 89.248996 -266.454382) (xy 89.244554 -266.445764) (xy 89.230479 -266.432453) (xy 89.212457 -266.425349)
			(xy 89.202768 -266.424918) (xy 88.885522 -266.424918) (xy 88.875771 -266.425341) (xy 88.857681 -266.432618)
			(xy 88.843646 -266.446155) (xy 88.839294 -266.45489) (xy 88.801194 -266.539218) (xy 88.797579 -266.548312)
			(xy 88.796794 -266.567848) (xy 88.803377 -266.586258) (xy 88.809576 -266.593828) (xy 88.827471 -266.614959)
			(xy 88.856095 -266.662352) (xy 88.875722 -266.714124) (xy 88.885711 -266.768583) (xy 88.886284 -266.796266)
			(xy 88.885762 -266.821521) (xy 88.877449 -266.871343) (xy 88.861048 -266.919117) (xy 88.837007 -266.96354)
			(xy 88.805983 -267.0034) (xy 88.768821 -267.03761) (xy 88.726535 -267.065236) (xy 88.680279 -267.085526)
			(xy 88.631314 -267.097926) (xy 88.580976 -267.102097) (xy 88.530638 -267.097926) (xy 88.481673 -267.085526)
			(xy 88.435417 -267.065236) (xy 88.393131 -267.03761) (xy 88.355969 -267.0034) (xy 88.324945 -266.96354)
			(xy 88.300904 -266.919117) (xy 88.284503 -266.871343) (xy 88.27619 -266.821521) (xy 88.275668 -266.796266)
			(xy 88.276262 -266.768581) (xy 88.286225 -266.714116) (xy 88.305837 -266.662337) (xy 88.334456 -266.614938)
			(xy 88.352376 -266.593828) (xy 88.358552 -266.586241) (xy 88.365148 -266.567843) (xy 88.364361 -266.548314)
			(xy 88.360758 -266.539218) (xy 88.322658 -266.45489) (xy 88.318254 -266.446195) (xy 88.304214 -266.432701)
			(xy 88.286165 -266.425386) (xy 88.27643 -266.424918) (xy 87.959184 -266.424918) (xy 87.949506 -266.425353)
			(xy 87.931522 -266.432516) (xy 87.917435 -266.445792) (xy 87.912956 -266.454382) (xy 87.874348 -266.537948)
			(xy 87.870658 -266.546878) (xy 87.869587 -266.566155) (xy 87.875747 -266.584452) (xy 87.881714 -266.59205)
			(xy 87.881714 -266.592304) (xy 87.899221 -266.613841) (xy 87.927173 -266.661787) (xy 87.946314 -266.71388)
			(xy 87.956055 -266.768517) (xy 87.956644 -266.796266) (xy 87.956157 -266.821076) (xy 87.948395 -266.870084)
			(xy 87.933062 -266.917274) (xy 87.910535 -266.961485) (xy 87.88137 -267.001628) (xy 87.846284 -267.036714)
			(xy 87.806141 -267.065879) (xy 87.76193 -267.088406) (xy 87.71474 -267.103739) (xy 87.665732 -267.111501)
			(xy 87.616112 -267.111501) (xy 87.567104 -267.103739) (xy 87.519914 -267.088406) (xy 87.475703 -267.065879)
			(xy 87.43556 -267.036714) (xy 87.400474 -267.001628) (xy 87.371309 -266.961485) (xy 87.348782 -266.917274)
			(xy 87.333449 -266.870084) (xy 87.325687 -266.821076) (xy 87.3252 -266.796266) (xy 87.325802 -266.768517)
			(xy 87.335538 -266.71388) (xy 87.354671 -266.661783) (xy 87.382611 -266.613831) (xy 87.40013 -266.592304)
			(xy 87.40013 -266.59205) (xy 87.406051 -266.584423) (xy 87.412211 -266.566139) (xy 87.411179 -266.546873)
			(xy 87.407496 -266.537948) (xy 87.368888 -266.454382) (xy 87.36445 -266.445754) (xy 87.35038 -266.432417)
			(xy 87.332355 -266.425282) (xy 87.32266 -266.424918) (xy 87.005668 -266.424918) (xy 86.995923 -266.42535)
			(xy 86.977849 -266.432639) (xy 86.963831 -266.446178) (xy 86.95944 -266.45489) (xy 86.92134 -266.539218)
			(xy 86.917727 -266.548313) (xy 86.916944 -266.567849) (xy 86.923521 -266.586261) (xy 86.929722 -266.593828)
			(xy 86.947615 -266.61496) (xy 86.976235 -266.662355) (xy 86.995858 -266.714126) (xy 87.005845 -266.768583)
			(xy 87.00643 -266.796266) (xy 87.005908 -266.821521) (xy 86.997595 -266.871343) (xy 86.981194 -266.919117)
			(xy 86.957153 -266.96354) (xy 86.926129 -267.0034) (xy 86.888967 -267.03761) (xy 86.846681 -267.065236)
			(xy 86.800425 -267.085526) (xy 86.75146 -267.097926) (xy 86.701122 -267.102097) (xy 86.650784 -267.097926)
			(xy 86.601819 -267.085526) (xy 86.555563 -267.065236) (xy 86.513277 -267.03761) (xy 86.476115 -267.0034)
			(xy 86.445091 -266.96354) (xy 86.42105 -266.919117) (xy 86.404649 -266.871343) (xy 86.396336 -266.821521)
			(xy 86.395814 -266.796266) (xy 86.396409 -266.768582) (xy 86.406373 -266.714118) (xy 86.425987 -266.66234)
			(xy 86.45461 -266.614944) (xy 86.472522 -266.593828) (xy 86.478703 -266.586243) (xy 86.485307 -266.567844)
			(xy 86.484519 -266.548311) (xy 86.480904 -266.539218) (xy 86.442804 -266.45489) (xy 86.438403 -266.44619)
			(xy 86.424364 -266.432683) (xy 86.406314 -266.425353) (xy 86.396576 -266.424918) (xy 86.07933 -266.424918)
			(xy 86.069647 -266.425345) (xy 86.05165 -266.432498) (xy 86.03755 -266.445773) (xy 86.033102 -266.454382)
			(xy 85.994494 -266.537948) (xy 85.990802 -266.546878) (xy 85.989729 -266.566155) (xy 85.995895 -266.58445)
			(xy 86.00186 -266.59205) (xy 86.00186 -266.592304) (xy 86.019308 -266.613832) (xy 86.047159 -266.661733)
			(xy 86.066232 -266.713756) (xy 86.075943 -266.768308) (xy 86.076536 -266.796012) (xy 86.076536 -266.796266)
			(xy 86.07605 -266.821056) (xy 86.068294 -266.870024) (xy 86.052973 -266.917177) (xy 86.030464 -266.961352)
			(xy 86.001322 -267.001463) (xy 85.966265 -267.03652) (xy 85.926154 -267.065662) (xy 85.881979 -267.088171)
			(xy 85.834826 -267.103492) (xy 85.785858 -267.111248) (xy 85.736278 -267.111248) (xy 85.68731 -267.103492)
			(xy 85.640157 -267.088171) (xy 85.595982 -267.065662) (xy 85.555871 -267.03652) (xy 85.520814 -267.001463)
			(xy 85.491672 -266.961352) (xy 85.469163 -266.917177) (xy 85.453842 -266.870024) (xy 85.446086 -266.821056)
			(xy 85.4456 -266.796266) (xy 85.4456 -266.796012) (xy 85.446173 -266.768304) (xy 85.455848 -266.713738)
			(xy 85.474921 -266.661707) (xy 85.502802 -266.613815) (xy 85.520276 -266.592304) (xy 85.520276 -266.59205)
			(xy 85.526193 -266.584421) (xy 85.532347 -266.566138) (xy 85.531316 -266.546875) (xy 85.527642 -266.537948)
			(xy 85.489034 -266.454382) (xy 85.484594 -266.44576) (xy 85.470521 -266.432438) (xy 85.452497 -266.425321)
			(xy 85.442806 -266.424918) (xy 85.139276 -266.424918) (xy 85.129599 -266.425354) (xy 85.111618 -266.432519)
			(xy 85.097533 -266.445796) (xy 85.093048 -266.454382) (xy 85.05444 -266.537948) (xy 85.050751 -266.546878)
			(xy 85.04968 -266.566155) (xy 85.055839 -266.584452) (xy 85.061806 -266.59205) (xy 85.061806 -266.592304)
			(xy 85.079314 -266.613841) (xy 85.107266 -266.661787) (xy 85.126407 -266.71388) (xy 85.136148 -266.768517)
			(xy 85.136736 -266.796266) (xy 85.136249 -266.821076) (xy 85.128487 -266.870084) (xy 85.113154 -266.917274)
			(xy 85.090627 -266.961485) (xy 85.061462 -267.001628) (xy 85.026376 -267.036714) (xy 84.986233 -267.065879)
			(xy 84.942022 -267.088406) (xy 84.894832 -267.103739) (xy 84.845824 -267.111501) (xy 84.796204 -267.111501)
			(xy 84.747196 -267.103739) (xy 84.700006 -267.088406) (xy 84.655795 -267.065879) (xy 84.615652 -267.036714)
			(xy 84.580566 -267.001628) (xy 84.551401 -266.961485) (xy 84.528874 -266.917274) (xy 84.513541 -266.870084)
			(xy 84.505779 -266.821076) (xy 84.505292 -266.796266) (xy 84.505894 -266.768517) (xy 84.51563 -266.713879)
			(xy 84.534762 -266.661783) (xy 84.562702 -266.61383) (xy 84.580222 -266.592304) (xy 84.580222 -266.59205)
			(xy 84.586144 -266.584423) (xy 84.592305 -266.566139) (xy 84.591273 -266.546872) (xy 84.587588 -266.537948)
			(xy 84.54898 -266.454382) (xy 84.544542 -266.445755) (xy 84.530471 -266.43242) (xy 84.512446 -266.425288)
			(xy 84.502752 -266.424918) (xy 84.185506 -266.424918) (xy 84.175757 -266.425344) (xy 84.157671 -266.432625)
			(xy 84.143642 -266.446162) (xy 84.139278 -266.45489) (xy 84.101178 -266.539218) (xy 84.097564 -266.548312)
			(xy 84.09678 -266.567848) (xy 84.10336 -266.586259) (xy 84.10956 -266.593828) (xy 84.127456 -266.614958)
			(xy 84.156082 -266.662352) (xy 84.175709 -266.714123) (xy 84.185699 -266.768582) (xy 84.186268 -266.796266)
			(xy 84.185746 -266.821521) (xy 84.177433 -266.871343) (xy 84.161032 -266.919117) (xy 84.136991 -266.96354)
			(xy 84.105967 -267.0034) (xy 84.068805 -267.03761) (xy 84.026519 -267.065236) (xy 83.980263 -267.085526)
			(xy 83.931298 -267.097926) (xy 83.88096 -267.102097) (xy 83.830622 -267.097926) (xy 83.781657 -267.085526)
			(xy 83.735401 -267.065236) (xy 83.693115 -267.03761) (xy 83.655953 -267.0034) (xy 83.624929 -266.96354)
			(xy 83.600888 -266.919117) (xy 83.584487 -266.871343) (xy 83.576174 -266.821521) (xy 83.575652 -266.796266)
			(xy 83.576246 -266.768581) (xy 83.586209 -266.714116) (xy 83.60582 -266.662336) (xy 83.634438 -266.614936)
			(xy 83.65236 -266.593828) (xy 83.658537 -266.586242) (xy 83.665136 -266.567843) (xy 83.664349 -266.548313)
			(xy 83.660742 -266.539218) (xy 83.622642 -266.45489) (xy 83.618238 -266.446197) (xy 83.604196 -266.432707)
			(xy 83.586148 -266.425398) (xy 83.576414 -266.424918) (xy 83.259168 -266.424918) (xy 83.249492 -266.425356)
			(xy 83.231513 -266.432522) (xy 83.21743 -266.445799) (xy 83.21294 -266.454382) (xy 83.174332 -266.537948)
			(xy 83.170643 -266.546879) (xy 83.169572 -266.566155) (xy 83.175731 -266.584453) (xy 83.181698 -266.59205)
			(xy 83.181698 -266.592304) (xy 83.199206 -266.613841) (xy 83.227159 -266.661786) (xy 83.246301 -266.71388)
			(xy 83.256042 -266.768517) (xy 83.256628 -266.796266) (xy 83.256141 -266.821076) (xy 83.248379 -266.870084)
			(xy 83.233046 -266.917274) (xy 83.210519 -266.961485) (xy 83.181354 -267.001628) (xy 83.146268 -267.036714)
			(xy 83.106125 -267.065879) (xy 83.061914 -267.088406) (xy 83.014724 -267.103739) (xy 82.965716 -267.111501)
			(xy 82.916096 -267.111501) (xy 82.867088 -267.103739) (xy 82.819898 -267.088406) (xy 82.775687 -267.065879)
			(xy 82.735544 -267.036714) (xy 82.700458 -267.001628) (xy 82.671293 -266.961485) (xy 82.648766 -266.917274)
			(xy 82.633433 -266.870084) (xy 82.625671 -266.821076) (xy 82.625184 -266.796266) (xy 82.625785 -266.768517)
			(xy 82.635521 -266.713879) (xy 82.654653 -266.661782) (xy 82.682592 -266.613829) (xy 82.700114 -266.592304)
			(xy 82.700114 -266.59205) (xy 82.706037 -266.584423) (xy 82.712199 -266.566139) (xy 82.711166 -266.546872)
			(xy 82.70748 -266.537948) (xy 82.668872 -266.454382) (xy 82.664434 -266.445755) (xy 82.650363 -266.432424)
			(xy 82.632338 -266.425293) (xy 82.622644 -266.424918) (xy 82.305652 -266.424918) (xy 82.295909 -266.425353)
			(xy 82.277839 -266.432645) (xy 82.263826 -266.446185) (xy 82.259424 -266.45489) (xy 82.221324 -266.539218)
			(xy 82.217707 -266.548311) (xy 82.216922 -266.567848) (xy 82.223508 -266.586257) (xy 82.229706 -266.593828)
			(xy 82.2476 -266.614959) (xy 82.276221 -266.662354) (xy 82.295846 -266.714125) (xy 82.305833 -266.768583)
			(xy 82.306414 -266.796266) (xy 82.305892 -266.821521) (xy 82.297579 -266.871343) (xy 82.281178 -266.919117)
			(xy 82.257137 -266.96354) (xy 82.226113 -267.0034) (xy 82.188951 -267.03761) (xy 82.146665 -267.065236)
			(xy 82.100409 -267.085526) (xy 82.051444 -267.097926) (xy 82.001106 -267.102097) (xy 81.950768 -267.097926)
			(xy 81.901803 -267.085526) (xy 81.855547 -267.065236) (xy 81.813261 -267.03761) (xy 81.776099 -267.0034)
			(xy 81.745075 -266.96354) (xy 81.721034 -266.919117) (xy 81.704633 -266.871343) (xy 81.69632 -266.821521)
			(xy 81.695798 -266.796266) (xy 81.696393 -266.768582) (xy 81.706356 -266.714117) (xy 81.72597 -266.662339)
			(xy 81.754591 -266.614942) (xy 81.772506 -266.593828) (xy 81.778679 -266.58624) (xy 81.785272 -266.567843)
			(xy 81.784485 -266.548315) (xy 81.780888 -266.539218) (xy 81.742788 -266.45489) (xy 81.738386 -266.446192)
			(xy 81.724346 -266.432689) (xy 81.706297 -266.425365) (xy 81.69656 -266.424918) (xy 81.379314 -266.424918)
			(xy 81.369633 -266.425348) (xy 81.351641 -266.432504) (xy 81.337545 -266.44578) (xy 81.333086 -266.454382)
			(xy 81.294478 -266.537948) (xy 81.290787 -266.546878) (xy 81.289715 -266.566155) (xy 81.295878 -266.584451)
			(xy 81.301844 -266.59205) (xy 81.301844 -266.592304) (xy 81.319293 -266.613831) (xy 81.347146 -266.661732)
			(xy 81.36622 -266.713755) (xy 81.37593 -266.768308) (xy 81.37652 -266.796012) (xy 81.37652 -266.796266)
			(xy 81.376034 -266.821056) (xy 81.368278 -266.870024) (xy 81.352957 -266.917177) (xy 81.330448 -266.961352)
			(xy 81.301306 -267.001463) (xy 81.266249 -267.03652) (xy 81.226138 -267.065662) (xy 81.181963 -267.088171)
			(xy 81.13481 -267.103492) (xy 81.085842 -267.111248) (xy 81.036262 -267.111248) (xy 80.987294 -267.103492)
			(xy 80.940141 -267.088171) (xy 80.895966 -267.065662) (xy 80.855855 -267.03652) (xy 80.820798 -267.001463)
			(xy 80.791656 -266.961352) (xy 80.769147 -266.917177) (xy 80.753826 -266.870024) (xy 80.74607 -266.821056)
			(xy 80.745584 -266.796266) (xy 80.745584 -266.796012) (xy 80.746157 -266.768303) (xy 80.755832 -266.713738)
			(xy 80.774903 -266.661706) (xy 80.802783 -266.613813) (xy 80.82026 -266.592304) (xy 80.82026 -266.59205)
			(xy 80.826178 -266.584422) (xy 80.832334 -266.566138) (xy 80.831303 -266.546874) (xy 80.827626 -266.537948)
			(xy 80.789018 -266.454382) (xy 80.784577 -266.445761) (xy 80.770503 -266.432445) (xy 80.75248 -266.425333)
			(xy 80.74279 -266.424918) (xy 80.425544 -266.424918) (xy 80.415802 -266.425355) (xy 80.397735 -266.432649)
			(xy 80.383724 -266.446188) (xy 80.379316 -266.45489) (xy 80.341216 -266.539218) (xy 80.337599 -266.548311)
			(xy 80.336815 -266.567848) (xy 80.3434 -266.586257) (xy 80.349598 -266.593828) (xy 80.367492 -266.614959)
			(xy 80.396114 -266.662353) (xy 80.415739 -266.714125) (xy 80.425727 -266.768583) (xy 80.426306 -266.796266)
			(xy 80.425784 -266.821521) (xy 80.417471 -266.871343) (xy 80.40107 -266.919117) (xy 80.377029 -266.96354)
			(xy 80.346005 -267.0034) (xy 80.308843 -267.03761) (xy 80.266557 -267.065236) (xy 80.220301 -267.085526)
			(xy 80.171336 -267.097926) (xy 80.120998 -267.102097) (xy 80.07066 -267.097926) (xy 80.021695 -267.085526)
			(xy 79.975439 -267.065236) (xy 79.933153 -267.03761) (xy 79.895991 -267.0034) (xy 79.864967 -266.96354)
			(xy 79.840926 -266.919117) (xy 79.824525 -266.871343) (xy 79.816212 -266.821521) (xy 79.81569 -266.796266)
			(xy 79.816285 -266.768582) (xy 79.826248 -266.714117) (xy 79.845861 -266.662339) (xy 79.874482 -266.614941)
			(xy 79.892398 -266.593828) (xy 79.898571 -266.58624) (xy 79.905165 -266.567843) (xy 79.904378 -266.548315)
			(xy 79.90078 -266.539218) (xy 79.86268 -266.45489) (xy 79.858277 -266.446193) (xy 79.844238 -266.432692)
			(xy 79.826189 -266.42537) (xy 79.816452 -266.424918) (xy 77.519784 -266.424918) (xy 77.509715 -266.425344)
			(xy 77.491117 -266.433065) (xy 77.483716 -266.439904) (xy 77.432916 -266.491212) (xy 77.426103 -266.49869)
			(xy 77.418511 -266.517423) (xy 77.418184 -266.527534) (xy 77.418184 -266.530328) (xy 77.417662 -266.555583)
			(xy 77.409349 -266.605405) (xy 77.392948 -266.653179) (xy 77.368907 -266.697602) (xy 77.337883 -266.737462)
			(xy 77.300721 -266.771672) (xy 77.258435 -266.799298) (xy 77.212179 -266.819588) (xy 77.163214 -266.831988)
			(xy 77.112876 -266.836159) (xy 77.062538 -266.831988) (xy 77.013573 -266.819588) (xy 76.967317 -266.799298)
			(xy 76.925031 -266.771672) (xy 76.887869 -266.737462) (xy 76.856845 -266.697602) (xy 76.832804 -266.653179)
			(xy 76.816403 -266.605405) (xy 76.80809 -266.555583) (xy 76.807568 -266.530328) (xy 76.807568 -266.527534)
			(xy 76.807224 -266.517429) (xy 76.799617 -266.498713) (xy 76.792836 -266.491212) (xy 76.742036 -266.439904)
			(xy 76.734634 -266.433067) (xy 76.716036 -266.425355) (xy 76.705968 -266.424918) (xy 74.001122 -266.424918)
			(xy 73.991059 -266.425356) (xy 73.972476 -266.433092) (xy 73.965054 -266.439904) (xy 73.243948 -267.16101)
			(xy 73.237098 -267.168407) (xy 73.229359 -267.187005) (xy 73.228962 -267.197078) (xy 73.228962 -267.606272)
			(xy 78.40524 -267.606272) (xy 78.4092 -267.557218) (xy 78.420977 -267.509434) (xy 78.440268 -267.464158)
			(xy 78.466571 -267.422562) (xy 78.499206 -267.385725) (xy 78.537327 -267.3546) (xy 78.579948 -267.329993)
			(xy 78.625964 -267.312541) (xy 78.674183 -267.302697) (xy 78.723358 -267.300716) (xy 78.772213 -267.306648)
			(xy 78.819484 -267.32034) (xy 78.863946 -267.341438) (xy 78.904449 -267.369394) (xy 78.939942 -267.403486)
			(xy 78.969507 -267.44283) (xy 78.992378 -267.486407) (xy 79.007962 -267.533088) (xy 79.015857 -267.581665)
			(xy 79.016352 -267.606272) (xy 80.285348 -267.606272) (xy 80.289308 -267.557218) (xy 80.301085 -267.509434)
			(xy 80.320376 -267.464158) (xy 80.346679 -267.422562) (xy 80.379314 -267.385725) (xy 80.417435 -267.3546)
			(xy 80.460056 -267.329993) (xy 80.506072 -267.312541) (xy 80.554291 -267.302697) (xy 80.603466 -267.300716)
			(xy 80.652321 -267.306648) (xy 80.699592 -267.32034) (xy 80.744054 -267.341438) (xy 80.784557 -267.369394)
			(xy 80.82005 -267.403486) (xy 80.849615 -267.44283) (xy 80.872486 -267.486407) (xy 80.88807 -267.533088)
			(xy 80.895965 -267.581665) (xy 80.89646 -267.606272) (xy 81.214717 -267.606272) (xy 81.218812 -267.555544)
			(xy 81.230991 -267.50613) (xy 81.250939 -267.45931) (xy 81.27814 -267.416296) (xy 81.311888 -267.378202)
			(xy 81.35131 -267.346015) (xy 81.395384 -267.320569) (xy 81.44297 -267.302522) (xy 81.492834 -267.292342)
			(xy 81.543686 -267.290293) (xy 81.594207 -267.296427) (xy 81.643091 -267.310587) (xy 81.68907 -267.332404)
			(xy 81.730954 -267.361314) (xy 81.767658 -267.396569) (xy 81.798231 -267.437255) (xy 81.821882 -267.482318)
			(xy 81.837998 -267.530592) (xy 81.846162 -267.580826) (xy 81.846674 -267.606272) (xy 82.165202 -267.606272)
			(xy 82.169162 -267.557218) (xy 82.180939 -267.509434) (xy 82.20023 -267.464158) (xy 82.226533 -267.422562)
			(xy 82.259168 -267.385725) (xy 82.297289 -267.3546) (xy 82.33991 -267.329993) (xy 82.385926 -267.312541)
			(xy 82.434145 -267.302697) (xy 82.48332 -267.300716) (xy 82.532175 -267.306648) (xy 82.579446 -267.32034)
			(xy 82.623908 -267.341438) (xy 82.664411 -267.369394) (xy 82.699904 -267.403486) (xy 82.729469 -267.44283)
			(xy 82.75234 -267.486407) (xy 82.767924 -267.533088) (xy 82.775819 -267.581665) (xy 82.776314 -267.606272)
			(xy 83.105256 -267.606272) (xy 83.109216 -267.557218) (xy 83.120993 -267.509434) (xy 83.140284 -267.464158)
			(xy 83.166587 -267.422562) (xy 83.199222 -267.385725) (xy 83.237343 -267.3546) (xy 83.279964 -267.329993)
			(xy 83.32598 -267.312541) (xy 83.374199 -267.302697) (xy 83.423374 -267.300716) (xy 83.472229 -267.306648)
			(xy 83.5195 -267.32034) (xy 83.563962 -267.341438) (xy 83.604465 -267.369394) (xy 83.639958 -267.403486)
			(xy 83.669523 -267.44283) (xy 83.692394 -267.486407) (xy 83.707978 -267.533088) (xy 83.715873 -267.581665)
			(xy 83.716368 -267.606272) (xy 84.034879 -267.606272) (xy 84.038974 -267.555544) (xy 84.051153 -267.50613)
			(xy 84.071101 -267.45931) (xy 84.098302 -267.416296) (xy 84.13205 -267.378202) (xy 84.171472 -267.346015)
			(xy 84.215546 -267.320569) (xy 84.263132 -267.302522) (xy 84.312996 -267.292342) (xy 84.363848 -267.290293)
			(xy 84.414369 -267.296427) (xy 84.463253 -267.310587) (xy 84.509232 -267.332404) (xy 84.551116 -267.361314)
			(xy 84.58782 -267.396569) (xy 84.618393 -267.437255) (xy 84.642044 -267.482318) (xy 84.65816 -267.530592)
			(xy 84.666324 -267.580826) (xy 84.666836 -267.606272) (xy 84.98511 -267.606272) (xy 84.98907 -267.557218)
			(xy 85.000847 -267.509434) (xy 85.020138 -267.464158) (xy 85.046441 -267.422562) (xy 85.079076 -267.385725)
			(xy 85.117197 -267.3546) (xy 85.159818 -267.329993) (xy 85.205834 -267.312541) (xy 85.254053 -267.302697)
			(xy 85.303228 -267.300716) (xy 85.352083 -267.306648) (xy 85.399354 -267.32034) (xy 85.443816 -267.341438)
			(xy 85.484319 -267.369394) (xy 85.519812 -267.403486) (xy 85.549377 -267.44283) (xy 85.572248 -267.486407)
			(xy 85.587832 -267.533088) (xy 85.595727 -267.581665) (xy 85.596222 -267.606272) (xy 85.925164 -267.606272)
			(xy 85.929124 -267.557218) (xy 85.940901 -267.509434) (xy 85.960192 -267.464158) (xy 85.986495 -267.422562)
			(xy 86.01913 -267.385725) (xy 86.057251 -267.3546) (xy 86.099872 -267.329993) (xy 86.145888 -267.312541)
			(xy 86.194107 -267.302697) (xy 86.243282 -267.300716) (xy 86.292137 -267.306648) (xy 86.339408 -267.32034)
			(xy 86.38387 -267.341438) (xy 86.424373 -267.369394) (xy 86.459866 -267.403486) (xy 86.489431 -267.44283)
			(xy 86.512302 -267.486407) (xy 86.527886 -267.533088) (xy 86.535781 -267.581665) (xy 86.536276 -267.606272)
			(xy 86.865218 -267.606272) (xy 86.869178 -267.557218) (xy 86.880955 -267.509434) (xy 86.900246 -267.464158)
			(xy 86.926549 -267.422562) (xy 86.959184 -267.385725) (xy 86.997305 -267.3546) (xy 87.039926 -267.329993)
			(xy 87.085942 -267.312541) (xy 87.134161 -267.302697) (xy 87.183336 -267.300716) (xy 87.232191 -267.306648)
			(xy 87.279462 -267.32034) (xy 87.323924 -267.341438) (xy 87.364427 -267.369394) (xy 87.39992 -267.403486)
			(xy 87.429485 -267.44283) (xy 87.452356 -267.486407) (xy 87.46794 -267.533088) (xy 87.475835 -267.581665)
			(xy 87.47633 -267.606272) (xy 87.794841 -267.606272) (xy 87.798936 -267.555544) (xy 87.811115 -267.50613)
			(xy 87.831063 -267.45931) (xy 87.858264 -267.416296) (xy 87.892012 -267.378202) (xy 87.931434 -267.346015)
			(xy 87.975508 -267.320569) (xy 88.023094 -267.302522) (xy 88.072958 -267.292342) (xy 88.12381 -267.290293)
			(xy 88.174331 -267.296427) (xy 88.223215 -267.310587) (xy 88.269194 -267.332404) (xy 88.311078 -267.361314)
			(xy 88.347782 -267.396569) (xy 88.378355 -267.437255) (xy 88.402006 -267.482318) (xy 88.418122 -267.530592)
			(xy 88.426286 -267.580826) (xy 88.426798 -267.606272) (xy 88.745326 -267.606272) (xy 88.749286 -267.557218)
			(xy 88.761063 -267.509434) (xy 88.780354 -267.464158) (xy 88.806657 -267.422562) (xy 88.839292 -267.385725)
			(xy 88.877413 -267.3546) (xy 88.920034 -267.329993) (xy 88.96605 -267.312541) (xy 89.014269 -267.302697)
			(xy 89.063444 -267.300716) (xy 89.112299 -267.306648) (xy 89.15957 -267.32034) (xy 89.204032 -267.341438)
			(xy 89.244535 -267.369394) (xy 89.280028 -267.403486) (xy 89.309593 -267.44283) (xy 89.332464 -267.486407)
			(xy 89.348048 -267.533088) (xy 89.355943 -267.581665) (xy 89.356438 -267.606272) (xy 89.685126 -267.606272)
			(xy 89.689086 -267.557218) (xy 89.700863 -267.509434) (xy 89.720154 -267.464158) (xy 89.746457 -267.422562)
			(xy 89.779092 -267.385725) (xy 89.817213 -267.3546) (xy 89.859834 -267.329993) (xy 89.90585 -267.312541)
			(xy 89.954069 -267.302697) (xy 90.003244 -267.300716) (xy 90.052099 -267.306648) (xy 90.09937 -267.32034)
			(xy 90.143832 -267.341438) (xy 90.184335 -267.369394) (xy 90.219828 -267.403486) (xy 90.249393 -267.44283)
			(xy 90.272264 -267.486407) (xy 90.287848 -267.533088) (xy 90.295743 -267.581665) (xy 90.296238 -267.606272)
			(xy 90.614749 -267.606272) (xy 90.618844 -267.555544) (xy 90.631023 -267.50613) (xy 90.650971 -267.45931)
			(xy 90.678172 -267.416296) (xy 90.71192 -267.378202) (xy 90.751342 -267.346015) (xy 90.795416 -267.320569)
			(xy 90.843002 -267.302522) (xy 90.892866 -267.292342) (xy 90.943718 -267.290293) (xy 90.994239 -267.296427)
			(xy 91.043123 -267.310587) (xy 91.089102 -267.332404) (xy 91.130986 -267.361314) (xy 91.16769 -267.396569)
			(xy 91.198263 -267.437255) (xy 91.221914 -267.482318) (xy 91.23803 -267.530592) (xy 91.246194 -267.580826)
			(xy 91.246706 -267.606272) (xy 91.565234 -267.606272) (xy 91.569194 -267.557218) (xy 91.580971 -267.509434)
			(xy 91.600262 -267.464158) (xy 91.626565 -267.422562) (xy 91.6592 -267.385725) (xy 91.697321 -267.3546)
			(xy 91.739942 -267.329993) (xy 91.785958 -267.312541) (xy 91.834177 -267.302697) (xy 91.883352 -267.300716)
			(xy 91.932207 -267.306648) (xy 91.979478 -267.32034) (xy 92.02394 -267.341438) (xy 92.064443 -267.369394)
			(xy 92.099936 -267.403486) (xy 92.129501 -267.44283) (xy 92.152372 -267.486407) (xy 92.167956 -267.533088)
			(xy 92.175851 -267.581665) (xy 92.176346 -267.606272) (xy 92.505288 -267.606272) (xy 92.509248 -267.557218)
			(xy 92.521025 -267.509434) (xy 92.540316 -267.464158) (xy 92.566619 -267.422562) (xy 92.599254 -267.385725)
			(xy 92.637375 -267.3546) (xy 92.679996 -267.329993) (xy 92.726012 -267.312541) (xy 92.774231 -267.302697)
			(xy 92.823406 -267.300716) (xy 92.872261 -267.306648) (xy 92.919532 -267.32034) (xy 92.963994 -267.341438)
			(xy 93.004497 -267.369394) (xy 93.03999 -267.403486) (xy 93.069555 -267.44283) (xy 93.092426 -267.486407)
			(xy 93.10801 -267.533088) (xy 93.115905 -267.581665) (xy 93.1164 -267.606272) (xy 93.445342 -267.606272)
			(xy 93.449302 -267.557218) (xy 93.461079 -267.509434) (xy 93.48037 -267.464158) (xy 93.506673 -267.422562)
			(xy 93.539308 -267.385725) (xy 93.577429 -267.3546) (xy 93.62005 -267.329993) (xy 93.666066 -267.312541)
			(xy 93.714285 -267.302697) (xy 93.76346 -267.300716) (xy 93.812315 -267.306648) (xy 93.859586 -267.32034)
			(xy 93.904048 -267.341438) (xy 93.944551 -267.369394) (xy 93.980044 -267.403486) (xy 94.009609 -267.44283)
			(xy 94.03248 -267.486407) (xy 94.048064 -267.533088) (xy 94.055959 -267.581665) (xy 94.056454 -267.606272)
			(xy 94.374711 -267.606272) (xy 94.378806 -267.555544) (xy 94.390985 -267.50613) (xy 94.410933 -267.45931)
			(xy 94.438134 -267.416296) (xy 94.471882 -267.378202) (xy 94.511304 -267.346015) (xy 94.555378 -267.320569)
			(xy 94.602964 -267.302522) (xy 94.652828 -267.292342) (xy 94.70368 -267.290293) (xy 94.754201 -267.296427)
			(xy 94.803085 -267.310587) (xy 94.849064 -267.332404) (xy 94.890948 -267.361314) (xy 94.927652 -267.396569)
			(xy 94.958225 -267.437255) (xy 94.981876 -267.482318) (xy 94.997992 -267.530592) (xy 95.006156 -267.580826)
			(xy 95.006668 -267.606272) (xy 95.325196 -267.606272) (xy 95.329156 -267.557218) (xy 95.340933 -267.509434)
			(xy 95.360224 -267.464158) (xy 95.386527 -267.422562) (xy 95.419162 -267.385725) (xy 95.457283 -267.3546)
			(xy 95.499904 -267.329993) (xy 95.54592 -267.312541) (xy 95.594139 -267.302697) (xy 95.643314 -267.300716)
			(xy 95.692169 -267.306648) (xy 95.73944 -267.32034) (xy 95.783902 -267.341438) (xy 95.824405 -267.369394)
			(xy 95.859898 -267.403486) (xy 95.889463 -267.44283) (xy 95.912334 -267.486407) (xy 95.927918 -267.533088)
			(xy 95.935813 -267.581665) (xy 95.936308 -267.606272) (xy 96.26525 -267.606272) (xy 96.26921 -267.557218)
			(xy 96.280987 -267.509434) (xy 96.300278 -267.464158) (xy 96.326581 -267.422562) (xy 96.359216 -267.385725)
			(xy 96.397337 -267.3546) (xy 96.439958 -267.329993) (xy 96.485974 -267.312541) (xy 96.534193 -267.302697)
			(xy 96.583368 -267.300716) (xy 96.632223 -267.306648) (xy 96.679494 -267.32034) (xy 96.723956 -267.341438)
			(xy 96.764459 -267.369394) (xy 96.799952 -267.403486) (xy 96.829517 -267.44283) (xy 96.852388 -267.486407)
			(xy 96.867972 -267.533088) (xy 96.875867 -267.581665) (xy 96.876362 -267.606272) (xy 97.205304 -267.606272)
			(xy 97.209264 -267.557218) (xy 97.221041 -267.509434) (xy 97.240332 -267.464158) (xy 97.266635 -267.422562)
			(xy 97.29927 -267.385725) (xy 97.337391 -267.3546) (xy 97.380012 -267.329993) (xy 97.426028 -267.312541)
			(xy 97.474247 -267.302697) (xy 97.523422 -267.300716) (xy 97.572277 -267.306648) (xy 97.619548 -267.32034)
			(xy 97.66401 -267.341438) (xy 97.704513 -267.369394) (xy 97.740006 -267.403486) (xy 97.769571 -267.44283)
			(xy 97.792442 -267.486407) (xy 97.808026 -267.533088) (xy 97.815921 -267.581665) (xy 97.816416 -267.606272)
			(xy 98.145358 -267.606272) (xy 98.149318 -267.557218) (xy 98.161095 -267.509434) (xy 98.180386 -267.464158)
			(xy 98.206689 -267.422562) (xy 98.239324 -267.385725) (xy 98.277445 -267.3546) (xy 98.320066 -267.329993)
			(xy 98.366082 -267.312541) (xy 98.414301 -267.302697) (xy 98.463476 -267.300716) (xy 98.512331 -267.306648)
			(xy 98.559602 -267.32034) (xy 98.604064 -267.341438) (xy 98.644567 -267.369394) (xy 98.68006 -267.403486)
			(xy 98.709625 -267.44283) (xy 98.732496 -267.486407) (xy 98.74808 -267.533088) (xy 98.755975 -267.581665)
			(xy 98.75647 -267.606272) (xy 99.085158 -267.606272) (xy 99.089118 -267.557218) (xy 99.100895 -267.509434)
			(xy 99.120186 -267.464158) (xy 99.146489 -267.422562) (xy 99.179124 -267.385725) (xy 99.217245 -267.3546)
			(xy 99.259866 -267.329993) (xy 99.305882 -267.312541) (xy 99.354101 -267.302697) (xy 99.403276 -267.300716)
			(xy 99.452131 -267.306648) (xy 99.499402 -267.32034) (xy 99.543864 -267.341438) (xy 99.584367 -267.369394)
			(xy 99.61986 -267.403486) (xy 99.649425 -267.44283) (xy 99.672296 -267.486407) (xy 99.68788 -267.533088)
			(xy 99.695775 -267.581665) (xy 99.69627 -267.606272) (xy 100.025212 -267.606272) (xy 100.029172 -267.557218)
			(xy 100.040949 -267.509434) (xy 100.06024 -267.464158) (xy 100.086543 -267.422562) (xy 100.119178 -267.385725)
			(xy 100.157299 -267.3546) (xy 100.19992 -267.329993) (xy 100.245936 -267.312541) (xy 100.294155 -267.302697)
			(xy 100.34333 -267.300716) (xy 100.392185 -267.306648) (xy 100.439456 -267.32034) (xy 100.483918 -267.341438)
			(xy 100.524421 -267.369394) (xy 100.559914 -267.403486) (xy 100.589479 -267.44283) (xy 100.61235 -267.486407)
			(xy 100.627934 -267.533088) (xy 100.635829 -267.581665) (xy 100.636324 -267.606272) (xy 100.635829 -267.630879)
			(xy 100.627934 -267.679456) (xy 100.61235 -267.726137) (xy 100.589479 -267.769714) (xy 100.559914 -267.809058)
			(xy 100.524421 -267.84315) (xy 100.483918 -267.871106) (xy 100.439456 -267.892204) (xy 100.392185 -267.905896)
			(xy 100.34333 -267.911828) (xy 100.294155 -267.909847) (xy 100.245936 -267.900003) (xy 100.19992 -267.882551)
			(xy 100.157299 -267.857944) (xy 100.119178 -267.826819) (xy 100.086543 -267.789982) (xy 100.06024 -267.748386)
			(xy 100.040949 -267.70311) (xy 100.029172 -267.655326) (xy 100.025212 -267.606272) (xy 99.69627 -267.606272)
			(xy 99.695775 -267.630879) (xy 99.68788 -267.679456) (xy 99.672296 -267.726137) (xy 99.649425 -267.769714)
			(xy 99.61986 -267.809058) (xy 99.584367 -267.84315) (xy 99.543864 -267.871106) (xy 99.499402 -267.892204)
			(xy 99.452131 -267.905896) (xy 99.403276 -267.911828) (xy 99.354101 -267.909847) (xy 99.305882 -267.900003)
			(xy 99.259866 -267.882551) (xy 99.217245 -267.857944) (xy 99.179124 -267.826819) (xy 99.146489 -267.789982)
			(xy 99.120186 -267.748386) (xy 99.100895 -267.70311) (xy 99.089118 -267.655326) (xy 99.085158 -267.606272)
			(xy 98.75647 -267.606272) (xy 98.755975 -267.630879) (xy 98.74808 -267.679456) (xy 98.732496 -267.726137)
			(xy 98.709625 -267.769714) (xy 98.68006 -267.809058) (xy 98.644567 -267.84315) (xy 98.604064 -267.871106)
			(xy 98.559602 -267.892204) (xy 98.512331 -267.905896) (xy 98.463476 -267.911828) (xy 98.414301 -267.909847)
			(xy 98.366082 -267.900003) (xy 98.320066 -267.882551) (xy 98.277445 -267.857944) (xy 98.239324 -267.826819)
			(xy 98.206689 -267.789982) (xy 98.180386 -267.748386) (xy 98.161095 -267.70311) (xy 98.149318 -267.655326)
			(xy 98.145358 -267.606272) (xy 97.816416 -267.606272) (xy 97.815921 -267.630879) (xy 97.808026 -267.679456)
			(xy 97.792442 -267.726137) (xy 97.769571 -267.769714) (xy 97.740006 -267.809058) (xy 97.704513 -267.84315)
			(xy 97.66401 -267.871106) (xy 97.619548 -267.892204) (xy 97.572277 -267.905896) (xy 97.523422 -267.911828)
			(xy 97.474247 -267.909847) (xy 97.426028 -267.900003) (xy 97.380012 -267.882551) (xy 97.337391 -267.857944)
			(xy 97.29927 -267.826819) (xy 97.266635 -267.789982) (xy 97.240332 -267.748386) (xy 97.221041 -267.70311)
			(xy 97.209264 -267.655326) (xy 97.205304 -267.606272) (xy 96.876362 -267.606272) (xy 96.875867 -267.630879)
			(xy 96.867972 -267.679456) (xy 96.852388 -267.726137) (xy 96.829517 -267.769714) (xy 96.799952 -267.809058)
			(xy 96.764459 -267.84315) (xy 96.723956 -267.871106) (xy 96.679494 -267.892204) (xy 96.632223 -267.905896)
			(xy 96.583368 -267.911828) (xy 96.534193 -267.909847) (xy 96.485974 -267.900003) (xy 96.439958 -267.882551)
			(xy 96.397337 -267.857944) (xy 96.359216 -267.826819) (xy 96.326581 -267.789982) (xy 96.300278 -267.748386)
			(xy 96.280987 -267.70311) (xy 96.26921 -267.655326) (xy 96.26525 -267.606272) (xy 95.936308 -267.606272)
			(xy 95.935813 -267.630879) (xy 95.927918 -267.679456) (xy 95.912334 -267.726137) (xy 95.889463 -267.769714)
			(xy 95.859898 -267.809058) (xy 95.824405 -267.84315) (xy 95.783902 -267.871106) (xy 95.73944 -267.892204)
			(xy 95.692169 -267.905896) (xy 95.643314 -267.911828) (xy 95.594139 -267.909847) (xy 95.54592 -267.900003)
			(xy 95.499904 -267.882551) (xy 95.457283 -267.857944) (xy 95.419162 -267.826819) (xy 95.386527 -267.789982)
			(xy 95.360224 -267.748386) (xy 95.340933 -267.70311) (xy 95.329156 -267.655326) (xy 95.325196 -267.606272)
			(xy 95.006668 -267.606272) (xy 95.006156 -267.631718) (xy 94.997992 -267.681952) (xy 94.981876 -267.730226)
			(xy 94.958225 -267.775289) (xy 94.927652 -267.815975) (xy 94.890948 -267.85123) (xy 94.849064 -267.88014)
			(xy 94.803085 -267.901957) (xy 94.754201 -267.916117) (xy 94.70368 -267.922251) (xy 94.652828 -267.920202)
			(xy 94.602964 -267.910022) (xy 94.555378 -267.891975) (xy 94.511304 -267.866529) (xy 94.471882 -267.834342)
			(xy 94.438134 -267.796248) (xy 94.410933 -267.753234) (xy 94.390985 -267.706414) (xy 94.378806 -267.657)
			(xy 94.374711 -267.606272) (xy 94.056454 -267.606272) (xy 94.055959 -267.630879) (xy 94.048064 -267.679456)
			(xy 94.03248 -267.726137) (xy 94.009609 -267.769714) (xy 93.980044 -267.809058) (xy 93.944551 -267.84315)
			(xy 93.904048 -267.871106) (xy 93.859586 -267.892204) (xy 93.812315 -267.905896) (xy 93.76346 -267.911828)
			(xy 93.714285 -267.909847) (xy 93.666066 -267.900003) (xy 93.62005 -267.882551) (xy 93.577429 -267.857944)
			(xy 93.539308 -267.826819) (xy 93.506673 -267.789982) (xy 93.48037 -267.748386) (xy 93.461079 -267.70311)
			(xy 93.449302 -267.655326) (xy 93.445342 -267.606272) (xy 93.1164 -267.606272) (xy 93.115905 -267.630879)
			(xy 93.10801 -267.679456) (xy 93.092426 -267.726137) (xy 93.069555 -267.769714) (xy 93.03999 -267.809058)
			(xy 93.004497 -267.84315) (xy 92.963994 -267.871106) (xy 92.919532 -267.892204) (xy 92.872261 -267.905896)
			(xy 92.823406 -267.911828) (xy 92.774231 -267.909847) (xy 92.726012 -267.900003) (xy 92.679996 -267.882551)
			(xy 92.637375 -267.857944) (xy 92.599254 -267.826819) (xy 92.566619 -267.789982) (xy 92.540316 -267.748386)
			(xy 92.521025 -267.70311) (xy 92.509248 -267.655326) (xy 92.505288 -267.606272) (xy 92.176346 -267.606272)
			(xy 92.175851 -267.630879) (xy 92.167956 -267.679456) (xy 92.152372 -267.726137) (xy 92.129501 -267.769714)
			(xy 92.099936 -267.809058) (xy 92.064443 -267.84315) (xy 92.02394 -267.871106) (xy 91.979478 -267.892204)
			(xy 91.932207 -267.905896) (xy 91.883352 -267.911828) (xy 91.834177 -267.909847) (xy 91.785958 -267.900003)
			(xy 91.739942 -267.882551) (xy 91.697321 -267.857944) (xy 91.6592 -267.826819) (xy 91.626565 -267.789982)
			(xy 91.600262 -267.748386) (xy 91.580971 -267.70311) (xy 91.569194 -267.655326) (xy 91.565234 -267.606272)
			(xy 91.246706 -267.606272) (xy 91.246194 -267.631718) (xy 91.23803 -267.681952) (xy 91.221914 -267.730226)
			(xy 91.198263 -267.775289) (xy 91.16769 -267.815975) (xy 91.130986 -267.85123) (xy 91.089102 -267.88014)
			(xy 91.043123 -267.901957) (xy 90.994239 -267.916117) (xy 90.943718 -267.922251) (xy 90.892866 -267.920202)
			(xy 90.843002 -267.910022) (xy 90.795416 -267.891975) (xy 90.751342 -267.866529) (xy 90.71192 -267.834342)
			(xy 90.678172 -267.796248) (xy 90.650971 -267.753234) (xy 90.631023 -267.706414) (xy 90.618844 -267.657)
			(xy 90.614749 -267.606272) (xy 90.296238 -267.606272) (xy 90.295743 -267.630879) (xy 90.287848 -267.679456)
			(xy 90.272264 -267.726137) (xy 90.249393 -267.769714) (xy 90.219828 -267.809058) (xy 90.184335 -267.84315)
			(xy 90.143832 -267.871106) (xy 90.09937 -267.892204) (xy 90.052099 -267.905896) (xy 90.003244 -267.911828)
			(xy 89.954069 -267.909847) (xy 89.90585 -267.900003) (xy 89.859834 -267.882551) (xy 89.817213 -267.857944)
			(xy 89.779092 -267.826819) (xy 89.746457 -267.789982) (xy 89.720154 -267.748386) (xy 89.700863 -267.70311)
			(xy 89.689086 -267.655326) (xy 89.685126 -267.606272) (xy 89.356438 -267.606272) (xy 89.355943 -267.630879)
			(xy 89.348048 -267.679456) (xy 89.332464 -267.726137) (xy 89.309593 -267.769714) (xy 89.280028 -267.809058)
			(xy 89.244535 -267.84315) (xy 89.204032 -267.871106) (xy 89.15957 -267.892204) (xy 89.112299 -267.905896)
			(xy 89.063444 -267.911828) (xy 89.014269 -267.909847) (xy 88.96605 -267.900003) (xy 88.920034 -267.882551)
			(xy 88.877413 -267.857944) (xy 88.839292 -267.826819) (xy 88.806657 -267.789982) (xy 88.780354 -267.748386)
			(xy 88.761063 -267.70311) (xy 88.749286 -267.655326) (xy 88.745326 -267.606272) (xy 88.426798 -267.606272)
			(xy 88.426286 -267.631718) (xy 88.418122 -267.681952) (xy 88.402006 -267.730226) (xy 88.378355 -267.775289)
			(xy 88.347782 -267.815975) (xy 88.311078 -267.85123) (xy 88.269194 -267.88014) (xy 88.223215 -267.901957)
			(xy 88.174331 -267.916117) (xy 88.12381 -267.922251) (xy 88.072958 -267.920202) (xy 88.023094 -267.910022)
			(xy 87.975508 -267.891975) (xy 87.931434 -267.866529) (xy 87.892012 -267.834342) (xy 87.858264 -267.796248)
			(xy 87.831063 -267.753234) (xy 87.811115 -267.706414) (xy 87.798936 -267.657) (xy 87.794841 -267.606272)
			(xy 87.47633 -267.606272) (xy 87.475835 -267.630879) (xy 87.46794 -267.679456) (xy 87.452356 -267.726137)
			(xy 87.429485 -267.769714) (xy 87.39992 -267.809058) (xy 87.364427 -267.84315) (xy 87.323924 -267.871106)
			(xy 87.279462 -267.892204) (xy 87.232191 -267.905896) (xy 87.183336 -267.911828) (xy 87.134161 -267.909847)
			(xy 87.085942 -267.900003) (xy 87.039926 -267.882551) (xy 86.997305 -267.857944) (xy 86.959184 -267.826819)
			(xy 86.926549 -267.789982) (xy 86.900246 -267.748386) (xy 86.880955 -267.70311) (xy 86.869178 -267.655326)
			(xy 86.865218 -267.606272) (xy 86.536276 -267.606272) (xy 86.535781 -267.630879) (xy 86.527886 -267.679456)
			(xy 86.512302 -267.726137) (xy 86.489431 -267.769714) (xy 86.459866 -267.809058) (xy 86.424373 -267.84315)
			(xy 86.38387 -267.871106) (xy 86.339408 -267.892204) (xy 86.292137 -267.905896) (xy 86.243282 -267.911828)
			(xy 86.194107 -267.909847) (xy 86.145888 -267.900003) (xy 86.099872 -267.882551) (xy 86.057251 -267.857944)
			(xy 86.01913 -267.826819) (xy 85.986495 -267.789982) (xy 85.960192 -267.748386) (xy 85.940901 -267.70311)
			(xy 85.929124 -267.655326) (xy 85.925164 -267.606272) (xy 85.596222 -267.606272) (xy 85.595727 -267.630879)
			(xy 85.587832 -267.679456) (xy 85.572248 -267.726137) (xy 85.549377 -267.769714) (xy 85.519812 -267.809058)
			(xy 85.484319 -267.84315) (xy 85.443816 -267.871106) (xy 85.399354 -267.892204) (xy 85.352083 -267.905896)
			(xy 85.303228 -267.911828) (xy 85.254053 -267.909847) (xy 85.205834 -267.900003) (xy 85.159818 -267.882551)
			(xy 85.117197 -267.857944) (xy 85.079076 -267.826819) (xy 85.046441 -267.789982) (xy 85.020138 -267.748386)
			(xy 85.000847 -267.70311) (xy 84.98907 -267.655326) (xy 84.98511 -267.606272) (xy 84.666836 -267.606272)
			(xy 84.666324 -267.631718) (xy 84.65816 -267.681952) (xy 84.642044 -267.730226) (xy 84.618393 -267.775289)
			(xy 84.58782 -267.815975) (xy 84.551116 -267.85123) (xy 84.509232 -267.88014) (xy 84.463253 -267.901957)
			(xy 84.414369 -267.916117) (xy 84.363848 -267.922251) (xy 84.312996 -267.920202) (xy 84.263132 -267.910022)
			(xy 84.215546 -267.891975) (xy 84.171472 -267.866529) (xy 84.13205 -267.834342) (xy 84.098302 -267.796248)
			(xy 84.071101 -267.753234) (xy 84.051153 -267.706414) (xy 84.038974 -267.657) (xy 84.034879 -267.606272)
			(xy 83.716368 -267.606272) (xy 83.715873 -267.630879) (xy 83.707978 -267.679456) (xy 83.692394 -267.726137)
			(xy 83.669523 -267.769714) (xy 83.639958 -267.809058) (xy 83.604465 -267.84315) (xy 83.563962 -267.871106)
			(xy 83.5195 -267.892204) (xy 83.472229 -267.905896) (xy 83.423374 -267.911828) (xy 83.374199 -267.909847)
			(xy 83.32598 -267.900003) (xy 83.279964 -267.882551) (xy 83.237343 -267.857944) (xy 83.199222 -267.826819)
			(xy 83.166587 -267.789982) (xy 83.140284 -267.748386) (xy 83.120993 -267.70311) (xy 83.109216 -267.655326)
			(xy 83.105256 -267.606272) (xy 82.776314 -267.606272) (xy 82.775819 -267.630879) (xy 82.767924 -267.679456)
			(xy 82.75234 -267.726137) (xy 82.729469 -267.769714) (xy 82.699904 -267.809058) (xy 82.664411 -267.84315)
			(xy 82.623908 -267.871106) (xy 82.579446 -267.892204) (xy 82.532175 -267.905896) (xy 82.48332 -267.911828)
			(xy 82.434145 -267.909847) (xy 82.385926 -267.900003) (xy 82.33991 -267.882551) (xy 82.297289 -267.857944)
			(xy 82.259168 -267.826819) (xy 82.226533 -267.789982) (xy 82.20023 -267.748386) (xy 82.180939 -267.70311)
			(xy 82.169162 -267.655326) (xy 82.165202 -267.606272) (xy 81.846674 -267.606272) (xy 81.846162 -267.631718)
			(xy 81.837998 -267.681952) (xy 81.821882 -267.730226) (xy 81.798231 -267.775289) (xy 81.767658 -267.815975)
			(xy 81.730954 -267.85123) (xy 81.68907 -267.88014) (xy 81.643091 -267.901957) (xy 81.594207 -267.916117)
			(xy 81.543686 -267.922251) (xy 81.492834 -267.920202) (xy 81.44297 -267.910022) (xy 81.395384 -267.891975)
			(xy 81.35131 -267.866529) (xy 81.311888 -267.834342) (xy 81.27814 -267.796248) (xy 81.250939 -267.753234)
			(xy 81.230991 -267.706414) (xy 81.218812 -267.657) (xy 81.214717 -267.606272) (xy 80.89646 -267.606272)
			(xy 80.895965 -267.630879) (xy 80.88807 -267.679456) (xy 80.872486 -267.726137) (xy 80.849615 -267.769714)
			(xy 80.82005 -267.809058) (xy 80.784557 -267.84315) (xy 80.744054 -267.871106) (xy 80.699592 -267.892204)
			(xy 80.652321 -267.905896) (xy 80.603466 -267.911828) (xy 80.554291 -267.909847) (xy 80.506072 -267.900003)
			(xy 80.460056 -267.882551) (xy 80.417435 -267.857944) (xy 80.379314 -267.826819) (xy 80.346679 -267.789982)
			(xy 80.320376 -267.748386) (xy 80.301085 -267.70311) (xy 80.289308 -267.655326) (xy 80.285348 -267.606272)
			(xy 79.016352 -267.606272) (xy 79.015857 -267.630879) (xy 79.007962 -267.679456) (xy 78.992378 -267.726137)
			(xy 78.969507 -267.769714) (xy 78.939942 -267.809058) (xy 78.904449 -267.84315) (xy 78.863946 -267.871106)
			(xy 78.819484 -267.892204) (xy 78.772213 -267.905896) (xy 78.723358 -267.911828) (xy 78.674183 -267.909847)
			(xy 78.625964 -267.900003) (xy 78.579948 -267.882551) (xy 78.537327 -267.857944) (xy 78.499206 -267.826819)
			(xy 78.466571 -267.789982) (xy 78.440268 -267.748386) (xy 78.420977 -267.70311) (xy 78.4092 -267.655326)
			(xy 78.40524 -267.606272) (xy 73.228962 -267.606272) (xy 73.228962 -268.15034) (xy 76.807072 -268.15034)
			(xy 76.811032 -268.101286) (xy 76.822809 -268.053502) (xy 76.8421 -268.008226) (xy 76.868403 -267.96663)
			(xy 76.901038 -267.929793) (xy 76.939159 -267.898668) (xy 76.98178 -267.874061) (xy 77.027796 -267.856609)
			(xy 77.076015 -267.846765) (xy 77.12519 -267.844784) (xy 77.174045 -267.850716) (xy 77.221316 -267.864408)
			(xy 77.265778 -267.885506) (xy 77.306281 -267.913462) (xy 77.341774 -267.947554) (xy 77.371339 -267.986898)
			(xy 77.381267 -268.005814) (xy 111.710473 -268.005814) (xy 111.714503 -267.953316) (xy 111.7265 -267.902048)
			(xy 111.746183 -267.853213) (xy 111.773089 -267.807954) (xy 111.806589 -267.767333) (xy 111.845897 -267.732302)
			(xy 111.890092 -267.703682) (xy 111.938137 -267.682143) (xy 111.988908 -267.668191) (xy 112.041213 -267.662153)
			(xy 112.093827 -267.66417) (xy 112.145517 -267.674194) (xy 112.19507 -267.691992) (xy 112.241326 -267.717145)
			(xy 112.2832 -267.749064) (xy 112.319712 -267.787002) (xy 112.350004 -267.830068) (xy 112.373367 -267.877253)
			(xy 112.389253 -267.927452) (xy 112.39729 -267.979488) (xy 112.397794 -268.005814) (xy 112.39729 -268.03214)
			(xy 112.389253 -268.084176) (xy 112.373367 -268.134375) (xy 112.350004 -268.18156) (xy 112.319712 -268.224626)
			(xy 112.2832 -268.262564) (xy 112.241326 -268.294483) (xy 112.19507 -268.319636) (xy 112.145517 -268.337434)
			(xy 112.093827 -268.347458) (xy 112.041213 -268.349475) (xy 111.988908 -268.343437) (xy 111.938137 -268.329485)
			(xy 111.890092 -268.307946) (xy 111.845897 -268.279326) (xy 111.806589 -268.244295) (xy 111.773089 -268.203674)
			(xy 111.746183 -268.158415) (xy 111.7265 -268.10958) (xy 111.714503 -268.058312) (xy 111.710473 -268.005814)
			(xy 77.381267 -268.005814) (xy 77.39421 -268.030475) (xy 77.409794 -268.077156) (xy 77.417689 -268.125733)
			(xy 77.418184 -268.15034) (xy 77.417689 -268.174947) (xy 77.409794 -268.223524) (xy 77.39421 -268.270205)
			(xy 77.371339 -268.313782) (xy 77.341774 -268.353126) (xy 77.306281 -268.387218) (xy 77.265778 -268.415174)
			(xy 77.263451 -268.416278) (xy 78.87514 -268.416278) (xy 78.8791 -268.367224) (xy 78.890877 -268.31944)
			(xy 78.910168 -268.274164) (xy 78.936471 -268.232568) (xy 78.969106 -268.195731) (xy 79.007227 -268.164606)
			(xy 79.049848 -268.139999) (xy 79.095864 -268.122547) (xy 79.144083 -268.112703) (xy 79.193258 -268.110722)
			(xy 79.242113 -268.116654) (xy 79.289384 -268.130346) (xy 79.333846 -268.151444) (xy 79.374349 -268.1794)
			(xy 79.409842 -268.213492) (xy 79.439407 -268.252836) (xy 79.462278 -268.296413) (xy 79.477862 -268.343094)
			(xy 79.485757 -268.391671) (xy 79.486252 -268.416278) (xy 79.815194 -268.416278) (xy 79.819154 -268.367224)
			(xy 79.830931 -268.31944) (xy 79.850222 -268.274164) (xy 79.876525 -268.232568) (xy 79.90916 -268.195731)
			(xy 79.947281 -268.164606) (xy 79.989902 -268.139999) (xy 80.035918 -268.122547) (xy 80.084137 -268.112703)
			(xy 80.133312 -268.110722) (xy 80.182167 -268.116654) (xy 80.229438 -268.130346) (xy 80.2739 -268.151444)
			(xy 80.314403 -268.1794) (xy 80.349896 -268.213492) (xy 80.379461 -268.252836) (xy 80.402332 -268.296413)
			(xy 80.417916 -268.343094) (xy 80.425811 -268.391671) (xy 80.426306 -268.416278) (xy 80.755248 -268.416278)
			(xy 80.759208 -268.367224) (xy 80.770985 -268.31944) (xy 80.790276 -268.274164) (xy 80.816579 -268.232568)
			(xy 80.849214 -268.195731) (xy 80.887335 -268.164606) (xy 80.929956 -268.139999) (xy 80.975972 -268.122547)
			(xy 81.024191 -268.112703) (xy 81.073366 -268.110722) (xy 81.122221 -268.116654) (xy 81.169492 -268.130346)
			(xy 81.213954 -268.151444) (xy 81.254457 -268.1794) (xy 81.28995 -268.213492) (xy 81.319515 -268.252836)
			(xy 81.342386 -268.296413) (xy 81.35797 -268.343094) (xy 81.365865 -268.391671) (xy 81.36636 -268.416278)
			(xy 81.695302 -268.416278) (xy 81.699262 -268.367224) (xy 81.711039 -268.31944) (xy 81.73033 -268.274164)
			(xy 81.756633 -268.232568) (xy 81.789268 -268.195731) (xy 81.827389 -268.164606) (xy 81.87001 -268.139999)
			(xy 81.916026 -268.122547) (xy 81.964245 -268.112703) (xy 82.01342 -268.110722) (xy 82.062275 -268.116654)
			(xy 82.109546 -268.130346) (xy 82.154008 -268.151444) (xy 82.194511 -268.1794) (xy 82.230004 -268.213492)
			(xy 82.259569 -268.252836) (xy 82.28244 -268.296413) (xy 82.298024 -268.343094) (xy 82.305919 -268.391671)
			(xy 82.306414 -268.416278) (xy 82.635102 -268.416278) (xy 82.639062 -268.367224) (xy 82.650839 -268.31944)
			(xy 82.67013 -268.274164) (xy 82.696433 -268.232568) (xy 82.729068 -268.195731) (xy 82.767189 -268.164606)
			(xy 82.80981 -268.139999) (xy 82.855826 -268.122547) (xy 82.904045 -268.112703) (xy 82.95322 -268.110722)
			(xy 83.002075 -268.116654) (xy 83.049346 -268.130346) (xy 83.093808 -268.151444) (xy 83.134311 -268.1794)
			(xy 83.169804 -268.213492) (xy 83.199369 -268.252836) (xy 83.22224 -268.296413) (xy 83.237824 -268.343094)
			(xy 83.245719 -268.391671) (xy 83.246214 -268.416278) (xy 83.575156 -268.416278) (xy 83.579116 -268.367224)
			(xy 83.590893 -268.31944) (xy 83.610184 -268.274164) (xy 83.636487 -268.232568) (xy 83.669122 -268.195731)
			(xy 83.707243 -268.164606) (xy 83.749864 -268.139999) (xy 83.79588 -268.122547) (xy 83.844099 -268.112703)
			(xy 83.893274 -268.110722) (xy 83.942129 -268.116654) (xy 83.9894 -268.130346) (xy 84.033862 -268.151444)
			(xy 84.074365 -268.1794) (xy 84.109858 -268.213492) (xy 84.139423 -268.252836) (xy 84.162294 -268.296413)
			(xy 84.177878 -268.343094) (xy 84.185773 -268.391671) (xy 84.186268 -268.416278) (xy 84.51521 -268.416278)
			(xy 84.51917 -268.367224) (xy 84.530947 -268.31944) (xy 84.550238 -268.274164) (xy 84.576541 -268.232568)
			(xy 84.609176 -268.195731) (xy 84.647297 -268.164606) (xy 84.689918 -268.139999) (xy 84.735934 -268.122547)
			(xy 84.784153 -268.112703) (xy 84.833328 -268.110722) (xy 84.882183 -268.116654) (xy 84.929454 -268.130346)
			(xy 84.973916 -268.151444) (xy 85.014419 -268.1794) (xy 85.049912 -268.213492) (xy 85.079477 -268.252836)
			(xy 85.102348 -268.296413) (xy 85.117932 -268.343094) (xy 85.125827 -268.391671) (xy 85.126322 -268.416278)
			(xy 85.455264 -268.416278) (xy 85.459224 -268.367224) (xy 85.471001 -268.31944) (xy 85.490292 -268.274164)
			(xy 85.516595 -268.232568) (xy 85.54923 -268.195731) (xy 85.587351 -268.164606) (xy 85.629972 -268.139999)
			(xy 85.675988 -268.122547) (xy 85.724207 -268.112703) (xy 85.773382 -268.110722) (xy 85.822237 -268.116654)
			(xy 85.869508 -268.130346) (xy 85.91397 -268.151444) (xy 85.954473 -268.1794) (xy 85.989966 -268.213492)
			(xy 86.019531 -268.252836) (xy 86.042402 -268.296413) (xy 86.057986 -268.343094) (xy 86.065881 -268.391671)
			(xy 86.066376 -268.416278) (xy 86.395318 -268.416278) (xy 86.399278 -268.367224) (xy 86.411055 -268.31944)
			(xy 86.430346 -268.274164) (xy 86.456649 -268.232568) (xy 86.489284 -268.195731) (xy 86.527405 -268.164606)
			(xy 86.570026 -268.139999) (xy 86.616042 -268.122547) (xy 86.664261 -268.112703) (xy 86.713436 -268.110722)
			(xy 86.762291 -268.116654) (xy 86.809562 -268.130346) (xy 86.854024 -268.151444) (xy 86.894527 -268.1794)
			(xy 86.93002 -268.213492) (xy 86.959585 -268.252836) (xy 86.982456 -268.296413) (xy 86.99804 -268.343094)
			(xy 87.005935 -268.391671) (xy 87.00643 -268.416278) (xy 87.335118 -268.416278) (xy 87.339078 -268.367224)
			(xy 87.350855 -268.31944) (xy 87.370146 -268.274164) (xy 87.396449 -268.232568) (xy 87.429084 -268.195731)
			(xy 87.467205 -268.164606) (xy 87.509826 -268.139999) (xy 87.555842 -268.122547) (xy 87.604061 -268.112703)
			(xy 87.653236 -268.110722) (xy 87.702091 -268.116654) (xy 87.749362 -268.130346) (xy 87.793824 -268.151444)
			(xy 87.834327 -268.1794) (xy 87.86982 -268.213492) (xy 87.899385 -268.252836) (xy 87.922256 -268.296413)
			(xy 87.93784 -268.343094) (xy 87.945735 -268.391671) (xy 87.94623 -268.416278) (xy 88.275172 -268.416278)
			(xy 88.279132 -268.367224) (xy 88.290909 -268.31944) (xy 88.3102 -268.274164) (xy 88.336503 -268.232568)
			(xy 88.369138 -268.195731) (xy 88.407259 -268.164606) (xy 88.44988 -268.139999) (xy 88.495896 -268.122547)
			(xy 88.544115 -268.112703) (xy 88.59329 -268.110722) (xy 88.642145 -268.116654) (xy 88.689416 -268.130346)
			(xy 88.733878 -268.151444) (xy 88.774381 -268.1794) (xy 88.809874 -268.213492) (xy 88.839439 -268.252836)
			(xy 88.86231 -268.296413) (xy 88.877894 -268.343094) (xy 88.885789 -268.391671) (xy 88.886284 -268.416278)
			(xy 89.215226 -268.416278) (xy 89.219186 -268.367224) (xy 89.230963 -268.31944) (xy 89.250254 -268.274164)
			(xy 89.276557 -268.232568) (xy 89.309192 -268.195731) (xy 89.347313 -268.164606) (xy 89.389934 -268.139999)
			(xy 89.43595 -268.122547) (xy 89.484169 -268.112703) (xy 89.533344 -268.110722) (xy 89.582199 -268.116654)
			(xy 89.62947 -268.130346) (xy 89.673932 -268.151444) (xy 89.714435 -268.1794) (xy 89.749928 -268.213492)
			(xy 89.779493 -268.252836) (xy 89.802364 -268.296413) (xy 89.817948 -268.343094) (xy 89.825843 -268.391671)
			(xy 89.826338 -268.416278) (xy 90.15528 -268.416278) (xy 90.15924 -268.367224) (xy 90.171017 -268.31944)
			(xy 90.190308 -268.274164) (xy 90.216611 -268.232568) (xy 90.249246 -268.195731) (xy 90.287367 -268.164606)
			(xy 90.329988 -268.139999) (xy 90.376004 -268.122547) (xy 90.424223 -268.112703) (xy 90.473398 -268.110722)
			(xy 90.522253 -268.116654) (xy 90.569524 -268.130346) (xy 90.613986 -268.151444) (xy 90.654489 -268.1794)
			(xy 90.689982 -268.213492) (xy 90.719547 -268.252836) (xy 90.742418 -268.296413) (xy 90.758002 -268.343094)
			(xy 90.765897 -268.391671) (xy 90.766392 -268.416278) (xy 91.095334 -268.416278) (xy 91.099294 -268.367224)
			(xy 91.111071 -268.31944) (xy 91.130362 -268.274164) (xy 91.156665 -268.232568) (xy 91.1893 -268.195731)
			(xy 91.227421 -268.164606) (xy 91.270042 -268.139999) (xy 91.316058 -268.122547) (xy 91.364277 -268.112703)
			(xy 91.413452 -268.110722) (xy 91.462307 -268.116654) (xy 91.509578 -268.130346) (xy 91.55404 -268.151444)
			(xy 91.594543 -268.1794) (xy 91.630036 -268.213492) (xy 91.659601 -268.252836) (xy 91.682472 -268.296413)
			(xy 91.698056 -268.343094) (xy 91.705951 -268.391671) (xy 91.706446 -268.416278) (xy 92.035134 -268.416278)
			(xy 92.039094 -268.367224) (xy 92.050871 -268.31944) (xy 92.070162 -268.274164) (xy 92.096465 -268.232568)
			(xy 92.1291 -268.195731) (xy 92.167221 -268.164606) (xy 92.209842 -268.139999) (xy 92.255858 -268.122547)
			(xy 92.304077 -268.112703) (xy 92.353252 -268.110722) (xy 92.402107 -268.116654) (xy 92.449378 -268.130346)
			(xy 92.49384 -268.151444) (xy 92.534343 -268.1794) (xy 92.569836 -268.213492) (xy 92.599401 -268.252836)
			(xy 92.622272 -268.296413) (xy 92.637856 -268.343094) (xy 92.645751 -268.391671) (xy 92.646246 -268.416278)
			(xy 92.975188 -268.416278) (xy 92.979148 -268.367224) (xy 92.990925 -268.31944) (xy 93.010216 -268.274164)
			(xy 93.036519 -268.232568) (xy 93.069154 -268.195731) (xy 93.107275 -268.164606) (xy 93.149896 -268.139999)
			(xy 93.195912 -268.122547) (xy 93.244131 -268.112703) (xy 93.293306 -268.110722) (xy 93.342161 -268.116654)
			(xy 93.389432 -268.130346) (xy 93.433894 -268.151444) (xy 93.474397 -268.1794) (xy 93.50989 -268.213492)
			(xy 93.539455 -268.252836) (xy 93.562326 -268.296413) (xy 93.57791 -268.343094) (xy 93.585805 -268.391671)
			(xy 93.5863 -268.416278) (xy 93.915242 -268.416278) (xy 93.919202 -268.367224) (xy 93.930979 -268.31944)
			(xy 93.95027 -268.274164) (xy 93.976573 -268.232568) (xy 94.009208 -268.195731) (xy 94.047329 -268.164606)
			(xy 94.08995 -268.139999) (xy 94.135966 -268.122547) (xy 94.184185 -268.112703) (xy 94.23336 -268.110722)
			(xy 94.282215 -268.116654) (xy 94.329486 -268.130346) (xy 94.373948 -268.151444) (xy 94.414451 -268.1794)
			(xy 94.449944 -268.213492) (xy 94.479509 -268.252836) (xy 94.50238 -268.296413) (xy 94.517964 -268.343094)
			(xy 94.525859 -268.391671) (xy 94.526354 -268.416278) (xy 94.855296 -268.416278) (xy 94.859256 -268.367224)
			(xy 94.871033 -268.31944) (xy 94.890324 -268.274164) (xy 94.916627 -268.232568) (xy 94.949262 -268.195731)
			(xy 94.987383 -268.164606) (xy 95.030004 -268.139999) (xy 95.07602 -268.122547) (xy 95.124239 -268.112703)
			(xy 95.173414 -268.110722) (xy 95.222269 -268.116654) (xy 95.26954 -268.130346) (xy 95.314002 -268.151444)
			(xy 95.354505 -268.1794) (xy 95.389998 -268.213492) (xy 95.419563 -268.252836) (xy 95.442434 -268.296413)
			(xy 95.458018 -268.343094) (xy 95.465913 -268.391671) (xy 95.466408 -268.416278) (xy 95.79535 -268.416278)
			(xy 95.79931 -268.367224) (xy 95.811087 -268.31944) (xy 95.830378 -268.274164) (xy 95.856681 -268.232568)
			(xy 95.889316 -268.195731) (xy 95.927437 -268.164606) (xy 95.970058 -268.139999) (xy 96.016074 -268.122547)
			(xy 96.064293 -268.112703) (xy 96.113468 -268.110722) (xy 96.162323 -268.116654) (xy 96.209594 -268.130346)
			(xy 96.254056 -268.151444) (xy 96.294559 -268.1794) (xy 96.330052 -268.213492) (xy 96.359617 -268.252836)
			(xy 96.382488 -268.296413) (xy 96.398072 -268.343094) (xy 96.405967 -268.391671) (xy 96.406462 -268.416278)
			(xy 96.73515 -268.416278) (xy 96.73911 -268.367224) (xy 96.750887 -268.31944) (xy 96.770178 -268.274164)
			(xy 96.796481 -268.232568) (xy 96.829116 -268.195731) (xy 96.867237 -268.164606) (xy 96.909858 -268.139999)
			(xy 96.955874 -268.122547) (xy 97.004093 -268.112703) (xy 97.053268 -268.110722) (xy 97.102123 -268.116654)
			(xy 97.149394 -268.130346) (xy 97.193856 -268.151444) (xy 97.234359 -268.1794) (xy 97.269852 -268.213492)
			(xy 97.299417 -268.252836) (xy 97.322288 -268.296413) (xy 97.337872 -268.343094) (xy 97.345767 -268.391671)
			(xy 97.346262 -268.416278) (xy 97.675204 -268.416278) (xy 97.679164 -268.367224) (xy 97.690941 -268.31944)
			(xy 97.710232 -268.274164) (xy 97.736535 -268.232568) (xy 97.76917 -268.195731) (xy 97.807291 -268.164606)
			(xy 97.849912 -268.139999) (xy 97.895928 -268.122547) (xy 97.944147 -268.112703) (xy 97.993322 -268.110722)
			(xy 98.042177 -268.116654) (xy 98.089448 -268.130346) (xy 98.13391 -268.151444) (xy 98.174413 -268.1794)
			(xy 98.209906 -268.213492) (xy 98.239471 -268.252836) (xy 98.262342 -268.296413) (xy 98.277926 -268.343094)
			(xy 98.285821 -268.391671) (xy 98.286316 -268.416278) (xy 99.555312 -268.416278) (xy 99.559272 -268.367224)
			(xy 99.571049 -268.31944) (xy 99.59034 -268.274164) (xy 99.616643 -268.232568) (xy 99.649278 -268.195731)
			(xy 99.687399 -268.164606) (xy 99.73002 -268.139999) (xy 99.776036 -268.122547) (xy 99.824255 -268.112703)
			(xy 99.87343 -268.110722) (xy 99.922285 -268.116654) (xy 99.969556 -268.130346) (xy 100.014018 -268.151444)
			(xy 100.054521 -268.1794) (xy 100.090014 -268.213492) (xy 100.119579 -268.252836) (xy 100.14245 -268.296413)
			(xy 100.158034 -268.343094) (xy 100.165929 -268.391671) (xy 100.166424 -268.416278) (xy 101.435166 -268.416278)
			(xy 101.439126 -268.367224) (xy 101.450903 -268.31944) (xy 101.470194 -268.274164) (xy 101.496497 -268.232568)
			(xy 101.529132 -268.195731) (xy 101.567253 -268.164606) (xy 101.609874 -268.139999) (xy 101.65589 -268.122547)
			(xy 101.704109 -268.112703) (xy 101.753284 -268.110722) (xy 101.802139 -268.116654) (xy 101.84941 -268.130346)
			(xy 101.893872 -268.151444) (xy 101.934375 -268.1794) (xy 101.969868 -268.213492) (xy 101.999433 -268.252836)
			(xy 102.022304 -268.296413) (xy 102.037888 -268.343094) (xy 102.045783 -268.391671) (xy 102.046278 -268.416278)
			(xy 103.315274 -268.416278) (xy 103.319234 -268.367224) (xy 103.331011 -268.31944) (xy 103.350302 -268.274164)
			(xy 103.376605 -268.232568) (xy 103.40924 -268.195731) (xy 103.447361 -268.164606) (xy 103.489982 -268.139999)
			(xy 103.535998 -268.122547) (xy 103.584217 -268.112703) (xy 103.633392 -268.110722) (xy 103.682247 -268.116654)
			(xy 103.729518 -268.130346) (xy 103.77398 -268.151444) (xy 103.814483 -268.1794) (xy 103.849976 -268.213492)
			(xy 103.879541 -268.252836) (xy 103.902412 -268.296413) (xy 103.917996 -268.343094) (xy 103.925891 -268.391671)
			(xy 103.926386 -268.416278) (xy 105.195128 -268.416278) (xy 105.199088 -268.367224) (xy 105.210865 -268.31944)
			(xy 105.230156 -268.274164) (xy 105.256459 -268.232568) (xy 105.289094 -268.195731) (xy 105.327215 -268.164606)
			(xy 105.369836 -268.139999) (xy 105.415852 -268.122547) (xy 105.464071 -268.112703) (xy 105.513246 -268.110722)
			(xy 105.562101 -268.116654) (xy 105.609372 -268.130346) (xy 105.653834 -268.151444) (xy 105.694337 -268.1794)
			(xy 105.72983 -268.213492) (xy 105.759395 -268.252836) (xy 105.782266 -268.296413) (xy 105.79785 -268.343094)
			(xy 105.805745 -268.391671) (xy 105.80624 -268.416278) (xy 107.075236 -268.416278) (xy 107.079196 -268.367224)
			(xy 107.090973 -268.31944) (xy 107.110264 -268.274164) (xy 107.136567 -268.232568) (xy 107.169202 -268.195731)
			(xy 107.207323 -268.164606) (xy 107.249944 -268.139999) (xy 107.29596 -268.122547) (xy 107.344179 -268.112703)
			(xy 107.393354 -268.110722) (xy 107.442209 -268.116654) (xy 107.48948 -268.130346) (xy 107.533942 -268.151444)
			(xy 107.574445 -268.1794) (xy 107.609938 -268.213492) (xy 107.639503 -268.252836) (xy 107.662374 -268.296413)
			(xy 107.677958 -268.343094) (xy 107.685853 -268.391671) (xy 107.686348 -268.416278) (xy 107.685853 -268.440885)
			(xy 107.677958 -268.489462) (xy 107.662374 -268.536143) (xy 107.639503 -268.57972) (xy 107.609938 -268.619064)
			(xy 107.574445 -268.653156) (xy 107.533942 -268.681112) (xy 107.48948 -268.70221) (xy 107.442209 -268.715902)
			(xy 107.393354 -268.721834) (xy 107.344179 -268.719853) (xy 107.29596 -268.710009) (xy 107.249944 -268.692557)
			(xy 107.207323 -268.66795) (xy 107.169202 -268.636825) (xy 107.136567 -268.599988) (xy 107.110264 -268.558392)
			(xy 107.090973 -268.513116) (xy 107.079196 -268.465332) (xy 107.075236 -268.416278) (xy 105.80624 -268.416278)
			(xy 105.805745 -268.440885) (xy 105.79785 -268.489462) (xy 105.782266 -268.536143) (xy 105.759395 -268.57972)
			(xy 105.72983 -268.619064) (xy 105.694337 -268.653156) (xy 105.653834 -268.681112) (xy 105.609372 -268.70221)
			(xy 105.562101 -268.715902) (xy 105.513246 -268.721834) (xy 105.464071 -268.719853) (xy 105.415852 -268.710009)
			(xy 105.369836 -268.692557) (xy 105.327215 -268.66795) (xy 105.289094 -268.636825) (xy 105.256459 -268.599988)
			(xy 105.230156 -268.558392) (xy 105.210865 -268.513116) (xy 105.199088 -268.465332) (xy 105.195128 -268.416278)
			(xy 103.926386 -268.416278) (xy 103.925891 -268.440885) (xy 103.917996 -268.489462) (xy 103.902412 -268.536143)
			(xy 103.879541 -268.57972) (xy 103.849976 -268.619064) (xy 103.814483 -268.653156) (xy 103.77398 -268.681112)
			(xy 103.729518 -268.70221) (xy 103.682247 -268.715902) (xy 103.633392 -268.721834) (xy 103.584217 -268.719853)
			(xy 103.535998 -268.710009) (xy 103.489982 -268.692557) (xy 103.447361 -268.66795) (xy 103.40924 -268.636825)
			(xy 103.376605 -268.599988) (xy 103.350302 -268.558392) (xy 103.331011 -268.513116) (xy 103.319234 -268.465332)
			(xy 103.315274 -268.416278) (xy 102.046278 -268.416278) (xy 102.045783 -268.440885) (xy 102.037888 -268.489462)
			(xy 102.022304 -268.536143) (xy 101.999433 -268.57972) (xy 101.969868 -268.619064) (xy 101.934375 -268.653156)
			(xy 101.893872 -268.681112) (xy 101.84941 -268.70221) (xy 101.802139 -268.715902) (xy 101.753284 -268.721834)
			(xy 101.704109 -268.719853) (xy 101.65589 -268.710009) (xy 101.609874 -268.692557) (xy 101.567253 -268.66795)
			(xy 101.529132 -268.636825) (xy 101.496497 -268.599988) (xy 101.470194 -268.558392) (xy 101.450903 -268.513116)
			(xy 101.439126 -268.465332) (xy 101.435166 -268.416278) (xy 100.166424 -268.416278) (xy 100.165929 -268.440885)
			(xy 100.158034 -268.489462) (xy 100.14245 -268.536143) (xy 100.119579 -268.57972) (xy 100.090014 -268.619064)
			(xy 100.054521 -268.653156) (xy 100.014018 -268.681112) (xy 99.969556 -268.70221) (xy 99.922285 -268.715902)
			(xy 99.87343 -268.721834) (xy 99.824255 -268.719853) (xy 99.776036 -268.710009) (xy 99.73002 -268.692557)
			(xy 99.687399 -268.66795) (xy 99.649278 -268.636825) (xy 99.616643 -268.599988) (xy 99.59034 -268.558392)
			(xy 99.571049 -268.513116) (xy 99.559272 -268.465332) (xy 99.555312 -268.416278) (xy 98.286316 -268.416278)
			(xy 98.285821 -268.440885) (xy 98.277926 -268.489462) (xy 98.262342 -268.536143) (xy 98.239471 -268.57972)
			(xy 98.209906 -268.619064) (xy 98.174413 -268.653156) (xy 98.13391 -268.681112) (xy 98.089448 -268.70221)
			(xy 98.042177 -268.715902) (xy 97.993322 -268.721834) (xy 97.944147 -268.719853) (xy 97.895928 -268.710009)
			(xy 97.849912 -268.692557) (xy 97.807291 -268.66795) (xy 97.76917 -268.636825) (xy 97.736535 -268.599988)
			(xy 97.710232 -268.558392) (xy 97.690941 -268.513116) (xy 97.679164 -268.465332) (xy 97.675204 -268.416278)
			(xy 97.346262 -268.416278) (xy 97.345767 -268.440885) (xy 97.337872 -268.489462) (xy 97.322288 -268.536143)
			(xy 97.299417 -268.57972) (xy 97.269852 -268.619064) (xy 97.234359 -268.653156) (xy 97.193856 -268.681112)
			(xy 97.149394 -268.70221) (xy 97.102123 -268.715902) (xy 97.053268 -268.721834) (xy 97.004093 -268.719853)
			(xy 96.955874 -268.710009) (xy 96.909858 -268.692557) (xy 96.867237 -268.66795) (xy 96.829116 -268.636825)
			(xy 96.796481 -268.599988) (xy 96.770178 -268.558392) (xy 96.750887 -268.513116) (xy 96.73911 -268.465332)
			(xy 96.73515 -268.416278) (xy 96.406462 -268.416278) (xy 96.405967 -268.440885) (xy 96.398072 -268.489462)
			(xy 96.382488 -268.536143) (xy 96.359617 -268.57972) (xy 96.330052 -268.619064) (xy 96.294559 -268.653156)
			(xy 96.254056 -268.681112) (xy 96.209594 -268.70221) (xy 96.162323 -268.715902) (xy 96.113468 -268.721834)
			(xy 96.064293 -268.719853) (xy 96.016074 -268.710009) (xy 95.970058 -268.692557) (xy 95.927437 -268.66795)
			(xy 95.889316 -268.636825) (xy 95.856681 -268.599988) (xy 95.830378 -268.558392) (xy 95.811087 -268.513116)
			(xy 95.79931 -268.465332) (xy 95.79535 -268.416278) (xy 95.466408 -268.416278) (xy 95.465913 -268.440885)
			(xy 95.458018 -268.489462) (xy 95.442434 -268.536143) (xy 95.419563 -268.57972) (xy 95.389998 -268.619064)
			(xy 95.354505 -268.653156) (xy 95.314002 -268.681112) (xy 95.26954 -268.70221) (xy 95.222269 -268.715902)
			(xy 95.173414 -268.721834) (xy 95.124239 -268.719853) (xy 95.07602 -268.710009) (xy 95.030004 -268.692557)
			(xy 94.987383 -268.66795) (xy 94.949262 -268.636825) (xy 94.916627 -268.599988) (xy 94.890324 -268.558392)
			(xy 94.871033 -268.513116) (xy 94.859256 -268.465332) (xy 94.855296 -268.416278) (xy 94.526354 -268.416278)
			(xy 94.525859 -268.440885) (xy 94.517964 -268.489462) (xy 94.50238 -268.536143) (xy 94.479509 -268.57972)
			(xy 94.449944 -268.619064) (xy 94.414451 -268.653156) (xy 94.373948 -268.681112) (xy 94.329486 -268.70221)
			(xy 94.282215 -268.715902) (xy 94.23336 -268.721834) (xy 94.184185 -268.719853) (xy 94.135966 -268.710009)
			(xy 94.08995 -268.692557) (xy 94.047329 -268.66795) (xy 94.009208 -268.636825) (xy 93.976573 -268.599988)
			(xy 93.95027 -268.558392) (xy 93.930979 -268.513116) (xy 93.919202 -268.465332) (xy 93.915242 -268.416278)
			(xy 93.5863 -268.416278) (xy 93.585805 -268.440885) (xy 93.57791 -268.489462) (xy 93.562326 -268.536143)
			(xy 93.539455 -268.57972) (xy 93.50989 -268.619064) (xy 93.474397 -268.653156) (xy 93.433894 -268.681112)
			(xy 93.389432 -268.70221) (xy 93.342161 -268.715902) (xy 93.293306 -268.721834) (xy 93.244131 -268.719853)
			(xy 93.195912 -268.710009) (xy 93.149896 -268.692557) (xy 93.107275 -268.66795) (xy 93.069154 -268.636825)
			(xy 93.036519 -268.599988) (xy 93.010216 -268.558392) (xy 92.990925 -268.513116) (xy 92.979148 -268.465332)
			(xy 92.975188 -268.416278) (xy 92.646246 -268.416278) (xy 92.645751 -268.440885) (xy 92.637856 -268.489462)
			(xy 92.622272 -268.536143) (xy 92.599401 -268.57972) (xy 92.569836 -268.619064) (xy 92.534343 -268.653156)
			(xy 92.49384 -268.681112) (xy 92.449378 -268.70221) (xy 92.402107 -268.715902) (xy 92.353252 -268.721834)
			(xy 92.304077 -268.719853) (xy 92.255858 -268.710009) (xy 92.209842 -268.692557) (xy 92.167221 -268.66795)
			(xy 92.1291 -268.636825) (xy 92.096465 -268.599988) (xy 92.070162 -268.558392) (xy 92.050871 -268.513116)
			(xy 92.039094 -268.465332) (xy 92.035134 -268.416278) (xy 91.706446 -268.416278) (xy 91.705951 -268.440885)
			(xy 91.698056 -268.489462) (xy 91.682472 -268.536143) (xy 91.659601 -268.57972) (xy 91.630036 -268.619064)
			(xy 91.594543 -268.653156) (xy 91.55404 -268.681112) (xy 91.509578 -268.70221) (xy 91.462307 -268.715902)
			(xy 91.413452 -268.721834) (xy 91.364277 -268.719853) (xy 91.316058 -268.710009) (xy 91.270042 -268.692557)
			(xy 91.227421 -268.66795) (xy 91.1893 -268.636825) (xy 91.156665 -268.599988) (xy 91.130362 -268.558392)
			(xy 91.111071 -268.513116) (xy 91.099294 -268.465332) (xy 91.095334 -268.416278) (xy 90.766392 -268.416278)
			(xy 90.765897 -268.440885) (xy 90.758002 -268.489462) (xy 90.742418 -268.536143) (xy 90.719547 -268.57972)
			(xy 90.689982 -268.619064) (xy 90.654489 -268.653156) (xy 90.613986 -268.681112) (xy 90.569524 -268.70221)
			(xy 90.522253 -268.715902) (xy 90.473398 -268.721834) (xy 90.424223 -268.719853) (xy 90.376004 -268.710009)
			(xy 90.329988 -268.692557) (xy 90.287367 -268.66795) (xy 90.249246 -268.636825) (xy 90.216611 -268.599988)
			(xy 90.190308 -268.558392) (xy 90.171017 -268.513116) (xy 90.15924 -268.465332) (xy 90.15528 -268.416278)
			(xy 89.826338 -268.416278) (xy 89.825843 -268.440885) (xy 89.817948 -268.489462) (xy 89.802364 -268.536143)
			(xy 89.779493 -268.57972) (xy 89.749928 -268.619064) (xy 89.714435 -268.653156) (xy 89.673932 -268.681112)
			(xy 89.62947 -268.70221) (xy 89.582199 -268.715902) (xy 89.533344 -268.721834) (xy 89.484169 -268.719853)
			(xy 89.43595 -268.710009) (xy 89.389934 -268.692557) (xy 89.347313 -268.66795) (xy 89.309192 -268.636825)
			(xy 89.276557 -268.599988) (xy 89.250254 -268.558392) (xy 89.230963 -268.513116) (xy 89.219186 -268.465332)
			(xy 89.215226 -268.416278) (xy 88.886284 -268.416278) (xy 88.885789 -268.440885) (xy 88.877894 -268.489462)
			(xy 88.86231 -268.536143) (xy 88.839439 -268.57972) (xy 88.809874 -268.619064) (xy 88.774381 -268.653156)
			(xy 88.733878 -268.681112) (xy 88.689416 -268.70221) (xy 88.642145 -268.715902) (xy 88.59329 -268.721834)
			(xy 88.544115 -268.719853) (xy 88.495896 -268.710009) (xy 88.44988 -268.692557) (xy 88.407259 -268.66795)
			(xy 88.369138 -268.636825) (xy 88.336503 -268.599988) (xy 88.3102 -268.558392) (xy 88.290909 -268.513116)
			(xy 88.279132 -268.465332) (xy 88.275172 -268.416278) (xy 87.94623 -268.416278) (xy 87.945735 -268.440885)
			(xy 87.93784 -268.489462) (xy 87.922256 -268.536143) (xy 87.899385 -268.57972) (xy 87.86982 -268.619064)
			(xy 87.834327 -268.653156) (xy 87.793824 -268.681112) (xy 87.749362 -268.70221) (xy 87.702091 -268.715902)
			(xy 87.653236 -268.721834) (xy 87.604061 -268.719853) (xy 87.555842 -268.710009) (xy 87.509826 -268.692557)
			(xy 87.467205 -268.66795) (xy 87.429084 -268.636825) (xy 87.396449 -268.599988) (xy 87.370146 -268.558392)
			(xy 87.350855 -268.513116) (xy 87.339078 -268.465332) (xy 87.335118 -268.416278) (xy 87.00643 -268.416278)
			(xy 87.005935 -268.440885) (xy 86.99804 -268.489462) (xy 86.982456 -268.536143) (xy 86.959585 -268.57972)
			(xy 86.93002 -268.619064) (xy 86.894527 -268.653156) (xy 86.854024 -268.681112) (xy 86.809562 -268.70221)
			(xy 86.762291 -268.715902) (xy 86.713436 -268.721834) (xy 86.664261 -268.719853) (xy 86.616042 -268.710009)
			(xy 86.570026 -268.692557) (xy 86.527405 -268.66795) (xy 86.489284 -268.636825) (xy 86.456649 -268.599988)
			(xy 86.430346 -268.558392) (xy 86.411055 -268.513116) (xy 86.399278 -268.465332) (xy 86.395318 -268.416278)
			(xy 86.066376 -268.416278) (xy 86.065881 -268.440885) (xy 86.057986 -268.489462) (xy 86.042402 -268.536143)
			(xy 86.019531 -268.57972) (xy 85.989966 -268.619064) (xy 85.954473 -268.653156) (xy 85.91397 -268.681112)
			(xy 85.869508 -268.70221) (xy 85.822237 -268.715902) (xy 85.773382 -268.721834) (xy 85.724207 -268.719853)
			(xy 85.675988 -268.710009) (xy 85.629972 -268.692557) (xy 85.587351 -268.66795) (xy 85.54923 -268.636825)
			(xy 85.516595 -268.599988) (xy 85.490292 -268.558392) (xy 85.471001 -268.513116) (xy 85.459224 -268.465332)
			(xy 85.455264 -268.416278) (xy 85.126322 -268.416278) (xy 85.125827 -268.440885) (xy 85.117932 -268.489462)
			(xy 85.102348 -268.536143) (xy 85.079477 -268.57972) (xy 85.049912 -268.619064) (xy 85.014419 -268.653156)
			(xy 84.973916 -268.681112) (xy 84.929454 -268.70221) (xy 84.882183 -268.715902) (xy 84.833328 -268.721834)
			(xy 84.784153 -268.719853) (xy 84.735934 -268.710009) (xy 84.689918 -268.692557) (xy 84.647297 -268.66795)
			(xy 84.609176 -268.636825) (xy 84.576541 -268.599988) (xy 84.550238 -268.558392) (xy 84.530947 -268.513116)
			(xy 84.51917 -268.465332) (xy 84.51521 -268.416278) (xy 84.186268 -268.416278) (xy 84.185773 -268.440885)
			(xy 84.177878 -268.489462) (xy 84.162294 -268.536143) (xy 84.139423 -268.57972) (xy 84.109858 -268.619064)
			(xy 84.074365 -268.653156) (xy 84.033862 -268.681112) (xy 83.9894 -268.70221) (xy 83.942129 -268.715902)
			(xy 83.893274 -268.721834) (xy 83.844099 -268.719853) (xy 83.79588 -268.710009) (xy 83.749864 -268.692557)
			(xy 83.707243 -268.66795) (xy 83.669122 -268.636825) (xy 83.636487 -268.599988) (xy 83.610184 -268.558392)
			(xy 83.590893 -268.513116) (xy 83.579116 -268.465332) (xy 83.575156 -268.416278) (xy 83.246214 -268.416278)
			(xy 83.245719 -268.440885) (xy 83.237824 -268.489462) (xy 83.22224 -268.536143) (xy 83.199369 -268.57972)
			(xy 83.169804 -268.619064) (xy 83.134311 -268.653156) (xy 83.093808 -268.681112) (xy 83.049346 -268.70221)
			(xy 83.002075 -268.715902) (xy 82.95322 -268.721834) (xy 82.904045 -268.719853) (xy 82.855826 -268.710009)
			(xy 82.80981 -268.692557) (xy 82.767189 -268.66795) (xy 82.729068 -268.636825) (xy 82.696433 -268.599988)
			(xy 82.67013 -268.558392) (xy 82.650839 -268.513116) (xy 82.639062 -268.465332) (xy 82.635102 -268.416278)
			(xy 82.306414 -268.416278) (xy 82.305919 -268.440885) (xy 82.298024 -268.489462) (xy 82.28244 -268.536143)
			(xy 82.259569 -268.57972) (xy 82.230004 -268.619064) (xy 82.194511 -268.653156) (xy 82.154008 -268.681112)
			(xy 82.109546 -268.70221) (xy 82.062275 -268.715902) (xy 82.01342 -268.721834) (xy 81.964245 -268.719853)
			(xy 81.916026 -268.710009) (xy 81.87001 -268.692557) (xy 81.827389 -268.66795) (xy 81.789268 -268.636825)
			(xy 81.756633 -268.599988) (xy 81.73033 -268.558392) (xy 81.711039 -268.513116) (xy 81.699262 -268.465332)
			(xy 81.695302 -268.416278) (xy 81.36636 -268.416278) (xy 81.365865 -268.440885) (xy 81.35797 -268.489462)
			(xy 81.342386 -268.536143) (xy 81.319515 -268.57972) (xy 81.28995 -268.619064) (xy 81.254457 -268.653156)
			(xy 81.213954 -268.681112) (xy 81.169492 -268.70221) (xy 81.122221 -268.715902) (xy 81.073366 -268.721834)
			(xy 81.024191 -268.719853) (xy 80.975972 -268.710009) (xy 80.929956 -268.692557) (xy 80.887335 -268.66795)
			(xy 80.849214 -268.636825) (xy 80.816579 -268.599988) (xy 80.790276 -268.558392) (xy 80.770985 -268.513116)
			(xy 80.759208 -268.465332) (xy 80.755248 -268.416278) (xy 80.426306 -268.416278) (xy 80.425811 -268.440885)
			(xy 80.417916 -268.489462) (xy 80.402332 -268.536143) (xy 80.379461 -268.57972) (xy 80.349896 -268.619064)
			(xy 80.314403 -268.653156) (xy 80.2739 -268.681112) (xy 80.229438 -268.70221) (xy 80.182167 -268.715902)
			(xy 80.133312 -268.721834) (xy 80.084137 -268.719853) (xy 80.035918 -268.710009) (xy 79.989902 -268.692557)
			(xy 79.947281 -268.66795) (xy 79.90916 -268.636825) (xy 79.876525 -268.599988) (xy 79.850222 -268.558392)
			(xy 79.830931 -268.513116) (xy 79.819154 -268.465332) (xy 79.815194 -268.416278) (xy 79.486252 -268.416278)
			(xy 79.485757 -268.440885) (xy 79.477862 -268.489462) (xy 79.462278 -268.536143) (xy 79.439407 -268.57972)
			(xy 79.409842 -268.619064) (xy 79.374349 -268.653156) (xy 79.333846 -268.681112) (xy 79.289384 -268.70221)
			(xy 79.242113 -268.715902) (xy 79.193258 -268.721834) (xy 79.144083 -268.719853) (xy 79.095864 -268.710009)
			(xy 79.049848 -268.692557) (xy 79.007227 -268.66795) (xy 78.969106 -268.636825) (xy 78.936471 -268.599988)
			(xy 78.910168 -268.558392) (xy 78.890877 -268.513116) (xy 78.8791 -268.465332) (xy 78.87514 -268.416278)
			(xy 77.263451 -268.416278) (xy 77.221316 -268.436272) (xy 77.174045 -268.449964) (xy 77.12519 -268.455896)
			(xy 77.076015 -268.453915) (xy 77.027796 -268.444071) (xy 76.98178 -268.426619) (xy 76.939159 -268.402012)
			(xy 76.901038 -268.370887) (xy 76.868403 -268.33405) (xy 76.8421 -268.292454) (xy 76.822809 -268.247178)
			(xy 76.811032 -268.199394) (xy 76.807072 -268.15034) (xy 73.228962 -268.15034) (xy 73.228962 -269.226284)
			(xy 78.40524 -269.226284) (xy 78.4092 -269.17723) (xy 78.420977 -269.129446) (xy 78.440268 -269.08417)
			(xy 78.466571 -269.042574) (xy 78.499206 -269.005737) (xy 78.537327 -268.974612) (xy 78.579948 -268.950005)
			(xy 78.625964 -268.932553) (xy 78.674183 -268.922709) (xy 78.723358 -268.920728) (xy 78.772213 -268.92666)
			(xy 78.819484 -268.940352) (xy 78.863946 -268.96145) (xy 78.904449 -268.989406) (xy 78.939942 -269.023498)
			(xy 78.969507 -269.062842) (xy 78.992378 -269.106419) (xy 79.007962 -269.1531) (xy 79.015857 -269.201677)
			(xy 79.016352 -269.226284) (xy 79.345294 -269.226284) (xy 79.349254 -269.17723) (xy 79.361031 -269.129446)
			(xy 79.380322 -269.08417) (xy 79.406625 -269.042574) (xy 79.43926 -269.005737) (xy 79.477381 -268.974612)
			(xy 79.520002 -268.950005) (xy 79.566018 -268.932553) (xy 79.614237 -268.922709) (xy 79.663412 -268.920728)
			(xy 79.712267 -268.92666) (xy 79.759538 -268.940352) (xy 79.804 -268.96145) (xy 79.844503 -268.989406)
			(xy 79.879996 -269.023498) (xy 79.909561 -269.062842) (xy 79.932432 -269.106419) (xy 79.948016 -269.1531)
			(xy 79.955911 -269.201677) (xy 79.956406 -269.226284) (xy 80.285348 -269.226284) (xy 80.289308 -269.17723)
			(xy 80.301085 -269.129446) (xy 80.320376 -269.08417) (xy 80.346679 -269.042574) (xy 80.379314 -269.005737)
			(xy 80.417435 -268.974612) (xy 80.460056 -268.950005) (xy 80.506072 -268.932553) (xy 80.554291 -268.922709)
			(xy 80.603466 -268.920728) (xy 80.652321 -268.92666) (xy 80.699592 -268.940352) (xy 80.744054 -268.96145)
			(xy 80.784557 -268.989406) (xy 80.82005 -269.023498) (xy 80.849615 -269.062842) (xy 80.872486 -269.106419)
			(xy 80.88807 -269.1531) (xy 80.895965 -269.201677) (xy 80.89646 -269.226284) (xy 81.214717 -269.226284)
			(xy 81.218812 -269.175556) (xy 81.230991 -269.126142) (xy 81.250939 -269.079322) (xy 81.27814 -269.036308)
			(xy 81.311888 -268.998214) (xy 81.35131 -268.966027) (xy 81.395384 -268.940581) (xy 81.44297 -268.922534)
			(xy 81.492834 -268.912354) (xy 81.543686 -268.910305) (xy 81.594207 -268.916439) (xy 81.643091 -268.930599)
			(xy 81.68907 -268.952416) (xy 81.730954 -268.981326) (xy 81.767658 -269.016581) (xy 81.798231 -269.057267)
			(xy 81.821882 -269.10233) (xy 81.837998 -269.150604) (xy 81.846162 -269.200838) (xy 81.846674 -269.226284)
			(xy 82.165202 -269.226284) (xy 82.169162 -269.17723) (xy 82.180939 -269.129446) (xy 82.20023 -269.08417)
			(xy 82.226533 -269.042574) (xy 82.259168 -269.005737) (xy 82.297289 -268.974612) (xy 82.33991 -268.950005)
			(xy 82.385926 -268.932553) (xy 82.434145 -268.922709) (xy 82.48332 -268.920728) (xy 82.532175 -268.92666)
			(xy 82.579446 -268.940352) (xy 82.623908 -268.96145) (xy 82.664411 -268.989406) (xy 82.699904 -269.023498)
			(xy 82.729469 -269.062842) (xy 82.75234 -269.106419) (xy 82.767924 -269.1531) (xy 82.775819 -269.201677)
			(xy 82.776314 -269.226284) (xy 83.105256 -269.226284) (xy 83.109216 -269.17723) (xy 83.120993 -269.129446)
			(xy 83.140284 -269.08417) (xy 83.166587 -269.042574) (xy 83.199222 -269.005737) (xy 83.237343 -268.974612)
			(xy 83.279964 -268.950005) (xy 83.32598 -268.932553) (xy 83.374199 -268.922709) (xy 83.423374 -268.920728)
			(xy 83.472229 -268.92666) (xy 83.5195 -268.940352) (xy 83.563962 -268.96145) (xy 83.604465 -268.989406)
			(xy 83.639958 -269.023498) (xy 83.669523 -269.062842) (xy 83.692394 -269.106419) (xy 83.707978 -269.1531)
			(xy 83.715873 -269.201677) (xy 83.716368 -269.226284) (xy 84.034879 -269.226284) (xy 84.038974 -269.175556)
			(xy 84.051153 -269.126142) (xy 84.071101 -269.079322) (xy 84.098302 -269.036308) (xy 84.13205 -268.998214)
			(xy 84.171472 -268.966027) (xy 84.215546 -268.940581) (xy 84.263132 -268.922534) (xy 84.312996 -268.912354)
			(xy 84.363848 -268.910305) (xy 84.414369 -268.916439) (xy 84.463253 -268.930599) (xy 84.509232 -268.952416)
			(xy 84.551116 -268.981326) (xy 84.58782 -269.016581) (xy 84.618393 -269.057267) (xy 84.642044 -269.10233)
			(xy 84.65816 -269.150604) (xy 84.666324 -269.200838) (xy 84.666836 -269.226284) (xy 84.98511 -269.226284)
			(xy 84.98907 -269.17723) (xy 85.000847 -269.129446) (xy 85.020138 -269.08417) (xy 85.046441 -269.042574)
			(xy 85.079076 -269.005737) (xy 85.117197 -268.974612) (xy 85.159818 -268.950005) (xy 85.205834 -268.932553)
			(xy 85.254053 -268.922709) (xy 85.303228 -268.920728) (xy 85.352083 -268.92666) (xy 85.399354 -268.940352)
			(xy 85.443816 -268.96145) (xy 85.484319 -268.989406) (xy 85.519812 -269.023498) (xy 85.549377 -269.062842)
			(xy 85.572248 -269.106419) (xy 85.587832 -269.1531) (xy 85.595727 -269.201677) (xy 85.596222 -269.226284)
			(xy 85.925164 -269.226284) (xy 85.929124 -269.17723) (xy 85.940901 -269.129446) (xy 85.960192 -269.08417)
			(xy 85.986495 -269.042574) (xy 86.01913 -269.005737) (xy 86.057251 -268.974612) (xy 86.099872 -268.950005)
			(xy 86.145888 -268.932553) (xy 86.194107 -268.922709) (xy 86.243282 -268.920728) (xy 86.292137 -268.92666)
			(xy 86.339408 -268.940352) (xy 86.38387 -268.96145) (xy 86.424373 -268.989406) (xy 86.459866 -269.023498)
			(xy 86.489431 -269.062842) (xy 86.512302 -269.106419) (xy 86.527886 -269.1531) (xy 86.535781 -269.201677)
			(xy 86.536276 -269.226284) (xy 86.865218 -269.226284) (xy 86.869178 -269.17723) (xy 86.880955 -269.129446)
			(xy 86.900246 -269.08417) (xy 86.926549 -269.042574) (xy 86.959184 -269.005737) (xy 86.997305 -268.974612)
			(xy 87.039926 -268.950005) (xy 87.085942 -268.932553) (xy 87.134161 -268.922709) (xy 87.183336 -268.920728)
			(xy 87.232191 -268.92666) (xy 87.279462 -268.940352) (xy 87.323924 -268.96145) (xy 87.364427 -268.989406)
			(xy 87.39992 -269.023498) (xy 87.429485 -269.062842) (xy 87.452356 -269.106419) (xy 87.46794 -269.1531)
			(xy 87.475835 -269.201677) (xy 87.47633 -269.226284) (xy 87.794841 -269.226284) (xy 87.798936 -269.175556)
			(xy 87.811115 -269.126142) (xy 87.831063 -269.079322) (xy 87.858264 -269.036308) (xy 87.892012 -268.998214)
			(xy 87.931434 -268.966027) (xy 87.975508 -268.940581) (xy 88.023094 -268.922534) (xy 88.072958 -268.912354)
			(xy 88.12381 -268.910305) (xy 88.174331 -268.916439) (xy 88.223215 -268.930599) (xy 88.269194 -268.952416)
			(xy 88.311078 -268.981326) (xy 88.347782 -269.016581) (xy 88.378355 -269.057267) (xy 88.402006 -269.10233)
			(xy 88.418122 -269.150604) (xy 88.426286 -269.200838) (xy 88.426798 -269.226284) (xy 88.745326 -269.226284)
			(xy 88.749286 -269.17723) (xy 88.761063 -269.129446) (xy 88.780354 -269.08417) (xy 88.806657 -269.042574)
			(xy 88.839292 -269.005737) (xy 88.877413 -268.974612) (xy 88.920034 -268.950005) (xy 88.96605 -268.932553)
			(xy 89.014269 -268.922709) (xy 89.063444 -268.920728) (xy 89.112299 -268.92666) (xy 89.15957 -268.940352)
			(xy 89.204032 -268.96145) (xy 89.244535 -268.989406) (xy 89.280028 -269.023498) (xy 89.309593 -269.062842)
			(xy 89.332464 -269.106419) (xy 89.348048 -269.1531) (xy 89.355943 -269.201677) (xy 89.356438 -269.226284)
			(xy 89.685126 -269.226284) (xy 89.689086 -269.17723) (xy 89.700863 -269.129446) (xy 89.720154 -269.08417)
			(xy 89.746457 -269.042574) (xy 89.779092 -269.005737) (xy 89.817213 -268.974612) (xy 89.859834 -268.950005)
			(xy 89.90585 -268.932553) (xy 89.954069 -268.922709) (xy 90.003244 -268.920728) (xy 90.052099 -268.92666)
			(xy 90.09937 -268.940352) (xy 90.143832 -268.96145) (xy 90.184335 -268.989406) (xy 90.219828 -269.023498)
			(xy 90.249393 -269.062842) (xy 90.272264 -269.106419) (xy 90.287848 -269.1531) (xy 90.295743 -269.201677)
			(xy 90.296238 -269.226284) (xy 90.614749 -269.226284) (xy 90.618844 -269.175556) (xy 90.631023 -269.126142)
			(xy 90.650971 -269.079322) (xy 90.678172 -269.036308) (xy 90.71192 -268.998214) (xy 90.751342 -268.966027)
			(xy 90.795416 -268.940581) (xy 90.843002 -268.922534) (xy 90.892866 -268.912354) (xy 90.943718 -268.910305)
			(xy 90.994239 -268.916439) (xy 91.043123 -268.930599) (xy 91.089102 -268.952416) (xy 91.130986 -268.981326)
			(xy 91.16769 -269.016581) (xy 91.198263 -269.057267) (xy 91.221914 -269.10233) (xy 91.23803 -269.150604)
			(xy 91.246194 -269.200838) (xy 91.246706 -269.226284) (xy 91.565234 -269.226284) (xy 91.569194 -269.17723)
			(xy 91.580971 -269.129446) (xy 91.600262 -269.08417) (xy 91.626565 -269.042574) (xy 91.6592 -269.005737)
			(xy 91.697321 -268.974612) (xy 91.739942 -268.950005) (xy 91.785958 -268.932553) (xy 91.834177 -268.922709)
			(xy 91.883352 -268.920728) (xy 91.932207 -268.92666) (xy 91.979478 -268.940352) (xy 92.02394 -268.96145)
			(xy 92.064443 -268.989406) (xy 92.099936 -269.023498) (xy 92.129501 -269.062842) (xy 92.152372 -269.106419)
			(xy 92.167956 -269.1531) (xy 92.175851 -269.201677) (xy 92.176346 -269.226284) (xy 92.505288 -269.226284)
			(xy 92.509248 -269.17723) (xy 92.521025 -269.129446) (xy 92.540316 -269.08417) (xy 92.566619 -269.042574)
			(xy 92.599254 -269.005737) (xy 92.637375 -268.974612) (xy 92.679996 -268.950005) (xy 92.726012 -268.932553)
			(xy 92.774231 -268.922709) (xy 92.823406 -268.920728) (xy 92.872261 -268.92666) (xy 92.919532 -268.940352)
			(xy 92.963994 -268.96145) (xy 93.004497 -268.989406) (xy 93.03999 -269.023498) (xy 93.069555 -269.062842)
			(xy 93.092426 -269.106419) (xy 93.10801 -269.1531) (xy 93.115905 -269.201677) (xy 93.1164 -269.226284)
			(xy 93.445342 -269.226284) (xy 93.449302 -269.17723) (xy 93.461079 -269.129446) (xy 93.48037 -269.08417)
			(xy 93.506673 -269.042574) (xy 93.539308 -269.005737) (xy 93.577429 -268.974612) (xy 93.62005 -268.950005)
			(xy 93.666066 -268.932553) (xy 93.714285 -268.922709) (xy 93.76346 -268.920728) (xy 93.812315 -268.92666)
			(xy 93.859586 -268.940352) (xy 93.904048 -268.96145) (xy 93.944551 -268.989406) (xy 93.980044 -269.023498)
			(xy 94.009609 -269.062842) (xy 94.03248 -269.106419) (xy 94.048064 -269.1531) (xy 94.055959 -269.201677)
			(xy 94.056454 -269.226284) (xy 94.374711 -269.226284) (xy 94.378806 -269.175556) (xy 94.390985 -269.126142)
			(xy 94.410933 -269.079322) (xy 94.438134 -269.036308) (xy 94.471882 -268.998214) (xy 94.511304 -268.966027)
			(xy 94.555378 -268.940581) (xy 94.602964 -268.922534) (xy 94.652828 -268.912354) (xy 94.70368 -268.910305)
			(xy 94.754201 -268.916439) (xy 94.803085 -268.930599) (xy 94.849064 -268.952416) (xy 94.890948 -268.981326)
			(xy 94.927652 -269.016581) (xy 94.958225 -269.057267) (xy 94.981876 -269.10233) (xy 94.997992 -269.150604)
			(xy 95.006156 -269.200838) (xy 95.006668 -269.226284) (xy 95.325196 -269.226284) (xy 95.329156 -269.17723)
			(xy 95.340933 -269.129446) (xy 95.360224 -269.08417) (xy 95.386527 -269.042574) (xy 95.419162 -269.005737)
			(xy 95.457283 -268.974612) (xy 95.499904 -268.950005) (xy 95.54592 -268.932553) (xy 95.594139 -268.922709)
			(xy 95.643314 -268.920728) (xy 95.692169 -268.92666) (xy 95.73944 -268.940352) (xy 95.783902 -268.96145)
			(xy 95.824405 -268.989406) (xy 95.859898 -269.023498) (xy 95.889463 -269.062842) (xy 95.912334 -269.106419)
			(xy 95.927918 -269.1531) (xy 95.935813 -269.201677) (xy 95.936308 -269.226284) (xy 96.26525 -269.226284)
			(xy 96.26921 -269.17723) (xy 96.280987 -269.129446) (xy 96.300278 -269.08417) (xy 96.326581 -269.042574)
			(xy 96.359216 -269.005737) (xy 96.397337 -268.974612) (xy 96.439958 -268.950005) (xy 96.485974 -268.932553)
			(xy 96.534193 -268.922709) (xy 96.583368 -268.920728) (xy 96.632223 -268.92666) (xy 96.679494 -268.940352)
			(xy 96.723956 -268.96145) (xy 96.764459 -268.989406) (xy 96.799952 -269.023498) (xy 96.829517 -269.062842)
			(xy 96.852388 -269.106419) (xy 96.867972 -269.1531) (xy 96.875867 -269.201677) (xy 96.876362 -269.226284)
			(xy 99.085158 -269.226284) (xy 99.089118 -269.17723) (xy 99.100895 -269.129446) (xy 99.120186 -269.08417)
			(xy 99.146489 -269.042574) (xy 99.179124 -269.005737) (xy 99.217245 -268.974612) (xy 99.259866 -268.950005)
			(xy 99.305882 -268.932553) (xy 99.354101 -268.922709) (xy 99.403276 -268.920728) (xy 99.452131 -268.92666)
			(xy 99.499402 -268.940352) (xy 99.543864 -268.96145) (xy 99.584367 -268.989406) (xy 99.61986 -269.023498)
			(xy 99.649425 -269.062842) (xy 99.672296 -269.106419) (xy 99.68788 -269.1531) (xy 99.695775 -269.201677)
			(xy 99.69627 -269.226284) (xy 101.90532 -269.226284) (xy 101.90928 -269.17723) (xy 101.921057 -269.129446)
			(xy 101.940348 -269.08417) (xy 101.966651 -269.042574) (xy 101.999286 -269.005737) (xy 102.037407 -268.974612)
			(xy 102.080028 -268.950005) (xy 102.126044 -268.932553) (xy 102.174263 -268.922709) (xy 102.223438 -268.920728)
			(xy 102.272293 -268.92666) (xy 102.319564 -268.940352) (xy 102.364026 -268.96145) (xy 102.404529 -268.989406)
			(xy 102.440022 -269.023498) (xy 102.469587 -269.062842) (xy 102.492458 -269.106419) (xy 102.508042 -269.1531)
			(xy 102.515937 -269.201677) (xy 102.516432 -269.226284) (xy 102.515937 -269.250891) (xy 102.508042 -269.299468)
			(xy 102.492458 -269.346149) (xy 102.469587 -269.389726) (xy 102.440022 -269.42907) (xy 102.404529 -269.463162)
			(xy 102.364026 -269.491118) (xy 102.319564 -269.512216) (xy 102.272293 -269.525908) (xy 102.223438 -269.53184)
			(xy 102.174263 -269.529859) (xy 102.126044 -269.520015) (xy 102.080028 -269.502563) (xy 102.037407 -269.477956)
			(xy 101.999286 -269.446831) (xy 101.966651 -269.409994) (xy 101.940348 -269.368398) (xy 101.921057 -269.323122)
			(xy 101.90928 -269.275338) (xy 101.90532 -269.226284) (xy 99.69627 -269.226284) (xy 99.695775 -269.250891)
			(xy 99.68788 -269.299468) (xy 99.672296 -269.346149) (xy 99.649425 -269.389726) (xy 99.61986 -269.42907)
			(xy 99.584367 -269.463162) (xy 99.543864 -269.491118) (xy 99.499402 -269.512216) (xy 99.452131 -269.525908)
			(xy 99.403276 -269.53184) (xy 99.354101 -269.529859) (xy 99.305882 -269.520015) (xy 99.259866 -269.502563)
			(xy 99.217245 -269.477956) (xy 99.179124 -269.446831) (xy 99.146489 -269.409994) (xy 99.120186 -269.368398)
			(xy 99.100895 -269.323122) (xy 99.089118 -269.275338) (xy 99.085158 -269.226284) (xy 96.876362 -269.226284)
			(xy 96.875867 -269.250891) (xy 96.867972 -269.299468) (xy 96.852388 -269.346149) (xy 96.829517 -269.389726)
			(xy 96.799952 -269.42907) (xy 96.764459 -269.463162) (xy 96.723956 -269.491118) (xy 96.679494 -269.512216)
			(xy 96.632223 -269.525908) (xy 96.583368 -269.53184) (xy 96.534193 -269.529859) (xy 96.485974 -269.520015)
			(xy 96.439958 -269.502563) (xy 96.397337 -269.477956) (xy 96.359216 -269.446831) (xy 96.326581 -269.409994)
			(xy 96.300278 -269.368398) (xy 96.280987 -269.323122) (xy 96.26921 -269.275338) (xy 96.26525 -269.226284)
			(xy 95.936308 -269.226284) (xy 95.935813 -269.250891) (xy 95.927918 -269.299468) (xy 95.912334 -269.346149)
			(xy 95.889463 -269.389726) (xy 95.859898 -269.42907) (xy 95.824405 -269.463162) (xy 95.783902 -269.491118)
			(xy 95.73944 -269.512216) (xy 95.692169 -269.525908) (xy 95.643314 -269.53184) (xy 95.594139 -269.529859)
			(xy 95.54592 -269.520015) (xy 95.499904 -269.502563) (xy 95.457283 -269.477956) (xy 95.419162 -269.446831)
			(xy 95.386527 -269.409994) (xy 95.360224 -269.368398) (xy 95.340933 -269.323122) (xy 95.329156 -269.275338)
			(xy 95.325196 -269.226284) (xy 95.006668 -269.226284) (xy 95.006156 -269.25173) (xy 94.997992 -269.301964)
			(xy 94.981876 -269.350238) (xy 94.958225 -269.395301) (xy 94.927652 -269.435987) (xy 94.890948 -269.471242)
			(xy 94.849064 -269.500152) (xy 94.803085 -269.521969) (xy 94.754201 -269.536129) (xy 94.70368 -269.542263)
			(xy 94.652828 -269.540214) (xy 94.602964 -269.530034) (xy 94.555378 -269.511987) (xy 94.511304 -269.486541)
			(xy 94.471882 -269.454354) (xy 94.438134 -269.41626) (xy 94.410933 -269.373246) (xy 94.390985 -269.326426)
			(xy 94.378806 -269.277012) (xy 94.374711 -269.226284) (xy 94.056454 -269.226284) (xy 94.055959 -269.250891)
			(xy 94.048064 -269.299468) (xy 94.03248 -269.346149) (xy 94.009609 -269.389726) (xy 93.980044 -269.42907)
			(xy 93.944551 -269.463162) (xy 93.904048 -269.491118) (xy 93.859586 -269.512216) (xy 93.812315 -269.525908)
			(xy 93.76346 -269.53184) (xy 93.714285 -269.529859) (xy 93.666066 -269.520015) (xy 93.62005 -269.502563)
			(xy 93.577429 -269.477956) (xy 93.539308 -269.446831) (xy 93.506673 -269.409994) (xy 93.48037 -269.368398)
			(xy 93.461079 -269.323122) (xy 93.449302 -269.275338) (xy 93.445342 -269.226284) (xy 93.1164 -269.226284)
			(xy 93.115905 -269.250891) (xy 93.10801 -269.299468) (xy 93.092426 -269.346149) (xy 93.069555 -269.389726)
			(xy 93.03999 -269.42907) (xy 93.004497 -269.463162) (xy 92.963994 -269.491118) (xy 92.919532 -269.512216)
			(xy 92.872261 -269.525908) (xy 92.823406 -269.53184) (xy 92.774231 -269.529859) (xy 92.726012 -269.520015)
			(xy 92.679996 -269.502563) (xy 92.637375 -269.477956) (xy 92.599254 -269.446831) (xy 92.566619 -269.409994)
			(xy 92.540316 -269.368398) (xy 92.521025 -269.323122) (xy 92.509248 -269.275338) (xy 92.505288 -269.226284)
			(xy 92.176346 -269.226284) (xy 92.175851 -269.250891) (xy 92.167956 -269.299468) (xy 92.152372 -269.346149)
			(xy 92.129501 -269.389726) (xy 92.099936 -269.42907) (xy 92.064443 -269.463162) (xy 92.02394 -269.491118)
			(xy 91.979478 -269.512216) (xy 91.932207 -269.525908) (xy 91.883352 -269.53184) (xy 91.834177 -269.529859)
			(xy 91.785958 -269.520015) (xy 91.739942 -269.502563) (xy 91.697321 -269.477956) (xy 91.6592 -269.446831)
			(xy 91.626565 -269.409994) (xy 91.600262 -269.368398) (xy 91.580971 -269.323122) (xy 91.569194 -269.275338)
			(xy 91.565234 -269.226284) (xy 91.246706 -269.226284) (xy 91.246194 -269.25173) (xy 91.23803 -269.301964)
			(xy 91.221914 -269.350238) (xy 91.198263 -269.395301) (xy 91.16769 -269.435987) (xy 91.130986 -269.471242)
			(xy 91.089102 -269.500152) (xy 91.043123 -269.521969) (xy 90.994239 -269.536129) (xy 90.943718 -269.542263)
			(xy 90.892866 -269.540214) (xy 90.843002 -269.530034) (xy 90.795416 -269.511987) (xy 90.751342 -269.486541)
			(xy 90.71192 -269.454354) (xy 90.678172 -269.41626) (xy 90.650971 -269.373246) (xy 90.631023 -269.326426)
			(xy 90.618844 -269.277012) (xy 90.614749 -269.226284) (xy 90.296238 -269.226284) (xy 90.295743 -269.250891)
			(xy 90.287848 -269.299468) (xy 90.272264 -269.346149) (xy 90.249393 -269.389726) (xy 90.219828 -269.42907)
			(xy 90.184335 -269.463162) (xy 90.143832 -269.491118) (xy 90.09937 -269.512216) (xy 90.052099 -269.525908)
			(xy 90.003244 -269.53184) (xy 89.954069 -269.529859) (xy 89.90585 -269.520015) (xy 89.859834 -269.502563)
			(xy 89.817213 -269.477956) (xy 89.779092 -269.446831) (xy 89.746457 -269.409994) (xy 89.720154 -269.368398)
			(xy 89.700863 -269.323122) (xy 89.689086 -269.275338) (xy 89.685126 -269.226284) (xy 89.356438 -269.226284)
			(xy 89.355943 -269.250891) (xy 89.348048 -269.299468) (xy 89.332464 -269.346149) (xy 89.309593 -269.389726)
			(xy 89.280028 -269.42907) (xy 89.244535 -269.463162) (xy 89.204032 -269.491118) (xy 89.15957 -269.512216)
			(xy 89.112299 -269.525908) (xy 89.063444 -269.53184) (xy 89.014269 -269.529859) (xy 88.96605 -269.520015)
			(xy 88.920034 -269.502563) (xy 88.877413 -269.477956) (xy 88.839292 -269.446831) (xy 88.806657 -269.409994)
			(xy 88.780354 -269.368398) (xy 88.761063 -269.323122) (xy 88.749286 -269.275338) (xy 88.745326 -269.226284)
			(xy 88.426798 -269.226284) (xy 88.426286 -269.25173) (xy 88.418122 -269.301964) (xy 88.402006 -269.350238)
			(xy 88.378355 -269.395301) (xy 88.347782 -269.435987) (xy 88.311078 -269.471242) (xy 88.269194 -269.500152)
			(xy 88.223215 -269.521969) (xy 88.174331 -269.536129) (xy 88.12381 -269.542263) (xy 88.072958 -269.540214)
			(xy 88.023094 -269.530034) (xy 87.975508 -269.511987) (xy 87.931434 -269.486541) (xy 87.892012 -269.454354)
			(xy 87.858264 -269.41626) (xy 87.831063 -269.373246) (xy 87.811115 -269.326426) (xy 87.798936 -269.277012)
			(xy 87.794841 -269.226284) (xy 87.47633 -269.226284) (xy 87.475835 -269.250891) (xy 87.46794 -269.299468)
			(xy 87.452356 -269.346149) (xy 87.429485 -269.389726) (xy 87.39992 -269.42907) (xy 87.364427 -269.463162)
			(xy 87.323924 -269.491118) (xy 87.279462 -269.512216) (xy 87.232191 -269.525908) (xy 87.183336 -269.53184)
			(xy 87.134161 -269.529859) (xy 87.085942 -269.520015) (xy 87.039926 -269.502563) (xy 86.997305 -269.477956)
			(xy 86.959184 -269.446831) (xy 86.926549 -269.409994) (xy 86.900246 -269.368398) (xy 86.880955 -269.323122)
			(xy 86.869178 -269.275338) (xy 86.865218 -269.226284) (xy 86.536276 -269.226284) (xy 86.535781 -269.250891)
			(xy 86.527886 -269.299468) (xy 86.512302 -269.346149) (xy 86.489431 -269.389726) (xy 86.459866 -269.42907)
			(xy 86.424373 -269.463162) (xy 86.38387 -269.491118) (xy 86.339408 -269.512216) (xy 86.292137 -269.525908)
			(xy 86.243282 -269.53184) (xy 86.194107 -269.529859) (xy 86.145888 -269.520015) (xy 86.099872 -269.502563)
			(xy 86.057251 -269.477956) (xy 86.01913 -269.446831) (xy 85.986495 -269.409994) (xy 85.960192 -269.368398)
			(xy 85.940901 -269.323122) (xy 85.929124 -269.275338) (xy 85.925164 -269.226284) (xy 85.596222 -269.226284)
			(xy 85.595727 -269.250891) (xy 85.587832 -269.299468) (xy 85.572248 -269.346149) (xy 85.549377 -269.389726)
			(xy 85.519812 -269.42907) (xy 85.484319 -269.463162) (xy 85.443816 -269.491118) (xy 85.399354 -269.512216)
			(xy 85.352083 -269.525908) (xy 85.303228 -269.53184) (xy 85.254053 -269.529859) (xy 85.205834 -269.520015)
			(xy 85.159818 -269.502563) (xy 85.117197 -269.477956) (xy 85.079076 -269.446831) (xy 85.046441 -269.409994)
			(xy 85.020138 -269.368398) (xy 85.000847 -269.323122) (xy 84.98907 -269.275338) (xy 84.98511 -269.226284)
			(xy 84.666836 -269.226284) (xy 84.666324 -269.25173) (xy 84.65816 -269.301964) (xy 84.642044 -269.350238)
			(xy 84.618393 -269.395301) (xy 84.58782 -269.435987) (xy 84.551116 -269.471242) (xy 84.509232 -269.500152)
			(xy 84.463253 -269.521969) (xy 84.414369 -269.536129) (xy 84.363848 -269.542263) (xy 84.312996 -269.540214)
			(xy 84.263132 -269.530034) (xy 84.215546 -269.511987) (xy 84.171472 -269.486541) (xy 84.13205 -269.454354)
			(xy 84.098302 -269.41626) (xy 84.071101 -269.373246) (xy 84.051153 -269.326426) (xy 84.038974 -269.277012)
			(xy 84.034879 -269.226284) (xy 83.716368 -269.226284) (xy 83.715873 -269.250891) (xy 83.707978 -269.299468)
			(xy 83.692394 -269.346149) (xy 83.669523 -269.389726) (xy 83.639958 -269.42907) (xy 83.604465 -269.463162)
			(xy 83.563962 -269.491118) (xy 83.5195 -269.512216) (xy 83.472229 -269.525908) (xy 83.423374 -269.53184)
			(xy 83.374199 -269.529859) (xy 83.32598 -269.520015) (xy 83.279964 -269.502563) (xy 83.237343 -269.477956)
			(xy 83.199222 -269.446831) (xy 83.166587 -269.409994) (xy 83.140284 -269.368398) (xy 83.120993 -269.323122)
			(xy 83.109216 -269.275338) (xy 83.105256 -269.226284) (xy 82.776314 -269.226284) (xy 82.775819 -269.250891)
			(xy 82.767924 -269.299468) (xy 82.75234 -269.346149) (xy 82.729469 -269.389726) (xy 82.699904 -269.42907)
			(xy 82.664411 -269.463162) (xy 82.623908 -269.491118) (xy 82.579446 -269.512216) (xy 82.532175 -269.525908)
			(xy 82.48332 -269.53184) (xy 82.434145 -269.529859) (xy 82.385926 -269.520015) (xy 82.33991 -269.502563)
			(xy 82.297289 -269.477956) (xy 82.259168 -269.446831) (xy 82.226533 -269.409994) (xy 82.20023 -269.368398)
			(xy 82.180939 -269.323122) (xy 82.169162 -269.275338) (xy 82.165202 -269.226284) (xy 81.846674 -269.226284)
			(xy 81.846162 -269.25173) (xy 81.837998 -269.301964) (xy 81.821882 -269.350238) (xy 81.798231 -269.395301)
			(xy 81.767658 -269.435987) (xy 81.730954 -269.471242) (xy 81.68907 -269.500152) (xy 81.643091 -269.521969)
			(xy 81.594207 -269.536129) (xy 81.543686 -269.542263) (xy 81.492834 -269.540214) (xy 81.44297 -269.530034)
			(xy 81.395384 -269.511987) (xy 81.35131 -269.486541) (xy 81.311888 -269.454354) (xy 81.27814 -269.41626)
			(xy 81.250939 -269.373246) (xy 81.230991 -269.326426) (xy 81.218812 -269.277012) (xy 81.214717 -269.226284)
			(xy 80.89646 -269.226284) (xy 80.895965 -269.250891) (xy 80.88807 -269.299468) (xy 80.872486 -269.346149)
			(xy 80.849615 -269.389726) (xy 80.82005 -269.42907) (xy 80.784557 -269.463162) (xy 80.744054 -269.491118)
			(xy 80.699592 -269.512216) (xy 80.652321 -269.525908) (xy 80.603466 -269.53184) (xy 80.554291 -269.529859)
			(xy 80.506072 -269.520015) (xy 80.460056 -269.502563) (xy 80.417435 -269.477956) (xy 80.379314 -269.446831)
			(xy 80.346679 -269.409994) (xy 80.320376 -269.368398) (xy 80.301085 -269.323122) (xy 80.289308 -269.275338)
			(xy 80.285348 -269.226284) (xy 79.956406 -269.226284) (xy 79.955911 -269.250891) (xy 79.948016 -269.299468)
			(xy 79.932432 -269.346149) (xy 79.909561 -269.389726) (xy 79.879996 -269.42907) (xy 79.844503 -269.463162)
			(xy 79.804 -269.491118) (xy 79.759538 -269.512216) (xy 79.712267 -269.525908) (xy 79.663412 -269.53184)
			(xy 79.614237 -269.529859) (xy 79.566018 -269.520015) (xy 79.520002 -269.502563) (xy 79.477381 -269.477956)
			(xy 79.43926 -269.446831) (xy 79.406625 -269.409994) (xy 79.380322 -269.368398) (xy 79.361031 -269.323122)
			(xy 79.349254 -269.275338) (xy 79.345294 -269.226284) (xy 79.016352 -269.226284) (xy 79.015857 -269.250891)
			(xy 79.007962 -269.299468) (xy 78.992378 -269.346149) (xy 78.969507 -269.389726) (xy 78.939942 -269.42907)
			(xy 78.904449 -269.463162) (xy 78.863946 -269.491118) (xy 78.819484 -269.512216) (xy 78.772213 -269.525908)
			(xy 78.723358 -269.53184) (xy 78.674183 -269.529859) (xy 78.625964 -269.520015) (xy 78.579948 -269.502563)
			(xy 78.537327 -269.477956) (xy 78.499206 -269.446831) (xy 78.466571 -269.409994) (xy 78.440268 -269.368398)
			(xy 78.420977 -269.323122) (xy 78.4092 -269.275338) (xy 78.40524 -269.226284) (xy 73.228962 -269.226284)
			(xy 73.228962 -269.770352) (xy 76.807072 -269.770352) (xy 76.811032 -269.721298) (xy 76.822809 -269.673514)
			(xy 76.8421 -269.628238) (xy 76.868403 -269.586642) (xy 76.901038 -269.549805) (xy 76.939159 -269.51868)
			(xy 76.98178 -269.494073) (xy 77.027796 -269.476621) (xy 77.076015 -269.466777) (xy 77.12519 -269.464796)
			(xy 77.174045 -269.470728) (xy 77.221316 -269.48442) (xy 77.265778 -269.505518) (xy 77.306281 -269.533474)
			(xy 77.341774 -269.567566) (xy 77.371339 -269.60691) (xy 77.39421 -269.650487) (xy 77.409794 -269.697168)
			(xy 77.417689 -269.745745) (xy 77.418184 -269.770352) (xy 77.417689 -269.794959) (xy 77.409794 -269.843536)
			(xy 77.39421 -269.890217) (xy 77.371339 -269.933794) (xy 77.341774 -269.973138) (xy 77.306281 -270.00723)
			(xy 77.265778 -270.035186) (xy 77.263451 -270.03629) (xy 79.815194 -270.03629) (xy 79.819154 -269.987236)
			(xy 79.830931 -269.939452) (xy 79.850222 -269.894176) (xy 79.876525 -269.85258) (xy 79.90916 -269.815743)
			(xy 79.947281 -269.784618) (xy 79.989902 -269.760011) (xy 80.035918 -269.742559) (xy 80.084137 -269.732715)
			(xy 80.133312 -269.730734) (xy 80.182167 -269.736666) (xy 80.229438 -269.750358) (xy 80.2739 -269.771456)
			(xy 80.314403 -269.799412) (xy 80.349896 -269.833504) (xy 80.379461 -269.872848) (xy 80.402332 -269.916425)
			(xy 80.417916 -269.963106) (xy 80.425811 -270.011683) (xy 80.426306 -270.03629) (xy 80.744817 -270.03629)
			(xy 80.748912 -269.985562) (xy 80.761091 -269.936148) (xy 80.781039 -269.889328) (xy 80.80824 -269.846314)
			(xy 80.841988 -269.80822) (xy 80.88141 -269.776033) (xy 80.925484 -269.750587) (xy 80.97307 -269.73254)
			(xy 81.022934 -269.72236) (xy 81.073786 -269.720311) (xy 81.124307 -269.726445) (xy 81.173191 -269.740605)
			(xy 81.21917 -269.762422) (xy 81.261054 -269.791332) (xy 81.297758 -269.826587) (xy 81.328331 -269.867273)
			(xy 81.351982 -269.912336) (xy 81.368098 -269.96061) (xy 81.376262 -270.010844) (xy 81.376774 -270.03629)
			(xy 81.695302 -270.03629) (xy 81.699262 -269.987236) (xy 81.711039 -269.939452) (xy 81.73033 -269.894176)
			(xy 81.756633 -269.85258) (xy 81.789268 -269.815743) (xy 81.827389 -269.784618) (xy 81.87001 -269.760011)
			(xy 81.916026 -269.742559) (xy 81.964245 -269.732715) (xy 82.01342 -269.730734) (xy 82.062275 -269.736666)
			(xy 82.109546 -269.750358) (xy 82.154008 -269.771456) (xy 82.194511 -269.799412) (xy 82.230004 -269.833504)
			(xy 82.259569 -269.872848) (xy 82.28244 -269.916425) (xy 82.298024 -269.963106) (xy 82.305919 -270.011683)
			(xy 82.306414 -270.03629) (xy 82.624671 -270.03629) (xy 82.628766 -269.985562) (xy 82.640945 -269.936148)
			(xy 82.660893 -269.889328) (xy 82.688094 -269.846314) (xy 82.721842 -269.80822) (xy 82.761264 -269.776033)
			(xy 82.805338 -269.750587) (xy 82.852924 -269.73254) (xy 82.902788 -269.72236) (xy 82.95364 -269.720311)
			(xy 83.004161 -269.726445) (xy 83.053045 -269.740605) (xy 83.099024 -269.762422) (xy 83.140908 -269.791332)
			(xy 83.177612 -269.826587) (xy 83.208185 -269.867273) (xy 83.231836 -269.912336) (xy 83.247952 -269.96061)
			(xy 83.256116 -270.010844) (xy 83.256628 -270.03629) (xy 83.575156 -270.03629) (xy 83.579116 -269.987236)
			(xy 83.590893 -269.939452) (xy 83.610184 -269.894176) (xy 83.636487 -269.85258) (xy 83.669122 -269.815743)
			(xy 83.707243 -269.784618) (xy 83.749864 -269.760011) (xy 83.79588 -269.742559) (xy 83.844099 -269.732715)
			(xy 83.893274 -269.730734) (xy 83.942129 -269.736666) (xy 83.9894 -269.750358) (xy 84.033862 -269.771456)
			(xy 84.074365 -269.799412) (xy 84.109858 -269.833504) (xy 84.139423 -269.872848) (xy 84.162294 -269.916425)
			(xy 84.177878 -269.963106) (xy 84.185773 -270.011683) (xy 84.186268 -270.03629) (xy 84.504779 -270.03629)
			(xy 84.508874 -269.985562) (xy 84.521053 -269.936148) (xy 84.541001 -269.889328) (xy 84.568202 -269.846314)
			(xy 84.60195 -269.80822) (xy 84.641372 -269.776033) (xy 84.685446 -269.750587) (xy 84.733032 -269.73254)
			(xy 84.782896 -269.72236) (xy 84.833748 -269.720311) (xy 84.884269 -269.726445) (xy 84.933153 -269.740605)
			(xy 84.979132 -269.762422) (xy 85.021016 -269.791332) (xy 85.05772 -269.826587) (xy 85.088293 -269.867273)
			(xy 85.111944 -269.912336) (xy 85.12806 -269.96061) (xy 85.136224 -270.010844) (xy 85.136736 -270.03629)
			(xy 85.444833 -270.03629) (xy 85.448928 -269.985562) (xy 85.461107 -269.936148) (xy 85.481055 -269.889328)
			(xy 85.508256 -269.846314) (xy 85.542004 -269.80822) (xy 85.581426 -269.776033) (xy 85.6255 -269.750587)
			(xy 85.673086 -269.73254) (xy 85.72295 -269.72236) (xy 85.773802 -269.720311) (xy 85.824323 -269.726445)
			(xy 85.873207 -269.740605) (xy 85.919186 -269.762422) (xy 85.96107 -269.791332) (xy 85.997774 -269.826587)
			(xy 86.028347 -269.867273) (xy 86.051998 -269.912336) (xy 86.068114 -269.96061) (xy 86.076278 -270.010844)
			(xy 86.07679 -270.03629) (xy 86.395318 -270.03629) (xy 86.399278 -269.987236) (xy 86.411055 -269.939452)
			(xy 86.430346 -269.894176) (xy 86.456649 -269.85258) (xy 86.489284 -269.815743) (xy 86.527405 -269.784618)
			(xy 86.570026 -269.760011) (xy 86.616042 -269.742559) (xy 86.664261 -269.732715) (xy 86.713436 -269.730734)
			(xy 86.762291 -269.736666) (xy 86.809562 -269.750358) (xy 86.854024 -269.771456) (xy 86.894527 -269.799412)
			(xy 86.93002 -269.833504) (xy 86.959585 -269.872848) (xy 86.982456 -269.916425) (xy 86.99804 -269.963106)
			(xy 87.005935 -270.011683) (xy 87.00643 -270.03629) (xy 87.324687 -270.03629) (xy 87.328782 -269.985562)
			(xy 87.340961 -269.936148) (xy 87.360909 -269.889328) (xy 87.38811 -269.846314) (xy 87.421858 -269.80822)
			(xy 87.46128 -269.776033) (xy 87.505354 -269.750587) (xy 87.55294 -269.73254) (xy 87.602804 -269.72236)
			(xy 87.653656 -269.720311) (xy 87.704177 -269.726445) (xy 87.753061 -269.740605) (xy 87.79904 -269.762422)
			(xy 87.840924 -269.791332) (xy 87.877628 -269.826587) (xy 87.908201 -269.867273) (xy 87.931852 -269.912336)
			(xy 87.947968 -269.96061) (xy 87.956132 -270.010844) (xy 87.956644 -270.03629) (xy 88.275172 -270.03629)
			(xy 88.279132 -269.987236) (xy 88.290909 -269.939452) (xy 88.3102 -269.894176) (xy 88.336503 -269.85258)
			(xy 88.369138 -269.815743) (xy 88.407259 -269.784618) (xy 88.44988 -269.760011) (xy 88.495896 -269.742559)
			(xy 88.544115 -269.732715) (xy 88.59329 -269.730734) (xy 88.642145 -269.736666) (xy 88.689416 -269.750358)
			(xy 88.733878 -269.771456) (xy 88.774381 -269.799412) (xy 88.809874 -269.833504) (xy 88.839439 -269.872848)
			(xy 88.86231 -269.916425) (xy 88.877894 -269.963106) (xy 88.885789 -270.011683) (xy 88.886284 -270.03629)
			(xy 89.204795 -270.03629) (xy 89.20889 -269.985562) (xy 89.221069 -269.936148) (xy 89.241017 -269.889328)
			(xy 89.268218 -269.846314) (xy 89.301966 -269.80822) (xy 89.341388 -269.776033) (xy 89.385462 -269.750587)
			(xy 89.433048 -269.73254) (xy 89.482912 -269.72236) (xy 89.533764 -269.720311) (xy 89.584285 -269.726445)
			(xy 89.633169 -269.740605) (xy 89.679148 -269.762422) (xy 89.721032 -269.791332) (xy 89.757736 -269.826587)
			(xy 89.788309 -269.867273) (xy 89.81196 -269.912336) (xy 89.828076 -269.96061) (xy 89.83624 -270.010844)
			(xy 89.836752 -270.03629) (xy 90.15528 -270.03629) (xy 90.15924 -269.987236) (xy 90.171017 -269.939452)
			(xy 90.190308 -269.894176) (xy 90.216611 -269.85258) (xy 90.249246 -269.815743) (xy 90.287367 -269.784618)
			(xy 90.329988 -269.760011) (xy 90.376004 -269.742559) (xy 90.424223 -269.732715) (xy 90.473398 -269.730734)
			(xy 90.522253 -269.736666) (xy 90.569524 -269.750358) (xy 90.613986 -269.771456) (xy 90.654489 -269.799412)
			(xy 90.689982 -269.833504) (xy 90.719547 -269.872848) (xy 90.742418 -269.916425) (xy 90.758002 -269.963106)
			(xy 90.765897 -270.011683) (xy 90.766392 -270.03629) (xy 91.084903 -270.03629) (xy 91.088998 -269.985562)
			(xy 91.101177 -269.936148) (xy 91.121125 -269.889328) (xy 91.148326 -269.846314) (xy 91.182074 -269.80822)
			(xy 91.221496 -269.776033) (xy 91.26557 -269.750587) (xy 91.313156 -269.73254) (xy 91.36302 -269.72236)
			(xy 91.413872 -269.720311) (xy 91.464393 -269.726445) (xy 91.513277 -269.740605) (xy 91.559256 -269.762422)
			(xy 91.60114 -269.791332) (xy 91.637844 -269.826587) (xy 91.668417 -269.867273) (xy 91.692068 -269.912336)
			(xy 91.708184 -269.96061) (xy 91.716348 -270.010844) (xy 91.71686 -270.03629) (xy 92.024703 -270.03629)
			(xy 92.028798 -269.985562) (xy 92.040977 -269.936148) (xy 92.060925 -269.889328) (xy 92.088126 -269.846314)
			(xy 92.121874 -269.80822) (xy 92.161296 -269.776033) (xy 92.20537 -269.750587) (xy 92.252956 -269.73254)
			(xy 92.30282 -269.72236) (xy 92.353672 -269.720311) (xy 92.404193 -269.726445) (xy 92.453077 -269.740605)
			(xy 92.499056 -269.762422) (xy 92.54094 -269.791332) (xy 92.577644 -269.826587) (xy 92.608217 -269.867273)
			(xy 92.631868 -269.912336) (xy 92.647984 -269.96061) (xy 92.656148 -270.010844) (xy 92.65666 -270.03629)
			(xy 92.975188 -270.03629) (xy 92.979148 -269.987236) (xy 92.990925 -269.939452) (xy 93.010216 -269.894176)
			(xy 93.036519 -269.85258) (xy 93.069154 -269.815743) (xy 93.107275 -269.784618) (xy 93.149896 -269.760011)
			(xy 93.195912 -269.742559) (xy 93.244131 -269.732715) (xy 93.293306 -269.730734) (xy 93.342161 -269.736666)
			(xy 93.389432 -269.750358) (xy 93.433894 -269.771456) (xy 93.474397 -269.799412) (xy 93.50989 -269.833504)
			(xy 93.539455 -269.872848) (xy 93.562326 -269.916425) (xy 93.57791 -269.963106) (xy 93.585805 -270.011683)
			(xy 93.5863 -270.03629) (xy 93.904811 -270.03629) (xy 93.908906 -269.985562) (xy 93.921085 -269.936148)
			(xy 93.941033 -269.889328) (xy 93.968234 -269.846314) (xy 94.001982 -269.80822) (xy 94.041404 -269.776033)
			(xy 94.085478 -269.750587) (xy 94.133064 -269.73254) (xy 94.182928 -269.72236) (xy 94.23378 -269.720311)
			(xy 94.284301 -269.726445) (xy 94.333185 -269.740605) (xy 94.379164 -269.762422) (xy 94.421048 -269.791332)
			(xy 94.457752 -269.826587) (xy 94.488325 -269.867273) (xy 94.511976 -269.912336) (xy 94.528092 -269.96061)
			(xy 94.536256 -270.010844) (xy 94.536768 -270.03629) (xy 94.855296 -270.03629) (xy 94.859256 -269.987236)
			(xy 94.871033 -269.939452) (xy 94.890324 -269.894176) (xy 94.916627 -269.85258) (xy 94.949262 -269.815743)
			(xy 94.987383 -269.784618) (xy 95.030004 -269.760011) (xy 95.07602 -269.742559) (xy 95.124239 -269.732715)
			(xy 95.173414 -269.730734) (xy 95.222269 -269.736666) (xy 95.26954 -269.750358) (xy 95.314002 -269.771456)
			(xy 95.354505 -269.799412) (xy 95.389998 -269.833504) (xy 95.419563 -269.872848) (xy 95.442434 -269.916425)
			(xy 95.458018 -269.963106) (xy 95.465913 -270.011683) (xy 95.466408 -270.03629) (xy 95.784919 -270.03629)
			(xy 95.789014 -269.985562) (xy 95.801193 -269.936148) (xy 95.821141 -269.889328) (xy 95.848342 -269.846314)
			(xy 95.88209 -269.80822) (xy 95.921512 -269.776033) (xy 95.965586 -269.750587) (xy 96.013172 -269.73254)
			(xy 96.063036 -269.72236) (xy 96.113888 -269.720311) (xy 96.164409 -269.726445) (xy 96.213293 -269.740605)
			(xy 96.259272 -269.762422) (xy 96.301156 -269.791332) (xy 96.33786 -269.826587) (xy 96.368433 -269.867273)
			(xy 96.392084 -269.912336) (xy 96.4082 -269.96061) (xy 96.416364 -270.010844) (xy 96.416876 -270.03629)
			(xy 96.73515 -270.03629) (xy 96.73911 -269.987236) (xy 96.750887 -269.939452) (xy 96.770178 -269.894176)
			(xy 96.796481 -269.85258) (xy 96.829116 -269.815743) (xy 96.867237 -269.784618) (xy 96.909858 -269.760011)
			(xy 96.955874 -269.742559) (xy 97.004093 -269.732715) (xy 97.053268 -269.730734) (xy 97.102123 -269.736666)
			(xy 97.149394 -269.750358) (xy 97.193856 -269.771456) (xy 97.234359 -269.799412) (xy 97.269852 -269.833504)
			(xy 97.299417 -269.872848) (xy 97.322288 -269.916425) (xy 97.337872 -269.963106) (xy 97.345767 -270.011683)
			(xy 97.346262 -270.03629) (xy 97.664773 -270.03629) (xy 97.668868 -269.985562) (xy 97.681047 -269.936148)
			(xy 97.700995 -269.889328) (xy 97.728196 -269.846314) (xy 97.761944 -269.80822) (xy 97.801366 -269.776033)
			(xy 97.84544 -269.750587) (xy 97.893026 -269.73254) (xy 97.94289 -269.72236) (xy 97.993742 -269.720311)
			(xy 98.044263 -269.726445) (xy 98.093147 -269.740605) (xy 98.139126 -269.762422) (xy 98.18101 -269.791332)
			(xy 98.217714 -269.826587) (xy 98.248287 -269.867273) (xy 98.271938 -269.912336) (xy 98.288054 -269.96061)
			(xy 98.296218 -270.010844) (xy 98.29673 -270.03629) (xy 98.604827 -270.03629) (xy 98.608922 -269.985562)
			(xy 98.621101 -269.936148) (xy 98.641049 -269.889328) (xy 98.66825 -269.846314) (xy 98.701998 -269.80822)
			(xy 98.74142 -269.776033) (xy 98.785494 -269.750587) (xy 98.83308 -269.73254) (xy 98.882944 -269.72236)
			(xy 98.933796 -269.720311) (xy 98.984317 -269.726445) (xy 99.033201 -269.740605) (xy 99.07918 -269.762422)
			(xy 99.121064 -269.791332) (xy 99.157768 -269.826587) (xy 99.188341 -269.867273) (xy 99.211992 -269.912336)
			(xy 99.228108 -269.96061) (xy 99.236272 -270.010844) (xy 99.236784 -270.03629) (xy 99.555312 -270.03629)
			(xy 99.559272 -269.987236) (xy 99.571049 -269.939452) (xy 99.59034 -269.894176) (xy 99.616643 -269.85258)
			(xy 99.649278 -269.815743) (xy 99.687399 -269.784618) (xy 99.73002 -269.760011) (xy 99.776036 -269.742559)
			(xy 99.824255 -269.732715) (xy 99.87343 -269.730734) (xy 99.922285 -269.736666) (xy 99.969556 -269.750358)
			(xy 100.014018 -269.771456) (xy 100.054521 -269.799412) (xy 100.090014 -269.833504) (xy 100.119579 -269.872848)
			(xy 100.14245 -269.916425) (xy 100.158034 -269.963106) (xy 100.165929 -270.011683) (xy 100.166424 -270.03629)
			(xy 100.484935 -270.03629) (xy 100.48903 -269.985562) (xy 100.501209 -269.936148) (xy 100.521157 -269.889328)
			(xy 100.548358 -269.846314) (xy 100.582106 -269.80822) (xy 100.621528 -269.776033) (xy 100.665602 -269.750587)
			(xy 100.713188 -269.73254) (xy 100.763052 -269.72236) (xy 100.813904 -269.720311) (xy 100.864425 -269.726445)
			(xy 100.913309 -269.740605) (xy 100.959288 -269.762422) (xy 101.001172 -269.791332) (xy 101.037876 -269.826587)
			(xy 101.068449 -269.867273) (xy 101.0921 -269.912336) (xy 101.108216 -269.96061) (xy 101.11638 -270.010844)
			(xy 101.116892 -270.03629) (xy 101.424735 -270.03629) (xy 101.42883 -269.985562) (xy 101.441009 -269.936148)
			(xy 101.460957 -269.889328) (xy 101.488158 -269.846314) (xy 101.521906 -269.80822) (xy 101.561328 -269.776033)
			(xy 101.605402 -269.750587) (xy 101.652988 -269.73254) (xy 101.702852 -269.72236) (xy 101.753704 -269.720311)
			(xy 101.804225 -269.726445) (xy 101.853109 -269.740605) (xy 101.899088 -269.762422) (xy 101.940972 -269.791332)
			(xy 101.977676 -269.826587) (xy 102.008249 -269.867273) (xy 102.0319 -269.912336) (xy 102.048016 -269.96061)
			(xy 102.05618 -270.010844) (xy 102.056692 -270.03629) (xy 102.05618 -270.061736) (xy 102.048016 -270.11197)
			(xy 102.0319 -270.160244) (xy 102.008249 -270.205307) (xy 101.977676 -270.245993) (xy 101.940972 -270.281248)
			(xy 101.899088 -270.310158) (xy 101.853109 -270.331975) (xy 101.804225 -270.346135) (xy 101.753704 -270.352269)
			(xy 101.702852 -270.35022) (xy 101.652988 -270.34004) (xy 101.605402 -270.321993) (xy 101.561328 -270.296547)
			(xy 101.521906 -270.26436) (xy 101.488158 -270.226266) (xy 101.460957 -270.183252) (xy 101.441009 -270.136432)
			(xy 101.42883 -270.087018) (xy 101.424735 -270.03629) (xy 101.116892 -270.03629) (xy 101.11638 -270.061736)
			(xy 101.108216 -270.11197) (xy 101.0921 -270.160244) (xy 101.068449 -270.205307) (xy 101.037876 -270.245993)
			(xy 101.001172 -270.281248) (xy 100.959288 -270.310158) (xy 100.913309 -270.331975) (xy 100.864425 -270.346135)
			(xy 100.813904 -270.352269) (xy 100.763052 -270.35022) (xy 100.713188 -270.34004) (xy 100.665602 -270.321993)
			(xy 100.621528 -270.296547) (xy 100.582106 -270.26436) (xy 100.548358 -270.226266) (xy 100.521157 -270.183252)
			(xy 100.501209 -270.136432) (xy 100.48903 -270.087018) (xy 100.484935 -270.03629) (xy 100.166424 -270.03629)
			(xy 100.165929 -270.060897) (xy 100.158034 -270.109474) (xy 100.14245 -270.156155) (xy 100.119579 -270.199732)
			(xy 100.090014 -270.239076) (xy 100.054521 -270.273168) (xy 100.014018 -270.301124) (xy 99.969556 -270.322222)
			(xy 99.922285 -270.335914) (xy 99.87343 -270.341846) (xy 99.824255 -270.339865) (xy 99.776036 -270.330021)
			(xy 99.73002 -270.312569) (xy 99.687399 -270.287962) (xy 99.649278 -270.256837) (xy 99.616643 -270.22)
			(xy 99.59034 -270.178404) (xy 99.571049 -270.133128) (xy 99.559272 -270.085344) (xy 99.555312 -270.03629)
			(xy 99.236784 -270.03629) (xy 99.236272 -270.061736) (xy 99.228108 -270.11197) (xy 99.211992 -270.160244)
			(xy 99.188341 -270.205307) (xy 99.157768 -270.245993) (xy 99.121064 -270.281248) (xy 99.07918 -270.310158)
			(xy 99.033201 -270.331975) (xy 98.984317 -270.346135) (xy 98.933796 -270.352269) (xy 98.882944 -270.35022)
			(xy 98.83308 -270.34004) (xy 98.785494 -270.321993) (xy 98.74142 -270.296547) (xy 98.701998 -270.26436)
			(xy 98.66825 -270.226266) (xy 98.641049 -270.183252) (xy 98.621101 -270.136432) (xy 98.608922 -270.087018)
			(xy 98.604827 -270.03629) (xy 98.29673 -270.03629) (xy 98.296218 -270.061736) (xy 98.288054 -270.11197)
			(xy 98.271938 -270.160244) (xy 98.248287 -270.205307) (xy 98.217714 -270.245993) (xy 98.18101 -270.281248)
			(xy 98.139126 -270.310158) (xy 98.093147 -270.331975) (xy 98.044263 -270.346135) (xy 97.993742 -270.352269)
			(xy 97.94289 -270.35022) (xy 97.893026 -270.34004) (xy 97.84544 -270.321993) (xy 97.801366 -270.296547)
			(xy 97.761944 -270.26436) (xy 97.728196 -270.226266) (xy 97.700995 -270.183252) (xy 97.681047 -270.136432)
			(xy 97.668868 -270.087018) (xy 97.664773 -270.03629) (xy 97.346262 -270.03629) (xy 97.345767 -270.060897)
			(xy 97.337872 -270.109474) (xy 97.322288 -270.156155) (xy 97.299417 -270.199732) (xy 97.269852 -270.239076)
			(xy 97.234359 -270.273168) (xy 97.193856 -270.301124) (xy 97.149394 -270.322222) (xy 97.102123 -270.335914)
			(xy 97.053268 -270.341846) (xy 97.004093 -270.339865) (xy 96.955874 -270.330021) (xy 96.909858 -270.312569)
			(xy 96.867237 -270.287962) (xy 96.829116 -270.256837) (xy 96.796481 -270.22) (xy 96.770178 -270.178404)
			(xy 96.750887 -270.133128) (xy 96.73911 -270.085344) (xy 96.73515 -270.03629) (xy 96.416876 -270.03629)
			(xy 96.416364 -270.061736) (xy 96.4082 -270.11197) (xy 96.392084 -270.160244) (xy 96.368433 -270.205307)
			(xy 96.33786 -270.245993) (xy 96.301156 -270.281248) (xy 96.259272 -270.310158) (xy 96.213293 -270.331975)
			(xy 96.164409 -270.346135) (xy 96.113888 -270.352269) (xy 96.063036 -270.35022) (xy 96.013172 -270.34004)
			(xy 95.965586 -270.321993) (xy 95.921512 -270.296547) (xy 95.88209 -270.26436) (xy 95.848342 -270.226266)
			(xy 95.821141 -270.183252) (xy 95.801193 -270.136432) (xy 95.789014 -270.087018) (xy 95.784919 -270.03629)
			(xy 95.466408 -270.03629) (xy 95.465913 -270.060897) (xy 95.458018 -270.109474) (xy 95.442434 -270.156155)
			(xy 95.419563 -270.199732) (xy 95.389998 -270.239076) (xy 95.354505 -270.273168) (xy 95.314002 -270.301124)
			(xy 95.26954 -270.322222) (xy 95.222269 -270.335914) (xy 95.173414 -270.341846) (xy 95.124239 -270.339865)
			(xy 95.07602 -270.330021) (xy 95.030004 -270.312569) (xy 94.987383 -270.287962) (xy 94.949262 -270.256837)
			(xy 94.916627 -270.22) (xy 94.890324 -270.178404) (xy 94.871033 -270.133128) (xy 94.859256 -270.085344)
			(xy 94.855296 -270.03629) (xy 94.536768 -270.03629) (xy 94.536256 -270.061736) (xy 94.528092 -270.11197)
			(xy 94.511976 -270.160244) (xy 94.488325 -270.205307) (xy 94.457752 -270.245993) (xy 94.421048 -270.281248)
			(xy 94.379164 -270.310158) (xy 94.333185 -270.331975) (xy 94.284301 -270.346135) (xy 94.23378 -270.352269)
			(xy 94.182928 -270.35022) (xy 94.133064 -270.34004) (xy 94.085478 -270.321993) (xy 94.041404 -270.296547)
			(xy 94.001982 -270.26436) (xy 93.968234 -270.226266) (xy 93.941033 -270.183252) (xy 93.921085 -270.136432)
			(xy 93.908906 -270.087018) (xy 93.904811 -270.03629) (xy 93.5863 -270.03629) (xy 93.585805 -270.060897)
			(xy 93.57791 -270.109474) (xy 93.562326 -270.156155) (xy 93.539455 -270.199732) (xy 93.50989 -270.239076)
			(xy 93.474397 -270.273168) (xy 93.433894 -270.301124) (xy 93.389432 -270.322222) (xy 93.342161 -270.335914)
			(xy 93.293306 -270.341846) (xy 93.244131 -270.339865) (xy 93.195912 -270.330021) (xy 93.149896 -270.312569)
			(xy 93.107275 -270.287962) (xy 93.069154 -270.256837) (xy 93.036519 -270.22) (xy 93.010216 -270.178404)
			(xy 92.990925 -270.133128) (xy 92.979148 -270.085344) (xy 92.975188 -270.03629) (xy 92.65666 -270.03629)
			(xy 92.656148 -270.061736) (xy 92.647984 -270.11197) (xy 92.631868 -270.160244) (xy 92.608217 -270.205307)
			(xy 92.577644 -270.245993) (xy 92.54094 -270.281248) (xy 92.499056 -270.310158) (xy 92.453077 -270.331975)
			(xy 92.404193 -270.346135) (xy 92.353672 -270.352269) (xy 92.30282 -270.35022) (xy 92.252956 -270.34004)
			(xy 92.20537 -270.321993) (xy 92.161296 -270.296547) (xy 92.121874 -270.26436) (xy 92.088126 -270.226266)
			(xy 92.060925 -270.183252) (xy 92.040977 -270.136432) (xy 92.028798 -270.087018) (xy 92.024703 -270.03629)
			(xy 91.71686 -270.03629) (xy 91.716348 -270.061736) (xy 91.708184 -270.11197) (xy 91.692068 -270.160244)
			(xy 91.668417 -270.205307) (xy 91.637844 -270.245993) (xy 91.60114 -270.281248) (xy 91.559256 -270.310158)
			(xy 91.513277 -270.331975) (xy 91.464393 -270.346135) (xy 91.413872 -270.352269) (xy 91.36302 -270.35022)
			(xy 91.313156 -270.34004) (xy 91.26557 -270.321993) (xy 91.221496 -270.296547) (xy 91.182074 -270.26436)
			(xy 91.148326 -270.226266) (xy 91.121125 -270.183252) (xy 91.101177 -270.136432) (xy 91.088998 -270.087018)
			(xy 91.084903 -270.03629) (xy 90.766392 -270.03629) (xy 90.765897 -270.060897) (xy 90.758002 -270.109474)
			(xy 90.742418 -270.156155) (xy 90.719547 -270.199732) (xy 90.689982 -270.239076) (xy 90.654489 -270.273168)
			(xy 90.613986 -270.301124) (xy 90.569524 -270.322222) (xy 90.522253 -270.335914) (xy 90.473398 -270.341846)
			(xy 90.424223 -270.339865) (xy 90.376004 -270.330021) (xy 90.329988 -270.312569) (xy 90.287367 -270.287962)
			(xy 90.249246 -270.256837) (xy 90.216611 -270.22) (xy 90.190308 -270.178404) (xy 90.171017 -270.133128)
			(xy 90.15924 -270.085344) (xy 90.15528 -270.03629) (xy 89.836752 -270.03629) (xy 89.83624 -270.061736)
			(xy 89.828076 -270.11197) (xy 89.81196 -270.160244) (xy 89.788309 -270.205307) (xy 89.757736 -270.245993)
			(xy 89.721032 -270.281248) (xy 89.679148 -270.310158) (xy 89.633169 -270.331975) (xy 89.584285 -270.346135)
			(xy 89.533764 -270.352269) (xy 89.482912 -270.35022) (xy 89.433048 -270.34004) (xy 89.385462 -270.321993)
			(xy 89.341388 -270.296547) (xy 89.301966 -270.26436) (xy 89.268218 -270.226266) (xy 89.241017 -270.183252)
			(xy 89.221069 -270.136432) (xy 89.20889 -270.087018) (xy 89.204795 -270.03629) (xy 88.886284 -270.03629)
			(xy 88.885789 -270.060897) (xy 88.877894 -270.109474) (xy 88.86231 -270.156155) (xy 88.839439 -270.199732)
			(xy 88.809874 -270.239076) (xy 88.774381 -270.273168) (xy 88.733878 -270.301124) (xy 88.689416 -270.322222)
			(xy 88.642145 -270.335914) (xy 88.59329 -270.341846) (xy 88.544115 -270.339865) (xy 88.495896 -270.330021)
			(xy 88.44988 -270.312569) (xy 88.407259 -270.287962) (xy 88.369138 -270.256837) (xy 88.336503 -270.22)
			(xy 88.3102 -270.178404) (xy 88.290909 -270.133128) (xy 88.279132 -270.085344) (xy 88.275172 -270.03629)
			(xy 87.956644 -270.03629) (xy 87.956132 -270.061736) (xy 87.947968 -270.11197) (xy 87.931852 -270.160244)
			(xy 87.908201 -270.205307) (xy 87.877628 -270.245993) (xy 87.840924 -270.281248) (xy 87.79904 -270.310158)
			(xy 87.753061 -270.331975) (xy 87.704177 -270.346135) (xy 87.653656 -270.352269) (xy 87.602804 -270.35022)
			(xy 87.55294 -270.34004) (xy 87.505354 -270.321993) (xy 87.46128 -270.296547) (xy 87.421858 -270.26436)
			(xy 87.38811 -270.226266) (xy 87.360909 -270.183252) (xy 87.340961 -270.136432) (xy 87.328782 -270.087018)
			(xy 87.324687 -270.03629) (xy 87.00643 -270.03629) (xy 87.005935 -270.060897) (xy 86.99804 -270.109474)
			(xy 86.982456 -270.156155) (xy 86.959585 -270.199732) (xy 86.93002 -270.239076) (xy 86.894527 -270.273168)
			(xy 86.854024 -270.301124) (xy 86.809562 -270.322222) (xy 86.762291 -270.335914) (xy 86.713436 -270.341846)
			(xy 86.664261 -270.339865) (xy 86.616042 -270.330021) (xy 86.570026 -270.312569) (xy 86.527405 -270.287962)
			(xy 86.489284 -270.256837) (xy 86.456649 -270.22) (xy 86.430346 -270.178404) (xy 86.411055 -270.133128)
			(xy 86.399278 -270.085344) (xy 86.395318 -270.03629) (xy 86.07679 -270.03629) (xy 86.076278 -270.061736)
			(xy 86.068114 -270.11197) (xy 86.051998 -270.160244) (xy 86.028347 -270.205307) (xy 85.997774 -270.245993)
			(xy 85.96107 -270.281248) (xy 85.919186 -270.310158) (xy 85.873207 -270.331975) (xy 85.824323 -270.346135)
			(xy 85.773802 -270.352269) (xy 85.72295 -270.35022) (xy 85.673086 -270.34004) (xy 85.6255 -270.321993)
			(xy 85.581426 -270.296547) (xy 85.542004 -270.26436) (xy 85.508256 -270.226266) (xy 85.481055 -270.183252)
			(xy 85.461107 -270.136432) (xy 85.448928 -270.087018) (xy 85.444833 -270.03629) (xy 85.136736 -270.03629)
			(xy 85.136224 -270.061736) (xy 85.12806 -270.11197) (xy 85.111944 -270.160244) (xy 85.088293 -270.205307)
			(xy 85.05772 -270.245993) (xy 85.021016 -270.281248) (xy 84.979132 -270.310158) (xy 84.933153 -270.331975)
			(xy 84.884269 -270.346135) (xy 84.833748 -270.352269) (xy 84.782896 -270.35022) (xy 84.733032 -270.34004)
			(xy 84.685446 -270.321993) (xy 84.641372 -270.296547) (xy 84.60195 -270.26436) (xy 84.568202 -270.226266)
			(xy 84.541001 -270.183252) (xy 84.521053 -270.136432) (xy 84.508874 -270.087018) (xy 84.504779 -270.03629)
			(xy 84.186268 -270.03629) (xy 84.185773 -270.060897) (xy 84.177878 -270.109474) (xy 84.162294 -270.156155)
			(xy 84.139423 -270.199732) (xy 84.109858 -270.239076) (xy 84.074365 -270.273168) (xy 84.033862 -270.301124)
			(xy 83.9894 -270.322222) (xy 83.942129 -270.335914) (xy 83.893274 -270.341846) (xy 83.844099 -270.339865)
			(xy 83.79588 -270.330021) (xy 83.749864 -270.312569) (xy 83.707243 -270.287962) (xy 83.669122 -270.256837)
			(xy 83.636487 -270.22) (xy 83.610184 -270.178404) (xy 83.590893 -270.133128) (xy 83.579116 -270.085344)
			(xy 83.575156 -270.03629) (xy 83.256628 -270.03629) (xy 83.256116 -270.061736) (xy 83.247952 -270.11197)
			(xy 83.231836 -270.160244) (xy 83.208185 -270.205307) (xy 83.177612 -270.245993) (xy 83.140908 -270.281248)
			(xy 83.099024 -270.310158) (xy 83.053045 -270.331975) (xy 83.004161 -270.346135) (xy 82.95364 -270.352269)
			(xy 82.902788 -270.35022) (xy 82.852924 -270.34004) (xy 82.805338 -270.321993) (xy 82.761264 -270.296547)
			(xy 82.721842 -270.26436) (xy 82.688094 -270.226266) (xy 82.660893 -270.183252) (xy 82.640945 -270.136432)
			(xy 82.628766 -270.087018) (xy 82.624671 -270.03629) (xy 82.306414 -270.03629) (xy 82.305919 -270.060897)
			(xy 82.298024 -270.109474) (xy 82.28244 -270.156155) (xy 82.259569 -270.199732) (xy 82.230004 -270.239076)
			(xy 82.194511 -270.273168) (xy 82.154008 -270.301124) (xy 82.109546 -270.322222) (xy 82.062275 -270.335914)
			(xy 82.01342 -270.341846) (xy 81.964245 -270.339865) (xy 81.916026 -270.330021) (xy 81.87001 -270.312569)
			(xy 81.827389 -270.287962) (xy 81.789268 -270.256837) (xy 81.756633 -270.22) (xy 81.73033 -270.178404)
			(xy 81.711039 -270.133128) (xy 81.699262 -270.085344) (xy 81.695302 -270.03629) (xy 81.376774 -270.03629)
			(xy 81.376262 -270.061736) (xy 81.368098 -270.11197) (xy 81.351982 -270.160244) (xy 81.328331 -270.205307)
			(xy 81.297758 -270.245993) (xy 81.261054 -270.281248) (xy 81.21917 -270.310158) (xy 81.173191 -270.331975)
			(xy 81.124307 -270.346135) (xy 81.073786 -270.352269) (xy 81.022934 -270.35022) (xy 80.97307 -270.34004)
			(xy 80.925484 -270.321993) (xy 80.88141 -270.296547) (xy 80.841988 -270.26436) (xy 80.80824 -270.226266)
			(xy 80.781039 -270.183252) (xy 80.761091 -270.136432) (xy 80.748912 -270.087018) (xy 80.744817 -270.03629)
			(xy 80.426306 -270.03629) (xy 80.425811 -270.060897) (xy 80.417916 -270.109474) (xy 80.402332 -270.156155)
			(xy 80.379461 -270.199732) (xy 80.349896 -270.239076) (xy 80.314403 -270.273168) (xy 80.2739 -270.301124)
			(xy 80.229438 -270.322222) (xy 80.182167 -270.335914) (xy 80.133312 -270.341846) (xy 80.084137 -270.339865)
			(xy 80.035918 -270.330021) (xy 79.989902 -270.312569) (xy 79.947281 -270.287962) (xy 79.90916 -270.256837)
			(xy 79.876525 -270.22) (xy 79.850222 -270.178404) (xy 79.830931 -270.133128) (xy 79.819154 -270.085344)
			(xy 79.815194 -270.03629) (xy 77.263451 -270.03629) (xy 77.221316 -270.056284) (xy 77.174045 -270.069976)
			(xy 77.12519 -270.075908) (xy 77.076015 -270.073927) (xy 77.027796 -270.064083) (xy 76.98178 -270.046631)
			(xy 76.939159 -270.022024) (xy 76.901038 -269.990899) (xy 76.868403 -269.954062) (xy 76.8421 -269.912466)
			(xy 76.822809 -269.86719) (xy 76.811032 -269.819406) (xy 76.807072 -269.770352) (xy 73.228962 -269.770352)
			(xy 73.228962 -270.846296) (xy 78.40524 -270.846296) (xy 78.4092 -270.797242) (xy 78.420977 -270.749458)
			(xy 78.440268 -270.704182) (xy 78.466571 -270.662586) (xy 78.499206 -270.625749) (xy 78.537327 -270.594624)
			(xy 78.579948 -270.570017) (xy 78.625964 -270.552565) (xy 78.674183 -270.542721) (xy 78.723358 -270.54074)
			(xy 78.772213 -270.546672) (xy 78.819484 -270.560364) (xy 78.863946 -270.581462) (xy 78.904449 -270.609418)
			(xy 78.939942 -270.64351) (xy 78.969507 -270.682854) (xy 78.992378 -270.726431) (xy 79.007962 -270.773112)
			(xy 79.015857 -270.821689) (xy 79.016352 -270.846296) (xy 80.285348 -270.846296) (xy 80.289308 -270.797242)
			(xy 80.301085 -270.749458) (xy 80.320376 -270.704182) (xy 80.346679 -270.662586) (xy 80.379314 -270.625749)
			(xy 80.417435 -270.594624) (xy 80.460056 -270.570017) (xy 80.506072 -270.552565) (xy 80.554291 -270.542721)
			(xy 80.603466 -270.54074) (xy 80.652321 -270.546672) (xy 80.699592 -270.560364) (xy 80.744054 -270.581462)
			(xy 80.784557 -270.609418) (xy 80.82005 -270.64351) (xy 80.849615 -270.682854) (xy 80.872486 -270.726431)
			(xy 80.88807 -270.773112) (xy 80.895965 -270.821689) (xy 80.89646 -270.846296) (xy 81.214717 -270.846296)
			(xy 81.218812 -270.795568) (xy 81.230991 -270.746154) (xy 81.250939 -270.699334) (xy 81.27814 -270.65632)
			(xy 81.311888 -270.618226) (xy 81.35131 -270.586039) (xy 81.395384 -270.560593) (xy 81.44297 -270.542546)
			(xy 81.492834 -270.532366) (xy 81.543686 -270.530317) (xy 81.594207 -270.536451) (xy 81.643091 -270.550611)
			(xy 81.68907 -270.572428) (xy 81.730954 -270.601338) (xy 81.767658 -270.636593) (xy 81.798231 -270.677279)
			(xy 81.821882 -270.722342) (xy 81.837998 -270.770616) (xy 81.846162 -270.82085) (xy 81.846674 -270.846296)
			(xy 82.154771 -270.846296) (xy 82.158866 -270.795568) (xy 82.171045 -270.746154) (xy 82.190993 -270.699334)
			(xy 82.218194 -270.65632) (xy 82.251942 -270.618226) (xy 82.291364 -270.586039) (xy 82.335438 -270.560593)
			(xy 82.383024 -270.542546) (xy 82.432888 -270.532366) (xy 82.48374 -270.530317) (xy 82.534261 -270.536451)
			(xy 82.583145 -270.550611) (xy 82.629124 -270.572428) (xy 82.671008 -270.601338) (xy 82.707712 -270.636593)
			(xy 82.738285 -270.677279) (xy 82.761936 -270.722342) (xy 82.778052 -270.770616) (xy 82.786216 -270.82085)
			(xy 82.786728 -270.846296) (xy 83.105256 -270.846296) (xy 83.109216 -270.797242) (xy 83.120993 -270.749458)
			(xy 83.140284 -270.704182) (xy 83.166587 -270.662586) (xy 83.199222 -270.625749) (xy 83.237343 -270.594624)
			(xy 83.279964 -270.570017) (xy 83.32598 -270.552565) (xy 83.374199 -270.542721) (xy 83.423374 -270.54074)
			(xy 83.472229 -270.546672) (xy 83.5195 -270.560364) (xy 83.563962 -270.581462) (xy 83.604465 -270.609418)
			(xy 83.639958 -270.64351) (xy 83.669523 -270.682854) (xy 83.692394 -270.726431) (xy 83.707978 -270.773112)
			(xy 83.715873 -270.821689) (xy 83.716368 -270.846296) (xy 84.034879 -270.846296) (xy 84.038974 -270.795568)
			(xy 84.051153 -270.746154) (xy 84.071101 -270.699334) (xy 84.098302 -270.65632) (xy 84.13205 -270.618226)
			(xy 84.171472 -270.586039) (xy 84.215546 -270.560593) (xy 84.263132 -270.542546) (xy 84.312996 -270.532366)
			(xy 84.363848 -270.530317) (xy 84.414369 -270.536451) (xy 84.463253 -270.550611) (xy 84.509232 -270.572428)
			(xy 84.551116 -270.601338) (xy 84.58782 -270.636593) (xy 84.618393 -270.677279) (xy 84.642044 -270.722342)
			(xy 84.65816 -270.770616) (xy 84.666324 -270.82085) (xy 84.666836 -270.846296) (xy 84.98511 -270.846296)
			(xy 84.98907 -270.797242) (xy 85.000847 -270.749458) (xy 85.020138 -270.704182) (xy 85.046441 -270.662586)
			(xy 85.079076 -270.625749) (xy 85.117197 -270.594624) (xy 85.159818 -270.570017) (xy 85.205834 -270.552565)
			(xy 85.254053 -270.542721) (xy 85.303228 -270.54074) (xy 85.352083 -270.546672) (xy 85.399354 -270.560364)
			(xy 85.443816 -270.581462) (xy 85.484319 -270.609418) (xy 85.519812 -270.64351) (xy 85.549377 -270.682854)
			(xy 85.572248 -270.726431) (xy 85.587832 -270.773112) (xy 85.595727 -270.821689) (xy 85.596222 -270.846296)
			(xy 85.914733 -270.846296) (xy 85.918828 -270.795568) (xy 85.931007 -270.746154) (xy 85.950955 -270.699334)
			(xy 85.978156 -270.65632) (xy 86.011904 -270.618226) (xy 86.051326 -270.586039) (xy 86.0954 -270.560593)
			(xy 86.142986 -270.542546) (xy 86.19285 -270.532366) (xy 86.243702 -270.530317) (xy 86.294223 -270.536451)
			(xy 86.343107 -270.550611) (xy 86.389086 -270.572428) (xy 86.43097 -270.601338) (xy 86.467674 -270.636593)
			(xy 86.498247 -270.677279) (xy 86.521898 -270.722342) (xy 86.538014 -270.770616) (xy 86.546178 -270.82085)
			(xy 86.54669 -270.846296) (xy 86.865218 -270.846296) (xy 86.869178 -270.797242) (xy 86.880955 -270.749458)
			(xy 86.900246 -270.704182) (xy 86.926549 -270.662586) (xy 86.959184 -270.625749) (xy 86.997305 -270.594624)
			(xy 87.039926 -270.570017) (xy 87.085942 -270.552565) (xy 87.134161 -270.542721) (xy 87.183336 -270.54074)
			(xy 87.232191 -270.546672) (xy 87.279462 -270.560364) (xy 87.323924 -270.581462) (xy 87.364427 -270.609418)
			(xy 87.39992 -270.64351) (xy 87.429485 -270.682854) (xy 87.452356 -270.726431) (xy 87.46794 -270.773112)
			(xy 87.475835 -270.821689) (xy 87.47633 -270.846296) (xy 87.794841 -270.846296) (xy 87.798936 -270.795568)
			(xy 87.811115 -270.746154) (xy 87.831063 -270.699334) (xy 87.858264 -270.65632) (xy 87.892012 -270.618226)
			(xy 87.931434 -270.586039) (xy 87.975508 -270.560593) (xy 88.023094 -270.542546) (xy 88.072958 -270.532366)
			(xy 88.12381 -270.530317) (xy 88.174331 -270.536451) (xy 88.223215 -270.550611) (xy 88.269194 -270.572428)
			(xy 88.311078 -270.601338) (xy 88.347782 -270.636593) (xy 88.378355 -270.677279) (xy 88.402006 -270.722342)
			(xy 88.418122 -270.770616) (xy 88.426286 -270.82085) (xy 88.426798 -270.846296) (xy 88.734895 -270.846296)
			(xy 88.73899 -270.795568) (xy 88.751169 -270.746154) (xy 88.771117 -270.699334) (xy 88.798318 -270.65632)
			(xy 88.832066 -270.618226) (xy 88.871488 -270.586039) (xy 88.915562 -270.560593) (xy 88.963148 -270.542546)
			(xy 89.013012 -270.532366) (xy 89.063864 -270.530317) (xy 89.114385 -270.536451) (xy 89.163269 -270.550611)
			(xy 89.209248 -270.572428) (xy 89.251132 -270.601338) (xy 89.287836 -270.636593) (xy 89.318409 -270.677279)
			(xy 89.34206 -270.722342) (xy 89.358176 -270.770616) (xy 89.36634 -270.82085) (xy 89.366852 -270.846296)
			(xy 89.685126 -270.846296) (xy 89.689086 -270.797242) (xy 89.700863 -270.749458) (xy 89.720154 -270.704182)
			(xy 89.746457 -270.662586) (xy 89.779092 -270.625749) (xy 89.817213 -270.594624) (xy 89.859834 -270.570017)
			(xy 89.90585 -270.552565) (xy 89.954069 -270.542721) (xy 90.003244 -270.54074) (xy 90.052099 -270.546672)
			(xy 90.09937 -270.560364) (xy 90.143832 -270.581462) (xy 90.184335 -270.609418) (xy 90.219828 -270.64351)
			(xy 90.249393 -270.682854) (xy 90.272264 -270.726431) (xy 90.287848 -270.773112) (xy 90.295743 -270.821689)
			(xy 90.296238 -270.846296) (xy 90.614749 -270.846296) (xy 90.618844 -270.795568) (xy 90.631023 -270.746154)
			(xy 90.650971 -270.699334) (xy 90.678172 -270.65632) (xy 90.71192 -270.618226) (xy 90.751342 -270.586039)
			(xy 90.795416 -270.560593) (xy 90.843002 -270.542546) (xy 90.892866 -270.532366) (xy 90.943718 -270.530317)
			(xy 90.994239 -270.536451) (xy 91.043123 -270.550611) (xy 91.089102 -270.572428) (xy 91.130986 -270.601338)
			(xy 91.16769 -270.636593) (xy 91.198263 -270.677279) (xy 91.221914 -270.722342) (xy 91.23803 -270.770616)
			(xy 91.246194 -270.82085) (xy 91.246706 -270.846296) (xy 91.565234 -270.846296) (xy 91.569194 -270.797242)
			(xy 91.580971 -270.749458) (xy 91.600262 -270.704182) (xy 91.626565 -270.662586) (xy 91.6592 -270.625749)
			(xy 91.697321 -270.594624) (xy 91.739942 -270.570017) (xy 91.785958 -270.552565) (xy 91.834177 -270.542721)
			(xy 91.883352 -270.54074) (xy 91.932207 -270.546672) (xy 91.979478 -270.560364) (xy 92.02394 -270.581462)
			(xy 92.064443 -270.609418) (xy 92.099936 -270.64351) (xy 92.129501 -270.682854) (xy 92.152372 -270.726431)
			(xy 92.167956 -270.773112) (xy 92.175851 -270.821689) (xy 92.176346 -270.846296) (xy 92.494857 -270.846296)
			(xy 92.498952 -270.795568) (xy 92.511131 -270.746154) (xy 92.531079 -270.699334) (xy 92.55828 -270.65632)
			(xy 92.592028 -270.618226) (xy 92.63145 -270.586039) (xy 92.675524 -270.560593) (xy 92.72311 -270.542546)
			(xy 92.772974 -270.532366) (xy 92.823826 -270.530317) (xy 92.874347 -270.536451) (xy 92.923231 -270.550611)
			(xy 92.96921 -270.572428) (xy 93.011094 -270.601338) (xy 93.047798 -270.636593) (xy 93.078371 -270.677279)
			(xy 93.102022 -270.722342) (xy 93.118138 -270.770616) (xy 93.126302 -270.82085) (xy 93.126814 -270.846296)
			(xy 93.445342 -270.846296) (xy 93.449302 -270.797242) (xy 93.461079 -270.749458) (xy 93.48037 -270.704182)
			(xy 93.506673 -270.662586) (xy 93.539308 -270.625749) (xy 93.577429 -270.594624) (xy 93.62005 -270.570017)
			(xy 93.666066 -270.552565) (xy 93.714285 -270.542721) (xy 93.76346 -270.54074) (xy 93.812315 -270.546672)
			(xy 93.859586 -270.560364) (xy 93.904048 -270.581462) (xy 93.944551 -270.609418) (xy 93.980044 -270.64351)
			(xy 94.009609 -270.682854) (xy 94.03248 -270.726431) (xy 94.048064 -270.773112) (xy 94.055959 -270.821689)
			(xy 94.056454 -270.846296) (xy 94.374711 -270.846296) (xy 94.378806 -270.795568) (xy 94.390985 -270.746154)
			(xy 94.410933 -270.699334) (xy 94.438134 -270.65632) (xy 94.471882 -270.618226) (xy 94.511304 -270.586039)
			(xy 94.555378 -270.560593) (xy 94.602964 -270.542546) (xy 94.652828 -270.532366) (xy 94.70368 -270.530317)
			(xy 94.754201 -270.536451) (xy 94.803085 -270.550611) (xy 94.849064 -270.572428) (xy 94.890948 -270.601338)
			(xy 94.927652 -270.636593) (xy 94.958225 -270.677279) (xy 94.981876 -270.722342) (xy 94.997992 -270.770616)
			(xy 95.006156 -270.82085) (xy 95.006668 -270.846296) (xy 95.314765 -270.846296) (xy 95.31886 -270.795568)
			(xy 95.331039 -270.746154) (xy 95.350987 -270.699334) (xy 95.378188 -270.65632) (xy 95.411936 -270.618226)
			(xy 95.451358 -270.586039) (xy 95.495432 -270.560593) (xy 95.543018 -270.542546) (xy 95.592882 -270.532366)
			(xy 95.643734 -270.530317) (xy 95.694255 -270.536451) (xy 95.743139 -270.550611) (xy 95.789118 -270.572428)
			(xy 95.831002 -270.601338) (xy 95.867706 -270.636593) (xy 95.898279 -270.677279) (xy 95.92193 -270.722342)
			(xy 95.938046 -270.770616) (xy 95.94621 -270.82085) (xy 95.946722 -270.846296) (xy 96.26525 -270.846296)
			(xy 96.26921 -270.797242) (xy 96.280987 -270.749458) (xy 96.300278 -270.704182) (xy 96.326581 -270.662586)
			(xy 96.359216 -270.625749) (xy 96.397337 -270.594624) (xy 96.439958 -270.570017) (xy 96.485974 -270.552565)
			(xy 96.534193 -270.542721) (xy 96.583368 -270.54074) (xy 96.632223 -270.546672) (xy 96.679494 -270.560364)
			(xy 96.723956 -270.581462) (xy 96.764459 -270.609418) (xy 96.799952 -270.64351) (xy 96.829517 -270.682854)
			(xy 96.852388 -270.726431) (xy 96.867972 -270.773112) (xy 96.875867 -270.821689) (xy 96.876362 -270.846296)
			(xy 97.205304 -270.846296) (xy 97.209264 -270.797242) (xy 97.221041 -270.749458) (xy 97.240332 -270.704182)
			(xy 97.266635 -270.662586) (xy 97.29927 -270.625749) (xy 97.337391 -270.594624) (xy 97.380012 -270.570017)
			(xy 97.426028 -270.552565) (xy 97.474247 -270.542721) (xy 97.523422 -270.54074) (xy 97.572277 -270.546672)
			(xy 97.619548 -270.560364) (xy 97.66401 -270.581462) (xy 97.704513 -270.609418) (xy 97.740006 -270.64351)
			(xy 97.769571 -270.682854) (xy 97.792442 -270.726431) (xy 97.808026 -270.773112) (xy 97.815921 -270.821689)
			(xy 97.816416 -270.846296) (xy 98.145358 -270.846296) (xy 98.149318 -270.797242) (xy 98.161095 -270.749458)
			(xy 98.180386 -270.704182) (xy 98.206689 -270.662586) (xy 98.239324 -270.625749) (xy 98.277445 -270.594624)
			(xy 98.320066 -270.570017) (xy 98.366082 -270.552565) (xy 98.414301 -270.542721) (xy 98.463476 -270.54074)
			(xy 98.512331 -270.546672) (xy 98.559602 -270.560364) (xy 98.604064 -270.581462) (xy 98.644567 -270.609418)
			(xy 98.68006 -270.64351) (xy 98.709625 -270.682854) (xy 98.732496 -270.726431) (xy 98.74808 -270.773112)
			(xy 98.755975 -270.821689) (xy 98.75647 -270.846296) (xy 99.085158 -270.846296) (xy 99.089118 -270.797242)
			(xy 99.100895 -270.749458) (xy 99.120186 -270.704182) (xy 99.146489 -270.662586) (xy 99.179124 -270.625749)
			(xy 99.217245 -270.594624) (xy 99.259866 -270.570017) (xy 99.305882 -270.552565) (xy 99.354101 -270.542721)
			(xy 99.403276 -270.54074) (xy 99.452131 -270.546672) (xy 99.499402 -270.560364) (xy 99.543864 -270.581462)
			(xy 99.584367 -270.609418) (xy 99.61986 -270.64351) (xy 99.649425 -270.682854) (xy 99.672296 -270.726431)
			(xy 99.68788 -270.773112) (xy 99.695775 -270.821689) (xy 99.69627 -270.846296) (xy 100.025212 -270.846296)
			(xy 100.029172 -270.797242) (xy 100.040949 -270.749458) (xy 100.06024 -270.704182) (xy 100.086543 -270.662586)
			(xy 100.119178 -270.625749) (xy 100.157299 -270.594624) (xy 100.19992 -270.570017) (xy 100.245936 -270.552565)
			(xy 100.294155 -270.542721) (xy 100.34333 -270.54074) (xy 100.392185 -270.546672) (xy 100.439456 -270.560364)
			(xy 100.483918 -270.581462) (xy 100.524421 -270.609418) (xy 100.559914 -270.64351) (xy 100.589479 -270.682854)
			(xy 100.61235 -270.726431) (xy 100.627934 -270.773112) (xy 100.635829 -270.821689) (xy 100.636324 -270.846296)
			(xy 100.965266 -270.846296) (xy 100.969226 -270.797242) (xy 100.981003 -270.749458) (xy 101.000294 -270.704182)
			(xy 101.026597 -270.662586) (xy 101.059232 -270.625749) (xy 101.097353 -270.594624) (xy 101.139974 -270.570017)
			(xy 101.18599 -270.552565) (xy 101.234209 -270.542721) (xy 101.283384 -270.54074) (xy 101.332239 -270.546672)
			(xy 101.37951 -270.560364) (xy 101.423972 -270.581462) (xy 101.464475 -270.609418) (xy 101.499968 -270.64351)
			(xy 101.529533 -270.682854) (xy 101.552404 -270.726431) (xy 101.567988 -270.773112) (xy 101.575883 -270.821689)
			(xy 101.576378 -270.846296) (xy 101.90532 -270.846296) (xy 101.90928 -270.797242) (xy 101.921057 -270.749458)
			(xy 101.940348 -270.704182) (xy 101.966651 -270.662586) (xy 101.999286 -270.625749) (xy 102.037407 -270.594624)
			(xy 102.080028 -270.570017) (xy 102.126044 -270.552565) (xy 102.174263 -270.542721) (xy 102.223438 -270.54074)
			(xy 102.272293 -270.546672) (xy 102.319564 -270.560364) (xy 102.364026 -270.581462) (xy 102.404529 -270.609418)
			(xy 102.440022 -270.64351) (xy 102.469587 -270.682854) (xy 102.492458 -270.726431) (xy 102.508042 -270.773112)
			(xy 102.515937 -270.821689) (xy 102.516432 -270.846296) (xy 102.515937 -270.870903) (xy 102.508042 -270.91948)
			(xy 102.492458 -270.966161) (xy 102.469587 -271.009738) (xy 102.440022 -271.049082) (xy 102.404529 -271.083174)
			(xy 102.364026 -271.11113) (xy 102.319564 -271.132228) (xy 102.272293 -271.14592) (xy 102.223438 -271.151852)
			(xy 102.174263 -271.149871) (xy 102.126044 -271.140027) (xy 102.080028 -271.122575) (xy 102.037407 -271.097968)
			(xy 101.999286 -271.066843) (xy 101.966651 -271.030006) (xy 101.940348 -270.98841) (xy 101.921057 -270.943134)
			(xy 101.90928 -270.89535) (xy 101.90532 -270.846296) (xy 101.576378 -270.846296) (xy 101.575883 -270.870903)
			(xy 101.567988 -270.91948) (xy 101.552404 -270.966161) (xy 101.529533 -271.009738) (xy 101.499968 -271.049082)
			(xy 101.464475 -271.083174) (xy 101.423972 -271.11113) (xy 101.37951 -271.132228) (xy 101.332239 -271.14592)
			(xy 101.283384 -271.151852) (xy 101.234209 -271.149871) (xy 101.18599 -271.140027) (xy 101.139974 -271.122575)
			(xy 101.097353 -271.097968) (xy 101.059232 -271.066843) (xy 101.026597 -271.030006) (xy 101.000294 -270.98841)
			(xy 100.981003 -270.943134) (xy 100.969226 -270.89535) (xy 100.965266 -270.846296) (xy 100.636324 -270.846296)
			(xy 100.635829 -270.870903) (xy 100.627934 -270.91948) (xy 100.61235 -270.966161) (xy 100.589479 -271.009738)
			(xy 100.559914 -271.049082) (xy 100.524421 -271.083174) (xy 100.483918 -271.11113) (xy 100.439456 -271.132228)
			(xy 100.392185 -271.14592) (xy 100.34333 -271.151852) (xy 100.294155 -271.149871) (xy 100.245936 -271.140027)
			(xy 100.19992 -271.122575) (xy 100.157299 -271.097968) (xy 100.119178 -271.066843) (xy 100.086543 -271.030006)
			(xy 100.06024 -270.98841) (xy 100.040949 -270.943134) (xy 100.029172 -270.89535) (xy 100.025212 -270.846296)
			(xy 99.69627 -270.846296) (xy 99.695775 -270.870903) (xy 99.68788 -270.91948) (xy 99.672296 -270.966161)
			(xy 99.649425 -271.009738) (xy 99.61986 -271.049082) (xy 99.584367 -271.083174) (xy 99.543864 -271.11113)
			(xy 99.499402 -271.132228) (xy 99.452131 -271.14592) (xy 99.403276 -271.151852) (xy 99.354101 -271.149871)
			(xy 99.305882 -271.140027) (xy 99.259866 -271.122575) (xy 99.217245 -271.097968) (xy 99.179124 -271.066843)
			(xy 99.146489 -271.030006) (xy 99.120186 -270.98841) (xy 99.100895 -270.943134) (xy 99.089118 -270.89535)
			(xy 99.085158 -270.846296) (xy 98.75647 -270.846296) (xy 98.755975 -270.870903) (xy 98.74808 -270.91948)
			(xy 98.732496 -270.966161) (xy 98.709625 -271.009738) (xy 98.68006 -271.049082) (xy 98.644567 -271.083174)
			(xy 98.604064 -271.11113) (xy 98.559602 -271.132228) (xy 98.512331 -271.14592) (xy 98.463476 -271.151852)
			(xy 98.414301 -271.149871) (xy 98.366082 -271.140027) (xy 98.320066 -271.122575) (xy 98.277445 -271.097968)
			(xy 98.239324 -271.066843) (xy 98.206689 -271.030006) (xy 98.180386 -270.98841) (xy 98.161095 -270.943134)
			(xy 98.149318 -270.89535) (xy 98.145358 -270.846296) (xy 97.816416 -270.846296) (xy 97.815921 -270.870903)
			(xy 97.808026 -270.91948) (xy 97.792442 -270.966161) (xy 97.769571 -271.009738) (xy 97.740006 -271.049082)
			(xy 97.704513 -271.083174) (xy 97.66401 -271.11113) (xy 97.619548 -271.132228) (xy 97.572277 -271.14592)
			(xy 97.523422 -271.151852) (xy 97.474247 -271.149871) (xy 97.426028 -271.140027) (xy 97.380012 -271.122575)
			(xy 97.337391 -271.097968) (xy 97.29927 -271.066843) (xy 97.266635 -271.030006) (xy 97.240332 -270.98841)
			(xy 97.221041 -270.943134) (xy 97.209264 -270.89535) (xy 97.205304 -270.846296) (xy 96.876362 -270.846296)
			(xy 96.875867 -270.870903) (xy 96.867972 -270.91948) (xy 96.852388 -270.966161) (xy 96.829517 -271.009738)
			(xy 96.799952 -271.049082) (xy 96.764459 -271.083174) (xy 96.723956 -271.11113) (xy 96.679494 -271.132228)
			(xy 96.632223 -271.14592) (xy 96.583368 -271.151852) (xy 96.534193 -271.149871) (xy 96.485974 -271.140027)
			(xy 96.439958 -271.122575) (xy 96.397337 -271.097968) (xy 96.359216 -271.066843) (xy 96.326581 -271.030006)
			(xy 96.300278 -270.98841) (xy 96.280987 -270.943134) (xy 96.26921 -270.89535) (xy 96.26525 -270.846296)
			(xy 95.946722 -270.846296) (xy 95.94621 -270.871742) (xy 95.938046 -270.921976) (xy 95.92193 -270.97025)
			(xy 95.898279 -271.015313) (xy 95.867706 -271.055999) (xy 95.831002 -271.091254) (xy 95.789118 -271.120164)
			(xy 95.743139 -271.141981) (xy 95.694255 -271.156141) (xy 95.643734 -271.162275) (xy 95.592882 -271.160226)
			(xy 95.543018 -271.150046) (xy 95.495432 -271.131999) (xy 95.451358 -271.106553) (xy 95.411936 -271.074366)
			(xy 95.378188 -271.036272) (xy 95.350987 -270.993258) (xy 95.331039 -270.946438) (xy 95.31886 -270.897024)
			(xy 95.314765 -270.846296) (xy 95.006668 -270.846296) (xy 95.006156 -270.871742) (xy 94.997992 -270.921976)
			(xy 94.981876 -270.97025) (xy 94.958225 -271.015313) (xy 94.927652 -271.055999) (xy 94.890948 -271.091254)
			(xy 94.849064 -271.120164) (xy 94.803085 -271.141981) (xy 94.754201 -271.156141) (xy 94.70368 -271.162275)
			(xy 94.652828 -271.160226) (xy 94.602964 -271.150046) (xy 94.555378 -271.131999) (xy 94.511304 -271.106553)
			(xy 94.471882 -271.074366) (xy 94.438134 -271.036272) (xy 94.410933 -270.993258) (xy 94.390985 -270.946438)
			(xy 94.378806 -270.897024) (xy 94.374711 -270.846296) (xy 94.056454 -270.846296) (xy 94.055959 -270.870903)
			(xy 94.048064 -270.91948) (xy 94.03248 -270.966161) (xy 94.009609 -271.009738) (xy 93.980044 -271.049082)
			(xy 93.944551 -271.083174) (xy 93.904048 -271.11113) (xy 93.859586 -271.132228) (xy 93.812315 -271.14592)
			(xy 93.76346 -271.151852) (xy 93.714285 -271.149871) (xy 93.666066 -271.140027) (xy 93.62005 -271.122575)
			(xy 93.577429 -271.097968) (xy 93.539308 -271.066843) (xy 93.506673 -271.030006) (xy 93.48037 -270.98841)
			(xy 93.461079 -270.943134) (xy 93.449302 -270.89535) (xy 93.445342 -270.846296) (xy 93.126814 -270.846296)
			(xy 93.126302 -270.871742) (xy 93.118138 -270.921976) (xy 93.102022 -270.97025) (xy 93.078371 -271.015313)
			(xy 93.047798 -271.055999) (xy 93.011094 -271.091254) (xy 92.96921 -271.120164) (xy 92.923231 -271.141981)
			(xy 92.874347 -271.156141) (xy 92.823826 -271.162275) (xy 92.772974 -271.160226) (xy 92.72311 -271.150046)
			(xy 92.675524 -271.131999) (xy 92.63145 -271.106553) (xy 92.592028 -271.074366) (xy 92.55828 -271.036272)
			(xy 92.531079 -270.993258) (xy 92.511131 -270.946438) (xy 92.498952 -270.897024) (xy 92.494857 -270.846296)
			(xy 92.176346 -270.846296) (xy 92.175851 -270.870903) (xy 92.167956 -270.91948) (xy 92.152372 -270.966161)
			(xy 92.129501 -271.009738) (xy 92.099936 -271.049082) (xy 92.064443 -271.083174) (xy 92.02394 -271.11113)
			(xy 91.979478 -271.132228) (xy 91.932207 -271.14592) (xy 91.883352 -271.151852) (xy 91.834177 -271.149871)
			(xy 91.785958 -271.140027) (xy 91.739942 -271.122575) (xy 91.697321 -271.097968) (xy 91.6592 -271.066843)
			(xy 91.626565 -271.030006) (xy 91.600262 -270.98841) (xy 91.580971 -270.943134) (xy 91.569194 -270.89535)
			(xy 91.565234 -270.846296) (xy 91.246706 -270.846296) (xy 91.246194 -270.871742) (xy 91.23803 -270.921976)
			(xy 91.221914 -270.97025) (xy 91.198263 -271.015313) (xy 91.16769 -271.055999) (xy 91.130986 -271.091254)
			(xy 91.089102 -271.120164) (xy 91.043123 -271.141981) (xy 90.994239 -271.156141) (xy 90.943718 -271.162275)
			(xy 90.892866 -271.160226) (xy 90.843002 -271.150046) (xy 90.795416 -271.131999) (xy 90.751342 -271.106553)
			(xy 90.71192 -271.074366) (xy 90.678172 -271.036272) (xy 90.650971 -270.993258) (xy 90.631023 -270.946438)
			(xy 90.618844 -270.897024) (xy 90.614749 -270.846296) (xy 90.296238 -270.846296) (xy 90.295743 -270.870903)
			(xy 90.287848 -270.91948) (xy 90.272264 -270.966161) (xy 90.249393 -271.009738) (xy 90.219828 -271.049082)
			(xy 90.184335 -271.083174) (xy 90.143832 -271.11113) (xy 90.09937 -271.132228) (xy 90.052099 -271.14592)
			(xy 90.003244 -271.151852) (xy 89.954069 -271.149871) (xy 89.90585 -271.140027) (xy 89.859834 -271.122575)
			(xy 89.817213 -271.097968) (xy 89.779092 -271.066843) (xy 89.746457 -271.030006) (xy 89.720154 -270.98841)
			(xy 89.700863 -270.943134) (xy 89.689086 -270.89535) (xy 89.685126 -270.846296) (xy 89.366852 -270.846296)
			(xy 89.36634 -270.871742) (xy 89.358176 -270.921976) (xy 89.34206 -270.97025) (xy 89.318409 -271.015313)
			(xy 89.287836 -271.055999) (xy 89.251132 -271.091254) (xy 89.209248 -271.120164) (xy 89.163269 -271.141981)
			(xy 89.114385 -271.156141) (xy 89.063864 -271.162275) (xy 89.013012 -271.160226) (xy 88.963148 -271.150046)
			(xy 88.915562 -271.131999) (xy 88.871488 -271.106553) (xy 88.832066 -271.074366) (xy 88.798318 -271.036272)
			(xy 88.771117 -270.993258) (xy 88.751169 -270.946438) (xy 88.73899 -270.897024) (xy 88.734895 -270.846296)
			(xy 88.426798 -270.846296) (xy 88.426286 -270.871742) (xy 88.418122 -270.921976) (xy 88.402006 -270.97025)
			(xy 88.378355 -271.015313) (xy 88.347782 -271.055999) (xy 88.311078 -271.091254) (xy 88.269194 -271.120164)
			(xy 88.223215 -271.141981) (xy 88.174331 -271.156141) (xy 88.12381 -271.162275) (xy 88.072958 -271.160226)
			(xy 88.023094 -271.150046) (xy 87.975508 -271.131999) (xy 87.931434 -271.106553) (xy 87.892012 -271.074366)
			(xy 87.858264 -271.036272) (xy 87.831063 -270.993258) (xy 87.811115 -270.946438) (xy 87.798936 -270.897024)
			(xy 87.794841 -270.846296) (xy 87.47633 -270.846296) (xy 87.475835 -270.870903) (xy 87.46794 -270.91948)
			(xy 87.452356 -270.966161) (xy 87.429485 -271.009738) (xy 87.39992 -271.049082) (xy 87.364427 -271.083174)
			(xy 87.323924 -271.11113) (xy 87.279462 -271.132228) (xy 87.232191 -271.14592) (xy 87.183336 -271.151852)
			(xy 87.134161 -271.149871) (xy 87.085942 -271.140027) (xy 87.039926 -271.122575) (xy 86.997305 -271.097968)
			(xy 86.959184 -271.066843) (xy 86.926549 -271.030006) (xy 86.900246 -270.98841) (xy 86.880955 -270.943134)
			(xy 86.869178 -270.89535) (xy 86.865218 -270.846296) (xy 86.54669 -270.846296) (xy 86.546178 -270.871742)
			(xy 86.538014 -270.921976) (xy 86.521898 -270.97025) (xy 86.498247 -271.015313) (xy 86.467674 -271.055999)
			(xy 86.43097 -271.091254) (xy 86.389086 -271.120164) (xy 86.343107 -271.141981) (xy 86.294223 -271.156141)
			(xy 86.243702 -271.162275) (xy 86.19285 -271.160226) (xy 86.142986 -271.150046) (xy 86.0954 -271.131999)
			(xy 86.051326 -271.106553) (xy 86.011904 -271.074366) (xy 85.978156 -271.036272) (xy 85.950955 -270.993258)
			(xy 85.931007 -270.946438) (xy 85.918828 -270.897024) (xy 85.914733 -270.846296) (xy 85.596222 -270.846296)
			(xy 85.595727 -270.870903) (xy 85.587832 -270.91948) (xy 85.572248 -270.966161) (xy 85.549377 -271.009738)
			(xy 85.519812 -271.049082) (xy 85.484319 -271.083174) (xy 85.443816 -271.11113) (xy 85.399354 -271.132228)
			(xy 85.352083 -271.14592) (xy 85.303228 -271.151852) (xy 85.254053 -271.149871) (xy 85.205834 -271.140027)
			(xy 85.159818 -271.122575) (xy 85.117197 -271.097968) (xy 85.079076 -271.066843) (xy 85.046441 -271.030006)
			(xy 85.020138 -270.98841) (xy 85.000847 -270.943134) (xy 84.98907 -270.89535) (xy 84.98511 -270.846296)
			(xy 84.666836 -270.846296) (xy 84.666324 -270.871742) (xy 84.65816 -270.921976) (xy 84.642044 -270.97025)
			(xy 84.618393 -271.015313) (xy 84.58782 -271.055999) (xy 84.551116 -271.091254) (xy 84.509232 -271.120164)
			(xy 84.463253 -271.141981) (xy 84.414369 -271.156141) (xy 84.363848 -271.162275) (xy 84.312996 -271.160226)
			(xy 84.263132 -271.150046) (xy 84.215546 -271.131999) (xy 84.171472 -271.106553) (xy 84.13205 -271.074366)
			(xy 84.098302 -271.036272) (xy 84.071101 -270.993258) (xy 84.051153 -270.946438) (xy 84.038974 -270.897024)
			(xy 84.034879 -270.846296) (xy 83.716368 -270.846296) (xy 83.715873 -270.870903) (xy 83.707978 -270.91948)
			(xy 83.692394 -270.966161) (xy 83.669523 -271.009738) (xy 83.639958 -271.049082) (xy 83.604465 -271.083174)
			(xy 83.563962 -271.11113) (xy 83.5195 -271.132228) (xy 83.472229 -271.14592) (xy 83.423374 -271.151852)
			(xy 83.374199 -271.149871) (xy 83.32598 -271.140027) (xy 83.279964 -271.122575) (xy 83.237343 -271.097968)
			(xy 83.199222 -271.066843) (xy 83.166587 -271.030006) (xy 83.140284 -270.98841) (xy 83.120993 -270.943134)
			(xy 83.109216 -270.89535) (xy 83.105256 -270.846296) (xy 82.786728 -270.846296) (xy 82.786216 -270.871742)
			(xy 82.778052 -270.921976) (xy 82.761936 -270.97025) (xy 82.738285 -271.015313) (xy 82.707712 -271.055999)
			(xy 82.671008 -271.091254) (xy 82.629124 -271.120164) (xy 82.583145 -271.141981) (xy 82.534261 -271.156141)
			(xy 82.48374 -271.162275) (xy 82.432888 -271.160226) (xy 82.383024 -271.150046) (xy 82.335438 -271.131999)
			(xy 82.291364 -271.106553) (xy 82.251942 -271.074366) (xy 82.218194 -271.036272) (xy 82.190993 -270.993258)
			(xy 82.171045 -270.946438) (xy 82.158866 -270.897024) (xy 82.154771 -270.846296) (xy 81.846674 -270.846296)
			(xy 81.846162 -270.871742) (xy 81.837998 -270.921976) (xy 81.821882 -270.97025) (xy 81.798231 -271.015313)
			(xy 81.767658 -271.055999) (xy 81.730954 -271.091254) (xy 81.68907 -271.120164) (xy 81.643091 -271.141981)
			(xy 81.594207 -271.156141) (xy 81.543686 -271.162275) (xy 81.492834 -271.160226) (xy 81.44297 -271.150046)
			(xy 81.395384 -271.131999) (xy 81.35131 -271.106553) (xy 81.311888 -271.074366) (xy 81.27814 -271.036272)
			(xy 81.250939 -270.993258) (xy 81.230991 -270.946438) (xy 81.218812 -270.897024) (xy 81.214717 -270.846296)
			(xy 80.89646 -270.846296) (xy 80.895965 -270.870903) (xy 80.88807 -270.91948) (xy 80.872486 -270.966161)
			(xy 80.849615 -271.009738) (xy 80.82005 -271.049082) (xy 80.784557 -271.083174) (xy 80.744054 -271.11113)
			(xy 80.699592 -271.132228) (xy 80.652321 -271.14592) (xy 80.603466 -271.151852) (xy 80.554291 -271.149871)
			(xy 80.506072 -271.140027) (xy 80.460056 -271.122575) (xy 80.417435 -271.097968) (xy 80.379314 -271.066843)
			(xy 80.346679 -271.030006) (xy 80.320376 -270.98841) (xy 80.301085 -270.943134) (xy 80.289308 -270.89535)
			(xy 80.285348 -270.846296) (xy 79.016352 -270.846296) (xy 79.015857 -270.870903) (xy 79.007962 -270.91948)
			(xy 78.992378 -270.966161) (xy 78.969507 -271.009738) (xy 78.939942 -271.049082) (xy 78.904449 -271.083174)
			(xy 78.863946 -271.11113) (xy 78.819484 -271.132228) (xy 78.772213 -271.14592) (xy 78.723358 -271.151852)
			(xy 78.674183 -271.149871) (xy 78.625964 -271.140027) (xy 78.579948 -271.122575) (xy 78.537327 -271.097968)
			(xy 78.499206 -271.066843) (xy 78.466571 -271.030006) (xy 78.440268 -270.98841) (xy 78.420977 -270.943134)
			(xy 78.4092 -270.89535) (xy 78.40524 -270.846296) (xy 73.228962 -270.846296) (xy 73.228962 -271.390364)
			(xy 76.807072 -271.390364) (xy 76.811032 -271.34131) (xy 76.822809 -271.293526) (xy 76.8421 -271.24825)
			(xy 76.868403 -271.206654) (xy 76.901038 -271.169817) (xy 76.939159 -271.138692) (xy 76.98178 -271.114085)
			(xy 77.027796 -271.096633) (xy 77.076015 -271.086789) (xy 77.12519 -271.084808) (xy 77.174045 -271.09074)
			(xy 77.221316 -271.104432) (xy 77.265778 -271.12553) (xy 77.306281 -271.153486) (xy 77.341774 -271.187578)
			(xy 77.371339 -271.226922) (xy 77.39421 -271.270499) (xy 77.409794 -271.31718) (xy 77.417689 -271.365757)
			(xy 77.418184 -271.390364) (xy 77.417689 -271.414971) (xy 77.409794 -271.463548) (xy 77.39421 -271.510229)
			(xy 77.371339 -271.553806) (xy 77.341774 -271.59315) (xy 77.306281 -271.627242) (xy 77.265778 -271.655198)
			(xy 77.263451 -271.656302) (xy 79.815194 -271.656302) (xy 79.819154 -271.607248) (xy 79.830931 -271.559464)
			(xy 79.850222 -271.514188) (xy 79.876525 -271.472592) (xy 79.90916 -271.435755) (xy 79.947281 -271.40463)
			(xy 79.989902 -271.380023) (xy 80.035918 -271.362571) (xy 80.084137 -271.352727) (xy 80.133312 -271.350746)
			(xy 80.182167 -271.356678) (xy 80.229438 -271.37037) (xy 80.2739 -271.391468) (xy 80.314403 -271.419424)
			(xy 80.349896 -271.453516) (xy 80.379461 -271.49286) (xy 80.402332 -271.536437) (xy 80.417916 -271.583118)
			(xy 80.425811 -271.631695) (xy 80.426306 -271.656302) (xy 80.744817 -271.656302) (xy 80.748912 -271.605574)
			(xy 80.761091 -271.55616) (xy 80.781039 -271.50934) (xy 80.80824 -271.466326) (xy 80.841988 -271.428232)
			(xy 80.88141 -271.396045) (xy 80.925484 -271.370599) (xy 80.97307 -271.352552) (xy 81.022934 -271.342372)
			(xy 81.073786 -271.340323) (xy 81.124307 -271.346457) (xy 81.173191 -271.360617) (xy 81.21917 -271.382434)
			(xy 81.261054 -271.411344) (xy 81.297758 -271.446599) (xy 81.328331 -271.487285) (xy 81.351982 -271.532348)
			(xy 81.368098 -271.580622) (xy 81.376262 -271.630856) (xy 81.376774 -271.656302) (xy 81.695302 -271.656302)
			(xy 81.699262 -271.607248) (xy 81.711039 -271.559464) (xy 81.73033 -271.514188) (xy 81.756633 -271.472592)
			(xy 81.789268 -271.435755) (xy 81.827389 -271.40463) (xy 81.87001 -271.380023) (xy 81.916026 -271.362571)
			(xy 81.964245 -271.352727) (xy 82.01342 -271.350746) (xy 82.062275 -271.356678) (xy 82.109546 -271.37037)
			(xy 82.154008 -271.391468) (xy 82.194511 -271.419424) (xy 82.230004 -271.453516) (xy 82.259569 -271.49286)
			(xy 82.28244 -271.536437) (xy 82.298024 -271.583118) (xy 82.305919 -271.631695) (xy 82.306414 -271.656302)
			(xy 82.624671 -271.656302) (xy 82.628766 -271.605574) (xy 82.640945 -271.55616) (xy 82.660893 -271.50934)
			(xy 82.688094 -271.466326) (xy 82.721842 -271.428232) (xy 82.761264 -271.396045) (xy 82.805338 -271.370599)
			(xy 82.852924 -271.352552) (xy 82.902788 -271.342372) (xy 82.95364 -271.340323) (xy 83.004161 -271.346457)
			(xy 83.053045 -271.360617) (xy 83.099024 -271.382434) (xy 83.140908 -271.411344) (xy 83.177612 -271.446599)
			(xy 83.208185 -271.487285) (xy 83.231836 -271.532348) (xy 83.247952 -271.580622) (xy 83.256116 -271.630856)
			(xy 83.256628 -271.656302) (xy 83.575156 -271.656302) (xy 83.579116 -271.607248) (xy 83.590893 -271.559464)
			(xy 83.610184 -271.514188) (xy 83.636487 -271.472592) (xy 83.669122 -271.435755) (xy 83.707243 -271.40463)
			(xy 83.749864 -271.380023) (xy 83.79588 -271.362571) (xy 83.844099 -271.352727) (xy 83.893274 -271.350746)
			(xy 83.942129 -271.356678) (xy 83.9894 -271.37037) (xy 84.033862 -271.391468) (xy 84.074365 -271.419424)
			(xy 84.109858 -271.453516) (xy 84.139423 -271.49286) (xy 84.162294 -271.536437) (xy 84.177878 -271.583118)
			(xy 84.185773 -271.631695) (xy 84.186268 -271.656302) (xy 84.504779 -271.656302) (xy 84.508874 -271.605574)
			(xy 84.521053 -271.55616) (xy 84.541001 -271.50934) (xy 84.568202 -271.466326) (xy 84.60195 -271.428232)
			(xy 84.641372 -271.396045) (xy 84.685446 -271.370599) (xy 84.733032 -271.352552) (xy 84.782896 -271.342372)
			(xy 84.833748 -271.340323) (xy 84.884269 -271.346457) (xy 84.933153 -271.360617) (xy 84.979132 -271.382434)
			(xy 85.021016 -271.411344) (xy 85.05772 -271.446599) (xy 85.088293 -271.487285) (xy 85.111944 -271.532348)
			(xy 85.12806 -271.580622) (xy 85.136224 -271.630856) (xy 85.136736 -271.656302) (xy 85.444833 -271.656302)
			(xy 85.448928 -271.605574) (xy 85.461107 -271.55616) (xy 85.481055 -271.50934) (xy 85.508256 -271.466326)
			(xy 85.542004 -271.428232) (xy 85.581426 -271.396045) (xy 85.6255 -271.370599) (xy 85.673086 -271.352552)
			(xy 85.72295 -271.342372) (xy 85.773802 -271.340323) (xy 85.824323 -271.346457) (xy 85.873207 -271.360617)
			(xy 85.919186 -271.382434) (xy 85.96107 -271.411344) (xy 85.997774 -271.446599) (xy 86.028347 -271.487285)
			(xy 86.051998 -271.532348) (xy 86.068114 -271.580622) (xy 86.076278 -271.630856) (xy 86.07679 -271.656302)
			(xy 86.395318 -271.656302) (xy 86.399278 -271.607248) (xy 86.411055 -271.559464) (xy 86.430346 -271.514188)
			(xy 86.456649 -271.472592) (xy 86.489284 -271.435755) (xy 86.527405 -271.40463) (xy 86.570026 -271.380023)
			(xy 86.616042 -271.362571) (xy 86.664261 -271.352727) (xy 86.713436 -271.350746) (xy 86.762291 -271.356678)
			(xy 86.809562 -271.37037) (xy 86.854024 -271.391468) (xy 86.894527 -271.419424) (xy 86.93002 -271.453516)
			(xy 86.959585 -271.49286) (xy 86.982456 -271.536437) (xy 86.99804 -271.583118) (xy 87.005935 -271.631695)
			(xy 87.00643 -271.656302) (xy 87.324687 -271.656302) (xy 87.328782 -271.605574) (xy 87.340961 -271.55616)
			(xy 87.360909 -271.50934) (xy 87.38811 -271.466326) (xy 87.421858 -271.428232) (xy 87.46128 -271.396045)
			(xy 87.505354 -271.370599) (xy 87.55294 -271.352552) (xy 87.602804 -271.342372) (xy 87.653656 -271.340323)
			(xy 87.704177 -271.346457) (xy 87.753061 -271.360617) (xy 87.79904 -271.382434) (xy 87.840924 -271.411344)
			(xy 87.877628 -271.446599) (xy 87.908201 -271.487285) (xy 87.931852 -271.532348) (xy 87.947968 -271.580622)
			(xy 87.956132 -271.630856) (xy 87.956644 -271.656302) (xy 88.275172 -271.656302) (xy 88.279132 -271.607248)
			(xy 88.290909 -271.559464) (xy 88.3102 -271.514188) (xy 88.336503 -271.472592) (xy 88.369138 -271.435755)
			(xy 88.407259 -271.40463) (xy 88.44988 -271.380023) (xy 88.495896 -271.362571) (xy 88.544115 -271.352727)
			(xy 88.59329 -271.350746) (xy 88.642145 -271.356678) (xy 88.689416 -271.37037) (xy 88.733878 -271.391468)
			(xy 88.774381 -271.419424) (xy 88.809874 -271.453516) (xy 88.839439 -271.49286) (xy 88.86231 -271.536437)
			(xy 88.877894 -271.583118) (xy 88.885789 -271.631695) (xy 88.886284 -271.656302) (xy 89.204795 -271.656302)
			(xy 89.20889 -271.605574) (xy 89.221069 -271.55616) (xy 89.241017 -271.50934) (xy 89.268218 -271.466326)
			(xy 89.301966 -271.428232) (xy 89.341388 -271.396045) (xy 89.385462 -271.370599) (xy 89.433048 -271.352552)
			(xy 89.482912 -271.342372) (xy 89.533764 -271.340323) (xy 89.584285 -271.346457) (xy 89.633169 -271.360617)
			(xy 89.679148 -271.382434) (xy 89.721032 -271.411344) (xy 89.757736 -271.446599) (xy 89.788309 -271.487285)
			(xy 89.81196 -271.532348) (xy 89.828076 -271.580622) (xy 89.83624 -271.630856) (xy 89.836752 -271.656302)
			(xy 90.15528 -271.656302) (xy 90.15924 -271.607248) (xy 90.171017 -271.559464) (xy 90.190308 -271.514188)
			(xy 90.216611 -271.472592) (xy 90.249246 -271.435755) (xy 90.287367 -271.40463) (xy 90.329988 -271.380023)
			(xy 90.376004 -271.362571) (xy 90.424223 -271.352727) (xy 90.473398 -271.350746) (xy 90.522253 -271.356678)
			(xy 90.569524 -271.37037) (xy 90.613986 -271.391468) (xy 90.654489 -271.419424) (xy 90.689982 -271.453516)
			(xy 90.719547 -271.49286) (xy 90.742418 -271.536437) (xy 90.758002 -271.583118) (xy 90.765897 -271.631695)
			(xy 90.766392 -271.656302) (xy 91.084903 -271.656302) (xy 91.088998 -271.605574) (xy 91.101177 -271.55616)
			(xy 91.121125 -271.50934) (xy 91.148326 -271.466326) (xy 91.182074 -271.428232) (xy 91.221496 -271.396045)
			(xy 91.26557 -271.370599) (xy 91.313156 -271.352552) (xy 91.36302 -271.342372) (xy 91.413872 -271.340323)
			(xy 91.464393 -271.346457) (xy 91.513277 -271.360617) (xy 91.559256 -271.382434) (xy 91.60114 -271.411344)
			(xy 91.637844 -271.446599) (xy 91.668417 -271.487285) (xy 91.692068 -271.532348) (xy 91.708184 -271.580622)
			(xy 91.716348 -271.630856) (xy 91.71686 -271.656302) (xy 92.024703 -271.656302) (xy 92.028798 -271.605574)
			(xy 92.040977 -271.55616) (xy 92.060925 -271.50934) (xy 92.088126 -271.466326) (xy 92.121874 -271.428232)
			(xy 92.161296 -271.396045) (xy 92.20537 -271.370599) (xy 92.252956 -271.352552) (xy 92.30282 -271.342372)
			(xy 92.353672 -271.340323) (xy 92.404193 -271.346457) (xy 92.453077 -271.360617) (xy 92.499056 -271.382434)
			(xy 92.54094 -271.411344) (xy 92.577644 -271.446599) (xy 92.608217 -271.487285) (xy 92.631868 -271.532348)
			(xy 92.647984 -271.580622) (xy 92.656148 -271.630856) (xy 92.65666 -271.656302) (xy 92.975188 -271.656302)
			(xy 92.979148 -271.607248) (xy 92.990925 -271.559464) (xy 93.010216 -271.514188) (xy 93.036519 -271.472592)
			(xy 93.069154 -271.435755) (xy 93.107275 -271.40463) (xy 93.149896 -271.380023) (xy 93.195912 -271.362571)
			(xy 93.244131 -271.352727) (xy 93.293306 -271.350746) (xy 93.342161 -271.356678) (xy 93.389432 -271.37037)
			(xy 93.433894 -271.391468) (xy 93.474397 -271.419424) (xy 93.50989 -271.453516) (xy 93.539455 -271.49286)
			(xy 93.562326 -271.536437) (xy 93.57791 -271.583118) (xy 93.585805 -271.631695) (xy 93.5863 -271.656302)
			(xy 93.904811 -271.656302) (xy 93.908906 -271.605574) (xy 93.921085 -271.55616) (xy 93.941033 -271.50934)
			(xy 93.968234 -271.466326) (xy 94.001982 -271.428232) (xy 94.041404 -271.396045) (xy 94.085478 -271.370599)
			(xy 94.133064 -271.352552) (xy 94.182928 -271.342372) (xy 94.23378 -271.340323) (xy 94.284301 -271.346457)
			(xy 94.333185 -271.360617) (xy 94.379164 -271.382434) (xy 94.421048 -271.411344) (xy 94.457752 -271.446599)
			(xy 94.488325 -271.487285) (xy 94.511976 -271.532348) (xy 94.528092 -271.580622) (xy 94.536256 -271.630856)
			(xy 94.536768 -271.656302) (xy 94.855296 -271.656302) (xy 94.859256 -271.607248) (xy 94.871033 -271.559464)
			(xy 94.890324 -271.514188) (xy 94.916627 -271.472592) (xy 94.949262 -271.435755) (xy 94.987383 -271.40463)
			(xy 95.030004 -271.380023) (xy 95.07602 -271.362571) (xy 95.124239 -271.352727) (xy 95.173414 -271.350746)
			(xy 95.222269 -271.356678) (xy 95.26954 -271.37037) (xy 95.314002 -271.391468) (xy 95.354505 -271.419424)
			(xy 95.389998 -271.453516) (xy 95.419563 -271.49286) (xy 95.442434 -271.536437) (xy 95.458018 -271.583118)
			(xy 95.465913 -271.631695) (xy 95.466408 -271.656302) (xy 95.784919 -271.656302) (xy 95.789014 -271.605574)
			(xy 95.801193 -271.55616) (xy 95.821141 -271.50934) (xy 95.848342 -271.466326) (xy 95.88209 -271.428232)
			(xy 95.921512 -271.396045) (xy 95.965586 -271.370599) (xy 96.013172 -271.352552) (xy 96.063036 -271.342372)
			(xy 96.113888 -271.340323) (xy 96.164409 -271.346457) (xy 96.213293 -271.360617) (xy 96.259272 -271.382434)
			(xy 96.301156 -271.411344) (xy 96.33786 -271.446599) (xy 96.368433 -271.487285) (xy 96.392084 -271.532348)
			(xy 96.4082 -271.580622) (xy 96.416364 -271.630856) (xy 96.416876 -271.656302) (xy 96.73515 -271.656302)
			(xy 96.73911 -271.607248) (xy 96.750887 -271.559464) (xy 96.770178 -271.514188) (xy 96.796481 -271.472592)
			(xy 96.829116 -271.435755) (xy 96.867237 -271.40463) (xy 96.909858 -271.380023) (xy 96.955874 -271.362571)
			(xy 97.004093 -271.352727) (xy 97.053268 -271.350746) (xy 97.102123 -271.356678) (xy 97.149394 -271.37037)
			(xy 97.193856 -271.391468) (xy 97.234359 -271.419424) (xy 97.269852 -271.453516) (xy 97.299417 -271.49286)
			(xy 97.322288 -271.536437) (xy 97.337872 -271.583118) (xy 97.345767 -271.631695) (xy 97.346262 -271.656302)
			(xy 97.664773 -271.656302) (xy 97.668868 -271.605574) (xy 97.681047 -271.55616) (xy 97.700995 -271.50934)
			(xy 97.728196 -271.466326) (xy 97.761944 -271.428232) (xy 97.801366 -271.396045) (xy 97.84544 -271.370599)
			(xy 97.893026 -271.352552) (xy 97.94289 -271.342372) (xy 97.993742 -271.340323) (xy 98.044263 -271.346457)
			(xy 98.093147 -271.360617) (xy 98.139126 -271.382434) (xy 98.18101 -271.411344) (xy 98.217714 -271.446599)
			(xy 98.248287 -271.487285) (xy 98.271938 -271.532348) (xy 98.288054 -271.580622) (xy 98.296218 -271.630856)
			(xy 98.29673 -271.656302) (xy 98.604827 -271.656302) (xy 98.608922 -271.605574) (xy 98.621101 -271.55616)
			(xy 98.641049 -271.50934) (xy 98.66825 -271.466326) (xy 98.701998 -271.428232) (xy 98.74142 -271.396045)
			(xy 98.785494 -271.370599) (xy 98.83308 -271.352552) (xy 98.882944 -271.342372) (xy 98.933796 -271.340323)
			(xy 98.984317 -271.346457) (xy 99.033201 -271.360617) (xy 99.07918 -271.382434) (xy 99.121064 -271.411344)
			(xy 99.157768 -271.446599) (xy 99.188341 -271.487285) (xy 99.211992 -271.532348) (xy 99.228108 -271.580622)
			(xy 99.236272 -271.630856) (xy 99.236784 -271.656302) (xy 99.555312 -271.656302) (xy 99.559272 -271.607248)
			(xy 99.571049 -271.559464) (xy 99.59034 -271.514188) (xy 99.616643 -271.472592) (xy 99.649278 -271.435755)
			(xy 99.687399 -271.40463) (xy 99.73002 -271.380023) (xy 99.776036 -271.362571) (xy 99.824255 -271.352727)
			(xy 99.87343 -271.350746) (xy 99.922285 -271.356678) (xy 99.969556 -271.37037) (xy 100.014018 -271.391468)
			(xy 100.054521 -271.419424) (xy 100.090014 -271.453516) (xy 100.119579 -271.49286) (xy 100.14245 -271.536437)
			(xy 100.158034 -271.583118) (xy 100.165929 -271.631695) (xy 100.166424 -271.656302) (xy 100.484935 -271.656302)
			(xy 100.48903 -271.605574) (xy 100.501209 -271.55616) (xy 100.521157 -271.50934) (xy 100.548358 -271.466326)
			(xy 100.582106 -271.428232) (xy 100.621528 -271.396045) (xy 100.665602 -271.370599) (xy 100.713188 -271.352552)
			(xy 100.763052 -271.342372) (xy 100.813904 -271.340323) (xy 100.864425 -271.346457) (xy 100.913309 -271.360617)
			(xy 100.959288 -271.382434) (xy 101.001172 -271.411344) (xy 101.037876 -271.446599) (xy 101.068449 -271.487285)
			(xy 101.0921 -271.532348) (xy 101.108216 -271.580622) (xy 101.11638 -271.630856) (xy 101.116892 -271.656302)
			(xy 101.424735 -271.656302) (xy 101.42883 -271.605574) (xy 101.441009 -271.55616) (xy 101.460957 -271.50934)
			(xy 101.488158 -271.466326) (xy 101.521906 -271.428232) (xy 101.561328 -271.396045) (xy 101.605402 -271.370599)
			(xy 101.652988 -271.352552) (xy 101.702852 -271.342372) (xy 101.753704 -271.340323) (xy 101.804225 -271.346457)
			(xy 101.853109 -271.360617) (xy 101.899088 -271.382434) (xy 101.940972 -271.411344) (xy 101.977676 -271.446599)
			(xy 102.008249 -271.487285) (xy 102.0319 -271.532348) (xy 102.048016 -271.580622) (xy 102.05618 -271.630856)
			(xy 102.056692 -271.656302) (xy 102.05618 -271.681748) (xy 102.048016 -271.731982) (xy 102.0319 -271.780256)
			(xy 102.008249 -271.825319) (xy 101.977676 -271.866005) (xy 101.940972 -271.90126) (xy 101.899088 -271.93017)
			(xy 101.853109 -271.951987) (xy 101.804225 -271.966147) (xy 101.753704 -271.972281) (xy 101.702852 -271.970232)
			(xy 101.652988 -271.960052) (xy 101.605402 -271.942005) (xy 101.561328 -271.916559) (xy 101.521906 -271.884372)
			(xy 101.488158 -271.846278) (xy 101.460957 -271.803264) (xy 101.441009 -271.756444) (xy 101.42883 -271.70703)
			(xy 101.424735 -271.656302) (xy 101.116892 -271.656302) (xy 101.11638 -271.681748) (xy 101.108216 -271.731982)
			(xy 101.0921 -271.780256) (xy 101.068449 -271.825319) (xy 101.037876 -271.866005) (xy 101.001172 -271.90126)
			(xy 100.959288 -271.93017) (xy 100.913309 -271.951987) (xy 100.864425 -271.966147) (xy 100.813904 -271.972281)
			(xy 100.763052 -271.970232) (xy 100.713188 -271.960052) (xy 100.665602 -271.942005) (xy 100.621528 -271.916559)
			(xy 100.582106 -271.884372) (xy 100.548358 -271.846278) (xy 100.521157 -271.803264) (xy 100.501209 -271.756444)
			(xy 100.48903 -271.70703) (xy 100.484935 -271.656302) (xy 100.166424 -271.656302) (xy 100.165929 -271.680909)
			(xy 100.158034 -271.729486) (xy 100.14245 -271.776167) (xy 100.119579 -271.819744) (xy 100.090014 -271.859088)
			(xy 100.054521 -271.89318) (xy 100.014018 -271.921136) (xy 99.969556 -271.942234) (xy 99.922285 -271.955926)
			(xy 99.87343 -271.961858) (xy 99.824255 -271.959877) (xy 99.776036 -271.950033) (xy 99.73002 -271.932581)
			(xy 99.687399 -271.907974) (xy 99.649278 -271.876849) (xy 99.616643 -271.840012) (xy 99.59034 -271.798416)
			(xy 99.571049 -271.75314) (xy 99.559272 -271.705356) (xy 99.555312 -271.656302) (xy 99.236784 -271.656302)
			(xy 99.236272 -271.681748) (xy 99.228108 -271.731982) (xy 99.211992 -271.780256) (xy 99.188341 -271.825319)
			(xy 99.157768 -271.866005) (xy 99.121064 -271.90126) (xy 99.07918 -271.93017) (xy 99.033201 -271.951987)
			(xy 98.984317 -271.966147) (xy 98.933796 -271.972281) (xy 98.882944 -271.970232) (xy 98.83308 -271.960052)
			(xy 98.785494 -271.942005) (xy 98.74142 -271.916559) (xy 98.701998 -271.884372) (xy 98.66825 -271.846278)
			(xy 98.641049 -271.803264) (xy 98.621101 -271.756444) (xy 98.608922 -271.70703) (xy 98.604827 -271.656302)
			(xy 98.29673 -271.656302) (xy 98.296218 -271.681748) (xy 98.288054 -271.731982) (xy 98.271938 -271.780256)
			(xy 98.248287 -271.825319) (xy 98.217714 -271.866005) (xy 98.18101 -271.90126) (xy 98.139126 -271.93017)
			(xy 98.093147 -271.951987) (xy 98.044263 -271.966147) (xy 97.993742 -271.972281) (xy 97.94289 -271.970232)
			(xy 97.893026 -271.960052) (xy 97.84544 -271.942005) (xy 97.801366 -271.916559) (xy 97.761944 -271.884372)
			(xy 97.728196 -271.846278) (xy 97.700995 -271.803264) (xy 97.681047 -271.756444) (xy 97.668868 -271.70703)
			(xy 97.664773 -271.656302) (xy 97.346262 -271.656302) (xy 97.345767 -271.680909) (xy 97.337872 -271.729486)
			(xy 97.322288 -271.776167) (xy 97.299417 -271.819744) (xy 97.269852 -271.859088) (xy 97.234359 -271.89318)
			(xy 97.193856 -271.921136) (xy 97.149394 -271.942234) (xy 97.102123 -271.955926) (xy 97.053268 -271.961858)
			(xy 97.004093 -271.959877) (xy 96.955874 -271.950033) (xy 96.909858 -271.932581) (xy 96.867237 -271.907974)
			(xy 96.829116 -271.876849) (xy 96.796481 -271.840012) (xy 96.770178 -271.798416) (xy 96.750887 -271.75314)
			(xy 96.73911 -271.705356) (xy 96.73515 -271.656302) (xy 96.416876 -271.656302) (xy 96.416364 -271.681748)
			(xy 96.4082 -271.731982) (xy 96.392084 -271.780256) (xy 96.368433 -271.825319) (xy 96.33786 -271.866005)
			(xy 96.301156 -271.90126) (xy 96.259272 -271.93017) (xy 96.213293 -271.951987) (xy 96.164409 -271.966147)
			(xy 96.113888 -271.972281) (xy 96.063036 -271.970232) (xy 96.013172 -271.960052) (xy 95.965586 -271.942005)
			(xy 95.921512 -271.916559) (xy 95.88209 -271.884372) (xy 95.848342 -271.846278) (xy 95.821141 -271.803264)
			(xy 95.801193 -271.756444) (xy 95.789014 -271.70703) (xy 95.784919 -271.656302) (xy 95.466408 -271.656302)
			(xy 95.465913 -271.680909) (xy 95.458018 -271.729486) (xy 95.442434 -271.776167) (xy 95.419563 -271.819744)
			(xy 95.389998 -271.859088) (xy 95.354505 -271.89318) (xy 95.314002 -271.921136) (xy 95.26954 -271.942234)
			(xy 95.222269 -271.955926) (xy 95.173414 -271.961858) (xy 95.124239 -271.959877) (xy 95.07602 -271.950033)
			(xy 95.030004 -271.932581) (xy 94.987383 -271.907974) (xy 94.949262 -271.876849) (xy 94.916627 -271.840012)
			(xy 94.890324 -271.798416) (xy 94.871033 -271.75314) (xy 94.859256 -271.705356) (xy 94.855296 -271.656302)
			(xy 94.536768 -271.656302) (xy 94.536256 -271.681748) (xy 94.528092 -271.731982) (xy 94.511976 -271.780256)
			(xy 94.488325 -271.825319) (xy 94.457752 -271.866005) (xy 94.421048 -271.90126) (xy 94.379164 -271.93017)
			(xy 94.333185 -271.951987) (xy 94.284301 -271.966147) (xy 94.23378 -271.972281) (xy 94.182928 -271.970232)
			(xy 94.133064 -271.960052) (xy 94.085478 -271.942005) (xy 94.041404 -271.916559) (xy 94.001982 -271.884372)
			(xy 93.968234 -271.846278) (xy 93.941033 -271.803264) (xy 93.921085 -271.756444) (xy 93.908906 -271.70703)
			(xy 93.904811 -271.656302) (xy 93.5863 -271.656302) (xy 93.585805 -271.680909) (xy 93.57791 -271.729486)
			(xy 93.562326 -271.776167) (xy 93.539455 -271.819744) (xy 93.50989 -271.859088) (xy 93.474397 -271.89318)
			(xy 93.433894 -271.921136) (xy 93.389432 -271.942234) (xy 93.342161 -271.955926) (xy 93.293306 -271.961858)
			(xy 93.244131 -271.959877) (xy 93.195912 -271.950033) (xy 93.149896 -271.932581) (xy 93.107275 -271.907974)
			(xy 93.069154 -271.876849) (xy 93.036519 -271.840012) (xy 93.010216 -271.798416) (xy 92.990925 -271.75314)
			(xy 92.979148 -271.705356) (xy 92.975188 -271.656302) (xy 92.65666 -271.656302) (xy 92.656148 -271.681748)
			(xy 92.647984 -271.731982) (xy 92.631868 -271.780256) (xy 92.608217 -271.825319) (xy 92.577644 -271.866005)
			(xy 92.54094 -271.90126) (xy 92.499056 -271.93017) (xy 92.453077 -271.951987) (xy 92.404193 -271.966147)
			(xy 92.353672 -271.972281) (xy 92.30282 -271.970232) (xy 92.252956 -271.960052) (xy 92.20537 -271.942005)
			(xy 92.161296 -271.916559) (xy 92.121874 -271.884372) (xy 92.088126 -271.846278) (xy 92.060925 -271.803264)
			(xy 92.040977 -271.756444) (xy 92.028798 -271.70703) (xy 92.024703 -271.656302) (xy 91.71686 -271.656302)
			(xy 91.716348 -271.681748) (xy 91.708184 -271.731982) (xy 91.692068 -271.780256) (xy 91.668417 -271.825319)
			(xy 91.637844 -271.866005) (xy 91.60114 -271.90126) (xy 91.559256 -271.93017) (xy 91.513277 -271.951987)
			(xy 91.464393 -271.966147) (xy 91.413872 -271.972281) (xy 91.36302 -271.970232) (xy 91.313156 -271.960052)
			(xy 91.26557 -271.942005) (xy 91.221496 -271.916559) (xy 91.182074 -271.884372) (xy 91.148326 -271.846278)
			(xy 91.121125 -271.803264) (xy 91.101177 -271.756444) (xy 91.088998 -271.70703) (xy 91.084903 -271.656302)
			(xy 90.766392 -271.656302) (xy 90.765897 -271.680909) (xy 90.758002 -271.729486) (xy 90.742418 -271.776167)
			(xy 90.719547 -271.819744) (xy 90.689982 -271.859088) (xy 90.654489 -271.89318) (xy 90.613986 -271.921136)
			(xy 90.569524 -271.942234) (xy 90.522253 -271.955926) (xy 90.473398 -271.961858) (xy 90.424223 -271.959877)
			(xy 90.376004 -271.950033) (xy 90.329988 -271.932581) (xy 90.287367 -271.907974) (xy 90.249246 -271.876849)
			(xy 90.216611 -271.840012) (xy 90.190308 -271.798416) (xy 90.171017 -271.75314) (xy 90.15924 -271.705356)
			(xy 90.15528 -271.656302) (xy 89.836752 -271.656302) (xy 89.83624 -271.681748) (xy 89.828076 -271.731982)
			(xy 89.81196 -271.780256) (xy 89.788309 -271.825319) (xy 89.757736 -271.866005) (xy 89.721032 -271.90126)
			(xy 89.679148 -271.93017) (xy 89.633169 -271.951987) (xy 89.584285 -271.966147) (xy 89.533764 -271.972281)
			(xy 89.482912 -271.970232) (xy 89.433048 -271.960052) (xy 89.385462 -271.942005) (xy 89.341388 -271.916559)
			(xy 89.301966 -271.884372) (xy 89.268218 -271.846278) (xy 89.241017 -271.803264) (xy 89.221069 -271.756444)
			(xy 89.20889 -271.70703) (xy 89.204795 -271.656302) (xy 88.886284 -271.656302) (xy 88.885789 -271.680909)
			(xy 88.877894 -271.729486) (xy 88.86231 -271.776167) (xy 88.839439 -271.819744) (xy 88.809874 -271.859088)
			(xy 88.774381 -271.89318) (xy 88.733878 -271.921136) (xy 88.689416 -271.942234) (xy 88.642145 -271.955926)
			(xy 88.59329 -271.961858) (xy 88.544115 -271.959877) (xy 88.495896 -271.950033) (xy 88.44988 -271.932581)
			(xy 88.407259 -271.907974) (xy 88.369138 -271.876849) (xy 88.336503 -271.840012) (xy 88.3102 -271.798416)
			(xy 88.290909 -271.75314) (xy 88.279132 -271.705356) (xy 88.275172 -271.656302) (xy 87.956644 -271.656302)
			(xy 87.956132 -271.681748) (xy 87.947968 -271.731982) (xy 87.931852 -271.780256) (xy 87.908201 -271.825319)
			(xy 87.877628 -271.866005) (xy 87.840924 -271.90126) (xy 87.79904 -271.93017) (xy 87.753061 -271.951987)
			(xy 87.704177 -271.966147) (xy 87.653656 -271.972281) (xy 87.602804 -271.970232) (xy 87.55294 -271.960052)
			(xy 87.505354 -271.942005) (xy 87.46128 -271.916559) (xy 87.421858 -271.884372) (xy 87.38811 -271.846278)
			(xy 87.360909 -271.803264) (xy 87.340961 -271.756444) (xy 87.328782 -271.70703) (xy 87.324687 -271.656302)
			(xy 87.00643 -271.656302) (xy 87.005935 -271.680909) (xy 86.99804 -271.729486) (xy 86.982456 -271.776167)
			(xy 86.959585 -271.819744) (xy 86.93002 -271.859088) (xy 86.894527 -271.89318) (xy 86.854024 -271.921136)
			(xy 86.809562 -271.942234) (xy 86.762291 -271.955926) (xy 86.713436 -271.961858) (xy 86.664261 -271.959877)
			(xy 86.616042 -271.950033) (xy 86.570026 -271.932581) (xy 86.527405 -271.907974) (xy 86.489284 -271.876849)
			(xy 86.456649 -271.840012) (xy 86.430346 -271.798416) (xy 86.411055 -271.75314) (xy 86.399278 -271.705356)
			(xy 86.395318 -271.656302) (xy 86.07679 -271.656302) (xy 86.076278 -271.681748) (xy 86.068114 -271.731982)
			(xy 86.051998 -271.780256) (xy 86.028347 -271.825319) (xy 85.997774 -271.866005) (xy 85.96107 -271.90126)
			(xy 85.919186 -271.93017) (xy 85.873207 -271.951987) (xy 85.824323 -271.966147) (xy 85.773802 -271.972281)
			(xy 85.72295 -271.970232) (xy 85.673086 -271.960052) (xy 85.6255 -271.942005) (xy 85.581426 -271.916559)
			(xy 85.542004 -271.884372) (xy 85.508256 -271.846278) (xy 85.481055 -271.803264) (xy 85.461107 -271.756444)
			(xy 85.448928 -271.70703) (xy 85.444833 -271.656302) (xy 85.136736 -271.656302) (xy 85.136224 -271.681748)
			(xy 85.12806 -271.731982) (xy 85.111944 -271.780256) (xy 85.088293 -271.825319) (xy 85.05772 -271.866005)
			(xy 85.021016 -271.90126) (xy 84.979132 -271.93017) (xy 84.933153 -271.951987) (xy 84.884269 -271.966147)
			(xy 84.833748 -271.972281) (xy 84.782896 -271.970232) (xy 84.733032 -271.960052) (xy 84.685446 -271.942005)
			(xy 84.641372 -271.916559) (xy 84.60195 -271.884372) (xy 84.568202 -271.846278) (xy 84.541001 -271.803264)
			(xy 84.521053 -271.756444) (xy 84.508874 -271.70703) (xy 84.504779 -271.656302) (xy 84.186268 -271.656302)
			(xy 84.185773 -271.680909) (xy 84.177878 -271.729486) (xy 84.162294 -271.776167) (xy 84.139423 -271.819744)
			(xy 84.109858 -271.859088) (xy 84.074365 -271.89318) (xy 84.033862 -271.921136) (xy 83.9894 -271.942234)
			(xy 83.942129 -271.955926) (xy 83.893274 -271.961858) (xy 83.844099 -271.959877) (xy 83.79588 -271.950033)
			(xy 83.749864 -271.932581) (xy 83.707243 -271.907974) (xy 83.669122 -271.876849) (xy 83.636487 -271.840012)
			(xy 83.610184 -271.798416) (xy 83.590893 -271.75314) (xy 83.579116 -271.705356) (xy 83.575156 -271.656302)
			(xy 83.256628 -271.656302) (xy 83.256116 -271.681748) (xy 83.247952 -271.731982) (xy 83.231836 -271.780256)
			(xy 83.208185 -271.825319) (xy 83.177612 -271.866005) (xy 83.140908 -271.90126) (xy 83.099024 -271.93017)
			(xy 83.053045 -271.951987) (xy 83.004161 -271.966147) (xy 82.95364 -271.972281) (xy 82.902788 -271.970232)
			(xy 82.852924 -271.960052) (xy 82.805338 -271.942005) (xy 82.761264 -271.916559) (xy 82.721842 -271.884372)
			(xy 82.688094 -271.846278) (xy 82.660893 -271.803264) (xy 82.640945 -271.756444) (xy 82.628766 -271.70703)
			(xy 82.624671 -271.656302) (xy 82.306414 -271.656302) (xy 82.305919 -271.680909) (xy 82.298024 -271.729486)
			(xy 82.28244 -271.776167) (xy 82.259569 -271.819744) (xy 82.230004 -271.859088) (xy 82.194511 -271.89318)
			(xy 82.154008 -271.921136) (xy 82.109546 -271.942234) (xy 82.062275 -271.955926) (xy 82.01342 -271.961858)
			(xy 81.964245 -271.959877) (xy 81.916026 -271.950033) (xy 81.87001 -271.932581) (xy 81.827389 -271.907974)
			(xy 81.789268 -271.876849) (xy 81.756633 -271.840012) (xy 81.73033 -271.798416) (xy 81.711039 -271.75314)
			(xy 81.699262 -271.705356) (xy 81.695302 -271.656302) (xy 81.376774 -271.656302) (xy 81.376262 -271.681748)
			(xy 81.368098 -271.731982) (xy 81.351982 -271.780256) (xy 81.328331 -271.825319) (xy 81.297758 -271.866005)
			(xy 81.261054 -271.90126) (xy 81.21917 -271.93017) (xy 81.173191 -271.951987) (xy 81.124307 -271.966147)
			(xy 81.073786 -271.972281) (xy 81.022934 -271.970232) (xy 80.97307 -271.960052) (xy 80.925484 -271.942005)
			(xy 80.88141 -271.916559) (xy 80.841988 -271.884372) (xy 80.80824 -271.846278) (xy 80.781039 -271.803264)
			(xy 80.761091 -271.756444) (xy 80.748912 -271.70703) (xy 80.744817 -271.656302) (xy 80.426306 -271.656302)
			(xy 80.425811 -271.680909) (xy 80.417916 -271.729486) (xy 80.402332 -271.776167) (xy 80.379461 -271.819744)
			(xy 80.349896 -271.859088) (xy 80.314403 -271.89318) (xy 80.2739 -271.921136) (xy 80.229438 -271.942234)
			(xy 80.182167 -271.955926) (xy 80.133312 -271.961858) (xy 80.084137 -271.959877) (xy 80.035918 -271.950033)
			(xy 79.989902 -271.932581) (xy 79.947281 -271.907974) (xy 79.90916 -271.876849) (xy 79.876525 -271.840012)
			(xy 79.850222 -271.798416) (xy 79.830931 -271.75314) (xy 79.819154 -271.705356) (xy 79.815194 -271.656302)
			(xy 77.263451 -271.656302) (xy 77.221316 -271.676296) (xy 77.174045 -271.689988) (xy 77.12519 -271.69592)
			(xy 77.076015 -271.693939) (xy 77.027796 -271.684095) (xy 76.98178 -271.666643) (xy 76.939159 -271.642036)
			(xy 76.901038 -271.610911) (xy 76.868403 -271.574074) (xy 76.8421 -271.532478) (xy 76.822809 -271.487202)
			(xy 76.811032 -271.439418) (xy 76.807072 -271.390364) (xy 73.228962 -271.390364) (xy 73.228962 -272.466308)
			(xy 78.40524 -272.466308) (xy 78.4092 -272.417254) (xy 78.420977 -272.36947) (xy 78.440268 -272.324194)
			(xy 78.466571 -272.282598) (xy 78.499206 -272.245761) (xy 78.537327 -272.214636) (xy 78.579948 -272.190029)
			(xy 78.625964 -272.172577) (xy 78.674183 -272.162733) (xy 78.723358 -272.160752) (xy 78.772213 -272.166684)
			(xy 78.819484 -272.180376) (xy 78.863946 -272.201474) (xy 78.904449 -272.22943) (xy 78.939942 -272.263522)
			(xy 78.969507 -272.302866) (xy 78.992378 -272.346443) (xy 79.007962 -272.393124) (xy 79.015857 -272.441701)
			(xy 79.016352 -272.466308) (xy 80.285348 -272.466308) (xy 80.289308 -272.417254) (xy 80.301085 -272.36947)
			(xy 80.320376 -272.324194) (xy 80.346679 -272.282598) (xy 80.379314 -272.245761) (xy 80.417435 -272.214636)
			(xy 80.460056 -272.190029) (xy 80.506072 -272.172577) (xy 80.554291 -272.162733) (xy 80.603466 -272.160752)
			(xy 80.652321 -272.166684) (xy 80.699592 -272.180376) (xy 80.744054 -272.201474) (xy 80.784557 -272.22943)
			(xy 80.82005 -272.263522) (xy 80.849615 -272.302866) (xy 80.872486 -272.346443) (xy 80.88807 -272.393124)
			(xy 80.895965 -272.441701) (xy 80.89646 -272.466308) (xy 81.214717 -272.466308) (xy 81.218812 -272.41558)
			(xy 81.230991 -272.366166) (xy 81.250939 -272.319346) (xy 81.27814 -272.276332) (xy 81.311888 -272.238238)
			(xy 81.35131 -272.206051) (xy 81.395384 -272.180605) (xy 81.44297 -272.162558) (xy 81.492834 -272.152378)
			(xy 81.543686 -272.150329) (xy 81.594207 -272.156463) (xy 81.643091 -272.170623) (xy 81.68907 -272.19244)
			(xy 81.730954 -272.22135) (xy 81.767658 -272.256605) (xy 81.798231 -272.297291) (xy 81.821882 -272.342354)
			(xy 81.837998 -272.390628) (xy 81.846162 -272.440862) (xy 81.846674 -272.466308) (xy 82.154771 -272.466308)
			(xy 82.158866 -272.41558) (xy 82.171045 -272.366166) (xy 82.190993 -272.319346) (xy 82.218194 -272.276332)
			(xy 82.251942 -272.238238) (xy 82.291364 -272.206051) (xy 82.335438 -272.180605) (xy 82.383024 -272.162558)
			(xy 82.432888 -272.152378) (xy 82.48374 -272.150329) (xy 82.534261 -272.156463) (xy 82.583145 -272.170623)
			(xy 82.629124 -272.19244) (xy 82.671008 -272.22135) (xy 82.707712 -272.256605) (xy 82.738285 -272.297291)
			(xy 82.761936 -272.342354) (xy 82.778052 -272.390628) (xy 82.786216 -272.440862) (xy 82.786728 -272.466308)
			(xy 83.105256 -272.466308) (xy 83.109216 -272.417254) (xy 83.120993 -272.36947) (xy 83.140284 -272.324194)
			(xy 83.166587 -272.282598) (xy 83.199222 -272.245761) (xy 83.237343 -272.214636) (xy 83.279964 -272.190029)
			(xy 83.32598 -272.172577) (xy 83.374199 -272.162733) (xy 83.423374 -272.160752) (xy 83.472229 -272.166684)
			(xy 83.5195 -272.180376) (xy 83.563962 -272.201474) (xy 83.604465 -272.22943) (xy 83.639958 -272.263522)
			(xy 83.669523 -272.302866) (xy 83.692394 -272.346443) (xy 83.707978 -272.393124) (xy 83.715873 -272.441701)
			(xy 83.716368 -272.466308) (xy 84.034879 -272.466308) (xy 84.038974 -272.41558) (xy 84.051153 -272.366166)
			(xy 84.071101 -272.319346) (xy 84.098302 -272.276332) (xy 84.13205 -272.238238) (xy 84.171472 -272.206051)
			(xy 84.215546 -272.180605) (xy 84.263132 -272.162558) (xy 84.312996 -272.152378) (xy 84.363848 -272.150329)
			(xy 84.414369 -272.156463) (xy 84.463253 -272.170623) (xy 84.509232 -272.19244) (xy 84.551116 -272.22135)
			(xy 84.58782 -272.256605) (xy 84.618393 -272.297291) (xy 84.642044 -272.342354) (xy 84.65816 -272.390628)
			(xy 84.666324 -272.440862) (xy 84.666836 -272.466308) (xy 84.98511 -272.466308) (xy 84.98907 -272.417254)
			(xy 85.000847 -272.36947) (xy 85.020138 -272.324194) (xy 85.046441 -272.282598) (xy 85.079076 -272.245761)
			(xy 85.117197 -272.214636) (xy 85.159818 -272.190029) (xy 85.205834 -272.172577) (xy 85.254053 -272.162733)
			(xy 85.303228 -272.160752) (xy 85.352083 -272.166684) (xy 85.399354 -272.180376) (xy 85.443816 -272.201474)
			(xy 85.484319 -272.22943) (xy 85.519812 -272.263522) (xy 85.549377 -272.302866) (xy 85.572248 -272.346443)
			(xy 85.587832 -272.393124) (xy 85.595727 -272.441701) (xy 85.596222 -272.466308) (xy 85.914733 -272.466308)
			(xy 85.918828 -272.41558) (xy 85.931007 -272.366166) (xy 85.950955 -272.319346) (xy 85.978156 -272.276332)
			(xy 86.011904 -272.238238) (xy 86.051326 -272.206051) (xy 86.0954 -272.180605) (xy 86.142986 -272.162558)
			(xy 86.19285 -272.152378) (xy 86.243702 -272.150329) (xy 86.294223 -272.156463) (xy 86.343107 -272.170623)
			(xy 86.389086 -272.19244) (xy 86.43097 -272.22135) (xy 86.467674 -272.256605) (xy 86.498247 -272.297291)
			(xy 86.521898 -272.342354) (xy 86.538014 -272.390628) (xy 86.546178 -272.440862) (xy 86.54669 -272.466308)
			(xy 86.865218 -272.466308) (xy 86.869178 -272.417254) (xy 86.880955 -272.36947) (xy 86.900246 -272.324194)
			(xy 86.926549 -272.282598) (xy 86.959184 -272.245761) (xy 86.997305 -272.214636) (xy 87.039926 -272.190029)
			(xy 87.085942 -272.172577) (xy 87.134161 -272.162733) (xy 87.183336 -272.160752) (xy 87.232191 -272.166684)
			(xy 87.279462 -272.180376) (xy 87.323924 -272.201474) (xy 87.364427 -272.22943) (xy 87.39992 -272.263522)
			(xy 87.429485 -272.302866) (xy 87.452356 -272.346443) (xy 87.46794 -272.393124) (xy 87.475835 -272.441701)
			(xy 87.47633 -272.466308) (xy 87.794841 -272.466308) (xy 87.798936 -272.41558) (xy 87.811115 -272.366166)
			(xy 87.831063 -272.319346) (xy 87.858264 -272.276332) (xy 87.892012 -272.238238) (xy 87.931434 -272.206051)
			(xy 87.975508 -272.180605) (xy 88.023094 -272.162558) (xy 88.072958 -272.152378) (xy 88.12381 -272.150329)
			(xy 88.174331 -272.156463) (xy 88.223215 -272.170623) (xy 88.269194 -272.19244) (xy 88.311078 -272.22135)
			(xy 88.347782 -272.256605) (xy 88.378355 -272.297291) (xy 88.402006 -272.342354) (xy 88.418122 -272.390628)
			(xy 88.426286 -272.440862) (xy 88.426798 -272.466308) (xy 88.734895 -272.466308) (xy 88.73899 -272.41558)
			(xy 88.751169 -272.366166) (xy 88.771117 -272.319346) (xy 88.798318 -272.276332) (xy 88.832066 -272.238238)
			(xy 88.871488 -272.206051) (xy 88.915562 -272.180605) (xy 88.963148 -272.162558) (xy 89.013012 -272.152378)
			(xy 89.063864 -272.150329) (xy 89.114385 -272.156463) (xy 89.163269 -272.170623) (xy 89.209248 -272.19244)
			(xy 89.251132 -272.22135) (xy 89.287836 -272.256605) (xy 89.318409 -272.297291) (xy 89.34206 -272.342354)
			(xy 89.358176 -272.390628) (xy 89.36634 -272.440862) (xy 89.366852 -272.466308) (xy 89.685126 -272.466308)
			(xy 89.689086 -272.417254) (xy 89.700863 -272.36947) (xy 89.720154 -272.324194) (xy 89.746457 -272.282598)
			(xy 89.779092 -272.245761) (xy 89.817213 -272.214636) (xy 89.859834 -272.190029) (xy 89.90585 -272.172577)
			(xy 89.954069 -272.162733) (xy 90.003244 -272.160752) (xy 90.052099 -272.166684) (xy 90.09937 -272.180376)
			(xy 90.143832 -272.201474) (xy 90.184335 -272.22943) (xy 90.219828 -272.263522) (xy 90.249393 -272.302866)
			(xy 90.272264 -272.346443) (xy 90.287848 -272.393124) (xy 90.295743 -272.441701) (xy 90.296238 -272.466308)
			(xy 90.614749 -272.466308) (xy 90.618844 -272.41558) (xy 90.631023 -272.366166) (xy 90.650971 -272.319346)
			(xy 90.678172 -272.276332) (xy 90.71192 -272.238238) (xy 90.751342 -272.206051) (xy 90.795416 -272.180605)
			(xy 90.843002 -272.162558) (xy 90.892866 -272.152378) (xy 90.943718 -272.150329) (xy 90.994239 -272.156463)
			(xy 91.043123 -272.170623) (xy 91.089102 -272.19244) (xy 91.130986 -272.22135) (xy 91.16769 -272.256605)
			(xy 91.198263 -272.297291) (xy 91.221914 -272.342354) (xy 91.23803 -272.390628) (xy 91.246194 -272.440862)
			(xy 91.246706 -272.466308) (xy 91.565234 -272.466308) (xy 91.569194 -272.417254) (xy 91.580971 -272.36947)
			(xy 91.600262 -272.324194) (xy 91.626565 -272.282598) (xy 91.6592 -272.245761) (xy 91.697321 -272.214636)
			(xy 91.739942 -272.190029) (xy 91.785958 -272.172577) (xy 91.834177 -272.162733) (xy 91.883352 -272.160752)
			(xy 91.932207 -272.166684) (xy 91.979478 -272.180376) (xy 92.02394 -272.201474) (xy 92.064443 -272.22943)
			(xy 92.099936 -272.263522) (xy 92.129501 -272.302866) (xy 92.152372 -272.346443) (xy 92.167956 -272.393124)
			(xy 92.175851 -272.441701) (xy 92.176346 -272.466308) (xy 92.494857 -272.466308) (xy 92.498952 -272.41558)
			(xy 92.511131 -272.366166) (xy 92.531079 -272.319346) (xy 92.55828 -272.276332) (xy 92.592028 -272.238238)
			(xy 92.63145 -272.206051) (xy 92.675524 -272.180605) (xy 92.72311 -272.162558) (xy 92.772974 -272.152378)
			(xy 92.823826 -272.150329) (xy 92.874347 -272.156463) (xy 92.923231 -272.170623) (xy 92.96921 -272.19244)
			(xy 93.011094 -272.22135) (xy 93.047798 -272.256605) (xy 93.078371 -272.297291) (xy 93.102022 -272.342354)
			(xy 93.118138 -272.390628) (xy 93.126302 -272.440862) (xy 93.126814 -272.466308) (xy 93.445342 -272.466308)
			(xy 93.449302 -272.417254) (xy 93.461079 -272.36947) (xy 93.48037 -272.324194) (xy 93.506673 -272.282598)
			(xy 93.539308 -272.245761) (xy 93.577429 -272.214636) (xy 93.62005 -272.190029) (xy 93.666066 -272.172577)
			(xy 93.714285 -272.162733) (xy 93.76346 -272.160752) (xy 93.812315 -272.166684) (xy 93.859586 -272.180376)
			(xy 93.904048 -272.201474) (xy 93.944551 -272.22943) (xy 93.980044 -272.263522) (xy 94.009609 -272.302866)
			(xy 94.03248 -272.346443) (xy 94.048064 -272.393124) (xy 94.055959 -272.441701) (xy 94.056454 -272.466308)
			(xy 94.374711 -272.466308) (xy 94.378806 -272.41558) (xy 94.390985 -272.366166) (xy 94.410933 -272.319346)
			(xy 94.438134 -272.276332) (xy 94.471882 -272.238238) (xy 94.511304 -272.206051) (xy 94.555378 -272.180605)
			(xy 94.602964 -272.162558) (xy 94.652828 -272.152378) (xy 94.70368 -272.150329) (xy 94.754201 -272.156463)
			(xy 94.803085 -272.170623) (xy 94.849064 -272.19244) (xy 94.890948 -272.22135) (xy 94.927652 -272.256605)
			(xy 94.958225 -272.297291) (xy 94.981876 -272.342354) (xy 94.997992 -272.390628) (xy 95.006156 -272.440862)
			(xy 95.006668 -272.466308) (xy 95.314765 -272.466308) (xy 95.31886 -272.41558) (xy 95.331039 -272.366166)
			(xy 95.350987 -272.319346) (xy 95.378188 -272.276332) (xy 95.411936 -272.238238) (xy 95.451358 -272.206051)
			(xy 95.495432 -272.180605) (xy 95.543018 -272.162558) (xy 95.592882 -272.152378) (xy 95.643734 -272.150329)
			(xy 95.694255 -272.156463) (xy 95.743139 -272.170623) (xy 95.789118 -272.19244) (xy 95.831002 -272.22135)
			(xy 95.867706 -272.256605) (xy 95.898279 -272.297291) (xy 95.92193 -272.342354) (xy 95.938046 -272.390628)
			(xy 95.94621 -272.440862) (xy 95.946722 -272.466308) (xy 96.26525 -272.466308) (xy 96.26921 -272.417254)
			(xy 96.280987 -272.36947) (xy 96.300278 -272.324194) (xy 96.326581 -272.282598) (xy 96.359216 -272.245761)
			(xy 96.397337 -272.214636) (xy 96.439958 -272.190029) (xy 96.485974 -272.172577) (xy 96.534193 -272.162733)
			(xy 96.583368 -272.160752) (xy 96.632223 -272.166684) (xy 96.679494 -272.180376) (xy 96.723956 -272.201474)
			(xy 96.764459 -272.22943) (xy 96.799952 -272.263522) (xy 96.829517 -272.302866) (xy 96.852388 -272.346443)
			(xy 96.867972 -272.393124) (xy 96.875867 -272.441701) (xy 96.876362 -272.466308) (xy 99.085158 -272.466308)
			(xy 99.089118 -272.417254) (xy 99.100895 -272.36947) (xy 99.120186 -272.324194) (xy 99.146489 -272.282598)
			(xy 99.179124 -272.245761) (xy 99.217245 -272.214636) (xy 99.259866 -272.190029) (xy 99.305882 -272.172577)
			(xy 99.354101 -272.162733) (xy 99.403276 -272.160752) (xy 99.452131 -272.166684) (xy 99.499402 -272.180376)
			(xy 99.543864 -272.201474) (xy 99.584367 -272.22943) (xy 99.61986 -272.263522) (xy 99.649425 -272.302866)
			(xy 99.672296 -272.346443) (xy 99.68788 -272.393124) (xy 99.695775 -272.441701) (xy 99.69627 -272.466308)
			(xy 101.90532 -272.466308) (xy 101.90928 -272.417254) (xy 101.921057 -272.36947) (xy 101.940348 -272.324194)
			(xy 101.966651 -272.282598) (xy 101.999286 -272.245761) (xy 102.037407 -272.214636) (xy 102.080028 -272.190029)
			(xy 102.126044 -272.172577) (xy 102.174263 -272.162733) (xy 102.223438 -272.160752) (xy 102.272293 -272.166684)
			(xy 102.319564 -272.180376) (xy 102.364026 -272.201474) (xy 102.404529 -272.22943) (xy 102.440022 -272.263522)
			(xy 102.469587 -272.302866) (xy 102.492458 -272.346443) (xy 102.508042 -272.393124) (xy 102.515937 -272.441701)
			(xy 102.516432 -272.466308) (xy 102.515937 -272.490915) (xy 102.508042 -272.539492) (xy 102.492458 -272.586173)
			(xy 102.469587 -272.62975) (xy 102.440022 -272.669094) (xy 102.404529 -272.703186) (xy 102.364026 -272.731142)
			(xy 102.319564 -272.75224) (xy 102.272293 -272.765932) (xy 102.223438 -272.771864) (xy 102.174263 -272.769883)
			(xy 102.126044 -272.760039) (xy 102.080028 -272.742587) (xy 102.037407 -272.71798) (xy 101.999286 -272.686855)
			(xy 101.966651 -272.650018) (xy 101.940348 -272.608422) (xy 101.921057 -272.563146) (xy 101.90928 -272.515362)
			(xy 101.90532 -272.466308) (xy 99.69627 -272.466308) (xy 99.695775 -272.490915) (xy 99.68788 -272.539492)
			(xy 99.672296 -272.586173) (xy 99.649425 -272.62975) (xy 99.61986 -272.669094) (xy 99.584367 -272.703186)
			(xy 99.543864 -272.731142) (xy 99.499402 -272.75224) (xy 99.452131 -272.765932) (xy 99.403276 -272.771864)
			(xy 99.354101 -272.769883) (xy 99.305882 -272.760039) (xy 99.259866 -272.742587) (xy 99.217245 -272.71798)
			(xy 99.179124 -272.686855) (xy 99.146489 -272.650018) (xy 99.120186 -272.608422) (xy 99.100895 -272.563146)
			(xy 99.089118 -272.515362) (xy 99.085158 -272.466308) (xy 96.876362 -272.466308) (xy 96.875867 -272.490915)
			(xy 96.867972 -272.539492) (xy 96.852388 -272.586173) (xy 96.829517 -272.62975) (xy 96.799952 -272.669094)
			(xy 96.764459 -272.703186) (xy 96.723956 -272.731142) (xy 96.679494 -272.75224) (xy 96.632223 -272.765932)
			(xy 96.583368 -272.771864) (xy 96.534193 -272.769883) (xy 96.485974 -272.760039) (xy 96.439958 -272.742587)
			(xy 96.397337 -272.71798) (xy 96.359216 -272.686855) (xy 96.326581 -272.650018) (xy 96.300278 -272.608422)
			(xy 96.280987 -272.563146) (xy 96.26921 -272.515362) (xy 96.26525 -272.466308) (xy 95.946722 -272.466308)
			(xy 95.94621 -272.491754) (xy 95.938046 -272.541988) (xy 95.92193 -272.590262) (xy 95.898279 -272.635325)
			(xy 95.867706 -272.676011) (xy 95.831002 -272.711266) (xy 95.789118 -272.740176) (xy 95.743139 -272.761993)
			(xy 95.694255 -272.776153) (xy 95.643734 -272.782287) (xy 95.592882 -272.780238) (xy 95.543018 -272.770058)
			(xy 95.495432 -272.752011) (xy 95.451358 -272.726565) (xy 95.411936 -272.694378) (xy 95.378188 -272.656284)
			(xy 95.350987 -272.61327) (xy 95.331039 -272.56645) (xy 95.31886 -272.517036) (xy 95.314765 -272.466308)
			(xy 95.006668 -272.466308) (xy 95.006156 -272.491754) (xy 94.997992 -272.541988) (xy 94.981876 -272.590262)
			(xy 94.958225 -272.635325) (xy 94.927652 -272.676011) (xy 94.890948 -272.711266) (xy 94.849064 -272.740176)
			(xy 94.803085 -272.761993) (xy 94.754201 -272.776153) (xy 94.70368 -272.782287) (xy 94.652828 -272.780238)
			(xy 94.602964 -272.770058) (xy 94.555378 -272.752011) (xy 94.511304 -272.726565) (xy 94.471882 -272.694378)
			(xy 94.438134 -272.656284) (xy 94.410933 -272.61327) (xy 94.390985 -272.56645) (xy 94.378806 -272.517036)
			(xy 94.374711 -272.466308) (xy 94.056454 -272.466308) (xy 94.055959 -272.490915) (xy 94.048064 -272.539492)
			(xy 94.03248 -272.586173) (xy 94.009609 -272.62975) (xy 93.980044 -272.669094) (xy 93.944551 -272.703186)
			(xy 93.904048 -272.731142) (xy 93.859586 -272.75224) (xy 93.812315 -272.765932) (xy 93.76346 -272.771864)
			(xy 93.714285 -272.769883) (xy 93.666066 -272.760039) (xy 93.62005 -272.742587) (xy 93.577429 -272.71798)
			(xy 93.539308 -272.686855) (xy 93.506673 -272.650018) (xy 93.48037 -272.608422) (xy 93.461079 -272.563146)
			(xy 93.449302 -272.515362) (xy 93.445342 -272.466308) (xy 93.126814 -272.466308) (xy 93.126302 -272.491754)
			(xy 93.118138 -272.541988) (xy 93.102022 -272.590262) (xy 93.078371 -272.635325) (xy 93.047798 -272.676011)
			(xy 93.011094 -272.711266) (xy 92.96921 -272.740176) (xy 92.923231 -272.761993) (xy 92.874347 -272.776153)
			(xy 92.823826 -272.782287) (xy 92.772974 -272.780238) (xy 92.72311 -272.770058) (xy 92.675524 -272.752011)
			(xy 92.63145 -272.726565) (xy 92.592028 -272.694378) (xy 92.55828 -272.656284) (xy 92.531079 -272.61327)
			(xy 92.511131 -272.56645) (xy 92.498952 -272.517036) (xy 92.494857 -272.466308) (xy 92.176346 -272.466308)
			(xy 92.175851 -272.490915) (xy 92.167956 -272.539492) (xy 92.152372 -272.586173) (xy 92.129501 -272.62975)
			(xy 92.099936 -272.669094) (xy 92.064443 -272.703186) (xy 92.02394 -272.731142) (xy 91.979478 -272.75224)
			(xy 91.932207 -272.765932) (xy 91.883352 -272.771864) (xy 91.834177 -272.769883) (xy 91.785958 -272.760039)
			(xy 91.739942 -272.742587) (xy 91.697321 -272.71798) (xy 91.6592 -272.686855) (xy 91.626565 -272.650018)
			(xy 91.600262 -272.608422) (xy 91.580971 -272.563146) (xy 91.569194 -272.515362) (xy 91.565234 -272.466308)
			(xy 91.246706 -272.466308) (xy 91.246194 -272.491754) (xy 91.23803 -272.541988) (xy 91.221914 -272.590262)
			(xy 91.198263 -272.635325) (xy 91.16769 -272.676011) (xy 91.130986 -272.711266) (xy 91.089102 -272.740176)
			(xy 91.043123 -272.761993) (xy 90.994239 -272.776153) (xy 90.943718 -272.782287) (xy 90.892866 -272.780238)
			(xy 90.843002 -272.770058) (xy 90.795416 -272.752011) (xy 90.751342 -272.726565) (xy 90.71192 -272.694378)
			(xy 90.678172 -272.656284) (xy 90.650971 -272.61327) (xy 90.631023 -272.56645) (xy 90.618844 -272.517036)
			(xy 90.614749 -272.466308) (xy 90.296238 -272.466308) (xy 90.295743 -272.490915) (xy 90.287848 -272.539492)
			(xy 90.272264 -272.586173) (xy 90.249393 -272.62975) (xy 90.219828 -272.669094) (xy 90.184335 -272.703186)
			(xy 90.143832 -272.731142) (xy 90.09937 -272.75224) (xy 90.052099 -272.765932) (xy 90.003244 -272.771864)
			(xy 89.954069 -272.769883) (xy 89.90585 -272.760039) (xy 89.859834 -272.742587) (xy 89.817213 -272.71798)
			(xy 89.779092 -272.686855) (xy 89.746457 -272.650018) (xy 89.720154 -272.608422) (xy 89.700863 -272.563146)
			(xy 89.689086 -272.515362) (xy 89.685126 -272.466308) (xy 89.366852 -272.466308) (xy 89.36634 -272.491754)
			(xy 89.358176 -272.541988) (xy 89.34206 -272.590262) (xy 89.318409 -272.635325) (xy 89.287836 -272.676011)
			(xy 89.251132 -272.711266) (xy 89.209248 -272.740176) (xy 89.163269 -272.761993) (xy 89.114385 -272.776153)
			(xy 89.063864 -272.782287) (xy 89.013012 -272.780238) (xy 88.963148 -272.770058) (xy 88.915562 -272.752011)
			(xy 88.871488 -272.726565) (xy 88.832066 -272.694378) (xy 88.798318 -272.656284) (xy 88.771117 -272.61327)
			(xy 88.751169 -272.56645) (xy 88.73899 -272.517036) (xy 88.734895 -272.466308) (xy 88.426798 -272.466308)
			(xy 88.426286 -272.491754) (xy 88.418122 -272.541988) (xy 88.402006 -272.590262) (xy 88.378355 -272.635325)
			(xy 88.347782 -272.676011) (xy 88.311078 -272.711266) (xy 88.269194 -272.740176) (xy 88.223215 -272.761993)
			(xy 88.174331 -272.776153) (xy 88.12381 -272.782287) (xy 88.072958 -272.780238) (xy 88.023094 -272.770058)
			(xy 87.975508 -272.752011) (xy 87.931434 -272.726565) (xy 87.892012 -272.694378) (xy 87.858264 -272.656284)
			(xy 87.831063 -272.61327) (xy 87.811115 -272.56645) (xy 87.798936 -272.517036) (xy 87.794841 -272.466308)
			(xy 87.47633 -272.466308) (xy 87.475835 -272.490915) (xy 87.46794 -272.539492) (xy 87.452356 -272.586173)
			(xy 87.429485 -272.62975) (xy 87.39992 -272.669094) (xy 87.364427 -272.703186) (xy 87.323924 -272.731142)
			(xy 87.279462 -272.75224) (xy 87.232191 -272.765932) (xy 87.183336 -272.771864) (xy 87.134161 -272.769883)
			(xy 87.085942 -272.760039) (xy 87.039926 -272.742587) (xy 86.997305 -272.71798) (xy 86.959184 -272.686855)
			(xy 86.926549 -272.650018) (xy 86.900246 -272.608422) (xy 86.880955 -272.563146) (xy 86.869178 -272.515362)
			(xy 86.865218 -272.466308) (xy 86.54669 -272.466308) (xy 86.546178 -272.491754) (xy 86.538014 -272.541988)
			(xy 86.521898 -272.590262) (xy 86.498247 -272.635325) (xy 86.467674 -272.676011) (xy 86.43097 -272.711266)
			(xy 86.389086 -272.740176) (xy 86.343107 -272.761993) (xy 86.294223 -272.776153) (xy 86.243702 -272.782287)
			(xy 86.19285 -272.780238) (xy 86.142986 -272.770058) (xy 86.0954 -272.752011) (xy 86.051326 -272.726565)
			(xy 86.011904 -272.694378) (xy 85.978156 -272.656284) (xy 85.950955 -272.61327) (xy 85.931007 -272.56645)
			(xy 85.918828 -272.517036) (xy 85.914733 -272.466308) (xy 85.596222 -272.466308) (xy 85.595727 -272.490915)
			(xy 85.587832 -272.539492) (xy 85.572248 -272.586173) (xy 85.549377 -272.62975) (xy 85.519812 -272.669094)
			(xy 85.484319 -272.703186) (xy 85.443816 -272.731142) (xy 85.399354 -272.75224) (xy 85.352083 -272.765932)
			(xy 85.303228 -272.771864) (xy 85.254053 -272.769883) (xy 85.205834 -272.760039) (xy 85.159818 -272.742587)
			(xy 85.117197 -272.71798) (xy 85.079076 -272.686855) (xy 85.046441 -272.650018) (xy 85.020138 -272.608422)
			(xy 85.000847 -272.563146) (xy 84.98907 -272.515362) (xy 84.98511 -272.466308) (xy 84.666836 -272.466308)
			(xy 84.666324 -272.491754) (xy 84.65816 -272.541988) (xy 84.642044 -272.590262) (xy 84.618393 -272.635325)
			(xy 84.58782 -272.676011) (xy 84.551116 -272.711266) (xy 84.509232 -272.740176) (xy 84.463253 -272.761993)
			(xy 84.414369 -272.776153) (xy 84.363848 -272.782287) (xy 84.312996 -272.780238) (xy 84.263132 -272.770058)
			(xy 84.215546 -272.752011) (xy 84.171472 -272.726565) (xy 84.13205 -272.694378) (xy 84.098302 -272.656284)
			(xy 84.071101 -272.61327) (xy 84.051153 -272.56645) (xy 84.038974 -272.517036) (xy 84.034879 -272.466308)
			(xy 83.716368 -272.466308) (xy 83.715873 -272.490915) (xy 83.707978 -272.539492) (xy 83.692394 -272.586173)
			(xy 83.669523 -272.62975) (xy 83.639958 -272.669094) (xy 83.604465 -272.703186) (xy 83.563962 -272.731142)
			(xy 83.5195 -272.75224) (xy 83.472229 -272.765932) (xy 83.423374 -272.771864) (xy 83.374199 -272.769883)
			(xy 83.32598 -272.760039) (xy 83.279964 -272.742587) (xy 83.237343 -272.71798) (xy 83.199222 -272.686855)
			(xy 83.166587 -272.650018) (xy 83.140284 -272.608422) (xy 83.120993 -272.563146) (xy 83.109216 -272.515362)
			(xy 83.105256 -272.466308) (xy 82.786728 -272.466308) (xy 82.786216 -272.491754) (xy 82.778052 -272.541988)
			(xy 82.761936 -272.590262) (xy 82.738285 -272.635325) (xy 82.707712 -272.676011) (xy 82.671008 -272.711266)
			(xy 82.629124 -272.740176) (xy 82.583145 -272.761993) (xy 82.534261 -272.776153) (xy 82.48374 -272.782287)
			(xy 82.432888 -272.780238) (xy 82.383024 -272.770058) (xy 82.335438 -272.752011) (xy 82.291364 -272.726565)
			(xy 82.251942 -272.694378) (xy 82.218194 -272.656284) (xy 82.190993 -272.61327) (xy 82.171045 -272.56645)
			(xy 82.158866 -272.517036) (xy 82.154771 -272.466308) (xy 81.846674 -272.466308) (xy 81.846162 -272.491754)
			(xy 81.837998 -272.541988) (xy 81.821882 -272.590262) (xy 81.798231 -272.635325) (xy 81.767658 -272.676011)
			(xy 81.730954 -272.711266) (xy 81.68907 -272.740176) (xy 81.643091 -272.761993) (xy 81.594207 -272.776153)
			(xy 81.543686 -272.782287) (xy 81.492834 -272.780238) (xy 81.44297 -272.770058) (xy 81.395384 -272.752011)
			(xy 81.35131 -272.726565) (xy 81.311888 -272.694378) (xy 81.27814 -272.656284) (xy 81.250939 -272.61327)
			(xy 81.230991 -272.56645) (xy 81.218812 -272.517036) (xy 81.214717 -272.466308) (xy 80.89646 -272.466308)
			(xy 80.895965 -272.490915) (xy 80.88807 -272.539492) (xy 80.872486 -272.586173) (xy 80.849615 -272.62975)
			(xy 80.82005 -272.669094) (xy 80.784557 -272.703186) (xy 80.744054 -272.731142) (xy 80.699592 -272.75224)
			(xy 80.652321 -272.765932) (xy 80.603466 -272.771864) (xy 80.554291 -272.769883) (xy 80.506072 -272.760039)
			(xy 80.460056 -272.742587) (xy 80.417435 -272.71798) (xy 80.379314 -272.686855) (xy 80.346679 -272.650018)
			(xy 80.320376 -272.608422) (xy 80.301085 -272.563146) (xy 80.289308 -272.515362) (xy 80.285348 -272.466308)
			(xy 79.016352 -272.466308) (xy 79.015857 -272.490915) (xy 79.007962 -272.539492) (xy 78.992378 -272.586173)
			(xy 78.969507 -272.62975) (xy 78.939942 -272.669094) (xy 78.904449 -272.703186) (xy 78.863946 -272.731142)
			(xy 78.819484 -272.75224) (xy 78.772213 -272.765932) (xy 78.723358 -272.771864) (xy 78.674183 -272.769883)
			(xy 78.625964 -272.760039) (xy 78.579948 -272.742587) (xy 78.537327 -272.71798) (xy 78.499206 -272.686855)
			(xy 78.466571 -272.650018) (xy 78.440268 -272.608422) (xy 78.420977 -272.563146) (xy 78.4092 -272.515362)
			(xy 78.40524 -272.466308) (xy 73.228962 -272.466308) (xy 73.228962 -273.010376) (xy 76.807072 -273.010376)
			(xy 76.811032 -272.961322) (xy 76.822809 -272.913538) (xy 76.8421 -272.868262) (xy 76.868403 -272.826666)
			(xy 76.901038 -272.789829) (xy 76.939159 -272.758704) (xy 76.98178 -272.734097) (xy 77.027796 -272.716645)
			(xy 77.076015 -272.706801) (xy 77.12519 -272.70482) (xy 77.174045 -272.710752) (xy 77.221316 -272.724444)
			(xy 77.265778 -272.745542) (xy 77.306281 -272.773498) (xy 77.341774 -272.80759) (xy 77.371339 -272.846934)
			(xy 77.39421 -272.890511) (xy 77.409794 -272.937192) (xy 77.417689 -272.985769) (xy 77.418184 -273.010376)
			(xy 77.417689 -273.034983) (xy 77.409794 -273.08356) (xy 77.39421 -273.130241) (xy 77.371339 -273.173818)
			(xy 77.341774 -273.213162) (xy 77.306281 -273.247254) (xy 77.265778 -273.27521) (xy 77.263451 -273.276314)
			(xy 79.815194 -273.276314) (xy 79.819154 -273.22726) (xy 79.830931 -273.179476) (xy 79.850222 -273.1342)
			(xy 79.876525 -273.092604) (xy 79.90916 -273.055767) (xy 79.947281 -273.024642) (xy 79.989902 -273.000035)
			(xy 80.035918 -272.982583) (xy 80.084137 -272.972739) (xy 80.133312 -272.970758) (xy 80.182167 -272.97669)
			(xy 80.229438 -272.990382) (xy 80.2739 -273.01148) (xy 80.314403 -273.039436) (xy 80.349896 -273.073528)
			(xy 80.379461 -273.112872) (xy 80.402332 -273.156449) (xy 80.417916 -273.20313) (xy 80.425811 -273.251707)
			(xy 80.426306 -273.276314) (xy 80.744817 -273.276314) (xy 80.748912 -273.225586) (xy 80.761091 -273.176172)
			(xy 80.781039 -273.129352) (xy 80.80824 -273.086338) (xy 80.841988 -273.048244) (xy 80.88141 -273.016057)
			(xy 80.925484 -272.990611) (xy 80.97307 -272.972564) (xy 81.022934 -272.962384) (xy 81.073786 -272.960335)
			(xy 81.124307 -272.966469) (xy 81.173191 -272.980629) (xy 81.21917 -273.002446) (xy 81.261054 -273.031356)
			(xy 81.297758 -273.066611) (xy 81.328331 -273.107297) (xy 81.351982 -273.15236) (xy 81.368098 -273.200634)
			(xy 81.376262 -273.250868) (xy 81.376774 -273.276314) (xy 81.695302 -273.276314) (xy 81.699262 -273.22726)
			(xy 81.711039 -273.179476) (xy 81.73033 -273.1342) (xy 81.756633 -273.092604) (xy 81.789268 -273.055767)
			(xy 81.827389 -273.024642) (xy 81.87001 -273.000035) (xy 81.916026 -272.982583) (xy 81.964245 -272.972739)
			(xy 82.01342 -272.970758) (xy 82.062275 -272.97669) (xy 82.109546 -272.990382) (xy 82.154008 -273.01148)
			(xy 82.194511 -273.039436) (xy 82.230004 -273.073528) (xy 82.259569 -273.112872) (xy 82.28244 -273.156449)
			(xy 82.298024 -273.20313) (xy 82.305919 -273.251707) (xy 82.306414 -273.276314) (xy 82.624671 -273.276314)
			(xy 82.628766 -273.225586) (xy 82.640945 -273.176172) (xy 82.660893 -273.129352) (xy 82.688094 -273.086338)
			(xy 82.721842 -273.048244) (xy 82.761264 -273.016057) (xy 82.805338 -272.990611) (xy 82.852924 -272.972564)
			(xy 82.902788 -272.962384) (xy 82.95364 -272.960335) (xy 83.004161 -272.966469) (xy 83.053045 -272.980629)
			(xy 83.099024 -273.002446) (xy 83.140908 -273.031356) (xy 83.177612 -273.066611) (xy 83.208185 -273.107297)
			(xy 83.231836 -273.15236) (xy 83.247952 -273.200634) (xy 83.256116 -273.250868) (xy 83.256628 -273.276314)
			(xy 83.575156 -273.276314) (xy 83.579116 -273.22726) (xy 83.590893 -273.179476) (xy 83.610184 -273.1342)
			(xy 83.636487 -273.092604) (xy 83.669122 -273.055767) (xy 83.707243 -273.024642) (xy 83.749864 -273.000035)
			(xy 83.79588 -272.982583) (xy 83.844099 -272.972739) (xy 83.893274 -272.970758) (xy 83.942129 -272.97669)
			(xy 83.9894 -272.990382) (xy 84.033862 -273.01148) (xy 84.074365 -273.039436) (xy 84.109858 -273.073528)
			(xy 84.139423 -273.112872) (xy 84.162294 -273.156449) (xy 84.177878 -273.20313) (xy 84.185773 -273.251707)
			(xy 84.186268 -273.276314) (xy 84.504779 -273.276314) (xy 84.508874 -273.225586) (xy 84.521053 -273.176172)
			(xy 84.541001 -273.129352) (xy 84.568202 -273.086338) (xy 84.60195 -273.048244) (xy 84.641372 -273.016057)
			(xy 84.685446 -272.990611) (xy 84.733032 -272.972564) (xy 84.782896 -272.962384) (xy 84.833748 -272.960335)
			(xy 84.884269 -272.966469) (xy 84.933153 -272.980629) (xy 84.979132 -273.002446) (xy 85.021016 -273.031356)
			(xy 85.05772 -273.066611) (xy 85.088293 -273.107297) (xy 85.111944 -273.15236) (xy 85.12806 -273.200634)
			(xy 85.136224 -273.250868) (xy 85.136736 -273.276314) (xy 85.444833 -273.276314) (xy 85.448928 -273.225586)
			(xy 85.461107 -273.176172) (xy 85.481055 -273.129352) (xy 85.508256 -273.086338) (xy 85.542004 -273.048244)
			(xy 85.581426 -273.016057) (xy 85.6255 -272.990611) (xy 85.673086 -272.972564) (xy 85.72295 -272.962384)
			(xy 85.773802 -272.960335) (xy 85.824323 -272.966469) (xy 85.873207 -272.980629) (xy 85.919186 -273.002446)
			(xy 85.96107 -273.031356) (xy 85.997774 -273.066611) (xy 86.028347 -273.107297) (xy 86.051998 -273.15236)
			(xy 86.068114 -273.200634) (xy 86.076278 -273.250868) (xy 86.07679 -273.276314) (xy 86.395318 -273.276314)
			(xy 86.399278 -273.22726) (xy 86.411055 -273.179476) (xy 86.430346 -273.1342) (xy 86.456649 -273.092604)
			(xy 86.489284 -273.055767) (xy 86.527405 -273.024642) (xy 86.570026 -273.000035) (xy 86.616042 -272.982583)
			(xy 86.664261 -272.972739) (xy 86.713436 -272.970758) (xy 86.762291 -272.97669) (xy 86.809562 -272.990382)
			(xy 86.854024 -273.01148) (xy 86.894527 -273.039436) (xy 86.93002 -273.073528) (xy 86.959585 -273.112872)
			(xy 86.982456 -273.156449) (xy 86.99804 -273.20313) (xy 87.005935 -273.251707) (xy 87.00643 -273.276314)
			(xy 87.324687 -273.276314) (xy 87.328782 -273.225586) (xy 87.340961 -273.176172) (xy 87.360909 -273.129352)
			(xy 87.38811 -273.086338) (xy 87.421858 -273.048244) (xy 87.46128 -273.016057) (xy 87.505354 -272.990611)
			(xy 87.55294 -272.972564) (xy 87.602804 -272.962384) (xy 87.653656 -272.960335) (xy 87.704177 -272.966469)
			(xy 87.753061 -272.980629) (xy 87.79904 -273.002446) (xy 87.840924 -273.031356) (xy 87.877628 -273.066611)
			(xy 87.908201 -273.107297) (xy 87.931852 -273.15236) (xy 87.947968 -273.200634) (xy 87.956132 -273.250868)
			(xy 87.956644 -273.276314) (xy 88.275172 -273.276314) (xy 88.279132 -273.22726) (xy 88.290909 -273.179476)
			(xy 88.3102 -273.1342) (xy 88.336503 -273.092604) (xy 88.369138 -273.055767) (xy 88.407259 -273.024642)
			(xy 88.44988 -273.000035) (xy 88.495896 -272.982583) (xy 88.544115 -272.972739) (xy 88.59329 -272.970758)
			(xy 88.642145 -272.97669) (xy 88.689416 -272.990382) (xy 88.733878 -273.01148) (xy 88.774381 -273.039436)
			(xy 88.809874 -273.073528) (xy 88.839439 -273.112872) (xy 88.86231 -273.156449) (xy 88.877894 -273.20313)
			(xy 88.885789 -273.251707) (xy 88.886284 -273.276314) (xy 89.204795 -273.276314) (xy 89.20889 -273.225586)
			(xy 89.221069 -273.176172) (xy 89.241017 -273.129352) (xy 89.268218 -273.086338) (xy 89.301966 -273.048244)
			(xy 89.341388 -273.016057) (xy 89.385462 -272.990611) (xy 89.433048 -272.972564) (xy 89.482912 -272.962384)
			(xy 89.533764 -272.960335) (xy 89.584285 -272.966469) (xy 89.633169 -272.980629) (xy 89.679148 -273.002446)
			(xy 89.721032 -273.031356) (xy 89.757736 -273.066611) (xy 89.788309 -273.107297) (xy 89.81196 -273.15236)
			(xy 89.828076 -273.200634) (xy 89.83624 -273.250868) (xy 89.836752 -273.276314) (xy 90.15528 -273.276314)
			(xy 90.15924 -273.22726) (xy 90.171017 -273.179476) (xy 90.190308 -273.1342) (xy 90.216611 -273.092604)
			(xy 90.249246 -273.055767) (xy 90.287367 -273.024642) (xy 90.329988 -273.000035) (xy 90.376004 -272.982583)
			(xy 90.424223 -272.972739) (xy 90.473398 -272.970758) (xy 90.522253 -272.97669) (xy 90.569524 -272.990382)
			(xy 90.613986 -273.01148) (xy 90.654489 -273.039436) (xy 90.689982 -273.073528) (xy 90.719547 -273.112872)
			(xy 90.742418 -273.156449) (xy 90.758002 -273.20313) (xy 90.765897 -273.251707) (xy 90.766392 -273.276314)
			(xy 91.084903 -273.276314) (xy 91.088998 -273.225586) (xy 91.101177 -273.176172) (xy 91.121125 -273.129352)
			(xy 91.148326 -273.086338) (xy 91.182074 -273.048244) (xy 91.221496 -273.016057) (xy 91.26557 -272.990611)
			(xy 91.313156 -272.972564) (xy 91.36302 -272.962384) (xy 91.413872 -272.960335) (xy 91.464393 -272.966469)
			(xy 91.513277 -272.980629) (xy 91.559256 -273.002446) (xy 91.60114 -273.031356) (xy 91.637844 -273.066611)
			(xy 91.668417 -273.107297) (xy 91.692068 -273.15236) (xy 91.708184 -273.200634) (xy 91.716348 -273.250868)
			(xy 91.71686 -273.276314) (xy 92.024703 -273.276314) (xy 92.028798 -273.225586) (xy 92.040977 -273.176172)
			(xy 92.060925 -273.129352) (xy 92.088126 -273.086338) (xy 92.121874 -273.048244) (xy 92.161296 -273.016057)
			(xy 92.20537 -272.990611) (xy 92.252956 -272.972564) (xy 92.30282 -272.962384) (xy 92.353672 -272.960335)
			(xy 92.404193 -272.966469) (xy 92.453077 -272.980629) (xy 92.499056 -273.002446) (xy 92.54094 -273.031356)
			(xy 92.577644 -273.066611) (xy 92.608217 -273.107297) (xy 92.631868 -273.15236) (xy 92.647984 -273.200634)
			(xy 92.656148 -273.250868) (xy 92.65666 -273.276314) (xy 92.975188 -273.276314) (xy 92.979148 -273.22726)
			(xy 92.990925 -273.179476) (xy 93.010216 -273.1342) (xy 93.036519 -273.092604) (xy 93.069154 -273.055767)
			(xy 93.107275 -273.024642) (xy 93.149896 -273.000035) (xy 93.195912 -272.982583) (xy 93.244131 -272.972739)
			(xy 93.293306 -272.970758) (xy 93.342161 -272.97669) (xy 93.389432 -272.990382) (xy 93.433894 -273.01148)
			(xy 93.474397 -273.039436) (xy 93.50989 -273.073528) (xy 93.539455 -273.112872) (xy 93.562326 -273.156449)
			(xy 93.57791 -273.20313) (xy 93.585805 -273.251707) (xy 93.5863 -273.276314) (xy 93.904811 -273.276314)
			(xy 93.908906 -273.225586) (xy 93.921085 -273.176172) (xy 93.941033 -273.129352) (xy 93.968234 -273.086338)
			(xy 94.001982 -273.048244) (xy 94.041404 -273.016057) (xy 94.085478 -272.990611) (xy 94.133064 -272.972564)
			(xy 94.182928 -272.962384) (xy 94.23378 -272.960335) (xy 94.284301 -272.966469) (xy 94.333185 -272.980629)
			(xy 94.379164 -273.002446) (xy 94.421048 -273.031356) (xy 94.457752 -273.066611) (xy 94.488325 -273.107297)
			(xy 94.511976 -273.15236) (xy 94.528092 -273.200634) (xy 94.536256 -273.250868) (xy 94.536768 -273.276314)
			(xy 94.855296 -273.276314) (xy 94.859256 -273.22726) (xy 94.871033 -273.179476) (xy 94.890324 -273.1342)
			(xy 94.916627 -273.092604) (xy 94.949262 -273.055767) (xy 94.987383 -273.024642) (xy 95.030004 -273.000035)
			(xy 95.07602 -272.982583) (xy 95.124239 -272.972739) (xy 95.173414 -272.970758) (xy 95.222269 -272.97669)
			(xy 95.26954 -272.990382) (xy 95.314002 -273.01148) (xy 95.354505 -273.039436) (xy 95.389998 -273.073528)
			(xy 95.419563 -273.112872) (xy 95.442434 -273.156449) (xy 95.458018 -273.20313) (xy 95.465913 -273.251707)
			(xy 95.466408 -273.276314) (xy 95.784919 -273.276314) (xy 95.789014 -273.225586) (xy 95.801193 -273.176172)
			(xy 95.821141 -273.129352) (xy 95.848342 -273.086338) (xy 95.88209 -273.048244) (xy 95.921512 -273.016057)
			(xy 95.965586 -272.990611) (xy 96.013172 -272.972564) (xy 96.063036 -272.962384) (xy 96.113888 -272.960335)
			(xy 96.164409 -272.966469) (xy 96.213293 -272.980629) (xy 96.259272 -273.002446) (xy 96.301156 -273.031356)
			(xy 96.33786 -273.066611) (xy 96.368433 -273.107297) (xy 96.392084 -273.15236) (xy 96.4082 -273.200634)
			(xy 96.416364 -273.250868) (xy 96.416876 -273.276314) (xy 96.73515 -273.276314) (xy 96.73911 -273.22726)
			(xy 96.750887 -273.179476) (xy 96.770178 -273.1342) (xy 96.796481 -273.092604) (xy 96.829116 -273.055767)
			(xy 96.867237 -273.024642) (xy 96.909858 -273.000035) (xy 96.955874 -272.982583) (xy 97.004093 -272.972739)
			(xy 97.053268 -272.970758) (xy 97.102123 -272.97669) (xy 97.149394 -272.990382) (xy 97.193856 -273.01148)
			(xy 97.234359 -273.039436) (xy 97.269852 -273.073528) (xy 97.299417 -273.112872) (xy 97.322288 -273.156449)
			(xy 97.337872 -273.20313) (xy 97.345767 -273.251707) (xy 97.346262 -273.276314) (xy 97.664773 -273.276314)
			(xy 97.668868 -273.225586) (xy 97.681047 -273.176172) (xy 97.700995 -273.129352) (xy 97.728196 -273.086338)
			(xy 97.761944 -273.048244) (xy 97.801366 -273.016057) (xy 97.84544 -272.990611) (xy 97.893026 -272.972564)
			(xy 97.94289 -272.962384) (xy 97.993742 -272.960335) (xy 98.044263 -272.966469) (xy 98.093147 -272.980629)
			(xy 98.139126 -273.002446) (xy 98.18101 -273.031356) (xy 98.217714 -273.066611) (xy 98.248287 -273.107297)
			(xy 98.271938 -273.15236) (xy 98.288054 -273.200634) (xy 98.296218 -273.250868) (xy 98.29673 -273.276314)
			(xy 98.604827 -273.276314) (xy 98.608922 -273.225586) (xy 98.621101 -273.176172) (xy 98.641049 -273.129352)
			(xy 98.66825 -273.086338) (xy 98.701998 -273.048244) (xy 98.74142 -273.016057) (xy 98.785494 -272.990611)
			(xy 98.83308 -272.972564) (xy 98.882944 -272.962384) (xy 98.933796 -272.960335) (xy 98.984317 -272.966469)
			(xy 99.033201 -272.980629) (xy 99.07918 -273.002446) (xy 99.121064 -273.031356) (xy 99.157768 -273.066611)
			(xy 99.188341 -273.107297) (xy 99.211992 -273.15236) (xy 99.228108 -273.200634) (xy 99.236272 -273.250868)
			(xy 99.236784 -273.276314) (xy 99.555312 -273.276314) (xy 99.559272 -273.22726) (xy 99.571049 -273.179476)
			(xy 99.59034 -273.1342) (xy 99.616643 -273.092604) (xy 99.649278 -273.055767) (xy 99.687399 -273.024642)
			(xy 99.73002 -273.000035) (xy 99.776036 -272.982583) (xy 99.824255 -272.972739) (xy 99.87343 -272.970758)
			(xy 99.922285 -272.97669) (xy 99.969556 -272.990382) (xy 100.014018 -273.01148) (xy 100.054521 -273.039436)
			(xy 100.090014 -273.073528) (xy 100.119579 -273.112872) (xy 100.14245 -273.156449) (xy 100.158034 -273.20313)
			(xy 100.165929 -273.251707) (xy 100.166424 -273.276314) (xy 100.484935 -273.276314) (xy 100.48903 -273.225586)
			(xy 100.501209 -273.176172) (xy 100.521157 -273.129352) (xy 100.548358 -273.086338) (xy 100.582106 -273.048244)
			(xy 100.621528 -273.016057) (xy 100.665602 -272.990611) (xy 100.713188 -272.972564) (xy 100.763052 -272.962384)
			(xy 100.813904 -272.960335) (xy 100.864425 -272.966469) (xy 100.913309 -272.980629) (xy 100.959288 -273.002446)
			(xy 101.001172 -273.031356) (xy 101.037876 -273.066611) (xy 101.068449 -273.107297) (xy 101.0921 -273.15236)
			(xy 101.108216 -273.200634) (xy 101.11638 -273.250868) (xy 101.116892 -273.276314) (xy 101.424735 -273.276314)
			(xy 101.42883 -273.225586) (xy 101.441009 -273.176172) (xy 101.460957 -273.129352) (xy 101.488158 -273.086338)
			(xy 101.521906 -273.048244) (xy 101.561328 -273.016057) (xy 101.605402 -272.990611) (xy 101.652988 -272.972564)
			(xy 101.702852 -272.962384) (xy 101.753704 -272.960335) (xy 101.804225 -272.966469) (xy 101.853109 -272.980629)
			(xy 101.899088 -273.002446) (xy 101.940972 -273.031356) (xy 101.977676 -273.066611) (xy 102.008249 -273.107297)
			(xy 102.0319 -273.15236) (xy 102.048016 -273.200634) (xy 102.05618 -273.250868) (xy 102.056692 -273.276314)
			(xy 102.05618 -273.30176) (xy 102.048016 -273.351994) (xy 102.0319 -273.400268) (xy 102.008249 -273.445331)
			(xy 101.977676 -273.486017) (xy 101.940972 -273.521272) (xy 101.899088 -273.550182) (xy 101.853109 -273.571999)
			(xy 101.804225 -273.586159) (xy 101.753704 -273.592293) (xy 101.702852 -273.590244) (xy 101.652988 -273.580064)
			(xy 101.605402 -273.562017) (xy 101.561328 -273.536571) (xy 101.521906 -273.504384) (xy 101.488158 -273.46629)
			(xy 101.460957 -273.423276) (xy 101.441009 -273.376456) (xy 101.42883 -273.327042) (xy 101.424735 -273.276314)
			(xy 101.116892 -273.276314) (xy 101.11638 -273.30176) (xy 101.108216 -273.351994) (xy 101.0921 -273.400268)
			(xy 101.068449 -273.445331) (xy 101.037876 -273.486017) (xy 101.001172 -273.521272) (xy 100.959288 -273.550182)
			(xy 100.913309 -273.571999) (xy 100.864425 -273.586159) (xy 100.813904 -273.592293) (xy 100.763052 -273.590244)
			(xy 100.713188 -273.580064) (xy 100.665602 -273.562017) (xy 100.621528 -273.536571) (xy 100.582106 -273.504384)
			(xy 100.548358 -273.46629) (xy 100.521157 -273.423276) (xy 100.501209 -273.376456) (xy 100.48903 -273.327042)
			(xy 100.484935 -273.276314) (xy 100.166424 -273.276314) (xy 100.165929 -273.300921) (xy 100.158034 -273.349498)
			(xy 100.14245 -273.396179) (xy 100.119579 -273.439756) (xy 100.090014 -273.4791) (xy 100.054521 -273.513192)
			(xy 100.014018 -273.541148) (xy 99.969556 -273.562246) (xy 99.922285 -273.575938) (xy 99.87343 -273.58187)
			(xy 99.824255 -273.579889) (xy 99.776036 -273.570045) (xy 99.73002 -273.552593) (xy 99.687399 -273.527986)
			(xy 99.649278 -273.496861) (xy 99.616643 -273.460024) (xy 99.59034 -273.418428) (xy 99.571049 -273.373152)
			(xy 99.559272 -273.325368) (xy 99.555312 -273.276314) (xy 99.236784 -273.276314) (xy 99.236272 -273.30176)
			(xy 99.228108 -273.351994) (xy 99.211992 -273.400268) (xy 99.188341 -273.445331) (xy 99.157768 -273.486017)
			(xy 99.121064 -273.521272) (xy 99.07918 -273.550182) (xy 99.033201 -273.571999) (xy 98.984317 -273.586159)
			(xy 98.933796 -273.592293) (xy 98.882944 -273.590244) (xy 98.83308 -273.580064) (xy 98.785494 -273.562017)
			(xy 98.74142 -273.536571) (xy 98.701998 -273.504384) (xy 98.66825 -273.46629) (xy 98.641049 -273.423276)
			(xy 98.621101 -273.376456) (xy 98.608922 -273.327042) (xy 98.604827 -273.276314) (xy 98.29673 -273.276314)
			(xy 98.296218 -273.30176) (xy 98.288054 -273.351994) (xy 98.271938 -273.400268) (xy 98.248287 -273.445331)
			(xy 98.217714 -273.486017) (xy 98.18101 -273.521272) (xy 98.139126 -273.550182) (xy 98.093147 -273.571999)
			(xy 98.044263 -273.586159) (xy 97.993742 -273.592293) (xy 97.94289 -273.590244) (xy 97.893026 -273.580064)
			(xy 97.84544 -273.562017) (xy 97.801366 -273.536571) (xy 97.761944 -273.504384) (xy 97.728196 -273.46629)
			(xy 97.700995 -273.423276) (xy 97.681047 -273.376456) (xy 97.668868 -273.327042) (xy 97.664773 -273.276314)
			(xy 97.346262 -273.276314) (xy 97.345767 -273.300921) (xy 97.337872 -273.349498) (xy 97.322288 -273.396179)
			(xy 97.299417 -273.439756) (xy 97.269852 -273.4791) (xy 97.234359 -273.513192) (xy 97.193856 -273.541148)
			(xy 97.149394 -273.562246) (xy 97.102123 -273.575938) (xy 97.053268 -273.58187) (xy 97.004093 -273.579889)
			(xy 96.955874 -273.570045) (xy 96.909858 -273.552593) (xy 96.867237 -273.527986) (xy 96.829116 -273.496861)
			(xy 96.796481 -273.460024) (xy 96.770178 -273.418428) (xy 96.750887 -273.373152) (xy 96.73911 -273.325368)
			(xy 96.73515 -273.276314) (xy 96.416876 -273.276314) (xy 96.416364 -273.30176) (xy 96.4082 -273.351994)
			(xy 96.392084 -273.400268) (xy 96.368433 -273.445331) (xy 96.33786 -273.486017) (xy 96.301156 -273.521272)
			(xy 96.259272 -273.550182) (xy 96.213293 -273.571999) (xy 96.164409 -273.586159) (xy 96.113888 -273.592293)
			(xy 96.063036 -273.590244) (xy 96.013172 -273.580064) (xy 95.965586 -273.562017) (xy 95.921512 -273.536571)
			(xy 95.88209 -273.504384) (xy 95.848342 -273.46629) (xy 95.821141 -273.423276) (xy 95.801193 -273.376456)
			(xy 95.789014 -273.327042) (xy 95.784919 -273.276314) (xy 95.466408 -273.276314) (xy 95.465913 -273.300921)
			(xy 95.458018 -273.349498) (xy 95.442434 -273.396179) (xy 95.419563 -273.439756) (xy 95.389998 -273.4791)
			(xy 95.354505 -273.513192) (xy 95.314002 -273.541148) (xy 95.26954 -273.562246) (xy 95.222269 -273.575938)
			(xy 95.173414 -273.58187) (xy 95.124239 -273.579889) (xy 95.07602 -273.570045) (xy 95.030004 -273.552593)
			(xy 94.987383 -273.527986) (xy 94.949262 -273.496861) (xy 94.916627 -273.460024) (xy 94.890324 -273.418428)
			(xy 94.871033 -273.373152) (xy 94.859256 -273.325368) (xy 94.855296 -273.276314) (xy 94.536768 -273.276314)
			(xy 94.536256 -273.30176) (xy 94.528092 -273.351994) (xy 94.511976 -273.400268) (xy 94.488325 -273.445331)
			(xy 94.457752 -273.486017) (xy 94.421048 -273.521272) (xy 94.379164 -273.550182) (xy 94.333185 -273.571999)
			(xy 94.284301 -273.586159) (xy 94.23378 -273.592293) (xy 94.182928 -273.590244) (xy 94.133064 -273.580064)
			(xy 94.085478 -273.562017) (xy 94.041404 -273.536571) (xy 94.001982 -273.504384) (xy 93.968234 -273.46629)
			(xy 93.941033 -273.423276) (xy 93.921085 -273.376456) (xy 93.908906 -273.327042) (xy 93.904811 -273.276314)
			(xy 93.5863 -273.276314) (xy 93.585805 -273.300921) (xy 93.57791 -273.349498) (xy 93.562326 -273.396179)
			(xy 93.539455 -273.439756) (xy 93.50989 -273.4791) (xy 93.474397 -273.513192) (xy 93.433894 -273.541148)
			(xy 93.389432 -273.562246) (xy 93.342161 -273.575938) (xy 93.293306 -273.58187) (xy 93.244131 -273.579889)
			(xy 93.195912 -273.570045) (xy 93.149896 -273.552593) (xy 93.107275 -273.527986) (xy 93.069154 -273.496861)
			(xy 93.036519 -273.460024) (xy 93.010216 -273.418428) (xy 92.990925 -273.373152) (xy 92.979148 -273.325368)
			(xy 92.975188 -273.276314) (xy 92.65666 -273.276314) (xy 92.656148 -273.30176) (xy 92.647984 -273.351994)
			(xy 92.631868 -273.400268) (xy 92.608217 -273.445331) (xy 92.577644 -273.486017) (xy 92.54094 -273.521272)
			(xy 92.499056 -273.550182) (xy 92.453077 -273.571999) (xy 92.404193 -273.586159) (xy 92.353672 -273.592293)
			(xy 92.30282 -273.590244) (xy 92.252956 -273.580064) (xy 92.20537 -273.562017) (xy 92.161296 -273.536571)
			(xy 92.121874 -273.504384) (xy 92.088126 -273.46629) (xy 92.060925 -273.423276) (xy 92.040977 -273.376456)
			(xy 92.028798 -273.327042) (xy 92.024703 -273.276314) (xy 91.71686 -273.276314) (xy 91.716348 -273.30176)
			(xy 91.708184 -273.351994) (xy 91.692068 -273.400268) (xy 91.668417 -273.445331) (xy 91.637844 -273.486017)
			(xy 91.60114 -273.521272) (xy 91.559256 -273.550182) (xy 91.513277 -273.571999) (xy 91.464393 -273.586159)
			(xy 91.413872 -273.592293) (xy 91.36302 -273.590244) (xy 91.313156 -273.580064) (xy 91.26557 -273.562017)
			(xy 91.221496 -273.536571) (xy 91.182074 -273.504384) (xy 91.148326 -273.46629) (xy 91.121125 -273.423276)
			(xy 91.101177 -273.376456) (xy 91.088998 -273.327042) (xy 91.084903 -273.276314) (xy 90.766392 -273.276314)
			(xy 90.765897 -273.300921) (xy 90.758002 -273.349498) (xy 90.742418 -273.396179) (xy 90.719547 -273.439756)
			(xy 90.689982 -273.4791) (xy 90.654489 -273.513192) (xy 90.613986 -273.541148) (xy 90.569524 -273.562246)
			(xy 90.522253 -273.575938) (xy 90.473398 -273.58187) (xy 90.424223 -273.579889) (xy 90.376004 -273.570045)
			(xy 90.329988 -273.552593) (xy 90.287367 -273.527986) (xy 90.249246 -273.496861) (xy 90.216611 -273.460024)
			(xy 90.190308 -273.418428) (xy 90.171017 -273.373152) (xy 90.15924 -273.325368) (xy 90.15528 -273.276314)
			(xy 89.836752 -273.276314) (xy 89.83624 -273.30176) (xy 89.828076 -273.351994) (xy 89.81196 -273.400268)
			(xy 89.788309 -273.445331) (xy 89.757736 -273.486017) (xy 89.721032 -273.521272) (xy 89.679148 -273.550182)
			(xy 89.633169 -273.571999) (xy 89.584285 -273.586159) (xy 89.533764 -273.592293) (xy 89.482912 -273.590244)
			(xy 89.433048 -273.580064) (xy 89.385462 -273.562017) (xy 89.341388 -273.536571) (xy 89.301966 -273.504384)
			(xy 89.268218 -273.46629) (xy 89.241017 -273.423276) (xy 89.221069 -273.376456) (xy 89.20889 -273.327042)
			(xy 89.204795 -273.276314) (xy 88.886284 -273.276314) (xy 88.885789 -273.300921) (xy 88.877894 -273.349498)
			(xy 88.86231 -273.396179) (xy 88.839439 -273.439756) (xy 88.809874 -273.4791) (xy 88.774381 -273.513192)
			(xy 88.733878 -273.541148) (xy 88.689416 -273.562246) (xy 88.642145 -273.575938) (xy 88.59329 -273.58187)
			(xy 88.544115 -273.579889) (xy 88.495896 -273.570045) (xy 88.44988 -273.552593) (xy 88.407259 -273.527986)
			(xy 88.369138 -273.496861) (xy 88.336503 -273.460024) (xy 88.3102 -273.418428) (xy 88.290909 -273.373152)
			(xy 88.279132 -273.325368) (xy 88.275172 -273.276314) (xy 87.956644 -273.276314) (xy 87.956132 -273.30176)
			(xy 87.947968 -273.351994) (xy 87.931852 -273.400268) (xy 87.908201 -273.445331) (xy 87.877628 -273.486017)
			(xy 87.840924 -273.521272) (xy 87.79904 -273.550182) (xy 87.753061 -273.571999) (xy 87.704177 -273.586159)
			(xy 87.653656 -273.592293) (xy 87.602804 -273.590244) (xy 87.55294 -273.580064) (xy 87.505354 -273.562017)
			(xy 87.46128 -273.536571) (xy 87.421858 -273.504384) (xy 87.38811 -273.46629) (xy 87.360909 -273.423276)
			(xy 87.340961 -273.376456) (xy 87.328782 -273.327042) (xy 87.324687 -273.276314) (xy 87.00643 -273.276314)
			(xy 87.005935 -273.300921) (xy 86.99804 -273.349498) (xy 86.982456 -273.396179) (xy 86.959585 -273.439756)
			(xy 86.93002 -273.4791) (xy 86.894527 -273.513192) (xy 86.854024 -273.541148) (xy 86.809562 -273.562246)
			(xy 86.762291 -273.575938) (xy 86.713436 -273.58187) (xy 86.664261 -273.579889) (xy 86.616042 -273.570045)
			(xy 86.570026 -273.552593) (xy 86.527405 -273.527986) (xy 86.489284 -273.496861) (xy 86.456649 -273.460024)
			(xy 86.430346 -273.418428) (xy 86.411055 -273.373152) (xy 86.399278 -273.325368) (xy 86.395318 -273.276314)
			(xy 86.07679 -273.276314) (xy 86.076278 -273.30176) (xy 86.068114 -273.351994) (xy 86.051998 -273.400268)
			(xy 86.028347 -273.445331) (xy 85.997774 -273.486017) (xy 85.96107 -273.521272) (xy 85.919186 -273.550182)
			(xy 85.873207 -273.571999) (xy 85.824323 -273.586159) (xy 85.773802 -273.592293) (xy 85.72295 -273.590244)
			(xy 85.673086 -273.580064) (xy 85.6255 -273.562017) (xy 85.581426 -273.536571) (xy 85.542004 -273.504384)
			(xy 85.508256 -273.46629) (xy 85.481055 -273.423276) (xy 85.461107 -273.376456) (xy 85.448928 -273.327042)
			(xy 85.444833 -273.276314) (xy 85.136736 -273.276314) (xy 85.136224 -273.30176) (xy 85.12806 -273.351994)
			(xy 85.111944 -273.400268) (xy 85.088293 -273.445331) (xy 85.05772 -273.486017) (xy 85.021016 -273.521272)
			(xy 84.979132 -273.550182) (xy 84.933153 -273.571999) (xy 84.884269 -273.586159) (xy 84.833748 -273.592293)
			(xy 84.782896 -273.590244) (xy 84.733032 -273.580064) (xy 84.685446 -273.562017) (xy 84.641372 -273.536571)
			(xy 84.60195 -273.504384) (xy 84.568202 -273.46629) (xy 84.541001 -273.423276) (xy 84.521053 -273.376456)
			(xy 84.508874 -273.327042) (xy 84.504779 -273.276314) (xy 84.186268 -273.276314) (xy 84.185773 -273.300921)
			(xy 84.177878 -273.349498) (xy 84.162294 -273.396179) (xy 84.139423 -273.439756) (xy 84.109858 -273.4791)
			(xy 84.074365 -273.513192) (xy 84.033862 -273.541148) (xy 83.9894 -273.562246) (xy 83.942129 -273.575938)
			(xy 83.893274 -273.58187) (xy 83.844099 -273.579889) (xy 83.79588 -273.570045) (xy 83.749864 -273.552593)
			(xy 83.707243 -273.527986) (xy 83.669122 -273.496861) (xy 83.636487 -273.460024) (xy 83.610184 -273.418428)
			(xy 83.590893 -273.373152) (xy 83.579116 -273.325368) (xy 83.575156 -273.276314) (xy 83.256628 -273.276314)
			(xy 83.256116 -273.30176) (xy 83.247952 -273.351994) (xy 83.231836 -273.400268) (xy 83.208185 -273.445331)
			(xy 83.177612 -273.486017) (xy 83.140908 -273.521272) (xy 83.099024 -273.550182) (xy 83.053045 -273.571999)
			(xy 83.004161 -273.586159) (xy 82.95364 -273.592293) (xy 82.902788 -273.590244) (xy 82.852924 -273.580064)
			(xy 82.805338 -273.562017) (xy 82.761264 -273.536571) (xy 82.721842 -273.504384) (xy 82.688094 -273.46629)
			(xy 82.660893 -273.423276) (xy 82.640945 -273.376456) (xy 82.628766 -273.327042) (xy 82.624671 -273.276314)
			(xy 82.306414 -273.276314) (xy 82.305919 -273.300921) (xy 82.298024 -273.349498) (xy 82.28244 -273.396179)
			(xy 82.259569 -273.439756) (xy 82.230004 -273.4791) (xy 82.194511 -273.513192) (xy 82.154008 -273.541148)
			(xy 82.109546 -273.562246) (xy 82.062275 -273.575938) (xy 82.01342 -273.58187) (xy 81.964245 -273.579889)
			(xy 81.916026 -273.570045) (xy 81.87001 -273.552593) (xy 81.827389 -273.527986) (xy 81.789268 -273.496861)
			(xy 81.756633 -273.460024) (xy 81.73033 -273.418428) (xy 81.711039 -273.373152) (xy 81.699262 -273.325368)
			(xy 81.695302 -273.276314) (xy 81.376774 -273.276314) (xy 81.376262 -273.30176) (xy 81.368098 -273.351994)
			(xy 81.351982 -273.400268) (xy 81.328331 -273.445331) (xy 81.297758 -273.486017) (xy 81.261054 -273.521272)
			(xy 81.21917 -273.550182) (xy 81.173191 -273.571999) (xy 81.124307 -273.586159) (xy 81.073786 -273.592293)
			(xy 81.022934 -273.590244) (xy 80.97307 -273.580064) (xy 80.925484 -273.562017) (xy 80.88141 -273.536571)
			(xy 80.841988 -273.504384) (xy 80.80824 -273.46629) (xy 80.781039 -273.423276) (xy 80.761091 -273.376456)
			(xy 80.748912 -273.327042) (xy 80.744817 -273.276314) (xy 80.426306 -273.276314) (xy 80.425811 -273.300921)
			(xy 80.417916 -273.349498) (xy 80.402332 -273.396179) (xy 80.379461 -273.439756) (xy 80.349896 -273.4791)
			(xy 80.314403 -273.513192) (xy 80.2739 -273.541148) (xy 80.229438 -273.562246) (xy 80.182167 -273.575938)
			(xy 80.133312 -273.58187) (xy 80.084137 -273.579889) (xy 80.035918 -273.570045) (xy 79.989902 -273.552593)
			(xy 79.947281 -273.527986) (xy 79.90916 -273.496861) (xy 79.876525 -273.460024) (xy 79.850222 -273.418428)
			(xy 79.830931 -273.373152) (xy 79.819154 -273.325368) (xy 79.815194 -273.276314) (xy 77.263451 -273.276314)
			(xy 77.221316 -273.296308) (xy 77.174045 -273.31) (xy 77.12519 -273.315932) (xy 77.076015 -273.313951)
			(xy 77.027796 -273.304107) (xy 76.98178 -273.286655) (xy 76.939159 -273.262048) (xy 76.901038 -273.230923)
			(xy 76.868403 -273.194086) (xy 76.8421 -273.15249) (xy 76.822809 -273.107214) (xy 76.811032 -273.05943)
			(xy 76.807072 -273.010376) (xy 73.228962 -273.010376) (xy 73.228962 -274.08632) (xy 78.40524 -274.08632)
			(xy 78.4092 -274.037266) (xy 78.420977 -273.989482) (xy 78.440268 -273.944206) (xy 78.466571 -273.90261)
			(xy 78.499206 -273.865773) (xy 78.537327 -273.834648) (xy 78.579948 -273.810041) (xy 78.625964 -273.792589)
			(xy 78.674183 -273.782745) (xy 78.723358 -273.780764) (xy 78.772213 -273.786696) (xy 78.819484 -273.800388)
			(xy 78.863946 -273.821486) (xy 78.904449 -273.849442) (xy 78.939942 -273.883534) (xy 78.969507 -273.922878)
			(xy 78.992378 -273.966455) (xy 79.007962 -274.013136) (xy 79.015857 -274.061713) (xy 79.016352 -274.08632)
			(xy 80.285348 -274.08632) (xy 80.289308 -274.037266) (xy 80.301085 -273.989482) (xy 80.320376 -273.944206)
			(xy 80.346679 -273.90261) (xy 80.379314 -273.865773) (xy 80.417435 -273.834648) (xy 80.460056 -273.810041)
			(xy 80.506072 -273.792589) (xy 80.554291 -273.782745) (xy 80.603466 -273.780764) (xy 80.652321 -273.786696)
			(xy 80.699592 -273.800388) (xy 80.744054 -273.821486) (xy 80.784557 -273.849442) (xy 80.82005 -273.883534)
			(xy 80.849615 -273.922878) (xy 80.872486 -273.966455) (xy 80.88807 -274.013136) (xy 80.895965 -274.061713)
			(xy 80.89646 -274.08632) (xy 81.214717 -274.08632) (xy 81.218812 -274.035592) (xy 81.230991 -273.986178)
			(xy 81.250939 -273.939358) (xy 81.27814 -273.896344) (xy 81.311888 -273.85825) (xy 81.35131 -273.826063)
			(xy 81.395384 -273.800617) (xy 81.44297 -273.78257) (xy 81.492834 -273.77239) (xy 81.543686 -273.770341)
			(xy 81.594207 -273.776475) (xy 81.643091 -273.790635) (xy 81.68907 -273.812452) (xy 81.730954 -273.841362)
			(xy 81.767658 -273.876617) (xy 81.798231 -273.917303) (xy 81.821882 -273.962366) (xy 81.837998 -274.01064)
			(xy 81.846162 -274.060874) (xy 81.846674 -274.08632) (xy 82.154771 -274.08632) (xy 82.158866 -274.035592)
			(xy 82.171045 -273.986178) (xy 82.190993 -273.939358) (xy 82.218194 -273.896344) (xy 82.251942 -273.85825)
			(xy 82.291364 -273.826063) (xy 82.335438 -273.800617) (xy 82.383024 -273.78257) (xy 82.432888 -273.77239)
			(xy 82.48374 -273.770341) (xy 82.534261 -273.776475) (xy 82.583145 -273.790635) (xy 82.629124 -273.812452)
			(xy 82.671008 -273.841362) (xy 82.707712 -273.876617) (xy 82.738285 -273.917303) (xy 82.761936 -273.962366)
			(xy 82.778052 -274.01064) (xy 82.786216 -274.060874) (xy 82.786728 -274.08632) (xy 83.105256 -274.08632)
			(xy 83.109216 -274.037266) (xy 83.120993 -273.989482) (xy 83.140284 -273.944206) (xy 83.166587 -273.90261)
			(xy 83.199222 -273.865773) (xy 83.237343 -273.834648) (xy 83.279964 -273.810041) (xy 83.32598 -273.792589)
			(xy 83.374199 -273.782745) (xy 83.423374 -273.780764) (xy 83.472229 -273.786696) (xy 83.5195 -273.800388)
			(xy 83.563962 -273.821486) (xy 83.604465 -273.849442) (xy 83.639958 -273.883534) (xy 83.669523 -273.922878)
			(xy 83.692394 -273.966455) (xy 83.707978 -274.013136) (xy 83.715873 -274.061713) (xy 83.716368 -274.08632)
			(xy 84.034879 -274.08632) (xy 84.038974 -274.035592) (xy 84.051153 -273.986178) (xy 84.071101 -273.939358)
			(xy 84.098302 -273.896344) (xy 84.13205 -273.85825) (xy 84.171472 -273.826063) (xy 84.215546 -273.800617)
			(xy 84.263132 -273.78257) (xy 84.312996 -273.77239) (xy 84.363848 -273.770341) (xy 84.414369 -273.776475)
			(xy 84.463253 -273.790635) (xy 84.509232 -273.812452) (xy 84.551116 -273.841362) (xy 84.58782 -273.876617)
			(xy 84.618393 -273.917303) (xy 84.642044 -273.962366) (xy 84.65816 -274.01064) (xy 84.666324 -274.060874)
			(xy 84.666836 -274.08632) (xy 84.98511 -274.08632) (xy 84.98907 -274.037266) (xy 85.000847 -273.989482)
			(xy 85.020138 -273.944206) (xy 85.046441 -273.90261) (xy 85.079076 -273.865773) (xy 85.117197 -273.834648)
			(xy 85.159818 -273.810041) (xy 85.205834 -273.792589) (xy 85.254053 -273.782745) (xy 85.303228 -273.780764)
			(xy 85.352083 -273.786696) (xy 85.399354 -273.800388) (xy 85.443816 -273.821486) (xy 85.484319 -273.849442)
			(xy 85.519812 -273.883534) (xy 85.549377 -273.922878) (xy 85.572248 -273.966455) (xy 85.587832 -274.013136)
			(xy 85.595727 -274.061713) (xy 85.596222 -274.08632) (xy 85.914733 -274.08632) (xy 85.918828 -274.035592)
			(xy 85.931007 -273.986178) (xy 85.950955 -273.939358) (xy 85.978156 -273.896344) (xy 86.011904 -273.85825)
			(xy 86.051326 -273.826063) (xy 86.0954 -273.800617) (xy 86.142986 -273.78257) (xy 86.19285 -273.77239)
			(xy 86.243702 -273.770341) (xy 86.294223 -273.776475) (xy 86.343107 -273.790635) (xy 86.389086 -273.812452)
			(xy 86.43097 -273.841362) (xy 86.467674 -273.876617) (xy 86.498247 -273.917303) (xy 86.521898 -273.962366)
			(xy 86.538014 -274.01064) (xy 86.546178 -274.060874) (xy 86.54669 -274.08632) (xy 86.865218 -274.08632)
			(xy 86.869178 -274.037266) (xy 86.880955 -273.989482) (xy 86.900246 -273.944206) (xy 86.926549 -273.90261)
			(xy 86.959184 -273.865773) (xy 86.997305 -273.834648) (xy 87.039926 -273.810041) (xy 87.085942 -273.792589)
			(xy 87.134161 -273.782745) (xy 87.183336 -273.780764) (xy 87.232191 -273.786696) (xy 87.279462 -273.800388)
			(xy 87.323924 -273.821486) (xy 87.364427 -273.849442) (xy 87.39992 -273.883534) (xy 87.429485 -273.922878)
			(xy 87.452356 -273.966455) (xy 87.46794 -274.013136) (xy 87.475835 -274.061713) (xy 87.47633 -274.08632)
			(xy 87.794841 -274.08632) (xy 87.798936 -274.035592) (xy 87.811115 -273.986178) (xy 87.831063 -273.939358)
			(xy 87.858264 -273.896344) (xy 87.892012 -273.85825) (xy 87.931434 -273.826063) (xy 87.975508 -273.800617)
			(xy 88.023094 -273.78257) (xy 88.072958 -273.77239) (xy 88.12381 -273.770341) (xy 88.174331 -273.776475)
			(xy 88.223215 -273.790635) (xy 88.269194 -273.812452) (xy 88.311078 -273.841362) (xy 88.347782 -273.876617)
			(xy 88.378355 -273.917303) (xy 88.402006 -273.962366) (xy 88.418122 -274.01064) (xy 88.426286 -274.060874)
			(xy 88.426798 -274.08632) (xy 88.734895 -274.08632) (xy 88.73899 -274.035592) (xy 88.751169 -273.986178)
			(xy 88.771117 -273.939358) (xy 88.798318 -273.896344) (xy 88.832066 -273.85825) (xy 88.871488 -273.826063)
			(xy 88.915562 -273.800617) (xy 88.963148 -273.78257) (xy 89.013012 -273.77239) (xy 89.063864 -273.770341)
			(xy 89.114385 -273.776475) (xy 89.163269 -273.790635) (xy 89.209248 -273.812452) (xy 89.251132 -273.841362)
			(xy 89.287836 -273.876617) (xy 89.318409 -273.917303) (xy 89.34206 -273.962366) (xy 89.358176 -274.01064)
			(xy 89.36634 -274.060874) (xy 89.366852 -274.08632) (xy 89.685126 -274.08632) (xy 89.689086 -274.037266)
			(xy 89.700863 -273.989482) (xy 89.720154 -273.944206) (xy 89.746457 -273.90261) (xy 89.779092 -273.865773)
			(xy 89.817213 -273.834648) (xy 89.859834 -273.810041) (xy 89.90585 -273.792589) (xy 89.954069 -273.782745)
			(xy 90.003244 -273.780764) (xy 90.052099 -273.786696) (xy 90.09937 -273.800388) (xy 90.143832 -273.821486)
			(xy 90.184335 -273.849442) (xy 90.219828 -273.883534) (xy 90.249393 -273.922878) (xy 90.272264 -273.966455)
			(xy 90.287848 -274.013136) (xy 90.295743 -274.061713) (xy 90.296238 -274.08632) (xy 90.614749 -274.08632)
			(xy 90.618844 -274.035592) (xy 90.631023 -273.986178) (xy 90.650971 -273.939358) (xy 90.678172 -273.896344)
			(xy 90.71192 -273.85825) (xy 90.751342 -273.826063) (xy 90.795416 -273.800617) (xy 90.843002 -273.78257)
			(xy 90.892866 -273.77239) (xy 90.943718 -273.770341) (xy 90.994239 -273.776475) (xy 91.043123 -273.790635)
			(xy 91.089102 -273.812452) (xy 91.130986 -273.841362) (xy 91.16769 -273.876617) (xy 91.198263 -273.917303)
			(xy 91.221914 -273.962366) (xy 91.23803 -274.01064) (xy 91.246194 -274.060874) (xy 91.246706 -274.08632)
			(xy 91.565234 -274.08632) (xy 91.569194 -274.037266) (xy 91.580971 -273.989482) (xy 91.600262 -273.944206)
			(xy 91.626565 -273.90261) (xy 91.6592 -273.865773) (xy 91.697321 -273.834648) (xy 91.739942 -273.810041)
			(xy 91.785958 -273.792589) (xy 91.834177 -273.782745) (xy 91.883352 -273.780764) (xy 91.932207 -273.786696)
			(xy 91.979478 -273.800388) (xy 92.02394 -273.821486) (xy 92.064443 -273.849442) (xy 92.099936 -273.883534)
			(xy 92.129501 -273.922878) (xy 92.152372 -273.966455) (xy 92.167956 -274.013136) (xy 92.175851 -274.061713)
			(xy 92.176346 -274.08632) (xy 92.494857 -274.08632) (xy 92.498952 -274.035592) (xy 92.511131 -273.986178)
			(xy 92.531079 -273.939358) (xy 92.55828 -273.896344) (xy 92.592028 -273.85825) (xy 92.63145 -273.826063)
			(xy 92.675524 -273.800617) (xy 92.72311 -273.78257) (xy 92.772974 -273.77239) (xy 92.823826 -273.770341)
			(xy 92.874347 -273.776475) (xy 92.923231 -273.790635) (xy 92.96921 -273.812452) (xy 93.011094 -273.841362)
			(xy 93.047798 -273.876617) (xy 93.078371 -273.917303) (xy 93.102022 -273.962366) (xy 93.118138 -274.01064)
			(xy 93.126302 -274.060874) (xy 93.126814 -274.08632) (xy 93.445342 -274.08632) (xy 93.449302 -274.037266)
			(xy 93.461079 -273.989482) (xy 93.48037 -273.944206) (xy 93.506673 -273.90261) (xy 93.539308 -273.865773)
			(xy 93.577429 -273.834648) (xy 93.62005 -273.810041) (xy 93.666066 -273.792589) (xy 93.714285 -273.782745)
			(xy 93.76346 -273.780764) (xy 93.812315 -273.786696) (xy 93.859586 -273.800388) (xy 93.904048 -273.821486)
			(xy 93.944551 -273.849442) (xy 93.980044 -273.883534) (xy 94.009609 -273.922878) (xy 94.03248 -273.966455)
			(xy 94.048064 -274.013136) (xy 94.055959 -274.061713) (xy 94.056454 -274.08632) (xy 94.374711 -274.08632)
			(xy 94.378806 -274.035592) (xy 94.390985 -273.986178) (xy 94.410933 -273.939358) (xy 94.438134 -273.896344)
			(xy 94.471882 -273.85825) (xy 94.511304 -273.826063) (xy 94.555378 -273.800617) (xy 94.602964 -273.78257)
			(xy 94.652828 -273.77239) (xy 94.70368 -273.770341) (xy 94.754201 -273.776475) (xy 94.803085 -273.790635)
			(xy 94.849064 -273.812452) (xy 94.890948 -273.841362) (xy 94.927652 -273.876617) (xy 94.958225 -273.917303)
			(xy 94.981876 -273.962366) (xy 94.997992 -274.01064) (xy 95.006156 -274.060874) (xy 95.006668 -274.08632)
			(xy 95.314765 -274.08632) (xy 95.31886 -274.035592) (xy 95.331039 -273.986178) (xy 95.350987 -273.939358)
			(xy 95.378188 -273.896344) (xy 95.411936 -273.85825) (xy 95.451358 -273.826063) (xy 95.495432 -273.800617)
			(xy 95.543018 -273.78257) (xy 95.592882 -273.77239) (xy 95.643734 -273.770341) (xy 95.694255 -273.776475)
			(xy 95.743139 -273.790635) (xy 95.789118 -273.812452) (xy 95.831002 -273.841362) (xy 95.867706 -273.876617)
			(xy 95.898279 -273.917303) (xy 95.92193 -273.962366) (xy 95.938046 -274.01064) (xy 95.94621 -274.060874)
			(xy 95.946722 -274.08632) (xy 96.26525 -274.08632) (xy 96.26921 -274.037266) (xy 96.280987 -273.989482)
			(xy 96.300278 -273.944206) (xy 96.326581 -273.90261) (xy 96.359216 -273.865773) (xy 96.397337 -273.834648)
			(xy 96.439958 -273.810041) (xy 96.485974 -273.792589) (xy 96.534193 -273.782745) (xy 96.583368 -273.780764)
			(xy 96.632223 -273.786696) (xy 96.679494 -273.800388) (xy 96.723956 -273.821486) (xy 96.764459 -273.849442)
			(xy 96.799952 -273.883534) (xy 96.829517 -273.922878) (xy 96.852388 -273.966455) (xy 96.867972 -274.013136)
			(xy 96.875867 -274.061713) (xy 96.876362 -274.08632) (xy 97.205304 -274.08632) (xy 97.209264 -274.037266)
			(xy 97.221041 -273.989482) (xy 97.240332 -273.944206) (xy 97.266635 -273.90261) (xy 97.29927 -273.865773)
			(xy 97.337391 -273.834648) (xy 97.380012 -273.810041) (xy 97.426028 -273.792589) (xy 97.474247 -273.782745)
			(xy 97.523422 -273.780764) (xy 97.572277 -273.786696) (xy 97.619548 -273.800388) (xy 97.66401 -273.821486)
			(xy 97.704513 -273.849442) (xy 97.740006 -273.883534) (xy 97.769571 -273.922878) (xy 97.792442 -273.966455)
			(xy 97.808026 -274.013136) (xy 97.815921 -274.061713) (xy 97.816416 -274.08632) (xy 98.145358 -274.08632)
			(xy 98.149318 -274.037266) (xy 98.161095 -273.989482) (xy 98.180386 -273.944206) (xy 98.206689 -273.90261)
			(xy 98.239324 -273.865773) (xy 98.277445 -273.834648) (xy 98.320066 -273.810041) (xy 98.366082 -273.792589)
			(xy 98.414301 -273.782745) (xy 98.463476 -273.780764) (xy 98.512331 -273.786696) (xy 98.559602 -273.800388)
			(xy 98.604064 -273.821486) (xy 98.644567 -273.849442) (xy 98.68006 -273.883534) (xy 98.709625 -273.922878)
			(xy 98.732496 -273.966455) (xy 98.74808 -274.013136) (xy 98.755975 -274.061713) (xy 98.75647 -274.08632)
			(xy 99.085158 -274.08632) (xy 99.089118 -274.037266) (xy 99.100895 -273.989482) (xy 99.120186 -273.944206)
			(xy 99.146489 -273.90261) (xy 99.179124 -273.865773) (xy 99.217245 -273.834648) (xy 99.259866 -273.810041)
			(xy 99.305882 -273.792589) (xy 99.354101 -273.782745) (xy 99.403276 -273.780764) (xy 99.452131 -273.786696)
			(xy 99.499402 -273.800388) (xy 99.543864 -273.821486) (xy 99.584367 -273.849442) (xy 99.61986 -273.883534)
			(xy 99.649425 -273.922878) (xy 99.672296 -273.966455) (xy 99.68788 -274.013136) (xy 99.695775 -274.061713)
			(xy 99.69627 -274.08632) (xy 100.025212 -274.08632) (xy 100.029172 -274.037266) (xy 100.040949 -273.989482)
			(xy 100.06024 -273.944206) (xy 100.086543 -273.90261) (xy 100.119178 -273.865773) (xy 100.157299 -273.834648)
			(xy 100.19992 -273.810041) (xy 100.245936 -273.792589) (xy 100.294155 -273.782745) (xy 100.34333 -273.780764)
			(xy 100.392185 -273.786696) (xy 100.439456 -273.800388) (xy 100.483918 -273.821486) (xy 100.524421 -273.849442)
			(xy 100.559914 -273.883534) (xy 100.589479 -273.922878) (xy 100.61235 -273.966455) (xy 100.627934 -274.013136)
			(xy 100.635829 -274.061713) (xy 100.636324 -274.08632) (xy 100.965266 -274.08632) (xy 100.969226 -274.037266)
			(xy 100.981003 -273.989482) (xy 101.000294 -273.944206) (xy 101.026597 -273.90261) (xy 101.059232 -273.865773)
			(xy 101.097353 -273.834648) (xy 101.139974 -273.810041) (xy 101.18599 -273.792589) (xy 101.234209 -273.782745)
			(xy 101.283384 -273.780764) (xy 101.332239 -273.786696) (xy 101.37951 -273.800388) (xy 101.423972 -273.821486)
			(xy 101.464475 -273.849442) (xy 101.499968 -273.883534) (xy 101.529533 -273.922878) (xy 101.552404 -273.966455)
			(xy 101.567988 -274.013136) (xy 101.575883 -274.061713) (xy 101.576378 -274.08632) (xy 101.90532 -274.08632)
			(xy 101.90928 -274.037266) (xy 101.921057 -273.989482) (xy 101.940348 -273.944206) (xy 101.966651 -273.90261)
			(xy 101.999286 -273.865773) (xy 102.037407 -273.834648) (xy 102.080028 -273.810041) (xy 102.126044 -273.792589)
			(xy 102.174263 -273.782745) (xy 102.223438 -273.780764) (xy 102.272293 -273.786696) (xy 102.319564 -273.800388)
			(xy 102.364026 -273.821486) (xy 102.404529 -273.849442) (xy 102.440022 -273.883534) (xy 102.469587 -273.922878)
			(xy 102.492458 -273.966455) (xy 102.508042 -274.013136) (xy 102.515937 -274.061713) (xy 102.516432 -274.08632)
			(xy 102.515937 -274.110927) (xy 102.508042 -274.159504) (xy 102.492458 -274.206185) (xy 102.469587 -274.249762)
			(xy 102.440022 -274.289106) (xy 102.404529 -274.323198) (xy 102.364026 -274.351154) (xy 102.319564 -274.372252)
			(xy 102.272293 -274.385944) (xy 102.223438 -274.391876) (xy 102.174263 -274.389895) (xy 102.126044 -274.380051)
			(xy 102.080028 -274.362599) (xy 102.037407 -274.337992) (xy 101.999286 -274.306867) (xy 101.966651 -274.27003)
			(xy 101.940348 -274.228434) (xy 101.921057 -274.183158) (xy 101.90928 -274.135374) (xy 101.90532 -274.08632)
			(xy 101.576378 -274.08632) (xy 101.575883 -274.110927) (xy 101.567988 -274.159504) (xy 101.552404 -274.206185)
			(xy 101.529533 -274.249762) (xy 101.499968 -274.289106) (xy 101.464475 -274.323198) (xy 101.423972 -274.351154)
			(xy 101.37951 -274.372252) (xy 101.332239 -274.385944) (xy 101.283384 -274.391876) (xy 101.234209 -274.389895)
			(xy 101.18599 -274.380051) (xy 101.139974 -274.362599) (xy 101.097353 -274.337992) (xy 101.059232 -274.306867)
			(xy 101.026597 -274.27003) (xy 101.000294 -274.228434) (xy 100.981003 -274.183158) (xy 100.969226 -274.135374)
			(xy 100.965266 -274.08632) (xy 100.636324 -274.08632) (xy 100.635829 -274.110927) (xy 100.627934 -274.159504)
			(xy 100.61235 -274.206185) (xy 100.589479 -274.249762) (xy 100.559914 -274.289106) (xy 100.524421 -274.323198)
			(xy 100.483918 -274.351154) (xy 100.439456 -274.372252) (xy 100.392185 -274.385944) (xy 100.34333 -274.391876)
			(xy 100.294155 -274.389895) (xy 100.245936 -274.380051) (xy 100.19992 -274.362599) (xy 100.157299 -274.337992)
			(xy 100.119178 -274.306867) (xy 100.086543 -274.27003) (xy 100.06024 -274.228434) (xy 100.040949 -274.183158)
			(xy 100.029172 -274.135374) (xy 100.025212 -274.08632) (xy 99.69627 -274.08632) (xy 99.695775 -274.110927)
			(xy 99.68788 -274.159504) (xy 99.672296 -274.206185) (xy 99.649425 -274.249762) (xy 99.61986 -274.289106)
			(xy 99.584367 -274.323198) (xy 99.543864 -274.351154) (xy 99.499402 -274.372252) (xy 99.452131 -274.385944)
			(xy 99.403276 -274.391876) (xy 99.354101 -274.389895) (xy 99.305882 -274.380051) (xy 99.259866 -274.362599)
			(xy 99.217245 -274.337992) (xy 99.179124 -274.306867) (xy 99.146489 -274.27003) (xy 99.120186 -274.228434)
			(xy 99.100895 -274.183158) (xy 99.089118 -274.135374) (xy 99.085158 -274.08632) (xy 98.75647 -274.08632)
			(xy 98.755975 -274.110927) (xy 98.74808 -274.159504) (xy 98.732496 -274.206185) (xy 98.709625 -274.249762)
			(xy 98.68006 -274.289106) (xy 98.644567 -274.323198) (xy 98.604064 -274.351154) (xy 98.559602 -274.372252)
			(xy 98.512331 -274.385944) (xy 98.463476 -274.391876) (xy 98.414301 -274.389895) (xy 98.366082 -274.380051)
			(xy 98.320066 -274.362599) (xy 98.277445 -274.337992) (xy 98.239324 -274.306867) (xy 98.206689 -274.27003)
			(xy 98.180386 -274.228434) (xy 98.161095 -274.183158) (xy 98.149318 -274.135374) (xy 98.145358 -274.08632)
			(xy 97.816416 -274.08632) (xy 97.815921 -274.110927) (xy 97.808026 -274.159504) (xy 97.792442 -274.206185)
			(xy 97.769571 -274.249762) (xy 97.740006 -274.289106) (xy 97.704513 -274.323198) (xy 97.66401 -274.351154)
			(xy 97.619548 -274.372252) (xy 97.572277 -274.385944) (xy 97.523422 -274.391876) (xy 97.474247 -274.389895)
			(xy 97.426028 -274.380051) (xy 97.380012 -274.362599) (xy 97.337391 -274.337992) (xy 97.29927 -274.306867)
			(xy 97.266635 -274.27003) (xy 97.240332 -274.228434) (xy 97.221041 -274.183158) (xy 97.209264 -274.135374)
			(xy 97.205304 -274.08632) (xy 96.876362 -274.08632) (xy 96.875867 -274.110927) (xy 96.867972 -274.159504)
			(xy 96.852388 -274.206185) (xy 96.829517 -274.249762) (xy 96.799952 -274.289106) (xy 96.764459 -274.323198)
			(xy 96.723956 -274.351154) (xy 96.679494 -274.372252) (xy 96.632223 -274.385944) (xy 96.583368 -274.391876)
			(xy 96.534193 -274.389895) (xy 96.485974 -274.380051) (xy 96.439958 -274.362599) (xy 96.397337 -274.337992)
			(xy 96.359216 -274.306867) (xy 96.326581 -274.27003) (xy 96.300278 -274.228434) (xy 96.280987 -274.183158)
			(xy 96.26921 -274.135374) (xy 96.26525 -274.08632) (xy 95.946722 -274.08632) (xy 95.94621 -274.111766)
			(xy 95.938046 -274.162) (xy 95.92193 -274.210274) (xy 95.898279 -274.255337) (xy 95.867706 -274.296023)
			(xy 95.831002 -274.331278) (xy 95.789118 -274.360188) (xy 95.743139 -274.382005) (xy 95.694255 -274.396165)
			(xy 95.643734 -274.402299) (xy 95.592882 -274.40025) (xy 95.543018 -274.39007) (xy 95.495432 -274.372023)
			(xy 95.451358 -274.346577) (xy 95.411936 -274.31439) (xy 95.378188 -274.276296) (xy 95.350987 -274.233282)
			(xy 95.331039 -274.186462) (xy 95.31886 -274.137048) (xy 95.314765 -274.08632) (xy 95.006668 -274.08632)
			(xy 95.006156 -274.111766) (xy 94.997992 -274.162) (xy 94.981876 -274.210274) (xy 94.958225 -274.255337)
			(xy 94.927652 -274.296023) (xy 94.890948 -274.331278) (xy 94.849064 -274.360188) (xy 94.803085 -274.382005)
			(xy 94.754201 -274.396165) (xy 94.70368 -274.402299) (xy 94.652828 -274.40025) (xy 94.602964 -274.39007)
			(xy 94.555378 -274.372023) (xy 94.511304 -274.346577) (xy 94.471882 -274.31439) (xy 94.438134 -274.276296)
			(xy 94.410933 -274.233282) (xy 94.390985 -274.186462) (xy 94.378806 -274.137048) (xy 94.374711 -274.08632)
			(xy 94.056454 -274.08632) (xy 94.055959 -274.110927) (xy 94.048064 -274.159504) (xy 94.03248 -274.206185)
			(xy 94.009609 -274.249762) (xy 93.980044 -274.289106) (xy 93.944551 -274.323198) (xy 93.904048 -274.351154)
			(xy 93.859586 -274.372252) (xy 93.812315 -274.385944) (xy 93.76346 -274.391876) (xy 93.714285 -274.389895)
			(xy 93.666066 -274.380051) (xy 93.62005 -274.362599) (xy 93.577429 -274.337992) (xy 93.539308 -274.306867)
			(xy 93.506673 -274.27003) (xy 93.48037 -274.228434) (xy 93.461079 -274.183158) (xy 93.449302 -274.135374)
			(xy 93.445342 -274.08632) (xy 93.126814 -274.08632) (xy 93.126302 -274.111766) (xy 93.118138 -274.162)
			(xy 93.102022 -274.210274) (xy 93.078371 -274.255337) (xy 93.047798 -274.296023) (xy 93.011094 -274.331278)
			(xy 92.96921 -274.360188) (xy 92.923231 -274.382005) (xy 92.874347 -274.396165) (xy 92.823826 -274.402299)
			(xy 92.772974 -274.40025) (xy 92.72311 -274.39007) (xy 92.675524 -274.372023) (xy 92.63145 -274.346577)
			(xy 92.592028 -274.31439) (xy 92.55828 -274.276296) (xy 92.531079 -274.233282) (xy 92.511131 -274.186462)
			(xy 92.498952 -274.137048) (xy 92.494857 -274.08632) (xy 92.176346 -274.08632) (xy 92.175851 -274.110927)
			(xy 92.167956 -274.159504) (xy 92.152372 -274.206185) (xy 92.129501 -274.249762) (xy 92.099936 -274.289106)
			(xy 92.064443 -274.323198) (xy 92.02394 -274.351154) (xy 91.979478 -274.372252) (xy 91.932207 -274.385944)
			(xy 91.883352 -274.391876) (xy 91.834177 -274.389895) (xy 91.785958 -274.380051) (xy 91.739942 -274.362599)
			(xy 91.697321 -274.337992) (xy 91.6592 -274.306867) (xy 91.626565 -274.27003) (xy 91.600262 -274.228434)
			(xy 91.580971 -274.183158) (xy 91.569194 -274.135374) (xy 91.565234 -274.08632) (xy 91.246706 -274.08632)
			(xy 91.246194 -274.111766) (xy 91.23803 -274.162) (xy 91.221914 -274.210274) (xy 91.198263 -274.255337)
			(xy 91.16769 -274.296023) (xy 91.130986 -274.331278) (xy 91.089102 -274.360188) (xy 91.043123 -274.382005)
			(xy 90.994239 -274.396165) (xy 90.943718 -274.402299) (xy 90.892866 -274.40025) (xy 90.843002 -274.39007)
			(xy 90.795416 -274.372023) (xy 90.751342 -274.346577) (xy 90.71192 -274.31439) (xy 90.678172 -274.276296)
			(xy 90.650971 -274.233282) (xy 90.631023 -274.186462) (xy 90.618844 -274.137048) (xy 90.614749 -274.08632)
			(xy 90.296238 -274.08632) (xy 90.295743 -274.110927) (xy 90.287848 -274.159504) (xy 90.272264 -274.206185)
			(xy 90.249393 -274.249762) (xy 90.219828 -274.289106) (xy 90.184335 -274.323198) (xy 90.143832 -274.351154)
			(xy 90.09937 -274.372252) (xy 90.052099 -274.385944) (xy 90.003244 -274.391876) (xy 89.954069 -274.389895)
			(xy 89.90585 -274.380051) (xy 89.859834 -274.362599) (xy 89.817213 -274.337992) (xy 89.779092 -274.306867)
			(xy 89.746457 -274.27003) (xy 89.720154 -274.228434) (xy 89.700863 -274.183158) (xy 89.689086 -274.135374)
			(xy 89.685126 -274.08632) (xy 89.366852 -274.08632) (xy 89.36634 -274.111766) (xy 89.358176 -274.162)
			(xy 89.34206 -274.210274) (xy 89.318409 -274.255337) (xy 89.287836 -274.296023) (xy 89.251132 -274.331278)
			(xy 89.209248 -274.360188) (xy 89.163269 -274.382005) (xy 89.114385 -274.396165) (xy 89.063864 -274.402299)
			(xy 89.013012 -274.40025) (xy 88.963148 -274.39007) (xy 88.915562 -274.372023) (xy 88.871488 -274.346577)
			(xy 88.832066 -274.31439) (xy 88.798318 -274.276296) (xy 88.771117 -274.233282) (xy 88.751169 -274.186462)
			(xy 88.73899 -274.137048) (xy 88.734895 -274.08632) (xy 88.426798 -274.08632) (xy 88.426286 -274.111766)
			(xy 88.418122 -274.162) (xy 88.402006 -274.210274) (xy 88.378355 -274.255337) (xy 88.347782 -274.296023)
			(xy 88.311078 -274.331278) (xy 88.269194 -274.360188) (xy 88.223215 -274.382005) (xy 88.174331 -274.396165)
			(xy 88.12381 -274.402299) (xy 88.072958 -274.40025) (xy 88.023094 -274.39007) (xy 87.975508 -274.372023)
			(xy 87.931434 -274.346577) (xy 87.892012 -274.31439) (xy 87.858264 -274.276296) (xy 87.831063 -274.233282)
			(xy 87.811115 -274.186462) (xy 87.798936 -274.137048) (xy 87.794841 -274.08632) (xy 87.47633 -274.08632)
			(xy 87.475835 -274.110927) (xy 87.46794 -274.159504) (xy 87.452356 -274.206185) (xy 87.429485 -274.249762)
			(xy 87.39992 -274.289106) (xy 87.364427 -274.323198) (xy 87.323924 -274.351154) (xy 87.279462 -274.372252)
			(xy 87.232191 -274.385944) (xy 87.183336 -274.391876) (xy 87.134161 -274.389895) (xy 87.085942 -274.380051)
			(xy 87.039926 -274.362599) (xy 86.997305 -274.337992) (xy 86.959184 -274.306867) (xy 86.926549 -274.27003)
			(xy 86.900246 -274.228434) (xy 86.880955 -274.183158) (xy 86.869178 -274.135374) (xy 86.865218 -274.08632)
			(xy 86.54669 -274.08632) (xy 86.546178 -274.111766) (xy 86.538014 -274.162) (xy 86.521898 -274.210274)
			(xy 86.498247 -274.255337) (xy 86.467674 -274.296023) (xy 86.43097 -274.331278) (xy 86.389086 -274.360188)
			(xy 86.343107 -274.382005) (xy 86.294223 -274.396165) (xy 86.243702 -274.402299) (xy 86.19285 -274.40025)
			(xy 86.142986 -274.39007) (xy 86.0954 -274.372023) (xy 86.051326 -274.346577) (xy 86.011904 -274.31439)
			(xy 85.978156 -274.276296) (xy 85.950955 -274.233282) (xy 85.931007 -274.186462) (xy 85.918828 -274.137048)
			(xy 85.914733 -274.08632) (xy 85.596222 -274.08632) (xy 85.595727 -274.110927) (xy 85.587832 -274.159504)
			(xy 85.572248 -274.206185) (xy 85.549377 -274.249762) (xy 85.519812 -274.289106) (xy 85.484319 -274.323198)
			(xy 85.443816 -274.351154) (xy 85.399354 -274.372252) (xy 85.352083 -274.385944) (xy 85.303228 -274.391876)
			(xy 85.254053 -274.389895) (xy 85.205834 -274.380051) (xy 85.159818 -274.362599) (xy 85.117197 -274.337992)
			(xy 85.079076 -274.306867) (xy 85.046441 -274.27003) (xy 85.020138 -274.228434) (xy 85.000847 -274.183158)
			(xy 84.98907 -274.135374) (xy 84.98511 -274.08632) (xy 84.666836 -274.08632) (xy 84.666324 -274.111766)
			(xy 84.65816 -274.162) (xy 84.642044 -274.210274) (xy 84.618393 -274.255337) (xy 84.58782 -274.296023)
			(xy 84.551116 -274.331278) (xy 84.509232 -274.360188) (xy 84.463253 -274.382005) (xy 84.414369 -274.396165)
			(xy 84.363848 -274.402299) (xy 84.312996 -274.40025) (xy 84.263132 -274.39007) (xy 84.215546 -274.372023)
			(xy 84.171472 -274.346577) (xy 84.13205 -274.31439) (xy 84.098302 -274.276296) (xy 84.071101 -274.233282)
			(xy 84.051153 -274.186462) (xy 84.038974 -274.137048) (xy 84.034879 -274.08632) (xy 83.716368 -274.08632)
			(xy 83.715873 -274.110927) (xy 83.707978 -274.159504) (xy 83.692394 -274.206185) (xy 83.669523 -274.249762)
			(xy 83.639958 -274.289106) (xy 83.604465 -274.323198) (xy 83.563962 -274.351154) (xy 83.5195 -274.372252)
			(xy 83.472229 -274.385944) (xy 83.423374 -274.391876) (xy 83.374199 -274.389895) (xy 83.32598 -274.380051)
			(xy 83.279964 -274.362599) (xy 83.237343 -274.337992) (xy 83.199222 -274.306867) (xy 83.166587 -274.27003)
			(xy 83.140284 -274.228434) (xy 83.120993 -274.183158) (xy 83.109216 -274.135374) (xy 83.105256 -274.08632)
			(xy 82.786728 -274.08632) (xy 82.786216 -274.111766) (xy 82.778052 -274.162) (xy 82.761936 -274.210274)
			(xy 82.738285 -274.255337) (xy 82.707712 -274.296023) (xy 82.671008 -274.331278) (xy 82.629124 -274.360188)
			(xy 82.583145 -274.382005) (xy 82.534261 -274.396165) (xy 82.48374 -274.402299) (xy 82.432888 -274.40025)
			(xy 82.383024 -274.39007) (xy 82.335438 -274.372023) (xy 82.291364 -274.346577) (xy 82.251942 -274.31439)
			(xy 82.218194 -274.276296) (xy 82.190993 -274.233282) (xy 82.171045 -274.186462) (xy 82.158866 -274.137048)
			(xy 82.154771 -274.08632) (xy 81.846674 -274.08632) (xy 81.846162 -274.111766) (xy 81.837998 -274.162)
			(xy 81.821882 -274.210274) (xy 81.798231 -274.255337) (xy 81.767658 -274.296023) (xy 81.730954 -274.331278)
			(xy 81.68907 -274.360188) (xy 81.643091 -274.382005) (xy 81.594207 -274.396165) (xy 81.543686 -274.402299)
			(xy 81.492834 -274.40025) (xy 81.44297 -274.39007) (xy 81.395384 -274.372023) (xy 81.35131 -274.346577)
			(xy 81.311888 -274.31439) (xy 81.27814 -274.276296) (xy 81.250939 -274.233282) (xy 81.230991 -274.186462)
			(xy 81.218812 -274.137048) (xy 81.214717 -274.08632) (xy 80.89646 -274.08632) (xy 80.895965 -274.110927)
			(xy 80.88807 -274.159504) (xy 80.872486 -274.206185) (xy 80.849615 -274.249762) (xy 80.82005 -274.289106)
			(xy 80.784557 -274.323198) (xy 80.744054 -274.351154) (xy 80.699592 -274.372252) (xy 80.652321 -274.385944)
			(xy 80.603466 -274.391876) (xy 80.554291 -274.389895) (xy 80.506072 -274.380051) (xy 80.460056 -274.362599)
			(xy 80.417435 -274.337992) (xy 80.379314 -274.306867) (xy 80.346679 -274.27003) (xy 80.320376 -274.228434)
			(xy 80.301085 -274.183158) (xy 80.289308 -274.135374) (xy 80.285348 -274.08632) (xy 79.016352 -274.08632)
			(xy 79.015857 -274.110927) (xy 79.007962 -274.159504) (xy 78.992378 -274.206185) (xy 78.969507 -274.249762)
			(xy 78.939942 -274.289106) (xy 78.904449 -274.323198) (xy 78.863946 -274.351154) (xy 78.819484 -274.372252)
			(xy 78.772213 -274.385944) (xy 78.723358 -274.391876) (xy 78.674183 -274.389895) (xy 78.625964 -274.380051)
			(xy 78.579948 -274.362599) (xy 78.537327 -274.337992) (xy 78.499206 -274.306867) (xy 78.466571 -274.27003)
			(xy 78.440268 -274.228434) (xy 78.420977 -274.183158) (xy 78.4092 -274.135374) (xy 78.40524 -274.08632)
			(xy 73.228962 -274.08632) (xy 73.228962 -274.630388) (xy 76.807072 -274.630388) (xy 76.811032 -274.581334)
			(xy 76.822809 -274.53355) (xy 76.8421 -274.488274) (xy 76.868403 -274.446678) (xy 76.901038 -274.409841)
			(xy 76.939159 -274.378716) (xy 76.98178 -274.354109) (xy 77.027796 -274.336657) (xy 77.076015 -274.326813)
			(xy 77.12519 -274.324832) (xy 77.174045 -274.330764) (xy 77.221316 -274.344456) (xy 77.265778 -274.365554)
			(xy 77.306281 -274.39351) (xy 77.341774 -274.427602) (xy 77.371339 -274.466946) (xy 77.39421 -274.510523)
			(xy 77.409794 -274.557204) (xy 77.417689 -274.605781) (xy 77.418184 -274.630388) (xy 77.417689 -274.654995)
			(xy 77.409794 -274.703572) (xy 77.39421 -274.750253) (xy 77.371339 -274.79383) (xy 77.341774 -274.833174)
			(xy 77.306281 -274.867266) (xy 77.265778 -274.895222) (xy 77.263451 -274.896326) (xy 79.815194 -274.896326)
			(xy 79.819154 -274.847272) (xy 79.830931 -274.799488) (xy 79.850222 -274.754212) (xy 79.876525 -274.712616)
			(xy 79.90916 -274.675779) (xy 79.947281 -274.644654) (xy 79.989902 -274.620047) (xy 80.035918 -274.602595)
			(xy 80.084137 -274.592751) (xy 80.133312 -274.59077) (xy 80.182167 -274.596702) (xy 80.229438 -274.610394)
			(xy 80.2739 -274.631492) (xy 80.314403 -274.659448) (xy 80.349896 -274.69354) (xy 80.379461 -274.732884)
			(xy 80.402332 -274.776461) (xy 80.417916 -274.823142) (xy 80.425811 -274.871719) (xy 80.426306 -274.896326)
			(xy 80.744817 -274.896326) (xy 80.748912 -274.845598) (xy 80.761091 -274.796184) (xy 80.781039 -274.749364)
			(xy 80.80824 -274.70635) (xy 80.841988 -274.668256) (xy 80.88141 -274.636069) (xy 80.925484 -274.610623)
			(xy 80.97307 -274.592576) (xy 81.022934 -274.582396) (xy 81.073786 -274.580347) (xy 81.124307 -274.586481)
			(xy 81.173191 -274.600641) (xy 81.21917 -274.622458) (xy 81.261054 -274.651368) (xy 81.297758 -274.686623)
			(xy 81.328331 -274.727309) (xy 81.351982 -274.772372) (xy 81.368098 -274.820646) (xy 81.376262 -274.87088)
			(xy 81.376774 -274.896326) (xy 81.695302 -274.896326) (xy 81.699262 -274.847272) (xy 81.711039 -274.799488)
			(xy 81.73033 -274.754212) (xy 81.756633 -274.712616) (xy 81.789268 -274.675779) (xy 81.827389 -274.644654)
			(xy 81.87001 -274.620047) (xy 81.916026 -274.602595) (xy 81.964245 -274.592751) (xy 82.01342 -274.59077)
			(xy 82.062275 -274.596702) (xy 82.109546 -274.610394) (xy 82.154008 -274.631492) (xy 82.194511 -274.659448)
			(xy 82.230004 -274.69354) (xy 82.259569 -274.732884) (xy 82.28244 -274.776461) (xy 82.298024 -274.823142)
			(xy 82.305919 -274.871719) (xy 82.306414 -274.896326) (xy 82.624671 -274.896326) (xy 82.628766 -274.845598)
			(xy 82.640945 -274.796184) (xy 82.660893 -274.749364) (xy 82.688094 -274.70635) (xy 82.721842 -274.668256)
			(xy 82.761264 -274.636069) (xy 82.805338 -274.610623) (xy 82.852924 -274.592576) (xy 82.902788 -274.582396)
			(xy 82.95364 -274.580347) (xy 83.004161 -274.586481) (xy 83.053045 -274.600641) (xy 83.099024 -274.622458)
			(xy 83.140908 -274.651368) (xy 83.177612 -274.686623) (xy 83.208185 -274.727309) (xy 83.231836 -274.772372)
			(xy 83.247952 -274.820646) (xy 83.256116 -274.87088) (xy 83.256628 -274.896326) (xy 83.575156 -274.896326)
			(xy 83.579116 -274.847272) (xy 83.590893 -274.799488) (xy 83.610184 -274.754212) (xy 83.636487 -274.712616)
			(xy 83.669122 -274.675779) (xy 83.707243 -274.644654) (xy 83.749864 -274.620047) (xy 83.79588 -274.602595)
			(xy 83.844099 -274.592751) (xy 83.893274 -274.59077) (xy 83.942129 -274.596702) (xy 83.9894 -274.610394)
			(xy 84.033862 -274.631492) (xy 84.074365 -274.659448) (xy 84.109858 -274.69354) (xy 84.139423 -274.732884)
			(xy 84.162294 -274.776461) (xy 84.177878 -274.823142) (xy 84.185773 -274.871719) (xy 84.186268 -274.896326)
			(xy 84.504779 -274.896326) (xy 84.508874 -274.845598) (xy 84.521053 -274.796184) (xy 84.541001 -274.749364)
			(xy 84.568202 -274.70635) (xy 84.60195 -274.668256) (xy 84.641372 -274.636069) (xy 84.685446 -274.610623)
			(xy 84.733032 -274.592576) (xy 84.782896 -274.582396) (xy 84.833748 -274.580347) (xy 84.884269 -274.586481)
			(xy 84.933153 -274.600641) (xy 84.979132 -274.622458) (xy 85.021016 -274.651368) (xy 85.05772 -274.686623)
			(xy 85.088293 -274.727309) (xy 85.111944 -274.772372) (xy 85.12806 -274.820646) (xy 85.136224 -274.87088)
			(xy 85.136736 -274.896326) (xy 85.444833 -274.896326) (xy 85.448928 -274.845598) (xy 85.461107 -274.796184)
			(xy 85.481055 -274.749364) (xy 85.508256 -274.70635) (xy 85.542004 -274.668256) (xy 85.581426 -274.636069)
			(xy 85.6255 -274.610623) (xy 85.673086 -274.592576) (xy 85.72295 -274.582396) (xy 85.773802 -274.580347)
			(xy 85.824323 -274.586481) (xy 85.873207 -274.600641) (xy 85.919186 -274.622458) (xy 85.96107 -274.651368)
			(xy 85.997774 -274.686623) (xy 86.028347 -274.727309) (xy 86.051998 -274.772372) (xy 86.068114 -274.820646)
			(xy 86.076278 -274.87088) (xy 86.07679 -274.896326) (xy 86.395318 -274.896326) (xy 86.399278 -274.847272)
			(xy 86.411055 -274.799488) (xy 86.430346 -274.754212) (xy 86.456649 -274.712616) (xy 86.489284 -274.675779)
			(xy 86.527405 -274.644654) (xy 86.570026 -274.620047) (xy 86.616042 -274.602595) (xy 86.664261 -274.592751)
			(xy 86.713436 -274.59077) (xy 86.762291 -274.596702) (xy 86.809562 -274.610394) (xy 86.854024 -274.631492)
			(xy 86.894527 -274.659448) (xy 86.93002 -274.69354) (xy 86.959585 -274.732884) (xy 86.982456 -274.776461)
			(xy 86.99804 -274.823142) (xy 87.005935 -274.871719) (xy 87.00643 -274.896326) (xy 87.324687 -274.896326)
			(xy 87.328782 -274.845598) (xy 87.340961 -274.796184) (xy 87.360909 -274.749364) (xy 87.38811 -274.70635)
			(xy 87.421858 -274.668256) (xy 87.46128 -274.636069) (xy 87.505354 -274.610623) (xy 87.55294 -274.592576)
			(xy 87.602804 -274.582396) (xy 87.653656 -274.580347) (xy 87.704177 -274.586481) (xy 87.753061 -274.600641)
			(xy 87.79904 -274.622458) (xy 87.840924 -274.651368) (xy 87.877628 -274.686623) (xy 87.908201 -274.727309)
			(xy 87.931852 -274.772372) (xy 87.947968 -274.820646) (xy 87.956132 -274.87088) (xy 87.956644 -274.896326)
			(xy 88.275172 -274.896326) (xy 88.279132 -274.847272) (xy 88.290909 -274.799488) (xy 88.3102 -274.754212)
			(xy 88.336503 -274.712616) (xy 88.369138 -274.675779) (xy 88.407259 -274.644654) (xy 88.44988 -274.620047)
			(xy 88.495896 -274.602595) (xy 88.544115 -274.592751) (xy 88.59329 -274.59077) (xy 88.642145 -274.596702)
			(xy 88.689416 -274.610394) (xy 88.733878 -274.631492) (xy 88.774381 -274.659448) (xy 88.809874 -274.69354)
			(xy 88.839439 -274.732884) (xy 88.86231 -274.776461) (xy 88.877894 -274.823142) (xy 88.885789 -274.871719)
			(xy 88.886284 -274.896326) (xy 89.204795 -274.896326) (xy 89.20889 -274.845598) (xy 89.221069 -274.796184)
			(xy 89.241017 -274.749364) (xy 89.268218 -274.70635) (xy 89.301966 -274.668256) (xy 89.341388 -274.636069)
			(xy 89.385462 -274.610623) (xy 89.433048 -274.592576) (xy 89.482912 -274.582396) (xy 89.533764 -274.580347)
			(xy 89.584285 -274.586481) (xy 89.633169 -274.600641) (xy 89.679148 -274.622458) (xy 89.721032 -274.651368)
			(xy 89.757736 -274.686623) (xy 89.788309 -274.727309) (xy 89.81196 -274.772372) (xy 89.828076 -274.820646)
			(xy 89.83624 -274.87088) (xy 89.836752 -274.896326) (xy 90.15528 -274.896326) (xy 90.15924 -274.847272)
			(xy 90.171017 -274.799488) (xy 90.190308 -274.754212) (xy 90.216611 -274.712616) (xy 90.249246 -274.675779)
			(xy 90.287367 -274.644654) (xy 90.329988 -274.620047) (xy 90.376004 -274.602595) (xy 90.424223 -274.592751)
			(xy 90.473398 -274.59077) (xy 90.522253 -274.596702) (xy 90.569524 -274.610394) (xy 90.613986 -274.631492)
			(xy 90.654489 -274.659448) (xy 90.689982 -274.69354) (xy 90.719547 -274.732884) (xy 90.742418 -274.776461)
			(xy 90.758002 -274.823142) (xy 90.765897 -274.871719) (xy 90.766392 -274.896326) (xy 91.084903 -274.896326)
			(xy 91.088998 -274.845598) (xy 91.101177 -274.796184) (xy 91.121125 -274.749364) (xy 91.148326 -274.70635)
			(xy 91.182074 -274.668256) (xy 91.221496 -274.636069) (xy 91.26557 -274.610623) (xy 91.313156 -274.592576)
			(xy 91.36302 -274.582396) (xy 91.413872 -274.580347) (xy 91.464393 -274.586481) (xy 91.513277 -274.600641)
			(xy 91.559256 -274.622458) (xy 91.60114 -274.651368) (xy 91.637844 -274.686623) (xy 91.668417 -274.727309)
			(xy 91.692068 -274.772372) (xy 91.708184 -274.820646) (xy 91.716348 -274.87088) (xy 91.71686 -274.896326)
			(xy 92.024703 -274.896326) (xy 92.028798 -274.845598) (xy 92.040977 -274.796184) (xy 92.060925 -274.749364)
			(xy 92.088126 -274.70635) (xy 92.121874 -274.668256) (xy 92.161296 -274.636069) (xy 92.20537 -274.610623)
			(xy 92.252956 -274.592576) (xy 92.30282 -274.582396) (xy 92.353672 -274.580347) (xy 92.404193 -274.586481)
			(xy 92.453077 -274.600641) (xy 92.499056 -274.622458) (xy 92.54094 -274.651368) (xy 92.577644 -274.686623)
			(xy 92.608217 -274.727309) (xy 92.631868 -274.772372) (xy 92.647984 -274.820646) (xy 92.656148 -274.87088)
			(xy 92.65666 -274.896326) (xy 92.975188 -274.896326) (xy 92.979148 -274.847272) (xy 92.990925 -274.799488)
			(xy 93.010216 -274.754212) (xy 93.036519 -274.712616) (xy 93.069154 -274.675779) (xy 93.107275 -274.644654)
			(xy 93.149896 -274.620047) (xy 93.195912 -274.602595) (xy 93.244131 -274.592751) (xy 93.293306 -274.59077)
			(xy 93.342161 -274.596702) (xy 93.389432 -274.610394) (xy 93.433894 -274.631492) (xy 93.474397 -274.659448)
			(xy 93.50989 -274.69354) (xy 93.539455 -274.732884) (xy 93.562326 -274.776461) (xy 93.57791 -274.823142)
			(xy 93.585805 -274.871719) (xy 93.5863 -274.896326) (xy 93.904811 -274.896326) (xy 93.908906 -274.845598)
			(xy 93.921085 -274.796184) (xy 93.941033 -274.749364) (xy 93.968234 -274.70635) (xy 94.001982 -274.668256)
			(xy 94.041404 -274.636069) (xy 94.085478 -274.610623) (xy 94.133064 -274.592576) (xy 94.182928 -274.582396)
			(xy 94.23378 -274.580347) (xy 94.284301 -274.586481) (xy 94.333185 -274.600641) (xy 94.379164 -274.622458)
			(xy 94.421048 -274.651368) (xy 94.457752 -274.686623) (xy 94.488325 -274.727309) (xy 94.511976 -274.772372)
			(xy 94.528092 -274.820646) (xy 94.536256 -274.87088) (xy 94.536768 -274.896326) (xy 94.855296 -274.896326)
			(xy 94.859256 -274.847272) (xy 94.871033 -274.799488) (xy 94.890324 -274.754212) (xy 94.916627 -274.712616)
			(xy 94.949262 -274.675779) (xy 94.987383 -274.644654) (xy 95.030004 -274.620047) (xy 95.07602 -274.602595)
			(xy 95.124239 -274.592751) (xy 95.173414 -274.59077) (xy 95.222269 -274.596702) (xy 95.26954 -274.610394)
			(xy 95.314002 -274.631492) (xy 95.354505 -274.659448) (xy 95.389998 -274.69354) (xy 95.419563 -274.732884)
			(xy 95.442434 -274.776461) (xy 95.458018 -274.823142) (xy 95.465913 -274.871719) (xy 95.466408 -274.896326)
			(xy 95.784919 -274.896326) (xy 95.789014 -274.845598) (xy 95.801193 -274.796184) (xy 95.821141 -274.749364)
			(xy 95.848342 -274.70635) (xy 95.88209 -274.668256) (xy 95.921512 -274.636069) (xy 95.965586 -274.610623)
			(xy 96.013172 -274.592576) (xy 96.063036 -274.582396) (xy 96.113888 -274.580347) (xy 96.164409 -274.586481)
			(xy 96.213293 -274.600641) (xy 96.259272 -274.622458) (xy 96.301156 -274.651368) (xy 96.33786 -274.686623)
			(xy 96.368433 -274.727309) (xy 96.392084 -274.772372) (xy 96.4082 -274.820646) (xy 96.416364 -274.87088)
			(xy 96.416876 -274.896326) (xy 96.73515 -274.896326) (xy 96.73911 -274.847272) (xy 96.750887 -274.799488)
			(xy 96.770178 -274.754212) (xy 96.796481 -274.712616) (xy 96.829116 -274.675779) (xy 96.867237 -274.644654)
			(xy 96.909858 -274.620047) (xy 96.955874 -274.602595) (xy 97.004093 -274.592751) (xy 97.053268 -274.59077)
			(xy 97.102123 -274.596702) (xy 97.149394 -274.610394) (xy 97.193856 -274.631492) (xy 97.234359 -274.659448)
			(xy 97.269852 -274.69354) (xy 97.299417 -274.732884) (xy 97.322288 -274.776461) (xy 97.337872 -274.823142)
			(xy 97.345767 -274.871719) (xy 97.346262 -274.896326) (xy 97.664773 -274.896326) (xy 97.668868 -274.845598)
			(xy 97.681047 -274.796184) (xy 97.700995 -274.749364) (xy 97.728196 -274.70635) (xy 97.761944 -274.668256)
			(xy 97.801366 -274.636069) (xy 97.84544 -274.610623) (xy 97.893026 -274.592576) (xy 97.94289 -274.582396)
			(xy 97.993742 -274.580347) (xy 98.044263 -274.586481) (xy 98.093147 -274.600641) (xy 98.139126 -274.622458)
			(xy 98.18101 -274.651368) (xy 98.217714 -274.686623) (xy 98.248287 -274.727309) (xy 98.271938 -274.772372)
			(xy 98.288054 -274.820646) (xy 98.296218 -274.87088) (xy 98.29673 -274.896326) (xy 98.604827 -274.896326)
			(xy 98.608922 -274.845598) (xy 98.621101 -274.796184) (xy 98.641049 -274.749364) (xy 98.66825 -274.70635)
			(xy 98.701998 -274.668256) (xy 98.74142 -274.636069) (xy 98.785494 -274.610623) (xy 98.83308 -274.592576)
			(xy 98.882944 -274.582396) (xy 98.933796 -274.580347) (xy 98.984317 -274.586481) (xy 99.033201 -274.600641)
			(xy 99.07918 -274.622458) (xy 99.121064 -274.651368) (xy 99.157768 -274.686623) (xy 99.188341 -274.727309)
			(xy 99.211992 -274.772372) (xy 99.228108 -274.820646) (xy 99.236272 -274.87088) (xy 99.236784 -274.896326)
			(xy 99.555312 -274.896326) (xy 99.559272 -274.847272) (xy 99.571049 -274.799488) (xy 99.59034 -274.754212)
			(xy 99.616643 -274.712616) (xy 99.649278 -274.675779) (xy 99.687399 -274.644654) (xy 99.73002 -274.620047)
			(xy 99.776036 -274.602595) (xy 99.824255 -274.592751) (xy 99.87343 -274.59077) (xy 99.922285 -274.596702)
			(xy 99.969556 -274.610394) (xy 100.014018 -274.631492) (xy 100.054521 -274.659448) (xy 100.090014 -274.69354)
			(xy 100.119579 -274.732884) (xy 100.14245 -274.776461) (xy 100.158034 -274.823142) (xy 100.165929 -274.871719)
			(xy 100.166424 -274.896326) (xy 100.484935 -274.896326) (xy 100.48903 -274.845598) (xy 100.501209 -274.796184)
			(xy 100.521157 -274.749364) (xy 100.548358 -274.70635) (xy 100.582106 -274.668256) (xy 100.621528 -274.636069)
			(xy 100.665602 -274.610623) (xy 100.713188 -274.592576) (xy 100.763052 -274.582396) (xy 100.813904 -274.580347)
			(xy 100.864425 -274.586481) (xy 100.913309 -274.600641) (xy 100.959288 -274.622458) (xy 101.001172 -274.651368)
			(xy 101.037876 -274.686623) (xy 101.068449 -274.727309) (xy 101.0921 -274.772372) (xy 101.108216 -274.820646)
			(xy 101.11638 -274.87088) (xy 101.116892 -274.896326) (xy 101.424735 -274.896326) (xy 101.42883 -274.845598)
			(xy 101.441009 -274.796184) (xy 101.460957 -274.749364) (xy 101.488158 -274.70635) (xy 101.521906 -274.668256)
			(xy 101.561328 -274.636069) (xy 101.605402 -274.610623) (xy 101.652988 -274.592576) (xy 101.702852 -274.582396)
			(xy 101.753704 -274.580347) (xy 101.804225 -274.586481) (xy 101.853109 -274.600641) (xy 101.899088 -274.622458)
			(xy 101.940972 -274.651368) (xy 101.977676 -274.686623) (xy 102.008249 -274.727309) (xy 102.0319 -274.772372)
			(xy 102.048016 -274.820646) (xy 102.05618 -274.87088) (xy 102.056692 -274.896326) (xy 102.05618 -274.921772)
			(xy 102.048016 -274.972006) (xy 102.0319 -275.02028) (xy 102.008249 -275.065343) (xy 101.977676 -275.106029)
			(xy 101.940972 -275.141284) (xy 101.899088 -275.170194) (xy 101.853109 -275.192011) (xy 101.804225 -275.206171)
			(xy 101.753704 -275.212305) (xy 101.702852 -275.210256) (xy 101.652988 -275.200076) (xy 101.605402 -275.182029)
			(xy 101.561328 -275.156583) (xy 101.521906 -275.124396) (xy 101.488158 -275.086302) (xy 101.460957 -275.043288)
			(xy 101.441009 -274.996468) (xy 101.42883 -274.947054) (xy 101.424735 -274.896326) (xy 101.116892 -274.896326)
			(xy 101.11638 -274.921772) (xy 101.108216 -274.972006) (xy 101.0921 -275.02028) (xy 101.068449 -275.065343)
			(xy 101.037876 -275.106029) (xy 101.001172 -275.141284) (xy 100.959288 -275.170194) (xy 100.913309 -275.192011)
			(xy 100.864425 -275.206171) (xy 100.813904 -275.212305) (xy 100.763052 -275.210256) (xy 100.713188 -275.200076)
			(xy 100.665602 -275.182029) (xy 100.621528 -275.156583) (xy 100.582106 -275.124396) (xy 100.548358 -275.086302)
			(xy 100.521157 -275.043288) (xy 100.501209 -274.996468) (xy 100.48903 -274.947054) (xy 100.484935 -274.896326)
			(xy 100.166424 -274.896326) (xy 100.165929 -274.920933) (xy 100.158034 -274.96951) (xy 100.14245 -275.016191)
			(xy 100.119579 -275.059768) (xy 100.090014 -275.099112) (xy 100.054521 -275.133204) (xy 100.014018 -275.16116)
			(xy 99.969556 -275.182258) (xy 99.922285 -275.19595) (xy 99.87343 -275.201882) (xy 99.824255 -275.199901)
			(xy 99.776036 -275.190057) (xy 99.73002 -275.172605) (xy 99.687399 -275.147998) (xy 99.649278 -275.116873)
			(xy 99.616643 -275.080036) (xy 99.59034 -275.03844) (xy 99.571049 -274.993164) (xy 99.559272 -274.94538)
			(xy 99.555312 -274.896326) (xy 99.236784 -274.896326) (xy 99.236272 -274.921772) (xy 99.228108 -274.972006)
			(xy 99.211992 -275.02028) (xy 99.188341 -275.065343) (xy 99.157768 -275.106029) (xy 99.121064 -275.141284)
			(xy 99.07918 -275.170194) (xy 99.033201 -275.192011) (xy 98.984317 -275.206171) (xy 98.933796 -275.212305)
			(xy 98.882944 -275.210256) (xy 98.83308 -275.200076) (xy 98.785494 -275.182029) (xy 98.74142 -275.156583)
			(xy 98.701998 -275.124396) (xy 98.66825 -275.086302) (xy 98.641049 -275.043288) (xy 98.621101 -274.996468)
			(xy 98.608922 -274.947054) (xy 98.604827 -274.896326) (xy 98.29673 -274.896326) (xy 98.296218 -274.921772)
			(xy 98.288054 -274.972006) (xy 98.271938 -275.02028) (xy 98.248287 -275.065343) (xy 98.217714 -275.106029)
			(xy 98.18101 -275.141284) (xy 98.139126 -275.170194) (xy 98.093147 -275.192011) (xy 98.044263 -275.206171)
			(xy 97.993742 -275.212305) (xy 97.94289 -275.210256) (xy 97.893026 -275.200076) (xy 97.84544 -275.182029)
			(xy 97.801366 -275.156583) (xy 97.761944 -275.124396) (xy 97.728196 -275.086302) (xy 97.700995 -275.043288)
			(xy 97.681047 -274.996468) (xy 97.668868 -274.947054) (xy 97.664773 -274.896326) (xy 97.346262 -274.896326)
			(xy 97.345767 -274.920933) (xy 97.337872 -274.96951) (xy 97.322288 -275.016191) (xy 97.299417 -275.059768)
			(xy 97.269852 -275.099112) (xy 97.234359 -275.133204) (xy 97.193856 -275.16116) (xy 97.149394 -275.182258)
			(xy 97.102123 -275.19595) (xy 97.053268 -275.201882) (xy 97.004093 -275.199901) (xy 96.955874 -275.190057)
			(xy 96.909858 -275.172605) (xy 96.867237 -275.147998) (xy 96.829116 -275.116873) (xy 96.796481 -275.080036)
			(xy 96.770178 -275.03844) (xy 96.750887 -274.993164) (xy 96.73911 -274.94538) (xy 96.73515 -274.896326)
			(xy 96.416876 -274.896326) (xy 96.416364 -274.921772) (xy 96.4082 -274.972006) (xy 96.392084 -275.02028)
			(xy 96.368433 -275.065343) (xy 96.33786 -275.106029) (xy 96.301156 -275.141284) (xy 96.259272 -275.170194)
			(xy 96.213293 -275.192011) (xy 96.164409 -275.206171) (xy 96.113888 -275.212305) (xy 96.063036 -275.210256)
			(xy 96.013172 -275.200076) (xy 95.965586 -275.182029) (xy 95.921512 -275.156583) (xy 95.88209 -275.124396)
			(xy 95.848342 -275.086302) (xy 95.821141 -275.043288) (xy 95.801193 -274.996468) (xy 95.789014 -274.947054)
			(xy 95.784919 -274.896326) (xy 95.466408 -274.896326) (xy 95.465913 -274.920933) (xy 95.458018 -274.96951)
			(xy 95.442434 -275.016191) (xy 95.419563 -275.059768) (xy 95.389998 -275.099112) (xy 95.354505 -275.133204)
			(xy 95.314002 -275.16116) (xy 95.26954 -275.182258) (xy 95.222269 -275.19595) (xy 95.173414 -275.201882)
			(xy 95.124239 -275.199901) (xy 95.07602 -275.190057) (xy 95.030004 -275.172605) (xy 94.987383 -275.147998)
			(xy 94.949262 -275.116873) (xy 94.916627 -275.080036) (xy 94.890324 -275.03844) (xy 94.871033 -274.993164)
			(xy 94.859256 -274.94538) (xy 94.855296 -274.896326) (xy 94.536768 -274.896326) (xy 94.536256 -274.921772)
			(xy 94.528092 -274.972006) (xy 94.511976 -275.02028) (xy 94.488325 -275.065343) (xy 94.457752 -275.106029)
			(xy 94.421048 -275.141284) (xy 94.379164 -275.170194) (xy 94.333185 -275.192011) (xy 94.284301 -275.206171)
			(xy 94.23378 -275.212305) (xy 94.182928 -275.210256) (xy 94.133064 -275.200076) (xy 94.085478 -275.182029)
			(xy 94.041404 -275.156583) (xy 94.001982 -275.124396) (xy 93.968234 -275.086302) (xy 93.941033 -275.043288)
			(xy 93.921085 -274.996468) (xy 93.908906 -274.947054) (xy 93.904811 -274.896326) (xy 93.5863 -274.896326)
			(xy 93.585805 -274.920933) (xy 93.57791 -274.96951) (xy 93.562326 -275.016191) (xy 93.539455 -275.059768)
			(xy 93.50989 -275.099112) (xy 93.474397 -275.133204) (xy 93.433894 -275.16116) (xy 93.389432 -275.182258)
			(xy 93.342161 -275.19595) (xy 93.293306 -275.201882) (xy 93.244131 -275.199901) (xy 93.195912 -275.190057)
			(xy 93.149896 -275.172605) (xy 93.107275 -275.147998) (xy 93.069154 -275.116873) (xy 93.036519 -275.080036)
			(xy 93.010216 -275.03844) (xy 92.990925 -274.993164) (xy 92.979148 -274.94538) (xy 92.975188 -274.896326)
			(xy 92.65666 -274.896326) (xy 92.656148 -274.921772) (xy 92.647984 -274.972006) (xy 92.631868 -275.02028)
			(xy 92.608217 -275.065343) (xy 92.577644 -275.106029) (xy 92.54094 -275.141284) (xy 92.499056 -275.170194)
			(xy 92.453077 -275.192011) (xy 92.404193 -275.206171) (xy 92.353672 -275.212305) (xy 92.30282 -275.210256)
			(xy 92.252956 -275.200076) (xy 92.20537 -275.182029) (xy 92.161296 -275.156583) (xy 92.121874 -275.124396)
			(xy 92.088126 -275.086302) (xy 92.060925 -275.043288) (xy 92.040977 -274.996468) (xy 92.028798 -274.947054)
			(xy 92.024703 -274.896326) (xy 91.71686 -274.896326) (xy 91.716348 -274.921772) (xy 91.708184 -274.972006)
			(xy 91.692068 -275.02028) (xy 91.668417 -275.065343) (xy 91.637844 -275.106029) (xy 91.60114 -275.141284)
			(xy 91.559256 -275.170194) (xy 91.513277 -275.192011) (xy 91.464393 -275.206171) (xy 91.413872 -275.212305)
			(xy 91.36302 -275.210256) (xy 91.313156 -275.200076) (xy 91.26557 -275.182029) (xy 91.221496 -275.156583)
			(xy 91.182074 -275.124396) (xy 91.148326 -275.086302) (xy 91.121125 -275.043288) (xy 91.101177 -274.996468)
			(xy 91.088998 -274.947054) (xy 91.084903 -274.896326) (xy 90.766392 -274.896326) (xy 90.765897 -274.920933)
			(xy 90.758002 -274.96951) (xy 90.742418 -275.016191) (xy 90.719547 -275.059768) (xy 90.689982 -275.099112)
			(xy 90.654489 -275.133204) (xy 90.613986 -275.16116) (xy 90.569524 -275.182258) (xy 90.522253 -275.19595)
			(xy 90.473398 -275.201882) (xy 90.424223 -275.199901) (xy 90.376004 -275.190057) (xy 90.329988 -275.172605)
			(xy 90.287367 -275.147998) (xy 90.249246 -275.116873) (xy 90.216611 -275.080036) (xy 90.190308 -275.03844)
			(xy 90.171017 -274.993164) (xy 90.15924 -274.94538) (xy 90.15528 -274.896326) (xy 89.836752 -274.896326)
			(xy 89.83624 -274.921772) (xy 89.828076 -274.972006) (xy 89.81196 -275.02028) (xy 89.788309 -275.065343)
			(xy 89.757736 -275.106029) (xy 89.721032 -275.141284) (xy 89.679148 -275.170194) (xy 89.633169 -275.192011)
			(xy 89.584285 -275.206171) (xy 89.533764 -275.212305) (xy 89.482912 -275.210256) (xy 89.433048 -275.200076)
			(xy 89.385462 -275.182029) (xy 89.341388 -275.156583) (xy 89.301966 -275.124396) (xy 89.268218 -275.086302)
			(xy 89.241017 -275.043288) (xy 89.221069 -274.996468) (xy 89.20889 -274.947054) (xy 89.204795 -274.896326)
			(xy 88.886284 -274.896326) (xy 88.885789 -274.920933) (xy 88.877894 -274.96951) (xy 88.86231 -275.016191)
			(xy 88.839439 -275.059768) (xy 88.809874 -275.099112) (xy 88.774381 -275.133204) (xy 88.733878 -275.16116)
			(xy 88.689416 -275.182258) (xy 88.642145 -275.19595) (xy 88.59329 -275.201882) (xy 88.544115 -275.199901)
			(xy 88.495896 -275.190057) (xy 88.44988 -275.172605) (xy 88.407259 -275.147998) (xy 88.369138 -275.116873)
			(xy 88.336503 -275.080036) (xy 88.3102 -275.03844) (xy 88.290909 -274.993164) (xy 88.279132 -274.94538)
			(xy 88.275172 -274.896326) (xy 87.956644 -274.896326) (xy 87.956132 -274.921772) (xy 87.947968 -274.972006)
			(xy 87.931852 -275.02028) (xy 87.908201 -275.065343) (xy 87.877628 -275.106029) (xy 87.840924 -275.141284)
			(xy 87.79904 -275.170194) (xy 87.753061 -275.192011) (xy 87.704177 -275.206171) (xy 87.653656 -275.212305)
			(xy 87.602804 -275.210256) (xy 87.55294 -275.200076) (xy 87.505354 -275.182029) (xy 87.46128 -275.156583)
			(xy 87.421858 -275.124396) (xy 87.38811 -275.086302) (xy 87.360909 -275.043288) (xy 87.340961 -274.996468)
			(xy 87.328782 -274.947054) (xy 87.324687 -274.896326) (xy 87.00643 -274.896326) (xy 87.005935 -274.920933)
			(xy 86.99804 -274.96951) (xy 86.982456 -275.016191) (xy 86.959585 -275.059768) (xy 86.93002 -275.099112)
			(xy 86.894527 -275.133204) (xy 86.854024 -275.16116) (xy 86.809562 -275.182258) (xy 86.762291 -275.19595)
			(xy 86.713436 -275.201882) (xy 86.664261 -275.199901) (xy 86.616042 -275.190057) (xy 86.570026 -275.172605)
			(xy 86.527405 -275.147998) (xy 86.489284 -275.116873) (xy 86.456649 -275.080036) (xy 86.430346 -275.03844)
			(xy 86.411055 -274.993164) (xy 86.399278 -274.94538) (xy 86.395318 -274.896326) (xy 86.07679 -274.896326)
			(xy 86.076278 -274.921772) (xy 86.068114 -274.972006) (xy 86.051998 -275.02028) (xy 86.028347 -275.065343)
			(xy 85.997774 -275.106029) (xy 85.96107 -275.141284) (xy 85.919186 -275.170194) (xy 85.873207 -275.192011)
			(xy 85.824323 -275.206171) (xy 85.773802 -275.212305) (xy 85.72295 -275.210256) (xy 85.673086 -275.200076)
			(xy 85.6255 -275.182029) (xy 85.581426 -275.156583) (xy 85.542004 -275.124396) (xy 85.508256 -275.086302)
			(xy 85.481055 -275.043288) (xy 85.461107 -274.996468) (xy 85.448928 -274.947054) (xy 85.444833 -274.896326)
			(xy 85.136736 -274.896326) (xy 85.136224 -274.921772) (xy 85.12806 -274.972006) (xy 85.111944 -275.02028)
			(xy 85.088293 -275.065343) (xy 85.05772 -275.106029) (xy 85.021016 -275.141284) (xy 84.979132 -275.170194)
			(xy 84.933153 -275.192011) (xy 84.884269 -275.206171) (xy 84.833748 -275.212305) (xy 84.782896 -275.210256)
			(xy 84.733032 -275.200076) (xy 84.685446 -275.182029) (xy 84.641372 -275.156583) (xy 84.60195 -275.124396)
			(xy 84.568202 -275.086302) (xy 84.541001 -275.043288) (xy 84.521053 -274.996468) (xy 84.508874 -274.947054)
			(xy 84.504779 -274.896326) (xy 84.186268 -274.896326) (xy 84.185773 -274.920933) (xy 84.177878 -274.96951)
			(xy 84.162294 -275.016191) (xy 84.139423 -275.059768) (xy 84.109858 -275.099112) (xy 84.074365 -275.133204)
			(xy 84.033862 -275.16116) (xy 83.9894 -275.182258) (xy 83.942129 -275.19595) (xy 83.893274 -275.201882)
			(xy 83.844099 -275.199901) (xy 83.79588 -275.190057) (xy 83.749864 -275.172605) (xy 83.707243 -275.147998)
			(xy 83.669122 -275.116873) (xy 83.636487 -275.080036) (xy 83.610184 -275.03844) (xy 83.590893 -274.993164)
			(xy 83.579116 -274.94538) (xy 83.575156 -274.896326) (xy 83.256628 -274.896326) (xy 83.256116 -274.921772)
			(xy 83.247952 -274.972006) (xy 83.231836 -275.02028) (xy 83.208185 -275.065343) (xy 83.177612 -275.106029)
			(xy 83.140908 -275.141284) (xy 83.099024 -275.170194) (xy 83.053045 -275.192011) (xy 83.004161 -275.206171)
			(xy 82.95364 -275.212305) (xy 82.902788 -275.210256) (xy 82.852924 -275.200076) (xy 82.805338 -275.182029)
			(xy 82.761264 -275.156583) (xy 82.721842 -275.124396) (xy 82.688094 -275.086302) (xy 82.660893 -275.043288)
			(xy 82.640945 -274.996468) (xy 82.628766 -274.947054) (xy 82.624671 -274.896326) (xy 82.306414 -274.896326)
			(xy 82.305919 -274.920933) (xy 82.298024 -274.96951) (xy 82.28244 -275.016191) (xy 82.259569 -275.059768)
			(xy 82.230004 -275.099112) (xy 82.194511 -275.133204) (xy 82.154008 -275.16116) (xy 82.109546 -275.182258)
			(xy 82.062275 -275.19595) (xy 82.01342 -275.201882) (xy 81.964245 -275.199901) (xy 81.916026 -275.190057)
			(xy 81.87001 -275.172605) (xy 81.827389 -275.147998) (xy 81.789268 -275.116873) (xy 81.756633 -275.080036)
			(xy 81.73033 -275.03844) (xy 81.711039 -274.993164) (xy 81.699262 -274.94538) (xy 81.695302 -274.896326)
			(xy 81.376774 -274.896326) (xy 81.376262 -274.921772) (xy 81.368098 -274.972006) (xy 81.351982 -275.02028)
			(xy 81.328331 -275.065343) (xy 81.297758 -275.106029) (xy 81.261054 -275.141284) (xy 81.21917 -275.170194)
			(xy 81.173191 -275.192011) (xy 81.124307 -275.206171) (xy 81.073786 -275.212305) (xy 81.022934 -275.210256)
			(xy 80.97307 -275.200076) (xy 80.925484 -275.182029) (xy 80.88141 -275.156583) (xy 80.841988 -275.124396)
			(xy 80.80824 -275.086302) (xy 80.781039 -275.043288) (xy 80.761091 -274.996468) (xy 80.748912 -274.947054)
			(xy 80.744817 -274.896326) (xy 80.426306 -274.896326) (xy 80.425811 -274.920933) (xy 80.417916 -274.96951)
			(xy 80.402332 -275.016191) (xy 80.379461 -275.059768) (xy 80.349896 -275.099112) (xy 80.314403 -275.133204)
			(xy 80.2739 -275.16116) (xy 80.229438 -275.182258) (xy 80.182167 -275.19595) (xy 80.133312 -275.201882)
			(xy 80.084137 -275.199901) (xy 80.035918 -275.190057) (xy 79.989902 -275.172605) (xy 79.947281 -275.147998)
			(xy 79.90916 -275.116873) (xy 79.876525 -275.080036) (xy 79.850222 -275.03844) (xy 79.830931 -274.993164)
			(xy 79.819154 -274.94538) (xy 79.815194 -274.896326) (xy 77.263451 -274.896326) (xy 77.221316 -274.91632)
			(xy 77.174045 -274.930012) (xy 77.12519 -274.935944) (xy 77.076015 -274.933963) (xy 77.027796 -274.924119)
			(xy 76.98178 -274.906667) (xy 76.939159 -274.88206) (xy 76.901038 -274.850935) (xy 76.868403 -274.814098)
			(xy 76.8421 -274.772502) (xy 76.822809 -274.727226) (xy 76.811032 -274.679442) (xy 76.807072 -274.630388)
			(xy 73.228962 -274.630388) (xy 73.228962 -275.706332) (xy 78.40524 -275.706332) (xy 78.4092 -275.657278)
			(xy 78.420977 -275.609494) (xy 78.440268 -275.564218) (xy 78.466571 -275.522622) (xy 78.499206 -275.485785)
			(xy 78.537327 -275.45466) (xy 78.579948 -275.430053) (xy 78.625964 -275.412601) (xy 78.674183 -275.402757)
			(xy 78.723358 -275.400776) (xy 78.772213 -275.406708) (xy 78.819484 -275.4204) (xy 78.863946 -275.441498)
			(xy 78.904449 -275.469454) (xy 78.939942 -275.503546) (xy 78.969507 -275.54289) (xy 78.992378 -275.586467)
			(xy 79.007962 -275.633148) (xy 79.015857 -275.681725) (xy 79.016352 -275.706332) (xy 80.285348 -275.706332)
			(xy 80.289308 -275.657278) (xy 80.301085 -275.609494) (xy 80.320376 -275.564218) (xy 80.346679 -275.522622)
			(xy 80.379314 -275.485785) (xy 80.417435 -275.45466) (xy 80.460056 -275.430053) (xy 80.506072 -275.412601)
			(xy 80.554291 -275.402757) (xy 80.603466 -275.400776) (xy 80.652321 -275.406708) (xy 80.699592 -275.4204)
			(xy 80.744054 -275.441498) (xy 80.784557 -275.469454) (xy 80.82005 -275.503546) (xy 80.849615 -275.54289)
			(xy 80.872486 -275.586467) (xy 80.88807 -275.633148) (xy 80.895965 -275.681725) (xy 80.89646 -275.706332)
			(xy 81.214717 -275.706332) (xy 81.218812 -275.655604) (xy 81.230991 -275.60619) (xy 81.250939 -275.55937)
			(xy 81.27814 -275.516356) (xy 81.311888 -275.478262) (xy 81.35131 -275.446075) (xy 81.395384 -275.420629)
			(xy 81.44297 -275.402582) (xy 81.492834 -275.392402) (xy 81.543686 -275.390353) (xy 81.594207 -275.396487)
			(xy 81.643091 -275.410647) (xy 81.68907 -275.432464) (xy 81.730954 -275.461374) (xy 81.767658 -275.496629)
			(xy 81.798231 -275.537315) (xy 81.821882 -275.582378) (xy 81.837998 -275.630652) (xy 81.846162 -275.680886)
			(xy 81.846674 -275.706332) (xy 82.154771 -275.706332) (xy 82.158866 -275.655604) (xy 82.171045 -275.60619)
			(xy 82.190993 -275.55937) (xy 82.218194 -275.516356) (xy 82.251942 -275.478262) (xy 82.291364 -275.446075)
			(xy 82.335438 -275.420629) (xy 82.383024 -275.402582) (xy 82.432888 -275.392402) (xy 82.48374 -275.390353)
			(xy 82.534261 -275.396487) (xy 82.583145 -275.410647) (xy 82.629124 -275.432464) (xy 82.671008 -275.461374)
			(xy 82.707712 -275.496629) (xy 82.738285 -275.537315) (xy 82.761936 -275.582378) (xy 82.778052 -275.630652)
			(xy 82.786216 -275.680886) (xy 82.786728 -275.706332) (xy 83.105256 -275.706332) (xy 83.109216 -275.657278)
			(xy 83.120993 -275.609494) (xy 83.140284 -275.564218) (xy 83.166587 -275.522622) (xy 83.199222 -275.485785)
			(xy 83.237343 -275.45466) (xy 83.279964 -275.430053) (xy 83.32598 -275.412601) (xy 83.374199 -275.402757)
			(xy 83.423374 -275.400776) (xy 83.472229 -275.406708) (xy 83.5195 -275.4204) (xy 83.563962 -275.441498)
			(xy 83.604465 -275.469454) (xy 83.639958 -275.503546) (xy 83.669523 -275.54289) (xy 83.692394 -275.586467)
			(xy 83.707978 -275.633148) (xy 83.715873 -275.681725) (xy 83.716368 -275.706332) (xy 84.034879 -275.706332)
			(xy 84.038974 -275.655604) (xy 84.051153 -275.60619) (xy 84.071101 -275.55937) (xy 84.098302 -275.516356)
			(xy 84.13205 -275.478262) (xy 84.171472 -275.446075) (xy 84.215546 -275.420629) (xy 84.263132 -275.402582)
			(xy 84.312996 -275.392402) (xy 84.363848 -275.390353) (xy 84.414369 -275.396487) (xy 84.463253 -275.410647)
			(xy 84.509232 -275.432464) (xy 84.551116 -275.461374) (xy 84.58782 -275.496629) (xy 84.618393 -275.537315)
			(xy 84.642044 -275.582378) (xy 84.65816 -275.630652) (xy 84.666324 -275.680886) (xy 84.666836 -275.706332)
			(xy 84.98511 -275.706332) (xy 84.98907 -275.657278) (xy 85.000847 -275.609494) (xy 85.020138 -275.564218)
			(xy 85.046441 -275.522622) (xy 85.079076 -275.485785) (xy 85.117197 -275.45466) (xy 85.159818 -275.430053)
			(xy 85.205834 -275.412601) (xy 85.254053 -275.402757) (xy 85.303228 -275.400776) (xy 85.352083 -275.406708)
			(xy 85.399354 -275.4204) (xy 85.443816 -275.441498) (xy 85.484319 -275.469454) (xy 85.519812 -275.503546)
			(xy 85.549377 -275.54289) (xy 85.572248 -275.586467) (xy 85.587832 -275.633148) (xy 85.595727 -275.681725)
			(xy 85.596222 -275.706332) (xy 85.914733 -275.706332) (xy 85.918828 -275.655604) (xy 85.931007 -275.60619)
			(xy 85.950955 -275.55937) (xy 85.978156 -275.516356) (xy 86.011904 -275.478262) (xy 86.051326 -275.446075)
			(xy 86.0954 -275.420629) (xy 86.142986 -275.402582) (xy 86.19285 -275.392402) (xy 86.243702 -275.390353)
			(xy 86.294223 -275.396487) (xy 86.343107 -275.410647) (xy 86.389086 -275.432464) (xy 86.43097 -275.461374)
			(xy 86.467674 -275.496629) (xy 86.498247 -275.537315) (xy 86.521898 -275.582378) (xy 86.538014 -275.630652)
			(xy 86.546178 -275.680886) (xy 86.54669 -275.706332) (xy 86.865218 -275.706332) (xy 86.869178 -275.657278)
			(xy 86.880955 -275.609494) (xy 86.900246 -275.564218) (xy 86.926549 -275.522622) (xy 86.959184 -275.485785)
			(xy 86.997305 -275.45466) (xy 87.039926 -275.430053) (xy 87.085942 -275.412601) (xy 87.134161 -275.402757)
			(xy 87.183336 -275.400776) (xy 87.232191 -275.406708) (xy 87.279462 -275.4204) (xy 87.323924 -275.441498)
			(xy 87.364427 -275.469454) (xy 87.39992 -275.503546) (xy 87.429485 -275.54289) (xy 87.452356 -275.586467)
			(xy 87.46794 -275.633148) (xy 87.475835 -275.681725) (xy 87.47633 -275.706332) (xy 87.794841 -275.706332)
			(xy 87.798936 -275.655604) (xy 87.811115 -275.60619) (xy 87.831063 -275.55937) (xy 87.858264 -275.516356)
			(xy 87.892012 -275.478262) (xy 87.931434 -275.446075) (xy 87.975508 -275.420629) (xy 88.023094 -275.402582)
			(xy 88.072958 -275.392402) (xy 88.12381 -275.390353) (xy 88.174331 -275.396487) (xy 88.223215 -275.410647)
			(xy 88.269194 -275.432464) (xy 88.311078 -275.461374) (xy 88.347782 -275.496629) (xy 88.378355 -275.537315)
			(xy 88.402006 -275.582378) (xy 88.418122 -275.630652) (xy 88.426286 -275.680886) (xy 88.426798 -275.706332)
			(xy 88.734895 -275.706332) (xy 88.73899 -275.655604) (xy 88.751169 -275.60619) (xy 88.771117 -275.55937)
			(xy 88.798318 -275.516356) (xy 88.832066 -275.478262) (xy 88.871488 -275.446075) (xy 88.915562 -275.420629)
			(xy 88.963148 -275.402582) (xy 89.013012 -275.392402) (xy 89.063864 -275.390353) (xy 89.114385 -275.396487)
			(xy 89.163269 -275.410647) (xy 89.209248 -275.432464) (xy 89.251132 -275.461374) (xy 89.287836 -275.496629)
			(xy 89.318409 -275.537315) (xy 89.34206 -275.582378) (xy 89.358176 -275.630652) (xy 89.36634 -275.680886)
			(xy 89.366852 -275.706332) (xy 89.685126 -275.706332) (xy 89.689086 -275.657278) (xy 89.700863 -275.609494)
			(xy 89.720154 -275.564218) (xy 89.746457 -275.522622) (xy 89.779092 -275.485785) (xy 89.817213 -275.45466)
			(xy 89.859834 -275.430053) (xy 89.90585 -275.412601) (xy 89.954069 -275.402757) (xy 90.003244 -275.400776)
			(xy 90.052099 -275.406708) (xy 90.09937 -275.4204) (xy 90.143832 -275.441498) (xy 90.184335 -275.469454)
			(xy 90.219828 -275.503546) (xy 90.249393 -275.54289) (xy 90.272264 -275.586467) (xy 90.287848 -275.633148)
			(xy 90.295743 -275.681725) (xy 90.296238 -275.706332) (xy 90.614749 -275.706332) (xy 90.618844 -275.655604)
			(xy 90.631023 -275.60619) (xy 90.650971 -275.55937) (xy 90.678172 -275.516356) (xy 90.71192 -275.478262)
			(xy 90.751342 -275.446075) (xy 90.795416 -275.420629) (xy 90.843002 -275.402582) (xy 90.892866 -275.392402)
			(xy 90.943718 -275.390353) (xy 90.994239 -275.396487) (xy 91.043123 -275.410647) (xy 91.089102 -275.432464)
			(xy 91.130986 -275.461374) (xy 91.16769 -275.496629) (xy 91.198263 -275.537315) (xy 91.221914 -275.582378)
			(xy 91.23803 -275.630652) (xy 91.246194 -275.680886) (xy 91.246706 -275.706332) (xy 91.565234 -275.706332)
			(xy 91.569194 -275.657278) (xy 91.580971 -275.609494) (xy 91.600262 -275.564218) (xy 91.626565 -275.522622)
			(xy 91.6592 -275.485785) (xy 91.697321 -275.45466) (xy 91.739942 -275.430053) (xy 91.785958 -275.412601)
			(xy 91.834177 -275.402757) (xy 91.883352 -275.400776) (xy 91.932207 -275.406708) (xy 91.979478 -275.4204)
			(xy 92.02394 -275.441498) (xy 92.064443 -275.469454) (xy 92.099936 -275.503546) (xy 92.129501 -275.54289)
			(xy 92.152372 -275.586467) (xy 92.167956 -275.633148) (xy 92.175851 -275.681725) (xy 92.176346 -275.706332)
			(xy 92.494857 -275.706332) (xy 92.498952 -275.655604) (xy 92.511131 -275.60619) (xy 92.531079 -275.55937)
			(xy 92.55828 -275.516356) (xy 92.592028 -275.478262) (xy 92.63145 -275.446075) (xy 92.675524 -275.420629)
			(xy 92.72311 -275.402582) (xy 92.772974 -275.392402) (xy 92.823826 -275.390353) (xy 92.874347 -275.396487)
			(xy 92.923231 -275.410647) (xy 92.96921 -275.432464) (xy 93.011094 -275.461374) (xy 93.047798 -275.496629)
			(xy 93.078371 -275.537315) (xy 93.102022 -275.582378) (xy 93.118138 -275.630652) (xy 93.126302 -275.680886)
			(xy 93.126814 -275.706332) (xy 93.445342 -275.706332) (xy 93.449302 -275.657278) (xy 93.461079 -275.609494)
			(xy 93.48037 -275.564218) (xy 93.506673 -275.522622) (xy 93.539308 -275.485785) (xy 93.577429 -275.45466)
			(xy 93.62005 -275.430053) (xy 93.666066 -275.412601) (xy 93.714285 -275.402757) (xy 93.76346 -275.400776)
			(xy 93.812315 -275.406708) (xy 93.859586 -275.4204) (xy 93.904048 -275.441498) (xy 93.944551 -275.469454)
			(xy 93.980044 -275.503546) (xy 94.009609 -275.54289) (xy 94.03248 -275.586467) (xy 94.048064 -275.633148)
			(xy 94.055959 -275.681725) (xy 94.056454 -275.706332) (xy 94.374711 -275.706332) (xy 94.378806 -275.655604)
			(xy 94.390985 -275.60619) (xy 94.410933 -275.55937) (xy 94.438134 -275.516356) (xy 94.471882 -275.478262)
			(xy 94.511304 -275.446075) (xy 94.555378 -275.420629) (xy 94.602964 -275.402582) (xy 94.652828 -275.392402)
			(xy 94.70368 -275.390353) (xy 94.754201 -275.396487) (xy 94.803085 -275.410647) (xy 94.849064 -275.432464)
			(xy 94.890948 -275.461374) (xy 94.927652 -275.496629) (xy 94.958225 -275.537315) (xy 94.981876 -275.582378)
			(xy 94.997992 -275.630652) (xy 95.006156 -275.680886) (xy 95.006668 -275.706332) (xy 95.314765 -275.706332)
			(xy 95.31886 -275.655604) (xy 95.331039 -275.60619) (xy 95.350987 -275.55937) (xy 95.378188 -275.516356)
			(xy 95.411936 -275.478262) (xy 95.451358 -275.446075) (xy 95.495432 -275.420629) (xy 95.543018 -275.402582)
			(xy 95.592882 -275.392402) (xy 95.643734 -275.390353) (xy 95.694255 -275.396487) (xy 95.743139 -275.410647)
			(xy 95.789118 -275.432464) (xy 95.831002 -275.461374) (xy 95.867706 -275.496629) (xy 95.898279 -275.537315)
			(xy 95.92193 -275.582378) (xy 95.938046 -275.630652) (xy 95.94621 -275.680886) (xy 95.946722 -275.706332)
			(xy 96.26525 -275.706332) (xy 96.26921 -275.657278) (xy 96.280987 -275.609494) (xy 96.300278 -275.564218)
			(xy 96.326581 -275.522622) (xy 96.359216 -275.485785) (xy 96.397337 -275.45466) (xy 96.439958 -275.430053)
			(xy 96.485974 -275.412601) (xy 96.534193 -275.402757) (xy 96.583368 -275.400776) (xy 96.632223 -275.406708)
			(xy 96.679494 -275.4204) (xy 96.723956 -275.441498) (xy 96.764459 -275.469454) (xy 96.799952 -275.503546)
			(xy 96.829517 -275.54289) (xy 96.852388 -275.586467) (xy 96.867972 -275.633148) (xy 96.875867 -275.681725)
			(xy 96.876362 -275.706332) (xy 99.085158 -275.706332) (xy 99.089118 -275.657278) (xy 99.100895 -275.609494)
			(xy 99.120186 -275.564218) (xy 99.146489 -275.522622) (xy 99.179124 -275.485785) (xy 99.217245 -275.45466)
			(xy 99.259866 -275.430053) (xy 99.305882 -275.412601) (xy 99.354101 -275.402757) (xy 99.403276 -275.400776)
			(xy 99.452131 -275.406708) (xy 99.499402 -275.4204) (xy 99.543864 -275.441498) (xy 99.584367 -275.469454)
			(xy 99.61986 -275.503546) (xy 99.649425 -275.54289) (xy 99.672296 -275.586467) (xy 99.68788 -275.633148)
			(xy 99.695775 -275.681725) (xy 99.69627 -275.706332) (xy 101.90532 -275.706332) (xy 101.90928 -275.657278)
			(xy 101.921057 -275.609494) (xy 101.940348 -275.564218) (xy 101.966651 -275.522622) (xy 101.999286 -275.485785)
			(xy 102.037407 -275.45466) (xy 102.080028 -275.430053) (xy 102.126044 -275.412601) (xy 102.174263 -275.402757)
			(xy 102.223438 -275.400776) (xy 102.272293 -275.406708) (xy 102.319564 -275.4204) (xy 102.364026 -275.441498)
			(xy 102.404529 -275.469454) (xy 102.440022 -275.503546) (xy 102.469587 -275.54289) (xy 102.492458 -275.586467)
			(xy 102.508042 -275.633148) (xy 102.515937 -275.681725) (xy 102.516432 -275.706332) (xy 102.515937 -275.730939)
			(xy 102.508042 -275.779516) (xy 102.492458 -275.826197) (xy 102.469587 -275.869774) (xy 102.440022 -275.909118)
			(xy 102.404529 -275.94321) (xy 102.364026 -275.971166) (xy 102.319564 -275.992264) (xy 102.272293 -276.005956)
			(xy 102.223438 -276.011888) (xy 102.174263 -276.009907) (xy 102.126044 -276.000063) (xy 102.080028 -275.982611)
			(xy 102.037407 -275.958004) (xy 101.999286 -275.926879) (xy 101.966651 -275.890042) (xy 101.940348 -275.848446)
			(xy 101.921057 -275.80317) (xy 101.90928 -275.755386) (xy 101.90532 -275.706332) (xy 99.69627 -275.706332)
			(xy 99.695775 -275.730939) (xy 99.68788 -275.779516) (xy 99.672296 -275.826197) (xy 99.649425 -275.869774)
			(xy 99.61986 -275.909118) (xy 99.584367 -275.94321) (xy 99.543864 -275.971166) (xy 99.499402 -275.992264)
			(xy 99.452131 -276.005956) (xy 99.403276 -276.011888) (xy 99.354101 -276.009907) (xy 99.305882 -276.000063)
			(xy 99.259866 -275.982611) (xy 99.217245 -275.958004) (xy 99.179124 -275.926879) (xy 99.146489 -275.890042)
			(xy 99.120186 -275.848446) (xy 99.100895 -275.80317) (xy 99.089118 -275.755386) (xy 99.085158 -275.706332)
			(xy 96.876362 -275.706332) (xy 96.875867 -275.730939) (xy 96.867972 -275.779516) (xy 96.852388 -275.826197)
			(xy 96.829517 -275.869774) (xy 96.799952 -275.909118) (xy 96.764459 -275.94321) (xy 96.723956 -275.971166)
			(xy 96.679494 -275.992264) (xy 96.632223 -276.005956) (xy 96.583368 -276.011888) (xy 96.534193 -276.009907)
			(xy 96.485974 -276.000063) (xy 96.439958 -275.982611) (xy 96.397337 -275.958004) (xy 96.359216 -275.926879)
			(xy 96.326581 -275.890042) (xy 96.300278 -275.848446) (xy 96.280987 -275.80317) (xy 96.26921 -275.755386)
			(xy 96.26525 -275.706332) (xy 95.946722 -275.706332) (xy 95.94621 -275.731778) (xy 95.938046 -275.782012)
			(xy 95.92193 -275.830286) (xy 95.898279 -275.875349) (xy 95.867706 -275.916035) (xy 95.831002 -275.95129)
			(xy 95.789118 -275.9802) (xy 95.743139 -276.002017) (xy 95.694255 -276.016177) (xy 95.643734 -276.022311)
			(xy 95.592882 -276.020262) (xy 95.543018 -276.010082) (xy 95.495432 -275.992035) (xy 95.451358 -275.966589)
			(xy 95.411936 -275.934402) (xy 95.378188 -275.896308) (xy 95.350987 -275.853294) (xy 95.331039 -275.806474)
			(xy 95.31886 -275.75706) (xy 95.314765 -275.706332) (xy 95.006668 -275.706332) (xy 95.006156 -275.731778)
			(xy 94.997992 -275.782012) (xy 94.981876 -275.830286) (xy 94.958225 -275.875349) (xy 94.927652 -275.916035)
			(xy 94.890948 -275.95129) (xy 94.849064 -275.9802) (xy 94.803085 -276.002017) (xy 94.754201 -276.016177)
			(xy 94.70368 -276.022311) (xy 94.652828 -276.020262) (xy 94.602964 -276.010082) (xy 94.555378 -275.992035)
			(xy 94.511304 -275.966589) (xy 94.471882 -275.934402) (xy 94.438134 -275.896308) (xy 94.410933 -275.853294)
			(xy 94.390985 -275.806474) (xy 94.378806 -275.75706) (xy 94.374711 -275.706332) (xy 94.056454 -275.706332)
			(xy 94.055959 -275.730939) (xy 94.048064 -275.779516) (xy 94.03248 -275.826197) (xy 94.009609 -275.869774)
			(xy 93.980044 -275.909118) (xy 93.944551 -275.94321) (xy 93.904048 -275.971166) (xy 93.859586 -275.992264)
			(xy 93.812315 -276.005956) (xy 93.76346 -276.011888) (xy 93.714285 -276.009907) (xy 93.666066 -276.000063)
			(xy 93.62005 -275.982611) (xy 93.577429 -275.958004) (xy 93.539308 -275.926879) (xy 93.506673 -275.890042)
			(xy 93.48037 -275.848446) (xy 93.461079 -275.80317) (xy 93.449302 -275.755386) (xy 93.445342 -275.706332)
			(xy 93.126814 -275.706332) (xy 93.126302 -275.731778) (xy 93.118138 -275.782012) (xy 93.102022 -275.830286)
			(xy 93.078371 -275.875349) (xy 93.047798 -275.916035) (xy 93.011094 -275.95129) (xy 92.96921 -275.9802)
			(xy 92.923231 -276.002017) (xy 92.874347 -276.016177) (xy 92.823826 -276.022311) (xy 92.772974 -276.020262)
			(xy 92.72311 -276.010082) (xy 92.675524 -275.992035) (xy 92.63145 -275.966589) (xy 92.592028 -275.934402)
			(xy 92.55828 -275.896308) (xy 92.531079 -275.853294) (xy 92.511131 -275.806474) (xy 92.498952 -275.75706)
			(xy 92.494857 -275.706332) (xy 92.176346 -275.706332) (xy 92.175851 -275.730939) (xy 92.167956 -275.779516)
			(xy 92.152372 -275.826197) (xy 92.129501 -275.869774) (xy 92.099936 -275.909118) (xy 92.064443 -275.94321)
			(xy 92.02394 -275.971166) (xy 91.979478 -275.992264) (xy 91.932207 -276.005956) (xy 91.883352 -276.011888)
			(xy 91.834177 -276.009907) (xy 91.785958 -276.000063) (xy 91.739942 -275.982611) (xy 91.697321 -275.958004)
			(xy 91.6592 -275.926879) (xy 91.626565 -275.890042) (xy 91.600262 -275.848446) (xy 91.580971 -275.80317)
			(xy 91.569194 -275.755386) (xy 91.565234 -275.706332) (xy 91.246706 -275.706332) (xy 91.246194 -275.731778)
			(xy 91.23803 -275.782012) (xy 91.221914 -275.830286) (xy 91.198263 -275.875349) (xy 91.16769 -275.916035)
			(xy 91.130986 -275.95129) (xy 91.089102 -275.9802) (xy 91.043123 -276.002017) (xy 90.994239 -276.016177)
			(xy 90.943718 -276.022311) (xy 90.892866 -276.020262) (xy 90.843002 -276.010082) (xy 90.795416 -275.992035)
			(xy 90.751342 -275.966589) (xy 90.71192 -275.934402) (xy 90.678172 -275.896308) (xy 90.650971 -275.853294)
			(xy 90.631023 -275.806474) (xy 90.618844 -275.75706) (xy 90.614749 -275.706332) (xy 90.296238 -275.706332)
			(xy 90.295743 -275.730939) (xy 90.287848 -275.779516) (xy 90.272264 -275.826197) (xy 90.249393 -275.869774)
			(xy 90.219828 -275.909118) (xy 90.184335 -275.94321) (xy 90.143832 -275.971166) (xy 90.09937 -275.992264)
			(xy 90.052099 -276.005956) (xy 90.003244 -276.011888) (xy 89.954069 -276.009907) (xy 89.90585 -276.000063)
			(xy 89.859834 -275.982611) (xy 89.817213 -275.958004) (xy 89.779092 -275.926879) (xy 89.746457 -275.890042)
			(xy 89.720154 -275.848446) (xy 89.700863 -275.80317) (xy 89.689086 -275.755386) (xy 89.685126 -275.706332)
			(xy 89.366852 -275.706332) (xy 89.36634 -275.731778) (xy 89.358176 -275.782012) (xy 89.34206 -275.830286)
			(xy 89.318409 -275.875349) (xy 89.287836 -275.916035) (xy 89.251132 -275.95129) (xy 89.209248 -275.9802)
			(xy 89.163269 -276.002017) (xy 89.114385 -276.016177) (xy 89.063864 -276.022311) (xy 89.013012 -276.020262)
			(xy 88.963148 -276.010082) (xy 88.915562 -275.992035) (xy 88.871488 -275.966589) (xy 88.832066 -275.934402)
			(xy 88.798318 -275.896308) (xy 88.771117 -275.853294) (xy 88.751169 -275.806474) (xy 88.73899 -275.75706)
			(xy 88.734895 -275.706332) (xy 88.426798 -275.706332) (xy 88.426286 -275.731778) (xy 88.418122 -275.782012)
			(xy 88.402006 -275.830286) (xy 88.378355 -275.875349) (xy 88.347782 -275.916035) (xy 88.311078 -275.95129)
			(xy 88.269194 -275.9802) (xy 88.223215 -276.002017) (xy 88.174331 -276.016177) (xy 88.12381 -276.022311)
			(xy 88.072958 -276.020262) (xy 88.023094 -276.010082) (xy 87.975508 -275.992035) (xy 87.931434 -275.966589)
			(xy 87.892012 -275.934402) (xy 87.858264 -275.896308) (xy 87.831063 -275.853294) (xy 87.811115 -275.806474)
			(xy 87.798936 -275.75706) (xy 87.794841 -275.706332) (xy 87.47633 -275.706332) (xy 87.475835 -275.730939)
			(xy 87.46794 -275.779516) (xy 87.452356 -275.826197) (xy 87.429485 -275.869774) (xy 87.39992 -275.909118)
			(xy 87.364427 -275.94321) (xy 87.323924 -275.971166) (xy 87.279462 -275.992264) (xy 87.232191 -276.005956)
			(xy 87.183336 -276.011888) (xy 87.134161 -276.009907) (xy 87.085942 -276.000063) (xy 87.039926 -275.982611)
			(xy 86.997305 -275.958004) (xy 86.959184 -275.926879) (xy 86.926549 -275.890042) (xy 86.900246 -275.848446)
			(xy 86.880955 -275.80317) (xy 86.869178 -275.755386) (xy 86.865218 -275.706332) (xy 86.54669 -275.706332)
			(xy 86.546178 -275.731778) (xy 86.538014 -275.782012) (xy 86.521898 -275.830286) (xy 86.498247 -275.875349)
			(xy 86.467674 -275.916035) (xy 86.43097 -275.95129) (xy 86.389086 -275.9802) (xy 86.343107 -276.002017)
			(xy 86.294223 -276.016177) (xy 86.243702 -276.022311) (xy 86.19285 -276.020262) (xy 86.142986 -276.010082)
			(xy 86.0954 -275.992035) (xy 86.051326 -275.966589) (xy 86.011904 -275.934402) (xy 85.978156 -275.896308)
			(xy 85.950955 -275.853294) (xy 85.931007 -275.806474) (xy 85.918828 -275.75706) (xy 85.914733 -275.706332)
			(xy 85.596222 -275.706332) (xy 85.595727 -275.730939) (xy 85.587832 -275.779516) (xy 85.572248 -275.826197)
			(xy 85.549377 -275.869774) (xy 85.519812 -275.909118) (xy 85.484319 -275.94321) (xy 85.443816 -275.971166)
			(xy 85.399354 -275.992264) (xy 85.352083 -276.005956) (xy 85.303228 -276.011888) (xy 85.254053 -276.009907)
			(xy 85.205834 -276.000063) (xy 85.159818 -275.982611) (xy 85.117197 -275.958004) (xy 85.079076 -275.926879)
			(xy 85.046441 -275.890042) (xy 85.020138 -275.848446) (xy 85.000847 -275.80317) (xy 84.98907 -275.755386)
			(xy 84.98511 -275.706332) (xy 84.666836 -275.706332) (xy 84.666324 -275.731778) (xy 84.65816 -275.782012)
			(xy 84.642044 -275.830286) (xy 84.618393 -275.875349) (xy 84.58782 -275.916035) (xy 84.551116 -275.95129)
			(xy 84.509232 -275.9802) (xy 84.463253 -276.002017) (xy 84.414369 -276.016177) (xy 84.363848 -276.022311)
			(xy 84.312996 -276.020262) (xy 84.263132 -276.010082) (xy 84.215546 -275.992035) (xy 84.171472 -275.966589)
			(xy 84.13205 -275.934402) (xy 84.098302 -275.896308) (xy 84.071101 -275.853294) (xy 84.051153 -275.806474)
			(xy 84.038974 -275.75706) (xy 84.034879 -275.706332) (xy 83.716368 -275.706332) (xy 83.715873 -275.730939)
			(xy 83.707978 -275.779516) (xy 83.692394 -275.826197) (xy 83.669523 -275.869774) (xy 83.639958 -275.909118)
			(xy 83.604465 -275.94321) (xy 83.563962 -275.971166) (xy 83.5195 -275.992264) (xy 83.472229 -276.005956)
			(xy 83.423374 -276.011888) (xy 83.374199 -276.009907) (xy 83.32598 -276.000063) (xy 83.279964 -275.982611)
			(xy 83.237343 -275.958004) (xy 83.199222 -275.926879) (xy 83.166587 -275.890042) (xy 83.140284 -275.848446)
			(xy 83.120993 -275.80317) (xy 83.109216 -275.755386) (xy 83.105256 -275.706332) (xy 82.786728 -275.706332)
			(xy 82.786216 -275.731778) (xy 82.778052 -275.782012) (xy 82.761936 -275.830286) (xy 82.738285 -275.875349)
			(xy 82.707712 -275.916035) (xy 82.671008 -275.95129) (xy 82.629124 -275.9802) (xy 82.583145 -276.002017)
			(xy 82.534261 -276.016177) (xy 82.48374 -276.022311) (xy 82.432888 -276.020262) (xy 82.383024 -276.010082)
			(xy 82.335438 -275.992035) (xy 82.291364 -275.966589) (xy 82.251942 -275.934402) (xy 82.218194 -275.896308)
			(xy 82.190993 -275.853294) (xy 82.171045 -275.806474) (xy 82.158866 -275.75706) (xy 82.154771 -275.706332)
			(xy 81.846674 -275.706332) (xy 81.846162 -275.731778) (xy 81.837998 -275.782012) (xy 81.821882 -275.830286)
			(xy 81.798231 -275.875349) (xy 81.767658 -275.916035) (xy 81.730954 -275.95129) (xy 81.68907 -275.9802)
			(xy 81.643091 -276.002017) (xy 81.594207 -276.016177) (xy 81.543686 -276.022311) (xy 81.492834 -276.020262)
			(xy 81.44297 -276.010082) (xy 81.395384 -275.992035) (xy 81.35131 -275.966589) (xy 81.311888 -275.934402)
			(xy 81.27814 -275.896308) (xy 81.250939 -275.853294) (xy 81.230991 -275.806474) (xy 81.218812 -275.75706)
			(xy 81.214717 -275.706332) (xy 80.89646 -275.706332) (xy 80.895965 -275.730939) (xy 80.88807 -275.779516)
			(xy 80.872486 -275.826197) (xy 80.849615 -275.869774) (xy 80.82005 -275.909118) (xy 80.784557 -275.94321)
			(xy 80.744054 -275.971166) (xy 80.699592 -275.992264) (xy 80.652321 -276.005956) (xy 80.603466 -276.011888)
			(xy 80.554291 -276.009907) (xy 80.506072 -276.000063) (xy 80.460056 -275.982611) (xy 80.417435 -275.958004)
			(xy 80.379314 -275.926879) (xy 80.346679 -275.890042) (xy 80.320376 -275.848446) (xy 80.301085 -275.80317)
			(xy 80.289308 -275.755386) (xy 80.285348 -275.706332) (xy 79.016352 -275.706332) (xy 79.015857 -275.730939)
			(xy 79.007962 -275.779516) (xy 78.992378 -275.826197) (xy 78.969507 -275.869774) (xy 78.939942 -275.909118)
			(xy 78.904449 -275.94321) (xy 78.863946 -275.971166) (xy 78.819484 -275.992264) (xy 78.772213 -276.005956)
			(xy 78.723358 -276.011888) (xy 78.674183 -276.009907) (xy 78.625964 -276.000063) (xy 78.579948 -275.982611)
			(xy 78.537327 -275.958004) (xy 78.499206 -275.926879) (xy 78.466571 -275.890042) (xy 78.440268 -275.848446)
			(xy 78.420977 -275.80317) (xy 78.4092 -275.755386) (xy 78.40524 -275.706332) (xy 73.228962 -275.706332)
			(xy 73.228962 -276.2504) (xy 76.807072 -276.2504) (xy 76.811032 -276.201346) (xy 76.822809 -276.153562)
			(xy 76.8421 -276.108286) (xy 76.868403 -276.06669) (xy 76.901038 -276.029853) (xy 76.939159 -275.998728)
			(xy 76.98178 -275.974121) (xy 77.027796 -275.956669) (xy 77.076015 -275.946825) (xy 77.12519 -275.944844)
			(xy 77.174045 -275.950776) (xy 77.221316 -275.964468) (xy 77.265778 -275.985566) (xy 77.306281 -276.013522)
			(xy 77.341774 -276.047614) (xy 77.371339 -276.086958) (xy 77.39421 -276.130535) (xy 77.409794 -276.177216)
			(xy 77.417689 -276.225793) (xy 77.418184 -276.2504) (xy 77.417689 -276.275007) (xy 77.409794 -276.323584)
			(xy 77.39421 -276.370265) (xy 77.371339 -276.413842) (xy 77.341774 -276.453186) (xy 77.306281 -276.487278)
			(xy 77.265778 -276.515234) (xy 77.263451 -276.516338) (xy 79.815194 -276.516338) (xy 79.819154 -276.467284)
			(xy 79.830931 -276.4195) (xy 79.850222 -276.374224) (xy 79.876525 -276.332628) (xy 79.90916 -276.295791)
			(xy 79.947281 -276.264666) (xy 79.989902 -276.240059) (xy 80.035918 -276.222607) (xy 80.084137 -276.212763)
			(xy 80.133312 -276.210782) (xy 80.182167 -276.216714) (xy 80.229438 -276.230406) (xy 80.2739 -276.251504)
			(xy 80.314403 -276.27946) (xy 80.349896 -276.313552) (xy 80.379461 -276.352896) (xy 80.402332 -276.396473)
			(xy 80.417916 -276.443154) (xy 80.425811 -276.491731) (xy 80.426306 -276.516338) (xy 80.744817 -276.516338)
			(xy 80.748912 -276.46561) (xy 80.761091 -276.416196) (xy 80.781039 -276.369376) (xy 80.80824 -276.326362)
			(xy 80.841988 -276.288268) (xy 80.88141 -276.256081) (xy 80.925484 -276.230635) (xy 80.97307 -276.212588)
			(xy 81.022934 -276.202408) (xy 81.073786 -276.200359) (xy 81.124307 -276.206493) (xy 81.173191 -276.220653)
			(xy 81.21917 -276.24247) (xy 81.261054 -276.27138) (xy 81.297758 -276.306635) (xy 81.328331 -276.347321)
			(xy 81.351982 -276.392384) (xy 81.368098 -276.440658) (xy 81.376262 -276.490892) (xy 81.376774 -276.516338)
			(xy 81.695302 -276.516338) (xy 81.699262 -276.467284) (xy 81.711039 -276.4195) (xy 81.73033 -276.374224)
			(xy 81.756633 -276.332628) (xy 81.789268 -276.295791) (xy 81.827389 -276.264666) (xy 81.87001 -276.240059)
			(xy 81.916026 -276.222607) (xy 81.964245 -276.212763) (xy 82.01342 -276.210782) (xy 82.062275 -276.216714)
			(xy 82.109546 -276.230406) (xy 82.154008 -276.251504) (xy 82.194511 -276.27946) (xy 82.230004 -276.313552)
			(xy 82.259569 -276.352896) (xy 82.28244 -276.396473) (xy 82.298024 -276.443154) (xy 82.305919 -276.491731)
			(xy 82.306414 -276.516338) (xy 82.624671 -276.516338) (xy 82.628766 -276.46561) (xy 82.640945 -276.416196)
			(xy 82.660893 -276.369376) (xy 82.688094 -276.326362) (xy 82.721842 -276.288268) (xy 82.761264 -276.256081)
			(xy 82.805338 -276.230635) (xy 82.852924 -276.212588) (xy 82.902788 -276.202408) (xy 82.95364 -276.200359)
			(xy 83.004161 -276.206493) (xy 83.053045 -276.220653) (xy 83.099024 -276.24247) (xy 83.140908 -276.27138)
			(xy 83.177612 -276.306635) (xy 83.208185 -276.347321) (xy 83.231836 -276.392384) (xy 83.247952 -276.440658)
			(xy 83.256116 -276.490892) (xy 83.256628 -276.516338) (xy 83.575156 -276.516338) (xy 83.579116 -276.467284)
			(xy 83.590893 -276.4195) (xy 83.610184 -276.374224) (xy 83.636487 -276.332628) (xy 83.669122 -276.295791)
			(xy 83.707243 -276.264666) (xy 83.749864 -276.240059) (xy 83.79588 -276.222607) (xy 83.844099 -276.212763)
			(xy 83.893274 -276.210782) (xy 83.942129 -276.216714) (xy 83.9894 -276.230406) (xy 84.033862 -276.251504)
			(xy 84.074365 -276.27946) (xy 84.109858 -276.313552) (xy 84.139423 -276.352896) (xy 84.162294 -276.396473)
			(xy 84.177878 -276.443154) (xy 84.185773 -276.491731) (xy 84.186268 -276.516338) (xy 84.504779 -276.516338)
			(xy 84.508874 -276.46561) (xy 84.521053 -276.416196) (xy 84.541001 -276.369376) (xy 84.568202 -276.326362)
			(xy 84.60195 -276.288268) (xy 84.641372 -276.256081) (xy 84.685446 -276.230635) (xy 84.733032 -276.212588)
			(xy 84.782896 -276.202408) (xy 84.833748 -276.200359) (xy 84.884269 -276.206493) (xy 84.933153 -276.220653)
			(xy 84.979132 -276.24247) (xy 85.021016 -276.27138) (xy 85.05772 -276.306635) (xy 85.088293 -276.347321)
			(xy 85.111944 -276.392384) (xy 85.12806 -276.440658) (xy 85.136224 -276.490892) (xy 85.136736 -276.516338)
			(xy 85.444833 -276.516338) (xy 85.448928 -276.46561) (xy 85.461107 -276.416196) (xy 85.481055 -276.369376)
			(xy 85.508256 -276.326362) (xy 85.542004 -276.288268) (xy 85.581426 -276.256081) (xy 85.6255 -276.230635)
			(xy 85.673086 -276.212588) (xy 85.72295 -276.202408) (xy 85.773802 -276.200359) (xy 85.824323 -276.206493)
			(xy 85.873207 -276.220653) (xy 85.919186 -276.24247) (xy 85.96107 -276.27138) (xy 85.997774 -276.306635)
			(xy 86.028347 -276.347321) (xy 86.051998 -276.392384) (xy 86.068114 -276.440658) (xy 86.076278 -276.490892)
			(xy 86.07679 -276.516338) (xy 86.395318 -276.516338) (xy 86.399278 -276.467284) (xy 86.411055 -276.4195)
			(xy 86.430346 -276.374224) (xy 86.456649 -276.332628) (xy 86.489284 -276.295791) (xy 86.527405 -276.264666)
			(xy 86.570026 -276.240059) (xy 86.616042 -276.222607) (xy 86.664261 -276.212763) (xy 86.713436 -276.210782)
			(xy 86.762291 -276.216714) (xy 86.809562 -276.230406) (xy 86.854024 -276.251504) (xy 86.894527 -276.27946)
			(xy 86.93002 -276.313552) (xy 86.959585 -276.352896) (xy 86.982456 -276.396473) (xy 86.99804 -276.443154)
			(xy 87.005935 -276.491731) (xy 87.00643 -276.516338) (xy 87.324687 -276.516338) (xy 87.328782 -276.46561)
			(xy 87.340961 -276.416196) (xy 87.360909 -276.369376) (xy 87.38811 -276.326362) (xy 87.421858 -276.288268)
			(xy 87.46128 -276.256081) (xy 87.505354 -276.230635) (xy 87.55294 -276.212588) (xy 87.602804 -276.202408)
			(xy 87.653656 -276.200359) (xy 87.704177 -276.206493) (xy 87.753061 -276.220653) (xy 87.79904 -276.24247)
			(xy 87.840924 -276.27138) (xy 87.877628 -276.306635) (xy 87.908201 -276.347321) (xy 87.931852 -276.392384)
			(xy 87.947968 -276.440658) (xy 87.956132 -276.490892) (xy 87.956644 -276.516338) (xy 88.275172 -276.516338)
			(xy 88.279132 -276.467284) (xy 88.290909 -276.4195) (xy 88.3102 -276.374224) (xy 88.336503 -276.332628)
			(xy 88.369138 -276.295791) (xy 88.407259 -276.264666) (xy 88.44988 -276.240059) (xy 88.495896 -276.222607)
			(xy 88.544115 -276.212763) (xy 88.59329 -276.210782) (xy 88.642145 -276.216714) (xy 88.689416 -276.230406)
			(xy 88.733878 -276.251504) (xy 88.774381 -276.27946) (xy 88.809874 -276.313552) (xy 88.839439 -276.352896)
			(xy 88.86231 -276.396473) (xy 88.877894 -276.443154) (xy 88.885789 -276.491731) (xy 88.886284 -276.516338)
			(xy 89.204795 -276.516338) (xy 89.20889 -276.46561) (xy 89.221069 -276.416196) (xy 89.241017 -276.369376)
			(xy 89.268218 -276.326362) (xy 89.301966 -276.288268) (xy 89.341388 -276.256081) (xy 89.385462 -276.230635)
			(xy 89.433048 -276.212588) (xy 89.482912 -276.202408) (xy 89.533764 -276.200359) (xy 89.584285 -276.206493)
			(xy 89.633169 -276.220653) (xy 89.679148 -276.24247) (xy 89.721032 -276.27138) (xy 89.757736 -276.306635)
			(xy 89.788309 -276.347321) (xy 89.81196 -276.392384) (xy 89.828076 -276.440658) (xy 89.83624 -276.490892)
			(xy 89.836752 -276.516338) (xy 90.15528 -276.516338) (xy 90.15924 -276.467284) (xy 90.171017 -276.4195)
			(xy 90.190308 -276.374224) (xy 90.216611 -276.332628) (xy 90.249246 -276.295791) (xy 90.287367 -276.264666)
			(xy 90.329988 -276.240059) (xy 90.376004 -276.222607) (xy 90.424223 -276.212763) (xy 90.473398 -276.210782)
			(xy 90.522253 -276.216714) (xy 90.569524 -276.230406) (xy 90.613986 -276.251504) (xy 90.654489 -276.27946)
			(xy 90.689982 -276.313552) (xy 90.719547 -276.352896) (xy 90.742418 -276.396473) (xy 90.758002 -276.443154)
			(xy 90.765897 -276.491731) (xy 90.766392 -276.516338) (xy 91.084903 -276.516338) (xy 91.088998 -276.46561)
			(xy 91.101177 -276.416196) (xy 91.121125 -276.369376) (xy 91.148326 -276.326362) (xy 91.182074 -276.288268)
			(xy 91.221496 -276.256081) (xy 91.26557 -276.230635) (xy 91.313156 -276.212588) (xy 91.36302 -276.202408)
			(xy 91.413872 -276.200359) (xy 91.464393 -276.206493) (xy 91.513277 -276.220653) (xy 91.559256 -276.24247)
			(xy 91.60114 -276.27138) (xy 91.637844 -276.306635) (xy 91.668417 -276.347321) (xy 91.692068 -276.392384)
			(xy 91.708184 -276.440658) (xy 91.716348 -276.490892) (xy 91.71686 -276.516338) (xy 92.024703 -276.516338)
			(xy 92.028798 -276.46561) (xy 92.040977 -276.416196) (xy 92.060925 -276.369376) (xy 92.088126 -276.326362)
			(xy 92.121874 -276.288268) (xy 92.161296 -276.256081) (xy 92.20537 -276.230635) (xy 92.252956 -276.212588)
			(xy 92.30282 -276.202408) (xy 92.353672 -276.200359) (xy 92.404193 -276.206493) (xy 92.453077 -276.220653)
			(xy 92.499056 -276.24247) (xy 92.54094 -276.27138) (xy 92.577644 -276.306635) (xy 92.608217 -276.347321)
			(xy 92.631868 -276.392384) (xy 92.647984 -276.440658) (xy 92.656148 -276.490892) (xy 92.65666 -276.516338)
			(xy 92.975188 -276.516338) (xy 92.979148 -276.467284) (xy 92.990925 -276.4195) (xy 93.010216 -276.374224)
			(xy 93.036519 -276.332628) (xy 93.069154 -276.295791) (xy 93.107275 -276.264666) (xy 93.149896 -276.240059)
			(xy 93.195912 -276.222607) (xy 93.244131 -276.212763) (xy 93.293306 -276.210782) (xy 93.342161 -276.216714)
			(xy 93.389432 -276.230406) (xy 93.433894 -276.251504) (xy 93.474397 -276.27946) (xy 93.50989 -276.313552)
			(xy 93.539455 -276.352896) (xy 93.562326 -276.396473) (xy 93.57791 -276.443154) (xy 93.585805 -276.491731)
			(xy 93.5863 -276.516338) (xy 93.904811 -276.516338) (xy 93.908906 -276.46561) (xy 93.921085 -276.416196)
			(xy 93.941033 -276.369376) (xy 93.968234 -276.326362) (xy 94.001982 -276.288268) (xy 94.041404 -276.256081)
			(xy 94.085478 -276.230635) (xy 94.133064 -276.212588) (xy 94.182928 -276.202408) (xy 94.23378 -276.200359)
			(xy 94.284301 -276.206493) (xy 94.333185 -276.220653) (xy 94.379164 -276.24247) (xy 94.421048 -276.27138)
			(xy 94.457752 -276.306635) (xy 94.488325 -276.347321) (xy 94.511976 -276.392384) (xy 94.528092 -276.440658)
			(xy 94.536256 -276.490892) (xy 94.536768 -276.516338) (xy 94.855296 -276.516338) (xy 94.859256 -276.467284)
			(xy 94.871033 -276.4195) (xy 94.890324 -276.374224) (xy 94.916627 -276.332628) (xy 94.949262 -276.295791)
			(xy 94.987383 -276.264666) (xy 95.030004 -276.240059) (xy 95.07602 -276.222607) (xy 95.124239 -276.212763)
			(xy 95.173414 -276.210782) (xy 95.222269 -276.216714) (xy 95.26954 -276.230406) (xy 95.314002 -276.251504)
			(xy 95.354505 -276.27946) (xy 95.389998 -276.313552) (xy 95.419563 -276.352896) (xy 95.442434 -276.396473)
			(xy 95.458018 -276.443154) (xy 95.465913 -276.491731) (xy 95.466408 -276.516338) (xy 95.784919 -276.516338)
			(xy 95.789014 -276.46561) (xy 95.801193 -276.416196) (xy 95.821141 -276.369376) (xy 95.848342 -276.326362)
			(xy 95.88209 -276.288268) (xy 95.921512 -276.256081) (xy 95.965586 -276.230635) (xy 96.013172 -276.212588)
			(xy 96.063036 -276.202408) (xy 96.113888 -276.200359) (xy 96.164409 -276.206493) (xy 96.213293 -276.220653)
			(xy 96.259272 -276.24247) (xy 96.301156 -276.27138) (xy 96.33786 -276.306635) (xy 96.368433 -276.347321)
			(xy 96.392084 -276.392384) (xy 96.4082 -276.440658) (xy 96.416364 -276.490892) (xy 96.416876 -276.516338)
			(xy 96.73515 -276.516338) (xy 96.73911 -276.467284) (xy 96.750887 -276.4195) (xy 96.770178 -276.374224)
			(xy 96.796481 -276.332628) (xy 96.829116 -276.295791) (xy 96.867237 -276.264666) (xy 96.909858 -276.240059)
			(xy 96.955874 -276.222607) (xy 97.004093 -276.212763) (xy 97.053268 -276.210782) (xy 97.102123 -276.216714)
			(xy 97.149394 -276.230406) (xy 97.193856 -276.251504) (xy 97.234359 -276.27946) (xy 97.269852 -276.313552)
			(xy 97.299417 -276.352896) (xy 97.322288 -276.396473) (xy 97.337872 -276.443154) (xy 97.345767 -276.491731)
			(xy 97.346262 -276.516338) (xy 97.664773 -276.516338) (xy 97.668868 -276.46561) (xy 97.681047 -276.416196)
			(xy 97.700995 -276.369376) (xy 97.728196 -276.326362) (xy 97.761944 -276.288268) (xy 97.801366 -276.256081)
			(xy 97.84544 -276.230635) (xy 97.893026 -276.212588) (xy 97.94289 -276.202408) (xy 97.993742 -276.200359)
			(xy 98.044263 -276.206493) (xy 98.093147 -276.220653) (xy 98.139126 -276.24247) (xy 98.18101 -276.27138)
			(xy 98.217714 -276.306635) (xy 98.248287 -276.347321) (xy 98.271938 -276.392384) (xy 98.288054 -276.440658)
			(xy 98.296218 -276.490892) (xy 98.29673 -276.516338) (xy 98.604827 -276.516338) (xy 98.608922 -276.46561)
			(xy 98.621101 -276.416196) (xy 98.641049 -276.369376) (xy 98.66825 -276.326362) (xy 98.701998 -276.288268)
			(xy 98.74142 -276.256081) (xy 98.785494 -276.230635) (xy 98.83308 -276.212588) (xy 98.882944 -276.202408)
			(xy 98.933796 -276.200359) (xy 98.984317 -276.206493) (xy 99.033201 -276.220653) (xy 99.07918 -276.24247)
			(xy 99.121064 -276.27138) (xy 99.157768 -276.306635) (xy 99.188341 -276.347321) (xy 99.211992 -276.392384)
			(xy 99.228108 -276.440658) (xy 99.236272 -276.490892) (xy 99.236784 -276.516338) (xy 99.555312 -276.516338)
			(xy 99.559272 -276.467284) (xy 99.571049 -276.4195) (xy 99.59034 -276.374224) (xy 99.616643 -276.332628)
			(xy 99.649278 -276.295791) (xy 99.687399 -276.264666) (xy 99.73002 -276.240059) (xy 99.776036 -276.222607)
			(xy 99.824255 -276.212763) (xy 99.87343 -276.210782) (xy 99.922285 -276.216714) (xy 99.969556 -276.230406)
			(xy 100.014018 -276.251504) (xy 100.054521 -276.27946) (xy 100.090014 -276.313552) (xy 100.119579 -276.352896)
			(xy 100.14245 -276.396473) (xy 100.158034 -276.443154) (xy 100.165929 -276.491731) (xy 100.166424 -276.516338)
			(xy 100.484935 -276.516338) (xy 100.48903 -276.46561) (xy 100.501209 -276.416196) (xy 100.521157 -276.369376)
			(xy 100.548358 -276.326362) (xy 100.582106 -276.288268) (xy 100.621528 -276.256081) (xy 100.665602 -276.230635)
			(xy 100.713188 -276.212588) (xy 100.763052 -276.202408) (xy 100.813904 -276.200359) (xy 100.864425 -276.206493)
			(xy 100.913309 -276.220653) (xy 100.959288 -276.24247) (xy 101.001172 -276.27138) (xy 101.037876 -276.306635)
			(xy 101.068449 -276.347321) (xy 101.0921 -276.392384) (xy 101.108216 -276.440658) (xy 101.11638 -276.490892)
			(xy 101.116892 -276.516338) (xy 101.424735 -276.516338) (xy 101.42883 -276.46561) (xy 101.441009 -276.416196)
			(xy 101.460957 -276.369376) (xy 101.488158 -276.326362) (xy 101.521906 -276.288268) (xy 101.561328 -276.256081)
			(xy 101.605402 -276.230635) (xy 101.652988 -276.212588) (xy 101.702852 -276.202408) (xy 101.753704 -276.200359)
			(xy 101.804225 -276.206493) (xy 101.853109 -276.220653) (xy 101.899088 -276.24247) (xy 101.940972 -276.27138)
			(xy 101.977676 -276.306635) (xy 102.008249 -276.347321) (xy 102.0319 -276.392384) (xy 102.048016 -276.440658)
			(xy 102.05618 -276.490892) (xy 102.056692 -276.516338) (xy 102.05618 -276.541784) (xy 102.048016 -276.592018)
			(xy 102.0319 -276.640292) (xy 102.008249 -276.685355) (xy 101.977676 -276.726041) (xy 101.940972 -276.761296)
			(xy 101.899088 -276.790206) (xy 101.853109 -276.812023) (xy 101.804225 -276.826183) (xy 101.753704 -276.832317)
			(xy 101.702852 -276.830268) (xy 101.652988 -276.820088) (xy 101.605402 -276.802041) (xy 101.561328 -276.776595)
			(xy 101.521906 -276.744408) (xy 101.488158 -276.706314) (xy 101.460957 -276.6633) (xy 101.441009 -276.61648)
			(xy 101.42883 -276.567066) (xy 101.424735 -276.516338) (xy 101.116892 -276.516338) (xy 101.11638 -276.541784)
			(xy 101.108216 -276.592018) (xy 101.0921 -276.640292) (xy 101.068449 -276.685355) (xy 101.037876 -276.726041)
			(xy 101.001172 -276.761296) (xy 100.959288 -276.790206) (xy 100.913309 -276.812023) (xy 100.864425 -276.826183)
			(xy 100.813904 -276.832317) (xy 100.763052 -276.830268) (xy 100.713188 -276.820088) (xy 100.665602 -276.802041)
			(xy 100.621528 -276.776595) (xy 100.582106 -276.744408) (xy 100.548358 -276.706314) (xy 100.521157 -276.6633)
			(xy 100.501209 -276.61648) (xy 100.48903 -276.567066) (xy 100.484935 -276.516338) (xy 100.166424 -276.516338)
			(xy 100.165929 -276.540945) (xy 100.158034 -276.589522) (xy 100.14245 -276.636203) (xy 100.119579 -276.67978)
			(xy 100.090014 -276.719124) (xy 100.054521 -276.753216) (xy 100.014018 -276.781172) (xy 99.969556 -276.80227)
			(xy 99.922285 -276.815962) (xy 99.87343 -276.821894) (xy 99.824255 -276.819913) (xy 99.776036 -276.810069)
			(xy 99.73002 -276.792617) (xy 99.687399 -276.76801) (xy 99.649278 -276.736885) (xy 99.616643 -276.700048)
			(xy 99.59034 -276.658452) (xy 99.571049 -276.613176) (xy 99.559272 -276.565392) (xy 99.555312 -276.516338)
			(xy 99.236784 -276.516338) (xy 99.236272 -276.541784) (xy 99.228108 -276.592018) (xy 99.211992 -276.640292)
			(xy 99.188341 -276.685355) (xy 99.157768 -276.726041) (xy 99.121064 -276.761296) (xy 99.07918 -276.790206)
			(xy 99.033201 -276.812023) (xy 98.984317 -276.826183) (xy 98.933796 -276.832317) (xy 98.882944 -276.830268)
			(xy 98.83308 -276.820088) (xy 98.785494 -276.802041) (xy 98.74142 -276.776595) (xy 98.701998 -276.744408)
			(xy 98.66825 -276.706314) (xy 98.641049 -276.6633) (xy 98.621101 -276.61648) (xy 98.608922 -276.567066)
			(xy 98.604827 -276.516338) (xy 98.29673 -276.516338) (xy 98.296218 -276.541784) (xy 98.288054 -276.592018)
			(xy 98.271938 -276.640292) (xy 98.248287 -276.685355) (xy 98.217714 -276.726041) (xy 98.18101 -276.761296)
			(xy 98.139126 -276.790206) (xy 98.093147 -276.812023) (xy 98.044263 -276.826183) (xy 97.993742 -276.832317)
			(xy 97.94289 -276.830268) (xy 97.893026 -276.820088) (xy 97.84544 -276.802041) (xy 97.801366 -276.776595)
			(xy 97.761944 -276.744408) (xy 97.728196 -276.706314) (xy 97.700995 -276.6633) (xy 97.681047 -276.61648)
			(xy 97.668868 -276.567066) (xy 97.664773 -276.516338) (xy 97.346262 -276.516338) (xy 97.345767 -276.540945)
			(xy 97.337872 -276.589522) (xy 97.322288 -276.636203) (xy 97.299417 -276.67978) (xy 97.269852 -276.719124)
			(xy 97.234359 -276.753216) (xy 97.193856 -276.781172) (xy 97.149394 -276.80227) (xy 97.102123 -276.815962)
			(xy 97.053268 -276.821894) (xy 97.004093 -276.819913) (xy 96.955874 -276.810069) (xy 96.909858 -276.792617)
			(xy 96.867237 -276.76801) (xy 96.829116 -276.736885) (xy 96.796481 -276.700048) (xy 96.770178 -276.658452)
			(xy 96.750887 -276.613176) (xy 96.73911 -276.565392) (xy 96.73515 -276.516338) (xy 96.416876 -276.516338)
			(xy 96.416364 -276.541784) (xy 96.4082 -276.592018) (xy 96.392084 -276.640292) (xy 96.368433 -276.685355)
			(xy 96.33786 -276.726041) (xy 96.301156 -276.761296) (xy 96.259272 -276.790206) (xy 96.213293 -276.812023)
			(xy 96.164409 -276.826183) (xy 96.113888 -276.832317) (xy 96.063036 -276.830268) (xy 96.013172 -276.820088)
			(xy 95.965586 -276.802041) (xy 95.921512 -276.776595) (xy 95.88209 -276.744408) (xy 95.848342 -276.706314)
			(xy 95.821141 -276.6633) (xy 95.801193 -276.61648) (xy 95.789014 -276.567066) (xy 95.784919 -276.516338)
			(xy 95.466408 -276.516338) (xy 95.465913 -276.540945) (xy 95.458018 -276.589522) (xy 95.442434 -276.636203)
			(xy 95.419563 -276.67978) (xy 95.389998 -276.719124) (xy 95.354505 -276.753216) (xy 95.314002 -276.781172)
			(xy 95.26954 -276.80227) (xy 95.222269 -276.815962) (xy 95.173414 -276.821894) (xy 95.124239 -276.819913)
			(xy 95.07602 -276.810069) (xy 95.030004 -276.792617) (xy 94.987383 -276.76801) (xy 94.949262 -276.736885)
			(xy 94.916627 -276.700048) (xy 94.890324 -276.658452) (xy 94.871033 -276.613176) (xy 94.859256 -276.565392)
			(xy 94.855296 -276.516338) (xy 94.536768 -276.516338) (xy 94.536256 -276.541784) (xy 94.528092 -276.592018)
			(xy 94.511976 -276.640292) (xy 94.488325 -276.685355) (xy 94.457752 -276.726041) (xy 94.421048 -276.761296)
			(xy 94.379164 -276.790206) (xy 94.333185 -276.812023) (xy 94.284301 -276.826183) (xy 94.23378 -276.832317)
			(xy 94.182928 -276.830268) (xy 94.133064 -276.820088) (xy 94.085478 -276.802041) (xy 94.041404 -276.776595)
			(xy 94.001982 -276.744408) (xy 93.968234 -276.706314) (xy 93.941033 -276.6633) (xy 93.921085 -276.61648)
			(xy 93.908906 -276.567066) (xy 93.904811 -276.516338) (xy 93.5863 -276.516338) (xy 93.585805 -276.540945)
			(xy 93.57791 -276.589522) (xy 93.562326 -276.636203) (xy 93.539455 -276.67978) (xy 93.50989 -276.719124)
			(xy 93.474397 -276.753216) (xy 93.433894 -276.781172) (xy 93.389432 -276.80227) (xy 93.342161 -276.815962)
			(xy 93.293306 -276.821894) (xy 93.244131 -276.819913) (xy 93.195912 -276.810069) (xy 93.149896 -276.792617)
			(xy 93.107275 -276.76801) (xy 93.069154 -276.736885) (xy 93.036519 -276.700048) (xy 93.010216 -276.658452)
			(xy 92.990925 -276.613176) (xy 92.979148 -276.565392) (xy 92.975188 -276.516338) (xy 92.65666 -276.516338)
			(xy 92.656148 -276.541784) (xy 92.647984 -276.592018) (xy 92.631868 -276.640292) (xy 92.608217 -276.685355)
			(xy 92.577644 -276.726041) (xy 92.54094 -276.761296) (xy 92.499056 -276.790206) (xy 92.453077 -276.812023)
			(xy 92.404193 -276.826183) (xy 92.353672 -276.832317) (xy 92.30282 -276.830268) (xy 92.252956 -276.820088)
			(xy 92.20537 -276.802041) (xy 92.161296 -276.776595) (xy 92.121874 -276.744408) (xy 92.088126 -276.706314)
			(xy 92.060925 -276.6633) (xy 92.040977 -276.61648) (xy 92.028798 -276.567066) (xy 92.024703 -276.516338)
			(xy 91.71686 -276.516338) (xy 91.716348 -276.541784) (xy 91.708184 -276.592018) (xy 91.692068 -276.640292)
			(xy 91.668417 -276.685355) (xy 91.637844 -276.726041) (xy 91.60114 -276.761296) (xy 91.559256 -276.790206)
			(xy 91.513277 -276.812023) (xy 91.464393 -276.826183) (xy 91.413872 -276.832317) (xy 91.36302 -276.830268)
			(xy 91.313156 -276.820088) (xy 91.26557 -276.802041) (xy 91.221496 -276.776595) (xy 91.182074 -276.744408)
			(xy 91.148326 -276.706314) (xy 91.121125 -276.6633) (xy 91.101177 -276.61648) (xy 91.088998 -276.567066)
			(xy 91.084903 -276.516338) (xy 90.766392 -276.516338) (xy 90.765897 -276.540945) (xy 90.758002 -276.589522)
			(xy 90.742418 -276.636203) (xy 90.719547 -276.67978) (xy 90.689982 -276.719124) (xy 90.654489 -276.753216)
			(xy 90.613986 -276.781172) (xy 90.569524 -276.80227) (xy 90.522253 -276.815962) (xy 90.473398 -276.821894)
			(xy 90.424223 -276.819913) (xy 90.376004 -276.810069) (xy 90.329988 -276.792617) (xy 90.287367 -276.76801)
			(xy 90.249246 -276.736885) (xy 90.216611 -276.700048) (xy 90.190308 -276.658452) (xy 90.171017 -276.613176)
			(xy 90.15924 -276.565392) (xy 90.15528 -276.516338) (xy 89.836752 -276.516338) (xy 89.83624 -276.541784)
			(xy 89.828076 -276.592018) (xy 89.81196 -276.640292) (xy 89.788309 -276.685355) (xy 89.757736 -276.726041)
			(xy 89.721032 -276.761296) (xy 89.679148 -276.790206) (xy 89.633169 -276.812023) (xy 89.584285 -276.826183)
			(xy 89.533764 -276.832317) (xy 89.482912 -276.830268) (xy 89.433048 -276.820088) (xy 89.385462 -276.802041)
			(xy 89.341388 -276.776595) (xy 89.301966 -276.744408) (xy 89.268218 -276.706314) (xy 89.241017 -276.6633)
			(xy 89.221069 -276.61648) (xy 89.20889 -276.567066) (xy 89.204795 -276.516338) (xy 88.886284 -276.516338)
			(xy 88.885789 -276.540945) (xy 88.877894 -276.589522) (xy 88.86231 -276.636203) (xy 88.839439 -276.67978)
			(xy 88.809874 -276.719124) (xy 88.774381 -276.753216) (xy 88.733878 -276.781172) (xy 88.689416 -276.80227)
			(xy 88.642145 -276.815962) (xy 88.59329 -276.821894) (xy 88.544115 -276.819913) (xy 88.495896 -276.810069)
			(xy 88.44988 -276.792617) (xy 88.407259 -276.76801) (xy 88.369138 -276.736885) (xy 88.336503 -276.700048)
			(xy 88.3102 -276.658452) (xy 88.290909 -276.613176) (xy 88.279132 -276.565392) (xy 88.275172 -276.516338)
			(xy 87.956644 -276.516338) (xy 87.956132 -276.541784) (xy 87.947968 -276.592018) (xy 87.931852 -276.640292)
			(xy 87.908201 -276.685355) (xy 87.877628 -276.726041) (xy 87.840924 -276.761296) (xy 87.79904 -276.790206)
			(xy 87.753061 -276.812023) (xy 87.704177 -276.826183) (xy 87.653656 -276.832317) (xy 87.602804 -276.830268)
			(xy 87.55294 -276.820088) (xy 87.505354 -276.802041) (xy 87.46128 -276.776595) (xy 87.421858 -276.744408)
			(xy 87.38811 -276.706314) (xy 87.360909 -276.6633) (xy 87.340961 -276.61648) (xy 87.328782 -276.567066)
			(xy 87.324687 -276.516338) (xy 87.00643 -276.516338) (xy 87.005935 -276.540945) (xy 86.99804 -276.589522)
			(xy 86.982456 -276.636203) (xy 86.959585 -276.67978) (xy 86.93002 -276.719124) (xy 86.894527 -276.753216)
			(xy 86.854024 -276.781172) (xy 86.809562 -276.80227) (xy 86.762291 -276.815962) (xy 86.713436 -276.821894)
			(xy 86.664261 -276.819913) (xy 86.616042 -276.810069) (xy 86.570026 -276.792617) (xy 86.527405 -276.76801)
			(xy 86.489284 -276.736885) (xy 86.456649 -276.700048) (xy 86.430346 -276.658452) (xy 86.411055 -276.613176)
			(xy 86.399278 -276.565392) (xy 86.395318 -276.516338) (xy 86.07679 -276.516338) (xy 86.076278 -276.541784)
			(xy 86.068114 -276.592018) (xy 86.051998 -276.640292) (xy 86.028347 -276.685355) (xy 85.997774 -276.726041)
			(xy 85.96107 -276.761296) (xy 85.919186 -276.790206) (xy 85.873207 -276.812023) (xy 85.824323 -276.826183)
			(xy 85.773802 -276.832317) (xy 85.72295 -276.830268) (xy 85.673086 -276.820088) (xy 85.6255 -276.802041)
			(xy 85.581426 -276.776595) (xy 85.542004 -276.744408) (xy 85.508256 -276.706314) (xy 85.481055 -276.6633)
			(xy 85.461107 -276.61648) (xy 85.448928 -276.567066) (xy 85.444833 -276.516338) (xy 85.136736 -276.516338)
			(xy 85.136224 -276.541784) (xy 85.12806 -276.592018) (xy 85.111944 -276.640292) (xy 85.088293 -276.685355)
			(xy 85.05772 -276.726041) (xy 85.021016 -276.761296) (xy 84.979132 -276.790206) (xy 84.933153 -276.812023)
			(xy 84.884269 -276.826183) (xy 84.833748 -276.832317) (xy 84.782896 -276.830268) (xy 84.733032 -276.820088)
			(xy 84.685446 -276.802041) (xy 84.641372 -276.776595) (xy 84.60195 -276.744408) (xy 84.568202 -276.706314)
			(xy 84.541001 -276.6633) (xy 84.521053 -276.61648) (xy 84.508874 -276.567066) (xy 84.504779 -276.516338)
			(xy 84.186268 -276.516338) (xy 84.185773 -276.540945) (xy 84.177878 -276.589522) (xy 84.162294 -276.636203)
			(xy 84.139423 -276.67978) (xy 84.109858 -276.719124) (xy 84.074365 -276.753216) (xy 84.033862 -276.781172)
			(xy 83.9894 -276.80227) (xy 83.942129 -276.815962) (xy 83.893274 -276.821894) (xy 83.844099 -276.819913)
			(xy 83.79588 -276.810069) (xy 83.749864 -276.792617) (xy 83.707243 -276.76801) (xy 83.669122 -276.736885)
			(xy 83.636487 -276.700048) (xy 83.610184 -276.658452) (xy 83.590893 -276.613176) (xy 83.579116 -276.565392)
			(xy 83.575156 -276.516338) (xy 83.256628 -276.516338) (xy 83.256116 -276.541784) (xy 83.247952 -276.592018)
			(xy 83.231836 -276.640292) (xy 83.208185 -276.685355) (xy 83.177612 -276.726041) (xy 83.140908 -276.761296)
			(xy 83.099024 -276.790206) (xy 83.053045 -276.812023) (xy 83.004161 -276.826183) (xy 82.95364 -276.832317)
			(xy 82.902788 -276.830268) (xy 82.852924 -276.820088) (xy 82.805338 -276.802041) (xy 82.761264 -276.776595)
			(xy 82.721842 -276.744408) (xy 82.688094 -276.706314) (xy 82.660893 -276.6633) (xy 82.640945 -276.61648)
			(xy 82.628766 -276.567066) (xy 82.624671 -276.516338) (xy 82.306414 -276.516338) (xy 82.305919 -276.540945)
			(xy 82.298024 -276.589522) (xy 82.28244 -276.636203) (xy 82.259569 -276.67978) (xy 82.230004 -276.719124)
			(xy 82.194511 -276.753216) (xy 82.154008 -276.781172) (xy 82.109546 -276.80227) (xy 82.062275 -276.815962)
			(xy 82.01342 -276.821894) (xy 81.964245 -276.819913) (xy 81.916026 -276.810069) (xy 81.87001 -276.792617)
			(xy 81.827389 -276.76801) (xy 81.789268 -276.736885) (xy 81.756633 -276.700048) (xy 81.73033 -276.658452)
			(xy 81.711039 -276.613176) (xy 81.699262 -276.565392) (xy 81.695302 -276.516338) (xy 81.376774 -276.516338)
			(xy 81.376262 -276.541784) (xy 81.368098 -276.592018) (xy 81.351982 -276.640292) (xy 81.328331 -276.685355)
			(xy 81.297758 -276.726041) (xy 81.261054 -276.761296) (xy 81.21917 -276.790206) (xy 81.173191 -276.812023)
			(xy 81.124307 -276.826183) (xy 81.073786 -276.832317) (xy 81.022934 -276.830268) (xy 80.97307 -276.820088)
			(xy 80.925484 -276.802041) (xy 80.88141 -276.776595) (xy 80.841988 -276.744408) (xy 80.80824 -276.706314)
			(xy 80.781039 -276.6633) (xy 80.761091 -276.61648) (xy 80.748912 -276.567066) (xy 80.744817 -276.516338)
			(xy 80.426306 -276.516338) (xy 80.425811 -276.540945) (xy 80.417916 -276.589522) (xy 80.402332 -276.636203)
			(xy 80.379461 -276.67978) (xy 80.349896 -276.719124) (xy 80.314403 -276.753216) (xy 80.2739 -276.781172)
			(xy 80.229438 -276.80227) (xy 80.182167 -276.815962) (xy 80.133312 -276.821894) (xy 80.084137 -276.819913)
			(xy 80.035918 -276.810069) (xy 79.989902 -276.792617) (xy 79.947281 -276.76801) (xy 79.90916 -276.736885)
			(xy 79.876525 -276.700048) (xy 79.850222 -276.658452) (xy 79.830931 -276.613176) (xy 79.819154 -276.565392)
			(xy 79.815194 -276.516338) (xy 77.263451 -276.516338) (xy 77.221316 -276.536332) (xy 77.174045 -276.550024)
			(xy 77.12519 -276.555956) (xy 77.076015 -276.553975) (xy 77.027796 -276.544131) (xy 76.98178 -276.526679)
			(xy 76.939159 -276.502072) (xy 76.901038 -276.470947) (xy 76.868403 -276.43411) (xy 76.8421 -276.392514)
			(xy 76.822809 -276.347238) (xy 76.811032 -276.299454) (xy 76.807072 -276.2504) (xy 73.228962 -276.2504)
			(xy 73.228962 -277.326344) (xy 78.40524 -277.326344) (xy 78.4092 -277.27729) (xy 78.420977 -277.229506)
			(xy 78.440268 -277.18423) (xy 78.466571 -277.142634) (xy 78.499206 -277.105797) (xy 78.537327 -277.074672)
			(xy 78.579948 -277.050065) (xy 78.625964 -277.032613) (xy 78.674183 -277.022769) (xy 78.723358 -277.020788)
			(xy 78.772213 -277.02672) (xy 78.819484 -277.040412) (xy 78.863946 -277.06151) (xy 78.904449 -277.089466)
			(xy 78.939942 -277.123558) (xy 78.969507 -277.162902) (xy 78.992378 -277.206479) (xy 79.007962 -277.25316)
			(xy 79.015857 -277.301737) (xy 79.016352 -277.326344) (xy 80.285348 -277.326344) (xy 80.289308 -277.27729)
			(xy 80.301085 -277.229506) (xy 80.320376 -277.18423) (xy 80.346679 -277.142634) (xy 80.379314 -277.105797)
			(xy 80.417435 -277.074672) (xy 80.460056 -277.050065) (xy 80.506072 -277.032613) (xy 80.554291 -277.022769)
			(xy 80.603466 -277.020788) (xy 80.652321 -277.02672) (xy 80.699592 -277.040412) (xy 80.744054 -277.06151)
			(xy 80.784557 -277.089466) (xy 80.82005 -277.123558) (xy 80.849615 -277.162902) (xy 80.872486 -277.206479)
			(xy 80.88807 -277.25316) (xy 80.895965 -277.301737) (xy 80.89646 -277.326344) (xy 81.214717 -277.326344)
			(xy 81.218812 -277.275616) (xy 81.230991 -277.226202) (xy 81.250939 -277.179382) (xy 81.27814 -277.136368)
			(xy 81.311888 -277.098274) (xy 81.35131 -277.066087) (xy 81.395384 -277.040641) (xy 81.44297 -277.022594)
			(xy 81.492834 -277.012414) (xy 81.543686 -277.010365) (xy 81.594207 -277.016499) (xy 81.643091 -277.030659)
			(xy 81.68907 -277.052476) (xy 81.730954 -277.081386) (xy 81.767658 -277.116641) (xy 81.798231 -277.157327)
			(xy 81.821882 -277.20239) (xy 81.837998 -277.250664) (xy 81.846162 -277.300898) (xy 81.846674 -277.326344)
			(xy 82.154771 -277.326344) (xy 82.158866 -277.275616) (xy 82.171045 -277.226202) (xy 82.190993 -277.179382)
			(xy 82.218194 -277.136368) (xy 82.251942 -277.098274) (xy 82.291364 -277.066087) (xy 82.335438 -277.040641)
			(xy 82.383024 -277.022594) (xy 82.432888 -277.012414) (xy 82.48374 -277.010365) (xy 82.534261 -277.016499)
			(xy 82.583145 -277.030659) (xy 82.629124 -277.052476) (xy 82.671008 -277.081386) (xy 82.707712 -277.116641)
			(xy 82.738285 -277.157327) (xy 82.761936 -277.20239) (xy 82.778052 -277.250664) (xy 82.786216 -277.300898)
			(xy 82.786728 -277.326344) (xy 83.105256 -277.326344) (xy 83.109216 -277.27729) (xy 83.120993 -277.229506)
			(xy 83.140284 -277.18423) (xy 83.166587 -277.142634) (xy 83.199222 -277.105797) (xy 83.237343 -277.074672)
			(xy 83.279964 -277.050065) (xy 83.32598 -277.032613) (xy 83.374199 -277.022769) (xy 83.423374 -277.020788)
			(xy 83.472229 -277.02672) (xy 83.5195 -277.040412) (xy 83.563962 -277.06151) (xy 83.604465 -277.089466)
			(xy 83.639958 -277.123558) (xy 83.669523 -277.162902) (xy 83.692394 -277.206479) (xy 83.707978 -277.25316)
			(xy 83.715873 -277.301737) (xy 83.716368 -277.326344) (xy 84.034879 -277.326344) (xy 84.038974 -277.275616)
			(xy 84.051153 -277.226202) (xy 84.071101 -277.179382) (xy 84.098302 -277.136368) (xy 84.13205 -277.098274)
			(xy 84.171472 -277.066087) (xy 84.215546 -277.040641) (xy 84.263132 -277.022594) (xy 84.312996 -277.012414)
			(xy 84.363848 -277.010365) (xy 84.414369 -277.016499) (xy 84.463253 -277.030659) (xy 84.509232 -277.052476)
			(xy 84.551116 -277.081386) (xy 84.58782 -277.116641) (xy 84.618393 -277.157327) (xy 84.642044 -277.20239)
			(xy 84.65816 -277.250664) (xy 84.666324 -277.300898) (xy 84.666836 -277.326344) (xy 84.98511 -277.326344)
			(xy 84.98907 -277.27729) (xy 85.000847 -277.229506) (xy 85.020138 -277.18423) (xy 85.046441 -277.142634)
			(xy 85.079076 -277.105797) (xy 85.117197 -277.074672) (xy 85.159818 -277.050065) (xy 85.205834 -277.032613)
			(xy 85.254053 -277.022769) (xy 85.303228 -277.020788) (xy 85.352083 -277.02672) (xy 85.399354 -277.040412)
			(xy 85.443816 -277.06151) (xy 85.484319 -277.089466) (xy 85.519812 -277.123558) (xy 85.549377 -277.162902)
			(xy 85.572248 -277.206479) (xy 85.587832 -277.25316) (xy 85.595727 -277.301737) (xy 85.596222 -277.326344)
			(xy 85.914733 -277.326344) (xy 85.918828 -277.275616) (xy 85.931007 -277.226202) (xy 85.950955 -277.179382)
			(xy 85.978156 -277.136368) (xy 86.011904 -277.098274) (xy 86.051326 -277.066087) (xy 86.0954 -277.040641)
			(xy 86.142986 -277.022594) (xy 86.19285 -277.012414) (xy 86.243702 -277.010365) (xy 86.294223 -277.016499)
			(xy 86.343107 -277.030659) (xy 86.389086 -277.052476) (xy 86.43097 -277.081386) (xy 86.467674 -277.116641)
			(xy 86.498247 -277.157327) (xy 86.521898 -277.20239) (xy 86.538014 -277.250664) (xy 86.546178 -277.300898)
			(xy 86.54669 -277.326344) (xy 86.865218 -277.326344) (xy 86.869178 -277.27729) (xy 86.880955 -277.229506)
			(xy 86.900246 -277.18423) (xy 86.926549 -277.142634) (xy 86.959184 -277.105797) (xy 86.997305 -277.074672)
			(xy 87.039926 -277.050065) (xy 87.085942 -277.032613) (xy 87.134161 -277.022769) (xy 87.183336 -277.020788)
			(xy 87.232191 -277.02672) (xy 87.279462 -277.040412) (xy 87.323924 -277.06151) (xy 87.364427 -277.089466)
			(xy 87.39992 -277.123558) (xy 87.429485 -277.162902) (xy 87.452356 -277.206479) (xy 87.46794 -277.25316)
			(xy 87.475835 -277.301737) (xy 87.47633 -277.326344) (xy 87.794841 -277.326344) (xy 87.798936 -277.275616)
			(xy 87.811115 -277.226202) (xy 87.831063 -277.179382) (xy 87.858264 -277.136368) (xy 87.892012 -277.098274)
			(xy 87.931434 -277.066087) (xy 87.975508 -277.040641) (xy 88.023094 -277.022594) (xy 88.072958 -277.012414)
			(xy 88.12381 -277.010365) (xy 88.174331 -277.016499) (xy 88.223215 -277.030659) (xy 88.269194 -277.052476)
			(xy 88.311078 -277.081386) (xy 88.347782 -277.116641) (xy 88.378355 -277.157327) (xy 88.402006 -277.20239)
			(xy 88.418122 -277.250664) (xy 88.426286 -277.300898) (xy 88.426798 -277.326344) (xy 88.734895 -277.326344)
			(xy 88.73899 -277.275616) (xy 88.751169 -277.226202) (xy 88.771117 -277.179382) (xy 88.798318 -277.136368)
			(xy 88.832066 -277.098274) (xy 88.871488 -277.066087) (xy 88.915562 -277.040641) (xy 88.963148 -277.022594)
			(xy 89.013012 -277.012414) (xy 89.063864 -277.010365) (xy 89.114385 -277.016499) (xy 89.163269 -277.030659)
			(xy 89.209248 -277.052476) (xy 89.251132 -277.081386) (xy 89.287836 -277.116641) (xy 89.318409 -277.157327)
			(xy 89.34206 -277.20239) (xy 89.358176 -277.250664) (xy 89.36634 -277.300898) (xy 89.366852 -277.326344)
			(xy 89.685126 -277.326344) (xy 89.689086 -277.27729) (xy 89.700863 -277.229506) (xy 89.720154 -277.18423)
			(xy 89.746457 -277.142634) (xy 89.779092 -277.105797) (xy 89.817213 -277.074672) (xy 89.859834 -277.050065)
			(xy 89.90585 -277.032613) (xy 89.954069 -277.022769) (xy 90.003244 -277.020788) (xy 90.052099 -277.02672)
			(xy 90.09937 -277.040412) (xy 90.143832 -277.06151) (xy 90.184335 -277.089466) (xy 90.219828 -277.123558)
			(xy 90.249393 -277.162902) (xy 90.272264 -277.206479) (xy 90.287848 -277.25316) (xy 90.295743 -277.301737)
			(xy 90.296238 -277.326344) (xy 90.614749 -277.326344) (xy 90.618844 -277.275616) (xy 90.631023 -277.226202)
			(xy 90.650971 -277.179382) (xy 90.678172 -277.136368) (xy 90.71192 -277.098274) (xy 90.751342 -277.066087)
			(xy 90.795416 -277.040641) (xy 90.843002 -277.022594) (xy 90.892866 -277.012414) (xy 90.943718 -277.010365)
			(xy 90.994239 -277.016499) (xy 91.043123 -277.030659) (xy 91.089102 -277.052476) (xy 91.130986 -277.081386)
			(xy 91.16769 -277.116641) (xy 91.198263 -277.157327) (xy 91.221914 -277.20239) (xy 91.23803 -277.250664)
			(xy 91.246194 -277.300898) (xy 91.246706 -277.326344) (xy 91.565234 -277.326344) (xy 91.569194 -277.27729)
			(xy 91.580971 -277.229506) (xy 91.600262 -277.18423) (xy 91.626565 -277.142634) (xy 91.6592 -277.105797)
			(xy 91.697321 -277.074672) (xy 91.739942 -277.050065) (xy 91.785958 -277.032613) (xy 91.834177 -277.022769)
			(xy 91.883352 -277.020788) (xy 91.932207 -277.02672) (xy 91.979478 -277.040412) (xy 92.02394 -277.06151)
			(xy 92.064443 -277.089466) (xy 92.099936 -277.123558) (xy 92.129501 -277.162902) (xy 92.152372 -277.206479)
			(xy 92.167956 -277.25316) (xy 92.175851 -277.301737) (xy 92.176346 -277.326344) (xy 92.494857 -277.326344)
			(xy 92.498952 -277.275616) (xy 92.511131 -277.226202) (xy 92.531079 -277.179382) (xy 92.55828 -277.136368)
			(xy 92.592028 -277.098274) (xy 92.63145 -277.066087) (xy 92.675524 -277.040641) (xy 92.72311 -277.022594)
			(xy 92.772974 -277.012414) (xy 92.823826 -277.010365) (xy 92.874347 -277.016499) (xy 92.923231 -277.030659)
			(xy 92.96921 -277.052476) (xy 93.011094 -277.081386) (xy 93.047798 -277.116641) (xy 93.078371 -277.157327)
			(xy 93.102022 -277.20239) (xy 93.118138 -277.250664) (xy 93.126302 -277.300898) (xy 93.126814 -277.326344)
			(xy 93.445342 -277.326344) (xy 93.449302 -277.27729) (xy 93.461079 -277.229506) (xy 93.48037 -277.18423)
			(xy 93.506673 -277.142634) (xy 93.539308 -277.105797) (xy 93.577429 -277.074672) (xy 93.62005 -277.050065)
			(xy 93.666066 -277.032613) (xy 93.714285 -277.022769) (xy 93.76346 -277.020788) (xy 93.812315 -277.02672)
			(xy 93.859586 -277.040412) (xy 93.904048 -277.06151) (xy 93.944551 -277.089466) (xy 93.980044 -277.123558)
			(xy 94.009609 -277.162902) (xy 94.03248 -277.206479) (xy 94.048064 -277.25316) (xy 94.055959 -277.301737)
			(xy 94.056454 -277.326344) (xy 94.374711 -277.326344) (xy 94.378806 -277.275616) (xy 94.390985 -277.226202)
			(xy 94.410933 -277.179382) (xy 94.438134 -277.136368) (xy 94.471882 -277.098274) (xy 94.511304 -277.066087)
			(xy 94.555378 -277.040641) (xy 94.602964 -277.022594) (xy 94.652828 -277.012414) (xy 94.70368 -277.010365)
			(xy 94.754201 -277.016499) (xy 94.803085 -277.030659) (xy 94.849064 -277.052476) (xy 94.890948 -277.081386)
			(xy 94.927652 -277.116641) (xy 94.958225 -277.157327) (xy 94.981876 -277.20239) (xy 94.997992 -277.250664)
			(xy 95.006156 -277.300898) (xy 95.006668 -277.326344) (xy 95.314765 -277.326344) (xy 95.31886 -277.275616)
			(xy 95.331039 -277.226202) (xy 95.350987 -277.179382) (xy 95.378188 -277.136368) (xy 95.411936 -277.098274)
			(xy 95.451358 -277.066087) (xy 95.495432 -277.040641) (xy 95.543018 -277.022594) (xy 95.592882 -277.012414)
			(xy 95.643734 -277.010365) (xy 95.694255 -277.016499) (xy 95.743139 -277.030659) (xy 95.789118 -277.052476)
			(xy 95.831002 -277.081386) (xy 95.867706 -277.116641) (xy 95.898279 -277.157327) (xy 95.92193 -277.20239)
			(xy 95.938046 -277.250664) (xy 95.94621 -277.300898) (xy 95.946722 -277.326344) (xy 96.26525 -277.326344)
			(xy 96.26921 -277.27729) (xy 96.280987 -277.229506) (xy 96.300278 -277.18423) (xy 96.326581 -277.142634)
			(xy 96.359216 -277.105797) (xy 96.397337 -277.074672) (xy 96.439958 -277.050065) (xy 96.485974 -277.032613)
			(xy 96.534193 -277.022769) (xy 96.583368 -277.020788) (xy 96.632223 -277.02672) (xy 96.679494 -277.040412)
			(xy 96.723956 -277.06151) (xy 96.764459 -277.089466) (xy 96.799952 -277.123558) (xy 96.829517 -277.162902)
			(xy 96.852388 -277.206479) (xy 96.867972 -277.25316) (xy 96.875867 -277.301737) (xy 96.876362 -277.326344)
			(xy 97.205304 -277.326344) (xy 97.209264 -277.27729) (xy 97.221041 -277.229506) (xy 97.240332 -277.18423)
			(xy 97.266635 -277.142634) (xy 97.29927 -277.105797) (xy 97.337391 -277.074672) (xy 97.380012 -277.050065)
			(xy 97.426028 -277.032613) (xy 97.474247 -277.022769) (xy 97.523422 -277.020788) (xy 97.572277 -277.02672)
			(xy 97.619548 -277.040412) (xy 97.66401 -277.06151) (xy 97.704513 -277.089466) (xy 97.740006 -277.123558)
			(xy 97.769571 -277.162902) (xy 97.792442 -277.206479) (xy 97.808026 -277.25316) (xy 97.815921 -277.301737)
			(xy 97.816416 -277.326344) (xy 98.145358 -277.326344) (xy 98.149318 -277.27729) (xy 98.161095 -277.229506)
			(xy 98.180386 -277.18423) (xy 98.206689 -277.142634) (xy 98.239324 -277.105797) (xy 98.277445 -277.074672)
			(xy 98.320066 -277.050065) (xy 98.366082 -277.032613) (xy 98.414301 -277.022769) (xy 98.463476 -277.020788)
			(xy 98.512331 -277.02672) (xy 98.559602 -277.040412) (xy 98.604064 -277.06151) (xy 98.644567 -277.089466)
			(xy 98.68006 -277.123558) (xy 98.709625 -277.162902) (xy 98.732496 -277.206479) (xy 98.74808 -277.25316)
			(xy 98.755975 -277.301737) (xy 98.75647 -277.326344) (xy 99.085158 -277.326344) (xy 99.089118 -277.27729)
			(xy 99.100895 -277.229506) (xy 99.120186 -277.18423) (xy 99.146489 -277.142634) (xy 99.179124 -277.105797)
			(xy 99.217245 -277.074672) (xy 99.259866 -277.050065) (xy 99.305882 -277.032613) (xy 99.354101 -277.022769)
			(xy 99.403276 -277.020788) (xy 99.452131 -277.02672) (xy 99.499402 -277.040412) (xy 99.543864 -277.06151)
			(xy 99.584367 -277.089466) (xy 99.61986 -277.123558) (xy 99.649425 -277.162902) (xy 99.672296 -277.206479)
			(xy 99.68788 -277.25316) (xy 99.695775 -277.301737) (xy 99.69627 -277.326344) (xy 100.025212 -277.326344)
			(xy 100.029172 -277.27729) (xy 100.040949 -277.229506) (xy 100.06024 -277.18423) (xy 100.086543 -277.142634)
			(xy 100.119178 -277.105797) (xy 100.157299 -277.074672) (xy 100.19992 -277.050065) (xy 100.245936 -277.032613)
			(xy 100.294155 -277.022769) (xy 100.34333 -277.020788) (xy 100.392185 -277.02672) (xy 100.439456 -277.040412)
			(xy 100.483918 -277.06151) (xy 100.524421 -277.089466) (xy 100.559914 -277.123558) (xy 100.589479 -277.162902)
			(xy 100.61235 -277.206479) (xy 100.627934 -277.25316) (xy 100.635829 -277.301737) (xy 100.636324 -277.326344)
			(xy 100.965266 -277.326344) (xy 100.969226 -277.27729) (xy 100.981003 -277.229506) (xy 101.000294 -277.18423)
			(xy 101.026597 -277.142634) (xy 101.059232 -277.105797) (xy 101.097353 -277.074672) (xy 101.139974 -277.050065)
			(xy 101.18599 -277.032613) (xy 101.234209 -277.022769) (xy 101.283384 -277.020788) (xy 101.332239 -277.02672)
			(xy 101.37951 -277.040412) (xy 101.423972 -277.06151) (xy 101.464475 -277.089466) (xy 101.499968 -277.123558)
			(xy 101.529533 -277.162902) (xy 101.552404 -277.206479) (xy 101.567988 -277.25316) (xy 101.575883 -277.301737)
			(xy 101.576378 -277.326344) (xy 101.90532 -277.326344) (xy 101.90928 -277.27729) (xy 101.921057 -277.229506)
			(xy 101.940348 -277.18423) (xy 101.966651 -277.142634) (xy 101.999286 -277.105797) (xy 102.037407 -277.074672)
			(xy 102.080028 -277.050065) (xy 102.126044 -277.032613) (xy 102.174263 -277.022769) (xy 102.223438 -277.020788)
			(xy 102.272293 -277.02672) (xy 102.319564 -277.040412) (xy 102.364026 -277.06151) (xy 102.404529 -277.089466)
			(xy 102.440022 -277.123558) (xy 102.469587 -277.162902) (xy 102.492458 -277.206479) (xy 102.508042 -277.25316)
			(xy 102.515937 -277.301737) (xy 102.516432 -277.326344) (xy 102.515937 -277.350951) (xy 102.508042 -277.399528)
			(xy 102.492458 -277.446209) (xy 102.469587 -277.489786) (xy 102.440022 -277.52913) (xy 102.404529 -277.563222)
			(xy 102.364026 -277.591178) (xy 102.319564 -277.612276) (xy 102.272293 -277.625968) (xy 102.223438 -277.6319)
			(xy 102.174263 -277.629919) (xy 102.126044 -277.620075) (xy 102.080028 -277.602623) (xy 102.037407 -277.578016)
			(xy 101.999286 -277.546891) (xy 101.966651 -277.510054) (xy 101.940348 -277.468458) (xy 101.921057 -277.423182)
			(xy 101.90928 -277.375398) (xy 101.90532 -277.326344) (xy 101.576378 -277.326344) (xy 101.575883 -277.350951)
			(xy 101.567988 -277.399528) (xy 101.552404 -277.446209) (xy 101.529533 -277.489786) (xy 101.499968 -277.52913)
			(xy 101.464475 -277.563222) (xy 101.423972 -277.591178) (xy 101.37951 -277.612276) (xy 101.332239 -277.625968)
			(xy 101.283384 -277.6319) (xy 101.234209 -277.629919) (xy 101.18599 -277.620075) (xy 101.139974 -277.602623)
			(xy 101.097353 -277.578016) (xy 101.059232 -277.546891) (xy 101.026597 -277.510054) (xy 101.000294 -277.468458)
			(xy 100.981003 -277.423182) (xy 100.969226 -277.375398) (xy 100.965266 -277.326344) (xy 100.636324 -277.326344)
			(xy 100.635829 -277.350951) (xy 100.627934 -277.399528) (xy 100.61235 -277.446209) (xy 100.589479 -277.489786)
			(xy 100.559914 -277.52913) (xy 100.524421 -277.563222) (xy 100.483918 -277.591178) (xy 100.439456 -277.612276)
			(xy 100.392185 -277.625968) (xy 100.34333 -277.6319) (xy 100.294155 -277.629919) (xy 100.245936 -277.620075)
			(xy 100.19992 -277.602623) (xy 100.157299 -277.578016) (xy 100.119178 -277.546891) (xy 100.086543 -277.510054)
			(xy 100.06024 -277.468458) (xy 100.040949 -277.423182) (xy 100.029172 -277.375398) (xy 100.025212 -277.326344)
			(xy 99.69627 -277.326344) (xy 99.695775 -277.350951) (xy 99.68788 -277.399528) (xy 99.672296 -277.446209)
			(xy 99.649425 -277.489786) (xy 99.61986 -277.52913) (xy 99.584367 -277.563222) (xy 99.543864 -277.591178)
			(xy 99.499402 -277.612276) (xy 99.452131 -277.625968) (xy 99.403276 -277.6319) (xy 99.354101 -277.629919)
			(xy 99.305882 -277.620075) (xy 99.259866 -277.602623) (xy 99.217245 -277.578016) (xy 99.179124 -277.546891)
			(xy 99.146489 -277.510054) (xy 99.120186 -277.468458) (xy 99.100895 -277.423182) (xy 99.089118 -277.375398)
			(xy 99.085158 -277.326344) (xy 98.75647 -277.326344) (xy 98.755975 -277.350951) (xy 98.74808 -277.399528)
			(xy 98.732496 -277.446209) (xy 98.709625 -277.489786) (xy 98.68006 -277.52913) (xy 98.644567 -277.563222)
			(xy 98.604064 -277.591178) (xy 98.559602 -277.612276) (xy 98.512331 -277.625968) (xy 98.463476 -277.6319)
			(xy 98.414301 -277.629919) (xy 98.366082 -277.620075) (xy 98.320066 -277.602623) (xy 98.277445 -277.578016)
			(xy 98.239324 -277.546891) (xy 98.206689 -277.510054) (xy 98.180386 -277.468458) (xy 98.161095 -277.423182)
			(xy 98.149318 -277.375398) (xy 98.145358 -277.326344) (xy 97.816416 -277.326344) (xy 97.815921 -277.350951)
			(xy 97.808026 -277.399528) (xy 97.792442 -277.446209) (xy 97.769571 -277.489786) (xy 97.740006 -277.52913)
			(xy 97.704513 -277.563222) (xy 97.66401 -277.591178) (xy 97.619548 -277.612276) (xy 97.572277 -277.625968)
			(xy 97.523422 -277.6319) (xy 97.474247 -277.629919) (xy 97.426028 -277.620075) (xy 97.380012 -277.602623)
			(xy 97.337391 -277.578016) (xy 97.29927 -277.546891) (xy 97.266635 -277.510054) (xy 97.240332 -277.468458)
			(xy 97.221041 -277.423182) (xy 97.209264 -277.375398) (xy 97.205304 -277.326344) (xy 96.876362 -277.326344)
			(xy 96.875867 -277.350951) (xy 96.867972 -277.399528) (xy 96.852388 -277.446209) (xy 96.829517 -277.489786)
			(xy 96.799952 -277.52913) (xy 96.764459 -277.563222) (xy 96.723956 -277.591178) (xy 96.679494 -277.612276)
			(xy 96.632223 -277.625968) (xy 96.583368 -277.6319) (xy 96.534193 -277.629919) (xy 96.485974 -277.620075)
			(xy 96.439958 -277.602623) (xy 96.397337 -277.578016) (xy 96.359216 -277.546891) (xy 96.326581 -277.510054)
			(xy 96.300278 -277.468458) (xy 96.280987 -277.423182) (xy 96.26921 -277.375398) (xy 96.26525 -277.326344)
			(xy 95.946722 -277.326344) (xy 95.94621 -277.35179) (xy 95.938046 -277.402024) (xy 95.92193 -277.450298)
			(xy 95.898279 -277.495361) (xy 95.867706 -277.536047) (xy 95.831002 -277.571302) (xy 95.789118 -277.600212)
			(xy 95.743139 -277.622029) (xy 95.694255 -277.636189) (xy 95.643734 -277.642323) (xy 95.592882 -277.640274)
			(xy 95.543018 -277.630094) (xy 95.495432 -277.612047) (xy 95.451358 -277.586601) (xy 95.411936 -277.554414)
			(xy 95.378188 -277.51632) (xy 95.350987 -277.473306) (xy 95.331039 -277.426486) (xy 95.31886 -277.377072)
			(xy 95.314765 -277.326344) (xy 95.006668 -277.326344) (xy 95.006156 -277.35179) (xy 94.997992 -277.402024)
			(xy 94.981876 -277.450298) (xy 94.958225 -277.495361) (xy 94.927652 -277.536047) (xy 94.890948 -277.571302)
			(xy 94.849064 -277.600212) (xy 94.803085 -277.622029) (xy 94.754201 -277.636189) (xy 94.70368 -277.642323)
			(xy 94.652828 -277.640274) (xy 94.602964 -277.630094) (xy 94.555378 -277.612047) (xy 94.511304 -277.586601)
			(xy 94.471882 -277.554414) (xy 94.438134 -277.51632) (xy 94.410933 -277.473306) (xy 94.390985 -277.426486)
			(xy 94.378806 -277.377072) (xy 94.374711 -277.326344) (xy 94.056454 -277.326344) (xy 94.055959 -277.350951)
			(xy 94.048064 -277.399528) (xy 94.03248 -277.446209) (xy 94.009609 -277.489786) (xy 93.980044 -277.52913)
			(xy 93.944551 -277.563222) (xy 93.904048 -277.591178) (xy 93.859586 -277.612276) (xy 93.812315 -277.625968)
			(xy 93.76346 -277.6319) (xy 93.714285 -277.629919) (xy 93.666066 -277.620075) (xy 93.62005 -277.602623)
			(xy 93.577429 -277.578016) (xy 93.539308 -277.546891) (xy 93.506673 -277.510054) (xy 93.48037 -277.468458)
			(xy 93.461079 -277.423182) (xy 93.449302 -277.375398) (xy 93.445342 -277.326344) (xy 93.126814 -277.326344)
			(xy 93.126302 -277.35179) (xy 93.118138 -277.402024) (xy 93.102022 -277.450298) (xy 93.078371 -277.495361)
			(xy 93.047798 -277.536047) (xy 93.011094 -277.571302) (xy 92.96921 -277.600212) (xy 92.923231 -277.622029)
			(xy 92.874347 -277.636189) (xy 92.823826 -277.642323) (xy 92.772974 -277.640274) (xy 92.72311 -277.630094)
			(xy 92.675524 -277.612047) (xy 92.63145 -277.586601) (xy 92.592028 -277.554414) (xy 92.55828 -277.51632)
			(xy 92.531079 -277.473306) (xy 92.511131 -277.426486) (xy 92.498952 -277.377072) (xy 92.494857 -277.326344)
			(xy 92.176346 -277.326344) (xy 92.175851 -277.350951) (xy 92.167956 -277.399528) (xy 92.152372 -277.446209)
			(xy 92.129501 -277.489786) (xy 92.099936 -277.52913) (xy 92.064443 -277.563222) (xy 92.02394 -277.591178)
			(xy 91.979478 -277.612276) (xy 91.932207 -277.625968) (xy 91.883352 -277.6319) (xy 91.834177 -277.629919)
			(xy 91.785958 -277.620075) (xy 91.739942 -277.602623) (xy 91.697321 -277.578016) (xy 91.6592 -277.546891)
			(xy 91.626565 -277.510054) (xy 91.600262 -277.468458) (xy 91.580971 -277.423182) (xy 91.569194 -277.375398)
			(xy 91.565234 -277.326344) (xy 91.246706 -277.326344) (xy 91.246194 -277.35179) (xy 91.23803 -277.402024)
			(xy 91.221914 -277.450298) (xy 91.198263 -277.495361) (xy 91.16769 -277.536047) (xy 91.130986 -277.571302)
			(xy 91.089102 -277.600212) (xy 91.043123 -277.622029) (xy 90.994239 -277.636189) (xy 90.943718 -277.642323)
			(xy 90.892866 -277.640274) (xy 90.843002 -277.630094) (xy 90.795416 -277.612047) (xy 90.751342 -277.586601)
			(xy 90.71192 -277.554414) (xy 90.678172 -277.51632) (xy 90.650971 -277.473306) (xy 90.631023 -277.426486)
			(xy 90.618844 -277.377072) (xy 90.614749 -277.326344) (xy 90.296238 -277.326344) (xy 90.295743 -277.350951)
			(xy 90.287848 -277.399528) (xy 90.272264 -277.446209) (xy 90.249393 -277.489786) (xy 90.219828 -277.52913)
			(xy 90.184335 -277.563222) (xy 90.143832 -277.591178) (xy 90.09937 -277.612276) (xy 90.052099 -277.625968)
			(xy 90.003244 -277.6319) (xy 89.954069 -277.629919) (xy 89.90585 -277.620075) (xy 89.859834 -277.602623)
			(xy 89.817213 -277.578016) (xy 89.779092 -277.546891) (xy 89.746457 -277.510054) (xy 89.720154 -277.468458)
			(xy 89.700863 -277.423182) (xy 89.689086 -277.375398) (xy 89.685126 -277.326344) (xy 89.366852 -277.326344)
			(xy 89.36634 -277.35179) (xy 89.358176 -277.402024) (xy 89.34206 -277.450298) (xy 89.318409 -277.495361)
			(xy 89.287836 -277.536047) (xy 89.251132 -277.571302) (xy 89.209248 -277.600212) (xy 89.163269 -277.622029)
			(xy 89.114385 -277.636189) (xy 89.063864 -277.642323) (xy 89.013012 -277.640274) (xy 88.963148 -277.630094)
			(xy 88.915562 -277.612047) (xy 88.871488 -277.586601) (xy 88.832066 -277.554414) (xy 88.798318 -277.51632)
			(xy 88.771117 -277.473306) (xy 88.751169 -277.426486) (xy 88.73899 -277.377072) (xy 88.734895 -277.326344)
			(xy 88.426798 -277.326344) (xy 88.426286 -277.35179) (xy 88.418122 -277.402024) (xy 88.402006 -277.450298)
			(xy 88.378355 -277.495361) (xy 88.347782 -277.536047) (xy 88.311078 -277.571302) (xy 88.269194 -277.600212)
			(xy 88.223215 -277.622029) (xy 88.174331 -277.636189) (xy 88.12381 -277.642323) (xy 88.072958 -277.640274)
			(xy 88.023094 -277.630094) (xy 87.975508 -277.612047) (xy 87.931434 -277.586601) (xy 87.892012 -277.554414)
			(xy 87.858264 -277.51632) (xy 87.831063 -277.473306) (xy 87.811115 -277.426486) (xy 87.798936 -277.377072)
			(xy 87.794841 -277.326344) (xy 87.47633 -277.326344) (xy 87.475835 -277.350951) (xy 87.46794 -277.399528)
			(xy 87.452356 -277.446209) (xy 87.429485 -277.489786) (xy 87.39992 -277.52913) (xy 87.364427 -277.563222)
			(xy 87.323924 -277.591178) (xy 87.279462 -277.612276) (xy 87.232191 -277.625968) (xy 87.183336 -277.6319)
			(xy 87.134161 -277.629919) (xy 87.085942 -277.620075) (xy 87.039926 -277.602623) (xy 86.997305 -277.578016)
			(xy 86.959184 -277.546891) (xy 86.926549 -277.510054) (xy 86.900246 -277.468458) (xy 86.880955 -277.423182)
			(xy 86.869178 -277.375398) (xy 86.865218 -277.326344) (xy 86.54669 -277.326344) (xy 86.546178 -277.35179)
			(xy 86.538014 -277.402024) (xy 86.521898 -277.450298) (xy 86.498247 -277.495361) (xy 86.467674 -277.536047)
			(xy 86.43097 -277.571302) (xy 86.389086 -277.600212) (xy 86.343107 -277.622029) (xy 86.294223 -277.636189)
			(xy 86.243702 -277.642323) (xy 86.19285 -277.640274) (xy 86.142986 -277.630094) (xy 86.0954 -277.612047)
			(xy 86.051326 -277.586601) (xy 86.011904 -277.554414) (xy 85.978156 -277.51632) (xy 85.950955 -277.473306)
			(xy 85.931007 -277.426486) (xy 85.918828 -277.377072) (xy 85.914733 -277.326344) (xy 85.596222 -277.326344)
			(xy 85.595727 -277.350951) (xy 85.587832 -277.399528) (xy 85.572248 -277.446209) (xy 85.549377 -277.489786)
			(xy 85.519812 -277.52913) (xy 85.484319 -277.563222) (xy 85.443816 -277.591178) (xy 85.399354 -277.612276)
			(xy 85.352083 -277.625968) (xy 85.303228 -277.6319) (xy 85.254053 -277.629919) (xy 85.205834 -277.620075)
			(xy 85.159818 -277.602623) (xy 85.117197 -277.578016) (xy 85.079076 -277.546891) (xy 85.046441 -277.510054)
			(xy 85.020138 -277.468458) (xy 85.000847 -277.423182) (xy 84.98907 -277.375398) (xy 84.98511 -277.326344)
			(xy 84.666836 -277.326344) (xy 84.666324 -277.35179) (xy 84.65816 -277.402024) (xy 84.642044 -277.450298)
			(xy 84.618393 -277.495361) (xy 84.58782 -277.536047) (xy 84.551116 -277.571302) (xy 84.509232 -277.600212)
			(xy 84.463253 -277.622029) (xy 84.414369 -277.636189) (xy 84.363848 -277.642323) (xy 84.312996 -277.640274)
			(xy 84.263132 -277.630094) (xy 84.215546 -277.612047) (xy 84.171472 -277.586601) (xy 84.13205 -277.554414)
			(xy 84.098302 -277.51632) (xy 84.071101 -277.473306) (xy 84.051153 -277.426486) (xy 84.038974 -277.377072)
			(xy 84.034879 -277.326344) (xy 83.716368 -277.326344) (xy 83.715873 -277.350951) (xy 83.707978 -277.399528)
			(xy 83.692394 -277.446209) (xy 83.669523 -277.489786) (xy 83.639958 -277.52913) (xy 83.604465 -277.563222)
			(xy 83.563962 -277.591178) (xy 83.5195 -277.612276) (xy 83.472229 -277.625968) (xy 83.423374 -277.6319)
			(xy 83.374199 -277.629919) (xy 83.32598 -277.620075) (xy 83.279964 -277.602623) (xy 83.237343 -277.578016)
			(xy 83.199222 -277.546891) (xy 83.166587 -277.510054) (xy 83.140284 -277.468458) (xy 83.120993 -277.423182)
			(xy 83.109216 -277.375398) (xy 83.105256 -277.326344) (xy 82.786728 -277.326344) (xy 82.786216 -277.35179)
			(xy 82.778052 -277.402024) (xy 82.761936 -277.450298) (xy 82.738285 -277.495361) (xy 82.707712 -277.536047)
			(xy 82.671008 -277.571302) (xy 82.629124 -277.600212) (xy 82.583145 -277.622029) (xy 82.534261 -277.636189)
			(xy 82.48374 -277.642323) (xy 82.432888 -277.640274) (xy 82.383024 -277.630094) (xy 82.335438 -277.612047)
			(xy 82.291364 -277.586601) (xy 82.251942 -277.554414) (xy 82.218194 -277.51632) (xy 82.190993 -277.473306)
			(xy 82.171045 -277.426486) (xy 82.158866 -277.377072) (xy 82.154771 -277.326344) (xy 81.846674 -277.326344)
			(xy 81.846162 -277.35179) (xy 81.837998 -277.402024) (xy 81.821882 -277.450298) (xy 81.798231 -277.495361)
			(xy 81.767658 -277.536047) (xy 81.730954 -277.571302) (xy 81.68907 -277.600212) (xy 81.643091 -277.622029)
			(xy 81.594207 -277.636189) (xy 81.543686 -277.642323) (xy 81.492834 -277.640274) (xy 81.44297 -277.630094)
			(xy 81.395384 -277.612047) (xy 81.35131 -277.586601) (xy 81.311888 -277.554414) (xy 81.27814 -277.51632)
			(xy 81.250939 -277.473306) (xy 81.230991 -277.426486) (xy 81.218812 -277.377072) (xy 81.214717 -277.326344)
			(xy 80.89646 -277.326344) (xy 80.895965 -277.350951) (xy 80.88807 -277.399528) (xy 80.872486 -277.446209)
			(xy 80.849615 -277.489786) (xy 80.82005 -277.52913) (xy 80.784557 -277.563222) (xy 80.744054 -277.591178)
			(xy 80.699592 -277.612276) (xy 80.652321 -277.625968) (xy 80.603466 -277.6319) (xy 80.554291 -277.629919)
			(xy 80.506072 -277.620075) (xy 80.460056 -277.602623) (xy 80.417435 -277.578016) (xy 80.379314 -277.546891)
			(xy 80.346679 -277.510054) (xy 80.320376 -277.468458) (xy 80.301085 -277.423182) (xy 80.289308 -277.375398)
			(xy 80.285348 -277.326344) (xy 79.016352 -277.326344) (xy 79.015857 -277.350951) (xy 79.007962 -277.399528)
			(xy 78.992378 -277.446209) (xy 78.969507 -277.489786) (xy 78.939942 -277.52913) (xy 78.904449 -277.563222)
			(xy 78.863946 -277.591178) (xy 78.819484 -277.612276) (xy 78.772213 -277.625968) (xy 78.723358 -277.6319)
			(xy 78.674183 -277.629919) (xy 78.625964 -277.620075) (xy 78.579948 -277.602623) (xy 78.537327 -277.578016)
			(xy 78.499206 -277.546891) (xy 78.466571 -277.510054) (xy 78.440268 -277.468458) (xy 78.420977 -277.423182)
			(xy 78.4092 -277.375398) (xy 78.40524 -277.326344) (xy 73.228962 -277.326344) (xy 73.228962 -277.870412)
			(xy 76.807072 -277.870412) (xy 76.811032 -277.821358) (xy 76.822809 -277.773574) (xy 76.8421 -277.728298)
			(xy 76.868403 -277.686702) (xy 76.901038 -277.649865) (xy 76.939159 -277.61874) (xy 76.98178 -277.594133)
			(xy 77.027796 -277.576681) (xy 77.076015 -277.566837) (xy 77.12519 -277.564856) (xy 77.174045 -277.570788)
			(xy 77.221316 -277.58448) (xy 77.265778 -277.605578) (xy 77.306281 -277.633534) (xy 77.341774 -277.667626)
			(xy 77.371339 -277.70697) (xy 77.39421 -277.750547) (xy 77.409794 -277.797228) (xy 77.417689 -277.845805)
			(xy 77.418184 -277.870412) (xy 77.417689 -277.895019) (xy 77.409794 -277.943596) (xy 77.39421 -277.990277)
			(xy 77.371339 -278.033854) (xy 77.341774 -278.073198) (xy 77.306281 -278.10729) (xy 77.265778 -278.135246)
			(xy 77.263451 -278.13635) (xy 79.815194 -278.13635) (xy 79.819154 -278.087296) (xy 79.830931 -278.039512)
			(xy 79.850222 -277.994236) (xy 79.876525 -277.95264) (xy 79.90916 -277.915803) (xy 79.947281 -277.884678)
			(xy 79.989902 -277.860071) (xy 80.035918 -277.842619) (xy 80.084137 -277.832775) (xy 80.133312 -277.830794)
			(xy 80.182167 -277.836726) (xy 80.229438 -277.850418) (xy 80.2739 -277.871516) (xy 80.314403 -277.899472)
			(xy 80.349896 -277.933564) (xy 80.379461 -277.972908) (xy 80.402332 -278.016485) (xy 80.417916 -278.063166)
			(xy 80.425811 -278.111743) (xy 80.426306 -278.13635) (xy 80.744817 -278.13635) (xy 80.748912 -278.085622)
			(xy 80.761091 -278.036208) (xy 80.781039 -277.989388) (xy 80.80824 -277.946374) (xy 80.841988 -277.90828)
			(xy 80.88141 -277.876093) (xy 80.925484 -277.850647) (xy 80.97307 -277.8326) (xy 81.022934 -277.82242)
			(xy 81.073786 -277.820371) (xy 81.124307 -277.826505) (xy 81.173191 -277.840665) (xy 81.21917 -277.862482)
			(xy 81.261054 -277.891392) (xy 81.297758 -277.926647) (xy 81.328331 -277.967333) (xy 81.351982 -278.012396)
			(xy 81.368098 -278.06067) (xy 81.376262 -278.110904) (xy 81.376774 -278.13635) (xy 81.695302 -278.13635)
			(xy 81.699262 -278.087296) (xy 81.711039 -278.039512) (xy 81.73033 -277.994236) (xy 81.756633 -277.95264)
			(xy 81.789268 -277.915803) (xy 81.827389 -277.884678) (xy 81.87001 -277.860071) (xy 81.916026 -277.842619)
			(xy 81.964245 -277.832775) (xy 82.01342 -277.830794) (xy 82.062275 -277.836726) (xy 82.109546 -277.850418)
			(xy 82.154008 -277.871516) (xy 82.194511 -277.899472) (xy 82.230004 -277.933564) (xy 82.259569 -277.972908)
			(xy 82.28244 -278.016485) (xy 82.298024 -278.063166) (xy 82.305919 -278.111743) (xy 82.306414 -278.13635)
			(xy 82.624671 -278.13635) (xy 82.628766 -278.085622) (xy 82.640945 -278.036208) (xy 82.660893 -277.989388)
			(xy 82.688094 -277.946374) (xy 82.721842 -277.90828) (xy 82.761264 -277.876093) (xy 82.805338 -277.850647)
			(xy 82.852924 -277.8326) (xy 82.902788 -277.82242) (xy 82.95364 -277.820371) (xy 83.004161 -277.826505)
			(xy 83.053045 -277.840665) (xy 83.099024 -277.862482) (xy 83.140908 -277.891392) (xy 83.177612 -277.926647)
			(xy 83.208185 -277.967333) (xy 83.231836 -278.012396) (xy 83.247952 -278.06067) (xy 83.256116 -278.110904)
			(xy 83.256628 -278.13635) (xy 83.575156 -278.13635) (xy 83.579116 -278.087296) (xy 83.590893 -278.039512)
			(xy 83.610184 -277.994236) (xy 83.636487 -277.95264) (xy 83.669122 -277.915803) (xy 83.707243 -277.884678)
			(xy 83.749864 -277.860071) (xy 83.79588 -277.842619) (xy 83.844099 -277.832775) (xy 83.893274 -277.830794)
			(xy 83.942129 -277.836726) (xy 83.9894 -277.850418) (xy 84.033862 -277.871516) (xy 84.074365 -277.899472)
			(xy 84.109858 -277.933564) (xy 84.139423 -277.972908) (xy 84.162294 -278.016485) (xy 84.177878 -278.063166)
			(xy 84.185773 -278.111743) (xy 84.186268 -278.13635) (xy 84.504779 -278.13635) (xy 84.508874 -278.085622)
			(xy 84.521053 -278.036208) (xy 84.541001 -277.989388) (xy 84.568202 -277.946374) (xy 84.60195 -277.90828)
			(xy 84.641372 -277.876093) (xy 84.685446 -277.850647) (xy 84.733032 -277.8326) (xy 84.782896 -277.82242)
			(xy 84.833748 -277.820371) (xy 84.884269 -277.826505) (xy 84.933153 -277.840665) (xy 84.979132 -277.862482)
			(xy 85.021016 -277.891392) (xy 85.05772 -277.926647) (xy 85.088293 -277.967333) (xy 85.111944 -278.012396)
			(xy 85.12806 -278.06067) (xy 85.136224 -278.110904) (xy 85.136736 -278.13635) (xy 85.444833 -278.13635)
			(xy 85.448928 -278.085622) (xy 85.461107 -278.036208) (xy 85.481055 -277.989388) (xy 85.508256 -277.946374)
			(xy 85.542004 -277.90828) (xy 85.581426 -277.876093) (xy 85.6255 -277.850647) (xy 85.673086 -277.8326)
			(xy 85.72295 -277.82242) (xy 85.773802 -277.820371) (xy 85.824323 -277.826505) (xy 85.873207 -277.840665)
			(xy 85.919186 -277.862482) (xy 85.96107 -277.891392) (xy 85.997774 -277.926647) (xy 86.028347 -277.967333)
			(xy 86.051998 -278.012396) (xy 86.068114 -278.06067) (xy 86.076278 -278.110904) (xy 86.07679 -278.13635)
			(xy 86.395318 -278.13635) (xy 86.399278 -278.087296) (xy 86.411055 -278.039512) (xy 86.430346 -277.994236)
			(xy 86.456649 -277.95264) (xy 86.489284 -277.915803) (xy 86.527405 -277.884678) (xy 86.570026 -277.860071)
			(xy 86.616042 -277.842619) (xy 86.664261 -277.832775) (xy 86.713436 -277.830794) (xy 86.762291 -277.836726)
			(xy 86.809562 -277.850418) (xy 86.854024 -277.871516) (xy 86.894527 -277.899472) (xy 86.93002 -277.933564)
			(xy 86.959585 -277.972908) (xy 86.982456 -278.016485) (xy 86.99804 -278.063166) (xy 87.005935 -278.111743)
			(xy 87.00643 -278.13635) (xy 87.324687 -278.13635) (xy 87.328782 -278.085622) (xy 87.340961 -278.036208)
			(xy 87.360909 -277.989388) (xy 87.38811 -277.946374) (xy 87.421858 -277.90828) (xy 87.46128 -277.876093)
			(xy 87.505354 -277.850647) (xy 87.55294 -277.8326) (xy 87.602804 -277.82242) (xy 87.653656 -277.820371)
			(xy 87.704177 -277.826505) (xy 87.753061 -277.840665) (xy 87.79904 -277.862482) (xy 87.840924 -277.891392)
			(xy 87.877628 -277.926647) (xy 87.908201 -277.967333) (xy 87.931852 -278.012396) (xy 87.947968 -278.06067)
			(xy 87.956132 -278.110904) (xy 87.956644 -278.13635) (xy 88.275172 -278.13635) (xy 88.279132 -278.087296)
			(xy 88.290909 -278.039512) (xy 88.3102 -277.994236) (xy 88.336503 -277.95264) (xy 88.369138 -277.915803)
			(xy 88.407259 -277.884678) (xy 88.44988 -277.860071) (xy 88.495896 -277.842619) (xy 88.544115 -277.832775)
			(xy 88.59329 -277.830794) (xy 88.642145 -277.836726) (xy 88.689416 -277.850418) (xy 88.733878 -277.871516)
			(xy 88.774381 -277.899472) (xy 88.809874 -277.933564) (xy 88.839439 -277.972908) (xy 88.86231 -278.016485)
			(xy 88.877894 -278.063166) (xy 88.885789 -278.111743) (xy 88.886284 -278.13635) (xy 89.204795 -278.13635)
			(xy 89.20889 -278.085622) (xy 89.221069 -278.036208) (xy 89.241017 -277.989388) (xy 89.268218 -277.946374)
			(xy 89.301966 -277.90828) (xy 89.341388 -277.876093) (xy 89.385462 -277.850647) (xy 89.433048 -277.8326)
			(xy 89.482912 -277.82242) (xy 89.533764 -277.820371) (xy 89.584285 -277.826505) (xy 89.633169 -277.840665)
			(xy 89.679148 -277.862482) (xy 89.721032 -277.891392) (xy 89.757736 -277.926647) (xy 89.788309 -277.967333)
			(xy 89.81196 -278.012396) (xy 89.828076 -278.06067) (xy 89.83624 -278.110904) (xy 89.836752 -278.13635)
			(xy 90.15528 -278.13635) (xy 90.15924 -278.087296) (xy 90.171017 -278.039512) (xy 90.190308 -277.994236)
			(xy 90.216611 -277.95264) (xy 90.249246 -277.915803) (xy 90.287367 -277.884678) (xy 90.329988 -277.860071)
			(xy 90.376004 -277.842619) (xy 90.424223 -277.832775) (xy 90.473398 -277.830794) (xy 90.522253 -277.836726)
			(xy 90.569524 -277.850418) (xy 90.613986 -277.871516) (xy 90.654489 -277.899472) (xy 90.689982 -277.933564)
			(xy 90.719547 -277.972908) (xy 90.742418 -278.016485) (xy 90.758002 -278.063166) (xy 90.765897 -278.111743)
			(xy 90.766392 -278.13635) (xy 91.084903 -278.13635) (xy 91.088998 -278.085622) (xy 91.101177 -278.036208)
			(xy 91.121125 -277.989388) (xy 91.148326 -277.946374) (xy 91.182074 -277.90828) (xy 91.221496 -277.876093)
			(xy 91.26557 -277.850647) (xy 91.313156 -277.8326) (xy 91.36302 -277.82242) (xy 91.413872 -277.820371)
			(xy 91.464393 -277.826505) (xy 91.513277 -277.840665) (xy 91.559256 -277.862482) (xy 91.60114 -277.891392)
			(xy 91.637844 -277.926647) (xy 91.668417 -277.967333) (xy 91.692068 -278.012396) (xy 91.708184 -278.06067)
			(xy 91.716348 -278.110904) (xy 91.71686 -278.13635) (xy 92.024703 -278.13635) (xy 92.028798 -278.085622)
			(xy 92.040977 -278.036208) (xy 92.060925 -277.989388) (xy 92.088126 -277.946374) (xy 92.121874 -277.90828)
			(xy 92.161296 -277.876093) (xy 92.20537 -277.850647) (xy 92.252956 -277.8326) (xy 92.30282 -277.82242)
			(xy 92.353672 -277.820371) (xy 92.404193 -277.826505) (xy 92.453077 -277.840665) (xy 92.499056 -277.862482)
			(xy 92.54094 -277.891392) (xy 92.577644 -277.926647) (xy 92.608217 -277.967333) (xy 92.631868 -278.012396)
			(xy 92.647984 -278.06067) (xy 92.656148 -278.110904) (xy 92.65666 -278.13635) (xy 92.975188 -278.13635)
			(xy 92.979148 -278.087296) (xy 92.990925 -278.039512) (xy 93.010216 -277.994236) (xy 93.036519 -277.95264)
			(xy 93.069154 -277.915803) (xy 93.107275 -277.884678) (xy 93.149896 -277.860071) (xy 93.195912 -277.842619)
			(xy 93.244131 -277.832775) (xy 93.293306 -277.830794) (xy 93.342161 -277.836726) (xy 93.389432 -277.850418)
			(xy 93.433894 -277.871516) (xy 93.474397 -277.899472) (xy 93.50989 -277.933564) (xy 93.539455 -277.972908)
			(xy 93.562326 -278.016485) (xy 93.57791 -278.063166) (xy 93.585805 -278.111743) (xy 93.5863 -278.13635)
			(xy 93.904811 -278.13635) (xy 93.908906 -278.085622) (xy 93.921085 -278.036208) (xy 93.941033 -277.989388)
			(xy 93.968234 -277.946374) (xy 94.001982 -277.90828) (xy 94.041404 -277.876093) (xy 94.085478 -277.850647)
			(xy 94.133064 -277.8326) (xy 94.182928 -277.82242) (xy 94.23378 -277.820371) (xy 94.284301 -277.826505)
			(xy 94.333185 -277.840665) (xy 94.379164 -277.862482) (xy 94.421048 -277.891392) (xy 94.457752 -277.926647)
			(xy 94.488325 -277.967333) (xy 94.511976 -278.012396) (xy 94.528092 -278.06067) (xy 94.536256 -278.110904)
			(xy 94.536768 -278.13635) (xy 94.855296 -278.13635) (xy 94.859256 -278.087296) (xy 94.871033 -278.039512)
			(xy 94.890324 -277.994236) (xy 94.916627 -277.95264) (xy 94.949262 -277.915803) (xy 94.987383 -277.884678)
			(xy 95.030004 -277.860071) (xy 95.07602 -277.842619) (xy 95.124239 -277.832775) (xy 95.173414 -277.830794)
			(xy 95.222269 -277.836726) (xy 95.26954 -277.850418) (xy 95.314002 -277.871516) (xy 95.354505 -277.899472)
			(xy 95.389998 -277.933564) (xy 95.419563 -277.972908) (xy 95.442434 -278.016485) (xy 95.458018 -278.063166)
			(xy 95.465913 -278.111743) (xy 95.466408 -278.13635) (xy 95.784919 -278.13635) (xy 95.789014 -278.085622)
			(xy 95.801193 -278.036208) (xy 95.821141 -277.989388) (xy 95.848342 -277.946374) (xy 95.88209 -277.90828)
			(xy 95.921512 -277.876093) (xy 95.965586 -277.850647) (xy 96.013172 -277.8326) (xy 96.063036 -277.82242)
			(xy 96.113888 -277.820371) (xy 96.164409 -277.826505) (xy 96.213293 -277.840665) (xy 96.259272 -277.862482)
			(xy 96.301156 -277.891392) (xy 96.33786 -277.926647) (xy 96.368433 -277.967333) (xy 96.392084 -278.012396)
			(xy 96.4082 -278.06067) (xy 96.416364 -278.110904) (xy 96.416876 -278.13635) (xy 96.73515 -278.13635)
			(xy 96.73911 -278.087296) (xy 96.750887 -278.039512) (xy 96.770178 -277.994236) (xy 96.796481 -277.95264)
			(xy 96.829116 -277.915803) (xy 96.867237 -277.884678) (xy 96.909858 -277.860071) (xy 96.955874 -277.842619)
			(xy 97.004093 -277.832775) (xy 97.053268 -277.830794) (xy 97.102123 -277.836726) (xy 97.149394 -277.850418)
			(xy 97.193856 -277.871516) (xy 97.234359 -277.899472) (xy 97.269852 -277.933564) (xy 97.299417 -277.972908)
			(xy 97.322288 -278.016485) (xy 97.337872 -278.063166) (xy 97.345767 -278.111743) (xy 97.346262 -278.13635)
			(xy 97.664773 -278.13635) (xy 97.668868 -278.085622) (xy 97.681047 -278.036208) (xy 97.700995 -277.989388)
			(xy 97.728196 -277.946374) (xy 97.761944 -277.90828) (xy 97.801366 -277.876093) (xy 97.84544 -277.850647)
			(xy 97.893026 -277.8326) (xy 97.94289 -277.82242) (xy 97.993742 -277.820371) (xy 98.044263 -277.826505)
			(xy 98.093147 -277.840665) (xy 98.139126 -277.862482) (xy 98.18101 -277.891392) (xy 98.217714 -277.926647)
			(xy 98.248287 -277.967333) (xy 98.271938 -278.012396) (xy 98.288054 -278.06067) (xy 98.296218 -278.110904)
			(xy 98.29673 -278.13635) (xy 98.604827 -278.13635) (xy 98.608922 -278.085622) (xy 98.621101 -278.036208)
			(xy 98.641049 -277.989388) (xy 98.66825 -277.946374) (xy 98.701998 -277.90828) (xy 98.74142 -277.876093)
			(xy 98.785494 -277.850647) (xy 98.83308 -277.8326) (xy 98.882944 -277.82242) (xy 98.933796 -277.820371)
			(xy 98.984317 -277.826505) (xy 99.033201 -277.840665) (xy 99.07918 -277.862482) (xy 99.121064 -277.891392)
			(xy 99.157768 -277.926647) (xy 99.188341 -277.967333) (xy 99.211992 -278.012396) (xy 99.228108 -278.06067)
			(xy 99.236272 -278.110904) (xy 99.236784 -278.13635) (xy 99.555312 -278.13635) (xy 99.559272 -278.087296)
			(xy 99.571049 -278.039512) (xy 99.59034 -277.994236) (xy 99.616643 -277.95264) (xy 99.649278 -277.915803)
			(xy 99.687399 -277.884678) (xy 99.73002 -277.860071) (xy 99.776036 -277.842619) (xy 99.824255 -277.832775)
			(xy 99.87343 -277.830794) (xy 99.922285 -277.836726) (xy 99.969556 -277.850418) (xy 100.014018 -277.871516)
			(xy 100.054521 -277.899472) (xy 100.090014 -277.933564) (xy 100.119579 -277.972908) (xy 100.14245 -278.016485)
			(xy 100.158034 -278.063166) (xy 100.165929 -278.111743) (xy 100.166424 -278.13635) (xy 100.484935 -278.13635)
			(xy 100.48903 -278.085622) (xy 100.501209 -278.036208) (xy 100.521157 -277.989388) (xy 100.548358 -277.946374)
			(xy 100.582106 -277.90828) (xy 100.621528 -277.876093) (xy 100.665602 -277.850647) (xy 100.713188 -277.8326)
			(xy 100.763052 -277.82242) (xy 100.813904 -277.820371) (xy 100.864425 -277.826505) (xy 100.913309 -277.840665)
			(xy 100.959288 -277.862482) (xy 101.001172 -277.891392) (xy 101.037876 -277.926647) (xy 101.068449 -277.967333)
			(xy 101.0921 -278.012396) (xy 101.108216 -278.06067) (xy 101.11638 -278.110904) (xy 101.116892 -278.13635)
			(xy 101.424735 -278.13635) (xy 101.42883 -278.085622) (xy 101.441009 -278.036208) (xy 101.460957 -277.989388)
			(xy 101.488158 -277.946374) (xy 101.521906 -277.90828) (xy 101.561328 -277.876093) (xy 101.605402 -277.850647)
			(xy 101.652988 -277.8326) (xy 101.702852 -277.82242) (xy 101.753704 -277.820371) (xy 101.804225 -277.826505)
			(xy 101.853109 -277.840665) (xy 101.899088 -277.862482) (xy 101.940972 -277.891392) (xy 101.977676 -277.926647)
			(xy 102.008249 -277.967333) (xy 102.0319 -278.012396) (xy 102.048016 -278.06067) (xy 102.05618 -278.110904)
			(xy 102.056692 -278.13635) (xy 102.05618 -278.161796) (xy 102.048016 -278.21203) (xy 102.0319 -278.260304)
			(xy 102.008249 -278.305367) (xy 101.977676 -278.346053) (xy 101.940972 -278.381308) (xy 101.899088 -278.410218)
			(xy 101.853109 -278.432035) (xy 101.804225 -278.446195) (xy 101.753704 -278.452329) (xy 101.702852 -278.45028)
			(xy 101.652988 -278.4401) (xy 101.605402 -278.422053) (xy 101.561328 -278.396607) (xy 101.521906 -278.36442)
			(xy 101.488158 -278.326326) (xy 101.460957 -278.283312) (xy 101.441009 -278.236492) (xy 101.42883 -278.187078)
			(xy 101.424735 -278.13635) (xy 101.116892 -278.13635) (xy 101.11638 -278.161796) (xy 101.108216 -278.21203)
			(xy 101.0921 -278.260304) (xy 101.068449 -278.305367) (xy 101.037876 -278.346053) (xy 101.001172 -278.381308)
			(xy 100.959288 -278.410218) (xy 100.913309 -278.432035) (xy 100.864425 -278.446195) (xy 100.813904 -278.452329)
			(xy 100.763052 -278.45028) (xy 100.713188 -278.4401) (xy 100.665602 -278.422053) (xy 100.621528 -278.396607)
			(xy 100.582106 -278.36442) (xy 100.548358 -278.326326) (xy 100.521157 -278.283312) (xy 100.501209 -278.236492)
			(xy 100.48903 -278.187078) (xy 100.484935 -278.13635) (xy 100.166424 -278.13635) (xy 100.165929 -278.160957)
			(xy 100.158034 -278.209534) (xy 100.14245 -278.256215) (xy 100.119579 -278.299792) (xy 100.090014 -278.339136)
			(xy 100.054521 -278.373228) (xy 100.014018 -278.401184) (xy 99.969556 -278.422282) (xy 99.922285 -278.435974)
			(xy 99.87343 -278.441906) (xy 99.824255 -278.439925) (xy 99.776036 -278.430081) (xy 99.73002 -278.412629)
			(xy 99.687399 -278.388022) (xy 99.649278 -278.356897) (xy 99.616643 -278.32006) (xy 99.59034 -278.278464)
			(xy 99.571049 -278.233188) (xy 99.559272 -278.185404) (xy 99.555312 -278.13635) (xy 99.236784 -278.13635)
			(xy 99.236272 -278.161796) (xy 99.228108 -278.21203) (xy 99.211992 -278.260304) (xy 99.188341 -278.305367)
			(xy 99.157768 -278.346053) (xy 99.121064 -278.381308) (xy 99.07918 -278.410218) (xy 99.033201 -278.432035)
			(xy 98.984317 -278.446195) (xy 98.933796 -278.452329) (xy 98.882944 -278.45028) (xy 98.83308 -278.4401)
			(xy 98.785494 -278.422053) (xy 98.74142 -278.396607) (xy 98.701998 -278.36442) (xy 98.66825 -278.326326)
			(xy 98.641049 -278.283312) (xy 98.621101 -278.236492) (xy 98.608922 -278.187078) (xy 98.604827 -278.13635)
			(xy 98.29673 -278.13635) (xy 98.296218 -278.161796) (xy 98.288054 -278.21203) (xy 98.271938 -278.260304)
			(xy 98.248287 -278.305367) (xy 98.217714 -278.346053) (xy 98.18101 -278.381308) (xy 98.139126 -278.410218)
			(xy 98.093147 -278.432035) (xy 98.044263 -278.446195) (xy 97.993742 -278.452329) (xy 97.94289 -278.45028)
			(xy 97.893026 -278.4401) (xy 97.84544 -278.422053) (xy 97.801366 -278.396607) (xy 97.761944 -278.36442)
			(xy 97.728196 -278.326326) (xy 97.700995 -278.283312) (xy 97.681047 -278.236492) (xy 97.668868 -278.187078)
			(xy 97.664773 -278.13635) (xy 97.346262 -278.13635) (xy 97.345767 -278.160957) (xy 97.337872 -278.209534)
			(xy 97.322288 -278.256215) (xy 97.299417 -278.299792) (xy 97.269852 -278.339136) (xy 97.234359 -278.373228)
			(xy 97.193856 -278.401184) (xy 97.149394 -278.422282) (xy 97.102123 -278.435974) (xy 97.053268 -278.441906)
			(xy 97.004093 -278.439925) (xy 96.955874 -278.430081) (xy 96.909858 -278.412629) (xy 96.867237 -278.388022)
			(xy 96.829116 -278.356897) (xy 96.796481 -278.32006) (xy 96.770178 -278.278464) (xy 96.750887 -278.233188)
			(xy 96.73911 -278.185404) (xy 96.73515 -278.13635) (xy 96.416876 -278.13635) (xy 96.416364 -278.161796)
			(xy 96.4082 -278.21203) (xy 96.392084 -278.260304) (xy 96.368433 -278.305367) (xy 96.33786 -278.346053)
			(xy 96.301156 -278.381308) (xy 96.259272 -278.410218) (xy 96.213293 -278.432035) (xy 96.164409 -278.446195)
			(xy 96.113888 -278.452329) (xy 96.063036 -278.45028) (xy 96.013172 -278.4401) (xy 95.965586 -278.422053)
			(xy 95.921512 -278.396607) (xy 95.88209 -278.36442) (xy 95.848342 -278.326326) (xy 95.821141 -278.283312)
			(xy 95.801193 -278.236492) (xy 95.789014 -278.187078) (xy 95.784919 -278.13635) (xy 95.466408 -278.13635)
			(xy 95.465913 -278.160957) (xy 95.458018 -278.209534) (xy 95.442434 -278.256215) (xy 95.419563 -278.299792)
			(xy 95.389998 -278.339136) (xy 95.354505 -278.373228) (xy 95.314002 -278.401184) (xy 95.26954 -278.422282)
			(xy 95.222269 -278.435974) (xy 95.173414 -278.441906) (xy 95.124239 -278.439925) (xy 95.07602 -278.430081)
			(xy 95.030004 -278.412629) (xy 94.987383 -278.388022) (xy 94.949262 -278.356897) (xy 94.916627 -278.32006)
			(xy 94.890324 -278.278464) (xy 94.871033 -278.233188) (xy 94.859256 -278.185404) (xy 94.855296 -278.13635)
			(xy 94.536768 -278.13635) (xy 94.536256 -278.161796) (xy 94.528092 -278.21203) (xy 94.511976 -278.260304)
			(xy 94.488325 -278.305367) (xy 94.457752 -278.346053) (xy 94.421048 -278.381308) (xy 94.379164 -278.410218)
			(xy 94.333185 -278.432035) (xy 94.284301 -278.446195) (xy 94.23378 -278.452329) (xy 94.182928 -278.45028)
			(xy 94.133064 -278.4401) (xy 94.085478 -278.422053) (xy 94.041404 -278.396607) (xy 94.001982 -278.36442)
			(xy 93.968234 -278.326326) (xy 93.941033 -278.283312) (xy 93.921085 -278.236492) (xy 93.908906 -278.187078)
			(xy 93.904811 -278.13635) (xy 93.5863 -278.13635) (xy 93.585805 -278.160957) (xy 93.57791 -278.209534)
			(xy 93.562326 -278.256215) (xy 93.539455 -278.299792) (xy 93.50989 -278.339136) (xy 93.474397 -278.373228)
			(xy 93.433894 -278.401184) (xy 93.389432 -278.422282) (xy 93.342161 -278.435974) (xy 93.293306 -278.441906)
			(xy 93.244131 -278.439925) (xy 93.195912 -278.430081) (xy 93.149896 -278.412629) (xy 93.107275 -278.388022)
			(xy 93.069154 -278.356897) (xy 93.036519 -278.32006) (xy 93.010216 -278.278464) (xy 92.990925 -278.233188)
			(xy 92.979148 -278.185404) (xy 92.975188 -278.13635) (xy 92.65666 -278.13635) (xy 92.656148 -278.161796)
			(xy 92.647984 -278.21203) (xy 92.631868 -278.260304) (xy 92.608217 -278.305367) (xy 92.577644 -278.346053)
			(xy 92.54094 -278.381308) (xy 92.499056 -278.410218) (xy 92.453077 -278.432035) (xy 92.404193 -278.446195)
			(xy 92.353672 -278.452329) (xy 92.30282 -278.45028) (xy 92.252956 -278.4401) (xy 92.20537 -278.422053)
			(xy 92.161296 -278.396607) (xy 92.121874 -278.36442) (xy 92.088126 -278.326326) (xy 92.060925 -278.283312)
			(xy 92.040977 -278.236492) (xy 92.028798 -278.187078) (xy 92.024703 -278.13635) (xy 91.71686 -278.13635)
			(xy 91.716348 -278.161796) (xy 91.708184 -278.21203) (xy 91.692068 -278.260304) (xy 91.668417 -278.305367)
			(xy 91.637844 -278.346053) (xy 91.60114 -278.381308) (xy 91.559256 -278.410218) (xy 91.513277 -278.432035)
			(xy 91.464393 -278.446195) (xy 91.413872 -278.452329) (xy 91.36302 -278.45028) (xy 91.313156 -278.4401)
			(xy 91.26557 -278.422053) (xy 91.221496 -278.396607) (xy 91.182074 -278.36442) (xy 91.148326 -278.326326)
			(xy 91.121125 -278.283312) (xy 91.101177 -278.236492) (xy 91.088998 -278.187078) (xy 91.084903 -278.13635)
			(xy 90.766392 -278.13635) (xy 90.765897 -278.160957) (xy 90.758002 -278.209534) (xy 90.742418 -278.256215)
			(xy 90.719547 -278.299792) (xy 90.689982 -278.339136) (xy 90.654489 -278.373228) (xy 90.613986 -278.401184)
			(xy 90.569524 -278.422282) (xy 90.522253 -278.435974) (xy 90.473398 -278.441906) (xy 90.424223 -278.439925)
			(xy 90.376004 -278.430081) (xy 90.329988 -278.412629) (xy 90.287367 -278.388022) (xy 90.249246 -278.356897)
			(xy 90.216611 -278.32006) (xy 90.190308 -278.278464) (xy 90.171017 -278.233188) (xy 90.15924 -278.185404)
			(xy 90.15528 -278.13635) (xy 89.836752 -278.13635) (xy 89.83624 -278.161796) (xy 89.828076 -278.21203)
			(xy 89.81196 -278.260304) (xy 89.788309 -278.305367) (xy 89.757736 -278.346053) (xy 89.721032 -278.381308)
			(xy 89.679148 -278.410218) (xy 89.633169 -278.432035) (xy 89.584285 -278.446195) (xy 89.533764 -278.452329)
			(xy 89.482912 -278.45028) (xy 89.433048 -278.4401) (xy 89.385462 -278.422053) (xy 89.341388 -278.396607)
			(xy 89.301966 -278.36442) (xy 89.268218 -278.326326) (xy 89.241017 -278.283312) (xy 89.221069 -278.236492)
			(xy 89.20889 -278.187078) (xy 89.204795 -278.13635) (xy 88.886284 -278.13635) (xy 88.885789 -278.160957)
			(xy 88.877894 -278.209534) (xy 88.86231 -278.256215) (xy 88.839439 -278.299792) (xy 88.809874 -278.339136)
			(xy 88.774381 -278.373228) (xy 88.733878 -278.401184) (xy 88.689416 -278.422282) (xy 88.642145 -278.435974)
			(xy 88.59329 -278.441906) (xy 88.544115 -278.439925) (xy 88.495896 -278.430081) (xy 88.44988 -278.412629)
			(xy 88.407259 -278.388022) (xy 88.369138 -278.356897) (xy 88.336503 -278.32006) (xy 88.3102 -278.278464)
			(xy 88.290909 -278.233188) (xy 88.279132 -278.185404) (xy 88.275172 -278.13635) (xy 87.956644 -278.13635)
			(xy 87.956132 -278.161796) (xy 87.947968 -278.21203) (xy 87.931852 -278.260304) (xy 87.908201 -278.305367)
			(xy 87.877628 -278.346053) (xy 87.840924 -278.381308) (xy 87.79904 -278.410218) (xy 87.753061 -278.432035)
			(xy 87.704177 -278.446195) (xy 87.653656 -278.452329) (xy 87.602804 -278.45028) (xy 87.55294 -278.4401)
			(xy 87.505354 -278.422053) (xy 87.46128 -278.396607) (xy 87.421858 -278.36442) (xy 87.38811 -278.326326)
			(xy 87.360909 -278.283312) (xy 87.340961 -278.236492) (xy 87.328782 -278.187078) (xy 87.324687 -278.13635)
			(xy 87.00643 -278.13635) (xy 87.005935 -278.160957) (xy 86.99804 -278.209534) (xy 86.982456 -278.256215)
			(xy 86.959585 -278.299792) (xy 86.93002 -278.339136) (xy 86.894527 -278.373228) (xy 86.854024 -278.401184)
			(xy 86.809562 -278.422282) (xy 86.762291 -278.435974) (xy 86.713436 -278.441906) (xy 86.664261 -278.439925)
			(xy 86.616042 -278.430081) (xy 86.570026 -278.412629) (xy 86.527405 -278.388022) (xy 86.489284 -278.356897)
			(xy 86.456649 -278.32006) (xy 86.430346 -278.278464) (xy 86.411055 -278.233188) (xy 86.399278 -278.185404)
			(xy 86.395318 -278.13635) (xy 86.07679 -278.13635) (xy 86.076278 -278.161796) (xy 86.068114 -278.21203)
			(xy 86.051998 -278.260304) (xy 86.028347 -278.305367) (xy 85.997774 -278.346053) (xy 85.96107 -278.381308)
			(xy 85.919186 -278.410218) (xy 85.873207 -278.432035) (xy 85.824323 -278.446195) (xy 85.773802 -278.452329)
			(xy 85.72295 -278.45028) (xy 85.673086 -278.4401) (xy 85.6255 -278.422053) (xy 85.581426 -278.396607)
			(xy 85.542004 -278.36442) (xy 85.508256 -278.326326) (xy 85.481055 -278.283312) (xy 85.461107 -278.236492)
			(xy 85.448928 -278.187078) (xy 85.444833 -278.13635) (xy 85.136736 -278.13635) (xy 85.136224 -278.161796)
			(xy 85.12806 -278.21203) (xy 85.111944 -278.260304) (xy 85.088293 -278.305367) (xy 85.05772 -278.346053)
			(xy 85.021016 -278.381308) (xy 84.979132 -278.410218) (xy 84.933153 -278.432035) (xy 84.884269 -278.446195)
			(xy 84.833748 -278.452329) (xy 84.782896 -278.45028) (xy 84.733032 -278.4401) (xy 84.685446 -278.422053)
			(xy 84.641372 -278.396607) (xy 84.60195 -278.36442) (xy 84.568202 -278.326326) (xy 84.541001 -278.283312)
			(xy 84.521053 -278.236492) (xy 84.508874 -278.187078) (xy 84.504779 -278.13635) (xy 84.186268 -278.13635)
			(xy 84.185773 -278.160957) (xy 84.177878 -278.209534) (xy 84.162294 -278.256215) (xy 84.139423 -278.299792)
			(xy 84.109858 -278.339136) (xy 84.074365 -278.373228) (xy 84.033862 -278.401184) (xy 83.9894 -278.422282)
			(xy 83.942129 -278.435974) (xy 83.893274 -278.441906) (xy 83.844099 -278.439925) (xy 83.79588 -278.430081)
			(xy 83.749864 -278.412629) (xy 83.707243 -278.388022) (xy 83.669122 -278.356897) (xy 83.636487 -278.32006)
			(xy 83.610184 -278.278464) (xy 83.590893 -278.233188) (xy 83.579116 -278.185404) (xy 83.575156 -278.13635)
			(xy 83.256628 -278.13635) (xy 83.256116 -278.161796) (xy 83.247952 -278.21203) (xy 83.231836 -278.260304)
			(xy 83.208185 -278.305367) (xy 83.177612 -278.346053) (xy 83.140908 -278.381308) (xy 83.099024 -278.410218)
			(xy 83.053045 -278.432035) (xy 83.004161 -278.446195) (xy 82.95364 -278.452329) (xy 82.902788 -278.45028)
			(xy 82.852924 -278.4401) (xy 82.805338 -278.422053) (xy 82.761264 -278.396607) (xy 82.721842 -278.36442)
			(xy 82.688094 -278.326326) (xy 82.660893 -278.283312) (xy 82.640945 -278.236492) (xy 82.628766 -278.187078)
			(xy 82.624671 -278.13635) (xy 82.306414 -278.13635) (xy 82.305919 -278.160957) (xy 82.298024 -278.209534)
			(xy 82.28244 -278.256215) (xy 82.259569 -278.299792) (xy 82.230004 -278.339136) (xy 82.194511 -278.373228)
			(xy 82.154008 -278.401184) (xy 82.109546 -278.422282) (xy 82.062275 -278.435974) (xy 82.01342 -278.441906)
			(xy 81.964245 -278.439925) (xy 81.916026 -278.430081) (xy 81.87001 -278.412629) (xy 81.827389 -278.388022)
			(xy 81.789268 -278.356897) (xy 81.756633 -278.32006) (xy 81.73033 -278.278464) (xy 81.711039 -278.233188)
			(xy 81.699262 -278.185404) (xy 81.695302 -278.13635) (xy 81.376774 -278.13635) (xy 81.376262 -278.161796)
			(xy 81.368098 -278.21203) (xy 81.351982 -278.260304) (xy 81.328331 -278.305367) (xy 81.297758 -278.346053)
			(xy 81.261054 -278.381308) (xy 81.21917 -278.410218) (xy 81.173191 -278.432035) (xy 81.124307 -278.446195)
			(xy 81.073786 -278.452329) (xy 81.022934 -278.45028) (xy 80.97307 -278.4401) (xy 80.925484 -278.422053)
			(xy 80.88141 -278.396607) (xy 80.841988 -278.36442) (xy 80.80824 -278.326326) (xy 80.781039 -278.283312)
			(xy 80.761091 -278.236492) (xy 80.748912 -278.187078) (xy 80.744817 -278.13635) (xy 80.426306 -278.13635)
			(xy 80.425811 -278.160957) (xy 80.417916 -278.209534) (xy 80.402332 -278.256215) (xy 80.379461 -278.299792)
			(xy 80.349896 -278.339136) (xy 80.314403 -278.373228) (xy 80.2739 -278.401184) (xy 80.229438 -278.422282)
			(xy 80.182167 -278.435974) (xy 80.133312 -278.441906) (xy 80.084137 -278.439925) (xy 80.035918 -278.430081)
			(xy 79.989902 -278.412629) (xy 79.947281 -278.388022) (xy 79.90916 -278.356897) (xy 79.876525 -278.32006)
			(xy 79.850222 -278.278464) (xy 79.830931 -278.233188) (xy 79.819154 -278.185404) (xy 79.815194 -278.13635)
			(xy 77.263451 -278.13635) (xy 77.221316 -278.156344) (xy 77.174045 -278.170036) (xy 77.12519 -278.175968)
			(xy 77.076015 -278.173987) (xy 77.027796 -278.164143) (xy 76.98178 -278.146691) (xy 76.939159 -278.122084)
			(xy 76.901038 -278.090959) (xy 76.868403 -278.054122) (xy 76.8421 -278.012526) (xy 76.822809 -277.96725)
			(xy 76.811032 -277.919466) (xy 76.807072 -277.870412) (xy 73.228962 -277.870412) (xy 73.228962 -278.946356)
			(xy 78.40524 -278.946356) (xy 78.4092 -278.897302) (xy 78.420977 -278.849518) (xy 78.440268 -278.804242)
			(xy 78.466571 -278.762646) (xy 78.499206 -278.725809) (xy 78.537327 -278.694684) (xy 78.579948 -278.670077)
			(xy 78.625964 -278.652625) (xy 78.674183 -278.642781) (xy 78.723358 -278.6408) (xy 78.772213 -278.646732)
			(xy 78.819484 -278.660424) (xy 78.863946 -278.681522) (xy 78.904449 -278.709478) (xy 78.939942 -278.74357)
			(xy 78.969507 -278.782914) (xy 78.992378 -278.826491) (xy 79.007962 -278.873172) (xy 79.015857 -278.921749)
			(xy 79.016352 -278.946356) (xy 80.285348 -278.946356) (xy 80.289308 -278.897302) (xy 80.301085 -278.849518)
			(xy 80.320376 -278.804242) (xy 80.346679 -278.762646) (xy 80.379314 -278.725809) (xy 80.417435 -278.694684)
			(xy 80.460056 -278.670077) (xy 80.506072 -278.652625) (xy 80.554291 -278.642781) (xy 80.603466 -278.6408)
			(xy 80.652321 -278.646732) (xy 80.699592 -278.660424) (xy 80.744054 -278.681522) (xy 80.784557 -278.709478)
			(xy 80.82005 -278.74357) (xy 80.849615 -278.782914) (xy 80.872486 -278.826491) (xy 80.88807 -278.873172)
			(xy 80.895965 -278.921749) (xy 80.89646 -278.946356) (xy 81.214717 -278.946356) (xy 81.218812 -278.895628)
			(xy 81.230991 -278.846214) (xy 81.250939 -278.799394) (xy 81.27814 -278.75638) (xy 81.311888 -278.718286)
			(xy 81.35131 -278.686099) (xy 81.395384 -278.660653) (xy 81.44297 -278.642606) (xy 81.492834 -278.632426)
			(xy 81.543686 -278.630377) (xy 81.594207 -278.636511) (xy 81.643091 -278.650671) (xy 81.68907 -278.672488)
			(xy 81.730954 -278.701398) (xy 81.767658 -278.736653) (xy 81.798231 -278.777339) (xy 81.821882 -278.822402)
			(xy 81.837998 -278.870676) (xy 81.846162 -278.92091) (xy 81.846674 -278.946356) (xy 82.154771 -278.946356)
			(xy 82.158866 -278.895628) (xy 82.171045 -278.846214) (xy 82.190993 -278.799394) (xy 82.218194 -278.75638)
			(xy 82.251942 -278.718286) (xy 82.291364 -278.686099) (xy 82.335438 -278.660653) (xy 82.383024 -278.642606)
			(xy 82.432888 -278.632426) (xy 82.48374 -278.630377) (xy 82.534261 -278.636511) (xy 82.583145 -278.650671)
			(xy 82.629124 -278.672488) (xy 82.671008 -278.701398) (xy 82.707712 -278.736653) (xy 82.738285 -278.777339)
			(xy 82.761936 -278.822402) (xy 82.778052 -278.870676) (xy 82.786216 -278.92091) (xy 82.786728 -278.946356)
			(xy 83.105256 -278.946356) (xy 83.109216 -278.897302) (xy 83.120993 -278.849518) (xy 83.140284 -278.804242)
			(xy 83.166587 -278.762646) (xy 83.199222 -278.725809) (xy 83.237343 -278.694684) (xy 83.279964 -278.670077)
			(xy 83.32598 -278.652625) (xy 83.374199 -278.642781) (xy 83.423374 -278.6408) (xy 83.472229 -278.646732)
			(xy 83.5195 -278.660424) (xy 83.563962 -278.681522) (xy 83.604465 -278.709478) (xy 83.639958 -278.74357)
			(xy 83.669523 -278.782914) (xy 83.692394 -278.826491) (xy 83.707978 -278.873172) (xy 83.715873 -278.921749)
			(xy 83.716368 -278.946356) (xy 84.034879 -278.946356) (xy 84.038974 -278.895628) (xy 84.051153 -278.846214)
			(xy 84.071101 -278.799394) (xy 84.098302 -278.75638) (xy 84.13205 -278.718286) (xy 84.171472 -278.686099)
			(xy 84.215546 -278.660653) (xy 84.263132 -278.642606) (xy 84.312996 -278.632426) (xy 84.363848 -278.630377)
			(xy 84.414369 -278.636511) (xy 84.463253 -278.650671) (xy 84.509232 -278.672488) (xy 84.551116 -278.701398)
			(xy 84.58782 -278.736653) (xy 84.618393 -278.777339) (xy 84.642044 -278.822402) (xy 84.65816 -278.870676)
			(xy 84.666324 -278.92091) (xy 84.666836 -278.946356) (xy 84.98511 -278.946356) (xy 84.98907 -278.897302)
			(xy 85.000847 -278.849518) (xy 85.020138 -278.804242) (xy 85.046441 -278.762646) (xy 85.079076 -278.725809)
			(xy 85.117197 -278.694684) (xy 85.159818 -278.670077) (xy 85.205834 -278.652625) (xy 85.254053 -278.642781)
			(xy 85.303228 -278.6408) (xy 85.352083 -278.646732) (xy 85.399354 -278.660424) (xy 85.443816 -278.681522)
			(xy 85.484319 -278.709478) (xy 85.519812 -278.74357) (xy 85.549377 -278.782914) (xy 85.572248 -278.826491)
			(xy 85.587832 -278.873172) (xy 85.595727 -278.921749) (xy 85.596222 -278.946356) (xy 85.914733 -278.946356)
			(xy 85.918828 -278.895628) (xy 85.931007 -278.846214) (xy 85.950955 -278.799394) (xy 85.978156 -278.75638)
			(xy 86.011904 -278.718286) (xy 86.051326 -278.686099) (xy 86.0954 -278.660653) (xy 86.142986 -278.642606)
			(xy 86.19285 -278.632426) (xy 86.243702 -278.630377) (xy 86.294223 -278.636511) (xy 86.343107 -278.650671)
			(xy 86.389086 -278.672488) (xy 86.43097 -278.701398) (xy 86.467674 -278.736653) (xy 86.498247 -278.777339)
			(xy 86.521898 -278.822402) (xy 86.538014 -278.870676) (xy 86.546178 -278.92091) (xy 86.54669 -278.946356)
			(xy 86.865218 -278.946356) (xy 86.869178 -278.897302) (xy 86.880955 -278.849518) (xy 86.900246 -278.804242)
			(xy 86.926549 -278.762646) (xy 86.959184 -278.725809) (xy 86.997305 -278.694684) (xy 87.039926 -278.670077)
			(xy 87.085942 -278.652625) (xy 87.134161 -278.642781) (xy 87.183336 -278.6408) (xy 87.232191 -278.646732)
			(xy 87.279462 -278.660424) (xy 87.323924 -278.681522) (xy 87.364427 -278.709478) (xy 87.39992 -278.74357)
			(xy 87.429485 -278.782914) (xy 87.452356 -278.826491) (xy 87.46794 -278.873172) (xy 87.475835 -278.921749)
			(xy 87.47633 -278.946356) (xy 87.794841 -278.946356) (xy 87.798936 -278.895628) (xy 87.811115 -278.846214)
			(xy 87.831063 -278.799394) (xy 87.858264 -278.75638) (xy 87.892012 -278.718286) (xy 87.931434 -278.686099)
			(xy 87.975508 -278.660653) (xy 88.023094 -278.642606) (xy 88.072958 -278.632426) (xy 88.12381 -278.630377)
			(xy 88.174331 -278.636511) (xy 88.223215 -278.650671) (xy 88.269194 -278.672488) (xy 88.311078 -278.701398)
			(xy 88.347782 -278.736653) (xy 88.378355 -278.777339) (xy 88.402006 -278.822402) (xy 88.418122 -278.870676)
			(xy 88.426286 -278.92091) (xy 88.426798 -278.946356) (xy 88.734895 -278.946356) (xy 88.73899 -278.895628)
			(xy 88.751169 -278.846214) (xy 88.771117 -278.799394) (xy 88.798318 -278.75638) (xy 88.832066 -278.718286)
			(xy 88.871488 -278.686099) (xy 88.915562 -278.660653) (xy 88.963148 -278.642606) (xy 89.013012 -278.632426)
			(xy 89.063864 -278.630377) (xy 89.114385 -278.636511) (xy 89.163269 -278.650671) (xy 89.209248 -278.672488)
			(xy 89.251132 -278.701398) (xy 89.287836 -278.736653) (xy 89.318409 -278.777339) (xy 89.34206 -278.822402)
			(xy 89.358176 -278.870676) (xy 89.36634 -278.92091) (xy 89.366852 -278.946356) (xy 89.685126 -278.946356)
			(xy 89.689086 -278.897302) (xy 89.700863 -278.849518) (xy 89.720154 -278.804242) (xy 89.746457 -278.762646)
			(xy 89.779092 -278.725809) (xy 89.817213 -278.694684) (xy 89.859834 -278.670077) (xy 89.90585 -278.652625)
			(xy 89.954069 -278.642781) (xy 90.003244 -278.6408) (xy 90.052099 -278.646732) (xy 90.09937 -278.660424)
			(xy 90.143832 -278.681522) (xy 90.184335 -278.709478) (xy 90.219828 -278.74357) (xy 90.249393 -278.782914)
			(xy 90.272264 -278.826491) (xy 90.287848 -278.873172) (xy 90.295743 -278.921749) (xy 90.296238 -278.946356)
			(xy 90.614749 -278.946356) (xy 90.618844 -278.895628) (xy 90.631023 -278.846214) (xy 90.650971 -278.799394)
			(xy 90.678172 -278.75638) (xy 90.71192 -278.718286) (xy 90.751342 -278.686099) (xy 90.795416 -278.660653)
			(xy 90.843002 -278.642606) (xy 90.892866 -278.632426) (xy 90.943718 -278.630377) (xy 90.994239 -278.636511)
			(xy 91.043123 -278.650671) (xy 91.089102 -278.672488) (xy 91.130986 -278.701398) (xy 91.16769 -278.736653)
			(xy 91.198263 -278.777339) (xy 91.221914 -278.822402) (xy 91.23803 -278.870676) (xy 91.246194 -278.92091)
			(xy 91.246706 -278.946356) (xy 91.565234 -278.946356) (xy 91.569194 -278.897302) (xy 91.580971 -278.849518)
			(xy 91.600262 -278.804242) (xy 91.626565 -278.762646) (xy 91.6592 -278.725809) (xy 91.697321 -278.694684)
			(xy 91.739942 -278.670077) (xy 91.785958 -278.652625) (xy 91.834177 -278.642781) (xy 91.883352 -278.6408)
			(xy 91.932207 -278.646732) (xy 91.979478 -278.660424) (xy 92.02394 -278.681522) (xy 92.064443 -278.709478)
			(xy 92.099936 -278.74357) (xy 92.129501 -278.782914) (xy 92.152372 -278.826491) (xy 92.167956 -278.873172)
			(xy 92.175851 -278.921749) (xy 92.176346 -278.946356) (xy 92.494857 -278.946356) (xy 92.498952 -278.895628)
			(xy 92.511131 -278.846214) (xy 92.531079 -278.799394) (xy 92.55828 -278.75638) (xy 92.592028 -278.718286)
			(xy 92.63145 -278.686099) (xy 92.675524 -278.660653) (xy 92.72311 -278.642606) (xy 92.772974 -278.632426)
			(xy 92.823826 -278.630377) (xy 92.874347 -278.636511) (xy 92.923231 -278.650671) (xy 92.96921 -278.672488)
			(xy 93.011094 -278.701398) (xy 93.047798 -278.736653) (xy 93.078371 -278.777339) (xy 93.102022 -278.822402)
			(xy 93.118138 -278.870676) (xy 93.126302 -278.92091) (xy 93.126814 -278.946356) (xy 93.445342 -278.946356)
			(xy 93.449302 -278.897302) (xy 93.461079 -278.849518) (xy 93.48037 -278.804242) (xy 93.506673 -278.762646)
			(xy 93.539308 -278.725809) (xy 93.577429 -278.694684) (xy 93.62005 -278.670077) (xy 93.666066 -278.652625)
			(xy 93.714285 -278.642781) (xy 93.76346 -278.6408) (xy 93.812315 -278.646732) (xy 93.859586 -278.660424)
			(xy 93.904048 -278.681522) (xy 93.944551 -278.709478) (xy 93.980044 -278.74357) (xy 94.009609 -278.782914)
			(xy 94.03248 -278.826491) (xy 94.048064 -278.873172) (xy 94.055959 -278.921749) (xy 94.056454 -278.946356)
			(xy 94.374711 -278.946356) (xy 94.378806 -278.895628) (xy 94.390985 -278.846214) (xy 94.410933 -278.799394)
			(xy 94.438134 -278.75638) (xy 94.471882 -278.718286) (xy 94.511304 -278.686099) (xy 94.555378 -278.660653)
			(xy 94.602964 -278.642606) (xy 94.652828 -278.632426) (xy 94.70368 -278.630377) (xy 94.754201 -278.636511)
			(xy 94.803085 -278.650671) (xy 94.849064 -278.672488) (xy 94.890948 -278.701398) (xy 94.927652 -278.736653)
			(xy 94.958225 -278.777339) (xy 94.981876 -278.822402) (xy 94.997992 -278.870676) (xy 95.006156 -278.92091)
			(xy 95.006668 -278.946356) (xy 95.314765 -278.946356) (xy 95.31886 -278.895628) (xy 95.331039 -278.846214)
			(xy 95.350987 -278.799394) (xy 95.378188 -278.75638) (xy 95.411936 -278.718286) (xy 95.451358 -278.686099)
			(xy 95.495432 -278.660653) (xy 95.543018 -278.642606) (xy 95.592882 -278.632426) (xy 95.643734 -278.630377)
			(xy 95.694255 -278.636511) (xy 95.743139 -278.650671) (xy 95.789118 -278.672488) (xy 95.831002 -278.701398)
			(xy 95.867706 -278.736653) (xy 95.898279 -278.777339) (xy 95.92193 -278.822402) (xy 95.938046 -278.870676)
			(xy 95.94621 -278.92091) (xy 95.946722 -278.946356) (xy 96.26525 -278.946356) (xy 96.26921 -278.897302)
			(xy 96.280987 -278.849518) (xy 96.300278 -278.804242) (xy 96.326581 -278.762646) (xy 96.359216 -278.725809)
			(xy 96.397337 -278.694684) (xy 96.439958 -278.670077) (xy 96.485974 -278.652625) (xy 96.534193 -278.642781)
			(xy 96.583368 -278.6408) (xy 96.632223 -278.646732) (xy 96.679494 -278.660424) (xy 96.723956 -278.681522)
			(xy 96.764459 -278.709478) (xy 96.799952 -278.74357) (xy 96.829517 -278.782914) (xy 96.852388 -278.826491)
			(xy 96.867972 -278.873172) (xy 96.875867 -278.921749) (xy 96.876362 -278.946356) (xy 99.085158 -278.946356)
			(xy 99.089118 -278.897302) (xy 99.100895 -278.849518) (xy 99.120186 -278.804242) (xy 99.146489 -278.762646)
			(xy 99.179124 -278.725809) (xy 99.217245 -278.694684) (xy 99.259866 -278.670077) (xy 99.305882 -278.652625)
			(xy 99.354101 -278.642781) (xy 99.403276 -278.6408) (xy 99.452131 -278.646732) (xy 99.499402 -278.660424)
			(xy 99.543864 -278.681522) (xy 99.584367 -278.709478) (xy 99.61986 -278.74357) (xy 99.649425 -278.782914)
			(xy 99.672296 -278.826491) (xy 99.68788 -278.873172) (xy 99.695775 -278.921749) (xy 99.69627 -278.946356)
			(xy 101.90532 -278.946356) (xy 101.90928 -278.897302) (xy 101.921057 -278.849518) (xy 101.940348 -278.804242)
			(xy 101.966651 -278.762646) (xy 101.999286 -278.725809) (xy 102.037407 -278.694684) (xy 102.080028 -278.670077)
			(xy 102.126044 -278.652625) (xy 102.174263 -278.642781) (xy 102.223438 -278.6408) (xy 102.272293 -278.646732)
			(xy 102.319564 -278.660424) (xy 102.364026 -278.681522) (xy 102.404529 -278.709478) (xy 102.440022 -278.74357)
			(xy 102.469587 -278.782914) (xy 102.492458 -278.826491) (xy 102.508042 -278.873172) (xy 102.515937 -278.921749)
			(xy 102.516432 -278.946356) (xy 102.515937 -278.970963) (xy 102.508042 -279.01954) (xy 102.492458 -279.066221)
			(xy 102.469587 -279.109798) (xy 102.440022 -279.149142) (xy 102.404529 -279.183234) (xy 102.364026 -279.21119)
			(xy 102.319564 -279.232288) (xy 102.272293 -279.24598) (xy 102.223438 -279.251912) (xy 102.174263 -279.249931)
			(xy 102.126044 -279.240087) (xy 102.080028 -279.222635) (xy 102.037407 -279.198028) (xy 101.999286 -279.166903)
			(xy 101.966651 -279.130066) (xy 101.940348 -279.08847) (xy 101.921057 -279.043194) (xy 101.90928 -278.99541)
			(xy 101.90532 -278.946356) (xy 99.69627 -278.946356) (xy 99.695775 -278.970963) (xy 99.68788 -279.01954)
			(xy 99.672296 -279.066221) (xy 99.649425 -279.109798) (xy 99.61986 -279.149142) (xy 99.584367 -279.183234)
			(xy 99.543864 -279.21119) (xy 99.499402 -279.232288) (xy 99.452131 -279.24598) (xy 99.403276 -279.251912)
			(xy 99.354101 -279.249931) (xy 99.305882 -279.240087) (xy 99.259866 -279.222635) (xy 99.217245 -279.198028)
			(xy 99.179124 -279.166903) (xy 99.146489 -279.130066) (xy 99.120186 -279.08847) (xy 99.100895 -279.043194)
			(xy 99.089118 -278.99541) (xy 99.085158 -278.946356) (xy 96.876362 -278.946356) (xy 96.875867 -278.970963)
			(xy 96.867972 -279.01954) (xy 96.852388 -279.066221) (xy 96.829517 -279.109798) (xy 96.799952 -279.149142)
			(xy 96.764459 -279.183234) (xy 96.723956 -279.21119) (xy 96.679494 -279.232288) (xy 96.632223 -279.24598)
			(xy 96.583368 -279.251912) (xy 96.534193 -279.249931) (xy 96.485974 -279.240087) (xy 96.439958 -279.222635)
			(xy 96.397337 -279.198028) (xy 96.359216 -279.166903) (xy 96.326581 -279.130066) (xy 96.300278 -279.08847)
			(xy 96.280987 -279.043194) (xy 96.26921 -278.99541) (xy 96.26525 -278.946356) (xy 95.946722 -278.946356)
			(xy 95.94621 -278.971802) (xy 95.938046 -279.022036) (xy 95.92193 -279.07031) (xy 95.898279 -279.115373)
			(xy 95.867706 -279.156059) (xy 95.831002 -279.191314) (xy 95.789118 -279.220224) (xy 95.743139 -279.242041)
			(xy 95.694255 -279.256201) (xy 95.643734 -279.262335) (xy 95.592882 -279.260286) (xy 95.543018 -279.250106)
			(xy 95.495432 -279.232059) (xy 95.451358 -279.206613) (xy 95.411936 -279.174426) (xy 95.378188 -279.136332)
			(xy 95.350987 -279.093318) (xy 95.331039 -279.046498) (xy 95.31886 -278.997084) (xy 95.314765 -278.946356)
			(xy 95.006668 -278.946356) (xy 95.006156 -278.971802) (xy 94.997992 -279.022036) (xy 94.981876 -279.07031)
			(xy 94.958225 -279.115373) (xy 94.927652 -279.156059) (xy 94.890948 -279.191314) (xy 94.849064 -279.220224)
			(xy 94.803085 -279.242041) (xy 94.754201 -279.256201) (xy 94.70368 -279.262335) (xy 94.652828 -279.260286)
			(xy 94.602964 -279.250106) (xy 94.555378 -279.232059) (xy 94.511304 -279.206613) (xy 94.471882 -279.174426)
			(xy 94.438134 -279.136332) (xy 94.410933 -279.093318) (xy 94.390985 -279.046498) (xy 94.378806 -278.997084)
			(xy 94.374711 -278.946356) (xy 94.056454 -278.946356) (xy 94.055959 -278.970963) (xy 94.048064 -279.01954)
			(xy 94.03248 -279.066221) (xy 94.009609 -279.109798) (xy 93.980044 -279.149142) (xy 93.944551 -279.183234)
			(xy 93.904048 -279.21119) (xy 93.859586 -279.232288) (xy 93.812315 -279.24598) (xy 93.76346 -279.251912)
			(xy 93.714285 -279.249931) (xy 93.666066 -279.240087) (xy 93.62005 -279.222635) (xy 93.577429 -279.198028)
			(xy 93.539308 -279.166903) (xy 93.506673 -279.130066) (xy 93.48037 -279.08847) (xy 93.461079 -279.043194)
			(xy 93.449302 -278.99541) (xy 93.445342 -278.946356) (xy 93.126814 -278.946356) (xy 93.126302 -278.971802)
			(xy 93.118138 -279.022036) (xy 93.102022 -279.07031) (xy 93.078371 -279.115373) (xy 93.047798 -279.156059)
			(xy 93.011094 -279.191314) (xy 92.96921 -279.220224) (xy 92.923231 -279.242041) (xy 92.874347 -279.256201)
			(xy 92.823826 -279.262335) (xy 92.772974 -279.260286) (xy 92.72311 -279.250106) (xy 92.675524 -279.232059)
			(xy 92.63145 -279.206613) (xy 92.592028 -279.174426) (xy 92.55828 -279.136332) (xy 92.531079 -279.093318)
			(xy 92.511131 -279.046498) (xy 92.498952 -278.997084) (xy 92.494857 -278.946356) (xy 92.176346 -278.946356)
			(xy 92.175851 -278.970963) (xy 92.167956 -279.01954) (xy 92.152372 -279.066221) (xy 92.129501 -279.109798)
			(xy 92.099936 -279.149142) (xy 92.064443 -279.183234) (xy 92.02394 -279.21119) (xy 91.979478 -279.232288)
			(xy 91.932207 -279.24598) (xy 91.883352 -279.251912) (xy 91.834177 -279.249931) (xy 91.785958 -279.240087)
			(xy 91.739942 -279.222635) (xy 91.697321 -279.198028) (xy 91.6592 -279.166903) (xy 91.626565 -279.130066)
			(xy 91.600262 -279.08847) (xy 91.580971 -279.043194) (xy 91.569194 -278.99541) (xy 91.565234 -278.946356)
			(xy 91.246706 -278.946356) (xy 91.246194 -278.971802) (xy 91.23803 -279.022036) (xy 91.221914 -279.07031)
			(xy 91.198263 -279.115373) (xy 91.16769 -279.156059) (xy 91.130986 -279.191314) (xy 91.089102 -279.220224)
			(xy 91.043123 -279.242041) (xy 90.994239 -279.256201) (xy 90.943718 -279.262335) (xy 90.892866 -279.260286)
			(xy 90.843002 -279.250106) (xy 90.795416 -279.232059) (xy 90.751342 -279.206613) (xy 90.71192 -279.174426)
			(xy 90.678172 -279.136332) (xy 90.650971 -279.093318) (xy 90.631023 -279.046498) (xy 90.618844 -278.997084)
			(xy 90.614749 -278.946356) (xy 90.296238 -278.946356) (xy 90.295743 -278.970963) (xy 90.287848 -279.01954)
			(xy 90.272264 -279.066221) (xy 90.249393 -279.109798) (xy 90.219828 -279.149142) (xy 90.184335 -279.183234)
			(xy 90.143832 -279.21119) (xy 90.09937 -279.232288) (xy 90.052099 -279.24598) (xy 90.003244 -279.251912)
			(xy 89.954069 -279.249931) (xy 89.90585 -279.240087) (xy 89.859834 -279.222635) (xy 89.817213 -279.198028)
			(xy 89.779092 -279.166903) (xy 89.746457 -279.130066) (xy 89.720154 -279.08847) (xy 89.700863 -279.043194)
			(xy 89.689086 -278.99541) (xy 89.685126 -278.946356) (xy 89.366852 -278.946356) (xy 89.36634 -278.971802)
			(xy 89.358176 -279.022036) (xy 89.34206 -279.07031) (xy 89.318409 -279.115373) (xy 89.287836 -279.156059)
			(xy 89.251132 -279.191314) (xy 89.209248 -279.220224) (xy 89.163269 -279.242041) (xy 89.114385 -279.256201)
			(xy 89.063864 -279.262335) (xy 89.013012 -279.260286) (xy 88.963148 -279.250106) (xy 88.915562 -279.232059)
			(xy 88.871488 -279.206613) (xy 88.832066 -279.174426) (xy 88.798318 -279.136332) (xy 88.771117 -279.093318)
			(xy 88.751169 -279.046498) (xy 88.73899 -278.997084) (xy 88.734895 -278.946356) (xy 88.426798 -278.946356)
			(xy 88.426286 -278.971802) (xy 88.418122 -279.022036) (xy 88.402006 -279.07031) (xy 88.378355 -279.115373)
			(xy 88.347782 -279.156059) (xy 88.311078 -279.191314) (xy 88.269194 -279.220224) (xy 88.223215 -279.242041)
			(xy 88.174331 -279.256201) (xy 88.12381 -279.262335) (xy 88.072958 -279.260286) (xy 88.023094 -279.250106)
			(xy 87.975508 -279.232059) (xy 87.931434 -279.206613) (xy 87.892012 -279.174426) (xy 87.858264 -279.136332)
			(xy 87.831063 -279.093318) (xy 87.811115 -279.046498) (xy 87.798936 -278.997084) (xy 87.794841 -278.946356)
			(xy 87.47633 -278.946356) (xy 87.475835 -278.970963) (xy 87.46794 -279.01954) (xy 87.452356 -279.066221)
			(xy 87.429485 -279.109798) (xy 87.39992 -279.149142) (xy 87.364427 -279.183234) (xy 87.323924 -279.21119)
			(xy 87.279462 -279.232288) (xy 87.232191 -279.24598) (xy 87.183336 -279.251912) (xy 87.134161 -279.249931)
			(xy 87.085942 -279.240087) (xy 87.039926 -279.222635) (xy 86.997305 -279.198028) (xy 86.959184 -279.166903)
			(xy 86.926549 -279.130066) (xy 86.900246 -279.08847) (xy 86.880955 -279.043194) (xy 86.869178 -278.99541)
			(xy 86.865218 -278.946356) (xy 86.54669 -278.946356) (xy 86.546178 -278.971802) (xy 86.538014 -279.022036)
			(xy 86.521898 -279.07031) (xy 86.498247 -279.115373) (xy 86.467674 -279.156059) (xy 86.43097 -279.191314)
			(xy 86.389086 -279.220224) (xy 86.343107 -279.242041) (xy 86.294223 -279.256201) (xy 86.243702 -279.262335)
			(xy 86.19285 -279.260286) (xy 86.142986 -279.250106) (xy 86.0954 -279.232059) (xy 86.051326 -279.206613)
			(xy 86.011904 -279.174426) (xy 85.978156 -279.136332) (xy 85.950955 -279.093318) (xy 85.931007 -279.046498)
			(xy 85.918828 -278.997084) (xy 85.914733 -278.946356) (xy 85.596222 -278.946356) (xy 85.595727 -278.970963)
			(xy 85.587832 -279.01954) (xy 85.572248 -279.066221) (xy 85.549377 -279.109798) (xy 85.519812 -279.149142)
			(xy 85.484319 -279.183234) (xy 85.443816 -279.21119) (xy 85.399354 -279.232288) (xy 85.352083 -279.24598)
			(xy 85.303228 -279.251912) (xy 85.254053 -279.249931) (xy 85.205834 -279.240087) (xy 85.159818 -279.222635)
			(xy 85.117197 -279.198028) (xy 85.079076 -279.166903) (xy 85.046441 -279.130066) (xy 85.020138 -279.08847)
			(xy 85.000847 -279.043194) (xy 84.98907 -278.99541) (xy 84.98511 -278.946356) (xy 84.666836 -278.946356)
			(xy 84.666324 -278.971802) (xy 84.65816 -279.022036) (xy 84.642044 -279.07031) (xy 84.618393 -279.115373)
			(xy 84.58782 -279.156059) (xy 84.551116 -279.191314) (xy 84.509232 -279.220224) (xy 84.463253 -279.242041)
			(xy 84.414369 -279.256201) (xy 84.363848 -279.262335) (xy 84.312996 -279.260286) (xy 84.263132 -279.250106)
			(xy 84.215546 -279.232059) (xy 84.171472 -279.206613) (xy 84.13205 -279.174426) (xy 84.098302 -279.136332)
			(xy 84.071101 -279.093318) (xy 84.051153 -279.046498) (xy 84.038974 -278.997084) (xy 84.034879 -278.946356)
			(xy 83.716368 -278.946356) (xy 83.715873 -278.970963) (xy 83.707978 -279.01954) (xy 83.692394 -279.066221)
			(xy 83.669523 -279.109798) (xy 83.639958 -279.149142) (xy 83.604465 -279.183234) (xy 83.563962 -279.21119)
			(xy 83.5195 -279.232288) (xy 83.472229 -279.24598) (xy 83.423374 -279.251912) (xy 83.374199 -279.249931)
			(xy 83.32598 -279.240087) (xy 83.279964 -279.222635) (xy 83.237343 -279.198028) (xy 83.199222 -279.166903)
			(xy 83.166587 -279.130066) (xy 83.140284 -279.08847) (xy 83.120993 -279.043194) (xy 83.109216 -278.99541)
			(xy 83.105256 -278.946356) (xy 82.786728 -278.946356) (xy 82.786216 -278.971802) (xy 82.778052 -279.022036)
			(xy 82.761936 -279.07031) (xy 82.738285 -279.115373) (xy 82.707712 -279.156059) (xy 82.671008 -279.191314)
			(xy 82.629124 -279.220224) (xy 82.583145 -279.242041) (xy 82.534261 -279.256201) (xy 82.48374 -279.262335)
			(xy 82.432888 -279.260286) (xy 82.383024 -279.250106) (xy 82.335438 -279.232059) (xy 82.291364 -279.206613)
			(xy 82.251942 -279.174426) (xy 82.218194 -279.136332) (xy 82.190993 -279.093318) (xy 82.171045 -279.046498)
			(xy 82.158866 -278.997084) (xy 82.154771 -278.946356) (xy 81.846674 -278.946356) (xy 81.846162 -278.971802)
			(xy 81.837998 -279.022036) (xy 81.821882 -279.07031) (xy 81.798231 -279.115373) (xy 81.767658 -279.156059)
			(xy 81.730954 -279.191314) (xy 81.68907 -279.220224) (xy 81.643091 -279.242041) (xy 81.594207 -279.256201)
			(xy 81.543686 -279.262335) (xy 81.492834 -279.260286) (xy 81.44297 -279.250106) (xy 81.395384 -279.232059)
			(xy 81.35131 -279.206613) (xy 81.311888 -279.174426) (xy 81.27814 -279.136332) (xy 81.250939 -279.093318)
			(xy 81.230991 -279.046498) (xy 81.218812 -278.997084) (xy 81.214717 -278.946356) (xy 80.89646 -278.946356)
			(xy 80.895965 -278.970963) (xy 80.88807 -279.01954) (xy 80.872486 -279.066221) (xy 80.849615 -279.109798)
			(xy 80.82005 -279.149142) (xy 80.784557 -279.183234) (xy 80.744054 -279.21119) (xy 80.699592 -279.232288)
			(xy 80.652321 -279.24598) (xy 80.603466 -279.251912) (xy 80.554291 -279.249931) (xy 80.506072 -279.240087)
			(xy 80.460056 -279.222635) (xy 80.417435 -279.198028) (xy 80.379314 -279.166903) (xy 80.346679 -279.130066)
			(xy 80.320376 -279.08847) (xy 80.301085 -279.043194) (xy 80.289308 -278.99541) (xy 80.285348 -278.946356)
			(xy 79.016352 -278.946356) (xy 79.015857 -278.970963) (xy 79.007962 -279.01954) (xy 78.992378 -279.066221)
			(xy 78.969507 -279.109798) (xy 78.939942 -279.149142) (xy 78.904449 -279.183234) (xy 78.863946 -279.21119)
			(xy 78.819484 -279.232288) (xy 78.772213 -279.24598) (xy 78.723358 -279.251912) (xy 78.674183 -279.249931)
			(xy 78.625964 -279.240087) (xy 78.579948 -279.222635) (xy 78.537327 -279.198028) (xy 78.499206 -279.166903)
			(xy 78.466571 -279.130066) (xy 78.440268 -279.08847) (xy 78.420977 -279.043194) (xy 78.4092 -278.99541)
			(xy 78.40524 -278.946356) (xy 73.228962 -278.946356) (xy 73.228962 -279.490424) (xy 76.807072 -279.490424)
			(xy 76.811032 -279.44137) (xy 76.822809 -279.393586) (xy 76.8421 -279.34831) (xy 76.868403 -279.306714)
			(xy 76.901038 -279.269877) (xy 76.939159 -279.238752) (xy 76.98178 -279.214145) (xy 77.027796 -279.196693)
			(xy 77.076015 -279.186849) (xy 77.12519 -279.184868) (xy 77.174045 -279.1908) (xy 77.221316 -279.204492)
			(xy 77.265778 -279.22559) (xy 77.306281 -279.253546) (xy 77.341774 -279.287638) (xy 77.371339 -279.326982)
			(xy 77.39421 -279.370559) (xy 77.409794 -279.41724) (xy 77.417689 -279.465817) (xy 77.418184 -279.490424)
			(xy 77.417689 -279.515031) (xy 77.409794 -279.563608) (xy 77.39421 -279.610289) (xy 77.371339 -279.653866)
			(xy 77.341774 -279.69321) (xy 77.306281 -279.727302) (xy 77.265778 -279.755258) (xy 77.263451 -279.756362)
			(xy 79.815194 -279.756362) (xy 79.819154 -279.707308) (xy 79.830931 -279.659524) (xy 79.850222 -279.614248)
			(xy 79.876525 -279.572652) (xy 79.90916 -279.535815) (xy 79.947281 -279.50469) (xy 79.989902 -279.480083)
			(xy 80.035918 -279.462631) (xy 80.084137 -279.452787) (xy 80.133312 -279.450806) (xy 80.182167 -279.456738)
			(xy 80.229438 -279.47043) (xy 80.2739 -279.491528) (xy 80.314403 -279.519484) (xy 80.349896 -279.553576)
			(xy 80.379461 -279.59292) (xy 80.402332 -279.636497) (xy 80.417916 -279.683178) (xy 80.425811 -279.731755)
			(xy 80.426306 -279.756362) (xy 80.744817 -279.756362) (xy 80.748912 -279.705634) (xy 80.761091 -279.65622)
			(xy 80.781039 -279.6094) (xy 80.80824 -279.566386) (xy 80.841988 -279.528292) (xy 80.88141 -279.496105)
			(xy 80.925484 -279.470659) (xy 80.97307 -279.452612) (xy 81.022934 -279.442432) (xy 81.073786 -279.440383)
			(xy 81.124307 -279.446517) (xy 81.173191 -279.460677) (xy 81.21917 -279.482494) (xy 81.261054 -279.511404)
			(xy 81.297758 -279.546659) (xy 81.328331 -279.587345) (xy 81.351982 -279.632408) (xy 81.368098 -279.680682)
			(xy 81.376262 -279.730916) (xy 81.376774 -279.756362) (xy 81.695302 -279.756362) (xy 81.699262 -279.707308)
			(xy 81.711039 -279.659524) (xy 81.73033 -279.614248) (xy 81.756633 -279.572652) (xy 81.789268 -279.535815)
			(xy 81.827389 -279.50469) (xy 81.87001 -279.480083) (xy 81.916026 -279.462631) (xy 81.964245 -279.452787)
			(xy 82.01342 -279.450806) (xy 82.062275 -279.456738) (xy 82.109546 -279.47043) (xy 82.154008 -279.491528)
			(xy 82.194511 -279.519484) (xy 82.230004 -279.553576) (xy 82.259569 -279.59292) (xy 82.28244 -279.636497)
			(xy 82.298024 -279.683178) (xy 82.305919 -279.731755) (xy 82.306414 -279.756362) (xy 82.624671 -279.756362)
			(xy 82.628766 -279.705634) (xy 82.640945 -279.65622) (xy 82.660893 -279.6094) (xy 82.688094 -279.566386)
			(xy 82.721842 -279.528292) (xy 82.761264 -279.496105) (xy 82.805338 -279.470659) (xy 82.852924 -279.452612)
			(xy 82.902788 -279.442432) (xy 82.95364 -279.440383) (xy 83.004161 -279.446517) (xy 83.053045 -279.460677)
			(xy 83.099024 -279.482494) (xy 83.140908 -279.511404) (xy 83.177612 -279.546659) (xy 83.208185 -279.587345)
			(xy 83.231836 -279.632408) (xy 83.247952 -279.680682) (xy 83.256116 -279.730916) (xy 83.256628 -279.756362)
			(xy 83.575156 -279.756362) (xy 83.579116 -279.707308) (xy 83.590893 -279.659524) (xy 83.610184 -279.614248)
			(xy 83.636487 -279.572652) (xy 83.669122 -279.535815) (xy 83.707243 -279.50469) (xy 83.749864 -279.480083)
			(xy 83.79588 -279.462631) (xy 83.844099 -279.452787) (xy 83.893274 -279.450806) (xy 83.942129 -279.456738)
			(xy 83.9894 -279.47043) (xy 84.033862 -279.491528) (xy 84.074365 -279.519484) (xy 84.109858 -279.553576)
			(xy 84.139423 -279.59292) (xy 84.162294 -279.636497) (xy 84.177878 -279.683178) (xy 84.185773 -279.731755)
			(xy 84.186268 -279.756362) (xy 84.504779 -279.756362) (xy 84.508874 -279.705634) (xy 84.521053 -279.65622)
			(xy 84.541001 -279.6094) (xy 84.568202 -279.566386) (xy 84.60195 -279.528292) (xy 84.641372 -279.496105)
			(xy 84.685446 -279.470659) (xy 84.733032 -279.452612) (xy 84.782896 -279.442432) (xy 84.833748 -279.440383)
			(xy 84.884269 -279.446517) (xy 84.933153 -279.460677) (xy 84.979132 -279.482494) (xy 85.021016 -279.511404)
			(xy 85.05772 -279.546659) (xy 85.088293 -279.587345) (xy 85.111944 -279.632408) (xy 85.12806 -279.680682)
			(xy 85.136224 -279.730916) (xy 85.136736 -279.756362) (xy 85.444833 -279.756362) (xy 85.448928 -279.705634)
			(xy 85.461107 -279.65622) (xy 85.481055 -279.6094) (xy 85.508256 -279.566386) (xy 85.542004 -279.528292)
			(xy 85.581426 -279.496105) (xy 85.6255 -279.470659) (xy 85.673086 -279.452612) (xy 85.72295 -279.442432)
			(xy 85.773802 -279.440383) (xy 85.824323 -279.446517) (xy 85.873207 -279.460677) (xy 85.919186 -279.482494)
			(xy 85.96107 -279.511404) (xy 85.997774 -279.546659) (xy 86.028347 -279.587345) (xy 86.051998 -279.632408)
			(xy 86.068114 -279.680682) (xy 86.076278 -279.730916) (xy 86.07679 -279.756362) (xy 86.395318 -279.756362)
			(xy 86.399278 -279.707308) (xy 86.411055 -279.659524) (xy 86.430346 -279.614248) (xy 86.456649 -279.572652)
			(xy 86.489284 -279.535815) (xy 86.527405 -279.50469) (xy 86.570026 -279.480083) (xy 86.616042 -279.462631)
			(xy 86.664261 -279.452787) (xy 86.713436 -279.450806) (xy 86.762291 -279.456738) (xy 86.809562 -279.47043)
			(xy 86.854024 -279.491528) (xy 86.894527 -279.519484) (xy 86.93002 -279.553576) (xy 86.959585 -279.59292)
			(xy 86.982456 -279.636497) (xy 86.99804 -279.683178) (xy 87.005935 -279.731755) (xy 87.00643 -279.756362)
			(xy 87.324687 -279.756362) (xy 87.328782 -279.705634) (xy 87.340961 -279.65622) (xy 87.360909 -279.6094)
			(xy 87.38811 -279.566386) (xy 87.421858 -279.528292) (xy 87.46128 -279.496105) (xy 87.505354 -279.470659)
			(xy 87.55294 -279.452612) (xy 87.602804 -279.442432) (xy 87.653656 -279.440383) (xy 87.704177 -279.446517)
			(xy 87.753061 -279.460677) (xy 87.79904 -279.482494) (xy 87.840924 -279.511404) (xy 87.877628 -279.546659)
			(xy 87.908201 -279.587345) (xy 87.931852 -279.632408) (xy 87.947968 -279.680682) (xy 87.956132 -279.730916)
			(xy 87.956644 -279.756362) (xy 88.275172 -279.756362) (xy 88.279132 -279.707308) (xy 88.290909 -279.659524)
			(xy 88.3102 -279.614248) (xy 88.336503 -279.572652) (xy 88.369138 -279.535815) (xy 88.407259 -279.50469)
			(xy 88.44988 -279.480083) (xy 88.495896 -279.462631) (xy 88.544115 -279.452787) (xy 88.59329 -279.450806)
			(xy 88.642145 -279.456738) (xy 88.689416 -279.47043) (xy 88.733878 -279.491528) (xy 88.774381 -279.519484)
			(xy 88.809874 -279.553576) (xy 88.839439 -279.59292) (xy 88.86231 -279.636497) (xy 88.877894 -279.683178)
			(xy 88.885789 -279.731755) (xy 88.886284 -279.756362) (xy 89.204795 -279.756362) (xy 89.20889 -279.705634)
			(xy 89.221069 -279.65622) (xy 89.241017 -279.6094) (xy 89.268218 -279.566386) (xy 89.301966 -279.528292)
			(xy 89.341388 -279.496105) (xy 89.385462 -279.470659) (xy 89.433048 -279.452612) (xy 89.482912 -279.442432)
			(xy 89.533764 -279.440383) (xy 89.584285 -279.446517) (xy 89.633169 -279.460677) (xy 89.679148 -279.482494)
			(xy 89.721032 -279.511404) (xy 89.757736 -279.546659) (xy 89.788309 -279.587345) (xy 89.81196 -279.632408)
			(xy 89.828076 -279.680682) (xy 89.83624 -279.730916) (xy 89.836752 -279.756362) (xy 90.15528 -279.756362)
			(xy 90.15924 -279.707308) (xy 90.171017 -279.659524) (xy 90.190308 -279.614248) (xy 90.216611 -279.572652)
			(xy 90.249246 -279.535815) (xy 90.287367 -279.50469) (xy 90.329988 -279.480083) (xy 90.376004 -279.462631)
			(xy 90.424223 -279.452787) (xy 90.473398 -279.450806) (xy 90.522253 -279.456738) (xy 90.569524 -279.47043)
			(xy 90.613986 -279.491528) (xy 90.654489 -279.519484) (xy 90.689982 -279.553576) (xy 90.719547 -279.59292)
			(xy 90.742418 -279.636497) (xy 90.758002 -279.683178) (xy 90.765897 -279.731755) (xy 90.766392 -279.756362)
			(xy 91.084903 -279.756362) (xy 91.088998 -279.705634) (xy 91.101177 -279.65622) (xy 91.121125 -279.6094)
			(xy 91.148326 -279.566386) (xy 91.182074 -279.528292) (xy 91.221496 -279.496105) (xy 91.26557 -279.470659)
			(xy 91.313156 -279.452612) (xy 91.36302 -279.442432) (xy 91.413872 -279.440383) (xy 91.464393 -279.446517)
			(xy 91.513277 -279.460677) (xy 91.559256 -279.482494) (xy 91.60114 -279.511404) (xy 91.637844 -279.546659)
			(xy 91.668417 -279.587345) (xy 91.692068 -279.632408) (xy 91.708184 -279.680682) (xy 91.716348 -279.730916)
			(xy 91.71686 -279.756362) (xy 92.024703 -279.756362) (xy 92.028798 -279.705634) (xy 92.040977 -279.65622)
			(xy 92.060925 -279.6094) (xy 92.088126 -279.566386) (xy 92.121874 -279.528292) (xy 92.161296 -279.496105)
			(xy 92.20537 -279.470659) (xy 92.252956 -279.452612) (xy 92.30282 -279.442432) (xy 92.353672 -279.440383)
			(xy 92.404193 -279.446517) (xy 92.453077 -279.460677) (xy 92.499056 -279.482494) (xy 92.54094 -279.511404)
			(xy 92.577644 -279.546659) (xy 92.608217 -279.587345) (xy 92.631868 -279.632408) (xy 92.647984 -279.680682)
			(xy 92.656148 -279.730916) (xy 92.65666 -279.756362) (xy 92.975188 -279.756362) (xy 92.979148 -279.707308)
			(xy 92.990925 -279.659524) (xy 93.010216 -279.614248) (xy 93.036519 -279.572652) (xy 93.069154 -279.535815)
			(xy 93.107275 -279.50469) (xy 93.149896 -279.480083) (xy 93.195912 -279.462631) (xy 93.244131 -279.452787)
			(xy 93.293306 -279.450806) (xy 93.342161 -279.456738) (xy 93.389432 -279.47043) (xy 93.433894 -279.491528)
			(xy 93.474397 -279.519484) (xy 93.50989 -279.553576) (xy 93.539455 -279.59292) (xy 93.562326 -279.636497)
			(xy 93.57791 -279.683178) (xy 93.585805 -279.731755) (xy 93.5863 -279.756362) (xy 93.904811 -279.756362)
			(xy 93.908906 -279.705634) (xy 93.921085 -279.65622) (xy 93.941033 -279.6094) (xy 93.968234 -279.566386)
			(xy 94.001982 -279.528292) (xy 94.041404 -279.496105) (xy 94.085478 -279.470659) (xy 94.133064 -279.452612)
			(xy 94.182928 -279.442432) (xy 94.23378 -279.440383) (xy 94.284301 -279.446517) (xy 94.333185 -279.460677)
			(xy 94.379164 -279.482494) (xy 94.421048 -279.511404) (xy 94.457752 -279.546659) (xy 94.488325 -279.587345)
			(xy 94.511976 -279.632408) (xy 94.528092 -279.680682) (xy 94.536256 -279.730916) (xy 94.536768 -279.756362)
			(xy 94.855296 -279.756362) (xy 94.859256 -279.707308) (xy 94.871033 -279.659524) (xy 94.890324 -279.614248)
			(xy 94.916627 -279.572652) (xy 94.949262 -279.535815) (xy 94.987383 -279.50469) (xy 95.030004 -279.480083)
			(xy 95.07602 -279.462631) (xy 95.124239 -279.452787) (xy 95.173414 -279.450806) (xy 95.222269 -279.456738)
			(xy 95.26954 -279.47043) (xy 95.314002 -279.491528) (xy 95.354505 -279.519484) (xy 95.389998 -279.553576)
			(xy 95.419563 -279.59292) (xy 95.442434 -279.636497) (xy 95.458018 -279.683178) (xy 95.465913 -279.731755)
			(xy 95.466408 -279.756362) (xy 95.784919 -279.756362) (xy 95.789014 -279.705634) (xy 95.801193 -279.65622)
			(xy 95.821141 -279.6094) (xy 95.848342 -279.566386) (xy 95.88209 -279.528292) (xy 95.921512 -279.496105)
			(xy 95.965586 -279.470659) (xy 96.013172 -279.452612) (xy 96.063036 -279.442432) (xy 96.113888 -279.440383)
			(xy 96.164409 -279.446517) (xy 96.213293 -279.460677) (xy 96.259272 -279.482494) (xy 96.301156 -279.511404)
			(xy 96.33786 -279.546659) (xy 96.368433 -279.587345) (xy 96.392084 -279.632408) (xy 96.4082 -279.680682)
			(xy 96.416364 -279.730916) (xy 96.416876 -279.756362) (xy 96.73515 -279.756362) (xy 96.73911 -279.707308)
			(xy 96.750887 -279.659524) (xy 96.770178 -279.614248) (xy 96.796481 -279.572652) (xy 96.829116 -279.535815)
			(xy 96.867237 -279.50469) (xy 96.909858 -279.480083) (xy 96.955874 -279.462631) (xy 97.004093 -279.452787)
			(xy 97.053268 -279.450806) (xy 97.102123 -279.456738) (xy 97.149394 -279.47043) (xy 97.193856 -279.491528)
			(xy 97.234359 -279.519484) (xy 97.269852 -279.553576) (xy 97.299417 -279.59292) (xy 97.322288 -279.636497)
			(xy 97.337872 -279.683178) (xy 97.345767 -279.731755) (xy 97.346262 -279.756362) (xy 97.675204 -279.756362)
			(xy 97.679164 -279.707308) (xy 97.690941 -279.659524) (xy 97.710232 -279.614248) (xy 97.736535 -279.572652)
			(xy 97.76917 -279.535815) (xy 97.807291 -279.50469) (xy 97.849912 -279.480083) (xy 97.895928 -279.462631)
			(xy 97.944147 -279.452787) (xy 97.993322 -279.450806) (xy 98.042177 -279.456738) (xy 98.089448 -279.47043)
			(xy 98.13391 -279.491528) (xy 98.174413 -279.519484) (xy 98.209906 -279.553576) (xy 98.239471 -279.59292)
			(xy 98.262342 -279.636497) (xy 98.277926 -279.683178) (xy 98.285821 -279.731755) (xy 98.286316 -279.756362)
			(xy 98.615258 -279.756362) (xy 98.619218 -279.707308) (xy 98.630995 -279.659524) (xy 98.650286 -279.614248)
			(xy 98.676589 -279.572652) (xy 98.709224 -279.535815) (xy 98.747345 -279.50469) (xy 98.789966 -279.480083)
			(xy 98.835982 -279.462631) (xy 98.884201 -279.452787) (xy 98.933376 -279.450806) (xy 98.982231 -279.456738)
			(xy 99.029502 -279.47043) (xy 99.073964 -279.491528) (xy 99.114467 -279.519484) (xy 99.14996 -279.553576)
			(xy 99.179525 -279.59292) (xy 99.202396 -279.636497) (xy 99.21798 -279.683178) (xy 99.225875 -279.731755)
			(xy 99.22637 -279.756362) (xy 99.555312 -279.756362) (xy 99.559272 -279.707308) (xy 99.571049 -279.659524)
			(xy 99.59034 -279.614248) (xy 99.616643 -279.572652) (xy 99.649278 -279.535815) (xy 99.687399 -279.50469)
			(xy 99.73002 -279.480083) (xy 99.776036 -279.462631) (xy 99.824255 -279.452787) (xy 99.87343 -279.450806)
			(xy 99.922285 -279.456738) (xy 99.969556 -279.47043) (xy 100.014018 -279.491528) (xy 100.054521 -279.519484)
			(xy 100.090014 -279.553576) (xy 100.119579 -279.59292) (xy 100.14245 -279.636497) (xy 100.158034 -279.683178)
			(xy 100.165929 -279.731755) (xy 100.166424 -279.756362) (xy 100.495366 -279.756362) (xy 100.499326 -279.707308)
			(xy 100.511103 -279.659524) (xy 100.530394 -279.614248) (xy 100.556697 -279.572652) (xy 100.589332 -279.535815)
			(xy 100.627453 -279.50469) (xy 100.670074 -279.480083) (xy 100.71609 -279.462631) (xy 100.764309 -279.452787)
			(xy 100.813484 -279.450806) (xy 100.862339 -279.456738) (xy 100.90961 -279.47043) (xy 100.954072 -279.491528)
			(xy 100.994575 -279.519484) (xy 101.030068 -279.553576) (xy 101.059633 -279.59292) (xy 101.082504 -279.636497)
			(xy 101.098088 -279.683178) (xy 101.105983 -279.731755) (xy 101.106478 -279.756362) (xy 101.435166 -279.756362)
			(xy 101.439126 -279.707308) (xy 101.450903 -279.659524) (xy 101.470194 -279.614248) (xy 101.496497 -279.572652)
			(xy 101.529132 -279.535815) (xy 101.567253 -279.50469) (xy 101.609874 -279.480083) (xy 101.65589 -279.462631)
			(xy 101.704109 -279.452787) (xy 101.753284 -279.450806) (xy 101.802139 -279.456738) (xy 101.84941 -279.47043)
			(xy 101.893872 -279.491528) (xy 101.934375 -279.519484) (xy 101.969868 -279.553576) (xy 101.999433 -279.59292)
			(xy 102.022304 -279.636497) (xy 102.037888 -279.683178) (xy 102.045783 -279.731755) (xy 102.046278 -279.756362)
			(xy 102.045783 -279.780969) (xy 102.037888 -279.829546) (xy 102.022304 -279.876227) (xy 101.999433 -279.919804)
			(xy 101.969868 -279.959148) (xy 101.934375 -279.99324) (xy 101.893872 -280.021196) (xy 101.84941 -280.042294)
			(xy 101.802139 -280.055986) (xy 101.753284 -280.061918) (xy 101.704109 -280.059937) (xy 101.65589 -280.050093)
			(xy 101.609874 -280.032641) (xy 101.567253 -280.008034) (xy 101.529132 -279.976909) (xy 101.496497 -279.940072)
			(xy 101.470194 -279.898476) (xy 101.450903 -279.8532) (xy 101.439126 -279.805416) (xy 101.435166 -279.756362)
			(xy 101.106478 -279.756362) (xy 101.105983 -279.780969) (xy 101.098088 -279.829546) (xy 101.082504 -279.876227)
			(xy 101.059633 -279.919804) (xy 101.030068 -279.959148) (xy 100.994575 -279.99324) (xy 100.954072 -280.021196)
			(xy 100.90961 -280.042294) (xy 100.862339 -280.055986) (xy 100.813484 -280.061918) (xy 100.764309 -280.059937)
			(xy 100.71609 -280.050093) (xy 100.670074 -280.032641) (xy 100.627453 -280.008034) (xy 100.589332 -279.976909)
			(xy 100.556697 -279.940072) (xy 100.530394 -279.898476) (xy 100.511103 -279.8532) (xy 100.499326 -279.805416)
			(xy 100.495366 -279.756362) (xy 100.166424 -279.756362) (xy 100.165929 -279.780969) (xy 100.158034 -279.829546)
			(xy 100.14245 -279.876227) (xy 100.119579 -279.919804) (xy 100.090014 -279.959148) (xy 100.054521 -279.99324)
			(xy 100.014018 -280.021196) (xy 99.969556 -280.042294) (xy 99.922285 -280.055986) (xy 99.87343 -280.061918)
			(xy 99.824255 -280.059937) (xy 99.776036 -280.050093) (xy 99.73002 -280.032641) (xy 99.687399 -280.008034)
			(xy 99.649278 -279.976909) (xy 99.616643 -279.940072) (xy 99.59034 -279.898476) (xy 99.571049 -279.8532)
			(xy 99.559272 -279.805416) (xy 99.555312 -279.756362) (xy 99.22637 -279.756362) (xy 99.225875 -279.780969)
			(xy 99.21798 -279.829546) (xy 99.202396 -279.876227) (xy 99.179525 -279.919804) (xy 99.14996 -279.959148)
			(xy 99.114467 -279.99324) (xy 99.073964 -280.021196) (xy 99.029502 -280.042294) (xy 98.982231 -280.055986)
			(xy 98.933376 -280.061918) (xy 98.884201 -280.059937) (xy 98.835982 -280.050093) (xy 98.789966 -280.032641)
			(xy 98.747345 -280.008034) (xy 98.709224 -279.976909) (xy 98.676589 -279.940072) (xy 98.650286 -279.898476)
			(xy 98.630995 -279.8532) (xy 98.619218 -279.805416) (xy 98.615258 -279.756362) (xy 98.286316 -279.756362)
			(xy 98.285821 -279.780969) (xy 98.277926 -279.829546) (xy 98.262342 -279.876227) (xy 98.239471 -279.919804)
			(xy 98.209906 -279.959148) (xy 98.174413 -279.99324) (xy 98.13391 -280.021196) (xy 98.089448 -280.042294)
			(xy 98.042177 -280.055986) (xy 97.993322 -280.061918) (xy 97.944147 -280.059937) (xy 97.895928 -280.050093)
			(xy 97.849912 -280.032641) (xy 97.807291 -280.008034) (xy 97.76917 -279.976909) (xy 97.736535 -279.940072)
			(xy 97.710232 -279.898476) (xy 97.690941 -279.8532) (xy 97.679164 -279.805416) (xy 97.675204 -279.756362)
			(xy 97.346262 -279.756362) (xy 97.345767 -279.780969) (xy 97.337872 -279.829546) (xy 97.322288 -279.876227)
			(xy 97.299417 -279.919804) (xy 97.269852 -279.959148) (xy 97.234359 -279.99324) (xy 97.193856 -280.021196)
			(xy 97.149394 -280.042294) (xy 97.102123 -280.055986) (xy 97.053268 -280.061918) (xy 97.004093 -280.059937)
			(xy 96.955874 -280.050093) (xy 96.909858 -280.032641) (xy 96.867237 -280.008034) (xy 96.829116 -279.976909)
			(xy 96.796481 -279.940072) (xy 96.770178 -279.898476) (xy 96.750887 -279.8532) (xy 96.73911 -279.805416)
			(xy 96.73515 -279.756362) (xy 96.416876 -279.756362) (xy 96.416364 -279.781808) (xy 96.4082 -279.832042)
			(xy 96.392084 -279.880316) (xy 96.368433 -279.925379) (xy 96.33786 -279.966065) (xy 96.301156 -280.00132)
			(xy 96.259272 -280.03023) (xy 96.213293 -280.052047) (xy 96.164409 -280.066207) (xy 96.113888 -280.072341)
			(xy 96.063036 -280.070292) (xy 96.013172 -280.060112) (xy 95.965586 -280.042065) (xy 95.921512 -280.016619)
			(xy 95.88209 -279.984432) (xy 95.848342 -279.946338) (xy 95.821141 -279.903324) (xy 95.801193 -279.856504)
			(xy 95.789014 -279.80709) (xy 95.784919 -279.756362) (xy 95.466408 -279.756362) (xy 95.465913 -279.780969)
			(xy 95.458018 -279.829546) (xy 95.442434 -279.876227) (xy 95.419563 -279.919804) (xy 95.389998 -279.959148)
			(xy 95.354505 -279.99324) (xy 95.314002 -280.021196) (xy 95.26954 -280.042294) (xy 95.222269 -280.055986)
			(xy 95.173414 -280.061918) (xy 95.124239 -280.059937) (xy 95.07602 -280.050093) (xy 95.030004 -280.032641)
			(xy 94.987383 -280.008034) (xy 94.949262 -279.976909) (xy 94.916627 -279.940072) (xy 94.890324 -279.898476)
			(xy 94.871033 -279.8532) (xy 94.859256 -279.805416) (xy 94.855296 -279.756362) (xy 94.536768 -279.756362)
			(xy 94.536256 -279.781808) (xy 94.528092 -279.832042) (xy 94.511976 -279.880316) (xy 94.488325 -279.925379)
			(xy 94.457752 -279.966065) (xy 94.421048 -280.00132) (xy 94.379164 -280.03023) (xy 94.333185 -280.052047)
			(xy 94.284301 -280.066207) (xy 94.23378 -280.072341) (xy 94.182928 -280.070292) (xy 94.133064 -280.060112)
			(xy 94.085478 -280.042065) (xy 94.041404 -280.016619) (xy 94.001982 -279.984432) (xy 93.968234 -279.946338)
			(xy 93.941033 -279.903324) (xy 93.921085 -279.856504) (xy 93.908906 -279.80709) (xy 93.904811 -279.756362)
			(xy 93.5863 -279.756362) (xy 93.585805 -279.780969) (xy 93.57791 -279.829546) (xy 93.562326 -279.876227)
			(xy 93.539455 -279.919804) (xy 93.50989 -279.959148) (xy 93.474397 -279.99324) (xy 93.433894 -280.021196)
			(xy 93.389432 -280.042294) (xy 93.342161 -280.055986) (xy 93.293306 -280.061918) (xy 93.244131 -280.059937)
			(xy 93.195912 -280.050093) (xy 93.149896 -280.032641) (xy 93.107275 -280.008034) (xy 93.069154 -279.976909)
			(xy 93.036519 -279.940072) (xy 93.010216 -279.898476) (xy 92.990925 -279.8532) (xy 92.979148 -279.805416)
			(xy 92.975188 -279.756362) (xy 92.65666 -279.756362) (xy 92.656148 -279.781808) (xy 92.647984 -279.832042)
			(xy 92.631868 -279.880316) (xy 92.608217 -279.925379) (xy 92.577644 -279.966065) (xy 92.54094 -280.00132)
			(xy 92.499056 -280.03023) (xy 92.453077 -280.052047) (xy 92.404193 -280.066207) (xy 92.353672 -280.072341)
			(xy 92.30282 -280.070292) (xy 92.252956 -280.060112) (xy 92.20537 -280.042065) (xy 92.161296 -280.016619)
			(xy 92.121874 -279.984432) (xy 92.088126 -279.946338) (xy 92.060925 -279.903324) (xy 92.040977 -279.856504)
			(xy 92.028798 -279.80709) (xy 92.024703 -279.756362) (xy 91.71686 -279.756362) (xy 91.716348 -279.781808)
			(xy 91.708184 -279.832042) (xy 91.692068 -279.880316) (xy 91.668417 -279.925379) (xy 91.637844 -279.966065)
			(xy 91.60114 -280.00132) (xy 91.559256 -280.03023) (xy 91.513277 -280.052047) (xy 91.464393 -280.066207)
			(xy 91.413872 -280.072341) (xy 91.36302 -280.070292) (xy 91.313156 -280.060112) (xy 91.26557 -280.042065)
			(xy 91.221496 -280.016619) (xy 91.182074 -279.984432) (xy 91.148326 -279.946338) (xy 91.121125 -279.903324)
			(xy 91.101177 -279.856504) (xy 91.088998 -279.80709) (xy 91.084903 -279.756362) (xy 90.766392 -279.756362)
			(xy 90.765897 -279.780969) (xy 90.758002 -279.829546) (xy 90.742418 -279.876227) (xy 90.719547 -279.919804)
			(xy 90.689982 -279.959148) (xy 90.654489 -279.99324) (xy 90.613986 -280.021196) (xy 90.569524 -280.042294)
			(xy 90.522253 -280.055986) (xy 90.473398 -280.061918) (xy 90.424223 -280.059937) (xy 90.376004 -280.050093)
			(xy 90.329988 -280.032641) (xy 90.287367 -280.008034) (xy 90.249246 -279.976909) (xy 90.216611 -279.940072)
			(xy 90.190308 -279.898476) (xy 90.171017 -279.8532) (xy 90.15924 -279.805416) (xy 90.15528 -279.756362)
			(xy 89.836752 -279.756362) (xy 89.83624 -279.781808) (xy 89.828076 -279.832042) (xy 89.81196 -279.880316)
			(xy 89.788309 -279.925379) (xy 89.757736 -279.966065) (xy 89.721032 -280.00132) (xy 89.679148 -280.03023)
			(xy 89.633169 -280.052047) (xy 89.584285 -280.066207) (xy 89.533764 -280.072341) (xy 89.482912 -280.070292)
			(xy 89.433048 -280.060112) (xy 89.385462 -280.042065) (xy 89.341388 -280.016619) (xy 89.301966 -279.984432)
			(xy 89.268218 -279.946338) (xy 89.241017 -279.903324) (xy 89.221069 -279.856504) (xy 89.20889 -279.80709)
			(xy 89.204795 -279.756362) (xy 88.886284 -279.756362) (xy 88.885789 -279.780969) (xy 88.877894 -279.829546)
			(xy 88.86231 -279.876227) (xy 88.839439 -279.919804) (xy 88.809874 -279.959148) (xy 88.774381 -279.99324)
			(xy 88.733878 -280.021196) (xy 88.689416 -280.042294) (xy 88.642145 -280.055986) (xy 88.59329 -280.061918)
			(xy 88.544115 -280.059937) (xy 88.495896 -280.050093) (xy 88.44988 -280.032641) (xy 88.407259 -280.008034)
			(xy 88.369138 -279.976909) (xy 88.336503 -279.940072) (xy 88.3102 -279.898476) (xy 88.290909 -279.8532)
			(xy 88.279132 -279.805416) (xy 88.275172 -279.756362) (xy 87.956644 -279.756362) (xy 87.956132 -279.781808)
			(xy 87.947968 -279.832042) (xy 87.931852 -279.880316) (xy 87.908201 -279.925379) (xy 87.877628 -279.966065)
			(xy 87.840924 -280.00132) (xy 87.79904 -280.03023) (xy 87.753061 -280.052047) (xy 87.704177 -280.066207)
			(xy 87.653656 -280.072341) (xy 87.602804 -280.070292) (xy 87.55294 -280.060112) (xy 87.505354 -280.042065)
			(xy 87.46128 -280.016619) (xy 87.421858 -279.984432) (xy 87.38811 -279.946338) (xy 87.360909 -279.903324)
			(xy 87.340961 -279.856504) (xy 87.328782 -279.80709) (xy 87.324687 -279.756362) (xy 87.00643 -279.756362)
			(xy 87.005935 -279.780969) (xy 86.99804 -279.829546) (xy 86.982456 -279.876227) (xy 86.959585 -279.919804)
			(xy 86.93002 -279.959148) (xy 86.894527 -279.99324) (xy 86.854024 -280.021196) (xy 86.809562 -280.042294)
			(xy 86.762291 -280.055986) (xy 86.713436 -280.061918) (xy 86.664261 -280.059937) (xy 86.616042 -280.050093)
			(xy 86.570026 -280.032641) (xy 86.527405 -280.008034) (xy 86.489284 -279.976909) (xy 86.456649 -279.940072)
			(xy 86.430346 -279.898476) (xy 86.411055 -279.8532) (xy 86.399278 -279.805416) (xy 86.395318 -279.756362)
			(xy 86.07679 -279.756362) (xy 86.076278 -279.781808) (xy 86.068114 -279.832042) (xy 86.051998 -279.880316)
			(xy 86.028347 -279.925379) (xy 85.997774 -279.966065) (xy 85.96107 -280.00132) (xy 85.919186 -280.03023)
			(xy 85.873207 -280.052047) (xy 85.824323 -280.066207) (xy 85.773802 -280.072341) (xy 85.72295 -280.070292)
			(xy 85.673086 -280.060112) (xy 85.6255 -280.042065) (xy 85.581426 -280.016619) (xy 85.542004 -279.984432)
			(xy 85.508256 -279.946338) (xy 85.481055 -279.903324) (xy 85.461107 -279.856504) (xy 85.448928 -279.80709)
			(xy 85.444833 -279.756362) (xy 85.136736 -279.756362) (xy 85.136224 -279.781808) (xy 85.12806 -279.832042)
			(xy 85.111944 -279.880316) (xy 85.088293 -279.925379) (xy 85.05772 -279.966065) (xy 85.021016 -280.00132)
			(xy 84.979132 -280.03023) (xy 84.933153 -280.052047) (xy 84.884269 -280.066207) (xy 84.833748 -280.072341)
			(xy 84.782896 -280.070292) (xy 84.733032 -280.060112) (xy 84.685446 -280.042065) (xy 84.641372 -280.016619)
			(xy 84.60195 -279.984432) (xy 84.568202 -279.946338) (xy 84.541001 -279.903324) (xy 84.521053 -279.856504)
			(xy 84.508874 -279.80709) (xy 84.504779 -279.756362) (xy 84.186268 -279.756362) (xy 84.185773 -279.780969)
			(xy 84.177878 -279.829546) (xy 84.162294 -279.876227) (xy 84.139423 -279.919804) (xy 84.109858 -279.959148)
			(xy 84.074365 -279.99324) (xy 84.033862 -280.021196) (xy 83.9894 -280.042294) (xy 83.942129 -280.055986)
			(xy 83.893274 -280.061918) (xy 83.844099 -280.059937) (xy 83.79588 -280.050093) (xy 83.749864 -280.032641)
			(xy 83.707243 -280.008034) (xy 83.669122 -279.976909) (xy 83.636487 -279.940072) (xy 83.610184 -279.898476)
			(xy 83.590893 -279.8532) (xy 83.579116 -279.805416) (xy 83.575156 -279.756362) (xy 83.256628 -279.756362)
			(xy 83.256116 -279.781808) (xy 83.247952 -279.832042) (xy 83.231836 -279.880316) (xy 83.208185 -279.925379)
			(xy 83.177612 -279.966065) (xy 83.140908 -280.00132) (xy 83.099024 -280.03023) (xy 83.053045 -280.052047)
			(xy 83.004161 -280.066207) (xy 82.95364 -280.072341) (xy 82.902788 -280.070292) (xy 82.852924 -280.060112)
			(xy 82.805338 -280.042065) (xy 82.761264 -280.016619) (xy 82.721842 -279.984432) (xy 82.688094 -279.946338)
			(xy 82.660893 -279.903324) (xy 82.640945 -279.856504) (xy 82.628766 -279.80709) (xy 82.624671 -279.756362)
			(xy 82.306414 -279.756362) (xy 82.305919 -279.780969) (xy 82.298024 -279.829546) (xy 82.28244 -279.876227)
			(xy 82.259569 -279.919804) (xy 82.230004 -279.959148) (xy 82.194511 -279.99324) (xy 82.154008 -280.021196)
			(xy 82.109546 -280.042294) (xy 82.062275 -280.055986) (xy 82.01342 -280.061918) (xy 81.964245 -280.059937)
			(xy 81.916026 -280.050093) (xy 81.87001 -280.032641) (xy 81.827389 -280.008034) (xy 81.789268 -279.976909)
			(xy 81.756633 -279.940072) (xy 81.73033 -279.898476) (xy 81.711039 -279.8532) (xy 81.699262 -279.805416)
			(xy 81.695302 -279.756362) (xy 81.376774 -279.756362) (xy 81.376262 -279.781808) (xy 81.368098 -279.832042)
			(xy 81.351982 -279.880316) (xy 81.328331 -279.925379) (xy 81.297758 -279.966065) (xy 81.261054 -280.00132)
			(xy 81.21917 -280.03023) (xy 81.173191 -280.052047) (xy 81.124307 -280.066207) (xy 81.073786 -280.072341)
			(xy 81.022934 -280.070292) (xy 80.97307 -280.060112) (xy 80.925484 -280.042065) (xy 80.88141 -280.016619)
			(xy 80.841988 -279.984432) (xy 80.80824 -279.946338) (xy 80.781039 -279.903324) (xy 80.761091 -279.856504)
			(xy 80.748912 -279.80709) (xy 80.744817 -279.756362) (xy 80.426306 -279.756362) (xy 80.425811 -279.780969)
			(xy 80.417916 -279.829546) (xy 80.402332 -279.876227) (xy 80.379461 -279.919804) (xy 80.349896 -279.959148)
			(xy 80.314403 -279.99324) (xy 80.2739 -280.021196) (xy 80.229438 -280.042294) (xy 80.182167 -280.055986)
			(xy 80.133312 -280.061918) (xy 80.084137 -280.059937) (xy 80.035918 -280.050093) (xy 79.989902 -280.032641)
			(xy 79.947281 -280.008034) (xy 79.90916 -279.976909) (xy 79.876525 -279.940072) (xy 79.850222 -279.898476)
			(xy 79.830931 -279.8532) (xy 79.819154 -279.805416) (xy 79.815194 -279.756362) (xy 77.263451 -279.756362)
			(xy 77.221316 -279.776356) (xy 77.174045 -279.790048) (xy 77.12519 -279.79598) (xy 77.076015 -279.793999)
			(xy 77.027796 -279.784155) (xy 76.98178 -279.766703) (xy 76.939159 -279.742096) (xy 76.901038 -279.710971)
			(xy 76.868403 -279.674134) (xy 76.8421 -279.632538) (xy 76.822809 -279.587262) (xy 76.811032 -279.539478)
			(xy 76.807072 -279.490424) (xy 73.228962 -279.490424) (xy 73.228962 -280.566368) (xy 78.40524 -280.566368)
			(xy 78.4092 -280.517314) (xy 78.420977 -280.46953) (xy 78.440268 -280.424254) (xy 78.466571 -280.382658)
			(xy 78.499206 -280.345821) (xy 78.537327 -280.314696) (xy 78.579948 -280.290089) (xy 78.625964 -280.272637)
			(xy 78.674183 -280.262793) (xy 78.723358 -280.260812) (xy 78.772213 -280.266744) (xy 78.819484 -280.280436)
			(xy 78.863946 -280.301534) (xy 78.904449 -280.32949) (xy 78.939942 -280.363582) (xy 78.969507 -280.402926)
			(xy 78.992378 -280.446503) (xy 79.007962 -280.493184) (xy 79.015857 -280.541761) (xy 79.016352 -280.566368)
			(xy 80.285348 -280.566368) (xy 80.289308 -280.517314) (xy 80.301085 -280.46953) (xy 80.320376 -280.424254)
			(xy 80.346679 -280.382658) (xy 80.379314 -280.345821) (xy 80.417435 -280.314696) (xy 80.460056 -280.290089)
			(xy 80.506072 -280.272637) (xy 80.554291 -280.262793) (xy 80.603466 -280.260812) (xy 80.652321 -280.266744)
			(xy 80.699592 -280.280436) (xy 80.744054 -280.301534) (xy 80.784557 -280.32949) (xy 80.82005 -280.363582)
			(xy 80.849615 -280.402926) (xy 80.872486 -280.446503) (xy 80.88807 -280.493184) (xy 80.895965 -280.541761)
			(xy 80.89646 -280.566368) (xy 81.214717 -280.566368) (xy 81.218812 -280.51564) (xy 81.230991 -280.466226)
			(xy 81.250939 -280.419406) (xy 81.27814 -280.376392) (xy 81.311888 -280.338298) (xy 81.35131 -280.306111)
			(xy 81.395384 -280.280665) (xy 81.44297 -280.262618) (xy 81.492834 -280.252438) (xy 81.543686 -280.250389)
			(xy 81.594207 -280.256523) (xy 81.643091 -280.270683) (xy 81.68907 -280.2925) (xy 81.730954 -280.32141)
			(xy 81.767658 -280.356665) (xy 81.798231 -280.397351) (xy 81.821882 -280.442414) (xy 81.837998 -280.490688)
			(xy 81.846162 -280.540922) (xy 81.846674 -280.566368) (xy 82.154771 -280.566368) (xy 82.158866 -280.51564)
			(xy 82.171045 -280.466226) (xy 82.190993 -280.419406) (xy 82.218194 -280.376392) (xy 82.251942 -280.338298)
			(xy 82.291364 -280.306111) (xy 82.335438 -280.280665) (xy 82.383024 -280.262618) (xy 82.432888 -280.252438)
			(xy 82.48374 -280.250389) (xy 82.534261 -280.256523) (xy 82.583145 -280.270683) (xy 82.629124 -280.2925)
			(xy 82.671008 -280.32141) (xy 82.707712 -280.356665) (xy 82.738285 -280.397351) (xy 82.761936 -280.442414)
			(xy 82.778052 -280.490688) (xy 82.786216 -280.540922) (xy 82.786728 -280.566368) (xy 83.105256 -280.566368)
			(xy 83.109216 -280.517314) (xy 83.120993 -280.46953) (xy 83.140284 -280.424254) (xy 83.166587 -280.382658)
			(xy 83.199222 -280.345821) (xy 83.237343 -280.314696) (xy 83.279964 -280.290089) (xy 83.32598 -280.272637)
			(xy 83.374199 -280.262793) (xy 83.423374 -280.260812) (xy 83.472229 -280.266744) (xy 83.5195 -280.280436)
			(xy 83.563962 -280.301534) (xy 83.604465 -280.32949) (xy 83.639958 -280.363582) (xy 83.669523 -280.402926)
			(xy 83.692394 -280.446503) (xy 83.707978 -280.493184) (xy 83.715873 -280.541761) (xy 83.716368 -280.566368)
			(xy 84.034879 -280.566368) (xy 84.038974 -280.51564) (xy 84.051153 -280.466226) (xy 84.071101 -280.419406)
			(xy 84.098302 -280.376392) (xy 84.13205 -280.338298) (xy 84.171472 -280.306111) (xy 84.215546 -280.280665)
			(xy 84.263132 -280.262618) (xy 84.312996 -280.252438) (xy 84.363848 -280.250389) (xy 84.414369 -280.256523)
			(xy 84.463253 -280.270683) (xy 84.509232 -280.2925) (xy 84.551116 -280.32141) (xy 84.58782 -280.356665)
			(xy 84.618393 -280.397351) (xy 84.642044 -280.442414) (xy 84.65816 -280.490688) (xy 84.666324 -280.540922)
			(xy 84.666836 -280.566368) (xy 84.98511 -280.566368) (xy 84.98907 -280.517314) (xy 85.000847 -280.46953)
			(xy 85.020138 -280.424254) (xy 85.046441 -280.382658) (xy 85.079076 -280.345821) (xy 85.117197 -280.314696)
			(xy 85.159818 -280.290089) (xy 85.205834 -280.272637) (xy 85.254053 -280.262793) (xy 85.303228 -280.260812)
			(xy 85.352083 -280.266744) (xy 85.399354 -280.280436) (xy 85.443816 -280.301534) (xy 85.484319 -280.32949)
			(xy 85.519812 -280.363582) (xy 85.549377 -280.402926) (xy 85.572248 -280.446503) (xy 85.587832 -280.493184)
			(xy 85.595727 -280.541761) (xy 85.596222 -280.566368) (xy 85.914733 -280.566368) (xy 85.918828 -280.51564)
			(xy 85.931007 -280.466226) (xy 85.950955 -280.419406) (xy 85.978156 -280.376392) (xy 86.011904 -280.338298)
			(xy 86.051326 -280.306111) (xy 86.0954 -280.280665) (xy 86.142986 -280.262618) (xy 86.19285 -280.252438)
			(xy 86.243702 -280.250389) (xy 86.294223 -280.256523) (xy 86.343107 -280.270683) (xy 86.389086 -280.2925)
			(xy 86.43097 -280.32141) (xy 86.467674 -280.356665) (xy 86.498247 -280.397351) (xy 86.521898 -280.442414)
			(xy 86.538014 -280.490688) (xy 86.546178 -280.540922) (xy 86.54669 -280.566368) (xy 86.865218 -280.566368)
			(xy 86.869178 -280.517314) (xy 86.880955 -280.46953) (xy 86.900246 -280.424254) (xy 86.926549 -280.382658)
			(xy 86.959184 -280.345821) (xy 86.997305 -280.314696) (xy 87.039926 -280.290089) (xy 87.085942 -280.272637)
			(xy 87.134161 -280.262793) (xy 87.183336 -280.260812) (xy 87.232191 -280.266744) (xy 87.279462 -280.280436)
			(xy 87.323924 -280.301534) (xy 87.364427 -280.32949) (xy 87.39992 -280.363582) (xy 87.429485 -280.402926)
			(xy 87.452356 -280.446503) (xy 87.46794 -280.493184) (xy 87.475835 -280.541761) (xy 87.47633 -280.566368)
			(xy 87.794841 -280.566368) (xy 87.798936 -280.51564) (xy 87.811115 -280.466226) (xy 87.831063 -280.419406)
			(xy 87.858264 -280.376392) (xy 87.892012 -280.338298) (xy 87.931434 -280.306111) (xy 87.975508 -280.280665)
			(xy 88.023094 -280.262618) (xy 88.072958 -280.252438) (xy 88.12381 -280.250389) (xy 88.174331 -280.256523)
			(xy 88.223215 -280.270683) (xy 88.269194 -280.2925) (xy 88.311078 -280.32141) (xy 88.347782 -280.356665)
			(xy 88.378355 -280.397351) (xy 88.402006 -280.442414) (xy 88.418122 -280.490688) (xy 88.426286 -280.540922)
			(xy 88.426798 -280.566368) (xy 88.734895 -280.566368) (xy 88.73899 -280.51564) (xy 88.751169 -280.466226)
			(xy 88.771117 -280.419406) (xy 88.798318 -280.376392) (xy 88.832066 -280.338298) (xy 88.871488 -280.306111)
			(xy 88.915562 -280.280665) (xy 88.963148 -280.262618) (xy 89.013012 -280.252438) (xy 89.063864 -280.250389)
			(xy 89.114385 -280.256523) (xy 89.163269 -280.270683) (xy 89.209248 -280.2925) (xy 89.251132 -280.32141)
			(xy 89.287836 -280.356665) (xy 89.318409 -280.397351) (xy 89.34206 -280.442414) (xy 89.358176 -280.490688)
			(xy 89.36634 -280.540922) (xy 89.366852 -280.566368) (xy 89.685126 -280.566368) (xy 89.689086 -280.517314)
			(xy 89.700863 -280.46953) (xy 89.720154 -280.424254) (xy 89.746457 -280.382658) (xy 89.779092 -280.345821)
			(xy 89.817213 -280.314696) (xy 89.859834 -280.290089) (xy 89.90585 -280.272637) (xy 89.954069 -280.262793)
			(xy 90.003244 -280.260812) (xy 90.052099 -280.266744) (xy 90.09937 -280.280436) (xy 90.143832 -280.301534)
			(xy 90.184335 -280.32949) (xy 90.219828 -280.363582) (xy 90.249393 -280.402926) (xy 90.272264 -280.446503)
			(xy 90.287848 -280.493184) (xy 90.295743 -280.541761) (xy 90.296238 -280.566368) (xy 90.614749 -280.566368)
			(xy 90.618844 -280.51564) (xy 90.631023 -280.466226) (xy 90.650971 -280.419406) (xy 90.678172 -280.376392)
			(xy 90.71192 -280.338298) (xy 90.751342 -280.306111) (xy 90.795416 -280.280665) (xy 90.843002 -280.262618)
			(xy 90.892866 -280.252438) (xy 90.943718 -280.250389) (xy 90.994239 -280.256523) (xy 91.043123 -280.270683)
			(xy 91.089102 -280.2925) (xy 91.130986 -280.32141) (xy 91.16769 -280.356665) (xy 91.198263 -280.397351)
			(xy 91.221914 -280.442414) (xy 91.23803 -280.490688) (xy 91.246194 -280.540922) (xy 91.246706 -280.566368)
			(xy 91.565234 -280.566368) (xy 91.569194 -280.517314) (xy 91.580971 -280.46953) (xy 91.600262 -280.424254)
			(xy 91.626565 -280.382658) (xy 91.6592 -280.345821) (xy 91.697321 -280.314696) (xy 91.739942 -280.290089)
			(xy 91.785958 -280.272637) (xy 91.834177 -280.262793) (xy 91.883352 -280.260812) (xy 91.932207 -280.266744)
			(xy 91.979478 -280.280436) (xy 92.02394 -280.301534) (xy 92.064443 -280.32949) (xy 92.099936 -280.363582)
			(xy 92.129501 -280.402926) (xy 92.152372 -280.446503) (xy 92.167956 -280.493184) (xy 92.175851 -280.541761)
			(xy 92.176346 -280.566368) (xy 92.494857 -280.566368) (xy 92.498952 -280.51564) (xy 92.511131 -280.466226)
			(xy 92.531079 -280.419406) (xy 92.55828 -280.376392) (xy 92.592028 -280.338298) (xy 92.63145 -280.306111)
			(xy 92.675524 -280.280665) (xy 92.72311 -280.262618) (xy 92.772974 -280.252438) (xy 92.823826 -280.250389)
			(xy 92.874347 -280.256523) (xy 92.923231 -280.270683) (xy 92.96921 -280.2925) (xy 93.011094 -280.32141)
			(xy 93.047798 -280.356665) (xy 93.078371 -280.397351) (xy 93.102022 -280.442414) (xy 93.118138 -280.490688)
			(xy 93.126302 -280.540922) (xy 93.126814 -280.566368) (xy 93.445342 -280.566368) (xy 93.449302 -280.517314)
			(xy 93.461079 -280.46953) (xy 93.48037 -280.424254) (xy 93.506673 -280.382658) (xy 93.539308 -280.345821)
			(xy 93.577429 -280.314696) (xy 93.62005 -280.290089) (xy 93.666066 -280.272637) (xy 93.714285 -280.262793)
			(xy 93.76346 -280.260812) (xy 93.812315 -280.266744) (xy 93.859586 -280.280436) (xy 93.904048 -280.301534)
			(xy 93.944551 -280.32949) (xy 93.980044 -280.363582) (xy 94.009609 -280.402926) (xy 94.03248 -280.446503)
			(xy 94.048064 -280.493184) (xy 94.055959 -280.541761) (xy 94.056454 -280.566368) (xy 94.374711 -280.566368)
			(xy 94.378806 -280.51564) (xy 94.390985 -280.466226) (xy 94.410933 -280.419406) (xy 94.438134 -280.376392)
			(xy 94.471882 -280.338298) (xy 94.511304 -280.306111) (xy 94.555378 -280.280665) (xy 94.602964 -280.262618)
			(xy 94.652828 -280.252438) (xy 94.70368 -280.250389) (xy 94.754201 -280.256523) (xy 94.803085 -280.270683)
			(xy 94.849064 -280.2925) (xy 94.890948 -280.32141) (xy 94.927652 -280.356665) (xy 94.958225 -280.397351)
			(xy 94.981876 -280.442414) (xy 94.997992 -280.490688) (xy 95.006156 -280.540922) (xy 95.006668 -280.566368)
			(xy 95.314765 -280.566368) (xy 95.31886 -280.51564) (xy 95.331039 -280.466226) (xy 95.350987 -280.419406)
			(xy 95.378188 -280.376392) (xy 95.411936 -280.338298) (xy 95.451358 -280.306111) (xy 95.495432 -280.280665)
			(xy 95.543018 -280.262618) (xy 95.592882 -280.252438) (xy 95.643734 -280.250389) (xy 95.694255 -280.256523)
			(xy 95.743139 -280.270683) (xy 95.789118 -280.2925) (xy 95.831002 -280.32141) (xy 95.867706 -280.356665)
			(xy 95.898279 -280.397351) (xy 95.92193 -280.442414) (xy 95.938046 -280.490688) (xy 95.94621 -280.540922)
			(xy 95.946722 -280.566368) (xy 96.26525 -280.566368) (xy 96.26921 -280.517314) (xy 96.280987 -280.46953)
			(xy 96.300278 -280.424254) (xy 96.326581 -280.382658) (xy 96.359216 -280.345821) (xy 96.397337 -280.314696)
			(xy 96.439958 -280.290089) (xy 96.485974 -280.272637) (xy 96.534193 -280.262793) (xy 96.583368 -280.260812)
			(xy 96.632223 -280.266744) (xy 96.679494 -280.280436) (xy 96.723956 -280.301534) (xy 96.764459 -280.32949)
			(xy 96.799952 -280.363582) (xy 96.829517 -280.402926) (xy 96.852388 -280.446503) (xy 96.867972 -280.493184)
			(xy 96.875867 -280.541761) (xy 96.876362 -280.566368) (xy 97.205304 -280.566368) (xy 97.209264 -280.517314)
			(xy 97.221041 -280.46953) (xy 97.240332 -280.424254) (xy 97.266635 -280.382658) (xy 97.29927 -280.345821)
			(xy 97.337391 -280.314696) (xy 97.380012 -280.290089) (xy 97.426028 -280.272637) (xy 97.474247 -280.262793)
			(xy 97.523422 -280.260812) (xy 97.572277 -280.266744) (xy 97.619548 -280.280436) (xy 97.66401 -280.301534)
			(xy 97.704513 -280.32949) (xy 97.740006 -280.363582) (xy 97.769571 -280.402926) (xy 97.792442 -280.446503)
			(xy 97.808026 -280.493184) (xy 97.815921 -280.541761) (xy 97.816416 -280.566368) (xy 98.145358 -280.566368)
			(xy 98.149318 -280.517314) (xy 98.161095 -280.46953) (xy 98.180386 -280.424254) (xy 98.206689 -280.382658)
			(xy 98.239324 -280.345821) (xy 98.277445 -280.314696) (xy 98.320066 -280.290089) (xy 98.366082 -280.272637)
			(xy 98.414301 -280.262793) (xy 98.463476 -280.260812) (xy 98.512331 -280.266744) (xy 98.559602 -280.280436)
			(xy 98.604064 -280.301534) (xy 98.644567 -280.32949) (xy 98.68006 -280.363582) (xy 98.709625 -280.402926)
			(xy 98.732496 -280.446503) (xy 98.74808 -280.493184) (xy 98.755975 -280.541761) (xy 98.75647 -280.566368)
			(xy 99.085158 -280.566368) (xy 99.089118 -280.517314) (xy 99.100895 -280.46953) (xy 99.120186 -280.424254)
			(xy 99.146489 -280.382658) (xy 99.179124 -280.345821) (xy 99.217245 -280.314696) (xy 99.259866 -280.290089)
			(xy 99.305882 -280.272637) (xy 99.354101 -280.262793) (xy 99.403276 -280.260812) (xy 99.452131 -280.266744)
			(xy 99.499402 -280.280436) (xy 99.543864 -280.301534) (xy 99.584367 -280.32949) (xy 99.61986 -280.363582)
			(xy 99.649425 -280.402926) (xy 99.672296 -280.446503) (xy 99.68788 -280.493184) (xy 99.695775 -280.541761)
			(xy 99.69627 -280.566368) (xy 100.025212 -280.566368) (xy 100.029172 -280.517314) (xy 100.040949 -280.46953)
			(xy 100.06024 -280.424254) (xy 100.086543 -280.382658) (xy 100.119178 -280.345821) (xy 100.157299 -280.314696)
			(xy 100.19992 -280.290089) (xy 100.245936 -280.272637) (xy 100.294155 -280.262793) (xy 100.34333 -280.260812)
			(xy 100.392185 -280.266744) (xy 100.439456 -280.280436) (xy 100.483918 -280.301534) (xy 100.524421 -280.32949)
			(xy 100.559914 -280.363582) (xy 100.589479 -280.402926) (xy 100.61235 -280.446503) (xy 100.627934 -280.493184)
			(xy 100.635829 -280.541761) (xy 100.636324 -280.566368) (xy 100.965266 -280.566368) (xy 100.969226 -280.517314)
			(xy 100.981003 -280.46953) (xy 101.000294 -280.424254) (xy 101.026597 -280.382658) (xy 101.059232 -280.345821)
			(xy 101.097353 -280.314696) (xy 101.139974 -280.290089) (xy 101.18599 -280.272637) (xy 101.234209 -280.262793)
			(xy 101.283384 -280.260812) (xy 101.332239 -280.266744) (xy 101.37951 -280.280436) (xy 101.423972 -280.301534)
			(xy 101.464475 -280.32949) (xy 101.499968 -280.363582) (xy 101.529533 -280.402926) (xy 101.552404 -280.446503)
			(xy 101.567988 -280.493184) (xy 101.575883 -280.541761) (xy 101.576378 -280.566368) (xy 101.90532 -280.566368)
			(xy 101.90928 -280.517314) (xy 101.921057 -280.46953) (xy 101.940348 -280.424254) (xy 101.966651 -280.382658)
			(xy 101.999286 -280.345821) (xy 102.037407 -280.314696) (xy 102.080028 -280.290089) (xy 102.126044 -280.272637)
			(xy 102.174263 -280.262793) (xy 102.223438 -280.260812) (xy 102.272293 -280.266744) (xy 102.319564 -280.280436)
			(xy 102.364026 -280.301534) (xy 102.404529 -280.32949) (xy 102.440022 -280.363582) (xy 102.469587 -280.402926)
			(xy 102.492458 -280.446503) (xy 102.508042 -280.493184) (xy 102.515937 -280.541761) (xy 102.516432 -280.566368)
			(xy 102.515937 -280.590975) (xy 102.508042 -280.639552) (xy 102.492458 -280.686233) (xy 102.469587 -280.72981)
			(xy 102.440022 -280.769154) (xy 102.404529 -280.803246) (xy 102.364026 -280.831202) (xy 102.319564 -280.8523)
			(xy 102.272293 -280.865992) (xy 102.223438 -280.871924) (xy 102.174263 -280.869943) (xy 102.126044 -280.860099)
			(xy 102.080028 -280.842647) (xy 102.037407 -280.81804) (xy 101.999286 -280.786915) (xy 101.966651 -280.750078)
			(xy 101.940348 -280.708482) (xy 101.921057 -280.663206) (xy 101.90928 -280.615422) (xy 101.90532 -280.566368)
			(xy 101.576378 -280.566368) (xy 101.575883 -280.590975) (xy 101.567988 -280.639552) (xy 101.552404 -280.686233)
			(xy 101.529533 -280.72981) (xy 101.499968 -280.769154) (xy 101.464475 -280.803246) (xy 101.423972 -280.831202)
			(xy 101.37951 -280.8523) (xy 101.332239 -280.865992) (xy 101.283384 -280.871924) (xy 101.234209 -280.869943)
			(xy 101.18599 -280.860099) (xy 101.139974 -280.842647) (xy 101.097353 -280.81804) (xy 101.059232 -280.786915)
			(xy 101.026597 -280.750078) (xy 101.000294 -280.708482) (xy 100.981003 -280.663206) (xy 100.969226 -280.615422)
			(xy 100.965266 -280.566368) (xy 100.636324 -280.566368) (xy 100.635829 -280.590975) (xy 100.627934 -280.639552)
			(xy 100.61235 -280.686233) (xy 100.589479 -280.72981) (xy 100.559914 -280.769154) (xy 100.524421 -280.803246)
			(xy 100.483918 -280.831202) (xy 100.439456 -280.8523) (xy 100.392185 -280.865992) (xy 100.34333 -280.871924)
			(xy 100.294155 -280.869943) (xy 100.245936 -280.860099) (xy 100.19992 -280.842647) (xy 100.157299 -280.81804)
			(xy 100.119178 -280.786915) (xy 100.086543 -280.750078) (xy 100.06024 -280.708482) (xy 100.040949 -280.663206)
			(xy 100.029172 -280.615422) (xy 100.025212 -280.566368) (xy 99.69627 -280.566368) (xy 99.695775 -280.590975)
			(xy 99.68788 -280.639552) (xy 99.672296 -280.686233) (xy 99.649425 -280.72981) (xy 99.61986 -280.769154)
			(xy 99.584367 -280.803246) (xy 99.543864 -280.831202) (xy 99.499402 -280.8523) (xy 99.452131 -280.865992)
			(xy 99.403276 -280.871924) (xy 99.354101 -280.869943) (xy 99.305882 -280.860099) (xy 99.259866 -280.842647)
			(xy 99.217245 -280.81804) (xy 99.179124 -280.786915) (xy 99.146489 -280.750078) (xy 99.120186 -280.708482)
			(xy 99.100895 -280.663206) (xy 99.089118 -280.615422) (xy 99.085158 -280.566368) (xy 98.75647 -280.566368)
			(xy 98.755975 -280.590975) (xy 98.74808 -280.639552) (xy 98.732496 -280.686233) (xy 98.709625 -280.72981)
			(xy 98.68006 -280.769154) (xy 98.644567 -280.803246) (xy 98.604064 -280.831202) (xy 98.559602 -280.8523)
			(xy 98.512331 -280.865992) (xy 98.463476 -280.871924) (xy 98.414301 -280.869943) (xy 98.366082 -280.860099)
			(xy 98.320066 -280.842647) (xy 98.277445 -280.81804) (xy 98.239324 -280.786915) (xy 98.206689 -280.750078)
			(xy 98.180386 -280.708482) (xy 98.161095 -280.663206) (xy 98.149318 -280.615422) (xy 98.145358 -280.566368)
			(xy 97.816416 -280.566368) (xy 97.815921 -280.590975) (xy 97.808026 -280.639552) (xy 97.792442 -280.686233)
			(xy 97.769571 -280.72981) (xy 97.740006 -280.769154) (xy 97.704513 -280.803246) (xy 97.66401 -280.831202)
			(xy 97.619548 -280.8523) (xy 97.572277 -280.865992) (xy 97.523422 -280.871924) (xy 97.474247 -280.869943)
			(xy 97.426028 -280.860099) (xy 97.380012 -280.842647) (xy 97.337391 -280.81804) (xy 97.29927 -280.786915)
			(xy 97.266635 -280.750078) (xy 97.240332 -280.708482) (xy 97.221041 -280.663206) (xy 97.209264 -280.615422)
			(xy 97.205304 -280.566368) (xy 96.876362 -280.566368) (xy 96.875867 -280.590975) (xy 96.867972 -280.639552)
			(xy 96.852388 -280.686233) (xy 96.829517 -280.72981) (xy 96.799952 -280.769154) (xy 96.764459 -280.803246)
			(xy 96.723956 -280.831202) (xy 96.679494 -280.8523) (xy 96.632223 -280.865992) (xy 96.583368 -280.871924)
			(xy 96.534193 -280.869943) (xy 96.485974 -280.860099) (xy 96.439958 -280.842647) (xy 96.397337 -280.81804)
			(xy 96.359216 -280.786915) (xy 96.326581 -280.750078) (xy 96.300278 -280.708482) (xy 96.280987 -280.663206)
			(xy 96.26921 -280.615422) (xy 96.26525 -280.566368) (xy 95.946722 -280.566368) (xy 95.94621 -280.591814)
			(xy 95.938046 -280.642048) (xy 95.92193 -280.690322) (xy 95.898279 -280.735385) (xy 95.867706 -280.776071)
			(xy 95.831002 -280.811326) (xy 95.789118 -280.840236) (xy 95.743139 -280.862053) (xy 95.694255 -280.876213)
			(xy 95.643734 -280.882347) (xy 95.592882 -280.880298) (xy 95.543018 -280.870118) (xy 95.495432 -280.852071)
			(xy 95.451358 -280.826625) (xy 95.411936 -280.794438) (xy 95.378188 -280.756344) (xy 95.350987 -280.71333)
			(xy 95.331039 -280.66651) (xy 95.31886 -280.617096) (xy 95.314765 -280.566368) (xy 95.006668 -280.566368)
			(xy 95.006156 -280.591814) (xy 94.997992 -280.642048) (xy 94.981876 -280.690322) (xy 94.958225 -280.735385)
			(xy 94.927652 -280.776071) (xy 94.890948 -280.811326) (xy 94.849064 -280.840236) (xy 94.803085 -280.862053)
			(xy 94.754201 -280.876213) (xy 94.70368 -280.882347) (xy 94.652828 -280.880298) (xy 94.602964 -280.870118)
			(xy 94.555378 -280.852071) (xy 94.511304 -280.826625) (xy 94.471882 -280.794438) (xy 94.438134 -280.756344)
			(xy 94.410933 -280.71333) (xy 94.390985 -280.66651) (xy 94.378806 -280.617096) (xy 94.374711 -280.566368)
			(xy 94.056454 -280.566368) (xy 94.055959 -280.590975) (xy 94.048064 -280.639552) (xy 94.03248 -280.686233)
			(xy 94.009609 -280.72981) (xy 93.980044 -280.769154) (xy 93.944551 -280.803246) (xy 93.904048 -280.831202)
			(xy 93.859586 -280.8523) (xy 93.812315 -280.865992) (xy 93.76346 -280.871924) (xy 93.714285 -280.869943)
			(xy 93.666066 -280.860099) (xy 93.62005 -280.842647) (xy 93.577429 -280.81804) (xy 93.539308 -280.786915)
			(xy 93.506673 -280.750078) (xy 93.48037 -280.708482) (xy 93.461079 -280.663206) (xy 93.449302 -280.615422)
			(xy 93.445342 -280.566368) (xy 93.126814 -280.566368) (xy 93.126302 -280.591814) (xy 93.118138 -280.642048)
			(xy 93.102022 -280.690322) (xy 93.078371 -280.735385) (xy 93.047798 -280.776071) (xy 93.011094 -280.811326)
			(xy 92.96921 -280.840236) (xy 92.923231 -280.862053) (xy 92.874347 -280.876213) (xy 92.823826 -280.882347)
			(xy 92.772974 -280.880298) (xy 92.72311 -280.870118) (xy 92.675524 -280.852071) (xy 92.63145 -280.826625)
			(xy 92.592028 -280.794438) (xy 92.55828 -280.756344) (xy 92.531079 -280.71333) (xy 92.511131 -280.66651)
			(xy 92.498952 -280.617096) (xy 92.494857 -280.566368) (xy 92.176346 -280.566368) (xy 92.175851 -280.590975)
			(xy 92.167956 -280.639552) (xy 92.152372 -280.686233) (xy 92.129501 -280.72981) (xy 92.099936 -280.769154)
			(xy 92.064443 -280.803246) (xy 92.02394 -280.831202) (xy 91.979478 -280.8523) (xy 91.932207 -280.865992)
			(xy 91.883352 -280.871924) (xy 91.834177 -280.869943) (xy 91.785958 -280.860099) (xy 91.739942 -280.842647)
			(xy 91.697321 -280.81804) (xy 91.6592 -280.786915) (xy 91.626565 -280.750078) (xy 91.600262 -280.708482)
			(xy 91.580971 -280.663206) (xy 91.569194 -280.615422) (xy 91.565234 -280.566368) (xy 91.246706 -280.566368)
			(xy 91.246194 -280.591814) (xy 91.23803 -280.642048) (xy 91.221914 -280.690322) (xy 91.198263 -280.735385)
			(xy 91.16769 -280.776071) (xy 91.130986 -280.811326) (xy 91.089102 -280.840236) (xy 91.043123 -280.862053)
			(xy 90.994239 -280.876213) (xy 90.943718 -280.882347) (xy 90.892866 -280.880298) (xy 90.843002 -280.870118)
			(xy 90.795416 -280.852071) (xy 90.751342 -280.826625) (xy 90.71192 -280.794438) (xy 90.678172 -280.756344)
			(xy 90.650971 -280.71333) (xy 90.631023 -280.66651) (xy 90.618844 -280.617096) (xy 90.614749 -280.566368)
			(xy 90.296238 -280.566368) (xy 90.295743 -280.590975) (xy 90.287848 -280.639552) (xy 90.272264 -280.686233)
			(xy 90.249393 -280.72981) (xy 90.219828 -280.769154) (xy 90.184335 -280.803246) (xy 90.143832 -280.831202)
			(xy 90.09937 -280.8523) (xy 90.052099 -280.865992) (xy 90.003244 -280.871924) (xy 89.954069 -280.869943)
			(xy 89.90585 -280.860099) (xy 89.859834 -280.842647) (xy 89.817213 -280.81804) (xy 89.779092 -280.786915)
			(xy 89.746457 -280.750078) (xy 89.720154 -280.708482) (xy 89.700863 -280.663206) (xy 89.689086 -280.615422)
			(xy 89.685126 -280.566368) (xy 89.366852 -280.566368) (xy 89.36634 -280.591814) (xy 89.358176 -280.642048)
			(xy 89.34206 -280.690322) (xy 89.318409 -280.735385) (xy 89.287836 -280.776071) (xy 89.251132 -280.811326)
			(xy 89.209248 -280.840236) (xy 89.163269 -280.862053) (xy 89.114385 -280.876213) (xy 89.063864 -280.882347)
			(xy 89.013012 -280.880298) (xy 88.963148 -280.870118) (xy 88.915562 -280.852071) (xy 88.871488 -280.826625)
			(xy 88.832066 -280.794438) (xy 88.798318 -280.756344) (xy 88.771117 -280.71333) (xy 88.751169 -280.66651)
			(xy 88.73899 -280.617096) (xy 88.734895 -280.566368) (xy 88.426798 -280.566368) (xy 88.426286 -280.591814)
			(xy 88.418122 -280.642048) (xy 88.402006 -280.690322) (xy 88.378355 -280.735385) (xy 88.347782 -280.776071)
			(xy 88.311078 -280.811326) (xy 88.269194 -280.840236) (xy 88.223215 -280.862053) (xy 88.174331 -280.876213)
			(xy 88.12381 -280.882347) (xy 88.072958 -280.880298) (xy 88.023094 -280.870118) (xy 87.975508 -280.852071)
			(xy 87.931434 -280.826625) (xy 87.892012 -280.794438) (xy 87.858264 -280.756344) (xy 87.831063 -280.71333)
			(xy 87.811115 -280.66651) (xy 87.798936 -280.617096) (xy 87.794841 -280.566368) (xy 87.47633 -280.566368)
			(xy 87.475835 -280.590975) (xy 87.46794 -280.639552) (xy 87.452356 -280.686233) (xy 87.429485 -280.72981)
			(xy 87.39992 -280.769154) (xy 87.364427 -280.803246) (xy 87.323924 -280.831202) (xy 87.279462 -280.8523)
			(xy 87.232191 -280.865992) (xy 87.183336 -280.871924) (xy 87.134161 -280.869943) (xy 87.085942 -280.860099)
			(xy 87.039926 -280.842647) (xy 86.997305 -280.81804) (xy 86.959184 -280.786915) (xy 86.926549 -280.750078)
			(xy 86.900246 -280.708482) (xy 86.880955 -280.663206) (xy 86.869178 -280.615422) (xy 86.865218 -280.566368)
			(xy 86.54669 -280.566368) (xy 86.546178 -280.591814) (xy 86.538014 -280.642048) (xy 86.521898 -280.690322)
			(xy 86.498247 -280.735385) (xy 86.467674 -280.776071) (xy 86.43097 -280.811326) (xy 86.389086 -280.840236)
			(xy 86.343107 -280.862053) (xy 86.294223 -280.876213) (xy 86.243702 -280.882347) (xy 86.19285 -280.880298)
			(xy 86.142986 -280.870118) (xy 86.0954 -280.852071) (xy 86.051326 -280.826625) (xy 86.011904 -280.794438)
			(xy 85.978156 -280.756344) (xy 85.950955 -280.71333) (xy 85.931007 -280.66651) (xy 85.918828 -280.617096)
			(xy 85.914733 -280.566368) (xy 85.596222 -280.566368) (xy 85.595727 -280.590975) (xy 85.587832 -280.639552)
			(xy 85.572248 -280.686233) (xy 85.549377 -280.72981) (xy 85.519812 -280.769154) (xy 85.484319 -280.803246)
			(xy 85.443816 -280.831202) (xy 85.399354 -280.8523) (xy 85.352083 -280.865992) (xy 85.303228 -280.871924)
			(xy 85.254053 -280.869943) (xy 85.205834 -280.860099) (xy 85.159818 -280.842647) (xy 85.117197 -280.81804)
			(xy 85.079076 -280.786915) (xy 85.046441 -280.750078) (xy 85.020138 -280.708482) (xy 85.000847 -280.663206)
			(xy 84.98907 -280.615422) (xy 84.98511 -280.566368) (xy 84.666836 -280.566368) (xy 84.666324 -280.591814)
			(xy 84.65816 -280.642048) (xy 84.642044 -280.690322) (xy 84.618393 -280.735385) (xy 84.58782 -280.776071)
			(xy 84.551116 -280.811326) (xy 84.509232 -280.840236) (xy 84.463253 -280.862053) (xy 84.414369 -280.876213)
			(xy 84.363848 -280.882347) (xy 84.312996 -280.880298) (xy 84.263132 -280.870118) (xy 84.215546 -280.852071)
			(xy 84.171472 -280.826625) (xy 84.13205 -280.794438) (xy 84.098302 -280.756344) (xy 84.071101 -280.71333)
			(xy 84.051153 -280.66651) (xy 84.038974 -280.617096) (xy 84.034879 -280.566368) (xy 83.716368 -280.566368)
			(xy 83.715873 -280.590975) (xy 83.707978 -280.639552) (xy 83.692394 -280.686233) (xy 83.669523 -280.72981)
			(xy 83.639958 -280.769154) (xy 83.604465 -280.803246) (xy 83.563962 -280.831202) (xy 83.5195 -280.8523)
			(xy 83.472229 -280.865992) (xy 83.423374 -280.871924) (xy 83.374199 -280.869943) (xy 83.32598 -280.860099)
			(xy 83.279964 -280.842647) (xy 83.237343 -280.81804) (xy 83.199222 -280.786915) (xy 83.166587 -280.750078)
			(xy 83.140284 -280.708482) (xy 83.120993 -280.663206) (xy 83.109216 -280.615422) (xy 83.105256 -280.566368)
			(xy 82.786728 -280.566368) (xy 82.786216 -280.591814) (xy 82.778052 -280.642048) (xy 82.761936 -280.690322)
			(xy 82.738285 -280.735385) (xy 82.707712 -280.776071) (xy 82.671008 -280.811326) (xy 82.629124 -280.840236)
			(xy 82.583145 -280.862053) (xy 82.534261 -280.876213) (xy 82.48374 -280.882347) (xy 82.432888 -280.880298)
			(xy 82.383024 -280.870118) (xy 82.335438 -280.852071) (xy 82.291364 -280.826625) (xy 82.251942 -280.794438)
			(xy 82.218194 -280.756344) (xy 82.190993 -280.71333) (xy 82.171045 -280.66651) (xy 82.158866 -280.617096)
			(xy 82.154771 -280.566368) (xy 81.846674 -280.566368) (xy 81.846162 -280.591814) (xy 81.837998 -280.642048)
			(xy 81.821882 -280.690322) (xy 81.798231 -280.735385) (xy 81.767658 -280.776071) (xy 81.730954 -280.811326)
			(xy 81.68907 -280.840236) (xy 81.643091 -280.862053) (xy 81.594207 -280.876213) (xy 81.543686 -280.882347)
			(xy 81.492834 -280.880298) (xy 81.44297 -280.870118) (xy 81.395384 -280.852071) (xy 81.35131 -280.826625)
			(xy 81.311888 -280.794438) (xy 81.27814 -280.756344) (xy 81.250939 -280.71333) (xy 81.230991 -280.66651)
			(xy 81.218812 -280.617096) (xy 81.214717 -280.566368) (xy 80.89646 -280.566368) (xy 80.895965 -280.590975)
			(xy 80.88807 -280.639552) (xy 80.872486 -280.686233) (xy 80.849615 -280.72981) (xy 80.82005 -280.769154)
			(xy 80.784557 -280.803246) (xy 80.744054 -280.831202) (xy 80.699592 -280.8523) (xy 80.652321 -280.865992)
			(xy 80.603466 -280.871924) (xy 80.554291 -280.869943) (xy 80.506072 -280.860099) (xy 80.460056 -280.842647)
			(xy 80.417435 -280.81804) (xy 80.379314 -280.786915) (xy 80.346679 -280.750078) (xy 80.320376 -280.708482)
			(xy 80.301085 -280.663206) (xy 80.289308 -280.615422) (xy 80.285348 -280.566368) (xy 79.016352 -280.566368)
			(xy 79.015857 -280.590975) (xy 79.007962 -280.639552) (xy 78.992378 -280.686233) (xy 78.969507 -280.72981)
			(xy 78.939942 -280.769154) (xy 78.904449 -280.803246) (xy 78.863946 -280.831202) (xy 78.819484 -280.8523)
			(xy 78.772213 -280.865992) (xy 78.723358 -280.871924) (xy 78.674183 -280.869943) (xy 78.625964 -280.860099)
			(xy 78.579948 -280.842647) (xy 78.537327 -280.81804) (xy 78.499206 -280.786915) (xy 78.466571 -280.750078)
			(xy 78.440268 -280.708482) (xy 78.420977 -280.663206) (xy 78.4092 -280.615422) (xy 78.40524 -280.566368)
			(xy 73.228962 -280.566368) (xy 73.228962 -281.110436) (xy 76.807072 -281.110436) (xy 76.811032 -281.061382)
			(xy 76.822809 -281.013598) (xy 76.8421 -280.968322) (xy 76.868403 -280.926726) (xy 76.901038 -280.889889)
			(xy 76.939159 -280.858764) (xy 76.98178 -280.834157) (xy 77.027796 -280.816705) (xy 77.076015 -280.806861)
			(xy 77.12519 -280.80488) (xy 77.174045 -280.810812) (xy 77.221316 -280.824504) (xy 77.265778 -280.845602)
			(xy 77.306281 -280.873558) (xy 77.341774 -280.90765) (xy 77.371339 -280.946994) (xy 77.39421 -280.990571)
			(xy 77.409794 -281.037252) (xy 77.417689 -281.085829) (xy 77.418184 -281.110436) (xy 77.417689 -281.135043)
			(xy 77.409794 -281.18362) (xy 77.39421 -281.230301) (xy 77.371339 -281.273878) (xy 77.341774 -281.313222)
			(xy 77.306281 -281.347314) (xy 77.265778 -281.37527) (xy 77.263451 -281.376374) (xy 79.815194 -281.376374)
			(xy 79.819154 -281.32732) (xy 79.830931 -281.279536) (xy 79.850222 -281.23426) (xy 79.876525 -281.192664)
			(xy 79.90916 -281.155827) (xy 79.947281 -281.124702) (xy 79.989902 -281.100095) (xy 80.035918 -281.082643)
			(xy 80.084137 -281.072799) (xy 80.133312 -281.070818) (xy 80.182167 -281.07675) (xy 80.229438 -281.090442)
			(xy 80.2739 -281.11154) (xy 80.314403 -281.139496) (xy 80.349896 -281.173588) (xy 80.379461 -281.212932)
			(xy 80.402332 -281.256509) (xy 80.417916 -281.30319) (xy 80.425811 -281.351767) (xy 80.426306 -281.376374)
			(xy 80.744817 -281.376374) (xy 80.748912 -281.325646) (xy 80.761091 -281.276232) (xy 80.781039 -281.229412)
			(xy 80.80824 -281.186398) (xy 80.841988 -281.148304) (xy 80.88141 -281.116117) (xy 80.925484 -281.090671)
			(xy 80.97307 -281.072624) (xy 81.022934 -281.062444) (xy 81.073786 -281.060395) (xy 81.124307 -281.066529)
			(xy 81.173191 -281.080689) (xy 81.21917 -281.102506) (xy 81.261054 -281.131416) (xy 81.297758 -281.166671)
			(xy 81.328331 -281.207357) (xy 81.351982 -281.25242) (xy 81.368098 -281.300694) (xy 81.376262 -281.350928)
			(xy 81.376774 -281.376374) (xy 81.695302 -281.376374) (xy 81.699262 -281.32732) (xy 81.711039 -281.279536)
			(xy 81.73033 -281.23426) (xy 81.756633 -281.192664) (xy 81.789268 -281.155827) (xy 81.827389 -281.124702)
			(xy 81.87001 -281.100095) (xy 81.916026 -281.082643) (xy 81.964245 -281.072799) (xy 82.01342 -281.070818)
			(xy 82.062275 -281.07675) (xy 82.109546 -281.090442) (xy 82.154008 -281.11154) (xy 82.194511 -281.139496)
			(xy 82.230004 -281.173588) (xy 82.259569 -281.212932) (xy 82.28244 -281.256509) (xy 82.298024 -281.30319)
			(xy 82.305919 -281.351767) (xy 82.306414 -281.376374) (xy 82.624671 -281.376374) (xy 82.628766 -281.325646)
			(xy 82.640945 -281.276232) (xy 82.660893 -281.229412) (xy 82.688094 -281.186398) (xy 82.721842 -281.148304)
			(xy 82.761264 -281.116117) (xy 82.805338 -281.090671) (xy 82.852924 -281.072624) (xy 82.902788 -281.062444)
			(xy 82.95364 -281.060395) (xy 83.004161 -281.066529) (xy 83.053045 -281.080689) (xy 83.099024 -281.102506)
			(xy 83.140908 -281.131416) (xy 83.177612 -281.166671) (xy 83.208185 -281.207357) (xy 83.231836 -281.25242)
			(xy 83.247952 -281.300694) (xy 83.256116 -281.350928) (xy 83.256628 -281.376374) (xy 83.575156 -281.376374)
			(xy 83.579116 -281.32732) (xy 83.590893 -281.279536) (xy 83.610184 -281.23426) (xy 83.636487 -281.192664)
			(xy 83.669122 -281.155827) (xy 83.707243 -281.124702) (xy 83.749864 -281.100095) (xy 83.79588 -281.082643)
			(xy 83.844099 -281.072799) (xy 83.893274 -281.070818) (xy 83.942129 -281.07675) (xy 83.9894 -281.090442)
			(xy 84.033862 -281.11154) (xy 84.074365 -281.139496) (xy 84.109858 -281.173588) (xy 84.139423 -281.212932)
			(xy 84.162294 -281.256509) (xy 84.177878 -281.30319) (xy 84.185773 -281.351767) (xy 84.186268 -281.376374)
			(xy 84.504779 -281.376374) (xy 84.508874 -281.325646) (xy 84.521053 -281.276232) (xy 84.541001 -281.229412)
			(xy 84.568202 -281.186398) (xy 84.60195 -281.148304) (xy 84.641372 -281.116117) (xy 84.685446 -281.090671)
			(xy 84.733032 -281.072624) (xy 84.782896 -281.062444) (xy 84.833748 -281.060395) (xy 84.884269 -281.066529)
			(xy 84.933153 -281.080689) (xy 84.979132 -281.102506) (xy 85.021016 -281.131416) (xy 85.05772 -281.166671)
			(xy 85.088293 -281.207357) (xy 85.111944 -281.25242) (xy 85.12806 -281.300694) (xy 85.136224 -281.350928)
			(xy 85.136736 -281.376374) (xy 85.444833 -281.376374) (xy 85.448928 -281.325646) (xy 85.461107 -281.276232)
			(xy 85.481055 -281.229412) (xy 85.508256 -281.186398) (xy 85.542004 -281.148304) (xy 85.581426 -281.116117)
			(xy 85.6255 -281.090671) (xy 85.673086 -281.072624) (xy 85.72295 -281.062444) (xy 85.773802 -281.060395)
			(xy 85.824323 -281.066529) (xy 85.873207 -281.080689) (xy 85.919186 -281.102506) (xy 85.96107 -281.131416)
			(xy 85.997774 -281.166671) (xy 86.028347 -281.207357) (xy 86.051998 -281.25242) (xy 86.068114 -281.300694)
			(xy 86.076278 -281.350928) (xy 86.07679 -281.376374) (xy 86.395318 -281.376374) (xy 86.399278 -281.32732)
			(xy 86.411055 -281.279536) (xy 86.430346 -281.23426) (xy 86.456649 -281.192664) (xy 86.489284 -281.155827)
			(xy 86.527405 -281.124702) (xy 86.570026 -281.100095) (xy 86.616042 -281.082643) (xy 86.664261 -281.072799)
			(xy 86.713436 -281.070818) (xy 86.762291 -281.07675) (xy 86.809562 -281.090442) (xy 86.854024 -281.11154)
			(xy 86.894527 -281.139496) (xy 86.93002 -281.173588) (xy 86.959585 -281.212932) (xy 86.982456 -281.256509)
			(xy 86.99804 -281.30319) (xy 87.005935 -281.351767) (xy 87.00643 -281.376374) (xy 87.324687 -281.376374)
			(xy 87.328782 -281.325646) (xy 87.340961 -281.276232) (xy 87.360909 -281.229412) (xy 87.38811 -281.186398)
			(xy 87.421858 -281.148304) (xy 87.46128 -281.116117) (xy 87.505354 -281.090671) (xy 87.55294 -281.072624)
			(xy 87.602804 -281.062444) (xy 87.653656 -281.060395) (xy 87.704177 -281.066529) (xy 87.753061 -281.080689)
			(xy 87.79904 -281.102506) (xy 87.840924 -281.131416) (xy 87.877628 -281.166671) (xy 87.908201 -281.207357)
			(xy 87.931852 -281.25242) (xy 87.947968 -281.300694) (xy 87.956132 -281.350928) (xy 87.956644 -281.376374)
			(xy 88.275172 -281.376374) (xy 88.279132 -281.32732) (xy 88.290909 -281.279536) (xy 88.3102 -281.23426)
			(xy 88.336503 -281.192664) (xy 88.369138 -281.155827) (xy 88.407259 -281.124702) (xy 88.44988 -281.100095)
			(xy 88.495896 -281.082643) (xy 88.544115 -281.072799) (xy 88.59329 -281.070818) (xy 88.642145 -281.07675)
			(xy 88.689416 -281.090442) (xy 88.733878 -281.11154) (xy 88.774381 -281.139496) (xy 88.809874 -281.173588)
			(xy 88.839439 -281.212932) (xy 88.86231 -281.256509) (xy 88.877894 -281.30319) (xy 88.885789 -281.351767)
			(xy 88.886284 -281.376374) (xy 89.204795 -281.376374) (xy 89.20889 -281.325646) (xy 89.221069 -281.276232)
			(xy 89.241017 -281.229412) (xy 89.268218 -281.186398) (xy 89.301966 -281.148304) (xy 89.341388 -281.116117)
			(xy 89.385462 -281.090671) (xy 89.433048 -281.072624) (xy 89.482912 -281.062444) (xy 89.533764 -281.060395)
			(xy 89.584285 -281.066529) (xy 89.633169 -281.080689) (xy 89.679148 -281.102506) (xy 89.721032 -281.131416)
			(xy 89.757736 -281.166671) (xy 89.788309 -281.207357) (xy 89.81196 -281.25242) (xy 89.828076 -281.300694)
			(xy 89.83624 -281.350928) (xy 89.836752 -281.376374) (xy 90.15528 -281.376374) (xy 90.15924 -281.32732)
			(xy 90.171017 -281.279536) (xy 90.190308 -281.23426) (xy 90.216611 -281.192664) (xy 90.249246 -281.155827)
			(xy 90.287367 -281.124702) (xy 90.329988 -281.100095) (xy 90.376004 -281.082643) (xy 90.424223 -281.072799)
			(xy 90.473398 -281.070818) (xy 90.522253 -281.07675) (xy 90.569524 -281.090442) (xy 90.613986 -281.11154)
			(xy 90.654489 -281.139496) (xy 90.689982 -281.173588) (xy 90.719547 -281.212932) (xy 90.742418 -281.256509)
			(xy 90.758002 -281.30319) (xy 90.765897 -281.351767) (xy 90.766392 -281.376374) (xy 91.084903 -281.376374)
			(xy 91.088998 -281.325646) (xy 91.101177 -281.276232) (xy 91.121125 -281.229412) (xy 91.148326 -281.186398)
			(xy 91.182074 -281.148304) (xy 91.221496 -281.116117) (xy 91.26557 -281.090671) (xy 91.313156 -281.072624)
			(xy 91.36302 -281.062444) (xy 91.413872 -281.060395) (xy 91.464393 -281.066529) (xy 91.513277 -281.080689)
			(xy 91.559256 -281.102506) (xy 91.60114 -281.131416) (xy 91.637844 -281.166671) (xy 91.668417 -281.207357)
			(xy 91.692068 -281.25242) (xy 91.708184 -281.300694) (xy 91.716348 -281.350928) (xy 91.71686 -281.376374)
			(xy 92.024703 -281.376374) (xy 92.028798 -281.325646) (xy 92.040977 -281.276232) (xy 92.060925 -281.229412)
			(xy 92.088126 -281.186398) (xy 92.121874 -281.148304) (xy 92.161296 -281.116117) (xy 92.20537 -281.090671)
			(xy 92.252956 -281.072624) (xy 92.30282 -281.062444) (xy 92.353672 -281.060395) (xy 92.404193 -281.066529)
			(xy 92.453077 -281.080689) (xy 92.499056 -281.102506) (xy 92.54094 -281.131416) (xy 92.577644 -281.166671)
			(xy 92.608217 -281.207357) (xy 92.631868 -281.25242) (xy 92.647984 -281.300694) (xy 92.656148 -281.350928)
			(xy 92.65666 -281.376374) (xy 92.975188 -281.376374) (xy 92.979148 -281.32732) (xy 92.990925 -281.279536)
			(xy 93.010216 -281.23426) (xy 93.036519 -281.192664) (xy 93.069154 -281.155827) (xy 93.107275 -281.124702)
			(xy 93.149896 -281.100095) (xy 93.195912 -281.082643) (xy 93.244131 -281.072799) (xy 93.293306 -281.070818)
			(xy 93.342161 -281.07675) (xy 93.389432 -281.090442) (xy 93.433894 -281.11154) (xy 93.474397 -281.139496)
			(xy 93.50989 -281.173588) (xy 93.539455 -281.212932) (xy 93.562326 -281.256509) (xy 93.57791 -281.30319)
			(xy 93.585805 -281.351767) (xy 93.5863 -281.376374) (xy 93.904811 -281.376374) (xy 93.908906 -281.325646)
			(xy 93.921085 -281.276232) (xy 93.941033 -281.229412) (xy 93.968234 -281.186398) (xy 94.001982 -281.148304)
			(xy 94.041404 -281.116117) (xy 94.085478 -281.090671) (xy 94.133064 -281.072624) (xy 94.182928 -281.062444)
			(xy 94.23378 -281.060395) (xy 94.284301 -281.066529) (xy 94.333185 -281.080689) (xy 94.379164 -281.102506)
			(xy 94.421048 -281.131416) (xy 94.457752 -281.166671) (xy 94.488325 -281.207357) (xy 94.511976 -281.25242)
			(xy 94.528092 -281.300694) (xy 94.536256 -281.350928) (xy 94.536768 -281.376374) (xy 94.855296 -281.376374)
			(xy 94.859256 -281.32732) (xy 94.871033 -281.279536) (xy 94.890324 -281.23426) (xy 94.916627 -281.192664)
			(xy 94.949262 -281.155827) (xy 94.987383 -281.124702) (xy 95.030004 -281.100095) (xy 95.07602 -281.082643)
			(xy 95.124239 -281.072799) (xy 95.173414 -281.070818) (xy 95.222269 -281.07675) (xy 95.26954 -281.090442)
			(xy 95.314002 -281.11154) (xy 95.354505 -281.139496) (xy 95.389998 -281.173588) (xy 95.419563 -281.212932)
			(xy 95.442434 -281.256509) (xy 95.458018 -281.30319) (xy 95.465913 -281.351767) (xy 95.466408 -281.376374)
			(xy 95.784919 -281.376374) (xy 95.789014 -281.325646) (xy 95.801193 -281.276232) (xy 95.821141 -281.229412)
			(xy 95.848342 -281.186398) (xy 95.88209 -281.148304) (xy 95.921512 -281.116117) (xy 95.965586 -281.090671)
			(xy 96.013172 -281.072624) (xy 96.063036 -281.062444) (xy 96.113888 -281.060395) (xy 96.164409 -281.066529)
			(xy 96.213293 -281.080689) (xy 96.259272 -281.102506) (xy 96.301156 -281.131416) (xy 96.33786 -281.166671)
			(xy 96.368433 -281.207357) (xy 96.392084 -281.25242) (xy 96.4082 -281.300694) (xy 96.416364 -281.350928)
			(xy 96.416876 -281.376374) (xy 96.73515 -281.376374) (xy 96.73911 -281.32732) (xy 96.750887 -281.279536)
			(xy 96.770178 -281.23426) (xy 96.796481 -281.192664) (xy 96.829116 -281.155827) (xy 96.867237 -281.124702)
			(xy 96.909858 -281.100095) (xy 96.955874 -281.082643) (xy 97.004093 -281.072799) (xy 97.053268 -281.070818)
			(xy 97.102123 -281.07675) (xy 97.149394 -281.090442) (xy 97.193856 -281.11154) (xy 97.234359 -281.139496)
			(xy 97.269852 -281.173588) (xy 97.299417 -281.212932) (xy 97.322288 -281.256509) (xy 97.337872 -281.30319)
			(xy 97.345767 -281.351767) (xy 97.346262 -281.376374) (xy 97.664773 -281.376374) (xy 97.668868 -281.325646)
			(xy 97.681047 -281.276232) (xy 97.700995 -281.229412) (xy 97.728196 -281.186398) (xy 97.761944 -281.148304)
			(xy 97.801366 -281.116117) (xy 97.84544 -281.090671) (xy 97.893026 -281.072624) (xy 97.94289 -281.062444)
			(xy 97.993742 -281.060395) (xy 98.044263 -281.066529) (xy 98.093147 -281.080689) (xy 98.139126 -281.102506)
			(xy 98.18101 -281.131416) (xy 98.217714 -281.166671) (xy 98.248287 -281.207357) (xy 98.271938 -281.25242)
			(xy 98.288054 -281.300694) (xy 98.296218 -281.350928) (xy 98.29673 -281.376374) (xy 98.604827 -281.376374)
			(xy 98.608922 -281.325646) (xy 98.621101 -281.276232) (xy 98.641049 -281.229412) (xy 98.66825 -281.186398)
			(xy 98.701998 -281.148304) (xy 98.74142 -281.116117) (xy 98.785494 -281.090671) (xy 98.83308 -281.072624)
			(xy 98.882944 -281.062444) (xy 98.933796 -281.060395) (xy 98.984317 -281.066529) (xy 99.033201 -281.080689)
			(xy 99.07918 -281.102506) (xy 99.121064 -281.131416) (xy 99.157768 -281.166671) (xy 99.188341 -281.207357)
			(xy 99.211992 -281.25242) (xy 99.228108 -281.300694) (xy 99.236272 -281.350928) (xy 99.236784 -281.376374)
			(xy 99.555312 -281.376374) (xy 99.559272 -281.32732) (xy 99.571049 -281.279536) (xy 99.59034 -281.23426)
			(xy 99.616643 -281.192664) (xy 99.649278 -281.155827) (xy 99.687399 -281.124702) (xy 99.73002 -281.100095)
			(xy 99.776036 -281.082643) (xy 99.824255 -281.072799) (xy 99.87343 -281.070818) (xy 99.922285 -281.07675)
			(xy 99.969556 -281.090442) (xy 100.014018 -281.11154) (xy 100.054521 -281.139496) (xy 100.090014 -281.173588)
			(xy 100.119579 -281.212932) (xy 100.14245 -281.256509) (xy 100.158034 -281.30319) (xy 100.165929 -281.351767)
			(xy 100.166424 -281.376374) (xy 100.484935 -281.376374) (xy 100.48903 -281.325646) (xy 100.501209 -281.276232)
			(xy 100.521157 -281.229412) (xy 100.548358 -281.186398) (xy 100.582106 -281.148304) (xy 100.621528 -281.116117)
			(xy 100.665602 -281.090671) (xy 100.713188 -281.072624) (xy 100.763052 -281.062444) (xy 100.813904 -281.060395)
			(xy 100.864425 -281.066529) (xy 100.913309 -281.080689) (xy 100.959288 -281.102506) (xy 101.001172 -281.131416)
			(xy 101.037876 -281.166671) (xy 101.068449 -281.207357) (xy 101.0921 -281.25242) (xy 101.108216 -281.300694)
			(xy 101.11638 -281.350928) (xy 101.116892 -281.376374) (xy 101.424735 -281.376374) (xy 101.42883 -281.325646)
			(xy 101.441009 -281.276232) (xy 101.460957 -281.229412) (xy 101.488158 -281.186398) (xy 101.521906 -281.148304)
			(xy 101.561328 -281.116117) (xy 101.605402 -281.090671) (xy 101.652988 -281.072624) (xy 101.702852 -281.062444)
			(xy 101.753704 -281.060395) (xy 101.804225 -281.066529) (xy 101.853109 -281.080689) (xy 101.899088 -281.102506)
			(xy 101.940972 -281.131416) (xy 101.977676 -281.166671) (xy 102.008249 -281.207357) (xy 102.0319 -281.25242)
			(xy 102.048016 -281.300694) (xy 102.05618 -281.350928) (xy 102.056692 -281.376374) (xy 102.05618 -281.40182)
			(xy 102.048016 -281.452054) (xy 102.0319 -281.500328) (xy 102.008249 -281.545391) (xy 101.977676 -281.586077)
			(xy 101.940972 -281.621332) (xy 101.899088 -281.650242) (xy 101.853109 -281.672059) (xy 101.804225 -281.686219)
			(xy 101.753704 -281.692353) (xy 101.702852 -281.690304) (xy 101.652988 -281.680124) (xy 101.605402 -281.662077)
			(xy 101.561328 -281.636631) (xy 101.521906 -281.604444) (xy 101.488158 -281.56635) (xy 101.460957 -281.523336)
			(xy 101.441009 -281.476516) (xy 101.42883 -281.427102) (xy 101.424735 -281.376374) (xy 101.116892 -281.376374)
			(xy 101.11638 -281.40182) (xy 101.108216 -281.452054) (xy 101.0921 -281.500328) (xy 101.068449 -281.545391)
			(xy 101.037876 -281.586077) (xy 101.001172 -281.621332) (xy 100.959288 -281.650242) (xy 100.913309 -281.672059)
			(xy 100.864425 -281.686219) (xy 100.813904 -281.692353) (xy 100.763052 -281.690304) (xy 100.713188 -281.680124)
			(xy 100.665602 -281.662077) (xy 100.621528 -281.636631) (xy 100.582106 -281.604444) (xy 100.548358 -281.56635)
			(xy 100.521157 -281.523336) (xy 100.501209 -281.476516) (xy 100.48903 -281.427102) (xy 100.484935 -281.376374)
			(xy 100.166424 -281.376374) (xy 100.165929 -281.400981) (xy 100.158034 -281.449558) (xy 100.14245 -281.496239)
			(xy 100.119579 -281.539816) (xy 100.090014 -281.57916) (xy 100.054521 -281.613252) (xy 100.014018 -281.641208)
			(xy 99.969556 -281.662306) (xy 99.922285 -281.675998) (xy 99.87343 -281.68193) (xy 99.824255 -281.679949)
			(xy 99.776036 -281.670105) (xy 99.73002 -281.652653) (xy 99.687399 -281.628046) (xy 99.649278 -281.596921)
			(xy 99.616643 -281.560084) (xy 99.59034 -281.518488) (xy 99.571049 -281.473212) (xy 99.559272 -281.425428)
			(xy 99.555312 -281.376374) (xy 99.236784 -281.376374) (xy 99.236272 -281.40182) (xy 99.228108 -281.452054)
			(xy 99.211992 -281.500328) (xy 99.188341 -281.545391) (xy 99.157768 -281.586077) (xy 99.121064 -281.621332)
			(xy 99.07918 -281.650242) (xy 99.033201 -281.672059) (xy 98.984317 -281.686219) (xy 98.933796 -281.692353)
			(xy 98.882944 -281.690304) (xy 98.83308 -281.680124) (xy 98.785494 -281.662077) (xy 98.74142 -281.636631)
			(xy 98.701998 -281.604444) (xy 98.66825 -281.56635) (xy 98.641049 -281.523336) (xy 98.621101 -281.476516)
			(xy 98.608922 -281.427102) (xy 98.604827 -281.376374) (xy 98.29673 -281.376374) (xy 98.296218 -281.40182)
			(xy 98.288054 -281.452054) (xy 98.271938 -281.500328) (xy 98.248287 -281.545391) (xy 98.217714 -281.586077)
			(xy 98.18101 -281.621332) (xy 98.139126 -281.650242) (xy 98.093147 -281.672059) (xy 98.044263 -281.686219)
			(xy 97.993742 -281.692353) (xy 97.94289 -281.690304) (xy 97.893026 -281.680124) (xy 97.84544 -281.662077)
			(xy 97.801366 -281.636631) (xy 97.761944 -281.604444) (xy 97.728196 -281.56635) (xy 97.700995 -281.523336)
			(xy 97.681047 -281.476516) (xy 97.668868 -281.427102) (xy 97.664773 -281.376374) (xy 97.346262 -281.376374)
			(xy 97.345767 -281.400981) (xy 97.337872 -281.449558) (xy 97.322288 -281.496239) (xy 97.299417 -281.539816)
			(xy 97.269852 -281.57916) (xy 97.234359 -281.613252) (xy 97.193856 -281.641208) (xy 97.149394 -281.662306)
			(xy 97.102123 -281.675998) (xy 97.053268 -281.68193) (xy 97.004093 -281.679949) (xy 96.955874 -281.670105)
			(xy 96.909858 -281.652653) (xy 96.867237 -281.628046) (xy 96.829116 -281.596921) (xy 96.796481 -281.560084)
			(xy 96.770178 -281.518488) (xy 96.750887 -281.473212) (xy 96.73911 -281.425428) (xy 96.73515 -281.376374)
			(xy 96.416876 -281.376374) (xy 96.416364 -281.40182) (xy 96.4082 -281.452054) (xy 96.392084 -281.500328)
			(xy 96.368433 -281.545391) (xy 96.33786 -281.586077) (xy 96.301156 -281.621332) (xy 96.259272 -281.650242)
			(xy 96.213293 -281.672059) (xy 96.164409 -281.686219) (xy 96.113888 -281.692353) (xy 96.063036 -281.690304)
			(xy 96.013172 -281.680124) (xy 95.965586 -281.662077) (xy 95.921512 -281.636631) (xy 95.88209 -281.604444)
			(xy 95.848342 -281.56635) (xy 95.821141 -281.523336) (xy 95.801193 -281.476516) (xy 95.789014 -281.427102)
			(xy 95.784919 -281.376374) (xy 95.466408 -281.376374) (xy 95.465913 -281.400981) (xy 95.458018 -281.449558)
			(xy 95.442434 -281.496239) (xy 95.419563 -281.539816) (xy 95.389998 -281.57916) (xy 95.354505 -281.613252)
			(xy 95.314002 -281.641208) (xy 95.26954 -281.662306) (xy 95.222269 -281.675998) (xy 95.173414 -281.68193)
			(xy 95.124239 -281.679949) (xy 95.07602 -281.670105) (xy 95.030004 -281.652653) (xy 94.987383 -281.628046)
			(xy 94.949262 -281.596921) (xy 94.916627 -281.560084) (xy 94.890324 -281.518488) (xy 94.871033 -281.473212)
			(xy 94.859256 -281.425428) (xy 94.855296 -281.376374) (xy 94.536768 -281.376374) (xy 94.536256 -281.40182)
			(xy 94.528092 -281.452054) (xy 94.511976 -281.500328) (xy 94.488325 -281.545391) (xy 94.457752 -281.586077)
			(xy 94.421048 -281.621332) (xy 94.379164 -281.650242) (xy 94.333185 -281.672059) (xy 94.284301 -281.686219)
			(xy 94.23378 -281.692353) (xy 94.182928 -281.690304) (xy 94.133064 -281.680124) (xy 94.085478 -281.662077)
			(xy 94.041404 -281.636631) (xy 94.001982 -281.604444) (xy 93.968234 -281.56635) (xy 93.941033 -281.523336)
			(xy 93.921085 -281.476516) (xy 93.908906 -281.427102) (xy 93.904811 -281.376374) (xy 93.5863 -281.376374)
			(xy 93.585805 -281.400981) (xy 93.57791 -281.449558) (xy 93.562326 -281.496239) (xy 93.539455 -281.539816)
			(xy 93.50989 -281.57916) (xy 93.474397 -281.613252) (xy 93.433894 -281.641208) (xy 93.389432 -281.662306)
			(xy 93.342161 -281.675998) (xy 93.293306 -281.68193) (xy 93.244131 -281.679949) (xy 93.195912 -281.670105)
			(xy 93.149896 -281.652653) (xy 93.107275 -281.628046) (xy 93.069154 -281.596921) (xy 93.036519 -281.560084)
			(xy 93.010216 -281.518488) (xy 92.990925 -281.473212) (xy 92.979148 -281.425428) (xy 92.975188 -281.376374)
			(xy 92.65666 -281.376374) (xy 92.656148 -281.40182) (xy 92.647984 -281.452054) (xy 92.631868 -281.500328)
			(xy 92.608217 -281.545391) (xy 92.577644 -281.586077) (xy 92.54094 -281.621332) (xy 92.499056 -281.650242)
			(xy 92.453077 -281.672059) (xy 92.404193 -281.686219) (xy 92.353672 -281.692353) (xy 92.30282 -281.690304)
			(xy 92.252956 -281.680124) (xy 92.20537 -281.662077) (xy 92.161296 -281.636631) (xy 92.121874 -281.604444)
			(xy 92.088126 -281.56635) (xy 92.060925 -281.523336) (xy 92.040977 -281.476516) (xy 92.028798 -281.427102)
			(xy 92.024703 -281.376374) (xy 91.71686 -281.376374) (xy 91.716348 -281.40182) (xy 91.708184 -281.452054)
			(xy 91.692068 -281.500328) (xy 91.668417 -281.545391) (xy 91.637844 -281.586077) (xy 91.60114 -281.621332)
			(xy 91.559256 -281.650242) (xy 91.513277 -281.672059) (xy 91.464393 -281.686219) (xy 91.413872 -281.692353)
			(xy 91.36302 -281.690304) (xy 91.313156 -281.680124) (xy 91.26557 -281.662077) (xy 91.221496 -281.636631)
			(xy 91.182074 -281.604444) (xy 91.148326 -281.56635) (xy 91.121125 -281.523336) (xy 91.101177 -281.476516)
			(xy 91.088998 -281.427102) (xy 91.084903 -281.376374) (xy 90.766392 -281.376374) (xy 90.765897 -281.400981)
			(xy 90.758002 -281.449558) (xy 90.742418 -281.496239) (xy 90.719547 -281.539816) (xy 90.689982 -281.57916)
			(xy 90.654489 -281.613252) (xy 90.613986 -281.641208) (xy 90.569524 -281.662306) (xy 90.522253 -281.675998)
			(xy 90.473398 -281.68193) (xy 90.424223 -281.679949) (xy 90.376004 -281.670105) (xy 90.329988 -281.652653)
			(xy 90.287367 -281.628046) (xy 90.249246 -281.596921) (xy 90.216611 -281.560084) (xy 90.190308 -281.518488)
			(xy 90.171017 -281.473212) (xy 90.15924 -281.425428) (xy 90.15528 -281.376374) (xy 89.836752 -281.376374)
			(xy 89.83624 -281.40182) (xy 89.828076 -281.452054) (xy 89.81196 -281.500328) (xy 89.788309 -281.545391)
			(xy 89.757736 -281.586077) (xy 89.721032 -281.621332) (xy 89.679148 -281.650242) (xy 89.633169 -281.672059)
			(xy 89.584285 -281.686219) (xy 89.533764 -281.692353) (xy 89.482912 -281.690304) (xy 89.433048 -281.680124)
			(xy 89.385462 -281.662077) (xy 89.341388 -281.636631) (xy 89.301966 -281.604444) (xy 89.268218 -281.56635)
			(xy 89.241017 -281.523336) (xy 89.221069 -281.476516) (xy 89.20889 -281.427102) (xy 89.204795 -281.376374)
			(xy 88.886284 -281.376374) (xy 88.885789 -281.400981) (xy 88.877894 -281.449558) (xy 88.86231 -281.496239)
			(xy 88.839439 -281.539816) (xy 88.809874 -281.57916) (xy 88.774381 -281.613252) (xy 88.733878 -281.641208)
			(xy 88.689416 -281.662306) (xy 88.642145 -281.675998) (xy 88.59329 -281.68193) (xy 88.544115 -281.679949)
			(xy 88.495896 -281.670105) (xy 88.44988 -281.652653) (xy 88.407259 -281.628046) (xy 88.369138 -281.596921)
			(xy 88.336503 -281.560084) (xy 88.3102 -281.518488) (xy 88.290909 -281.473212) (xy 88.279132 -281.425428)
			(xy 88.275172 -281.376374) (xy 87.956644 -281.376374) (xy 87.956132 -281.40182) (xy 87.947968 -281.452054)
			(xy 87.931852 -281.500328) (xy 87.908201 -281.545391) (xy 87.877628 -281.586077) (xy 87.840924 -281.621332)
			(xy 87.79904 -281.650242) (xy 87.753061 -281.672059) (xy 87.704177 -281.686219) (xy 87.653656 -281.692353)
			(xy 87.602804 -281.690304) (xy 87.55294 -281.680124) (xy 87.505354 -281.662077) (xy 87.46128 -281.636631)
			(xy 87.421858 -281.604444) (xy 87.38811 -281.56635) (xy 87.360909 -281.523336) (xy 87.340961 -281.476516)
			(xy 87.328782 -281.427102) (xy 87.324687 -281.376374) (xy 87.00643 -281.376374) (xy 87.005935 -281.400981)
			(xy 86.99804 -281.449558) (xy 86.982456 -281.496239) (xy 86.959585 -281.539816) (xy 86.93002 -281.57916)
			(xy 86.894527 -281.613252) (xy 86.854024 -281.641208) (xy 86.809562 -281.662306) (xy 86.762291 -281.675998)
			(xy 86.713436 -281.68193) (xy 86.664261 -281.679949) (xy 86.616042 -281.670105) (xy 86.570026 -281.652653)
			(xy 86.527405 -281.628046) (xy 86.489284 -281.596921) (xy 86.456649 -281.560084) (xy 86.430346 -281.518488)
			(xy 86.411055 -281.473212) (xy 86.399278 -281.425428) (xy 86.395318 -281.376374) (xy 86.07679 -281.376374)
			(xy 86.076278 -281.40182) (xy 86.068114 -281.452054) (xy 86.051998 -281.500328) (xy 86.028347 -281.545391)
			(xy 85.997774 -281.586077) (xy 85.96107 -281.621332) (xy 85.919186 -281.650242) (xy 85.873207 -281.672059)
			(xy 85.824323 -281.686219) (xy 85.773802 -281.692353) (xy 85.72295 -281.690304) (xy 85.673086 -281.680124)
			(xy 85.6255 -281.662077) (xy 85.581426 -281.636631) (xy 85.542004 -281.604444) (xy 85.508256 -281.56635)
			(xy 85.481055 -281.523336) (xy 85.461107 -281.476516) (xy 85.448928 -281.427102) (xy 85.444833 -281.376374)
			(xy 85.136736 -281.376374) (xy 85.136224 -281.40182) (xy 85.12806 -281.452054) (xy 85.111944 -281.500328)
			(xy 85.088293 -281.545391) (xy 85.05772 -281.586077) (xy 85.021016 -281.621332) (xy 84.979132 -281.650242)
			(xy 84.933153 -281.672059) (xy 84.884269 -281.686219) (xy 84.833748 -281.692353) (xy 84.782896 -281.690304)
			(xy 84.733032 -281.680124) (xy 84.685446 -281.662077) (xy 84.641372 -281.636631) (xy 84.60195 -281.604444)
			(xy 84.568202 -281.56635) (xy 84.541001 -281.523336) (xy 84.521053 -281.476516) (xy 84.508874 -281.427102)
			(xy 84.504779 -281.376374) (xy 84.186268 -281.376374) (xy 84.185773 -281.400981) (xy 84.177878 -281.449558)
			(xy 84.162294 -281.496239) (xy 84.139423 -281.539816) (xy 84.109858 -281.57916) (xy 84.074365 -281.613252)
			(xy 84.033862 -281.641208) (xy 83.9894 -281.662306) (xy 83.942129 -281.675998) (xy 83.893274 -281.68193)
			(xy 83.844099 -281.679949) (xy 83.79588 -281.670105) (xy 83.749864 -281.652653) (xy 83.707243 -281.628046)
			(xy 83.669122 -281.596921) (xy 83.636487 -281.560084) (xy 83.610184 -281.518488) (xy 83.590893 -281.473212)
			(xy 83.579116 -281.425428) (xy 83.575156 -281.376374) (xy 83.256628 -281.376374) (xy 83.256116 -281.40182)
			(xy 83.247952 -281.452054) (xy 83.231836 -281.500328) (xy 83.208185 -281.545391) (xy 83.177612 -281.586077)
			(xy 83.140908 -281.621332) (xy 83.099024 -281.650242) (xy 83.053045 -281.672059) (xy 83.004161 -281.686219)
			(xy 82.95364 -281.692353) (xy 82.902788 -281.690304) (xy 82.852924 -281.680124) (xy 82.805338 -281.662077)
			(xy 82.761264 -281.636631) (xy 82.721842 -281.604444) (xy 82.688094 -281.56635) (xy 82.660893 -281.523336)
			(xy 82.640945 -281.476516) (xy 82.628766 -281.427102) (xy 82.624671 -281.376374) (xy 82.306414 -281.376374)
			(xy 82.305919 -281.400981) (xy 82.298024 -281.449558) (xy 82.28244 -281.496239) (xy 82.259569 -281.539816)
			(xy 82.230004 -281.57916) (xy 82.194511 -281.613252) (xy 82.154008 -281.641208) (xy 82.109546 -281.662306)
			(xy 82.062275 -281.675998) (xy 82.01342 -281.68193) (xy 81.964245 -281.679949) (xy 81.916026 -281.670105)
			(xy 81.87001 -281.652653) (xy 81.827389 -281.628046) (xy 81.789268 -281.596921) (xy 81.756633 -281.560084)
			(xy 81.73033 -281.518488) (xy 81.711039 -281.473212) (xy 81.699262 -281.425428) (xy 81.695302 -281.376374)
			(xy 81.376774 -281.376374) (xy 81.376262 -281.40182) (xy 81.368098 -281.452054) (xy 81.351982 -281.500328)
			(xy 81.328331 -281.545391) (xy 81.297758 -281.586077) (xy 81.261054 -281.621332) (xy 81.21917 -281.650242)
			(xy 81.173191 -281.672059) (xy 81.124307 -281.686219) (xy 81.073786 -281.692353) (xy 81.022934 -281.690304)
			(xy 80.97307 -281.680124) (xy 80.925484 -281.662077) (xy 80.88141 -281.636631) (xy 80.841988 -281.604444)
			(xy 80.80824 -281.56635) (xy 80.781039 -281.523336) (xy 80.761091 -281.476516) (xy 80.748912 -281.427102)
			(xy 80.744817 -281.376374) (xy 80.426306 -281.376374) (xy 80.425811 -281.400981) (xy 80.417916 -281.449558)
			(xy 80.402332 -281.496239) (xy 80.379461 -281.539816) (xy 80.349896 -281.57916) (xy 80.314403 -281.613252)
			(xy 80.2739 -281.641208) (xy 80.229438 -281.662306) (xy 80.182167 -281.675998) (xy 80.133312 -281.68193)
			(xy 80.084137 -281.679949) (xy 80.035918 -281.670105) (xy 79.989902 -281.652653) (xy 79.947281 -281.628046)
			(xy 79.90916 -281.596921) (xy 79.876525 -281.560084) (xy 79.850222 -281.518488) (xy 79.830931 -281.473212)
			(xy 79.819154 -281.425428) (xy 79.815194 -281.376374) (xy 77.263451 -281.376374) (xy 77.221316 -281.396368)
			(xy 77.174045 -281.41006) (xy 77.12519 -281.415992) (xy 77.076015 -281.414011) (xy 77.027796 -281.404167)
			(xy 76.98178 -281.386715) (xy 76.939159 -281.362108) (xy 76.901038 -281.330983) (xy 76.868403 -281.294146)
			(xy 76.8421 -281.25255) (xy 76.822809 -281.207274) (xy 76.811032 -281.15949) (xy 76.807072 -281.110436)
			(xy 73.228962 -281.110436) (xy 73.228962 -282.18638) (xy 78.40524 -282.18638) (xy 78.4092 -282.137326)
			(xy 78.420977 -282.089542) (xy 78.440268 -282.044266) (xy 78.466571 -282.00267) (xy 78.499206 -281.965833)
			(xy 78.537327 -281.934708) (xy 78.579948 -281.910101) (xy 78.625964 -281.892649) (xy 78.674183 -281.882805)
			(xy 78.723358 -281.880824) (xy 78.772213 -281.886756) (xy 78.819484 -281.900448) (xy 78.863946 -281.921546)
			(xy 78.904449 -281.949502) (xy 78.939942 -281.983594) (xy 78.969507 -282.022938) (xy 78.992378 -282.066515)
			(xy 79.007962 -282.113196) (xy 79.015857 -282.161773) (xy 79.016352 -282.18638) (xy 80.285348 -282.18638)
			(xy 80.289308 -282.137326) (xy 80.301085 -282.089542) (xy 80.320376 -282.044266) (xy 80.346679 -282.00267)
			(xy 80.379314 -281.965833) (xy 80.417435 -281.934708) (xy 80.460056 -281.910101) (xy 80.506072 -281.892649)
			(xy 80.554291 -281.882805) (xy 80.603466 -281.880824) (xy 80.652321 -281.886756) (xy 80.699592 -281.900448)
			(xy 80.744054 -281.921546) (xy 80.784557 -281.949502) (xy 80.82005 -281.983594) (xy 80.849615 -282.022938)
			(xy 80.872486 -282.066515) (xy 80.88807 -282.113196) (xy 80.895965 -282.161773) (xy 80.89646 -282.18638)
			(xy 81.214717 -282.18638) (xy 81.218812 -282.135652) (xy 81.230991 -282.086238) (xy 81.250939 -282.039418)
			(xy 81.27814 -281.996404) (xy 81.311888 -281.95831) (xy 81.35131 -281.926123) (xy 81.395384 -281.900677)
			(xy 81.44297 -281.88263) (xy 81.492834 -281.87245) (xy 81.543686 -281.870401) (xy 81.594207 -281.876535)
			(xy 81.643091 -281.890695) (xy 81.68907 -281.912512) (xy 81.730954 -281.941422) (xy 81.767658 -281.976677)
			(xy 81.798231 -282.017363) (xy 81.821882 -282.062426) (xy 81.837998 -282.1107) (xy 81.846162 -282.160934)
			(xy 81.846674 -282.18638) (xy 82.154771 -282.18638) (xy 82.158866 -282.135652) (xy 82.171045 -282.086238)
			(xy 82.190993 -282.039418) (xy 82.218194 -281.996404) (xy 82.251942 -281.95831) (xy 82.291364 -281.926123)
			(xy 82.335438 -281.900677) (xy 82.383024 -281.88263) (xy 82.432888 -281.87245) (xy 82.48374 -281.870401)
			(xy 82.534261 -281.876535) (xy 82.583145 -281.890695) (xy 82.629124 -281.912512) (xy 82.671008 -281.941422)
			(xy 82.707712 -281.976677) (xy 82.738285 -282.017363) (xy 82.761936 -282.062426) (xy 82.778052 -282.1107)
			(xy 82.786216 -282.160934) (xy 82.786728 -282.18638) (xy 83.105256 -282.18638) (xy 83.109216 -282.137326)
			(xy 83.120993 -282.089542) (xy 83.140284 -282.044266) (xy 83.166587 -282.00267) (xy 83.199222 -281.965833)
			(xy 83.237343 -281.934708) (xy 83.279964 -281.910101) (xy 83.32598 -281.892649) (xy 83.374199 -281.882805)
			(xy 83.423374 -281.880824) (xy 83.472229 -281.886756) (xy 83.5195 -281.900448) (xy 83.563962 -281.921546)
			(xy 83.604465 -281.949502) (xy 83.639958 -281.983594) (xy 83.669523 -282.022938) (xy 83.692394 -282.066515)
			(xy 83.707978 -282.113196) (xy 83.715873 -282.161773) (xy 83.716368 -282.18638) (xy 84.034879 -282.18638)
			(xy 84.038974 -282.135652) (xy 84.051153 -282.086238) (xy 84.071101 -282.039418) (xy 84.098302 -281.996404)
			(xy 84.13205 -281.95831) (xy 84.171472 -281.926123) (xy 84.215546 -281.900677) (xy 84.263132 -281.88263)
			(xy 84.312996 -281.87245) (xy 84.363848 -281.870401) (xy 84.414369 -281.876535) (xy 84.463253 -281.890695)
			(xy 84.509232 -281.912512) (xy 84.551116 -281.941422) (xy 84.58782 -281.976677) (xy 84.618393 -282.017363)
			(xy 84.642044 -282.062426) (xy 84.65816 -282.1107) (xy 84.666324 -282.160934) (xy 84.666836 -282.18638)
			(xy 84.98511 -282.18638) (xy 84.98907 -282.137326) (xy 85.000847 -282.089542) (xy 85.020138 -282.044266)
			(xy 85.046441 -282.00267) (xy 85.079076 -281.965833) (xy 85.117197 -281.934708) (xy 85.159818 -281.910101)
			(xy 85.205834 -281.892649) (xy 85.254053 -281.882805) (xy 85.303228 -281.880824) (xy 85.352083 -281.886756)
			(xy 85.399354 -281.900448) (xy 85.443816 -281.921546) (xy 85.484319 -281.949502) (xy 85.519812 -281.983594)
			(xy 85.549377 -282.022938) (xy 85.572248 -282.066515) (xy 85.587832 -282.113196) (xy 85.595727 -282.161773)
			(xy 85.596222 -282.18638) (xy 85.914733 -282.18638) (xy 85.918828 -282.135652) (xy 85.931007 -282.086238)
			(xy 85.950955 -282.039418) (xy 85.978156 -281.996404) (xy 86.011904 -281.95831) (xy 86.051326 -281.926123)
			(xy 86.0954 -281.900677) (xy 86.142986 -281.88263) (xy 86.19285 -281.87245) (xy 86.243702 -281.870401)
			(xy 86.294223 -281.876535) (xy 86.343107 -281.890695) (xy 86.389086 -281.912512) (xy 86.43097 -281.941422)
			(xy 86.467674 -281.976677) (xy 86.498247 -282.017363) (xy 86.521898 -282.062426) (xy 86.538014 -282.1107)
			(xy 86.546178 -282.160934) (xy 86.54669 -282.18638) (xy 86.865218 -282.18638) (xy 86.869178 -282.137326)
			(xy 86.880955 -282.089542) (xy 86.900246 -282.044266) (xy 86.926549 -282.00267) (xy 86.959184 -281.965833)
			(xy 86.997305 -281.934708) (xy 87.039926 -281.910101) (xy 87.085942 -281.892649) (xy 87.134161 -281.882805)
			(xy 87.183336 -281.880824) (xy 87.232191 -281.886756) (xy 87.279462 -281.900448) (xy 87.323924 -281.921546)
			(xy 87.364427 -281.949502) (xy 87.39992 -281.983594) (xy 87.429485 -282.022938) (xy 87.452356 -282.066515)
			(xy 87.46794 -282.113196) (xy 87.475835 -282.161773) (xy 87.47633 -282.18638) (xy 87.794841 -282.18638)
			(xy 87.798936 -282.135652) (xy 87.811115 -282.086238) (xy 87.831063 -282.039418) (xy 87.858264 -281.996404)
			(xy 87.892012 -281.95831) (xy 87.931434 -281.926123) (xy 87.975508 -281.900677) (xy 88.023094 -281.88263)
			(xy 88.072958 -281.87245) (xy 88.12381 -281.870401) (xy 88.174331 -281.876535) (xy 88.223215 -281.890695)
			(xy 88.269194 -281.912512) (xy 88.311078 -281.941422) (xy 88.347782 -281.976677) (xy 88.378355 -282.017363)
			(xy 88.402006 -282.062426) (xy 88.418122 -282.1107) (xy 88.426286 -282.160934) (xy 88.426798 -282.18638)
			(xy 88.734895 -282.18638) (xy 88.73899 -282.135652) (xy 88.751169 -282.086238) (xy 88.771117 -282.039418)
			(xy 88.798318 -281.996404) (xy 88.832066 -281.95831) (xy 88.871488 -281.926123) (xy 88.915562 -281.900677)
			(xy 88.963148 -281.88263) (xy 89.013012 -281.87245) (xy 89.063864 -281.870401) (xy 89.114385 -281.876535)
			(xy 89.163269 -281.890695) (xy 89.209248 -281.912512) (xy 89.251132 -281.941422) (xy 89.287836 -281.976677)
			(xy 89.318409 -282.017363) (xy 89.34206 -282.062426) (xy 89.358176 -282.1107) (xy 89.36634 -282.160934)
			(xy 89.366852 -282.18638) (xy 89.685126 -282.18638) (xy 89.689086 -282.137326) (xy 89.700863 -282.089542)
			(xy 89.720154 -282.044266) (xy 89.746457 -282.00267) (xy 89.779092 -281.965833) (xy 89.817213 -281.934708)
			(xy 89.859834 -281.910101) (xy 89.90585 -281.892649) (xy 89.954069 -281.882805) (xy 90.003244 -281.880824)
			(xy 90.052099 -281.886756) (xy 90.09937 -281.900448) (xy 90.143832 -281.921546) (xy 90.184335 -281.949502)
			(xy 90.219828 -281.983594) (xy 90.249393 -282.022938) (xy 90.272264 -282.066515) (xy 90.287848 -282.113196)
			(xy 90.295743 -282.161773) (xy 90.296238 -282.18638) (xy 90.614749 -282.18638) (xy 90.618844 -282.135652)
			(xy 90.631023 -282.086238) (xy 90.650971 -282.039418) (xy 90.678172 -281.996404) (xy 90.71192 -281.95831)
			(xy 90.751342 -281.926123) (xy 90.795416 -281.900677) (xy 90.843002 -281.88263) (xy 90.892866 -281.87245)
			(xy 90.943718 -281.870401) (xy 90.994239 -281.876535) (xy 91.043123 -281.890695) (xy 91.089102 -281.912512)
			(xy 91.130986 -281.941422) (xy 91.16769 -281.976677) (xy 91.198263 -282.017363) (xy 91.221914 -282.062426)
			(xy 91.23803 -282.1107) (xy 91.246194 -282.160934) (xy 91.246706 -282.18638) (xy 91.565234 -282.18638)
			(xy 91.569194 -282.137326) (xy 91.580971 -282.089542) (xy 91.600262 -282.044266) (xy 91.626565 -282.00267)
			(xy 91.6592 -281.965833) (xy 91.697321 -281.934708) (xy 91.739942 -281.910101) (xy 91.785958 -281.892649)
			(xy 91.834177 -281.882805) (xy 91.883352 -281.880824) (xy 91.932207 -281.886756) (xy 91.979478 -281.900448)
			(xy 92.02394 -281.921546) (xy 92.064443 -281.949502) (xy 92.099936 -281.983594) (xy 92.129501 -282.022938)
			(xy 92.152372 -282.066515) (xy 92.167956 -282.113196) (xy 92.175851 -282.161773) (xy 92.176346 -282.18638)
			(xy 92.494857 -282.18638) (xy 92.498952 -282.135652) (xy 92.511131 -282.086238) (xy 92.531079 -282.039418)
			(xy 92.55828 -281.996404) (xy 92.592028 -281.95831) (xy 92.63145 -281.926123) (xy 92.675524 -281.900677)
			(xy 92.72311 -281.88263) (xy 92.772974 -281.87245) (xy 92.823826 -281.870401) (xy 92.874347 -281.876535)
			(xy 92.923231 -281.890695) (xy 92.96921 -281.912512) (xy 93.011094 -281.941422) (xy 93.047798 -281.976677)
			(xy 93.078371 -282.017363) (xy 93.102022 -282.062426) (xy 93.118138 -282.1107) (xy 93.126302 -282.160934)
			(xy 93.126814 -282.18638) (xy 93.445342 -282.18638) (xy 93.449302 -282.137326) (xy 93.461079 -282.089542)
			(xy 93.48037 -282.044266) (xy 93.506673 -282.00267) (xy 93.539308 -281.965833) (xy 93.577429 -281.934708)
			(xy 93.62005 -281.910101) (xy 93.666066 -281.892649) (xy 93.714285 -281.882805) (xy 93.76346 -281.880824)
			(xy 93.812315 -281.886756) (xy 93.859586 -281.900448) (xy 93.904048 -281.921546) (xy 93.944551 -281.949502)
			(xy 93.980044 -281.983594) (xy 94.009609 -282.022938) (xy 94.03248 -282.066515) (xy 94.048064 -282.113196)
			(xy 94.055959 -282.161773) (xy 94.056454 -282.18638) (xy 94.374711 -282.18638) (xy 94.378806 -282.135652)
			(xy 94.390985 -282.086238) (xy 94.410933 -282.039418) (xy 94.438134 -281.996404) (xy 94.471882 -281.95831)
			(xy 94.511304 -281.926123) (xy 94.555378 -281.900677) (xy 94.602964 -281.88263) (xy 94.652828 -281.87245)
			(xy 94.70368 -281.870401) (xy 94.754201 -281.876535) (xy 94.803085 -281.890695) (xy 94.849064 -281.912512)
			(xy 94.890948 -281.941422) (xy 94.927652 -281.976677) (xy 94.958225 -282.017363) (xy 94.981876 -282.062426)
			(xy 94.997992 -282.1107) (xy 95.006156 -282.160934) (xy 95.006668 -282.18638) (xy 95.314765 -282.18638)
			(xy 95.31886 -282.135652) (xy 95.331039 -282.086238) (xy 95.350987 -282.039418) (xy 95.378188 -281.996404)
			(xy 95.411936 -281.95831) (xy 95.451358 -281.926123) (xy 95.495432 -281.900677) (xy 95.543018 -281.88263)
			(xy 95.592882 -281.87245) (xy 95.643734 -281.870401) (xy 95.694255 -281.876535) (xy 95.743139 -281.890695)
			(xy 95.789118 -281.912512) (xy 95.831002 -281.941422) (xy 95.867706 -281.976677) (xy 95.898279 -282.017363)
			(xy 95.92193 -282.062426) (xy 95.938046 -282.1107) (xy 95.94621 -282.160934) (xy 95.946722 -282.18638)
			(xy 96.26525 -282.18638) (xy 96.26921 -282.137326) (xy 96.280987 -282.089542) (xy 96.300278 -282.044266)
			(xy 96.326581 -282.00267) (xy 96.359216 -281.965833) (xy 96.397337 -281.934708) (xy 96.439958 -281.910101)
			(xy 96.485974 -281.892649) (xy 96.534193 -281.882805) (xy 96.583368 -281.880824) (xy 96.632223 -281.886756)
			(xy 96.679494 -281.900448) (xy 96.723956 -281.921546) (xy 96.764459 -281.949502) (xy 96.799952 -281.983594)
			(xy 96.829517 -282.022938) (xy 96.852388 -282.066515) (xy 96.867972 -282.113196) (xy 96.875867 -282.161773)
			(xy 96.876362 -282.18638) (xy 97.205304 -282.18638) (xy 97.209264 -282.137326) (xy 97.221041 -282.089542)
			(xy 97.240332 -282.044266) (xy 97.266635 -282.00267) (xy 97.29927 -281.965833) (xy 97.337391 -281.934708)
			(xy 97.380012 -281.910101) (xy 97.426028 -281.892649) (xy 97.474247 -281.882805) (xy 97.523422 -281.880824)
			(xy 97.572277 -281.886756) (xy 97.619548 -281.900448) (xy 97.66401 -281.921546) (xy 97.704513 -281.949502)
			(xy 97.740006 -281.983594) (xy 97.769571 -282.022938) (xy 97.792442 -282.066515) (xy 97.808026 -282.113196)
			(xy 97.815921 -282.161773) (xy 97.816416 -282.18638) (xy 98.145358 -282.18638) (xy 98.149318 -282.137326)
			(xy 98.161095 -282.089542) (xy 98.180386 -282.044266) (xy 98.206689 -282.00267) (xy 98.239324 -281.965833)
			(xy 98.277445 -281.934708) (xy 98.320066 -281.910101) (xy 98.366082 -281.892649) (xy 98.414301 -281.882805)
			(xy 98.463476 -281.880824) (xy 98.512331 -281.886756) (xy 98.559602 -281.900448) (xy 98.604064 -281.921546)
			(xy 98.644567 -281.949502) (xy 98.68006 -281.983594) (xy 98.709625 -282.022938) (xy 98.732496 -282.066515)
			(xy 98.74808 -282.113196) (xy 98.755975 -282.161773) (xy 98.75647 -282.18638) (xy 99.085158 -282.18638)
			(xy 99.089118 -282.137326) (xy 99.100895 -282.089542) (xy 99.120186 -282.044266) (xy 99.146489 -282.00267)
			(xy 99.179124 -281.965833) (xy 99.217245 -281.934708) (xy 99.259866 -281.910101) (xy 99.305882 -281.892649)
			(xy 99.354101 -281.882805) (xy 99.403276 -281.880824) (xy 99.452131 -281.886756) (xy 99.499402 -281.900448)
			(xy 99.543864 -281.921546) (xy 99.584367 -281.949502) (xy 99.61986 -281.983594) (xy 99.649425 -282.022938)
			(xy 99.672296 -282.066515) (xy 99.68788 -282.113196) (xy 99.695775 -282.161773) (xy 99.69627 -282.18638)
			(xy 100.025212 -282.18638) (xy 100.029172 -282.137326) (xy 100.040949 -282.089542) (xy 100.06024 -282.044266)
			(xy 100.086543 -282.00267) (xy 100.119178 -281.965833) (xy 100.157299 -281.934708) (xy 100.19992 -281.910101)
			(xy 100.245936 -281.892649) (xy 100.294155 -281.882805) (xy 100.34333 -281.880824) (xy 100.392185 -281.886756)
			(xy 100.439456 -281.900448) (xy 100.483918 -281.921546) (xy 100.524421 -281.949502) (xy 100.559914 -281.983594)
			(xy 100.589479 -282.022938) (xy 100.61235 -282.066515) (xy 100.627934 -282.113196) (xy 100.635829 -282.161773)
			(xy 100.636324 -282.18638) (xy 100.965266 -282.18638) (xy 100.969226 -282.137326) (xy 100.981003 -282.089542)
			(xy 101.000294 -282.044266) (xy 101.026597 -282.00267) (xy 101.059232 -281.965833) (xy 101.097353 -281.934708)
			(xy 101.139974 -281.910101) (xy 101.18599 -281.892649) (xy 101.234209 -281.882805) (xy 101.283384 -281.880824)
			(xy 101.332239 -281.886756) (xy 101.37951 -281.900448) (xy 101.423972 -281.921546) (xy 101.464475 -281.949502)
			(xy 101.499968 -281.983594) (xy 101.529533 -282.022938) (xy 101.552404 -282.066515) (xy 101.567988 -282.113196)
			(xy 101.575883 -282.161773) (xy 101.576378 -282.18638) (xy 101.90532 -282.18638) (xy 101.90928 -282.137326)
			(xy 101.921057 -282.089542) (xy 101.940348 -282.044266) (xy 101.966651 -282.00267) (xy 101.999286 -281.965833)
			(xy 102.037407 -281.934708) (xy 102.080028 -281.910101) (xy 102.126044 -281.892649) (xy 102.174263 -281.882805)
			(xy 102.223438 -281.880824) (xy 102.272293 -281.886756) (xy 102.319564 -281.900448) (xy 102.364026 -281.921546)
			(xy 102.404529 -281.949502) (xy 102.440022 -281.983594) (xy 102.469587 -282.022938) (xy 102.492458 -282.066515)
			(xy 102.508042 -282.113196) (xy 102.515937 -282.161773) (xy 102.516432 -282.18638) (xy 102.515937 -282.210987)
			(xy 102.508042 -282.259564) (xy 102.492458 -282.306245) (xy 102.469587 -282.349822) (xy 102.440022 -282.389166)
			(xy 102.404529 -282.423258) (xy 102.364026 -282.451214) (xy 102.319564 -282.472312) (xy 102.272293 -282.486004)
			(xy 102.223438 -282.491936) (xy 102.174263 -282.489955) (xy 102.126044 -282.480111) (xy 102.080028 -282.462659)
			(xy 102.037407 -282.438052) (xy 101.999286 -282.406927) (xy 101.966651 -282.37009) (xy 101.940348 -282.328494)
			(xy 101.921057 -282.283218) (xy 101.90928 -282.235434) (xy 101.90532 -282.18638) (xy 101.576378 -282.18638)
			(xy 101.575883 -282.210987) (xy 101.567988 -282.259564) (xy 101.552404 -282.306245) (xy 101.529533 -282.349822)
			(xy 101.499968 -282.389166) (xy 101.464475 -282.423258) (xy 101.423972 -282.451214) (xy 101.37951 -282.472312)
			(xy 101.332239 -282.486004) (xy 101.283384 -282.491936) (xy 101.234209 -282.489955) (xy 101.18599 -282.480111)
			(xy 101.139974 -282.462659) (xy 101.097353 -282.438052) (xy 101.059232 -282.406927) (xy 101.026597 -282.37009)
			(xy 101.000294 -282.328494) (xy 100.981003 -282.283218) (xy 100.969226 -282.235434) (xy 100.965266 -282.18638)
			(xy 100.636324 -282.18638) (xy 100.635829 -282.210987) (xy 100.627934 -282.259564) (xy 100.61235 -282.306245)
			(xy 100.589479 -282.349822) (xy 100.559914 -282.389166) (xy 100.524421 -282.423258) (xy 100.483918 -282.451214)
			(xy 100.439456 -282.472312) (xy 100.392185 -282.486004) (xy 100.34333 -282.491936) (xy 100.294155 -282.489955)
			(xy 100.245936 -282.480111) (xy 100.19992 -282.462659) (xy 100.157299 -282.438052) (xy 100.119178 -282.406927)
			(xy 100.086543 -282.37009) (xy 100.06024 -282.328494) (xy 100.040949 -282.283218) (xy 100.029172 -282.235434)
			(xy 100.025212 -282.18638) (xy 99.69627 -282.18638) (xy 99.695775 -282.210987) (xy 99.68788 -282.259564)
			(xy 99.672296 -282.306245) (xy 99.649425 -282.349822) (xy 99.61986 -282.389166) (xy 99.584367 -282.423258)
			(xy 99.543864 -282.451214) (xy 99.499402 -282.472312) (xy 99.452131 -282.486004) (xy 99.403276 -282.491936)
			(xy 99.354101 -282.489955) (xy 99.305882 -282.480111) (xy 99.259866 -282.462659) (xy 99.217245 -282.438052)
			(xy 99.179124 -282.406927) (xy 99.146489 -282.37009) (xy 99.120186 -282.328494) (xy 99.100895 -282.283218)
			(xy 99.089118 -282.235434) (xy 99.085158 -282.18638) (xy 98.75647 -282.18638) (xy 98.755975 -282.210987)
			(xy 98.74808 -282.259564) (xy 98.732496 -282.306245) (xy 98.709625 -282.349822) (xy 98.68006 -282.389166)
			(xy 98.644567 -282.423258) (xy 98.604064 -282.451214) (xy 98.559602 -282.472312) (xy 98.512331 -282.486004)
			(xy 98.463476 -282.491936) (xy 98.414301 -282.489955) (xy 98.366082 -282.480111) (xy 98.320066 -282.462659)
			(xy 98.277445 -282.438052) (xy 98.239324 -282.406927) (xy 98.206689 -282.37009) (xy 98.180386 -282.328494)
			(xy 98.161095 -282.283218) (xy 98.149318 -282.235434) (xy 98.145358 -282.18638) (xy 97.816416 -282.18638)
			(xy 97.815921 -282.210987) (xy 97.808026 -282.259564) (xy 97.792442 -282.306245) (xy 97.769571 -282.349822)
			(xy 97.740006 -282.389166) (xy 97.704513 -282.423258) (xy 97.66401 -282.451214) (xy 97.619548 -282.472312)
			(xy 97.572277 -282.486004) (xy 97.523422 -282.491936) (xy 97.474247 -282.489955) (xy 97.426028 -282.480111)
			(xy 97.380012 -282.462659) (xy 97.337391 -282.438052) (xy 97.29927 -282.406927) (xy 97.266635 -282.37009)
			(xy 97.240332 -282.328494) (xy 97.221041 -282.283218) (xy 97.209264 -282.235434) (xy 97.205304 -282.18638)
			(xy 96.876362 -282.18638) (xy 96.875867 -282.210987) (xy 96.867972 -282.259564) (xy 96.852388 -282.306245)
			(xy 96.829517 -282.349822) (xy 96.799952 -282.389166) (xy 96.764459 -282.423258) (xy 96.723956 -282.451214)
			(xy 96.679494 -282.472312) (xy 96.632223 -282.486004) (xy 96.583368 -282.491936) (xy 96.534193 -282.489955)
			(xy 96.485974 -282.480111) (xy 96.439958 -282.462659) (xy 96.397337 -282.438052) (xy 96.359216 -282.406927)
			(xy 96.326581 -282.37009) (xy 96.300278 -282.328494) (xy 96.280987 -282.283218) (xy 96.26921 -282.235434)
			(xy 96.26525 -282.18638) (xy 95.946722 -282.18638) (xy 95.94621 -282.211826) (xy 95.938046 -282.26206)
			(xy 95.92193 -282.310334) (xy 95.898279 -282.355397) (xy 95.867706 -282.396083) (xy 95.831002 -282.431338)
			(xy 95.789118 -282.460248) (xy 95.743139 -282.482065) (xy 95.694255 -282.496225) (xy 95.643734 -282.502359)
			(xy 95.592882 -282.50031) (xy 95.543018 -282.49013) (xy 95.495432 -282.472083) (xy 95.451358 -282.446637)
			(xy 95.411936 -282.41445) (xy 95.378188 -282.376356) (xy 95.350987 -282.333342) (xy 95.331039 -282.286522)
			(xy 95.31886 -282.237108) (xy 95.314765 -282.18638) (xy 95.006668 -282.18638) (xy 95.006156 -282.211826)
			(xy 94.997992 -282.26206) (xy 94.981876 -282.310334) (xy 94.958225 -282.355397) (xy 94.927652 -282.396083)
			(xy 94.890948 -282.431338) (xy 94.849064 -282.460248) (xy 94.803085 -282.482065) (xy 94.754201 -282.496225)
			(xy 94.70368 -282.502359) (xy 94.652828 -282.50031) (xy 94.602964 -282.49013) (xy 94.555378 -282.472083)
			(xy 94.511304 -282.446637) (xy 94.471882 -282.41445) (xy 94.438134 -282.376356) (xy 94.410933 -282.333342)
			(xy 94.390985 -282.286522) (xy 94.378806 -282.237108) (xy 94.374711 -282.18638) (xy 94.056454 -282.18638)
			(xy 94.055959 -282.210987) (xy 94.048064 -282.259564) (xy 94.03248 -282.306245) (xy 94.009609 -282.349822)
			(xy 93.980044 -282.389166) (xy 93.944551 -282.423258) (xy 93.904048 -282.451214) (xy 93.859586 -282.472312)
			(xy 93.812315 -282.486004) (xy 93.76346 -282.491936) (xy 93.714285 -282.489955) (xy 93.666066 -282.480111)
			(xy 93.62005 -282.462659) (xy 93.577429 -282.438052) (xy 93.539308 -282.406927) (xy 93.506673 -282.37009)
			(xy 93.48037 -282.328494) (xy 93.461079 -282.283218) (xy 93.449302 -282.235434) (xy 93.445342 -282.18638)
			(xy 93.126814 -282.18638) (xy 93.126302 -282.211826) (xy 93.118138 -282.26206) (xy 93.102022 -282.310334)
			(xy 93.078371 -282.355397) (xy 93.047798 -282.396083) (xy 93.011094 -282.431338) (xy 92.96921 -282.460248)
			(xy 92.923231 -282.482065) (xy 92.874347 -282.496225) (xy 92.823826 -282.502359) (xy 92.772974 -282.50031)
			(xy 92.72311 -282.49013) (xy 92.675524 -282.472083) (xy 92.63145 -282.446637) (xy 92.592028 -282.41445)
			(xy 92.55828 -282.376356) (xy 92.531079 -282.333342) (xy 92.511131 -282.286522) (xy 92.498952 -282.237108)
			(xy 92.494857 -282.18638) (xy 92.176346 -282.18638) (xy 92.175851 -282.210987) (xy 92.167956 -282.259564)
			(xy 92.152372 -282.306245) (xy 92.129501 -282.349822) (xy 92.099936 -282.389166) (xy 92.064443 -282.423258)
			(xy 92.02394 -282.451214) (xy 91.979478 -282.472312) (xy 91.932207 -282.486004) (xy 91.883352 -282.491936)
			(xy 91.834177 -282.489955) (xy 91.785958 -282.480111) (xy 91.739942 -282.462659) (xy 91.697321 -282.438052)
			(xy 91.6592 -282.406927) (xy 91.626565 -282.37009) (xy 91.600262 -282.328494) (xy 91.580971 -282.283218)
			(xy 91.569194 -282.235434) (xy 91.565234 -282.18638) (xy 91.246706 -282.18638) (xy 91.246194 -282.211826)
			(xy 91.23803 -282.26206) (xy 91.221914 -282.310334) (xy 91.198263 -282.355397) (xy 91.16769 -282.396083)
			(xy 91.130986 -282.431338) (xy 91.089102 -282.460248) (xy 91.043123 -282.482065) (xy 90.994239 -282.496225)
			(xy 90.943718 -282.502359) (xy 90.892866 -282.50031) (xy 90.843002 -282.49013) (xy 90.795416 -282.472083)
			(xy 90.751342 -282.446637) (xy 90.71192 -282.41445) (xy 90.678172 -282.376356) (xy 90.650971 -282.333342)
			(xy 90.631023 -282.286522) (xy 90.618844 -282.237108) (xy 90.614749 -282.18638) (xy 90.296238 -282.18638)
			(xy 90.295743 -282.210987) (xy 90.287848 -282.259564) (xy 90.272264 -282.306245) (xy 90.249393 -282.349822)
			(xy 90.219828 -282.389166) (xy 90.184335 -282.423258) (xy 90.143832 -282.451214) (xy 90.09937 -282.472312)
			(xy 90.052099 -282.486004) (xy 90.003244 -282.491936) (xy 89.954069 -282.489955) (xy 89.90585 -282.480111)
			(xy 89.859834 -282.462659) (xy 89.817213 -282.438052) (xy 89.779092 -282.406927) (xy 89.746457 -282.37009)
			(xy 89.720154 -282.328494) (xy 89.700863 -282.283218) (xy 89.689086 -282.235434) (xy 89.685126 -282.18638)
			(xy 89.366852 -282.18638) (xy 89.36634 -282.211826) (xy 89.358176 -282.26206) (xy 89.34206 -282.310334)
			(xy 89.318409 -282.355397) (xy 89.287836 -282.396083) (xy 89.251132 -282.431338) (xy 89.209248 -282.460248)
			(xy 89.163269 -282.482065) (xy 89.114385 -282.496225) (xy 89.063864 -282.502359) (xy 89.013012 -282.50031)
			(xy 88.963148 -282.49013) (xy 88.915562 -282.472083) (xy 88.871488 -282.446637) (xy 88.832066 -282.41445)
			(xy 88.798318 -282.376356) (xy 88.771117 -282.333342) (xy 88.751169 -282.286522) (xy 88.73899 -282.237108)
			(xy 88.734895 -282.18638) (xy 88.426798 -282.18638) (xy 88.426286 -282.211826) (xy 88.418122 -282.26206)
			(xy 88.402006 -282.310334) (xy 88.378355 -282.355397) (xy 88.347782 -282.396083) (xy 88.311078 -282.431338)
			(xy 88.269194 -282.460248) (xy 88.223215 -282.482065) (xy 88.174331 -282.496225) (xy 88.12381 -282.502359)
			(xy 88.072958 -282.50031) (xy 88.023094 -282.49013) (xy 87.975508 -282.472083) (xy 87.931434 -282.446637)
			(xy 87.892012 -282.41445) (xy 87.858264 -282.376356) (xy 87.831063 -282.333342) (xy 87.811115 -282.286522)
			(xy 87.798936 -282.237108) (xy 87.794841 -282.18638) (xy 87.47633 -282.18638) (xy 87.475835 -282.210987)
			(xy 87.46794 -282.259564) (xy 87.452356 -282.306245) (xy 87.429485 -282.349822) (xy 87.39992 -282.389166)
			(xy 87.364427 -282.423258) (xy 87.323924 -282.451214) (xy 87.279462 -282.472312) (xy 87.232191 -282.486004)
			(xy 87.183336 -282.491936) (xy 87.134161 -282.489955) (xy 87.085942 -282.480111) (xy 87.039926 -282.462659)
			(xy 86.997305 -282.438052) (xy 86.959184 -282.406927) (xy 86.926549 -282.37009) (xy 86.900246 -282.328494)
			(xy 86.880955 -282.283218) (xy 86.869178 -282.235434) (xy 86.865218 -282.18638) (xy 86.54669 -282.18638)
			(xy 86.546178 -282.211826) (xy 86.538014 -282.26206) (xy 86.521898 -282.310334) (xy 86.498247 -282.355397)
			(xy 86.467674 -282.396083) (xy 86.43097 -282.431338) (xy 86.389086 -282.460248) (xy 86.343107 -282.482065)
			(xy 86.294223 -282.496225) (xy 86.243702 -282.502359) (xy 86.19285 -282.50031) (xy 86.142986 -282.49013)
			(xy 86.0954 -282.472083) (xy 86.051326 -282.446637) (xy 86.011904 -282.41445) (xy 85.978156 -282.376356)
			(xy 85.950955 -282.333342) (xy 85.931007 -282.286522) (xy 85.918828 -282.237108) (xy 85.914733 -282.18638)
			(xy 85.596222 -282.18638) (xy 85.595727 -282.210987) (xy 85.587832 -282.259564) (xy 85.572248 -282.306245)
			(xy 85.549377 -282.349822) (xy 85.519812 -282.389166) (xy 85.484319 -282.423258) (xy 85.443816 -282.451214)
			(xy 85.399354 -282.472312) (xy 85.352083 -282.486004) (xy 85.303228 -282.491936) (xy 85.254053 -282.489955)
			(xy 85.205834 -282.480111) (xy 85.159818 -282.462659) (xy 85.117197 -282.438052) (xy 85.079076 -282.406927)
			(xy 85.046441 -282.37009) (xy 85.020138 -282.328494) (xy 85.000847 -282.283218) (xy 84.98907 -282.235434)
			(xy 84.98511 -282.18638) (xy 84.666836 -282.18638) (xy 84.666324 -282.211826) (xy 84.65816 -282.26206)
			(xy 84.642044 -282.310334) (xy 84.618393 -282.355397) (xy 84.58782 -282.396083) (xy 84.551116 -282.431338)
			(xy 84.509232 -282.460248) (xy 84.463253 -282.482065) (xy 84.414369 -282.496225) (xy 84.363848 -282.502359)
			(xy 84.312996 -282.50031) (xy 84.263132 -282.49013) (xy 84.215546 -282.472083) (xy 84.171472 -282.446637)
			(xy 84.13205 -282.41445) (xy 84.098302 -282.376356) (xy 84.071101 -282.333342) (xy 84.051153 -282.286522)
			(xy 84.038974 -282.237108) (xy 84.034879 -282.18638) (xy 83.716368 -282.18638) (xy 83.715873 -282.210987)
			(xy 83.707978 -282.259564) (xy 83.692394 -282.306245) (xy 83.669523 -282.349822) (xy 83.639958 -282.389166)
			(xy 83.604465 -282.423258) (xy 83.563962 -282.451214) (xy 83.5195 -282.472312) (xy 83.472229 -282.486004)
			(xy 83.423374 -282.491936) (xy 83.374199 -282.489955) (xy 83.32598 -282.480111) (xy 83.279964 -282.462659)
			(xy 83.237343 -282.438052) (xy 83.199222 -282.406927) (xy 83.166587 -282.37009) (xy 83.140284 -282.328494)
			(xy 83.120993 -282.283218) (xy 83.109216 -282.235434) (xy 83.105256 -282.18638) (xy 82.786728 -282.18638)
			(xy 82.786216 -282.211826) (xy 82.778052 -282.26206) (xy 82.761936 -282.310334) (xy 82.738285 -282.355397)
			(xy 82.707712 -282.396083) (xy 82.671008 -282.431338) (xy 82.629124 -282.460248) (xy 82.583145 -282.482065)
			(xy 82.534261 -282.496225) (xy 82.48374 -282.502359) (xy 82.432888 -282.50031) (xy 82.383024 -282.49013)
			(xy 82.335438 -282.472083) (xy 82.291364 -282.446637) (xy 82.251942 -282.41445) (xy 82.218194 -282.376356)
			(xy 82.190993 -282.333342) (xy 82.171045 -282.286522) (xy 82.158866 -282.237108) (xy 82.154771 -282.18638)
			(xy 81.846674 -282.18638) (xy 81.846162 -282.211826) (xy 81.837998 -282.26206) (xy 81.821882 -282.310334)
			(xy 81.798231 -282.355397) (xy 81.767658 -282.396083) (xy 81.730954 -282.431338) (xy 81.68907 -282.460248)
			(xy 81.643091 -282.482065) (xy 81.594207 -282.496225) (xy 81.543686 -282.502359) (xy 81.492834 -282.50031)
			(xy 81.44297 -282.49013) (xy 81.395384 -282.472083) (xy 81.35131 -282.446637) (xy 81.311888 -282.41445)
			(xy 81.27814 -282.376356) (xy 81.250939 -282.333342) (xy 81.230991 -282.286522) (xy 81.218812 -282.237108)
			(xy 81.214717 -282.18638) (xy 80.89646 -282.18638) (xy 80.895965 -282.210987) (xy 80.88807 -282.259564)
			(xy 80.872486 -282.306245) (xy 80.849615 -282.349822) (xy 80.82005 -282.389166) (xy 80.784557 -282.423258)
			(xy 80.744054 -282.451214) (xy 80.699592 -282.472312) (xy 80.652321 -282.486004) (xy 80.603466 -282.491936)
			(xy 80.554291 -282.489955) (xy 80.506072 -282.480111) (xy 80.460056 -282.462659) (xy 80.417435 -282.438052)
			(xy 80.379314 -282.406927) (xy 80.346679 -282.37009) (xy 80.320376 -282.328494) (xy 80.301085 -282.283218)
			(xy 80.289308 -282.235434) (xy 80.285348 -282.18638) (xy 79.016352 -282.18638) (xy 79.015857 -282.210987)
			(xy 79.007962 -282.259564) (xy 78.992378 -282.306245) (xy 78.969507 -282.349822) (xy 78.939942 -282.389166)
			(xy 78.904449 -282.423258) (xy 78.863946 -282.451214) (xy 78.819484 -282.472312) (xy 78.772213 -282.486004)
			(xy 78.723358 -282.491936) (xy 78.674183 -282.489955) (xy 78.625964 -282.480111) (xy 78.579948 -282.462659)
			(xy 78.537327 -282.438052) (xy 78.499206 -282.406927) (xy 78.466571 -282.37009) (xy 78.440268 -282.328494)
			(xy 78.420977 -282.283218) (xy 78.4092 -282.235434) (xy 78.40524 -282.18638) (xy 73.228962 -282.18638)
			(xy 73.228962 -282.730448) (xy 76.807072 -282.730448) (xy 76.811032 -282.681394) (xy 76.822809 -282.63361)
			(xy 76.8421 -282.588334) (xy 76.868403 -282.546738) (xy 76.901038 -282.509901) (xy 76.939159 -282.478776)
			(xy 76.98178 -282.454169) (xy 77.027796 -282.436717) (xy 77.076015 -282.426873) (xy 77.12519 -282.424892)
			(xy 77.174045 -282.430824) (xy 77.221316 -282.444516) (xy 77.265778 -282.465614) (xy 77.306281 -282.49357)
			(xy 77.341774 -282.527662) (xy 77.371339 -282.567006) (xy 77.39421 -282.610583) (xy 77.409794 -282.657264)
			(xy 77.417689 -282.705841) (xy 77.418184 -282.730448) (xy 77.417689 -282.755055) (xy 77.409794 -282.803632)
			(xy 77.39421 -282.850313) (xy 77.371339 -282.89389) (xy 77.341774 -282.933234) (xy 77.306281 -282.967326)
			(xy 77.265778 -282.995282) (xy 77.263451 -282.996386) (xy 79.815194 -282.996386) (xy 79.819154 -282.947332)
			(xy 79.830931 -282.899548) (xy 79.850222 -282.854272) (xy 79.876525 -282.812676) (xy 79.90916 -282.775839)
			(xy 79.947281 -282.744714) (xy 79.989902 -282.720107) (xy 80.035918 -282.702655) (xy 80.084137 -282.692811)
			(xy 80.133312 -282.69083) (xy 80.182167 -282.696762) (xy 80.229438 -282.710454) (xy 80.2739 -282.731552)
			(xy 80.314403 -282.759508) (xy 80.349896 -282.7936) (xy 80.379461 -282.832944) (xy 80.402332 -282.876521)
			(xy 80.417916 -282.923202) (xy 80.425811 -282.971779) (xy 80.426306 -282.996386) (xy 80.744817 -282.996386)
			(xy 80.748912 -282.945658) (xy 80.761091 -282.896244) (xy 80.781039 -282.849424) (xy 80.80824 -282.80641)
			(xy 80.841988 -282.768316) (xy 80.88141 -282.736129) (xy 80.925484 -282.710683) (xy 80.97307 -282.692636)
			(xy 81.022934 -282.682456) (xy 81.073786 -282.680407) (xy 81.124307 -282.686541) (xy 81.173191 -282.700701)
			(xy 81.21917 -282.722518) (xy 81.261054 -282.751428) (xy 81.297758 -282.786683) (xy 81.328331 -282.827369)
			(xy 81.351982 -282.872432) (xy 81.368098 -282.920706) (xy 81.376262 -282.97094) (xy 81.376774 -282.996386)
			(xy 81.695302 -282.996386) (xy 81.699262 -282.947332) (xy 81.711039 -282.899548) (xy 81.73033 -282.854272)
			(xy 81.756633 -282.812676) (xy 81.789268 -282.775839) (xy 81.827389 -282.744714) (xy 81.87001 -282.720107)
			(xy 81.916026 -282.702655) (xy 81.964245 -282.692811) (xy 82.01342 -282.69083) (xy 82.062275 -282.696762)
			(xy 82.109546 -282.710454) (xy 82.154008 -282.731552) (xy 82.194511 -282.759508) (xy 82.230004 -282.7936)
			(xy 82.259569 -282.832944) (xy 82.28244 -282.876521) (xy 82.298024 -282.923202) (xy 82.305919 -282.971779)
			(xy 82.306414 -282.996386) (xy 82.624671 -282.996386) (xy 82.628766 -282.945658) (xy 82.640945 -282.896244)
			(xy 82.660893 -282.849424) (xy 82.688094 -282.80641) (xy 82.721842 -282.768316) (xy 82.761264 -282.736129)
			(xy 82.805338 -282.710683) (xy 82.852924 -282.692636) (xy 82.902788 -282.682456) (xy 82.95364 -282.680407)
			(xy 83.004161 -282.686541) (xy 83.053045 -282.700701) (xy 83.099024 -282.722518) (xy 83.140908 -282.751428)
			(xy 83.177612 -282.786683) (xy 83.208185 -282.827369) (xy 83.231836 -282.872432) (xy 83.247952 -282.920706)
			(xy 83.256116 -282.97094) (xy 83.256628 -282.996386) (xy 83.575156 -282.996386) (xy 83.579116 -282.947332)
			(xy 83.590893 -282.899548) (xy 83.610184 -282.854272) (xy 83.636487 -282.812676) (xy 83.669122 -282.775839)
			(xy 83.707243 -282.744714) (xy 83.749864 -282.720107) (xy 83.79588 -282.702655) (xy 83.844099 -282.692811)
			(xy 83.893274 -282.69083) (xy 83.942129 -282.696762) (xy 83.9894 -282.710454) (xy 84.033862 -282.731552)
			(xy 84.074365 -282.759508) (xy 84.109858 -282.7936) (xy 84.139423 -282.832944) (xy 84.162294 -282.876521)
			(xy 84.177878 -282.923202) (xy 84.185773 -282.971779) (xy 84.186268 -282.996386) (xy 84.504779 -282.996386)
			(xy 84.508874 -282.945658) (xy 84.521053 -282.896244) (xy 84.541001 -282.849424) (xy 84.568202 -282.80641)
			(xy 84.60195 -282.768316) (xy 84.641372 -282.736129) (xy 84.685446 -282.710683) (xy 84.733032 -282.692636)
			(xy 84.782896 -282.682456) (xy 84.833748 -282.680407) (xy 84.884269 -282.686541) (xy 84.933153 -282.700701)
			(xy 84.979132 -282.722518) (xy 85.021016 -282.751428) (xy 85.05772 -282.786683) (xy 85.088293 -282.827369)
			(xy 85.111944 -282.872432) (xy 85.12806 -282.920706) (xy 85.136224 -282.97094) (xy 85.136736 -282.996386)
			(xy 85.444833 -282.996386) (xy 85.448928 -282.945658) (xy 85.461107 -282.896244) (xy 85.481055 -282.849424)
			(xy 85.508256 -282.80641) (xy 85.542004 -282.768316) (xy 85.581426 -282.736129) (xy 85.6255 -282.710683)
			(xy 85.673086 -282.692636) (xy 85.72295 -282.682456) (xy 85.773802 -282.680407) (xy 85.824323 -282.686541)
			(xy 85.873207 -282.700701) (xy 85.919186 -282.722518) (xy 85.96107 -282.751428) (xy 85.997774 -282.786683)
			(xy 86.028347 -282.827369) (xy 86.051998 -282.872432) (xy 86.068114 -282.920706) (xy 86.076278 -282.97094)
			(xy 86.07679 -282.996386) (xy 86.395318 -282.996386) (xy 86.399278 -282.947332) (xy 86.411055 -282.899548)
			(xy 86.430346 -282.854272) (xy 86.456649 -282.812676) (xy 86.489284 -282.775839) (xy 86.527405 -282.744714)
			(xy 86.570026 -282.720107) (xy 86.616042 -282.702655) (xy 86.664261 -282.692811) (xy 86.713436 -282.69083)
			(xy 86.762291 -282.696762) (xy 86.809562 -282.710454) (xy 86.854024 -282.731552) (xy 86.894527 -282.759508)
			(xy 86.93002 -282.7936) (xy 86.959585 -282.832944) (xy 86.982456 -282.876521) (xy 86.99804 -282.923202)
			(xy 87.005935 -282.971779) (xy 87.00643 -282.996386) (xy 87.324687 -282.996386) (xy 87.328782 -282.945658)
			(xy 87.340961 -282.896244) (xy 87.360909 -282.849424) (xy 87.38811 -282.80641) (xy 87.421858 -282.768316)
			(xy 87.46128 -282.736129) (xy 87.505354 -282.710683) (xy 87.55294 -282.692636) (xy 87.602804 -282.682456)
			(xy 87.653656 -282.680407) (xy 87.704177 -282.686541) (xy 87.753061 -282.700701) (xy 87.79904 -282.722518)
			(xy 87.840924 -282.751428) (xy 87.877628 -282.786683) (xy 87.908201 -282.827369) (xy 87.931852 -282.872432)
			(xy 87.947968 -282.920706) (xy 87.956132 -282.97094) (xy 87.956644 -282.996386) (xy 88.275172 -282.996386)
			(xy 88.279132 -282.947332) (xy 88.290909 -282.899548) (xy 88.3102 -282.854272) (xy 88.336503 -282.812676)
			(xy 88.369138 -282.775839) (xy 88.407259 -282.744714) (xy 88.44988 -282.720107) (xy 88.495896 -282.702655)
			(xy 88.544115 -282.692811) (xy 88.59329 -282.69083) (xy 88.642145 -282.696762) (xy 88.689416 -282.710454)
			(xy 88.733878 -282.731552) (xy 88.774381 -282.759508) (xy 88.809874 -282.7936) (xy 88.839439 -282.832944)
			(xy 88.86231 -282.876521) (xy 88.877894 -282.923202) (xy 88.885789 -282.971779) (xy 88.886284 -282.996386)
			(xy 89.204795 -282.996386) (xy 89.20889 -282.945658) (xy 89.221069 -282.896244) (xy 89.241017 -282.849424)
			(xy 89.268218 -282.80641) (xy 89.301966 -282.768316) (xy 89.341388 -282.736129) (xy 89.385462 -282.710683)
			(xy 89.433048 -282.692636) (xy 89.482912 -282.682456) (xy 89.533764 -282.680407) (xy 89.584285 -282.686541)
			(xy 89.633169 -282.700701) (xy 89.679148 -282.722518) (xy 89.721032 -282.751428) (xy 89.757736 -282.786683)
			(xy 89.788309 -282.827369) (xy 89.81196 -282.872432) (xy 89.828076 -282.920706) (xy 89.83624 -282.97094)
			(xy 89.836752 -282.996386) (xy 90.15528 -282.996386) (xy 90.15924 -282.947332) (xy 90.171017 -282.899548)
			(xy 90.190308 -282.854272) (xy 90.216611 -282.812676) (xy 90.249246 -282.775839) (xy 90.287367 -282.744714)
			(xy 90.329988 -282.720107) (xy 90.376004 -282.702655) (xy 90.424223 -282.692811) (xy 90.473398 -282.69083)
			(xy 90.522253 -282.696762) (xy 90.569524 -282.710454) (xy 90.613986 -282.731552) (xy 90.654489 -282.759508)
			(xy 90.689982 -282.7936) (xy 90.719547 -282.832944) (xy 90.742418 -282.876521) (xy 90.758002 -282.923202)
			(xy 90.765897 -282.971779) (xy 90.766392 -282.996386) (xy 91.084903 -282.996386) (xy 91.088998 -282.945658)
			(xy 91.101177 -282.896244) (xy 91.121125 -282.849424) (xy 91.148326 -282.80641) (xy 91.182074 -282.768316)
			(xy 91.221496 -282.736129) (xy 91.26557 -282.710683) (xy 91.313156 -282.692636) (xy 91.36302 -282.682456)
			(xy 91.413872 -282.680407) (xy 91.464393 -282.686541) (xy 91.513277 -282.700701) (xy 91.559256 -282.722518)
			(xy 91.60114 -282.751428) (xy 91.637844 -282.786683) (xy 91.668417 -282.827369) (xy 91.692068 -282.872432)
			(xy 91.708184 -282.920706) (xy 91.716348 -282.97094) (xy 91.71686 -282.996386) (xy 92.024703 -282.996386)
			(xy 92.028798 -282.945658) (xy 92.040977 -282.896244) (xy 92.060925 -282.849424) (xy 92.088126 -282.80641)
			(xy 92.121874 -282.768316) (xy 92.161296 -282.736129) (xy 92.20537 -282.710683) (xy 92.252956 -282.692636)
			(xy 92.30282 -282.682456) (xy 92.353672 -282.680407) (xy 92.404193 -282.686541) (xy 92.453077 -282.700701)
			(xy 92.499056 -282.722518) (xy 92.54094 -282.751428) (xy 92.577644 -282.786683) (xy 92.608217 -282.827369)
			(xy 92.631868 -282.872432) (xy 92.647984 -282.920706) (xy 92.656148 -282.97094) (xy 92.65666 -282.996386)
			(xy 92.975188 -282.996386) (xy 92.979148 -282.947332) (xy 92.990925 -282.899548) (xy 93.010216 -282.854272)
			(xy 93.036519 -282.812676) (xy 93.069154 -282.775839) (xy 93.107275 -282.744714) (xy 93.149896 -282.720107)
			(xy 93.195912 -282.702655) (xy 93.244131 -282.692811) (xy 93.293306 -282.69083) (xy 93.342161 -282.696762)
			(xy 93.389432 -282.710454) (xy 93.433894 -282.731552) (xy 93.474397 -282.759508) (xy 93.50989 -282.7936)
			(xy 93.539455 -282.832944) (xy 93.562326 -282.876521) (xy 93.57791 -282.923202) (xy 93.585805 -282.971779)
			(xy 93.5863 -282.996386) (xy 93.904811 -282.996386) (xy 93.908906 -282.945658) (xy 93.921085 -282.896244)
			(xy 93.941033 -282.849424) (xy 93.968234 -282.80641) (xy 94.001982 -282.768316) (xy 94.041404 -282.736129)
			(xy 94.085478 -282.710683) (xy 94.133064 -282.692636) (xy 94.182928 -282.682456) (xy 94.23378 -282.680407)
			(xy 94.284301 -282.686541) (xy 94.333185 -282.700701) (xy 94.379164 -282.722518) (xy 94.421048 -282.751428)
			(xy 94.457752 -282.786683) (xy 94.488325 -282.827369) (xy 94.511976 -282.872432) (xy 94.528092 -282.920706)
			(xy 94.536256 -282.97094) (xy 94.536768 -282.996386) (xy 94.855296 -282.996386) (xy 94.859256 -282.947332)
			(xy 94.871033 -282.899548) (xy 94.890324 -282.854272) (xy 94.916627 -282.812676) (xy 94.949262 -282.775839)
			(xy 94.987383 -282.744714) (xy 95.030004 -282.720107) (xy 95.07602 -282.702655) (xy 95.124239 -282.692811)
			(xy 95.173414 -282.69083) (xy 95.222269 -282.696762) (xy 95.26954 -282.710454) (xy 95.314002 -282.731552)
			(xy 95.354505 -282.759508) (xy 95.389998 -282.7936) (xy 95.419563 -282.832944) (xy 95.442434 -282.876521)
			(xy 95.458018 -282.923202) (xy 95.465913 -282.971779) (xy 95.466408 -282.996386) (xy 95.784919 -282.996386)
			(xy 95.789014 -282.945658) (xy 95.801193 -282.896244) (xy 95.821141 -282.849424) (xy 95.848342 -282.80641)
			(xy 95.88209 -282.768316) (xy 95.921512 -282.736129) (xy 95.965586 -282.710683) (xy 96.013172 -282.692636)
			(xy 96.063036 -282.682456) (xy 96.113888 -282.680407) (xy 96.164409 -282.686541) (xy 96.213293 -282.700701)
			(xy 96.259272 -282.722518) (xy 96.301156 -282.751428) (xy 96.33786 -282.786683) (xy 96.368433 -282.827369)
			(xy 96.392084 -282.872432) (xy 96.4082 -282.920706) (xy 96.416364 -282.97094) (xy 96.416876 -282.996386)
			(xy 96.73515 -282.996386) (xy 96.73911 -282.947332) (xy 96.750887 -282.899548) (xy 96.770178 -282.854272)
			(xy 96.796481 -282.812676) (xy 96.829116 -282.775839) (xy 96.867237 -282.744714) (xy 96.909858 -282.720107)
			(xy 96.955874 -282.702655) (xy 97.004093 -282.692811) (xy 97.053268 -282.69083) (xy 97.102123 -282.696762)
			(xy 97.149394 -282.710454) (xy 97.193856 -282.731552) (xy 97.234359 -282.759508) (xy 97.269852 -282.7936)
			(xy 97.299417 -282.832944) (xy 97.322288 -282.876521) (xy 97.337872 -282.923202) (xy 97.345767 -282.971779)
			(xy 97.346262 -282.996386) (xy 97.664773 -282.996386) (xy 97.668868 -282.945658) (xy 97.681047 -282.896244)
			(xy 97.700995 -282.849424) (xy 97.728196 -282.80641) (xy 97.761944 -282.768316) (xy 97.801366 -282.736129)
			(xy 97.84544 -282.710683) (xy 97.893026 -282.692636) (xy 97.94289 -282.682456) (xy 97.993742 -282.680407)
			(xy 98.044263 -282.686541) (xy 98.093147 -282.700701) (xy 98.139126 -282.722518) (xy 98.18101 -282.751428)
			(xy 98.217714 -282.786683) (xy 98.248287 -282.827369) (xy 98.271938 -282.872432) (xy 98.288054 -282.920706)
			(xy 98.296218 -282.97094) (xy 98.29673 -282.996386) (xy 98.604827 -282.996386) (xy 98.608922 -282.945658)
			(xy 98.621101 -282.896244) (xy 98.641049 -282.849424) (xy 98.66825 -282.80641) (xy 98.701998 -282.768316)
			(xy 98.74142 -282.736129) (xy 98.785494 -282.710683) (xy 98.83308 -282.692636) (xy 98.882944 -282.682456)
			(xy 98.933796 -282.680407) (xy 98.984317 -282.686541) (xy 99.033201 -282.700701) (xy 99.07918 -282.722518)
			(xy 99.121064 -282.751428) (xy 99.157768 -282.786683) (xy 99.188341 -282.827369) (xy 99.211992 -282.872432)
			(xy 99.228108 -282.920706) (xy 99.236272 -282.97094) (xy 99.236784 -282.996386) (xy 99.555312 -282.996386)
			(xy 99.559272 -282.947332) (xy 99.571049 -282.899548) (xy 99.59034 -282.854272) (xy 99.616643 -282.812676)
			(xy 99.649278 -282.775839) (xy 99.687399 -282.744714) (xy 99.73002 -282.720107) (xy 99.776036 -282.702655)
			(xy 99.824255 -282.692811) (xy 99.87343 -282.69083) (xy 99.922285 -282.696762) (xy 99.969556 -282.710454)
			(xy 100.014018 -282.731552) (xy 100.054521 -282.759508) (xy 100.090014 -282.7936) (xy 100.119579 -282.832944)
			(xy 100.14245 -282.876521) (xy 100.158034 -282.923202) (xy 100.165929 -282.971779) (xy 100.166424 -282.996386)
			(xy 100.484935 -282.996386) (xy 100.48903 -282.945658) (xy 100.501209 -282.896244) (xy 100.521157 -282.849424)
			(xy 100.548358 -282.80641) (xy 100.582106 -282.768316) (xy 100.621528 -282.736129) (xy 100.665602 -282.710683)
			(xy 100.713188 -282.692636) (xy 100.763052 -282.682456) (xy 100.813904 -282.680407) (xy 100.864425 -282.686541)
			(xy 100.913309 -282.700701) (xy 100.959288 -282.722518) (xy 101.001172 -282.751428) (xy 101.037876 -282.786683)
			(xy 101.068449 -282.827369) (xy 101.0921 -282.872432) (xy 101.108216 -282.920706) (xy 101.11638 -282.97094)
			(xy 101.116892 -282.996386) (xy 101.424735 -282.996386) (xy 101.42883 -282.945658) (xy 101.441009 -282.896244)
			(xy 101.460957 -282.849424) (xy 101.488158 -282.80641) (xy 101.521906 -282.768316) (xy 101.561328 -282.736129)
			(xy 101.605402 -282.710683) (xy 101.652988 -282.692636) (xy 101.702852 -282.682456) (xy 101.753704 -282.680407)
			(xy 101.804225 -282.686541) (xy 101.853109 -282.700701) (xy 101.899088 -282.722518) (xy 101.940972 -282.751428)
			(xy 101.977676 -282.786683) (xy 102.008249 -282.827369) (xy 102.0319 -282.872432) (xy 102.048016 -282.920706)
			(xy 102.05618 -282.97094) (xy 102.056692 -282.996386) (xy 102.05618 -283.021832) (xy 102.048016 -283.072066)
			(xy 102.0319 -283.12034) (xy 102.008249 -283.165403) (xy 101.977676 -283.206089) (xy 101.940972 -283.241344)
			(xy 101.899088 -283.270254) (xy 101.853109 -283.292071) (xy 101.804225 -283.306231) (xy 101.753704 -283.312365)
			(xy 101.702852 -283.310316) (xy 101.652988 -283.300136) (xy 101.605402 -283.282089) (xy 101.561328 -283.256643)
			(xy 101.521906 -283.224456) (xy 101.488158 -283.186362) (xy 101.460957 -283.143348) (xy 101.441009 -283.096528)
			(xy 101.42883 -283.047114) (xy 101.424735 -282.996386) (xy 101.116892 -282.996386) (xy 101.11638 -283.021832)
			(xy 101.108216 -283.072066) (xy 101.0921 -283.12034) (xy 101.068449 -283.165403) (xy 101.037876 -283.206089)
			(xy 101.001172 -283.241344) (xy 100.959288 -283.270254) (xy 100.913309 -283.292071) (xy 100.864425 -283.306231)
			(xy 100.813904 -283.312365) (xy 100.763052 -283.310316) (xy 100.713188 -283.300136) (xy 100.665602 -283.282089)
			(xy 100.621528 -283.256643) (xy 100.582106 -283.224456) (xy 100.548358 -283.186362) (xy 100.521157 -283.143348)
			(xy 100.501209 -283.096528) (xy 100.48903 -283.047114) (xy 100.484935 -282.996386) (xy 100.166424 -282.996386)
			(xy 100.165929 -283.020993) (xy 100.158034 -283.06957) (xy 100.14245 -283.116251) (xy 100.119579 -283.159828)
			(xy 100.090014 -283.199172) (xy 100.054521 -283.233264) (xy 100.014018 -283.26122) (xy 99.969556 -283.282318)
			(xy 99.922285 -283.29601) (xy 99.87343 -283.301942) (xy 99.824255 -283.299961) (xy 99.776036 -283.290117)
			(xy 99.73002 -283.272665) (xy 99.687399 -283.248058) (xy 99.649278 -283.216933) (xy 99.616643 -283.180096)
			(xy 99.59034 -283.1385) (xy 99.571049 -283.093224) (xy 99.559272 -283.04544) (xy 99.555312 -282.996386)
			(xy 99.236784 -282.996386) (xy 99.236272 -283.021832) (xy 99.228108 -283.072066) (xy 99.211992 -283.12034)
			(xy 99.188341 -283.165403) (xy 99.157768 -283.206089) (xy 99.121064 -283.241344) (xy 99.07918 -283.270254)
			(xy 99.033201 -283.292071) (xy 98.984317 -283.306231) (xy 98.933796 -283.312365) (xy 98.882944 -283.310316)
			(xy 98.83308 -283.300136) (xy 98.785494 -283.282089) (xy 98.74142 -283.256643) (xy 98.701998 -283.224456)
			(xy 98.66825 -283.186362) (xy 98.641049 -283.143348) (xy 98.621101 -283.096528) (xy 98.608922 -283.047114)
			(xy 98.604827 -282.996386) (xy 98.29673 -282.996386) (xy 98.296218 -283.021832) (xy 98.288054 -283.072066)
			(xy 98.271938 -283.12034) (xy 98.248287 -283.165403) (xy 98.217714 -283.206089) (xy 98.18101 -283.241344)
			(xy 98.139126 -283.270254) (xy 98.093147 -283.292071) (xy 98.044263 -283.306231) (xy 97.993742 -283.312365)
			(xy 97.94289 -283.310316) (xy 97.893026 -283.300136) (xy 97.84544 -283.282089) (xy 97.801366 -283.256643)
			(xy 97.761944 -283.224456) (xy 97.728196 -283.186362) (xy 97.700995 -283.143348) (xy 97.681047 -283.096528)
			(xy 97.668868 -283.047114) (xy 97.664773 -282.996386) (xy 97.346262 -282.996386) (xy 97.345767 -283.020993)
			(xy 97.337872 -283.06957) (xy 97.322288 -283.116251) (xy 97.299417 -283.159828) (xy 97.269852 -283.199172)
			(xy 97.234359 -283.233264) (xy 97.193856 -283.26122) (xy 97.149394 -283.282318) (xy 97.102123 -283.29601)
			(xy 97.053268 -283.301942) (xy 97.004093 -283.299961) (xy 96.955874 -283.290117) (xy 96.909858 -283.272665)
			(xy 96.867237 -283.248058) (xy 96.829116 -283.216933) (xy 96.796481 -283.180096) (xy 96.770178 -283.1385)
			(xy 96.750887 -283.093224) (xy 96.73911 -283.04544) (xy 96.73515 -282.996386) (xy 96.416876 -282.996386)
			(xy 96.416364 -283.021832) (xy 96.4082 -283.072066) (xy 96.392084 -283.12034) (xy 96.368433 -283.165403)
			(xy 96.33786 -283.206089) (xy 96.301156 -283.241344) (xy 96.259272 -283.270254) (xy 96.213293 -283.292071)
			(xy 96.164409 -283.306231) (xy 96.113888 -283.312365) (xy 96.063036 -283.310316) (xy 96.013172 -283.300136)
			(xy 95.965586 -283.282089) (xy 95.921512 -283.256643) (xy 95.88209 -283.224456) (xy 95.848342 -283.186362)
			(xy 95.821141 -283.143348) (xy 95.801193 -283.096528) (xy 95.789014 -283.047114) (xy 95.784919 -282.996386)
			(xy 95.466408 -282.996386) (xy 95.465913 -283.020993) (xy 95.458018 -283.06957) (xy 95.442434 -283.116251)
			(xy 95.419563 -283.159828) (xy 95.389998 -283.199172) (xy 95.354505 -283.233264) (xy 95.314002 -283.26122)
			(xy 95.26954 -283.282318) (xy 95.222269 -283.29601) (xy 95.173414 -283.301942) (xy 95.124239 -283.299961)
			(xy 95.07602 -283.290117) (xy 95.030004 -283.272665) (xy 94.987383 -283.248058) (xy 94.949262 -283.216933)
			(xy 94.916627 -283.180096) (xy 94.890324 -283.1385) (xy 94.871033 -283.093224) (xy 94.859256 -283.04544)
			(xy 94.855296 -282.996386) (xy 94.536768 -282.996386) (xy 94.536256 -283.021832) (xy 94.528092 -283.072066)
			(xy 94.511976 -283.12034) (xy 94.488325 -283.165403) (xy 94.457752 -283.206089) (xy 94.421048 -283.241344)
			(xy 94.379164 -283.270254) (xy 94.333185 -283.292071) (xy 94.284301 -283.306231) (xy 94.23378 -283.312365)
			(xy 94.182928 -283.310316) (xy 94.133064 -283.300136) (xy 94.085478 -283.282089) (xy 94.041404 -283.256643)
			(xy 94.001982 -283.224456) (xy 93.968234 -283.186362) (xy 93.941033 -283.143348) (xy 93.921085 -283.096528)
			(xy 93.908906 -283.047114) (xy 93.904811 -282.996386) (xy 93.5863 -282.996386) (xy 93.585805 -283.020993)
			(xy 93.57791 -283.06957) (xy 93.562326 -283.116251) (xy 93.539455 -283.159828) (xy 93.50989 -283.199172)
			(xy 93.474397 -283.233264) (xy 93.433894 -283.26122) (xy 93.389432 -283.282318) (xy 93.342161 -283.29601)
			(xy 93.293306 -283.301942) (xy 93.244131 -283.299961) (xy 93.195912 -283.290117) (xy 93.149896 -283.272665)
			(xy 93.107275 -283.248058) (xy 93.069154 -283.216933) (xy 93.036519 -283.180096) (xy 93.010216 -283.1385)
			(xy 92.990925 -283.093224) (xy 92.979148 -283.04544) (xy 92.975188 -282.996386) (xy 92.65666 -282.996386)
			(xy 92.656148 -283.021832) (xy 92.647984 -283.072066) (xy 92.631868 -283.12034) (xy 92.608217 -283.165403)
			(xy 92.577644 -283.206089) (xy 92.54094 -283.241344) (xy 92.499056 -283.270254) (xy 92.453077 -283.292071)
			(xy 92.404193 -283.306231) (xy 92.353672 -283.312365) (xy 92.30282 -283.310316) (xy 92.252956 -283.300136)
			(xy 92.20537 -283.282089) (xy 92.161296 -283.256643) (xy 92.121874 -283.224456) (xy 92.088126 -283.186362)
			(xy 92.060925 -283.143348) (xy 92.040977 -283.096528) (xy 92.028798 -283.047114) (xy 92.024703 -282.996386)
			(xy 91.71686 -282.996386) (xy 91.716348 -283.021832) (xy 91.708184 -283.072066) (xy 91.692068 -283.12034)
			(xy 91.668417 -283.165403) (xy 91.637844 -283.206089) (xy 91.60114 -283.241344) (xy 91.559256 -283.270254)
			(xy 91.513277 -283.292071) (xy 91.464393 -283.306231) (xy 91.413872 -283.312365) (xy 91.36302 -283.310316)
			(xy 91.313156 -283.300136) (xy 91.26557 -283.282089) (xy 91.221496 -283.256643) (xy 91.182074 -283.224456)
			(xy 91.148326 -283.186362) (xy 91.121125 -283.143348) (xy 91.101177 -283.096528) (xy 91.088998 -283.047114)
			(xy 91.084903 -282.996386) (xy 90.766392 -282.996386) (xy 90.765897 -283.020993) (xy 90.758002 -283.06957)
			(xy 90.742418 -283.116251) (xy 90.719547 -283.159828) (xy 90.689982 -283.199172) (xy 90.654489 -283.233264)
			(xy 90.613986 -283.26122) (xy 90.569524 -283.282318) (xy 90.522253 -283.29601) (xy 90.473398 -283.301942)
			(xy 90.424223 -283.299961) (xy 90.376004 -283.290117) (xy 90.329988 -283.272665) (xy 90.287367 -283.248058)
			(xy 90.249246 -283.216933) (xy 90.216611 -283.180096) (xy 90.190308 -283.1385) (xy 90.171017 -283.093224)
			(xy 90.15924 -283.04544) (xy 90.15528 -282.996386) (xy 89.836752 -282.996386) (xy 89.83624 -283.021832)
			(xy 89.828076 -283.072066) (xy 89.81196 -283.12034) (xy 89.788309 -283.165403) (xy 89.757736 -283.206089)
			(xy 89.721032 -283.241344) (xy 89.679148 -283.270254) (xy 89.633169 -283.292071) (xy 89.584285 -283.306231)
			(xy 89.533764 -283.312365) (xy 89.482912 -283.310316) (xy 89.433048 -283.300136) (xy 89.385462 -283.282089)
			(xy 89.341388 -283.256643) (xy 89.301966 -283.224456) (xy 89.268218 -283.186362) (xy 89.241017 -283.143348)
			(xy 89.221069 -283.096528) (xy 89.20889 -283.047114) (xy 89.204795 -282.996386) (xy 88.886284 -282.996386)
			(xy 88.885789 -283.020993) (xy 88.877894 -283.06957) (xy 88.86231 -283.116251) (xy 88.839439 -283.159828)
			(xy 88.809874 -283.199172) (xy 88.774381 -283.233264) (xy 88.733878 -283.26122) (xy 88.689416 -283.282318)
			(xy 88.642145 -283.29601) (xy 88.59329 -283.301942) (xy 88.544115 -283.299961) (xy 88.495896 -283.290117)
			(xy 88.44988 -283.272665) (xy 88.407259 -283.248058) (xy 88.369138 -283.216933) (xy 88.336503 -283.180096)
			(xy 88.3102 -283.1385) (xy 88.290909 -283.093224) (xy 88.279132 -283.04544) (xy 88.275172 -282.996386)
			(xy 87.956644 -282.996386) (xy 87.956132 -283.021832) (xy 87.947968 -283.072066) (xy 87.931852 -283.12034)
			(xy 87.908201 -283.165403) (xy 87.877628 -283.206089) (xy 87.840924 -283.241344) (xy 87.79904 -283.270254)
			(xy 87.753061 -283.292071) (xy 87.704177 -283.306231) (xy 87.653656 -283.312365) (xy 87.602804 -283.310316)
			(xy 87.55294 -283.300136) (xy 87.505354 -283.282089) (xy 87.46128 -283.256643) (xy 87.421858 -283.224456)
			(xy 87.38811 -283.186362) (xy 87.360909 -283.143348) (xy 87.340961 -283.096528) (xy 87.328782 -283.047114)
			(xy 87.324687 -282.996386) (xy 87.00643 -282.996386) (xy 87.005935 -283.020993) (xy 86.99804 -283.06957)
			(xy 86.982456 -283.116251) (xy 86.959585 -283.159828) (xy 86.93002 -283.199172) (xy 86.894527 -283.233264)
			(xy 86.854024 -283.26122) (xy 86.809562 -283.282318) (xy 86.762291 -283.29601) (xy 86.713436 -283.301942)
			(xy 86.664261 -283.299961) (xy 86.616042 -283.290117) (xy 86.570026 -283.272665) (xy 86.527405 -283.248058)
			(xy 86.489284 -283.216933) (xy 86.456649 -283.180096) (xy 86.430346 -283.1385) (xy 86.411055 -283.093224)
			(xy 86.399278 -283.04544) (xy 86.395318 -282.996386) (xy 86.07679 -282.996386) (xy 86.076278 -283.021832)
			(xy 86.068114 -283.072066) (xy 86.051998 -283.12034) (xy 86.028347 -283.165403) (xy 85.997774 -283.206089)
			(xy 85.96107 -283.241344) (xy 85.919186 -283.270254) (xy 85.873207 -283.292071) (xy 85.824323 -283.306231)
			(xy 85.773802 -283.312365) (xy 85.72295 -283.310316) (xy 85.673086 -283.300136) (xy 85.6255 -283.282089)
			(xy 85.581426 -283.256643) (xy 85.542004 -283.224456) (xy 85.508256 -283.186362) (xy 85.481055 -283.143348)
			(xy 85.461107 -283.096528) (xy 85.448928 -283.047114) (xy 85.444833 -282.996386) (xy 85.136736 -282.996386)
			(xy 85.136224 -283.021832) (xy 85.12806 -283.072066) (xy 85.111944 -283.12034) (xy 85.088293 -283.165403)
			(xy 85.05772 -283.206089) (xy 85.021016 -283.241344) (xy 84.979132 -283.270254) (xy 84.933153 -283.292071)
			(xy 84.884269 -283.306231) (xy 84.833748 -283.312365) (xy 84.782896 -283.310316) (xy 84.733032 -283.300136)
			(xy 84.685446 -283.282089) (xy 84.641372 -283.256643) (xy 84.60195 -283.224456) (xy 84.568202 -283.186362)
			(xy 84.541001 -283.143348) (xy 84.521053 -283.096528) (xy 84.508874 -283.047114) (xy 84.504779 -282.996386)
			(xy 84.186268 -282.996386) (xy 84.185773 -283.020993) (xy 84.177878 -283.06957) (xy 84.162294 -283.116251)
			(xy 84.139423 -283.159828) (xy 84.109858 -283.199172) (xy 84.074365 -283.233264) (xy 84.033862 -283.26122)
			(xy 83.9894 -283.282318) (xy 83.942129 -283.29601) (xy 83.893274 -283.301942) (xy 83.844099 -283.299961)
			(xy 83.79588 -283.290117) (xy 83.749864 -283.272665) (xy 83.707243 -283.248058) (xy 83.669122 -283.216933)
			(xy 83.636487 -283.180096) (xy 83.610184 -283.1385) (xy 83.590893 -283.093224) (xy 83.579116 -283.04544)
			(xy 83.575156 -282.996386) (xy 83.256628 -282.996386) (xy 83.256116 -283.021832) (xy 83.247952 -283.072066)
			(xy 83.231836 -283.12034) (xy 83.208185 -283.165403) (xy 83.177612 -283.206089) (xy 83.140908 -283.241344)
			(xy 83.099024 -283.270254) (xy 83.053045 -283.292071) (xy 83.004161 -283.306231) (xy 82.95364 -283.312365)
			(xy 82.902788 -283.310316) (xy 82.852924 -283.300136) (xy 82.805338 -283.282089) (xy 82.761264 -283.256643)
			(xy 82.721842 -283.224456) (xy 82.688094 -283.186362) (xy 82.660893 -283.143348) (xy 82.640945 -283.096528)
			(xy 82.628766 -283.047114) (xy 82.624671 -282.996386) (xy 82.306414 -282.996386) (xy 82.305919 -283.020993)
			(xy 82.298024 -283.06957) (xy 82.28244 -283.116251) (xy 82.259569 -283.159828) (xy 82.230004 -283.199172)
			(xy 82.194511 -283.233264) (xy 82.154008 -283.26122) (xy 82.109546 -283.282318) (xy 82.062275 -283.29601)
			(xy 82.01342 -283.301942) (xy 81.964245 -283.299961) (xy 81.916026 -283.290117) (xy 81.87001 -283.272665)
			(xy 81.827389 -283.248058) (xy 81.789268 -283.216933) (xy 81.756633 -283.180096) (xy 81.73033 -283.1385)
			(xy 81.711039 -283.093224) (xy 81.699262 -283.04544) (xy 81.695302 -282.996386) (xy 81.376774 -282.996386)
			(xy 81.376262 -283.021832) (xy 81.368098 -283.072066) (xy 81.351982 -283.12034) (xy 81.328331 -283.165403)
			(xy 81.297758 -283.206089) (xy 81.261054 -283.241344) (xy 81.21917 -283.270254) (xy 81.173191 -283.292071)
			(xy 81.124307 -283.306231) (xy 81.073786 -283.312365) (xy 81.022934 -283.310316) (xy 80.97307 -283.300136)
			(xy 80.925484 -283.282089) (xy 80.88141 -283.256643) (xy 80.841988 -283.224456) (xy 80.80824 -283.186362)
			(xy 80.781039 -283.143348) (xy 80.761091 -283.096528) (xy 80.748912 -283.047114) (xy 80.744817 -282.996386)
			(xy 80.426306 -282.996386) (xy 80.425811 -283.020993) (xy 80.417916 -283.06957) (xy 80.402332 -283.116251)
			(xy 80.379461 -283.159828) (xy 80.349896 -283.199172) (xy 80.314403 -283.233264) (xy 80.2739 -283.26122)
			(xy 80.229438 -283.282318) (xy 80.182167 -283.29601) (xy 80.133312 -283.301942) (xy 80.084137 -283.299961)
			(xy 80.035918 -283.290117) (xy 79.989902 -283.272665) (xy 79.947281 -283.248058) (xy 79.90916 -283.216933)
			(xy 79.876525 -283.180096) (xy 79.850222 -283.1385) (xy 79.830931 -283.093224) (xy 79.819154 -283.04544)
			(xy 79.815194 -282.996386) (xy 77.263451 -282.996386) (xy 77.221316 -283.01638) (xy 77.174045 -283.030072)
			(xy 77.12519 -283.036004) (xy 77.076015 -283.034023) (xy 77.027796 -283.024179) (xy 76.98178 -283.006727)
			(xy 76.939159 -282.98212) (xy 76.901038 -282.950995) (xy 76.868403 -282.914158) (xy 76.8421 -282.872562)
			(xy 76.822809 -282.827286) (xy 76.811032 -282.779502) (xy 76.807072 -282.730448) (xy 73.228962 -282.730448)
			(xy 73.228962 -283.806392) (xy 78.40524 -283.806392) (xy 78.4092 -283.757338) (xy 78.420977 -283.709554)
			(xy 78.440268 -283.664278) (xy 78.466571 -283.622682) (xy 78.499206 -283.585845) (xy 78.537327 -283.55472)
			(xy 78.579948 -283.530113) (xy 78.625964 -283.512661) (xy 78.674183 -283.502817) (xy 78.723358 -283.500836)
			(xy 78.772213 -283.506768) (xy 78.819484 -283.52046) (xy 78.863946 -283.541558) (xy 78.904449 -283.569514)
			(xy 78.939942 -283.603606) (xy 78.969507 -283.64295) (xy 78.992378 -283.686527) (xy 79.007962 -283.733208)
			(xy 79.015857 -283.781785) (xy 79.016352 -283.806392) (xy 80.285348 -283.806392) (xy 80.289308 -283.757338)
			(xy 80.301085 -283.709554) (xy 80.320376 -283.664278) (xy 80.346679 -283.622682) (xy 80.379314 -283.585845)
			(xy 80.417435 -283.55472) (xy 80.460056 -283.530113) (xy 80.506072 -283.512661) (xy 80.554291 -283.502817)
			(xy 80.603466 -283.500836) (xy 80.652321 -283.506768) (xy 80.699592 -283.52046) (xy 80.744054 -283.541558)
			(xy 80.784557 -283.569514) (xy 80.82005 -283.603606) (xy 80.849615 -283.64295) (xy 80.872486 -283.686527)
			(xy 80.88807 -283.733208) (xy 80.895965 -283.781785) (xy 80.89646 -283.806392) (xy 81.214717 -283.806392)
			(xy 81.218812 -283.755664) (xy 81.230991 -283.70625) (xy 81.250939 -283.65943) (xy 81.27814 -283.616416)
			(xy 81.311888 -283.578322) (xy 81.35131 -283.546135) (xy 81.395384 -283.520689) (xy 81.44297 -283.502642)
			(xy 81.492834 -283.492462) (xy 81.543686 -283.490413) (xy 81.594207 -283.496547) (xy 81.643091 -283.510707)
			(xy 81.68907 -283.532524) (xy 81.730954 -283.561434) (xy 81.767658 -283.596689) (xy 81.798231 -283.637375)
			(xy 81.821882 -283.682438) (xy 81.837998 -283.730712) (xy 81.846162 -283.780946) (xy 81.846674 -283.806392)
			(xy 82.154771 -283.806392) (xy 82.158866 -283.755664) (xy 82.171045 -283.70625) (xy 82.190993 -283.65943)
			(xy 82.218194 -283.616416) (xy 82.251942 -283.578322) (xy 82.291364 -283.546135) (xy 82.335438 -283.520689)
			(xy 82.383024 -283.502642) (xy 82.432888 -283.492462) (xy 82.48374 -283.490413) (xy 82.534261 -283.496547)
			(xy 82.583145 -283.510707) (xy 82.629124 -283.532524) (xy 82.671008 -283.561434) (xy 82.707712 -283.596689)
			(xy 82.738285 -283.637375) (xy 82.761936 -283.682438) (xy 82.778052 -283.730712) (xy 82.786216 -283.780946)
			(xy 82.786728 -283.806392) (xy 83.105256 -283.806392) (xy 83.109216 -283.757338) (xy 83.120993 -283.709554)
			(xy 83.140284 -283.664278) (xy 83.166587 -283.622682) (xy 83.199222 -283.585845) (xy 83.237343 -283.55472)
			(xy 83.279964 -283.530113) (xy 83.32598 -283.512661) (xy 83.374199 -283.502817) (xy 83.423374 -283.500836)
			(xy 83.472229 -283.506768) (xy 83.5195 -283.52046) (xy 83.563962 -283.541558) (xy 83.604465 -283.569514)
			(xy 83.639958 -283.603606) (xy 83.669523 -283.64295) (xy 83.692394 -283.686527) (xy 83.707978 -283.733208)
			(xy 83.715873 -283.781785) (xy 83.716368 -283.806392) (xy 84.034879 -283.806392) (xy 84.038974 -283.755664)
			(xy 84.051153 -283.70625) (xy 84.071101 -283.65943) (xy 84.098302 -283.616416) (xy 84.13205 -283.578322)
			(xy 84.171472 -283.546135) (xy 84.215546 -283.520689) (xy 84.263132 -283.502642) (xy 84.312996 -283.492462)
			(xy 84.363848 -283.490413) (xy 84.414369 -283.496547) (xy 84.463253 -283.510707) (xy 84.509232 -283.532524)
			(xy 84.551116 -283.561434) (xy 84.58782 -283.596689) (xy 84.618393 -283.637375) (xy 84.642044 -283.682438)
			(xy 84.65816 -283.730712) (xy 84.666324 -283.780946) (xy 84.666836 -283.806392) (xy 84.98511 -283.806392)
			(xy 84.98907 -283.757338) (xy 85.000847 -283.709554) (xy 85.020138 -283.664278) (xy 85.046441 -283.622682)
			(xy 85.079076 -283.585845) (xy 85.117197 -283.55472) (xy 85.159818 -283.530113) (xy 85.205834 -283.512661)
			(xy 85.254053 -283.502817) (xy 85.303228 -283.500836) (xy 85.352083 -283.506768) (xy 85.399354 -283.52046)
			(xy 85.443816 -283.541558) (xy 85.484319 -283.569514) (xy 85.519812 -283.603606) (xy 85.549377 -283.64295)
			(xy 85.572248 -283.686527) (xy 85.587832 -283.733208) (xy 85.595727 -283.781785) (xy 85.596222 -283.806392)
			(xy 85.914733 -283.806392) (xy 85.918828 -283.755664) (xy 85.931007 -283.70625) (xy 85.950955 -283.65943)
			(xy 85.978156 -283.616416) (xy 86.011904 -283.578322) (xy 86.051326 -283.546135) (xy 86.0954 -283.520689)
			(xy 86.142986 -283.502642) (xy 86.19285 -283.492462) (xy 86.243702 -283.490413) (xy 86.294223 -283.496547)
			(xy 86.343107 -283.510707) (xy 86.389086 -283.532524) (xy 86.43097 -283.561434) (xy 86.467674 -283.596689)
			(xy 86.498247 -283.637375) (xy 86.521898 -283.682438) (xy 86.538014 -283.730712) (xy 86.546178 -283.780946)
			(xy 86.54669 -283.806392) (xy 86.865218 -283.806392) (xy 86.869178 -283.757338) (xy 86.880955 -283.709554)
			(xy 86.900246 -283.664278) (xy 86.926549 -283.622682) (xy 86.959184 -283.585845) (xy 86.997305 -283.55472)
			(xy 87.039926 -283.530113) (xy 87.085942 -283.512661) (xy 87.134161 -283.502817) (xy 87.183336 -283.500836)
			(xy 87.232191 -283.506768) (xy 87.279462 -283.52046) (xy 87.323924 -283.541558) (xy 87.364427 -283.569514)
			(xy 87.39992 -283.603606) (xy 87.429485 -283.64295) (xy 87.452356 -283.686527) (xy 87.46794 -283.733208)
			(xy 87.475835 -283.781785) (xy 87.47633 -283.806392) (xy 87.794841 -283.806392) (xy 87.798936 -283.755664)
			(xy 87.811115 -283.70625) (xy 87.831063 -283.65943) (xy 87.858264 -283.616416) (xy 87.892012 -283.578322)
			(xy 87.931434 -283.546135) (xy 87.975508 -283.520689) (xy 88.023094 -283.502642) (xy 88.072958 -283.492462)
			(xy 88.12381 -283.490413) (xy 88.174331 -283.496547) (xy 88.223215 -283.510707) (xy 88.269194 -283.532524)
			(xy 88.311078 -283.561434) (xy 88.347782 -283.596689) (xy 88.378355 -283.637375) (xy 88.402006 -283.682438)
			(xy 88.418122 -283.730712) (xy 88.426286 -283.780946) (xy 88.426798 -283.806392) (xy 88.734895 -283.806392)
			(xy 88.73899 -283.755664) (xy 88.751169 -283.70625) (xy 88.771117 -283.65943) (xy 88.798318 -283.616416)
			(xy 88.832066 -283.578322) (xy 88.871488 -283.546135) (xy 88.915562 -283.520689) (xy 88.963148 -283.502642)
			(xy 89.013012 -283.492462) (xy 89.063864 -283.490413) (xy 89.114385 -283.496547) (xy 89.163269 -283.510707)
			(xy 89.209248 -283.532524) (xy 89.251132 -283.561434) (xy 89.287836 -283.596689) (xy 89.318409 -283.637375)
			(xy 89.34206 -283.682438) (xy 89.358176 -283.730712) (xy 89.36634 -283.780946) (xy 89.366852 -283.806392)
			(xy 89.685126 -283.806392) (xy 89.689086 -283.757338) (xy 89.700863 -283.709554) (xy 89.720154 -283.664278)
			(xy 89.746457 -283.622682) (xy 89.779092 -283.585845) (xy 89.817213 -283.55472) (xy 89.859834 -283.530113)
			(xy 89.90585 -283.512661) (xy 89.954069 -283.502817) (xy 90.003244 -283.500836) (xy 90.052099 -283.506768)
			(xy 90.09937 -283.52046) (xy 90.143832 -283.541558) (xy 90.184335 -283.569514) (xy 90.219828 -283.603606)
			(xy 90.249393 -283.64295) (xy 90.272264 -283.686527) (xy 90.287848 -283.733208) (xy 90.295743 -283.781785)
			(xy 90.296238 -283.806392) (xy 90.614749 -283.806392) (xy 90.618844 -283.755664) (xy 90.631023 -283.70625)
			(xy 90.650971 -283.65943) (xy 90.678172 -283.616416) (xy 90.71192 -283.578322) (xy 90.751342 -283.546135)
			(xy 90.795416 -283.520689) (xy 90.843002 -283.502642) (xy 90.892866 -283.492462) (xy 90.943718 -283.490413)
			(xy 90.994239 -283.496547) (xy 91.043123 -283.510707) (xy 91.089102 -283.532524) (xy 91.130986 -283.561434)
			(xy 91.16769 -283.596689) (xy 91.198263 -283.637375) (xy 91.221914 -283.682438) (xy 91.23803 -283.730712)
			(xy 91.246194 -283.780946) (xy 91.246706 -283.806392) (xy 91.565234 -283.806392) (xy 91.569194 -283.757338)
			(xy 91.580971 -283.709554) (xy 91.600262 -283.664278) (xy 91.626565 -283.622682) (xy 91.6592 -283.585845)
			(xy 91.697321 -283.55472) (xy 91.739942 -283.530113) (xy 91.785958 -283.512661) (xy 91.834177 -283.502817)
			(xy 91.883352 -283.500836) (xy 91.932207 -283.506768) (xy 91.979478 -283.52046) (xy 92.02394 -283.541558)
			(xy 92.064443 -283.569514) (xy 92.099936 -283.603606) (xy 92.129501 -283.64295) (xy 92.152372 -283.686527)
			(xy 92.167956 -283.733208) (xy 92.175851 -283.781785) (xy 92.176346 -283.806392) (xy 92.494857 -283.806392)
			(xy 92.498952 -283.755664) (xy 92.511131 -283.70625) (xy 92.531079 -283.65943) (xy 92.55828 -283.616416)
			(xy 92.592028 -283.578322) (xy 92.63145 -283.546135) (xy 92.675524 -283.520689) (xy 92.72311 -283.502642)
			(xy 92.772974 -283.492462) (xy 92.823826 -283.490413) (xy 92.874347 -283.496547) (xy 92.923231 -283.510707)
			(xy 92.96921 -283.532524) (xy 93.011094 -283.561434) (xy 93.047798 -283.596689) (xy 93.078371 -283.637375)
			(xy 93.102022 -283.682438) (xy 93.118138 -283.730712) (xy 93.126302 -283.780946) (xy 93.126814 -283.806392)
			(xy 93.445342 -283.806392) (xy 93.449302 -283.757338) (xy 93.461079 -283.709554) (xy 93.48037 -283.664278)
			(xy 93.506673 -283.622682) (xy 93.539308 -283.585845) (xy 93.577429 -283.55472) (xy 93.62005 -283.530113)
			(xy 93.666066 -283.512661) (xy 93.714285 -283.502817) (xy 93.76346 -283.500836) (xy 93.812315 -283.506768)
			(xy 93.859586 -283.52046) (xy 93.904048 -283.541558) (xy 93.944551 -283.569514) (xy 93.980044 -283.603606)
			(xy 94.009609 -283.64295) (xy 94.03248 -283.686527) (xy 94.048064 -283.733208) (xy 94.055959 -283.781785)
			(xy 94.056454 -283.806392) (xy 94.374711 -283.806392) (xy 94.378806 -283.755664) (xy 94.390985 -283.70625)
			(xy 94.410933 -283.65943) (xy 94.438134 -283.616416) (xy 94.471882 -283.578322) (xy 94.511304 -283.546135)
			(xy 94.555378 -283.520689) (xy 94.602964 -283.502642) (xy 94.652828 -283.492462) (xy 94.70368 -283.490413)
			(xy 94.754201 -283.496547) (xy 94.803085 -283.510707) (xy 94.849064 -283.532524) (xy 94.890948 -283.561434)
			(xy 94.927652 -283.596689) (xy 94.958225 -283.637375) (xy 94.981876 -283.682438) (xy 94.997992 -283.730712)
			(xy 95.006156 -283.780946) (xy 95.006668 -283.806392) (xy 95.314765 -283.806392) (xy 95.31886 -283.755664)
			(xy 95.331039 -283.70625) (xy 95.350987 -283.65943) (xy 95.378188 -283.616416) (xy 95.411936 -283.578322)
			(xy 95.451358 -283.546135) (xy 95.495432 -283.520689) (xy 95.543018 -283.502642) (xy 95.592882 -283.492462)
			(xy 95.643734 -283.490413) (xy 95.694255 -283.496547) (xy 95.743139 -283.510707) (xy 95.789118 -283.532524)
			(xy 95.831002 -283.561434) (xy 95.867706 -283.596689) (xy 95.898279 -283.637375) (xy 95.92193 -283.682438)
			(xy 95.938046 -283.730712) (xy 95.94621 -283.780946) (xy 95.946722 -283.806392) (xy 96.26525 -283.806392)
			(xy 96.26921 -283.757338) (xy 96.280987 -283.709554) (xy 96.300278 -283.664278) (xy 96.326581 -283.622682)
			(xy 96.359216 -283.585845) (xy 96.397337 -283.55472) (xy 96.439958 -283.530113) (xy 96.485974 -283.512661)
			(xy 96.534193 -283.502817) (xy 96.583368 -283.500836) (xy 96.632223 -283.506768) (xy 96.679494 -283.52046)
			(xy 96.723956 -283.541558) (xy 96.764459 -283.569514) (xy 96.799952 -283.603606) (xy 96.829517 -283.64295)
			(xy 96.852388 -283.686527) (xy 96.867972 -283.733208) (xy 96.875867 -283.781785) (xy 96.876362 -283.806392)
			(xy 99.085158 -283.806392) (xy 99.089118 -283.757338) (xy 99.100895 -283.709554) (xy 99.120186 -283.664278)
			(xy 99.146489 -283.622682) (xy 99.179124 -283.585845) (xy 99.217245 -283.55472) (xy 99.259866 -283.530113)
			(xy 99.305882 -283.512661) (xy 99.354101 -283.502817) (xy 99.403276 -283.500836) (xy 99.452131 -283.506768)
			(xy 99.499402 -283.52046) (xy 99.543864 -283.541558) (xy 99.584367 -283.569514) (xy 99.61986 -283.603606)
			(xy 99.649425 -283.64295) (xy 99.672296 -283.686527) (xy 99.68788 -283.733208) (xy 99.695775 -283.781785)
			(xy 99.69627 -283.806392) (xy 101.90532 -283.806392) (xy 101.90928 -283.757338) (xy 101.921057 -283.709554)
			(xy 101.940348 -283.664278) (xy 101.966651 -283.622682) (xy 101.999286 -283.585845) (xy 102.037407 -283.55472)
			(xy 102.080028 -283.530113) (xy 102.126044 -283.512661) (xy 102.174263 -283.502817) (xy 102.223438 -283.500836)
			(xy 102.272293 -283.506768) (xy 102.319564 -283.52046) (xy 102.364026 -283.541558) (xy 102.404529 -283.569514)
			(xy 102.440022 -283.603606) (xy 102.469587 -283.64295) (xy 102.492458 -283.686527) (xy 102.508042 -283.733208)
			(xy 102.515937 -283.781785) (xy 102.516432 -283.806392) (xy 102.515937 -283.830999) (xy 102.508042 -283.879576)
			(xy 102.492458 -283.926257) (xy 102.469587 -283.969834) (xy 102.440022 -284.009178) (xy 102.404529 -284.04327)
			(xy 102.364026 -284.071226) (xy 102.319564 -284.092324) (xy 102.272293 -284.106016) (xy 102.223438 -284.111948)
			(xy 102.174263 -284.109967) (xy 102.126044 -284.100123) (xy 102.080028 -284.082671) (xy 102.037407 -284.058064)
			(xy 101.999286 -284.026939) (xy 101.966651 -283.990102) (xy 101.940348 -283.948506) (xy 101.921057 -283.90323)
			(xy 101.90928 -283.855446) (xy 101.90532 -283.806392) (xy 99.69627 -283.806392) (xy 99.695775 -283.830999)
			(xy 99.68788 -283.879576) (xy 99.672296 -283.926257) (xy 99.649425 -283.969834) (xy 99.61986 -284.009178)
			(xy 99.584367 -284.04327) (xy 99.543864 -284.071226) (xy 99.499402 -284.092324) (xy 99.452131 -284.106016)
			(xy 99.403276 -284.111948) (xy 99.354101 -284.109967) (xy 99.305882 -284.100123) (xy 99.259866 -284.082671)
			(xy 99.217245 -284.058064) (xy 99.179124 -284.026939) (xy 99.146489 -283.990102) (xy 99.120186 -283.948506)
			(xy 99.100895 -283.90323) (xy 99.089118 -283.855446) (xy 99.085158 -283.806392) (xy 96.876362 -283.806392)
			(xy 96.875867 -283.830999) (xy 96.867972 -283.879576) (xy 96.852388 -283.926257) (xy 96.829517 -283.969834)
			(xy 96.799952 -284.009178) (xy 96.764459 -284.04327) (xy 96.723956 -284.071226) (xy 96.679494 -284.092324)
			(xy 96.632223 -284.106016) (xy 96.583368 -284.111948) (xy 96.534193 -284.109967) (xy 96.485974 -284.100123)
			(xy 96.439958 -284.082671) (xy 96.397337 -284.058064) (xy 96.359216 -284.026939) (xy 96.326581 -283.990102)
			(xy 96.300278 -283.948506) (xy 96.280987 -283.90323) (xy 96.26921 -283.855446) (xy 96.26525 -283.806392)
			(xy 95.946722 -283.806392) (xy 95.94621 -283.831838) (xy 95.938046 -283.882072) (xy 95.92193 -283.930346)
			(xy 95.898279 -283.975409) (xy 95.867706 -284.016095) (xy 95.831002 -284.05135) (xy 95.789118 -284.08026)
			(xy 95.743139 -284.102077) (xy 95.694255 -284.116237) (xy 95.643734 -284.122371) (xy 95.592882 -284.120322)
			(xy 95.543018 -284.110142) (xy 95.495432 -284.092095) (xy 95.451358 -284.066649) (xy 95.411936 -284.034462)
			(xy 95.378188 -283.996368) (xy 95.350987 -283.953354) (xy 95.331039 -283.906534) (xy 95.31886 -283.85712)
			(xy 95.314765 -283.806392) (xy 95.006668 -283.806392) (xy 95.006156 -283.831838) (xy 94.997992 -283.882072)
			(xy 94.981876 -283.930346) (xy 94.958225 -283.975409) (xy 94.927652 -284.016095) (xy 94.890948 -284.05135)
			(xy 94.849064 -284.08026) (xy 94.803085 -284.102077) (xy 94.754201 -284.116237) (xy 94.70368 -284.122371)
			(xy 94.652828 -284.120322) (xy 94.602964 -284.110142) (xy 94.555378 -284.092095) (xy 94.511304 -284.066649)
			(xy 94.471882 -284.034462) (xy 94.438134 -283.996368) (xy 94.410933 -283.953354) (xy 94.390985 -283.906534)
			(xy 94.378806 -283.85712) (xy 94.374711 -283.806392) (xy 94.056454 -283.806392) (xy 94.055959 -283.830999)
			(xy 94.048064 -283.879576) (xy 94.03248 -283.926257) (xy 94.009609 -283.969834) (xy 93.980044 -284.009178)
			(xy 93.944551 -284.04327) (xy 93.904048 -284.071226) (xy 93.859586 -284.092324) (xy 93.812315 -284.106016)
			(xy 93.76346 -284.111948) (xy 93.714285 -284.109967) (xy 93.666066 -284.100123) (xy 93.62005 -284.082671)
			(xy 93.577429 -284.058064) (xy 93.539308 -284.026939) (xy 93.506673 -283.990102) (xy 93.48037 -283.948506)
			(xy 93.461079 -283.90323) (xy 93.449302 -283.855446) (xy 93.445342 -283.806392) (xy 93.126814 -283.806392)
			(xy 93.126302 -283.831838) (xy 93.118138 -283.882072) (xy 93.102022 -283.930346) (xy 93.078371 -283.975409)
			(xy 93.047798 -284.016095) (xy 93.011094 -284.05135) (xy 92.96921 -284.08026) (xy 92.923231 -284.102077)
			(xy 92.874347 -284.116237) (xy 92.823826 -284.122371) (xy 92.772974 -284.120322) (xy 92.72311 -284.110142)
			(xy 92.675524 -284.092095) (xy 92.63145 -284.066649) (xy 92.592028 -284.034462) (xy 92.55828 -283.996368)
			(xy 92.531079 -283.953354) (xy 92.511131 -283.906534) (xy 92.498952 -283.85712) (xy 92.494857 -283.806392)
			(xy 92.176346 -283.806392) (xy 92.175851 -283.830999) (xy 92.167956 -283.879576) (xy 92.152372 -283.926257)
			(xy 92.129501 -283.969834) (xy 92.099936 -284.009178) (xy 92.064443 -284.04327) (xy 92.02394 -284.071226)
			(xy 91.979478 -284.092324) (xy 91.932207 -284.106016) (xy 91.883352 -284.111948) (xy 91.834177 -284.109967)
			(xy 91.785958 -284.100123) (xy 91.739942 -284.082671) (xy 91.697321 -284.058064) (xy 91.6592 -284.026939)
			(xy 91.626565 -283.990102) (xy 91.600262 -283.948506) (xy 91.580971 -283.90323) (xy 91.569194 -283.855446)
			(xy 91.565234 -283.806392) (xy 91.246706 -283.806392) (xy 91.246194 -283.831838) (xy 91.23803 -283.882072)
			(xy 91.221914 -283.930346) (xy 91.198263 -283.975409) (xy 91.16769 -284.016095) (xy 91.130986 -284.05135)
			(xy 91.089102 -284.08026) (xy 91.043123 -284.102077) (xy 90.994239 -284.116237) (xy 90.943718 -284.122371)
			(xy 90.892866 -284.120322) (xy 90.843002 -284.110142) (xy 90.795416 -284.092095) (xy 90.751342 -284.066649)
			(xy 90.71192 -284.034462) (xy 90.678172 -283.996368) (xy 90.650971 -283.953354) (xy 90.631023 -283.906534)
			(xy 90.618844 -283.85712) (xy 90.614749 -283.806392) (xy 90.296238 -283.806392) (xy 90.295743 -283.830999)
			(xy 90.287848 -283.879576) (xy 90.272264 -283.926257) (xy 90.249393 -283.969834) (xy 90.219828 -284.009178)
			(xy 90.184335 -284.04327) (xy 90.143832 -284.071226) (xy 90.09937 -284.092324) (xy 90.052099 -284.106016)
			(xy 90.003244 -284.111948) (xy 89.954069 -284.109967) (xy 89.90585 -284.100123) (xy 89.859834 -284.082671)
			(xy 89.817213 -284.058064) (xy 89.779092 -284.026939) (xy 89.746457 -283.990102) (xy 89.720154 -283.948506)
			(xy 89.700863 -283.90323) (xy 89.689086 -283.855446) (xy 89.685126 -283.806392) (xy 89.366852 -283.806392)
			(xy 89.36634 -283.831838) (xy 89.358176 -283.882072) (xy 89.34206 -283.930346) (xy 89.318409 -283.975409)
			(xy 89.287836 -284.016095) (xy 89.251132 -284.05135) (xy 89.209248 -284.08026) (xy 89.163269 -284.102077)
			(xy 89.114385 -284.116237) (xy 89.063864 -284.122371) (xy 89.013012 -284.120322) (xy 88.963148 -284.110142)
			(xy 88.915562 -284.092095) (xy 88.871488 -284.066649) (xy 88.832066 -284.034462) (xy 88.798318 -283.996368)
			(xy 88.771117 -283.953354) (xy 88.751169 -283.906534) (xy 88.73899 -283.85712) (xy 88.734895 -283.806392)
			(xy 88.426798 -283.806392) (xy 88.426286 -283.831838) (xy 88.418122 -283.882072) (xy 88.402006 -283.930346)
			(xy 88.378355 -283.975409) (xy 88.347782 -284.016095) (xy 88.311078 -284.05135) (xy 88.269194 -284.08026)
			(xy 88.223215 -284.102077) (xy 88.174331 -284.116237) (xy 88.12381 -284.122371) (xy 88.072958 -284.120322)
			(xy 88.023094 -284.110142) (xy 87.975508 -284.092095) (xy 87.931434 -284.066649) (xy 87.892012 -284.034462)
			(xy 87.858264 -283.996368) (xy 87.831063 -283.953354) (xy 87.811115 -283.906534) (xy 87.798936 -283.85712)
			(xy 87.794841 -283.806392) (xy 87.47633 -283.806392) (xy 87.475835 -283.830999) (xy 87.46794 -283.879576)
			(xy 87.452356 -283.926257) (xy 87.429485 -283.969834) (xy 87.39992 -284.009178) (xy 87.364427 -284.04327)
			(xy 87.323924 -284.071226) (xy 87.279462 -284.092324) (xy 87.232191 -284.106016) (xy 87.183336 -284.111948)
			(xy 87.134161 -284.109967) (xy 87.085942 -284.100123) (xy 87.039926 -284.082671) (xy 86.997305 -284.058064)
			(xy 86.959184 -284.026939) (xy 86.926549 -283.990102) (xy 86.900246 -283.948506) (xy 86.880955 -283.90323)
			(xy 86.869178 -283.855446) (xy 86.865218 -283.806392) (xy 86.54669 -283.806392) (xy 86.546178 -283.831838)
			(xy 86.538014 -283.882072) (xy 86.521898 -283.930346) (xy 86.498247 -283.975409) (xy 86.467674 -284.016095)
			(xy 86.43097 -284.05135) (xy 86.389086 -284.08026) (xy 86.343107 -284.102077) (xy 86.294223 -284.116237)
			(xy 86.243702 -284.122371) (xy 86.19285 -284.120322) (xy 86.142986 -284.110142) (xy 86.0954 -284.092095)
			(xy 86.051326 -284.066649) (xy 86.011904 -284.034462) (xy 85.978156 -283.996368) (xy 85.950955 -283.953354)
			(xy 85.931007 -283.906534) (xy 85.918828 -283.85712) (xy 85.914733 -283.806392) (xy 85.596222 -283.806392)
			(xy 85.595727 -283.830999) (xy 85.587832 -283.879576) (xy 85.572248 -283.926257) (xy 85.549377 -283.969834)
			(xy 85.519812 -284.009178) (xy 85.484319 -284.04327) (xy 85.443816 -284.071226) (xy 85.399354 -284.092324)
			(xy 85.352083 -284.106016) (xy 85.303228 -284.111948) (xy 85.254053 -284.109967) (xy 85.205834 -284.100123)
			(xy 85.159818 -284.082671) (xy 85.117197 -284.058064) (xy 85.079076 -284.026939) (xy 85.046441 -283.990102)
			(xy 85.020138 -283.948506) (xy 85.000847 -283.90323) (xy 84.98907 -283.855446) (xy 84.98511 -283.806392)
			(xy 84.666836 -283.806392) (xy 84.666324 -283.831838) (xy 84.65816 -283.882072) (xy 84.642044 -283.930346)
			(xy 84.618393 -283.975409) (xy 84.58782 -284.016095) (xy 84.551116 -284.05135) (xy 84.509232 -284.08026)
			(xy 84.463253 -284.102077) (xy 84.414369 -284.116237) (xy 84.363848 -284.122371) (xy 84.312996 -284.120322)
			(xy 84.263132 -284.110142) (xy 84.215546 -284.092095) (xy 84.171472 -284.066649) (xy 84.13205 -284.034462)
			(xy 84.098302 -283.996368) (xy 84.071101 -283.953354) (xy 84.051153 -283.906534) (xy 84.038974 -283.85712)
			(xy 84.034879 -283.806392) (xy 83.716368 -283.806392) (xy 83.715873 -283.830999) (xy 83.707978 -283.879576)
			(xy 83.692394 -283.926257) (xy 83.669523 -283.969834) (xy 83.639958 -284.009178) (xy 83.604465 -284.04327)
			(xy 83.563962 -284.071226) (xy 83.5195 -284.092324) (xy 83.472229 -284.106016) (xy 83.423374 -284.111948)
			(xy 83.374199 -284.109967) (xy 83.32598 -284.100123) (xy 83.279964 -284.082671) (xy 83.237343 -284.058064)
			(xy 83.199222 -284.026939) (xy 83.166587 -283.990102) (xy 83.140284 -283.948506) (xy 83.120993 -283.90323)
			(xy 83.109216 -283.855446) (xy 83.105256 -283.806392) (xy 82.786728 -283.806392) (xy 82.786216 -283.831838)
			(xy 82.778052 -283.882072) (xy 82.761936 -283.930346) (xy 82.738285 -283.975409) (xy 82.707712 -284.016095)
			(xy 82.671008 -284.05135) (xy 82.629124 -284.08026) (xy 82.583145 -284.102077) (xy 82.534261 -284.116237)
			(xy 82.48374 -284.122371) (xy 82.432888 -284.120322) (xy 82.383024 -284.110142) (xy 82.335438 -284.092095)
			(xy 82.291364 -284.066649) (xy 82.251942 -284.034462) (xy 82.218194 -283.996368) (xy 82.190993 -283.953354)
			(xy 82.171045 -283.906534) (xy 82.158866 -283.85712) (xy 82.154771 -283.806392) (xy 81.846674 -283.806392)
			(xy 81.846162 -283.831838) (xy 81.837998 -283.882072) (xy 81.821882 -283.930346) (xy 81.798231 -283.975409)
			(xy 81.767658 -284.016095) (xy 81.730954 -284.05135) (xy 81.68907 -284.08026) (xy 81.643091 -284.102077)
			(xy 81.594207 -284.116237) (xy 81.543686 -284.122371) (xy 81.492834 -284.120322) (xy 81.44297 -284.110142)
			(xy 81.395384 -284.092095) (xy 81.35131 -284.066649) (xy 81.311888 -284.034462) (xy 81.27814 -283.996368)
			(xy 81.250939 -283.953354) (xy 81.230991 -283.906534) (xy 81.218812 -283.85712) (xy 81.214717 -283.806392)
			(xy 80.89646 -283.806392) (xy 80.895965 -283.830999) (xy 80.88807 -283.879576) (xy 80.872486 -283.926257)
			(xy 80.849615 -283.969834) (xy 80.82005 -284.009178) (xy 80.784557 -284.04327) (xy 80.744054 -284.071226)
			(xy 80.699592 -284.092324) (xy 80.652321 -284.106016) (xy 80.603466 -284.111948) (xy 80.554291 -284.109967)
			(xy 80.506072 -284.100123) (xy 80.460056 -284.082671) (xy 80.417435 -284.058064) (xy 80.379314 -284.026939)
			(xy 80.346679 -283.990102) (xy 80.320376 -283.948506) (xy 80.301085 -283.90323) (xy 80.289308 -283.855446)
			(xy 80.285348 -283.806392) (xy 79.016352 -283.806392) (xy 79.015857 -283.830999) (xy 79.007962 -283.879576)
			(xy 78.992378 -283.926257) (xy 78.969507 -283.969834) (xy 78.939942 -284.009178) (xy 78.904449 -284.04327)
			(xy 78.863946 -284.071226) (xy 78.819484 -284.092324) (xy 78.772213 -284.106016) (xy 78.723358 -284.111948)
			(xy 78.674183 -284.109967) (xy 78.625964 -284.100123) (xy 78.579948 -284.082671) (xy 78.537327 -284.058064)
			(xy 78.499206 -284.026939) (xy 78.466571 -283.990102) (xy 78.440268 -283.948506) (xy 78.420977 -283.90323)
			(xy 78.4092 -283.855446) (xy 78.40524 -283.806392) (xy 73.228962 -283.806392) (xy 73.228962 -284.35046)
			(xy 76.807072 -284.35046) (xy 76.811032 -284.301406) (xy 76.822809 -284.253622) (xy 76.8421 -284.208346)
			(xy 76.868403 -284.16675) (xy 76.901038 -284.129913) (xy 76.939159 -284.098788) (xy 76.98178 -284.074181)
			(xy 77.027796 -284.056729) (xy 77.076015 -284.046885) (xy 77.12519 -284.044904) (xy 77.174045 -284.050836)
			(xy 77.221316 -284.064528) (xy 77.265778 -284.085626) (xy 77.306281 -284.113582) (xy 77.341774 -284.147674)
			(xy 77.371339 -284.187018) (xy 77.39421 -284.230595) (xy 77.409794 -284.277276) (xy 77.417689 -284.325853)
			(xy 77.418184 -284.35046) (xy 77.417689 -284.375067) (xy 77.409794 -284.423644) (xy 77.39421 -284.470325)
			(xy 77.371339 -284.513902) (xy 77.341774 -284.553246) (xy 77.306281 -284.587338) (xy 77.265778 -284.615294)
			(xy 77.263451 -284.616398) (xy 79.815194 -284.616398) (xy 79.819154 -284.567344) (xy 79.830931 -284.51956)
			(xy 79.850222 -284.474284) (xy 79.876525 -284.432688) (xy 79.90916 -284.395851) (xy 79.947281 -284.364726)
			(xy 79.989902 -284.340119) (xy 80.035918 -284.322667) (xy 80.084137 -284.312823) (xy 80.133312 -284.310842)
			(xy 80.182167 -284.316774) (xy 80.229438 -284.330466) (xy 80.2739 -284.351564) (xy 80.314403 -284.37952)
			(xy 80.349896 -284.413612) (xy 80.379461 -284.452956) (xy 80.402332 -284.496533) (xy 80.417916 -284.543214)
			(xy 80.425811 -284.591791) (xy 80.426306 -284.616398) (xy 80.744817 -284.616398) (xy 80.748912 -284.56567)
			(xy 80.761091 -284.516256) (xy 80.781039 -284.469436) (xy 80.80824 -284.426422) (xy 80.841988 -284.388328)
			(xy 80.88141 -284.356141) (xy 80.925484 -284.330695) (xy 80.97307 -284.312648) (xy 81.022934 -284.302468)
			(xy 81.073786 -284.300419) (xy 81.124307 -284.306553) (xy 81.173191 -284.320713) (xy 81.21917 -284.34253)
			(xy 81.261054 -284.37144) (xy 81.297758 -284.406695) (xy 81.328331 -284.447381) (xy 81.351982 -284.492444)
			(xy 81.368098 -284.540718) (xy 81.376262 -284.590952) (xy 81.376774 -284.616398) (xy 81.695302 -284.616398)
			(xy 81.699262 -284.567344) (xy 81.711039 -284.51956) (xy 81.73033 -284.474284) (xy 81.756633 -284.432688)
			(xy 81.789268 -284.395851) (xy 81.827389 -284.364726) (xy 81.87001 -284.340119) (xy 81.916026 -284.322667)
			(xy 81.964245 -284.312823) (xy 82.01342 -284.310842) (xy 82.062275 -284.316774) (xy 82.109546 -284.330466)
			(xy 82.154008 -284.351564) (xy 82.194511 -284.37952) (xy 82.230004 -284.413612) (xy 82.259569 -284.452956)
			(xy 82.28244 -284.496533) (xy 82.298024 -284.543214) (xy 82.305919 -284.591791) (xy 82.306414 -284.616398)
			(xy 82.624671 -284.616398) (xy 82.628766 -284.56567) (xy 82.640945 -284.516256) (xy 82.660893 -284.469436)
			(xy 82.688094 -284.426422) (xy 82.721842 -284.388328) (xy 82.761264 -284.356141) (xy 82.805338 -284.330695)
			(xy 82.852924 -284.312648) (xy 82.902788 -284.302468) (xy 82.95364 -284.300419) (xy 83.004161 -284.306553)
			(xy 83.053045 -284.320713) (xy 83.099024 -284.34253) (xy 83.140908 -284.37144) (xy 83.177612 -284.406695)
			(xy 83.208185 -284.447381) (xy 83.231836 -284.492444) (xy 83.247952 -284.540718) (xy 83.256116 -284.590952)
			(xy 83.256628 -284.616398) (xy 83.575156 -284.616398) (xy 83.579116 -284.567344) (xy 83.590893 -284.51956)
			(xy 83.610184 -284.474284) (xy 83.636487 -284.432688) (xy 83.669122 -284.395851) (xy 83.707243 -284.364726)
			(xy 83.749864 -284.340119) (xy 83.79588 -284.322667) (xy 83.844099 -284.312823) (xy 83.893274 -284.310842)
			(xy 83.942129 -284.316774) (xy 83.9894 -284.330466) (xy 84.033862 -284.351564) (xy 84.074365 -284.37952)
			(xy 84.109858 -284.413612) (xy 84.139423 -284.452956) (xy 84.162294 -284.496533) (xy 84.177878 -284.543214)
			(xy 84.185773 -284.591791) (xy 84.186268 -284.616398) (xy 84.504779 -284.616398) (xy 84.508874 -284.56567)
			(xy 84.521053 -284.516256) (xy 84.541001 -284.469436) (xy 84.568202 -284.426422) (xy 84.60195 -284.388328)
			(xy 84.641372 -284.356141) (xy 84.685446 -284.330695) (xy 84.733032 -284.312648) (xy 84.782896 -284.302468)
			(xy 84.833748 -284.300419) (xy 84.884269 -284.306553) (xy 84.933153 -284.320713) (xy 84.979132 -284.34253)
			(xy 85.021016 -284.37144) (xy 85.05772 -284.406695) (xy 85.088293 -284.447381) (xy 85.111944 -284.492444)
			(xy 85.12806 -284.540718) (xy 85.136224 -284.590952) (xy 85.136736 -284.616398) (xy 85.444833 -284.616398)
			(xy 85.448928 -284.56567) (xy 85.461107 -284.516256) (xy 85.481055 -284.469436) (xy 85.508256 -284.426422)
			(xy 85.542004 -284.388328) (xy 85.581426 -284.356141) (xy 85.6255 -284.330695) (xy 85.673086 -284.312648)
			(xy 85.72295 -284.302468) (xy 85.773802 -284.300419) (xy 85.824323 -284.306553) (xy 85.873207 -284.320713)
			(xy 85.919186 -284.34253) (xy 85.96107 -284.37144) (xy 85.997774 -284.406695) (xy 86.028347 -284.447381)
			(xy 86.051998 -284.492444) (xy 86.068114 -284.540718) (xy 86.076278 -284.590952) (xy 86.07679 -284.616398)
			(xy 86.395318 -284.616398) (xy 86.399278 -284.567344) (xy 86.411055 -284.51956) (xy 86.430346 -284.474284)
			(xy 86.456649 -284.432688) (xy 86.489284 -284.395851) (xy 86.527405 -284.364726) (xy 86.570026 -284.340119)
			(xy 86.616042 -284.322667) (xy 86.664261 -284.312823) (xy 86.713436 -284.310842) (xy 86.762291 -284.316774)
			(xy 86.809562 -284.330466) (xy 86.854024 -284.351564) (xy 86.894527 -284.37952) (xy 86.93002 -284.413612)
			(xy 86.959585 -284.452956) (xy 86.982456 -284.496533) (xy 86.99804 -284.543214) (xy 87.005935 -284.591791)
			(xy 87.00643 -284.616398) (xy 87.324687 -284.616398) (xy 87.328782 -284.56567) (xy 87.340961 -284.516256)
			(xy 87.360909 -284.469436) (xy 87.38811 -284.426422) (xy 87.421858 -284.388328) (xy 87.46128 -284.356141)
			(xy 87.505354 -284.330695) (xy 87.55294 -284.312648) (xy 87.602804 -284.302468) (xy 87.653656 -284.300419)
			(xy 87.704177 -284.306553) (xy 87.753061 -284.320713) (xy 87.79904 -284.34253) (xy 87.840924 -284.37144)
			(xy 87.877628 -284.406695) (xy 87.908201 -284.447381) (xy 87.931852 -284.492444) (xy 87.947968 -284.540718)
			(xy 87.956132 -284.590952) (xy 87.956644 -284.616398) (xy 88.275172 -284.616398) (xy 88.279132 -284.567344)
			(xy 88.290909 -284.51956) (xy 88.3102 -284.474284) (xy 88.336503 -284.432688) (xy 88.369138 -284.395851)
			(xy 88.407259 -284.364726) (xy 88.44988 -284.340119) (xy 88.495896 -284.322667) (xy 88.544115 -284.312823)
			(xy 88.59329 -284.310842) (xy 88.642145 -284.316774) (xy 88.689416 -284.330466) (xy 88.733878 -284.351564)
			(xy 88.774381 -284.37952) (xy 88.809874 -284.413612) (xy 88.839439 -284.452956) (xy 88.86231 -284.496533)
			(xy 88.877894 -284.543214) (xy 88.885789 -284.591791) (xy 88.886284 -284.616398) (xy 89.204795 -284.616398)
			(xy 89.20889 -284.56567) (xy 89.221069 -284.516256) (xy 89.241017 -284.469436) (xy 89.268218 -284.426422)
			(xy 89.301966 -284.388328) (xy 89.341388 -284.356141) (xy 89.385462 -284.330695) (xy 89.433048 -284.312648)
			(xy 89.482912 -284.302468) (xy 89.533764 -284.300419) (xy 89.584285 -284.306553) (xy 89.633169 -284.320713)
			(xy 89.679148 -284.34253) (xy 89.721032 -284.37144) (xy 89.757736 -284.406695) (xy 89.788309 -284.447381)
			(xy 89.81196 -284.492444) (xy 89.828076 -284.540718) (xy 89.83624 -284.590952) (xy 89.836752 -284.616398)
			(xy 90.15528 -284.616398) (xy 90.15924 -284.567344) (xy 90.171017 -284.51956) (xy 90.190308 -284.474284)
			(xy 90.216611 -284.432688) (xy 90.249246 -284.395851) (xy 90.287367 -284.364726) (xy 90.329988 -284.340119)
			(xy 90.376004 -284.322667) (xy 90.424223 -284.312823) (xy 90.473398 -284.310842) (xy 90.522253 -284.316774)
			(xy 90.569524 -284.330466) (xy 90.613986 -284.351564) (xy 90.654489 -284.37952) (xy 90.689982 -284.413612)
			(xy 90.719547 -284.452956) (xy 90.742418 -284.496533) (xy 90.758002 -284.543214) (xy 90.765897 -284.591791)
			(xy 90.766392 -284.616398) (xy 91.084903 -284.616398) (xy 91.088998 -284.56567) (xy 91.101177 -284.516256)
			(xy 91.121125 -284.469436) (xy 91.148326 -284.426422) (xy 91.182074 -284.388328) (xy 91.221496 -284.356141)
			(xy 91.26557 -284.330695) (xy 91.313156 -284.312648) (xy 91.36302 -284.302468) (xy 91.413872 -284.300419)
			(xy 91.464393 -284.306553) (xy 91.513277 -284.320713) (xy 91.559256 -284.34253) (xy 91.60114 -284.37144)
			(xy 91.637844 -284.406695) (xy 91.668417 -284.447381) (xy 91.692068 -284.492444) (xy 91.708184 -284.540718)
			(xy 91.716348 -284.590952) (xy 91.71686 -284.616398) (xy 92.024703 -284.616398) (xy 92.028798 -284.56567)
			(xy 92.040977 -284.516256) (xy 92.060925 -284.469436) (xy 92.088126 -284.426422) (xy 92.121874 -284.388328)
			(xy 92.161296 -284.356141) (xy 92.20537 -284.330695) (xy 92.252956 -284.312648) (xy 92.30282 -284.302468)
			(xy 92.353672 -284.300419) (xy 92.404193 -284.306553) (xy 92.453077 -284.320713) (xy 92.499056 -284.34253)
			(xy 92.54094 -284.37144) (xy 92.577644 -284.406695) (xy 92.608217 -284.447381) (xy 92.631868 -284.492444)
			(xy 92.647984 -284.540718) (xy 92.656148 -284.590952) (xy 92.65666 -284.616398) (xy 92.975188 -284.616398)
			(xy 92.979148 -284.567344) (xy 92.990925 -284.51956) (xy 93.010216 -284.474284) (xy 93.036519 -284.432688)
			(xy 93.069154 -284.395851) (xy 93.107275 -284.364726) (xy 93.149896 -284.340119) (xy 93.195912 -284.322667)
			(xy 93.244131 -284.312823) (xy 93.293306 -284.310842) (xy 93.342161 -284.316774) (xy 93.389432 -284.330466)
			(xy 93.433894 -284.351564) (xy 93.474397 -284.37952) (xy 93.50989 -284.413612) (xy 93.539455 -284.452956)
			(xy 93.562326 -284.496533) (xy 93.57791 -284.543214) (xy 93.585805 -284.591791) (xy 93.5863 -284.616398)
			(xy 93.904811 -284.616398) (xy 93.908906 -284.56567) (xy 93.921085 -284.516256) (xy 93.941033 -284.469436)
			(xy 93.968234 -284.426422) (xy 94.001982 -284.388328) (xy 94.041404 -284.356141) (xy 94.085478 -284.330695)
			(xy 94.133064 -284.312648) (xy 94.182928 -284.302468) (xy 94.23378 -284.300419) (xy 94.284301 -284.306553)
			(xy 94.333185 -284.320713) (xy 94.379164 -284.34253) (xy 94.421048 -284.37144) (xy 94.457752 -284.406695)
			(xy 94.488325 -284.447381) (xy 94.511976 -284.492444) (xy 94.528092 -284.540718) (xy 94.536256 -284.590952)
			(xy 94.536768 -284.616398) (xy 94.855296 -284.616398) (xy 94.859256 -284.567344) (xy 94.871033 -284.51956)
			(xy 94.890324 -284.474284) (xy 94.916627 -284.432688) (xy 94.949262 -284.395851) (xy 94.987383 -284.364726)
			(xy 95.030004 -284.340119) (xy 95.07602 -284.322667) (xy 95.124239 -284.312823) (xy 95.173414 -284.310842)
			(xy 95.222269 -284.316774) (xy 95.26954 -284.330466) (xy 95.314002 -284.351564) (xy 95.354505 -284.37952)
			(xy 95.389998 -284.413612) (xy 95.419563 -284.452956) (xy 95.442434 -284.496533) (xy 95.458018 -284.543214)
			(xy 95.465913 -284.591791) (xy 95.466408 -284.616398) (xy 95.784919 -284.616398) (xy 95.789014 -284.56567)
			(xy 95.801193 -284.516256) (xy 95.821141 -284.469436) (xy 95.848342 -284.426422) (xy 95.88209 -284.388328)
			(xy 95.921512 -284.356141) (xy 95.965586 -284.330695) (xy 96.013172 -284.312648) (xy 96.063036 -284.302468)
			(xy 96.113888 -284.300419) (xy 96.164409 -284.306553) (xy 96.213293 -284.320713) (xy 96.259272 -284.34253)
			(xy 96.301156 -284.37144) (xy 96.33786 -284.406695) (xy 96.368433 -284.447381) (xy 96.392084 -284.492444)
			(xy 96.4082 -284.540718) (xy 96.416364 -284.590952) (xy 96.416876 -284.616398) (xy 96.73515 -284.616398)
			(xy 96.73911 -284.567344) (xy 96.750887 -284.51956) (xy 96.770178 -284.474284) (xy 96.796481 -284.432688)
			(xy 96.829116 -284.395851) (xy 96.867237 -284.364726) (xy 96.909858 -284.340119) (xy 96.955874 -284.322667)
			(xy 97.004093 -284.312823) (xy 97.053268 -284.310842) (xy 97.102123 -284.316774) (xy 97.149394 -284.330466)
			(xy 97.193856 -284.351564) (xy 97.234359 -284.37952) (xy 97.269852 -284.413612) (xy 97.299417 -284.452956)
			(xy 97.322288 -284.496533) (xy 97.337872 -284.543214) (xy 97.345767 -284.591791) (xy 97.346262 -284.616398)
			(xy 97.664773 -284.616398) (xy 97.668868 -284.56567) (xy 97.681047 -284.516256) (xy 97.700995 -284.469436)
			(xy 97.728196 -284.426422) (xy 97.761944 -284.388328) (xy 97.801366 -284.356141) (xy 97.84544 -284.330695)
			(xy 97.893026 -284.312648) (xy 97.94289 -284.302468) (xy 97.993742 -284.300419) (xy 98.044263 -284.306553)
			(xy 98.093147 -284.320713) (xy 98.139126 -284.34253) (xy 98.18101 -284.37144) (xy 98.217714 -284.406695)
			(xy 98.248287 -284.447381) (xy 98.271938 -284.492444) (xy 98.288054 -284.540718) (xy 98.296218 -284.590952)
			(xy 98.29673 -284.616398) (xy 98.604827 -284.616398) (xy 98.608922 -284.56567) (xy 98.621101 -284.516256)
			(xy 98.641049 -284.469436) (xy 98.66825 -284.426422) (xy 98.701998 -284.388328) (xy 98.74142 -284.356141)
			(xy 98.785494 -284.330695) (xy 98.83308 -284.312648) (xy 98.882944 -284.302468) (xy 98.933796 -284.300419)
			(xy 98.984317 -284.306553) (xy 99.033201 -284.320713) (xy 99.07918 -284.34253) (xy 99.121064 -284.37144)
			(xy 99.157768 -284.406695) (xy 99.188341 -284.447381) (xy 99.211992 -284.492444) (xy 99.228108 -284.540718)
			(xy 99.236272 -284.590952) (xy 99.236784 -284.616398) (xy 99.555312 -284.616398) (xy 99.559272 -284.567344)
			(xy 99.571049 -284.51956) (xy 99.59034 -284.474284) (xy 99.616643 -284.432688) (xy 99.649278 -284.395851)
			(xy 99.687399 -284.364726) (xy 99.73002 -284.340119) (xy 99.776036 -284.322667) (xy 99.824255 -284.312823)
			(xy 99.87343 -284.310842) (xy 99.922285 -284.316774) (xy 99.969556 -284.330466) (xy 100.014018 -284.351564)
			(xy 100.054521 -284.37952) (xy 100.090014 -284.413612) (xy 100.119579 -284.452956) (xy 100.14245 -284.496533)
			(xy 100.158034 -284.543214) (xy 100.165929 -284.591791) (xy 100.166424 -284.616398) (xy 100.484935 -284.616398)
			(xy 100.48903 -284.56567) (xy 100.501209 -284.516256) (xy 100.521157 -284.469436) (xy 100.548358 -284.426422)
			(xy 100.582106 -284.388328) (xy 100.621528 -284.356141) (xy 100.665602 -284.330695) (xy 100.713188 -284.312648)
			(xy 100.763052 -284.302468) (xy 100.813904 -284.300419) (xy 100.864425 -284.306553) (xy 100.913309 -284.320713)
			(xy 100.959288 -284.34253) (xy 101.001172 -284.37144) (xy 101.037876 -284.406695) (xy 101.068449 -284.447381)
			(xy 101.0921 -284.492444) (xy 101.108216 -284.540718) (xy 101.11638 -284.590952) (xy 101.116892 -284.616398)
			(xy 101.424735 -284.616398) (xy 101.42883 -284.56567) (xy 101.441009 -284.516256) (xy 101.460957 -284.469436)
			(xy 101.488158 -284.426422) (xy 101.521906 -284.388328) (xy 101.561328 -284.356141) (xy 101.605402 -284.330695)
			(xy 101.652988 -284.312648) (xy 101.702852 -284.302468) (xy 101.753704 -284.300419) (xy 101.804225 -284.306553)
			(xy 101.853109 -284.320713) (xy 101.899088 -284.34253) (xy 101.940972 -284.37144) (xy 101.977676 -284.406695)
			(xy 102.008249 -284.447381) (xy 102.0319 -284.492444) (xy 102.048016 -284.540718) (xy 102.05618 -284.590952)
			(xy 102.056692 -284.616398) (xy 102.05618 -284.641844) (xy 102.048016 -284.692078) (xy 102.0319 -284.740352)
			(xy 102.008249 -284.785415) (xy 101.977676 -284.826101) (xy 101.940972 -284.861356) (xy 101.899088 -284.890266)
			(xy 101.853109 -284.912083) (xy 101.804225 -284.926243) (xy 101.753704 -284.932377) (xy 101.702852 -284.930328)
			(xy 101.652988 -284.920148) (xy 101.605402 -284.902101) (xy 101.561328 -284.876655) (xy 101.521906 -284.844468)
			(xy 101.488158 -284.806374) (xy 101.460957 -284.76336) (xy 101.441009 -284.71654) (xy 101.42883 -284.667126)
			(xy 101.424735 -284.616398) (xy 101.116892 -284.616398) (xy 101.11638 -284.641844) (xy 101.108216 -284.692078)
			(xy 101.0921 -284.740352) (xy 101.068449 -284.785415) (xy 101.037876 -284.826101) (xy 101.001172 -284.861356)
			(xy 100.959288 -284.890266) (xy 100.913309 -284.912083) (xy 100.864425 -284.926243) (xy 100.813904 -284.932377)
			(xy 100.763052 -284.930328) (xy 100.713188 -284.920148) (xy 100.665602 -284.902101) (xy 100.621528 -284.876655)
			(xy 100.582106 -284.844468) (xy 100.548358 -284.806374) (xy 100.521157 -284.76336) (xy 100.501209 -284.71654)
			(xy 100.48903 -284.667126) (xy 100.484935 -284.616398) (xy 100.166424 -284.616398) (xy 100.165929 -284.641005)
			(xy 100.158034 -284.689582) (xy 100.14245 -284.736263) (xy 100.119579 -284.77984) (xy 100.090014 -284.819184)
			(xy 100.054521 -284.853276) (xy 100.014018 -284.881232) (xy 99.969556 -284.90233) (xy 99.922285 -284.916022)
			(xy 99.87343 -284.921954) (xy 99.824255 -284.919973) (xy 99.776036 -284.910129) (xy 99.73002 -284.892677)
			(xy 99.687399 -284.86807) (xy 99.649278 -284.836945) (xy 99.616643 -284.800108) (xy 99.59034 -284.758512)
			(xy 99.571049 -284.713236) (xy 99.559272 -284.665452) (xy 99.555312 -284.616398) (xy 99.236784 -284.616398)
			(xy 99.236272 -284.641844) (xy 99.228108 -284.692078) (xy 99.211992 -284.740352) (xy 99.188341 -284.785415)
			(xy 99.157768 -284.826101) (xy 99.121064 -284.861356) (xy 99.07918 -284.890266) (xy 99.033201 -284.912083)
			(xy 98.984317 -284.926243) (xy 98.933796 -284.932377) (xy 98.882944 -284.930328) (xy 98.83308 -284.920148)
			(xy 98.785494 -284.902101) (xy 98.74142 -284.876655) (xy 98.701998 -284.844468) (xy 98.66825 -284.806374)
			(xy 98.641049 -284.76336) (xy 98.621101 -284.71654) (xy 98.608922 -284.667126) (xy 98.604827 -284.616398)
			(xy 98.29673 -284.616398) (xy 98.296218 -284.641844) (xy 98.288054 -284.692078) (xy 98.271938 -284.740352)
			(xy 98.248287 -284.785415) (xy 98.217714 -284.826101) (xy 98.18101 -284.861356) (xy 98.139126 -284.890266)
			(xy 98.093147 -284.912083) (xy 98.044263 -284.926243) (xy 97.993742 -284.932377) (xy 97.94289 -284.930328)
			(xy 97.893026 -284.920148) (xy 97.84544 -284.902101) (xy 97.801366 -284.876655) (xy 97.761944 -284.844468)
			(xy 97.728196 -284.806374) (xy 97.700995 -284.76336) (xy 97.681047 -284.71654) (xy 97.668868 -284.667126)
			(xy 97.664773 -284.616398) (xy 97.346262 -284.616398) (xy 97.345767 -284.641005) (xy 97.337872 -284.689582)
			(xy 97.322288 -284.736263) (xy 97.299417 -284.77984) (xy 97.269852 -284.819184) (xy 97.234359 -284.853276)
			(xy 97.193856 -284.881232) (xy 97.149394 -284.90233) (xy 97.102123 -284.916022) (xy 97.053268 -284.921954)
			(xy 97.004093 -284.919973) (xy 96.955874 -284.910129) (xy 96.909858 -284.892677) (xy 96.867237 -284.86807)
			(xy 96.829116 -284.836945) (xy 96.796481 -284.800108) (xy 96.770178 -284.758512) (xy 96.750887 -284.713236)
			(xy 96.73911 -284.665452) (xy 96.73515 -284.616398) (xy 96.416876 -284.616398) (xy 96.416364 -284.641844)
			(xy 96.4082 -284.692078) (xy 96.392084 -284.740352) (xy 96.368433 -284.785415) (xy 96.33786 -284.826101)
			(xy 96.301156 -284.861356) (xy 96.259272 -284.890266) (xy 96.213293 -284.912083) (xy 96.164409 -284.926243)
			(xy 96.113888 -284.932377) (xy 96.063036 -284.930328) (xy 96.013172 -284.920148) (xy 95.965586 -284.902101)
			(xy 95.921512 -284.876655) (xy 95.88209 -284.844468) (xy 95.848342 -284.806374) (xy 95.821141 -284.76336)
			(xy 95.801193 -284.71654) (xy 95.789014 -284.667126) (xy 95.784919 -284.616398) (xy 95.466408 -284.616398)
			(xy 95.465913 -284.641005) (xy 95.458018 -284.689582) (xy 95.442434 -284.736263) (xy 95.419563 -284.77984)
			(xy 95.389998 -284.819184) (xy 95.354505 -284.853276) (xy 95.314002 -284.881232) (xy 95.26954 -284.90233)
			(xy 95.222269 -284.916022) (xy 95.173414 -284.921954) (xy 95.124239 -284.919973) (xy 95.07602 -284.910129)
			(xy 95.030004 -284.892677) (xy 94.987383 -284.86807) (xy 94.949262 -284.836945) (xy 94.916627 -284.800108)
			(xy 94.890324 -284.758512) (xy 94.871033 -284.713236) (xy 94.859256 -284.665452) (xy 94.855296 -284.616398)
			(xy 94.536768 -284.616398) (xy 94.536256 -284.641844) (xy 94.528092 -284.692078) (xy 94.511976 -284.740352)
			(xy 94.488325 -284.785415) (xy 94.457752 -284.826101) (xy 94.421048 -284.861356) (xy 94.379164 -284.890266)
			(xy 94.333185 -284.912083) (xy 94.284301 -284.926243) (xy 94.23378 -284.932377) (xy 94.182928 -284.930328)
			(xy 94.133064 -284.920148) (xy 94.085478 -284.902101) (xy 94.041404 -284.876655) (xy 94.001982 -284.844468)
			(xy 93.968234 -284.806374) (xy 93.941033 -284.76336) (xy 93.921085 -284.71654) (xy 93.908906 -284.667126)
			(xy 93.904811 -284.616398) (xy 93.5863 -284.616398) (xy 93.585805 -284.641005) (xy 93.57791 -284.689582)
			(xy 93.562326 -284.736263) (xy 93.539455 -284.77984) (xy 93.50989 -284.819184) (xy 93.474397 -284.853276)
			(xy 93.433894 -284.881232) (xy 93.389432 -284.90233) (xy 93.342161 -284.916022) (xy 93.293306 -284.921954)
			(xy 93.244131 -284.919973) (xy 93.195912 -284.910129) (xy 93.149896 -284.892677) (xy 93.107275 -284.86807)
			(xy 93.069154 -284.836945) (xy 93.036519 -284.800108) (xy 93.010216 -284.758512) (xy 92.990925 -284.713236)
			(xy 92.979148 -284.665452) (xy 92.975188 -284.616398) (xy 92.65666 -284.616398) (xy 92.656148 -284.641844)
			(xy 92.647984 -284.692078) (xy 92.631868 -284.740352) (xy 92.608217 -284.785415) (xy 92.577644 -284.826101)
			(xy 92.54094 -284.861356) (xy 92.499056 -284.890266) (xy 92.453077 -284.912083) (xy 92.404193 -284.926243)
			(xy 92.353672 -284.932377) (xy 92.30282 -284.930328) (xy 92.252956 -284.920148) (xy 92.20537 -284.902101)
			(xy 92.161296 -284.876655) (xy 92.121874 -284.844468) (xy 92.088126 -284.806374) (xy 92.060925 -284.76336)
			(xy 92.040977 -284.71654) (xy 92.028798 -284.667126) (xy 92.024703 -284.616398) (xy 91.71686 -284.616398)
			(xy 91.716348 -284.641844) (xy 91.708184 -284.692078) (xy 91.692068 -284.740352) (xy 91.668417 -284.785415)
			(xy 91.637844 -284.826101) (xy 91.60114 -284.861356) (xy 91.559256 -284.890266) (xy 91.513277 -284.912083)
			(xy 91.464393 -284.926243) (xy 91.413872 -284.932377) (xy 91.36302 -284.930328) (xy 91.313156 -284.920148)
			(xy 91.26557 -284.902101) (xy 91.221496 -284.876655) (xy 91.182074 -284.844468) (xy 91.148326 -284.806374)
			(xy 91.121125 -284.76336) (xy 91.101177 -284.71654) (xy 91.088998 -284.667126) (xy 91.084903 -284.616398)
			(xy 90.766392 -284.616398) (xy 90.765897 -284.641005) (xy 90.758002 -284.689582) (xy 90.742418 -284.736263)
			(xy 90.719547 -284.77984) (xy 90.689982 -284.819184) (xy 90.654489 -284.853276) (xy 90.613986 -284.881232)
			(xy 90.569524 -284.90233) (xy 90.522253 -284.916022) (xy 90.473398 -284.921954) (xy 90.424223 -284.919973)
			(xy 90.376004 -284.910129) (xy 90.329988 -284.892677) (xy 90.287367 -284.86807) (xy 90.249246 -284.836945)
			(xy 90.216611 -284.800108) (xy 90.190308 -284.758512) (xy 90.171017 -284.713236) (xy 90.15924 -284.665452)
			(xy 90.15528 -284.616398) (xy 89.836752 -284.616398) (xy 89.83624 -284.641844) (xy 89.828076 -284.692078)
			(xy 89.81196 -284.740352) (xy 89.788309 -284.785415) (xy 89.757736 -284.826101) (xy 89.721032 -284.861356)
			(xy 89.679148 -284.890266) (xy 89.633169 -284.912083) (xy 89.584285 -284.926243) (xy 89.533764 -284.932377)
			(xy 89.482912 -284.930328) (xy 89.433048 -284.920148) (xy 89.385462 -284.902101) (xy 89.341388 -284.876655)
			(xy 89.301966 -284.844468) (xy 89.268218 -284.806374) (xy 89.241017 -284.76336) (xy 89.221069 -284.71654)
			(xy 89.20889 -284.667126) (xy 89.204795 -284.616398) (xy 88.886284 -284.616398) (xy 88.885789 -284.641005)
			(xy 88.877894 -284.689582) (xy 88.86231 -284.736263) (xy 88.839439 -284.77984) (xy 88.809874 -284.819184)
			(xy 88.774381 -284.853276) (xy 88.733878 -284.881232) (xy 88.689416 -284.90233) (xy 88.642145 -284.916022)
			(xy 88.59329 -284.921954) (xy 88.544115 -284.919973) (xy 88.495896 -284.910129) (xy 88.44988 -284.892677)
			(xy 88.407259 -284.86807) (xy 88.369138 -284.836945) (xy 88.336503 -284.800108) (xy 88.3102 -284.758512)
			(xy 88.290909 -284.713236) (xy 88.279132 -284.665452) (xy 88.275172 -284.616398) (xy 87.956644 -284.616398)
			(xy 87.956132 -284.641844) (xy 87.947968 -284.692078) (xy 87.931852 -284.740352) (xy 87.908201 -284.785415)
			(xy 87.877628 -284.826101) (xy 87.840924 -284.861356) (xy 87.79904 -284.890266) (xy 87.753061 -284.912083)
			(xy 87.704177 -284.926243) (xy 87.653656 -284.932377) (xy 87.602804 -284.930328) (xy 87.55294 -284.920148)
			(xy 87.505354 -284.902101) (xy 87.46128 -284.876655) (xy 87.421858 -284.844468) (xy 87.38811 -284.806374)
			(xy 87.360909 -284.76336) (xy 87.340961 -284.71654) (xy 87.328782 -284.667126) (xy 87.324687 -284.616398)
			(xy 87.00643 -284.616398) (xy 87.005935 -284.641005) (xy 86.99804 -284.689582) (xy 86.982456 -284.736263)
			(xy 86.959585 -284.77984) (xy 86.93002 -284.819184) (xy 86.894527 -284.853276) (xy 86.854024 -284.881232)
			(xy 86.809562 -284.90233) (xy 86.762291 -284.916022) (xy 86.713436 -284.921954) (xy 86.664261 -284.919973)
			(xy 86.616042 -284.910129) (xy 86.570026 -284.892677) (xy 86.527405 -284.86807) (xy 86.489284 -284.836945)
			(xy 86.456649 -284.800108) (xy 86.430346 -284.758512) (xy 86.411055 -284.713236) (xy 86.399278 -284.665452)
			(xy 86.395318 -284.616398) (xy 86.07679 -284.616398) (xy 86.076278 -284.641844) (xy 86.068114 -284.692078)
			(xy 86.051998 -284.740352) (xy 86.028347 -284.785415) (xy 85.997774 -284.826101) (xy 85.96107 -284.861356)
			(xy 85.919186 -284.890266) (xy 85.873207 -284.912083) (xy 85.824323 -284.926243) (xy 85.773802 -284.932377)
			(xy 85.72295 -284.930328) (xy 85.673086 -284.920148) (xy 85.6255 -284.902101) (xy 85.581426 -284.876655)
			(xy 85.542004 -284.844468) (xy 85.508256 -284.806374) (xy 85.481055 -284.76336) (xy 85.461107 -284.71654)
			(xy 85.448928 -284.667126) (xy 85.444833 -284.616398) (xy 85.136736 -284.616398) (xy 85.136224 -284.641844)
			(xy 85.12806 -284.692078) (xy 85.111944 -284.740352) (xy 85.088293 -284.785415) (xy 85.05772 -284.826101)
			(xy 85.021016 -284.861356) (xy 84.979132 -284.890266) (xy 84.933153 -284.912083) (xy 84.884269 -284.926243)
			(xy 84.833748 -284.932377) (xy 84.782896 -284.930328) (xy 84.733032 -284.920148) (xy 84.685446 -284.902101)
			(xy 84.641372 -284.876655) (xy 84.60195 -284.844468) (xy 84.568202 -284.806374) (xy 84.541001 -284.76336)
			(xy 84.521053 -284.71654) (xy 84.508874 -284.667126) (xy 84.504779 -284.616398) (xy 84.186268 -284.616398)
			(xy 84.185773 -284.641005) (xy 84.177878 -284.689582) (xy 84.162294 -284.736263) (xy 84.139423 -284.77984)
			(xy 84.109858 -284.819184) (xy 84.074365 -284.853276) (xy 84.033862 -284.881232) (xy 83.9894 -284.90233)
			(xy 83.942129 -284.916022) (xy 83.893274 -284.921954) (xy 83.844099 -284.919973) (xy 83.79588 -284.910129)
			(xy 83.749864 -284.892677) (xy 83.707243 -284.86807) (xy 83.669122 -284.836945) (xy 83.636487 -284.800108)
			(xy 83.610184 -284.758512) (xy 83.590893 -284.713236) (xy 83.579116 -284.665452) (xy 83.575156 -284.616398)
			(xy 83.256628 -284.616398) (xy 83.256116 -284.641844) (xy 83.247952 -284.692078) (xy 83.231836 -284.740352)
			(xy 83.208185 -284.785415) (xy 83.177612 -284.826101) (xy 83.140908 -284.861356) (xy 83.099024 -284.890266)
			(xy 83.053045 -284.912083) (xy 83.004161 -284.926243) (xy 82.95364 -284.932377) (xy 82.902788 -284.930328)
			(xy 82.852924 -284.920148) (xy 82.805338 -284.902101) (xy 82.761264 -284.876655) (xy 82.721842 -284.844468)
			(xy 82.688094 -284.806374) (xy 82.660893 -284.76336) (xy 82.640945 -284.71654) (xy 82.628766 -284.667126)
			(xy 82.624671 -284.616398) (xy 82.306414 -284.616398) (xy 82.305919 -284.641005) (xy 82.298024 -284.689582)
			(xy 82.28244 -284.736263) (xy 82.259569 -284.77984) (xy 82.230004 -284.819184) (xy 82.194511 -284.853276)
			(xy 82.154008 -284.881232) (xy 82.109546 -284.90233) (xy 82.062275 -284.916022) (xy 82.01342 -284.921954)
			(xy 81.964245 -284.919973) (xy 81.916026 -284.910129) (xy 81.87001 -284.892677) (xy 81.827389 -284.86807)
			(xy 81.789268 -284.836945) (xy 81.756633 -284.800108) (xy 81.73033 -284.758512) (xy 81.711039 -284.713236)
			(xy 81.699262 -284.665452) (xy 81.695302 -284.616398) (xy 81.376774 -284.616398) (xy 81.376262 -284.641844)
			(xy 81.368098 -284.692078) (xy 81.351982 -284.740352) (xy 81.328331 -284.785415) (xy 81.297758 -284.826101)
			(xy 81.261054 -284.861356) (xy 81.21917 -284.890266) (xy 81.173191 -284.912083) (xy 81.124307 -284.926243)
			(xy 81.073786 -284.932377) (xy 81.022934 -284.930328) (xy 80.97307 -284.920148) (xy 80.925484 -284.902101)
			(xy 80.88141 -284.876655) (xy 80.841988 -284.844468) (xy 80.80824 -284.806374) (xy 80.781039 -284.76336)
			(xy 80.761091 -284.71654) (xy 80.748912 -284.667126) (xy 80.744817 -284.616398) (xy 80.426306 -284.616398)
			(xy 80.425811 -284.641005) (xy 80.417916 -284.689582) (xy 80.402332 -284.736263) (xy 80.379461 -284.77984)
			(xy 80.349896 -284.819184) (xy 80.314403 -284.853276) (xy 80.2739 -284.881232) (xy 80.229438 -284.90233)
			(xy 80.182167 -284.916022) (xy 80.133312 -284.921954) (xy 80.084137 -284.919973) (xy 80.035918 -284.910129)
			(xy 79.989902 -284.892677) (xy 79.947281 -284.86807) (xy 79.90916 -284.836945) (xy 79.876525 -284.800108)
			(xy 79.850222 -284.758512) (xy 79.830931 -284.713236) (xy 79.819154 -284.665452) (xy 79.815194 -284.616398)
			(xy 77.263451 -284.616398) (xy 77.221316 -284.636392) (xy 77.174045 -284.650084) (xy 77.12519 -284.656016)
			(xy 77.076015 -284.654035) (xy 77.027796 -284.644191) (xy 76.98178 -284.626739) (xy 76.939159 -284.602132)
			(xy 76.901038 -284.571007) (xy 76.868403 -284.53417) (xy 76.8421 -284.492574) (xy 76.822809 -284.447298)
			(xy 76.811032 -284.399514) (xy 76.807072 -284.35046) (xy 73.228962 -284.35046) (xy 73.228962 -285.426404)
			(xy 78.40524 -285.426404) (xy 78.4092 -285.37735) (xy 78.420977 -285.329566) (xy 78.440268 -285.28429)
			(xy 78.466571 -285.242694) (xy 78.499206 -285.205857) (xy 78.537327 -285.174732) (xy 78.579948 -285.150125)
			(xy 78.625964 -285.132673) (xy 78.674183 -285.122829) (xy 78.723358 -285.120848) (xy 78.772213 -285.12678)
			(xy 78.819484 -285.140472) (xy 78.863946 -285.16157) (xy 78.904449 -285.189526) (xy 78.939942 -285.223618)
			(xy 78.969507 -285.262962) (xy 78.992378 -285.306539) (xy 79.007962 -285.35322) (xy 79.015857 -285.401797)
			(xy 79.016352 -285.426404) (xy 80.285348 -285.426404) (xy 80.289308 -285.37735) (xy 80.301085 -285.329566)
			(xy 80.320376 -285.28429) (xy 80.346679 -285.242694) (xy 80.379314 -285.205857) (xy 80.417435 -285.174732)
			(xy 80.460056 -285.150125) (xy 80.506072 -285.132673) (xy 80.554291 -285.122829) (xy 80.603466 -285.120848)
			(xy 80.652321 -285.12678) (xy 80.699592 -285.140472) (xy 80.744054 -285.16157) (xy 80.784557 -285.189526)
			(xy 80.82005 -285.223618) (xy 80.849615 -285.262962) (xy 80.872486 -285.306539) (xy 80.88807 -285.35322)
			(xy 80.895965 -285.401797) (xy 80.89646 -285.426404) (xy 81.214717 -285.426404) (xy 81.218812 -285.375676)
			(xy 81.230991 -285.326262) (xy 81.250939 -285.279442) (xy 81.27814 -285.236428) (xy 81.311888 -285.198334)
			(xy 81.35131 -285.166147) (xy 81.395384 -285.140701) (xy 81.44297 -285.122654) (xy 81.492834 -285.112474)
			(xy 81.543686 -285.110425) (xy 81.594207 -285.116559) (xy 81.643091 -285.130719) (xy 81.68907 -285.152536)
			(xy 81.730954 -285.181446) (xy 81.767658 -285.216701) (xy 81.798231 -285.257387) (xy 81.821882 -285.30245)
			(xy 81.837998 -285.350724) (xy 81.846162 -285.400958) (xy 81.846674 -285.426404) (xy 82.154771 -285.426404)
			(xy 82.158866 -285.375676) (xy 82.171045 -285.326262) (xy 82.190993 -285.279442) (xy 82.218194 -285.236428)
			(xy 82.251942 -285.198334) (xy 82.291364 -285.166147) (xy 82.335438 -285.140701) (xy 82.383024 -285.122654)
			(xy 82.432888 -285.112474) (xy 82.48374 -285.110425) (xy 82.534261 -285.116559) (xy 82.583145 -285.130719)
			(xy 82.629124 -285.152536) (xy 82.671008 -285.181446) (xy 82.707712 -285.216701) (xy 82.738285 -285.257387)
			(xy 82.761936 -285.30245) (xy 82.778052 -285.350724) (xy 82.786216 -285.400958) (xy 82.786728 -285.426404)
			(xy 83.105256 -285.426404) (xy 83.109216 -285.37735) (xy 83.120993 -285.329566) (xy 83.140284 -285.28429)
			(xy 83.166587 -285.242694) (xy 83.199222 -285.205857) (xy 83.237343 -285.174732) (xy 83.279964 -285.150125)
			(xy 83.32598 -285.132673) (xy 83.374199 -285.122829) (xy 83.423374 -285.120848) (xy 83.472229 -285.12678)
			(xy 83.5195 -285.140472) (xy 83.563962 -285.16157) (xy 83.604465 -285.189526) (xy 83.639958 -285.223618)
			(xy 83.669523 -285.262962) (xy 83.692394 -285.306539) (xy 83.707978 -285.35322) (xy 83.715873 -285.401797)
			(xy 83.716368 -285.426404) (xy 84.034879 -285.426404) (xy 84.038974 -285.375676) (xy 84.051153 -285.326262)
			(xy 84.071101 -285.279442) (xy 84.098302 -285.236428) (xy 84.13205 -285.198334) (xy 84.171472 -285.166147)
			(xy 84.215546 -285.140701) (xy 84.263132 -285.122654) (xy 84.312996 -285.112474) (xy 84.363848 -285.110425)
			(xy 84.414369 -285.116559) (xy 84.463253 -285.130719) (xy 84.509232 -285.152536) (xy 84.551116 -285.181446)
			(xy 84.58782 -285.216701) (xy 84.618393 -285.257387) (xy 84.642044 -285.30245) (xy 84.65816 -285.350724)
			(xy 84.666324 -285.400958) (xy 84.666836 -285.426404) (xy 84.98511 -285.426404) (xy 84.98907 -285.37735)
			(xy 85.000847 -285.329566) (xy 85.020138 -285.28429) (xy 85.046441 -285.242694) (xy 85.079076 -285.205857)
			(xy 85.117197 -285.174732) (xy 85.159818 -285.150125) (xy 85.205834 -285.132673) (xy 85.254053 -285.122829)
			(xy 85.303228 -285.120848) (xy 85.352083 -285.12678) (xy 85.399354 -285.140472) (xy 85.443816 -285.16157)
			(xy 85.484319 -285.189526) (xy 85.519812 -285.223618) (xy 85.549377 -285.262962) (xy 85.572248 -285.306539)
			(xy 85.587832 -285.35322) (xy 85.595727 -285.401797) (xy 85.596222 -285.426404) (xy 85.914733 -285.426404)
			(xy 85.918828 -285.375676) (xy 85.931007 -285.326262) (xy 85.950955 -285.279442) (xy 85.978156 -285.236428)
			(xy 86.011904 -285.198334) (xy 86.051326 -285.166147) (xy 86.0954 -285.140701) (xy 86.142986 -285.122654)
			(xy 86.19285 -285.112474) (xy 86.243702 -285.110425) (xy 86.294223 -285.116559) (xy 86.343107 -285.130719)
			(xy 86.389086 -285.152536) (xy 86.43097 -285.181446) (xy 86.467674 -285.216701) (xy 86.498247 -285.257387)
			(xy 86.521898 -285.30245) (xy 86.538014 -285.350724) (xy 86.546178 -285.400958) (xy 86.54669 -285.426404)
			(xy 86.865218 -285.426404) (xy 86.869178 -285.37735) (xy 86.880955 -285.329566) (xy 86.900246 -285.28429)
			(xy 86.926549 -285.242694) (xy 86.959184 -285.205857) (xy 86.997305 -285.174732) (xy 87.039926 -285.150125)
			(xy 87.085942 -285.132673) (xy 87.134161 -285.122829) (xy 87.183336 -285.120848) (xy 87.232191 -285.12678)
			(xy 87.279462 -285.140472) (xy 87.323924 -285.16157) (xy 87.364427 -285.189526) (xy 87.39992 -285.223618)
			(xy 87.429485 -285.262962) (xy 87.452356 -285.306539) (xy 87.46794 -285.35322) (xy 87.475835 -285.401797)
			(xy 87.47633 -285.426404) (xy 87.794841 -285.426404) (xy 87.798936 -285.375676) (xy 87.811115 -285.326262)
			(xy 87.831063 -285.279442) (xy 87.858264 -285.236428) (xy 87.892012 -285.198334) (xy 87.931434 -285.166147)
			(xy 87.975508 -285.140701) (xy 88.023094 -285.122654) (xy 88.072958 -285.112474) (xy 88.12381 -285.110425)
			(xy 88.174331 -285.116559) (xy 88.223215 -285.130719) (xy 88.269194 -285.152536) (xy 88.311078 -285.181446)
			(xy 88.347782 -285.216701) (xy 88.378355 -285.257387) (xy 88.402006 -285.30245) (xy 88.418122 -285.350724)
			(xy 88.426286 -285.400958) (xy 88.426798 -285.426404) (xy 88.734895 -285.426404) (xy 88.73899 -285.375676)
			(xy 88.751169 -285.326262) (xy 88.771117 -285.279442) (xy 88.798318 -285.236428) (xy 88.832066 -285.198334)
			(xy 88.871488 -285.166147) (xy 88.915562 -285.140701) (xy 88.963148 -285.122654) (xy 89.013012 -285.112474)
			(xy 89.063864 -285.110425) (xy 89.114385 -285.116559) (xy 89.163269 -285.130719) (xy 89.209248 -285.152536)
			(xy 89.251132 -285.181446) (xy 89.287836 -285.216701) (xy 89.318409 -285.257387) (xy 89.34206 -285.30245)
			(xy 89.358176 -285.350724) (xy 89.36634 -285.400958) (xy 89.366852 -285.426404) (xy 89.685126 -285.426404)
			(xy 89.689086 -285.37735) (xy 89.700863 -285.329566) (xy 89.720154 -285.28429) (xy 89.746457 -285.242694)
			(xy 89.779092 -285.205857) (xy 89.817213 -285.174732) (xy 89.859834 -285.150125) (xy 89.90585 -285.132673)
			(xy 89.954069 -285.122829) (xy 90.003244 -285.120848) (xy 90.052099 -285.12678) (xy 90.09937 -285.140472)
			(xy 90.143832 -285.16157) (xy 90.184335 -285.189526) (xy 90.219828 -285.223618) (xy 90.249393 -285.262962)
			(xy 90.272264 -285.306539) (xy 90.287848 -285.35322) (xy 90.295743 -285.401797) (xy 90.296238 -285.426404)
			(xy 90.614749 -285.426404) (xy 90.618844 -285.375676) (xy 90.631023 -285.326262) (xy 90.650971 -285.279442)
			(xy 90.678172 -285.236428) (xy 90.71192 -285.198334) (xy 90.751342 -285.166147) (xy 90.795416 -285.140701)
			(xy 90.843002 -285.122654) (xy 90.892866 -285.112474) (xy 90.943718 -285.110425) (xy 90.994239 -285.116559)
			(xy 91.043123 -285.130719) (xy 91.089102 -285.152536) (xy 91.130986 -285.181446) (xy 91.16769 -285.216701)
			(xy 91.198263 -285.257387) (xy 91.221914 -285.30245) (xy 91.23803 -285.350724) (xy 91.246194 -285.400958)
			(xy 91.246706 -285.426404) (xy 91.565234 -285.426404) (xy 91.569194 -285.37735) (xy 91.580971 -285.329566)
			(xy 91.600262 -285.28429) (xy 91.626565 -285.242694) (xy 91.6592 -285.205857) (xy 91.697321 -285.174732)
			(xy 91.739942 -285.150125) (xy 91.785958 -285.132673) (xy 91.834177 -285.122829) (xy 91.883352 -285.120848)
			(xy 91.932207 -285.12678) (xy 91.979478 -285.140472) (xy 92.02394 -285.16157) (xy 92.064443 -285.189526)
			(xy 92.099936 -285.223618) (xy 92.129501 -285.262962) (xy 92.152372 -285.306539) (xy 92.167956 -285.35322)
			(xy 92.175851 -285.401797) (xy 92.176346 -285.426404) (xy 92.494857 -285.426404) (xy 92.498952 -285.375676)
			(xy 92.511131 -285.326262) (xy 92.531079 -285.279442) (xy 92.55828 -285.236428) (xy 92.592028 -285.198334)
			(xy 92.63145 -285.166147) (xy 92.675524 -285.140701) (xy 92.72311 -285.122654) (xy 92.772974 -285.112474)
			(xy 92.823826 -285.110425) (xy 92.874347 -285.116559) (xy 92.923231 -285.130719) (xy 92.96921 -285.152536)
			(xy 93.011094 -285.181446) (xy 93.047798 -285.216701) (xy 93.078371 -285.257387) (xy 93.102022 -285.30245)
			(xy 93.118138 -285.350724) (xy 93.126302 -285.400958) (xy 93.126814 -285.426404) (xy 93.445342 -285.426404)
			(xy 93.449302 -285.37735) (xy 93.461079 -285.329566) (xy 93.48037 -285.28429) (xy 93.506673 -285.242694)
			(xy 93.539308 -285.205857) (xy 93.577429 -285.174732) (xy 93.62005 -285.150125) (xy 93.666066 -285.132673)
			(xy 93.714285 -285.122829) (xy 93.76346 -285.120848) (xy 93.812315 -285.12678) (xy 93.859586 -285.140472)
			(xy 93.904048 -285.16157) (xy 93.944551 -285.189526) (xy 93.980044 -285.223618) (xy 94.009609 -285.262962)
			(xy 94.03248 -285.306539) (xy 94.048064 -285.35322) (xy 94.055959 -285.401797) (xy 94.056454 -285.426404)
			(xy 94.374711 -285.426404) (xy 94.378806 -285.375676) (xy 94.390985 -285.326262) (xy 94.410933 -285.279442)
			(xy 94.438134 -285.236428) (xy 94.471882 -285.198334) (xy 94.511304 -285.166147) (xy 94.555378 -285.140701)
			(xy 94.602964 -285.122654) (xy 94.652828 -285.112474) (xy 94.70368 -285.110425) (xy 94.754201 -285.116559)
			(xy 94.803085 -285.130719) (xy 94.849064 -285.152536) (xy 94.890948 -285.181446) (xy 94.927652 -285.216701)
			(xy 94.958225 -285.257387) (xy 94.981876 -285.30245) (xy 94.997992 -285.350724) (xy 95.006156 -285.400958)
			(xy 95.006668 -285.426404) (xy 95.314765 -285.426404) (xy 95.31886 -285.375676) (xy 95.331039 -285.326262)
			(xy 95.350987 -285.279442) (xy 95.378188 -285.236428) (xy 95.411936 -285.198334) (xy 95.451358 -285.166147)
			(xy 95.495432 -285.140701) (xy 95.543018 -285.122654) (xy 95.592882 -285.112474) (xy 95.643734 -285.110425)
			(xy 95.694255 -285.116559) (xy 95.743139 -285.130719) (xy 95.789118 -285.152536) (xy 95.831002 -285.181446)
			(xy 95.867706 -285.216701) (xy 95.898279 -285.257387) (xy 95.92193 -285.30245) (xy 95.938046 -285.350724)
			(xy 95.94621 -285.400958) (xy 95.946722 -285.426404) (xy 96.26525 -285.426404) (xy 96.26921 -285.37735)
			(xy 96.280987 -285.329566) (xy 96.300278 -285.28429) (xy 96.326581 -285.242694) (xy 96.359216 -285.205857)
			(xy 96.397337 -285.174732) (xy 96.439958 -285.150125) (xy 96.485974 -285.132673) (xy 96.534193 -285.122829)
			(xy 96.583368 -285.120848) (xy 96.632223 -285.12678) (xy 96.679494 -285.140472) (xy 96.723956 -285.16157)
			(xy 96.764459 -285.189526) (xy 96.799952 -285.223618) (xy 96.829517 -285.262962) (xy 96.852388 -285.306539)
			(xy 96.867972 -285.35322) (xy 96.875867 -285.401797) (xy 96.876362 -285.426404) (xy 97.205304 -285.426404)
			(xy 97.209264 -285.37735) (xy 97.221041 -285.329566) (xy 97.240332 -285.28429) (xy 97.266635 -285.242694)
			(xy 97.29927 -285.205857) (xy 97.337391 -285.174732) (xy 97.380012 -285.150125) (xy 97.426028 -285.132673)
			(xy 97.474247 -285.122829) (xy 97.523422 -285.120848) (xy 97.572277 -285.12678) (xy 97.619548 -285.140472)
			(xy 97.66401 -285.16157) (xy 97.704513 -285.189526) (xy 97.740006 -285.223618) (xy 97.769571 -285.262962)
			(xy 97.792442 -285.306539) (xy 97.808026 -285.35322) (xy 97.815921 -285.401797) (xy 97.816416 -285.426404)
			(xy 98.145358 -285.426404) (xy 98.149318 -285.37735) (xy 98.161095 -285.329566) (xy 98.180386 -285.28429)
			(xy 98.206689 -285.242694) (xy 98.239324 -285.205857) (xy 98.277445 -285.174732) (xy 98.320066 -285.150125)
			(xy 98.366082 -285.132673) (xy 98.414301 -285.122829) (xy 98.463476 -285.120848) (xy 98.512331 -285.12678)
			(xy 98.559602 -285.140472) (xy 98.604064 -285.16157) (xy 98.644567 -285.189526) (xy 98.68006 -285.223618)
			(xy 98.709625 -285.262962) (xy 98.732496 -285.306539) (xy 98.74808 -285.35322) (xy 98.755975 -285.401797)
			(xy 98.75647 -285.426404) (xy 99.085158 -285.426404) (xy 99.089118 -285.37735) (xy 99.100895 -285.329566)
			(xy 99.120186 -285.28429) (xy 99.146489 -285.242694) (xy 99.179124 -285.205857) (xy 99.217245 -285.174732)
			(xy 99.259866 -285.150125) (xy 99.305882 -285.132673) (xy 99.354101 -285.122829) (xy 99.403276 -285.120848)
			(xy 99.452131 -285.12678) (xy 99.499402 -285.140472) (xy 99.543864 -285.16157) (xy 99.584367 -285.189526)
			(xy 99.61986 -285.223618) (xy 99.649425 -285.262962) (xy 99.672296 -285.306539) (xy 99.68788 -285.35322)
			(xy 99.695775 -285.401797) (xy 99.69627 -285.426404) (xy 100.025212 -285.426404) (xy 100.029172 -285.37735)
			(xy 100.040949 -285.329566) (xy 100.06024 -285.28429) (xy 100.086543 -285.242694) (xy 100.119178 -285.205857)
			(xy 100.157299 -285.174732) (xy 100.19992 -285.150125) (xy 100.245936 -285.132673) (xy 100.294155 -285.122829)
			(xy 100.34333 -285.120848) (xy 100.392185 -285.12678) (xy 100.439456 -285.140472) (xy 100.483918 -285.16157)
			(xy 100.524421 -285.189526) (xy 100.559914 -285.223618) (xy 100.589479 -285.262962) (xy 100.61235 -285.306539)
			(xy 100.627934 -285.35322) (xy 100.635829 -285.401797) (xy 100.636324 -285.426404) (xy 100.965266 -285.426404)
			(xy 100.969226 -285.37735) (xy 100.981003 -285.329566) (xy 101.000294 -285.28429) (xy 101.026597 -285.242694)
			(xy 101.059232 -285.205857) (xy 101.097353 -285.174732) (xy 101.139974 -285.150125) (xy 101.18599 -285.132673)
			(xy 101.234209 -285.122829) (xy 101.283384 -285.120848) (xy 101.332239 -285.12678) (xy 101.37951 -285.140472)
			(xy 101.423972 -285.16157) (xy 101.464475 -285.189526) (xy 101.499968 -285.223618) (xy 101.529533 -285.262962)
			(xy 101.552404 -285.306539) (xy 101.567988 -285.35322) (xy 101.575883 -285.401797) (xy 101.576378 -285.426404)
			(xy 101.90532 -285.426404) (xy 101.90928 -285.37735) (xy 101.921057 -285.329566) (xy 101.940348 -285.28429)
			(xy 101.966651 -285.242694) (xy 101.999286 -285.205857) (xy 102.037407 -285.174732) (xy 102.080028 -285.150125)
			(xy 102.126044 -285.132673) (xy 102.174263 -285.122829) (xy 102.223438 -285.120848) (xy 102.272293 -285.12678)
			(xy 102.319564 -285.140472) (xy 102.364026 -285.16157) (xy 102.404529 -285.189526) (xy 102.440022 -285.223618)
			(xy 102.469587 -285.262962) (xy 102.492458 -285.306539) (xy 102.508042 -285.35322) (xy 102.515937 -285.401797)
			(xy 102.516432 -285.426404) (xy 102.515937 -285.451011) (xy 102.508042 -285.499588) (xy 102.492458 -285.546269)
			(xy 102.469587 -285.589846) (xy 102.440022 -285.62919) (xy 102.404529 -285.663282) (xy 102.364026 -285.691238)
			(xy 102.319564 -285.712336) (xy 102.272293 -285.726028) (xy 102.223438 -285.73196) (xy 102.174263 -285.729979)
			(xy 102.126044 -285.720135) (xy 102.080028 -285.702683) (xy 102.037407 -285.678076) (xy 101.999286 -285.646951)
			(xy 101.966651 -285.610114) (xy 101.940348 -285.568518) (xy 101.921057 -285.523242) (xy 101.90928 -285.475458)
			(xy 101.90532 -285.426404) (xy 101.576378 -285.426404) (xy 101.575883 -285.451011) (xy 101.567988 -285.499588)
			(xy 101.552404 -285.546269) (xy 101.529533 -285.589846) (xy 101.499968 -285.62919) (xy 101.464475 -285.663282)
			(xy 101.423972 -285.691238) (xy 101.37951 -285.712336) (xy 101.332239 -285.726028) (xy 101.283384 -285.73196)
			(xy 101.234209 -285.729979) (xy 101.18599 -285.720135) (xy 101.139974 -285.702683) (xy 101.097353 -285.678076)
			(xy 101.059232 -285.646951) (xy 101.026597 -285.610114) (xy 101.000294 -285.568518) (xy 100.981003 -285.523242)
			(xy 100.969226 -285.475458) (xy 100.965266 -285.426404) (xy 100.636324 -285.426404) (xy 100.635829 -285.451011)
			(xy 100.627934 -285.499588) (xy 100.61235 -285.546269) (xy 100.589479 -285.589846) (xy 100.559914 -285.62919)
			(xy 100.524421 -285.663282) (xy 100.483918 -285.691238) (xy 100.439456 -285.712336) (xy 100.392185 -285.726028)
			(xy 100.34333 -285.73196) (xy 100.294155 -285.729979) (xy 100.245936 -285.720135) (xy 100.19992 -285.702683)
			(xy 100.157299 -285.678076) (xy 100.119178 -285.646951) (xy 100.086543 -285.610114) (xy 100.06024 -285.568518)
			(xy 100.040949 -285.523242) (xy 100.029172 -285.475458) (xy 100.025212 -285.426404) (xy 99.69627 -285.426404)
			(xy 99.695775 -285.451011) (xy 99.68788 -285.499588) (xy 99.672296 -285.546269) (xy 99.649425 -285.589846)
			(xy 99.61986 -285.62919) (xy 99.584367 -285.663282) (xy 99.543864 -285.691238) (xy 99.499402 -285.712336)
			(xy 99.452131 -285.726028) (xy 99.403276 -285.73196) (xy 99.354101 -285.729979) (xy 99.305882 -285.720135)
			(xy 99.259866 -285.702683) (xy 99.217245 -285.678076) (xy 99.179124 -285.646951) (xy 99.146489 -285.610114)
			(xy 99.120186 -285.568518) (xy 99.100895 -285.523242) (xy 99.089118 -285.475458) (xy 99.085158 -285.426404)
			(xy 98.75647 -285.426404) (xy 98.755975 -285.451011) (xy 98.74808 -285.499588) (xy 98.732496 -285.546269)
			(xy 98.709625 -285.589846) (xy 98.68006 -285.62919) (xy 98.644567 -285.663282) (xy 98.604064 -285.691238)
			(xy 98.559602 -285.712336) (xy 98.512331 -285.726028) (xy 98.463476 -285.73196) (xy 98.414301 -285.729979)
			(xy 98.366082 -285.720135) (xy 98.320066 -285.702683) (xy 98.277445 -285.678076) (xy 98.239324 -285.646951)
			(xy 98.206689 -285.610114) (xy 98.180386 -285.568518) (xy 98.161095 -285.523242) (xy 98.149318 -285.475458)
			(xy 98.145358 -285.426404) (xy 97.816416 -285.426404) (xy 97.815921 -285.451011) (xy 97.808026 -285.499588)
			(xy 97.792442 -285.546269) (xy 97.769571 -285.589846) (xy 97.740006 -285.62919) (xy 97.704513 -285.663282)
			(xy 97.66401 -285.691238) (xy 97.619548 -285.712336) (xy 97.572277 -285.726028) (xy 97.523422 -285.73196)
			(xy 97.474247 -285.729979) (xy 97.426028 -285.720135) (xy 97.380012 -285.702683) (xy 97.337391 -285.678076)
			(xy 97.29927 -285.646951) (xy 97.266635 -285.610114) (xy 97.240332 -285.568518) (xy 97.221041 -285.523242)
			(xy 97.209264 -285.475458) (xy 97.205304 -285.426404) (xy 96.876362 -285.426404) (xy 96.875867 -285.451011)
			(xy 96.867972 -285.499588) (xy 96.852388 -285.546269) (xy 96.829517 -285.589846) (xy 96.799952 -285.62919)
			(xy 96.764459 -285.663282) (xy 96.723956 -285.691238) (xy 96.679494 -285.712336) (xy 96.632223 -285.726028)
			(xy 96.583368 -285.73196) (xy 96.534193 -285.729979) (xy 96.485974 -285.720135) (xy 96.439958 -285.702683)
			(xy 96.397337 -285.678076) (xy 96.359216 -285.646951) (xy 96.326581 -285.610114) (xy 96.300278 -285.568518)
			(xy 96.280987 -285.523242) (xy 96.26921 -285.475458) (xy 96.26525 -285.426404) (xy 95.946722 -285.426404)
			(xy 95.94621 -285.45185) (xy 95.938046 -285.502084) (xy 95.92193 -285.550358) (xy 95.898279 -285.595421)
			(xy 95.867706 -285.636107) (xy 95.831002 -285.671362) (xy 95.789118 -285.700272) (xy 95.743139 -285.722089)
			(xy 95.694255 -285.736249) (xy 95.643734 -285.742383) (xy 95.592882 -285.740334) (xy 95.543018 -285.730154)
			(xy 95.495432 -285.712107) (xy 95.451358 -285.686661) (xy 95.411936 -285.654474) (xy 95.378188 -285.61638)
			(xy 95.350987 -285.573366) (xy 95.331039 -285.526546) (xy 95.31886 -285.477132) (xy 95.314765 -285.426404)
			(xy 95.006668 -285.426404) (xy 95.006156 -285.45185) (xy 94.997992 -285.502084) (xy 94.981876 -285.550358)
			(xy 94.958225 -285.595421) (xy 94.927652 -285.636107) (xy 94.890948 -285.671362) (xy 94.849064 -285.700272)
			(xy 94.803085 -285.722089) (xy 94.754201 -285.736249) (xy 94.70368 -285.742383) (xy 94.652828 -285.740334)
			(xy 94.602964 -285.730154) (xy 94.555378 -285.712107) (xy 94.511304 -285.686661) (xy 94.471882 -285.654474)
			(xy 94.438134 -285.61638) (xy 94.410933 -285.573366) (xy 94.390985 -285.526546) (xy 94.378806 -285.477132)
			(xy 94.374711 -285.426404) (xy 94.056454 -285.426404) (xy 94.055959 -285.451011) (xy 94.048064 -285.499588)
			(xy 94.03248 -285.546269) (xy 94.009609 -285.589846) (xy 93.980044 -285.62919) (xy 93.944551 -285.663282)
			(xy 93.904048 -285.691238) (xy 93.859586 -285.712336) (xy 93.812315 -285.726028) (xy 93.76346 -285.73196)
			(xy 93.714285 -285.729979) (xy 93.666066 -285.720135) (xy 93.62005 -285.702683) (xy 93.577429 -285.678076)
			(xy 93.539308 -285.646951) (xy 93.506673 -285.610114) (xy 93.48037 -285.568518) (xy 93.461079 -285.523242)
			(xy 93.449302 -285.475458) (xy 93.445342 -285.426404) (xy 93.126814 -285.426404) (xy 93.126302 -285.45185)
			(xy 93.118138 -285.502084) (xy 93.102022 -285.550358) (xy 93.078371 -285.595421) (xy 93.047798 -285.636107)
			(xy 93.011094 -285.671362) (xy 92.96921 -285.700272) (xy 92.923231 -285.722089) (xy 92.874347 -285.736249)
			(xy 92.823826 -285.742383) (xy 92.772974 -285.740334) (xy 92.72311 -285.730154) (xy 92.675524 -285.712107)
			(xy 92.63145 -285.686661) (xy 92.592028 -285.654474) (xy 92.55828 -285.61638) (xy 92.531079 -285.573366)
			(xy 92.511131 -285.526546) (xy 92.498952 -285.477132) (xy 92.494857 -285.426404) (xy 92.176346 -285.426404)
			(xy 92.175851 -285.451011) (xy 92.167956 -285.499588) (xy 92.152372 -285.546269) (xy 92.129501 -285.589846)
			(xy 92.099936 -285.62919) (xy 92.064443 -285.663282) (xy 92.02394 -285.691238) (xy 91.979478 -285.712336)
			(xy 91.932207 -285.726028) (xy 91.883352 -285.73196) (xy 91.834177 -285.729979) (xy 91.785958 -285.720135)
			(xy 91.739942 -285.702683) (xy 91.697321 -285.678076) (xy 91.6592 -285.646951) (xy 91.626565 -285.610114)
			(xy 91.600262 -285.568518) (xy 91.580971 -285.523242) (xy 91.569194 -285.475458) (xy 91.565234 -285.426404)
			(xy 91.246706 -285.426404) (xy 91.246194 -285.45185) (xy 91.23803 -285.502084) (xy 91.221914 -285.550358)
			(xy 91.198263 -285.595421) (xy 91.16769 -285.636107) (xy 91.130986 -285.671362) (xy 91.089102 -285.700272)
			(xy 91.043123 -285.722089) (xy 90.994239 -285.736249) (xy 90.943718 -285.742383) (xy 90.892866 -285.740334)
			(xy 90.843002 -285.730154) (xy 90.795416 -285.712107) (xy 90.751342 -285.686661) (xy 90.71192 -285.654474)
			(xy 90.678172 -285.61638) (xy 90.650971 -285.573366) (xy 90.631023 -285.526546) (xy 90.618844 -285.477132)
			(xy 90.614749 -285.426404) (xy 90.296238 -285.426404) (xy 90.295743 -285.451011) (xy 90.287848 -285.499588)
			(xy 90.272264 -285.546269) (xy 90.249393 -285.589846) (xy 90.219828 -285.62919) (xy 90.184335 -285.663282)
			(xy 90.143832 -285.691238) (xy 90.09937 -285.712336) (xy 90.052099 -285.726028) (xy 90.003244 -285.73196)
			(xy 89.954069 -285.729979) (xy 89.90585 -285.720135) (xy 89.859834 -285.702683) (xy 89.817213 -285.678076)
			(xy 89.779092 -285.646951) (xy 89.746457 -285.610114) (xy 89.720154 -285.568518) (xy 89.700863 -285.523242)
			(xy 89.689086 -285.475458) (xy 89.685126 -285.426404) (xy 89.366852 -285.426404) (xy 89.36634 -285.45185)
			(xy 89.358176 -285.502084) (xy 89.34206 -285.550358) (xy 89.318409 -285.595421) (xy 89.287836 -285.636107)
			(xy 89.251132 -285.671362) (xy 89.209248 -285.700272) (xy 89.163269 -285.722089) (xy 89.114385 -285.736249)
			(xy 89.063864 -285.742383) (xy 89.013012 -285.740334) (xy 88.963148 -285.730154) (xy 88.915562 -285.712107)
			(xy 88.871488 -285.686661) (xy 88.832066 -285.654474) (xy 88.798318 -285.61638) (xy 88.771117 -285.573366)
			(xy 88.751169 -285.526546) (xy 88.73899 -285.477132) (xy 88.734895 -285.426404) (xy 88.426798 -285.426404)
			(xy 88.426286 -285.45185) (xy 88.418122 -285.502084) (xy 88.402006 -285.550358) (xy 88.378355 -285.595421)
			(xy 88.347782 -285.636107) (xy 88.311078 -285.671362) (xy 88.269194 -285.700272) (xy 88.223215 -285.722089)
			(xy 88.174331 -285.736249) (xy 88.12381 -285.742383) (xy 88.072958 -285.740334) (xy 88.023094 -285.730154)
			(xy 87.975508 -285.712107) (xy 87.931434 -285.686661) (xy 87.892012 -285.654474) (xy 87.858264 -285.61638)
			(xy 87.831063 -285.573366) (xy 87.811115 -285.526546) (xy 87.798936 -285.477132) (xy 87.794841 -285.426404)
			(xy 87.47633 -285.426404) (xy 87.475835 -285.451011) (xy 87.46794 -285.499588) (xy 87.452356 -285.546269)
			(xy 87.429485 -285.589846) (xy 87.39992 -285.62919) (xy 87.364427 -285.663282) (xy 87.323924 -285.691238)
			(xy 87.279462 -285.712336) (xy 87.232191 -285.726028) (xy 87.183336 -285.73196) (xy 87.134161 -285.729979)
			(xy 87.085942 -285.720135) (xy 87.039926 -285.702683) (xy 86.997305 -285.678076) (xy 86.959184 -285.646951)
			(xy 86.926549 -285.610114) (xy 86.900246 -285.568518) (xy 86.880955 -285.523242) (xy 86.869178 -285.475458)
			(xy 86.865218 -285.426404) (xy 86.54669 -285.426404) (xy 86.546178 -285.45185) (xy 86.538014 -285.502084)
			(xy 86.521898 -285.550358) (xy 86.498247 -285.595421) (xy 86.467674 -285.636107) (xy 86.43097 -285.671362)
			(xy 86.389086 -285.700272) (xy 86.343107 -285.722089) (xy 86.294223 -285.736249) (xy 86.243702 -285.742383)
			(xy 86.19285 -285.740334) (xy 86.142986 -285.730154) (xy 86.0954 -285.712107) (xy 86.051326 -285.686661)
			(xy 86.011904 -285.654474) (xy 85.978156 -285.61638) (xy 85.950955 -285.573366) (xy 85.931007 -285.526546)
			(xy 85.918828 -285.477132) (xy 85.914733 -285.426404) (xy 85.596222 -285.426404) (xy 85.595727 -285.451011)
			(xy 85.587832 -285.499588) (xy 85.572248 -285.546269) (xy 85.549377 -285.589846) (xy 85.519812 -285.62919)
			(xy 85.484319 -285.663282) (xy 85.443816 -285.691238) (xy 85.399354 -285.712336) (xy 85.352083 -285.726028)
			(xy 85.303228 -285.73196) (xy 85.254053 -285.729979) (xy 85.205834 -285.720135) (xy 85.159818 -285.702683)
			(xy 85.117197 -285.678076) (xy 85.079076 -285.646951) (xy 85.046441 -285.610114) (xy 85.020138 -285.568518)
			(xy 85.000847 -285.523242) (xy 84.98907 -285.475458) (xy 84.98511 -285.426404) (xy 84.666836 -285.426404)
			(xy 84.666324 -285.45185) (xy 84.65816 -285.502084) (xy 84.642044 -285.550358) (xy 84.618393 -285.595421)
			(xy 84.58782 -285.636107) (xy 84.551116 -285.671362) (xy 84.509232 -285.700272) (xy 84.463253 -285.722089)
			(xy 84.414369 -285.736249) (xy 84.363848 -285.742383) (xy 84.312996 -285.740334) (xy 84.263132 -285.730154)
			(xy 84.215546 -285.712107) (xy 84.171472 -285.686661) (xy 84.13205 -285.654474) (xy 84.098302 -285.61638)
			(xy 84.071101 -285.573366) (xy 84.051153 -285.526546) (xy 84.038974 -285.477132) (xy 84.034879 -285.426404)
			(xy 83.716368 -285.426404) (xy 83.715873 -285.451011) (xy 83.707978 -285.499588) (xy 83.692394 -285.546269)
			(xy 83.669523 -285.589846) (xy 83.639958 -285.62919) (xy 83.604465 -285.663282) (xy 83.563962 -285.691238)
			(xy 83.5195 -285.712336) (xy 83.472229 -285.726028) (xy 83.423374 -285.73196) (xy 83.374199 -285.729979)
			(xy 83.32598 -285.720135) (xy 83.279964 -285.702683) (xy 83.237343 -285.678076) (xy 83.199222 -285.646951)
			(xy 83.166587 -285.610114) (xy 83.140284 -285.568518) (xy 83.120993 -285.523242) (xy 83.109216 -285.475458)
			(xy 83.105256 -285.426404) (xy 82.786728 -285.426404) (xy 82.786216 -285.45185) (xy 82.778052 -285.502084)
			(xy 82.761936 -285.550358) (xy 82.738285 -285.595421) (xy 82.707712 -285.636107) (xy 82.671008 -285.671362)
			(xy 82.629124 -285.700272) (xy 82.583145 -285.722089) (xy 82.534261 -285.736249) (xy 82.48374 -285.742383)
			(xy 82.432888 -285.740334) (xy 82.383024 -285.730154) (xy 82.335438 -285.712107) (xy 82.291364 -285.686661)
			(xy 82.251942 -285.654474) (xy 82.218194 -285.61638) (xy 82.190993 -285.573366) (xy 82.171045 -285.526546)
			(xy 82.158866 -285.477132) (xy 82.154771 -285.426404) (xy 81.846674 -285.426404) (xy 81.846162 -285.45185)
			(xy 81.837998 -285.502084) (xy 81.821882 -285.550358) (xy 81.798231 -285.595421) (xy 81.767658 -285.636107)
			(xy 81.730954 -285.671362) (xy 81.68907 -285.700272) (xy 81.643091 -285.722089) (xy 81.594207 -285.736249)
			(xy 81.543686 -285.742383) (xy 81.492834 -285.740334) (xy 81.44297 -285.730154) (xy 81.395384 -285.712107)
			(xy 81.35131 -285.686661) (xy 81.311888 -285.654474) (xy 81.27814 -285.61638) (xy 81.250939 -285.573366)
			(xy 81.230991 -285.526546) (xy 81.218812 -285.477132) (xy 81.214717 -285.426404) (xy 80.89646 -285.426404)
			(xy 80.895965 -285.451011) (xy 80.88807 -285.499588) (xy 80.872486 -285.546269) (xy 80.849615 -285.589846)
			(xy 80.82005 -285.62919) (xy 80.784557 -285.663282) (xy 80.744054 -285.691238) (xy 80.699592 -285.712336)
			(xy 80.652321 -285.726028) (xy 80.603466 -285.73196) (xy 80.554291 -285.729979) (xy 80.506072 -285.720135)
			(xy 80.460056 -285.702683) (xy 80.417435 -285.678076) (xy 80.379314 -285.646951) (xy 80.346679 -285.610114)
			(xy 80.320376 -285.568518) (xy 80.301085 -285.523242) (xy 80.289308 -285.475458) (xy 80.285348 -285.426404)
			(xy 79.016352 -285.426404) (xy 79.015857 -285.451011) (xy 79.007962 -285.499588) (xy 78.992378 -285.546269)
			(xy 78.969507 -285.589846) (xy 78.939942 -285.62919) (xy 78.904449 -285.663282) (xy 78.863946 -285.691238)
			(xy 78.819484 -285.712336) (xy 78.772213 -285.726028) (xy 78.723358 -285.73196) (xy 78.674183 -285.729979)
			(xy 78.625964 -285.720135) (xy 78.579948 -285.702683) (xy 78.537327 -285.678076) (xy 78.499206 -285.646951)
			(xy 78.466571 -285.610114) (xy 78.440268 -285.568518) (xy 78.420977 -285.523242) (xy 78.4092 -285.475458)
			(xy 78.40524 -285.426404) (xy 73.228962 -285.426404) (xy 73.228962 -285.970472) (xy 76.807072 -285.970472)
			(xy 76.811032 -285.921418) (xy 76.822809 -285.873634) (xy 76.8421 -285.828358) (xy 76.868403 -285.786762)
			(xy 76.901038 -285.749925) (xy 76.939159 -285.7188) (xy 76.98178 -285.694193) (xy 77.027796 -285.676741)
			(xy 77.076015 -285.666897) (xy 77.12519 -285.664916) (xy 77.174045 -285.670848) (xy 77.221316 -285.68454)
			(xy 77.265778 -285.705638) (xy 77.306281 -285.733594) (xy 77.341774 -285.767686) (xy 77.371339 -285.80703)
			(xy 77.39421 -285.850607) (xy 77.409794 -285.897288) (xy 77.417689 -285.945865) (xy 77.418184 -285.970472)
			(xy 77.417689 -285.995079) (xy 77.409794 -286.043656) (xy 77.39421 -286.090337) (xy 77.371339 -286.133914)
			(xy 77.341774 -286.173258) (xy 77.306281 -286.20735) (xy 77.265778 -286.235306) (xy 77.263451 -286.23641)
			(xy 79.815194 -286.23641) (xy 79.819154 -286.187356) (xy 79.830931 -286.139572) (xy 79.850222 -286.094296)
			(xy 79.876525 -286.0527) (xy 79.90916 -286.015863) (xy 79.947281 -285.984738) (xy 79.989902 -285.960131)
			(xy 80.035918 -285.942679) (xy 80.084137 -285.932835) (xy 80.133312 -285.930854) (xy 80.182167 -285.936786)
			(xy 80.229438 -285.950478) (xy 80.2739 -285.971576) (xy 80.314403 -285.999532) (xy 80.349896 -286.033624)
			(xy 80.379461 -286.072968) (xy 80.402332 -286.116545) (xy 80.417916 -286.163226) (xy 80.425811 -286.211803)
			(xy 80.426306 -286.23641) (xy 80.744817 -286.23641) (xy 80.748912 -286.185682) (xy 80.761091 -286.136268)
			(xy 80.781039 -286.089448) (xy 80.80824 -286.046434) (xy 80.841988 -286.00834) (xy 80.88141 -285.976153)
			(xy 80.925484 -285.950707) (xy 80.97307 -285.93266) (xy 81.022934 -285.92248) (xy 81.073786 -285.920431)
			(xy 81.124307 -285.926565) (xy 81.173191 -285.940725) (xy 81.21917 -285.962542) (xy 81.261054 -285.991452)
			(xy 81.297758 -286.026707) (xy 81.328331 -286.067393) (xy 81.351982 -286.112456) (xy 81.368098 -286.16073)
			(xy 81.376262 -286.210964) (xy 81.376774 -286.23641) (xy 81.695302 -286.23641) (xy 81.699262 -286.187356)
			(xy 81.711039 -286.139572) (xy 81.73033 -286.094296) (xy 81.756633 -286.0527) (xy 81.789268 -286.015863)
			(xy 81.827389 -285.984738) (xy 81.87001 -285.960131) (xy 81.916026 -285.942679) (xy 81.964245 -285.932835)
			(xy 82.01342 -285.930854) (xy 82.062275 -285.936786) (xy 82.109546 -285.950478) (xy 82.154008 -285.971576)
			(xy 82.194511 -285.999532) (xy 82.230004 -286.033624) (xy 82.259569 -286.072968) (xy 82.28244 -286.116545)
			(xy 82.298024 -286.163226) (xy 82.305919 -286.211803) (xy 82.306414 -286.23641) (xy 82.624671 -286.23641)
			(xy 82.628766 -286.185682) (xy 82.640945 -286.136268) (xy 82.660893 -286.089448) (xy 82.688094 -286.046434)
			(xy 82.721842 -286.00834) (xy 82.761264 -285.976153) (xy 82.805338 -285.950707) (xy 82.852924 -285.93266)
			(xy 82.902788 -285.92248) (xy 82.95364 -285.920431) (xy 83.004161 -285.926565) (xy 83.053045 -285.940725)
			(xy 83.099024 -285.962542) (xy 83.140908 -285.991452) (xy 83.177612 -286.026707) (xy 83.208185 -286.067393)
			(xy 83.231836 -286.112456) (xy 83.247952 -286.16073) (xy 83.256116 -286.210964) (xy 83.256628 -286.23641)
			(xy 83.575156 -286.23641) (xy 83.579116 -286.187356) (xy 83.590893 -286.139572) (xy 83.610184 -286.094296)
			(xy 83.636487 -286.0527) (xy 83.669122 -286.015863) (xy 83.707243 -285.984738) (xy 83.749864 -285.960131)
			(xy 83.79588 -285.942679) (xy 83.844099 -285.932835) (xy 83.893274 -285.930854) (xy 83.942129 -285.936786)
			(xy 83.9894 -285.950478) (xy 84.033862 -285.971576) (xy 84.074365 -285.999532) (xy 84.109858 -286.033624)
			(xy 84.139423 -286.072968) (xy 84.162294 -286.116545) (xy 84.177878 -286.163226) (xy 84.185773 -286.211803)
			(xy 84.186268 -286.23641) (xy 84.504779 -286.23641) (xy 84.508874 -286.185682) (xy 84.521053 -286.136268)
			(xy 84.541001 -286.089448) (xy 84.568202 -286.046434) (xy 84.60195 -286.00834) (xy 84.641372 -285.976153)
			(xy 84.685446 -285.950707) (xy 84.733032 -285.93266) (xy 84.782896 -285.92248) (xy 84.833748 -285.920431)
			(xy 84.884269 -285.926565) (xy 84.933153 -285.940725) (xy 84.979132 -285.962542) (xy 85.021016 -285.991452)
			(xy 85.05772 -286.026707) (xy 85.088293 -286.067393) (xy 85.111944 -286.112456) (xy 85.12806 -286.16073)
			(xy 85.136224 -286.210964) (xy 85.136736 -286.23641) (xy 85.444833 -286.23641) (xy 85.448928 -286.185682)
			(xy 85.461107 -286.136268) (xy 85.481055 -286.089448) (xy 85.508256 -286.046434) (xy 85.542004 -286.00834)
			(xy 85.581426 -285.976153) (xy 85.6255 -285.950707) (xy 85.673086 -285.93266) (xy 85.72295 -285.92248)
			(xy 85.773802 -285.920431) (xy 85.824323 -285.926565) (xy 85.873207 -285.940725) (xy 85.919186 -285.962542)
			(xy 85.96107 -285.991452) (xy 85.997774 -286.026707) (xy 86.028347 -286.067393) (xy 86.051998 -286.112456)
			(xy 86.068114 -286.16073) (xy 86.076278 -286.210964) (xy 86.07679 -286.23641) (xy 86.395318 -286.23641)
			(xy 86.399278 -286.187356) (xy 86.411055 -286.139572) (xy 86.430346 -286.094296) (xy 86.456649 -286.0527)
			(xy 86.489284 -286.015863) (xy 86.527405 -285.984738) (xy 86.570026 -285.960131) (xy 86.616042 -285.942679)
			(xy 86.664261 -285.932835) (xy 86.713436 -285.930854) (xy 86.762291 -285.936786) (xy 86.809562 -285.950478)
			(xy 86.854024 -285.971576) (xy 86.894527 -285.999532) (xy 86.93002 -286.033624) (xy 86.959585 -286.072968)
			(xy 86.982456 -286.116545) (xy 86.99804 -286.163226) (xy 87.005935 -286.211803) (xy 87.00643 -286.23641)
			(xy 87.324687 -286.23641) (xy 87.328782 -286.185682) (xy 87.340961 -286.136268) (xy 87.360909 -286.089448)
			(xy 87.38811 -286.046434) (xy 87.421858 -286.00834) (xy 87.46128 -285.976153) (xy 87.505354 -285.950707)
			(xy 87.55294 -285.93266) (xy 87.602804 -285.92248) (xy 87.653656 -285.920431) (xy 87.704177 -285.926565)
			(xy 87.753061 -285.940725) (xy 87.79904 -285.962542) (xy 87.840924 -285.991452) (xy 87.877628 -286.026707)
			(xy 87.908201 -286.067393) (xy 87.931852 -286.112456) (xy 87.947968 -286.16073) (xy 87.956132 -286.210964)
			(xy 87.956644 -286.23641) (xy 88.275172 -286.23641) (xy 88.279132 -286.187356) (xy 88.290909 -286.139572)
			(xy 88.3102 -286.094296) (xy 88.336503 -286.0527) (xy 88.369138 -286.015863) (xy 88.407259 -285.984738)
			(xy 88.44988 -285.960131) (xy 88.495896 -285.942679) (xy 88.544115 -285.932835) (xy 88.59329 -285.930854)
			(xy 88.642145 -285.936786) (xy 88.689416 -285.950478) (xy 88.733878 -285.971576) (xy 88.774381 -285.999532)
			(xy 88.809874 -286.033624) (xy 88.839439 -286.072968) (xy 88.86231 -286.116545) (xy 88.877894 -286.163226)
			(xy 88.885789 -286.211803) (xy 88.886284 -286.23641) (xy 89.204795 -286.23641) (xy 89.20889 -286.185682)
			(xy 89.221069 -286.136268) (xy 89.241017 -286.089448) (xy 89.268218 -286.046434) (xy 89.301966 -286.00834)
			(xy 89.341388 -285.976153) (xy 89.385462 -285.950707) (xy 89.433048 -285.93266) (xy 89.482912 -285.92248)
			(xy 89.533764 -285.920431) (xy 89.584285 -285.926565) (xy 89.633169 -285.940725) (xy 89.679148 -285.962542)
			(xy 89.721032 -285.991452) (xy 89.757736 -286.026707) (xy 89.788309 -286.067393) (xy 89.81196 -286.112456)
			(xy 89.828076 -286.16073) (xy 89.83624 -286.210964) (xy 89.836752 -286.23641) (xy 90.15528 -286.23641)
			(xy 90.15924 -286.187356) (xy 90.171017 -286.139572) (xy 90.190308 -286.094296) (xy 90.216611 -286.0527)
			(xy 90.249246 -286.015863) (xy 90.287367 -285.984738) (xy 90.329988 -285.960131) (xy 90.376004 -285.942679)
			(xy 90.424223 -285.932835) (xy 90.473398 -285.930854) (xy 90.522253 -285.936786) (xy 90.569524 -285.950478)
			(xy 90.613986 -285.971576) (xy 90.654489 -285.999532) (xy 90.689982 -286.033624) (xy 90.719547 -286.072968)
			(xy 90.742418 -286.116545) (xy 90.758002 -286.163226) (xy 90.765897 -286.211803) (xy 90.766392 -286.23641)
			(xy 91.084903 -286.23641) (xy 91.088998 -286.185682) (xy 91.101177 -286.136268) (xy 91.121125 -286.089448)
			(xy 91.148326 -286.046434) (xy 91.182074 -286.00834) (xy 91.221496 -285.976153) (xy 91.26557 -285.950707)
			(xy 91.313156 -285.93266) (xy 91.36302 -285.92248) (xy 91.413872 -285.920431) (xy 91.464393 -285.926565)
			(xy 91.513277 -285.940725) (xy 91.559256 -285.962542) (xy 91.60114 -285.991452) (xy 91.637844 -286.026707)
			(xy 91.668417 -286.067393) (xy 91.692068 -286.112456) (xy 91.708184 -286.16073) (xy 91.716348 -286.210964)
			(xy 91.71686 -286.23641) (xy 92.024703 -286.23641) (xy 92.028798 -286.185682) (xy 92.040977 -286.136268)
			(xy 92.060925 -286.089448) (xy 92.088126 -286.046434) (xy 92.121874 -286.00834) (xy 92.161296 -285.976153)
			(xy 92.20537 -285.950707) (xy 92.252956 -285.93266) (xy 92.30282 -285.92248) (xy 92.353672 -285.920431)
			(xy 92.404193 -285.926565) (xy 92.453077 -285.940725) (xy 92.499056 -285.962542) (xy 92.54094 -285.991452)
			(xy 92.577644 -286.026707) (xy 92.608217 -286.067393) (xy 92.631868 -286.112456) (xy 92.647984 -286.16073)
			(xy 92.656148 -286.210964) (xy 92.65666 -286.23641) (xy 92.975188 -286.23641) (xy 92.979148 -286.187356)
			(xy 92.990925 -286.139572) (xy 93.010216 -286.094296) (xy 93.036519 -286.0527) (xy 93.069154 -286.015863)
			(xy 93.107275 -285.984738) (xy 93.149896 -285.960131) (xy 93.195912 -285.942679) (xy 93.244131 -285.932835)
			(xy 93.293306 -285.930854) (xy 93.342161 -285.936786) (xy 93.389432 -285.950478) (xy 93.433894 -285.971576)
			(xy 93.474397 -285.999532) (xy 93.50989 -286.033624) (xy 93.539455 -286.072968) (xy 93.562326 -286.116545)
			(xy 93.57791 -286.163226) (xy 93.585805 -286.211803) (xy 93.5863 -286.23641) (xy 93.904811 -286.23641)
			(xy 93.908906 -286.185682) (xy 93.921085 -286.136268) (xy 93.941033 -286.089448) (xy 93.968234 -286.046434)
			(xy 94.001982 -286.00834) (xy 94.041404 -285.976153) (xy 94.085478 -285.950707) (xy 94.133064 -285.93266)
			(xy 94.182928 -285.92248) (xy 94.23378 -285.920431) (xy 94.284301 -285.926565) (xy 94.333185 -285.940725)
			(xy 94.379164 -285.962542) (xy 94.421048 -285.991452) (xy 94.457752 -286.026707) (xy 94.488325 -286.067393)
			(xy 94.511976 -286.112456) (xy 94.528092 -286.16073) (xy 94.536256 -286.210964) (xy 94.536768 -286.23641)
			(xy 94.855296 -286.23641) (xy 94.859256 -286.187356) (xy 94.871033 -286.139572) (xy 94.890324 -286.094296)
			(xy 94.916627 -286.0527) (xy 94.949262 -286.015863) (xy 94.987383 -285.984738) (xy 95.030004 -285.960131)
			(xy 95.07602 -285.942679) (xy 95.124239 -285.932835) (xy 95.173414 -285.930854) (xy 95.222269 -285.936786)
			(xy 95.26954 -285.950478) (xy 95.314002 -285.971576) (xy 95.354505 -285.999532) (xy 95.389998 -286.033624)
			(xy 95.419563 -286.072968) (xy 95.442434 -286.116545) (xy 95.458018 -286.163226) (xy 95.465913 -286.211803)
			(xy 95.466408 -286.23641) (xy 95.784919 -286.23641) (xy 95.789014 -286.185682) (xy 95.801193 -286.136268)
			(xy 95.821141 -286.089448) (xy 95.848342 -286.046434) (xy 95.88209 -286.00834) (xy 95.921512 -285.976153)
			(xy 95.965586 -285.950707) (xy 96.013172 -285.93266) (xy 96.063036 -285.92248) (xy 96.113888 -285.920431)
			(xy 96.164409 -285.926565) (xy 96.213293 -285.940725) (xy 96.259272 -285.962542) (xy 96.301156 -285.991452)
			(xy 96.33786 -286.026707) (xy 96.368433 -286.067393) (xy 96.392084 -286.112456) (xy 96.4082 -286.16073)
			(xy 96.416364 -286.210964) (xy 96.416876 -286.23641) (xy 96.73515 -286.23641) (xy 96.73911 -286.187356)
			(xy 96.750887 -286.139572) (xy 96.770178 -286.094296) (xy 96.796481 -286.0527) (xy 96.829116 -286.015863)
			(xy 96.867237 -285.984738) (xy 96.909858 -285.960131) (xy 96.955874 -285.942679) (xy 97.004093 -285.932835)
			(xy 97.053268 -285.930854) (xy 97.102123 -285.936786) (xy 97.149394 -285.950478) (xy 97.193856 -285.971576)
			(xy 97.234359 -285.999532) (xy 97.269852 -286.033624) (xy 97.299417 -286.072968) (xy 97.322288 -286.116545)
			(xy 97.337872 -286.163226) (xy 97.345767 -286.211803) (xy 97.346262 -286.23641) (xy 97.664773 -286.23641)
			(xy 97.668868 -286.185682) (xy 97.681047 -286.136268) (xy 97.700995 -286.089448) (xy 97.728196 -286.046434)
			(xy 97.761944 -286.00834) (xy 97.801366 -285.976153) (xy 97.84544 -285.950707) (xy 97.893026 -285.93266)
			(xy 97.94289 -285.92248) (xy 97.993742 -285.920431) (xy 98.044263 -285.926565) (xy 98.093147 -285.940725)
			(xy 98.139126 -285.962542) (xy 98.18101 -285.991452) (xy 98.217714 -286.026707) (xy 98.248287 -286.067393)
			(xy 98.271938 -286.112456) (xy 98.288054 -286.16073) (xy 98.296218 -286.210964) (xy 98.29673 -286.23641)
			(xy 98.604827 -286.23641) (xy 98.608922 -286.185682) (xy 98.621101 -286.136268) (xy 98.641049 -286.089448)
			(xy 98.66825 -286.046434) (xy 98.701998 -286.00834) (xy 98.74142 -285.976153) (xy 98.785494 -285.950707)
			(xy 98.83308 -285.93266) (xy 98.882944 -285.92248) (xy 98.933796 -285.920431) (xy 98.984317 -285.926565)
			(xy 99.033201 -285.940725) (xy 99.07918 -285.962542) (xy 99.121064 -285.991452) (xy 99.157768 -286.026707)
			(xy 99.188341 -286.067393) (xy 99.211992 -286.112456) (xy 99.228108 -286.16073) (xy 99.236272 -286.210964)
			(xy 99.236784 -286.23641) (xy 99.555312 -286.23641) (xy 99.559272 -286.187356) (xy 99.571049 -286.139572)
			(xy 99.59034 -286.094296) (xy 99.616643 -286.0527) (xy 99.649278 -286.015863) (xy 99.687399 -285.984738)
			(xy 99.73002 -285.960131) (xy 99.776036 -285.942679) (xy 99.824255 -285.932835) (xy 99.87343 -285.930854)
			(xy 99.922285 -285.936786) (xy 99.969556 -285.950478) (xy 100.014018 -285.971576) (xy 100.054521 -285.999532)
			(xy 100.090014 -286.033624) (xy 100.119579 -286.072968) (xy 100.14245 -286.116545) (xy 100.158034 -286.163226)
			(xy 100.165929 -286.211803) (xy 100.166424 -286.23641) (xy 100.484935 -286.23641) (xy 100.48903 -286.185682)
			(xy 100.501209 -286.136268) (xy 100.521157 -286.089448) (xy 100.548358 -286.046434) (xy 100.582106 -286.00834)
			(xy 100.621528 -285.976153) (xy 100.665602 -285.950707) (xy 100.713188 -285.93266) (xy 100.763052 -285.92248)
			(xy 100.813904 -285.920431) (xy 100.864425 -285.926565) (xy 100.913309 -285.940725) (xy 100.959288 -285.962542)
			(xy 101.001172 -285.991452) (xy 101.037876 -286.026707) (xy 101.068449 -286.067393) (xy 101.0921 -286.112456)
			(xy 101.108216 -286.16073) (xy 101.11638 -286.210964) (xy 101.116892 -286.23641) (xy 101.424735 -286.23641)
			(xy 101.42883 -286.185682) (xy 101.441009 -286.136268) (xy 101.460957 -286.089448) (xy 101.488158 -286.046434)
			(xy 101.521906 -286.00834) (xy 101.561328 -285.976153) (xy 101.605402 -285.950707) (xy 101.652988 -285.93266)
			(xy 101.702852 -285.92248) (xy 101.753704 -285.920431) (xy 101.804225 -285.926565) (xy 101.853109 -285.940725)
			(xy 101.899088 -285.962542) (xy 101.940972 -285.991452) (xy 101.977676 -286.026707) (xy 102.008249 -286.067393)
			(xy 102.0319 -286.112456) (xy 102.048016 -286.16073) (xy 102.05618 -286.210964) (xy 102.056692 -286.23641)
			(xy 102.05618 -286.261856) (xy 102.048016 -286.31209) (xy 102.0319 -286.360364) (xy 102.008249 -286.405427)
			(xy 101.977676 -286.446113) (xy 101.940972 -286.481368) (xy 101.899088 -286.510278) (xy 101.853109 -286.532095)
			(xy 101.804225 -286.546255) (xy 101.753704 -286.552389) (xy 101.702852 -286.55034) (xy 101.652988 -286.54016)
			(xy 101.605402 -286.522113) (xy 101.561328 -286.496667) (xy 101.521906 -286.46448) (xy 101.488158 -286.426386)
			(xy 101.460957 -286.383372) (xy 101.441009 -286.336552) (xy 101.42883 -286.287138) (xy 101.424735 -286.23641)
			(xy 101.116892 -286.23641) (xy 101.11638 -286.261856) (xy 101.108216 -286.31209) (xy 101.0921 -286.360364)
			(xy 101.068449 -286.405427) (xy 101.037876 -286.446113) (xy 101.001172 -286.481368) (xy 100.959288 -286.510278)
			(xy 100.913309 -286.532095) (xy 100.864425 -286.546255) (xy 100.813904 -286.552389) (xy 100.763052 -286.55034)
			(xy 100.713188 -286.54016) (xy 100.665602 -286.522113) (xy 100.621528 -286.496667) (xy 100.582106 -286.46448)
			(xy 100.548358 -286.426386) (xy 100.521157 -286.383372) (xy 100.501209 -286.336552) (xy 100.48903 -286.287138)
			(xy 100.484935 -286.23641) (xy 100.166424 -286.23641) (xy 100.165929 -286.261017) (xy 100.158034 -286.309594)
			(xy 100.14245 -286.356275) (xy 100.119579 -286.399852) (xy 100.090014 -286.439196) (xy 100.054521 -286.473288)
			(xy 100.014018 -286.501244) (xy 99.969556 -286.522342) (xy 99.922285 -286.536034) (xy 99.87343 -286.541966)
			(xy 99.824255 -286.539985) (xy 99.776036 -286.530141) (xy 99.73002 -286.512689) (xy 99.687399 -286.488082)
			(xy 99.649278 -286.456957) (xy 99.616643 -286.42012) (xy 99.59034 -286.378524) (xy 99.571049 -286.333248)
			(xy 99.559272 -286.285464) (xy 99.555312 -286.23641) (xy 99.236784 -286.23641) (xy 99.236272 -286.261856)
			(xy 99.228108 -286.31209) (xy 99.211992 -286.360364) (xy 99.188341 -286.405427) (xy 99.157768 -286.446113)
			(xy 99.121064 -286.481368) (xy 99.07918 -286.510278) (xy 99.033201 -286.532095) (xy 98.984317 -286.546255)
			(xy 98.933796 -286.552389) (xy 98.882944 -286.55034) (xy 98.83308 -286.54016) (xy 98.785494 -286.522113)
			(xy 98.74142 -286.496667) (xy 98.701998 -286.46448) (xy 98.66825 -286.426386) (xy 98.641049 -286.383372)
			(xy 98.621101 -286.336552) (xy 98.608922 -286.287138) (xy 98.604827 -286.23641) (xy 98.29673 -286.23641)
			(xy 98.296218 -286.261856) (xy 98.288054 -286.31209) (xy 98.271938 -286.360364) (xy 98.248287 -286.405427)
			(xy 98.217714 -286.446113) (xy 98.18101 -286.481368) (xy 98.139126 -286.510278) (xy 98.093147 -286.532095)
			(xy 98.044263 -286.546255) (xy 97.993742 -286.552389) (xy 97.94289 -286.55034) (xy 97.893026 -286.54016)
			(xy 97.84544 -286.522113) (xy 97.801366 -286.496667) (xy 97.761944 -286.46448) (xy 97.728196 -286.426386)
			(xy 97.700995 -286.383372) (xy 97.681047 -286.336552) (xy 97.668868 -286.287138) (xy 97.664773 -286.23641)
			(xy 97.346262 -286.23641) (xy 97.345767 -286.261017) (xy 97.337872 -286.309594) (xy 97.322288 -286.356275)
			(xy 97.299417 -286.399852) (xy 97.269852 -286.439196) (xy 97.234359 -286.473288) (xy 97.193856 -286.501244)
			(xy 97.149394 -286.522342) (xy 97.102123 -286.536034) (xy 97.053268 -286.541966) (xy 97.004093 -286.539985)
			(xy 96.955874 -286.530141) (xy 96.909858 -286.512689) (xy 96.867237 -286.488082) (xy 96.829116 -286.456957)
			(xy 96.796481 -286.42012) (xy 96.770178 -286.378524) (xy 96.750887 -286.333248) (xy 96.73911 -286.285464)
			(xy 96.73515 -286.23641) (xy 96.416876 -286.23641) (xy 96.416364 -286.261856) (xy 96.4082 -286.31209)
			(xy 96.392084 -286.360364) (xy 96.368433 -286.405427) (xy 96.33786 -286.446113) (xy 96.301156 -286.481368)
			(xy 96.259272 -286.510278) (xy 96.213293 -286.532095) (xy 96.164409 -286.546255) (xy 96.113888 -286.552389)
			(xy 96.063036 -286.55034) (xy 96.013172 -286.54016) (xy 95.965586 -286.522113) (xy 95.921512 -286.496667)
			(xy 95.88209 -286.46448) (xy 95.848342 -286.426386) (xy 95.821141 -286.383372) (xy 95.801193 -286.336552)
			(xy 95.789014 -286.287138) (xy 95.784919 -286.23641) (xy 95.466408 -286.23641) (xy 95.465913 -286.261017)
			(xy 95.458018 -286.309594) (xy 95.442434 -286.356275) (xy 95.419563 -286.399852) (xy 95.389998 -286.439196)
			(xy 95.354505 -286.473288) (xy 95.314002 -286.501244) (xy 95.26954 -286.522342) (xy 95.222269 -286.536034)
			(xy 95.173414 -286.541966) (xy 95.124239 -286.539985) (xy 95.07602 -286.530141) (xy 95.030004 -286.512689)
			(xy 94.987383 -286.488082) (xy 94.949262 -286.456957) (xy 94.916627 -286.42012) (xy 94.890324 -286.378524)
			(xy 94.871033 -286.333248) (xy 94.859256 -286.285464) (xy 94.855296 -286.23641) (xy 94.536768 -286.23641)
			(xy 94.536256 -286.261856) (xy 94.528092 -286.31209) (xy 94.511976 -286.360364) (xy 94.488325 -286.405427)
			(xy 94.457752 -286.446113) (xy 94.421048 -286.481368) (xy 94.379164 -286.510278) (xy 94.333185 -286.532095)
			(xy 94.284301 -286.546255) (xy 94.23378 -286.552389) (xy 94.182928 -286.55034) (xy 94.133064 -286.54016)
			(xy 94.085478 -286.522113) (xy 94.041404 -286.496667) (xy 94.001982 -286.46448) (xy 93.968234 -286.426386)
			(xy 93.941033 -286.383372) (xy 93.921085 -286.336552) (xy 93.908906 -286.287138) (xy 93.904811 -286.23641)
			(xy 93.5863 -286.23641) (xy 93.585805 -286.261017) (xy 93.57791 -286.309594) (xy 93.562326 -286.356275)
			(xy 93.539455 -286.399852) (xy 93.50989 -286.439196) (xy 93.474397 -286.473288) (xy 93.433894 -286.501244)
			(xy 93.389432 -286.522342) (xy 93.342161 -286.536034) (xy 93.293306 -286.541966) (xy 93.244131 -286.539985)
			(xy 93.195912 -286.530141) (xy 93.149896 -286.512689) (xy 93.107275 -286.488082) (xy 93.069154 -286.456957)
			(xy 93.036519 -286.42012) (xy 93.010216 -286.378524) (xy 92.990925 -286.333248) (xy 92.979148 -286.285464)
			(xy 92.975188 -286.23641) (xy 92.65666 -286.23641) (xy 92.656148 -286.261856) (xy 92.647984 -286.31209)
			(xy 92.631868 -286.360364) (xy 92.608217 -286.405427) (xy 92.577644 -286.446113) (xy 92.54094 -286.481368)
			(xy 92.499056 -286.510278) (xy 92.453077 -286.532095) (xy 92.404193 -286.546255) (xy 92.353672 -286.552389)
			(xy 92.30282 -286.55034) (xy 92.252956 -286.54016) (xy 92.20537 -286.522113) (xy 92.161296 -286.496667)
			(xy 92.121874 -286.46448) (xy 92.088126 -286.426386) (xy 92.060925 -286.383372) (xy 92.040977 -286.336552)
			(xy 92.028798 -286.287138) (xy 92.024703 -286.23641) (xy 91.71686 -286.23641) (xy 91.716348 -286.261856)
			(xy 91.708184 -286.31209) (xy 91.692068 -286.360364) (xy 91.668417 -286.405427) (xy 91.637844 -286.446113)
			(xy 91.60114 -286.481368) (xy 91.559256 -286.510278) (xy 91.513277 -286.532095) (xy 91.464393 -286.546255)
			(xy 91.413872 -286.552389) (xy 91.36302 -286.55034) (xy 91.313156 -286.54016) (xy 91.26557 -286.522113)
			(xy 91.221496 -286.496667) (xy 91.182074 -286.46448) (xy 91.148326 -286.426386) (xy 91.121125 -286.383372)
			(xy 91.101177 -286.336552) (xy 91.088998 -286.287138) (xy 91.084903 -286.23641) (xy 90.766392 -286.23641)
			(xy 90.765897 -286.261017) (xy 90.758002 -286.309594) (xy 90.742418 -286.356275) (xy 90.719547 -286.399852)
			(xy 90.689982 -286.439196) (xy 90.654489 -286.473288) (xy 90.613986 -286.501244) (xy 90.569524 -286.522342)
			(xy 90.522253 -286.536034) (xy 90.473398 -286.541966) (xy 90.424223 -286.539985) (xy 90.376004 -286.530141)
			(xy 90.329988 -286.512689) (xy 90.287367 -286.488082) (xy 90.249246 -286.456957) (xy 90.216611 -286.42012)
			(xy 90.190308 -286.378524) (xy 90.171017 -286.333248) (xy 90.15924 -286.285464) (xy 90.15528 -286.23641)
			(xy 89.836752 -286.23641) (xy 89.83624 -286.261856) (xy 89.828076 -286.31209) (xy 89.81196 -286.360364)
			(xy 89.788309 -286.405427) (xy 89.757736 -286.446113) (xy 89.721032 -286.481368) (xy 89.679148 -286.510278)
			(xy 89.633169 -286.532095) (xy 89.584285 -286.546255) (xy 89.533764 -286.552389) (xy 89.482912 -286.55034)
			(xy 89.433048 -286.54016) (xy 89.385462 -286.522113) (xy 89.341388 -286.496667) (xy 89.301966 -286.46448)
			(xy 89.268218 -286.426386) (xy 89.241017 -286.383372) (xy 89.221069 -286.336552) (xy 89.20889 -286.287138)
			(xy 89.204795 -286.23641) (xy 88.886284 -286.23641) (xy 88.885789 -286.261017) (xy 88.877894 -286.309594)
			(xy 88.86231 -286.356275) (xy 88.839439 -286.399852) (xy 88.809874 -286.439196) (xy 88.774381 -286.473288)
			(xy 88.733878 -286.501244) (xy 88.689416 -286.522342) (xy 88.642145 -286.536034) (xy 88.59329 -286.541966)
			(xy 88.544115 -286.539985) (xy 88.495896 -286.530141) (xy 88.44988 -286.512689) (xy 88.407259 -286.488082)
			(xy 88.369138 -286.456957) (xy 88.336503 -286.42012) (xy 88.3102 -286.378524) (xy 88.290909 -286.333248)
			(xy 88.279132 -286.285464) (xy 88.275172 -286.23641) (xy 87.956644 -286.23641) (xy 87.956132 -286.261856)
			(xy 87.947968 -286.31209) (xy 87.931852 -286.360364) (xy 87.908201 -286.405427) (xy 87.877628 -286.446113)
			(xy 87.840924 -286.481368) (xy 87.79904 -286.510278) (xy 87.753061 -286.532095) (xy 87.704177 -286.546255)
			(xy 87.653656 -286.552389) (xy 87.602804 -286.55034) (xy 87.55294 -286.54016) (xy 87.505354 -286.522113)
			(xy 87.46128 -286.496667) (xy 87.421858 -286.46448) (xy 87.38811 -286.426386) (xy 87.360909 -286.383372)
			(xy 87.340961 -286.336552) (xy 87.328782 -286.287138) (xy 87.324687 -286.23641) (xy 87.00643 -286.23641)
			(xy 87.005935 -286.261017) (xy 86.99804 -286.309594) (xy 86.982456 -286.356275) (xy 86.959585 -286.399852)
			(xy 86.93002 -286.439196) (xy 86.894527 -286.473288) (xy 86.854024 -286.501244) (xy 86.809562 -286.522342)
			(xy 86.762291 -286.536034) (xy 86.713436 -286.541966) (xy 86.664261 -286.539985) (xy 86.616042 -286.530141)
			(xy 86.570026 -286.512689) (xy 86.527405 -286.488082) (xy 86.489284 -286.456957) (xy 86.456649 -286.42012)
			(xy 86.430346 -286.378524) (xy 86.411055 -286.333248) (xy 86.399278 -286.285464) (xy 86.395318 -286.23641)
			(xy 86.07679 -286.23641) (xy 86.076278 -286.261856) (xy 86.068114 -286.31209) (xy 86.051998 -286.360364)
			(xy 86.028347 -286.405427) (xy 85.997774 -286.446113) (xy 85.96107 -286.481368) (xy 85.919186 -286.510278)
			(xy 85.873207 -286.532095) (xy 85.824323 -286.546255) (xy 85.773802 -286.552389) (xy 85.72295 -286.55034)
			(xy 85.673086 -286.54016) (xy 85.6255 -286.522113) (xy 85.581426 -286.496667) (xy 85.542004 -286.46448)
			(xy 85.508256 -286.426386) (xy 85.481055 -286.383372) (xy 85.461107 -286.336552) (xy 85.448928 -286.287138)
			(xy 85.444833 -286.23641) (xy 85.136736 -286.23641) (xy 85.136224 -286.261856) (xy 85.12806 -286.31209)
			(xy 85.111944 -286.360364) (xy 85.088293 -286.405427) (xy 85.05772 -286.446113) (xy 85.021016 -286.481368)
			(xy 84.979132 -286.510278) (xy 84.933153 -286.532095) (xy 84.884269 -286.546255) (xy 84.833748 -286.552389)
			(xy 84.782896 -286.55034) (xy 84.733032 -286.54016) (xy 84.685446 -286.522113) (xy 84.641372 -286.496667)
			(xy 84.60195 -286.46448) (xy 84.568202 -286.426386) (xy 84.541001 -286.383372) (xy 84.521053 -286.336552)
			(xy 84.508874 -286.287138) (xy 84.504779 -286.23641) (xy 84.186268 -286.23641) (xy 84.185773 -286.261017)
			(xy 84.177878 -286.309594) (xy 84.162294 -286.356275) (xy 84.139423 -286.399852) (xy 84.109858 -286.439196)
			(xy 84.074365 -286.473288) (xy 84.033862 -286.501244) (xy 83.9894 -286.522342) (xy 83.942129 -286.536034)
			(xy 83.893274 -286.541966) (xy 83.844099 -286.539985) (xy 83.79588 -286.530141) (xy 83.749864 -286.512689)
			(xy 83.707243 -286.488082) (xy 83.669122 -286.456957) (xy 83.636487 -286.42012) (xy 83.610184 -286.378524)
			(xy 83.590893 -286.333248) (xy 83.579116 -286.285464) (xy 83.575156 -286.23641) (xy 83.256628 -286.23641)
			(xy 83.256116 -286.261856) (xy 83.247952 -286.31209) (xy 83.231836 -286.360364) (xy 83.208185 -286.405427)
			(xy 83.177612 -286.446113) (xy 83.140908 -286.481368) (xy 83.099024 -286.510278) (xy 83.053045 -286.532095)
			(xy 83.004161 -286.546255) (xy 82.95364 -286.552389) (xy 82.902788 -286.55034) (xy 82.852924 -286.54016)
			(xy 82.805338 -286.522113) (xy 82.761264 -286.496667) (xy 82.721842 -286.46448) (xy 82.688094 -286.426386)
			(xy 82.660893 -286.383372) (xy 82.640945 -286.336552) (xy 82.628766 -286.287138) (xy 82.624671 -286.23641)
			(xy 82.306414 -286.23641) (xy 82.305919 -286.261017) (xy 82.298024 -286.309594) (xy 82.28244 -286.356275)
			(xy 82.259569 -286.399852) (xy 82.230004 -286.439196) (xy 82.194511 -286.473288) (xy 82.154008 -286.501244)
			(xy 82.109546 -286.522342) (xy 82.062275 -286.536034) (xy 82.01342 -286.541966) (xy 81.964245 -286.539985)
			(xy 81.916026 -286.530141) (xy 81.87001 -286.512689) (xy 81.827389 -286.488082) (xy 81.789268 -286.456957)
			(xy 81.756633 -286.42012) (xy 81.73033 -286.378524) (xy 81.711039 -286.333248) (xy 81.699262 -286.285464)
			(xy 81.695302 -286.23641) (xy 81.376774 -286.23641) (xy 81.376262 -286.261856) (xy 81.368098 -286.31209)
			(xy 81.351982 -286.360364) (xy 81.328331 -286.405427) (xy 81.297758 -286.446113) (xy 81.261054 -286.481368)
			(xy 81.21917 -286.510278) (xy 81.173191 -286.532095) (xy 81.124307 -286.546255) (xy 81.073786 -286.552389)
			(xy 81.022934 -286.55034) (xy 80.97307 -286.54016) (xy 80.925484 -286.522113) (xy 80.88141 -286.496667)
			(xy 80.841988 -286.46448) (xy 80.80824 -286.426386) (xy 80.781039 -286.383372) (xy 80.761091 -286.336552)
			(xy 80.748912 -286.287138) (xy 80.744817 -286.23641) (xy 80.426306 -286.23641) (xy 80.425811 -286.261017)
			(xy 80.417916 -286.309594) (xy 80.402332 -286.356275) (xy 80.379461 -286.399852) (xy 80.349896 -286.439196)
			(xy 80.314403 -286.473288) (xy 80.2739 -286.501244) (xy 80.229438 -286.522342) (xy 80.182167 -286.536034)
			(xy 80.133312 -286.541966) (xy 80.084137 -286.539985) (xy 80.035918 -286.530141) (xy 79.989902 -286.512689)
			(xy 79.947281 -286.488082) (xy 79.90916 -286.456957) (xy 79.876525 -286.42012) (xy 79.850222 -286.378524)
			(xy 79.830931 -286.333248) (xy 79.819154 -286.285464) (xy 79.815194 -286.23641) (xy 77.263451 -286.23641)
			(xy 77.221316 -286.256404) (xy 77.174045 -286.270096) (xy 77.12519 -286.276028) (xy 77.076015 -286.274047)
			(xy 77.027796 -286.264203) (xy 76.98178 -286.246751) (xy 76.939159 -286.222144) (xy 76.901038 -286.191019)
			(xy 76.868403 -286.154182) (xy 76.8421 -286.112586) (xy 76.822809 -286.06731) (xy 76.811032 -286.019526)
			(xy 76.807072 -285.970472) (xy 73.228962 -285.970472) (xy 73.228962 -287.046162) (xy 78.40524 -287.046162)
			(xy 78.4092 -286.997108) (xy 78.420977 -286.949324) (xy 78.440268 -286.904048) (xy 78.466571 -286.862452)
			(xy 78.499206 -286.825615) (xy 78.537327 -286.79449) (xy 78.579948 -286.769883) (xy 78.625964 -286.752431)
			(xy 78.674183 -286.742587) (xy 78.723358 -286.740606) (xy 78.772213 -286.746538) (xy 78.819484 -286.76023)
			(xy 78.863946 -286.781328) (xy 78.904449 -286.809284) (xy 78.939942 -286.843376) (xy 78.969507 -286.88272)
			(xy 78.992378 -286.926297) (xy 79.007962 -286.972978) (xy 79.015857 -287.021555) (xy 79.016352 -287.046162)
			(xy 80.285348 -287.046162) (xy 80.289308 -286.997108) (xy 80.301085 -286.949324) (xy 80.320376 -286.904048)
			(xy 80.346679 -286.862452) (xy 80.379314 -286.825615) (xy 80.417435 -286.79449) (xy 80.460056 -286.769883)
			(xy 80.506072 -286.752431) (xy 80.554291 -286.742587) (xy 80.603466 -286.740606) (xy 80.652321 -286.746538)
			(xy 80.699592 -286.76023) (xy 80.744054 -286.781328) (xy 80.784557 -286.809284) (xy 80.82005 -286.843376)
			(xy 80.849615 -286.88272) (xy 80.872486 -286.926297) (xy 80.88807 -286.972978) (xy 80.895965 -287.021555)
			(xy 80.89646 -287.046162) (xy 81.214717 -287.046162) (xy 81.218812 -286.995434) (xy 81.230991 -286.94602)
			(xy 81.250939 -286.8992) (xy 81.27814 -286.856186) (xy 81.311888 -286.818092) (xy 81.35131 -286.785905)
			(xy 81.395384 -286.760459) (xy 81.44297 -286.742412) (xy 81.492834 -286.732232) (xy 81.543686 -286.730183)
			(xy 81.594207 -286.736317) (xy 81.643091 -286.750477) (xy 81.68907 -286.772294) (xy 81.730954 -286.801204)
			(xy 81.767658 -286.836459) (xy 81.798231 -286.877145) (xy 81.821882 -286.922208) (xy 81.837998 -286.970482)
			(xy 81.846162 -287.020716) (xy 81.846674 -287.046162) (xy 82.154771 -287.046162) (xy 82.158866 -286.995434)
			(xy 82.171045 -286.94602) (xy 82.190993 -286.8992) (xy 82.218194 -286.856186) (xy 82.251942 -286.818092)
			(xy 82.291364 -286.785905) (xy 82.335438 -286.760459) (xy 82.383024 -286.742412) (xy 82.432888 -286.732232)
			(xy 82.48374 -286.730183) (xy 82.534261 -286.736317) (xy 82.583145 -286.750477) (xy 82.629124 -286.772294)
			(xy 82.671008 -286.801204) (xy 82.707712 -286.836459) (xy 82.738285 -286.877145) (xy 82.761936 -286.922208)
			(xy 82.778052 -286.970482) (xy 82.786216 -287.020716) (xy 82.786728 -287.046162) (xy 83.105256 -287.046162)
			(xy 83.109216 -286.997108) (xy 83.120993 -286.949324) (xy 83.140284 -286.904048) (xy 83.166587 -286.862452)
			(xy 83.199222 -286.825615) (xy 83.237343 -286.79449) (xy 83.279964 -286.769883) (xy 83.32598 -286.752431)
			(xy 83.374199 -286.742587) (xy 83.423374 -286.740606) (xy 83.472229 -286.746538) (xy 83.5195 -286.76023)
			(xy 83.563962 -286.781328) (xy 83.604465 -286.809284) (xy 83.639958 -286.843376) (xy 83.669523 -286.88272)
			(xy 83.692394 -286.926297) (xy 83.707978 -286.972978) (xy 83.715873 -287.021555) (xy 83.716368 -287.046162)
			(xy 84.034879 -287.046162) (xy 84.038974 -286.995434) (xy 84.051153 -286.94602) (xy 84.071101 -286.8992)
			(xy 84.098302 -286.856186) (xy 84.13205 -286.818092) (xy 84.171472 -286.785905) (xy 84.215546 -286.760459)
			(xy 84.263132 -286.742412) (xy 84.312996 -286.732232) (xy 84.363848 -286.730183) (xy 84.414369 -286.736317)
			(xy 84.463253 -286.750477) (xy 84.509232 -286.772294) (xy 84.551116 -286.801204) (xy 84.58782 -286.836459)
			(xy 84.618393 -286.877145) (xy 84.642044 -286.922208) (xy 84.65816 -286.970482) (xy 84.666324 -287.020716)
			(xy 84.666836 -287.046162) (xy 84.666826 -287.04667) (xy 84.985364 -287.04667) (xy 84.989324 -286.997616)
			(xy 85.001101 -286.949832) (xy 85.020392 -286.904556) (xy 85.046695 -286.86296) (xy 85.07933 -286.826123)
			(xy 85.117451 -286.794998) (xy 85.160072 -286.770391) (xy 85.206088 -286.752939) (xy 85.254307 -286.743095)
			(xy 85.303482 -286.741114) (xy 85.352337 -286.747046) (xy 85.399608 -286.760738) (xy 85.44407 -286.781836)
			(xy 85.484573 -286.809792) (xy 85.520066 -286.843884) (xy 85.549631 -286.883228) (xy 85.572502 -286.926805)
			(xy 85.588086 -286.973486) (xy 85.595981 -287.022063) (xy 85.596466 -287.046162) (xy 85.914733 -287.046162)
			(xy 85.918828 -286.995434) (xy 85.931007 -286.94602) (xy 85.950955 -286.8992) (xy 85.978156 -286.856186)
			(xy 86.011904 -286.818092) (xy 86.051326 -286.785905) (xy 86.0954 -286.760459) (xy 86.142986 -286.742412)
			(xy 86.19285 -286.732232) (xy 86.243702 -286.730183) (xy 86.294223 -286.736317) (xy 86.343107 -286.750477)
			(xy 86.389086 -286.772294) (xy 86.43097 -286.801204) (xy 86.467674 -286.836459) (xy 86.498247 -286.877145)
			(xy 86.521898 -286.922208) (xy 86.538014 -286.970482) (xy 86.546178 -287.020716) (xy 86.54669 -287.046162)
			(xy 86.865218 -287.046162) (xy 86.869178 -286.997108) (xy 86.880955 -286.949324) (xy 86.900246 -286.904048)
			(xy 86.926549 -286.862452) (xy 86.959184 -286.825615) (xy 86.997305 -286.79449) (xy 87.039926 -286.769883)
			(xy 87.085942 -286.752431) (xy 87.134161 -286.742587) (xy 87.183336 -286.740606) (xy 87.232191 -286.746538)
			(xy 87.279462 -286.76023) (xy 87.323924 -286.781328) (xy 87.364427 -286.809284) (xy 87.39992 -286.843376)
			(xy 87.429485 -286.88272) (xy 87.452356 -286.926297) (xy 87.46794 -286.972978) (xy 87.475835 -287.021555)
			(xy 87.47633 -287.046162) (xy 87.794841 -287.046162) (xy 87.798936 -286.995434) (xy 87.811115 -286.94602)
			(xy 87.831063 -286.8992) (xy 87.858264 -286.856186) (xy 87.892012 -286.818092) (xy 87.931434 -286.785905)
			(xy 87.975508 -286.760459) (xy 88.023094 -286.742412) (xy 88.072958 -286.732232) (xy 88.12381 -286.730183)
			(xy 88.174331 -286.736317) (xy 88.223215 -286.750477) (xy 88.269194 -286.772294) (xy 88.311078 -286.801204)
			(xy 88.347782 -286.836459) (xy 88.378355 -286.877145) (xy 88.402006 -286.922208) (xy 88.418122 -286.970482)
			(xy 88.426286 -287.020716) (xy 88.426798 -287.046162) (xy 88.734895 -287.046162) (xy 88.73899 -286.995434)
			(xy 88.751169 -286.94602) (xy 88.771117 -286.8992) (xy 88.798318 -286.856186) (xy 88.832066 -286.818092)
			(xy 88.871488 -286.785905) (xy 88.915562 -286.760459) (xy 88.963148 -286.742412) (xy 89.013012 -286.732232)
			(xy 89.063864 -286.730183) (xy 89.114385 -286.736317) (xy 89.163269 -286.750477) (xy 89.209248 -286.772294)
			(xy 89.251132 -286.801204) (xy 89.287836 -286.836459) (xy 89.318409 -286.877145) (xy 89.34206 -286.922208)
			(xy 89.358176 -286.970482) (xy 89.36634 -287.020716) (xy 89.366852 -287.046162) (xy 89.366842 -287.04667)
			(xy 89.68538 -287.04667) (xy 89.68934 -286.997616) (xy 89.701117 -286.949832) (xy 89.720408 -286.904556)
			(xy 89.746711 -286.86296) (xy 89.779346 -286.826123) (xy 89.817467 -286.794998) (xy 89.860088 -286.770391)
			(xy 89.906104 -286.752939) (xy 89.954323 -286.743095) (xy 90.003498 -286.741114) (xy 90.052353 -286.747046)
			(xy 90.099624 -286.760738) (xy 90.144086 -286.781836) (xy 90.184589 -286.809792) (xy 90.220082 -286.843884)
			(xy 90.249647 -286.883228) (xy 90.272518 -286.926805) (xy 90.288102 -286.973486) (xy 90.295997 -287.022063)
			(xy 90.296482 -287.046162) (xy 90.614749 -287.046162) (xy 90.618844 -286.995434) (xy 90.631023 -286.94602)
			(xy 90.650971 -286.8992) (xy 90.678172 -286.856186) (xy 90.71192 -286.818092) (xy 90.751342 -286.785905)
			(xy 90.795416 -286.760459) (xy 90.843002 -286.742412) (xy 90.892866 -286.732232) (xy 90.943718 -286.730183)
			(xy 90.994239 -286.736317) (xy 91.043123 -286.750477) (xy 91.089102 -286.772294) (xy 91.130986 -286.801204)
			(xy 91.16769 -286.836459) (xy 91.198263 -286.877145) (xy 91.221914 -286.922208) (xy 91.23803 -286.970482)
			(xy 91.246194 -287.020716) (xy 91.246706 -287.046162) (xy 91.565234 -287.046162) (xy 91.569194 -286.997108)
			(xy 91.580971 -286.949324) (xy 91.600262 -286.904048) (xy 91.626565 -286.862452) (xy 91.6592 -286.825615)
			(xy 91.697321 -286.79449) (xy 91.739942 -286.769883) (xy 91.785958 -286.752431) (xy 91.834177 -286.742587)
			(xy 91.883352 -286.740606) (xy 91.932207 -286.746538) (xy 91.979478 -286.76023) (xy 92.02394 -286.781328)
			(xy 92.064443 -286.809284) (xy 92.099936 -286.843376) (xy 92.129501 -286.88272) (xy 92.152372 -286.926297)
			(xy 92.167956 -286.972978) (xy 92.175851 -287.021555) (xy 92.176346 -287.046162) (xy 92.494857 -287.046162)
			(xy 92.498952 -286.995434) (xy 92.511131 -286.94602) (xy 92.531079 -286.8992) (xy 92.55828 -286.856186)
			(xy 92.592028 -286.818092) (xy 92.63145 -286.785905) (xy 92.675524 -286.760459) (xy 92.72311 -286.742412)
			(xy 92.772974 -286.732232) (xy 92.823826 -286.730183) (xy 92.874347 -286.736317) (xy 92.923231 -286.750477)
			(xy 92.96921 -286.772294) (xy 93.011094 -286.801204) (xy 93.047798 -286.836459) (xy 93.078371 -286.877145)
			(xy 93.102022 -286.922208) (xy 93.118138 -286.970482) (xy 93.126302 -287.020716) (xy 93.126814 -287.046162)
			(xy 93.445342 -287.046162) (xy 93.449302 -286.997108) (xy 93.461079 -286.949324) (xy 93.48037 -286.904048)
			(xy 93.506673 -286.862452) (xy 93.539308 -286.825615) (xy 93.577429 -286.79449) (xy 93.62005 -286.769883)
			(xy 93.666066 -286.752431) (xy 93.714285 -286.742587) (xy 93.76346 -286.740606) (xy 93.812315 -286.746538)
			(xy 93.859586 -286.76023) (xy 93.904048 -286.781328) (xy 93.944551 -286.809284) (xy 93.980044 -286.843376)
			(xy 94.009609 -286.88272) (xy 94.03248 -286.926297) (xy 94.048064 -286.972978) (xy 94.055959 -287.021555)
			(xy 94.056454 -287.046162) (xy 94.374711 -287.046162) (xy 94.378806 -286.995434) (xy 94.390985 -286.94602)
			(xy 94.410933 -286.8992) (xy 94.438134 -286.856186) (xy 94.471882 -286.818092) (xy 94.511304 -286.785905)
			(xy 94.555378 -286.760459) (xy 94.602964 -286.742412) (xy 94.652828 -286.732232) (xy 94.70368 -286.730183)
			(xy 94.754201 -286.736317) (xy 94.803085 -286.750477) (xy 94.849064 -286.772294) (xy 94.890948 -286.801204)
			(xy 94.927652 -286.836459) (xy 94.958225 -286.877145) (xy 94.981876 -286.922208) (xy 94.997992 -286.970482)
			(xy 95.006156 -287.020716) (xy 95.006668 -287.046162) (xy 95.314765 -287.046162) (xy 95.31886 -286.995434)
			(xy 95.331039 -286.94602) (xy 95.350987 -286.8992) (xy 95.378188 -286.856186) (xy 95.411936 -286.818092)
			(xy 95.451358 -286.785905) (xy 95.495432 -286.760459) (xy 95.543018 -286.742412) (xy 95.592882 -286.732232)
			(xy 95.643734 -286.730183) (xy 95.694255 -286.736317) (xy 95.743139 -286.750477) (xy 95.789118 -286.772294)
			(xy 95.831002 -286.801204) (xy 95.867706 -286.836459) (xy 95.898279 -286.877145) (xy 95.92193 -286.922208)
			(xy 95.938046 -286.970482) (xy 95.94621 -287.020716) (xy 95.946722 -287.046162) (xy 96.26525 -287.046162)
			(xy 96.26921 -286.997108) (xy 96.280987 -286.949324) (xy 96.300278 -286.904048) (xy 96.326581 -286.862452)
			(xy 96.359216 -286.825615) (xy 96.397337 -286.79449) (xy 96.439958 -286.769883) (xy 96.485974 -286.752431)
			(xy 96.534193 -286.742587) (xy 96.583368 -286.740606) (xy 96.632223 -286.746538) (xy 96.679494 -286.76023)
			(xy 96.723956 -286.781328) (xy 96.764459 -286.809284) (xy 96.799952 -286.843376) (xy 96.829517 -286.88272)
			(xy 96.852388 -286.926297) (xy 96.867972 -286.972978) (xy 96.875867 -287.021555) (xy 96.876362 -287.046162)
			(xy 96.876352 -287.04667) (xy 99.085412 -287.04667) (xy 99.089372 -286.997616) (xy 99.101149 -286.949832)
			(xy 99.12044 -286.904556) (xy 99.146743 -286.86296) (xy 99.179378 -286.826123) (xy 99.217499 -286.794998)
			(xy 99.26012 -286.770391) (xy 99.306136 -286.752939) (xy 99.354355 -286.743095) (xy 99.40353 -286.741114)
			(xy 99.452385 -286.747046) (xy 99.499656 -286.760738) (xy 99.544118 -286.781836) (xy 99.584621 -286.809792)
			(xy 99.620114 -286.843884) (xy 99.649679 -286.883228) (xy 99.67255 -286.926805) (xy 99.688134 -286.973486)
			(xy 99.696029 -287.022063) (xy 99.696514 -287.046162) (xy 101.90532 -287.046162) (xy 101.90928 -286.997108)
			(xy 101.921057 -286.949324) (xy 101.940348 -286.904048) (xy 101.966651 -286.862452) (xy 101.999286 -286.825615)
			(xy 102.037407 -286.79449) (xy 102.080028 -286.769883) (xy 102.126044 -286.752431) (xy 102.174263 -286.742587)
			(xy 102.223438 -286.740606) (xy 102.272293 -286.746538) (xy 102.319564 -286.76023) (xy 102.364026 -286.781328)
			(xy 102.404529 -286.809284) (xy 102.440022 -286.843376) (xy 102.469587 -286.88272) (xy 102.492458 -286.926297)
			(xy 102.508042 -286.972978) (xy 102.515937 -287.021555) (xy 102.516432 -287.046162) (xy 102.515937 -287.070769)
			(xy 102.508042 -287.119346) (xy 102.492458 -287.166027) (xy 102.469587 -287.209604) (xy 102.440022 -287.248948)
			(xy 102.404529 -287.28304) (xy 102.364026 -287.310996) (xy 102.319564 -287.332094) (xy 102.272293 -287.345786)
			(xy 102.223438 -287.351718) (xy 102.174263 -287.349737) (xy 102.126044 -287.339893) (xy 102.080028 -287.322441)
			(xy 102.037407 -287.297834) (xy 101.999286 -287.266709) (xy 101.966651 -287.229872) (xy 101.940348 -287.188276)
			(xy 101.921057 -287.143) (xy 101.90928 -287.095216) (xy 101.90532 -287.046162) (xy 99.696514 -287.046162)
			(xy 99.696524 -287.04667) (xy 99.696029 -287.071277) (xy 99.688134 -287.119854) (xy 99.67255 -287.166535)
			(xy 99.649679 -287.210112) (xy 99.620114 -287.249456) (xy 99.584621 -287.283548) (xy 99.544118 -287.311504)
			(xy 99.499656 -287.332602) (xy 99.452385 -287.346294) (xy 99.40353 -287.352226) (xy 99.354355 -287.350245)
			(xy 99.306136 -287.340401) (xy 99.26012 -287.322949) (xy 99.217499 -287.298342) (xy 99.179378 -287.267217)
			(xy 99.146743 -287.23038) (xy 99.12044 -287.188784) (xy 99.101149 -287.143508) (xy 99.089372 -287.095724)
			(xy 99.085412 -287.04667) (xy 96.876352 -287.04667) (xy 96.875867 -287.070769) (xy 96.867972 -287.119346)
			(xy 96.852388 -287.166027) (xy 96.829517 -287.209604) (xy 96.799952 -287.248948) (xy 96.764459 -287.28304)
			(xy 96.723956 -287.310996) (xy 96.679494 -287.332094) (xy 96.632223 -287.345786) (xy 96.583368 -287.351718)
			(xy 96.534193 -287.349737) (xy 96.485974 -287.339893) (xy 96.439958 -287.322441) (xy 96.397337 -287.297834)
			(xy 96.359216 -287.266709) (xy 96.326581 -287.229872) (xy 96.300278 -287.188276) (xy 96.280987 -287.143)
			(xy 96.26921 -287.095216) (xy 96.26525 -287.046162) (xy 95.946722 -287.046162) (xy 95.94621 -287.071608)
			(xy 95.938046 -287.121842) (xy 95.92193 -287.170116) (xy 95.898279 -287.215179) (xy 95.867706 -287.255865)
			(xy 95.831002 -287.29112) (xy 95.789118 -287.32003) (xy 95.743139 -287.341847) (xy 95.694255 -287.356007)
			(xy 95.643734 -287.362141) (xy 95.592882 -287.360092) (xy 95.543018 -287.349912) (xy 95.495432 -287.331865)
			(xy 95.451358 -287.306419) (xy 95.411936 -287.274232) (xy 95.378188 -287.236138) (xy 95.350987 -287.193124)
			(xy 95.331039 -287.146304) (xy 95.31886 -287.09689) (xy 95.314765 -287.046162) (xy 95.006668 -287.046162)
			(xy 95.006156 -287.071608) (xy 94.997992 -287.121842) (xy 94.981876 -287.170116) (xy 94.958225 -287.215179)
			(xy 94.927652 -287.255865) (xy 94.890948 -287.29112) (xy 94.849064 -287.32003) (xy 94.803085 -287.341847)
			(xy 94.754201 -287.356007) (xy 94.70368 -287.362141) (xy 94.652828 -287.360092) (xy 94.602964 -287.349912)
			(xy 94.555378 -287.331865) (xy 94.511304 -287.306419) (xy 94.471882 -287.274232) (xy 94.438134 -287.236138)
			(xy 94.410933 -287.193124) (xy 94.390985 -287.146304) (xy 94.378806 -287.09689) (xy 94.374711 -287.046162)
			(xy 94.056454 -287.046162) (xy 94.055959 -287.070769) (xy 94.048064 -287.119346) (xy 94.03248 -287.166027)
			(xy 94.009609 -287.209604) (xy 93.980044 -287.248948) (xy 93.944551 -287.28304) (xy 93.904048 -287.310996)
			(xy 93.859586 -287.332094) (xy 93.812315 -287.345786) (xy 93.76346 -287.351718) (xy 93.714285 -287.349737)
			(xy 93.666066 -287.339893) (xy 93.62005 -287.322441) (xy 93.577429 -287.297834) (xy 93.539308 -287.266709)
			(xy 93.506673 -287.229872) (xy 93.48037 -287.188276) (xy 93.461079 -287.143) (xy 93.449302 -287.095216)
			(xy 93.445342 -287.046162) (xy 93.126814 -287.046162) (xy 93.126302 -287.071608) (xy 93.118138 -287.121842)
			(xy 93.102022 -287.170116) (xy 93.078371 -287.215179) (xy 93.047798 -287.255865) (xy 93.011094 -287.29112)
			(xy 92.96921 -287.32003) (xy 92.923231 -287.341847) (xy 92.874347 -287.356007) (xy 92.823826 -287.362141)
			(xy 92.772974 -287.360092) (xy 92.72311 -287.349912) (xy 92.675524 -287.331865) (xy 92.63145 -287.306419)
			(xy 92.592028 -287.274232) (xy 92.55828 -287.236138) (xy 92.531079 -287.193124) (xy 92.511131 -287.146304)
			(xy 92.498952 -287.09689) (xy 92.494857 -287.046162) (xy 92.176346 -287.046162) (xy 92.175851 -287.070769)
			(xy 92.167956 -287.119346) (xy 92.152372 -287.166027) (xy 92.129501 -287.209604) (xy 92.099936 -287.248948)
			(xy 92.064443 -287.28304) (xy 92.02394 -287.310996) (xy 91.979478 -287.332094) (xy 91.932207 -287.345786)
			(xy 91.883352 -287.351718) (xy 91.834177 -287.349737) (xy 91.785958 -287.339893) (xy 91.739942 -287.322441)
			(xy 91.697321 -287.297834) (xy 91.6592 -287.266709) (xy 91.626565 -287.229872) (xy 91.600262 -287.188276)
			(xy 91.580971 -287.143) (xy 91.569194 -287.095216) (xy 91.565234 -287.046162) (xy 91.246706 -287.046162)
			(xy 91.246194 -287.071608) (xy 91.23803 -287.121842) (xy 91.221914 -287.170116) (xy 91.198263 -287.215179)
			(xy 91.16769 -287.255865) (xy 91.130986 -287.29112) (xy 91.089102 -287.32003) (xy 91.043123 -287.341847)
			(xy 90.994239 -287.356007) (xy 90.943718 -287.362141) (xy 90.892866 -287.360092) (xy 90.843002 -287.349912)
			(xy 90.795416 -287.331865) (xy 90.751342 -287.306419) (xy 90.71192 -287.274232) (xy 90.678172 -287.236138)
			(xy 90.650971 -287.193124) (xy 90.631023 -287.146304) (xy 90.618844 -287.09689) (xy 90.614749 -287.046162)
			(xy 90.296482 -287.046162) (xy 90.296492 -287.04667) (xy 90.295997 -287.071277) (xy 90.288102 -287.119854)
			(xy 90.272518 -287.166535) (xy 90.249647 -287.210112) (xy 90.220082 -287.249456) (xy 90.184589 -287.283548)
			(xy 90.144086 -287.311504) (xy 90.099624 -287.332602) (xy 90.052353 -287.346294) (xy 90.003498 -287.352226)
			(xy 89.954323 -287.350245) (xy 89.906104 -287.340401) (xy 89.860088 -287.322949) (xy 89.817467 -287.298342)
			(xy 89.779346 -287.267217) (xy 89.746711 -287.23038) (xy 89.720408 -287.188784) (xy 89.701117 -287.143508)
			(xy 89.68934 -287.095724) (xy 89.68538 -287.04667) (xy 89.366842 -287.04667) (xy 89.36634 -287.071608)
			(xy 89.358176 -287.121842) (xy 89.34206 -287.170116) (xy 89.318409 -287.215179) (xy 89.287836 -287.255865)
			(xy 89.251132 -287.29112) (xy 89.209248 -287.32003) (xy 89.163269 -287.341847) (xy 89.114385 -287.356007)
			(xy 89.063864 -287.362141) (xy 89.013012 -287.360092) (xy 88.963148 -287.349912) (xy 88.915562 -287.331865)
			(xy 88.871488 -287.306419) (xy 88.832066 -287.274232) (xy 88.798318 -287.236138) (xy 88.771117 -287.193124)
			(xy 88.751169 -287.146304) (xy 88.73899 -287.09689) (xy 88.734895 -287.046162) (xy 88.426798 -287.046162)
			(xy 88.426286 -287.071608) (xy 88.418122 -287.121842) (xy 88.402006 -287.170116) (xy 88.378355 -287.215179)
			(xy 88.347782 -287.255865) (xy 88.311078 -287.29112) (xy 88.269194 -287.32003) (xy 88.223215 -287.341847)
			(xy 88.174331 -287.356007) (xy 88.12381 -287.362141) (xy 88.072958 -287.360092) (xy 88.023094 -287.349912)
			(xy 87.975508 -287.331865) (xy 87.931434 -287.306419) (xy 87.892012 -287.274232) (xy 87.858264 -287.236138)
			(xy 87.831063 -287.193124) (xy 87.811115 -287.146304) (xy 87.798936 -287.09689) (xy 87.794841 -287.046162)
			(xy 87.47633 -287.046162) (xy 87.475835 -287.070769) (xy 87.46794 -287.119346) (xy 87.452356 -287.166027)
			(xy 87.429485 -287.209604) (xy 87.39992 -287.248948) (xy 87.364427 -287.28304) (xy 87.323924 -287.310996)
			(xy 87.279462 -287.332094) (xy 87.232191 -287.345786) (xy 87.183336 -287.351718) (xy 87.134161 -287.349737)
			(xy 87.085942 -287.339893) (xy 87.039926 -287.322441) (xy 86.997305 -287.297834) (xy 86.959184 -287.266709)
			(xy 86.926549 -287.229872) (xy 86.900246 -287.188276) (xy 86.880955 -287.143) (xy 86.869178 -287.095216)
			(xy 86.865218 -287.046162) (xy 86.54669 -287.046162) (xy 86.546178 -287.071608) (xy 86.538014 -287.121842)
			(xy 86.521898 -287.170116) (xy 86.498247 -287.215179) (xy 86.467674 -287.255865) (xy 86.43097 -287.29112)
			(xy 86.389086 -287.32003) (xy 86.343107 -287.341847) (xy 86.294223 -287.356007) (xy 86.243702 -287.362141)
			(xy 86.19285 -287.360092) (xy 86.142986 -287.349912) (xy 86.0954 -287.331865) (xy 86.051326 -287.306419)
			(xy 86.011904 -287.274232) (xy 85.978156 -287.236138) (xy 85.950955 -287.193124) (xy 85.931007 -287.146304)
			(xy 85.918828 -287.09689) (xy 85.914733 -287.046162) (xy 85.596466 -287.046162) (xy 85.596476 -287.04667)
			(xy 85.595981 -287.071277) (xy 85.588086 -287.119854) (xy 85.572502 -287.166535) (xy 85.549631 -287.210112)
			(xy 85.520066 -287.249456) (xy 85.484573 -287.283548) (xy 85.44407 -287.311504) (xy 85.399608 -287.332602)
			(xy 85.352337 -287.346294) (xy 85.303482 -287.352226) (xy 85.254307 -287.350245) (xy 85.206088 -287.340401)
			(xy 85.160072 -287.322949) (xy 85.117451 -287.298342) (xy 85.07933 -287.267217) (xy 85.046695 -287.23038)
			(xy 85.020392 -287.188784) (xy 85.001101 -287.143508) (xy 84.989324 -287.095724) (xy 84.985364 -287.04667)
			(xy 84.666826 -287.04667) (xy 84.666324 -287.071608) (xy 84.65816 -287.121842) (xy 84.642044 -287.170116)
			(xy 84.618393 -287.215179) (xy 84.58782 -287.255865) (xy 84.551116 -287.29112) (xy 84.509232 -287.32003)
			(xy 84.463253 -287.341847) (xy 84.414369 -287.356007) (xy 84.363848 -287.362141) (xy 84.312996 -287.360092)
			(xy 84.263132 -287.349912) (xy 84.215546 -287.331865) (xy 84.171472 -287.306419) (xy 84.13205 -287.274232)
			(xy 84.098302 -287.236138) (xy 84.071101 -287.193124) (xy 84.051153 -287.146304) (xy 84.038974 -287.09689)
			(xy 84.034879 -287.046162) (xy 83.716368 -287.046162) (xy 83.715873 -287.070769) (xy 83.707978 -287.119346)
			(xy 83.692394 -287.166027) (xy 83.669523 -287.209604) (xy 83.639958 -287.248948) (xy 83.604465 -287.28304)
			(xy 83.563962 -287.310996) (xy 83.5195 -287.332094) (xy 83.472229 -287.345786) (xy 83.423374 -287.351718)
			(xy 83.374199 -287.349737) (xy 83.32598 -287.339893) (xy 83.279964 -287.322441) (xy 83.237343 -287.297834)
			(xy 83.199222 -287.266709) (xy 83.166587 -287.229872) (xy 83.140284 -287.188276) (xy 83.120993 -287.143)
			(xy 83.109216 -287.095216) (xy 83.105256 -287.046162) (xy 82.786728 -287.046162) (xy 82.786216 -287.071608)
			(xy 82.778052 -287.121842) (xy 82.761936 -287.170116) (xy 82.738285 -287.215179) (xy 82.707712 -287.255865)
			(xy 82.671008 -287.29112) (xy 82.629124 -287.32003) (xy 82.583145 -287.341847) (xy 82.534261 -287.356007)
			(xy 82.48374 -287.362141) (xy 82.432888 -287.360092) (xy 82.383024 -287.349912) (xy 82.335438 -287.331865)
			(xy 82.291364 -287.306419) (xy 82.251942 -287.274232) (xy 82.218194 -287.236138) (xy 82.190993 -287.193124)
			(xy 82.171045 -287.146304) (xy 82.158866 -287.09689) (xy 82.154771 -287.046162) (xy 81.846674 -287.046162)
			(xy 81.846162 -287.071608) (xy 81.837998 -287.121842) (xy 81.821882 -287.170116) (xy 81.798231 -287.215179)
			(xy 81.767658 -287.255865) (xy 81.730954 -287.29112) (xy 81.68907 -287.32003) (xy 81.643091 -287.341847)
			(xy 81.594207 -287.356007) (xy 81.543686 -287.362141) (xy 81.492834 -287.360092) (xy 81.44297 -287.349912)
			(xy 81.395384 -287.331865) (xy 81.35131 -287.306419) (xy 81.311888 -287.274232) (xy 81.27814 -287.236138)
			(xy 81.250939 -287.193124) (xy 81.230991 -287.146304) (xy 81.218812 -287.09689) (xy 81.214717 -287.046162)
			(xy 80.89646 -287.046162) (xy 80.895965 -287.070769) (xy 80.88807 -287.119346) (xy 80.872486 -287.166027)
			(xy 80.849615 -287.209604) (xy 80.82005 -287.248948) (xy 80.784557 -287.28304) (xy 80.744054 -287.310996)
			(xy 80.699592 -287.332094) (xy 80.652321 -287.345786) (xy 80.603466 -287.351718) (xy 80.554291 -287.349737)
			(xy 80.506072 -287.339893) (xy 80.460056 -287.322441) (xy 80.417435 -287.297834) (xy 80.379314 -287.266709)
			(xy 80.346679 -287.229872) (xy 80.320376 -287.188276) (xy 80.301085 -287.143) (xy 80.289308 -287.095216)
			(xy 80.285348 -287.046162) (xy 79.016352 -287.046162) (xy 79.015857 -287.070769) (xy 79.007962 -287.119346)
			(xy 78.992378 -287.166027) (xy 78.969507 -287.209604) (xy 78.939942 -287.248948) (xy 78.904449 -287.28304)
			(xy 78.863946 -287.310996) (xy 78.819484 -287.332094) (xy 78.772213 -287.345786) (xy 78.723358 -287.351718)
			(xy 78.674183 -287.349737) (xy 78.625964 -287.339893) (xy 78.579948 -287.322441) (xy 78.537327 -287.297834)
			(xy 78.499206 -287.266709) (xy 78.466571 -287.229872) (xy 78.440268 -287.188276) (xy 78.420977 -287.143)
			(xy 78.4092 -287.095216) (xy 78.40524 -287.046162) (xy 73.228962 -287.046162) (xy 73.228962 -287.590484)
			(xy 76.807072 -287.590484) (xy 76.811032 -287.54143) (xy 76.822809 -287.493646) (xy 76.8421 -287.44837)
			(xy 76.868403 -287.406774) (xy 76.901038 -287.369937) (xy 76.939159 -287.338812) (xy 76.98178 -287.314205)
			(xy 77.027796 -287.296753) (xy 77.076015 -287.286909) (xy 77.12519 -287.284928) (xy 77.174045 -287.29086)
			(xy 77.221316 -287.304552) (xy 77.265778 -287.32565) (xy 77.306281 -287.353606) (xy 77.341774 -287.387698)
			(xy 77.371339 -287.427042) (xy 77.39421 -287.470619) (xy 77.409794 -287.5173) (xy 77.417689 -287.565877)
			(xy 77.418184 -287.590484) (xy 77.417689 -287.615091) (xy 77.409794 -287.663668) (xy 77.39421 -287.710349)
			(xy 77.371339 -287.753926) (xy 77.341774 -287.79327) (xy 77.306281 -287.827362) (xy 77.265778 -287.855318)
			(xy 77.263451 -287.856422) (xy 79.815194 -287.856422) (xy 79.819154 -287.807368) (xy 79.830931 -287.759584)
			(xy 79.850222 -287.714308) (xy 79.876525 -287.672712) (xy 79.90916 -287.635875) (xy 79.947281 -287.60475)
			(xy 79.989902 -287.580143) (xy 80.035918 -287.562691) (xy 80.084137 -287.552847) (xy 80.133312 -287.550866)
			(xy 80.182167 -287.556798) (xy 80.229438 -287.57049) (xy 80.2739 -287.591588) (xy 80.314403 -287.619544)
			(xy 80.349896 -287.653636) (xy 80.379461 -287.69298) (xy 80.402332 -287.736557) (xy 80.417916 -287.783238)
			(xy 80.425811 -287.831815) (xy 80.426306 -287.856422) (xy 80.744817 -287.856422) (xy 80.748912 -287.805694)
			(xy 80.761091 -287.75628) (xy 80.781039 -287.70946) (xy 80.80824 -287.666446) (xy 80.841988 -287.628352)
			(xy 80.88141 -287.596165) (xy 80.925484 -287.570719) (xy 80.97307 -287.552672) (xy 81.022934 -287.542492)
			(xy 81.073786 -287.540443) (xy 81.124307 -287.546577) (xy 81.173191 -287.560737) (xy 81.21917 -287.582554)
			(xy 81.261054 -287.611464) (xy 81.297758 -287.646719) (xy 81.328331 -287.687405) (xy 81.351982 -287.732468)
			(xy 81.368098 -287.780742) (xy 81.376262 -287.830976) (xy 81.376774 -287.856422) (xy 81.695302 -287.856422)
			(xy 81.699262 -287.807368) (xy 81.711039 -287.759584) (xy 81.73033 -287.714308) (xy 81.756633 -287.672712)
			(xy 81.789268 -287.635875) (xy 81.827389 -287.60475) (xy 81.87001 -287.580143) (xy 81.916026 -287.562691)
			(xy 81.964245 -287.552847) (xy 82.01342 -287.550866) (xy 82.062275 -287.556798) (xy 82.109546 -287.57049)
			(xy 82.154008 -287.591588) (xy 82.194511 -287.619544) (xy 82.230004 -287.653636) (xy 82.259569 -287.69298)
			(xy 82.28244 -287.736557) (xy 82.298024 -287.783238) (xy 82.305919 -287.831815) (xy 82.306414 -287.856422)
			(xy 82.624671 -287.856422) (xy 82.628766 -287.805694) (xy 82.640945 -287.75628) (xy 82.660893 -287.70946)
			(xy 82.688094 -287.666446) (xy 82.721842 -287.628352) (xy 82.761264 -287.596165) (xy 82.805338 -287.570719)
			(xy 82.852924 -287.552672) (xy 82.902788 -287.542492) (xy 82.95364 -287.540443) (xy 83.004161 -287.546577)
			(xy 83.053045 -287.560737) (xy 83.099024 -287.582554) (xy 83.140908 -287.611464) (xy 83.177612 -287.646719)
			(xy 83.208185 -287.687405) (xy 83.231836 -287.732468) (xy 83.247952 -287.780742) (xy 83.256116 -287.830976)
			(xy 83.256628 -287.856422) (xy 83.575156 -287.856422) (xy 83.579116 -287.807368) (xy 83.590893 -287.759584)
			(xy 83.610184 -287.714308) (xy 83.636487 -287.672712) (xy 83.669122 -287.635875) (xy 83.707243 -287.60475)
			(xy 83.749864 -287.580143) (xy 83.79588 -287.562691) (xy 83.844099 -287.552847) (xy 83.893274 -287.550866)
			(xy 83.942129 -287.556798) (xy 83.9894 -287.57049) (xy 84.033862 -287.591588) (xy 84.074365 -287.619544)
			(xy 84.109858 -287.653636) (xy 84.139423 -287.69298) (xy 84.162294 -287.736557) (xy 84.177878 -287.783238)
			(xy 84.185773 -287.831815) (xy 84.186268 -287.856422) (xy 84.504779 -287.856422) (xy 84.508874 -287.805694)
			(xy 84.521053 -287.75628) (xy 84.541001 -287.70946) (xy 84.568202 -287.666446) (xy 84.60195 -287.628352)
			(xy 84.641372 -287.596165) (xy 84.685446 -287.570719) (xy 84.733032 -287.552672) (xy 84.782896 -287.542492)
			(xy 84.833748 -287.540443) (xy 84.884269 -287.546577) (xy 84.933153 -287.560737) (xy 84.979132 -287.582554)
			(xy 85.021016 -287.611464) (xy 85.05772 -287.646719) (xy 85.088293 -287.687405) (xy 85.111944 -287.732468)
			(xy 85.12806 -287.780742) (xy 85.136224 -287.830976) (xy 85.136736 -287.856422) (xy 85.444833 -287.856422)
			(xy 85.448928 -287.805694) (xy 85.461107 -287.75628) (xy 85.481055 -287.70946) (xy 85.508256 -287.666446)
			(xy 85.542004 -287.628352) (xy 85.581426 -287.596165) (xy 85.6255 -287.570719) (xy 85.673086 -287.552672)
			(xy 85.72295 -287.542492) (xy 85.773802 -287.540443) (xy 85.824323 -287.546577) (xy 85.873207 -287.560737)
			(xy 85.919186 -287.582554) (xy 85.96107 -287.611464) (xy 85.997774 -287.646719) (xy 86.028347 -287.687405)
			(xy 86.051998 -287.732468) (xy 86.068114 -287.780742) (xy 86.076278 -287.830976) (xy 86.07679 -287.856422)
			(xy 86.395318 -287.856422) (xy 86.399278 -287.807368) (xy 86.411055 -287.759584) (xy 86.430346 -287.714308)
			(xy 86.456649 -287.672712) (xy 86.489284 -287.635875) (xy 86.527405 -287.60475) (xy 86.570026 -287.580143)
			(xy 86.616042 -287.562691) (xy 86.664261 -287.552847) (xy 86.713436 -287.550866) (xy 86.762291 -287.556798)
			(xy 86.809562 -287.57049) (xy 86.854024 -287.591588) (xy 86.894527 -287.619544) (xy 86.93002 -287.653636)
			(xy 86.959585 -287.69298) (xy 86.982456 -287.736557) (xy 86.99804 -287.783238) (xy 87.005935 -287.831815)
			(xy 87.00643 -287.856422) (xy 87.324687 -287.856422) (xy 87.328782 -287.805694) (xy 87.340961 -287.75628)
			(xy 87.360909 -287.70946) (xy 87.38811 -287.666446) (xy 87.421858 -287.628352) (xy 87.46128 -287.596165)
			(xy 87.505354 -287.570719) (xy 87.55294 -287.552672) (xy 87.602804 -287.542492) (xy 87.653656 -287.540443)
			(xy 87.704177 -287.546577) (xy 87.753061 -287.560737) (xy 87.79904 -287.582554) (xy 87.840924 -287.611464)
			(xy 87.877628 -287.646719) (xy 87.908201 -287.687405) (xy 87.931852 -287.732468) (xy 87.947968 -287.780742)
			(xy 87.956132 -287.830976) (xy 87.956644 -287.856422) (xy 88.275172 -287.856422) (xy 88.279132 -287.807368)
			(xy 88.290909 -287.759584) (xy 88.3102 -287.714308) (xy 88.336503 -287.672712) (xy 88.369138 -287.635875)
			(xy 88.407259 -287.60475) (xy 88.44988 -287.580143) (xy 88.495896 -287.562691) (xy 88.544115 -287.552847)
			(xy 88.59329 -287.550866) (xy 88.642145 -287.556798) (xy 88.689416 -287.57049) (xy 88.733878 -287.591588)
			(xy 88.774381 -287.619544) (xy 88.809874 -287.653636) (xy 88.839439 -287.69298) (xy 88.86231 -287.736557)
			(xy 88.877894 -287.783238) (xy 88.885789 -287.831815) (xy 88.886284 -287.856422) (xy 89.204795 -287.856422)
			(xy 89.20889 -287.805694) (xy 89.221069 -287.75628) (xy 89.241017 -287.70946) (xy 89.268218 -287.666446)
			(xy 89.301966 -287.628352) (xy 89.341388 -287.596165) (xy 89.385462 -287.570719) (xy 89.433048 -287.552672)
			(xy 89.482912 -287.542492) (xy 89.533764 -287.540443) (xy 89.584285 -287.546577) (xy 89.633169 -287.560737)
			(xy 89.679148 -287.582554) (xy 89.721032 -287.611464) (xy 89.757736 -287.646719) (xy 89.788309 -287.687405)
			(xy 89.81196 -287.732468) (xy 89.828076 -287.780742) (xy 89.83624 -287.830976) (xy 89.836752 -287.856422)
			(xy 90.15528 -287.856422) (xy 90.15924 -287.807368) (xy 90.171017 -287.759584) (xy 90.190308 -287.714308)
			(xy 90.216611 -287.672712) (xy 90.249246 -287.635875) (xy 90.287367 -287.60475) (xy 90.329988 -287.580143)
			(xy 90.376004 -287.562691) (xy 90.424223 -287.552847) (xy 90.473398 -287.550866) (xy 90.522253 -287.556798)
			(xy 90.569524 -287.57049) (xy 90.613986 -287.591588) (xy 90.654489 -287.619544) (xy 90.689982 -287.653636)
			(xy 90.719547 -287.69298) (xy 90.742418 -287.736557) (xy 90.758002 -287.783238) (xy 90.765897 -287.831815)
			(xy 90.766392 -287.856422) (xy 91.084903 -287.856422) (xy 91.088998 -287.805694) (xy 91.101177 -287.75628)
			(xy 91.121125 -287.70946) (xy 91.148326 -287.666446) (xy 91.182074 -287.628352) (xy 91.221496 -287.596165)
			(xy 91.26557 -287.570719) (xy 91.313156 -287.552672) (xy 91.36302 -287.542492) (xy 91.413872 -287.540443)
			(xy 91.464393 -287.546577) (xy 91.513277 -287.560737) (xy 91.559256 -287.582554) (xy 91.60114 -287.611464)
			(xy 91.637844 -287.646719) (xy 91.668417 -287.687405) (xy 91.692068 -287.732468) (xy 91.708184 -287.780742)
			(xy 91.716348 -287.830976) (xy 91.71686 -287.856422) (xy 92.024703 -287.856422) (xy 92.028798 -287.805694)
			(xy 92.040977 -287.75628) (xy 92.060925 -287.70946) (xy 92.088126 -287.666446) (xy 92.121874 -287.628352)
			(xy 92.161296 -287.596165) (xy 92.20537 -287.570719) (xy 92.252956 -287.552672) (xy 92.30282 -287.542492)
			(xy 92.353672 -287.540443) (xy 92.404193 -287.546577) (xy 92.453077 -287.560737) (xy 92.499056 -287.582554)
			(xy 92.54094 -287.611464) (xy 92.577644 -287.646719) (xy 92.608217 -287.687405) (xy 92.631868 -287.732468)
			(xy 92.647984 -287.780742) (xy 92.656148 -287.830976) (xy 92.65666 -287.856422) (xy 92.975188 -287.856422)
			(xy 92.979148 -287.807368) (xy 92.990925 -287.759584) (xy 93.010216 -287.714308) (xy 93.036519 -287.672712)
			(xy 93.069154 -287.635875) (xy 93.107275 -287.60475) (xy 93.149896 -287.580143) (xy 93.195912 -287.562691)
			(xy 93.244131 -287.552847) (xy 93.293306 -287.550866) (xy 93.342161 -287.556798) (xy 93.389432 -287.57049)
			(xy 93.433894 -287.591588) (xy 93.474397 -287.619544) (xy 93.50989 -287.653636) (xy 93.539455 -287.69298)
			(xy 93.562326 -287.736557) (xy 93.57791 -287.783238) (xy 93.585805 -287.831815) (xy 93.5863 -287.856422)
			(xy 93.904811 -287.856422) (xy 93.908906 -287.805694) (xy 93.921085 -287.75628) (xy 93.941033 -287.70946)
			(xy 93.968234 -287.666446) (xy 94.001982 -287.628352) (xy 94.041404 -287.596165) (xy 94.085478 -287.570719)
			(xy 94.133064 -287.552672) (xy 94.182928 -287.542492) (xy 94.23378 -287.540443) (xy 94.284301 -287.546577)
			(xy 94.333185 -287.560737) (xy 94.379164 -287.582554) (xy 94.421048 -287.611464) (xy 94.457752 -287.646719)
			(xy 94.488325 -287.687405) (xy 94.511976 -287.732468) (xy 94.528092 -287.780742) (xy 94.536256 -287.830976)
			(xy 94.536768 -287.856422) (xy 94.855296 -287.856422) (xy 94.859256 -287.807368) (xy 94.871033 -287.759584)
			(xy 94.890324 -287.714308) (xy 94.916627 -287.672712) (xy 94.949262 -287.635875) (xy 94.987383 -287.60475)
			(xy 95.030004 -287.580143) (xy 95.07602 -287.562691) (xy 95.124239 -287.552847) (xy 95.173414 -287.550866)
			(xy 95.222269 -287.556798) (xy 95.26954 -287.57049) (xy 95.314002 -287.591588) (xy 95.354505 -287.619544)
			(xy 95.389998 -287.653636) (xy 95.419563 -287.69298) (xy 95.442434 -287.736557) (xy 95.458018 -287.783238)
			(xy 95.465913 -287.831815) (xy 95.466408 -287.856422) (xy 95.784919 -287.856422) (xy 95.789014 -287.805694)
			(xy 95.801193 -287.75628) (xy 95.821141 -287.70946) (xy 95.848342 -287.666446) (xy 95.88209 -287.628352)
			(xy 95.921512 -287.596165) (xy 95.965586 -287.570719) (xy 96.013172 -287.552672) (xy 96.063036 -287.542492)
			(xy 96.113888 -287.540443) (xy 96.164409 -287.546577) (xy 96.213293 -287.560737) (xy 96.259272 -287.582554)
			(xy 96.301156 -287.611464) (xy 96.33786 -287.646719) (xy 96.368433 -287.687405) (xy 96.392084 -287.732468)
			(xy 96.4082 -287.780742) (xy 96.416364 -287.830976) (xy 96.416876 -287.856422) (xy 96.73515 -287.856422)
			(xy 96.73911 -287.807368) (xy 96.750887 -287.759584) (xy 96.770178 -287.714308) (xy 96.796481 -287.672712)
			(xy 96.829116 -287.635875) (xy 96.867237 -287.60475) (xy 96.909858 -287.580143) (xy 96.955874 -287.562691)
			(xy 97.004093 -287.552847) (xy 97.053268 -287.550866) (xy 97.102123 -287.556798) (xy 97.149394 -287.57049)
			(xy 97.193856 -287.591588) (xy 97.234359 -287.619544) (xy 97.269852 -287.653636) (xy 97.299417 -287.69298)
			(xy 97.322288 -287.736557) (xy 97.337872 -287.783238) (xy 97.345767 -287.831815) (xy 97.346262 -287.856422)
			(xy 97.664773 -287.856422) (xy 97.668868 -287.805694) (xy 97.681047 -287.75628) (xy 97.700995 -287.70946)
			(xy 97.728196 -287.666446) (xy 97.761944 -287.628352) (xy 97.801366 -287.596165) (xy 97.84544 -287.570719)
			(xy 97.893026 -287.552672) (xy 97.94289 -287.542492) (xy 97.993742 -287.540443) (xy 98.044263 -287.546577)
			(xy 98.093147 -287.560737) (xy 98.139126 -287.582554) (xy 98.18101 -287.611464) (xy 98.217714 -287.646719)
			(xy 98.248287 -287.687405) (xy 98.271938 -287.732468) (xy 98.288054 -287.780742) (xy 98.296218 -287.830976)
			(xy 98.29673 -287.856422) (xy 98.604827 -287.856422) (xy 98.608922 -287.805694) (xy 98.621101 -287.75628)
			(xy 98.641049 -287.70946) (xy 98.66825 -287.666446) (xy 98.701998 -287.628352) (xy 98.74142 -287.596165)
			(xy 98.785494 -287.570719) (xy 98.83308 -287.552672) (xy 98.882944 -287.542492) (xy 98.933796 -287.540443)
			(xy 98.984317 -287.546577) (xy 99.033201 -287.560737) (xy 99.07918 -287.582554) (xy 99.121064 -287.611464)
			(xy 99.157768 -287.646719) (xy 99.188341 -287.687405) (xy 99.211992 -287.732468) (xy 99.228108 -287.780742)
			(xy 99.236272 -287.830976) (xy 99.236784 -287.856422) (xy 99.555312 -287.856422) (xy 99.559272 -287.807368)
			(xy 99.571049 -287.759584) (xy 99.59034 -287.714308) (xy 99.616643 -287.672712) (xy 99.649278 -287.635875)
			(xy 99.687399 -287.60475) (xy 99.73002 -287.580143) (xy 99.776036 -287.562691) (xy 99.824255 -287.552847)
			(xy 99.87343 -287.550866) (xy 99.922285 -287.556798) (xy 99.969556 -287.57049) (xy 100.014018 -287.591588)
			(xy 100.054521 -287.619544) (xy 100.090014 -287.653636) (xy 100.119579 -287.69298) (xy 100.14245 -287.736557)
			(xy 100.158034 -287.783238) (xy 100.165929 -287.831815) (xy 100.166424 -287.856422) (xy 100.484935 -287.856422)
			(xy 100.48903 -287.805694) (xy 100.501209 -287.75628) (xy 100.521157 -287.70946) (xy 100.548358 -287.666446)
			(xy 100.582106 -287.628352) (xy 100.621528 -287.596165) (xy 100.665602 -287.570719) (xy 100.713188 -287.552672)
			(xy 100.763052 -287.542492) (xy 100.813904 -287.540443) (xy 100.864425 -287.546577) (xy 100.913309 -287.560737)
			(xy 100.959288 -287.582554) (xy 101.001172 -287.611464) (xy 101.037876 -287.646719) (xy 101.068449 -287.687405)
			(xy 101.0921 -287.732468) (xy 101.108216 -287.780742) (xy 101.11638 -287.830976) (xy 101.116892 -287.856422)
			(xy 101.424735 -287.856422) (xy 101.42883 -287.805694) (xy 101.441009 -287.75628) (xy 101.460957 -287.70946)
			(xy 101.488158 -287.666446) (xy 101.521906 -287.628352) (xy 101.561328 -287.596165) (xy 101.605402 -287.570719)
			(xy 101.652988 -287.552672) (xy 101.702852 -287.542492) (xy 101.753704 -287.540443) (xy 101.804225 -287.546577)
			(xy 101.853109 -287.560737) (xy 101.899088 -287.582554) (xy 101.940972 -287.611464) (xy 101.977676 -287.646719)
			(xy 102.008249 -287.687405) (xy 102.0319 -287.732468) (xy 102.048016 -287.780742) (xy 102.05618 -287.830976)
			(xy 102.056692 -287.856422) (xy 102.05618 -287.881868) (xy 102.048016 -287.932102) (xy 102.0319 -287.980376)
			(xy 102.008249 -288.025439) (xy 101.977676 -288.066125) (xy 101.940972 -288.10138) (xy 101.899088 -288.13029)
			(xy 101.853109 -288.152107) (xy 101.804225 -288.166267) (xy 101.753704 -288.172401) (xy 101.702852 -288.170352)
			(xy 101.652988 -288.160172) (xy 101.605402 -288.142125) (xy 101.561328 -288.116679) (xy 101.521906 -288.084492)
			(xy 101.488158 -288.046398) (xy 101.460957 -288.003384) (xy 101.441009 -287.956564) (xy 101.42883 -287.90715)
			(xy 101.424735 -287.856422) (xy 101.116892 -287.856422) (xy 101.11638 -287.881868) (xy 101.108216 -287.932102)
			(xy 101.0921 -287.980376) (xy 101.068449 -288.025439) (xy 101.037876 -288.066125) (xy 101.001172 -288.10138)
			(xy 100.959288 -288.13029) (xy 100.913309 -288.152107) (xy 100.864425 -288.166267) (xy 100.813904 -288.172401)
			(xy 100.763052 -288.170352) (xy 100.713188 -288.160172) (xy 100.665602 -288.142125) (xy 100.621528 -288.116679)
			(xy 100.582106 -288.084492) (xy 100.548358 -288.046398) (xy 100.521157 -288.003384) (xy 100.501209 -287.956564)
			(xy 100.48903 -287.90715) (xy 100.484935 -287.856422) (xy 100.166424 -287.856422) (xy 100.165929 -287.881029)
			(xy 100.158034 -287.929606) (xy 100.14245 -287.976287) (xy 100.119579 -288.019864) (xy 100.090014 -288.059208)
			(xy 100.054521 -288.0933) (xy 100.014018 -288.121256) (xy 99.969556 -288.142354) (xy 99.922285 -288.156046)
			(xy 99.87343 -288.161978) (xy 99.824255 -288.159997) (xy 99.776036 -288.150153) (xy 99.73002 -288.132701)
			(xy 99.687399 -288.108094) (xy 99.649278 -288.076969) (xy 99.616643 -288.040132) (xy 99.59034 -287.998536)
			(xy 99.571049 -287.95326) (xy 99.559272 -287.905476) (xy 99.555312 -287.856422) (xy 99.236784 -287.856422)
			(xy 99.236272 -287.881868) (xy 99.228108 -287.932102) (xy 99.211992 -287.980376) (xy 99.188341 -288.025439)
			(xy 99.157768 -288.066125) (xy 99.121064 -288.10138) (xy 99.07918 -288.13029) (xy 99.033201 -288.152107)
			(xy 98.984317 -288.166267) (xy 98.933796 -288.172401) (xy 98.882944 -288.170352) (xy 98.83308 -288.160172)
			(xy 98.785494 -288.142125) (xy 98.74142 -288.116679) (xy 98.701998 -288.084492) (xy 98.66825 -288.046398)
			(xy 98.641049 -288.003384) (xy 98.621101 -287.956564) (xy 98.608922 -287.90715) (xy 98.604827 -287.856422)
			(xy 98.29673 -287.856422) (xy 98.296218 -287.881868) (xy 98.288054 -287.932102) (xy 98.271938 -287.980376)
			(xy 98.248287 -288.025439) (xy 98.217714 -288.066125) (xy 98.18101 -288.10138) (xy 98.139126 -288.13029)
			(xy 98.093147 -288.152107) (xy 98.044263 -288.166267) (xy 97.993742 -288.172401) (xy 97.94289 -288.170352)
			(xy 97.893026 -288.160172) (xy 97.84544 -288.142125) (xy 97.801366 -288.116679) (xy 97.761944 -288.084492)
			(xy 97.728196 -288.046398) (xy 97.700995 -288.003384) (xy 97.681047 -287.956564) (xy 97.668868 -287.90715)
			(xy 97.664773 -287.856422) (xy 97.346262 -287.856422) (xy 97.345767 -287.881029) (xy 97.337872 -287.929606)
			(xy 97.322288 -287.976287) (xy 97.299417 -288.019864) (xy 97.269852 -288.059208) (xy 97.234359 -288.0933)
			(xy 97.193856 -288.121256) (xy 97.149394 -288.142354) (xy 97.102123 -288.156046) (xy 97.053268 -288.161978)
			(xy 97.004093 -288.159997) (xy 96.955874 -288.150153) (xy 96.909858 -288.132701) (xy 96.867237 -288.108094)
			(xy 96.829116 -288.076969) (xy 96.796481 -288.040132) (xy 96.770178 -287.998536) (xy 96.750887 -287.95326)
			(xy 96.73911 -287.905476) (xy 96.73515 -287.856422) (xy 96.416876 -287.856422) (xy 96.416364 -287.881868)
			(xy 96.4082 -287.932102) (xy 96.392084 -287.980376) (xy 96.368433 -288.025439) (xy 96.33786 -288.066125)
			(xy 96.301156 -288.10138) (xy 96.259272 -288.13029) (xy 96.213293 -288.152107) (xy 96.164409 -288.166267)
			(xy 96.113888 -288.172401) (xy 96.063036 -288.170352) (xy 96.013172 -288.160172) (xy 95.965586 -288.142125)
			(xy 95.921512 -288.116679) (xy 95.88209 -288.084492) (xy 95.848342 -288.046398) (xy 95.821141 -288.003384)
			(xy 95.801193 -287.956564) (xy 95.789014 -287.90715) (xy 95.784919 -287.856422) (xy 95.466408 -287.856422)
			(xy 95.465913 -287.881029) (xy 95.458018 -287.929606) (xy 95.442434 -287.976287) (xy 95.419563 -288.019864)
			(xy 95.389998 -288.059208) (xy 95.354505 -288.0933) (xy 95.314002 -288.121256) (xy 95.26954 -288.142354)
			(xy 95.222269 -288.156046) (xy 95.173414 -288.161978) (xy 95.124239 -288.159997) (xy 95.07602 -288.150153)
			(xy 95.030004 -288.132701) (xy 94.987383 -288.108094) (xy 94.949262 -288.076969) (xy 94.916627 -288.040132)
			(xy 94.890324 -287.998536) (xy 94.871033 -287.95326) (xy 94.859256 -287.905476) (xy 94.855296 -287.856422)
			(xy 94.536768 -287.856422) (xy 94.536256 -287.881868) (xy 94.528092 -287.932102) (xy 94.511976 -287.980376)
			(xy 94.488325 -288.025439) (xy 94.457752 -288.066125) (xy 94.421048 -288.10138) (xy 94.379164 -288.13029)
			(xy 94.333185 -288.152107) (xy 94.284301 -288.166267) (xy 94.23378 -288.172401) (xy 94.182928 -288.170352)
			(xy 94.133064 -288.160172) (xy 94.085478 -288.142125) (xy 94.041404 -288.116679) (xy 94.001982 -288.084492)
			(xy 93.968234 -288.046398) (xy 93.941033 -288.003384) (xy 93.921085 -287.956564) (xy 93.908906 -287.90715)
			(xy 93.904811 -287.856422) (xy 93.5863 -287.856422) (xy 93.585805 -287.881029) (xy 93.57791 -287.929606)
			(xy 93.562326 -287.976287) (xy 93.539455 -288.019864) (xy 93.50989 -288.059208) (xy 93.474397 -288.0933)
			(xy 93.433894 -288.121256) (xy 93.389432 -288.142354) (xy 93.342161 -288.156046) (xy 93.293306 -288.161978)
			(xy 93.244131 -288.159997) (xy 93.195912 -288.150153) (xy 93.149896 -288.132701) (xy 93.107275 -288.108094)
			(xy 93.069154 -288.076969) (xy 93.036519 -288.040132) (xy 93.010216 -287.998536) (xy 92.990925 -287.95326)
			(xy 92.979148 -287.905476) (xy 92.975188 -287.856422) (xy 92.65666 -287.856422) (xy 92.656148 -287.881868)
			(xy 92.647984 -287.932102) (xy 92.631868 -287.980376) (xy 92.608217 -288.025439) (xy 92.577644 -288.066125)
			(xy 92.54094 -288.10138) (xy 92.499056 -288.13029) (xy 92.453077 -288.152107) (xy 92.404193 -288.166267)
			(xy 92.353672 -288.172401) (xy 92.30282 -288.170352) (xy 92.252956 -288.160172) (xy 92.20537 -288.142125)
			(xy 92.161296 -288.116679) (xy 92.121874 -288.084492) (xy 92.088126 -288.046398) (xy 92.060925 -288.003384)
			(xy 92.040977 -287.956564) (xy 92.028798 -287.90715) (xy 92.024703 -287.856422) (xy 91.71686 -287.856422)
			(xy 91.716348 -287.881868) (xy 91.708184 -287.932102) (xy 91.692068 -287.980376) (xy 91.668417 -288.025439)
			(xy 91.637844 -288.066125) (xy 91.60114 -288.10138) (xy 91.559256 -288.13029) (xy 91.513277 -288.152107)
			(xy 91.464393 -288.166267) (xy 91.413872 -288.172401) (xy 91.36302 -288.170352) (xy 91.313156 -288.160172)
			(xy 91.26557 -288.142125) (xy 91.221496 -288.116679) (xy 91.182074 -288.084492) (xy 91.148326 -288.046398)
			(xy 91.121125 -288.003384) (xy 91.101177 -287.956564) (xy 91.088998 -287.90715) (xy 91.084903 -287.856422)
			(xy 90.766392 -287.856422) (xy 90.765897 -287.881029) (xy 90.758002 -287.929606) (xy 90.742418 -287.976287)
			(xy 90.719547 -288.019864) (xy 90.689982 -288.059208) (xy 90.654489 -288.0933) (xy 90.613986 -288.121256)
			(xy 90.569524 -288.142354) (xy 90.522253 -288.156046) (xy 90.473398 -288.161978) (xy 90.424223 -288.159997)
			(xy 90.376004 -288.150153) (xy 90.329988 -288.132701) (xy 90.287367 -288.108094) (xy 90.249246 -288.076969)
			(xy 90.216611 -288.040132) (xy 90.190308 -287.998536) (xy 90.171017 -287.95326) (xy 90.15924 -287.905476)
			(xy 90.15528 -287.856422) (xy 89.836752 -287.856422) (xy 89.83624 -287.881868) (xy 89.828076 -287.932102)
			(xy 89.81196 -287.980376) (xy 89.788309 -288.025439) (xy 89.757736 -288.066125) (xy 89.721032 -288.10138)
			(xy 89.679148 -288.13029) (xy 89.633169 -288.152107) (xy 89.584285 -288.166267) (xy 89.533764 -288.172401)
			(xy 89.482912 -288.170352) (xy 89.433048 -288.160172) (xy 89.385462 -288.142125) (xy 89.341388 -288.116679)
			(xy 89.301966 -288.084492) (xy 89.268218 -288.046398) (xy 89.241017 -288.003384) (xy 89.221069 -287.956564)
			(xy 89.20889 -287.90715) (xy 89.204795 -287.856422) (xy 88.886284 -287.856422) (xy 88.885789 -287.881029)
			(xy 88.877894 -287.929606) (xy 88.86231 -287.976287) (xy 88.839439 -288.019864) (xy 88.809874 -288.059208)
			(xy 88.774381 -288.0933) (xy 88.733878 -288.121256) (xy 88.689416 -288.142354) (xy 88.642145 -288.156046)
			(xy 88.59329 -288.161978) (xy 88.544115 -288.159997) (xy 88.495896 -288.150153) (xy 88.44988 -288.132701)
			(xy 88.407259 -288.108094) (xy 88.369138 -288.076969) (xy 88.336503 -288.040132) (xy 88.3102 -287.998536)
			(xy 88.290909 -287.95326) (xy 88.279132 -287.905476) (xy 88.275172 -287.856422) (xy 87.956644 -287.856422)
			(xy 87.956132 -287.881868) (xy 87.947968 -287.932102) (xy 87.931852 -287.980376) (xy 87.908201 -288.025439)
			(xy 87.877628 -288.066125) (xy 87.840924 -288.10138) (xy 87.79904 -288.13029) (xy 87.753061 -288.152107)
			(xy 87.704177 -288.166267) (xy 87.653656 -288.172401) (xy 87.602804 -288.170352) (xy 87.55294 -288.160172)
			(xy 87.505354 -288.142125) (xy 87.46128 -288.116679) (xy 87.421858 -288.084492) (xy 87.38811 -288.046398)
			(xy 87.360909 -288.003384) (xy 87.340961 -287.956564) (xy 87.328782 -287.90715) (xy 87.324687 -287.856422)
			(xy 87.00643 -287.856422) (xy 87.005935 -287.881029) (xy 86.99804 -287.929606) (xy 86.982456 -287.976287)
			(xy 86.959585 -288.019864) (xy 86.93002 -288.059208) (xy 86.894527 -288.0933) (xy 86.854024 -288.121256)
			(xy 86.809562 -288.142354) (xy 86.762291 -288.156046) (xy 86.713436 -288.161978) (xy 86.664261 -288.159997)
			(xy 86.616042 -288.150153) (xy 86.570026 -288.132701) (xy 86.527405 -288.108094) (xy 86.489284 -288.076969)
			(xy 86.456649 -288.040132) (xy 86.430346 -287.998536) (xy 86.411055 -287.95326) (xy 86.399278 -287.905476)
			(xy 86.395318 -287.856422) (xy 86.07679 -287.856422) (xy 86.076278 -287.881868) (xy 86.068114 -287.932102)
			(xy 86.051998 -287.980376) (xy 86.028347 -288.025439) (xy 85.997774 -288.066125) (xy 85.96107 -288.10138)
			(xy 85.919186 -288.13029) (xy 85.873207 -288.152107) (xy 85.824323 -288.166267) (xy 85.773802 -288.172401)
			(xy 85.72295 -288.170352) (xy 85.673086 -288.160172) (xy 85.6255 -288.142125) (xy 85.581426 -288.116679)
			(xy 85.542004 -288.084492) (xy 85.508256 -288.046398) (xy 85.481055 -288.003384) (xy 85.461107 -287.956564)
			(xy 85.448928 -287.90715) (xy 85.444833 -287.856422) (xy 85.136736 -287.856422) (xy 85.136224 -287.881868)
			(xy 85.12806 -287.932102) (xy 85.111944 -287.980376) (xy 85.088293 -288.025439) (xy 85.05772 -288.066125)
			(xy 85.021016 -288.10138) (xy 84.979132 -288.13029) (xy 84.933153 -288.152107) (xy 84.884269 -288.166267)
			(xy 84.833748 -288.172401) (xy 84.782896 -288.170352) (xy 84.733032 -288.160172) (xy 84.685446 -288.142125)
			(xy 84.641372 -288.116679) (xy 84.60195 -288.084492) (xy 84.568202 -288.046398) (xy 84.541001 -288.003384)
			(xy 84.521053 -287.956564) (xy 84.508874 -287.90715) (xy 84.504779 -287.856422) (xy 84.186268 -287.856422)
			(xy 84.185773 -287.881029) (xy 84.177878 -287.929606) (xy 84.162294 -287.976287) (xy 84.139423 -288.019864)
			(xy 84.109858 -288.059208) (xy 84.074365 -288.0933) (xy 84.033862 -288.121256) (xy 83.9894 -288.142354)
			(xy 83.942129 -288.156046) (xy 83.893274 -288.161978) (xy 83.844099 -288.159997) (xy 83.79588 -288.150153)
			(xy 83.749864 -288.132701) (xy 83.707243 -288.108094) (xy 83.669122 -288.076969) (xy 83.636487 -288.040132)
			(xy 83.610184 -287.998536) (xy 83.590893 -287.95326) (xy 83.579116 -287.905476) (xy 83.575156 -287.856422)
			(xy 83.256628 -287.856422) (xy 83.256116 -287.881868) (xy 83.247952 -287.932102) (xy 83.231836 -287.980376)
			(xy 83.208185 -288.025439) (xy 83.177612 -288.066125) (xy 83.140908 -288.10138) (xy 83.099024 -288.13029)
			(xy 83.053045 -288.152107) (xy 83.004161 -288.166267) (xy 82.95364 -288.172401) (xy 82.902788 -288.170352)
			(xy 82.852924 -288.160172) (xy 82.805338 -288.142125) (xy 82.761264 -288.116679) (xy 82.721842 -288.084492)
			(xy 82.688094 -288.046398) (xy 82.660893 -288.003384) (xy 82.640945 -287.956564) (xy 82.628766 -287.90715)
			(xy 82.624671 -287.856422) (xy 82.306414 -287.856422) (xy 82.305919 -287.881029) (xy 82.298024 -287.929606)
			(xy 82.28244 -287.976287) (xy 82.259569 -288.019864) (xy 82.230004 -288.059208) (xy 82.194511 -288.0933)
			(xy 82.154008 -288.121256) (xy 82.109546 -288.142354) (xy 82.062275 -288.156046) (xy 82.01342 -288.161978)
			(xy 81.964245 -288.159997) (xy 81.916026 -288.150153) (xy 81.87001 -288.132701) (xy 81.827389 -288.108094)
			(xy 81.789268 -288.076969) (xy 81.756633 -288.040132) (xy 81.73033 -287.998536) (xy 81.711039 -287.95326)
			(xy 81.699262 -287.905476) (xy 81.695302 -287.856422) (xy 81.376774 -287.856422) (xy 81.376262 -287.881868)
			(xy 81.368098 -287.932102) (xy 81.351982 -287.980376) (xy 81.328331 -288.025439) (xy 81.297758 -288.066125)
			(xy 81.261054 -288.10138) (xy 81.21917 -288.13029) (xy 81.173191 -288.152107) (xy 81.124307 -288.166267)
			(xy 81.073786 -288.172401) (xy 81.022934 -288.170352) (xy 80.97307 -288.160172) (xy 80.925484 -288.142125)
			(xy 80.88141 -288.116679) (xy 80.841988 -288.084492) (xy 80.80824 -288.046398) (xy 80.781039 -288.003384)
			(xy 80.761091 -287.956564) (xy 80.748912 -287.90715) (xy 80.744817 -287.856422) (xy 80.426306 -287.856422)
			(xy 80.425811 -287.881029) (xy 80.417916 -287.929606) (xy 80.402332 -287.976287) (xy 80.379461 -288.019864)
			(xy 80.349896 -288.059208) (xy 80.314403 -288.0933) (xy 80.2739 -288.121256) (xy 80.229438 -288.142354)
			(xy 80.182167 -288.156046) (xy 80.133312 -288.161978) (xy 80.084137 -288.159997) (xy 80.035918 -288.150153)
			(xy 79.989902 -288.132701) (xy 79.947281 -288.108094) (xy 79.90916 -288.076969) (xy 79.876525 -288.040132)
			(xy 79.850222 -287.998536) (xy 79.830931 -287.95326) (xy 79.819154 -287.905476) (xy 79.815194 -287.856422)
			(xy 77.263451 -287.856422) (xy 77.221316 -287.876416) (xy 77.174045 -287.890108) (xy 77.12519 -287.89604)
			(xy 77.076015 -287.894059) (xy 77.027796 -287.884215) (xy 76.98178 -287.866763) (xy 76.939159 -287.842156)
			(xy 76.901038 -287.811031) (xy 76.868403 -287.774194) (xy 76.8421 -287.732598) (xy 76.822809 -287.687322)
			(xy 76.811032 -287.639538) (xy 76.807072 -287.590484) (xy 73.228962 -287.590484) (xy 73.228962 -288.666174)
			(xy 78.40524 -288.666174) (xy 78.4092 -288.61712) (xy 78.420977 -288.569336) (xy 78.440268 -288.52406)
			(xy 78.466571 -288.482464) (xy 78.499206 -288.445627) (xy 78.537327 -288.414502) (xy 78.579948 -288.389895)
			(xy 78.625964 -288.372443) (xy 78.674183 -288.362599) (xy 78.723358 -288.360618) (xy 78.772213 -288.36655)
			(xy 78.819484 -288.380242) (xy 78.863946 -288.40134) (xy 78.904449 -288.429296) (xy 78.939942 -288.463388)
			(xy 78.969507 -288.502732) (xy 78.992378 -288.546309) (xy 79.007962 -288.59299) (xy 79.015857 -288.641567)
			(xy 79.016352 -288.666174) (xy 80.285348 -288.666174) (xy 80.289308 -288.61712) (xy 80.301085 -288.569336)
			(xy 80.320376 -288.52406) (xy 80.346679 -288.482464) (xy 80.379314 -288.445627) (xy 80.417435 -288.414502)
			(xy 80.460056 -288.389895) (xy 80.506072 -288.372443) (xy 80.554291 -288.362599) (xy 80.603466 -288.360618)
			(xy 80.652321 -288.36655) (xy 80.699592 -288.380242) (xy 80.744054 -288.40134) (xy 80.784557 -288.429296)
			(xy 80.82005 -288.463388) (xy 80.849615 -288.502732) (xy 80.872486 -288.546309) (xy 80.88807 -288.59299)
			(xy 80.895965 -288.641567) (xy 80.89646 -288.666174) (xy 81.214717 -288.666174) (xy 81.218812 -288.615446)
			(xy 81.230991 -288.566032) (xy 81.250939 -288.519212) (xy 81.27814 -288.476198) (xy 81.311888 -288.438104)
			(xy 81.35131 -288.405917) (xy 81.395384 -288.380471) (xy 81.44297 -288.362424) (xy 81.492834 -288.352244)
			(xy 81.543686 -288.350195) (xy 81.594207 -288.356329) (xy 81.643091 -288.370489) (xy 81.68907 -288.392306)
			(xy 81.730954 -288.421216) (xy 81.767658 -288.456471) (xy 81.798231 -288.497157) (xy 81.821882 -288.54222)
			(xy 81.837998 -288.590494) (xy 81.846162 -288.640728) (xy 81.846674 -288.666174) (xy 82.154771 -288.666174)
			(xy 82.158866 -288.615446) (xy 82.171045 -288.566032) (xy 82.190993 -288.519212) (xy 82.218194 -288.476198)
			(xy 82.251942 -288.438104) (xy 82.291364 -288.405917) (xy 82.335438 -288.380471) (xy 82.383024 -288.362424)
			(xy 82.432888 -288.352244) (xy 82.48374 -288.350195) (xy 82.534261 -288.356329) (xy 82.583145 -288.370489)
			(xy 82.629124 -288.392306) (xy 82.671008 -288.421216) (xy 82.707712 -288.456471) (xy 82.738285 -288.497157)
			(xy 82.761936 -288.54222) (xy 82.778052 -288.590494) (xy 82.786216 -288.640728) (xy 82.786728 -288.666174)
			(xy 83.105256 -288.666174) (xy 83.109216 -288.61712) (xy 83.120993 -288.569336) (xy 83.140284 -288.52406)
			(xy 83.166587 -288.482464) (xy 83.199222 -288.445627) (xy 83.237343 -288.414502) (xy 83.279964 -288.389895)
			(xy 83.32598 -288.372443) (xy 83.374199 -288.362599) (xy 83.423374 -288.360618) (xy 83.472229 -288.36655)
			(xy 83.5195 -288.380242) (xy 83.563962 -288.40134) (xy 83.604465 -288.429296) (xy 83.639958 -288.463388)
			(xy 83.669523 -288.502732) (xy 83.692394 -288.546309) (xy 83.707978 -288.59299) (xy 83.715873 -288.641567)
			(xy 83.716368 -288.666174) (xy 84.034879 -288.666174) (xy 84.038974 -288.615446) (xy 84.051153 -288.566032)
			(xy 84.071101 -288.519212) (xy 84.098302 -288.476198) (xy 84.13205 -288.438104) (xy 84.171472 -288.405917)
			(xy 84.215546 -288.380471) (xy 84.263132 -288.362424) (xy 84.312996 -288.352244) (xy 84.363848 -288.350195)
			(xy 84.414369 -288.356329) (xy 84.463253 -288.370489) (xy 84.509232 -288.392306) (xy 84.551116 -288.421216)
			(xy 84.58782 -288.456471) (xy 84.618393 -288.497157) (xy 84.642044 -288.54222) (xy 84.65816 -288.590494)
			(xy 84.666324 -288.640728) (xy 84.666836 -288.666174) (xy 84.98511 -288.666174) (xy 84.98907 -288.61712)
			(xy 85.000847 -288.569336) (xy 85.020138 -288.52406) (xy 85.046441 -288.482464) (xy 85.079076 -288.445627)
			(xy 85.117197 -288.414502) (xy 85.159818 -288.389895) (xy 85.205834 -288.372443) (xy 85.254053 -288.362599)
			(xy 85.303228 -288.360618) (xy 85.352083 -288.36655) (xy 85.399354 -288.380242) (xy 85.443816 -288.40134)
			(xy 85.484319 -288.429296) (xy 85.519812 -288.463388) (xy 85.549377 -288.502732) (xy 85.572248 -288.546309)
			(xy 85.587832 -288.59299) (xy 85.595727 -288.641567) (xy 85.596222 -288.666174) (xy 85.914733 -288.666174)
			(xy 85.918828 -288.615446) (xy 85.931007 -288.566032) (xy 85.950955 -288.519212) (xy 85.978156 -288.476198)
			(xy 86.011904 -288.438104) (xy 86.051326 -288.405917) (xy 86.0954 -288.380471) (xy 86.142986 -288.362424)
			(xy 86.19285 -288.352244) (xy 86.243702 -288.350195) (xy 86.294223 -288.356329) (xy 86.343107 -288.370489)
			(xy 86.389086 -288.392306) (xy 86.43097 -288.421216) (xy 86.467674 -288.456471) (xy 86.498247 -288.497157)
			(xy 86.521898 -288.54222) (xy 86.538014 -288.590494) (xy 86.546178 -288.640728) (xy 86.54669 -288.666174)
			(xy 86.865218 -288.666174) (xy 86.869178 -288.61712) (xy 86.880955 -288.569336) (xy 86.900246 -288.52406)
			(xy 86.926549 -288.482464) (xy 86.959184 -288.445627) (xy 86.997305 -288.414502) (xy 87.039926 -288.389895)
			(xy 87.085942 -288.372443) (xy 87.134161 -288.362599) (xy 87.183336 -288.360618) (xy 87.232191 -288.36655)
			(xy 87.279462 -288.380242) (xy 87.323924 -288.40134) (xy 87.364427 -288.429296) (xy 87.39992 -288.463388)
			(xy 87.429485 -288.502732) (xy 87.452356 -288.546309) (xy 87.46794 -288.59299) (xy 87.475835 -288.641567)
			(xy 87.47633 -288.666174) (xy 87.794841 -288.666174) (xy 87.798936 -288.615446) (xy 87.811115 -288.566032)
			(xy 87.831063 -288.519212) (xy 87.858264 -288.476198) (xy 87.892012 -288.438104) (xy 87.931434 -288.405917)
			(xy 87.975508 -288.380471) (xy 88.023094 -288.362424) (xy 88.072958 -288.352244) (xy 88.12381 -288.350195)
			(xy 88.174331 -288.356329) (xy 88.223215 -288.370489) (xy 88.269194 -288.392306) (xy 88.311078 -288.421216)
			(xy 88.347782 -288.456471) (xy 88.378355 -288.497157) (xy 88.402006 -288.54222) (xy 88.418122 -288.590494)
			(xy 88.426286 -288.640728) (xy 88.426798 -288.666174) (xy 88.734895 -288.666174) (xy 88.73899 -288.615446)
			(xy 88.751169 -288.566032) (xy 88.771117 -288.519212) (xy 88.798318 -288.476198) (xy 88.832066 -288.438104)
			(xy 88.871488 -288.405917) (xy 88.915562 -288.380471) (xy 88.963148 -288.362424) (xy 89.013012 -288.352244)
			(xy 89.063864 -288.350195) (xy 89.114385 -288.356329) (xy 89.163269 -288.370489) (xy 89.209248 -288.392306)
			(xy 89.251132 -288.421216) (xy 89.287836 -288.456471) (xy 89.318409 -288.497157) (xy 89.34206 -288.54222)
			(xy 89.358176 -288.590494) (xy 89.36634 -288.640728) (xy 89.366852 -288.666174) (xy 89.685126 -288.666174)
			(xy 89.689086 -288.61712) (xy 89.700863 -288.569336) (xy 89.720154 -288.52406) (xy 89.746457 -288.482464)
			(xy 89.779092 -288.445627) (xy 89.817213 -288.414502) (xy 89.859834 -288.389895) (xy 89.90585 -288.372443)
			(xy 89.954069 -288.362599) (xy 90.003244 -288.360618) (xy 90.052099 -288.36655) (xy 90.09937 -288.380242)
			(xy 90.143832 -288.40134) (xy 90.184335 -288.429296) (xy 90.219828 -288.463388) (xy 90.249393 -288.502732)
			(xy 90.272264 -288.546309) (xy 90.287848 -288.59299) (xy 90.295743 -288.641567) (xy 90.296238 -288.666174)
			(xy 90.614749 -288.666174) (xy 90.618844 -288.615446) (xy 90.631023 -288.566032) (xy 90.650971 -288.519212)
			(xy 90.678172 -288.476198) (xy 90.71192 -288.438104) (xy 90.751342 -288.405917) (xy 90.795416 -288.380471)
			(xy 90.843002 -288.362424) (xy 90.892866 -288.352244) (xy 90.943718 -288.350195) (xy 90.994239 -288.356329)
			(xy 91.043123 -288.370489) (xy 91.089102 -288.392306) (xy 91.130986 -288.421216) (xy 91.16769 -288.456471)
			(xy 91.198263 -288.497157) (xy 91.221914 -288.54222) (xy 91.23803 -288.590494) (xy 91.246194 -288.640728)
			(xy 91.246706 -288.666174) (xy 91.565234 -288.666174) (xy 91.569194 -288.61712) (xy 91.580971 -288.569336)
			(xy 91.600262 -288.52406) (xy 91.626565 -288.482464) (xy 91.6592 -288.445627) (xy 91.697321 -288.414502)
			(xy 91.739942 -288.389895) (xy 91.785958 -288.372443) (xy 91.834177 -288.362599) (xy 91.883352 -288.360618)
			(xy 91.932207 -288.36655) (xy 91.979478 -288.380242) (xy 92.02394 -288.40134) (xy 92.064443 -288.429296)
			(xy 92.099936 -288.463388) (xy 92.129501 -288.502732) (xy 92.152372 -288.546309) (xy 92.167956 -288.59299)
			(xy 92.175851 -288.641567) (xy 92.176346 -288.666174) (xy 92.494857 -288.666174) (xy 92.498952 -288.615446)
			(xy 92.511131 -288.566032) (xy 92.531079 -288.519212) (xy 92.55828 -288.476198) (xy 92.592028 -288.438104)
			(xy 92.63145 -288.405917) (xy 92.675524 -288.380471) (xy 92.72311 -288.362424) (xy 92.772974 -288.352244)
			(xy 92.823826 -288.350195) (xy 92.874347 -288.356329) (xy 92.923231 -288.370489) (xy 92.96921 -288.392306)
			(xy 93.011094 -288.421216) (xy 93.047798 -288.456471) (xy 93.078371 -288.497157) (xy 93.102022 -288.54222)
			(xy 93.118138 -288.590494) (xy 93.126302 -288.640728) (xy 93.126814 -288.666174) (xy 93.445342 -288.666174)
			(xy 93.449302 -288.61712) (xy 93.461079 -288.569336) (xy 93.48037 -288.52406) (xy 93.506673 -288.482464)
			(xy 93.539308 -288.445627) (xy 93.577429 -288.414502) (xy 93.62005 -288.389895) (xy 93.666066 -288.372443)
			(xy 93.714285 -288.362599) (xy 93.76346 -288.360618) (xy 93.812315 -288.36655) (xy 93.859586 -288.380242)
			(xy 93.904048 -288.40134) (xy 93.944551 -288.429296) (xy 93.980044 -288.463388) (xy 94.009609 -288.502732)
			(xy 94.03248 -288.546309) (xy 94.048064 -288.59299) (xy 94.055959 -288.641567) (xy 94.056454 -288.666174)
			(xy 94.374711 -288.666174) (xy 94.378806 -288.615446) (xy 94.390985 -288.566032) (xy 94.410933 -288.519212)
			(xy 94.438134 -288.476198) (xy 94.471882 -288.438104) (xy 94.511304 -288.405917) (xy 94.555378 -288.380471)
			(xy 94.602964 -288.362424) (xy 94.652828 -288.352244) (xy 94.70368 -288.350195) (xy 94.754201 -288.356329)
			(xy 94.803085 -288.370489) (xy 94.849064 -288.392306) (xy 94.890948 -288.421216) (xy 94.927652 -288.456471)
			(xy 94.958225 -288.497157) (xy 94.981876 -288.54222) (xy 94.997992 -288.590494) (xy 95.006156 -288.640728)
			(xy 95.006668 -288.666174) (xy 95.314765 -288.666174) (xy 95.31886 -288.615446) (xy 95.331039 -288.566032)
			(xy 95.350987 -288.519212) (xy 95.378188 -288.476198) (xy 95.411936 -288.438104) (xy 95.451358 -288.405917)
			(xy 95.495432 -288.380471) (xy 95.543018 -288.362424) (xy 95.592882 -288.352244) (xy 95.643734 -288.350195)
			(xy 95.694255 -288.356329) (xy 95.743139 -288.370489) (xy 95.789118 -288.392306) (xy 95.831002 -288.421216)
			(xy 95.867706 -288.456471) (xy 95.898279 -288.497157) (xy 95.92193 -288.54222) (xy 95.938046 -288.590494)
			(xy 95.94621 -288.640728) (xy 95.946722 -288.666174) (xy 96.26525 -288.666174) (xy 96.26921 -288.61712)
			(xy 96.280987 -288.569336) (xy 96.300278 -288.52406) (xy 96.326581 -288.482464) (xy 96.359216 -288.445627)
			(xy 96.397337 -288.414502) (xy 96.439958 -288.389895) (xy 96.485974 -288.372443) (xy 96.534193 -288.362599)
			(xy 96.583368 -288.360618) (xy 96.632223 -288.36655) (xy 96.679494 -288.380242) (xy 96.723956 -288.40134)
			(xy 96.764459 -288.429296) (xy 96.799952 -288.463388) (xy 96.829517 -288.502732) (xy 96.852388 -288.546309)
			(xy 96.867972 -288.59299) (xy 96.875867 -288.641567) (xy 96.876362 -288.666174) (xy 97.205304 -288.666174)
			(xy 97.209264 -288.61712) (xy 97.221041 -288.569336) (xy 97.240332 -288.52406) (xy 97.266635 -288.482464)
			(xy 97.29927 -288.445627) (xy 97.337391 -288.414502) (xy 97.380012 -288.389895) (xy 97.426028 -288.372443)
			(xy 97.474247 -288.362599) (xy 97.523422 -288.360618) (xy 97.572277 -288.36655) (xy 97.619548 -288.380242)
			(xy 97.66401 -288.40134) (xy 97.704513 -288.429296) (xy 97.740006 -288.463388) (xy 97.769571 -288.502732)
			(xy 97.792442 -288.546309) (xy 97.808026 -288.59299) (xy 97.815921 -288.641567) (xy 97.816416 -288.666174)
			(xy 98.145358 -288.666174) (xy 98.149318 -288.61712) (xy 98.161095 -288.569336) (xy 98.180386 -288.52406)
			(xy 98.206689 -288.482464) (xy 98.239324 -288.445627) (xy 98.277445 -288.414502) (xy 98.320066 -288.389895)
			(xy 98.366082 -288.372443) (xy 98.414301 -288.362599) (xy 98.463476 -288.360618) (xy 98.512331 -288.36655)
			(xy 98.559602 -288.380242) (xy 98.604064 -288.40134) (xy 98.644567 -288.429296) (xy 98.68006 -288.463388)
			(xy 98.709625 -288.502732) (xy 98.732496 -288.546309) (xy 98.74808 -288.59299) (xy 98.755975 -288.641567)
			(xy 98.75647 -288.666174) (xy 99.085158 -288.666174) (xy 99.089118 -288.61712) (xy 99.100895 -288.569336)
			(xy 99.120186 -288.52406) (xy 99.146489 -288.482464) (xy 99.179124 -288.445627) (xy 99.217245 -288.414502)
			(xy 99.259866 -288.389895) (xy 99.305882 -288.372443) (xy 99.354101 -288.362599) (xy 99.403276 -288.360618)
			(xy 99.452131 -288.36655) (xy 99.499402 -288.380242) (xy 99.543864 -288.40134) (xy 99.584367 -288.429296)
			(xy 99.61986 -288.463388) (xy 99.649425 -288.502732) (xy 99.672296 -288.546309) (xy 99.68788 -288.59299)
			(xy 99.695775 -288.641567) (xy 99.69627 -288.666174) (xy 100.025212 -288.666174) (xy 100.029172 -288.61712)
			(xy 100.040949 -288.569336) (xy 100.06024 -288.52406) (xy 100.086543 -288.482464) (xy 100.119178 -288.445627)
			(xy 100.157299 -288.414502) (xy 100.19992 -288.389895) (xy 100.245936 -288.372443) (xy 100.294155 -288.362599)
			(xy 100.34333 -288.360618) (xy 100.392185 -288.36655) (xy 100.439456 -288.380242) (xy 100.483918 -288.40134)
			(xy 100.524421 -288.429296) (xy 100.559914 -288.463388) (xy 100.589479 -288.502732) (xy 100.61235 -288.546309)
			(xy 100.627934 -288.59299) (xy 100.635829 -288.641567) (xy 100.636324 -288.666174) (xy 100.965266 -288.666174)
			(xy 100.969226 -288.61712) (xy 100.981003 -288.569336) (xy 101.000294 -288.52406) (xy 101.026597 -288.482464)
			(xy 101.059232 -288.445627) (xy 101.097353 -288.414502) (xy 101.139974 -288.389895) (xy 101.18599 -288.372443)
			(xy 101.234209 -288.362599) (xy 101.283384 -288.360618) (xy 101.332239 -288.36655) (xy 101.37951 -288.380242)
			(xy 101.423972 -288.40134) (xy 101.464475 -288.429296) (xy 101.499968 -288.463388) (xy 101.529533 -288.502732)
			(xy 101.552404 -288.546309) (xy 101.567988 -288.59299) (xy 101.575883 -288.641567) (xy 101.576378 -288.666174)
			(xy 101.90532 -288.666174) (xy 101.90928 -288.61712) (xy 101.921057 -288.569336) (xy 101.940348 -288.52406)
			(xy 101.966651 -288.482464) (xy 101.999286 -288.445627) (xy 102.037407 -288.414502) (xy 102.080028 -288.389895)
			(xy 102.126044 -288.372443) (xy 102.174263 -288.362599) (xy 102.223438 -288.360618) (xy 102.272293 -288.36655)
			(xy 102.319564 -288.380242) (xy 102.364026 -288.40134) (xy 102.404529 -288.429296) (xy 102.440022 -288.463388)
			(xy 102.469587 -288.502732) (xy 102.492458 -288.546309) (xy 102.508042 -288.59299) (xy 102.515937 -288.641567)
			(xy 102.516432 -288.666174) (xy 102.515937 -288.690781) (xy 102.508042 -288.739358) (xy 102.492458 -288.786039)
			(xy 102.469587 -288.829616) (xy 102.440022 -288.86896) (xy 102.404529 -288.903052) (xy 102.364026 -288.931008)
			(xy 102.319564 -288.952106) (xy 102.272293 -288.965798) (xy 102.223438 -288.97173) (xy 102.174263 -288.969749)
			(xy 102.126044 -288.959905) (xy 102.080028 -288.942453) (xy 102.037407 -288.917846) (xy 101.999286 -288.886721)
			(xy 101.966651 -288.849884) (xy 101.940348 -288.808288) (xy 101.921057 -288.763012) (xy 101.90928 -288.715228)
			(xy 101.90532 -288.666174) (xy 101.576378 -288.666174) (xy 101.575883 -288.690781) (xy 101.567988 -288.739358)
			(xy 101.552404 -288.786039) (xy 101.529533 -288.829616) (xy 101.499968 -288.86896) (xy 101.464475 -288.903052)
			(xy 101.423972 -288.931008) (xy 101.37951 -288.952106) (xy 101.332239 -288.965798) (xy 101.283384 -288.97173)
			(xy 101.234209 -288.969749) (xy 101.18599 -288.959905) (xy 101.139974 -288.942453) (xy 101.097353 -288.917846)
			(xy 101.059232 -288.886721) (xy 101.026597 -288.849884) (xy 101.000294 -288.808288) (xy 100.981003 -288.763012)
			(xy 100.969226 -288.715228) (xy 100.965266 -288.666174) (xy 100.636324 -288.666174) (xy 100.635829 -288.690781)
			(xy 100.627934 -288.739358) (xy 100.61235 -288.786039) (xy 100.589479 -288.829616) (xy 100.559914 -288.86896)
			(xy 100.524421 -288.903052) (xy 100.483918 -288.931008) (xy 100.439456 -288.952106) (xy 100.392185 -288.965798)
			(xy 100.34333 -288.97173) (xy 100.294155 -288.969749) (xy 100.245936 -288.959905) (xy 100.19992 -288.942453)
			(xy 100.157299 -288.917846) (xy 100.119178 -288.886721) (xy 100.086543 -288.849884) (xy 100.06024 -288.808288)
			(xy 100.040949 -288.763012) (xy 100.029172 -288.715228) (xy 100.025212 -288.666174) (xy 99.69627 -288.666174)
			(xy 99.695775 -288.690781) (xy 99.68788 -288.739358) (xy 99.672296 -288.786039) (xy 99.649425 -288.829616)
			(xy 99.61986 -288.86896) (xy 99.584367 -288.903052) (xy 99.543864 -288.931008) (xy 99.499402 -288.952106)
			(xy 99.452131 -288.965798) (xy 99.403276 -288.97173) (xy 99.354101 -288.969749) (xy 99.305882 -288.959905)
			(xy 99.259866 -288.942453) (xy 99.217245 -288.917846) (xy 99.179124 -288.886721) (xy 99.146489 -288.849884)
			(xy 99.120186 -288.808288) (xy 99.100895 -288.763012) (xy 99.089118 -288.715228) (xy 99.085158 -288.666174)
			(xy 98.75647 -288.666174) (xy 98.755975 -288.690781) (xy 98.74808 -288.739358) (xy 98.732496 -288.786039)
			(xy 98.709625 -288.829616) (xy 98.68006 -288.86896) (xy 98.644567 -288.903052) (xy 98.604064 -288.931008)
			(xy 98.559602 -288.952106) (xy 98.512331 -288.965798) (xy 98.463476 -288.97173) (xy 98.414301 -288.969749)
			(xy 98.366082 -288.959905) (xy 98.320066 -288.942453) (xy 98.277445 -288.917846) (xy 98.239324 -288.886721)
			(xy 98.206689 -288.849884) (xy 98.180386 -288.808288) (xy 98.161095 -288.763012) (xy 98.149318 -288.715228)
			(xy 98.145358 -288.666174) (xy 97.816416 -288.666174) (xy 97.815921 -288.690781) (xy 97.808026 -288.739358)
			(xy 97.792442 -288.786039) (xy 97.769571 -288.829616) (xy 97.740006 -288.86896) (xy 97.704513 -288.903052)
			(xy 97.66401 -288.931008) (xy 97.619548 -288.952106) (xy 97.572277 -288.965798) (xy 97.523422 -288.97173)
			(xy 97.474247 -288.969749) (xy 97.426028 -288.959905) (xy 97.380012 -288.942453) (xy 97.337391 -288.917846)
			(xy 97.29927 -288.886721) (xy 97.266635 -288.849884) (xy 97.240332 -288.808288) (xy 97.221041 -288.763012)
			(xy 97.209264 -288.715228) (xy 97.205304 -288.666174) (xy 96.876362 -288.666174) (xy 96.875867 -288.690781)
			(xy 96.867972 -288.739358) (xy 96.852388 -288.786039) (xy 96.829517 -288.829616) (xy 96.799952 -288.86896)
			(xy 96.764459 -288.903052) (xy 96.723956 -288.931008) (xy 96.679494 -288.952106) (xy 96.632223 -288.965798)
			(xy 96.583368 -288.97173) (xy 96.534193 -288.969749) (xy 96.485974 -288.959905) (xy 96.439958 -288.942453)
			(xy 96.397337 -288.917846) (xy 96.359216 -288.886721) (xy 96.326581 -288.849884) (xy 96.300278 -288.808288)
			(xy 96.280987 -288.763012) (xy 96.26921 -288.715228) (xy 96.26525 -288.666174) (xy 95.946722 -288.666174)
			(xy 95.94621 -288.69162) (xy 95.938046 -288.741854) (xy 95.92193 -288.790128) (xy 95.898279 -288.835191)
			(xy 95.867706 -288.875877) (xy 95.831002 -288.911132) (xy 95.789118 -288.940042) (xy 95.743139 -288.961859)
			(xy 95.694255 -288.976019) (xy 95.643734 -288.982153) (xy 95.592882 -288.980104) (xy 95.543018 -288.969924)
			(xy 95.495432 -288.951877) (xy 95.451358 -288.926431) (xy 95.411936 -288.894244) (xy 95.378188 -288.85615)
			(xy 95.350987 -288.813136) (xy 95.331039 -288.766316) (xy 95.31886 -288.716902) (xy 95.314765 -288.666174)
			(xy 95.006668 -288.666174) (xy 95.006156 -288.69162) (xy 94.997992 -288.741854) (xy 94.981876 -288.790128)
			(xy 94.958225 -288.835191) (xy 94.927652 -288.875877) (xy 94.890948 -288.911132) (xy 94.849064 -288.940042)
			(xy 94.803085 -288.961859) (xy 94.754201 -288.976019) (xy 94.70368 -288.982153) (xy 94.652828 -288.980104)
			(xy 94.602964 -288.969924) (xy 94.555378 -288.951877) (xy 94.511304 -288.926431) (xy 94.471882 -288.894244)
			(xy 94.438134 -288.85615) (xy 94.410933 -288.813136) (xy 94.390985 -288.766316) (xy 94.378806 -288.716902)
			(xy 94.374711 -288.666174) (xy 94.056454 -288.666174) (xy 94.055959 -288.690781) (xy 94.048064 -288.739358)
			(xy 94.03248 -288.786039) (xy 94.009609 -288.829616) (xy 93.980044 -288.86896) (xy 93.944551 -288.903052)
			(xy 93.904048 -288.931008) (xy 93.859586 -288.952106) (xy 93.812315 -288.965798) (xy 93.76346 -288.97173)
			(xy 93.714285 -288.969749) (xy 93.666066 -288.959905) (xy 93.62005 -288.942453) (xy 93.577429 -288.917846)
			(xy 93.539308 -288.886721) (xy 93.506673 -288.849884) (xy 93.48037 -288.808288) (xy 93.461079 -288.763012)
			(xy 93.449302 -288.715228) (xy 93.445342 -288.666174) (xy 93.126814 -288.666174) (xy 93.126302 -288.69162)
			(xy 93.118138 -288.741854) (xy 93.102022 -288.790128) (xy 93.078371 -288.835191) (xy 93.047798 -288.875877)
			(xy 93.011094 -288.911132) (xy 92.96921 -288.940042) (xy 92.923231 -288.961859) (xy 92.874347 -288.976019)
			(xy 92.823826 -288.982153) (xy 92.772974 -288.980104) (xy 92.72311 -288.969924) (xy 92.675524 -288.951877)
			(xy 92.63145 -288.926431) (xy 92.592028 -288.894244) (xy 92.55828 -288.85615) (xy 92.531079 -288.813136)
			(xy 92.511131 -288.766316) (xy 92.498952 -288.716902) (xy 92.494857 -288.666174) (xy 92.176346 -288.666174)
			(xy 92.175851 -288.690781) (xy 92.167956 -288.739358) (xy 92.152372 -288.786039) (xy 92.129501 -288.829616)
			(xy 92.099936 -288.86896) (xy 92.064443 -288.903052) (xy 92.02394 -288.931008) (xy 91.979478 -288.952106)
			(xy 91.932207 -288.965798) (xy 91.883352 -288.97173) (xy 91.834177 -288.969749) (xy 91.785958 -288.959905)
			(xy 91.739942 -288.942453) (xy 91.697321 -288.917846) (xy 91.6592 -288.886721) (xy 91.626565 -288.849884)
			(xy 91.600262 -288.808288) (xy 91.580971 -288.763012) (xy 91.569194 -288.715228) (xy 91.565234 -288.666174)
			(xy 91.246706 -288.666174) (xy 91.246194 -288.69162) (xy 91.23803 -288.741854) (xy 91.221914 -288.790128)
			(xy 91.198263 -288.835191) (xy 91.16769 -288.875877) (xy 91.130986 -288.911132) (xy 91.089102 -288.940042)
			(xy 91.043123 -288.961859) (xy 90.994239 -288.976019) (xy 90.943718 -288.982153) (xy 90.892866 -288.980104)
			(xy 90.843002 -288.969924) (xy 90.795416 -288.951877) (xy 90.751342 -288.926431) (xy 90.71192 -288.894244)
			(xy 90.678172 -288.85615) (xy 90.650971 -288.813136) (xy 90.631023 -288.766316) (xy 90.618844 -288.716902)
			(xy 90.614749 -288.666174) (xy 90.296238 -288.666174) (xy 90.295743 -288.690781) (xy 90.287848 -288.739358)
			(xy 90.272264 -288.786039) (xy 90.249393 -288.829616) (xy 90.219828 -288.86896) (xy 90.184335 -288.903052)
			(xy 90.143832 -288.931008) (xy 90.09937 -288.952106) (xy 90.052099 -288.965798) (xy 90.003244 -288.97173)
			(xy 89.954069 -288.969749) (xy 89.90585 -288.959905) (xy 89.859834 -288.942453) (xy 89.817213 -288.917846)
			(xy 89.779092 -288.886721) (xy 89.746457 -288.849884) (xy 89.720154 -288.808288) (xy 89.700863 -288.763012)
			(xy 89.689086 -288.715228) (xy 89.685126 -288.666174) (xy 89.366852 -288.666174) (xy 89.36634 -288.69162)
			(xy 89.358176 -288.741854) (xy 89.34206 -288.790128) (xy 89.318409 -288.835191) (xy 89.287836 -288.875877)
			(xy 89.251132 -288.911132) (xy 89.209248 -288.940042) (xy 89.163269 -288.961859) (xy 89.114385 -288.976019)
			(xy 89.063864 -288.982153) (xy 89.013012 -288.980104) (xy 88.963148 -288.969924) (xy 88.915562 -288.951877)
			(xy 88.871488 -288.926431) (xy 88.832066 -288.894244) (xy 88.798318 -288.85615) (xy 88.771117 -288.813136)
			(xy 88.751169 -288.766316) (xy 88.73899 -288.716902) (xy 88.734895 -288.666174) (xy 88.426798 -288.666174)
			(xy 88.426286 -288.69162) (xy 88.418122 -288.741854) (xy 88.402006 -288.790128) (xy 88.378355 -288.835191)
			(xy 88.347782 -288.875877) (xy 88.311078 -288.911132) (xy 88.269194 -288.940042) (xy 88.223215 -288.961859)
			(xy 88.174331 -288.976019) (xy 88.12381 -288.982153) (xy 88.072958 -288.980104) (xy 88.023094 -288.969924)
			(xy 87.975508 -288.951877) (xy 87.931434 -288.926431) (xy 87.892012 -288.894244) (xy 87.858264 -288.85615)
			(xy 87.831063 -288.813136) (xy 87.811115 -288.766316) (xy 87.798936 -288.716902) (xy 87.794841 -288.666174)
			(xy 87.47633 -288.666174) (xy 87.475835 -288.690781) (xy 87.46794 -288.739358) (xy 87.452356 -288.786039)
			(xy 87.429485 -288.829616) (xy 87.39992 -288.86896) (xy 87.364427 -288.903052) (xy 87.323924 -288.931008)
			(xy 87.279462 -288.952106) (xy 87.232191 -288.965798) (xy 87.183336 -288.97173) (xy 87.134161 -288.969749)
			(xy 87.085942 -288.959905) (xy 87.039926 -288.942453) (xy 86.997305 -288.917846) (xy 86.959184 -288.886721)
			(xy 86.926549 -288.849884) (xy 86.900246 -288.808288) (xy 86.880955 -288.763012) (xy 86.869178 -288.715228)
			(xy 86.865218 -288.666174) (xy 86.54669 -288.666174) (xy 86.546178 -288.69162) (xy 86.538014 -288.741854)
			(xy 86.521898 -288.790128) (xy 86.498247 -288.835191) (xy 86.467674 -288.875877) (xy 86.43097 -288.911132)
			(xy 86.389086 -288.940042) (xy 86.343107 -288.961859) (xy 86.294223 -288.976019) (xy 86.243702 -288.982153)
			(xy 86.19285 -288.980104) (xy 86.142986 -288.969924) (xy 86.0954 -288.951877) (xy 86.051326 -288.926431)
			(xy 86.011904 -288.894244) (xy 85.978156 -288.85615) (xy 85.950955 -288.813136) (xy 85.931007 -288.766316)
			(xy 85.918828 -288.716902) (xy 85.914733 -288.666174) (xy 85.596222 -288.666174) (xy 85.595727 -288.690781)
			(xy 85.587832 -288.739358) (xy 85.572248 -288.786039) (xy 85.549377 -288.829616) (xy 85.519812 -288.86896)
			(xy 85.484319 -288.903052) (xy 85.443816 -288.931008) (xy 85.399354 -288.952106) (xy 85.352083 -288.965798)
			(xy 85.303228 -288.97173) (xy 85.254053 -288.969749) (xy 85.205834 -288.959905) (xy 85.159818 -288.942453)
			(xy 85.117197 -288.917846) (xy 85.079076 -288.886721) (xy 85.046441 -288.849884) (xy 85.020138 -288.808288)
			(xy 85.000847 -288.763012) (xy 84.98907 -288.715228) (xy 84.98511 -288.666174) (xy 84.666836 -288.666174)
			(xy 84.666324 -288.69162) (xy 84.65816 -288.741854) (xy 84.642044 -288.790128) (xy 84.618393 -288.835191)
			(xy 84.58782 -288.875877) (xy 84.551116 -288.911132) (xy 84.509232 -288.940042) (xy 84.463253 -288.961859)
			(xy 84.414369 -288.976019) (xy 84.363848 -288.982153) (xy 84.312996 -288.980104) (xy 84.263132 -288.969924)
			(xy 84.215546 -288.951877) (xy 84.171472 -288.926431) (xy 84.13205 -288.894244) (xy 84.098302 -288.85615)
			(xy 84.071101 -288.813136) (xy 84.051153 -288.766316) (xy 84.038974 -288.716902) (xy 84.034879 -288.666174)
			(xy 83.716368 -288.666174) (xy 83.715873 -288.690781) (xy 83.707978 -288.739358) (xy 83.692394 -288.786039)
			(xy 83.669523 -288.829616) (xy 83.639958 -288.86896) (xy 83.604465 -288.903052) (xy 83.563962 -288.931008)
			(xy 83.5195 -288.952106) (xy 83.472229 -288.965798) (xy 83.423374 -288.97173) (xy 83.374199 -288.969749)
			(xy 83.32598 -288.959905) (xy 83.279964 -288.942453) (xy 83.237343 -288.917846) (xy 83.199222 -288.886721)
			(xy 83.166587 -288.849884) (xy 83.140284 -288.808288) (xy 83.120993 -288.763012) (xy 83.109216 -288.715228)
			(xy 83.105256 -288.666174) (xy 82.786728 -288.666174) (xy 82.786216 -288.69162) (xy 82.778052 -288.741854)
			(xy 82.761936 -288.790128) (xy 82.738285 -288.835191) (xy 82.707712 -288.875877) (xy 82.671008 -288.911132)
			(xy 82.629124 -288.940042) (xy 82.583145 -288.961859) (xy 82.534261 -288.976019) (xy 82.48374 -288.982153)
			(xy 82.432888 -288.980104) (xy 82.383024 -288.969924) (xy 82.335438 -288.951877) (xy 82.291364 -288.926431)
			(xy 82.251942 -288.894244) (xy 82.218194 -288.85615) (xy 82.190993 -288.813136) (xy 82.171045 -288.766316)
			(xy 82.158866 -288.716902) (xy 82.154771 -288.666174) (xy 81.846674 -288.666174) (xy 81.846162 -288.69162)
			(xy 81.837998 -288.741854) (xy 81.821882 -288.790128) (xy 81.798231 -288.835191) (xy 81.767658 -288.875877)
			(xy 81.730954 -288.911132) (xy 81.68907 -288.940042) (xy 81.643091 -288.961859) (xy 81.594207 -288.976019)
			(xy 81.543686 -288.982153) (xy 81.492834 -288.980104) (xy 81.44297 -288.969924) (xy 81.395384 -288.951877)
			(xy 81.35131 -288.926431) (xy 81.311888 -288.894244) (xy 81.27814 -288.85615) (xy 81.250939 -288.813136)
			(xy 81.230991 -288.766316) (xy 81.218812 -288.716902) (xy 81.214717 -288.666174) (xy 80.89646 -288.666174)
			(xy 80.895965 -288.690781) (xy 80.88807 -288.739358) (xy 80.872486 -288.786039) (xy 80.849615 -288.829616)
			(xy 80.82005 -288.86896) (xy 80.784557 -288.903052) (xy 80.744054 -288.931008) (xy 80.699592 -288.952106)
			(xy 80.652321 -288.965798) (xy 80.603466 -288.97173) (xy 80.554291 -288.969749) (xy 80.506072 -288.959905)
			(xy 80.460056 -288.942453) (xy 80.417435 -288.917846) (xy 80.379314 -288.886721) (xy 80.346679 -288.849884)
			(xy 80.320376 -288.808288) (xy 80.301085 -288.763012) (xy 80.289308 -288.715228) (xy 80.285348 -288.666174)
			(xy 79.016352 -288.666174) (xy 79.015857 -288.690781) (xy 79.007962 -288.739358) (xy 78.992378 -288.786039)
			(xy 78.969507 -288.829616) (xy 78.939942 -288.86896) (xy 78.904449 -288.903052) (xy 78.863946 -288.931008)
			(xy 78.819484 -288.952106) (xy 78.772213 -288.965798) (xy 78.723358 -288.97173) (xy 78.674183 -288.969749)
			(xy 78.625964 -288.959905) (xy 78.579948 -288.942453) (xy 78.537327 -288.917846) (xy 78.499206 -288.886721)
			(xy 78.466571 -288.849884) (xy 78.440268 -288.808288) (xy 78.420977 -288.763012) (xy 78.4092 -288.715228)
			(xy 78.40524 -288.666174) (xy 73.228962 -288.666174) (xy 73.228962 -289.210242) (xy 76.807072 -289.210242)
			(xy 76.811032 -289.161188) (xy 76.822809 -289.113404) (xy 76.8421 -289.068128) (xy 76.868403 -289.026532)
			(xy 76.901038 -288.989695) (xy 76.939159 -288.95857) (xy 76.98178 -288.933963) (xy 77.027796 -288.916511)
			(xy 77.076015 -288.906667) (xy 77.12519 -288.904686) (xy 77.174045 -288.910618) (xy 77.221316 -288.92431)
			(xy 77.265778 -288.945408) (xy 77.306281 -288.973364) (xy 77.341774 -289.007456) (xy 77.371339 -289.0468)
			(xy 77.39421 -289.090377) (xy 77.409794 -289.137058) (xy 77.417689 -289.185635) (xy 77.418184 -289.210242)
			(xy 77.417689 -289.234849) (xy 77.409794 -289.283426) (xy 77.39421 -289.330107) (xy 77.371339 -289.373684)
			(xy 77.341774 -289.413028) (xy 77.306281 -289.44712) (xy 77.265778 -289.475076) (xy 77.263451 -289.47618)
			(xy 79.815194 -289.47618) (xy 79.819154 -289.427126) (xy 79.830931 -289.379342) (xy 79.850222 -289.334066)
			(xy 79.876525 -289.29247) (xy 79.90916 -289.255633) (xy 79.947281 -289.224508) (xy 79.989902 -289.199901)
			(xy 80.035918 -289.182449) (xy 80.084137 -289.172605) (xy 80.133312 -289.170624) (xy 80.182167 -289.176556)
			(xy 80.229438 -289.190248) (xy 80.2739 -289.211346) (xy 80.314403 -289.239302) (xy 80.349896 -289.273394)
			(xy 80.379461 -289.312738) (xy 80.402332 -289.356315) (xy 80.417916 -289.402996) (xy 80.425811 -289.451573)
			(xy 80.426306 -289.47618) (xy 80.744817 -289.47618) (xy 80.748912 -289.425452) (xy 80.761091 -289.376038)
			(xy 80.781039 -289.329218) (xy 80.80824 -289.286204) (xy 80.841988 -289.24811) (xy 80.88141 -289.215923)
			(xy 80.925484 -289.190477) (xy 80.97307 -289.17243) (xy 81.022934 -289.16225) (xy 81.073786 -289.160201)
			(xy 81.124307 -289.166335) (xy 81.173191 -289.180495) (xy 81.21917 -289.202312) (xy 81.261054 -289.231222)
			(xy 81.297758 -289.266477) (xy 81.328331 -289.307163) (xy 81.351982 -289.352226) (xy 81.368098 -289.4005)
			(xy 81.376262 -289.450734) (xy 81.376774 -289.47618) (xy 81.695302 -289.47618) (xy 81.699262 -289.427126)
			(xy 81.711039 -289.379342) (xy 81.73033 -289.334066) (xy 81.756633 -289.29247) (xy 81.789268 -289.255633)
			(xy 81.827389 -289.224508) (xy 81.87001 -289.199901) (xy 81.916026 -289.182449) (xy 81.964245 -289.172605)
			(xy 82.01342 -289.170624) (xy 82.062275 -289.176556) (xy 82.109546 -289.190248) (xy 82.154008 -289.211346)
			(xy 82.194511 -289.239302) (xy 82.230004 -289.273394) (xy 82.259569 -289.312738) (xy 82.28244 -289.356315)
			(xy 82.298024 -289.402996) (xy 82.305919 -289.451573) (xy 82.306414 -289.47618) (xy 82.624671 -289.47618)
			(xy 82.628766 -289.425452) (xy 82.640945 -289.376038) (xy 82.660893 -289.329218) (xy 82.688094 -289.286204)
			(xy 82.721842 -289.24811) (xy 82.761264 -289.215923) (xy 82.805338 -289.190477) (xy 82.852924 -289.17243)
			(xy 82.902788 -289.16225) (xy 82.95364 -289.160201) (xy 83.004161 -289.166335) (xy 83.053045 -289.180495)
			(xy 83.099024 -289.202312) (xy 83.140908 -289.231222) (xy 83.177612 -289.266477) (xy 83.208185 -289.307163)
			(xy 83.231836 -289.352226) (xy 83.247952 -289.4005) (xy 83.256116 -289.450734) (xy 83.256628 -289.47618)
			(xy 83.575156 -289.47618) (xy 83.579116 -289.427126) (xy 83.590893 -289.379342) (xy 83.610184 -289.334066)
			(xy 83.636487 -289.29247) (xy 83.669122 -289.255633) (xy 83.707243 -289.224508) (xy 83.749864 -289.199901)
			(xy 83.79588 -289.182449) (xy 83.844099 -289.172605) (xy 83.893274 -289.170624) (xy 83.942129 -289.176556)
			(xy 83.9894 -289.190248) (xy 84.033862 -289.211346) (xy 84.074365 -289.239302) (xy 84.109858 -289.273394)
			(xy 84.139423 -289.312738) (xy 84.162294 -289.356315) (xy 84.177878 -289.402996) (xy 84.185773 -289.451573)
			(xy 84.186268 -289.47618) (xy 84.504779 -289.47618) (xy 84.508874 -289.425452) (xy 84.521053 -289.376038)
			(xy 84.541001 -289.329218) (xy 84.568202 -289.286204) (xy 84.60195 -289.24811) (xy 84.641372 -289.215923)
			(xy 84.685446 -289.190477) (xy 84.733032 -289.17243) (xy 84.782896 -289.16225) (xy 84.833748 -289.160201)
			(xy 84.884269 -289.166335) (xy 84.933153 -289.180495) (xy 84.979132 -289.202312) (xy 85.021016 -289.231222)
			(xy 85.05772 -289.266477) (xy 85.088293 -289.307163) (xy 85.111944 -289.352226) (xy 85.12806 -289.4005)
			(xy 85.136224 -289.450734) (xy 85.136736 -289.47618) (xy 85.444833 -289.47618) (xy 85.448928 -289.425452)
			(xy 85.461107 -289.376038) (xy 85.481055 -289.329218) (xy 85.508256 -289.286204) (xy 85.542004 -289.24811)
			(xy 85.581426 -289.215923) (xy 85.6255 -289.190477) (xy 85.673086 -289.17243) (xy 85.72295 -289.16225)
			(xy 85.773802 -289.160201) (xy 85.824323 -289.166335) (xy 85.873207 -289.180495) (xy 85.919186 -289.202312)
			(xy 85.96107 -289.231222) (xy 85.997774 -289.266477) (xy 86.028347 -289.307163) (xy 86.051998 -289.352226)
			(xy 86.068114 -289.4005) (xy 86.076278 -289.450734) (xy 86.07679 -289.47618) (xy 86.395318 -289.47618)
			(xy 86.399278 -289.427126) (xy 86.411055 -289.379342) (xy 86.430346 -289.334066) (xy 86.456649 -289.29247)
			(xy 86.489284 -289.255633) (xy 86.527405 -289.224508) (xy 86.570026 -289.199901) (xy 86.616042 -289.182449)
			(xy 86.664261 -289.172605) (xy 86.713436 -289.170624) (xy 86.762291 -289.176556) (xy 86.809562 -289.190248)
			(xy 86.854024 -289.211346) (xy 86.894527 -289.239302) (xy 86.93002 -289.273394) (xy 86.959585 -289.312738)
			(xy 86.982456 -289.356315) (xy 86.99804 -289.402996) (xy 87.005935 -289.451573) (xy 87.00643 -289.47618)
			(xy 87.324687 -289.47618) (xy 87.328782 -289.425452) (xy 87.340961 -289.376038) (xy 87.360909 -289.329218)
			(xy 87.38811 -289.286204) (xy 87.421858 -289.24811) (xy 87.46128 -289.215923) (xy 87.505354 -289.190477)
			(xy 87.55294 -289.17243) (xy 87.602804 -289.16225) (xy 87.653656 -289.160201) (xy 87.704177 -289.166335)
			(xy 87.753061 -289.180495) (xy 87.79904 -289.202312) (xy 87.840924 -289.231222) (xy 87.877628 -289.266477)
			(xy 87.908201 -289.307163) (xy 87.931852 -289.352226) (xy 87.947968 -289.4005) (xy 87.956132 -289.450734)
			(xy 87.956644 -289.47618) (xy 88.275172 -289.47618) (xy 88.279132 -289.427126) (xy 88.290909 -289.379342)
			(xy 88.3102 -289.334066) (xy 88.336503 -289.29247) (xy 88.369138 -289.255633) (xy 88.407259 -289.224508)
			(xy 88.44988 -289.199901) (xy 88.495896 -289.182449) (xy 88.544115 -289.172605) (xy 88.59329 -289.170624)
			(xy 88.642145 -289.176556) (xy 88.689416 -289.190248) (xy 88.733878 -289.211346) (xy 88.774381 -289.239302)
			(xy 88.809874 -289.273394) (xy 88.839439 -289.312738) (xy 88.86231 -289.356315) (xy 88.877894 -289.402996)
			(xy 88.885789 -289.451573) (xy 88.886284 -289.47618) (xy 89.204795 -289.47618) (xy 89.20889 -289.425452)
			(xy 89.221069 -289.376038) (xy 89.241017 -289.329218) (xy 89.268218 -289.286204) (xy 89.301966 -289.24811)
			(xy 89.341388 -289.215923) (xy 89.385462 -289.190477) (xy 89.433048 -289.17243) (xy 89.482912 -289.16225)
			(xy 89.533764 -289.160201) (xy 89.584285 -289.166335) (xy 89.633169 -289.180495) (xy 89.679148 -289.202312)
			(xy 89.721032 -289.231222) (xy 89.757736 -289.266477) (xy 89.788309 -289.307163) (xy 89.81196 -289.352226)
			(xy 89.828076 -289.4005) (xy 89.83624 -289.450734) (xy 89.836752 -289.47618) (xy 90.15528 -289.47618)
			(xy 90.15924 -289.427126) (xy 90.171017 -289.379342) (xy 90.190308 -289.334066) (xy 90.216611 -289.29247)
			(xy 90.249246 -289.255633) (xy 90.287367 -289.224508) (xy 90.329988 -289.199901) (xy 90.376004 -289.182449)
			(xy 90.424223 -289.172605) (xy 90.473398 -289.170624) (xy 90.522253 -289.176556) (xy 90.569524 -289.190248)
			(xy 90.613986 -289.211346) (xy 90.654489 -289.239302) (xy 90.689982 -289.273394) (xy 90.719547 -289.312738)
			(xy 90.742418 -289.356315) (xy 90.758002 -289.402996) (xy 90.765897 -289.451573) (xy 90.766392 -289.47618)
			(xy 91.084903 -289.47618) (xy 91.088998 -289.425452) (xy 91.101177 -289.376038) (xy 91.121125 -289.329218)
			(xy 91.148326 -289.286204) (xy 91.182074 -289.24811) (xy 91.221496 -289.215923) (xy 91.26557 -289.190477)
			(xy 91.313156 -289.17243) (xy 91.36302 -289.16225) (xy 91.413872 -289.160201) (xy 91.464393 -289.166335)
			(xy 91.513277 -289.180495) (xy 91.559256 -289.202312) (xy 91.60114 -289.231222) (xy 91.637844 -289.266477)
			(xy 91.668417 -289.307163) (xy 91.692068 -289.352226) (xy 91.708184 -289.4005) (xy 91.716348 -289.450734)
			(xy 91.71686 -289.47618) (xy 92.024703 -289.47618) (xy 92.028798 -289.425452) (xy 92.040977 -289.376038)
			(xy 92.060925 -289.329218) (xy 92.088126 -289.286204) (xy 92.121874 -289.24811) (xy 92.161296 -289.215923)
			(xy 92.20537 -289.190477) (xy 92.252956 -289.17243) (xy 92.30282 -289.16225) (xy 92.353672 -289.160201)
			(xy 92.404193 -289.166335) (xy 92.453077 -289.180495) (xy 92.499056 -289.202312) (xy 92.54094 -289.231222)
			(xy 92.577644 -289.266477) (xy 92.608217 -289.307163) (xy 92.631868 -289.352226) (xy 92.647984 -289.4005)
			(xy 92.656148 -289.450734) (xy 92.65666 -289.47618) (xy 92.975188 -289.47618) (xy 92.979148 -289.427126)
			(xy 92.990925 -289.379342) (xy 93.010216 -289.334066) (xy 93.036519 -289.29247) (xy 93.069154 -289.255633)
			(xy 93.107275 -289.224508) (xy 93.149896 -289.199901) (xy 93.195912 -289.182449) (xy 93.244131 -289.172605)
			(xy 93.293306 -289.170624) (xy 93.342161 -289.176556) (xy 93.389432 -289.190248) (xy 93.433894 -289.211346)
			(xy 93.474397 -289.239302) (xy 93.50989 -289.273394) (xy 93.539455 -289.312738) (xy 93.562326 -289.356315)
			(xy 93.57791 -289.402996) (xy 93.585805 -289.451573) (xy 93.5863 -289.47618) (xy 93.904811 -289.47618)
			(xy 93.908906 -289.425452) (xy 93.921085 -289.376038) (xy 93.941033 -289.329218) (xy 93.968234 -289.286204)
			(xy 94.001982 -289.24811) (xy 94.041404 -289.215923) (xy 94.085478 -289.190477) (xy 94.133064 -289.17243)
			(xy 94.182928 -289.16225) (xy 94.23378 -289.160201) (xy 94.284301 -289.166335) (xy 94.333185 -289.180495)
			(xy 94.379164 -289.202312) (xy 94.421048 -289.231222) (xy 94.457752 -289.266477) (xy 94.488325 -289.307163)
			(xy 94.511976 -289.352226) (xy 94.528092 -289.4005) (xy 94.536256 -289.450734) (xy 94.536768 -289.47618)
			(xy 94.855296 -289.47618) (xy 94.859256 -289.427126) (xy 94.871033 -289.379342) (xy 94.890324 -289.334066)
			(xy 94.916627 -289.29247) (xy 94.949262 -289.255633) (xy 94.987383 -289.224508) (xy 95.030004 -289.199901)
			(xy 95.07602 -289.182449) (xy 95.124239 -289.172605) (xy 95.173414 -289.170624) (xy 95.222269 -289.176556)
			(xy 95.26954 -289.190248) (xy 95.314002 -289.211346) (xy 95.354505 -289.239302) (xy 95.389998 -289.273394)
			(xy 95.419563 -289.312738) (xy 95.442434 -289.356315) (xy 95.458018 -289.402996) (xy 95.465913 -289.451573)
			(xy 95.466408 -289.47618) (xy 95.784919 -289.47618) (xy 95.789014 -289.425452) (xy 95.801193 -289.376038)
			(xy 95.821141 -289.329218) (xy 95.848342 -289.286204) (xy 95.88209 -289.24811) (xy 95.921512 -289.215923)
			(xy 95.965586 -289.190477) (xy 96.013172 -289.17243) (xy 96.063036 -289.16225) (xy 96.113888 -289.160201)
			(xy 96.164409 -289.166335) (xy 96.213293 -289.180495) (xy 96.259272 -289.202312) (xy 96.301156 -289.231222)
			(xy 96.33786 -289.266477) (xy 96.368433 -289.307163) (xy 96.392084 -289.352226) (xy 96.4082 -289.4005)
			(xy 96.416364 -289.450734) (xy 96.416876 -289.47618) (xy 96.73515 -289.47618) (xy 96.73911 -289.427126)
			(xy 96.750887 -289.379342) (xy 96.770178 -289.334066) (xy 96.796481 -289.29247) (xy 96.829116 -289.255633)
			(xy 96.867237 -289.224508) (xy 96.909858 -289.199901) (xy 96.955874 -289.182449) (xy 97.004093 -289.172605)
			(xy 97.053268 -289.170624) (xy 97.102123 -289.176556) (xy 97.149394 -289.190248) (xy 97.193856 -289.211346)
			(xy 97.234359 -289.239302) (xy 97.269852 -289.273394) (xy 97.299417 -289.312738) (xy 97.322288 -289.356315)
			(xy 97.337872 -289.402996) (xy 97.345767 -289.451573) (xy 97.346262 -289.47618) (xy 97.664773 -289.47618)
			(xy 97.668868 -289.425452) (xy 97.681047 -289.376038) (xy 97.700995 -289.329218) (xy 97.728196 -289.286204)
			(xy 97.761944 -289.24811) (xy 97.801366 -289.215923) (xy 97.84544 -289.190477) (xy 97.893026 -289.17243)
			(xy 97.94289 -289.16225) (xy 97.993742 -289.160201) (xy 98.044263 -289.166335) (xy 98.093147 -289.180495)
			(xy 98.139126 -289.202312) (xy 98.18101 -289.231222) (xy 98.217714 -289.266477) (xy 98.248287 -289.307163)
			(xy 98.271938 -289.352226) (xy 98.288054 -289.4005) (xy 98.296218 -289.450734) (xy 98.29673 -289.47618)
			(xy 98.604827 -289.47618) (xy 98.608922 -289.425452) (xy 98.621101 -289.376038) (xy 98.641049 -289.329218)
			(xy 98.66825 -289.286204) (xy 98.701998 -289.24811) (xy 98.74142 -289.215923) (xy 98.785494 -289.190477)
			(xy 98.83308 -289.17243) (xy 98.882944 -289.16225) (xy 98.933796 -289.160201) (xy 98.984317 -289.166335)
			(xy 99.033201 -289.180495) (xy 99.07918 -289.202312) (xy 99.121064 -289.231222) (xy 99.157768 -289.266477)
			(xy 99.188341 -289.307163) (xy 99.211992 -289.352226) (xy 99.228108 -289.4005) (xy 99.236272 -289.450734)
			(xy 99.236784 -289.47618) (xy 99.555312 -289.47618) (xy 99.559272 -289.427126) (xy 99.571049 -289.379342)
			(xy 99.59034 -289.334066) (xy 99.616643 -289.29247) (xy 99.649278 -289.255633) (xy 99.687399 -289.224508)
			(xy 99.73002 -289.199901) (xy 99.776036 -289.182449) (xy 99.824255 -289.172605) (xy 99.87343 -289.170624)
			(xy 99.922285 -289.176556) (xy 99.969556 -289.190248) (xy 100.014018 -289.211346) (xy 100.054521 -289.239302)
			(xy 100.090014 -289.273394) (xy 100.119579 -289.312738) (xy 100.14245 -289.356315) (xy 100.158034 -289.402996)
			(xy 100.165929 -289.451573) (xy 100.166424 -289.47618) (xy 100.484935 -289.47618) (xy 100.48903 -289.425452)
			(xy 100.501209 -289.376038) (xy 100.521157 -289.329218) (xy 100.548358 -289.286204) (xy 100.582106 -289.24811)
			(xy 100.621528 -289.215923) (xy 100.665602 -289.190477) (xy 100.713188 -289.17243) (xy 100.763052 -289.16225)
			(xy 100.813904 -289.160201) (xy 100.864425 -289.166335) (xy 100.913309 -289.180495) (xy 100.959288 -289.202312)
			(xy 101.001172 -289.231222) (xy 101.037876 -289.266477) (xy 101.068449 -289.307163) (xy 101.0921 -289.352226)
			(xy 101.108216 -289.4005) (xy 101.11638 -289.450734) (xy 101.116892 -289.47618) (xy 101.424735 -289.47618)
			(xy 101.42883 -289.425452) (xy 101.441009 -289.376038) (xy 101.460957 -289.329218) (xy 101.488158 -289.286204)
			(xy 101.521906 -289.24811) (xy 101.561328 -289.215923) (xy 101.605402 -289.190477) (xy 101.652988 -289.17243)
			(xy 101.702852 -289.16225) (xy 101.753704 -289.160201) (xy 101.804225 -289.166335) (xy 101.853109 -289.180495)
			(xy 101.899088 -289.202312) (xy 101.940972 -289.231222) (xy 101.977676 -289.266477) (xy 102.008249 -289.307163)
			(xy 102.0319 -289.352226) (xy 102.048016 -289.4005) (xy 102.05618 -289.450734) (xy 102.056692 -289.47618)
			(xy 102.05618 -289.501626) (xy 102.048016 -289.55186) (xy 102.0319 -289.600134) (xy 102.008249 -289.645197)
			(xy 101.977676 -289.685883) (xy 101.940972 -289.721138) (xy 101.899088 -289.750048) (xy 101.853109 -289.771865)
			(xy 101.804225 -289.786025) (xy 101.753704 -289.792159) (xy 101.702852 -289.79011) (xy 101.652988 -289.77993)
			(xy 101.605402 -289.761883) (xy 101.561328 -289.736437) (xy 101.521906 -289.70425) (xy 101.488158 -289.666156)
			(xy 101.460957 -289.623142) (xy 101.441009 -289.576322) (xy 101.42883 -289.526908) (xy 101.424735 -289.47618)
			(xy 101.116892 -289.47618) (xy 101.11638 -289.501626) (xy 101.108216 -289.55186) (xy 101.0921 -289.600134)
			(xy 101.068449 -289.645197) (xy 101.037876 -289.685883) (xy 101.001172 -289.721138) (xy 100.959288 -289.750048)
			(xy 100.913309 -289.771865) (xy 100.864425 -289.786025) (xy 100.813904 -289.792159) (xy 100.763052 -289.79011)
			(xy 100.713188 -289.77993) (xy 100.665602 -289.761883) (xy 100.621528 -289.736437) (xy 100.582106 -289.70425)
			(xy 100.548358 -289.666156) (xy 100.521157 -289.623142) (xy 100.501209 -289.576322) (xy 100.48903 -289.526908)
			(xy 100.484935 -289.47618) (xy 100.166424 -289.47618) (xy 100.165929 -289.500787) (xy 100.158034 -289.549364)
			(xy 100.14245 -289.596045) (xy 100.119579 -289.639622) (xy 100.090014 -289.678966) (xy 100.054521 -289.713058)
			(xy 100.014018 -289.741014) (xy 99.969556 -289.762112) (xy 99.922285 -289.775804) (xy 99.87343 -289.781736)
			(xy 99.824255 -289.779755) (xy 99.776036 -289.769911) (xy 99.73002 -289.752459) (xy 99.687399 -289.727852)
			(xy 99.649278 -289.696727) (xy 99.616643 -289.65989) (xy 99.59034 -289.618294) (xy 99.571049 -289.573018)
			(xy 99.559272 -289.525234) (xy 99.555312 -289.47618) (xy 99.236784 -289.47618) (xy 99.236272 -289.501626)
			(xy 99.228108 -289.55186) (xy 99.211992 -289.600134) (xy 99.188341 -289.645197) (xy 99.157768 -289.685883)
			(xy 99.121064 -289.721138) (xy 99.07918 -289.750048) (xy 99.033201 -289.771865) (xy 98.984317 -289.786025)
			(xy 98.933796 -289.792159) (xy 98.882944 -289.79011) (xy 98.83308 -289.77993) (xy 98.785494 -289.761883)
			(xy 98.74142 -289.736437) (xy 98.701998 -289.70425) (xy 98.66825 -289.666156) (xy 98.641049 -289.623142)
			(xy 98.621101 -289.576322) (xy 98.608922 -289.526908) (xy 98.604827 -289.47618) (xy 98.29673 -289.47618)
			(xy 98.296218 -289.501626) (xy 98.288054 -289.55186) (xy 98.271938 -289.600134) (xy 98.248287 -289.645197)
			(xy 98.217714 -289.685883) (xy 98.18101 -289.721138) (xy 98.139126 -289.750048) (xy 98.093147 -289.771865)
			(xy 98.044263 -289.786025) (xy 97.993742 -289.792159) (xy 97.94289 -289.79011) (xy 97.893026 -289.77993)
			(xy 97.84544 -289.761883) (xy 97.801366 -289.736437) (xy 97.761944 -289.70425) (xy 97.728196 -289.666156)
			(xy 97.700995 -289.623142) (xy 97.681047 -289.576322) (xy 97.668868 -289.526908) (xy 97.664773 -289.47618)
			(xy 97.346262 -289.47618) (xy 97.345767 -289.500787) (xy 97.337872 -289.549364) (xy 97.322288 -289.596045)
			(xy 97.299417 -289.639622) (xy 97.269852 -289.678966) (xy 97.234359 -289.713058) (xy 97.193856 -289.741014)
			(xy 97.149394 -289.762112) (xy 97.102123 -289.775804) (xy 97.053268 -289.781736) (xy 97.004093 -289.779755)
			(xy 96.955874 -289.769911) (xy 96.909858 -289.752459) (xy 96.867237 -289.727852) (xy 96.829116 -289.696727)
			(xy 96.796481 -289.65989) (xy 96.770178 -289.618294) (xy 96.750887 -289.573018) (xy 96.73911 -289.525234)
			(xy 96.73515 -289.47618) (xy 96.416876 -289.47618) (xy 96.416364 -289.501626) (xy 96.4082 -289.55186)
			(xy 96.392084 -289.600134) (xy 96.368433 -289.645197) (xy 96.33786 -289.685883) (xy 96.301156 -289.721138)
			(xy 96.259272 -289.750048) (xy 96.213293 -289.771865) (xy 96.164409 -289.786025) (xy 96.113888 -289.792159)
			(xy 96.063036 -289.79011) (xy 96.013172 -289.77993) (xy 95.965586 -289.761883) (xy 95.921512 -289.736437)
			(xy 95.88209 -289.70425) (xy 95.848342 -289.666156) (xy 95.821141 -289.623142) (xy 95.801193 -289.576322)
			(xy 95.789014 -289.526908) (xy 95.784919 -289.47618) (xy 95.466408 -289.47618) (xy 95.465913 -289.500787)
			(xy 95.458018 -289.549364) (xy 95.442434 -289.596045) (xy 95.419563 -289.639622) (xy 95.389998 -289.678966)
			(xy 95.354505 -289.713058) (xy 95.314002 -289.741014) (xy 95.26954 -289.762112) (xy 95.222269 -289.775804)
			(xy 95.173414 -289.781736) (xy 95.124239 -289.779755) (xy 95.07602 -289.769911) (xy 95.030004 -289.752459)
			(xy 94.987383 -289.727852) (xy 94.949262 -289.696727) (xy 94.916627 -289.65989) (xy 94.890324 -289.618294)
			(xy 94.871033 -289.573018) (xy 94.859256 -289.525234) (xy 94.855296 -289.47618) (xy 94.536768 -289.47618)
			(xy 94.536256 -289.501626) (xy 94.528092 -289.55186) (xy 94.511976 -289.600134) (xy 94.488325 -289.645197)
			(xy 94.457752 -289.685883) (xy 94.421048 -289.721138) (xy 94.379164 -289.750048) (xy 94.333185 -289.771865)
			(xy 94.284301 -289.786025) (xy 94.23378 -289.792159) (xy 94.182928 -289.79011) (xy 94.133064 -289.77993)
			(xy 94.085478 -289.761883) (xy 94.041404 -289.736437) (xy 94.001982 -289.70425) (xy 93.968234 -289.666156)
			(xy 93.941033 -289.623142) (xy 93.921085 -289.576322) (xy 93.908906 -289.526908) (xy 93.904811 -289.47618)
			(xy 93.5863 -289.47618) (xy 93.585805 -289.500787) (xy 93.57791 -289.549364) (xy 93.562326 -289.596045)
			(xy 93.539455 -289.639622) (xy 93.50989 -289.678966) (xy 93.474397 -289.713058) (xy 93.433894 -289.741014)
			(xy 93.389432 -289.762112) (xy 93.342161 -289.775804) (xy 93.293306 -289.781736) (xy 93.244131 -289.779755)
			(xy 93.195912 -289.769911) (xy 93.149896 -289.752459) (xy 93.107275 -289.727852) (xy 93.069154 -289.696727)
			(xy 93.036519 -289.65989) (xy 93.010216 -289.618294) (xy 92.990925 -289.573018) (xy 92.979148 -289.525234)
			(xy 92.975188 -289.47618) (xy 92.65666 -289.47618) (xy 92.656148 -289.501626) (xy 92.647984 -289.55186)
			(xy 92.631868 -289.600134) (xy 92.608217 -289.645197) (xy 92.577644 -289.685883) (xy 92.54094 -289.721138)
			(xy 92.499056 -289.750048) (xy 92.453077 -289.771865) (xy 92.404193 -289.786025) (xy 92.353672 -289.792159)
			(xy 92.30282 -289.79011) (xy 92.252956 -289.77993) (xy 92.20537 -289.761883) (xy 92.161296 -289.736437)
			(xy 92.121874 -289.70425) (xy 92.088126 -289.666156) (xy 92.060925 -289.623142) (xy 92.040977 -289.576322)
			(xy 92.028798 -289.526908) (xy 92.024703 -289.47618) (xy 91.71686 -289.47618) (xy 91.716348 -289.501626)
			(xy 91.708184 -289.55186) (xy 91.692068 -289.600134) (xy 91.668417 -289.645197) (xy 91.637844 -289.685883)
			(xy 91.60114 -289.721138) (xy 91.559256 -289.750048) (xy 91.513277 -289.771865) (xy 91.464393 -289.786025)
			(xy 91.413872 -289.792159) (xy 91.36302 -289.79011) (xy 91.313156 -289.77993) (xy 91.26557 -289.761883)
			(xy 91.221496 -289.736437) (xy 91.182074 -289.70425) (xy 91.148326 -289.666156) (xy 91.121125 -289.623142)
			(xy 91.101177 -289.576322) (xy 91.088998 -289.526908) (xy 91.084903 -289.47618) (xy 90.766392 -289.47618)
			(xy 90.765897 -289.500787) (xy 90.758002 -289.549364) (xy 90.742418 -289.596045) (xy 90.719547 -289.639622)
			(xy 90.689982 -289.678966) (xy 90.654489 -289.713058) (xy 90.613986 -289.741014) (xy 90.569524 -289.762112)
			(xy 90.522253 -289.775804) (xy 90.473398 -289.781736) (xy 90.424223 -289.779755) (xy 90.376004 -289.769911)
			(xy 90.329988 -289.752459) (xy 90.287367 -289.727852) (xy 90.249246 -289.696727) (xy 90.216611 -289.65989)
			(xy 90.190308 -289.618294) (xy 90.171017 -289.573018) (xy 90.15924 -289.525234) (xy 90.15528 -289.47618)
			(xy 89.836752 -289.47618) (xy 89.83624 -289.501626) (xy 89.828076 -289.55186) (xy 89.81196 -289.600134)
			(xy 89.788309 -289.645197) (xy 89.757736 -289.685883) (xy 89.721032 -289.721138) (xy 89.679148 -289.750048)
			(xy 89.633169 -289.771865) (xy 89.584285 -289.786025) (xy 89.533764 -289.792159) (xy 89.482912 -289.79011)
			(xy 89.433048 -289.77993) (xy 89.385462 -289.761883) (xy 89.341388 -289.736437) (xy 89.301966 -289.70425)
			(xy 89.268218 -289.666156) (xy 89.241017 -289.623142) (xy 89.221069 -289.576322) (xy 89.20889 -289.526908)
			(xy 89.204795 -289.47618) (xy 88.886284 -289.47618) (xy 88.885789 -289.500787) (xy 88.877894 -289.549364)
			(xy 88.86231 -289.596045) (xy 88.839439 -289.639622) (xy 88.809874 -289.678966) (xy 88.774381 -289.713058)
			(xy 88.733878 -289.741014) (xy 88.689416 -289.762112) (xy 88.642145 -289.775804) (xy 88.59329 -289.781736)
			(xy 88.544115 -289.779755) (xy 88.495896 -289.769911) (xy 88.44988 -289.752459) (xy 88.407259 -289.727852)
			(xy 88.369138 -289.696727) (xy 88.336503 -289.65989) (xy 88.3102 -289.618294) (xy 88.290909 -289.573018)
			(xy 88.279132 -289.525234) (xy 88.275172 -289.47618) (xy 87.956644 -289.47618) (xy 87.956132 -289.501626)
			(xy 87.947968 -289.55186) (xy 87.931852 -289.600134) (xy 87.908201 -289.645197) (xy 87.877628 -289.685883)
			(xy 87.840924 -289.721138) (xy 87.79904 -289.750048) (xy 87.753061 -289.771865) (xy 87.704177 -289.786025)
			(xy 87.653656 -289.792159) (xy 87.602804 -289.79011) (xy 87.55294 -289.77993) (xy 87.505354 -289.761883)
			(xy 87.46128 -289.736437) (xy 87.421858 -289.70425) (xy 87.38811 -289.666156) (xy 87.360909 -289.623142)
			(xy 87.340961 -289.576322) (xy 87.328782 -289.526908) (xy 87.324687 -289.47618) (xy 87.00643 -289.47618)
			(xy 87.005935 -289.500787) (xy 86.99804 -289.549364) (xy 86.982456 -289.596045) (xy 86.959585 -289.639622)
			(xy 86.93002 -289.678966) (xy 86.894527 -289.713058) (xy 86.854024 -289.741014) (xy 86.809562 -289.762112)
			(xy 86.762291 -289.775804) (xy 86.713436 -289.781736) (xy 86.664261 -289.779755) (xy 86.616042 -289.769911)
			(xy 86.570026 -289.752459) (xy 86.527405 -289.727852) (xy 86.489284 -289.696727) (xy 86.456649 -289.65989)
			(xy 86.430346 -289.618294) (xy 86.411055 -289.573018) (xy 86.399278 -289.525234) (xy 86.395318 -289.47618)
			(xy 86.07679 -289.47618) (xy 86.076278 -289.501626) (xy 86.068114 -289.55186) (xy 86.051998 -289.600134)
			(xy 86.028347 -289.645197) (xy 85.997774 -289.685883) (xy 85.96107 -289.721138) (xy 85.919186 -289.750048)
			(xy 85.873207 -289.771865) (xy 85.824323 -289.786025) (xy 85.773802 -289.792159) (xy 85.72295 -289.79011)
			(xy 85.673086 -289.77993) (xy 85.6255 -289.761883) (xy 85.581426 -289.736437) (xy 85.542004 -289.70425)
			(xy 85.508256 -289.666156) (xy 85.481055 -289.623142) (xy 85.461107 -289.576322) (xy 85.448928 -289.526908)
			(xy 85.444833 -289.47618) (xy 85.136736 -289.47618) (xy 85.136224 -289.501626) (xy 85.12806 -289.55186)
			(xy 85.111944 -289.600134) (xy 85.088293 -289.645197) (xy 85.05772 -289.685883) (xy 85.021016 -289.721138)
			(xy 84.979132 -289.750048) (xy 84.933153 -289.771865) (xy 84.884269 -289.786025) (xy 84.833748 -289.792159)
			(xy 84.782896 -289.79011) (xy 84.733032 -289.77993) (xy 84.685446 -289.761883) (xy 84.641372 -289.736437)
			(xy 84.60195 -289.70425) (xy 84.568202 -289.666156) (xy 84.541001 -289.623142) (xy 84.521053 -289.576322)
			(xy 84.508874 -289.526908) (xy 84.504779 -289.47618) (xy 84.186268 -289.47618) (xy 84.185773 -289.500787)
			(xy 84.177878 -289.549364) (xy 84.162294 -289.596045) (xy 84.139423 -289.639622) (xy 84.109858 -289.678966)
			(xy 84.074365 -289.713058) (xy 84.033862 -289.741014) (xy 83.9894 -289.762112) (xy 83.942129 -289.775804)
			(xy 83.893274 -289.781736) (xy 83.844099 -289.779755) (xy 83.79588 -289.769911) (xy 83.749864 -289.752459)
			(xy 83.707243 -289.727852) (xy 83.669122 -289.696727) (xy 83.636487 -289.65989) (xy 83.610184 -289.618294)
			(xy 83.590893 -289.573018) (xy 83.579116 -289.525234) (xy 83.575156 -289.47618) (xy 83.256628 -289.47618)
			(xy 83.256116 -289.501626) (xy 83.247952 -289.55186) (xy 83.231836 -289.600134) (xy 83.208185 -289.645197)
			(xy 83.177612 -289.685883) (xy 83.140908 -289.721138) (xy 83.099024 -289.750048) (xy 83.053045 -289.771865)
			(xy 83.004161 -289.786025) (xy 82.95364 -289.792159) (xy 82.902788 -289.79011) (xy 82.852924 -289.77993)
			(xy 82.805338 -289.761883) (xy 82.761264 -289.736437) (xy 82.721842 -289.70425) (xy 82.688094 -289.666156)
			(xy 82.660893 -289.623142) (xy 82.640945 -289.576322) (xy 82.628766 -289.526908) (xy 82.624671 -289.47618)
			(xy 82.306414 -289.47618) (xy 82.305919 -289.500787) (xy 82.298024 -289.549364) (xy 82.28244 -289.596045)
			(xy 82.259569 -289.639622) (xy 82.230004 -289.678966) (xy 82.194511 -289.713058) (xy 82.154008 -289.741014)
			(xy 82.109546 -289.762112) (xy 82.062275 -289.775804) (xy 82.01342 -289.781736) (xy 81.964245 -289.779755)
			(xy 81.916026 -289.769911) (xy 81.87001 -289.752459) (xy 81.827389 -289.727852) (xy 81.789268 -289.696727)
			(xy 81.756633 -289.65989) (xy 81.73033 -289.618294) (xy 81.711039 -289.573018) (xy 81.699262 -289.525234)
			(xy 81.695302 -289.47618) (xy 81.376774 -289.47618) (xy 81.376262 -289.501626) (xy 81.368098 -289.55186)
			(xy 81.351982 -289.600134) (xy 81.328331 -289.645197) (xy 81.297758 -289.685883) (xy 81.261054 -289.721138)
			(xy 81.21917 -289.750048) (xy 81.173191 -289.771865) (xy 81.124307 -289.786025) (xy 81.073786 -289.792159)
			(xy 81.022934 -289.79011) (xy 80.97307 -289.77993) (xy 80.925484 -289.761883) (xy 80.88141 -289.736437)
			(xy 80.841988 -289.70425) (xy 80.80824 -289.666156) (xy 80.781039 -289.623142) (xy 80.761091 -289.576322)
			(xy 80.748912 -289.526908) (xy 80.744817 -289.47618) (xy 80.426306 -289.47618) (xy 80.425811 -289.500787)
			(xy 80.417916 -289.549364) (xy 80.402332 -289.596045) (xy 80.379461 -289.639622) (xy 80.349896 -289.678966)
			(xy 80.314403 -289.713058) (xy 80.2739 -289.741014) (xy 80.229438 -289.762112) (xy 80.182167 -289.775804)
			(xy 80.133312 -289.781736) (xy 80.084137 -289.779755) (xy 80.035918 -289.769911) (xy 79.989902 -289.752459)
			(xy 79.947281 -289.727852) (xy 79.90916 -289.696727) (xy 79.876525 -289.65989) (xy 79.850222 -289.618294)
			(xy 79.830931 -289.573018) (xy 79.819154 -289.525234) (xy 79.815194 -289.47618) (xy 77.263451 -289.47618)
			(xy 77.221316 -289.496174) (xy 77.174045 -289.509866) (xy 77.12519 -289.515798) (xy 77.076015 -289.513817)
			(xy 77.027796 -289.503973) (xy 76.98178 -289.486521) (xy 76.939159 -289.461914) (xy 76.901038 -289.430789)
			(xy 76.868403 -289.393952) (xy 76.8421 -289.352356) (xy 76.822809 -289.30708) (xy 76.811032 -289.259296)
			(xy 76.807072 -289.210242) (xy 73.228962 -289.210242) (xy 73.228962 -290.286186) (xy 78.40524 -290.286186)
			(xy 78.4092 -290.237132) (xy 78.420977 -290.189348) (xy 78.440268 -290.144072) (xy 78.466571 -290.102476)
			(xy 78.499206 -290.065639) (xy 78.537327 -290.034514) (xy 78.579948 -290.009907) (xy 78.625964 -289.992455)
			(xy 78.674183 -289.982611) (xy 78.723358 -289.98063) (xy 78.772213 -289.986562) (xy 78.819484 -290.000254)
			(xy 78.863946 -290.021352) (xy 78.904449 -290.049308) (xy 78.939942 -290.0834) (xy 78.969507 -290.122744)
			(xy 78.992378 -290.166321) (xy 79.007962 -290.213002) (xy 79.015857 -290.261579) (xy 79.016352 -290.286186)
			(xy 80.285348 -290.286186) (xy 80.289308 -290.237132) (xy 80.301085 -290.189348) (xy 80.320376 -290.144072)
			(xy 80.346679 -290.102476) (xy 80.379314 -290.065639) (xy 80.417435 -290.034514) (xy 80.460056 -290.009907)
			(xy 80.506072 -289.992455) (xy 80.554291 -289.982611) (xy 80.603466 -289.98063) (xy 80.652321 -289.986562)
			(xy 80.699592 -290.000254) (xy 80.744054 -290.021352) (xy 80.784557 -290.049308) (xy 80.82005 -290.0834)
			(xy 80.849615 -290.122744) (xy 80.872486 -290.166321) (xy 80.88807 -290.213002) (xy 80.895965 -290.261579)
			(xy 80.89646 -290.286186) (xy 81.214717 -290.286186) (xy 81.218812 -290.235458) (xy 81.230991 -290.186044)
			(xy 81.250939 -290.139224) (xy 81.27814 -290.09621) (xy 81.311888 -290.058116) (xy 81.35131 -290.025929)
			(xy 81.395384 -290.000483) (xy 81.44297 -289.982436) (xy 81.492834 -289.972256) (xy 81.543686 -289.970207)
			(xy 81.594207 -289.976341) (xy 81.643091 -289.990501) (xy 81.68907 -290.012318) (xy 81.730954 -290.041228)
			(xy 81.767658 -290.076483) (xy 81.798231 -290.117169) (xy 81.821882 -290.162232) (xy 81.837998 -290.210506)
			(xy 81.846162 -290.26074) (xy 81.846674 -290.286186) (xy 82.154771 -290.286186) (xy 82.158866 -290.235458)
			(xy 82.171045 -290.186044) (xy 82.190993 -290.139224) (xy 82.218194 -290.09621) (xy 82.251942 -290.058116)
			(xy 82.291364 -290.025929) (xy 82.335438 -290.000483) (xy 82.383024 -289.982436) (xy 82.432888 -289.972256)
			(xy 82.48374 -289.970207) (xy 82.534261 -289.976341) (xy 82.583145 -289.990501) (xy 82.629124 -290.012318)
			(xy 82.671008 -290.041228) (xy 82.707712 -290.076483) (xy 82.738285 -290.117169) (xy 82.761936 -290.162232)
			(xy 82.778052 -290.210506) (xy 82.786216 -290.26074) (xy 82.786728 -290.286186) (xy 83.105256 -290.286186)
			(xy 83.109216 -290.237132) (xy 83.120993 -290.189348) (xy 83.140284 -290.144072) (xy 83.166587 -290.102476)
			(xy 83.199222 -290.065639) (xy 83.237343 -290.034514) (xy 83.279964 -290.009907) (xy 83.32598 -289.992455)
			(xy 83.374199 -289.982611) (xy 83.423374 -289.98063) (xy 83.472229 -289.986562) (xy 83.5195 -290.000254)
			(xy 83.563962 -290.021352) (xy 83.604465 -290.049308) (xy 83.639958 -290.0834) (xy 83.669523 -290.122744)
			(xy 83.692394 -290.166321) (xy 83.707978 -290.213002) (xy 83.715873 -290.261579) (xy 83.716368 -290.286186)
			(xy 84.034879 -290.286186) (xy 84.038974 -290.235458) (xy 84.051153 -290.186044) (xy 84.071101 -290.139224)
			(xy 84.098302 -290.09621) (xy 84.13205 -290.058116) (xy 84.171472 -290.025929) (xy 84.215546 -290.000483)
			(xy 84.263132 -289.982436) (xy 84.312996 -289.972256) (xy 84.363848 -289.970207) (xy 84.414369 -289.976341)
			(xy 84.463253 -289.990501) (xy 84.509232 -290.012318) (xy 84.551116 -290.041228) (xy 84.58782 -290.076483)
			(xy 84.618393 -290.117169) (xy 84.642044 -290.162232) (xy 84.65816 -290.210506) (xy 84.666324 -290.26074)
			(xy 84.666836 -290.286186) (xy 84.98511 -290.286186) (xy 84.98907 -290.237132) (xy 85.000847 -290.189348)
			(xy 85.020138 -290.144072) (xy 85.046441 -290.102476) (xy 85.079076 -290.065639) (xy 85.117197 -290.034514)
			(xy 85.159818 -290.009907) (xy 85.205834 -289.992455) (xy 85.254053 -289.982611) (xy 85.303228 -289.98063)
			(xy 85.352083 -289.986562) (xy 85.399354 -290.000254) (xy 85.443816 -290.021352) (xy 85.484319 -290.049308)
			(xy 85.519812 -290.0834) (xy 85.549377 -290.122744) (xy 85.572248 -290.166321) (xy 85.587832 -290.213002)
			(xy 85.595727 -290.261579) (xy 85.596222 -290.286186) (xy 85.914733 -290.286186) (xy 85.918828 -290.235458)
			(xy 85.931007 -290.186044) (xy 85.950955 -290.139224) (xy 85.978156 -290.09621) (xy 86.011904 -290.058116)
			(xy 86.051326 -290.025929) (xy 86.0954 -290.000483) (xy 86.142986 -289.982436) (xy 86.19285 -289.972256)
			(xy 86.243702 -289.970207) (xy 86.294223 -289.976341) (xy 86.343107 -289.990501) (xy 86.389086 -290.012318)
			(xy 86.43097 -290.041228) (xy 86.467674 -290.076483) (xy 86.498247 -290.117169) (xy 86.521898 -290.162232)
			(xy 86.538014 -290.210506) (xy 86.546178 -290.26074) (xy 86.54669 -290.286186) (xy 86.865218 -290.286186)
			(xy 86.869178 -290.237132) (xy 86.880955 -290.189348) (xy 86.900246 -290.144072) (xy 86.926549 -290.102476)
			(xy 86.959184 -290.065639) (xy 86.997305 -290.034514) (xy 87.039926 -290.009907) (xy 87.085942 -289.992455)
			(xy 87.134161 -289.982611) (xy 87.183336 -289.98063) (xy 87.232191 -289.986562) (xy 87.279462 -290.000254)
			(xy 87.323924 -290.021352) (xy 87.364427 -290.049308) (xy 87.39992 -290.0834) (xy 87.429485 -290.122744)
			(xy 87.452356 -290.166321) (xy 87.46794 -290.213002) (xy 87.475835 -290.261579) (xy 87.47633 -290.286186)
			(xy 87.794841 -290.286186) (xy 87.798936 -290.235458) (xy 87.811115 -290.186044) (xy 87.831063 -290.139224)
			(xy 87.858264 -290.09621) (xy 87.892012 -290.058116) (xy 87.931434 -290.025929) (xy 87.975508 -290.000483)
			(xy 88.023094 -289.982436) (xy 88.072958 -289.972256) (xy 88.12381 -289.970207) (xy 88.174331 -289.976341)
			(xy 88.223215 -289.990501) (xy 88.269194 -290.012318) (xy 88.311078 -290.041228) (xy 88.347782 -290.076483)
			(xy 88.378355 -290.117169) (xy 88.402006 -290.162232) (xy 88.418122 -290.210506) (xy 88.426286 -290.26074)
			(xy 88.426798 -290.286186) (xy 88.734895 -290.286186) (xy 88.73899 -290.235458) (xy 88.751169 -290.186044)
			(xy 88.771117 -290.139224) (xy 88.798318 -290.09621) (xy 88.832066 -290.058116) (xy 88.871488 -290.025929)
			(xy 88.915562 -290.000483) (xy 88.963148 -289.982436) (xy 89.013012 -289.972256) (xy 89.063864 -289.970207)
			(xy 89.114385 -289.976341) (xy 89.163269 -289.990501) (xy 89.209248 -290.012318) (xy 89.251132 -290.041228)
			(xy 89.287836 -290.076483) (xy 89.318409 -290.117169) (xy 89.34206 -290.162232) (xy 89.358176 -290.210506)
			(xy 89.36634 -290.26074) (xy 89.366852 -290.286186) (xy 89.685126 -290.286186) (xy 89.689086 -290.237132)
			(xy 89.700863 -290.189348) (xy 89.720154 -290.144072) (xy 89.746457 -290.102476) (xy 89.779092 -290.065639)
			(xy 89.817213 -290.034514) (xy 89.859834 -290.009907) (xy 89.90585 -289.992455) (xy 89.954069 -289.982611)
			(xy 90.003244 -289.98063) (xy 90.052099 -289.986562) (xy 90.09937 -290.000254) (xy 90.143832 -290.021352)
			(xy 90.184335 -290.049308) (xy 90.219828 -290.0834) (xy 90.249393 -290.122744) (xy 90.272264 -290.166321)
			(xy 90.287848 -290.213002) (xy 90.295743 -290.261579) (xy 90.296238 -290.286186) (xy 90.614749 -290.286186)
			(xy 90.618844 -290.235458) (xy 90.631023 -290.186044) (xy 90.650971 -290.139224) (xy 90.678172 -290.09621)
			(xy 90.71192 -290.058116) (xy 90.751342 -290.025929) (xy 90.795416 -290.000483) (xy 90.843002 -289.982436)
			(xy 90.892866 -289.972256) (xy 90.943718 -289.970207) (xy 90.994239 -289.976341) (xy 91.043123 -289.990501)
			(xy 91.089102 -290.012318) (xy 91.130986 -290.041228) (xy 91.16769 -290.076483) (xy 91.198263 -290.117169)
			(xy 91.221914 -290.162232) (xy 91.23803 -290.210506) (xy 91.246194 -290.26074) (xy 91.246706 -290.286186)
			(xy 91.565234 -290.286186) (xy 91.569194 -290.237132) (xy 91.580971 -290.189348) (xy 91.600262 -290.144072)
			(xy 91.626565 -290.102476) (xy 91.6592 -290.065639) (xy 91.697321 -290.034514) (xy 91.739942 -290.009907)
			(xy 91.785958 -289.992455) (xy 91.834177 -289.982611) (xy 91.883352 -289.98063) (xy 91.932207 -289.986562)
			(xy 91.979478 -290.000254) (xy 92.02394 -290.021352) (xy 92.064443 -290.049308) (xy 92.099936 -290.0834)
			(xy 92.129501 -290.122744) (xy 92.152372 -290.166321) (xy 92.167956 -290.213002) (xy 92.175851 -290.261579)
			(xy 92.176346 -290.286186) (xy 92.494857 -290.286186) (xy 92.498952 -290.235458) (xy 92.511131 -290.186044)
			(xy 92.531079 -290.139224) (xy 92.55828 -290.09621) (xy 92.592028 -290.058116) (xy 92.63145 -290.025929)
			(xy 92.675524 -290.000483) (xy 92.72311 -289.982436) (xy 92.772974 -289.972256) (xy 92.823826 -289.970207)
			(xy 92.874347 -289.976341) (xy 92.923231 -289.990501) (xy 92.96921 -290.012318) (xy 93.011094 -290.041228)
			(xy 93.047798 -290.076483) (xy 93.078371 -290.117169) (xy 93.102022 -290.162232) (xy 93.118138 -290.210506)
			(xy 93.126302 -290.26074) (xy 93.126814 -290.286186) (xy 93.445342 -290.286186) (xy 93.449302 -290.237132)
			(xy 93.461079 -290.189348) (xy 93.48037 -290.144072) (xy 93.506673 -290.102476) (xy 93.539308 -290.065639)
			(xy 93.577429 -290.034514) (xy 93.62005 -290.009907) (xy 93.666066 -289.992455) (xy 93.714285 -289.982611)
			(xy 93.76346 -289.98063) (xy 93.812315 -289.986562) (xy 93.859586 -290.000254) (xy 93.904048 -290.021352)
			(xy 93.944551 -290.049308) (xy 93.980044 -290.0834) (xy 94.009609 -290.122744) (xy 94.03248 -290.166321)
			(xy 94.048064 -290.213002) (xy 94.055959 -290.261579) (xy 94.056454 -290.286186) (xy 94.374711 -290.286186)
			(xy 94.378806 -290.235458) (xy 94.390985 -290.186044) (xy 94.410933 -290.139224) (xy 94.438134 -290.09621)
			(xy 94.471882 -290.058116) (xy 94.511304 -290.025929) (xy 94.555378 -290.000483) (xy 94.602964 -289.982436)
			(xy 94.652828 -289.972256) (xy 94.70368 -289.970207) (xy 94.754201 -289.976341) (xy 94.803085 -289.990501)
			(xy 94.849064 -290.012318) (xy 94.890948 -290.041228) (xy 94.927652 -290.076483) (xy 94.958225 -290.117169)
			(xy 94.981876 -290.162232) (xy 94.997992 -290.210506) (xy 95.006156 -290.26074) (xy 95.006668 -290.286186)
			(xy 95.314765 -290.286186) (xy 95.31886 -290.235458) (xy 95.331039 -290.186044) (xy 95.350987 -290.139224)
			(xy 95.378188 -290.09621) (xy 95.411936 -290.058116) (xy 95.451358 -290.025929) (xy 95.495432 -290.000483)
			(xy 95.543018 -289.982436) (xy 95.592882 -289.972256) (xy 95.643734 -289.970207) (xy 95.694255 -289.976341)
			(xy 95.743139 -289.990501) (xy 95.789118 -290.012318) (xy 95.831002 -290.041228) (xy 95.867706 -290.076483)
			(xy 95.898279 -290.117169) (xy 95.92193 -290.162232) (xy 95.938046 -290.210506) (xy 95.94621 -290.26074)
			(xy 95.946722 -290.286186) (xy 96.26525 -290.286186) (xy 96.26921 -290.237132) (xy 96.280987 -290.189348)
			(xy 96.300278 -290.144072) (xy 96.326581 -290.102476) (xy 96.359216 -290.065639) (xy 96.397337 -290.034514)
			(xy 96.439958 -290.009907) (xy 96.485974 -289.992455) (xy 96.534193 -289.982611) (xy 96.583368 -289.98063)
			(xy 96.632223 -289.986562) (xy 96.679494 -290.000254) (xy 96.723956 -290.021352) (xy 96.764459 -290.049308)
			(xy 96.799952 -290.0834) (xy 96.829517 -290.122744) (xy 96.852388 -290.166321) (xy 96.867972 -290.213002)
			(xy 96.875867 -290.261579) (xy 96.876362 -290.286186) (xy 99.085158 -290.286186) (xy 99.089118 -290.237132)
			(xy 99.100895 -290.189348) (xy 99.120186 -290.144072) (xy 99.146489 -290.102476) (xy 99.179124 -290.065639)
			(xy 99.217245 -290.034514) (xy 99.259866 -290.009907) (xy 99.305882 -289.992455) (xy 99.354101 -289.982611)
			(xy 99.403276 -289.98063) (xy 99.452131 -289.986562) (xy 99.499402 -290.000254) (xy 99.543864 -290.021352)
			(xy 99.584367 -290.049308) (xy 99.61986 -290.0834) (xy 99.649425 -290.122744) (xy 99.672296 -290.166321)
			(xy 99.68788 -290.213002) (xy 99.695775 -290.261579) (xy 99.69627 -290.286186) (xy 101.90532 -290.286186)
			(xy 101.90928 -290.237132) (xy 101.921057 -290.189348) (xy 101.940348 -290.144072) (xy 101.966651 -290.102476)
			(xy 101.999286 -290.065639) (xy 102.037407 -290.034514) (xy 102.080028 -290.009907) (xy 102.126044 -289.992455)
			(xy 102.174263 -289.982611) (xy 102.223438 -289.98063) (xy 102.272293 -289.986562) (xy 102.319564 -290.000254)
			(xy 102.364026 -290.021352) (xy 102.404529 -290.049308) (xy 102.440022 -290.0834) (xy 102.469587 -290.122744)
			(xy 102.492458 -290.166321) (xy 102.508042 -290.213002) (xy 102.515937 -290.261579) (xy 102.516432 -290.286186)
			(xy 102.515937 -290.310793) (xy 102.508042 -290.35937) (xy 102.492458 -290.406051) (xy 102.469587 -290.449628)
			(xy 102.440022 -290.488972) (xy 102.404529 -290.523064) (xy 102.364026 -290.55102) (xy 102.319564 -290.572118)
			(xy 102.272293 -290.58581) (xy 102.223438 -290.591742) (xy 102.174263 -290.589761) (xy 102.126044 -290.579917)
			(xy 102.080028 -290.562465) (xy 102.037407 -290.537858) (xy 101.999286 -290.506733) (xy 101.966651 -290.469896)
			(xy 101.940348 -290.4283) (xy 101.921057 -290.383024) (xy 101.90928 -290.33524) (xy 101.90532 -290.286186)
			(xy 99.69627 -290.286186) (xy 99.695775 -290.310793) (xy 99.68788 -290.35937) (xy 99.672296 -290.406051)
			(xy 99.649425 -290.449628) (xy 99.61986 -290.488972) (xy 99.584367 -290.523064) (xy 99.543864 -290.55102)
			(xy 99.499402 -290.572118) (xy 99.452131 -290.58581) (xy 99.403276 -290.591742) (xy 99.354101 -290.589761)
			(xy 99.305882 -290.579917) (xy 99.259866 -290.562465) (xy 99.217245 -290.537858) (xy 99.179124 -290.506733)
			(xy 99.146489 -290.469896) (xy 99.120186 -290.4283) (xy 99.100895 -290.383024) (xy 99.089118 -290.33524)
			(xy 99.085158 -290.286186) (xy 96.876362 -290.286186) (xy 96.875867 -290.310793) (xy 96.867972 -290.35937)
			(xy 96.852388 -290.406051) (xy 96.829517 -290.449628) (xy 96.799952 -290.488972) (xy 96.764459 -290.523064)
			(xy 96.723956 -290.55102) (xy 96.679494 -290.572118) (xy 96.632223 -290.58581) (xy 96.583368 -290.591742)
			(xy 96.534193 -290.589761) (xy 96.485974 -290.579917) (xy 96.439958 -290.562465) (xy 96.397337 -290.537858)
			(xy 96.359216 -290.506733) (xy 96.326581 -290.469896) (xy 96.300278 -290.4283) (xy 96.280987 -290.383024)
			(xy 96.26921 -290.33524) (xy 96.26525 -290.286186) (xy 95.946722 -290.286186) (xy 95.94621 -290.311632)
			(xy 95.938046 -290.361866) (xy 95.92193 -290.41014) (xy 95.898279 -290.455203) (xy 95.867706 -290.495889)
			(xy 95.831002 -290.531144) (xy 95.789118 -290.560054) (xy 95.743139 -290.581871) (xy 95.694255 -290.596031)
			(xy 95.643734 -290.602165) (xy 95.592882 -290.600116) (xy 95.543018 -290.589936) (xy 95.495432 -290.571889)
			(xy 95.451358 -290.546443) (xy 95.411936 -290.514256) (xy 95.378188 -290.476162) (xy 95.350987 -290.433148)
			(xy 95.331039 -290.386328) (xy 95.31886 -290.336914) (xy 95.314765 -290.286186) (xy 95.006668 -290.286186)
			(xy 95.006156 -290.311632) (xy 94.997992 -290.361866) (xy 94.981876 -290.41014) (xy 94.958225 -290.455203)
			(xy 94.927652 -290.495889) (xy 94.890948 -290.531144) (xy 94.849064 -290.560054) (xy 94.803085 -290.581871)
			(xy 94.754201 -290.596031) (xy 94.70368 -290.602165) (xy 94.652828 -290.600116) (xy 94.602964 -290.589936)
			(xy 94.555378 -290.571889) (xy 94.511304 -290.546443) (xy 94.471882 -290.514256) (xy 94.438134 -290.476162)
			(xy 94.410933 -290.433148) (xy 94.390985 -290.386328) (xy 94.378806 -290.336914) (xy 94.374711 -290.286186)
			(xy 94.056454 -290.286186) (xy 94.055959 -290.310793) (xy 94.048064 -290.35937) (xy 94.03248 -290.406051)
			(xy 94.009609 -290.449628) (xy 93.980044 -290.488972) (xy 93.944551 -290.523064) (xy 93.904048 -290.55102)
			(xy 93.859586 -290.572118) (xy 93.812315 -290.58581) (xy 93.76346 -290.591742) (xy 93.714285 -290.589761)
			(xy 93.666066 -290.579917) (xy 93.62005 -290.562465) (xy 93.577429 -290.537858) (xy 93.539308 -290.506733)
			(xy 93.506673 -290.469896) (xy 93.48037 -290.4283) (xy 93.461079 -290.383024) (xy 93.449302 -290.33524)
			(xy 93.445342 -290.286186) (xy 93.126814 -290.286186) (xy 93.126302 -290.311632) (xy 93.118138 -290.361866)
			(xy 93.102022 -290.41014) (xy 93.078371 -290.455203) (xy 93.047798 -290.495889) (xy 93.011094 -290.531144)
			(xy 92.96921 -290.560054) (xy 92.923231 -290.581871) (xy 92.874347 -290.596031) (xy 92.823826 -290.602165)
			(xy 92.772974 -290.600116) (xy 92.72311 -290.589936) (xy 92.675524 -290.571889) (xy 92.63145 -290.546443)
			(xy 92.592028 -290.514256) (xy 92.55828 -290.476162) (xy 92.531079 -290.433148) (xy 92.511131 -290.386328)
			(xy 92.498952 -290.336914) (xy 92.494857 -290.286186) (xy 92.176346 -290.286186) (xy 92.175851 -290.310793)
			(xy 92.167956 -290.35937) (xy 92.152372 -290.406051) (xy 92.129501 -290.449628) (xy 92.099936 -290.488972)
			(xy 92.064443 -290.523064) (xy 92.02394 -290.55102) (xy 91.979478 -290.572118) (xy 91.932207 -290.58581)
			(xy 91.883352 -290.591742) (xy 91.834177 -290.589761) (xy 91.785958 -290.579917) (xy 91.739942 -290.562465)
			(xy 91.697321 -290.537858) (xy 91.6592 -290.506733) (xy 91.626565 -290.469896) (xy 91.600262 -290.4283)
			(xy 91.580971 -290.383024) (xy 91.569194 -290.33524) (xy 91.565234 -290.286186) (xy 91.246706 -290.286186)
			(xy 91.246194 -290.311632) (xy 91.23803 -290.361866) (xy 91.221914 -290.41014) (xy 91.198263 -290.455203)
			(xy 91.16769 -290.495889) (xy 91.130986 -290.531144) (xy 91.089102 -290.560054) (xy 91.043123 -290.581871)
			(xy 90.994239 -290.596031) (xy 90.943718 -290.602165) (xy 90.892866 -290.600116) (xy 90.843002 -290.589936)
			(xy 90.795416 -290.571889) (xy 90.751342 -290.546443) (xy 90.71192 -290.514256) (xy 90.678172 -290.476162)
			(xy 90.650971 -290.433148) (xy 90.631023 -290.386328) (xy 90.618844 -290.336914) (xy 90.614749 -290.286186)
			(xy 90.296238 -290.286186) (xy 90.295743 -290.310793) (xy 90.287848 -290.35937) (xy 90.272264 -290.406051)
			(xy 90.249393 -290.449628) (xy 90.219828 -290.488972) (xy 90.184335 -290.523064) (xy 90.143832 -290.55102)
			(xy 90.09937 -290.572118) (xy 90.052099 -290.58581) (xy 90.003244 -290.591742) (xy 89.954069 -290.589761)
			(xy 89.90585 -290.579917) (xy 89.859834 -290.562465) (xy 89.817213 -290.537858) (xy 89.779092 -290.506733)
			(xy 89.746457 -290.469896) (xy 89.720154 -290.4283) (xy 89.700863 -290.383024) (xy 89.689086 -290.33524)
			(xy 89.685126 -290.286186) (xy 89.366852 -290.286186) (xy 89.36634 -290.311632) (xy 89.358176 -290.361866)
			(xy 89.34206 -290.41014) (xy 89.318409 -290.455203) (xy 89.287836 -290.495889) (xy 89.251132 -290.531144)
			(xy 89.209248 -290.560054) (xy 89.163269 -290.581871) (xy 89.114385 -290.596031) (xy 89.063864 -290.602165)
			(xy 89.013012 -290.600116) (xy 88.963148 -290.589936) (xy 88.915562 -290.571889) (xy 88.871488 -290.546443)
			(xy 88.832066 -290.514256) (xy 88.798318 -290.476162) (xy 88.771117 -290.433148) (xy 88.751169 -290.386328)
			(xy 88.73899 -290.336914) (xy 88.734895 -290.286186) (xy 88.426798 -290.286186) (xy 88.426286 -290.311632)
			(xy 88.418122 -290.361866) (xy 88.402006 -290.41014) (xy 88.378355 -290.455203) (xy 88.347782 -290.495889)
			(xy 88.311078 -290.531144) (xy 88.269194 -290.560054) (xy 88.223215 -290.581871) (xy 88.174331 -290.596031)
			(xy 88.12381 -290.602165) (xy 88.072958 -290.600116) (xy 88.023094 -290.589936) (xy 87.975508 -290.571889)
			(xy 87.931434 -290.546443) (xy 87.892012 -290.514256) (xy 87.858264 -290.476162) (xy 87.831063 -290.433148)
			(xy 87.811115 -290.386328) (xy 87.798936 -290.336914) (xy 87.794841 -290.286186) (xy 87.47633 -290.286186)
			(xy 87.475835 -290.310793) (xy 87.46794 -290.35937) (xy 87.452356 -290.406051) (xy 87.429485 -290.449628)
			(xy 87.39992 -290.488972) (xy 87.364427 -290.523064) (xy 87.323924 -290.55102) (xy 87.279462 -290.572118)
			(xy 87.232191 -290.58581) (xy 87.183336 -290.591742) (xy 87.134161 -290.589761) (xy 87.085942 -290.579917)
			(xy 87.039926 -290.562465) (xy 86.997305 -290.537858) (xy 86.959184 -290.506733) (xy 86.926549 -290.469896)
			(xy 86.900246 -290.4283) (xy 86.880955 -290.383024) (xy 86.869178 -290.33524) (xy 86.865218 -290.286186)
			(xy 86.54669 -290.286186) (xy 86.546178 -290.311632) (xy 86.538014 -290.361866) (xy 86.521898 -290.41014)
			(xy 86.498247 -290.455203) (xy 86.467674 -290.495889) (xy 86.43097 -290.531144) (xy 86.389086 -290.560054)
			(xy 86.343107 -290.581871) (xy 86.294223 -290.596031) (xy 86.243702 -290.602165) (xy 86.19285 -290.600116)
			(xy 86.142986 -290.589936) (xy 86.0954 -290.571889) (xy 86.051326 -290.546443) (xy 86.011904 -290.514256)
			(xy 85.978156 -290.476162) (xy 85.950955 -290.433148) (xy 85.931007 -290.386328) (xy 85.918828 -290.336914)
			(xy 85.914733 -290.286186) (xy 85.596222 -290.286186) (xy 85.595727 -290.310793) (xy 85.587832 -290.35937)
			(xy 85.572248 -290.406051) (xy 85.549377 -290.449628) (xy 85.519812 -290.488972) (xy 85.484319 -290.523064)
			(xy 85.443816 -290.55102) (xy 85.399354 -290.572118) (xy 85.352083 -290.58581) (xy 85.303228 -290.591742)
			(xy 85.254053 -290.589761) (xy 85.205834 -290.579917) (xy 85.159818 -290.562465) (xy 85.117197 -290.537858)
			(xy 85.079076 -290.506733) (xy 85.046441 -290.469896) (xy 85.020138 -290.4283) (xy 85.000847 -290.383024)
			(xy 84.98907 -290.33524) (xy 84.98511 -290.286186) (xy 84.666836 -290.286186) (xy 84.666324 -290.311632)
			(xy 84.65816 -290.361866) (xy 84.642044 -290.41014) (xy 84.618393 -290.455203) (xy 84.58782 -290.495889)
			(xy 84.551116 -290.531144) (xy 84.509232 -290.560054) (xy 84.463253 -290.581871) (xy 84.414369 -290.596031)
			(xy 84.363848 -290.602165) (xy 84.312996 -290.600116) (xy 84.263132 -290.589936) (xy 84.215546 -290.571889)
			(xy 84.171472 -290.546443) (xy 84.13205 -290.514256) (xy 84.098302 -290.476162) (xy 84.071101 -290.433148)
			(xy 84.051153 -290.386328) (xy 84.038974 -290.336914) (xy 84.034879 -290.286186) (xy 83.716368 -290.286186)
			(xy 83.715873 -290.310793) (xy 83.707978 -290.35937) (xy 83.692394 -290.406051) (xy 83.669523 -290.449628)
			(xy 83.639958 -290.488972) (xy 83.604465 -290.523064) (xy 83.563962 -290.55102) (xy 83.5195 -290.572118)
			(xy 83.472229 -290.58581) (xy 83.423374 -290.591742) (xy 83.374199 -290.589761) (xy 83.32598 -290.579917)
			(xy 83.279964 -290.562465) (xy 83.237343 -290.537858) (xy 83.199222 -290.506733) (xy 83.166587 -290.469896)
			(xy 83.140284 -290.4283) (xy 83.120993 -290.383024) (xy 83.109216 -290.33524) (xy 83.105256 -290.286186)
			(xy 82.786728 -290.286186) (xy 82.786216 -290.311632) (xy 82.778052 -290.361866) (xy 82.761936 -290.41014)
			(xy 82.738285 -290.455203) (xy 82.707712 -290.495889) (xy 82.671008 -290.531144) (xy 82.629124 -290.560054)
			(xy 82.583145 -290.581871) (xy 82.534261 -290.596031) (xy 82.48374 -290.602165) (xy 82.432888 -290.600116)
			(xy 82.383024 -290.589936) (xy 82.335438 -290.571889) (xy 82.291364 -290.546443) (xy 82.251942 -290.514256)
			(xy 82.218194 -290.476162) (xy 82.190993 -290.433148) (xy 82.171045 -290.386328) (xy 82.158866 -290.336914)
			(xy 82.154771 -290.286186) (xy 81.846674 -290.286186) (xy 81.846162 -290.311632) (xy 81.837998 -290.361866)
			(xy 81.821882 -290.41014) (xy 81.798231 -290.455203) (xy 81.767658 -290.495889) (xy 81.730954 -290.531144)
			(xy 81.68907 -290.560054) (xy 81.643091 -290.581871) (xy 81.594207 -290.596031) (xy 81.543686 -290.602165)
			(xy 81.492834 -290.600116) (xy 81.44297 -290.589936) (xy 81.395384 -290.571889) (xy 81.35131 -290.546443)
			(xy 81.311888 -290.514256) (xy 81.27814 -290.476162) (xy 81.250939 -290.433148) (xy 81.230991 -290.386328)
			(xy 81.218812 -290.336914) (xy 81.214717 -290.286186) (xy 80.89646 -290.286186) (xy 80.895965 -290.310793)
			(xy 80.88807 -290.35937) (xy 80.872486 -290.406051) (xy 80.849615 -290.449628) (xy 80.82005 -290.488972)
			(xy 80.784557 -290.523064) (xy 80.744054 -290.55102) (xy 80.699592 -290.572118) (xy 80.652321 -290.58581)
			(xy 80.603466 -290.591742) (xy 80.554291 -290.589761) (xy 80.506072 -290.579917) (xy 80.460056 -290.562465)
			(xy 80.417435 -290.537858) (xy 80.379314 -290.506733) (xy 80.346679 -290.469896) (xy 80.320376 -290.4283)
			(xy 80.301085 -290.383024) (xy 80.289308 -290.33524) (xy 80.285348 -290.286186) (xy 79.016352 -290.286186)
			(xy 79.015857 -290.310793) (xy 79.007962 -290.35937) (xy 78.992378 -290.406051) (xy 78.969507 -290.449628)
			(xy 78.939942 -290.488972) (xy 78.904449 -290.523064) (xy 78.863946 -290.55102) (xy 78.819484 -290.572118)
			(xy 78.772213 -290.58581) (xy 78.723358 -290.591742) (xy 78.674183 -290.589761) (xy 78.625964 -290.579917)
			(xy 78.579948 -290.562465) (xy 78.537327 -290.537858) (xy 78.499206 -290.506733) (xy 78.466571 -290.469896)
			(xy 78.440268 -290.4283) (xy 78.420977 -290.383024) (xy 78.4092 -290.33524) (xy 78.40524 -290.286186)
			(xy 73.228962 -290.286186) (xy 73.228962 -290.830254) (xy 76.807072 -290.830254) (xy 76.811032 -290.7812)
			(xy 76.822809 -290.733416) (xy 76.8421 -290.68814) (xy 76.868403 -290.646544) (xy 76.901038 -290.609707)
			(xy 76.939159 -290.578582) (xy 76.98178 -290.553975) (xy 77.027796 -290.536523) (xy 77.076015 -290.526679)
			(xy 77.12519 -290.524698) (xy 77.174045 -290.53063) (xy 77.221316 -290.544322) (xy 77.265778 -290.56542)
			(xy 77.306281 -290.593376) (xy 77.341774 -290.627468) (xy 77.371339 -290.666812) (xy 77.39421 -290.710389)
			(xy 77.409794 -290.75707) (xy 77.417689 -290.805647) (xy 77.418184 -290.830254) (xy 77.417689 -290.854861)
			(xy 77.409794 -290.903438) (xy 77.39421 -290.950119) (xy 77.371339 -290.993696) (xy 77.341774 -291.03304)
			(xy 77.306281 -291.067132) (xy 77.265778 -291.095088) (xy 77.263451 -291.096192) (xy 79.815194 -291.096192)
			(xy 79.819154 -291.047138) (xy 79.830931 -290.999354) (xy 79.850222 -290.954078) (xy 79.876525 -290.912482)
			(xy 79.90916 -290.875645) (xy 79.947281 -290.84452) (xy 79.989902 -290.819913) (xy 80.035918 -290.802461)
			(xy 80.084137 -290.792617) (xy 80.133312 -290.790636) (xy 80.182167 -290.796568) (xy 80.229438 -290.81026)
			(xy 80.2739 -290.831358) (xy 80.314403 -290.859314) (xy 80.349896 -290.893406) (xy 80.379461 -290.93275)
			(xy 80.402332 -290.976327) (xy 80.417916 -291.023008) (xy 80.425811 -291.071585) (xy 80.426306 -291.096192)
			(xy 80.744817 -291.096192) (xy 80.748912 -291.045464) (xy 80.761091 -290.99605) (xy 80.781039 -290.94923)
			(xy 80.80824 -290.906216) (xy 80.841988 -290.868122) (xy 80.88141 -290.835935) (xy 80.925484 -290.810489)
			(xy 80.97307 -290.792442) (xy 81.022934 -290.782262) (xy 81.073786 -290.780213) (xy 81.124307 -290.786347)
			(xy 81.173191 -290.800507) (xy 81.21917 -290.822324) (xy 81.261054 -290.851234) (xy 81.297758 -290.886489)
			(xy 81.328331 -290.927175) (xy 81.351982 -290.972238) (xy 81.368098 -291.020512) (xy 81.376262 -291.070746)
			(xy 81.376774 -291.096192) (xy 81.695302 -291.096192) (xy 81.699262 -291.047138) (xy 81.711039 -290.999354)
			(xy 81.73033 -290.954078) (xy 81.756633 -290.912482) (xy 81.789268 -290.875645) (xy 81.827389 -290.84452)
			(xy 81.87001 -290.819913) (xy 81.916026 -290.802461) (xy 81.964245 -290.792617) (xy 82.01342 -290.790636)
			(xy 82.062275 -290.796568) (xy 82.109546 -290.81026) (xy 82.154008 -290.831358) (xy 82.194511 -290.859314)
			(xy 82.230004 -290.893406) (xy 82.259569 -290.93275) (xy 82.28244 -290.976327) (xy 82.298024 -291.023008)
			(xy 82.305919 -291.071585) (xy 82.306414 -291.096192) (xy 82.624671 -291.096192) (xy 82.628766 -291.045464)
			(xy 82.640945 -290.99605) (xy 82.660893 -290.94923) (xy 82.688094 -290.906216) (xy 82.721842 -290.868122)
			(xy 82.761264 -290.835935) (xy 82.805338 -290.810489) (xy 82.852924 -290.792442) (xy 82.902788 -290.782262)
			(xy 82.95364 -290.780213) (xy 83.004161 -290.786347) (xy 83.053045 -290.800507) (xy 83.099024 -290.822324)
			(xy 83.140908 -290.851234) (xy 83.177612 -290.886489) (xy 83.208185 -290.927175) (xy 83.231836 -290.972238)
			(xy 83.247952 -291.020512) (xy 83.256116 -291.070746) (xy 83.256628 -291.096192) (xy 83.575156 -291.096192)
			(xy 83.579116 -291.047138) (xy 83.590893 -290.999354) (xy 83.610184 -290.954078) (xy 83.636487 -290.912482)
			(xy 83.669122 -290.875645) (xy 83.707243 -290.84452) (xy 83.749864 -290.819913) (xy 83.79588 -290.802461)
			(xy 83.844099 -290.792617) (xy 83.893274 -290.790636) (xy 83.942129 -290.796568) (xy 83.9894 -290.81026)
			(xy 84.033862 -290.831358) (xy 84.074365 -290.859314) (xy 84.109858 -290.893406) (xy 84.139423 -290.93275)
			(xy 84.162294 -290.976327) (xy 84.177878 -291.023008) (xy 84.185773 -291.071585) (xy 84.186268 -291.096192)
			(xy 84.504779 -291.096192) (xy 84.508874 -291.045464) (xy 84.521053 -290.99605) (xy 84.541001 -290.94923)
			(xy 84.568202 -290.906216) (xy 84.60195 -290.868122) (xy 84.641372 -290.835935) (xy 84.685446 -290.810489)
			(xy 84.733032 -290.792442) (xy 84.782896 -290.782262) (xy 84.833748 -290.780213) (xy 84.884269 -290.786347)
			(xy 84.933153 -290.800507) (xy 84.979132 -290.822324) (xy 85.021016 -290.851234) (xy 85.05772 -290.886489)
			(xy 85.088293 -290.927175) (xy 85.111944 -290.972238) (xy 85.12806 -291.020512) (xy 85.136224 -291.070746)
			(xy 85.136736 -291.096192) (xy 85.444833 -291.096192) (xy 85.448928 -291.045464) (xy 85.461107 -290.99605)
			(xy 85.481055 -290.94923) (xy 85.508256 -290.906216) (xy 85.542004 -290.868122) (xy 85.581426 -290.835935)
			(xy 85.6255 -290.810489) (xy 85.673086 -290.792442) (xy 85.72295 -290.782262) (xy 85.773802 -290.780213)
			(xy 85.824323 -290.786347) (xy 85.873207 -290.800507) (xy 85.919186 -290.822324) (xy 85.96107 -290.851234)
			(xy 85.997774 -290.886489) (xy 86.028347 -290.927175) (xy 86.051998 -290.972238) (xy 86.068114 -291.020512)
			(xy 86.076278 -291.070746) (xy 86.07679 -291.096192) (xy 86.395318 -291.096192) (xy 86.399278 -291.047138)
			(xy 86.411055 -290.999354) (xy 86.430346 -290.954078) (xy 86.456649 -290.912482) (xy 86.489284 -290.875645)
			(xy 86.527405 -290.84452) (xy 86.570026 -290.819913) (xy 86.616042 -290.802461) (xy 86.664261 -290.792617)
			(xy 86.713436 -290.790636) (xy 86.762291 -290.796568) (xy 86.809562 -290.81026) (xy 86.854024 -290.831358)
			(xy 86.894527 -290.859314) (xy 86.93002 -290.893406) (xy 86.959585 -290.93275) (xy 86.982456 -290.976327)
			(xy 86.99804 -291.023008) (xy 87.005935 -291.071585) (xy 87.00643 -291.096192) (xy 87.324687 -291.096192)
			(xy 87.328782 -291.045464) (xy 87.340961 -290.99605) (xy 87.360909 -290.94923) (xy 87.38811 -290.906216)
			(xy 87.421858 -290.868122) (xy 87.46128 -290.835935) (xy 87.505354 -290.810489) (xy 87.55294 -290.792442)
			(xy 87.602804 -290.782262) (xy 87.653656 -290.780213) (xy 87.704177 -290.786347) (xy 87.753061 -290.800507)
			(xy 87.79904 -290.822324) (xy 87.840924 -290.851234) (xy 87.877628 -290.886489) (xy 87.908201 -290.927175)
			(xy 87.931852 -290.972238) (xy 87.947968 -291.020512) (xy 87.956132 -291.070746) (xy 87.956644 -291.096192)
			(xy 88.275172 -291.096192) (xy 88.279132 -291.047138) (xy 88.290909 -290.999354) (xy 88.3102 -290.954078)
			(xy 88.336503 -290.912482) (xy 88.369138 -290.875645) (xy 88.407259 -290.84452) (xy 88.44988 -290.819913)
			(xy 88.495896 -290.802461) (xy 88.544115 -290.792617) (xy 88.59329 -290.790636) (xy 88.642145 -290.796568)
			(xy 88.689416 -290.81026) (xy 88.733878 -290.831358) (xy 88.774381 -290.859314) (xy 88.809874 -290.893406)
			(xy 88.839439 -290.93275) (xy 88.86231 -290.976327) (xy 88.877894 -291.023008) (xy 88.885789 -291.071585)
			(xy 88.886284 -291.096192) (xy 89.204795 -291.096192) (xy 89.20889 -291.045464) (xy 89.221069 -290.99605)
			(xy 89.241017 -290.94923) (xy 89.268218 -290.906216) (xy 89.301966 -290.868122) (xy 89.341388 -290.835935)
			(xy 89.385462 -290.810489) (xy 89.433048 -290.792442) (xy 89.482912 -290.782262) (xy 89.533764 -290.780213)
			(xy 89.584285 -290.786347) (xy 89.633169 -290.800507) (xy 89.679148 -290.822324) (xy 89.721032 -290.851234)
			(xy 89.757736 -290.886489) (xy 89.788309 -290.927175) (xy 89.81196 -290.972238) (xy 89.828076 -291.020512)
			(xy 89.83624 -291.070746) (xy 89.836752 -291.096192) (xy 90.15528 -291.096192) (xy 90.15924 -291.047138)
			(xy 90.171017 -290.999354) (xy 90.190308 -290.954078) (xy 90.216611 -290.912482) (xy 90.249246 -290.875645)
			(xy 90.287367 -290.84452) (xy 90.329988 -290.819913) (xy 90.376004 -290.802461) (xy 90.424223 -290.792617)
			(xy 90.473398 -290.790636) (xy 90.522253 -290.796568) (xy 90.569524 -290.81026) (xy 90.613986 -290.831358)
			(xy 90.654489 -290.859314) (xy 90.689982 -290.893406) (xy 90.719547 -290.93275) (xy 90.742418 -290.976327)
			(xy 90.758002 -291.023008) (xy 90.765897 -291.071585) (xy 90.766392 -291.096192) (xy 91.084903 -291.096192)
			(xy 91.088998 -291.045464) (xy 91.101177 -290.99605) (xy 91.121125 -290.94923) (xy 91.148326 -290.906216)
			(xy 91.182074 -290.868122) (xy 91.221496 -290.835935) (xy 91.26557 -290.810489) (xy 91.313156 -290.792442)
			(xy 91.36302 -290.782262) (xy 91.413872 -290.780213) (xy 91.464393 -290.786347) (xy 91.513277 -290.800507)
			(xy 91.559256 -290.822324) (xy 91.60114 -290.851234) (xy 91.637844 -290.886489) (xy 91.668417 -290.927175)
			(xy 91.692068 -290.972238) (xy 91.708184 -291.020512) (xy 91.716348 -291.070746) (xy 91.71686 -291.096192)
			(xy 92.024703 -291.096192) (xy 92.028798 -291.045464) (xy 92.040977 -290.99605) (xy 92.060925 -290.94923)
			(xy 92.088126 -290.906216) (xy 92.121874 -290.868122) (xy 92.161296 -290.835935) (xy 92.20537 -290.810489)
			(xy 92.252956 -290.792442) (xy 92.30282 -290.782262) (xy 92.353672 -290.780213) (xy 92.404193 -290.786347)
			(xy 92.453077 -290.800507) (xy 92.499056 -290.822324) (xy 92.54094 -290.851234) (xy 92.577644 -290.886489)
			(xy 92.608217 -290.927175) (xy 92.631868 -290.972238) (xy 92.647984 -291.020512) (xy 92.656148 -291.070746)
			(xy 92.65666 -291.096192) (xy 92.975188 -291.096192) (xy 92.979148 -291.047138) (xy 92.990925 -290.999354)
			(xy 93.010216 -290.954078) (xy 93.036519 -290.912482) (xy 93.069154 -290.875645) (xy 93.107275 -290.84452)
			(xy 93.149896 -290.819913) (xy 93.195912 -290.802461) (xy 93.244131 -290.792617) (xy 93.293306 -290.790636)
			(xy 93.342161 -290.796568) (xy 93.389432 -290.81026) (xy 93.433894 -290.831358) (xy 93.474397 -290.859314)
			(xy 93.50989 -290.893406) (xy 93.539455 -290.93275) (xy 93.562326 -290.976327) (xy 93.57791 -291.023008)
			(xy 93.585805 -291.071585) (xy 93.5863 -291.096192) (xy 93.904811 -291.096192) (xy 93.908906 -291.045464)
			(xy 93.921085 -290.99605) (xy 93.941033 -290.94923) (xy 93.968234 -290.906216) (xy 94.001982 -290.868122)
			(xy 94.041404 -290.835935) (xy 94.085478 -290.810489) (xy 94.133064 -290.792442) (xy 94.182928 -290.782262)
			(xy 94.23378 -290.780213) (xy 94.284301 -290.786347) (xy 94.333185 -290.800507) (xy 94.379164 -290.822324)
			(xy 94.421048 -290.851234) (xy 94.457752 -290.886489) (xy 94.488325 -290.927175) (xy 94.511976 -290.972238)
			(xy 94.528092 -291.020512) (xy 94.536256 -291.070746) (xy 94.536768 -291.096192) (xy 94.855296 -291.096192)
			(xy 94.859256 -291.047138) (xy 94.871033 -290.999354) (xy 94.890324 -290.954078) (xy 94.916627 -290.912482)
			(xy 94.949262 -290.875645) (xy 94.987383 -290.84452) (xy 95.030004 -290.819913) (xy 95.07602 -290.802461)
			(xy 95.124239 -290.792617) (xy 95.173414 -290.790636) (xy 95.222269 -290.796568) (xy 95.26954 -290.81026)
			(xy 95.314002 -290.831358) (xy 95.354505 -290.859314) (xy 95.389998 -290.893406) (xy 95.419563 -290.93275)
			(xy 95.442434 -290.976327) (xy 95.458018 -291.023008) (xy 95.465913 -291.071585) (xy 95.466408 -291.096192)
			(xy 95.784919 -291.096192) (xy 95.789014 -291.045464) (xy 95.801193 -290.99605) (xy 95.821141 -290.94923)
			(xy 95.848342 -290.906216) (xy 95.88209 -290.868122) (xy 95.921512 -290.835935) (xy 95.965586 -290.810489)
			(xy 96.013172 -290.792442) (xy 96.063036 -290.782262) (xy 96.113888 -290.780213) (xy 96.164409 -290.786347)
			(xy 96.213293 -290.800507) (xy 96.259272 -290.822324) (xy 96.301156 -290.851234) (xy 96.33786 -290.886489)
			(xy 96.368433 -290.927175) (xy 96.392084 -290.972238) (xy 96.4082 -291.020512) (xy 96.416364 -291.070746)
			(xy 96.416876 -291.096192) (xy 96.73515 -291.096192) (xy 96.73911 -291.047138) (xy 96.750887 -290.999354)
			(xy 96.770178 -290.954078) (xy 96.796481 -290.912482) (xy 96.829116 -290.875645) (xy 96.867237 -290.84452)
			(xy 96.909858 -290.819913) (xy 96.955874 -290.802461) (xy 97.004093 -290.792617) (xy 97.053268 -290.790636)
			(xy 97.102123 -290.796568) (xy 97.149394 -290.81026) (xy 97.193856 -290.831358) (xy 97.234359 -290.859314)
			(xy 97.269852 -290.893406) (xy 97.299417 -290.93275) (xy 97.322288 -290.976327) (xy 97.337872 -291.023008)
			(xy 97.345767 -291.071585) (xy 97.346262 -291.096192) (xy 97.664773 -291.096192) (xy 97.668868 -291.045464)
			(xy 97.681047 -290.99605) (xy 97.700995 -290.94923) (xy 97.728196 -290.906216) (xy 97.761944 -290.868122)
			(xy 97.801366 -290.835935) (xy 97.84544 -290.810489) (xy 97.893026 -290.792442) (xy 97.94289 -290.782262)
			(xy 97.993742 -290.780213) (xy 98.044263 -290.786347) (xy 98.093147 -290.800507) (xy 98.139126 -290.822324)
			(xy 98.18101 -290.851234) (xy 98.217714 -290.886489) (xy 98.248287 -290.927175) (xy 98.271938 -290.972238)
			(xy 98.288054 -291.020512) (xy 98.296218 -291.070746) (xy 98.29673 -291.096192) (xy 98.604827 -291.096192)
			(xy 98.608922 -291.045464) (xy 98.621101 -290.99605) (xy 98.641049 -290.94923) (xy 98.66825 -290.906216)
			(xy 98.701998 -290.868122) (xy 98.74142 -290.835935) (xy 98.785494 -290.810489) (xy 98.83308 -290.792442)
			(xy 98.882944 -290.782262) (xy 98.933796 -290.780213) (xy 98.984317 -290.786347) (xy 99.033201 -290.800507)
			(xy 99.07918 -290.822324) (xy 99.121064 -290.851234) (xy 99.157768 -290.886489) (xy 99.188341 -290.927175)
			(xy 99.211992 -290.972238) (xy 99.228108 -291.020512) (xy 99.236272 -291.070746) (xy 99.236784 -291.096192)
			(xy 99.555312 -291.096192) (xy 99.559272 -291.047138) (xy 99.571049 -290.999354) (xy 99.59034 -290.954078)
			(xy 99.616643 -290.912482) (xy 99.649278 -290.875645) (xy 99.687399 -290.84452) (xy 99.73002 -290.819913)
			(xy 99.776036 -290.802461) (xy 99.824255 -290.792617) (xy 99.87343 -290.790636) (xy 99.922285 -290.796568)
			(xy 99.969556 -290.81026) (xy 100.014018 -290.831358) (xy 100.054521 -290.859314) (xy 100.090014 -290.893406)
			(xy 100.119579 -290.93275) (xy 100.14245 -290.976327) (xy 100.158034 -291.023008) (xy 100.165929 -291.071585)
			(xy 100.166424 -291.096192) (xy 100.484935 -291.096192) (xy 100.48903 -291.045464) (xy 100.501209 -290.99605)
			(xy 100.521157 -290.94923) (xy 100.548358 -290.906216) (xy 100.582106 -290.868122) (xy 100.621528 -290.835935)
			(xy 100.665602 -290.810489) (xy 100.713188 -290.792442) (xy 100.763052 -290.782262) (xy 100.813904 -290.780213)
			(xy 100.864425 -290.786347) (xy 100.913309 -290.800507) (xy 100.959288 -290.822324) (xy 101.001172 -290.851234)
			(xy 101.037876 -290.886489) (xy 101.068449 -290.927175) (xy 101.0921 -290.972238) (xy 101.108216 -291.020512)
			(xy 101.11638 -291.070746) (xy 101.116892 -291.096192) (xy 101.424735 -291.096192) (xy 101.42883 -291.045464)
			(xy 101.441009 -290.99605) (xy 101.460957 -290.94923) (xy 101.488158 -290.906216) (xy 101.521906 -290.868122)
			(xy 101.561328 -290.835935) (xy 101.605402 -290.810489) (xy 101.652988 -290.792442) (xy 101.702852 -290.782262)
			(xy 101.753704 -290.780213) (xy 101.804225 -290.786347) (xy 101.853109 -290.800507) (xy 101.899088 -290.822324)
			(xy 101.940972 -290.851234) (xy 101.977676 -290.886489) (xy 102.008249 -290.927175) (xy 102.0319 -290.972238)
			(xy 102.048016 -291.020512) (xy 102.05618 -291.070746) (xy 102.056692 -291.096192) (xy 102.05618 -291.121638)
			(xy 102.048016 -291.171872) (xy 102.0319 -291.220146) (xy 102.008249 -291.265209) (xy 101.977676 -291.305895)
			(xy 101.940972 -291.34115) (xy 101.899088 -291.37006) (xy 101.853109 -291.391877) (xy 101.804225 -291.406037)
			(xy 101.753704 -291.412171) (xy 101.702852 -291.410122) (xy 101.652988 -291.399942) (xy 101.605402 -291.381895)
			(xy 101.561328 -291.356449) (xy 101.521906 -291.324262) (xy 101.488158 -291.286168) (xy 101.460957 -291.243154)
			(xy 101.441009 -291.196334) (xy 101.42883 -291.14692) (xy 101.424735 -291.096192) (xy 101.116892 -291.096192)
			(xy 101.11638 -291.121638) (xy 101.108216 -291.171872) (xy 101.0921 -291.220146) (xy 101.068449 -291.265209)
			(xy 101.037876 -291.305895) (xy 101.001172 -291.34115) (xy 100.959288 -291.37006) (xy 100.913309 -291.391877)
			(xy 100.864425 -291.406037) (xy 100.813904 -291.412171) (xy 100.763052 -291.410122) (xy 100.713188 -291.399942)
			(xy 100.665602 -291.381895) (xy 100.621528 -291.356449) (xy 100.582106 -291.324262) (xy 100.548358 -291.286168)
			(xy 100.521157 -291.243154) (xy 100.501209 -291.196334) (xy 100.48903 -291.14692) (xy 100.484935 -291.096192)
			(xy 100.166424 -291.096192) (xy 100.165929 -291.120799) (xy 100.158034 -291.169376) (xy 100.14245 -291.216057)
			(xy 100.119579 -291.259634) (xy 100.090014 -291.298978) (xy 100.054521 -291.33307) (xy 100.014018 -291.361026)
			(xy 99.969556 -291.382124) (xy 99.922285 -291.395816) (xy 99.87343 -291.401748) (xy 99.824255 -291.399767)
			(xy 99.776036 -291.389923) (xy 99.73002 -291.372471) (xy 99.687399 -291.347864) (xy 99.649278 -291.316739)
			(xy 99.616643 -291.279902) (xy 99.59034 -291.238306) (xy 99.571049 -291.19303) (xy 99.559272 -291.145246)
			(xy 99.555312 -291.096192) (xy 99.236784 -291.096192) (xy 99.236272 -291.121638) (xy 99.228108 -291.171872)
			(xy 99.211992 -291.220146) (xy 99.188341 -291.265209) (xy 99.157768 -291.305895) (xy 99.121064 -291.34115)
			(xy 99.07918 -291.37006) (xy 99.033201 -291.391877) (xy 98.984317 -291.406037) (xy 98.933796 -291.412171)
			(xy 98.882944 -291.410122) (xy 98.83308 -291.399942) (xy 98.785494 -291.381895) (xy 98.74142 -291.356449)
			(xy 98.701998 -291.324262) (xy 98.66825 -291.286168) (xy 98.641049 -291.243154) (xy 98.621101 -291.196334)
			(xy 98.608922 -291.14692) (xy 98.604827 -291.096192) (xy 98.29673 -291.096192) (xy 98.296218 -291.121638)
			(xy 98.288054 -291.171872) (xy 98.271938 -291.220146) (xy 98.248287 -291.265209) (xy 98.217714 -291.305895)
			(xy 98.18101 -291.34115) (xy 98.139126 -291.37006) (xy 98.093147 -291.391877) (xy 98.044263 -291.406037)
			(xy 97.993742 -291.412171) (xy 97.94289 -291.410122) (xy 97.893026 -291.399942) (xy 97.84544 -291.381895)
			(xy 97.801366 -291.356449) (xy 97.761944 -291.324262) (xy 97.728196 -291.286168) (xy 97.700995 -291.243154)
			(xy 97.681047 -291.196334) (xy 97.668868 -291.14692) (xy 97.664773 -291.096192) (xy 97.346262 -291.096192)
			(xy 97.345767 -291.120799) (xy 97.337872 -291.169376) (xy 97.322288 -291.216057) (xy 97.299417 -291.259634)
			(xy 97.269852 -291.298978) (xy 97.234359 -291.33307) (xy 97.193856 -291.361026) (xy 97.149394 -291.382124)
			(xy 97.102123 -291.395816) (xy 97.053268 -291.401748) (xy 97.004093 -291.399767) (xy 96.955874 -291.389923)
			(xy 96.909858 -291.372471) (xy 96.867237 -291.347864) (xy 96.829116 -291.316739) (xy 96.796481 -291.279902)
			(xy 96.770178 -291.238306) (xy 96.750887 -291.19303) (xy 96.73911 -291.145246) (xy 96.73515 -291.096192)
			(xy 96.416876 -291.096192) (xy 96.416364 -291.121638) (xy 96.4082 -291.171872) (xy 96.392084 -291.220146)
			(xy 96.368433 -291.265209) (xy 96.33786 -291.305895) (xy 96.301156 -291.34115) (xy 96.259272 -291.37006)
			(xy 96.213293 -291.391877) (xy 96.164409 -291.406037) (xy 96.113888 -291.412171) (xy 96.063036 -291.410122)
			(xy 96.013172 -291.399942) (xy 95.965586 -291.381895) (xy 95.921512 -291.356449) (xy 95.88209 -291.324262)
			(xy 95.848342 -291.286168) (xy 95.821141 -291.243154) (xy 95.801193 -291.196334) (xy 95.789014 -291.14692)
			(xy 95.784919 -291.096192) (xy 95.466408 -291.096192) (xy 95.465913 -291.120799) (xy 95.458018 -291.169376)
			(xy 95.442434 -291.216057) (xy 95.419563 -291.259634) (xy 95.389998 -291.298978) (xy 95.354505 -291.33307)
			(xy 95.314002 -291.361026) (xy 95.26954 -291.382124) (xy 95.222269 -291.395816) (xy 95.173414 -291.401748)
			(xy 95.124239 -291.399767) (xy 95.07602 -291.389923) (xy 95.030004 -291.372471) (xy 94.987383 -291.347864)
			(xy 94.949262 -291.316739) (xy 94.916627 -291.279902) (xy 94.890324 -291.238306) (xy 94.871033 -291.19303)
			(xy 94.859256 -291.145246) (xy 94.855296 -291.096192) (xy 94.536768 -291.096192) (xy 94.536256 -291.121638)
			(xy 94.528092 -291.171872) (xy 94.511976 -291.220146) (xy 94.488325 -291.265209) (xy 94.457752 -291.305895)
			(xy 94.421048 -291.34115) (xy 94.379164 -291.37006) (xy 94.333185 -291.391877) (xy 94.284301 -291.406037)
			(xy 94.23378 -291.412171) (xy 94.182928 -291.410122) (xy 94.133064 -291.399942) (xy 94.085478 -291.381895)
			(xy 94.041404 -291.356449) (xy 94.001982 -291.324262) (xy 93.968234 -291.286168) (xy 93.941033 -291.243154)
			(xy 93.921085 -291.196334) (xy 93.908906 -291.14692) (xy 93.904811 -291.096192) (xy 93.5863 -291.096192)
			(xy 93.585805 -291.120799) (xy 93.57791 -291.169376) (xy 93.562326 -291.216057) (xy 93.539455 -291.259634)
			(xy 93.50989 -291.298978) (xy 93.474397 -291.33307) (xy 93.433894 -291.361026) (xy 93.389432 -291.382124)
			(xy 93.342161 -291.395816) (xy 93.293306 -291.401748) (xy 93.244131 -291.399767) (xy 93.195912 -291.389923)
			(xy 93.149896 -291.372471) (xy 93.107275 -291.347864) (xy 93.069154 -291.316739) (xy 93.036519 -291.279902)
			(xy 93.010216 -291.238306) (xy 92.990925 -291.19303) (xy 92.979148 -291.145246) (xy 92.975188 -291.096192)
			(xy 92.65666 -291.096192) (xy 92.656148 -291.121638) (xy 92.647984 -291.171872) (xy 92.631868 -291.220146)
			(xy 92.608217 -291.265209) (xy 92.577644 -291.305895) (xy 92.54094 -291.34115) (xy 92.499056 -291.37006)
			(xy 92.453077 -291.391877) (xy 92.404193 -291.406037) (xy 92.353672 -291.412171) (xy 92.30282 -291.410122)
			(xy 92.252956 -291.399942) (xy 92.20537 -291.381895) (xy 92.161296 -291.356449) (xy 92.121874 -291.324262)
			(xy 92.088126 -291.286168) (xy 92.060925 -291.243154) (xy 92.040977 -291.196334) (xy 92.028798 -291.14692)
			(xy 92.024703 -291.096192) (xy 91.71686 -291.096192) (xy 91.716348 -291.121638) (xy 91.708184 -291.171872)
			(xy 91.692068 -291.220146) (xy 91.668417 -291.265209) (xy 91.637844 -291.305895) (xy 91.60114 -291.34115)
			(xy 91.559256 -291.37006) (xy 91.513277 -291.391877) (xy 91.464393 -291.406037) (xy 91.413872 -291.412171)
			(xy 91.36302 -291.410122) (xy 91.313156 -291.399942) (xy 91.26557 -291.381895) (xy 91.221496 -291.356449)
			(xy 91.182074 -291.324262) (xy 91.148326 -291.286168) (xy 91.121125 -291.243154) (xy 91.101177 -291.196334)
			(xy 91.088998 -291.14692) (xy 91.084903 -291.096192) (xy 90.766392 -291.096192) (xy 90.765897 -291.120799)
			(xy 90.758002 -291.169376) (xy 90.742418 -291.216057) (xy 90.719547 -291.259634) (xy 90.689982 -291.298978)
			(xy 90.654489 -291.33307) (xy 90.613986 -291.361026) (xy 90.569524 -291.382124) (xy 90.522253 -291.395816)
			(xy 90.473398 -291.401748) (xy 90.424223 -291.399767) (xy 90.376004 -291.389923) (xy 90.329988 -291.372471)
			(xy 90.287367 -291.347864) (xy 90.249246 -291.316739) (xy 90.216611 -291.279902) (xy 90.190308 -291.238306)
			(xy 90.171017 -291.19303) (xy 90.15924 -291.145246) (xy 90.15528 -291.096192) (xy 89.836752 -291.096192)
			(xy 89.83624 -291.121638) (xy 89.828076 -291.171872) (xy 89.81196 -291.220146) (xy 89.788309 -291.265209)
			(xy 89.757736 -291.305895) (xy 89.721032 -291.34115) (xy 89.679148 -291.37006) (xy 89.633169 -291.391877)
			(xy 89.584285 -291.406037) (xy 89.533764 -291.412171) (xy 89.482912 -291.410122) (xy 89.433048 -291.399942)
			(xy 89.385462 -291.381895) (xy 89.341388 -291.356449) (xy 89.301966 -291.324262) (xy 89.268218 -291.286168)
			(xy 89.241017 -291.243154) (xy 89.221069 -291.196334) (xy 89.20889 -291.14692) (xy 89.204795 -291.096192)
			(xy 88.886284 -291.096192) (xy 88.885789 -291.120799) (xy 88.877894 -291.169376) (xy 88.86231 -291.216057)
			(xy 88.839439 -291.259634) (xy 88.809874 -291.298978) (xy 88.774381 -291.33307) (xy 88.733878 -291.361026)
			(xy 88.689416 -291.382124) (xy 88.642145 -291.395816) (xy 88.59329 -291.401748) (xy 88.544115 -291.399767)
			(xy 88.495896 -291.389923) (xy 88.44988 -291.372471) (xy 88.407259 -291.347864) (xy 88.369138 -291.316739)
			(xy 88.336503 -291.279902) (xy 88.3102 -291.238306) (xy 88.290909 -291.19303) (xy 88.279132 -291.145246)
			(xy 88.275172 -291.096192) (xy 87.956644 -291.096192) (xy 87.956132 -291.121638) (xy 87.947968 -291.171872)
			(xy 87.931852 -291.220146) (xy 87.908201 -291.265209) (xy 87.877628 -291.305895) (xy 87.840924 -291.34115)
			(xy 87.79904 -291.37006) (xy 87.753061 -291.391877) (xy 87.704177 -291.406037) (xy 87.653656 -291.412171)
			(xy 87.602804 -291.410122) (xy 87.55294 -291.399942) (xy 87.505354 -291.381895) (xy 87.46128 -291.356449)
			(xy 87.421858 -291.324262) (xy 87.38811 -291.286168) (xy 87.360909 -291.243154) (xy 87.340961 -291.196334)
			(xy 87.328782 -291.14692) (xy 87.324687 -291.096192) (xy 87.00643 -291.096192) (xy 87.005935 -291.120799)
			(xy 86.99804 -291.169376) (xy 86.982456 -291.216057) (xy 86.959585 -291.259634) (xy 86.93002 -291.298978)
			(xy 86.894527 -291.33307) (xy 86.854024 -291.361026) (xy 86.809562 -291.382124) (xy 86.762291 -291.395816)
			(xy 86.713436 -291.401748) (xy 86.664261 -291.399767) (xy 86.616042 -291.389923) (xy 86.570026 -291.372471)
			(xy 86.527405 -291.347864) (xy 86.489284 -291.316739) (xy 86.456649 -291.279902) (xy 86.430346 -291.238306)
			(xy 86.411055 -291.19303) (xy 86.399278 -291.145246) (xy 86.395318 -291.096192) (xy 86.07679 -291.096192)
			(xy 86.076278 -291.121638) (xy 86.068114 -291.171872) (xy 86.051998 -291.220146) (xy 86.028347 -291.265209)
			(xy 85.997774 -291.305895) (xy 85.96107 -291.34115) (xy 85.919186 -291.37006) (xy 85.873207 -291.391877)
			(xy 85.824323 -291.406037) (xy 85.773802 -291.412171) (xy 85.72295 -291.410122) (xy 85.673086 -291.399942)
			(xy 85.6255 -291.381895) (xy 85.581426 -291.356449) (xy 85.542004 -291.324262) (xy 85.508256 -291.286168)
			(xy 85.481055 -291.243154) (xy 85.461107 -291.196334) (xy 85.448928 -291.14692) (xy 85.444833 -291.096192)
			(xy 85.136736 -291.096192) (xy 85.136224 -291.121638) (xy 85.12806 -291.171872) (xy 85.111944 -291.220146)
			(xy 85.088293 -291.265209) (xy 85.05772 -291.305895) (xy 85.021016 -291.34115) (xy 84.979132 -291.37006)
			(xy 84.933153 -291.391877) (xy 84.884269 -291.406037) (xy 84.833748 -291.412171) (xy 84.782896 -291.410122)
			(xy 84.733032 -291.399942) (xy 84.685446 -291.381895) (xy 84.641372 -291.356449) (xy 84.60195 -291.324262)
			(xy 84.568202 -291.286168) (xy 84.541001 -291.243154) (xy 84.521053 -291.196334) (xy 84.508874 -291.14692)
			(xy 84.504779 -291.096192) (xy 84.186268 -291.096192) (xy 84.185773 -291.120799) (xy 84.177878 -291.169376)
			(xy 84.162294 -291.216057) (xy 84.139423 -291.259634) (xy 84.109858 -291.298978) (xy 84.074365 -291.33307)
			(xy 84.033862 -291.361026) (xy 83.9894 -291.382124) (xy 83.942129 -291.395816) (xy 83.893274 -291.401748)
			(xy 83.844099 -291.399767) (xy 83.79588 -291.389923) (xy 83.749864 -291.372471) (xy 83.707243 -291.347864)
			(xy 83.669122 -291.316739) (xy 83.636487 -291.279902) (xy 83.610184 -291.238306) (xy 83.590893 -291.19303)
			(xy 83.579116 -291.145246) (xy 83.575156 -291.096192) (xy 83.256628 -291.096192) (xy 83.256116 -291.121638)
			(xy 83.247952 -291.171872) (xy 83.231836 -291.220146) (xy 83.208185 -291.265209) (xy 83.177612 -291.305895)
			(xy 83.140908 -291.34115) (xy 83.099024 -291.37006) (xy 83.053045 -291.391877) (xy 83.004161 -291.406037)
			(xy 82.95364 -291.412171) (xy 82.902788 -291.410122) (xy 82.852924 -291.399942) (xy 82.805338 -291.381895)
			(xy 82.761264 -291.356449) (xy 82.721842 -291.324262) (xy 82.688094 -291.286168) (xy 82.660893 -291.243154)
			(xy 82.640945 -291.196334) (xy 82.628766 -291.14692) (xy 82.624671 -291.096192) (xy 82.306414 -291.096192)
			(xy 82.305919 -291.120799) (xy 82.298024 -291.169376) (xy 82.28244 -291.216057) (xy 82.259569 -291.259634)
			(xy 82.230004 -291.298978) (xy 82.194511 -291.33307) (xy 82.154008 -291.361026) (xy 82.109546 -291.382124)
			(xy 82.062275 -291.395816) (xy 82.01342 -291.401748) (xy 81.964245 -291.399767) (xy 81.916026 -291.389923)
			(xy 81.87001 -291.372471) (xy 81.827389 -291.347864) (xy 81.789268 -291.316739) (xy 81.756633 -291.279902)
			(xy 81.73033 -291.238306) (xy 81.711039 -291.19303) (xy 81.699262 -291.145246) (xy 81.695302 -291.096192)
			(xy 81.376774 -291.096192) (xy 81.376262 -291.121638) (xy 81.368098 -291.171872) (xy 81.351982 -291.220146)
			(xy 81.328331 -291.265209) (xy 81.297758 -291.305895) (xy 81.261054 -291.34115) (xy 81.21917 -291.37006)
			(xy 81.173191 -291.391877) (xy 81.124307 -291.406037) (xy 81.073786 -291.412171) (xy 81.022934 -291.410122)
			(xy 80.97307 -291.399942) (xy 80.925484 -291.381895) (xy 80.88141 -291.356449) (xy 80.841988 -291.324262)
			(xy 80.80824 -291.286168) (xy 80.781039 -291.243154) (xy 80.761091 -291.196334) (xy 80.748912 -291.14692)
			(xy 80.744817 -291.096192) (xy 80.426306 -291.096192) (xy 80.425811 -291.120799) (xy 80.417916 -291.169376)
			(xy 80.402332 -291.216057) (xy 80.379461 -291.259634) (xy 80.349896 -291.298978) (xy 80.314403 -291.33307)
			(xy 80.2739 -291.361026) (xy 80.229438 -291.382124) (xy 80.182167 -291.395816) (xy 80.133312 -291.401748)
			(xy 80.084137 -291.399767) (xy 80.035918 -291.389923) (xy 79.989902 -291.372471) (xy 79.947281 -291.347864)
			(xy 79.90916 -291.316739) (xy 79.876525 -291.279902) (xy 79.850222 -291.238306) (xy 79.830931 -291.19303)
			(xy 79.819154 -291.145246) (xy 79.815194 -291.096192) (xy 77.263451 -291.096192) (xy 77.221316 -291.116186)
			(xy 77.174045 -291.129878) (xy 77.12519 -291.13581) (xy 77.076015 -291.133829) (xy 77.027796 -291.123985)
			(xy 76.98178 -291.106533) (xy 76.939159 -291.081926) (xy 76.901038 -291.050801) (xy 76.868403 -291.013964)
			(xy 76.8421 -290.972368) (xy 76.822809 -290.927092) (xy 76.811032 -290.879308) (xy 76.807072 -290.830254)
			(xy 73.228962 -290.830254) (xy 73.228962 -291.906198) (xy 78.40524 -291.906198) (xy 78.4092 -291.857144)
			(xy 78.420977 -291.80936) (xy 78.440268 -291.764084) (xy 78.466571 -291.722488) (xy 78.499206 -291.685651)
			(xy 78.537327 -291.654526) (xy 78.579948 -291.629919) (xy 78.625964 -291.612467) (xy 78.674183 -291.602623)
			(xy 78.723358 -291.600642) (xy 78.772213 -291.606574) (xy 78.819484 -291.620266) (xy 78.863946 -291.641364)
			(xy 78.904449 -291.66932) (xy 78.939942 -291.703412) (xy 78.969507 -291.742756) (xy 78.992378 -291.786333)
			(xy 79.007962 -291.833014) (xy 79.015857 -291.881591) (xy 79.016352 -291.906198) (xy 80.285348 -291.906198)
			(xy 80.289308 -291.857144) (xy 80.301085 -291.80936) (xy 80.320376 -291.764084) (xy 80.346679 -291.722488)
			(xy 80.379314 -291.685651) (xy 80.417435 -291.654526) (xy 80.460056 -291.629919) (xy 80.506072 -291.612467)
			(xy 80.554291 -291.602623) (xy 80.603466 -291.600642) (xy 80.652321 -291.606574) (xy 80.699592 -291.620266)
			(xy 80.744054 -291.641364) (xy 80.784557 -291.66932) (xy 80.82005 -291.703412) (xy 80.849615 -291.742756)
			(xy 80.872486 -291.786333) (xy 80.88807 -291.833014) (xy 80.895965 -291.881591) (xy 80.89646 -291.906198)
			(xy 81.214717 -291.906198) (xy 81.218812 -291.85547) (xy 81.230991 -291.806056) (xy 81.250939 -291.759236)
			(xy 81.27814 -291.716222) (xy 81.311888 -291.678128) (xy 81.35131 -291.645941) (xy 81.395384 -291.620495)
			(xy 81.44297 -291.602448) (xy 81.492834 -291.592268) (xy 81.543686 -291.590219) (xy 81.594207 -291.596353)
			(xy 81.643091 -291.610513) (xy 81.68907 -291.63233) (xy 81.730954 -291.66124) (xy 81.767658 -291.696495)
			(xy 81.798231 -291.737181) (xy 81.821882 -291.782244) (xy 81.837998 -291.830518) (xy 81.846162 -291.880752)
			(xy 81.846674 -291.906198) (xy 82.154771 -291.906198) (xy 82.158866 -291.85547) (xy 82.171045 -291.806056)
			(xy 82.190993 -291.759236) (xy 82.218194 -291.716222) (xy 82.251942 -291.678128) (xy 82.291364 -291.645941)
			(xy 82.335438 -291.620495) (xy 82.383024 -291.602448) (xy 82.432888 -291.592268) (xy 82.48374 -291.590219)
			(xy 82.534261 -291.596353) (xy 82.583145 -291.610513) (xy 82.629124 -291.63233) (xy 82.671008 -291.66124)
			(xy 82.707712 -291.696495) (xy 82.738285 -291.737181) (xy 82.761936 -291.782244) (xy 82.778052 -291.830518)
			(xy 82.786216 -291.880752) (xy 82.786728 -291.906198) (xy 83.105256 -291.906198) (xy 83.109216 -291.857144)
			(xy 83.120993 -291.80936) (xy 83.140284 -291.764084) (xy 83.166587 -291.722488) (xy 83.199222 -291.685651)
			(xy 83.237343 -291.654526) (xy 83.279964 -291.629919) (xy 83.32598 -291.612467) (xy 83.374199 -291.602623)
			(xy 83.423374 -291.600642) (xy 83.472229 -291.606574) (xy 83.5195 -291.620266) (xy 83.563962 -291.641364)
			(xy 83.604465 -291.66932) (xy 83.639958 -291.703412) (xy 83.669523 -291.742756) (xy 83.692394 -291.786333)
			(xy 83.707978 -291.833014) (xy 83.715873 -291.881591) (xy 83.716368 -291.906198) (xy 84.034879 -291.906198)
			(xy 84.038974 -291.85547) (xy 84.051153 -291.806056) (xy 84.071101 -291.759236) (xy 84.098302 -291.716222)
			(xy 84.13205 -291.678128) (xy 84.171472 -291.645941) (xy 84.215546 -291.620495) (xy 84.263132 -291.602448)
			(xy 84.312996 -291.592268) (xy 84.363848 -291.590219) (xy 84.414369 -291.596353) (xy 84.463253 -291.610513)
			(xy 84.509232 -291.63233) (xy 84.551116 -291.66124) (xy 84.58782 -291.696495) (xy 84.618393 -291.737181)
			(xy 84.642044 -291.782244) (xy 84.65816 -291.830518) (xy 84.666324 -291.880752) (xy 84.666836 -291.906198)
			(xy 84.98511 -291.906198) (xy 84.98907 -291.857144) (xy 85.000847 -291.80936) (xy 85.020138 -291.764084)
			(xy 85.046441 -291.722488) (xy 85.079076 -291.685651) (xy 85.117197 -291.654526) (xy 85.159818 -291.629919)
			(xy 85.205834 -291.612467) (xy 85.254053 -291.602623) (xy 85.303228 -291.600642) (xy 85.352083 -291.606574)
			(xy 85.399354 -291.620266) (xy 85.443816 -291.641364) (xy 85.484319 -291.66932) (xy 85.519812 -291.703412)
			(xy 85.549377 -291.742756) (xy 85.572248 -291.786333) (xy 85.587832 -291.833014) (xy 85.595727 -291.881591)
			(xy 85.596222 -291.906198) (xy 85.914733 -291.906198) (xy 85.918828 -291.85547) (xy 85.931007 -291.806056)
			(xy 85.950955 -291.759236) (xy 85.978156 -291.716222) (xy 86.011904 -291.678128) (xy 86.051326 -291.645941)
			(xy 86.0954 -291.620495) (xy 86.142986 -291.602448) (xy 86.19285 -291.592268) (xy 86.243702 -291.590219)
			(xy 86.294223 -291.596353) (xy 86.343107 -291.610513) (xy 86.389086 -291.63233) (xy 86.43097 -291.66124)
			(xy 86.467674 -291.696495) (xy 86.498247 -291.737181) (xy 86.521898 -291.782244) (xy 86.538014 -291.830518)
			(xy 86.546178 -291.880752) (xy 86.54669 -291.906198) (xy 86.865218 -291.906198) (xy 86.869178 -291.857144)
			(xy 86.880955 -291.80936) (xy 86.900246 -291.764084) (xy 86.926549 -291.722488) (xy 86.959184 -291.685651)
			(xy 86.997305 -291.654526) (xy 87.039926 -291.629919) (xy 87.085942 -291.612467) (xy 87.134161 -291.602623)
			(xy 87.183336 -291.600642) (xy 87.232191 -291.606574) (xy 87.279462 -291.620266) (xy 87.323924 -291.641364)
			(xy 87.364427 -291.66932) (xy 87.39992 -291.703412) (xy 87.429485 -291.742756) (xy 87.452356 -291.786333)
			(xy 87.46794 -291.833014) (xy 87.475835 -291.881591) (xy 87.47633 -291.906198) (xy 87.794841 -291.906198)
			(xy 87.798936 -291.85547) (xy 87.811115 -291.806056) (xy 87.831063 -291.759236) (xy 87.858264 -291.716222)
			(xy 87.892012 -291.678128) (xy 87.931434 -291.645941) (xy 87.975508 -291.620495) (xy 88.023094 -291.602448)
			(xy 88.072958 -291.592268) (xy 88.12381 -291.590219) (xy 88.174331 -291.596353) (xy 88.223215 -291.610513)
			(xy 88.269194 -291.63233) (xy 88.311078 -291.66124) (xy 88.347782 -291.696495) (xy 88.378355 -291.737181)
			(xy 88.402006 -291.782244) (xy 88.418122 -291.830518) (xy 88.426286 -291.880752) (xy 88.426798 -291.906198)
			(xy 88.734895 -291.906198) (xy 88.73899 -291.85547) (xy 88.751169 -291.806056) (xy 88.771117 -291.759236)
			(xy 88.798318 -291.716222) (xy 88.832066 -291.678128) (xy 88.871488 -291.645941) (xy 88.915562 -291.620495)
			(xy 88.963148 -291.602448) (xy 89.013012 -291.592268) (xy 89.063864 -291.590219) (xy 89.114385 -291.596353)
			(xy 89.163269 -291.610513) (xy 89.209248 -291.63233) (xy 89.251132 -291.66124) (xy 89.287836 -291.696495)
			(xy 89.318409 -291.737181) (xy 89.34206 -291.782244) (xy 89.358176 -291.830518) (xy 89.36634 -291.880752)
			(xy 89.366852 -291.906198) (xy 89.685126 -291.906198) (xy 89.689086 -291.857144) (xy 89.700863 -291.80936)
			(xy 89.720154 -291.764084) (xy 89.746457 -291.722488) (xy 89.779092 -291.685651) (xy 89.817213 -291.654526)
			(xy 89.859834 -291.629919) (xy 89.90585 -291.612467) (xy 89.954069 -291.602623) (xy 90.003244 -291.600642)
			(xy 90.052099 -291.606574) (xy 90.09937 -291.620266) (xy 90.143832 -291.641364) (xy 90.184335 -291.66932)
			(xy 90.219828 -291.703412) (xy 90.249393 -291.742756) (xy 90.272264 -291.786333) (xy 90.287848 -291.833014)
			(xy 90.295743 -291.881591) (xy 90.296238 -291.906198) (xy 90.614749 -291.906198) (xy 90.618844 -291.85547)
			(xy 90.631023 -291.806056) (xy 90.650971 -291.759236) (xy 90.678172 -291.716222) (xy 90.71192 -291.678128)
			(xy 90.751342 -291.645941) (xy 90.795416 -291.620495) (xy 90.843002 -291.602448) (xy 90.892866 -291.592268)
			(xy 90.943718 -291.590219) (xy 90.994239 -291.596353) (xy 91.043123 -291.610513) (xy 91.089102 -291.63233)
			(xy 91.130986 -291.66124) (xy 91.16769 -291.696495) (xy 91.198263 -291.737181) (xy 91.221914 -291.782244)
			(xy 91.23803 -291.830518) (xy 91.246194 -291.880752) (xy 91.246706 -291.906198) (xy 91.565234 -291.906198)
			(xy 91.569194 -291.857144) (xy 91.580971 -291.80936) (xy 91.600262 -291.764084) (xy 91.626565 -291.722488)
			(xy 91.6592 -291.685651) (xy 91.697321 -291.654526) (xy 91.739942 -291.629919) (xy 91.785958 -291.612467)
			(xy 91.834177 -291.602623) (xy 91.883352 -291.600642) (xy 91.932207 -291.606574) (xy 91.979478 -291.620266)
			(xy 92.02394 -291.641364) (xy 92.064443 -291.66932) (xy 92.099936 -291.703412) (xy 92.129501 -291.742756)
			(xy 92.152372 -291.786333) (xy 92.167956 -291.833014) (xy 92.175851 -291.881591) (xy 92.176346 -291.906198)
			(xy 92.494857 -291.906198) (xy 92.498952 -291.85547) (xy 92.511131 -291.806056) (xy 92.531079 -291.759236)
			(xy 92.55828 -291.716222) (xy 92.592028 -291.678128) (xy 92.63145 -291.645941) (xy 92.675524 -291.620495)
			(xy 92.72311 -291.602448) (xy 92.772974 -291.592268) (xy 92.823826 -291.590219) (xy 92.874347 -291.596353)
			(xy 92.923231 -291.610513) (xy 92.96921 -291.63233) (xy 93.011094 -291.66124) (xy 93.047798 -291.696495)
			(xy 93.078371 -291.737181) (xy 93.102022 -291.782244) (xy 93.118138 -291.830518) (xy 93.126302 -291.880752)
			(xy 93.126814 -291.906198) (xy 93.445342 -291.906198) (xy 93.449302 -291.857144) (xy 93.461079 -291.80936)
			(xy 93.48037 -291.764084) (xy 93.506673 -291.722488) (xy 93.539308 -291.685651) (xy 93.577429 -291.654526)
			(xy 93.62005 -291.629919) (xy 93.666066 -291.612467) (xy 93.714285 -291.602623) (xy 93.76346 -291.600642)
			(xy 93.812315 -291.606574) (xy 93.859586 -291.620266) (xy 93.904048 -291.641364) (xy 93.944551 -291.66932)
			(xy 93.980044 -291.703412) (xy 94.009609 -291.742756) (xy 94.03248 -291.786333) (xy 94.048064 -291.833014)
			(xy 94.055959 -291.881591) (xy 94.056454 -291.906198) (xy 94.374711 -291.906198) (xy 94.378806 -291.85547)
			(xy 94.390985 -291.806056) (xy 94.410933 -291.759236) (xy 94.438134 -291.716222) (xy 94.471882 -291.678128)
			(xy 94.511304 -291.645941) (xy 94.555378 -291.620495) (xy 94.602964 -291.602448) (xy 94.652828 -291.592268)
			(xy 94.70368 -291.590219) (xy 94.754201 -291.596353) (xy 94.803085 -291.610513) (xy 94.849064 -291.63233)
			(xy 94.890948 -291.66124) (xy 94.927652 -291.696495) (xy 94.958225 -291.737181) (xy 94.981876 -291.782244)
			(xy 94.997992 -291.830518) (xy 95.006156 -291.880752) (xy 95.006668 -291.906198) (xy 95.314765 -291.906198)
			(xy 95.31886 -291.85547) (xy 95.331039 -291.806056) (xy 95.350987 -291.759236) (xy 95.378188 -291.716222)
			(xy 95.411936 -291.678128) (xy 95.451358 -291.645941) (xy 95.495432 -291.620495) (xy 95.543018 -291.602448)
			(xy 95.592882 -291.592268) (xy 95.643734 -291.590219) (xy 95.694255 -291.596353) (xy 95.743139 -291.610513)
			(xy 95.789118 -291.63233) (xy 95.831002 -291.66124) (xy 95.867706 -291.696495) (xy 95.898279 -291.737181)
			(xy 95.92193 -291.782244) (xy 95.938046 -291.830518) (xy 95.94621 -291.880752) (xy 95.946722 -291.906198)
			(xy 97.205304 -291.906198) (xy 97.209264 -291.857144) (xy 97.221041 -291.80936) (xy 97.240332 -291.764084)
			(xy 97.266635 -291.722488) (xy 97.29927 -291.685651) (xy 97.337391 -291.654526) (xy 97.380012 -291.629919)
			(xy 97.426028 -291.612467) (xy 97.474247 -291.602623) (xy 97.523422 -291.600642) (xy 97.572277 -291.606574)
			(xy 97.619548 -291.620266) (xy 97.66401 -291.641364) (xy 97.704513 -291.66932) (xy 97.740006 -291.703412)
			(xy 97.769571 -291.742756) (xy 97.792442 -291.786333) (xy 97.808026 -291.833014) (xy 97.815921 -291.881591)
			(xy 97.816416 -291.906198) (xy 98.145358 -291.906198) (xy 98.149318 -291.857144) (xy 98.161095 -291.80936)
			(xy 98.180386 -291.764084) (xy 98.206689 -291.722488) (xy 98.239324 -291.685651) (xy 98.277445 -291.654526)
			(xy 98.320066 -291.629919) (xy 98.366082 -291.612467) (xy 98.414301 -291.602623) (xy 98.463476 -291.600642)
			(xy 98.512331 -291.606574) (xy 98.559602 -291.620266) (xy 98.604064 -291.641364) (xy 98.644567 -291.66932)
			(xy 98.68006 -291.703412) (xy 98.709625 -291.742756) (xy 98.732496 -291.786333) (xy 98.74808 -291.833014)
			(xy 98.755975 -291.881591) (xy 98.75647 -291.906198) (xy 100.025212 -291.906198) (xy 100.029172 -291.857144)
			(xy 100.040949 -291.80936) (xy 100.06024 -291.764084) (xy 100.086543 -291.722488) (xy 100.119178 -291.685651)
			(xy 100.157299 -291.654526) (xy 100.19992 -291.629919) (xy 100.245936 -291.612467) (xy 100.294155 -291.602623)
			(xy 100.34333 -291.600642) (xy 100.392185 -291.606574) (xy 100.439456 -291.620266) (xy 100.483918 -291.641364)
			(xy 100.524421 -291.66932) (xy 100.559914 -291.703412) (xy 100.589479 -291.742756) (xy 100.61235 -291.786333)
			(xy 100.627934 -291.833014) (xy 100.635829 -291.881591) (xy 100.636324 -291.906198) (xy 100.965266 -291.906198)
			(xy 100.969226 -291.857144) (xy 100.981003 -291.80936) (xy 101.000294 -291.764084) (xy 101.026597 -291.722488)
			(xy 101.059232 -291.685651) (xy 101.097353 -291.654526) (xy 101.139974 -291.629919) (xy 101.18599 -291.612467)
			(xy 101.234209 -291.602623) (xy 101.283384 -291.600642) (xy 101.332239 -291.606574) (xy 101.37951 -291.620266)
			(xy 101.423972 -291.641364) (xy 101.464475 -291.66932) (xy 101.499968 -291.703412) (xy 101.529533 -291.742756)
			(xy 101.552404 -291.786333) (xy 101.567988 -291.833014) (xy 101.575883 -291.881591) (xy 101.576378 -291.906198)
			(xy 101.575883 -291.930805) (xy 101.567988 -291.979382) (xy 101.552404 -292.026063) (xy 101.529533 -292.06964)
			(xy 101.499968 -292.108984) (xy 101.464475 -292.143076) (xy 101.423972 -292.171032) (xy 101.37951 -292.19213)
			(xy 101.332239 -292.205822) (xy 101.283384 -292.211754) (xy 101.234209 -292.209773) (xy 101.18599 -292.199929)
			(xy 101.139974 -292.182477) (xy 101.097353 -292.15787) (xy 101.059232 -292.126745) (xy 101.026597 -292.089908)
			(xy 101.000294 -292.048312) (xy 100.981003 -292.003036) (xy 100.969226 -291.955252) (xy 100.965266 -291.906198)
			(xy 100.636324 -291.906198) (xy 100.635829 -291.930805) (xy 100.627934 -291.979382) (xy 100.61235 -292.026063)
			(xy 100.589479 -292.06964) (xy 100.559914 -292.108984) (xy 100.524421 -292.143076) (xy 100.483918 -292.171032)
			(xy 100.439456 -292.19213) (xy 100.392185 -292.205822) (xy 100.34333 -292.211754) (xy 100.294155 -292.209773)
			(xy 100.245936 -292.199929) (xy 100.19992 -292.182477) (xy 100.157299 -292.15787) (xy 100.119178 -292.126745)
			(xy 100.086543 -292.089908) (xy 100.06024 -292.048312) (xy 100.040949 -292.003036) (xy 100.029172 -291.955252)
			(xy 100.025212 -291.906198) (xy 98.75647 -291.906198) (xy 98.755975 -291.930805) (xy 98.74808 -291.979382)
			(xy 98.732496 -292.026063) (xy 98.709625 -292.06964) (xy 98.68006 -292.108984) (xy 98.644567 -292.143076)
			(xy 98.604064 -292.171032) (xy 98.559602 -292.19213) (xy 98.512331 -292.205822) (xy 98.463476 -292.211754)
			(xy 98.414301 -292.209773) (xy 98.366082 -292.199929) (xy 98.320066 -292.182477) (xy 98.277445 -292.15787)
			(xy 98.239324 -292.126745) (xy 98.206689 -292.089908) (xy 98.180386 -292.048312) (xy 98.161095 -292.003036)
			(xy 98.149318 -291.955252) (xy 98.145358 -291.906198) (xy 97.816416 -291.906198) (xy 97.815921 -291.930805)
			(xy 97.808026 -291.979382) (xy 97.792442 -292.026063) (xy 97.769571 -292.06964) (xy 97.740006 -292.108984)
			(xy 97.704513 -292.143076) (xy 97.66401 -292.171032) (xy 97.619548 -292.19213) (xy 97.572277 -292.205822)
			(xy 97.523422 -292.211754) (xy 97.474247 -292.209773) (xy 97.426028 -292.199929) (xy 97.380012 -292.182477)
			(xy 97.337391 -292.15787) (xy 97.29927 -292.126745) (xy 97.266635 -292.089908) (xy 97.240332 -292.048312)
			(xy 97.221041 -292.003036) (xy 97.209264 -291.955252) (xy 97.205304 -291.906198) (xy 95.946722 -291.906198)
			(xy 95.94621 -291.931644) (xy 95.938046 -291.981878) (xy 95.92193 -292.030152) (xy 95.898279 -292.075215)
			(xy 95.867706 -292.115901) (xy 95.831002 -292.151156) (xy 95.789118 -292.180066) (xy 95.743139 -292.201883)
			(xy 95.694255 -292.216043) (xy 95.643734 -292.222177) (xy 95.592882 -292.220128) (xy 95.543018 -292.209948)
			(xy 95.495432 -292.191901) (xy 95.451358 -292.166455) (xy 95.411936 -292.134268) (xy 95.378188 -292.096174)
			(xy 95.350987 -292.05316) (xy 95.331039 -292.00634) (xy 95.31886 -291.956926) (xy 95.314765 -291.906198)
			(xy 95.006668 -291.906198) (xy 95.006156 -291.931644) (xy 94.997992 -291.981878) (xy 94.981876 -292.030152)
			(xy 94.958225 -292.075215) (xy 94.927652 -292.115901) (xy 94.890948 -292.151156) (xy 94.849064 -292.180066)
			(xy 94.803085 -292.201883) (xy 94.754201 -292.216043) (xy 94.70368 -292.222177) (xy 94.652828 -292.220128)
			(xy 94.602964 -292.209948) (xy 94.555378 -292.191901) (xy 94.511304 -292.166455) (xy 94.471882 -292.134268)
			(xy 94.438134 -292.096174) (xy 94.410933 -292.05316) (xy 94.390985 -292.00634) (xy 94.378806 -291.956926)
			(xy 94.374711 -291.906198) (xy 94.056454 -291.906198) (xy 94.055959 -291.930805) (xy 94.048064 -291.979382)
			(xy 94.03248 -292.026063) (xy 94.009609 -292.06964) (xy 93.980044 -292.108984) (xy 93.944551 -292.143076)
			(xy 93.904048 -292.171032) (xy 93.859586 -292.19213) (xy 93.812315 -292.205822) (xy 93.76346 -292.211754)
			(xy 93.714285 -292.209773) (xy 93.666066 -292.199929) (xy 93.62005 -292.182477) (xy 93.577429 -292.15787)
			(xy 93.539308 -292.126745) (xy 93.506673 -292.089908) (xy 93.48037 -292.048312) (xy 93.461079 -292.003036)
			(xy 93.449302 -291.955252) (xy 93.445342 -291.906198) (xy 93.126814 -291.906198) (xy 93.126302 -291.931644)
			(xy 93.118138 -291.981878) (xy 93.102022 -292.030152) (xy 93.078371 -292.075215) (xy 93.047798 -292.115901)
			(xy 93.011094 -292.151156) (xy 92.96921 -292.180066) (xy 92.923231 -292.201883) (xy 92.874347 -292.216043)
			(xy 92.823826 -292.222177) (xy 92.772974 -292.220128) (xy 92.72311 -292.209948) (xy 92.675524 -292.191901)
			(xy 92.63145 -292.166455) (xy 92.592028 -292.134268) (xy 92.55828 -292.096174) (xy 92.531079 -292.05316)
			(xy 92.511131 -292.00634) (xy 92.498952 -291.956926) (xy 92.494857 -291.906198) (xy 92.176346 -291.906198)
			(xy 92.175851 -291.930805) (xy 92.167956 -291.979382) (xy 92.152372 -292.026063) (xy 92.129501 -292.06964)
			(xy 92.099936 -292.108984) (xy 92.064443 -292.143076) (xy 92.02394 -292.171032) (xy 91.979478 -292.19213)
			(xy 91.932207 -292.205822) (xy 91.883352 -292.211754) (xy 91.834177 -292.209773) (xy 91.785958 -292.199929)
			(xy 91.739942 -292.182477) (xy 91.697321 -292.15787) (xy 91.6592 -292.126745) (xy 91.626565 -292.089908)
			(xy 91.600262 -292.048312) (xy 91.580971 -292.003036) (xy 91.569194 -291.955252) (xy 91.565234 -291.906198)
			(xy 91.246706 -291.906198) (xy 91.246194 -291.931644) (xy 91.23803 -291.981878) (xy 91.221914 -292.030152)
			(xy 91.198263 -292.075215) (xy 91.16769 -292.115901) (xy 91.130986 -292.151156) (xy 91.089102 -292.180066)
			(xy 91.043123 -292.201883) (xy 90.994239 -292.216043) (xy 90.943718 -292.222177) (xy 90.892866 -292.220128)
			(xy 90.843002 -292.209948) (xy 90.795416 -292.191901) (xy 90.751342 -292.166455) (xy 90.71192 -292.134268)
			(xy 90.678172 -292.096174) (xy 90.650971 -292.05316) (xy 90.631023 -292.00634) (xy 90.618844 -291.956926)
			(xy 90.614749 -291.906198) (xy 90.296238 -291.906198) (xy 90.295743 -291.930805) (xy 90.287848 -291.979382)
			(xy 90.272264 -292.026063) (xy 90.249393 -292.06964) (xy 90.219828 -292.108984) (xy 90.184335 -292.143076)
			(xy 90.143832 -292.171032) (xy 90.09937 -292.19213) (xy 90.052099 -292.205822) (xy 90.003244 -292.211754)
			(xy 89.954069 -292.209773) (xy 89.90585 -292.199929) (xy 89.859834 -292.182477) (xy 89.817213 -292.15787)
			(xy 89.779092 -292.126745) (xy 89.746457 -292.089908) (xy 89.720154 -292.048312) (xy 89.700863 -292.003036)
			(xy 89.689086 -291.955252) (xy 89.685126 -291.906198) (xy 89.366852 -291.906198) (xy 89.36634 -291.931644)
			(xy 89.358176 -291.981878) (xy 89.34206 -292.030152) (xy 89.318409 -292.075215) (xy 89.287836 -292.115901)
			(xy 89.251132 -292.151156) (xy 89.209248 -292.180066) (xy 89.163269 -292.201883) (xy 89.114385 -292.216043)
			(xy 89.063864 -292.222177) (xy 89.013012 -292.220128) (xy 88.963148 -292.209948) (xy 88.915562 -292.191901)
			(xy 88.871488 -292.166455) (xy 88.832066 -292.134268) (xy 88.798318 -292.096174) (xy 88.771117 -292.05316)
			(xy 88.751169 -292.00634) (xy 88.73899 -291.956926) (xy 88.734895 -291.906198) (xy 88.426798 -291.906198)
			(xy 88.426286 -291.931644) (xy 88.418122 -291.981878) (xy 88.402006 -292.030152) (xy 88.378355 -292.075215)
			(xy 88.347782 -292.115901) (xy 88.311078 -292.151156) (xy 88.269194 -292.180066) (xy 88.223215 -292.201883)
			(xy 88.174331 -292.216043) (xy 88.12381 -292.222177) (xy 88.072958 -292.220128) (xy 88.023094 -292.209948)
			(xy 87.975508 -292.191901) (xy 87.931434 -292.166455) (xy 87.892012 -292.134268) (xy 87.858264 -292.096174)
			(xy 87.831063 -292.05316) (xy 87.811115 -292.00634) (xy 87.798936 -291.956926) (xy 87.794841 -291.906198)
			(xy 87.47633 -291.906198) (xy 87.475835 -291.930805) (xy 87.46794 -291.979382) (xy 87.452356 -292.026063)
			(xy 87.429485 -292.06964) (xy 87.39992 -292.108984) (xy 87.364427 -292.143076) (xy 87.323924 -292.171032)
			(xy 87.279462 -292.19213) (xy 87.232191 -292.205822) (xy 87.183336 -292.211754) (xy 87.134161 -292.209773)
			(xy 87.085942 -292.199929) (xy 87.039926 -292.182477) (xy 86.997305 -292.15787) (xy 86.959184 -292.126745)
			(xy 86.926549 -292.089908) (xy 86.900246 -292.048312) (xy 86.880955 -292.003036) (xy 86.869178 -291.955252)
			(xy 86.865218 -291.906198) (xy 86.54669 -291.906198) (xy 86.546178 -291.931644) (xy 86.538014 -291.981878)
			(xy 86.521898 -292.030152) (xy 86.498247 -292.075215) (xy 86.467674 -292.115901) (xy 86.43097 -292.151156)
			(xy 86.389086 -292.180066) (xy 86.343107 -292.201883) (xy 86.294223 -292.216043) (xy 86.243702 -292.222177)
			(xy 86.19285 -292.220128) (xy 86.142986 -292.209948) (xy 86.0954 -292.191901) (xy 86.051326 -292.166455)
			(xy 86.011904 -292.134268) (xy 85.978156 -292.096174) (xy 85.950955 -292.05316) (xy 85.931007 -292.00634)
			(xy 85.918828 -291.956926) (xy 85.914733 -291.906198) (xy 85.596222 -291.906198) (xy 85.595727 -291.930805)
			(xy 85.587832 -291.979382) (xy 85.572248 -292.026063) (xy 85.549377 -292.06964) (xy 85.519812 -292.108984)
			(xy 85.484319 -292.143076) (xy 85.443816 -292.171032) (xy 85.399354 -292.19213) (xy 85.352083 -292.205822)
			(xy 85.303228 -292.211754) (xy 85.254053 -292.209773) (xy 85.205834 -292.199929) (xy 85.159818 -292.182477)
			(xy 85.117197 -292.15787) (xy 85.079076 -292.126745) (xy 85.046441 -292.089908) (xy 85.020138 -292.048312)
			(xy 85.000847 -292.003036) (xy 84.98907 -291.955252) (xy 84.98511 -291.906198) (xy 84.666836 -291.906198)
			(xy 84.666324 -291.931644) (xy 84.65816 -291.981878) (xy 84.642044 -292.030152) (xy 84.618393 -292.075215)
			(xy 84.58782 -292.115901) (xy 84.551116 -292.151156) (xy 84.509232 -292.180066) (xy 84.463253 -292.201883)
			(xy 84.414369 -292.216043) (xy 84.363848 -292.222177) (xy 84.312996 -292.220128) (xy 84.263132 -292.209948)
			(xy 84.215546 -292.191901) (xy 84.171472 -292.166455) (xy 84.13205 -292.134268) (xy 84.098302 -292.096174)
			(xy 84.071101 -292.05316) (xy 84.051153 -292.00634) (xy 84.038974 -291.956926) (xy 84.034879 -291.906198)
			(xy 83.716368 -291.906198) (xy 83.715873 -291.930805) (xy 83.707978 -291.979382) (xy 83.692394 -292.026063)
			(xy 83.669523 -292.06964) (xy 83.639958 -292.108984) (xy 83.604465 -292.143076) (xy 83.563962 -292.171032)
			(xy 83.5195 -292.19213) (xy 83.472229 -292.205822) (xy 83.423374 -292.211754) (xy 83.374199 -292.209773)
			(xy 83.32598 -292.199929) (xy 83.279964 -292.182477) (xy 83.237343 -292.15787) (xy 83.199222 -292.126745)
			(xy 83.166587 -292.089908) (xy 83.140284 -292.048312) (xy 83.120993 -292.003036) (xy 83.109216 -291.955252)
			(xy 83.105256 -291.906198) (xy 82.786728 -291.906198) (xy 82.786216 -291.931644) (xy 82.778052 -291.981878)
			(xy 82.761936 -292.030152) (xy 82.738285 -292.075215) (xy 82.707712 -292.115901) (xy 82.671008 -292.151156)
			(xy 82.629124 -292.180066) (xy 82.583145 -292.201883) (xy 82.534261 -292.216043) (xy 82.48374 -292.222177)
			(xy 82.432888 -292.220128) (xy 82.383024 -292.209948) (xy 82.335438 -292.191901) (xy 82.291364 -292.166455)
			(xy 82.251942 -292.134268) (xy 82.218194 -292.096174) (xy 82.190993 -292.05316) (xy 82.171045 -292.00634)
			(xy 82.158866 -291.956926) (xy 82.154771 -291.906198) (xy 81.846674 -291.906198) (xy 81.846162 -291.931644)
			(xy 81.837998 -291.981878) (xy 81.821882 -292.030152) (xy 81.798231 -292.075215) (xy 81.767658 -292.115901)
			(xy 81.730954 -292.151156) (xy 81.68907 -292.180066) (xy 81.643091 -292.201883) (xy 81.594207 -292.216043)
			(xy 81.543686 -292.222177) (xy 81.492834 -292.220128) (xy 81.44297 -292.209948) (xy 81.395384 -292.191901)
			(xy 81.35131 -292.166455) (xy 81.311888 -292.134268) (xy 81.27814 -292.096174) (xy 81.250939 -292.05316)
			(xy 81.230991 -292.00634) (xy 81.218812 -291.956926) (xy 81.214717 -291.906198) (xy 80.89646 -291.906198)
			(xy 80.895965 -291.930805) (xy 80.88807 -291.979382) (xy 80.872486 -292.026063) (xy 80.849615 -292.06964)
			(xy 80.82005 -292.108984) (xy 80.784557 -292.143076) (xy 80.744054 -292.171032) (xy 80.699592 -292.19213)
			(xy 80.652321 -292.205822) (xy 80.603466 -292.211754) (xy 80.554291 -292.209773) (xy 80.506072 -292.199929)
			(xy 80.460056 -292.182477) (xy 80.417435 -292.15787) (xy 80.379314 -292.126745) (xy 80.346679 -292.089908)
			(xy 80.320376 -292.048312) (xy 80.301085 -292.003036) (xy 80.289308 -291.955252) (xy 80.285348 -291.906198)
			(xy 79.016352 -291.906198) (xy 79.015857 -291.930805) (xy 79.007962 -291.979382) (xy 78.992378 -292.026063)
			(xy 78.969507 -292.06964) (xy 78.939942 -292.108984) (xy 78.904449 -292.143076) (xy 78.863946 -292.171032)
			(xy 78.819484 -292.19213) (xy 78.772213 -292.205822) (xy 78.723358 -292.211754) (xy 78.674183 -292.209773)
			(xy 78.625964 -292.199929) (xy 78.579948 -292.182477) (xy 78.537327 -292.15787) (xy 78.499206 -292.126745)
			(xy 78.466571 -292.089908) (xy 78.440268 -292.048312) (xy 78.420977 -292.003036) (xy 78.4092 -291.955252)
			(xy 78.40524 -291.906198) (xy 73.228962 -291.906198) (xy 73.228962 -292.450266) (xy 76.807072 -292.450266)
			(xy 76.811032 -292.401212) (xy 76.822809 -292.353428) (xy 76.8421 -292.308152) (xy 76.868403 -292.266556)
			(xy 76.901038 -292.229719) (xy 76.939159 -292.198594) (xy 76.98178 -292.173987) (xy 77.027796 -292.156535)
			(xy 77.076015 -292.146691) (xy 77.12519 -292.14471) (xy 77.174045 -292.150642) (xy 77.221316 -292.164334)
			(xy 77.265778 -292.185432) (xy 77.306281 -292.213388) (xy 77.341774 -292.24748) (xy 77.371339 -292.286824)
			(xy 77.39421 -292.330401) (xy 77.409794 -292.377082) (xy 77.417689 -292.425659) (xy 77.418184 -292.450266)
			(xy 77.417689 -292.474873) (xy 77.409794 -292.52345) (xy 77.39421 -292.570131) (xy 77.371339 -292.613708)
			(xy 77.341774 -292.653052) (xy 77.306281 -292.687144) (xy 77.265778 -292.7151) (xy 77.263451 -292.716204)
			(xy 79.815194 -292.716204) (xy 79.819154 -292.66715) (xy 79.830931 -292.619366) (xy 79.850222 -292.57409)
			(xy 79.876525 -292.532494) (xy 79.90916 -292.495657) (xy 79.947281 -292.464532) (xy 79.989902 -292.439925)
			(xy 80.035918 -292.422473) (xy 80.084137 -292.412629) (xy 80.133312 -292.410648) (xy 80.182167 -292.41658)
			(xy 80.229438 -292.430272) (xy 80.2739 -292.45137) (xy 80.314403 -292.479326) (xy 80.349896 -292.513418)
			(xy 80.379461 -292.552762) (xy 80.402332 -292.596339) (xy 80.417916 -292.64302) (xy 80.425811 -292.691597)
			(xy 80.426306 -292.716204) (xy 80.744817 -292.716204) (xy 80.748912 -292.665476) (xy 80.761091 -292.616062)
			(xy 80.781039 -292.569242) (xy 80.80824 -292.526228) (xy 80.841988 -292.488134) (xy 80.88141 -292.455947)
			(xy 80.925484 -292.430501) (xy 80.97307 -292.412454) (xy 81.022934 -292.402274) (xy 81.073786 -292.400225)
			(xy 81.124307 -292.406359) (xy 81.173191 -292.420519) (xy 81.21917 -292.442336) (xy 81.261054 -292.471246)
			(xy 81.297758 -292.506501) (xy 81.328331 -292.547187) (xy 81.351982 -292.59225) (xy 81.368098 -292.640524)
			(xy 81.376262 -292.690758) (xy 81.376774 -292.716204) (xy 81.695302 -292.716204) (xy 81.699262 -292.66715)
			(xy 81.711039 -292.619366) (xy 81.73033 -292.57409) (xy 81.756633 -292.532494) (xy 81.789268 -292.495657)
			(xy 81.827389 -292.464532) (xy 81.87001 -292.439925) (xy 81.916026 -292.422473) (xy 81.964245 -292.412629)
			(xy 82.01342 -292.410648) (xy 82.062275 -292.41658) (xy 82.109546 -292.430272) (xy 82.154008 -292.45137)
			(xy 82.194511 -292.479326) (xy 82.230004 -292.513418) (xy 82.259569 -292.552762) (xy 82.28244 -292.596339)
			(xy 82.298024 -292.64302) (xy 82.305919 -292.691597) (xy 82.306414 -292.716204) (xy 82.624671 -292.716204)
			(xy 82.628766 -292.665476) (xy 82.640945 -292.616062) (xy 82.660893 -292.569242) (xy 82.688094 -292.526228)
			(xy 82.721842 -292.488134) (xy 82.761264 -292.455947) (xy 82.805338 -292.430501) (xy 82.852924 -292.412454)
			(xy 82.902788 -292.402274) (xy 82.95364 -292.400225) (xy 83.004161 -292.406359) (xy 83.053045 -292.420519)
			(xy 83.099024 -292.442336) (xy 83.140908 -292.471246) (xy 83.177612 -292.506501) (xy 83.208185 -292.547187)
			(xy 83.231836 -292.59225) (xy 83.247952 -292.640524) (xy 83.256116 -292.690758) (xy 83.256628 -292.716204)
			(xy 83.575156 -292.716204) (xy 83.579116 -292.66715) (xy 83.590893 -292.619366) (xy 83.610184 -292.57409)
			(xy 83.636487 -292.532494) (xy 83.669122 -292.495657) (xy 83.707243 -292.464532) (xy 83.749864 -292.439925)
			(xy 83.79588 -292.422473) (xy 83.844099 -292.412629) (xy 83.893274 -292.410648) (xy 83.942129 -292.41658)
			(xy 83.9894 -292.430272) (xy 84.033862 -292.45137) (xy 84.074365 -292.479326) (xy 84.109858 -292.513418)
			(xy 84.139423 -292.552762) (xy 84.162294 -292.596339) (xy 84.177878 -292.64302) (xy 84.185773 -292.691597)
			(xy 84.186268 -292.716204) (xy 84.504779 -292.716204) (xy 84.508874 -292.665476) (xy 84.521053 -292.616062)
			(xy 84.541001 -292.569242) (xy 84.568202 -292.526228) (xy 84.60195 -292.488134) (xy 84.641372 -292.455947)
			(xy 84.685446 -292.430501) (xy 84.733032 -292.412454) (xy 84.782896 -292.402274) (xy 84.833748 -292.400225)
			(xy 84.884269 -292.406359) (xy 84.933153 -292.420519) (xy 84.979132 -292.442336) (xy 85.021016 -292.471246)
			(xy 85.05772 -292.506501) (xy 85.088293 -292.547187) (xy 85.111944 -292.59225) (xy 85.12806 -292.640524)
			(xy 85.136224 -292.690758) (xy 85.136736 -292.716204) (xy 85.444833 -292.716204) (xy 85.448928 -292.665476)
			(xy 85.461107 -292.616062) (xy 85.481055 -292.569242) (xy 85.508256 -292.526228) (xy 85.542004 -292.488134)
			(xy 85.581426 -292.455947) (xy 85.6255 -292.430501) (xy 85.673086 -292.412454) (xy 85.72295 -292.402274)
			(xy 85.773802 -292.400225) (xy 85.824323 -292.406359) (xy 85.873207 -292.420519) (xy 85.919186 -292.442336)
			(xy 85.96107 -292.471246) (xy 85.997774 -292.506501) (xy 86.028347 -292.547187) (xy 86.051998 -292.59225)
			(xy 86.068114 -292.640524) (xy 86.076278 -292.690758) (xy 86.07679 -292.716204) (xy 86.395318 -292.716204)
			(xy 86.399278 -292.66715) (xy 86.411055 -292.619366) (xy 86.430346 -292.57409) (xy 86.456649 -292.532494)
			(xy 86.489284 -292.495657) (xy 86.527405 -292.464532) (xy 86.570026 -292.439925) (xy 86.616042 -292.422473)
			(xy 86.664261 -292.412629) (xy 86.713436 -292.410648) (xy 86.762291 -292.41658) (xy 86.809562 -292.430272)
			(xy 86.854024 -292.45137) (xy 86.894527 -292.479326) (xy 86.93002 -292.513418) (xy 86.959585 -292.552762)
			(xy 86.982456 -292.596339) (xy 86.99804 -292.64302) (xy 87.005935 -292.691597) (xy 87.00643 -292.716204)
			(xy 87.324687 -292.716204) (xy 87.328782 -292.665476) (xy 87.340961 -292.616062) (xy 87.360909 -292.569242)
			(xy 87.38811 -292.526228) (xy 87.421858 -292.488134) (xy 87.46128 -292.455947) (xy 87.505354 -292.430501)
			(xy 87.55294 -292.412454) (xy 87.602804 -292.402274) (xy 87.653656 -292.400225) (xy 87.704177 -292.406359)
			(xy 87.753061 -292.420519) (xy 87.79904 -292.442336) (xy 87.840924 -292.471246) (xy 87.877628 -292.506501)
			(xy 87.908201 -292.547187) (xy 87.931852 -292.59225) (xy 87.947968 -292.640524) (xy 87.956132 -292.690758)
			(xy 87.956644 -292.716204) (xy 88.275172 -292.716204) (xy 88.279132 -292.66715) (xy 88.290909 -292.619366)
			(xy 88.3102 -292.57409) (xy 88.336503 -292.532494) (xy 88.369138 -292.495657) (xy 88.407259 -292.464532)
			(xy 88.44988 -292.439925) (xy 88.495896 -292.422473) (xy 88.544115 -292.412629) (xy 88.59329 -292.410648)
			(xy 88.642145 -292.41658) (xy 88.689416 -292.430272) (xy 88.733878 -292.45137) (xy 88.774381 -292.479326)
			(xy 88.809874 -292.513418) (xy 88.839439 -292.552762) (xy 88.86231 -292.596339) (xy 88.877894 -292.64302)
			(xy 88.885789 -292.691597) (xy 88.886284 -292.716204) (xy 89.204795 -292.716204) (xy 89.20889 -292.665476)
			(xy 89.221069 -292.616062) (xy 89.241017 -292.569242) (xy 89.268218 -292.526228) (xy 89.301966 -292.488134)
			(xy 89.341388 -292.455947) (xy 89.385462 -292.430501) (xy 89.433048 -292.412454) (xy 89.482912 -292.402274)
			(xy 89.533764 -292.400225) (xy 89.584285 -292.406359) (xy 89.633169 -292.420519) (xy 89.679148 -292.442336)
			(xy 89.721032 -292.471246) (xy 89.757736 -292.506501) (xy 89.788309 -292.547187) (xy 89.81196 -292.59225)
			(xy 89.828076 -292.640524) (xy 89.83624 -292.690758) (xy 89.836752 -292.716204) (xy 90.15528 -292.716204)
			(xy 90.15924 -292.66715) (xy 90.171017 -292.619366) (xy 90.190308 -292.57409) (xy 90.216611 -292.532494)
			(xy 90.249246 -292.495657) (xy 90.287367 -292.464532) (xy 90.329988 -292.439925) (xy 90.376004 -292.422473)
			(xy 90.424223 -292.412629) (xy 90.473398 -292.410648) (xy 90.522253 -292.41658) (xy 90.569524 -292.430272)
			(xy 90.613986 -292.45137) (xy 90.654489 -292.479326) (xy 90.689982 -292.513418) (xy 90.719547 -292.552762)
			(xy 90.742418 -292.596339) (xy 90.758002 -292.64302) (xy 90.765897 -292.691597) (xy 90.766392 -292.716204)
			(xy 91.084903 -292.716204) (xy 91.088998 -292.665476) (xy 91.101177 -292.616062) (xy 91.121125 -292.569242)
			(xy 91.148326 -292.526228) (xy 91.182074 -292.488134) (xy 91.221496 -292.455947) (xy 91.26557 -292.430501)
			(xy 91.313156 -292.412454) (xy 91.36302 -292.402274) (xy 91.413872 -292.400225) (xy 91.464393 -292.406359)
			(xy 91.513277 -292.420519) (xy 91.559256 -292.442336) (xy 91.60114 -292.471246) (xy 91.637844 -292.506501)
			(xy 91.668417 -292.547187) (xy 91.692068 -292.59225) (xy 91.708184 -292.640524) (xy 91.716348 -292.690758)
			(xy 91.71686 -292.716204) (xy 92.024703 -292.716204) (xy 92.028798 -292.665476) (xy 92.040977 -292.616062)
			(xy 92.060925 -292.569242) (xy 92.088126 -292.526228) (xy 92.121874 -292.488134) (xy 92.161296 -292.455947)
			(xy 92.20537 -292.430501) (xy 92.252956 -292.412454) (xy 92.30282 -292.402274) (xy 92.353672 -292.400225)
			(xy 92.404193 -292.406359) (xy 92.453077 -292.420519) (xy 92.499056 -292.442336) (xy 92.54094 -292.471246)
			(xy 92.577644 -292.506501) (xy 92.608217 -292.547187) (xy 92.631868 -292.59225) (xy 92.647984 -292.640524)
			(xy 92.656148 -292.690758) (xy 92.65666 -292.716204) (xy 92.975188 -292.716204) (xy 92.979148 -292.66715)
			(xy 92.990925 -292.619366) (xy 93.010216 -292.57409) (xy 93.036519 -292.532494) (xy 93.069154 -292.495657)
			(xy 93.107275 -292.464532) (xy 93.149896 -292.439925) (xy 93.195912 -292.422473) (xy 93.244131 -292.412629)
			(xy 93.293306 -292.410648) (xy 93.342161 -292.41658) (xy 93.389432 -292.430272) (xy 93.433894 -292.45137)
			(xy 93.474397 -292.479326) (xy 93.50989 -292.513418) (xy 93.539455 -292.552762) (xy 93.562326 -292.596339)
			(xy 93.57791 -292.64302) (xy 93.585805 -292.691597) (xy 93.5863 -292.716204) (xy 93.904811 -292.716204)
			(xy 93.908906 -292.665476) (xy 93.921085 -292.616062) (xy 93.941033 -292.569242) (xy 93.968234 -292.526228)
			(xy 94.001982 -292.488134) (xy 94.041404 -292.455947) (xy 94.085478 -292.430501) (xy 94.133064 -292.412454)
			(xy 94.182928 -292.402274) (xy 94.23378 -292.400225) (xy 94.284301 -292.406359) (xy 94.333185 -292.420519)
			(xy 94.379164 -292.442336) (xy 94.421048 -292.471246) (xy 94.457752 -292.506501) (xy 94.488325 -292.547187)
			(xy 94.511976 -292.59225) (xy 94.528092 -292.640524) (xy 94.536256 -292.690758) (xy 94.536768 -292.716204)
			(xy 94.855296 -292.716204) (xy 94.859256 -292.66715) (xy 94.871033 -292.619366) (xy 94.890324 -292.57409)
			(xy 94.916627 -292.532494) (xy 94.949262 -292.495657) (xy 94.987383 -292.464532) (xy 95.030004 -292.439925)
			(xy 95.07602 -292.422473) (xy 95.124239 -292.412629) (xy 95.173414 -292.410648) (xy 95.222269 -292.41658)
			(xy 95.26954 -292.430272) (xy 95.314002 -292.45137) (xy 95.354505 -292.479326) (xy 95.389998 -292.513418)
			(xy 95.419563 -292.552762) (xy 95.442434 -292.596339) (xy 95.458018 -292.64302) (xy 95.465913 -292.691597)
			(xy 95.466408 -292.716204) (xy 95.784919 -292.716204) (xy 95.789014 -292.665476) (xy 95.801193 -292.616062)
			(xy 95.821141 -292.569242) (xy 95.848342 -292.526228) (xy 95.88209 -292.488134) (xy 95.921512 -292.455947)
			(xy 95.965586 -292.430501) (xy 96.013172 -292.412454) (xy 96.063036 -292.402274) (xy 96.113888 -292.400225)
			(xy 96.164409 -292.406359) (xy 96.213293 -292.420519) (xy 96.259272 -292.442336) (xy 96.301156 -292.471246)
			(xy 96.33786 -292.506501) (xy 96.368433 -292.547187) (xy 96.392084 -292.59225) (xy 96.4082 -292.640524)
			(xy 96.416364 -292.690758) (xy 96.416876 -292.716204) (xy 97.664773 -292.716204) (xy 97.668868 -292.665476)
			(xy 97.681047 -292.616062) (xy 97.700995 -292.569242) (xy 97.728196 -292.526228) (xy 97.761944 -292.488134)
			(xy 97.801366 -292.455947) (xy 97.84544 -292.430501) (xy 97.893026 -292.412454) (xy 97.94289 -292.402274)
			(xy 97.993742 -292.400225) (xy 98.044263 -292.406359) (xy 98.093147 -292.420519) (xy 98.139126 -292.442336)
			(xy 98.18101 -292.471246) (xy 98.217714 -292.506501) (xy 98.248287 -292.547187) (xy 98.271938 -292.59225)
			(xy 98.288054 -292.640524) (xy 98.296218 -292.690758) (xy 98.29673 -292.716204) (xy 98.604827 -292.716204)
			(xy 98.608922 -292.665476) (xy 98.621101 -292.616062) (xy 98.641049 -292.569242) (xy 98.66825 -292.526228)
			(xy 98.701998 -292.488134) (xy 98.74142 -292.455947) (xy 98.785494 -292.430501) (xy 98.83308 -292.412454)
			(xy 98.882944 -292.402274) (xy 98.933796 -292.400225) (xy 98.984317 -292.406359) (xy 99.033201 -292.420519)
			(xy 99.07918 -292.442336) (xy 99.121064 -292.471246) (xy 99.157768 -292.506501) (xy 99.188341 -292.547187)
			(xy 99.211992 -292.59225) (xy 99.228108 -292.640524) (xy 99.236272 -292.690758) (xy 99.236784 -292.716204)
			(xy 100.484935 -292.716204) (xy 100.48903 -292.665476) (xy 100.501209 -292.616062) (xy 100.521157 -292.569242)
			(xy 100.548358 -292.526228) (xy 100.582106 -292.488134) (xy 100.621528 -292.455947) (xy 100.665602 -292.430501)
			(xy 100.713188 -292.412454) (xy 100.763052 -292.402274) (xy 100.813904 -292.400225) (xy 100.864425 -292.406359)
			(xy 100.913309 -292.420519) (xy 100.959288 -292.442336) (xy 101.001172 -292.471246) (xy 101.037876 -292.506501)
			(xy 101.068449 -292.547187) (xy 101.0921 -292.59225) (xy 101.108216 -292.640524) (xy 101.11638 -292.690758)
			(xy 101.116892 -292.716204) (xy 101.424735 -292.716204) (xy 101.42883 -292.665476) (xy 101.441009 -292.616062)
			(xy 101.460957 -292.569242) (xy 101.488158 -292.526228) (xy 101.521906 -292.488134) (xy 101.561328 -292.455947)
			(xy 101.605402 -292.430501) (xy 101.652988 -292.412454) (xy 101.702852 -292.402274) (xy 101.753704 -292.400225)
			(xy 101.804225 -292.406359) (xy 101.853109 -292.420519) (xy 101.899088 -292.442336) (xy 101.940972 -292.471246)
			(xy 101.977676 -292.506501) (xy 102.008249 -292.547187) (xy 102.0319 -292.59225) (xy 102.048016 -292.640524)
			(xy 102.05618 -292.690758) (xy 102.056692 -292.716204) (xy 102.05618 -292.74165) (xy 102.048016 -292.791884)
			(xy 102.0319 -292.840158) (xy 102.008249 -292.885221) (xy 101.977676 -292.925907) (xy 101.940972 -292.961162)
			(xy 101.899088 -292.990072) (xy 101.853109 -293.011889) (xy 101.804225 -293.026049) (xy 101.753704 -293.032183)
			(xy 101.702852 -293.030134) (xy 101.652988 -293.019954) (xy 101.605402 -293.001907) (xy 101.561328 -292.976461)
			(xy 101.521906 -292.944274) (xy 101.488158 -292.90618) (xy 101.460957 -292.863166) (xy 101.441009 -292.816346)
			(xy 101.42883 -292.766932) (xy 101.424735 -292.716204) (xy 101.116892 -292.716204) (xy 101.11638 -292.74165)
			(xy 101.108216 -292.791884) (xy 101.0921 -292.840158) (xy 101.068449 -292.885221) (xy 101.037876 -292.925907)
			(xy 101.001172 -292.961162) (xy 100.959288 -292.990072) (xy 100.913309 -293.011889) (xy 100.864425 -293.026049)
			(xy 100.813904 -293.032183) (xy 100.763052 -293.030134) (xy 100.713188 -293.019954) (xy 100.665602 -293.001907)
			(xy 100.621528 -292.976461) (xy 100.582106 -292.944274) (xy 100.548358 -292.90618) (xy 100.521157 -292.863166)
			(xy 100.501209 -292.816346) (xy 100.48903 -292.766932) (xy 100.484935 -292.716204) (xy 99.236784 -292.716204)
			(xy 99.236272 -292.74165) (xy 99.228108 -292.791884) (xy 99.211992 -292.840158) (xy 99.188341 -292.885221)
			(xy 99.157768 -292.925907) (xy 99.121064 -292.961162) (xy 99.07918 -292.990072) (xy 99.033201 -293.011889)
			(xy 98.984317 -293.026049) (xy 98.933796 -293.032183) (xy 98.882944 -293.030134) (xy 98.83308 -293.019954)
			(xy 98.785494 -293.001907) (xy 98.74142 -292.976461) (xy 98.701998 -292.944274) (xy 98.66825 -292.90618)
			(xy 98.641049 -292.863166) (xy 98.621101 -292.816346) (xy 98.608922 -292.766932) (xy 98.604827 -292.716204)
			(xy 98.29673 -292.716204) (xy 98.296218 -292.74165) (xy 98.288054 -292.791884) (xy 98.271938 -292.840158)
			(xy 98.248287 -292.885221) (xy 98.217714 -292.925907) (xy 98.18101 -292.961162) (xy 98.139126 -292.990072)
			(xy 98.093147 -293.011889) (xy 98.044263 -293.026049) (xy 97.993742 -293.032183) (xy 97.94289 -293.030134)
			(xy 97.893026 -293.019954) (xy 97.84544 -293.001907) (xy 97.801366 -292.976461) (xy 97.761944 -292.944274)
			(xy 97.728196 -292.90618) (xy 97.700995 -292.863166) (xy 97.681047 -292.816346) (xy 97.668868 -292.766932)
			(xy 97.664773 -292.716204) (xy 96.416876 -292.716204) (xy 96.416364 -292.74165) (xy 96.4082 -292.791884)
			(xy 96.392084 -292.840158) (xy 96.368433 -292.885221) (xy 96.33786 -292.925907) (xy 96.301156 -292.961162)
			(xy 96.259272 -292.990072) (xy 96.213293 -293.011889) (xy 96.164409 -293.026049) (xy 96.113888 -293.032183)
			(xy 96.063036 -293.030134) (xy 96.013172 -293.019954) (xy 95.965586 -293.001907) (xy 95.921512 -292.976461)
			(xy 95.88209 -292.944274) (xy 95.848342 -292.90618) (xy 95.821141 -292.863166) (xy 95.801193 -292.816346)
			(xy 95.789014 -292.766932) (xy 95.784919 -292.716204) (xy 95.466408 -292.716204) (xy 95.465913 -292.740811)
			(xy 95.458018 -292.789388) (xy 95.442434 -292.836069) (xy 95.419563 -292.879646) (xy 95.389998 -292.91899)
			(xy 95.354505 -292.953082) (xy 95.314002 -292.981038) (xy 95.26954 -293.002136) (xy 95.222269 -293.015828)
			(xy 95.173414 -293.02176) (xy 95.124239 -293.019779) (xy 95.07602 -293.009935) (xy 95.030004 -292.992483)
			(xy 94.987383 -292.967876) (xy 94.949262 -292.936751) (xy 94.916627 -292.899914) (xy 94.890324 -292.858318)
			(xy 94.871033 -292.813042) (xy 94.859256 -292.765258) (xy 94.855296 -292.716204) (xy 94.536768 -292.716204)
			(xy 94.536256 -292.74165) (xy 94.528092 -292.791884) (xy 94.511976 -292.840158) (xy 94.488325 -292.885221)
			(xy 94.457752 -292.925907) (xy 94.421048 -292.961162) (xy 94.379164 -292.990072) (xy 94.333185 -293.011889)
			(xy 94.284301 -293.026049) (xy 94.23378 -293.032183) (xy 94.182928 -293.030134) (xy 94.133064 -293.019954)
			(xy 94.085478 -293.001907) (xy 94.041404 -292.976461) (xy 94.001982 -292.944274) (xy 93.968234 -292.90618)
			(xy 93.941033 -292.863166) (xy 93.921085 -292.816346) (xy 93.908906 -292.766932) (xy 93.904811 -292.716204)
			(xy 93.5863 -292.716204) (xy 93.585805 -292.740811) (xy 93.57791 -292.789388) (xy 93.562326 -292.836069)
			(xy 93.539455 -292.879646) (xy 93.50989 -292.91899) (xy 93.474397 -292.953082) (xy 93.433894 -292.981038)
			(xy 93.389432 -293.002136) (xy 93.342161 -293.015828) (xy 93.293306 -293.02176) (xy 93.244131 -293.019779)
			(xy 93.195912 -293.009935) (xy 93.149896 -292.992483) (xy 93.107275 -292.967876) (xy 93.069154 -292.936751)
			(xy 93.036519 -292.899914) (xy 93.010216 -292.858318) (xy 92.990925 -292.813042) (xy 92.979148 -292.765258)
			(xy 92.975188 -292.716204) (xy 92.65666 -292.716204) (xy 92.656148 -292.74165) (xy 92.647984 -292.791884)
			(xy 92.631868 -292.840158) (xy 92.608217 -292.885221) (xy 92.577644 -292.925907) (xy 92.54094 -292.961162)
			(xy 92.499056 -292.990072) (xy 92.453077 -293.011889) (xy 92.404193 -293.026049) (xy 92.353672 -293.032183)
			(xy 92.30282 -293.030134) (xy 92.252956 -293.019954) (xy 92.20537 -293.001907) (xy 92.161296 -292.976461)
			(xy 92.121874 -292.944274) (xy 92.088126 -292.90618) (xy 92.060925 -292.863166) (xy 92.040977 -292.816346)
			(xy 92.028798 -292.766932) (xy 92.024703 -292.716204) (xy 91.71686 -292.716204) (xy 91.716348 -292.74165)
			(xy 91.708184 -292.791884) (xy 91.692068 -292.840158) (xy 91.668417 -292.885221) (xy 91.637844 -292.925907)
			(xy 91.60114 -292.961162) (xy 91.559256 -292.990072) (xy 91.513277 -293.011889) (xy 91.464393 -293.026049)
			(xy 91.413872 -293.032183) (xy 91.36302 -293.030134) (xy 91.313156 -293.019954) (xy 91.26557 -293.001907)
			(xy 91.221496 -292.976461) (xy 91.182074 -292.944274) (xy 91.148326 -292.90618) (xy 91.121125 -292.863166)
			(xy 91.101177 -292.816346) (xy 91.088998 -292.766932) (xy 91.084903 -292.716204) (xy 90.766392 -292.716204)
			(xy 90.765897 -292.740811) (xy 90.758002 -292.789388) (xy 90.742418 -292.836069) (xy 90.719547 -292.879646)
			(xy 90.689982 -292.91899) (xy 90.654489 -292.953082) (xy 90.613986 -292.981038) (xy 90.569524 -293.002136)
			(xy 90.522253 -293.015828) (xy 90.473398 -293.02176) (xy 90.424223 -293.019779) (xy 90.376004 -293.009935)
			(xy 90.329988 -292.992483) (xy 90.287367 -292.967876) (xy 90.249246 -292.936751) (xy 90.216611 -292.899914)
			(xy 90.190308 -292.858318) (xy 90.171017 -292.813042) (xy 90.15924 -292.765258) (xy 90.15528 -292.716204)
			(xy 89.836752 -292.716204) (xy 89.83624 -292.74165) (xy 89.828076 -292.791884) (xy 89.81196 -292.840158)
			(xy 89.788309 -292.885221) (xy 89.757736 -292.925907) (xy 89.721032 -292.961162) (xy 89.679148 -292.990072)
			(xy 89.633169 -293.011889) (xy 89.584285 -293.026049) (xy 89.533764 -293.032183) (xy 89.482912 -293.030134)
			(xy 89.433048 -293.019954) (xy 89.385462 -293.001907) (xy 89.341388 -292.976461) (xy 89.301966 -292.944274)
			(xy 89.268218 -292.90618) (xy 89.241017 -292.863166) (xy 89.221069 -292.816346) (xy 89.20889 -292.766932)
			(xy 89.204795 -292.716204) (xy 88.886284 -292.716204) (xy 88.885789 -292.740811) (xy 88.877894 -292.789388)
			(xy 88.86231 -292.836069) (xy 88.839439 -292.879646) (xy 88.809874 -292.91899) (xy 88.774381 -292.953082)
			(xy 88.733878 -292.981038) (xy 88.689416 -293.002136) (xy 88.642145 -293.015828) (xy 88.59329 -293.02176)
			(xy 88.544115 -293.019779) (xy 88.495896 -293.009935) (xy 88.44988 -292.992483) (xy 88.407259 -292.967876)
			(xy 88.369138 -292.936751) (xy 88.336503 -292.899914) (xy 88.3102 -292.858318) (xy 88.290909 -292.813042)
			(xy 88.279132 -292.765258) (xy 88.275172 -292.716204) (xy 87.956644 -292.716204) (xy 87.956132 -292.74165)
			(xy 87.947968 -292.791884) (xy 87.931852 -292.840158) (xy 87.908201 -292.885221) (xy 87.877628 -292.925907)
			(xy 87.840924 -292.961162) (xy 87.79904 -292.990072) (xy 87.753061 -293.011889) (xy 87.704177 -293.026049)
			(xy 87.653656 -293.032183) (xy 87.602804 -293.030134) (xy 87.55294 -293.019954) (xy 87.505354 -293.001907)
			(xy 87.46128 -292.976461) (xy 87.421858 -292.944274) (xy 87.38811 -292.90618) (xy 87.360909 -292.863166)
			(xy 87.340961 -292.816346) (xy 87.328782 -292.766932) (xy 87.324687 -292.716204) (xy 87.00643 -292.716204)
			(xy 87.005935 -292.740811) (xy 86.99804 -292.789388) (xy 86.982456 -292.836069) (xy 86.959585 -292.879646)
			(xy 86.93002 -292.91899) (xy 86.894527 -292.953082) (xy 86.854024 -292.981038) (xy 86.809562 -293.002136)
			(xy 86.762291 -293.015828) (xy 86.713436 -293.02176) (xy 86.664261 -293.019779) (xy 86.616042 -293.009935)
			(xy 86.570026 -292.992483) (xy 86.527405 -292.967876) (xy 86.489284 -292.936751) (xy 86.456649 -292.899914)
			(xy 86.430346 -292.858318) (xy 86.411055 -292.813042) (xy 86.399278 -292.765258) (xy 86.395318 -292.716204)
			(xy 86.07679 -292.716204) (xy 86.076278 -292.74165) (xy 86.068114 -292.791884) (xy 86.051998 -292.840158)
			(xy 86.028347 -292.885221) (xy 85.997774 -292.925907) (xy 85.96107 -292.961162) (xy 85.919186 -292.990072)
			(xy 85.873207 -293.011889) (xy 85.824323 -293.026049) (xy 85.773802 -293.032183) (xy 85.72295 -293.030134)
			(xy 85.673086 -293.019954) (xy 85.6255 -293.001907) (xy 85.581426 -292.976461) (xy 85.542004 -292.944274)
			(xy 85.508256 -292.90618) (xy 85.481055 -292.863166) (xy 85.461107 -292.816346) (xy 85.448928 -292.766932)
			(xy 85.444833 -292.716204) (xy 85.136736 -292.716204) (xy 85.136224 -292.74165) (xy 85.12806 -292.791884)
			(xy 85.111944 -292.840158) (xy 85.088293 -292.885221) (xy 85.05772 -292.925907) (xy 85.021016 -292.961162)
			(xy 84.979132 -292.990072) (xy 84.933153 -293.011889) (xy 84.884269 -293.026049) (xy 84.833748 -293.032183)
			(xy 84.782896 -293.030134) (xy 84.733032 -293.019954) (xy 84.685446 -293.001907) (xy 84.641372 -292.976461)
			(xy 84.60195 -292.944274) (xy 84.568202 -292.90618) (xy 84.541001 -292.863166) (xy 84.521053 -292.816346)
			(xy 84.508874 -292.766932) (xy 84.504779 -292.716204) (xy 84.186268 -292.716204) (xy 84.185773 -292.740811)
			(xy 84.177878 -292.789388) (xy 84.162294 -292.836069) (xy 84.139423 -292.879646) (xy 84.109858 -292.91899)
			(xy 84.074365 -292.953082) (xy 84.033862 -292.981038) (xy 83.9894 -293.002136) (xy 83.942129 -293.015828)
			(xy 83.893274 -293.02176) (xy 83.844099 -293.019779) (xy 83.79588 -293.009935) (xy 83.749864 -292.992483)
			(xy 83.707243 -292.967876) (xy 83.669122 -292.936751) (xy 83.636487 -292.899914) (xy 83.610184 -292.858318)
			(xy 83.590893 -292.813042) (xy 83.579116 -292.765258) (xy 83.575156 -292.716204) (xy 83.256628 -292.716204)
			(xy 83.256116 -292.74165) (xy 83.247952 -292.791884) (xy 83.231836 -292.840158) (xy 83.208185 -292.885221)
			(xy 83.177612 -292.925907) (xy 83.140908 -292.961162) (xy 83.099024 -292.990072) (xy 83.053045 -293.011889)
			(xy 83.004161 -293.026049) (xy 82.95364 -293.032183) (xy 82.902788 -293.030134) (xy 82.852924 -293.019954)
			(xy 82.805338 -293.001907) (xy 82.761264 -292.976461) (xy 82.721842 -292.944274) (xy 82.688094 -292.90618)
			(xy 82.660893 -292.863166) (xy 82.640945 -292.816346) (xy 82.628766 -292.766932) (xy 82.624671 -292.716204)
			(xy 82.306414 -292.716204) (xy 82.305919 -292.740811) (xy 82.298024 -292.789388) (xy 82.28244 -292.836069)
			(xy 82.259569 -292.879646) (xy 82.230004 -292.91899) (xy 82.194511 -292.953082) (xy 82.154008 -292.981038)
			(xy 82.109546 -293.002136) (xy 82.062275 -293.015828) (xy 82.01342 -293.02176) (xy 81.964245 -293.019779)
			(xy 81.916026 -293.009935) (xy 81.87001 -292.992483) (xy 81.827389 -292.967876) (xy 81.789268 -292.936751)
			(xy 81.756633 -292.899914) (xy 81.73033 -292.858318) (xy 81.711039 -292.813042) (xy 81.699262 -292.765258)
			(xy 81.695302 -292.716204) (xy 81.376774 -292.716204) (xy 81.376262 -292.74165) (xy 81.368098 -292.791884)
			(xy 81.351982 -292.840158) (xy 81.328331 -292.885221) (xy 81.297758 -292.925907) (xy 81.261054 -292.961162)
			(xy 81.21917 -292.990072) (xy 81.173191 -293.011889) (xy 81.124307 -293.026049) (xy 81.073786 -293.032183)
			(xy 81.022934 -293.030134) (xy 80.97307 -293.019954) (xy 80.925484 -293.001907) (xy 80.88141 -292.976461)
			(xy 80.841988 -292.944274) (xy 80.80824 -292.90618) (xy 80.781039 -292.863166) (xy 80.761091 -292.816346)
			(xy 80.748912 -292.766932) (xy 80.744817 -292.716204) (xy 80.426306 -292.716204) (xy 80.425811 -292.740811)
			(xy 80.417916 -292.789388) (xy 80.402332 -292.836069) (xy 80.379461 -292.879646) (xy 80.349896 -292.91899)
			(xy 80.314403 -292.953082) (xy 80.2739 -292.981038) (xy 80.229438 -293.002136) (xy 80.182167 -293.015828)
			(xy 80.133312 -293.02176) (xy 80.084137 -293.019779) (xy 80.035918 -293.009935) (xy 79.989902 -292.992483)
			(xy 79.947281 -292.967876) (xy 79.90916 -292.936751) (xy 79.876525 -292.899914) (xy 79.850222 -292.858318)
			(xy 79.830931 -292.813042) (xy 79.819154 -292.765258) (xy 79.815194 -292.716204) (xy 77.263451 -292.716204)
			(xy 77.221316 -292.736198) (xy 77.174045 -292.74989) (xy 77.12519 -292.755822) (xy 77.076015 -292.753841)
			(xy 77.027796 -292.743997) (xy 76.98178 -292.726545) (xy 76.939159 -292.701938) (xy 76.901038 -292.670813)
			(xy 76.868403 -292.633976) (xy 76.8421 -292.59238) (xy 76.822809 -292.547104) (xy 76.811032 -292.49932)
			(xy 76.807072 -292.450266) (xy 73.228962 -292.450266) (xy 73.228962 -293.52621) (xy 78.40524 -293.52621)
			(xy 78.4092 -293.477156) (xy 78.420977 -293.429372) (xy 78.440268 -293.384096) (xy 78.466571 -293.3425)
			(xy 78.499206 -293.305663) (xy 78.537327 -293.274538) (xy 78.579948 -293.249931) (xy 78.625964 -293.232479)
			(xy 78.674183 -293.222635) (xy 78.723358 -293.220654) (xy 78.772213 -293.226586) (xy 78.819484 -293.240278)
			(xy 78.863946 -293.261376) (xy 78.904449 -293.289332) (xy 78.939942 -293.323424) (xy 78.969507 -293.362768)
			(xy 78.992378 -293.406345) (xy 79.007962 -293.453026) (xy 79.015857 -293.501603) (xy 79.016352 -293.52621)
			(xy 79.345294 -293.52621) (xy 79.349254 -293.477156) (xy 79.361031 -293.429372) (xy 79.380322 -293.384096)
			(xy 79.406625 -293.3425) (xy 79.43926 -293.305663) (xy 79.477381 -293.274538) (xy 79.520002 -293.249931)
			(xy 79.566018 -293.232479) (xy 79.614237 -293.222635) (xy 79.663412 -293.220654) (xy 79.712267 -293.226586)
			(xy 79.759538 -293.240278) (xy 79.804 -293.261376) (xy 79.844503 -293.289332) (xy 79.879996 -293.323424)
			(xy 79.909561 -293.362768) (xy 79.932432 -293.406345) (xy 79.948016 -293.453026) (xy 79.955911 -293.501603)
			(xy 79.956406 -293.52621) (xy 80.285348 -293.52621) (xy 80.289308 -293.477156) (xy 80.301085 -293.429372)
			(xy 80.320376 -293.384096) (xy 80.346679 -293.3425) (xy 80.379314 -293.305663) (xy 80.417435 -293.274538)
			(xy 80.460056 -293.249931) (xy 80.506072 -293.232479) (xy 80.554291 -293.222635) (xy 80.603466 -293.220654)
			(xy 80.652321 -293.226586) (xy 80.699592 -293.240278) (xy 80.744054 -293.261376) (xy 80.784557 -293.289332)
			(xy 80.82005 -293.323424) (xy 80.849615 -293.362768) (xy 80.872486 -293.406345) (xy 80.88807 -293.453026)
			(xy 80.895965 -293.501603) (xy 80.89646 -293.52621) (xy 81.225148 -293.52621) (xy 81.229108 -293.477156)
			(xy 81.240885 -293.429372) (xy 81.260176 -293.384096) (xy 81.286479 -293.3425) (xy 81.319114 -293.305663)
			(xy 81.357235 -293.274538) (xy 81.399856 -293.249931) (xy 81.445872 -293.232479) (xy 81.494091 -293.222635)
			(xy 81.543266 -293.220654) (xy 81.592121 -293.226586) (xy 81.639392 -293.240278) (xy 81.683854 -293.261376)
			(xy 81.724357 -293.289332) (xy 81.75985 -293.323424) (xy 81.789415 -293.362768) (xy 81.812286 -293.406345)
			(xy 81.82787 -293.453026) (xy 81.835765 -293.501603) (xy 81.83626 -293.52621) (xy 82.154771 -293.52621)
			(xy 82.158866 -293.475482) (xy 82.171045 -293.426068) (xy 82.190993 -293.379248) (xy 82.218194 -293.336234)
			(xy 82.251942 -293.29814) (xy 82.291364 -293.265953) (xy 82.335438 -293.240507) (xy 82.383024 -293.22246)
			(xy 82.432888 -293.21228) (xy 82.48374 -293.210231) (xy 82.534261 -293.216365) (xy 82.583145 -293.230525)
			(xy 82.629124 -293.252342) (xy 82.671008 -293.281252) (xy 82.707712 -293.316507) (xy 82.738285 -293.357193)
			(xy 82.761936 -293.402256) (xy 82.778052 -293.45053) (xy 82.786216 -293.500764) (xy 82.786728 -293.52621)
			(xy 83.105256 -293.52621) (xy 83.109216 -293.477156) (xy 83.120993 -293.429372) (xy 83.140284 -293.384096)
			(xy 83.166587 -293.3425) (xy 83.199222 -293.305663) (xy 83.237343 -293.274538) (xy 83.279964 -293.249931)
			(xy 83.32598 -293.232479) (xy 83.374199 -293.222635) (xy 83.423374 -293.220654) (xy 83.472229 -293.226586)
			(xy 83.5195 -293.240278) (xy 83.563962 -293.261376) (xy 83.604465 -293.289332) (xy 83.639958 -293.323424)
			(xy 83.669523 -293.362768) (xy 83.692394 -293.406345) (xy 83.707978 -293.453026) (xy 83.715873 -293.501603)
			(xy 83.716368 -293.52621) (xy 84.034879 -293.52621) (xy 84.038974 -293.475482) (xy 84.051153 -293.426068)
			(xy 84.071101 -293.379248) (xy 84.098302 -293.336234) (xy 84.13205 -293.29814) (xy 84.171472 -293.265953)
			(xy 84.215546 -293.240507) (xy 84.263132 -293.22246) (xy 84.312996 -293.21228) (xy 84.363848 -293.210231)
			(xy 84.414369 -293.216365) (xy 84.463253 -293.230525) (xy 84.509232 -293.252342) (xy 84.551116 -293.281252)
			(xy 84.58782 -293.316507) (xy 84.618393 -293.357193) (xy 84.642044 -293.402256) (xy 84.65816 -293.45053)
			(xy 84.666324 -293.500764) (xy 84.666836 -293.52621) (xy 84.98511 -293.52621) (xy 84.98907 -293.477156)
			(xy 85.000847 -293.429372) (xy 85.020138 -293.384096) (xy 85.046441 -293.3425) (xy 85.079076 -293.305663)
			(xy 85.117197 -293.274538) (xy 85.159818 -293.249931) (xy 85.205834 -293.232479) (xy 85.254053 -293.222635)
			(xy 85.303228 -293.220654) (xy 85.352083 -293.226586) (xy 85.399354 -293.240278) (xy 85.443816 -293.261376)
			(xy 85.484319 -293.289332) (xy 85.519812 -293.323424) (xy 85.549377 -293.362768) (xy 85.572248 -293.406345)
			(xy 85.587832 -293.453026) (xy 85.595727 -293.501603) (xy 85.596222 -293.52621) (xy 85.925164 -293.52621)
			(xy 85.929124 -293.477156) (xy 85.940901 -293.429372) (xy 85.960192 -293.384096) (xy 85.986495 -293.3425)
			(xy 86.01913 -293.305663) (xy 86.057251 -293.274538) (xy 86.099872 -293.249931) (xy 86.145888 -293.232479)
			(xy 86.194107 -293.222635) (xy 86.243282 -293.220654) (xy 86.292137 -293.226586) (xy 86.339408 -293.240278)
			(xy 86.38387 -293.261376) (xy 86.424373 -293.289332) (xy 86.459866 -293.323424) (xy 86.489431 -293.362768)
			(xy 86.512302 -293.406345) (xy 86.527886 -293.453026) (xy 86.535781 -293.501603) (xy 86.536276 -293.52621)
			(xy 86.865218 -293.52621) (xy 86.869178 -293.477156) (xy 86.880955 -293.429372) (xy 86.900246 -293.384096)
			(xy 86.926549 -293.3425) (xy 86.959184 -293.305663) (xy 86.997305 -293.274538) (xy 87.039926 -293.249931)
			(xy 87.085942 -293.232479) (xy 87.134161 -293.222635) (xy 87.183336 -293.220654) (xy 87.232191 -293.226586)
			(xy 87.279462 -293.240278) (xy 87.323924 -293.261376) (xy 87.364427 -293.289332) (xy 87.39992 -293.323424)
			(xy 87.429485 -293.362768) (xy 87.452356 -293.406345) (xy 87.46794 -293.453026) (xy 87.475835 -293.501603)
			(xy 87.47633 -293.52621) (xy 87.805272 -293.52621) (xy 87.809232 -293.477156) (xy 87.821009 -293.429372)
			(xy 87.8403 -293.384096) (xy 87.866603 -293.3425) (xy 87.899238 -293.305663) (xy 87.937359 -293.274538)
			(xy 87.97998 -293.249931) (xy 88.025996 -293.232479) (xy 88.074215 -293.222635) (xy 88.12339 -293.220654)
			(xy 88.172245 -293.226586) (xy 88.219516 -293.240278) (xy 88.263978 -293.261376) (xy 88.304481 -293.289332)
			(xy 88.339974 -293.323424) (xy 88.369539 -293.362768) (xy 88.39241 -293.406345) (xy 88.407994 -293.453026)
			(xy 88.415889 -293.501603) (xy 88.416384 -293.52621) (xy 88.734895 -293.52621) (xy 88.73899 -293.475482)
			(xy 88.751169 -293.426068) (xy 88.771117 -293.379248) (xy 88.798318 -293.336234) (xy 88.832066 -293.29814)
			(xy 88.871488 -293.265953) (xy 88.915562 -293.240507) (xy 88.963148 -293.22246) (xy 89.013012 -293.21228)
			(xy 89.063864 -293.210231) (xy 89.114385 -293.216365) (xy 89.163269 -293.230525) (xy 89.209248 -293.252342)
			(xy 89.251132 -293.281252) (xy 89.287836 -293.316507) (xy 89.318409 -293.357193) (xy 89.34206 -293.402256)
			(xy 89.358176 -293.45053) (xy 89.36634 -293.500764) (xy 89.366852 -293.52621) (xy 89.685126 -293.52621)
			(xy 89.689086 -293.477156) (xy 89.700863 -293.429372) (xy 89.720154 -293.384096) (xy 89.746457 -293.3425)
			(xy 89.779092 -293.305663) (xy 89.817213 -293.274538) (xy 89.859834 -293.249931) (xy 89.90585 -293.232479)
			(xy 89.954069 -293.222635) (xy 90.003244 -293.220654) (xy 90.052099 -293.226586) (xy 90.09937 -293.240278)
			(xy 90.143832 -293.261376) (xy 90.184335 -293.289332) (xy 90.219828 -293.323424) (xy 90.249393 -293.362768)
			(xy 90.272264 -293.406345) (xy 90.287848 -293.453026) (xy 90.295743 -293.501603) (xy 90.296238 -293.52621)
			(xy 90.614749 -293.52621) (xy 90.618844 -293.475482) (xy 90.631023 -293.426068) (xy 90.650971 -293.379248)
			(xy 90.678172 -293.336234) (xy 90.71192 -293.29814) (xy 90.751342 -293.265953) (xy 90.795416 -293.240507)
			(xy 90.843002 -293.22246) (xy 90.892866 -293.21228) (xy 90.943718 -293.210231) (xy 90.994239 -293.216365)
			(xy 91.043123 -293.230525) (xy 91.089102 -293.252342) (xy 91.130986 -293.281252) (xy 91.16769 -293.316507)
			(xy 91.198263 -293.357193) (xy 91.221914 -293.402256) (xy 91.23803 -293.45053) (xy 91.246194 -293.500764)
			(xy 91.246706 -293.52621) (xy 91.565234 -293.52621) (xy 91.569194 -293.477156) (xy 91.580971 -293.429372)
			(xy 91.600262 -293.384096) (xy 91.626565 -293.3425) (xy 91.6592 -293.305663) (xy 91.697321 -293.274538)
			(xy 91.739942 -293.249931) (xy 91.785958 -293.232479) (xy 91.834177 -293.222635) (xy 91.883352 -293.220654)
			(xy 91.932207 -293.226586) (xy 91.979478 -293.240278) (xy 92.02394 -293.261376) (xy 92.064443 -293.289332)
			(xy 92.099936 -293.323424) (xy 92.129501 -293.362768) (xy 92.152372 -293.406345) (xy 92.167956 -293.453026)
			(xy 92.175851 -293.501603) (xy 92.176346 -293.52621) (xy 92.505288 -293.52621) (xy 92.509248 -293.477156)
			(xy 92.521025 -293.429372) (xy 92.540316 -293.384096) (xy 92.566619 -293.3425) (xy 92.599254 -293.305663)
			(xy 92.637375 -293.274538) (xy 92.679996 -293.249931) (xy 92.726012 -293.232479) (xy 92.774231 -293.222635)
			(xy 92.823406 -293.220654) (xy 92.872261 -293.226586) (xy 92.919532 -293.240278) (xy 92.963994 -293.261376)
			(xy 93.004497 -293.289332) (xy 93.03999 -293.323424) (xy 93.069555 -293.362768) (xy 93.092426 -293.406345)
			(xy 93.10801 -293.453026) (xy 93.115905 -293.501603) (xy 93.1164 -293.52621) (xy 93.445342 -293.52621)
			(xy 93.449302 -293.477156) (xy 93.461079 -293.429372) (xy 93.48037 -293.384096) (xy 93.506673 -293.3425)
			(xy 93.539308 -293.305663) (xy 93.577429 -293.274538) (xy 93.62005 -293.249931) (xy 93.666066 -293.232479)
			(xy 93.714285 -293.222635) (xy 93.76346 -293.220654) (xy 93.812315 -293.226586) (xy 93.859586 -293.240278)
			(xy 93.904048 -293.261376) (xy 93.944551 -293.289332) (xy 93.980044 -293.323424) (xy 94.009609 -293.362768)
			(xy 94.03248 -293.406345) (xy 94.048064 -293.453026) (xy 94.055959 -293.501603) (xy 94.056454 -293.52621)
			(xy 94.385142 -293.52621) (xy 94.389102 -293.477156) (xy 94.400879 -293.429372) (xy 94.42017 -293.384096)
			(xy 94.446473 -293.3425) (xy 94.479108 -293.305663) (xy 94.517229 -293.274538) (xy 94.55985 -293.249931)
			(xy 94.605866 -293.232479) (xy 94.654085 -293.222635) (xy 94.70326 -293.220654) (xy 94.752115 -293.226586)
			(xy 94.799386 -293.240278) (xy 94.843848 -293.261376) (xy 94.884351 -293.289332) (xy 94.919844 -293.323424)
			(xy 94.949409 -293.362768) (xy 94.97228 -293.406345) (xy 94.987864 -293.453026) (xy 94.995759 -293.501603)
			(xy 94.996254 -293.52621) (xy 95.314765 -293.52621) (xy 95.31886 -293.475482) (xy 95.331039 -293.426068)
			(xy 95.350987 -293.379248) (xy 95.378188 -293.336234) (xy 95.411936 -293.29814) (xy 95.451358 -293.265953)
			(xy 95.495432 -293.240507) (xy 95.543018 -293.22246) (xy 95.592882 -293.21228) (xy 95.643734 -293.210231)
			(xy 95.694255 -293.216365) (xy 95.743139 -293.230525) (xy 95.789118 -293.252342) (xy 95.831002 -293.281252)
			(xy 95.867706 -293.316507) (xy 95.898279 -293.357193) (xy 95.92193 -293.402256) (xy 95.938046 -293.45053)
			(xy 95.94621 -293.500764) (xy 95.946722 -293.52621) (xy 96.26525 -293.52621) (xy 96.26921 -293.477156)
			(xy 96.280987 -293.429372) (xy 96.300278 -293.384096) (xy 96.326581 -293.3425) (xy 96.359216 -293.305663)
			(xy 96.397337 -293.274538) (xy 96.439958 -293.249931) (xy 96.485974 -293.232479) (xy 96.534193 -293.222635)
			(xy 96.583368 -293.220654) (xy 96.632223 -293.226586) (xy 96.679494 -293.240278) (xy 96.723956 -293.261376)
			(xy 96.764459 -293.289332) (xy 96.799952 -293.323424) (xy 96.829517 -293.362768) (xy 96.852388 -293.406345)
			(xy 96.867972 -293.453026) (xy 96.875867 -293.501603) (xy 96.876362 -293.52621) (xy 97.205304 -293.52621)
			(xy 97.209264 -293.477156) (xy 97.221041 -293.429372) (xy 97.240332 -293.384096) (xy 97.266635 -293.3425)
			(xy 97.29927 -293.305663) (xy 97.337391 -293.274538) (xy 97.380012 -293.249931) (xy 97.426028 -293.232479)
			(xy 97.474247 -293.222635) (xy 97.523422 -293.220654) (xy 97.572277 -293.226586) (xy 97.619548 -293.240278)
			(xy 97.66401 -293.261376) (xy 97.704513 -293.289332) (xy 97.740006 -293.323424) (xy 97.769571 -293.362768)
			(xy 97.792442 -293.406345) (xy 97.808026 -293.453026) (xy 97.815921 -293.501603) (xy 97.816416 -293.52621)
			(xy 98.145358 -293.52621) (xy 98.149318 -293.477156) (xy 98.161095 -293.429372) (xy 98.180386 -293.384096)
			(xy 98.206689 -293.3425) (xy 98.239324 -293.305663) (xy 98.277445 -293.274538) (xy 98.320066 -293.249931)
			(xy 98.366082 -293.232479) (xy 98.414301 -293.222635) (xy 98.463476 -293.220654) (xy 98.512331 -293.226586)
			(xy 98.559602 -293.240278) (xy 98.604064 -293.261376) (xy 98.644567 -293.289332) (xy 98.68006 -293.323424)
			(xy 98.709625 -293.362768) (xy 98.732496 -293.406345) (xy 98.74808 -293.453026) (xy 98.755975 -293.501603)
			(xy 98.75647 -293.52621) (xy 99.085158 -293.52621) (xy 99.089118 -293.477156) (xy 99.100895 -293.429372)
			(xy 99.120186 -293.384096) (xy 99.146489 -293.3425) (xy 99.179124 -293.305663) (xy 99.217245 -293.274538)
			(xy 99.259866 -293.249931) (xy 99.305882 -293.232479) (xy 99.354101 -293.222635) (xy 99.403276 -293.220654)
			(xy 99.452131 -293.226586) (xy 99.499402 -293.240278) (xy 99.543864 -293.261376) (xy 99.584367 -293.289332)
			(xy 99.61986 -293.323424) (xy 99.649425 -293.362768) (xy 99.672296 -293.406345) (xy 99.68788 -293.453026)
			(xy 99.695775 -293.501603) (xy 99.69627 -293.52621) (xy 100.025212 -293.52621) (xy 100.029172 -293.477156)
			(xy 100.040949 -293.429372) (xy 100.06024 -293.384096) (xy 100.086543 -293.3425) (xy 100.119178 -293.305663)
			(xy 100.157299 -293.274538) (xy 100.19992 -293.249931) (xy 100.245936 -293.232479) (xy 100.294155 -293.222635)
			(xy 100.34333 -293.220654) (xy 100.392185 -293.226586) (xy 100.439456 -293.240278) (xy 100.483918 -293.261376)
			(xy 100.524421 -293.289332) (xy 100.559914 -293.323424) (xy 100.589479 -293.362768) (xy 100.61235 -293.406345)
			(xy 100.627934 -293.453026) (xy 100.635829 -293.501603) (xy 100.636324 -293.52621) (xy 100.965266 -293.52621)
			(xy 100.969226 -293.477156) (xy 100.981003 -293.429372) (xy 101.000294 -293.384096) (xy 101.026597 -293.3425)
			(xy 101.059232 -293.305663) (xy 101.097353 -293.274538) (xy 101.139974 -293.249931) (xy 101.18599 -293.232479)
			(xy 101.234209 -293.222635) (xy 101.283384 -293.220654) (xy 101.332239 -293.226586) (xy 101.37951 -293.240278)
			(xy 101.423972 -293.261376) (xy 101.464475 -293.289332) (xy 101.499968 -293.323424) (xy 101.529533 -293.362768)
			(xy 101.552404 -293.406345) (xy 101.567988 -293.453026) (xy 101.575883 -293.501603) (xy 101.576378 -293.52621)
			(xy 101.90532 -293.52621) (xy 101.90928 -293.477156) (xy 101.921057 -293.429372) (xy 101.940348 -293.384096)
			(xy 101.966651 -293.3425) (xy 101.999286 -293.305663) (xy 102.037407 -293.274538) (xy 102.080028 -293.249931)
			(xy 102.126044 -293.232479) (xy 102.174263 -293.222635) (xy 102.223438 -293.220654) (xy 102.272293 -293.226586)
			(xy 102.319564 -293.240278) (xy 102.364026 -293.261376) (xy 102.404529 -293.289332) (xy 102.440022 -293.323424)
			(xy 102.469587 -293.362768) (xy 102.492458 -293.406345) (xy 102.508042 -293.453026) (xy 102.515937 -293.501603)
			(xy 102.516432 -293.52621) (xy 102.515937 -293.550817) (xy 102.508042 -293.599394) (xy 102.492458 -293.646075)
			(xy 102.469587 -293.689652) (xy 102.440022 -293.728996) (xy 102.404529 -293.763088) (xy 102.364026 -293.791044)
			(xy 102.319564 -293.812142) (xy 102.272293 -293.825834) (xy 102.223438 -293.831766) (xy 102.174263 -293.829785)
			(xy 102.126044 -293.819941) (xy 102.080028 -293.802489) (xy 102.037407 -293.777882) (xy 101.999286 -293.746757)
			(xy 101.966651 -293.70992) (xy 101.940348 -293.668324) (xy 101.921057 -293.623048) (xy 101.90928 -293.575264)
			(xy 101.90532 -293.52621) (xy 101.576378 -293.52621) (xy 101.575883 -293.550817) (xy 101.567988 -293.599394)
			(xy 101.552404 -293.646075) (xy 101.529533 -293.689652) (xy 101.499968 -293.728996) (xy 101.464475 -293.763088)
			(xy 101.423972 -293.791044) (xy 101.37951 -293.812142) (xy 101.332239 -293.825834) (xy 101.283384 -293.831766)
			(xy 101.234209 -293.829785) (xy 101.18599 -293.819941) (xy 101.139974 -293.802489) (xy 101.097353 -293.777882)
			(xy 101.059232 -293.746757) (xy 101.026597 -293.70992) (xy 101.000294 -293.668324) (xy 100.981003 -293.623048)
			(xy 100.969226 -293.575264) (xy 100.965266 -293.52621) (xy 100.636324 -293.52621) (xy 100.635829 -293.550817)
			(xy 100.627934 -293.599394) (xy 100.61235 -293.646075) (xy 100.589479 -293.689652) (xy 100.559914 -293.728996)
			(xy 100.524421 -293.763088) (xy 100.483918 -293.791044) (xy 100.439456 -293.812142) (xy 100.392185 -293.825834)
			(xy 100.34333 -293.831766) (xy 100.294155 -293.829785) (xy 100.245936 -293.819941) (xy 100.19992 -293.802489)
			(xy 100.157299 -293.777882) (xy 100.119178 -293.746757) (xy 100.086543 -293.70992) (xy 100.06024 -293.668324)
			(xy 100.040949 -293.623048) (xy 100.029172 -293.575264) (xy 100.025212 -293.52621) (xy 99.69627 -293.52621)
			(xy 99.695775 -293.550817) (xy 99.68788 -293.599394) (xy 99.672296 -293.646075) (xy 99.649425 -293.689652)
			(xy 99.61986 -293.728996) (xy 99.584367 -293.763088) (xy 99.543864 -293.791044) (xy 99.499402 -293.812142)
			(xy 99.452131 -293.825834) (xy 99.403276 -293.831766) (xy 99.354101 -293.829785) (xy 99.305882 -293.819941)
			(xy 99.259866 -293.802489) (xy 99.217245 -293.777882) (xy 99.179124 -293.746757) (xy 99.146489 -293.70992)
			(xy 99.120186 -293.668324) (xy 99.100895 -293.623048) (xy 99.089118 -293.575264) (xy 99.085158 -293.52621)
			(xy 98.75647 -293.52621) (xy 98.755975 -293.550817) (xy 98.74808 -293.599394) (xy 98.732496 -293.646075)
			(xy 98.709625 -293.689652) (xy 98.68006 -293.728996) (xy 98.644567 -293.763088) (xy 98.604064 -293.791044)
			(xy 98.559602 -293.812142) (xy 98.512331 -293.825834) (xy 98.463476 -293.831766) (xy 98.414301 -293.829785)
			(xy 98.366082 -293.819941) (xy 98.320066 -293.802489) (xy 98.277445 -293.777882) (xy 98.239324 -293.746757)
			(xy 98.206689 -293.70992) (xy 98.180386 -293.668324) (xy 98.161095 -293.623048) (xy 98.149318 -293.575264)
			(xy 98.145358 -293.52621) (xy 97.816416 -293.52621) (xy 97.815921 -293.550817) (xy 97.808026 -293.599394)
			(xy 97.792442 -293.646075) (xy 97.769571 -293.689652) (xy 97.740006 -293.728996) (xy 97.704513 -293.763088)
			(xy 97.66401 -293.791044) (xy 97.619548 -293.812142) (xy 97.572277 -293.825834) (xy 97.523422 -293.831766)
			(xy 97.474247 -293.829785) (xy 97.426028 -293.819941) (xy 97.380012 -293.802489) (xy 97.337391 -293.777882)
			(xy 97.29927 -293.746757) (xy 97.266635 -293.70992) (xy 97.240332 -293.668324) (xy 97.221041 -293.623048)
			(xy 97.209264 -293.575264) (xy 97.205304 -293.52621) (xy 96.876362 -293.52621) (xy 96.875867 -293.550817)
			(xy 96.867972 -293.599394) (xy 96.852388 -293.646075) (xy 96.829517 -293.689652) (xy 96.799952 -293.728996)
			(xy 96.764459 -293.763088) (xy 96.723956 -293.791044) (xy 96.679494 -293.812142) (xy 96.632223 -293.825834)
			(xy 96.583368 -293.831766) (xy 96.534193 -293.829785) (xy 96.485974 -293.819941) (xy 96.439958 -293.802489)
			(xy 96.397337 -293.777882) (xy 96.359216 -293.746757) (xy 96.326581 -293.70992) (xy 96.300278 -293.668324)
			(xy 96.280987 -293.623048) (xy 96.26921 -293.575264) (xy 96.26525 -293.52621) (xy 95.946722 -293.52621)
			(xy 95.94621 -293.551656) (xy 95.938046 -293.60189) (xy 95.92193 -293.650164) (xy 95.898279 -293.695227)
			(xy 95.867706 -293.735913) (xy 95.831002 -293.771168) (xy 95.789118 -293.800078) (xy 95.743139 -293.821895)
			(xy 95.694255 -293.836055) (xy 95.643734 -293.842189) (xy 95.592882 -293.84014) (xy 95.543018 -293.82996)
			(xy 95.495432 -293.811913) (xy 95.451358 -293.786467) (xy 95.411936 -293.75428) (xy 95.378188 -293.716186)
			(xy 95.350987 -293.673172) (xy 95.331039 -293.626352) (xy 95.31886 -293.576938) (xy 95.314765 -293.52621)
			(xy 94.996254 -293.52621) (xy 94.995759 -293.550817) (xy 94.987864 -293.599394) (xy 94.97228 -293.646075)
			(xy 94.949409 -293.689652) (xy 94.919844 -293.728996) (xy 94.884351 -293.763088) (xy 94.843848 -293.791044)
			(xy 94.799386 -293.812142) (xy 94.752115 -293.825834) (xy 94.70326 -293.831766) (xy 94.654085 -293.829785)
			(xy 94.605866 -293.819941) (xy 94.55985 -293.802489) (xy 94.517229 -293.777882) (xy 94.479108 -293.746757)
			(xy 94.446473 -293.70992) (xy 94.42017 -293.668324) (xy 94.400879 -293.623048) (xy 94.389102 -293.575264)
			(xy 94.385142 -293.52621) (xy 94.056454 -293.52621) (xy 94.055959 -293.550817) (xy 94.048064 -293.599394)
			(xy 94.03248 -293.646075) (xy 94.009609 -293.689652) (xy 93.980044 -293.728996) (xy 93.944551 -293.763088)
			(xy 93.904048 -293.791044) (xy 93.859586 -293.812142) (xy 93.812315 -293.825834) (xy 93.76346 -293.831766)
			(xy 93.714285 -293.829785) (xy 93.666066 -293.819941) (xy 93.62005 -293.802489) (xy 93.577429 -293.777882)
			(xy 93.539308 -293.746757) (xy 93.506673 -293.70992) (xy 93.48037 -293.668324) (xy 93.461079 -293.623048)
			(xy 93.449302 -293.575264) (xy 93.445342 -293.52621) (xy 93.1164 -293.52621) (xy 93.115905 -293.550817)
			(xy 93.10801 -293.599394) (xy 93.092426 -293.646075) (xy 93.069555 -293.689652) (xy 93.03999 -293.728996)
			(xy 93.004497 -293.763088) (xy 92.963994 -293.791044) (xy 92.919532 -293.812142) (xy 92.872261 -293.825834)
			(xy 92.823406 -293.831766) (xy 92.774231 -293.829785) (xy 92.726012 -293.819941) (xy 92.679996 -293.802489)
			(xy 92.637375 -293.777882) (xy 92.599254 -293.746757) (xy 92.566619 -293.70992) (xy 92.540316 -293.668324)
			(xy 92.521025 -293.623048) (xy 92.509248 -293.575264) (xy 92.505288 -293.52621) (xy 92.176346 -293.52621)
			(xy 92.175851 -293.550817) (xy 92.167956 -293.599394) (xy 92.152372 -293.646075) (xy 92.129501 -293.689652)
			(xy 92.099936 -293.728996) (xy 92.064443 -293.763088) (xy 92.02394 -293.791044) (xy 91.979478 -293.812142)
			(xy 91.932207 -293.825834) (xy 91.883352 -293.831766) (xy 91.834177 -293.829785) (xy 91.785958 -293.819941)
			(xy 91.739942 -293.802489) (xy 91.697321 -293.777882) (xy 91.6592 -293.746757) (xy 91.626565 -293.70992)
			(xy 91.600262 -293.668324) (xy 91.580971 -293.623048) (xy 91.569194 -293.575264) (xy 91.565234 -293.52621)
			(xy 91.246706 -293.52621) (xy 91.246194 -293.551656) (xy 91.23803 -293.60189) (xy 91.221914 -293.650164)
			(xy 91.198263 -293.695227) (xy 91.16769 -293.735913) (xy 91.130986 -293.771168) (xy 91.089102 -293.800078)
			(xy 91.043123 -293.821895) (xy 90.994239 -293.836055) (xy 90.943718 -293.842189) (xy 90.892866 -293.84014)
			(xy 90.843002 -293.82996) (xy 90.795416 -293.811913) (xy 90.751342 -293.786467) (xy 90.71192 -293.75428)
			(xy 90.678172 -293.716186) (xy 90.650971 -293.673172) (xy 90.631023 -293.626352) (xy 90.618844 -293.576938)
			(xy 90.614749 -293.52621) (xy 90.296238 -293.52621) (xy 90.295743 -293.550817) (xy 90.287848 -293.599394)
			(xy 90.272264 -293.646075) (xy 90.249393 -293.689652) (xy 90.219828 -293.728996) (xy 90.184335 -293.763088)
			(xy 90.143832 -293.791044) (xy 90.09937 -293.812142) (xy 90.052099 -293.825834) (xy 90.003244 -293.831766)
			(xy 89.954069 -293.829785) (xy 89.90585 -293.819941) (xy 89.859834 -293.802489) (xy 89.817213 -293.777882)
			(xy 89.779092 -293.746757) (xy 89.746457 -293.70992) (xy 89.720154 -293.668324) (xy 89.700863 -293.623048)
			(xy 89.689086 -293.575264) (xy 89.685126 -293.52621) (xy 89.366852 -293.52621) (xy 89.36634 -293.551656)
			(xy 89.358176 -293.60189) (xy 89.34206 -293.650164) (xy 89.318409 -293.695227) (xy 89.287836 -293.735913)
			(xy 89.251132 -293.771168) (xy 89.209248 -293.800078) (xy 89.163269 -293.821895) (xy 89.114385 -293.836055)
			(xy 89.063864 -293.842189) (xy 89.013012 -293.84014) (xy 88.963148 -293.82996) (xy 88.915562 -293.811913)
			(xy 88.871488 -293.786467) (xy 88.832066 -293.75428) (xy 88.798318 -293.716186) (xy 88.771117 -293.673172)
			(xy 88.751169 -293.626352) (xy 88.73899 -293.576938) (xy 88.734895 -293.52621) (xy 88.416384 -293.52621)
			(xy 88.415889 -293.550817) (xy 88.407994 -293.599394) (xy 88.39241 -293.646075) (xy 88.369539 -293.689652)
			(xy 88.339974 -293.728996) (xy 88.304481 -293.763088) (xy 88.263978 -293.791044) (xy 88.219516 -293.812142)
			(xy 88.172245 -293.825834) (xy 88.12339 -293.831766) (xy 88.074215 -293.829785) (xy 88.025996 -293.819941)
			(xy 87.97998 -293.802489) (xy 87.937359 -293.777882) (xy 87.899238 -293.746757) (xy 87.866603 -293.70992)
			(xy 87.8403 -293.668324) (xy 87.821009 -293.623048) (xy 87.809232 -293.575264) (xy 87.805272 -293.52621)
			(xy 87.47633 -293.52621) (xy 87.475835 -293.550817) (xy 87.46794 -293.599394) (xy 87.452356 -293.646075)
			(xy 87.429485 -293.689652) (xy 87.39992 -293.728996) (xy 87.364427 -293.763088) (xy 87.323924 -293.791044)
			(xy 87.279462 -293.812142) (xy 87.232191 -293.825834) (xy 87.183336 -293.831766) (xy 87.134161 -293.829785)
			(xy 87.085942 -293.819941) (xy 87.039926 -293.802489) (xy 86.997305 -293.777882) (xy 86.959184 -293.746757)
			(xy 86.926549 -293.70992) (xy 86.900246 -293.668324) (xy 86.880955 -293.623048) (xy 86.869178 -293.575264)
			(xy 86.865218 -293.52621) (xy 86.536276 -293.52621) (xy 86.535781 -293.550817) (xy 86.527886 -293.599394)
			(xy 86.512302 -293.646075) (xy 86.489431 -293.689652) (xy 86.459866 -293.728996) (xy 86.424373 -293.763088)
			(xy 86.38387 -293.791044) (xy 86.339408 -293.812142) (xy 86.292137 -293.825834) (xy 86.243282 -293.831766)
			(xy 86.194107 -293.829785) (xy 86.145888 -293.819941) (xy 86.099872 -293.802489) (xy 86.057251 -293.777882)
			(xy 86.01913 -293.746757) (xy 85.986495 -293.70992) (xy 85.960192 -293.668324) (xy 85.940901 -293.623048)
			(xy 85.929124 -293.575264) (xy 85.925164 -293.52621) (xy 85.596222 -293.52621) (xy 85.595727 -293.550817)
			(xy 85.587832 -293.599394) (xy 85.572248 -293.646075) (xy 85.549377 -293.689652) (xy 85.519812 -293.728996)
			(xy 85.484319 -293.763088) (xy 85.443816 -293.791044) (xy 85.399354 -293.812142) (xy 85.352083 -293.825834)
			(xy 85.303228 -293.831766) (xy 85.254053 -293.829785) (xy 85.205834 -293.819941) (xy 85.159818 -293.802489)
			(xy 85.117197 -293.777882) (xy 85.079076 -293.746757) (xy 85.046441 -293.70992) (xy 85.020138 -293.668324)
			(xy 85.000847 -293.623048) (xy 84.98907 -293.575264) (xy 84.98511 -293.52621) (xy 84.666836 -293.52621)
			(xy 84.666324 -293.551656) (xy 84.65816 -293.60189) (xy 84.642044 -293.650164) (xy 84.618393 -293.695227)
			(xy 84.58782 -293.735913) (xy 84.551116 -293.771168) (xy 84.509232 -293.800078) (xy 84.463253 -293.821895)
			(xy 84.414369 -293.836055) (xy 84.363848 -293.842189) (xy 84.312996 -293.84014) (xy 84.263132 -293.82996)
			(xy 84.215546 -293.811913) (xy 84.171472 -293.786467) (xy 84.13205 -293.75428) (xy 84.098302 -293.716186)
			(xy 84.071101 -293.673172) (xy 84.051153 -293.626352) (xy 84.038974 -293.576938) (xy 84.034879 -293.52621)
			(xy 83.716368 -293.52621) (xy 83.715873 -293.550817) (xy 83.707978 -293.599394) (xy 83.692394 -293.646075)
			(xy 83.669523 -293.689652) (xy 83.639958 -293.728996) (xy 83.604465 -293.763088) (xy 83.563962 -293.791044)
			(xy 83.5195 -293.812142) (xy 83.472229 -293.825834) (xy 83.423374 -293.831766) (xy 83.374199 -293.829785)
			(xy 83.32598 -293.819941) (xy 83.279964 -293.802489) (xy 83.237343 -293.777882) (xy 83.199222 -293.746757)
			(xy 83.166587 -293.70992) (xy 83.140284 -293.668324) (xy 83.120993 -293.623048) (xy 83.109216 -293.575264)
			(xy 83.105256 -293.52621) (xy 82.786728 -293.52621) (xy 82.786216 -293.551656) (xy 82.778052 -293.60189)
			(xy 82.761936 -293.650164) (xy 82.738285 -293.695227) (xy 82.707712 -293.735913) (xy 82.671008 -293.771168)
			(xy 82.629124 -293.800078) (xy 82.583145 -293.821895) (xy 82.534261 -293.836055) (xy 82.48374 -293.842189)
			(xy 82.432888 -293.84014) (xy 82.383024 -293.82996) (xy 82.335438 -293.811913) (xy 82.291364 -293.786467)
			(xy 82.251942 -293.75428) (xy 82.218194 -293.716186) (xy 82.190993 -293.673172) (xy 82.171045 -293.626352)
			(xy 82.158866 -293.576938) (xy 82.154771 -293.52621) (xy 81.83626 -293.52621) (xy 81.835765 -293.550817)
			(xy 81.82787 -293.599394) (xy 81.812286 -293.646075) (xy 81.789415 -293.689652) (xy 81.75985 -293.728996)
			(xy 81.724357 -293.763088) (xy 81.683854 -293.791044) (xy 81.639392 -293.812142) (xy 81.592121 -293.825834)
			(xy 81.543266 -293.831766) (xy 81.494091 -293.829785) (xy 81.445872 -293.819941) (xy 81.399856 -293.802489)
			(xy 81.357235 -293.777882) (xy 81.319114 -293.746757) (xy 81.286479 -293.70992) (xy 81.260176 -293.668324)
			(xy 81.240885 -293.623048) (xy 81.229108 -293.575264) (xy 81.225148 -293.52621) (xy 80.89646 -293.52621)
			(xy 80.895965 -293.550817) (xy 80.88807 -293.599394) (xy 80.872486 -293.646075) (xy 80.849615 -293.689652)
			(xy 80.82005 -293.728996) (xy 80.784557 -293.763088) (xy 80.744054 -293.791044) (xy 80.699592 -293.812142)
			(xy 80.652321 -293.825834) (xy 80.603466 -293.831766) (xy 80.554291 -293.829785) (xy 80.506072 -293.819941)
			(xy 80.460056 -293.802489) (xy 80.417435 -293.777882) (xy 80.379314 -293.746757) (xy 80.346679 -293.70992)
			(xy 80.320376 -293.668324) (xy 80.301085 -293.623048) (xy 80.289308 -293.575264) (xy 80.285348 -293.52621)
			(xy 79.956406 -293.52621) (xy 79.955911 -293.550817) (xy 79.948016 -293.599394) (xy 79.932432 -293.646075)
			(xy 79.909561 -293.689652) (xy 79.879996 -293.728996) (xy 79.844503 -293.763088) (xy 79.804 -293.791044)
			(xy 79.759538 -293.812142) (xy 79.712267 -293.825834) (xy 79.663412 -293.831766) (xy 79.614237 -293.829785)
			(xy 79.566018 -293.819941) (xy 79.520002 -293.802489) (xy 79.477381 -293.777882) (xy 79.43926 -293.746757)
			(xy 79.406625 -293.70992) (xy 79.380322 -293.668324) (xy 79.361031 -293.623048) (xy 79.349254 -293.575264)
			(xy 79.345294 -293.52621) (xy 79.016352 -293.52621) (xy 79.015857 -293.550817) (xy 79.007962 -293.599394)
			(xy 78.992378 -293.646075) (xy 78.969507 -293.689652) (xy 78.939942 -293.728996) (xy 78.904449 -293.763088)
			(xy 78.863946 -293.791044) (xy 78.819484 -293.812142) (xy 78.772213 -293.825834) (xy 78.723358 -293.831766)
			(xy 78.674183 -293.829785) (xy 78.625964 -293.819941) (xy 78.579948 -293.802489) (xy 78.537327 -293.777882)
			(xy 78.499206 -293.746757) (xy 78.466571 -293.70992) (xy 78.440268 -293.668324) (xy 78.420977 -293.623048)
			(xy 78.4092 -293.575264) (xy 78.40524 -293.52621) (xy 73.228962 -293.52621) (xy 73.228962 -293.875968)
			(xy 73.229399 -293.886031) (xy 73.237138 -293.904612) (xy 73.243948 -293.912036) (xy 73.40219 -294.070278)
			(xy 76.807072 -294.070278) (xy 76.811032 -294.021224) (xy 76.822809 -293.97344) (xy 76.8421 -293.928164)
			(xy 76.868403 -293.886568) (xy 76.901038 -293.849731) (xy 76.939159 -293.818606) (xy 76.98178 -293.793999)
			(xy 77.027796 -293.776547) (xy 77.076015 -293.766703) (xy 77.12519 -293.764722) (xy 77.174045 -293.770654)
			(xy 77.221316 -293.784346) (xy 77.265778 -293.805444) (xy 77.306281 -293.8334) (xy 77.341774 -293.867492)
			(xy 77.371339 -293.906836) (xy 77.39421 -293.950413) (xy 77.409794 -293.997094) (xy 77.417689 -294.045671)
			(xy 77.418184 -294.070278) (xy 77.417689 -294.094885) (xy 77.409794 -294.143462) (xy 77.39421 -294.190143)
			(xy 77.371339 -294.23372) (xy 77.341774 -294.273064) (xy 77.306281 -294.307156) (xy 77.265778 -294.335112)
			(xy 77.263451 -294.336216) (xy 77.93534 -294.336216) (xy 77.9393 -294.287162) (xy 77.951077 -294.239378)
			(xy 77.970368 -294.194102) (xy 77.996671 -294.152506) (xy 78.029306 -294.115669) (xy 78.067427 -294.084544)
			(xy 78.110048 -294.059937) (xy 78.156064 -294.042485) (xy 78.204283 -294.032641) (xy 78.253458 -294.03066)
			(xy 78.302313 -294.036592) (xy 78.349584 -294.050284) (xy 78.394046 -294.071382) (xy 78.434549 -294.099338)
			(xy 78.470042 -294.13343) (xy 78.499607 -294.172774) (xy 78.522478 -294.216351) (xy 78.538062 -294.263032)
			(xy 78.545957 -294.311609) (xy 78.546452 -294.336216) (xy 79.815194 -294.336216) (xy 79.819154 -294.287162)
			(xy 79.830931 -294.239378) (xy 79.850222 -294.194102) (xy 79.876525 -294.152506) (xy 79.90916 -294.115669)
			(xy 79.947281 -294.084544) (xy 79.989902 -294.059937) (xy 80.035918 -294.042485) (xy 80.084137 -294.032641)
			(xy 80.133312 -294.03066) (xy 80.182167 -294.036592) (xy 80.229438 -294.050284) (xy 80.2739 -294.071382)
			(xy 80.314403 -294.099338) (xy 80.349896 -294.13343) (xy 80.379461 -294.172774) (xy 80.402332 -294.216351)
			(xy 80.417916 -294.263032) (xy 80.425811 -294.311609) (xy 80.426306 -294.336216) (xy 80.755248 -294.336216)
			(xy 80.759208 -294.287162) (xy 80.770985 -294.239378) (xy 80.790276 -294.194102) (xy 80.816579 -294.152506)
			(xy 80.849214 -294.115669) (xy 80.887335 -294.084544) (xy 80.929956 -294.059937) (xy 80.975972 -294.042485)
			(xy 81.024191 -294.032641) (xy 81.073366 -294.03066) (xy 81.122221 -294.036592) (xy 81.169492 -294.050284)
			(xy 81.213954 -294.071382) (xy 81.254457 -294.099338) (xy 81.28995 -294.13343) (xy 81.319515 -294.172774)
			(xy 81.342386 -294.216351) (xy 81.35797 -294.263032) (xy 81.365865 -294.311609) (xy 81.36636 -294.336216)
			(xy 81.695302 -294.336216) (xy 81.699262 -294.287162) (xy 81.711039 -294.239378) (xy 81.73033 -294.194102)
			(xy 81.756633 -294.152506) (xy 81.789268 -294.115669) (xy 81.827389 -294.084544) (xy 81.87001 -294.059937)
			(xy 81.916026 -294.042485) (xy 81.964245 -294.032641) (xy 82.01342 -294.03066) (xy 82.062275 -294.036592)
			(xy 82.109546 -294.050284) (xy 82.154008 -294.071382) (xy 82.194511 -294.099338) (xy 82.230004 -294.13343)
			(xy 82.259569 -294.172774) (xy 82.28244 -294.216351) (xy 82.298024 -294.263032) (xy 82.305919 -294.311609)
			(xy 82.306414 -294.336216) (xy 82.635102 -294.336216) (xy 82.639062 -294.287162) (xy 82.650839 -294.239378)
			(xy 82.67013 -294.194102) (xy 82.696433 -294.152506) (xy 82.729068 -294.115669) (xy 82.767189 -294.084544)
			(xy 82.80981 -294.059937) (xy 82.855826 -294.042485) (xy 82.904045 -294.032641) (xy 82.95322 -294.03066)
			(xy 83.002075 -294.036592) (xy 83.049346 -294.050284) (xy 83.093808 -294.071382) (xy 83.134311 -294.099338)
			(xy 83.169804 -294.13343) (xy 83.199369 -294.172774) (xy 83.22224 -294.216351) (xy 83.237824 -294.263032)
			(xy 83.245719 -294.311609) (xy 83.246214 -294.336216) (xy 83.575156 -294.336216) (xy 83.579116 -294.287162)
			(xy 83.590893 -294.239378) (xy 83.610184 -294.194102) (xy 83.636487 -294.152506) (xy 83.669122 -294.115669)
			(xy 83.707243 -294.084544) (xy 83.749864 -294.059937) (xy 83.79588 -294.042485) (xy 83.844099 -294.032641)
			(xy 83.893274 -294.03066) (xy 83.942129 -294.036592) (xy 83.9894 -294.050284) (xy 84.033862 -294.071382)
			(xy 84.074365 -294.099338) (xy 84.109858 -294.13343) (xy 84.139423 -294.172774) (xy 84.162294 -294.216351)
			(xy 84.177878 -294.263032) (xy 84.185773 -294.311609) (xy 84.186268 -294.336216) (xy 84.51521 -294.336216)
			(xy 84.51917 -294.287162) (xy 84.530947 -294.239378) (xy 84.550238 -294.194102) (xy 84.576541 -294.152506)
			(xy 84.609176 -294.115669) (xy 84.647297 -294.084544) (xy 84.689918 -294.059937) (xy 84.735934 -294.042485)
			(xy 84.784153 -294.032641) (xy 84.833328 -294.03066) (xy 84.882183 -294.036592) (xy 84.929454 -294.050284)
			(xy 84.973916 -294.071382) (xy 85.014419 -294.099338) (xy 85.049912 -294.13343) (xy 85.079477 -294.172774)
			(xy 85.102348 -294.216351) (xy 85.117932 -294.263032) (xy 85.125827 -294.311609) (xy 85.126322 -294.336216)
			(xy 85.455264 -294.336216) (xy 85.459224 -294.287162) (xy 85.471001 -294.239378) (xy 85.490292 -294.194102)
			(xy 85.516595 -294.152506) (xy 85.54923 -294.115669) (xy 85.587351 -294.084544) (xy 85.629972 -294.059937)
			(xy 85.675988 -294.042485) (xy 85.724207 -294.032641) (xy 85.773382 -294.03066) (xy 85.822237 -294.036592)
			(xy 85.869508 -294.050284) (xy 85.91397 -294.071382) (xy 85.954473 -294.099338) (xy 85.989966 -294.13343)
			(xy 86.019531 -294.172774) (xy 86.042402 -294.216351) (xy 86.057986 -294.263032) (xy 86.065881 -294.311609)
			(xy 86.066376 -294.336216) (xy 86.395318 -294.336216) (xy 86.399278 -294.287162) (xy 86.411055 -294.239378)
			(xy 86.430346 -294.194102) (xy 86.456649 -294.152506) (xy 86.489284 -294.115669) (xy 86.527405 -294.084544)
			(xy 86.570026 -294.059937) (xy 86.616042 -294.042485) (xy 86.664261 -294.032641) (xy 86.713436 -294.03066)
			(xy 86.762291 -294.036592) (xy 86.809562 -294.050284) (xy 86.854024 -294.071382) (xy 86.894527 -294.099338)
			(xy 86.93002 -294.13343) (xy 86.959585 -294.172774) (xy 86.982456 -294.216351) (xy 86.99804 -294.263032)
			(xy 87.005935 -294.311609) (xy 87.00643 -294.336216) (xy 87.335118 -294.336216) (xy 87.339078 -294.287162)
			(xy 87.350855 -294.239378) (xy 87.370146 -294.194102) (xy 87.396449 -294.152506) (xy 87.429084 -294.115669)
			(xy 87.467205 -294.084544) (xy 87.509826 -294.059937) (xy 87.555842 -294.042485) (xy 87.604061 -294.032641)
			(xy 87.653236 -294.03066) (xy 87.702091 -294.036592) (xy 87.749362 -294.050284) (xy 87.793824 -294.071382)
			(xy 87.834327 -294.099338) (xy 87.86982 -294.13343) (xy 87.899385 -294.172774) (xy 87.922256 -294.216351)
			(xy 87.93784 -294.263032) (xy 87.945735 -294.311609) (xy 87.94623 -294.336216) (xy 88.275172 -294.336216)
			(xy 88.279132 -294.287162) (xy 88.290909 -294.239378) (xy 88.3102 -294.194102) (xy 88.336503 -294.152506)
			(xy 88.369138 -294.115669) (xy 88.407259 -294.084544) (xy 88.44988 -294.059937) (xy 88.495896 -294.042485)
			(xy 88.544115 -294.032641) (xy 88.59329 -294.03066) (xy 88.642145 -294.036592) (xy 88.689416 -294.050284)
			(xy 88.733878 -294.071382) (xy 88.774381 -294.099338) (xy 88.809874 -294.13343) (xy 88.839439 -294.172774)
			(xy 88.86231 -294.216351) (xy 88.877894 -294.263032) (xy 88.885789 -294.311609) (xy 88.886284 -294.336216)
			(xy 89.215226 -294.336216) (xy 89.219186 -294.287162) (xy 89.230963 -294.239378) (xy 89.250254 -294.194102)
			(xy 89.276557 -294.152506) (xy 89.309192 -294.115669) (xy 89.347313 -294.084544) (xy 89.389934 -294.059937)
			(xy 89.43595 -294.042485) (xy 89.484169 -294.032641) (xy 89.533344 -294.03066) (xy 89.582199 -294.036592)
			(xy 89.62947 -294.050284) (xy 89.673932 -294.071382) (xy 89.714435 -294.099338) (xy 89.749928 -294.13343)
			(xy 89.779493 -294.172774) (xy 89.802364 -294.216351) (xy 89.817948 -294.263032) (xy 89.825843 -294.311609)
			(xy 89.826338 -294.336216) (xy 90.15528 -294.336216) (xy 90.15924 -294.287162) (xy 90.171017 -294.239378)
			(xy 90.190308 -294.194102) (xy 90.216611 -294.152506) (xy 90.249246 -294.115669) (xy 90.287367 -294.084544)
			(xy 90.329988 -294.059937) (xy 90.376004 -294.042485) (xy 90.424223 -294.032641) (xy 90.473398 -294.03066)
			(xy 90.522253 -294.036592) (xy 90.569524 -294.050284) (xy 90.613986 -294.071382) (xy 90.654489 -294.099338)
			(xy 90.689982 -294.13343) (xy 90.719547 -294.172774) (xy 90.742418 -294.216351) (xy 90.758002 -294.263032)
			(xy 90.765897 -294.311609) (xy 90.766392 -294.336216) (xy 91.095334 -294.336216) (xy 91.099294 -294.287162)
			(xy 91.111071 -294.239378) (xy 91.130362 -294.194102) (xy 91.156665 -294.152506) (xy 91.1893 -294.115669)
			(xy 91.227421 -294.084544) (xy 91.270042 -294.059937) (xy 91.316058 -294.042485) (xy 91.364277 -294.032641)
			(xy 91.413452 -294.03066) (xy 91.462307 -294.036592) (xy 91.509578 -294.050284) (xy 91.55404 -294.071382)
			(xy 91.594543 -294.099338) (xy 91.630036 -294.13343) (xy 91.659601 -294.172774) (xy 91.682472 -294.216351)
			(xy 91.698056 -294.263032) (xy 91.705951 -294.311609) (xy 91.706446 -294.336216) (xy 92.035134 -294.336216)
			(xy 92.039094 -294.287162) (xy 92.050871 -294.239378) (xy 92.070162 -294.194102) (xy 92.096465 -294.152506)
			(xy 92.1291 -294.115669) (xy 92.167221 -294.084544) (xy 92.209842 -294.059937) (xy 92.255858 -294.042485)
			(xy 92.304077 -294.032641) (xy 92.353252 -294.03066) (xy 92.402107 -294.036592) (xy 92.449378 -294.050284)
			(xy 92.49384 -294.071382) (xy 92.534343 -294.099338) (xy 92.569836 -294.13343) (xy 92.599401 -294.172774)
			(xy 92.622272 -294.216351) (xy 92.637856 -294.263032) (xy 92.645751 -294.311609) (xy 92.646246 -294.336216)
			(xy 92.975188 -294.336216) (xy 92.979148 -294.287162) (xy 92.990925 -294.239378) (xy 93.010216 -294.194102)
			(xy 93.036519 -294.152506) (xy 93.069154 -294.115669) (xy 93.107275 -294.084544) (xy 93.149896 -294.059937)
			(xy 93.195912 -294.042485) (xy 93.244131 -294.032641) (xy 93.293306 -294.03066) (xy 93.342161 -294.036592)
			(xy 93.389432 -294.050284) (xy 93.433894 -294.071382) (xy 93.474397 -294.099338) (xy 93.50989 -294.13343)
			(xy 93.539455 -294.172774) (xy 93.562326 -294.216351) (xy 93.57791 -294.263032) (xy 93.585805 -294.311609)
			(xy 93.5863 -294.336216) (xy 94.855296 -294.336216) (xy 94.859256 -294.287162) (xy 94.871033 -294.239378)
			(xy 94.890324 -294.194102) (xy 94.916627 -294.152506) (xy 94.949262 -294.115669) (xy 94.987383 -294.084544)
			(xy 95.030004 -294.059937) (xy 95.07602 -294.042485) (xy 95.124239 -294.032641) (xy 95.173414 -294.03066)
			(xy 95.222269 -294.036592) (xy 95.26954 -294.050284) (xy 95.314002 -294.071382) (xy 95.354505 -294.099338)
			(xy 95.389998 -294.13343) (xy 95.419563 -294.172774) (xy 95.442434 -294.216351) (xy 95.458018 -294.263032)
			(xy 95.465913 -294.311609) (xy 95.466408 -294.336216) (xy 95.79535 -294.336216) (xy 95.79931 -294.287162)
			(xy 95.811087 -294.239378) (xy 95.830378 -294.194102) (xy 95.856681 -294.152506) (xy 95.889316 -294.115669)
			(xy 95.927437 -294.084544) (xy 95.970058 -294.059937) (xy 96.016074 -294.042485) (xy 96.064293 -294.032641)
			(xy 96.113468 -294.03066) (xy 96.162323 -294.036592) (xy 96.209594 -294.050284) (xy 96.254056 -294.071382)
			(xy 96.294559 -294.099338) (xy 96.330052 -294.13343) (xy 96.359617 -294.172774) (xy 96.382488 -294.216351)
			(xy 96.398072 -294.263032) (xy 96.405967 -294.311609) (xy 96.406462 -294.336216) (xy 96.724719 -294.336216)
			(xy 96.728814 -294.285488) (xy 96.740993 -294.236074) (xy 96.760941 -294.189254) (xy 96.788142 -294.14624)
			(xy 96.82189 -294.108146) (xy 96.861312 -294.075959) (xy 96.905386 -294.050513) (xy 96.952972 -294.032466)
			(xy 97.002836 -294.022286) (xy 97.053688 -294.020237) (xy 97.104209 -294.026371) (xy 97.153093 -294.040531)
			(xy 97.199072 -294.062348) (xy 97.240956 -294.091258) (xy 97.27766 -294.126513) (xy 97.308233 -294.167199)
			(xy 97.331884 -294.212262) (xy 97.348 -294.260536) (xy 97.356164 -294.31077) (xy 97.356676 -294.336216)
			(xy 97.664773 -294.336216) (xy 97.668868 -294.285488) (xy 97.681047 -294.236074) (xy 97.700995 -294.189254)
			(xy 97.728196 -294.14624) (xy 97.761944 -294.108146) (xy 97.801366 -294.075959) (xy 97.84544 -294.050513)
			(xy 97.893026 -294.032466) (xy 97.94289 -294.022286) (xy 97.993742 -294.020237) (xy 98.044263 -294.026371)
			(xy 98.093147 -294.040531) (xy 98.139126 -294.062348) (xy 98.18101 -294.091258) (xy 98.217714 -294.126513)
			(xy 98.248287 -294.167199) (xy 98.271938 -294.212262) (xy 98.288054 -294.260536) (xy 98.296218 -294.31077)
			(xy 98.29673 -294.336216) (xy 98.615258 -294.336216) (xy 98.619218 -294.287162) (xy 98.630995 -294.239378)
			(xy 98.650286 -294.194102) (xy 98.676589 -294.152506) (xy 98.709224 -294.115669) (xy 98.747345 -294.084544)
			(xy 98.789966 -294.059937) (xy 98.835982 -294.042485) (xy 98.884201 -294.032641) (xy 98.933376 -294.03066)
			(xy 98.982231 -294.036592) (xy 99.029502 -294.050284) (xy 99.073964 -294.071382) (xy 99.114467 -294.099338)
			(xy 99.14996 -294.13343) (xy 99.179525 -294.172774) (xy 99.202396 -294.216351) (xy 99.21798 -294.263032)
			(xy 99.225875 -294.311609) (xy 99.22637 -294.336216) (xy 99.544881 -294.336216) (xy 99.548976 -294.285488)
			(xy 99.561155 -294.236074) (xy 99.581103 -294.189254) (xy 99.608304 -294.14624) (xy 99.642052 -294.108146)
			(xy 99.681474 -294.075959) (xy 99.725548 -294.050513) (xy 99.773134 -294.032466) (xy 99.822998 -294.022286)
			(xy 99.87385 -294.020237) (xy 99.924371 -294.026371) (xy 99.973255 -294.040531) (xy 100.019234 -294.062348)
			(xy 100.061118 -294.091258) (xy 100.097822 -294.126513) (xy 100.128395 -294.167199) (xy 100.152046 -294.212262)
			(xy 100.168162 -294.260536) (xy 100.176326 -294.31077) (xy 100.176838 -294.336216) (xy 100.484935 -294.336216)
			(xy 100.48903 -294.285488) (xy 100.501209 -294.236074) (xy 100.521157 -294.189254) (xy 100.548358 -294.14624)
			(xy 100.582106 -294.108146) (xy 100.621528 -294.075959) (xy 100.665602 -294.050513) (xy 100.713188 -294.032466)
			(xy 100.763052 -294.022286) (xy 100.813904 -294.020237) (xy 100.864425 -294.026371) (xy 100.913309 -294.040531)
			(xy 100.959288 -294.062348) (xy 101.001172 -294.091258) (xy 101.037876 -294.126513) (xy 101.068449 -294.167199)
			(xy 101.0921 -294.212262) (xy 101.108216 -294.260536) (xy 101.11638 -294.31077) (xy 101.116892 -294.336216)
			(xy 101.435166 -294.336216) (xy 101.439126 -294.287162) (xy 101.450903 -294.239378) (xy 101.470194 -294.194102)
			(xy 101.496497 -294.152506) (xy 101.529132 -294.115669) (xy 101.567253 -294.084544) (xy 101.609874 -294.059937)
			(xy 101.65589 -294.042485) (xy 101.704109 -294.032641) (xy 101.753284 -294.03066) (xy 101.802139 -294.036592)
			(xy 101.84941 -294.050284) (xy 101.893872 -294.071382) (xy 101.934375 -294.099338) (xy 101.969868 -294.13343)
			(xy 101.999433 -294.172774) (xy 102.022304 -294.216351) (xy 102.037888 -294.263032) (xy 102.045783 -294.311609)
			(xy 102.046278 -294.336216) (xy 102.045783 -294.360823) (xy 102.037888 -294.4094) (xy 102.022304 -294.456081)
			(xy 101.999433 -294.499658) (xy 101.969868 -294.539002) (xy 101.934375 -294.573094) (xy 101.893872 -294.60105)
			(xy 101.84941 -294.622148) (xy 101.802139 -294.63584) (xy 101.753284 -294.641772) (xy 101.704109 -294.639791)
			(xy 101.65589 -294.629947) (xy 101.609874 -294.612495) (xy 101.567253 -294.587888) (xy 101.529132 -294.556763)
			(xy 101.496497 -294.519926) (xy 101.470194 -294.47833) (xy 101.450903 -294.433054) (xy 101.439126 -294.38527)
			(xy 101.435166 -294.336216) (xy 101.116892 -294.336216) (xy 101.11638 -294.361662) (xy 101.108216 -294.411896)
			(xy 101.0921 -294.46017) (xy 101.068449 -294.505233) (xy 101.037876 -294.545919) (xy 101.001172 -294.581174)
			(xy 100.959288 -294.610084) (xy 100.913309 -294.631901) (xy 100.864425 -294.646061) (xy 100.813904 -294.652195)
			(xy 100.763052 -294.650146) (xy 100.713188 -294.639966) (xy 100.665602 -294.621919) (xy 100.621528 -294.596473)
			(xy 100.582106 -294.564286) (xy 100.548358 -294.526192) (xy 100.521157 -294.483178) (xy 100.501209 -294.436358)
			(xy 100.48903 -294.386944) (xy 100.484935 -294.336216) (xy 100.176838 -294.336216) (xy 100.176326 -294.361662)
			(xy 100.168162 -294.411896) (xy 100.152046 -294.46017) (xy 100.128395 -294.505233) (xy 100.097822 -294.545919)
			(xy 100.061118 -294.581174) (xy 100.019234 -294.610084) (xy 99.973255 -294.631901) (xy 99.924371 -294.646061)
			(xy 99.87385 -294.652195) (xy 99.822998 -294.650146) (xy 99.773134 -294.639966) (xy 99.725548 -294.621919)
			(xy 99.681474 -294.596473) (xy 99.642052 -294.564286) (xy 99.608304 -294.526192) (xy 99.581103 -294.483178)
			(xy 99.561155 -294.436358) (xy 99.548976 -294.386944) (xy 99.544881 -294.336216) (xy 99.22637 -294.336216)
			(xy 99.225875 -294.360823) (xy 99.21798 -294.4094) (xy 99.202396 -294.456081) (xy 99.179525 -294.499658)
			(xy 99.14996 -294.539002) (xy 99.114467 -294.573094) (xy 99.073964 -294.60105) (xy 99.029502 -294.622148)
			(xy 98.982231 -294.63584) (xy 98.933376 -294.641772) (xy 98.884201 -294.639791) (xy 98.835982 -294.629947)
			(xy 98.789966 -294.612495) (xy 98.747345 -294.587888) (xy 98.709224 -294.556763) (xy 98.676589 -294.519926)
			(xy 98.650286 -294.47833) (xy 98.630995 -294.433054) (xy 98.619218 -294.38527) (xy 98.615258 -294.336216)
			(xy 98.29673 -294.336216) (xy 98.296218 -294.361662) (xy 98.288054 -294.411896) (xy 98.271938 -294.46017)
			(xy 98.248287 -294.505233) (xy 98.217714 -294.545919) (xy 98.18101 -294.581174) (xy 98.139126 -294.610084)
			(xy 98.093147 -294.631901) (xy 98.044263 -294.646061) (xy 97.993742 -294.652195) (xy 97.94289 -294.650146)
			(xy 97.893026 -294.639966) (xy 97.84544 -294.621919) (xy 97.801366 -294.596473) (xy 97.761944 -294.564286)
			(xy 97.728196 -294.526192) (xy 97.700995 -294.483178) (xy 97.681047 -294.436358) (xy 97.668868 -294.386944)
			(xy 97.664773 -294.336216) (xy 97.356676 -294.336216) (xy 97.356164 -294.361662) (xy 97.348 -294.411896)
			(xy 97.331884 -294.46017) (xy 97.308233 -294.505233) (xy 97.27766 -294.545919) (xy 97.240956 -294.581174)
			(xy 97.199072 -294.610084) (xy 97.153093 -294.631901) (xy 97.104209 -294.646061) (xy 97.053688 -294.652195)
			(xy 97.002836 -294.650146) (xy 96.952972 -294.639966) (xy 96.905386 -294.621919) (xy 96.861312 -294.596473)
			(xy 96.82189 -294.564286) (xy 96.788142 -294.526192) (xy 96.760941 -294.483178) (xy 96.740993 -294.436358)
			(xy 96.728814 -294.386944) (xy 96.724719 -294.336216) (xy 96.406462 -294.336216) (xy 96.405967 -294.360823)
			(xy 96.398072 -294.4094) (xy 96.382488 -294.456081) (xy 96.359617 -294.499658) (xy 96.330052 -294.539002)
			(xy 96.294559 -294.573094) (xy 96.254056 -294.60105) (xy 96.209594 -294.622148) (xy 96.162323 -294.63584)
			(xy 96.113468 -294.641772) (xy 96.064293 -294.639791) (xy 96.016074 -294.629947) (xy 95.970058 -294.612495)
			(xy 95.927437 -294.587888) (xy 95.889316 -294.556763) (xy 95.856681 -294.519926) (xy 95.830378 -294.47833)
			(xy 95.811087 -294.433054) (xy 95.79931 -294.38527) (xy 95.79535 -294.336216) (xy 95.466408 -294.336216)
			(xy 95.465913 -294.360823) (xy 95.458018 -294.4094) (xy 95.442434 -294.456081) (xy 95.419563 -294.499658)
			(xy 95.389998 -294.539002) (xy 95.354505 -294.573094) (xy 95.314002 -294.60105) (xy 95.26954 -294.622148)
			(xy 95.222269 -294.63584) (xy 95.173414 -294.641772) (xy 95.124239 -294.639791) (xy 95.07602 -294.629947)
			(xy 95.030004 -294.612495) (xy 94.987383 -294.587888) (xy 94.949262 -294.556763) (xy 94.916627 -294.519926)
			(xy 94.890324 -294.47833) (xy 94.871033 -294.433054) (xy 94.859256 -294.38527) (xy 94.855296 -294.336216)
			(xy 93.5863 -294.336216) (xy 93.585805 -294.360823) (xy 93.57791 -294.4094) (xy 93.562326 -294.456081)
			(xy 93.539455 -294.499658) (xy 93.50989 -294.539002) (xy 93.474397 -294.573094) (xy 93.433894 -294.60105)
			(xy 93.389432 -294.622148) (xy 93.342161 -294.63584) (xy 93.293306 -294.641772) (xy 93.244131 -294.639791)
			(xy 93.195912 -294.629947) (xy 93.149896 -294.612495) (xy 93.107275 -294.587888) (xy 93.069154 -294.556763)
			(xy 93.036519 -294.519926) (xy 93.010216 -294.47833) (xy 92.990925 -294.433054) (xy 92.979148 -294.38527)
			(xy 92.975188 -294.336216) (xy 92.646246 -294.336216) (xy 92.645751 -294.360823) (xy 92.637856 -294.4094)
			(xy 92.622272 -294.456081) (xy 92.599401 -294.499658) (xy 92.569836 -294.539002) (xy 92.534343 -294.573094)
			(xy 92.49384 -294.60105) (xy 92.449378 -294.622148) (xy 92.402107 -294.63584) (xy 92.353252 -294.641772)
			(xy 92.304077 -294.639791) (xy 92.255858 -294.629947) (xy 92.209842 -294.612495) (xy 92.167221 -294.587888)
			(xy 92.1291 -294.556763) (xy 92.096465 -294.519926) (xy 92.070162 -294.47833) (xy 92.050871 -294.433054)
			(xy 92.039094 -294.38527) (xy 92.035134 -294.336216) (xy 91.706446 -294.336216) (xy 91.705951 -294.360823)
			(xy 91.698056 -294.4094) (xy 91.682472 -294.456081) (xy 91.659601 -294.499658) (xy 91.630036 -294.539002)
			(xy 91.594543 -294.573094) (xy 91.55404 -294.60105) (xy 91.509578 -294.622148) (xy 91.462307 -294.63584)
			(xy 91.413452 -294.641772) (xy 91.364277 -294.639791) (xy 91.316058 -294.629947) (xy 91.270042 -294.612495)
			(xy 91.227421 -294.587888) (xy 91.1893 -294.556763) (xy 91.156665 -294.519926) (xy 91.130362 -294.47833)
			(xy 91.111071 -294.433054) (xy 91.099294 -294.38527) (xy 91.095334 -294.336216) (xy 90.766392 -294.336216)
			(xy 90.765897 -294.360823) (xy 90.758002 -294.4094) (xy 90.742418 -294.456081) (xy 90.719547 -294.499658)
			(xy 90.689982 -294.539002) (xy 90.654489 -294.573094) (xy 90.613986 -294.60105) (xy 90.569524 -294.622148)
			(xy 90.522253 -294.63584) (xy 90.473398 -294.641772) (xy 90.424223 -294.639791) (xy 90.376004 -294.629947)
			(xy 90.329988 -294.612495) (xy 90.287367 -294.587888) (xy 90.249246 -294.556763) (xy 90.216611 -294.519926)
			(xy 90.190308 -294.47833) (xy 90.171017 -294.433054) (xy 90.15924 -294.38527) (xy 90.15528 -294.336216)
			(xy 89.826338 -294.336216) (xy 89.825843 -294.360823) (xy 89.817948 -294.4094) (xy 89.802364 -294.456081)
			(xy 89.779493 -294.499658) (xy 89.749928 -294.539002) (xy 89.714435 -294.573094) (xy 89.673932 -294.60105)
			(xy 89.62947 -294.622148) (xy 89.582199 -294.63584) (xy 89.533344 -294.641772) (xy 89.484169 -294.639791)
			(xy 89.43595 -294.629947) (xy 89.389934 -294.612495) (xy 89.347313 -294.587888) (xy 89.309192 -294.556763)
			(xy 89.276557 -294.519926) (xy 89.250254 -294.47833) (xy 89.230963 -294.433054) (xy 89.219186 -294.38527)
			(xy 89.215226 -294.336216) (xy 88.886284 -294.336216) (xy 88.885789 -294.360823) (xy 88.877894 -294.4094)
			(xy 88.86231 -294.456081) (xy 88.839439 -294.499658) (xy 88.809874 -294.539002) (xy 88.774381 -294.573094)
			(xy 88.733878 -294.60105) (xy 88.689416 -294.622148) (xy 88.642145 -294.63584) (xy 88.59329 -294.641772)
			(xy 88.544115 -294.639791) (xy 88.495896 -294.629947) (xy 88.44988 -294.612495) (xy 88.407259 -294.587888)
			(xy 88.369138 -294.556763) (xy 88.336503 -294.519926) (xy 88.3102 -294.47833) (xy 88.290909 -294.433054)
			(xy 88.279132 -294.38527) (xy 88.275172 -294.336216) (xy 87.94623 -294.336216) (xy 87.945735 -294.360823)
			(xy 87.93784 -294.4094) (xy 87.922256 -294.456081) (xy 87.899385 -294.499658) (xy 87.86982 -294.539002)
			(xy 87.834327 -294.573094) (xy 87.793824 -294.60105) (xy 87.749362 -294.622148) (xy 87.702091 -294.63584)
			(xy 87.653236 -294.641772) (xy 87.604061 -294.639791) (xy 87.555842 -294.629947) (xy 87.509826 -294.612495)
			(xy 87.467205 -294.587888) (xy 87.429084 -294.556763) (xy 87.396449 -294.519926) (xy 87.370146 -294.47833)
			(xy 87.350855 -294.433054) (xy 87.339078 -294.38527) (xy 87.335118 -294.336216) (xy 87.00643 -294.336216)
			(xy 87.005935 -294.360823) (xy 86.99804 -294.4094) (xy 86.982456 -294.456081) (xy 86.959585 -294.499658)
			(xy 86.93002 -294.539002) (xy 86.894527 -294.573094) (xy 86.854024 -294.60105) (xy 86.809562 -294.622148)
			(xy 86.762291 -294.63584) (xy 86.713436 -294.641772) (xy 86.664261 -294.639791) (xy 86.616042 -294.629947)
			(xy 86.570026 -294.612495) (xy 86.527405 -294.587888) (xy 86.489284 -294.556763) (xy 86.456649 -294.519926)
			(xy 86.430346 -294.47833) (xy 86.411055 -294.433054) (xy 86.399278 -294.38527) (xy 86.395318 -294.336216)
			(xy 86.066376 -294.336216) (xy 86.065881 -294.360823) (xy 86.057986 -294.4094) (xy 86.042402 -294.456081)
			(xy 86.019531 -294.499658) (xy 85.989966 -294.539002) (xy 85.954473 -294.573094) (xy 85.91397 -294.60105)
			(xy 85.869508 -294.622148) (xy 85.822237 -294.63584) (xy 85.773382 -294.641772) (xy 85.724207 -294.639791)
			(xy 85.675988 -294.629947) (xy 85.629972 -294.612495) (xy 85.587351 -294.587888) (xy 85.54923 -294.556763)
			(xy 85.516595 -294.519926) (xy 85.490292 -294.47833) (xy 85.471001 -294.433054) (xy 85.459224 -294.38527)
			(xy 85.455264 -294.336216) (xy 85.126322 -294.336216) (xy 85.125827 -294.360823) (xy 85.117932 -294.4094)
			(xy 85.102348 -294.456081) (xy 85.079477 -294.499658) (xy 85.049912 -294.539002) (xy 85.014419 -294.573094)
			(xy 84.973916 -294.60105) (xy 84.929454 -294.622148) (xy 84.882183 -294.63584) (xy 84.833328 -294.641772)
			(xy 84.784153 -294.639791) (xy 84.735934 -294.629947) (xy 84.689918 -294.612495) (xy 84.647297 -294.587888)
			(xy 84.609176 -294.556763) (xy 84.576541 -294.519926) (xy 84.550238 -294.47833) (xy 84.530947 -294.433054)
			(xy 84.51917 -294.38527) (xy 84.51521 -294.336216) (xy 84.186268 -294.336216) (xy 84.185773 -294.360823)
			(xy 84.177878 -294.4094) (xy 84.162294 -294.456081) (xy 84.139423 -294.499658) (xy 84.109858 -294.539002)
			(xy 84.074365 -294.573094) (xy 84.033862 -294.60105) (xy 83.9894 -294.622148) (xy 83.942129 -294.63584)
			(xy 83.893274 -294.641772) (xy 83.844099 -294.639791) (xy 83.79588 -294.629947) (xy 83.749864 -294.612495)
			(xy 83.707243 -294.587888) (xy 83.669122 -294.556763) (xy 83.636487 -294.519926) (xy 83.610184 -294.47833)
			(xy 83.590893 -294.433054) (xy 83.579116 -294.38527) (xy 83.575156 -294.336216) (xy 83.246214 -294.336216)
			(xy 83.245719 -294.360823) (xy 83.237824 -294.4094) (xy 83.22224 -294.456081) (xy 83.199369 -294.499658)
			(xy 83.169804 -294.539002) (xy 83.134311 -294.573094) (xy 83.093808 -294.60105) (xy 83.049346 -294.622148)
			(xy 83.002075 -294.63584) (xy 82.95322 -294.641772) (xy 82.904045 -294.639791) (xy 82.855826 -294.629947)
			(xy 82.80981 -294.612495) (xy 82.767189 -294.587888) (xy 82.729068 -294.556763) (xy 82.696433 -294.519926)
			(xy 82.67013 -294.47833) (xy 82.650839 -294.433054) (xy 82.639062 -294.38527) (xy 82.635102 -294.336216)
			(xy 82.306414 -294.336216) (xy 82.305919 -294.360823) (xy 82.298024 -294.4094) (xy 82.28244 -294.456081)
			(xy 82.259569 -294.499658) (xy 82.230004 -294.539002) (xy 82.194511 -294.573094) (xy 82.154008 -294.60105)
			(xy 82.109546 -294.622148) (xy 82.062275 -294.63584) (xy 82.01342 -294.641772) (xy 81.964245 -294.639791)
			(xy 81.916026 -294.629947) (xy 81.87001 -294.612495) (xy 81.827389 -294.587888) (xy 81.789268 -294.556763)
			(xy 81.756633 -294.519926) (xy 81.73033 -294.47833) (xy 81.711039 -294.433054) (xy 81.699262 -294.38527)
			(xy 81.695302 -294.336216) (xy 81.36636 -294.336216) (xy 81.365865 -294.360823) (xy 81.35797 -294.4094)
			(xy 81.342386 -294.456081) (xy 81.319515 -294.499658) (xy 81.28995 -294.539002) (xy 81.254457 -294.573094)
			(xy 81.213954 -294.60105) (xy 81.169492 -294.622148) (xy 81.122221 -294.63584) (xy 81.073366 -294.641772)
			(xy 81.024191 -294.639791) (xy 80.975972 -294.629947) (xy 80.929956 -294.612495) (xy 80.887335 -294.587888)
			(xy 80.849214 -294.556763) (xy 80.816579 -294.519926) (xy 80.790276 -294.47833) (xy 80.770985 -294.433054)
			(xy 80.759208 -294.38527) (xy 80.755248 -294.336216) (xy 80.426306 -294.336216) (xy 80.425811 -294.360823)
			(xy 80.417916 -294.4094) (xy 80.402332 -294.456081) (xy 80.379461 -294.499658) (xy 80.349896 -294.539002)
			(xy 80.314403 -294.573094) (xy 80.2739 -294.60105) (xy 80.229438 -294.622148) (xy 80.182167 -294.63584)
			(xy 80.133312 -294.641772) (xy 80.084137 -294.639791) (xy 80.035918 -294.629947) (xy 79.989902 -294.612495)
			(xy 79.947281 -294.587888) (xy 79.90916 -294.556763) (xy 79.876525 -294.519926) (xy 79.850222 -294.47833)
			(xy 79.830931 -294.433054) (xy 79.819154 -294.38527) (xy 79.815194 -294.336216) (xy 78.546452 -294.336216)
			(xy 78.545957 -294.360823) (xy 78.538062 -294.4094) (xy 78.522478 -294.456081) (xy 78.499607 -294.499658)
			(xy 78.470042 -294.539002) (xy 78.434549 -294.573094) (xy 78.394046 -294.60105) (xy 78.349584 -294.622148)
			(xy 78.302313 -294.63584) (xy 78.253458 -294.641772) (xy 78.204283 -294.639791) (xy 78.156064 -294.629947)
			(xy 78.110048 -294.612495) (xy 78.067427 -294.587888) (xy 78.029306 -294.556763) (xy 77.996671 -294.519926)
			(xy 77.970368 -294.47833) (xy 77.951077 -294.433054) (xy 77.9393 -294.38527) (xy 77.93534 -294.336216)
			(xy 77.263451 -294.336216) (xy 77.221316 -294.35621) (xy 77.174045 -294.369902) (xy 77.12519 -294.375834)
			(xy 77.076015 -294.373853) (xy 77.027796 -294.364009) (xy 76.98178 -294.346557) (xy 76.939159 -294.32195)
			(xy 76.901038 -294.290825) (xy 76.868403 -294.253988) (xy 76.8421 -294.212392) (xy 76.822809 -294.167116)
			(xy 76.811032 -294.119332) (xy 76.807072 -294.070278) (xy 73.40219 -294.070278) (xy 74.478134 -295.146222)
			(xy 81.225148 -295.146222) (xy 81.229108 -295.097168) (xy 81.240885 -295.049384) (xy 81.260176 -295.004108)
			(xy 81.286479 -294.962512) (xy 81.319114 -294.925675) (xy 81.357235 -294.89455) (xy 81.399856 -294.869943)
			(xy 81.445872 -294.852491) (xy 81.494091 -294.842647) (xy 81.543266 -294.840666) (xy 81.592121 -294.846598)
			(xy 81.639392 -294.86029) (xy 81.683854 -294.881388) (xy 81.724357 -294.909344) (xy 81.75985 -294.943436)
			(xy 81.789415 -294.98278) (xy 81.812286 -295.026357) (xy 81.82787 -295.073038) (xy 81.835765 -295.121615)
			(xy 81.83626 -295.146222) (xy 82.165202 -295.146222) (xy 82.169162 -295.097168) (xy 82.180939 -295.049384)
			(xy 82.20023 -295.004108) (xy 82.226533 -294.962512) (xy 82.259168 -294.925675) (xy 82.297289 -294.89455)
			(xy 82.33991 -294.869943) (xy 82.385926 -294.852491) (xy 82.434145 -294.842647) (xy 82.48332 -294.840666)
			(xy 82.532175 -294.846598) (xy 82.579446 -294.86029) (xy 82.623908 -294.881388) (xy 82.664411 -294.909344)
			(xy 82.699904 -294.943436) (xy 82.729469 -294.98278) (xy 82.75234 -295.026357) (xy 82.767924 -295.073038)
			(xy 82.775819 -295.121615) (xy 82.776314 -295.146222) (xy 83.105256 -295.146222) (xy 83.109216 -295.097168)
			(xy 83.120993 -295.049384) (xy 83.140284 -295.004108) (xy 83.166587 -294.962512) (xy 83.199222 -294.925675)
			(xy 83.237343 -294.89455) (xy 83.279964 -294.869943) (xy 83.32598 -294.852491) (xy 83.374199 -294.842647)
			(xy 83.423374 -294.840666) (xy 83.472229 -294.846598) (xy 83.5195 -294.86029) (xy 83.563962 -294.881388)
			(xy 83.604465 -294.909344) (xy 83.639958 -294.943436) (xy 83.669523 -294.98278) (xy 83.692394 -295.026357)
			(xy 83.707978 -295.073038) (xy 83.715873 -295.121615) (xy 83.716368 -295.146222) (xy 84.04531 -295.146222)
			(xy 84.04927 -295.097168) (xy 84.061047 -295.049384) (xy 84.080338 -295.004108) (xy 84.106641 -294.962512)
			(xy 84.139276 -294.925675) (xy 84.177397 -294.89455) (xy 84.220018 -294.869943) (xy 84.266034 -294.852491)
			(xy 84.314253 -294.842647) (xy 84.363428 -294.840666) (xy 84.412283 -294.846598) (xy 84.459554 -294.86029)
			(xy 84.504016 -294.881388) (xy 84.544519 -294.909344) (xy 84.580012 -294.943436) (xy 84.609577 -294.98278)
			(xy 84.632448 -295.026357) (xy 84.648032 -295.073038) (xy 84.655927 -295.121615) (xy 84.656422 -295.146222)
			(xy 84.98511 -295.146222) (xy 84.98907 -295.097168) (xy 85.000847 -295.049384) (xy 85.020138 -295.004108)
			(xy 85.046441 -294.962512) (xy 85.079076 -294.925675) (xy 85.117197 -294.89455) (xy 85.159818 -294.869943)
			(xy 85.205834 -294.852491) (xy 85.254053 -294.842647) (xy 85.303228 -294.840666) (xy 85.352083 -294.846598)
			(xy 85.399354 -294.86029) (xy 85.443816 -294.881388) (xy 85.484319 -294.909344) (xy 85.519812 -294.943436)
			(xy 85.549377 -294.98278) (xy 85.572248 -295.026357) (xy 85.587832 -295.073038) (xy 85.595727 -295.121615)
			(xy 85.596222 -295.146222) (xy 85.925164 -295.146222) (xy 85.929124 -295.097168) (xy 85.940901 -295.049384)
			(xy 85.960192 -295.004108) (xy 85.986495 -294.962512) (xy 86.01913 -294.925675) (xy 86.057251 -294.89455)
			(xy 86.099872 -294.869943) (xy 86.145888 -294.852491) (xy 86.194107 -294.842647) (xy 86.243282 -294.840666)
			(xy 86.292137 -294.846598) (xy 86.339408 -294.86029) (xy 86.38387 -294.881388) (xy 86.424373 -294.909344)
			(xy 86.459866 -294.943436) (xy 86.489431 -294.98278) (xy 86.512302 -295.026357) (xy 86.527886 -295.073038)
			(xy 86.535781 -295.121615) (xy 86.536276 -295.146222) (xy 86.865218 -295.146222) (xy 86.869178 -295.097168)
			(xy 86.880955 -295.049384) (xy 86.900246 -295.004108) (xy 86.926549 -294.962512) (xy 86.959184 -294.925675)
			(xy 86.997305 -294.89455) (xy 87.039926 -294.869943) (xy 87.085942 -294.852491) (xy 87.134161 -294.842647)
			(xy 87.183336 -294.840666) (xy 87.232191 -294.846598) (xy 87.279462 -294.86029) (xy 87.323924 -294.881388)
			(xy 87.364427 -294.909344) (xy 87.39992 -294.943436) (xy 87.429485 -294.98278) (xy 87.452356 -295.026357)
			(xy 87.46794 -295.073038) (xy 87.475835 -295.121615) (xy 87.47633 -295.146222) (xy 87.805272 -295.146222)
			(xy 87.809232 -295.097168) (xy 87.821009 -295.049384) (xy 87.8403 -295.004108) (xy 87.866603 -294.962512)
			(xy 87.899238 -294.925675) (xy 87.937359 -294.89455) (xy 87.97998 -294.869943) (xy 88.025996 -294.852491)
			(xy 88.074215 -294.842647) (xy 88.12339 -294.840666) (xy 88.172245 -294.846598) (xy 88.219516 -294.86029)
			(xy 88.263978 -294.881388) (xy 88.304481 -294.909344) (xy 88.339974 -294.943436) (xy 88.369539 -294.98278)
			(xy 88.39241 -295.026357) (xy 88.407994 -295.073038) (xy 88.415889 -295.121615) (xy 88.416384 -295.146222)
			(xy 88.745326 -295.146222) (xy 88.749286 -295.097168) (xy 88.761063 -295.049384) (xy 88.780354 -295.004108)
			(xy 88.806657 -294.962512) (xy 88.839292 -294.925675) (xy 88.877413 -294.89455) (xy 88.920034 -294.869943)
			(xy 88.96605 -294.852491) (xy 89.014269 -294.842647) (xy 89.063444 -294.840666) (xy 89.112299 -294.846598)
			(xy 89.15957 -294.86029) (xy 89.204032 -294.881388) (xy 89.244535 -294.909344) (xy 89.280028 -294.943436)
			(xy 89.309593 -294.98278) (xy 89.332464 -295.026357) (xy 89.348048 -295.073038) (xy 89.355943 -295.121615)
			(xy 89.356438 -295.146222) (xy 89.685126 -295.146222) (xy 89.689086 -295.097168) (xy 89.700863 -295.049384)
			(xy 89.720154 -295.004108) (xy 89.746457 -294.962512) (xy 89.779092 -294.925675) (xy 89.817213 -294.89455)
			(xy 89.859834 -294.869943) (xy 89.90585 -294.852491) (xy 89.954069 -294.842647) (xy 90.003244 -294.840666)
			(xy 90.052099 -294.846598) (xy 90.09937 -294.86029) (xy 90.143832 -294.881388) (xy 90.184335 -294.909344)
			(xy 90.219828 -294.943436) (xy 90.249393 -294.98278) (xy 90.272264 -295.026357) (xy 90.287848 -295.073038)
			(xy 90.295743 -295.121615) (xy 90.296238 -295.146222) (xy 90.62518 -295.146222) (xy 90.62914 -295.097168)
			(xy 90.640917 -295.049384) (xy 90.660208 -295.004108) (xy 90.686511 -294.962512) (xy 90.719146 -294.925675)
			(xy 90.757267 -294.89455) (xy 90.799888 -294.869943) (xy 90.845904 -294.852491) (xy 90.894123 -294.842647)
			(xy 90.943298 -294.840666) (xy 90.992153 -294.846598) (xy 91.039424 -294.86029) (xy 91.083886 -294.881388)
			(xy 91.124389 -294.909344) (xy 91.159882 -294.943436) (xy 91.189447 -294.98278) (xy 91.212318 -295.026357)
			(xy 91.227902 -295.073038) (xy 91.235797 -295.121615) (xy 91.236292 -295.146222) (xy 91.565234 -295.146222)
			(xy 91.569194 -295.097168) (xy 91.580971 -295.049384) (xy 91.600262 -295.004108) (xy 91.626565 -294.962512)
			(xy 91.6592 -294.925675) (xy 91.697321 -294.89455) (xy 91.739942 -294.869943) (xy 91.785958 -294.852491)
			(xy 91.834177 -294.842647) (xy 91.883352 -294.840666) (xy 91.932207 -294.846598) (xy 91.979478 -294.86029)
			(xy 92.02394 -294.881388) (xy 92.064443 -294.909344) (xy 92.099936 -294.943436) (xy 92.129501 -294.98278)
			(xy 92.152372 -295.026357) (xy 92.167956 -295.073038) (xy 92.175851 -295.121615) (xy 92.176346 -295.146222)
			(xy 92.505288 -295.146222) (xy 92.509248 -295.097168) (xy 92.521025 -295.049384) (xy 92.540316 -295.004108)
			(xy 92.566619 -294.962512) (xy 92.599254 -294.925675) (xy 92.637375 -294.89455) (xy 92.679996 -294.869943)
			(xy 92.726012 -294.852491) (xy 92.774231 -294.842647) (xy 92.823406 -294.840666) (xy 92.872261 -294.846598)
			(xy 92.919532 -294.86029) (xy 92.963994 -294.881388) (xy 93.004497 -294.909344) (xy 93.03999 -294.943436)
			(xy 93.069555 -294.98278) (xy 93.092426 -295.026357) (xy 93.10801 -295.073038) (xy 93.115905 -295.121615)
			(xy 93.1164 -295.146222) (xy 95.325196 -295.146222) (xy 95.329156 -295.097168) (xy 95.340933 -295.049384)
			(xy 95.360224 -295.004108) (xy 95.386527 -294.962512) (xy 95.419162 -294.925675) (xy 95.457283 -294.89455)
			(xy 95.499904 -294.869943) (xy 95.54592 -294.852491) (xy 95.594139 -294.842647) (xy 95.643314 -294.840666)
			(xy 95.692169 -294.846598) (xy 95.73944 -294.86029) (xy 95.783902 -294.881388) (xy 95.824405 -294.909344)
			(xy 95.859898 -294.943436) (xy 95.889463 -294.98278) (xy 95.912334 -295.026357) (xy 95.927918 -295.073038)
			(xy 95.935813 -295.121615) (xy 95.936308 -295.146222) (xy 98.145358 -295.146222) (xy 98.149318 -295.097168)
			(xy 98.161095 -295.049384) (xy 98.180386 -295.004108) (xy 98.206689 -294.962512) (xy 98.239324 -294.925675)
			(xy 98.277445 -294.89455) (xy 98.320066 -294.869943) (xy 98.366082 -294.852491) (xy 98.414301 -294.842647)
			(xy 98.463476 -294.840666) (xy 98.512331 -294.846598) (xy 98.559602 -294.86029) (xy 98.604064 -294.881388)
			(xy 98.644567 -294.909344) (xy 98.68006 -294.943436) (xy 98.709625 -294.98278) (xy 98.732496 -295.026357)
			(xy 98.74808 -295.073038) (xy 98.755975 -295.121615) (xy 98.75647 -295.146222) (xy 100.965266 -295.146222)
			(xy 100.969226 -295.097168) (xy 100.981003 -295.049384) (xy 101.000294 -295.004108) (xy 101.026597 -294.962512)
			(xy 101.059232 -294.925675) (xy 101.097353 -294.89455) (xy 101.139974 -294.869943) (xy 101.18599 -294.852491)
			(xy 101.234209 -294.842647) (xy 101.283384 -294.840666) (xy 101.332239 -294.846598) (xy 101.37951 -294.86029)
			(xy 101.423972 -294.881388) (xy 101.464475 -294.909344) (xy 101.499968 -294.943436) (xy 101.529533 -294.98278)
			(xy 101.552404 -295.026357) (xy 101.567988 -295.073038) (xy 101.575883 -295.121615) (xy 101.576378 -295.146222)
			(xy 101.575883 -295.170829) (xy 101.567988 -295.219406) (xy 101.552404 -295.266087) (xy 101.529533 -295.309664)
			(xy 101.499968 -295.349008) (xy 101.464475 -295.3831) (xy 101.423972 -295.411056) (xy 101.37951 -295.432154)
			(xy 101.332239 -295.445846) (xy 101.283384 -295.451778) (xy 101.234209 -295.449797) (xy 101.18599 -295.439953)
			(xy 101.139974 -295.422501) (xy 101.097353 -295.397894) (xy 101.059232 -295.366769) (xy 101.026597 -295.329932)
			(xy 101.000294 -295.288336) (xy 100.981003 -295.24306) (xy 100.969226 -295.195276) (xy 100.965266 -295.146222)
			(xy 98.75647 -295.146222) (xy 98.755975 -295.170829) (xy 98.74808 -295.219406) (xy 98.732496 -295.266087)
			(xy 98.709625 -295.309664) (xy 98.68006 -295.349008) (xy 98.644567 -295.3831) (xy 98.604064 -295.411056)
			(xy 98.559602 -295.432154) (xy 98.512331 -295.445846) (xy 98.463476 -295.451778) (xy 98.414301 -295.449797)
			(xy 98.366082 -295.439953) (xy 98.320066 -295.422501) (xy 98.277445 -295.397894) (xy 98.239324 -295.366769)
			(xy 98.206689 -295.329932) (xy 98.180386 -295.288336) (xy 98.161095 -295.24306) (xy 98.149318 -295.195276)
			(xy 98.145358 -295.146222) (xy 95.936308 -295.146222) (xy 95.935813 -295.170829) (xy 95.927918 -295.219406)
			(xy 95.912334 -295.266087) (xy 95.889463 -295.309664) (xy 95.859898 -295.349008) (xy 95.824405 -295.3831)
			(xy 95.783902 -295.411056) (xy 95.73944 -295.432154) (xy 95.692169 -295.445846) (xy 95.643314 -295.451778)
			(xy 95.594139 -295.449797) (xy 95.54592 -295.439953) (xy 95.499904 -295.422501) (xy 95.457283 -295.397894)
			(xy 95.419162 -295.366769) (xy 95.386527 -295.329932) (xy 95.360224 -295.288336) (xy 95.340933 -295.24306)
			(xy 95.329156 -295.195276) (xy 95.325196 -295.146222) (xy 93.1164 -295.146222) (xy 93.115905 -295.170829)
			(xy 93.10801 -295.219406) (xy 93.092426 -295.266087) (xy 93.069555 -295.309664) (xy 93.03999 -295.349008)
			(xy 93.004497 -295.3831) (xy 92.963994 -295.411056) (xy 92.919532 -295.432154) (xy 92.872261 -295.445846)
			(xy 92.823406 -295.451778) (xy 92.774231 -295.449797) (xy 92.726012 -295.439953) (xy 92.679996 -295.422501)
			(xy 92.637375 -295.397894) (xy 92.599254 -295.366769) (xy 92.566619 -295.329932) (xy 92.540316 -295.288336)
			(xy 92.521025 -295.24306) (xy 92.509248 -295.195276) (xy 92.505288 -295.146222) (xy 92.176346 -295.146222)
			(xy 92.175851 -295.170829) (xy 92.167956 -295.219406) (xy 92.152372 -295.266087) (xy 92.129501 -295.309664)
			(xy 92.099936 -295.349008) (xy 92.064443 -295.3831) (xy 92.02394 -295.411056) (xy 91.979478 -295.432154)
			(xy 91.932207 -295.445846) (xy 91.883352 -295.451778) (xy 91.834177 -295.449797) (xy 91.785958 -295.439953)
			(xy 91.739942 -295.422501) (xy 91.697321 -295.397894) (xy 91.6592 -295.366769) (xy 91.626565 -295.329932)
			(xy 91.600262 -295.288336) (xy 91.580971 -295.24306) (xy 91.569194 -295.195276) (xy 91.565234 -295.146222)
			(xy 91.236292 -295.146222) (xy 91.235797 -295.170829) (xy 91.227902 -295.219406) (xy 91.212318 -295.266087)
			(xy 91.189447 -295.309664) (xy 91.159882 -295.349008) (xy 91.124389 -295.3831) (xy 91.083886 -295.411056)
			(xy 91.039424 -295.432154) (xy 90.992153 -295.445846) (xy 90.943298 -295.451778) (xy 90.894123 -295.449797)
			(xy 90.845904 -295.439953) (xy 90.799888 -295.422501) (xy 90.757267 -295.397894) (xy 90.719146 -295.366769)
			(xy 90.686511 -295.329932) (xy 90.660208 -295.288336) (xy 90.640917 -295.24306) (xy 90.62914 -295.195276)
			(xy 90.62518 -295.146222) (xy 90.296238 -295.146222) (xy 90.295743 -295.170829) (xy 90.287848 -295.219406)
			(xy 90.272264 -295.266087) (xy 90.249393 -295.309664) (xy 90.219828 -295.349008) (xy 90.184335 -295.3831)
			(xy 90.143832 -295.411056) (xy 90.09937 -295.432154) (xy 90.052099 -295.445846) (xy 90.003244 -295.451778)
			(xy 89.954069 -295.449797) (xy 89.90585 -295.439953) (xy 89.859834 -295.422501) (xy 89.817213 -295.397894)
			(xy 89.779092 -295.366769) (xy 89.746457 -295.329932) (xy 89.720154 -295.288336) (xy 89.700863 -295.24306)
			(xy 89.689086 -295.195276) (xy 89.685126 -295.146222) (xy 89.356438 -295.146222) (xy 89.355943 -295.170829)
			(xy 89.348048 -295.219406) (xy 89.332464 -295.266087) (xy 89.309593 -295.309664) (xy 89.280028 -295.349008)
			(xy 89.244535 -295.3831) (xy 89.204032 -295.411056) (xy 89.15957 -295.432154) (xy 89.112299 -295.445846)
			(xy 89.063444 -295.451778) (xy 89.014269 -295.449797) (xy 88.96605 -295.439953) (xy 88.920034 -295.422501)
			(xy 88.877413 -295.397894) (xy 88.839292 -295.366769) (xy 88.806657 -295.329932) (xy 88.780354 -295.288336)
			(xy 88.761063 -295.24306) (xy 88.749286 -295.195276) (xy 88.745326 -295.146222) (xy 88.416384 -295.146222)
			(xy 88.415889 -295.170829) (xy 88.407994 -295.219406) (xy 88.39241 -295.266087) (xy 88.369539 -295.309664)
			(xy 88.339974 -295.349008) (xy 88.304481 -295.3831) (xy 88.263978 -295.411056) (xy 88.219516 -295.432154)
			(xy 88.172245 -295.445846) (xy 88.12339 -295.451778) (xy 88.074215 -295.449797) (xy 88.025996 -295.439953)
			(xy 87.97998 -295.422501) (xy 87.937359 -295.397894) (xy 87.899238 -295.366769) (xy 87.866603 -295.329932)
			(xy 87.8403 -295.288336) (xy 87.821009 -295.24306) (xy 87.809232 -295.195276) (xy 87.805272 -295.146222)
			(xy 87.47633 -295.146222) (xy 87.475835 -295.170829) (xy 87.46794 -295.219406) (xy 87.452356 -295.266087)
			(xy 87.429485 -295.309664) (xy 87.39992 -295.349008) (xy 87.364427 -295.3831) (xy 87.323924 -295.411056)
			(xy 87.279462 -295.432154) (xy 87.232191 -295.445846) (xy 87.183336 -295.451778) (xy 87.134161 -295.449797)
			(xy 87.085942 -295.439953) (xy 87.039926 -295.422501) (xy 86.997305 -295.397894) (xy 86.959184 -295.366769)
			(xy 86.926549 -295.329932) (xy 86.900246 -295.288336) (xy 86.880955 -295.24306) (xy 86.869178 -295.195276)
			(xy 86.865218 -295.146222) (xy 86.536276 -295.146222) (xy 86.535781 -295.170829) (xy 86.527886 -295.219406)
			(xy 86.512302 -295.266087) (xy 86.489431 -295.309664) (xy 86.459866 -295.349008) (xy 86.424373 -295.3831)
			(xy 86.38387 -295.411056) (xy 86.339408 -295.432154) (xy 86.292137 -295.445846) (xy 86.243282 -295.451778)
			(xy 86.194107 -295.449797) (xy 86.145888 -295.439953) (xy 86.099872 -295.422501) (xy 86.057251 -295.397894)
			(xy 86.01913 -295.366769) (xy 85.986495 -295.329932) (xy 85.960192 -295.288336) (xy 85.940901 -295.24306)
			(xy 85.929124 -295.195276) (xy 85.925164 -295.146222) (xy 85.596222 -295.146222) (xy 85.595727 -295.170829)
			(xy 85.587832 -295.219406) (xy 85.572248 -295.266087) (xy 85.549377 -295.309664) (xy 85.519812 -295.349008)
			(xy 85.484319 -295.3831) (xy 85.443816 -295.411056) (xy 85.399354 -295.432154) (xy 85.352083 -295.445846)
			(xy 85.303228 -295.451778) (xy 85.254053 -295.449797) (xy 85.205834 -295.439953) (xy 85.159818 -295.422501)
			(xy 85.117197 -295.397894) (xy 85.079076 -295.366769) (xy 85.046441 -295.329932) (xy 85.020138 -295.288336)
			(xy 85.000847 -295.24306) (xy 84.98907 -295.195276) (xy 84.98511 -295.146222) (xy 84.656422 -295.146222)
			(xy 84.655927 -295.170829) (xy 84.648032 -295.219406) (xy 84.632448 -295.266087) (xy 84.609577 -295.309664)
			(xy 84.580012 -295.349008) (xy 84.544519 -295.3831) (xy 84.504016 -295.411056) (xy 84.459554 -295.432154)
			(xy 84.412283 -295.445846) (xy 84.363428 -295.451778) (xy 84.314253 -295.449797) (xy 84.266034 -295.439953)
			(xy 84.220018 -295.422501) (xy 84.177397 -295.397894) (xy 84.139276 -295.366769) (xy 84.106641 -295.329932)
			(xy 84.080338 -295.288336) (xy 84.061047 -295.24306) (xy 84.04927 -295.195276) (xy 84.04531 -295.146222)
			(xy 83.716368 -295.146222) (xy 83.715873 -295.170829) (xy 83.707978 -295.219406) (xy 83.692394 -295.266087)
			(xy 83.669523 -295.309664) (xy 83.639958 -295.349008) (xy 83.604465 -295.3831) (xy 83.563962 -295.411056)
			(xy 83.5195 -295.432154) (xy 83.472229 -295.445846) (xy 83.423374 -295.451778) (xy 83.374199 -295.449797)
			(xy 83.32598 -295.439953) (xy 83.279964 -295.422501) (xy 83.237343 -295.397894) (xy 83.199222 -295.366769)
			(xy 83.166587 -295.329932) (xy 83.140284 -295.288336) (xy 83.120993 -295.24306) (xy 83.109216 -295.195276)
			(xy 83.105256 -295.146222) (xy 82.776314 -295.146222) (xy 82.775819 -295.170829) (xy 82.767924 -295.219406)
			(xy 82.75234 -295.266087) (xy 82.729469 -295.309664) (xy 82.699904 -295.349008) (xy 82.664411 -295.3831)
			(xy 82.623908 -295.411056) (xy 82.579446 -295.432154) (xy 82.532175 -295.445846) (xy 82.48332 -295.451778)
			(xy 82.434145 -295.449797) (xy 82.385926 -295.439953) (xy 82.33991 -295.422501) (xy 82.297289 -295.397894)
			(xy 82.259168 -295.366769) (xy 82.226533 -295.329932) (xy 82.20023 -295.288336) (xy 82.180939 -295.24306)
			(xy 82.169162 -295.195276) (xy 82.165202 -295.146222) (xy 81.83626 -295.146222) (xy 81.835765 -295.170829)
			(xy 81.82787 -295.219406) (xy 81.812286 -295.266087) (xy 81.789415 -295.309664) (xy 81.75985 -295.349008)
			(xy 81.724357 -295.3831) (xy 81.683854 -295.411056) (xy 81.639392 -295.432154) (xy 81.592121 -295.445846)
			(xy 81.543266 -295.451778) (xy 81.494091 -295.449797) (xy 81.445872 -295.439953) (xy 81.399856 -295.422501)
			(xy 81.357235 -295.397894) (xy 81.319114 -295.366769) (xy 81.286479 -295.329932) (xy 81.260176 -295.288336)
			(xy 81.240885 -295.24306) (xy 81.229108 -295.195276) (xy 81.225148 -295.146222) (xy 74.478134 -295.146222)
			(xy 75.28814 -295.956228) (xy 78.87514 -295.956228) (xy 78.8791 -295.907174) (xy 78.890877 -295.85939)
			(xy 78.910168 -295.814114) (xy 78.936471 -295.772518) (xy 78.969106 -295.735681) (xy 79.007227 -295.704556)
			(xy 79.049848 -295.679949) (xy 79.095864 -295.662497) (xy 79.144083 -295.652653) (xy 79.193258 -295.650672)
			(xy 79.242113 -295.656604) (xy 79.289384 -295.670296) (xy 79.333846 -295.691394) (xy 79.374349 -295.71935)
			(xy 79.409842 -295.753442) (xy 79.439407 -295.792786) (xy 79.462278 -295.836363) (xy 79.477862 -295.883044)
			(xy 79.485757 -295.931621) (xy 79.486252 -295.956228) (xy 82.635102 -295.956228) (xy 82.639062 -295.907174)
			(xy 82.650839 -295.85939) (xy 82.67013 -295.814114) (xy 82.696433 -295.772518) (xy 82.729068 -295.735681)
			(xy 82.767189 -295.704556) (xy 82.80981 -295.679949) (xy 82.855826 -295.662497) (xy 82.904045 -295.652653)
			(xy 82.95322 -295.650672) (xy 83.002075 -295.656604) (xy 83.049346 -295.670296) (xy 83.093808 -295.691394)
			(xy 83.134311 -295.71935) (xy 83.169804 -295.753442) (xy 83.199369 -295.792786) (xy 83.22224 -295.836363)
			(xy 83.237824 -295.883044) (xy 83.245719 -295.931621) (xy 83.246214 -295.956228) (xy 83.575156 -295.956228)
			(xy 83.579116 -295.907174) (xy 83.590893 -295.85939) (xy 83.610184 -295.814114) (xy 83.636487 -295.772518)
			(xy 83.669122 -295.735681) (xy 83.707243 -295.704556) (xy 83.749864 -295.679949) (xy 83.79588 -295.662497)
			(xy 83.844099 -295.652653) (xy 83.893274 -295.650672) (xy 83.942129 -295.656604) (xy 83.9894 -295.670296)
			(xy 84.033862 -295.691394) (xy 84.074365 -295.71935) (xy 84.109858 -295.753442) (xy 84.139423 -295.792786)
			(xy 84.162294 -295.836363) (xy 84.177878 -295.883044) (xy 84.185773 -295.931621) (xy 84.186268 -295.956228)
			(xy 84.51521 -295.956228) (xy 84.51917 -295.907174) (xy 84.530947 -295.85939) (xy 84.550238 -295.814114)
			(xy 84.576541 -295.772518) (xy 84.609176 -295.735681) (xy 84.647297 -295.704556) (xy 84.689918 -295.679949)
			(xy 84.735934 -295.662497) (xy 84.784153 -295.652653) (xy 84.833328 -295.650672) (xy 84.882183 -295.656604)
			(xy 84.929454 -295.670296) (xy 84.973916 -295.691394) (xy 85.014419 -295.71935) (xy 85.049912 -295.753442)
			(xy 85.079477 -295.792786) (xy 85.102348 -295.836363) (xy 85.117932 -295.883044) (xy 85.125827 -295.931621)
			(xy 85.126322 -295.956228) (xy 85.455264 -295.956228) (xy 85.459224 -295.907174) (xy 85.471001 -295.85939)
			(xy 85.490292 -295.814114) (xy 85.516595 -295.772518) (xy 85.54923 -295.735681) (xy 85.587351 -295.704556)
			(xy 85.629972 -295.679949) (xy 85.675988 -295.662497) (xy 85.724207 -295.652653) (xy 85.773382 -295.650672)
			(xy 85.822237 -295.656604) (xy 85.869508 -295.670296) (xy 85.91397 -295.691394) (xy 85.954473 -295.71935)
			(xy 85.989966 -295.753442) (xy 86.019531 -295.792786) (xy 86.042402 -295.836363) (xy 86.057986 -295.883044)
			(xy 86.065881 -295.931621) (xy 86.066376 -295.956228) (xy 86.395318 -295.956228) (xy 86.399278 -295.907174)
			(xy 86.411055 -295.85939) (xy 86.430346 -295.814114) (xy 86.456649 -295.772518) (xy 86.489284 -295.735681)
			(xy 86.527405 -295.704556) (xy 86.570026 -295.679949) (xy 86.616042 -295.662497) (xy 86.664261 -295.652653)
			(xy 86.713436 -295.650672) (xy 86.762291 -295.656604) (xy 86.809562 -295.670296) (xy 86.854024 -295.691394)
			(xy 86.894527 -295.71935) (xy 86.93002 -295.753442) (xy 86.959585 -295.792786) (xy 86.982456 -295.836363)
			(xy 86.99804 -295.883044) (xy 87.005935 -295.931621) (xy 87.00643 -295.956228) (xy 88.275172 -295.956228)
			(xy 88.279132 -295.907174) (xy 88.290909 -295.85939) (xy 88.3102 -295.814114) (xy 88.336503 -295.772518)
			(xy 88.369138 -295.735681) (xy 88.407259 -295.704556) (xy 88.44988 -295.679949) (xy 88.495896 -295.662497)
			(xy 88.544115 -295.652653) (xy 88.59329 -295.650672) (xy 88.642145 -295.656604) (xy 88.689416 -295.670296)
			(xy 88.733878 -295.691394) (xy 88.774381 -295.71935) (xy 88.809874 -295.753442) (xy 88.839439 -295.792786)
			(xy 88.86231 -295.836363) (xy 88.877894 -295.883044) (xy 88.885789 -295.931621) (xy 88.886284 -295.956228)
			(xy 89.215226 -295.956228) (xy 89.219186 -295.907174) (xy 89.230963 -295.85939) (xy 89.250254 -295.814114)
			(xy 89.276557 -295.772518) (xy 89.309192 -295.735681) (xy 89.347313 -295.704556) (xy 89.389934 -295.679949)
			(xy 89.43595 -295.662497) (xy 89.484169 -295.652653) (xy 89.533344 -295.650672) (xy 89.582199 -295.656604)
			(xy 89.62947 -295.670296) (xy 89.673932 -295.691394) (xy 89.714435 -295.71935) (xy 89.749928 -295.753442)
			(xy 89.779493 -295.792786) (xy 89.802364 -295.836363) (xy 89.817948 -295.883044) (xy 89.825843 -295.931621)
			(xy 89.826338 -295.956228) (xy 90.15528 -295.956228) (xy 90.15924 -295.907174) (xy 90.171017 -295.85939)
			(xy 90.190308 -295.814114) (xy 90.216611 -295.772518) (xy 90.249246 -295.735681) (xy 90.287367 -295.704556)
			(xy 90.329988 -295.679949) (xy 90.376004 -295.662497) (xy 90.424223 -295.652653) (xy 90.473398 -295.650672)
			(xy 90.522253 -295.656604) (xy 90.569524 -295.670296) (xy 90.613986 -295.691394) (xy 90.654489 -295.71935)
			(xy 90.689982 -295.753442) (xy 90.719547 -295.792786) (xy 90.742418 -295.836363) (xy 90.758002 -295.883044)
			(xy 90.765897 -295.931621) (xy 90.766392 -295.956228) (xy 91.095334 -295.956228) (xy 91.099294 -295.907174)
			(xy 91.111071 -295.85939) (xy 91.130362 -295.814114) (xy 91.156665 -295.772518) (xy 91.1893 -295.735681)
			(xy 91.227421 -295.704556) (xy 91.270042 -295.679949) (xy 91.316058 -295.662497) (xy 91.364277 -295.652653)
			(xy 91.413452 -295.650672) (xy 91.462307 -295.656604) (xy 91.509578 -295.670296) (xy 91.55404 -295.691394)
			(xy 91.594543 -295.71935) (xy 91.630036 -295.753442) (xy 91.659601 -295.792786) (xy 91.682472 -295.836363)
			(xy 91.698056 -295.883044) (xy 91.705951 -295.931621) (xy 91.706446 -295.956228) (xy 92.035134 -295.956228)
			(xy 92.039094 -295.907174) (xy 92.050871 -295.85939) (xy 92.070162 -295.814114) (xy 92.096465 -295.772518)
			(xy 92.1291 -295.735681) (xy 92.167221 -295.704556) (xy 92.209842 -295.679949) (xy 92.255858 -295.662497)
			(xy 92.304077 -295.652653) (xy 92.353252 -295.650672) (xy 92.402107 -295.656604) (xy 92.449378 -295.670296)
			(xy 92.49384 -295.691394) (xy 92.534343 -295.71935) (xy 92.569836 -295.753442) (xy 92.599401 -295.792786)
			(xy 92.622272 -295.836363) (xy 92.637856 -295.883044) (xy 92.645751 -295.931621) (xy 92.646246 -295.956228)
			(xy 94.855296 -295.956228) (xy 94.859256 -295.907174) (xy 94.871033 -295.85939) (xy 94.890324 -295.814114)
			(xy 94.916627 -295.772518) (xy 94.949262 -295.735681) (xy 94.987383 -295.704556) (xy 95.030004 -295.679949)
			(xy 95.07602 -295.662497) (xy 95.124239 -295.652653) (xy 95.173414 -295.650672) (xy 95.222269 -295.656604)
			(xy 95.26954 -295.670296) (xy 95.314002 -295.691394) (xy 95.354505 -295.71935) (xy 95.389998 -295.753442)
			(xy 95.419563 -295.792786) (xy 95.442434 -295.836363) (xy 95.458018 -295.883044) (xy 95.465913 -295.931621)
			(xy 95.466408 -295.956228) (xy 95.79535 -295.956228) (xy 95.79931 -295.907174) (xy 95.811087 -295.85939)
			(xy 95.830378 -295.814114) (xy 95.856681 -295.772518) (xy 95.889316 -295.735681) (xy 95.927437 -295.704556)
			(xy 95.970058 -295.679949) (xy 96.016074 -295.662497) (xy 96.064293 -295.652653) (xy 96.113468 -295.650672)
			(xy 96.162323 -295.656604) (xy 96.209594 -295.670296) (xy 96.254056 -295.691394) (xy 96.294559 -295.71935)
			(xy 96.330052 -295.753442) (xy 96.359617 -295.792786) (xy 96.382488 -295.836363) (xy 96.398072 -295.883044)
			(xy 96.405967 -295.931621) (xy 96.406462 -295.956228) (xy 101.435166 -295.956228) (xy 101.439126 -295.907174)
			(xy 101.450903 -295.85939) (xy 101.470194 -295.814114) (xy 101.496497 -295.772518) (xy 101.529132 -295.735681)
			(xy 101.567253 -295.704556) (xy 101.609874 -295.679949) (xy 101.65589 -295.662497) (xy 101.704109 -295.652653)
			(xy 101.753284 -295.650672) (xy 101.802139 -295.656604) (xy 101.84941 -295.670296) (xy 101.893872 -295.691394)
			(xy 101.934375 -295.71935) (xy 101.969868 -295.753442) (xy 101.999433 -295.792786) (xy 102.022304 -295.836363)
			(xy 102.037888 -295.883044) (xy 102.045783 -295.931621) (xy 102.046278 -295.956228) (xy 102.045783 -295.980835)
			(xy 102.037888 -296.029412) (xy 102.022304 -296.076093) (xy 101.999433 -296.11967) (xy 101.969868 -296.159014)
			(xy 101.934375 -296.193106) (xy 101.893872 -296.221062) (xy 101.84941 -296.24216) (xy 101.802139 -296.255852)
			(xy 101.753284 -296.261784) (xy 101.704109 -296.259803) (xy 101.65589 -296.249959) (xy 101.609874 -296.232507)
			(xy 101.567253 -296.2079) (xy 101.529132 -296.176775) (xy 101.496497 -296.139938) (xy 101.470194 -296.098342)
			(xy 101.450903 -296.053066) (xy 101.439126 -296.005282) (xy 101.435166 -295.956228) (xy 96.406462 -295.956228)
			(xy 96.405967 -295.980835) (xy 96.398072 -296.029412) (xy 96.382488 -296.076093) (xy 96.359617 -296.11967)
			(xy 96.330052 -296.159014) (xy 96.294559 -296.193106) (xy 96.254056 -296.221062) (xy 96.209594 -296.24216)
			(xy 96.162323 -296.255852) (xy 96.113468 -296.261784) (xy 96.064293 -296.259803) (xy 96.016074 -296.249959)
			(xy 95.970058 -296.232507) (xy 95.927437 -296.2079) (xy 95.889316 -296.176775) (xy 95.856681 -296.139938)
			(xy 95.830378 -296.098342) (xy 95.811087 -296.053066) (xy 95.79931 -296.005282) (xy 95.79535 -295.956228)
			(xy 95.466408 -295.956228) (xy 95.465913 -295.980835) (xy 95.458018 -296.029412) (xy 95.442434 -296.076093)
			(xy 95.419563 -296.11967) (xy 95.389998 -296.159014) (xy 95.354505 -296.193106) (xy 95.314002 -296.221062)
			(xy 95.26954 -296.24216) (xy 95.222269 -296.255852) (xy 95.173414 -296.261784) (xy 95.124239 -296.259803)
			(xy 95.07602 -296.249959) (xy 95.030004 -296.232507) (xy 94.987383 -296.2079) (xy 94.949262 -296.176775)
			(xy 94.916627 -296.139938) (xy 94.890324 -296.098342) (xy 94.871033 -296.053066) (xy 94.859256 -296.005282)
			(xy 94.855296 -295.956228) (xy 92.646246 -295.956228) (xy 92.645751 -295.980835) (xy 92.637856 -296.029412)
			(xy 92.622272 -296.076093) (xy 92.599401 -296.11967) (xy 92.569836 -296.159014) (xy 92.534343 -296.193106)
			(xy 92.49384 -296.221062) (xy 92.449378 -296.24216) (xy 92.402107 -296.255852) (xy 92.353252 -296.261784)
			(xy 92.304077 -296.259803) (xy 92.255858 -296.249959) (xy 92.209842 -296.232507) (xy 92.167221 -296.2079)
			(xy 92.1291 -296.176775) (xy 92.096465 -296.139938) (xy 92.070162 -296.098342) (xy 92.050871 -296.053066)
			(xy 92.039094 -296.005282) (xy 92.035134 -295.956228) (xy 91.706446 -295.956228) (xy 91.705951 -295.980835)
			(xy 91.698056 -296.029412) (xy 91.682472 -296.076093) (xy 91.659601 -296.11967) (xy 91.630036 -296.159014)
			(xy 91.594543 -296.193106) (xy 91.55404 -296.221062) (xy 91.509578 -296.24216) (xy 91.462307 -296.255852)
			(xy 91.413452 -296.261784) (xy 91.364277 -296.259803) (xy 91.316058 -296.249959) (xy 91.270042 -296.232507)
			(xy 91.227421 -296.2079) (xy 91.1893 -296.176775) (xy 91.156665 -296.139938) (xy 91.130362 -296.098342)
			(xy 91.111071 -296.053066) (xy 91.099294 -296.005282) (xy 91.095334 -295.956228) (xy 90.766392 -295.956228)
			(xy 90.765897 -295.980835) (xy 90.758002 -296.029412) (xy 90.742418 -296.076093) (xy 90.719547 -296.11967)
			(xy 90.689982 -296.159014) (xy 90.654489 -296.193106) (xy 90.613986 -296.221062) (xy 90.569524 -296.24216)
			(xy 90.522253 -296.255852) (xy 90.473398 -296.261784) (xy 90.424223 -296.259803) (xy 90.376004 -296.249959)
			(xy 90.329988 -296.232507) (xy 90.287367 -296.2079) (xy 90.249246 -296.176775) (xy 90.216611 -296.139938)
			(xy 90.190308 -296.098342) (xy 90.171017 -296.053066) (xy 90.15924 -296.005282) (xy 90.15528 -295.956228)
			(xy 89.826338 -295.956228) (xy 89.825843 -295.980835) (xy 89.817948 -296.029412) (xy 89.802364 -296.076093)
			(xy 89.779493 -296.11967) (xy 89.749928 -296.159014) (xy 89.714435 -296.193106) (xy 89.673932 -296.221062)
			(xy 89.62947 -296.24216) (xy 89.582199 -296.255852) (xy 89.533344 -296.261784) (xy 89.484169 -296.259803)
			(xy 89.43595 -296.249959) (xy 89.389934 -296.232507) (xy 89.347313 -296.2079) (xy 89.309192 -296.176775)
			(xy 89.276557 -296.139938) (xy 89.250254 -296.098342) (xy 89.230963 -296.053066) (xy 89.219186 -296.005282)
			(xy 89.215226 -295.956228) (xy 88.886284 -295.956228) (xy 88.885789 -295.980835) (xy 88.877894 -296.029412)
			(xy 88.86231 -296.076093) (xy 88.839439 -296.11967) (xy 88.809874 -296.159014) (xy 88.774381 -296.193106)
			(xy 88.733878 -296.221062) (xy 88.689416 -296.24216) (xy 88.642145 -296.255852) (xy 88.59329 -296.261784)
			(xy 88.544115 -296.259803) (xy 88.495896 -296.249959) (xy 88.44988 -296.232507) (xy 88.407259 -296.2079)
			(xy 88.369138 -296.176775) (xy 88.336503 -296.139938) (xy 88.3102 -296.098342) (xy 88.290909 -296.053066)
			(xy 88.279132 -296.005282) (xy 88.275172 -295.956228) (xy 87.00643 -295.956228) (xy 87.005935 -295.980835)
			(xy 86.99804 -296.029412) (xy 86.982456 -296.076093) (xy 86.959585 -296.11967) (xy 86.93002 -296.159014)
			(xy 86.894527 -296.193106) (xy 86.854024 -296.221062) (xy 86.809562 -296.24216) (xy 86.762291 -296.255852)
			(xy 86.713436 -296.261784) (xy 86.664261 -296.259803) (xy 86.616042 -296.249959) (xy 86.570026 -296.232507)
			(xy 86.527405 -296.2079) (xy 86.489284 -296.176775) (xy 86.456649 -296.139938) (xy 86.430346 -296.098342)
			(xy 86.411055 -296.053066) (xy 86.399278 -296.005282) (xy 86.395318 -295.956228) (xy 86.066376 -295.956228)
			(xy 86.065881 -295.980835) (xy 86.057986 -296.029412) (xy 86.042402 -296.076093) (xy 86.019531 -296.11967)
			(xy 85.989966 -296.159014) (xy 85.954473 -296.193106) (xy 85.91397 -296.221062) (xy 85.869508 -296.24216)
			(xy 85.822237 -296.255852) (xy 85.773382 -296.261784) (xy 85.724207 -296.259803) (xy 85.675988 -296.249959)
			(xy 85.629972 -296.232507) (xy 85.587351 -296.2079) (xy 85.54923 -296.176775) (xy 85.516595 -296.139938)
			(xy 85.490292 -296.098342) (xy 85.471001 -296.053066) (xy 85.459224 -296.005282) (xy 85.455264 -295.956228)
			(xy 85.126322 -295.956228) (xy 85.125827 -295.980835) (xy 85.117932 -296.029412) (xy 85.102348 -296.076093)
			(xy 85.079477 -296.11967) (xy 85.049912 -296.159014) (xy 85.014419 -296.193106) (xy 84.973916 -296.221062)
			(xy 84.929454 -296.24216) (xy 84.882183 -296.255852) (xy 84.833328 -296.261784) (xy 84.784153 -296.259803)
			(xy 84.735934 -296.249959) (xy 84.689918 -296.232507) (xy 84.647297 -296.2079) (xy 84.609176 -296.176775)
			(xy 84.576541 -296.139938) (xy 84.550238 -296.098342) (xy 84.530947 -296.053066) (xy 84.51917 -296.005282)
			(xy 84.51521 -295.956228) (xy 84.186268 -295.956228) (xy 84.185773 -295.980835) (xy 84.177878 -296.029412)
			(xy 84.162294 -296.076093) (xy 84.139423 -296.11967) (xy 84.109858 -296.159014) (xy 84.074365 -296.193106)
			(xy 84.033862 -296.221062) (xy 83.9894 -296.24216) (xy 83.942129 -296.255852) (xy 83.893274 -296.261784)
			(xy 83.844099 -296.259803) (xy 83.79588 -296.249959) (xy 83.749864 -296.232507) (xy 83.707243 -296.2079)
			(xy 83.669122 -296.176775) (xy 83.636487 -296.139938) (xy 83.610184 -296.098342) (xy 83.590893 -296.053066)
			(xy 83.579116 -296.005282) (xy 83.575156 -295.956228) (xy 83.246214 -295.956228) (xy 83.245719 -295.980835)
			(xy 83.237824 -296.029412) (xy 83.22224 -296.076093) (xy 83.199369 -296.11967) (xy 83.169804 -296.159014)
			(xy 83.134311 -296.193106) (xy 83.093808 -296.221062) (xy 83.049346 -296.24216) (xy 83.002075 -296.255852)
			(xy 82.95322 -296.261784) (xy 82.904045 -296.259803) (xy 82.855826 -296.249959) (xy 82.80981 -296.232507)
			(xy 82.767189 -296.2079) (xy 82.729068 -296.176775) (xy 82.696433 -296.139938) (xy 82.67013 -296.098342)
			(xy 82.650839 -296.053066) (xy 82.639062 -296.005282) (xy 82.635102 -295.956228) (xy 79.486252 -295.956228)
			(xy 79.485757 -295.980835) (xy 79.477862 -296.029412) (xy 79.462278 -296.076093) (xy 79.439407 -296.11967)
			(xy 79.409842 -296.159014) (xy 79.374349 -296.193106) (xy 79.333846 -296.221062) (xy 79.289384 -296.24216)
			(xy 79.242113 -296.255852) (xy 79.193258 -296.261784) (xy 79.144083 -296.259803) (xy 79.095864 -296.249959)
			(xy 79.049848 -296.232507) (xy 79.007227 -296.2079) (xy 78.969106 -296.176775) (xy 78.936471 -296.139938)
			(xy 78.910168 -296.098342) (xy 78.890877 -296.053066) (xy 78.8791 -296.005282) (xy 78.87514 -295.956228)
			(xy 75.28814 -295.956228) (xy 77.646995 -298.315083) (xy 87.657172 -298.315083) (xy 87.657172 -298.251161)
			(xy 87.665183 -298.187743) (xy 87.68108 -298.125829) (xy 87.704612 -298.066396) (xy 87.735406 -298.010381)
			(xy 87.772979 -297.958666) (xy 87.816736 -297.912069) (xy 87.865989 -297.871324) (xy 87.91996 -297.837073)
			(xy 87.977799 -297.809856) (xy 88.038592 -297.790103) (xy 88.101382 -297.778125) (xy 88.165178 -297.774112)
			(xy 88.228974 -297.778125) (xy 88.291764 -297.790103) (xy 88.352557 -297.809856) (xy 88.410396 -297.837073)
			(xy 88.464367 -297.871324) (xy 88.51362 -297.912069) (xy 88.557377 -297.958666) (xy 88.59495 -298.010381)
			(xy 88.625744 -298.066396) (xy 88.649276 -298.125829) (xy 88.665173 -298.187743) (xy 88.673184 -298.251161)
			(xy 88.673686 -298.283122) (xy 88.673184 -298.315083) (xy 88.665173 -298.378501) (xy 88.649276 -298.440415)
			(xy 88.625744 -298.499848) (xy 88.59495 -298.555863) (xy 88.557377 -298.607578) (xy 88.51362 -298.654175)
			(xy 88.464367 -298.69492) (xy 88.410396 -298.729171) (xy 88.352557 -298.756388) (xy 88.291764 -298.776141)
			(xy 88.228974 -298.788119) (xy 88.165178 -298.792133) (xy 88.101382 -298.788119) (xy 88.038592 -298.776141)
			(xy 87.977799 -298.756388) (xy 87.91996 -298.729171) (xy 87.865989 -298.69492) (xy 87.816736 -298.654175)
			(xy 87.772979 -298.607578) (xy 87.735406 -298.555863) (xy 87.704612 -298.499848) (xy 87.68108 -298.440415)
			(xy 87.665183 -298.378501) (xy 87.657172 -298.315083) (xy 77.646995 -298.315083) (xy 80.308958 -300.977046)
			(xy 95.651064 -300.977046) (xy 95.655135 -300.921424) (xy 95.667261 -300.866987) (xy 95.687184 -300.814896)
			(xy 95.71448 -300.766261) (xy 95.748566 -300.722118) (xy 95.788715 -300.683409) (xy 95.834073 -300.650958)
			(xy 95.883673 -300.625457) (xy 95.936457 -300.60745) (xy 95.9913 -300.59732) (xy 96.047034 -300.595283)
			(xy 96.102471 -300.601383) (xy 96.156428 -300.615489) (xy 96.207757 -300.637301) (xy 96.255363 -300.666355)
			(xy 96.298231 -300.70203) (xy 96.335448 -300.743567) (xy 96.366221 -300.79008) (xy 96.389893 -300.840577)
			(xy 96.405961 -300.893984) (xy 96.414081 -300.94916) (xy 96.41459 -300.977046) (xy 96.414081 -301.004932)
			(xy 96.405961 -301.060108) (xy 96.389893 -301.113515) (xy 96.366221 -301.164012) (xy 96.335448 -301.210525)
			(xy 96.298231 -301.252062) (xy 96.255363 -301.287737) (xy 96.207757 -301.316791) (xy 96.156428 -301.338603)
			(xy 96.102471 -301.352709) (xy 96.047034 -301.358809) (xy 95.9913 -301.356772) (xy 95.936457 -301.346642)
			(xy 95.883673 -301.328635) (xy 95.834073 -301.303134) (xy 95.788715 -301.270683) (xy 95.748566 -301.231974)
			(xy 95.71448 -301.187831) (xy 95.687184 -301.139196) (xy 95.667261 -301.087105) (xy 95.655135 -301.032668)
			(xy 95.651064 -300.977046) (xy 80.308958 -300.977046) (xy 81.111598 -301.779686) (xy 92.19006 -301.779686)
			(xy 92.194131 -301.724064) (xy 92.206257 -301.669627) (xy 92.22618 -301.617536) (xy 92.253476 -301.568901)
			(xy 92.287562 -301.524758) (xy 92.327711 -301.486049) (xy 92.373069 -301.453598) (xy 92.422669 -301.428097)
			(xy 92.475453 -301.41009) (xy 92.530296 -301.39996) (xy 92.58603 -301.397923) (xy 92.641467 -301.404023)
			(xy 92.695424 -301.418129) (xy 92.746753 -301.439941) (xy 92.794359 -301.468995) (xy 92.837227 -301.50467)
			(xy 92.874444 -301.546207) (xy 92.905217 -301.59272) (xy 92.928889 -301.643217) (xy 92.944957 -301.696624)
			(xy 92.953077 -301.7518) (xy 92.953586 -301.779686) (xy 92.953077 -301.807572) (xy 92.944957 -301.862748)
			(xy 92.928889 -301.916155) (xy 92.905217 -301.966652) (xy 92.874444 -302.013165) (xy 92.837227 -302.054702)
			(xy 92.794359 -302.090377) (xy 92.746753 -302.119431) (xy 92.695424 -302.141243) (xy 92.641467 -302.155349)
			(xy 92.58603 -302.161449) (xy 92.530296 -302.159412) (xy 92.475453 -302.149282) (xy 92.422669 -302.131275)
			(xy 92.373069 -302.105774) (xy 92.327711 -302.073323) (xy 92.287562 -302.034614) (xy 92.253476 -301.990471)
			(xy 92.22618 -301.941836) (xy 92.206257 -301.889745) (xy 92.194131 -301.835308) (xy 92.19006 -301.779686)
			(xy 81.111598 -301.779686) (xy 81.601056 -302.269144) (xy 81.607127 -302.274851) (xy 81.622049 -302.282241)
			(xy 81.630266 -302.283622) (xy 81.630774 -302.283622) (xy 81.699859 -302.29249) (xy 81.837003 -302.316903)
			(xy 81.972586 -302.348871) (xy 82.106192 -302.388294) (xy 82.23741 -302.435052) (xy 82.365839 -302.489001)
			(xy 82.491085 -302.549977) (xy 82.612764 -302.617791) (xy 82.730503 -302.692237) (xy 82.843941 -302.773086)
			(xy 82.873093 -302.7964) (xy 84.778634 -302.7964) (xy 84.782549 -302.719211) (xy 84.794252 -302.642815)
			(xy 84.813625 -302.567994) (xy 84.840468 -302.495517) (xy 84.874505 -302.426128) (xy 84.915388 -302.360538)
			(xy 84.962697 -302.299421) (xy 85.015946 -302.243403) (xy 85.074589 -302.193061) (xy 85.138025 -302.148909)
			(xy 85.205602 -302.111402) (xy 85.276627 -302.080924) (xy 85.35037 -302.057788) (xy 85.426076 -302.042231)
			(xy 85.502968 -302.034413) (xy 85.541612 -302.03394) (xy 85.579854 -302.034414) (xy 85.655949 -302.042117)
			(xy 85.730889 -302.057403) (xy 85.803921 -302.08012) (xy 85.8393 -302.094646) (xy 85.848893 -302.098199)
			(xy 85.869331 -302.098199) (xy 85.878924 -302.094646) (xy 85.91431 -302.08014) (xy 85.987342 -302.057433)
			(xy 86.06228 -302.042148) (xy 86.138372 -302.034437) (xy 86.176612 -302.03394) (xy 86.215259 -302.034334)
			(xy 86.292157 -302.042155) (xy 86.367869 -302.057715) (xy 86.441619 -302.080855) (xy 86.512649 -302.111338)
			(xy 86.58023 -302.148849) (xy 86.643671 -302.193006) (xy 86.702318 -302.243354) (xy 86.755571 -302.299377)
			(xy 86.802883 -302.3605) (xy 86.843769 -302.426096) (xy 86.877808 -302.495491) (xy 86.904653 -302.567974)
			(xy 86.924027 -302.642801) (xy 86.935731 -302.719205) (xy 86.939646 -302.7964) (xy 86.935731 -302.873595)
			(xy 86.924027 -302.949999) (xy 86.904653 -303.024826) (xy 86.877808 -303.097309) (xy 86.843769 -303.166704)
			(xy 86.802883 -303.2323) (xy 86.785179 -303.255172) (xy 92.274134 -303.255172) (xy 92.278205 -303.19955)
			(xy 92.290331 -303.145113) (xy 92.310254 -303.093022) (xy 92.33755 -303.044387) (xy 92.371636 -303.000244)
			(xy 92.411785 -302.961535) (xy 92.457143 -302.929084) (xy 92.506743 -302.903583) (xy 92.559527 -302.885576)
			(xy 92.61437 -302.875446) (xy 92.670104 -302.873409) (xy 92.725541 -302.879509) (xy 92.779498 -302.893615)
			(xy 92.830827 -302.915427) (xy 92.878433 -302.944481) (xy 92.921301 -302.980156) (xy 92.958518 -303.021693)
			(xy 92.989291 -303.068206) (xy 93.012963 -303.118703) (xy 93.029031 -303.17211) (xy 93.037151 -303.227286)
			(xy 93.03766 -303.255172) (xy 93.037151 -303.283058) (xy 93.029031 -303.338234) (xy 93.012963 -303.391641)
			(xy 92.989291 -303.442138) (xy 92.958518 -303.488651) (xy 92.921301 -303.530188) (xy 92.878433 -303.565863)
			(xy 92.830827 -303.594917) (xy 92.779498 -303.616729) (xy 92.725541 -303.630835) (xy 92.670104 -303.636935)
			(xy 92.61437 -303.634898) (xy 92.559527 -303.624768) (xy 92.506743 -303.606761) (xy 92.457143 -303.58126)
			(xy 92.411785 -303.548809) (xy 92.371636 -303.5101) (xy 92.33755 -303.465957) (xy 92.310254 -303.417322)
			(xy 92.290331 -303.365231) (xy 92.278205 -303.310794) (xy 92.274134 -303.255172) (xy 86.785179 -303.255172)
			(xy 86.755571 -303.293423) (xy 86.702318 -303.349446) (xy 86.643671 -303.399794) (xy 86.58023 -303.443951)
			(xy 86.512649 -303.481462) (xy 86.441619 -303.511945) (xy 86.367869 -303.535085) (xy 86.292157 -303.550645)
			(xy 86.215259 -303.558466) (xy 86.176612 -303.558956) (xy 86.138371 -303.558474) (xy 86.062276 -303.550774)
			(xy 85.987335 -303.53549) (xy 85.914303 -303.512775) (xy 85.878924 -303.49825) (xy 85.869331 -303.494697)
			(xy 85.848893 -303.494697) (xy 85.8393 -303.49825) (xy 85.803924 -303.512781) (xy 85.730888 -303.535481)
			(xy 85.655947 -303.550759) (xy 85.579853 -303.558462) (xy 85.541612 -303.558956) (xy 85.502968 -303.558387)
			(xy 85.426076 -303.550569) (xy 85.35037 -303.535012) (xy 85.276627 -303.511876) (xy 85.205602 -303.481398)
			(xy 85.138025 -303.443891) (xy 85.074589 -303.399739) (xy 85.015946 -303.349397) (xy 84.962697 -303.293379)
			(xy 84.915388 -303.232262) (xy 84.874505 -303.166672) (xy 84.840468 -303.097283) (xy 84.813625 -303.024806)
			(xy 84.794252 -302.949985) (xy 84.782549 -302.873589) (xy 84.778634 -302.7964) (xy 82.873093 -302.7964)
			(xy 82.95273 -302.860089) (xy 83.056536 -302.952981) (xy 83.155041 -303.051476) (xy 83.247944 -303.155273)
			(xy 83.334958 -303.264053) (xy 83.415818 -303.377482) (xy 83.490276 -303.495213) (xy 83.558103 -303.616885)
			(xy 83.619092 -303.742125) (xy 83.673054 -303.870549) (xy 83.719826 -304.001762) (xy 83.729098 -304.033174)
			(xy 92.945966 -304.033174) (xy 92.946468 -304.001213) (xy 92.954479 -303.937795) (xy 92.970376 -303.875881)
			(xy 92.993908 -303.816448) (xy 93.024702 -303.760433) (xy 93.062275 -303.708718) (xy 93.106032 -303.662121)
			(xy 93.155285 -303.621376) (xy 93.209256 -303.587125) (xy 93.267095 -303.559908) (xy 93.327888 -303.540155)
			(xy 93.390678 -303.528177) (xy 93.454474 -303.524164) (xy 93.51827 -303.528177) (xy 93.58106 -303.540155)
			(xy 93.641853 -303.559908) (xy 93.699692 -303.587125) (xy 93.753663 -303.621376) (xy 93.802916 -303.662121)
			(xy 93.846673 -303.708718) (xy 93.884246 -303.760433) (xy 93.91504 -303.816448) (xy 93.938572 -303.875881)
			(xy 93.954469 -303.937795) (xy 93.96248 -304.001213) (xy 93.962982 -304.033174) (xy 93.962469 -304.065957)
			(xy 93.954045 -304.13098) (xy 93.937332 -304.19438) (xy 93.912609 -304.255106) (xy 93.880284 -304.312151)
			(xy 93.840896 -304.364567) (xy 93.795096 -304.411486) (xy 93.769688 -304.432208) (xy 93.762771 -304.438106)
			(xy 93.753283 -304.453598) (xy 93.751146 -304.462434) (xy 93.745304 -304.492152) (xy 93.743955 -304.500954)
			(xy 93.74683 -304.518517) (xy 93.750892 -304.526442) (xy 93.765761 -304.554834) (xy 93.786839 -304.615355)
			(xy 93.797504 -304.678548) (xy 93.798136 -304.710592) (xy 93.79765 -304.737843) (xy 93.789894 -304.791791)
			(xy 93.774539 -304.844086) (xy 93.751897 -304.893663) (xy 93.722431 -304.939513) (xy 93.68674 -304.980704)
			(xy 93.645549 -305.016395) (xy 93.599699 -305.045861) (xy 93.550122 -305.068503) (xy 93.497827 -305.083858)
			(xy 93.443879 -305.091614) (xy 93.389377 -305.091614) (xy 93.335429 -305.083858) (xy 93.283134 -305.068503)
			(xy 93.233557 -305.045861) (xy 93.187707 -305.016395) (xy 93.146516 -304.980704) (xy 93.110825 -304.939513)
			(xy 93.081359 -304.893663) (xy 93.058717 -304.844086) (xy 93.043362 -304.791791) (xy 93.035606 -304.737843)
			(xy 93.03512 -304.710592) (xy 93.035659 -304.681226) (xy 93.0447 -304.623194) (xy 93.062521 -304.567231)
			(xy 93.088702 -304.514657) (xy 93.105224 -304.490374) (xy 93.110038 -304.482893) (xy 93.114699 -304.465737)
			(xy 93.114368 -304.456846) (xy 93.111574 -304.426366) (xy 93.110508 -304.417453) (xy 93.102963 -304.401181)
			(xy 93.096842 -304.394616) (xy 93.073395 -304.370658) (xy 93.032348 -304.317659) (xy 92.99862 -304.259726)
			(xy 92.972796 -304.197864) (xy 92.955324 -304.133145) (xy 92.946506 -304.066692) (xy 92.945966 -304.033174)
			(xy 83.729098 -304.033174) (xy 83.759263 -304.135364) (xy 83.791244 -304.270943) (xy 83.815672 -304.408085)
			(xy 83.824572 -304.477166) (xy 83.824572 -304.477928) (xy 83.826023 -304.486122) (xy 83.833403 -304.501026)
			(xy 83.83905 -304.507138) (xy 84.070401 -304.738489) (xy 91.753938 -304.738489) (xy 91.753938 -304.674567)
			(xy 91.761949 -304.611149) (xy 91.777846 -304.549235) (xy 91.801378 -304.489802) (xy 91.832172 -304.433787)
			(xy 91.869745 -304.382072) (xy 91.913502 -304.335475) (xy 91.962755 -304.29473) (xy 92.016726 -304.260479)
			(xy 92.074565 -304.233262) (xy 92.135358 -304.213509) (xy 92.198148 -304.201531) (xy 92.261944 -304.197518)
			(xy 92.32574 -304.201531) (xy 92.38853 -304.213509) (xy 92.449323 -304.233262) (xy 92.507162 -304.260479)
			(xy 92.561133 -304.29473) (xy 92.610386 -304.335475) (xy 92.654143 -304.382072) (xy 92.691716 -304.433787)
			(xy 92.72251 -304.489802) (xy 92.746042 -304.549235) (xy 92.761939 -304.611149) (xy 92.76995 -304.674567)
			(xy 92.770452 -304.706528) (xy 92.76995 -304.738489) (xy 92.761939 -304.801907) (xy 92.746042 -304.863821)
			(xy 92.72251 -304.923254) (xy 92.691716 -304.979269) (xy 92.654143 -305.030984) (xy 92.610386 -305.077581)
			(xy 92.561133 -305.118326) (xy 92.507162 -305.152577) (xy 92.449323 -305.179794) (xy 92.38853 -305.199547)
			(xy 92.32574 -305.211525) (xy 92.261944 -305.215539) (xy 92.198148 -305.211525) (xy 92.135358 -305.199547)
			(xy 92.074565 -305.179794) (xy 92.016726 -305.152577) (xy 91.962755 -305.118326) (xy 91.913502 -305.077581)
			(xy 91.869745 -305.030984) (xy 91.832172 -304.979269) (xy 91.801378 -304.923254) (xy 91.777846 -304.863821)
			(xy 91.761949 -304.801907) (xy 91.753938 -304.738489) (xy 84.070401 -304.738489) (xy 85.796077 -306.464165)
			(xy 87.854784 -306.464165) (xy 87.854784 -306.400243) (xy 87.862795 -306.336825) (xy 87.878692 -306.274911)
			(xy 87.902224 -306.215478) (xy 87.933018 -306.159463) (xy 87.970591 -306.107748) (xy 88.014348 -306.061151)
			(xy 88.063601 -306.020406) (xy 88.117572 -305.986155) (xy 88.175411 -305.958938) (xy 88.236204 -305.939185)
			(xy 88.298994 -305.927207) (xy 88.36279 -305.923194) (xy 88.426586 -305.927207) (xy 88.489376 -305.939185)
			(xy 88.550169 -305.958938) (xy 88.608008 -305.986155) (xy 88.659611 -306.018903) (xy 93.552258 -306.018903)
			(xy 93.552258 -305.954981) (xy 93.560269 -305.891563) (xy 93.576166 -305.829649) (xy 93.599698 -305.770216)
			(xy 93.630492 -305.714201) (xy 93.668065 -305.662486) (xy 93.711822 -305.615889) (xy 93.761075 -305.575144)
			(xy 93.815046 -305.540893) (xy 93.872885 -305.513676) (xy 93.933678 -305.493923) (xy 93.996468 -305.481945)
			(xy 94.060264 -305.477932) (xy 94.12406 -305.481945) (xy 94.18685 -305.493923) (xy 94.247643 -305.513676)
			(xy 94.305482 -305.540893) (xy 94.359453 -305.575144) (xy 94.408706 -305.615889) (xy 94.452463 -305.662486)
			(xy 94.490036 -305.714201) (xy 94.52083 -305.770216) (xy 94.544362 -305.829649) (xy 94.560259 -305.891563)
			(xy 94.56827 -305.954981) (xy 94.568772 -305.986942) (xy 94.56827 -306.018903) (xy 94.560259 -306.082321)
			(xy 94.544362 -306.144235) (xy 94.52083 -306.203668) (xy 94.490036 -306.259683) (xy 94.452463 -306.311398)
			(xy 94.408706 -306.357995) (xy 94.359453 -306.39874) (xy 94.305482 -306.432991) (xy 94.247643 -306.460208)
			(xy 94.18685 -306.479961) (xy 94.12406 -306.491939) (xy 94.060264 -306.495953) (xy 93.996468 -306.491939)
			(xy 93.933678 -306.479961) (xy 93.872885 -306.460208) (xy 93.815046 -306.432991) (xy 93.761075 -306.39874)
			(xy 93.711822 -306.357995) (xy 93.668065 -306.311398) (xy 93.630492 -306.259683) (xy 93.599698 -306.203668)
			(xy 93.576166 -306.144235) (xy 93.560269 -306.082321) (xy 93.552258 -306.018903) (xy 88.659611 -306.018903)
			(xy 88.661979 -306.020406) (xy 88.711232 -306.061151) (xy 88.754989 -306.107748) (xy 88.792562 -306.159463)
			(xy 88.823356 -306.215478) (xy 88.846888 -306.274911) (xy 88.862785 -306.336825) (xy 88.870796 -306.400243)
			(xy 88.871298 -306.432204) (xy 88.870796 -306.464165) (xy 88.862785 -306.527583) (xy 88.846888 -306.589497)
			(xy 88.823356 -306.64893) (xy 88.792562 -306.704945) (xy 88.754989 -306.75666) (xy 88.711232 -306.803257)
			(xy 88.661979 -306.844002) (xy 88.608008 -306.878253) (xy 88.550169 -306.90547) (xy 88.489376 -306.925223)
			(xy 88.426586 -306.937201) (xy 88.36279 -306.941215) (xy 88.298994 -306.937201) (xy 88.236204 -306.925223)
			(xy 88.175411 -306.90547) (xy 88.117572 -306.878253) (xy 88.063601 -306.844002) (xy 88.014348 -306.803257)
			(xy 87.970591 -306.75666) (xy 87.933018 -306.704945) (xy 87.902224 -306.64893) (xy 87.878692 -306.589497)
			(xy 87.862795 -306.527583) (xy 87.854784 -306.464165) (xy 85.796077 -306.464165) (xy 86.757002 -307.42509)
			(xy 86.7644 -307.431937) (xy 86.782998 -307.439672) (xy 86.79307 -307.440076) (xy 88.649048 -307.440076)
			(xy 88.658861 -307.439583) (xy 88.677029 -307.432145) (xy 88.684354 -307.425598) (xy 88.74252 -307.368956)
			(xy 88.750394 -307.350922) (xy 88.750648 -307.341016) (xy 88.751874 -307.309569) (xy 88.761137 -307.247321)
			(xy 88.778013 -307.186692) (xy 88.802243 -307.128609) (xy 88.833457 -307.073961) (xy 88.871178 -307.023584)
			(xy 88.914828 -306.978248) (xy 88.96374 -306.938646) (xy 89.017166 -306.905385) (xy 89.074289 -306.878972)
			(xy 89.134235 -306.859811) (xy 89.196088 -306.848197) (xy 89.258902 -306.844305) (xy 89.321716 -306.848197)
			(xy 89.383569 -306.859811) (xy 89.443515 -306.878972) (xy 89.500638 -306.905385) (xy 89.554064 -306.938646)
			(xy 89.602976 -306.978248) (xy 89.646626 -307.023584) (xy 89.684347 -307.073961) (xy 89.715561 -307.128609)
			(xy 89.739791 -307.186692) (xy 89.756667 -307.247321) (xy 89.76593 -307.309569) (xy 89.767156 -307.341016)
			(xy 89.76741 -307.350922) (xy 89.775284 -307.368956) (xy 89.83345 -307.425598) (xy 89.840775 -307.432151)
			(xy 89.858939 -307.439609) (xy 89.868756 -307.440076) (xy 90.19286 -307.440076) (xy 90.201342 -307.43976)
			(xy 90.217367 -307.434194) (xy 90.230671 -307.423669) (xy 90.235532 -307.416708) (xy 90.288872 -307.33365)
			(xy 90.29065 -307.307742) (xy 90.285062 -307.296058) (xy 90.270312 -307.262532) (xy 90.249502 -307.192308)
			(xy 90.238966 -307.119827) (xy 90.238326 -307.083206) (xy 90.238326 -307.082952) (xy 90.238828 -307.050991)
			(xy 90.246839 -306.987573) (xy 90.262736 -306.925659) (xy 90.286268 -306.866226) (xy 90.317062 -306.810211)
			(xy 90.354635 -306.758496) (xy 90.398392 -306.711899) (xy 90.447645 -306.671154) (xy 90.501616 -306.636903)
			(xy 90.559455 -306.609686) (xy 90.620248 -306.589933) (xy 90.683038 -306.577955) (xy 90.746834 -306.573942)
			(xy 90.81063 -306.577955) (xy 90.833276 -306.582275) (xy 91.420182 -306.582275) (xy 91.420182 -306.518353)
			(xy 91.428193 -306.454935) (xy 91.44409 -306.393021) (xy 91.467622 -306.333588) (xy 91.498416 -306.277573)
			(xy 91.535989 -306.225858) (xy 91.579746 -306.179261) (xy 91.628999 -306.138516) (xy 91.68297 -306.104265)
			(xy 91.740809 -306.077048) (xy 91.801602 -306.057295) (xy 91.864392 -306.045317) (xy 91.928188 -306.041304)
			(xy 91.991984 -306.045317) (xy 92.054774 -306.057295) (xy 92.115567 -306.077048) (xy 92.173406 -306.104265)
			(xy 92.227377 -306.138516) (xy 92.27663 -306.179261) (xy 92.320387 -306.225858) (xy 92.35796 -306.277573)
			(xy 92.388754 -306.333588) (xy 92.412286 -306.393021) (xy 92.428183 -306.454935) (xy 92.436194 -306.518353)
			(xy 92.436696 -306.550314) (xy 92.436194 -306.582275) (xy 92.428183 -306.645693) (xy 92.412286 -306.707607)
			(xy 92.40187 -306.733913) (xy 95.064828 -306.733913) (xy 95.064828 -306.669991) (xy 95.072839 -306.606573)
			(xy 95.088736 -306.544659) (xy 95.112268 -306.485226) (xy 95.143062 -306.429211) (xy 95.180635 -306.377496)
			(xy 95.224392 -306.330899) (xy 95.273645 -306.290154) (xy 95.327616 -306.255903) (xy 95.385455 -306.228686)
			(xy 95.446248 -306.208933) (xy 95.509038 -306.196955) (xy 95.572834 -306.192942) (xy 95.63663 -306.196955)
			(xy 95.69942 -306.208933) (xy 95.760213 -306.228686) (xy 95.818052 -306.255903) (xy 95.872023 -306.290154)
			(xy 95.921276 -306.330899) (xy 95.965033 -306.377496) (xy 96.002606 -306.429211) (xy 96.0334 -306.485226)
			(xy 96.056932 -306.544659) (xy 96.072829 -306.606573) (xy 96.08084 -306.669991) (xy 96.081342 -306.701952)
			(xy 96.08084 -306.733913) (xy 96.072829 -306.797331) (xy 96.056932 -306.859245) (xy 96.0334 -306.918678)
			(xy 96.002606 -306.974693) (xy 95.965033 -307.026408) (xy 95.921276 -307.073005) (xy 95.872023 -307.11375)
			(xy 95.818052 -307.148001) (xy 95.760213 -307.175218) (xy 95.69942 -307.194971) (xy 95.63663 -307.206949)
			(xy 95.572834 -307.210963) (xy 95.509038 -307.206949) (xy 95.446248 -307.194971) (xy 95.385455 -307.175218)
			(xy 95.327616 -307.148001) (xy 95.273645 -307.11375) (xy 95.224392 -307.073005) (xy 95.180635 -307.026408)
			(xy 95.143062 -306.974693) (xy 95.112268 -306.918678) (xy 95.088736 -306.859245) (xy 95.072839 -306.797331)
			(xy 95.064828 -306.733913) (xy 92.40187 -306.733913) (xy 92.388754 -306.76704) (xy 92.35796 -306.823055)
			(xy 92.320387 -306.87477) (xy 92.27663 -306.921367) (xy 92.227377 -306.962112) (xy 92.173406 -306.996363)
			(xy 92.115567 -307.02358) (xy 92.054774 -307.043333) (xy 91.991984 -307.055311) (xy 91.928188 -307.059325)
			(xy 91.864392 -307.055311) (xy 91.801602 -307.043333) (xy 91.740809 -307.02358) (xy 91.68297 -306.996363)
			(xy 91.628999 -306.962112) (xy 91.579746 -306.921367) (xy 91.535989 -306.87477) (xy 91.498416 -306.823055)
			(xy 91.467622 -306.76704) (xy 91.44409 -306.707607) (xy 91.428193 -306.645693) (xy 91.420182 -306.582275)
			(xy 90.833276 -306.582275) (xy 90.87342 -306.589933) (xy 90.934213 -306.609686) (xy 90.992052 -306.636903)
			(xy 91.046023 -306.671154) (xy 91.095276 -306.711899) (xy 91.139033 -306.758496) (xy 91.176606 -306.810211)
			(xy 91.2074 -306.866226) (xy 91.230932 -306.925659) (xy 91.246829 -306.987573) (xy 91.25484 -307.050991)
			(xy 91.255342 -307.082952) (xy 91.255342 -307.083206) (xy 91.254707 -307.119829) (xy 91.244194 -307.192315)
			(xy 91.223372 -307.262538) (xy 91.208606 -307.296058) (xy 91.203018 -307.307742) (xy 91.204796 -307.33365)
			(xy 91.258136 -307.416708) (xy 91.262989 -307.423669) (xy 91.276314 -307.43416) (xy 91.292329 -307.439742)
			(xy 91.300808 -307.440076) (xy 92.963492 -307.440076) (xy 92.975159 -307.439506) (xy 92.996084 -307.429185)
			(xy 93.003624 -307.420264) (xy 93.052646 -307.356764) (xy 93.059431 -307.347063) (xy 93.064068 -307.323878)
			(xy 93.061536 -307.312314) (xy 93.055604 -307.288367) (xy 93.04923 -307.239445) (xy 93.048836 -307.214778)
			(xy 93.048836 -307.214524) (xy 93.049322 -307.187273) (xy 93.057078 -307.133325) (xy 93.072433 -307.08103)
			(xy 93.095075 -307.031453) (xy 93.124541 -306.985603) (xy 93.160232 -306.944412) (xy 93.201423 -306.908721)
			(xy 93.247273 -306.879255) (xy 93.29685 -306.856613) (xy 93.349145 -306.841258) (xy 93.403093 -306.833502)
			(xy 93.457595 -306.833502) (xy 93.511543 -306.841258) (xy 93.563838 -306.856613) (xy 93.613415 -306.879255)
			(xy 93.659265 -306.908721) (xy 93.700456 -306.944412) (xy 93.736147 -306.985603) (xy 93.765613 -307.031453)
			(xy 93.788255 -307.08103) (xy 93.80361 -307.133325) (xy 93.811366 -307.187273) (xy 93.811852 -307.214524)
			(xy 93.811852 -307.214778) (xy 93.811468 -307.239447) (xy 93.805102 -307.288371) (xy 93.799152 -307.312314)
			(xy 93.796683 -307.323876) (xy 93.80133 -307.347029) (xy 93.808042 -307.356764) (xy 93.857064 -307.420264)
			(xy 93.864647 -307.42913) (xy 93.885546 -307.439445) (xy 93.897196 -307.440076) (xy 98.035618 -307.440076)
			(xy 98.045687 -307.440502) (xy 98.064289 -307.448218) (xy 98.071686 -307.455062) (xy 100.469954 -309.85333)
			(xy 100.476801 -309.860728) (xy 100.484531 -309.879327) (xy 100.48494 -309.889398) (xy 100.48494 -314.592462)
			(xy 100.484504 -314.602526) (xy 100.476767 -314.621108) (xy 100.469954 -314.62853) (xy 99.175824 -315.92266)
			(xy 99.168423 -315.929499) (xy 99.149825 -315.937212) (xy 99.139756 -315.937646) (xy 97.526348 -315.937646)
			(xy 97.516283 -315.937212) (xy 97.497698 -315.929478) (xy 97.49028 -315.92266) (xy 97.483422 -315.915802)
			(xy 97.476019 -315.908968) (xy 97.457421 -315.901262) (xy 97.447354 -315.900816) (xy 80.957674 -315.900816)
			(xy 80.955134 -315.900816) (xy 71.609204 -316.359794) (xy 71.599803 -316.360642) (xy 71.582587 -316.368349)
			(xy 71.575676 -316.37478) (xy 64.202056 -323.7484) (xy 64.194655 -323.75524) (xy 64.184207 -323.759576)
			(xy 107.193588 -323.759576) (xy 107.19405 -323.728855) (xy 107.201451 -323.667861) (xy 107.216145 -323.608203)
			(xy 107.237915 -323.550747) (xy 107.266446 -323.496332) (xy 107.283504 -323.470778) (xy 107.288917 -323.462104)
			(xy 107.292972 -323.44208) (xy 107.288902 -323.422059) (xy 107.283504 -323.413374) (xy 107.266423 -323.387835)
			(xy 107.23789 -323.333418) (xy 107.216119 -323.27596) (xy 107.201428 -323.216299) (xy 107.194029 -323.155302)
			(xy 107.194032 -323.093858) (xy 107.201435 -323.032862) (xy 107.216131 -322.973202) (xy 107.237906 -322.915746)
			(xy 107.266443 -322.861331) (xy 107.283504 -322.835778) (xy 107.288917 -322.827104) (xy 107.292972 -322.80708)
			(xy 107.288902 -322.787059) (xy 107.283504 -322.778374) (xy 107.266423 -322.752835) (xy 107.23789 -322.698418)
			(xy 107.216119 -322.64096) (xy 107.201428 -322.581299) (xy 107.194029 -322.520302) (xy 107.194032 -322.458858)
			(xy 107.201435 -322.397862) (xy 107.216131 -322.338202) (xy 107.237906 -322.280746) (xy 107.266443 -322.226331)
			(xy 107.283504 -322.200778) (xy 107.288917 -322.192104) (xy 107.292972 -322.17208) (xy 107.288902 -322.152059)
			(xy 107.283504 -322.143374) (xy 107.26644 -322.117824) (xy 107.237908 -322.063408) (xy 107.216138 -322.005952)
			(xy 107.201447 -321.946292) (xy 107.194049 -321.885297) (xy 107.193588 -321.854576) (xy 107.19409 -321.822615)
			(xy 107.202101 -321.759197) (xy 107.217998 -321.697283) (xy 107.24153 -321.63785) (xy 107.272324 -321.581835)
			(xy 107.309897 -321.53012) (xy 107.353654 -321.483523) (xy 107.402907 -321.442778) (xy 107.456878 -321.408527)
			(xy 107.514717 -321.38131) (xy 107.57551 -321.361557) (xy 107.6383 -321.349579) (xy 107.702096 -321.345566)
			(xy 107.765892 -321.349579) (xy 107.828682 -321.361557) (xy 107.889475 -321.38131) (xy 107.947314 -321.408527)
			(xy 108.001285 -321.442778) (xy 108.050538 -321.483523) (xy 108.094295 -321.53012) (xy 108.131868 -321.581835)
			(xy 108.162662 -321.63785) (xy 108.186194 -321.697283) (xy 108.202091 -321.759197) (xy 108.210102 -321.822615)
			(xy 108.210604 -321.854576) (xy 108.21012 -321.885296) (xy 108.202723 -321.946289) (xy 108.188035 -322.005948)
			(xy 108.16627 -322.063403) (xy 108.137743 -322.117819) (xy 108.120688 -322.143374) (xy 108.115316 -322.15207)
			(xy 108.111248 -322.17208) (xy 108.1153 -322.192093) (xy 108.120688 -322.200778) (xy 108.137723 -322.226347)
			(xy 108.166253 -322.28076) (xy 108.188023 -322.338213) (xy 108.202716 -322.397869) (xy 108.210117 -322.458861)
			(xy 108.210119 -322.5203) (xy 108.202723 -322.581292) (xy 108.188035 -322.64095) (xy 108.166269 -322.698404)
			(xy 108.137743 -322.75282) (xy 108.120688 -322.778374) (xy 108.115316 -322.78707) (xy 108.111248 -322.80708)
			(xy 108.1153 -322.827093) (xy 108.120688 -322.835778) (xy 108.137723 -322.861347) (xy 108.166253 -322.91576)
			(xy 108.188023 -322.973213) (xy 108.202716 -323.032869) (xy 108.210117 -323.093861) (xy 108.210119 -323.1553)
			(xy 108.202723 -323.216292) (xy 108.188035 -323.27595) (xy 108.166269 -323.333404) (xy 108.137743 -323.38782)
			(xy 108.120688 -323.413374) (xy 108.115316 -323.42207) (xy 108.111248 -323.44208) (xy 108.1153 -323.462093)
			(xy 108.120688 -323.470778) (xy 108.128935 -323.48296) (xy 108.144186 -323.508121) (xy 108.151168 -323.52107)
			(xy 108.15688 -323.530618) (xy 108.17469 -323.543915) (xy 108.185458 -323.546724) (xy 108.261404 -323.563234)
			(xy 108.27226 -323.565028) (xy 108.293722 -323.560297) (xy 108.302806 -323.55409) (xy 108.303314 -323.553582)
			(xy 108.330098 -323.533509) (xy 108.387968 -323.499871) (xy 108.449753 -323.474123) (xy 108.514384 -323.456711)
			(xy 108.580742 -323.447936) (xy 108.61421 -323.44741) (xy 108.644943 -323.447828) (xy 108.705961 -323.455238)
			(xy 108.76564 -323.46995) (xy 108.823112 -323.491747) (xy 108.877536 -323.520313) (xy 108.928121 -323.555231)
			(xy 108.974128 -323.595992) (xy 109.014886 -323.642001) (xy 109.049801 -323.692588) (xy 109.078364 -323.747014)
			(xy 109.100159 -323.804486) (xy 109.114867 -323.864167) (xy 109.122273 -323.925185) (xy 109.122718 -323.955918)
			(xy 109.122252 -323.986639) (xy 109.114851 -324.047632) (xy 109.100159 -324.107291) (xy 109.078389 -324.164746)
			(xy 109.049859 -324.219162) (xy 109.032802 -324.244716) (xy 109.027393 -324.253392) (xy 109.023336 -324.273415)
			(xy 109.027405 -324.293435) (xy 109.032802 -324.30212) (xy 109.049878 -324.327663) (xy 109.07841 -324.382079)
			(xy 109.100181 -324.439536) (xy 109.114873 -324.499197) (xy 109.122272 -324.560193) (xy 109.12227 -324.621636)
			(xy 109.114868 -324.682632) (xy 109.100172 -324.742292) (xy 109.078398 -324.799748) (xy 109.049862 -324.854163)
			(xy 109.032802 -324.879716) (xy 109.027393 -324.888392) (xy 109.023336 -324.908415) (xy 109.027405 -324.928435)
			(xy 109.032802 -324.93712) (xy 109.049878 -324.962663) (xy 109.07841 -325.017079) (xy 109.100181 -325.074536)
			(xy 109.114873 -325.134197) (xy 109.122272 -325.195193) (xy 109.12227 -325.256636) (xy 109.114868 -325.317632)
			(xy 109.100172 -325.377292) (xy 109.078398 -325.434748) (xy 109.049862 -325.489163) (xy 109.032802 -325.514716)
			(xy 109.027393 -325.523392) (xy 109.023336 -325.543415) (xy 109.027405 -325.563435) (xy 109.032802 -325.57212)
			(xy 109.049865 -325.597671) (xy 109.078397 -325.652086) (xy 109.100167 -325.709542) (xy 109.114858 -325.769202)
			(xy 109.122256 -325.830197) (xy 109.122718 -325.860918) (xy 109.122216 -325.892879) (xy 109.114205 -325.956297)
			(xy 109.098308 -326.018211) (xy 109.074776 -326.077644) (xy 109.043982 -326.133659) (xy 109.006409 -326.185374)
			(xy 108.962652 -326.231971) (xy 108.913399 -326.272716) (xy 108.859428 -326.306967) (xy 108.801589 -326.334184)
			(xy 108.740796 -326.353937) (xy 108.678006 -326.365915) (xy 108.61421 -326.369929) (xy 108.550414 -326.365915)
			(xy 108.487624 -326.353937) (xy 108.426831 -326.334184) (xy 108.368992 -326.306967) (xy 108.315021 -326.272716)
			(xy 108.265768 -326.231971) (xy 108.222011 -326.185374) (xy 108.184438 -326.133659) (xy 108.153644 -326.077644)
			(xy 108.130112 -326.018211) (xy 108.114215 -325.956297) (xy 108.106204 -325.892879) (xy 108.105702 -325.860918)
			(xy 108.106182 -325.830198) (xy 108.11358 -325.769205) (xy 108.128268 -325.709546) (xy 108.150035 -325.652091)
			(xy 108.178562 -325.597675) (xy 108.195618 -325.57212) (xy 108.200995 -325.563427) (xy 108.20506 -325.543415)
			(xy 108.201006 -325.523401) (xy 108.195618 -325.514716) (xy 108.178578 -325.489151) (xy 108.150047 -325.434737)
			(xy 108.128278 -325.377284) (xy 108.113585 -325.317627) (xy 108.106184 -325.256635) (xy 108.106183 -325.195195)
			(xy 108.11358 -325.134202) (xy 108.128269 -325.074544) (xy 108.150035 -325.01709) (xy 108.178562 -324.962674)
			(xy 108.195618 -324.93712) (xy 108.200995 -324.928427) (xy 108.20506 -324.908415) (xy 108.201006 -324.888401)
			(xy 108.195618 -324.879716) (xy 108.178578 -324.854151) (xy 108.150047 -324.799737) (xy 108.128278 -324.742284)
			(xy 108.113585 -324.682627) (xy 108.106184 -324.621635) (xy 108.106183 -324.560195) (xy 108.11358 -324.499202)
			(xy 108.128269 -324.439544) (xy 108.150035 -324.38209) (xy 108.178562 -324.327674) (xy 108.195618 -324.30212)
			(xy 108.200995 -324.293427) (xy 108.20506 -324.273415) (xy 108.201006 -324.253401) (xy 108.195618 -324.244716)
			(xy 108.187371 -324.232534) (xy 108.17212 -324.207373) (xy 108.165138 -324.194424) (xy 108.159397 -324.184897)
			(xy 108.141609 -324.171585) (xy 108.130848 -324.16877) (xy 108.054902 -324.15226) (xy 108.044046 -324.150471)
			(xy 108.022584 -324.155198) (xy 108.0135 -324.161404) (xy 108.012992 -324.161912) (xy 107.986205 -324.181982)
			(xy 107.928336 -324.21562) (xy 107.866552 -324.241369) (xy 107.801921 -324.258782) (xy 107.735564 -324.267557)
			(xy 107.702096 -324.268084) (xy 107.671363 -324.267666) (xy 107.610345 -324.260256) (xy 107.550665 -324.245546)
			(xy 107.493193 -324.223749) (xy 107.438768 -324.195183) (xy 107.388183 -324.160265) (xy 107.342176 -324.119504)
			(xy 107.301418 -324.073495) (xy 107.266503 -324.022908) (xy 107.23794 -323.968481) (xy 107.216146 -323.911008)
			(xy 107.201438 -323.851328) (xy 107.194032 -323.790309) (xy 107.193588 -323.759576) (xy 64.184207 -323.759576)
			(xy 64.176057 -323.762958) (xy 64.165988 -323.763386) (xy 63.481966 -323.763386) (xy 63.475362 -323.76999)
			(xy 59.599322 -323.76999) (xy 59.589258 -323.770427) (xy 59.570673 -323.77816) (xy 59.563254 -323.784976)
			(xy 59.416442 -323.931788) (xy 59.409589 -323.939184) (xy 59.401844 -323.957782) (xy 59.401456 -323.967856)
			(xy 59.401456 -325.14667) (xy 59.401019 -325.156734) (xy 59.393282 -325.175315) (xy 59.38647 -325.182738)
			(xy 58.571384 -325.997824) (xy 58.568681 -326.000677) (xy 58.564095 -326.007059) (xy 58.56224 -326.010524)
			(xy 58.559653 -326.01595) (xy 58.556823 -326.02763) (xy 58.556652 -326.033638) (xy 58.556652 -333.976726)
			(xy 58.557668 -333.986124) (xy 58.557668 -333.986632) (xy 58.559377 -333.993789) (xy 58.566216 -334.006809)
			(xy 58.57113 -334.012286) (xy 59.71032 -335.151476) (xy 59.712606 -335.153508) (xy 59.729878 -335.159858)
			(xy 59.73375 -335.161159) (xy 59.741796 -335.162564) (xy 59.74588 -335.162652)
		)
		(stroke
			(width 0)
			(type solid)
		)
		(fill yes)
		(layer "In15.Cu")
		(net "PVDDCR_CPU1_P1")
	)
	(gr_poly
		(pts
			(xy 215.930734 -330.315824) (xy 215.934943 -330.315745) (xy 215.943241 -330.314334) (xy 215.947244 -330.31303)
			(xy 215.970358 -330.304902) (xy 215.976454 -330.30033) (xy 216.002258 -330.281681) (xy 216.05763 -330.250257)
			(xy 216.116491 -330.225988) (xy 216.17792 -330.209253) (xy 216.209372 -330.204318) (xy 216.2175 -330.203048)
			(xy 216.232232 -330.195682) (xy 216.39911 -330.028804) (xy 216.405967 -330.02141) (xy 216.413717 -330.002811)
			(xy 216.414096 -329.992736) (xy 216.414096 -327.377552) (xy 216.406476 -327.358756) (xy 216.39911 -327.351644)
			(xy 212.061806 -323.01434) (xy 212.051629 -323.004794) (xy 212.027298 -322.991156) (xy 212.000187 -322.984596)
			(xy 211.972312 -322.9856) (xy 211.945745 -322.994095) (xy 211.922458 -323.009449) (xy 211.912962 -323.019674)
			(xy 211.871872 -323.066548) (xy 211.784779 -323.155744) (xy 211.692383 -323.239434) (xy 211.59503 -323.317303)
			(xy 211.493088 -323.389059) (xy 211.386938 -323.454431) (xy 211.276982 -323.513174) (xy 211.163631 -323.565067)
			(xy 211.047313 -323.609914) (xy 210.928465 -323.647547) (xy 210.807534 -323.677824) (xy 210.684974 -323.700632)
			(xy 210.561246 -323.715885) (xy 210.436816 -323.723526) (xy 210.374484 -323.724016) (xy 210.310619 -323.723514)
			(xy 210.183142 -323.715493) (xy 210.05642 -323.699483) (xy 209.930954 -323.675549) (xy 209.807238 -323.643783)
			(xy 209.68576 -323.604311) (xy 209.567001 -323.557291) (xy 209.451428 -323.502905) (xy 209.339499 -323.441371)
			(xy 209.231654 -323.37293) (xy 209.128319 -323.297852) (xy 209.029902 -323.216434) (xy 208.936792 -323.128997)
			(xy 208.849356 -323.035886) (xy 208.767938 -322.937468) (xy 208.692861 -322.834133) (xy 208.624421 -322.726287)
			(xy 208.562887 -322.614357) (xy 208.508503 -322.498784) (xy 208.461483 -322.380025) (xy 208.422013 -322.258547)
			(xy 208.390248 -322.134831) (xy 208.366314 -322.009364) (xy 208.350305 -321.882642) (xy 208.342285 -321.755165)
			(xy 208.342285 -321.627435) (xy 208.350305 -321.499958) (xy 208.366314 -321.373236) (xy 208.390248 -321.247769)
			(xy 208.422013 -321.124053) (xy 208.461483 -321.002575) (xy 208.508503 -320.883816) (xy 208.562887 -320.768243)
			(xy 208.624421 -320.656313) (xy 208.692861 -320.548467) (xy 208.767938 -320.445132) (xy 208.849356 -320.346714)
			(xy 208.936792 -320.253603) (xy 209.029902 -320.166166) (xy 209.128319 -320.084748) (xy 209.231654 -320.00967)
			(xy 209.339499 -319.941229) (xy 209.451428 -319.879695) (xy 209.567001 -319.825309) (xy 209.68576 -319.778289)
			(xy 209.807238 -319.738817) (xy 209.930954 -319.707051) (xy 210.05642 -319.683117) (xy 210.183142 -319.667107)
			(xy 210.310619 -319.659086) (xy 210.374484 -319.658492) (xy 210.442031 -319.659058) (xy 210.576826 -319.66805)
			(xy 210.710726 -319.685969) (xy 210.843142 -319.712736) (xy 210.973489 -319.748232) (xy 211.101193 -319.792302)
			(xy 211.163662 -319.818004) (xy 211.177045 -319.823101) (xy 211.205476 -319.826426) (xy 211.233712 -319.821725)
			(xy 211.259532 -319.809368) (xy 211.280904 -319.790327) (xy 211.296148 -319.766099) (xy 211.304065 -319.738591)
			(xy 211.304632 -319.724278) (xy 211.304632 -319.415668) (xy 211.297012 -319.396872) (xy 211.289646 -319.38976)
			(xy 210.316572 -318.416686) (xy 210.30972 -318.40929) (xy 210.301979 -318.390691) (xy 210.301586 -318.380618)
			(xy 210.301586 -317.136526) (xy 210.301101 -317.122564) (xy 210.29345 -317.095705) (xy 210.278821 -317.071915)
			(xy 210.258305 -317.052968) (xy 210.233429 -317.040275) (xy 210.206047 -317.034781) (xy 210.1782 -317.036896)
			(xy 210.164934 -317.041276) (xy 210.137153 -317.051088) (xy 210.079896 -317.064981) (xy 210.021416 -317.072165)
			(xy 209.99196 -317.072772) (xy 209.978423 -317.073257) (xy 209.952333 -317.080501) (xy 209.929071 -317.094361)
			(xy 209.910281 -317.113857) (xy 209.897288 -317.137614) (xy 209.89101 -317.163953) (xy 209.891891 -317.191017)
			(xy 209.89544 -317.20409) (xy 209.905755 -317.240239) (xy 209.916854 -317.314587) (xy 209.917538 -317.352172)
			(xy 209.917538 -317.35268) (xy 209.917036 -317.384657) (xy 209.909021 -317.448107) (xy 209.893116 -317.510052)
			(xy 209.869573 -317.569514) (xy 209.838763 -317.625558) (xy 209.801171 -317.677298) (xy 209.757392 -317.723918)
			(xy 209.708114 -317.764684) (xy 209.654116 -317.798952) (xy 209.596249 -317.826183) (xy 209.535425 -317.845946)
			(xy 209.472604 -317.857929) (xy 209.408776 -317.861945) (xy 209.344948 -317.857929) (xy 209.282127 -317.845946)
			(xy 209.221303 -317.826183) (xy 209.163436 -317.798952) (xy 209.109438 -317.764684) (xy 209.06016 -317.723918)
			(xy 209.016381 -317.677298) (xy 208.978789 -317.625558) (xy 208.947979 -317.569514) (xy 208.924436 -317.510052)
			(xy 208.908531 -317.448107) (xy 208.900516 -317.384657) (xy 208.900014 -317.35268) (xy 208.900551 -317.319497)
			(xy 208.909183 -317.253694) (xy 208.926298 -317.189572) (xy 208.951604 -317.12822) (xy 208.984673 -317.070679)
			(xy 209.024943 -317.017927) (xy 209.07173 -316.970858) (xy 209.12424 -316.930273) (xy 209.181582 -316.896859)
			(xy 209.242781 -316.871185) (xy 209.306799 -316.853686) (xy 209.372549 -316.84466) (xy 209.405728 -316.843918)
			(xy 209.419265 -316.843434) (xy 209.445357 -316.836192) (xy 209.46862 -316.822333) (xy 209.487411 -316.802836)
			(xy 209.500404 -316.779079) (xy 209.50668 -316.752738) (xy 209.505797 -316.725674) (xy 209.502248 -316.7126)
			(xy 209.491932 -316.676451) (xy 209.480833 -316.602104) (xy 209.48015 -316.564518) (xy 209.48015 -316.56401)
			(xy 209.480595 -316.533262) (xy 209.488006 -316.472215) (xy 209.502722 -316.412507) (xy 209.524528 -316.355008)
			(xy 209.553106 -316.300556) (xy 209.588039 -316.249947) (xy 209.628818 -316.203917) (xy 209.674848 -316.163138)
			(xy 209.725458 -316.128205) (xy 209.77991 -316.099628) (xy 209.837409 -316.077822) (xy 209.897117 -316.063106)
			(xy 209.958164 -316.055695) (xy 209.988912 -316.055248) (xy 210.018879 -316.0557) (xy 210.078394 -316.062772)
			(xy 210.136668 -316.076781) (xy 210.164934 -316.086744) (xy 210.178203 -316.091157) (xy 210.206071 -316.09333)
			(xy 210.233485 -316.087864) (xy 210.258389 -316.075169) (xy 210.278917 -316.056197) (xy 210.293531 -316.032369)
			(xy 210.301136 -316.00547) (xy 210.301586 -315.991494) (xy 210.301586 -314.116466) (xy 210.30124 -314.107487)
			(xy 210.295041 -314.090635) (xy 210.283388 -314.076973) (xy 210.267724 -314.068195) (xy 210.258914 -314.066428)
			(xy 210.228149 -314.061) (xy 210.168145 -314.043606) (xy 210.110723 -314.018997) (xy 210.056744 -313.987543)
			(xy 210.007023 -313.949718) (xy 209.962305 -313.906091) (xy 209.923266 -313.857317) (xy 209.89049 -313.804131)
			(xy 209.864472 -313.747333) (xy 209.845603 -313.687777) (xy 209.834167 -313.626359) (xy 209.830335 -313.564003)
			(xy 209.834166 -313.501646) (xy 209.845602 -313.440228) (xy 209.86447 -313.380672) (xy 209.890488 -313.323873)
			(xy 209.923263 -313.270687) (xy 209.962302 -313.221913) (xy 210.007019 -313.178285) (xy 210.05674 -313.14046)
			(xy 210.110718 -313.109006) (xy 210.16814 -313.084396) (xy 210.228144 -313.067001) (xy 210.258914 -313.061604)
			(xy 210.267708 -313.059811) (xy 210.28333 -313.051001) (xy 210.294965 -313.037352) (xy 210.301193 -313.020532)
			(xy 210.301586 -313.011566) (xy 210.301586 -299.37329) (xy 210.301108 -299.362541) (xy 210.292292 -299.342935)
			(xy 210.284568 -299.335444) (xy 210.260291 -299.3131) (xy 210.217131 -299.263196) (xy 210.180784 -299.208131)
			(xy 210.151861 -299.148829) (xy 210.130847 -299.086285) (xy 210.118096 -299.02155) (xy 210.113821 -298.955709)
			(xy 210.118094 -298.889868) (xy 210.130843 -298.825133) (xy 210.151854 -298.762588) (xy 210.180774 -298.703285)
			(xy 210.217119 -298.648218) (xy 210.260278 -298.598313) (xy 210.284568 -298.575984) (xy 210.292192 -298.568421)
			(xy 210.300993 -298.54886) (xy 210.301586 -298.538138) (xy 210.301586 -297.180762) (xy 210.287362 -297.145964)
			(xy 210.281012 -297.139106) (xy 210.259911 -297.115545) (xy 210.223094 -297.064114) (xy 210.192935 -297.008516)
			(xy 210.169899 -296.94961) (xy 210.154341 -296.888303) (xy 210.1465 -296.82554) (xy 210.146498 -296.762289)
			(xy 210.154335 -296.699526) (xy 210.16989 -296.638218) (xy 210.192923 -296.57931) (xy 210.223079 -296.523711)
			(xy 210.259892 -296.472278) (xy 210.281012 -296.448734) (xy 210.287362 -296.441876) (xy 210.301586 -296.407078)
			(xy 210.301586 -209.206084) (xy 210.30116 -209.196015) (xy 210.29344 -209.177416) (xy 210.2866 -209.170016)
			(xy 207.8863 -206.769716) (xy 207.879467 -206.762313) (xy 207.871763 -206.743715) (xy 207.871314 -206.733648)
			(xy 207.871314 -204.26172) (xy 207.871752 -204.251657) (xy 207.879488 -204.233075) (xy 207.8863 -204.225652)
			(xy 207.96123 -204.150722) (xy 207.968072 -204.143323) (xy 207.975789 -204.124724) (xy 207.976216 -204.114654)
			(xy 207.976216 -196.00291) (xy 207.975691 -195.992376) (xy 207.967225 -195.973085) (xy 207.951717 -195.958826)
			(xy 207.941926 -195.954904) (xy 207.836008 -195.918328) (xy 207.80502 -195.927472) (xy 207.79486 -195.940426)
			(xy 207.774663 -195.965485) (xy 207.728847 -196.010688) (xy 207.677569 -196.049585) (xy 207.621691 -196.081524)
			(xy 207.562152 -196.105969) (xy 207.499952 -196.122508) (xy 207.436135 -196.130864) (xy 207.403954 -196.131434)
			(xy 207.4037 -196.131434) (xy 207.37122 -196.130926) (xy 207.306817 -196.122446) (xy 207.244071 -196.105633)
			(xy 207.184057 -196.080774) (xy 207.127801 -196.048293) (xy 207.076266 -196.008747) (xy 207.030335 -195.962812)
			(xy 206.990792 -195.911276) (xy 206.958314 -195.855018) (xy 206.933458 -195.795002) (xy 206.916648 -195.732256)
			(xy 206.908172 -195.667852) (xy 206.907638 -195.635372) (xy 206.907638 -195.634864) (xy 206.908178 -195.602135)
			(xy 206.916817 -195.537249) (xy 206.933912 -195.474062) (xy 206.959168 -195.413671) (xy 206.992146 -195.357127)
			(xy 207.032273 -195.305409) (xy 207.055212 -195.282058) (xy 207.062578 -195.274692) (xy 207.070452 -195.25615)
			(xy 207.070452 -195.181474) (xy 207.062324 -195.162678) (xy 207.05445 -195.155312) (xy 207.029734 -195.131175)
			(xy 206.986388 -195.077384) (xy 206.950715 -195.018224) (xy 206.923374 -194.954782) (xy 206.904865 -194.888225)
			(xy 206.895529 -194.819776) (xy 206.894938 -194.785234) (xy 206.895382 -194.754485) (xy 206.902791 -194.693436)
			(xy 206.917505 -194.633724) (xy 206.939309 -194.576222) (xy 206.967886 -194.521767) (xy 207.002818 -194.471154)
			(xy 207.043597 -194.425121) (xy 207.089627 -194.384339) (xy 207.140238 -194.349403) (xy 207.194691 -194.320823)
			(xy 207.252192 -194.299015) (xy 207.311902 -194.284297) (xy 207.372951 -194.276884) (xy 207.4037 -194.276472)
			(xy 207.434659 -194.27693) (xy 207.496118 -194.284442) (xy 207.556213 -194.299355) (xy 207.614054 -194.321448)
			(xy 207.668787 -194.350396) (xy 207.719605 -194.38577) (xy 207.765755 -194.427048) (xy 207.806557 -194.47362)
			(xy 207.824324 -194.498976) (xy 207.8355 -194.502278) (xy 207.941926 -194.465702) (xy 207.951721 -194.461784)
			(xy 207.967231 -194.447519) (xy 207.975719 -194.428231) (xy 207.976216 -194.417696) (xy 207.976216 -193.639948)
			(xy 207.975784 -193.629882) (xy 207.968058 -193.611289) (xy 207.96123 -193.60388) (xy 207.475074 -193.117724)
			(xy 207.455262 -193.110104) (xy 207.444086 -193.110866) (xy 207.391 -193.11239) (xy 207.349234 -193.111911)
			(xy 207.266082 -193.103971) (xy 207.184062 -193.088153) (xy 207.143858 -193.07683) (xy 207.136746 -193.074798)
			(xy 203.702666 -193.074798) (xy 203.673202 -193.102992) (xy 203.67244 -193.123312) (xy 203.670837 -193.149586)
			(xy 203.661114 -193.201317) (xy 203.644137 -193.251142) (xy 203.620249 -193.298046) (xy 203.589936 -193.341079)
			(xy 203.553814 -193.379366) (xy 203.533502 -193.396108) (xy 203.523596 -193.404236) (xy 203.513436 -193.427096)
			(xy 203.522072 -193.536316) (xy 203.535534 -193.557398) (xy 203.54671 -193.563748) (xy 203.575098 -193.580295)
			(xy 203.627648 -193.619742) (xy 203.67453 -193.665781) (xy 203.714922 -193.717608) (xy 203.748119 -193.774313)
			(xy 203.773539 -193.834905) (xy 203.790736 -193.898323) (xy 203.79941 -193.963456) (xy 203.799948 -193.99631)
			(xy 203.799437 -194.028465) (xy 203.791123 -194.092235) (xy 203.774636 -194.154395) (xy 203.750253 -194.213903)
			(xy 203.718382 -194.26976) (xy 203.679558 -194.321028) (xy 203.634433 -194.366848) (xy 203.583765 -194.406451)
			(xy 203.556362 -194.423284) (xy 203.551282 -194.426332) (xy 203.5429 -194.43446) (xy 203.52766 -194.458082)
			(xy 203.524434 -194.463425) (xy 203.520442 -194.475244) (xy 203.519786 -194.48145) (xy 203.512928 -194.565524)
			(xy 203.522834 -194.588638) (xy 203.532994 -194.596766) (xy 203.554388 -194.614332) (xy 203.592163 -194.654792)
			(xy 203.623456 -194.700451) (xy 203.647562 -194.75028) (xy 203.663938 -194.803156) (xy 203.672214 -194.857887)
			(xy 203.672694 -194.885564) (xy 203.672178 -194.913183) (xy 203.663945 -194.967803) (xy 203.647664 -195.020587)
			(xy 203.623697 -195.070354) (xy 203.592581 -195.115993) (xy 203.55501 -195.156485) (xy 203.511824 -195.190925)
			(xy 203.463987 -195.218544) (xy 203.412567 -195.238724) (xy 203.358715 -195.251016) (xy 203.303632 -195.255144)
			(xy 203.248549 -195.251016) (xy 203.194697 -195.238724) (xy 203.143277 -195.218544) (xy 203.09544 -195.190925)
			(xy 203.052254 -195.156485) (xy 203.014683 -195.115993) (xy 202.983567 -195.070354) (xy 202.9596 -195.020587)
			(xy 202.943319 -194.967803) (xy 202.935086 -194.913183) (xy 202.93457 -194.885564) (xy 202.935068 -194.857903)
			(xy 202.943338 -194.803202) (xy 202.959687 -194.75035) (xy 202.983749 -194.700534) (xy 203.014983 -194.654872)
			(xy 203.052688 -194.614388) (xy 203.074016 -194.596766) (xy 203.07427 -194.596512) (xy 203.074778 -194.596004)
			(xy 203.079259 -194.592156) (xy 203.086438 -194.582783) (xy 203.089002 -194.577462) (xy 203.089002 -194.577208)
			(xy 203.091432 -194.57136) (xy 203.093628 -194.558894) (xy 203.09332 -194.55257) (xy 203.0857 -194.456304)
			(xy 203.072238 -194.435222) (xy 203.061062 -194.428872) (xy 203.032675 -194.412325) (xy 202.980126 -194.372877)
			(xy 202.933245 -194.326837) (xy 202.892852 -194.27501) (xy 202.859655 -194.218305) (xy 202.834235 -194.157714)
			(xy 202.817036 -194.094296) (xy 202.80836 -194.029164) (xy 202.807824 -193.99631) (xy 202.808355 -193.963479)
			(xy 202.81702 -193.898392) (xy 202.834199 -193.835017) (xy 202.859591 -193.774464) (xy 202.892753 -193.717792)
			(xy 202.933105 -193.665993) (xy 202.97994 -193.619972) (xy 203.032439 -193.580534) (xy 203.060808 -193.564002)
			(xy 203.071392 -193.557325) (xy 203.084878 -193.53628) (xy 203.086462 -193.52387) (xy 203.093066 -193.440304)
			(xy 203.093349 -193.43398) (xy 203.091165 -193.421516) (xy 203.088748 -193.415666) (xy 203.088748 -193.415412)
			(xy 203.086163 -193.410106) (xy 203.078973 -193.40075) (xy 203.074524 -193.39687) (xy 203.074016 -193.396362)
			(xy 203.073762 -193.396108) (xy 203.053466 -193.379352) (xy 203.017363 -193.341054) (xy 202.987064 -193.29802)
			(xy 202.963181 -193.251119) (xy 202.946199 -193.201303) (xy 202.936461 -193.149581) (xy 202.934824 -193.123312)
			(xy 202.934062 -193.102992) (xy 202.904598 -193.074798) (xy 201.911458 -193.074798) (xy 201.882248 -193.102992)
			(xy 201.881232 -193.123312) (xy 201.878995 -193.163733) (xy 201.868014 -193.243945) (xy 201.84969 -193.322805)
			(xy 201.824178 -193.399641) (xy 201.791696 -193.4738) (xy 201.75252 -193.544651) (xy 201.706984 -193.611591)
			(xy 201.655473 -193.674052) (xy 201.598428 -193.731501) (xy 201.536332 -193.783451) (xy 201.50328 -193.806826)
			(xy 201.495612 -193.812615) (xy 201.484922 -193.828562) (xy 201.48083 -193.84732) (xy 201.481944 -193.856864)
			(xy 201.484887 -193.876353) (xy 201.488063 -193.915642) (xy 201.488294 -193.93535) (xy 201.487805 -193.967233)
			(xy 201.479643 -194.030474) (xy 201.463446 -194.092148) (xy 201.439482 -194.151239) (xy 201.408145 -194.206774)
			(xy 201.369952 -194.257836) (xy 201.348086 -194.281044) (xy 201.347832 -194.281298) (xy 201.341158 -194.288831)
			(xy 201.333834 -194.307558) (xy 201.333608 -194.31762) (xy 201.334624 -194.388232) (xy 201.334883 -194.393002)
			(xy 201.336924 -194.402334) (xy 201.338688 -194.406774) (xy 201.342498 -194.416426) (xy 201.349864 -194.423538)
			(xy 201.373352 -194.447497) (xy 201.414468 -194.500519) (xy 201.448251 -194.558489) (xy 201.474115 -194.620399)
			(xy 201.491609 -194.685173) (xy 201.500431 -194.751686) (xy 201.500994 -194.785234) (xy 201.500492 -194.817211)
			(xy 201.492477 -194.880661) (xy 201.476572 -194.942606) (xy 201.453029 -195.002068) (xy 201.422219 -195.058112)
			(xy 201.384627 -195.109852) (xy 201.340848 -195.156472) (xy 201.29157 -195.197238) (xy 201.237572 -195.231506)
			(xy 201.179705 -195.258737) (xy 201.118881 -195.2785) (xy 201.05606 -195.290483) (xy 200.992232 -195.294499)
			(xy 200.928404 -195.290483) (xy 200.865583 -195.2785) (xy 200.804759 -195.258737) (xy 200.746892 -195.231506)
			(xy 200.692894 -195.197238) (xy 200.643616 -195.156472) (xy 200.599837 -195.109852) (xy 200.562245 -195.058112)
			(xy 200.531435 -195.002068) (xy 200.507892 -194.942606) (xy 200.491987 -194.880661) (xy 200.483972 -194.817211)
			(xy 200.48347 -194.785234) (xy 200.484029 -194.751689) (xy 200.492887 -194.685186) (xy 200.510401 -194.620422)
			(xy 200.536268 -194.558518) (xy 200.57004 -194.500548) (xy 200.611132 -194.447514) (xy 200.6346 -194.423538)
			(xy 200.641966 -194.416426) (xy 200.645776 -194.406774) (xy 200.647575 -194.402344) (xy 200.64963 -194.393008)
			(xy 200.64984 -194.388232) (xy 200.650856 -194.31762) (xy 200.650636 -194.307557) (xy 200.643311 -194.288826)
			(xy 200.636632 -194.281298) (xy 200.636378 -194.281044) (xy 200.614526 -194.257824) (xy 200.576341 -194.20676)
			(xy 200.545009 -194.151227) (xy 200.521045 -194.092138) (xy 200.504845 -194.030468) (xy 200.496674 -193.967231)
			(xy 200.49617 -193.93535) (xy 200.496456 -193.9119) (xy 200.500911 -193.865213) (xy 200.50506 -193.842132)
			(xy 200.50633 -193.83502) (xy 200.50506 -193.820796) (xy 200.499726 -193.80708) (xy 200.49109 -193.795904)
			(xy 200.485248 -193.791586) (xy 200.453191 -193.767454) (xy 200.393159 -193.714206) (xy 200.338243 -193.655696)
			(xy 200.288902 -193.592415) (xy 200.245548 -193.52489) (xy 200.208544 -193.453686) (xy 200.178201 -193.3794)
			(xy 200.154771 -193.302652) (xy 200.13845 -193.224085) (xy 200.133458 -193.184272) (xy 200.133458 -193.183764)
			(xy 200.131634 -193.173483) (xy 200.121 -193.155539) (xy 200.112884 -193.148966) (xy 200.053448 -193.105278)
			(xy 200.044742 -193.09953) (xy 200.024412 -193.094953) (xy 200.014078 -193.096388) (xy 200.013824 -193.096388)
			(xy 199.972577 -193.103883) (xy 199.88912 -193.111894) (xy 199.8472 -193.11239) (xy 199.805434 -193.111911)
			(xy 199.722282 -193.103971) (xy 199.640262 -193.088153) (xy 199.600058 -193.07683) (xy 199.592946 -193.074798)
			(xy 196.158866 -193.074798) (xy 196.129402 -193.102992) (xy 196.12864 -193.123312) (xy 196.127029 -193.149615)
			(xy 196.117281 -193.201403) (xy 196.100268 -193.251278) (xy 196.076335 -193.298227) (xy 196.045971 -193.341296)
			(xy 196.00979 -193.37961) (xy 195.989448 -193.396362) (xy 195.979288 -193.40449) (xy 195.969382 -193.42735)
			(xy 195.978018 -193.53657) (xy 195.99148 -193.557652) (xy 196.002656 -193.564002) (xy 196.029387 -193.579551)
			(xy 196.079132 -193.616293) (xy 196.123925 -193.658932) (xy 196.163071 -193.706808) (xy 196.195963 -193.759178)
			(xy 196.22209 -193.81523) (xy 196.241048 -193.874095) (xy 196.252542 -193.93486) (xy 196.256395 -193.996582)
			(xy 196.252547 -194.058305) (xy 196.241057 -194.119071) (xy 196.222103 -194.177937) (xy 196.195979 -194.233991)
			(xy 196.163092 -194.286364) (xy 196.123949 -194.334242) (xy 196.079159 -194.376885) (xy 196.029417 -194.41363)
			(xy 196.002656 -194.429126) (xy 195.99148 -194.435476) (xy 195.978018 -194.456558) (xy 195.969382 -194.565778)
			(xy 195.979542 -194.588638) (xy 195.989448 -194.596766) (xy 196.0108 -194.614359) (xy 196.048494 -194.654854)
			(xy 196.079718 -194.700524) (xy 196.103771 -194.750345) (xy 196.120115 -194.8032) (xy 196.128382 -194.857902)
			(xy 196.128894 -194.885564) (xy 196.128378 -194.913183) (xy 196.120145 -194.967803) (xy 196.103864 -195.020587)
			(xy 196.079897 -195.070354) (xy 196.048781 -195.115993) (xy 196.01121 -195.156485) (xy 195.968024 -195.190925)
			(xy 195.920187 -195.218544) (xy 195.868767 -195.238724) (xy 195.814915 -195.251016) (xy 195.759832 -195.255144)
			(xy 195.704749 -195.251016) (xy 195.650897 -195.238724) (xy 195.599477 -195.218544) (xy 195.55164 -195.190925)
			(xy 195.508454 -195.156485) (xy 195.470883 -195.115993) (xy 195.439767 -195.070354) (xy 195.4158 -195.020587)
			(xy 195.399519 -194.967803) (xy 195.391286 -194.913183) (xy 195.39077 -194.885564) (xy 195.391268 -194.857903)
			(xy 195.399538 -194.803202) (xy 195.415887 -194.75035) (xy 195.439949 -194.700534) (xy 195.471183 -194.654872)
			(xy 195.508888 -194.614388) (xy 195.530216 -194.596766) (xy 195.540376 -194.588638) (xy 195.550282 -194.565778)
			(xy 195.541646 -194.456558) (xy 195.528184 -194.435476) (xy 195.517008 -194.429126) (xy 195.490278 -194.413579)
			(xy 195.440536 -194.376842) (xy 195.395747 -194.334207) (xy 195.356604 -194.286335) (xy 195.323716 -194.233969)
			(xy 195.297592 -194.177921) (xy 195.278638 -194.11906) (xy 195.267147 -194.0583) (xy 195.263299 -193.996582)
			(xy 195.267152 -193.934865) (xy 195.278647 -193.874106) (xy 195.297605 -193.815246) (xy 195.323733 -193.7592)
			(xy 195.356625 -193.706836) (xy 195.395771 -193.658967) (xy 195.440563 -193.616335) (xy 195.490308 -193.579602)
			(xy 195.517008 -193.564002) (xy 195.528184 -193.557652) (xy 195.541646 -193.53657) (xy 195.550282 -193.42735)
			(xy 195.540122 -193.40449) (xy 195.530216 -193.396362) (xy 195.509875 -193.379607) (xy 195.473689 -193.341297)
			(xy 195.443319 -193.298229) (xy 195.419383 -193.251281) (xy 195.402367 -193.201405) (xy 195.392617 -193.149617)
			(xy 195.391024 -193.123312) (xy 195.390262 -193.102992) (xy 195.360798 -193.074798) (xy 194.367658 -193.074798)
			(xy 194.338448 -193.102992) (xy 194.337432 -193.123312) (xy 194.335195 -193.163733) (xy 194.324214 -193.243945)
			(xy 194.30589 -193.322805) (xy 194.280378 -193.399641) (xy 194.247896 -193.4738) (xy 194.20872 -193.544651)
			(xy 194.163184 -193.611591) (xy 194.111673 -193.674052) (xy 194.054628 -193.731501) (xy 193.992532 -193.783451)
			(xy 193.95948 -193.806826) (xy 193.951812 -193.812615) (xy 193.941122 -193.828562) (xy 193.93703 -193.84732)
			(xy 193.938144 -193.856864) (xy 193.941087 -193.876353) (xy 193.944263 -193.915642) (xy 193.944494 -193.93535)
			(xy 193.944005 -193.967233) (xy 193.935843 -194.030474) (xy 193.919646 -194.092148) (xy 193.895682 -194.151239)
			(xy 193.864345 -194.206774) (xy 193.826152 -194.257836) (xy 193.804286 -194.281044) (xy 193.804032 -194.281298)
			(xy 193.797358 -194.288831) (xy 193.790034 -194.307558) (xy 193.789808 -194.31762) (xy 193.790824 -194.388232)
			(xy 193.791083 -194.393002) (xy 193.793124 -194.402334) (xy 193.794888 -194.406774) (xy 193.798698 -194.416426)
			(xy 193.806064 -194.423538) (xy 193.829552 -194.447497) (xy 193.870668 -194.500519) (xy 193.904451 -194.558489)
			(xy 193.930315 -194.620399) (xy 193.947809 -194.685173) (xy 193.956631 -194.751686) (xy 193.957194 -194.785234)
			(xy 193.956692 -194.817211) (xy 193.948677 -194.880661) (xy 193.932772 -194.942606) (xy 193.909229 -195.002068)
			(xy 193.878419 -195.058112) (xy 193.840827 -195.109852) (xy 193.797048 -195.156472) (xy 193.74777 -195.197238)
			(xy 193.693772 -195.231506) (xy 193.635905 -195.258737) (xy 193.575081 -195.2785) (xy 193.51226 -195.290483)
			(xy 193.448432 -195.294499) (xy 193.384604 -195.290483) (xy 193.321783 -195.2785) (xy 193.260959 -195.258737)
			(xy 193.203092 -195.231506) (xy 193.149094 -195.197238) (xy 193.099816 -195.156472) (xy 193.056037 -195.109852)
			(xy 193.018445 -195.058112) (xy 192.987635 -195.002068) (xy 192.964092 -194.942606) (xy 192.948187 -194.880661)
			(xy 192.940172 -194.817211) (xy 192.93967 -194.785234) (xy 192.940229 -194.751689) (xy 192.949087 -194.685186)
			(xy 192.966601 -194.620422) (xy 192.992468 -194.558518) (xy 193.02624 -194.500548) (xy 193.067332 -194.447514)
			(xy 193.0908 -194.423538) (xy 193.098166 -194.416426) (xy 193.101976 -194.406774) (xy 193.103775 -194.402344)
			(xy 193.10583 -194.393008) (xy 193.10604 -194.388232) (xy 193.107056 -194.31762) (xy 193.106836 -194.307557)
			(xy 193.099511 -194.288826) (xy 193.092832 -194.281298) (xy 193.092578 -194.281044) (xy 193.070726 -194.257824)
			(xy 193.032541 -194.20676) (xy 193.001209 -194.151227) (xy 192.977245 -194.092138) (xy 192.961045 -194.030468)
			(xy 192.952874 -193.967231) (xy 192.95237 -193.93535) (xy 192.952656 -193.9119) (xy 192.957111 -193.865213)
			(xy 192.96126 -193.842132) (xy 192.96253 -193.83502) (xy 192.96126 -193.820796) (xy 192.955926 -193.80708)
			(xy 192.94729 -193.795904) (xy 192.941448 -193.791586) (xy 192.909391 -193.767454) (xy 192.849359 -193.714206)
			(xy 192.794443 -193.655696) (xy 192.745102 -193.592415) (xy 192.701748 -193.52489) (xy 192.664744 -193.453686)
			(xy 192.634401 -193.3794) (xy 192.610971 -193.302652) (xy 192.59465 -193.224085) (xy 192.589658 -193.184272)
			(xy 192.589658 -193.183764) (xy 192.587834 -193.173483) (xy 192.5772 -193.155539) (xy 192.569084 -193.148966)
			(xy 192.501012 -193.098928) (xy 192.480438 -193.094356) (xy 192.470024 -193.096388) (xy 192.428714 -193.103892)
			(xy 192.34513 -193.111902) (xy 192.303146 -193.11239) (xy 192.261381 -193.111909) (xy 192.178229 -193.103964)
			(xy 192.096211 -193.088141) (xy 192.056004 -193.07683) (xy 192.048892 -193.074798) (xy 188.614812 -193.074798)
			(xy 188.585348 -193.102992) (xy 188.584586 -193.123312) (xy 188.582975 -193.149615) (xy 188.573225 -193.201401)
			(xy 188.55621 -193.251274) (xy 188.532276 -193.298221) (xy 188.501908 -193.341287) (xy 188.465725 -193.379596)
			(xy 188.445394 -193.396362) (xy 188.435234 -193.40449) (xy 188.425328 -193.42735) (xy 188.433964 -193.53657)
			(xy 188.447426 -193.557652) (xy 188.458602 -193.564002) (xy 188.485336 -193.579549) (xy 188.535086 -193.616288)
			(xy 188.579883 -193.658925) (xy 188.619033 -193.706801) (xy 188.651929 -193.759171) (xy 188.678059 -193.815224)
			(xy 188.69702 -193.874091) (xy 188.708516 -193.934858) (xy 188.712369 -193.996582) (xy 188.70852 -194.058307)
			(xy 188.697028 -194.119075) (xy 188.678072 -194.177943) (xy 188.651946 -194.233998) (xy 188.619054 -194.286371)
			(xy 188.579907 -194.334249) (xy 188.535113 -194.376889) (xy 188.485365 -194.413631) (xy 188.458602 -194.429126)
			(xy 188.447426 -194.435476) (xy 188.433964 -194.456558) (xy 188.425328 -194.565778) (xy 188.435488 -194.588638)
			(xy 188.445394 -194.596766) (xy 188.466748 -194.614358) (xy 188.504447 -194.654851) (xy 188.535676 -194.70052)
			(xy 188.559733 -194.750342) (xy 188.576079 -194.803197) (xy 188.584348 -194.857901) (xy 188.58484 -194.885564)
			(xy 188.584324 -194.913183) (xy 188.576091 -194.967803) (xy 188.55981 -195.020587) (xy 188.535843 -195.070354)
			(xy 188.504727 -195.115993) (xy 188.467156 -195.156485) (xy 188.42397 -195.190925) (xy 188.376133 -195.218544)
			(xy 188.324713 -195.238724) (xy 188.270861 -195.251016) (xy 188.215778 -195.255144) (xy 188.160695 -195.251016)
			(xy 188.106843 -195.238724) (xy 188.055423 -195.218544) (xy 188.007586 -195.190925) (xy 187.9644 -195.156485)
			(xy 187.926829 -195.115993) (xy 187.895713 -195.070354) (xy 187.871746 -195.020587) (xy 187.855465 -194.967803)
			(xy 187.847232 -194.913183) (xy 187.846716 -194.885564) (xy 187.847214 -194.857902) (xy 187.855483 -194.8032)
			(xy 187.871831 -194.750347) (xy 187.89589 -194.700529) (xy 187.927121 -194.654863) (xy 187.964823 -194.614375)
			(xy 187.986162 -194.596766) (xy 187.996322 -194.588638) (xy 188.006228 -194.565778) (xy 187.997592 -194.456558)
			(xy 187.98413 -194.435476) (xy 187.972954 -194.429126) (xy 187.946227 -194.413577) (xy 187.89649 -194.376838)
			(xy 187.851705 -194.334201) (xy 187.812566 -194.286328) (xy 187.779682 -194.233962) (xy 187.753561 -194.177915)
			(xy 187.734609 -194.119056) (xy 187.72312 -194.058298) (xy 187.719272 -193.996582) (xy 187.723125 -193.934867)
			(xy 187.734618 -193.87411) (xy 187.753574 -193.815252) (xy 187.779699 -193.759207) (xy 187.812587 -193.706843)
			(xy 187.851729 -193.658973) (xy 187.896517 -193.61634) (xy 187.946256 -193.579604) (xy 187.972954 -193.564002)
			(xy 187.98413 -193.557652) (xy 187.997592 -193.53657) (xy 188.006228 -193.42735) (xy 187.996068 -193.40449)
			(xy 187.986162 -193.396362) (xy 187.965823 -193.379606) (xy 187.929642 -193.341293) (xy 187.899277 -193.298225)
			(xy 187.875345 -193.251276) (xy 187.858332 -193.201402) (xy 187.848583 -193.149615) (xy 187.84697 -193.123312)
			(xy 187.846208 -193.102992) (xy 187.816744 -193.074798) (xy 186.823604 -193.074798) (xy 186.794394 -193.102992)
			(xy 186.793378 -193.123312) (xy 186.791141 -193.163733) (xy 186.780159 -193.243944) (xy 186.761834 -193.322803)
			(xy 186.736322 -193.399638) (xy 186.703838 -193.473795) (xy 186.664661 -193.544644) (xy 186.619123 -193.611583)
			(xy 186.567611 -193.674041) (xy 186.510563 -193.731487) (xy 186.448466 -193.783434) (xy 186.415426 -193.806826)
			(xy 186.407765 -193.812619) (xy 186.397086 -193.828567) (xy 186.392999 -193.847319) (xy 186.39409 -193.856864)
			(xy 186.397033 -193.876353) (xy 186.40021 -193.915642) (xy 186.40044 -193.93535) (xy 186.399952 -193.967233)
			(xy 186.39179 -194.030475) (xy 186.375594 -194.09215) (xy 186.351631 -194.151243) (xy 186.320297 -194.206779)
			(xy 186.282106 -194.257843) (xy 186.260232 -194.281044) (xy 186.259978 -194.281298) (xy 186.253334 -194.288774)
			(xy 186.246002 -194.307367) (xy 186.245754 -194.317366) (xy 186.24677 -194.388232) (xy 186.24677 -194.39001)
			(xy 186.247278 -194.399662) (xy 186.255152 -194.416934) (xy 186.261756 -194.423538) (xy 186.285243 -194.4475)
			(xy 186.326357 -194.500525) (xy 186.360143 -194.558494) (xy 186.386015 -194.620402) (xy 186.403524 -194.685174)
			(xy 186.412367 -194.751686) (xy 186.412886 -194.785234) (xy 186.41242 -194.815963) (xy 186.405008 -194.876973)
			(xy 186.390296 -194.936645) (xy 186.368499 -194.994108) (xy 186.339935 -195.048525) (xy 186.30502 -195.099102)
			(xy 186.264263 -195.145102) (xy 186.218258 -195.185854) (xy 186.167677 -195.220764) (xy 186.113257 -195.249322)
			(xy 186.055791 -195.271113) (xy 185.996118 -195.285818) (xy 185.935107 -195.293223) (xy 185.904378 -195.293742)
			(xy 185.877626 -195.293344) (xy 185.82443 -195.287616) (xy 185.798206 -195.282312) (xy 185.792872 -195.281296)
			(xy 185.787538 -195.281296) (xy 185.756835 -195.280603) (xy 185.695951 -195.272559) (xy 185.636525 -195.25706)
			(xy 185.579467 -195.234343) (xy 185.52565 -195.204756) (xy 185.475897 -195.16875) (xy 185.430971 -195.126878)
			(xy 185.391557 -195.07978) (xy 185.374534 -195.05422) (xy 185.366211 -195.042208) (xy 185.344072 -195.02315)
			(xy 185.317448 -195.011128) (xy 185.288512 -195.007123) (xy 185.259623 -195.011461) (xy 185.23314 -195.023788)
			(xy 185.211221 -195.043099) (xy 185.203084 -195.055236) (xy 185.187051 -195.080036) (xy 185.150127 -195.126125)
			(xy 185.129424 -195.147184) (xy 185.122312 -195.154296) (xy 185.114438 -195.172584) (xy 185.113168 -195.253102)
			(xy 185.113393 -195.263162) (xy 185.120726 -195.281886) (xy 185.127392 -195.289424) (xy 185.127646 -195.289678)
			(xy 185.1495 -195.312896) (xy 185.187688 -195.363959) (xy 185.219023 -195.419493) (xy 185.242987 -195.478581)
			(xy 185.259188 -195.540252) (xy 185.267357 -195.60349) (xy 185.267854 -195.635372) (xy 185.267365 -195.666551)
			(xy 185.259549 -195.728417) (xy 185.244041 -195.788815) (xy 185.221086 -195.846794) (xy 185.214156 -195.8594)
			(xy 189.495938 -195.8594) (xy 189.496465 -195.826241) (xy 189.505082 -195.760485) (xy 189.52217 -195.696406)
			(xy 189.547439 -195.635091) (xy 189.580461 -195.577578) (xy 189.620675 -195.524844) (xy 189.667401 -195.477783)
			(xy 189.693296 -195.457064) (xy 189.702187 -195.449494) (xy 189.712528 -195.428593) (xy 189.713108 -195.416932)
			(xy 189.713108 -195.336668) (xy 189.712482 -195.325018) (xy 189.702162 -195.30412) (xy 189.693296 -195.296536)
			(xy 189.667406 -195.275812) (xy 189.620681 -195.228751) (xy 189.580467 -195.176017) (xy 189.547446 -195.118506)
			(xy 189.522177 -195.057191) (xy 189.505089 -194.993114) (xy 189.496473 -194.927359) (xy 189.495938 -194.8942)
			(xy 189.496487 -194.860426) (xy 189.505437 -194.793472) (xy 189.523167 -194.728292) (xy 189.549364 -194.66603)
			(xy 189.583568 -194.607781) (xy 189.625179 -194.554569) (xy 189.673463 -194.507331) (xy 189.727573 -194.466896)
			(xy 189.756796 -194.449954) (xy 189.767972 -194.443858) (xy 189.781688 -194.422776) (xy 189.791086 -194.31381)
			(xy 189.781434 -194.290442) (xy 189.771528 -194.282568) (xy 189.750686 -194.264951) (xy 189.713925 -194.22462)
			(xy 189.683503 -194.179316) (xy 189.660084 -194.130025) (xy 189.644179 -194.077824) (xy 189.636134 -194.023849)
			(xy 189.635638 -193.996564) (xy 189.636154 -193.968964) (xy 189.644381 -193.914381) (xy 189.660651 -193.861634)
			(xy 189.684601 -193.811902) (xy 189.715696 -193.766294) (xy 189.753241 -193.72583) (xy 189.796398 -193.691413)
			(xy 189.844202 -193.663814) (xy 189.895586 -193.643647) (xy 189.949401 -193.631364) (xy 190.004446 -193.627239)
			(xy 190.059491 -193.631364) (xy 190.113306 -193.643647) (xy 190.16469 -193.663814) (xy 190.212494 -193.691413)
			(xy 190.255651 -193.72583) (xy 190.293196 -193.766294) (xy 190.324291 -193.811902) (xy 190.348241 -193.861634)
			(xy 190.364511 -193.914381) (xy 190.372738 -193.968964) (xy 190.373254 -193.996564) (xy 190.372763 -194.023851)
			(xy 190.364737 -194.077832) (xy 190.348841 -194.13004) (xy 190.325421 -194.179333) (xy 190.29499 -194.224636)
			(xy 190.258213 -194.264957) (xy 190.237364 -194.282568) (xy 190.227458 -194.290442) (xy 190.217806 -194.31381)
			(xy 190.227204 -194.422776) (xy 190.24092 -194.443858) (xy 190.252096 -194.449954) (xy 190.28131 -194.466914)
			(xy 190.335428 -194.507338) (xy 190.383719 -194.554569) (xy 190.425334 -194.607777) (xy 190.459541 -194.666025)
			(xy 190.485737 -194.728288) (xy 190.503461 -194.79347) (xy 190.512402 -194.860425) (xy 190.512954 -194.8942)
			(xy 190.51243 -194.927359) (xy 190.503813 -194.993115) (xy 190.486725 -195.057195) (xy 190.461455 -195.11851)
			(xy 190.428433 -195.176022) (xy 190.388218 -195.228756) (xy 190.341491 -195.275818) (xy 190.315596 -195.296536)
			(xy 190.306703 -195.304104) (xy 190.296364 -195.325007) (xy 190.295784 -195.336668) (xy 190.295784 -195.416932)
			(xy 190.296412 -195.428582) (xy 190.306731 -195.44948) (xy 190.315596 -195.457064) (xy 190.341484 -195.47779)
			(xy 190.38821 -195.524851) (xy 190.428424 -195.577584) (xy 190.461446 -195.635095) (xy 190.46156 -195.635372)
			(xy 191.820038 -195.635372) (xy 191.820563 -195.602652) (xy 191.82916 -195.537778) (xy 191.846214 -195.474599)
			(xy 191.871429 -195.414211) (xy 191.904367 -195.357664) (xy 191.944455 -195.30594) (xy 191.967358 -195.282566)
			(xy 191.974724 -195.275454) (xy 191.982598 -195.256658) (xy 191.982598 -195.163948) (xy 191.974724 -195.145152)
			(xy 191.967358 -195.13804) (xy 191.944466 -195.114656) (xy 191.904383 -195.062931) (xy 191.871447 -195.006384)
			(xy 191.846231 -194.945999) (xy 191.829171 -194.882824) (xy 191.820564 -194.817953) (xy 191.820038 -194.785234)
			(xy 191.820527 -194.754071) (xy 191.828339 -194.692237) (xy 191.843839 -194.631869) (xy 191.866782 -194.573921)
			(xy 191.896808 -194.519304) (xy 191.933442 -194.468882) (xy 191.976107 -194.423448) (xy 192.024129 -194.38372)
			(xy 192.076753 -194.350325) (xy 192.133147 -194.323788) (xy 192.192422 -194.304528) (xy 192.253643 -194.292849)
			(xy 192.315846 -194.288936) (xy 192.378049 -194.292849) (xy 192.43927 -194.304528) (xy 192.498545 -194.323788)
			(xy 192.554939 -194.350325) (xy 192.607563 -194.38372) (xy 192.655585 -194.423448) (xy 192.69825 -194.468882)
			(xy 192.734884 -194.519304) (xy 192.76491 -194.573921) (xy 192.787853 -194.631869) (xy 192.803353 -194.692237)
			(xy 192.811165 -194.754071) (xy 192.811654 -194.785234) (xy 192.811135 -194.817955) (xy 192.802537 -194.882828)
			(xy 192.785482 -194.946008) (xy 192.760266 -195.006395) (xy 192.727327 -195.062942) (xy 192.687237 -195.114666)
			(xy 192.664334 -195.13804) (xy 192.656968 -195.145152) (xy 192.649094 -195.163948) (xy 192.649094 -195.256658)
			(xy 192.656968 -195.275454) (xy 192.664334 -195.282566) (xy 192.687228 -195.305948) (xy 192.727311 -195.357674)
			(xy 192.760247 -195.414221) (xy 192.785463 -195.474606) (xy 192.802522 -195.537782) (xy 192.811128 -195.602653)
			(xy 192.811654 -195.635372) (xy 192.811165 -195.666535) (xy 192.803353 -195.728369) (xy 192.787853 -195.788737)
			(xy 192.76491 -195.846685) (xy 192.75792 -195.8594) (xy 197.039992 -195.8594) (xy 197.040498 -195.82624)
			(xy 197.049116 -195.760482) (xy 197.066206 -195.696402) (xy 197.091478 -195.635086) (xy 197.124503 -195.577574)
			(xy 197.164722 -195.524841) (xy 197.211453 -195.477781) (xy 197.23735 -195.457064) (xy 197.24625 -195.449504)
			(xy 197.256583 -195.428594) (xy 197.257162 -195.416932) (xy 197.257162 -195.336668) (xy 197.256552 -195.325015)
			(xy 197.246222 -195.304116) (xy 197.23735 -195.296536) (xy 197.21145 -195.275824) (xy 197.164728 -195.228759)
			(xy 197.124516 -195.176023) (xy 197.091496 -195.11851) (xy 197.066229 -195.057194) (xy 197.049143 -194.993115)
			(xy 197.040526 -194.927359) (xy 197.039992 -194.8942) (xy 197.04048 -194.862961) (xy 197.048156 -194.800955)
			(xy 197.063369 -194.740356) (xy 197.085888 -194.682077) (xy 197.115376 -194.626994) (xy 197.151387 -194.575937)
			(xy 197.193381 -194.529675) (xy 197.240724 -194.488904) (xy 197.292704 -194.454238) (xy 197.320408 -194.439794)
			(xy 197.331838 -194.433952) (xy 197.346316 -194.413378) (xy 197.36054 -194.304666) (xy 197.35165 -194.281298)
			(xy 197.342252 -194.272916) (xy 197.323038 -194.255336) (xy 197.289279 -194.215681) (xy 197.261432 -194.171673)
			(xy 197.240048 -194.124187) (xy 197.225554 -194.074166) (xy 197.218237 -194.022603) (xy 197.217792 -193.996564)
			(xy 197.218308 -193.968964) (xy 197.226535 -193.914381) (xy 197.242805 -193.861634) (xy 197.266755 -193.811902)
			(xy 197.29785 -193.766294) (xy 197.335395 -193.72583) (xy 197.378552 -193.691413) (xy 197.426356 -193.663814)
			(xy 197.47774 -193.643647) (xy 197.531555 -193.631364) (xy 197.5866 -193.627239) (xy 197.641645 -193.631364)
			(xy 197.69546 -193.643647) (xy 197.746844 -193.663814) (xy 197.794648 -193.691413) (xy 197.837805 -193.72583)
			(xy 197.87535 -193.766294) (xy 197.906445 -193.811902) (xy 197.930395 -193.861634) (xy 197.946665 -193.914381)
			(xy 197.954892 -193.968964) (xy 197.955408 -193.996564) (xy 197.954861 -194.025208) (xy 197.946001 -194.081806)
			(xy 197.928489 -194.136351) (xy 197.902748 -194.187529) (xy 197.869396 -194.234107) (xy 197.829238 -194.274963)
			(xy 197.806564 -194.292474) (xy 197.796404 -194.300094) (xy 197.785736 -194.3227) (xy 197.790562 -194.432428)
			(xy 197.803262 -194.454018) (xy 197.814184 -194.460622) (xy 197.841596 -194.478018) (xy 197.892185 -194.518709)
			(xy 197.937184 -194.565509) (xy 197.975859 -194.617655) (xy 198.007583 -194.6743) (xy 198.031839 -194.734523)
			(xy 198.048232 -194.797343) (xy 198.056495 -194.861738) (xy 198.057008 -194.8942) (xy 198.056502 -194.92736)
			(xy 198.047884 -194.993118) (xy 198.030794 -195.057198) (xy 198.005522 -195.118514) (xy 197.972497 -195.176026)
			(xy 197.932278 -195.228759) (xy 197.885547 -195.275819) (xy 197.85965 -195.296536) (xy 197.85075 -195.304096)
			(xy 197.840417 -195.325006) (xy 197.839838 -195.336668) (xy 197.839838 -195.416932) (xy 197.840448 -195.428585)
			(xy 197.850778 -195.449484) (xy 197.85965 -195.457064) (xy 197.88555 -195.477776) (xy 197.932272 -195.524841)
			(xy 197.972484 -195.577577) (xy 198.005504 -195.63509) (xy 198.00562 -195.635372) (xy 199.364092 -195.635372)
			(xy 199.364631 -195.602652) (xy 199.373227 -195.53778) (xy 199.390279 -195.474601) (xy 199.415492 -195.414214)
			(xy 199.448426 -195.357667) (xy 199.488511 -195.305941) (xy 199.511412 -195.282566) (xy 199.518778 -195.275454)
			(xy 199.526652 -195.256658) (xy 199.526652 -195.163948) (xy 199.518778 -195.145152) (xy 199.511412 -195.13804)
			(xy 199.488511 -195.114665) (xy 199.44843 -195.062936) (xy 199.415497 -195.006388) (xy 199.390282 -194.946002)
			(xy 199.373224 -194.882825) (xy 199.364617 -194.817954) (xy 199.364092 -194.785234) (xy 199.364581 -194.754071)
			(xy 199.372393 -194.692237) (xy 199.387893 -194.631869) (xy 199.410836 -194.573921) (xy 199.440862 -194.519304)
			(xy 199.477496 -194.468882) (xy 199.520161 -194.423448) (xy 199.568183 -194.38372) (xy 199.620807 -194.350325)
			(xy 199.677201 -194.323788) (xy 199.736476 -194.304528) (xy 199.797697 -194.292849) (xy 199.8599 -194.288936)
			(xy 199.922103 -194.292849) (xy 199.983324 -194.304528) (xy 200.042599 -194.323788) (xy 200.098993 -194.350325)
			(xy 200.151617 -194.38372) (xy 200.199639 -194.423448) (xy 200.242304 -194.468882) (xy 200.278938 -194.519304)
			(xy 200.308964 -194.573921) (xy 200.331907 -194.631869) (xy 200.347407 -194.692237) (xy 200.355219 -194.754071)
			(xy 200.355708 -194.785234) (xy 200.355173 -194.817954) (xy 200.346576 -194.882826) (xy 200.329523 -194.946005)
			(xy 200.30431 -195.006392) (xy 200.271375 -195.06294) (xy 200.231289 -195.114665) (xy 200.208388 -195.13804)
			(xy 200.201022 -195.145152) (xy 200.193148 -195.163948) (xy 200.193148 -195.256658) (xy 200.201022 -195.275454)
			(xy 200.208388 -195.282566) (xy 200.231292 -195.305938) (xy 200.271372 -195.357668) (xy 200.304305 -195.414216)
			(xy 200.32952 -195.474603) (xy 200.346577 -195.537781) (xy 200.355183 -195.602652) (xy 200.355708 -195.635372)
			(xy 200.355219 -195.666535) (xy 200.347407 -195.728369) (xy 200.331907 -195.788737) (xy 200.31821 -195.823332)
			(xy 204.50175 -195.823332) (xy 204.502181 -195.792842) (xy 204.50946 -195.732298) (xy 204.52393 -195.67306)
			(xy 204.545382 -195.615978) (xy 204.57351 -195.561872) (xy 204.607907 -195.51152) (xy 204.648082 -195.465644)
			(xy 204.693455 -195.424904) (xy 204.718158 -195.407026) (xy 204.727556 -195.400422) (xy 204.738478 -195.381372)
			(xy 204.747368 -195.281296) (xy 204.740002 -195.260468) (xy 204.731874 -195.25234) (xy 204.708883 -195.228442)
			(xy 204.668645 -195.175729) (xy 204.635602 -195.118232) (xy 204.610315 -195.056927) (xy 204.593212 -194.992855)
			(xy 204.584585 -194.927104) (xy 204.584046 -194.893946) (xy 204.584628 -194.860173) (xy 204.593573 -194.79322)
			(xy 204.611297 -194.72804) (xy 204.637489 -194.665778) (xy 204.671689 -194.607529) (xy 204.713295 -194.554317)
			(xy 204.761576 -194.507078) (xy 204.815682 -194.466642) (xy 204.844904 -194.4497) (xy 204.85608 -194.443604)
			(xy 204.869796 -194.422522) (xy 204.879194 -194.313556) (xy 204.869542 -194.290188) (xy 204.859636 -194.282314)
			(xy 204.83877 -194.264725) (xy 204.80201 -194.224388) (xy 204.771591 -194.179078) (xy 204.748176 -194.129782)
			(xy 204.732276 -194.077576) (xy 204.724238 -194.023597) (xy 204.723746 -193.99631) (xy 204.724262 -193.96871)
			(xy 204.732489 -193.914127) (xy 204.748759 -193.86138) (xy 204.772709 -193.811648) (xy 204.803804 -193.76604)
			(xy 204.841349 -193.725576) (xy 204.884506 -193.691159) (xy 204.93231 -193.66356) (xy 204.983694 -193.643393)
			(xy 205.037509 -193.63111) (xy 205.092554 -193.626985) (xy 205.147599 -193.63111) (xy 205.201414 -193.643393)
			(xy 205.252798 -193.66356) (xy 205.300602 -193.691159) (xy 205.343759 -193.725576) (xy 205.381304 -193.76604)
			(xy 205.412399 -193.811648) (xy 205.436349 -193.86138) (xy 205.452619 -193.914127) (xy 205.460846 -193.96871)
			(xy 205.461362 -193.99631) (xy 205.4609 -194.023598) (xy 205.452868 -194.07758) (xy 205.436965 -194.129788)
			(xy 205.41354 -194.179082) (xy 205.383104 -194.224383) (xy 205.346323 -194.264703) (xy 205.325472 -194.282314)
			(xy 205.315566 -194.290188) (xy 205.305914 -194.313556) (xy 205.315312 -194.422522) (xy 205.329028 -194.443604)
			(xy 205.340204 -194.4497) (xy 205.36944 -194.466623) (xy 205.423558 -194.507053) (xy 205.471848 -194.55429)
			(xy 205.513462 -194.607503) (xy 205.547665 -194.665756) (xy 205.573858 -194.728024) (xy 205.591577 -194.793211)
			(xy 205.600513 -194.86017) (xy 205.601062 -194.893946) (xy 205.600609 -194.924435) (xy 205.593333 -194.984978)
			(xy 205.578866 -195.044216) (xy 205.557416 -195.101297) (xy 205.529292 -195.155403) (xy 205.494898 -195.205756)
			(xy 205.454726 -195.251632) (xy 205.409355 -195.292373) (xy 205.384654 -195.310252) (xy 205.375256 -195.316856)
			(xy 205.364334 -195.335906) (xy 205.355444 -195.435982) (xy 205.36281 -195.45681) (xy 205.370938 -195.464938)
			(xy 205.393921 -195.488844) (xy 205.434159 -195.541555) (xy 205.467203 -195.599051) (xy 205.492492 -195.660354)
			(xy 205.509596 -195.724424) (xy 205.518226 -195.790175) (xy 205.518766 -195.823332) (xy 205.518264 -195.855293)
			(xy 205.510253 -195.918711) (xy 205.494356 -195.980625) (xy 205.470824 -196.040058) (xy 205.44003 -196.096073)
			(xy 205.402457 -196.147788) (xy 205.3587 -196.194385) (xy 205.309447 -196.23513) (xy 205.255476 -196.269381)
			(xy 205.197637 -196.296598) (xy 205.136844 -196.316351) (xy 205.074054 -196.328329) (xy 205.010258 -196.332343)
			(xy 204.946462 -196.328329) (xy 204.883672 -196.316351) (xy 204.822879 -196.296598) (xy 204.76504 -196.269381)
			(xy 204.711069 -196.23513) (xy 204.661816 -196.194385) (xy 204.618059 -196.147788) (xy 204.580486 -196.096073)
			(xy 204.549692 -196.040058) (xy 204.52616 -195.980625) (xy 204.510263 -195.918711) (xy 204.502252 -195.855293)
			(xy 204.50175 -195.823332) (xy 200.31821 -195.823332) (xy 200.308964 -195.846685) (xy 200.278938 -195.901302)
			(xy 200.242304 -195.951724) (xy 200.199639 -195.997158) (xy 200.151617 -196.036886) (xy 200.098993 -196.070281)
			(xy 200.042599 -196.096818) (xy 199.983324 -196.116078) (xy 199.922103 -196.127757) (xy 199.8599 -196.13167)
			(xy 199.797697 -196.127757) (xy 199.736476 -196.116078) (xy 199.677201 -196.096818) (xy 199.620807 -196.070281)
			(xy 199.568183 -196.036886) (xy 199.520161 -195.997158) (xy 199.477496 -195.951724) (xy 199.440862 -195.901302)
			(xy 199.410836 -195.846685) (xy 199.387893 -195.788737) (xy 199.372393 -195.728369) (xy 199.364581 -195.666535)
			(xy 199.364092 -195.635372) (xy 198.00562 -195.635372) (xy 198.030771 -195.696406) (xy 198.047857 -195.760485)
			(xy 198.056474 -195.826241) (xy 198.057008 -195.8594) (xy 198.056506 -195.891361) (xy 198.048495 -195.954779)
			(xy 198.032598 -196.016693) (xy 198.009066 -196.076126) (xy 197.978272 -196.132141) (xy 197.940699 -196.183856)
			(xy 197.896942 -196.230453) (xy 197.847689 -196.271198) (xy 197.793718 -196.305449) (xy 197.735879 -196.332666)
			(xy 197.675086 -196.352419) (xy 197.612296 -196.364397) (xy 197.5485 -196.368411) (xy 197.484704 -196.364397)
			(xy 197.421914 -196.352419) (xy 197.361121 -196.332666) (xy 197.303282 -196.305449) (xy 197.249311 -196.271198)
			(xy 197.200058 -196.230453) (xy 197.156301 -196.183856) (xy 197.118728 -196.132141) (xy 197.087934 -196.076126)
			(xy 197.064402 -196.016693) (xy 197.048505 -195.954779) (xy 197.040494 -195.891361) (xy 197.039992 -195.8594)
			(xy 192.75792 -195.8594) (xy 192.734884 -195.901302) (xy 192.69825 -195.951724) (xy 192.655585 -195.997158)
			(xy 192.607563 -196.036886) (xy 192.554939 -196.070281) (xy 192.498545 -196.096818) (xy 192.43927 -196.116078)
			(xy 192.378049 -196.127757) (xy 192.315846 -196.13167) (xy 192.253643 -196.127757) (xy 192.192422 -196.116078)
			(xy 192.133147 -196.096818) (xy 192.076753 -196.070281) (xy 192.024129 -196.036886) (xy 191.976107 -195.997158)
			(xy 191.933442 -195.951724) (xy 191.896808 -195.901302) (xy 191.866782 -195.846685) (xy 191.843839 -195.788737)
			(xy 191.828339 -195.728369) (xy 191.820527 -195.666535) (xy 191.820038 -195.635372) (xy 190.46156 -195.635372)
			(xy 190.486715 -195.696409) (xy 190.503802 -195.760487) (xy 190.512419 -195.826241) (xy 190.512954 -195.8594)
			(xy 190.512452 -195.891361) (xy 190.504441 -195.954779) (xy 190.488544 -196.016693) (xy 190.465012 -196.076126)
			(xy 190.434218 -196.132141) (xy 190.396645 -196.183856) (xy 190.352888 -196.230453) (xy 190.303635 -196.271198)
			(xy 190.249664 -196.305449) (xy 190.191825 -196.332666) (xy 190.131032 -196.352419) (xy 190.068242 -196.364397)
			(xy 190.004446 -196.368411) (xy 189.94065 -196.364397) (xy 189.87786 -196.352419) (xy 189.817067 -196.332666)
			(xy 189.759228 -196.305449) (xy 189.705257 -196.271198) (xy 189.656004 -196.230453) (xy 189.612247 -196.183856)
			(xy 189.574674 -196.132141) (xy 189.54388 -196.076126) (xy 189.520348 -196.016693) (xy 189.504451 -195.954779)
			(xy 189.49644 -195.891361) (xy 189.495938 -195.8594) (xy 185.214156 -195.8594) (xy 185.191045 -195.901438)
			(xy 185.154392 -195.951886) (xy 185.111706 -195.997343) (xy 185.063658 -196.037091) (xy 185.011008 -196.070504)
			(xy 184.954585 -196.097055) (xy 184.89528 -196.116324) (xy 184.834027 -196.128009) (xy 184.771792 -196.131925)
			(xy 184.709557 -196.128009) (xy 184.648304 -196.116324) (xy 184.588999 -196.097055) (xy 184.532576 -196.070504)
			(xy 184.479926 -196.037091) (xy 184.431878 -195.997343) (xy 184.389192 -195.951886) (xy 184.352539 -195.901438)
			(xy 184.322498 -195.846794) (xy 184.299543 -195.788815) (xy 184.284035 -195.728417) (xy 184.276219 -195.666551)
			(xy 184.27573 -195.635372) (xy 184.276223 -195.603491) (xy 184.284394 -195.540253) (xy 184.300596 -195.478583)
			(xy 184.324565 -195.419497) (xy 184.355903 -195.363967) (xy 184.394096 -195.312908) (xy 184.415938 -195.289678)
			(xy 184.416192 -195.289424) (xy 184.422877 -195.281896) (xy 184.430221 -195.263167) (xy 184.430416 -195.253102)
			(xy 184.429146 -195.172584) (xy 184.421272 -195.154296) (xy 184.41416 -195.147184) (xy 184.390669 -195.1232)
			(xy 184.349551 -195.070131) (xy 184.315765 -195.012118) (xy 184.289897 -194.950166) (xy 184.272397 -194.885353)
			(xy 184.263568 -194.818801) (xy 184.26303 -194.785234) (xy 184.263474 -194.754485) (xy 184.270883 -194.693435)
			(xy 184.285596 -194.633723) (xy 184.307401 -194.57622) (xy 184.335977 -194.521765) (xy 184.37091 -194.471152)
			(xy 184.411689 -194.425118) (xy 184.457719 -194.384336) (xy 184.508329 -194.349399) (xy 184.562782 -194.320818)
			(xy 184.620283 -194.299009) (xy 184.679994 -194.28429) (xy 184.741043 -194.276876) (xy 184.771792 -194.276472)
			(xy 184.803954 -194.276965) (xy 184.867764 -194.285078) (xy 184.930042 -194.301174) (xy 184.989792 -194.324996)
			(xy 185.046059 -194.356165) (xy 185.097946 -194.394182) (xy 185.144624 -194.438441) (xy 185.185346 -194.488233)
			(xy 185.20283 -194.515232) (xy 185.211001 -194.527353) (xy 185.232906 -194.546693) (xy 185.259388 -194.559044)
			(xy 185.288283 -194.563396) (xy 185.317228 -194.559394) (xy 185.343857 -194.547364) (xy 185.365994 -194.52829)
			(xy 185.37428 -194.516248) (xy 185.39076 -194.491537) (xy 185.428712 -194.445844) (xy 185.471844 -194.405005)
			(xy 185.495438 -194.386962) (xy 185.50608 -194.378528) (xy 185.522844 -194.357179) (xy 185.533396 -194.332169)
			(xy 185.536992 -194.305264) (xy 185.533377 -194.278361) (xy 185.522807 -194.25336) (xy 185.514742 -194.242436)
			(xy 185.494679 -194.216074) (xy 185.460976 -194.159041) (xy 185.435158 -194.098032) (xy 185.417685 -194.034131)
			(xy 185.408866 -193.968473) (xy 185.408316 -193.93535) (xy 185.408602 -193.911901) (xy 185.413057 -193.865213)
			(xy 185.417206 -193.842132) (xy 185.418476 -193.83502) (xy 185.417206 -193.820796) (xy 185.411872 -193.80708)
			(xy 185.403236 -193.795904) (xy 185.397394 -193.791586) (xy 185.365336 -193.767455) (xy 185.305301 -193.714209)
			(xy 185.250382 -193.6557) (xy 185.201038 -193.592419) (xy 185.157682 -193.524894) (xy 185.120677 -193.453691)
			(xy 185.090331 -193.379404) (xy 185.0669 -193.302656) (xy 185.050578 -193.224088) (xy 185.045604 -193.184272)
			(xy 185.045604 -193.183764) (xy 185.043782 -193.173481) (xy 185.033154 -193.15553) (xy 185.02503 -193.148966)
			(xy 184.956958 -193.098928) (xy 184.936384 -193.094356) (xy 184.92597 -193.096388) (xy 184.88466 -193.103894)
			(xy 184.801076 -193.111908) (xy 184.759092 -193.11239) (xy 184.717326 -193.111911) (xy 184.634174 -193.10397)
			(xy 184.552154 -193.088151) (xy 184.51195 -193.07683) (xy 184.504838 -193.074798) (xy 181.089808 -193.074798)
			(xy 181.080385 -193.075234) (xy 181.062794 -193.082003) (xy 181.055518 -193.088006) (xy 181.055264 -193.08826)
			(xy 181.048686 -193.094797) (xy 181.040344 -193.111342) (xy 181.039008 -193.120518) (xy 181.039008 -193.121026)
			(xy 181.036018 -193.146947) (xy 181.023678 -193.197645) (xy 181.00433 -193.246103) (xy 180.978358 -193.291357)
			(xy 180.94628 -193.332509) (xy 180.908732 -193.36874) (xy 180.887878 -193.384424) (xy 180.87721 -193.392298)
			(xy 180.866034 -193.41592) (xy 180.874162 -193.528188) (xy 180.88864 -193.550032) (xy 180.900578 -193.556128)
			(xy 180.927094 -193.570401) (xy 180.976781 -193.604427) (xy 181.021986 -193.644215) (xy 181.062043 -193.689181)
			(xy 181.096365 -193.738664) (xy 181.124446 -193.791936) (xy 181.145875 -193.848216) (xy 181.160335 -193.906674)
			(xy 181.167615 -193.966454) (xy 181.16804 -193.996564) (xy 181.167509 -194.029419) (xy 181.158838 -194.094555)
			(xy 181.141643 -194.157975) (xy 181.116225 -194.21857) (xy 181.083029 -194.275279) (xy 181.042636 -194.327108)
			(xy 180.995754 -194.37315) (xy 180.943203 -194.4126) (xy 180.914802 -194.429126) (xy 180.914548 -194.429126)
			(xy 180.904058 -194.43586) (xy 180.890734 -194.456895) (xy 180.889148 -194.469258) (xy 180.881274 -194.565524)
			(xy 180.89118 -194.588384) (xy 180.90134 -194.596512) (xy 180.922701 -194.614126) (xy 180.96041 -194.654665)
			(xy 180.991645 -194.700378) (xy 181.015706 -194.750241) (xy 181.032055 -194.803137) (xy 181.040325 -194.857881)
			(xy 181.040786 -194.885564) (xy 181.04027 -194.913183) (xy 181.032037 -194.967803) (xy 181.015756 -195.020587)
			(xy 180.991789 -195.070354) (xy 180.960673 -195.115993) (xy 180.923102 -195.156485) (xy 180.879916 -195.190925)
			(xy 180.832079 -195.218544) (xy 180.780659 -195.238724) (xy 180.726807 -195.251016) (xy 180.671724 -195.255144)
			(xy 180.616641 -195.251016) (xy 180.562789 -195.238724) (xy 180.511369 -195.218544) (xy 180.463532 -195.190925)
			(xy 180.420346 -195.156485) (xy 180.382775 -195.115993) (xy 180.351659 -195.070354) (xy 180.327692 -195.020587)
			(xy 180.311411 -194.967803) (xy 180.303178 -194.913183) (xy 180.302662 -194.885564) (xy 180.303155 -194.85831)
			(xy 180.311182 -194.804395) (xy 180.327057 -194.752249) (xy 180.350434 -194.703008) (xy 180.380804 -194.657743)
			(xy 180.417505 -194.617441) (xy 180.438298 -194.599814) (xy 180.44287 -194.59575) (xy 180.450998 -194.585082)
			(xy 180.456266 -194.577491) (xy 180.46146 -194.559775) (xy 180.461158 -194.550538) (xy 180.454554 -194.469004)
			(xy 180.452943 -194.456649) (xy 180.439628 -194.435621) (xy 180.429154 -194.428872) (xy 180.4289 -194.428872)
			(xy 180.400531 -194.412334) (xy 180.348017 -194.372907) (xy 180.301169 -194.326893) (xy 180.260805 -194.275097)
			(xy 180.227633 -194.218424) (xy 180.202233 -194.157869) (xy 180.18505 -194.09449) (xy 180.176386 -194.029397)
			(xy 180.175916 -193.996564) (xy 180.176359 -193.966476) (xy 180.183639 -193.906742) (xy 180.198089 -193.848326)
			(xy 180.219497 -193.792087) (xy 180.247547 -193.738848) (xy 180.281829 -193.689392) (xy 180.32184 -193.644444)
			(xy 180.366992 -193.604664) (xy 180.416623 -193.570635) (xy 180.443124 -193.556382) (xy 180.443632 -193.556382)
			(xy 180.443632 -193.556128) (xy 180.451081 -193.551847) (xy 180.462773 -193.539273) (xy 180.469604 -193.52352)
			(xy 180.470556 -193.51498) (xy 180.476652 -193.429128) (xy 180.47692 -193.420583) (xy 180.472429 -193.404098)
			(xy 180.462761 -193.39001) (xy 180.456078 -193.384678) (xy 180.455824 -193.384424) (xy 180.45557 -193.38417)
			(xy 180.434692 -193.368542) (xy 180.397132 -193.332365) (xy 180.365044 -193.291256) (xy 180.339067 -193.246036)
			(xy 180.319722 -193.197608) (xy 180.307392 -193.146937) (xy 180.30444 -193.121026) (xy 180.30444 -193.120518)
			(xy 180.30306 -193.111357) (xy 180.294718 -193.094829) (xy 180.288184 -193.08826) (xy 180.28793 -193.088006)
			(xy 180.280701 -193.081926) (xy 180.263081 -193.075155) (xy 180.25364 -193.074798) (xy 179.27955 -193.074798)
			(xy 179.25034 -193.102992) (xy 179.249324 -193.123312) (xy 179.247087 -193.163733) (xy 179.236106 -193.243945)
			(xy 179.217781 -193.322805) (xy 179.19227 -193.399641) (xy 179.159788 -193.473799) (xy 179.120611 -193.54465)
			(xy 179.075075 -193.61159) (xy 179.023564 -193.67405) (xy 178.966518 -193.731499) (xy 178.904422 -193.783448)
			(xy 178.871372 -193.806826) (xy 178.863705 -193.812616) (xy 178.853016 -193.828563) (xy 178.848925 -193.84732)
			(xy 178.850036 -193.856864) (xy 178.852979 -193.876353) (xy 178.856155 -193.915642) (xy 178.856386 -193.93535)
			(xy 178.855897 -193.967233) (xy 178.847735 -194.030474) (xy 178.831538 -194.092148) (xy 178.807573 -194.151239)
			(xy 178.776236 -194.206773) (xy 178.738043 -194.257835) (xy 178.716178 -194.281044) (xy 178.715924 -194.281298)
			(xy 178.709251 -194.288831) (xy 178.701928 -194.307558) (xy 178.7017 -194.31762) (xy 178.702716 -194.388232)
			(xy 178.702975 -194.393002) (xy 178.705016 -194.402334) (xy 178.70678 -194.406774) (xy 178.71059 -194.416426)
			(xy 178.717956 -194.423538) (xy 178.741445 -194.447497) (xy 178.782561 -194.500518) (xy 178.816344 -194.558488)
			(xy 178.842209 -194.620398) (xy 178.859704 -194.685173) (xy 178.868526 -194.751686) (xy 178.869086 -194.785234)
			(xy 178.868584 -194.817211) (xy 178.860569 -194.880661) (xy 178.844664 -194.942606) (xy 178.821121 -195.002068)
			(xy 178.790311 -195.058112) (xy 178.752719 -195.109852) (xy 178.70894 -195.156472) (xy 178.659662 -195.197238)
			(xy 178.605664 -195.231506) (xy 178.547797 -195.258737) (xy 178.486973 -195.2785) (xy 178.424152 -195.290483)
			(xy 178.360324 -195.294499) (xy 178.296496 -195.290483) (xy 178.233675 -195.2785) (xy 178.172851 -195.258737)
			(xy 178.114984 -195.231506) (xy 178.060986 -195.197238) (xy 178.011708 -195.156472) (xy 177.967929 -195.109852)
			(xy 177.930337 -195.058112) (xy 177.899527 -195.002068) (xy 177.875984 -194.942606) (xy 177.860079 -194.880661)
			(xy 177.852064 -194.817211) (xy 177.851562 -194.785234) (xy 177.852121 -194.751689) (xy 177.860979 -194.685186)
			(xy 177.878493 -194.620421) (xy 177.904359 -194.558518) (xy 177.938131 -194.500547) (xy 177.979223 -194.447513)
			(xy 178.002692 -194.423538) (xy 178.010058 -194.416426) (xy 178.013868 -194.406774) (xy 178.015664 -194.402344)
			(xy 178.017715 -194.393007) (xy 178.017932 -194.388232) (xy 178.018948 -194.31762) (xy 178.018728 -194.307558)
			(xy 178.011402 -194.288827) (xy 178.004724 -194.281298) (xy 178.00447 -194.281044) (xy 177.982618 -194.257824)
			(xy 177.944434 -194.20676) (xy 177.913102 -194.151226) (xy 177.889139 -194.092138) (xy 177.872939 -194.030468)
			(xy 177.864768 -193.967231) (xy 177.864262 -193.93535) (xy 177.864548 -193.9119) (xy 177.869002 -193.865213)
			(xy 177.873152 -193.842132) (xy 177.874422 -193.83502) (xy 177.873152 -193.820796) (xy 177.867818 -193.80708)
			(xy 177.859182 -193.795904) (xy 177.85334 -193.791586) (xy 177.821284 -193.767454) (xy 177.761252 -193.714206)
			(xy 177.706336 -193.655696) (xy 177.656995 -193.592414) (xy 177.613642 -193.524889) (xy 177.576639 -193.453685)
			(xy 177.546296 -193.379399) (xy 177.522866 -193.302652) (xy 177.506545 -193.224085) (xy 177.50155 -193.184272)
			(xy 177.50155 -193.183764) (xy 177.499726 -193.173484) (xy 177.48909 -193.15554) (xy 177.480976 -193.148966)
			(xy 177.412904 -193.098928) (xy 177.39233 -193.094356) (xy 177.381916 -193.096388) (xy 177.340606 -193.103896)
			(xy 177.257022 -193.111915) (xy 177.215038 -193.11239) (xy 177.173273 -193.111908) (xy 177.090122 -193.103963)
			(xy 177.008104 -193.088139) (xy 176.967896 -193.07683) (xy 176.960784 -193.074798) (xy 173.562518 -193.074798)
			(xy 173.553094 -193.075232) (xy 173.535501 -193.081999) (xy 173.528228 -193.088006) (xy 173.527974 -193.08826)
			(xy 173.521395 -193.094796) (xy 173.513051 -193.111341) (xy 173.511718 -193.120518) (xy 173.511718 -193.121026)
			(xy 173.508734 -193.147092) (xy 173.496338 -193.198072) (xy 173.476847 -193.246781) (xy 173.450654 -193.29224)
			(xy 173.418286 -193.33353) (xy 173.380397 -193.36982) (xy 173.359318 -193.38544) (xy 173.354238 -193.388996)
			(xy 173.345348 -193.39941) (xy 173.339335 -193.407141) (xy 173.333081 -193.425683) (xy 173.333156 -193.435478)
			(xy 173.338744 -193.531998) (xy 173.352714 -193.554096) (xy 173.364398 -193.560446) (xy 173.393427 -193.576797)
			(xy 173.447222 -193.616106) (xy 173.49527 -193.662262) (xy 173.536707 -193.714435) (xy 173.570787 -193.771685)
			(xy 173.596897 -193.832983) (xy 173.614566 -193.897223) (xy 173.623476 -193.963251) (xy 173.623986 -193.996564)
			(xy 173.623455 -194.02942) (xy 173.614785 -194.094557) (xy 173.597591 -194.157978) (xy 173.572174 -194.218575)
			(xy 173.538979 -194.275286) (xy 173.498589 -194.327118) (xy 173.451708 -194.373164) (xy 173.399159 -194.412618)
			(xy 173.370748 -194.429126) (xy 173.370494 -194.429126) (xy 173.360013 -194.435866) (xy 173.346703 -194.456901)
			(xy 173.345094 -194.469258) (xy 173.33722 -194.565524) (xy 173.347126 -194.588384) (xy 173.357286 -194.596512)
			(xy 173.378645 -194.614128) (xy 173.416349 -194.654668) (xy 173.44758 -194.700382) (xy 173.471638 -194.750245)
			(xy 173.487985 -194.80314) (xy 173.496254 -194.857882) (xy 173.496732 -194.885564) (xy 173.496216 -194.913183)
			(xy 173.487983 -194.967803) (xy 173.471702 -195.020587) (xy 173.447735 -195.070354) (xy 173.416619 -195.115993)
			(xy 173.379048 -195.156485) (xy 173.335862 -195.190925) (xy 173.288025 -195.218544) (xy 173.236605 -195.238724)
			(xy 173.182753 -195.251016) (xy 173.12767 -195.255144) (xy 173.072587 -195.251016) (xy 173.018735 -195.238724)
			(xy 172.967315 -195.218544) (xy 172.919478 -195.190925) (xy 172.876292 -195.156485) (xy 172.838721 -195.115993)
			(xy 172.807605 -195.070354) (xy 172.783638 -195.020587) (xy 172.767357 -194.967803) (xy 172.759124 -194.913183)
			(xy 172.758608 -194.885564) (xy 172.759101 -194.85831) (xy 172.767129 -194.804397) (xy 172.783006 -194.752252)
			(xy 172.806385 -194.703012) (xy 172.836757 -194.65775) (xy 172.87346 -194.617452) (xy 172.894244 -194.599814)
			(xy 172.898816 -194.59575) (xy 172.906944 -194.585082) (xy 172.912216 -194.577492) (xy 172.917416 -194.559775)
			(xy 172.917104 -194.550538) (xy 172.9105 -194.469004) (xy 172.908891 -194.456646) (xy 172.895583 -194.435609)
			(xy 172.8851 -194.428872) (xy 172.884846 -194.428872) (xy 172.85648 -194.412332) (xy 172.803971 -194.372902)
			(xy 172.757127 -194.326887) (xy 172.716768 -194.275089) (xy 172.6836 -194.218418) (xy 172.658203 -194.157863)
			(xy 172.641023 -194.094487) (xy 172.632359 -194.029396) (xy 172.631862 -193.996564) (xy 172.632317 -193.965973)
			(xy 172.639846 -193.905257) (xy 172.654785 -193.845927) (xy 172.676907 -193.788885) (xy 172.705876 -193.734997)
			(xy 172.741253 -193.68508) (xy 172.7825 -193.639893) (xy 172.828992 -193.600122) (xy 172.880022 -193.566371)
			(xy 172.907198 -193.552318) (xy 172.907706 -193.552064) (xy 172.90796 -193.552064) (xy 172.913508 -193.549013)
			(xy 172.92302 -193.540664) (xy 172.926756 -193.535554) (xy 172.930232 -193.530146) (xy 172.934601 -193.518058)
			(xy 172.935392 -193.511678) (xy 172.943266 -193.42608) (xy 172.943756 -193.417466) (xy 172.939612 -193.400729)
			(xy 172.930137 -193.386323) (xy 172.923454 -193.380868) (xy 172.9232 -193.380614) (xy 172.922946 -193.380614)
			(xy 172.902771 -193.364932) (xy 172.866523 -193.328916) (xy 172.835592 -193.288242) (xy 172.81057 -193.24369)
			(xy 172.791934 -193.19611) (xy 172.780043 -193.146415) (xy 172.77715 -193.121026) (xy 172.77715 -193.120518)
			(xy 172.77577 -193.111356) (xy 172.76743 -193.094828) (xy 172.760894 -193.08826) (xy 172.76064 -193.088006)
			(xy 172.753411 -193.081924) (xy 172.735791 -193.07515) (xy 172.72635 -193.074798) (xy 171.735496 -193.074798)
			(xy 171.706286 -193.102992) (xy 171.70527 -193.123312) (xy 171.703033 -193.163733) (xy 171.692051 -193.243944)
			(xy 171.673726 -193.322803) (xy 171.648213 -193.399637) (xy 171.61573 -193.473795) (xy 171.576552 -193.544644)
			(xy 171.531014 -193.611582) (xy 171.479501 -193.674039) (xy 171.422454 -193.731485) (xy 171.360356 -193.783431)
			(xy 171.327318 -193.806826) (xy 171.319658 -193.81262) (xy 171.308981 -193.828567) (xy 171.304894 -193.847319)
			(xy 171.305982 -193.856864) (xy 171.308926 -193.876353) (xy 171.312102 -193.915642) (xy 171.312332 -193.93535)
			(xy 171.311844 -193.967233) (xy 171.303682 -194.030475) (xy 171.287486 -194.09215) (xy 171.263523 -194.151242)
			(xy 171.232188 -194.206778) (xy 171.193997 -194.257842) (xy 171.172124 -194.281044) (xy 171.17187 -194.281298)
			(xy 171.165192 -194.288829) (xy 171.157862 -194.307557) (xy 171.157646 -194.31762) (xy 171.158662 -194.388232)
			(xy 171.15892 -194.393003) (xy 171.160959 -194.402335) (xy 171.162726 -194.406774) (xy 171.166536 -194.416426)
			(xy 171.173902 -194.423538) (xy 171.197389 -194.447498) (xy 171.238501 -194.500521) (xy 171.272282 -194.558491)
			(xy 171.298144 -194.620401) (xy 171.315637 -194.685175) (xy 171.324458 -194.751687) (xy 171.325032 -194.785234)
			(xy 171.32453 -194.817211) (xy 171.316515 -194.880661) (xy 171.30061 -194.942606) (xy 171.277067 -195.002068)
			(xy 171.246257 -195.058112) (xy 171.208665 -195.109852) (xy 171.164886 -195.156472) (xy 171.115608 -195.197238)
			(xy 171.06161 -195.231506) (xy 171.003743 -195.258737) (xy 170.942919 -195.2785) (xy 170.880098 -195.290483)
			(xy 170.81627 -195.294499) (xy 170.752442 -195.290483) (xy 170.689621 -195.2785) (xy 170.628797 -195.258737)
			(xy 170.57093 -195.231506) (xy 170.516932 -195.197238) (xy 170.467654 -195.156472) (xy 170.423875 -195.109852)
			(xy 170.386283 -195.058112) (xy 170.355473 -195.002068) (xy 170.33193 -194.942606) (xy 170.316025 -194.880661)
			(xy 170.30801 -194.817211) (xy 170.307508 -194.785234) (xy 170.308067 -194.751689) (xy 170.316925 -194.685187)
			(xy 170.334441 -194.620423) (xy 170.360309 -194.558521) (xy 170.394083 -194.500552) (xy 170.435177 -194.447521)
			(xy 170.458638 -194.423538) (xy 170.466004 -194.416426) (xy 170.469814 -194.406774) (xy 170.471612 -194.402344)
			(xy 170.473665 -194.393008) (xy 170.473878 -194.388232) (xy 170.474894 -194.31762) (xy 170.474606 -194.307569)
			(xy 170.467295 -194.28886) (xy 170.46067 -194.281298) (xy 170.460416 -194.281044) (xy 170.438562 -194.257825)
			(xy 170.400375 -194.206762) (xy 170.36904 -194.151229) (xy 170.345075 -194.09214) (xy 170.328873 -194.030469)
			(xy 170.320702 -193.967232) (xy 170.320208 -193.93535) (xy 170.320494 -193.911901) (xy 170.324949 -193.865213)
			(xy 170.329098 -193.842132) (xy 170.330368 -193.83502) (xy 170.329098 -193.820796) (xy 170.323764 -193.80708)
			(xy 170.315128 -193.795904) (xy 170.309286 -193.791586) (xy 170.277228 -193.767455) (xy 170.217194 -193.714208)
			(xy 170.162275 -193.6557) (xy 170.112932 -193.592418) (xy 170.069576 -193.524893) (xy 170.032571 -193.45369)
			(xy 170.002226 -193.379403) (xy 169.978795 -193.302655) (xy 169.962473 -193.224087) (xy 169.957496 -193.184272)
			(xy 169.957496 -193.183764) (xy 169.955674 -193.173482) (xy 169.945044 -193.155531) (xy 169.936922 -193.148966)
			(xy 169.86885 -193.098928) (xy 169.848276 -193.094356) (xy 169.837862 -193.096388) (xy 169.796552 -193.103893)
			(xy 169.712968 -193.111907) (xy 169.670984 -193.11239) (xy 169.629219 -193.111911) (xy 169.546066 -193.103969)
			(xy 169.464047 -193.08815) (xy 169.423842 -193.07683) (xy 169.41673 -193.074798) (xy 168.547796 -193.074798)
			(xy 168.537726 -193.075222) (xy 168.519123 -193.082937) (xy 168.511728 -193.089784) (xy 167.743378 -193.858134)
			(xy 167.737494 -193.864552) (xy 167.730083 -193.880295) (xy 167.728403 -193.897613) (xy 167.73017 -193.90614)
			(xy 167.73017 -193.906394) (xy 167.735408 -193.928567) (xy 167.741018 -193.973783) (xy 167.741346 -193.996564)
			(xy 167.740877 -194.023873) (xy 167.73287 -194.077899) (xy 167.716982 -194.130153) (xy 167.69356 -194.179492)
			(xy 167.663117 -194.224836) (xy 167.626319 -194.265195) (xy 167.605456 -194.282822) (xy 167.600376 -194.286632)
			(xy 167.59301 -194.296538) (xy 167.590724 -194.30238) (xy 167.588388 -194.308182) (xy 167.586333 -194.320517)
			(xy 167.58666 -194.326764) (xy 167.595296 -194.422522) (xy 167.609012 -194.443604) (xy 167.619934 -194.4497)
			(xy 167.649203 -194.466629) (xy 167.703402 -194.507054) (xy 167.751771 -194.5543) (xy 167.793456 -194.607536)
			(xy 167.827725 -194.665823) (xy 167.853972 -194.728136) (xy 167.871736 -194.793375) (xy 167.880704 -194.860393)
			(xy 167.8813 -194.8942) (xy 167.880766 -194.927359) (xy 167.872149 -194.993115) (xy 167.855062 -195.057193)
			(xy 167.829795 -195.118509) (xy 167.796775 -195.176022) (xy 167.756563 -195.228758) (xy 167.70984 -195.275822)
			(xy 167.683942 -195.296536) (xy 167.672058 -195.306441) (xy 167.654411 -195.331832) (xy 167.645164 -195.361339)
			(xy 167.645164 -195.392261) (xy 167.654411 -195.421768) (xy 167.672058 -195.447159) (xy 167.683942 -195.457064)
			(xy 167.70984 -195.477781) (xy 167.756571 -195.52484) (xy 167.79679 -195.577573) (xy 167.829816 -195.635085)
			(xy 167.829934 -195.635372) (xy 169.187876 -195.635372) (xy 169.18842 -195.602652) (xy 169.197015 -195.537781)
			(xy 169.214067 -195.474602) (xy 169.239279 -195.414215) (xy 169.272212 -195.357667) (xy 169.312296 -195.305942)
			(xy 169.335196 -195.282566) (xy 169.342562 -195.275454) (xy 169.350436 -195.256658) (xy 169.350436 -195.163948)
			(xy 169.342562 -195.145152) (xy 169.335196 -195.13804) (xy 169.312311 -195.11465) (xy 169.272226 -195.062926)
			(xy 169.239288 -195.006382) (xy 169.21407 -194.945998) (xy 169.197009 -194.882823) (xy 169.188402 -194.817953)
			(xy 169.187876 -194.785234) (xy 169.188365 -194.754071) (xy 169.196177 -194.692237) (xy 169.211677 -194.631869)
			(xy 169.23462 -194.573921) (xy 169.264646 -194.519304) (xy 169.30128 -194.468882) (xy 169.343945 -194.423448)
			(xy 169.391967 -194.38372) (xy 169.444591 -194.350325) (xy 169.500985 -194.323788) (xy 169.56026 -194.304528)
			(xy 169.621481 -194.292849) (xy 169.683684 -194.288936) (xy 169.745887 -194.292849) (xy 169.807108 -194.304528)
			(xy 169.866383 -194.323788) (xy 169.922777 -194.350325) (xy 169.975401 -194.38372) (xy 170.023423 -194.423448)
			(xy 170.066088 -194.468882) (xy 170.102722 -194.519304) (xy 170.132748 -194.573921) (xy 170.155691 -194.631869)
			(xy 170.171191 -194.692237) (xy 170.179003 -194.754071) (xy 170.179492 -194.785234) (xy 170.178962 -194.817954)
			(xy 170.170364 -194.882827) (xy 170.153311 -194.946006) (xy 170.128097 -195.006393) (xy 170.09516 -195.06294)
			(xy 170.055074 -195.114665) (xy 170.032172 -195.13804) (xy 170.024806 -195.145152) (xy 170.016932 -195.163948)
			(xy 170.016932 -195.256658) (xy 170.024806 -195.275454) (xy 170.032172 -195.282566) (xy 170.055073 -195.305941)
			(xy 170.095154 -195.35767) (xy 170.128088 -195.414218) (xy 170.153303 -195.474604) (xy 170.170361 -195.537781)
			(xy 170.178967 -195.602652) (xy 170.179492 -195.635372) (xy 170.179003 -195.666535) (xy 170.171191 -195.728369)
			(xy 170.155691 -195.788737) (xy 170.132748 -195.846685) (xy 170.125758 -195.8594) (xy 174.408084 -195.8594)
			(xy 174.408593 -195.82624) (xy 174.417211 -195.760483) (xy 174.4343 -195.696403) (xy 174.459572 -195.635087)
			(xy 174.492597 -195.577574) (xy 174.532815 -195.524841) (xy 174.579545 -195.477781) (xy 174.605442 -195.457064)
			(xy 174.614341 -195.449502) (xy 174.624675 -195.428594) (xy 174.625254 -195.416932) (xy 174.625254 -195.336668)
			(xy 174.624647 -195.325015) (xy 174.614315 -195.304116) (xy 174.605442 -195.296536) (xy 174.579541 -195.275826)
			(xy 174.532818 -195.228761) (xy 174.492607 -195.176024) (xy 174.459588 -195.118511) (xy 174.434321 -195.057194)
			(xy 174.417235 -194.993115) (xy 174.408618 -194.927359) (xy 174.408084 -194.8942) (xy 174.408606 -194.860436)
			(xy 174.417548 -194.793503) (xy 174.435275 -194.728344) (xy 174.461474 -194.666106) (xy 174.495684 -194.607886)
			(xy 174.537303 -194.554708) (xy 174.585597 -194.50751) (xy 174.639716 -194.467123) (xy 174.668942 -194.450208)
			(xy 174.679864 -194.443858) (xy 174.69358 -194.422776) (xy 174.703232 -194.31381) (xy 174.693326 -194.290696)
			(xy 174.68342 -194.282568) (xy 174.662597 -194.264929) (xy 174.62583 -194.224606) (xy 174.595404 -194.179306)
			(xy 174.571981 -194.13002) (xy 174.556073 -194.077821) (xy 174.548026 -194.023848) (xy 174.54753 -193.996564)
			(xy 174.548046 -193.968964) (xy 174.556273 -193.914381) (xy 174.572543 -193.861634) (xy 174.596493 -193.811902)
			(xy 174.627588 -193.766294) (xy 174.665133 -193.72583) (xy 174.70829 -193.691413) (xy 174.756094 -193.663814)
			(xy 174.807478 -193.643647) (xy 174.861293 -193.631364) (xy 174.916338 -193.627239) (xy 174.971383 -193.631364)
			(xy 175.025198 -193.643647) (xy 175.076582 -193.663814) (xy 175.124386 -193.691413) (xy 175.167543 -193.72583)
			(xy 175.205088 -193.766294) (xy 175.236183 -193.811902) (xy 175.260133 -193.861634) (xy 175.276403 -193.914381)
			(xy 175.28463 -193.968964) (xy 175.285146 -193.996564) (xy 175.284658 -194.023851) (xy 175.276632 -194.077832)
			(xy 175.260735 -194.13004) (xy 175.237315 -194.179334) (xy 175.206883 -194.224636) (xy 175.170105 -194.264957)
			(xy 175.149256 -194.282568) (xy 175.13935 -194.290442) (xy 175.129698 -194.313556) (xy 175.13935 -194.422776)
			(xy 175.153066 -194.443858) (xy 175.163988 -194.449954) (xy 175.193222 -194.4669) (xy 175.247388 -194.507296)
			(xy 175.295726 -194.554511) (xy 175.337384 -194.607714) (xy 175.371627 -194.665965) (xy 175.397851 -194.72824)
			(xy 175.415595 -194.793439) (xy 175.424546 -194.860415) (xy 175.4251 -194.8942) (xy 175.424597 -194.92736)
			(xy 175.415979 -194.993118) (xy 175.398889 -195.057198) (xy 175.373616 -195.118515) (xy 175.34059 -195.176027)
			(xy 175.300371 -195.22876) (xy 175.25364 -195.275819) (xy 175.227742 -195.296536) (xy 175.218841 -195.304095)
			(xy 175.208509 -195.325005) (xy 175.20793 -195.336668) (xy 175.20793 -195.416932) (xy 175.208543 -195.428584)
			(xy 175.218871 -195.449483) (xy 175.227742 -195.457064) (xy 175.25364 -195.477778) (xy 175.300363 -195.524842)
			(xy 175.340575 -195.577578) (xy 175.373595 -195.635091) (xy 175.373711 -195.635372) (xy 176.73193 -195.635372)
			(xy 176.732458 -195.602652) (xy 176.741055 -195.537779) (xy 176.758108 -195.474599) (xy 176.783323 -195.414212)
			(xy 176.81626 -195.357665) (xy 176.856348 -195.30594) (xy 176.87925 -195.282566) (xy 176.886616 -195.275454)
			(xy 176.89449 -195.256658) (xy 176.89449 -195.163948) (xy 176.886616 -195.145152) (xy 176.87925 -195.13804)
			(xy 176.856356 -195.114658) (xy 176.816274 -195.062932) (xy 176.783338 -195.006385) (xy 176.758122 -194.946)
			(xy 176.741063 -194.882824) (xy 176.732456 -194.817953) (xy 176.73193 -194.785234) (xy 176.732419 -194.754071)
			(xy 176.740231 -194.692237) (xy 176.755731 -194.631869) (xy 176.778674 -194.573921) (xy 176.8087 -194.519304)
			(xy 176.845334 -194.468882) (xy 176.887999 -194.423448) (xy 176.936021 -194.38372) (xy 176.988645 -194.350325)
			(xy 177.045039 -194.323788) (xy 177.104314 -194.304528) (xy 177.165535 -194.292849) (xy 177.227738 -194.288936)
			(xy 177.289941 -194.292849) (xy 177.351162 -194.304528) (xy 177.410437 -194.323788) (xy 177.466831 -194.350325)
			(xy 177.519455 -194.38372) (xy 177.567477 -194.423448) (xy 177.610142 -194.468882) (xy 177.646776 -194.519304)
			(xy 177.676802 -194.573921) (xy 177.699745 -194.631869) (xy 177.715245 -194.692237) (xy 177.723057 -194.754071)
			(xy 177.723546 -194.785234) (xy 177.723029 -194.817955) (xy 177.714431 -194.882829) (xy 177.697376 -194.946008)
			(xy 177.672159 -195.006396) (xy 177.63922 -195.062943) (xy 177.59913 -195.114666) (xy 177.576226 -195.13804)
			(xy 177.56886 -195.145152) (xy 177.560986 -195.163948) (xy 177.560986 -195.256658) (xy 177.56886 -195.275454)
			(xy 177.576226 -195.282566) (xy 177.599118 -195.30595) (xy 177.639202 -195.357675) (xy 177.672138 -195.414221)
			(xy 177.697355 -195.474606) (xy 177.714414 -195.537782) (xy 177.72302 -195.602653) (xy 177.723546 -195.635372)
			(xy 177.723057 -195.666535) (xy 177.715245 -195.728369) (xy 177.699745 -195.788737) (xy 177.676802 -195.846685)
			(xy 177.669812 -195.8594) (xy 181.952138 -195.8594) (xy 181.952665 -195.826241) (xy 181.961282 -195.760485)
			(xy 181.97837 -195.696406) (xy 182.003639 -195.635091) (xy 182.036661 -195.577578) (xy 182.076875 -195.524844)
			(xy 182.123601 -195.477783) (xy 182.149496 -195.457064) (xy 182.158387 -195.449494) (xy 182.168728 -195.428593)
			(xy 182.169308 -195.416932) (xy 182.169308 -195.336668) (xy 182.168682 -195.325018) (xy 182.158362 -195.30412)
			(xy 182.149496 -195.296536) (xy 182.123606 -195.275812) (xy 182.076881 -195.228751) (xy 182.036667 -195.176017)
			(xy 182.003646 -195.118506) (xy 181.978377 -195.057191) (xy 181.961289 -194.993114) (xy 181.952673 -194.927359)
			(xy 181.952138 -194.8942) (xy 181.952683 -194.860437) (xy 181.961624 -194.793506) (xy 181.979349 -194.728349)
			(xy 182.005546 -194.666112) (xy 182.039753 -194.607892) (xy 182.081368 -194.554714) (xy 182.129657 -194.507514)
			(xy 182.183772 -194.467125) (xy 182.212996 -194.450208) (xy 182.223918 -194.443858) (xy 182.237634 -194.422776)
			(xy 182.247286 -194.31381) (xy 182.23738 -194.290696) (xy 182.227474 -194.282568) (xy 182.206642 -194.26494)
			(xy 182.169878 -194.224613) (xy 182.139453 -194.179311) (xy 182.116033 -194.130023) (xy 182.100126 -194.077823)
			(xy 182.09208 -194.023849) (xy 182.091584 -193.996564) (xy 182.0921 -193.968964) (xy 182.100327 -193.914381)
			(xy 182.116597 -193.861634) (xy 182.140547 -193.811902) (xy 182.171642 -193.766294) (xy 182.209187 -193.72583)
			(xy 182.252344 -193.691413) (xy 182.300148 -193.663814) (xy 182.351532 -193.643647) (xy 182.405347 -193.631364)
			(xy 182.460392 -193.627239) (xy 182.515437 -193.631364) (xy 182.569252 -193.643647) (xy 182.620636 -193.663814)
			(xy 182.66844 -193.691413) (xy 182.711597 -193.72583) (xy 182.749142 -193.766294) (xy 182.780237 -193.811902)
			(xy 182.804187 -193.861634) (xy 182.820457 -193.914381) (xy 182.828684 -193.968964) (xy 182.8292 -193.996564)
			(xy 182.828729 -194.023852) (xy 182.820701 -194.077835) (xy 182.804802 -194.130044) (xy 182.781379 -194.179338)
			(xy 182.750944 -194.224639) (xy 182.714161 -194.264958) (xy 182.69331 -194.282568) (xy 182.683404 -194.290442)
			(xy 182.673752 -194.313556) (xy 182.683404 -194.422776) (xy 182.69712 -194.443858) (xy 182.708042 -194.449954)
			(xy 182.737289 -194.466879) (xy 182.791453 -194.50728) (xy 182.839788 -194.554499) (xy 182.881444 -194.607705)
			(xy 182.915684 -194.665959) (xy 182.941907 -194.728236) (xy 182.95965 -194.793437) (xy 182.9686 -194.860414)
			(xy 182.969154 -194.8942) (xy 182.96863 -194.927359) (xy 182.960013 -194.993115) (xy 182.942925 -195.057195)
			(xy 182.917655 -195.11851) (xy 182.884633 -195.176022) (xy 182.844418 -195.228756) (xy 182.797691 -195.275818)
			(xy 182.771796 -195.296536) (xy 182.762903 -195.304104) (xy 182.752564 -195.325007) (xy 182.751984 -195.336668)
			(xy 182.751984 -195.416932) (xy 182.752612 -195.428582) (xy 182.762931 -195.44948) (xy 182.771796 -195.457064)
			(xy 182.797684 -195.47779) (xy 182.84441 -195.524851) (xy 182.884624 -195.577584) (xy 182.917646 -195.635095)
			(xy 182.942915 -195.696409) (xy 182.960002 -195.760487) (xy 182.968619 -195.826241) (xy 182.969154 -195.8594)
			(xy 182.968652 -195.891361) (xy 182.960641 -195.954779) (xy 182.944744 -196.016693) (xy 182.921212 -196.076126)
			(xy 182.890418 -196.132141) (xy 182.852845 -196.183856) (xy 182.809088 -196.230453) (xy 182.759835 -196.271198)
			(xy 182.705864 -196.305449) (xy 182.648025 -196.332666) (xy 182.587232 -196.352419) (xy 182.524442 -196.364397)
			(xy 182.460646 -196.368411) (xy 182.39685 -196.364397) (xy 182.33406 -196.352419) (xy 182.273267 -196.332666)
			(xy 182.215428 -196.305449) (xy 182.161457 -196.271198) (xy 182.112204 -196.230453) (xy 182.068447 -196.183856)
			(xy 182.030874 -196.132141) (xy 182.00008 -196.076126) (xy 181.976548 -196.016693) (xy 181.960651 -195.954779)
			(xy 181.95264 -195.891361) (xy 181.952138 -195.8594) (xy 177.669812 -195.8594) (xy 177.646776 -195.901302)
			(xy 177.610142 -195.951724) (xy 177.567477 -195.997158) (xy 177.519455 -196.036886) (xy 177.466831 -196.070281)
			(xy 177.410437 -196.096818) (xy 177.351162 -196.116078) (xy 177.289941 -196.127757) (xy 177.227738 -196.13167)
			(xy 177.165535 -196.127757) (xy 177.104314 -196.116078) (xy 177.045039 -196.096818) (xy 176.988645 -196.070281)
			(xy 176.936021 -196.036886) (xy 176.887999 -195.997158) (xy 176.845334 -195.951724) (xy 176.8087 -195.901302)
			(xy 176.778674 -195.846685) (xy 176.755731 -195.788737) (xy 176.740231 -195.728369) (xy 176.732419 -195.666535)
			(xy 176.73193 -195.635372) (xy 175.373711 -195.635372) (xy 175.398862 -195.696407) (xy 175.415949 -195.760485)
			(xy 175.424566 -195.826241) (xy 175.4251 -195.8594) (xy 175.424598 -195.891361) (xy 175.416587 -195.954779)
			(xy 175.40069 -196.016693) (xy 175.377158 -196.076126) (xy 175.346364 -196.132141) (xy 175.308791 -196.183856)
			(xy 175.265034 -196.230453) (xy 175.215781 -196.271198) (xy 175.16181 -196.305449) (xy 175.103971 -196.332666)
			(xy 175.043178 -196.352419) (xy 174.980388 -196.364397) (xy 174.916592 -196.368411) (xy 174.852796 -196.364397)
			(xy 174.790006 -196.352419) (xy 174.729213 -196.332666) (xy 174.671374 -196.305449) (xy 174.617403 -196.271198)
			(xy 174.56815 -196.230453) (xy 174.524393 -196.183856) (xy 174.48682 -196.132141) (xy 174.456026 -196.076126)
			(xy 174.432494 -196.016693) (xy 174.416597 -195.954779) (xy 174.408586 -195.891361) (xy 174.408084 -195.8594)
			(xy 170.125758 -195.8594) (xy 170.102722 -195.901302) (xy 170.066088 -195.951724) (xy 170.023423 -195.997158)
			(xy 169.975401 -196.036886) (xy 169.922777 -196.070281) (xy 169.866383 -196.096818) (xy 169.807108 -196.116078)
			(xy 169.745887 -196.127757) (xy 169.683684 -196.13167) (xy 169.621481 -196.127757) (xy 169.56026 -196.116078)
			(xy 169.500985 -196.096818) (xy 169.444591 -196.070281) (xy 169.391967 -196.036886) (xy 169.343945 -195.997158)
			(xy 169.30128 -195.951724) (xy 169.264646 -195.901302) (xy 169.23462 -195.846685) (xy 169.211677 -195.788737)
			(xy 169.196177 -195.728369) (xy 169.188365 -195.666535) (xy 169.187876 -195.635372) (xy 167.829934 -195.635372)
			(xy 167.855089 -195.696402) (xy 167.872179 -195.760482) (xy 167.880797 -195.82624) (xy 167.8813 -195.8594)
			(xy 167.880798 -195.891377) (xy 167.872783 -195.954827) (xy 167.856878 -196.016772) (xy 167.833335 -196.076234)
			(xy 167.802525 -196.132278) (xy 167.764933 -196.184018) (xy 167.721154 -196.230638) (xy 167.671876 -196.271404)
			(xy 167.617878 -196.305672) (xy 167.560011 -196.332903) (xy 167.499187 -196.352666) (xy 167.436366 -196.364649)
			(xy 167.372538 -196.368665) (xy 167.30871 -196.364649) (xy 167.245889 -196.352666) (xy 167.185065 -196.332903)
			(xy 167.127198 -196.305672) (xy 167.0732 -196.271404) (xy 167.023922 -196.230638) (xy 166.980143 -196.184018)
			(xy 166.942551 -196.132278) (xy 166.911741 -196.076234) (xy 166.888198 -196.016772) (xy 166.872293 -195.954827)
			(xy 166.864278 -195.891377) (xy 166.863776 -195.8594) (xy 166.86431 -195.826241) (xy 166.872927 -195.760485)
			(xy 166.890013 -195.696405) (xy 166.915279 -195.635089) (xy 166.948298 -195.577575) (xy 166.988509 -195.524838)
			(xy 167.035231 -195.477772) (xy 167.061134 -195.457064) (xy 167.07302 -195.44716) (xy 167.090672 -195.42177)
			(xy 167.099921 -195.392262) (xy 167.099921 -195.361338) (xy 167.090672 -195.33183) (xy 167.07302 -195.30644)
			(xy 167.061134 -195.296536) (xy 167.035439 -195.275977) (xy 166.989044 -195.229308) (xy 166.949051 -195.177048)
			(xy 166.916128 -195.120069) (xy 166.890824 -195.059321) (xy 166.873561 -194.995819) (xy 166.868602 -194.963288)
			(xy 166.868602 -194.963034) (xy 166.866932 -194.953801) (xy 166.857788 -194.93743) (xy 166.843335 -194.925483)
			(xy 166.834566 -194.92214) (xy 166.748714 -194.89293) (xy 166.739612 -194.890322) (xy 166.720715 -194.891156)
			(xy 166.703388 -194.898747) (xy 166.69639 -194.905122) (xy 165.116256 -196.485256) (xy 168.158683 -196.485256)
			(xy 168.162618 -196.431485) (xy 168.174341 -196.378861) (xy 168.193601 -196.328504) (xy 168.219987 -196.281487)
			(xy 168.252939 -196.238814) (xy 168.291752 -196.201393) (xy 168.3356 -196.170023) (xy 168.383548 -196.145371)
			(xy 168.434575 -196.127963) (xy 168.487593 -196.11817) (xy 168.541472 -196.116201) (xy 168.595063 -196.122098)
			(xy 168.647224 -196.135734) (xy 168.696844 -196.156821) (xy 168.742865 -196.184907) (xy 168.784307 -196.219395)
			(xy 168.820285 -196.259549) (xy 168.850033 -196.304513) (xy 168.872918 -196.35333) (xy 168.88845 -196.404959)
			(xy 168.8963 -196.458299) (xy 168.896792 -196.485256) (xy 168.8963 -196.512213) (xy 168.88845 -196.565553)
			(xy 168.872918 -196.617182) (xy 168.850033 -196.665999) (xy 168.820285 -196.710963) (xy 168.784307 -196.751117)
			(xy 168.742865 -196.785605) (xy 168.696844 -196.813691) (xy 168.647224 -196.834778) (xy 168.595063 -196.848414)
			(xy 168.541472 -196.854311) (xy 168.487593 -196.852342) (xy 168.434575 -196.842549) (xy 168.383548 -196.825141)
			(xy 168.3356 -196.800489) (xy 168.291752 -196.769119) (xy 168.252939 -196.731698) (xy 168.219987 -196.689025)
			(xy 168.193601 -196.642008) (xy 168.174341 -196.591651) (xy 168.162618 -196.539027) (xy 168.158683 -196.485256)
			(xy 165.116256 -196.485256) (xy 164.67963 -196.921882) (xy 164.671502 -196.93255) (xy 164.668295 -196.938538)
			(xy 164.664824 -196.951667) (xy 164.664644 -196.958458) (xy 164.665406 -197.041262) (xy 164.673534 -197.060058)
			(xy 164.681154 -197.067424) (xy 164.699053 -197.084901) (xy 164.730447 -197.12385) (xy 164.756286 -197.166687)
			(xy 164.776096 -197.212623) (xy 164.789514 -197.260816) (xy 164.796292 -197.310381) (xy 164.796724 -197.335394)
			(xy 164.796255 -197.361739) (xy 164.788757 -197.413892) (xy 164.773914 -197.464448) (xy 164.752027 -197.512376)
			(xy 164.723542 -197.556702) (xy 164.689039 -197.596523) (xy 164.64922 -197.631029) (xy 164.604896 -197.659516)
			(xy 164.556968 -197.681406) (xy 164.506414 -197.696252) (xy 164.454261 -197.703753) (xy 164.427916 -197.704202)
			(xy 164.402913 -197.703787) (xy 164.353364 -197.697036) (xy 164.30518 -197.683655) (xy 164.259246 -197.663889)
			(xy 164.216401 -197.638101) (xy 164.177432 -197.606763) (xy 164.159946 -197.588886) (xy 164.152834 -197.581266)
			(xy 164.134038 -197.572884) (xy 164.040566 -197.572122) (xy 164.02177 -197.579742) (xy 164.014404 -197.587108)
			(xy 163.416234 -198.185278) (xy 168.158683 -198.185278) (xy 168.162618 -198.131507) (xy 168.174341 -198.078883)
			(xy 168.193601 -198.028526) (xy 168.219987 -197.981509) (xy 168.252939 -197.938836) (xy 168.291752 -197.901415)
			(xy 168.3356 -197.870045) (xy 168.383548 -197.845393) (xy 168.434575 -197.827985) (xy 168.487593 -197.818192)
			(xy 168.541472 -197.816223) (xy 168.595063 -197.82212) (xy 168.647224 -197.835756) (xy 168.696844 -197.856843)
			(xy 168.742865 -197.884929) (xy 168.784307 -197.919417) (xy 168.820285 -197.959571) (xy 168.850033 -198.004535)
			(xy 168.872918 -198.053352) (xy 168.88845 -198.104981) (xy 168.8963 -198.158321) (xy 168.896792 -198.185278)
			(xy 168.8963 -198.212235) (xy 168.88845 -198.265575) (xy 168.872918 -198.317204) (xy 168.850033 -198.366021)
			(xy 168.820285 -198.410985) (xy 168.784307 -198.451139) (xy 168.742865 -198.485627) (xy 168.696844 -198.513713)
			(xy 168.647224 -198.5348) (xy 168.595063 -198.548436) (xy 168.541472 -198.554333) (xy 168.487593 -198.552364)
			(xy 168.434575 -198.542571) (xy 168.383548 -198.525163) (xy 168.3356 -198.500511) (xy 168.291752 -198.469141)
			(xy 168.252939 -198.43172) (xy 168.219987 -198.389047) (xy 168.193601 -198.34203) (xy 168.174341 -198.291673)
			(xy 168.162618 -198.239049) (xy 168.158683 -198.185278) (xy 163.416234 -198.185278) (xy 162.566096 -199.035416)
			(xy 164.058615 -199.035416) (xy 164.06255 -198.981645) (xy 164.074273 -198.929021) (xy 164.093533 -198.878664)
			(xy 164.119919 -198.831647) (xy 164.152871 -198.788974) (xy 164.191684 -198.751553) (xy 164.235532 -198.720183)
			(xy 164.28348 -198.695531) (xy 164.334507 -198.678123) (xy 164.387525 -198.66833) (xy 164.441404 -198.666361)
			(xy 164.494995 -198.672258) (xy 164.547156 -198.685894) (xy 164.596776 -198.706981) (xy 164.642797 -198.735067)
			(xy 164.684239 -198.769555) (xy 164.720217 -198.809709) (xy 164.749965 -198.854673) (xy 164.77285 -198.90349)
			(xy 164.788382 -198.955119) (xy 164.796232 -199.008459) (xy 164.796724 -199.035416) (xy 164.796232 -199.062373)
			(xy 164.788382 -199.115713) (xy 164.77285 -199.167342) (xy 164.749965 -199.216159) (xy 164.720217 -199.261123)
			(xy 164.684239 -199.301277) (xy 164.642797 -199.335765) (xy 164.596776 -199.363851) (xy 164.547156 -199.384938)
			(xy 164.494995 -199.398574) (xy 164.441404 -199.404471) (xy 164.387525 -199.402502) (xy 164.334507 -199.392709)
			(xy 164.28348 -199.375301) (xy 164.235532 -199.350649) (xy 164.191684 -199.319279) (xy 164.152871 -199.281858)
			(xy 164.119919 -199.239185) (xy 164.093533 -199.192168) (xy 164.074273 -199.141811) (xy 164.06255 -199.089187)
			(xy 164.058615 -199.035416) (xy 162.566096 -199.035416) (xy 161.716212 -199.8853) (xy 166.774383 -199.8853)
			(xy 166.778318 -199.831529) (xy 166.790041 -199.778905) (xy 166.809301 -199.728548) (xy 166.835687 -199.681531)
			(xy 166.868639 -199.638858) (xy 166.907452 -199.601437) (xy 166.9513 -199.570067) (xy 166.999248 -199.545415)
			(xy 167.050275 -199.528007) (xy 167.103293 -199.518214) (xy 167.157172 -199.516245) (xy 167.210763 -199.522142)
			(xy 167.262924 -199.535778) (xy 167.312544 -199.556865) (xy 167.358565 -199.584951) (xy 167.400007 -199.619439)
			(xy 167.435985 -199.659593) (xy 167.465733 -199.704557) (xy 167.488618 -199.753374) (xy 167.50415 -199.805003)
			(xy 167.512 -199.858343) (xy 167.512492 -199.8853) (xy 171.476162 -199.8853) (xy 171.476616 -199.854103)
			(xy 171.484438 -199.7922) (xy 171.49997 -199.73177) (xy 171.522966 -199.673768) (xy 171.553063 -199.619112)
			(xy 171.589784 -199.568668) (xy 171.632549 -199.523233) (xy 171.680679 -199.483527) (xy 171.706794 -199.466454)
			(xy 171.716954 -199.45985) (xy 171.729146 -199.440038) (xy 171.738544 -199.335898) (xy 171.730162 -199.314308)
			(xy 171.721272 -199.305926) (xy 171.702995 -199.288402) (xy 171.670915 -199.249227) (xy 171.644496 -199.206032)
			(xy 171.624234 -199.159629) (xy 171.61051 -199.110891) (xy 171.603581 -199.060733) (xy 171.603162 -199.035416)
			(xy 171.603616 -199.010069) (xy 171.610546 -198.959851) (xy 171.624289 -198.911057) (xy 171.644589 -198.864605)
			(xy 171.671061 -198.821372) (xy 171.703206 -198.782174) (xy 171.721526 -198.764652) (xy 171.730416 -198.756524)
			(xy 171.738798 -198.73468) (xy 171.729146 -198.63054) (xy 171.716954 -198.610728) (xy 171.706794 -198.604378)
			(xy 171.680664 -198.587305) (xy 171.632543 -198.547549) (xy 171.589788 -198.502071) (xy 171.553075 -198.45159)
			(xy 171.522984 -198.396902) (xy 171.499991 -198.338871) (xy 171.484458 -198.278415) (xy 171.476632 -198.216488)
			(xy 171.476162 -198.185278) (xy 171.476599 -198.15408) (xy 171.484423 -198.092177) (xy 171.499958 -198.031746)
			(xy 171.522957 -197.973744) (xy 171.553056 -197.919088) (xy 171.58978 -197.868644) (xy 171.632546 -197.82321)
			(xy 171.680678 -197.783505) (xy 171.706794 -197.766432) (xy 171.716954 -197.759828) (xy 171.729146 -197.740016)
			(xy 171.738544 -197.635876) (xy 171.730162 -197.614286) (xy 171.721272 -197.605904) (xy 171.702984 -197.588391)
			(xy 171.670906 -197.549214) (xy 171.644488 -197.506016) (xy 171.624228 -197.459611) (xy 171.610506 -197.410871)
			(xy 171.60358 -197.360712) (xy 171.603162 -197.335394) (xy 171.603678 -197.307794) (xy 171.611905 -197.253211)
			(xy 171.628175 -197.200464) (xy 171.652125 -197.150732) (xy 171.68322 -197.105124) (xy 171.720765 -197.06466)
			(xy 171.763922 -197.030243) (xy 171.811726 -197.002644) (xy 171.86311 -196.982477) (xy 171.916925 -196.970194)
			(xy 171.97197 -196.966069) (xy 172.027015 -196.970194) (xy 172.08083 -196.982477) (xy 172.132214 -197.002644)
			(xy 172.180018 -197.030243) (xy 172.223175 -197.06466) (xy 172.26072 -197.105124) (xy 172.291815 -197.150732)
			(xy 172.315765 -197.200464) (xy 172.332035 -197.253211) (xy 172.340262 -197.307794) (xy 172.340778 -197.335394)
			(xy 172.340373 -197.360712) (xy 172.333446 -197.410872) (xy 172.319722 -197.459613) (xy 172.299459 -197.506017)
			(xy 172.273037 -197.549213) (xy 172.240954 -197.588388) (xy 172.222668 -197.605904) (xy 172.213778 -197.614286)
			(xy 172.205396 -197.635876) (xy 172.214794 -197.740016) (xy 172.226986 -197.759828) (xy 172.237146 -197.766432)
			(xy 172.263254 -197.783513) (xy 172.311373 -197.823227) (xy 172.354128 -197.868665) (xy 172.390843 -197.919109)
			(xy 172.420937 -197.973763) (xy 172.443935 -198.03176) (xy 172.459473 -198.092185) (xy 172.467306 -198.154083)
			(xy 172.467778 -198.185278) (xy 172.467349 -198.216489) (xy 172.45952 -198.278418) (xy 172.443983 -198.338875)
			(xy 172.420983 -198.396905) (xy 172.390884 -198.45159) (xy 172.354161 -198.502067) (xy 172.311396 -198.547538)
			(xy 172.263263 -198.587283) (xy 172.237146 -198.604378) (xy 172.226986 -198.610728) (xy 172.214794 -198.63054)
			(xy 172.205142 -198.73468) (xy 172.213524 -198.756524) (xy 172.222414 -198.764652) (xy 172.240761 -198.782147)
			(xy 172.272901 -198.821355) (xy 172.299371 -198.864594) (xy 172.319671 -198.911049) (xy 172.33342 -198.959847)
			(xy 172.340359 -199.010067) (xy 172.340778 -199.035416) (xy 175.57623 -199.035416) (xy 175.576651 -199.004205)
			(xy 175.584481 -198.942276) (xy 175.600019 -198.881818) (xy 175.62302 -198.823788) (xy 175.65312 -198.769103)
			(xy 175.689844 -198.718626) (xy 175.73261 -198.673155) (xy 175.780744 -198.63341) (xy 175.806862 -198.616316)
			(xy 175.817022 -198.609966) (xy 175.829214 -198.590154) (xy 175.838866 -198.486014) (xy 175.830484 -198.46417)
			(xy 175.821594 -198.456042) (xy 175.803245 -198.438548) (xy 175.771105 -198.39934) (xy 175.744636 -198.356101)
			(xy 175.724335 -198.309645) (xy 175.710587 -198.260848) (xy 175.703649 -198.210627) (xy 175.70323 -198.185278)
			(xy 175.703681 -198.159962) (xy 175.710598 -198.109804) (xy 175.724313 -198.061064) (xy 175.744568 -198.014659)
			(xy 175.770982 -197.971462) (xy 175.803058 -197.932285) (xy 175.82134 -197.914768) (xy 175.83023 -197.906386)
			(xy 175.838612 -197.884796) (xy 175.829214 -197.780656) (xy 175.817022 -197.760844) (xy 175.806862 -197.75424)
			(xy 175.78072 -197.737209) (xy 175.732605 -197.697485) (xy 175.689855 -197.652038) (xy 175.653145 -197.601585)
			(xy 175.623055 -197.546926) (xy 175.600062 -197.488922) (xy 175.584529 -197.428493) (xy 175.576701 -197.366591)
			(xy 175.57623 -197.335394) (xy 175.576712 -197.304185) (xy 175.584532 -197.242258) (xy 175.600061 -197.181802)
			(xy 175.623053 -197.123772) (xy 175.653145 -197.069087) (xy 175.689861 -197.018609) (xy 175.73262 -196.973137)
			(xy 175.780747 -196.933389) (xy 175.806862 -196.916294) (xy 175.817022 -196.909944) (xy 175.829214 -196.890132)
			(xy 175.838866 -196.785992) (xy 175.830484 -196.764148) (xy 175.821594 -196.75602) (xy 175.803283 -196.738489)
			(xy 175.771139 -196.699289) (xy 175.744665 -196.656058) (xy 175.724358 -196.609609) (xy 175.710602 -196.560818)
			(xy 175.703654 -196.510603) (xy 175.70323 -196.485256) (xy 175.703746 -196.457656) (xy 175.711973 -196.403073)
			(xy 175.728243 -196.350326) (xy 175.752193 -196.300594) (xy 175.783288 -196.254986) (xy 175.820833 -196.214522)
			(xy 175.86399 -196.180105) (xy 175.911794 -196.152506) (xy 175.963178 -196.132339) (xy 176.016993 -196.120056)
			(xy 176.072038 -196.115931) (xy 176.127083 -196.120056) (xy 176.180898 -196.132339) (xy 176.232282 -196.152506)
			(xy 176.280086 -196.180105) (xy 176.323243 -196.214522) (xy 176.360788 -196.254986) (xy 176.391883 -196.300594)
			(xy 176.415833 -196.350326) (xy 176.432103 -196.403073) (xy 176.44033 -196.457656) (xy 176.440846 -196.485256)
			(xy 176.440437 -196.510604) (xy 176.433498 -196.560824) (xy 176.419745 -196.60962) (xy 176.399437 -196.656071)
			(xy 176.372958 -196.699303) (xy 176.340805 -196.738499) (xy 176.322482 -196.75602) (xy 176.313592 -196.764148)
			(xy 176.30521 -196.785992) (xy 176.314862 -196.890132) (xy 176.327054 -196.909944) (xy 176.337214 -196.916294)
			(xy 176.363333 -196.933383) (xy 176.411454 -196.973137) (xy 176.454209 -197.018612) (xy 176.490923 -197.069092)
			(xy 176.521015 -197.123777) (xy 176.54401 -197.181806) (xy 176.559545 -197.24226) (xy 176.567375 -197.304185)
			(xy 176.567846 -197.335394) (xy 176.567383 -197.366591) (xy 176.559563 -197.428493) (xy 176.544032 -197.488923)
			(xy 176.521037 -197.546925) (xy 176.490941 -197.601581) (xy 176.454221 -197.652025) (xy 176.411458 -197.69746)
			(xy 176.363328 -197.737166) (xy 176.337214 -197.75424) (xy 176.327054 -197.760844) (xy 176.314862 -197.780656)
			(xy 176.305464 -197.884796) (xy 176.313846 -197.906386) (xy 176.322736 -197.914768) (xy 176.341012 -197.932293)
			(xy 176.373091 -197.971468) (xy 176.39951 -198.014663) (xy 176.419773 -198.061066) (xy 176.433497 -198.109804)
			(xy 176.440426 -198.159961) (xy 176.440846 -198.185278) (xy 176.440385 -198.210625) (xy 176.433457 -198.260842)
			(xy 176.419714 -198.309637) (xy 176.399416 -198.356088) (xy 176.372945 -198.399321) (xy 176.340802 -198.43852)
			(xy 176.322482 -198.456042) (xy 176.313592 -198.46417) (xy 176.30521 -198.486014) (xy 176.314862 -198.590154)
			(xy 176.327054 -198.609966) (xy 176.337214 -198.616316) (xy 176.363343 -198.63339) (xy 176.411464 -198.673146)
			(xy 176.454219 -198.718624) (xy 176.490931 -198.769106) (xy 176.521022 -198.823793) (xy 176.544015 -198.881823)
			(xy 176.559549 -198.942279) (xy 176.567376 -199.004206) (xy 176.567846 -199.035416) (xy 176.567357 -199.066579)
			(xy 176.559545 -199.128413) (xy 176.544045 -199.188781) (xy 176.521102 -199.246729) (xy 176.491076 -199.301346)
			(xy 176.454442 -199.351768) (xy 176.411777 -199.397202) (xy 176.363755 -199.43693) (xy 176.311131 -199.470325)
			(xy 176.254737 -199.496862) (xy 176.195462 -199.516122) (xy 176.134241 -199.527801) (xy 176.072038 -199.531714)
			(xy 176.009835 -199.527801) (xy 175.948614 -199.516122) (xy 175.889339 -199.496862) (xy 175.832945 -199.470325)
			(xy 175.780321 -199.43693) (xy 175.732299 -199.397202) (xy 175.689634 -199.351768) (xy 175.653 -199.301346)
			(xy 175.622974 -199.246729) (xy 175.600031 -199.188781) (xy 175.584531 -199.128413) (xy 175.576719 -199.066579)
			(xy 175.57623 -199.035416) (xy 172.340778 -199.035416) (xy 172.340388 -199.060734) (xy 172.333458 -199.110895)
			(xy 172.319731 -199.159636) (xy 172.299465 -199.206041) (xy 172.27304 -199.249236) (xy 172.240955 -199.288411)
			(xy 172.222668 -199.305926) (xy 172.213778 -199.314308) (xy 172.205396 -199.335898) (xy 172.214794 -199.440038)
			(xy 172.226986 -199.45985) (xy 172.237146 -199.466454) (xy 172.263264 -199.483521) (xy 172.311383 -199.523236)
			(xy 172.354138 -199.568677) (xy 172.390852 -199.619123) (xy 172.420945 -199.673778) (xy 172.443941 -199.731778)
			(xy 172.459477 -199.792205) (xy 172.467307 -199.854104) (xy 172.467778 -199.8853) (xy 174.318437 -199.8853)
			(xy 174.322372 -199.831529) (xy 174.334095 -199.778905) (xy 174.353355 -199.728548) (xy 174.379741 -199.681531)
			(xy 174.412693 -199.638858) (xy 174.451506 -199.601437) (xy 174.495354 -199.570067) (xy 174.543302 -199.545415)
			(xy 174.594329 -199.528007) (xy 174.647347 -199.518214) (xy 174.701226 -199.516245) (xy 174.754817 -199.522142)
			(xy 174.806978 -199.535778) (xy 174.856598 -199.556865) (xy 174.902619 -199.584951) (xy 174.944061 -199.619439)
			(xy 174.980039 -199.659593) (xy 175.009787 -199.704557) (xy 175.032672 -199.753374) (xy 175.048204 -199.805003)
			(xy 175.056054 -199.858343) (xy 175.056546 -199.8853) (xy 179.020216 -199.8853) (xy 179.020645 -199.854102)
			(xy 179.028468 -199.792197) (xy 179.044001 -199.731765) (xy 179.067001 -199.673762) (xy 179.097101 -199.619106)
			(xy 179.133827 -199.568662) (xy 179.176595 -199.523229) (xy 179.224731 -199.483526) (xy 179.250848 -199.466454)
			(xy 179.261008 -199.45985) (xy 179.2732 -199.440038) (xy 179.282598 -199.335898) (xy 179.274216 -199.314308)
			(xy 179.265326 -199.305926) (xy 179.24704 -199.288411) (xy 179.214963 -199.249233) (xy 179.188546 -199.206036)
			(xy 179.168286 -199.159631) (xy 179.154563 -199.110892) (xy 179.147635 -199.060733) (xy 179.147216 -199.035416)
			(xy 179.147653 -199.010068) (xy 179.154583 -198.959849) (xy 179.16833 -198.911053) (xy 179.188632 -198.864601)
			(xy 179.215108 -198.821369) (xy 179.247257 -198.782172) (xy 179.26558 -198.764652) (xy 179.27447 -198.756524)
			(xy 179.282852 -198.73468) (xy 179.2732 -198.63054) (xy 179.261008 -198.610728) (xy 179.250848 -198.604378)
			(xy 179.224707 -198.587322) (xy 179.176588 -198.547562) (xy 179.133835 -198.50208) (xy 179.097124 -198.451596)
			(xy 179.067035 -198.396906) (xy 179.044043 -198.338874) (xy 179.028511 -198.278417) (xy 179.020685 -198.216488)
			(xy 179.020216 -198.185278) (xy 179.020628 -198.154079) (xy 179.028453 -198.092174) (xy 179.04399 -198.031741)
			(xy 179.066991 -197.973738) (xy 179.097094 -197.919082) (xy 179.133822 -197.868638) (xy 179.176593 -197.823206)
			(xy 179.22473 -197.783503) (xy 179.250848 -197.766432) (xy 179.261008 -197.759828) (xy 179.2732 -197.740016)
			(xy 179.282598 -197.635876) (xy 179.274216 -197.614286) (xy 179.265326 -197.605904) (xy 179.247029 -197.5884)
			(xy 179.214954 -197.549219) (xy 179.188538 -197.50602) (xy 179.16828 -197.459613) (xy 179.154559 -197.410872)
			(xy 179.147634 -197.360712) (xy 179.147216 -197.335394) (xy 179.147732 -197.307794) (xy 179.155959 -197.253211)
			(xy 179.172229 -197.200464) (xy 179.196179 -197.150732) (xy 179.227274 -197.105124) (xy 179.264819 -197.06466)
			(xy 179.307976 -197.030243) (xy 179.35578 -197.002644) (xy 179.407164 -196.982477) (xy 179.460979 -196.970194)
			(xy 179.516024 -196.966069) (xy 179.571069 -196.970194) (xy 179.624884 -196.982477) (xy 179.676268 -197.002644)
			(xy 179.724072 -197.030243) (xy 179.767229 -197.06466) (xy 179.804774 -197.105124) (xy 179.835869 -197.150732)
			(xy 179.859819 -197.200464) (xy 179.876089 -197.253211) (xy 179.884316 -197.307794) (xy 179.884832 -197.335394)
			(xy 179.884441 -197.360713) (xy 179.877513 -197.410874) (xy 179.863787 -197.459615) (xy 179.843521 -197.50602)
			(xy 179.817096 -197.549216) (xy 179.78501 -197.588389) (xy 179.766722 -197.605904) (xy 179.757832 -197.614286)
			(xy 179.74945 -197.635876) (xy 179.758848 -197.740016) (xy 179.77104 -197.759828) (xy 179.7812 -197.766432)
			(xy 179.80732 -197.783495) (xy 179.855437 -197.823213) (xy 179.89819 -197.868655) (xy 179.934902 -197.919102)
			(xy 179.964995 -197.973758) (xy 179.987991 -198.031757) (xy 180.003528 -198.092184) (xy 180.01136 -198.154082)
			(xy 180.011832 -198.185278) (xy 180.011378 -198.216488) (xy 180.00355 -198.278415) (xy 179.988014 -198.33887)
			(xy 179.965017 -198.396899) (xy 179.934922 -198.451584) (xy 179.898204 -198.502061) (xy 179.855443 -198.547533)
			(xy 179.807315 -198.587282) (xy 179.7812 -198.604378) (xy 179.77104 -198.610728) (xy 179.758848 -198.63054)
			(xy 179.749196 -198.73468) (xy 179.757578 -198.756524) (xy 179.766468 -198.764652) (xy 179.784807 -198.782156)
			(xy 179.816949 -198.821361) (xy 179.843421 -198.864597) (xy 179.863723 -198.911052) (xy 179.877473 -198.959848)
			(xy 179.884413 -199.010068) (xy 179.884832 -199.035416) (xy 183.120284 -199.035416) (xy 183.120726 -199.004206)
			(xy 183.128555 -198.942278) (xy 183.144092 -198.881822) (xy 183.16709 -198.823793) (xy 183.197188 -198.769108)
			(xy 183.233908 -198.718631) (xy 183.27667 -198.673159) (xy 183.3248 -198.633412) (xy 183.350916 -198.616316)
			(xy 183.361076 -198.609966) (xy 183.373268 -198.590154) (xy 183.38292 -198.486014) (xy 183.374538 -198.46417)
			(xy 183.365648 -198.456042) (xy 183.347309 -198.438538) (xy 183.315166 -198.399333) (xy 183.288694 -198.356097)
			(xy 183.268392 -198.309643) (xy 183.254642 -198.260846) (xy 183.247703 -198.210626) (xy 183.247284 -198.185278)
			(xy 183.247749 -198.159962) (xy 183.254666 -198.109805) (xy 183.268379 -198.061066) (xy 183.288631 -198.014662)
			(xy 183.315042 -197.971464) (xy 183.347114 -197.932286) (xy 183.365394 -197.914768) (xy 183.374284 -197.906386)
			(xy 183.382666 -197.884796) (xy 183.373268 -197.780656) (xy 183.361076 -197.760844) (xy 183.350916 -197.75424)
			(xy 183.324787 -197.737191) (xy 183.276669 -197.697471) (xy 183.233917 -197.652027) (xy 183.197204 -197.601578)
			(xy 183.167113 -197.546921) (xy 183.144118 -197.488919) (xy 183.128584 -197.428491) (xy 183.120755 -197.366591)
			(xy 183.120284 -197.335394) (xy 183.120787 -197.304186) (xy 183.128606 -197.242261) (xy 183.144134 -197.181806)
			(xy 183.167123 -197.123777) (xy 183.197212 -197.069092) (xy 183.233925 -197.018614) (xy 183.27668 -196.97314)
			(xy 183.324803 -196.933391) (xy 183.350916 -196.916294) (xy 183.361076 -196.909944) (xy 183.373268 -196.890132)
			(xy 183.38292 -196.785992) (xy 183.374538 -196.764148) (xy 183.365648 -196.75602) (xy 183.347347 -196.738478)
			(xy 183.315201 -196.699282) (xy 183.288724 -196.656053) (xy 183.268415 -196.609606) (xy 183.254656 -196.560817)
			(xy 183.247708 -196.510602) (xy 183.247284 -196.485256) (xy 183.2478 -196.457656) (xy 183.256027 -196.403073)
			(xy 183.272297 -196.350326) (xy 183.296247 -196.300594) (xy 183.327342 -196.254986) (xy 183.364887 -196.214522)
			(xy 183.408044 -196.180105) (xy 183.455848 -196.152506) (xy 183.507232 -196.132339) (xy 183.561047 -196.120056)
			(xy 183.616092 -196.115931) (xy 183.671137 -196.120056) (xy 183.724952 -196.132339) (xy 183.776336 -196.152506)
			(xy 183.82414 -196.180105) (xy 183.867297 -196.214522) (xy 183.904842 -196.254986) (xy 183.935937 -196.300594)
			(xy 183.959887 -196.350326) (xy 183.976157 -196.403073) (xy 183.984384 -196.457656) (xy 183.9849 -196.485256)
			(xy 183.984506 -196.510605) (xy 183.977566 -196.560826) (xy 183.963811 -196.609622) (xy 183.943501 -196.656074)
			(xy 183.917018 -196.699305) (xy 183.884861 -196.738501) (xy 183.866536 -196.75602) (xy 183.857646 -196.764148)
			(xy 183.849264 -196.785992) (xy 183.858916 -196.890132) (xy 183.871108 -196.909944) (xy 183.881268 -196.916294)
			(xy 183.907376 -196.933398) (xy 183.9555 -196.973149) (xy 183.998257 -197.018621) (xy 184.034972 -197.069098)
			(xy 184.065066 -197.123782) (xy 184.088062 -197.181808) (xy 184.103598 -197.242261) (xy 184.111429 -197.304185)
			(xy 184.1119 -197.335394) (xy 184.111459 -197.366592) (xy 184.103637 -197.428496) (xy 184.088105 -197.488927)
			(xy 184.065107 -197.54693) (xy 184.035008 -197.601586) (xy 183.998285 -197.65203) (xy 183.955518 -197.697464)
			(xy 183.907385 -197.737168) (xy 183.881268 -197.75424) (xy 183.871108 -197.760844) (xy 183.858916 -197.780656)
			(xy 183.849518 -197.884796) (xy 183.8579 -197.906386) (xy 183.86679 -197.914768) (xy 183.885076 -197.932282)
			(xy 183.917152 -197.971461) (xy 183.943569 -198.014659) (xy 183.963829 -198.061063) (xy 183.977552 -198.109802)
			(xy 183.98448 -198.159961) (xy 183.9849 -198.185278) (xy 183.984454 -198.210625) (xy 183.977525 -198.260844)
			(xy 183.96378 -198.309639) (xy 183.943479 -198.356091) (xy 183.917005 -198.399324) (xy 183.884858 -198.438521)
			(xy 183.866536 -198.456042) (xy 183.857646 -198.46417) (xy 183.849264 -198.486014) (xy 183.858916 -198.590154)
			(xy 183.871108 -198.609966) (xy 183.881268 -198.616316) (xy 183.907386 -198.633406) (xy 183.95551 -198.673158)
			(xy 183.998266 -198.718633) (xy 184.034981 -198.769112) (xy 184.065073 -198.823797) (xy 184.088068 -198.881826)
			(xy 184.103602 -198.942281) (xy 184.11143 -199.004207) (xy 184.1119 -199.035416) (xy 184.111411 -199.066579)
			(xy 184.103599 -199.128413) (xy 184.088099 -199.188781) (xy 184.065156 -199.246729) (xy 184.03513 -199.301346)
			(xy 183.998496 -199.351768) (xy 183.955831 -199.397202) (xy 183.907809 -199.43693) (xy 183.855185 -199.470325)
			(xy 183.798791 -199.496862) (xy 183.739516 -199.516122) (xy 183.678295 -199.527801) (xy 183.616092 -199.531714)
			(xy 183.553889 -199.527801) (xy 183.492668 -199.516122) (xy 183.433393 -199.496862) (xy 183.376999 -199.470325)
			(xy 183.324375 -199.43693) (xy 183.276353 -199.397202) (xy 183.233688 -199.351768) (xy 183.197054 -199.301346)
			(xy 183.167028 -199.246729) (xy 183.144085 -199.188781) (xy 183.128585 -199.128413) (xy 183.120773 -199.066579)
			(xy 183.120284 -199.035416) (xy 179.884832 -199.035416) (xy 179.884456 -199.060735) (xy 179.877525 -199.110897)
			(xy 179.863797 -199.159639) (xy 179.843528 -199.206044) (xy 179.8171 -199.249239) (xy 179.785011 -199.288412)
			(xy 179.766722 -199.305926) (xy 179.757832 -199.314308) (xy 179.74945 -199.335898) (xy 179.758848 -199.440038)
			(xy 179.77104 -199.45985) (xy 179.7812 -199.466454) (xy 179.80733 -199.483502) (xy 179.855447 -199.523222)
			(xy 179.898199 -199.568666) (xy 179.934911 -199.619116) (xy 179.965002 -199.673773) (xy 179.987997 -199.731775)
			(xy 180.003532 -199.792203) (xy 180.011361 -199.854103) (xy 180.011832 -199.8853) (xy 181.862491 -199.8853)
			(xy 181.866426 -199.831529) (xy 181.878149 -199.778905) (xy 181.897409 -199.728548) (xy 181.923795 -199.681531)
			(xy 181.956747 -199.638858) (xy 181.99556 -199.601437) (xy 182.039408 -199.570067) (xy 182.087356 -199.545415)
			(xy 182.138383 -199.528007) (xy 182.191401 -199.518214) (xy 182.24528 -199.516245) (xy 182.298871 -199.522142)
			(xy 182.351032 -199.535778) (xy 182.400652 -199.556865) (xy 182.446673 -199.584951) (xy 182.488115 -199.619439)
			(xy 182.524093 -199.659593) (xy 182.553841 -199.704557) (xy 182.576726 -199.753374) (xy 182.592258 -199.805003)
			(xy 182.600108 -199.858343) (xy 182.6006 -199.8853) (xy 186.56427 -199.8853) (xy 186.56472 -199.854102)
			(xy 186.572542 -199.7922) (xy 186.588074 -199.731769) (xy 186.611071 -199.673767) (xy 186.641169 -199.619111)
			(xy 186.677891 -199.568667) (xy 186.720655 -199.523232) (xy 186.768787 -199.483527) (xy 186.794902 -199.466454)
			(xy 186.805062 -199.45985) (xy 186.817254 -199.440038) (xy 186.826652 -199.335898) (xy 186.81827 -199.314308)
			(xy 186.80938 -199.305926) (xy 186.791104 -199.288401) (xy 186.759024 -199.249226) (xy 186.732605 -199.206031)
			(xy 186.712342 -199.159629) (xy 186.698618 -199.11089) (xy 186.691689 -199.060733) (xy 186.69127 -199.035416)
			(xy 186.691722 -199.010069) (xy 186.698651 -198.959851) (xy 186.712395 -198.911056) (xy 186.732695 -198.864604)
			(xy 186.759168 -198.821372) (xy 186.791313 -198.782173) (xy 186.809634 -198.764652) (xy 186.818524 -198.756524)
			(xy 186.826906 -198.73468) (xy 186.817254 -198.63054) (xy 186.805062 -198.610728) (xy 186.794902 -198.604378)
			(xy 186.768774 -198.587303) (xy 186.720652 -198.547547) (xy 186.677897 -198.50207) (xy 186.641184 -198.451589)
			(xy 186.611093 -198.396901) (xy 186.588099 -198.338871) (xy 186.572567 -198.278415) (xy 186.56474 -198.216488)
			(xy 186.56427 -198.185278) (xy 186.564703 -198.15408) (xy 186.572528 -198.092177) (xy 186.588062 -198.031745)
			(xy 186.611062 -197.973743) (xy 186.641162 -197.919087) (xy 186.677886 -197.868643) (xy 186.720653 -197.823209)
			(xy 186.768786 -197.783505) (xy 186.794902 -197.766432) (xy 186.805062 -197.759828) (xy 186.817254 -197.740016)
			(xy 186.826652 -197.635876) (xy 186.81827 -197.614286) (xy 186.80938 -197.605904) (xy 186.791094 -197.58839)
			(xy 186.759015 -197.549212) (xy 186.732597 -197.506015) (xy 186.712336 -197.459611) (xy 186.698614 -197.410871)
			(xy 186.691688 -197.360711) (xy 186.69127 -197.335394) (xy 186.691786 -197.307794) (xy 186.700013 -197.253211)
			(xy 186.716283 -197.200464) (xy 186.740233 -197.150732) (xy 186.771328 -197.105124) (xy 186.808873 -197.06466)
			(xy 186.85203 -197.030243) (xy 186.899834 -197.002644) (xy 186.951218 -196.982477) (xy 187.005033 -196.970194)
			(xy 187.060078 -196.966069) (xy 187.115123 -196.970194) (xy 187.168938 -196.982477) (xy 187.220322 -197.002644)
			(xy 187.268126 -197.030243) (xy 187.311283 -197.06466) (xy 187.348828 -197.105124) (xy 187.379923 -197.150732)
			(xy 187.403873 -197.200464) (xy 187.420143 -197.253211) (xy 187.42837 -197.307794) (xy 187.428886 -197.335394)
			(xy 187.428478 -197.360712) (xy 187.421552 -197.410872) (xy 187.407828 -197.459612) (xy 187.387565 -197.506017)
			(xy 187.361144 -197.549213) (xy 187.329062 -197.588388) (xy 187.310776 -197.605904) (xy 187.301886 -197.614286)
			(xy 187.293504 -197.635876) (xy 187.302902 -197.740016) (xy 187.315094 -197.759828) (xy 187.325254 -197.766432)
			(xy 187.351364 -197.783511) (xy 187.399482 -197.823225) (xy 187.442237 -197.868664) (xy 187.478952 -197.919108)
			(xy 187.509046 -197.973762) (xy 187.532044 -198.03176) (xy 187.547581 -198.092185) (xy 187.555414 -198.154082)
			(xy 187.555886 -198.185278) (xy 187.555453 -198.216489) (xy 187.547624 -198.278417) (xy 187.532087 -198.338874)
			(xy 187.509088 -198.396904) (xy 187.478989 -198.451589) (xy 187.442268 -198.502066) (xy 187.399503 -198.547537)
			(xy 187.351371 -198.587283) (xy 187.325254 -198.604378) (xy 187.315094 -198.610728) (xy 187.302902 -198.63054)
			(xy 187.29325 -198.73468) (xy 187.301632 -198.756524) (xy 187.310522 -198.764652) (xy 187.328871 -198.782145)
			(xy 187.36101 -198.821354) (xy 187.387479 -198.864593) (xy 187.407779 -198.911049) (xy 187.421528 -198.959847)
			(xy 187.428467 -199.010067) (xy 187.428886 -199.035416) (xy 190.664338 -199.035416) (xy 190.664755 -199.004205)
			(xy 190.672585 -198.942275) (xy 190.688124 -198.881818) (xy 190.711125 -198.823787) (xy 190.741226 -198.769102)
			(xy 190.77795 -198.718625) (xy 190.820717 -198.673155) (xy 190.868852 -198.63341) (xy 190.89497 -198.616316)
			(xy 190.90513 -198.609966) (xy 190.917322 -198.590154) (xy 190.926974 -198.486014) (xy 190.918592 -198.46417)
			(xy 190.909702 -198.456042) (xy 190.891355 -198.438547) (xy 190.859214 -198.399339) (xy 190.832744 -198.356101)
			(xy 190.812444 -198.309645) (xy 190.798695 -198.260847) (xy 190.791757 -198.210627) (xy 190.791338 -198.185278)
			(xy 190.791786 -198.159961) (xy 190.798704 -198.109803) (xy 190.812419 -198.061063) (xy 190.832674 -198.014658)
			(xy 190.859089 -197.971461) (xy 190.891165 -197.932285) (xy 190.909448 -197.914768) (xy 190.918338 -197.906386)
			(xy 190.92672 -197.884796) (xy 190.917322 -197.780656) (xy 190.90513 -197.760844) (xy 190.89497 -197.75424)
			(xy 190.86883 -197.737206) (xy 190.820715 -197.697483) (xy 190.777964 -197.652036) (xy 190.741254 -197.601584)
			(xy 190.711164 -197.546925) (xy 190.688171 -197.488922) (xy 190.672637 -197.428492) (xy 190.664809 -197.366591)
			(xy 190.664338 -197.335394) (xy 190.664816 -197.304185) (xy 190.672636 -197.242258) (xy 190.688166 -197.181801)
			(xy 190.711158 -197.123772) (xy 190.74125 -197.069086) (xy 190.777967 -197.018608) (xy 190.820727 -196.973136)
			(xy 190.868855 -196.933389) (xy 190.89497 -196.916294) (xy 190.90513 -196.909944) (xy 190.917322 -196.890132)
			(xy 190.926974 -196.785992) (xy 190.918592 -196.764148) (xy 190.909702 -196.75602) (xy 190.891392 -196.738487)
			(xy 190.859248 -196.699288) (xy 190.832774 -196.656057) (xy 190.812467 -196.609609) (xy 190.79871 -196.560818)
			(xy 190.791762 -196.510603) (xy 190.791338 -196.485256) (xy 190.791854 -196.457656) (xy 190.800081 -196.403073)
			(xy 190.816351 -196.350326) (xy 190.840301 -196.300594) (xy 190.871396 -196.254986) (xy 190.908941 -196.214522)
			(xy 190.952098 -196.180105) (xy 190.999902 -196.152506) (xy 191.051286 -196.132339) (xy 191.105101 -196.120056)
			(xy 191.160146 -196.115931) (xy 191.215191 -196.120056) (xy 191.269006 -196.132339) (xy 191.32039 -196.152506)
			(xy 191.368194 -196.180105) (xy 191.411351 -196.214522) (xy 191.448896 -196.254986) (xy 191.479991 -196.300594)
			(xy 191.503941 -196.350326) (xy 191.520211 -196.403073) (xy 191.528438 -196.457656) (xy 191.528954 -196.485256)
			(xy 191.528574 -196.510606) (xy 191.521634 -196.560828) (xy 191.507877 -196.609625) (xy 191.487564 -196.656077)
			(xy 191.461077 -196.699308) (xy 191.428917 -196.738502) (xy 191.41059 -196.75602) (xy 191.4017 -196.764148)
			(xy 191.393318 -196.785992) (xy 191.40297 -196.890132) (xy 191.415162 -196.909944) (xy 191.425322 -196.916294)
			(xy 191.451443 -196.93338) (xy 191.499564 -196.973134) (xy 191.542319 -197.018611) (xy 191.579032 -197.06909)
			(xy 191.609123 -197.123776) (xy 191.632118 -197.181805) (xy 191.647653 -197.242259) (xy 191.655483 -197.304185)
			(xy 191.655954 -197.335394) (xy 191.655488 -197.366591) (xy 191.647667 -197.428493) (xy 191.632137 -197.488922)
			(xy 191.609142 -197.546924) (xy 191.579046 -197.60158) (xy 191.542327 -197.652024) (xy 191.499565 -197.697459)
			(xy 191.451436 -197.737166) (xy 191.425322 -197.75424) (xy 191.415162 -197.760844) (xy 191.40297 -197.780656)
			(xy 191.393572 -197.884796) (xy 191.401954 -197.906386) (xy 191.410844 -197.914768) (xy 191.429121 -197.932291)
			(xy 191.4612 -197.971467) (xy 191.487619 -198.014662) (xy 191.507881 -198.061065) (xy 191.521605 -198.109804)
			(xy 191.528534 -198.159961) (xy 191.528954 -198.185278) (xy 191.528522 -198.210626) (xy 191.521592 -198.260846)
			(xy 191.507846 -198.309642) (xy 191.487542 -198.356094) (xy 191.461065 -198.399326) (xy 191.428914 -198.438522)
			(xy 191.41059 -198.456042) (xy 191.4017 -198.46417) (xy 191.393318 -198.486014) (xy 191.40297 -198.590154)
			(xy 191.415162 -198.609966) (xy 191.425322 -198.616316) (xy 191.451453 -198.633387) (xy 191.499574 -198.673144)
			(xy 191.542328 -198.718622) (xy 191.579041 -198.769104) (xy 191.609131 -198.823792) (xy 191.632124 -198.881823)
			(xy 191.647657 -198.942279) (xy 191.655484 -199.004206) (xy 191.655954 -199.035416) (xy 191.655465 -199.066579)
			(xy 191.647653 -199.128413) (xy 191.632153 -199.188781) (xy 191.60921 -199.246729) (xy 191.579184 -199.301346)
			(xy 191.54255 -199.351768) (xy 191.499885 -199.397202) (xy 191.451863 -199.43693) (xy 191.399239 -199.470325)
			(xy 191.342845 -199.496862) (xy 191.28357 -199.516122) (xy 191.222349 -199.527801) (xy 191.160146 -199.531714)
			(xy 191.097943 -199.527801) (xy 191.036722 -199.516122) (xy 190.977447 -199.496862) (xy 190.921053 -199.470325)
			(xy 190.868429 -199.43693) (xy 190.820407 -199.397202) (xy 190.777742 -199.351768) (xy 190.741108 -199.301346)
			(xy 190.711082 -199.246729) (xy 190.688139 -199.188781) (xy 190.672639 -199.128413) (xy 190.664827 -199.066579)
			(xy 190.664338 -199.035416) (xy 187.428886 -199.035416) (xy 187.428493 -199.060734) (xy 187.421563 -199.110895)
			(xy 187.407837 -199.159635) (xy 187.387571 -199.20604) (xy 187.361147 -199.249236) (xy 187.329063 -199.288411)
			(xy 187.310776 -199.305926) (xy 187.301886 -199.314308) (xy 187.293504 -199.335898) (xy 187.302902 -199.440038)
			(xy 187.315094 -199.45985) (xy 187.325254 -199.466454) (xy 187.351374 -199.483518) (xy 187.399492 -199.523234)
			(xy 187.442247 -199.568675) (xy 187.47896 -199.619122) (xy 187.509053 -199.673778) (xy 187.532049 -199.731778)
			(xy 187.547585 -199.792205) (xy 187.555415 -199.854104) (xy 187.555886 -199.8853) (xy 189.406545 -199.8853)
			(xy 189.41048 -199.831529) (xy 189.422203 -199.778905) (xy 189.441463 -199.728548) (xy 189.467849 -199.681531)
			(xy 189.500801 -199.638858) (xy 189.539614 -199.601437) (xy 189.583462 -199.570067) (xy 189.63141 -199.545415)
			(xy 189.682437 -199.528007) (xy 189.735455 -199.518214) (xy 189.789334 -199.516245) (xy 189.842925 -199.522142)
			(xy 189.895086 -199.535778) (xy 189.944706 -199.556865) (xy 189.990727 -199.584951) (xy 190.032169 -199.619439)
			(xy 190.068147 -199.659593) (xy 190.097895 -199.704557) (xy 190.12078 -199.753374) (xy 190.136312 -199.805003)
			(xy 190.144162 -199.858343) (xy 190.144654 -199.8853) (xy 194.108324 -199.8853) (xy 194.108749 -199.854101)
			(xy 194.116572 -199.792197) (xy 194.132106 -199.731764) (xy 194.155106 -199.673761) (xy 194.185207 -199.619105)
			(xy 194.221933 -199.568661) (xy 194.264702 -199.523228) (xy 194.312838 -199.483525) (xy 194.338956 -199.466454)
			(xy 194.349116 -199.45985) (xy 194.361308 -199.440038) (xy 194.370706 -199.335898) (xy 194.362324 -199.314308)
			(xy 194.353434 -199.305926) (xy 194.33515 -199.28841) (xy 194.303072 -199.249232) (xy 194.276655 -199.206035)
			(xy 194.256394 -199.159631) (xy 194.242671 -199.110892) (xy 194.235743 -199.060733) (xy 194.235324 -199.035416)
			(xy 194.235759 -199.010068) (xy 194.242689 -198.959849) (xy 194.256435 -198.911053) (xy 194.276738 -198.864601)
			(xy 194.303215 -198.821369) (xy 194.335365 -198.782172) (xy 194.353688 -198.764652) (xy 194.362578 -198.756524)
			(xy 194.37096 -198.73468) (xy 194.361308 -198.63054) (xy 194.349116 -198.610728) (xy 194.338956 -198.604378)
			(xy 194.312817 -198.587319) (xy 194.264697 -198.54756) (xy 194.221944 -198.502079) (xy 194.185233 -198.451595)
			(xy 194.155144 -198.396905) (xy 194.132151 -198.338874) (xy 194.11662 -198.278416) (xy 194.108793 -198.216488)
			(xy 194.108324 -198.185278) (xy 194.108732 -198.154079) (xy 194.116558 -198.092174) (xy 194.132094 -198.031741)
			(xy 194.155096 -197.973737) (xy 194.1852 -197.919081) (xy 194.221928 -197.868638) (xy 194.2647 -197.823205)
			(xy 194.312837 -197.783503) (xy 194.338956 -197.766432) (xy 194.349116 -197.759828) (xy 194.361308 -197.740016)
			(xy 194.370706 -197.635876) (xy 194.362324 -197.614286) (xy 194.353434 -197.605904) (xy 194.335139 -197.588398)
			(xy 194.303063 -197.549218) (xy 194.276647 -197.506019) (xy 194.256388 -197.459613) (xy 194.242667 -197.410872)
			(xy 194.235742 -197.360712) (xy 194.235324 -197.335394) (xy 194.23584 -197.307794) (xy 194.244067 -197.253211)
			(xy 194.260337 -197.200464) (xy 194.284287 -197.150732) (xy 194.315382 -197.105124) (xy 194.352927 -197.06466)
			(xy 194.396084 -197.030243) (xy 194.443888 -197.002644) (xy 194.495272 -196.982477) (xy 194.549087 -196.970194)
			(xy 194.604132 -196.966069) (xy 194.659177 -196.970194) (xy 194.712992 -196.982477) (xy 194.764376 -197.002644)
			(xy 194.81218 -197.030243) (xy 194.855337 -197.06466) (xy 194.892882 -197.105124) (xy 194.923977 -197.150732)
			(xy 194.947927 -197.200464) (xy 194.964197 -197.253211) (xy 194.972424 -197.307794) (xy 194.97294 -197.335394)
			(xy 194.972547 -197.360713) (xy 194.965619 -197.410873) (xy 194.951893 -197.459615) (xy 194.931628 -197.50602)
			(xy 194.905203 -197.549215) (xy 194.873117 -197.588389) (xy 194.85483 -197.605904) (xy 194.84594 -197.614286)
			(xy 194.837558 -197.635876) (xy 194.846956 -197.740016) (xy 194.859148 -197.759828) (xy 194.869308 -197.766432)
			(xy 194.89543 -197.783492) (xy 194.943546 -197.823211) (xy 194.986299 -197.868653) (xy 195.023011 -197.919101)
			(xy 195.053103 -197.973757) (xy 195.076099 -198.031756) (xy 195.091636 -198.092183) (xy 195.099468 -198.154082)
			(xy 195.09994 -198.185278) (xy 195.099482 -198.216488) (xy 195.091654 -198.278414) (xy 195.076119 -198.338869)
			(xy 195.053122 -198.396898) (xy 195.023028 -198.451583) (xy 194.98631 -198.502061) (xy 194.94355 -198.547533)
			(xy 194.895423 -198.587281) (xy 194.869308 -198.604378) (xy 194.859148 -198.610728) (xy 194.846956 -198.63054)
			(xy 194.837304 -198.73468) (xy 194.845686 -198.756524) (xy 194.854576 -198.764652) (xy 194.872916 -198.782154)
			(xy 194.905058 -198.82136) (xy 194.93153 -198.864597) (xy 194.951831 -198.911051) (xy 194.965582 -198.959848)
			(xy 194.972521 -199.010068) (xy 194.97294 -199.035416) (xy 198.208392 -199.035416) (xy 198.20883 -199.004206)
			(xy 198.21666 -198.942278) (xy 198.232196 -198.881821) (xy 198.255196 -198.823792) (xy 198.285293 -198.769107)
			(xy 198.322014 -198.71863) (xy 198.364777 -198.673158) (xy 198.412908 -198.633411) (xy 198.439024 -198.616316)
			(xy 198.449184 -198.609966) (xy 198.461376 -198.590154) (xy 198.471028 -198.486014) (xy 198.462646 -198.46417)
			(xy 198.453756 -198.456042) (xy 198.435419 -198.438536) (xy 198.403275 -198.399332) (xy 198.376803 -198.356096)
			(xy 198.3565 -198.309642) (xy 198.34275 -198.260846) (xy 198.335811 -198.210626) (xy 198.335392 -198.185278)
			(xy 198.335855 -198.159962) (xy 198.342771 -198.109805) (xy 198.356485 -198.061066) (xy 198.376738 -198.014661)
			(xy 198.403149 -197.971464) (xy 198.435221 -197.932286) (xy 198.453502 -197.914768) (xy 198.462392 -197.906386)
			(xy 198.470774 -197.884796) (xy 198.461376 -197.780656) (xy 198.449184 -197.760844) (xy 198.439024 -197.75424)
			(xy 198.412897 -197.737188) (xy 198.364779 -197.697469) (xy 198.322026 -197.652026) (xy 198.285313 -197.601577)
			(xy 198.255221 -197.54692) (xy 198.232226 -197.488919) (xy 198.216692 -197.428491) (xy 198.208863 -197.366591)
			(xy 198.208392 -197.335394) (xy 198.208891 -197.304185) (xy 198.216711 -197.24226) (xy 198.232238 -197.181805)
			(xy 198.255229 -197.123777) (xy 198.285318 -197.069091) (xy 198.322031 -197.018613) (xy 198.364787 -196.97314)
			(xy 198.412911 -196.933391) (xy 198.439024 -196.916294) (xy 198.449184 -196.909944) (xy 198.461376 -196.890132)
			(xy 198.471028 -196.785992) (xy 198.462646 -196.764148) (xy 198.453756 -196.75602) (xy 198.435457 -196.738477)
			(xy 198.40331 -196.699281) (xy 198.376832 -196.656053) (xy 198.356523 -196.609606) (xy 198.342765 -196.560816)
			(xy 198.335816 -196.510602) (xy 198.335392 -196.485256) (xy 198.335908 -196.457656) (xy 198.344135 -196.403073)
			(xy 198.360405 -196.350326) (xy 198.384355 -196.300594) (xy 198.41545 -196.254986) (xy 198.452995 -196.214522)
			(xy 198.496152 -196.180105) (xy 198.543956 -196.152506) (xy 198.59534 -196.132339) (xy 198.649155 -196.120056)
			(xy 198.7042 -196.115931) (xy 198.759245 -196.120056) (xy 198.81306 -196.132339) (xy 198.864444 -196.152506)
			(xy 198.912248 -196.180105) (xy 198.955405 -196.214522) (xy 198.99295 -196.254986) (xy 199.024045 -196.300594)
			(xy 199.047995 -196.350326) (xy 199.064265 -196.403073) (xy 199.072492 -196.457656) (xy 199.073008 -196.485256)
			(xy 199.072611 -196.510605) (xy 199.065672 -196.560826) (xy 199.051917 -196.609622) (xy 199.031607 -196.656074)
			(xy 199.005125 -196.699305) (xy 198.972969 -196.7385) (xy 198.954644 -196.75602) (xy 198.945754 -196.764148)
			(xy 198.937372 -196.785992) (xy 198.947024 -196.890132) (xy 198.959216 -196.909944) (xy 198.969376 -196.916294)
			(xy 198.995486 -196.933396) (xy 199.043609 -196.973146) (xy 199.086366 -197.01862) (xy 199.123081 -197.069097)
			(xy 199.153174 -197.123781) (xy 199.17617 -197.181808) (xy 199.191706 -197.242261) (xy 199.199537 -197.304185)
			(xy 199.200008 -197.335394) (xy 199.199563 -197.366592) (xy 199.191742 -197.428495) (xy 199.176209 -197.488926)
			(xy 199.153212 -197.546929) (xy 199.123114 -197.601585) (xy 199.086391 -197.652029) (xy 199.043625 -197.697463)
			(xy 198.995492 -197.737168) (xy 198.969376 -197.75424) (xy 198.959216 -197.760844) (xy 198.947024 -197.780656)
			(xy 198.937626 -197.884796) (xy 198.946008 -197.906386) (xy 198.954898 -197.914768) (xy 198.973167 -197.9323)
			(xy 199.005248 -197.971473) (xy 199.031669 -198.014666) (xy 199.051933 -198.061068) (xy 199.065659 -198.109805)
			(xy 199.072588 -198.159961) (xy 199.073008 -198.185278) (xy 199.072559 -198.210625) (xy 199.06563 -198.260843)
			(xy 199.051886 -198.309639) (xy 199.031586 -198.356091) (xy 199.005112 -198.399323) (xy 198.972965 -198.438521)
			(xy 198.954644 -198.456042) (xy 198.945754 -198.46417) (xy 198.937372 -198.486014) (xy 198.947024 -198.590154)
			(xy 198.959216 -198.609966) (xy 198.969376 -198.616316) (xy 198.995496 -198.633403) (xy 199.043619 -198.673156)
			(xy 199.086375 -198.718631) (xy 199.12309 -198.769111) (xy 199.153182 -198.823797) (xy 199.176176 -198.881826)
			(xy 199.19171 -198.942281) (xy 199.199538 -199.004207) (xy 199.200008 -199.035416) (xy 199.199519 -199.066579)
			(xy 199.191707 -199.128413) (xy 199.176207 -199.188781) (xy 199.153264 -199.246729) (xy 199.123238 -199.301346)
			(xy 199.086604 -199.351768) (xy 199.043939 -199.397202) (xy 198.995917 -199.43693) (xy 198.943293 -199.470325)
			(xy 198.886899 -199.496862) (xy 198.827624 -199.516122) (xy 198.766403 -199.527801) (xy 198.7042 -199.531714)
			(xy 198.641997 -199.527801) (xy 198.580776 -199.516122) (xy 198.521501 -199.496862) (xy 198.465107 -199.470325)
			(xy 198.412483 -199.43693) (xy 198.364461 -199.397202) (xy 198.321796 -199.351768) (xy 198.285162 -199.301346)
			(xy 198.255136 -199.246729) (xy 198.232193 -199.188781) (xy 198.216693 -199.128413) (xy 198.208881 -199.066579)
			(xy 198.208392 -199.035416) (xy 194.97294 -199.035416) (xy 194.972562 -199.060735) (xy 194.965631 -199.110897)
			(xy 194.951903 -199.159638) (xy 194.931634 -199.206043) (xy 194.905207 -199.249238) (xy 194.873119 -199.288412)
			(xy 194.85483 -199.305926) (xy 194.84594 -199.314308) (xy 194.837558 -199.335898) (xy 194.846956 -199.440038)
			(xy 194.859148 -199.45985) (xy 194.869308 -199.466454) (xy 194.89544 -199.483499) (xy 194.943556 -199.52322)
			(xy 194.986308 -199.568665) (xy 195.02302 -199.619115) (xy 195.053111 -199.673773) (xy 195.076105 -199.731774)
			(xy 195.09164 -199.792203) (xy 195.099469 -199.854103) (xy 195.09994 -199.8853) (xy 196.950599 -199.8853)
			(xy 196.954534 -199.831529) (xy 196.966257 -199.778905) (xy 196.985517 -199.728548) (xy 197.011903 -199.681531)
			(xy 197.044855 -199.638858) (xy 197.083668 -199.601437) (xy 197.127516 -199.570067) (xy 197.175464 -199.545415)
			(xy 197.226491 -199.528007) (xy 197.279509 -199.518214) (xy 197.333388 -199.516245) (xy 197.386979 -199.522142)
			(xy 197.43914 -199.535778) (xy 197.48876 -199.556865) (xy 197.534781 -199.584951) (xy 197.576223 -199.619439)
			(xy 197.612201 -199.659593) (xy 197.641949 -199.704557) (xy 197.664834 -199.753374) (xy 197.680366 -199.805003)
			(xy 197.688216 -199.858343) (xy 197.688708 -199.8853) (xy 201.652124 -199.8853) (xy 201.652549 -199.854101)
			(xy 201.660372 -199.792197) (xy 201.675906 -199.731764) (xy 201.698906 -199.673761) (xy 201.729007 -199.619105)
			(xy 201.765733 -199.568661) (xy 201.808502 -199.523228) (xy 201.856638 -199.483525) (xy 201.882756 -199.466454)
			(xy 201.892916 -199.45985) (xy 201.905108 -199.440038) (xy 201.914506 -199.335898) (xy 201.906124 -199.314308)
			(xy 201.897234 -199.305926) (xy 201.87895 -199.28841) (xy 201.846872 -199.249232) (xy 201.820455 -199.206035)
			(xy 201.800194 -199.159631) (xy 201.786471 -199.110892) (xy 201.779543 -199.060733) (xy 201.779124 -199.035416)
			(xy 201.779559 -199.010068) (xy 201.786489 -198.959849) (xy 201.800235 -198.911053) (xy 201.820538 -198.864601)
			(xy 201.847015 -198.821369) (xy 201.879165 -198.782172) (xy 201.897488 -198.764652) (xy 201.906378 -198.756524)
			(xy 201.91476 -198.73468) (xy 201.905108 -198.63054) (xy 201.892916 -198.610728) (xy 201.882756 -198.604378)
			(xy 201.856617 -198.587319) (xy 201.808497 -198.54756) (xy 201.765744 -198.502079) (xy 201.729033 -198.451595)
			(xy 201.698944 -198.396905) (xy 201.675951 -198.338874) (xy 201.66042 -198.278416) (xy 201.652593 -198.216488)
			(xy 201.652124 -198.185278) (xy 201.652532 -198.154079) (xy 201.660358 -198.092174) (xy 201.675894 -198.031741)
			(xy 201.698896 -197.973737) (xy 201.729 -197.919081) (xy 201.765728 -197.868638) (xy 201.8085 -197.823205)
			(xy 201.856637 -197.783503) (xy 201.882756 -197.766432) (xy 201.892916 -197.759828) (xy 201.905108 -197.740016)
			(xy 201.914506 -197.635876) (xy 201.906124 -197.614286) (xy 201.897234 -197.605904) (xy 201.878939 -197.588398)
			(xy 201.846863 -197.549218) (xy 201.820447 -197.506019) (xy 201.800188 -197.459613) (xy 201.786467 -197.410872)
			(xy 201.779542 -197.360712) (xy 201.779124 -197.335394) (xy 201.77964 -197.307794) (xy 201.787867 -197.253211)
			(xy 201.804137 -197.200464) (xy 201.828087 -197.150732) (xy 201.859182 -197.105124) (xy 201.896727 -197.06466)
			(xy 201.939884 -197.030243) (xy 201.987688 -197.002644) (xy 202.039072 -196.982477) (xy 202.092887 -196.970194)
			(xy 202.147932 -196.966069) (xy 202.202977 -196.970194) (xy 202.256792 -196.982477) (xy 202.308176 -197.002644)
			(xy 202.35598 -197.030243) (xy 202.399137 -197.06466) (xy 202.436682 -197.105124) (xy 202.467777 -197.150732)
			(xy 202.491727 -197.200464) (xy 202.507997 -197.253211) (xy 202.516224 -197.307794) (xy 202.51674 -197.335394)
			(xy 202.516347 -197.360713) (xy 202.509419 -197.410873) (xy 202.495693 -197.459615) (xy 202.475428 -197.50602)
			(xy 202.449003 -197.549215) (xy 202.416917 -197.588389) (xy 202.39863 -197.605904) (xy 202.38974 -197.614286)
			(xy 202.381358 -197.635876) (xy 202.390756 -197.740016) (xy 202.402948 -197.759828) (xy 202.413108 -197.766432)
			(xy 202.43923 -197.783492) (xy 202.487346 -197.823211) (xy 202.530099 -197.868653) (xy 202.566811 -197.919101)
			(xy 202.596903 -197.973757) (xy 202.619899 -198.031756) (xy 202.635436 -198.092183) (xy 202.643268 -198.154082)
			(xy 202.64374 -198.185278) (xy 202.643282 -198.216488) (xy 202.635454 -198.278414) (xy 202.619919 -198.338869)
			(xy 202.596922 -198.396898) (xy 202.566828 -198.451583) (xy 202.53011 -198.502061) (xy 202.48735 -198.547533)
			(xy 202.439223 -198.587281) (xy 202.413108 -198.604378) (xy 202.402948 -198.610728) (xy 202.390756 -198.63054)
			(xy 202.381104 -198.73468) (xy 202.389486 -198.756524) (xy 202.398376 -198.764652) (xy 202.416716 -198.782154)
			(xy 202.448858 -198.82136) (xy 202.47533 -198.864597) (xy 202.495631 -198.911051) (xy 202.509382 -198.959848)
			(xy 202.516321 -199.010068) (xy 202.51674 -199.035416) (xy 205.752192 -199.035416) (xy 205.75263 -199.004206)
			(xy 205.76046 -198.942278) (xy 205.775996 -198.881821) (xy 205.798996 -198.823792) (xy 205.829093 -198.769107)
			(xy 205.865814 -198.71863) (xy 205.908577 -198.673158) (xy 205.956708 -198.633411) (xy 205.982824 -198.616316)
			(xy 205.992984 -198.609966) (xy 206.005176 -198.590154) (xy 206.014828 -198.486014) (xy 206.006446 -198.46417)
			(xy 205.997556 -198.456042) (xy 205.979219 -198.438536) (xy 205.947075 -198.399332) (xy 205.920603 -198.356096)
			(xy 205.9003 -198.309642) (xy 205.88655 -198.260846) (xy 205.879611 -198.210626) (xy 205.879192 -198.185278)
			(xy 205.879655 -198.159962) (xy 205.886571 -198.109805) (xy 205.900285 -198.061066) (xy 205.920538 -198.014661)
			(xy 205.946949 -197.971464) (xy 205.979021 -197.932286) (xy 205.997302 -197.914768) (xy 206.006192 -197.906386)
			(xy 206.014574 -197.884796) (xy 206.005176 -197.780656) (xy 205.992984 -197.760844) (xy 205.982824 -197.75424)
			(xy 205.956697 -197.737188) (xy 205.908579 -197.697469) (xy 205.865826 -197.652026) (xy 205.829113 -197.601577)
			(xy 205.799021 -197.54692) (xy 205.776026 -197.488919) (xy 205.760492 -197.428491) (xy 205.752663 -197.366591)
			(xy 205.752192 -197.335394) (xy 205.752691 -197.304185) (xy 205.760511 -197.24226) (xy 205.776038 -197.181805)
			(xy 205.799029 -197.123777) (xy 205.829118 -197.069091) (xy 205.865831 -197.018613) (xy 205.908587 -196.97314)
			(xy 205.956711 -196.933391) (xy 205.982824 -196.916294) (xy 205.992984 -196.909944) (xy 206.005176 -196.890132)
			(xy 206.014828 -196.785992) (xy 206.006446 -196.764148) (xy 205.997556 -196.75602) (xy 205.979257 -196.738477)
			(xy 205.94711 -196.699281) (xy 205.920632 -196.656053) (xy 205.900323 -196.609606) (xy 205.886565 -196.560816)
			(xy 205.879616 -196.510602) (xy 205.879192 -196.485256) (xy 205.879708 -196.457656) (xy 205.887935 -196.403073)
			(xy 205.904205 -196.350326) (xy 205.928155 -196.300594) (xy 205.95925 -196.254986) (xy 205.996795 -196.214522)
			(xy 206.039952 -196.180105) (xy 206.087756 -196.152506) (xy 206.13914 -196.132339) (xy 206.192955 -196.120056)
			(xy 206.248 -196.115931) (xy 206.303045 -196.120056) (xy 206.35686 -196.132339) (xy 206.408244 -196.152506)
			(xy 206.456048 -196.180105) (xy 206.499205 -196.214522) (xy 206.53675 -196.254986) (xy 206.567845 -196.300594)
			(xy 206.591795 -196.350326) (xy 206.608065 -196.403073) (xy 206.616292 -196.457656) (xy 206.616808 -196.485256)
			(xy 206.616411 -196.510605) (xy 206.609472 -196.560826) (xy 206.595717 -196.609622) (xy 206.575407 -196.656074)
			(xy 206.548925 -196.699305) (xy 206.516769 -196.7385) (xy 206.498444 -196.75602) (xy 206.489554 -196.764148)
			(xy 206.481172 -196.785992) (xy 206.490824 -196.890132) (xy 206.503016 -196.909944) (xy 206.513176 -196.916294)
			(xy 206.539286 -196.933396) (xy 206.587409 -196.973146) (xy 206.630166 -197.01862) (xy 206.666881 -197.069097)
			(xy 206.696974 -197.123781) (xy 206.71997 -197.181808) (xy 206.735506 -197.242261) (xy 206.743337 -197.304185)
			(xy 206.743808 -197.335394) (xy 206.743363 -197.366592) (xy 206.735542 -197.428495) (xy 206.720009 -197.488926)
			(xy 206.697012 -197.546929) (xy 206.666914 -197.601585) (xy 206.630191 -197.652029) (xy 206.587425 -197.697463)
			(xy 206.539292 -197.737168) (xy 206.513176 -197.75424) (xy 206.503016 -197.760844) (xy 206.490824 -197.780656)
			(xy 206.481426 -197.884796) (xy 206.489808 -197.906386) (xy 206.498698 -197.914768) (xy 206.516967 -197.9323)
			(xy 206.549048 -197.971473) (xy 206.575469 -198.014666) (xy 206.595733 -198.061068) (xy 206.609459 -198.109805)
			(xy 206.616388 -198.159961) (xy 206.616808 -198.185278) (xy 206.616359 -198.210625) (xy 206.60943 -198.260843)
			(xy 206.595686 -198.309639) (xy 206.575386 -198.356091) (xy 206.548912 -198.399323) (xy 206.516765 -198.438521)
			(xy 206.498444 -198.456042) (xy 206.489554 -198.46417) (xy 206.481172 -198.486014) (xy 206.490824 -198.590154)
			(xy 206.503016 -198.609966) (xy 206.513176 -198.616316) (xy 206.539296 -198.633403) (xy 206.587419 -198.673156)
			(xy 206.630175 -198.718631) (xy 206.66689 -198.769111) (xy 206.696982 -198.823797) (xy 206.719976 -198.881826)
			(xy 206.73551 -198.942281) (xy 206.743338 -199.004207) (xy 206.743808 -199.035416) (xy 206.743319 -199.066579)
			(xy 206.735507 -199.128413) (xy 206.720007 -199.188781) (xy 206.697064 -199.246729) (xy 206.667038 -199.301346)
			(xy 206.630404 -199.351768) (xy 206.587739 -199.397202) (xy 206.539717 -199.43693) (xy 206.487093 -199.470325)
			(xy 206.430699 -199.496862) (xy 206.371424 -199.516122) (xy 206.310203 -199.527801) (xy 206.248 -199.531714)
			(xy 206.185797 -199.527801) (xy 206.124576 -199.516122) (xy 206.065301 -199.496862) (xy 206.008907 -199.470325)
			(xy 205.956283 -199.43693) (xy 205.908261 -199.397202) (xy 205.865596 -199.351768) (xy 205.828962 -199.301346)
			(xy 205.798936 -199.246729) (xy 205.775993 -199.188781) (xy 205.760493 -199.128413) (xy 205.752681 -199.066579)
			(xy 205.752192 -199.035416) (xy 202.51674 -199.035416) (xy 202.516362 -199.060735) (xy 202.509431 -199.110897)
			(xy 202.495703 -199.159638) (xy 202.475434 -199.206043) (xy 202.449007 -199.249238) (xy 202.416919 -199.288412)
			(xy 202.39863 -199.305926) (xy 202.38974 -199.314308) (xy 202.381358 -199.335898) (xy 202.390756 -199.440038)
			(xy 202.402948 -199.45985) (xy 202.413108 -199.466454) (xy 202.43924 -199.483499) (xy 202.487356 -199.52322)
			(xy 202.530108 -199.568665) (xy 202.56682 -199.619115) (xy 202.596911 -199.673773) (xy 202.619905 -199.731774)
			(xy 202.63544 -199.792203) (xy 202.643269 -199.854103) (xy 202.64374 -199.8853) (xy 204.494399 -199.8853)
			(xy 204.498334 -199.831529) (xy 204.510057 -199.778905) (xy 204.529317 -199.728548) (xy 204.555703 -199.681531)
			(xy 204.588655 -199.638858) (xy 204.627468 -199.601437) (xy 204.671316 -199.570067) (xy 204.719264 -199.545415)
			(xy 204.770291 -199.528007) (xy 204.823309 -199.518214) (xy 204.877188 -199.516245) (xy 204.930779 -199.522142)
			(xy 204.98294 -199.535778) (xy 205.03256 -199.556865) (xy 205.078581 -199.584951) (xy 205.120023 -199.619439)
			(xy 205.156001 -199.659593) (xy 205.185749 -199.704557) (xy 205.208634 -199.753374) (xy 205.224166 -199.805003)
			(xy 205.232016 -199.858343) (xy 205.232508 -199.8853) (xy 205.232016 -199.912257) (xy 205.224166 -199.965597)
			(xy 205.208634 -200.017226) (xy 205.185749 -200.066043) (xy 205.156001 -200.111007) (xy 205.120023 -200.151161)
			(xy 205.078581 -200.185649) (xy 205.03256 -200.213735) (xy 204.98294 -200.234822) (xy 204.930779 -200.248458)
			(xy 204.877188 -200.254355) (xy 204.823309 -200.252386) (xy 204.770291 -200.242593) (xy 204.719264 -200.225185)
			(xy 204.671316 -200.200533) (xy 204.627468 -200.169163) (xy 204.588655 -200.131742) (xy 204.555703 -200.089069)
			(xy 204.529317 -200.042052) (xy 204.510057 -199.991695) (xy 204.498334 -199.939071) (xy 204.494399 -199.8853)
			(xy 202.64374 -199.8853) (xy 202.643251 -199.916463) (xy 202.635439 -199.978297) (xy 202.619939 -200.038665)
			(xy 202.596996 -200.096613) (xy 202.56697 -200.15123) (xy 202.530336 -200.201652) (xy 202.487671 -200.247086)
			(xy 202.439649 -200.286814) (xy 202.387025 -200.320209) (xy 202.330631 -200.346746) (xy 202.271356 -200.366006)
			(xy 202.210135 -200.377685) (xy 202.147932 -200.381598) (xy 202.085729 -200.377685) (xy 202.024508 -200.366006)
			(xy 201.965233 -200.346746) (xy 201.908839 -200.320209) (xy 201.856215 -200.286814) (xy 201.808193 -200.247086)
			(xy 201.765528 -200.201652) (xy 201.728894 -200.15123) (xy 201.698868 -200.096613) (xy 201.675925 -200.038665)
			(xy 201.660425 -199.978297) (xy 201.652613 -199.916463) (xy 201.652124 -199.8853) (xy 197.688708 -199.8853)
			(xy 197.688216 -199.912257) (xy 197.680366 -199.965597) (xy 197.664834 -200.017226) (xy 197.641949 -200.066043)
			(xy 197.612201 -200.111007) (xy 197.576223 -200.151161) (xy 197.534781 -200.185649) (xy 197.48876 -200.213735)
			(xy 197.43914 -200.234822) (xy 197.386979 -200.248458) (xy 197.333388 -200.254355) (xy 197.279509 -200.252386)
			(xy 197.226491 -200.242593) (xy 197.175464 -200.225185) (xy 197.127516 -200.200533) (xy 197.083668 -200.169163)
			(xy 197.044855 -200.131742) (xy 197.011903 -200.089069) (xy 196.985517 -200.042052) (xy 196.966257 -199.991695)
			(xy 196.954534 -199.939071) (xy 196.950599 -199.8853) (xy 195.09994 -199.8853) (xy 195.099451 -199.916463)
			(xy 195.091639 -199.978297) (xy 195.076139 -200.038665) (xy 195.053196 -200.096613) (xy 195.02317 -200.15123)
			(xy 194.986536 -200.201652) (xy 194.943871 -200.247086) (xy 194.895849 -200.286814) (xy 194.843225 -200.320209)
			(xy 194.786831 -200.346746) (xy 194.727556 -200.366006) (xy 194.666335 -200.377685) (xy 194.604132 -200.381598)
			(xy 194.541929 -200.377685) (xy 194.480708 -200.366006) (xy 194.421433 -200.346746) (xy 194.365039 -200.320209)
			(xy 194.312415 -200.286814) (xy 194.264393 -200.247086) (xy 194.221728 -200.201652) (xy 194.185094 -200.15123)
			(xy 194.155068 -200.096613) (xy 194.132125 -200.038665) (xy 194.116625 -199.978297) (xy 194.108813 -199.916463)
			(xy 194.108324 -199.8853) (xy 190.144654 -199.8853) (xy 190.144162 -199.912257) (xy 190.136312 -199.965597)
			(xy 190.12078 -200.017226) (xy 190.097895 -200.066043) (xy 190.068147 -200.111007) (xy 190.032169 -200.151161)
			(xy 189.990727 -200.185649) (xy 189.944706 -200.213735) (xy 189.895086 -200.234822) (xy 189.842925 -200.248458)
			(xy 189.789334 -200.254355) (xy 189.735455 -200.252386) (xy 189.682437 -200.242593) (xy 189.63141 -200.225185)
			(xy 189.583462 -200.200533) (xy 189.539614 -200.169163) (xy 189.500801 -200.131742) (xy 189.467849 -200.089069)
			(xy 189.441463 -200.042052) (xy 189.422203 -199.991695) (xy 189.41048 -199.939071) (xy 189.406545 -199.8853)
			(xy 187.555886 -199.8853) (xy 187.555397 -199.916463) (xy 187.547585 -199.978297) (xy 187.532085 -200.038665)
			(xy 187.509142 -200.096613) (xy 187.479116 -200.15123) (xy 187.442482 -200.201652) (xy 187.399817 -200.247086)
			(xy 187.351795 -200.286814) (xy 187.299171 -200.320209) (xy 187.242777 -200.346746) (xy 187.183502 -200.366006)
			(xy 187.122281 -200.377685) (xy 187.060078 -200.381598) (xy 186.997875 -200.377685) (xy 186.936654 -200.366006)
			(xy 186.877379 -200.346746) (xy 186.820985 -200.320209) (xy 186.768361 -200.286814) (xy 186.720339 -200.247086)
			(xy 186.677674 -200.201652) (xy 186.64104 -200.15123) (xy 186.611014 -200.096613) (xy 186.588071 -200.038665)
			(xy 186.572571 -199.978297) (xy 186.564759 -199.916463) (xy 186.56427 -199.8853) (xy 182.6006 -199.8853)
			(xy 182.600108 -199.912257) (xy 182.592258 -199.965597) (xy 182.576726 -200.017226) (xy 182.553841 -200.066043)
			(xy 182.524093 -200.111007) (xy 182.488115 -200.151161) (xy 182.446673 -200.185649) (xy 182.400652 -200.213735)
			(xy 182.351032 -200.234822) (xy 182.298871 -200.248458) (xy 182.24528 -200.254355) (xy 182.191401 -200.252386)
			(xy 182.138383 -200.242593) (xy 182.087356 -200.225185) (xy 182.039408 -200.200533) (xy 181.99556 -200.169163)
			(xy 181.956747 -200.131742) (xy 181.923795 -200.089069) (xy 181.897409 -200.042052) (xy 181.878149 -199.991695)
			(xy 181.866426 -199.939071) (xy 181.862491 -199.8853) (xy 180.011832 -199.8853) (xy 180.011343 -199.916463)
			(xy 180.003531 -199.978297) (xy 179.988031 -200.038665) (xy 179.965088 -200.096613) (xy 179.935062 -200.15123)
			(xy 179.898428 -200.201652) (xy 179.855763 -200.247086) (xy 179.807741 -200.286814) (xy 179.755117 -200.320209)
			(xy 179.698723 -200.346746) (xy 179.639448 -200.366006) (xy 179.578227 -200.377685) (xy 179.516024 -200.381598)
			(xy 179.453821 -200.377685) (xy 179.3926 -200.366006) (xy 179.333325 -200.346746) (xy 179.276931 -200.320209)
			(xy 179.224307 -200.286814) (xy 179.176285 -200.247086) (xy 179.13362 -200.201652) (xy 179.096986 -200.15123)
			(xy 179.06696 -200.096613) (xy 179.044017 -200.038665) (xy 179.028517 -199.978297) (xy 179.020705 -199.916463)
			(xy 179.020216 -199.8853) (xy 175.056546 -199.8853) (xy 175.056054 -199.912257) (xy 175.048204 -199.965597)
			(xy 175.032672 -200.017226) (xy 175.009787 -200.066043) (xy 174.980039 -200.111007) (xy 174.944061 -200.151161)
			(xy 174.902619 -200.185649) (xy 174.856598 -200.213735) (xy 174.806978 -200.234822) (xy 174.754817 -200.248458)
			(xy 174.701226 -200.254355) (xy 174.647347 -200.252386) (xy 174.594329 -200.242593) (xy 174.543302 -200.225185)
			(xy 174.495354 -200.200533) (xy 174.451506 -200.169163) (xy 174.412693 -200.131742) (xy 174.379741 -200.089069)
			(xy 174.353355 -200.042052) (xy 174.334095 -199.991695) (xy 174.322372 -199.939071) (xy 174.318437 -199.8853)
			(xy 172.467778 -199.8853) (xy 172.467289 -199.916463) (xy 172.459477 -199.978297) (xy 172.443977 -200.038665)
			(xy 172.421034 -200.096613) (xy 172.391008 -200.15123) (xy 172.354374 -200.201652) (xy 172.311709 -200.247086)
			(xy 172.263687 -200.286814) (xy 172.211063 -200.320209) (xy 172.154669 -200.346746) (xy 172.095394 -200.366006)
			(xy 172.034173 -200.377685) (xy 171.97197 -200.381598) (xy 171.909767 -200.377685) (xy 171.848546 -200.366006)
			(xy 171.789271 -200.346746) (xy 171.732877 -200.320209) (xy 171.680253 -200.286814) (xy 171.632231 -200.247086)
			(xy 171.589566 -200.201652) (xy 171.552932 -200.15123) (xy 171.522906 -200.096613) (xy 171.499963 -200.038665)
			(xy 171.484463 -199.978297) (xy 171.476651 -199.916463) (xy 171.476162 -199.8853) (xy 167.512492 -199.8853)
			(xy 167.512 -199.912257) (xy 167.50415 -199.965597) (xy 167.488618 -200.017226) (xy 167.465733 -200.066043)
			(xy 167.435985 -200.111007) (xy 167.400007 -200.151161) (xy 167.358565 -200.185649) (xy 167.312544 -200.213735)
			(xy 167.262924 -200.234822) (xy 167.210763 -200.248458) (xy 167.157172 -200.254355) (xy 167.103293 -200.252386)
			(xy 167.050275 -200.242593) (xy 166.999248 -200.225185) (xy 166.9513 -200.200533) (xy 166.907452 -200.169163)
			(xy 166.868639 -200.131742) (xy 166.835687 -200.089069) (xy 166.809301 -200.042052) (xy 166.790041 -199.991695)
			(xy 166.778318 -199.939071) (xy 166.774383 -199.8853) (xy 161.716212 -199.8853) (xy 161.62782 -199.973692)
			(xy 161.620454 -199.980804) (xy 161.612834 -199.9996) (xy 161.612834 -200.735438) (xy 165.442915 -200.735438)
			(xy 165.44685 -200.681667) (xy 165.458573 -200.629043) (xy 165.477833 -200.578686) (xy 165.504219 -200.531669)
			(xy 165.537171 -200.488996) (xy 165.575984 -200.451575) (xy 165.619832 -200.420205) (xy 165.66778 -200.395553)
			(xy 165.718807 -200.378145) (xy 165.771825 -200.368352) (xy 165.825704 -200.366383) (xy 165.879295 -200.37228)
			(xy 165.931456 -200.385916) (xy 165.981076 -200.407003) (xy 166.027097 -200.435089) (xy 166.068539 -200.469577)
			(xy 166.104517 -200.509731) (xy 166.134265 -200.554695) (xy 166.15715 -200.603512) (xy 166.172682 -200.655141)
			(xy 166.180532 -200.708481) (xy 166.181024 -200.735438) (xy 172.986969 -200.735438) (xy 172.990904 -200.681667)
			(xy 173.002627 -200.629043) (xy 173.021887 -200.578686) (xy 173.048273 -200.531669) (xy 173.081225 -200.488996)
			(xy 173.120038 -200.451575) (xy 173.163886 -200.420205) (xy 173.211834 -200.395553) (xy 173.262861 -200.378145)
			(xy 173.315879 -200.368352) (xy 173.369758 -200.366383) (xy 173.423349 -200.37228) (xy 173.47551 -200.385916)
			(xy 173.52513 -200.407003) (xy 173.571151 -200.435089) (xy 173.612593 -200.469577) (xy 173.648571 -200.509731)
			(xy 173.678319 -200.554695) (xy 173.701204 -200.603512) (xy 173.716736 -200.655141) (xy 173.724586 -200.708481)
			(xy 173.725078 -200.735438) (xy 173.724586 -200.762395) (xy 173.716736 -200.815735) (xy 173.701204 -200.867364)
			(xy 173.678319 -200.916181) (xy 173.648571 -200.961145) (xy 173.612593 -201.001299) (xy 173.571151 -201.035787)
			(xy 173.52513 -201.063873) (xy 173.47551 -201.08496) (xy 173.423349 -201.098596) (xy 173.369758 -201.104493)
			(xy 173.315879 -201.102524) (xy 173.262861 -201.092731) (xy 173.211834 -201.075323) (xy 173.163886 -201.050671)
			(xy 173.120038 -201.019301) (xy 173.081225 -200.98188) (xy 173.048273 -200.939207) (xy 173.021887 -200.89219)
			(xy 173.002627 -200.841833) (xy 172.990904 -200.789209) (xy 172.986969 -200.735438) (xy 166.181024 -200.735438)
			(xy 166.180532 -200.762395) (xy 166.172682 -200.815735) (xy 166.15715 -200.867364) (xy 166.134265 -200.916181)
			(xy 166.104517 -200.961145) (xy 166.068539 -201.001299) (xy 166.027097 -201.035787) (xy 165.981076 -201.063873)
			(xy 165.931456 -201.08496) (xy 165.879295 -201.098596) (xy 165.825704 -201.104493) (xy 165.771825 -201.102524)
			(xy 165.718807 -201.092731) (xy 165.66778 -201.075323) (xy 165.619832 -201.050671) (xy 165.575984 -201.019301)
			(xy 165.537171 -200.98188) (xy 165.504219 -200.939207) (xy 165.477833 -200.89219) (xy 165.458573 -200.841833)
			(xy 165.44685 -200.789209) (xy 165.442915 -200.735438) (xy 161.612834 -200.735438) (xy 161.612834 -201.16038)
			(xy 169.276283 -201.16038) (xy 169.280218 -201.106609) (xy 169.291941 -201.053985) (xy 169.311201 -201.003628)
			(xy 169.337587 -200.956611) (xy 169.370539 -200.913938) (xy 169.409352 -200.876517) (xy 169.4532 -200.845147)
			(xy 169.501148 -200.820495) (xy 169.552175 -200.803087) (xy 169.605193 -200.793294) (xy 169.659072 -200.791325)
			(xy 169.712663 -200.797222) (xy 169.764824 -200.810858) (xy 169.814444 -200.831945) (xy 169.860465 -200.860031)
			(xy 169.901907 -200.894519) (xy 169.937885 -200.934673) (xy 169.967633 -200.979637) (xy 169.990518 -201.028454)
			(xy 170.00605 -201.080083) (xy 170.0139 -201.133423) (xy 170.014392 -201.16038) (xy 170.0139 -201.187337)
			(xy 170.00605 -201.240677) (xy 169.990518 -201.292306) (xy 169.967633 -201.341123) (xy 169.937885 -201.386087)
			(xy 169.901907 -201.426241) (xy 169.860465 -201.460729) (xy 169.814444 -201.488815) (xy 169.764824 -201.509902)
			(xy 169.712663 -201.523538) (xy 169.659072 -201.529435) (xy 169.605193 -201.527466) (xy 169.552175 -201.517673)
			(xy 169.501148 -201.500265) (xy 169.4532 -201.475613) (xy 169.409352 -201.444243) (xy 169.370539 -201.406822)
			(xy 169.337587 -201.364149) (xy 169.311201 -201.317132) (xy 169.291941 -201.266775) (xy 169.280218 -201.214151)
			(xy 169.276283 -201.16038) (xy 161.612834 -201.16038) (xy 161.612834 -202.010264) (xy 165.176215 -202.010264)
			(xy 165.18015 -201.956493) (xy 165.191873 -201.903869) (xy 165.211133 -201.853512) (xy 165.237519 -201.806495)
			(xy 165.270471 -201.763822) (xy 165.309284 -201.726401) (xy 165.353132 -201.695031) (xy 165.40108 -201.670379)
			(xy 165.452107 -201.652971) (xy 165.505125 -201.643178) (xy 165.559004 -201.641209) (xy 165.612595 -201.647106)
			(xy 165.664756 -201.660742) (xy 165.714376 -201.681829) (xy 165.760397 -201.709915) (xy 165.801839 -201.744403)
			(xy 165.837817 -201.784557) (xy 165.867565 -201.829521) (xy 165.89045 -201.878338) (xy 165.905982 -201.929967)
			(xy 165.913832 -201.983307) (xy 165.914324 -202.010264) (xy 165.913832 -202.037221) (xy 165.905982 -202.090561)
			(xy 165.89045 -202.14219) (xy 165.867565 -202.191007) (xy 165.837817 -202.235971) (xy 165.801839 -202.276125)
			(xy 165.760397 -202.310613) (xy 165.714376 -202.338699) (xy 165.664756 -202.359786) (xy 165.612595 -202.373422)
			(xy 165.559004 -202.379319) (xy 165.505125 -202.37735) (xy 165.452107 -202.367557) (xy 165.40108 -202.350149)
			(xy 165.353132 -202.325497) (xy 165.309284 -202.294127) (xy 165.270471 -202.256706) (xy 165.237519 -202.214033)
			(xy 165.211133 -202.167016) (xy 165.191873 -202.116659) (xy 165.18015 -202.064035) (xy 165.176215 -202.010264)
			(xy 161.612834 -202.010264) (xy 161.612834 -202.435206) (xy 166.774383 -202.435206) (xy 166.778318 -202.381435)
			(xy 166.790041 -202.328811) (xy 166.809301 -202.278454) (xy 166.835687 -202.231437) (xy 166.868639 -202.188764)
			(xy 166.907452 -202.151343) (xy 166.9513 -202.119973) (xy 166.999248 -202.095321) (xy 167.050275 -202.077913)
			(xy 167.103293 -202.06812) (xy 167.157172 -202.066151) (xy 167.210763 -202.072048) (xy 167.262924 -202.085684)
			(xy 167.312544 -202.106771) (xy 167.358565 -202.134857) (xy 167.400007 -202.169345) (xy 167.435985 -202.209499)
			(xy 167.465733 -202.254463) (xy 167.488618 -202.30328) (xy 167.50415 -202.354909) (xy 167.512 -202.408249)
			(xy 167.512492 -202.435206) (xy 171.476162 -202.435206) (xy 171.476665 -202.402505) (xy 171.485278 -202.337672)
			(xy 171.502344 -202.274535) (xy 171.527564 -202.214191) (xy 171.560502 -202.157688) (xy 171.600585 -202.106007)
			(xy 171.623482 -202.082654) (xy 171.630848 -202.075288) (xy 171.638468 -202.056746) (xy 171.638468 -201.963782)
			(xy 171.630848 -201.94524) (xy 171.623482 -201.937874) (xy 171.600607 -201.9145) (xy 171.560519 -201.862827)
			(xy 171.527579 -201.806329) (xy 171.502358 -201.745988) (xy 171.485296 -201.682853) (xy 171.476688 -201.618022)
			(xy 171.476162 -201.585322) (xy 171.476651 -201.554159) (xy 171.484463 -201.492325) (xy 171.499963 -201.431957)
			(xy 171.522906 -201.374009) (xy 171.552932 -201.319392) (xy 171.589566 -201.26897) (xy 171.632231 -201.223536)
			(xy 171.680253 -201.183808) (xy 171.732877 -201.150413) (xy 171.789271 -201.123876) (xy 171.848546 -201.104616)
			(xy 171.909767 -201.092937) (xy 171.97197 -201.089024) (xy 172.034173 -201.092937) (xy 172.095394 -201.104616)
			(xy 172.154669 -201.123876) (xy 172.211063 -201.150413) (xy 172.263687 -201.183808) (xy 172.311709 -201.223536)
			(xy 172.354374 -201.26897) (xy 172.391008 -201.319392) (xy 172.421034 -201.374009) (xy 172.443977 -201.431957)
			(xy 172.459477 -201.492325) (xy 172.467289 -201.554159) (xy 172.467778 -201.585322) (xy 175.57623 -201.585322)
			(xy 175.576752 -201.552622) (xy 175.585363 -201.48779) (xy 175.602426 -201.424654) (xy 175.627643 -201.36431)
			(xy 175.660576 -201.307806) (xy 175.700655 -201.256124) (xy 175.72355 -201.23277) (xy 175.730916 -201.225404)
			(xy 175.738536 -201.206862) (xy 175.738536 -201.113898) (xy 175.730916 -201.095356) (xy 175.72355 -201.08799)
			(xy 175.700629 -201.06466) (xy 175.660547 -201.012977) (xy 175.627613 -200.956469) (xy 175.602401 -200.896119)
			(xy 175.585348 -200.832977) (xy 175.576751 -200.76814) (xy 175.57623 -200.735438) (xy 175.576719 -200.704275)
			(xy 175.584531 -200.642441) (xy 175.600031 -200.582073) (xy 175.622974 -200.524125) (xy 175.653 -200.469508)
			(xy 175.689634 -200.419086) (xy 175.732299 -200.373652) (xy 175.780321 -200.333924) (xy 175.832945 -200.300529)
			(xy 175.889339 -200.273992) (xy 175.948614 -200.254732) (xy 176.009835 -200.243053) (xy 176.072038 -200.23914)
			(xy 176.134241 -200.243053) (xy 176.195462 -200.254732) (xy 176.254737 -200.273992) (xy 176.311131 -200.300529)
			(xy 176.363755 -200.333924) (xy 176.411777 -200.373652) (xy 176.454442 -200.419086) (xy 176.491076 -200.469508)
			(xy 176.521102 -200.524125) (xy 176.544045 -200.582073) (xy 176.559545 -200.642441) (xy 176.567357 -200.704275)
			(xy 176.567846 -200.735438) (xy 180.531023 -200.735438) (xy 180.534958 -200.681667) (xy 180.546681 -200.629043)
			(xy 180.565941 -200.578686) (xy 180.592327 -200.531669) (xy 180.625279 -200.488996) (xy 180.664092 -200.451575)
			(xy 180.70794 -200.420205) (xy 180.755888 -200.395553) (xy 180.806915 -200.378145) (xy 180.859933 -200.368352)
			(xy 180.913812 -200.366383) (xy 180.967403 -200.37228) (xy 181.019564 -200.385916) (xy 181.069184 -200.407003)
			(xy 181.115205 -200.435089) (xy 181.156647 -200.469577) (xy 181.192625 -200.509731) (xy 181.222373 -200.554695)
			(xy 181.245258 -200.603512) (xy 181.26079 -200.655141) (xy 181.26864 -200.708481) (xy 181.269132 -200.735438)
			(xy 181.26864 -200.762395) (xy 181.26079 -200.815735) (xy 181.245258 -200.867364) (xy 181.222373 -200.916181)
			(xy 181.192625 -200.961145) (xy 181.156647 -201.001299) (xy 181.115205 -201.035787) (xy 181.069184 -201.063873)
			(xy 181.019564 -201.08496) (xy 180.967403 -201.098596) (xy 180.913812 -201.104493) (xy 180.859933 -201.102524)
			(xy 180.806915 -201.092731) (xy 180.755888 -201.075323) (xy 180.70794 -201.050671) (xy 180.664092 -201.019301)
			(xy 180.625279 -200.98188) (xy 180.592327 -200.939207) (xy 180.565941 -200.89219) (xy 180.546681 -200.841833)
			(xy 180.534958 -200.789209) (xy 180.531023 -200.735438) (xy 176.567846 -200.735438) (xy 176.567305 -200.768138)
			(xy 176.558699 -200.832969) (xy 176.541641 -200.896105) (xy 176.516427 -200.95645) (xy 176.483496 -201.012954)
			(xy 176.44342 -201.064636) (xy 176.420526 -201.08799) (xy 176.41316 -201.095356) (xy 176.40554 -201.113898)
			(xy 176.40554 -201.16038) (xy 176.820337 -201.16038) (xy 176.824272 -201.106609) (xy 176.835995 -201.053985)
			(xy 176.855255 -201.003628) (xy 176.881641 -200.956611) (xy 176.914593 -200.913938) (xy 176.953406 -200.876517)
			(xy 176.997254 -200.845147) (xy 177.045202 -200.820495) (xy 177.096229 -200.803087) (xy 177.149247 -200.793294)
			(xy 177.203126 -200.791325) (xy 177.256717 -200.797222) (xy 177.308878 -200.810858) (xy 177.358498 -200.831945)
			(xy 177.404519 -200.860031) (xy 177.445961 -200.894519) (xy 177.481939 -200.934673) (xy 177.511687 -200.979637)
			(xy 177.534572 -201.028454) (xy 177.550104 -201.080083) (xy 177.557954 -201.133423) (xy 177.558446 -201.16038)
			(xy 177.557954 -201.187337) (xy 177.550104 -201.240677) (xy 177.534572 -201.292306) (xy 177.511687 -201.341123)
			(xy 177.481939 -201.386087) (xy 177.445961 -201.426241) (xy 177.404519 -201.460729) (xy 177.358498 -201.488815)
			(xy 177.308878 -201.509902) (xy 177.256717 -201.523538) (xy 177.203126 -201.529435) (xy 177.149247 -201.527466)
			(xy 177.096229 -201.517673) (xy 177.045202 -201.500265) (xy 176.997254 -201.475613) (xy 176.953406 -201.444243)
			(xy 176.914593 -201.406822) (xy 176.881641 -201.364149) (xy 176.855255 -201.317132) (xy 176.835995 -201.266775)
			(xy 176.824272 -201.214151) (xy 176.820337 -201.16038) (xy 176.40554 -201.16038) (xy 176.40554 -201.206862)
			(xy 176.41316 -201.225404) (xy 176.420526 -201.23277) (xy 176.443424 -201.256122) (xy 176.483509 -201.3078)
			(xy 176.516446 -201.364303) (xy 176.541663 -201.424649) (xy 176.558721 -201.487787) (xy 176.567323 -201.552621)
			(xy 176.567846 -201.585322) (xy 176.567357 -201.616485) (xy 176.559545 -201.678319) (xy 176.544045 -201.738687)
			(xy 176.521102 -201.796635) (xy 176.491076 -201.851252) (xy 176.454442 -201.901674) (xy 176.411777 -201.947108)
			(xy 176.363755 -201.986836) (xy 176.311131 -202.020231) (xy 176.254737 -202.046768) (xy 176.195462 -202.066028)
			(xy 176.134241 -202.077707) (xy 176.072038 -202.08162) (xy 176.009835 -202.077707) (xy 175.948614 -202.066028)
			(xy 175.889339 -202.046768) (xy 175.832945 -202.020231) (xy 175.780321 -201.986836) (xy 175.732299 -201.947108)
			(xy 175.689634 -201.901674) (xy 175.653 -201.851252) (xy 175.622974 -201.796635) (xy 175.600031 -201.738687)
			(xy 175.584531 -201.678319) (xy 175.576719 -201.616485) (xy 175.57623 -201.585322) (xy 172.467778 -201.585322)
			(xy 172.467217 -201.618021) (xy 172.458614 -201.682851) (xy 172.441559 -201.745987) (xy 172.416349 -201.806331)
			(xy 172.383422 -201.862835) (xy 172.34335 -201.914519) (xy 172.320458 -201.937874) (xy 172.313092 -201.94524)
			(xy 172.305472 -201.963782) (xy 172.305472 -202.010264) (xy 172.720269 -202.010264) (xy 172.724204 -201.956493)
			(xy 172.735927 -201.903869) (xy 172.755187 -201.853512) (xy 172.781573 -201.806495) (xy 172.814525 -201.763822)
			(xy 172.853338 -201.726401) (xy 172.897186 -201.695031) (xy 172.945134 -201.670379) (xy 172.996161 -201.652971)
			(xy 173.049179 -201.643178) (xy 173.103058 -201.641209) (xy 173.156649 -201.647106) (xy 173.20881 -201.660742)
			(xy 173.25843 -201.681829) (xy 173.304451 -201.709915) (xy 173.345893 -201.744403) (xy 173.381871 -201.784557)
			(xy 173.411619 -201.829521) (xy 173.434504 -201.878338) (xy 173.450036 -201.929967) (xy 173.457886 -201.983307)
			(xy 173.458378 -202.010264) (xy 173.457886 -202.037221) (xy 173.450036 -202.090561) (xy 173.434504 -202.14219)
			(xy 173.411619 -202.191007) (xy 173.381871 -202.235971) (xy 173.345893 -202.276125) (xy 173.304451 -202.310613)
			(xy 173.25843 -202.338699) (xy 173.20881 -202.359786) (xy 173.156649 -202.373422) (xy 173.103058 -202.379319)
			(xy 173.049179 -202.37735) (xy 172.996161 -202.367557) (xy 172.945134 -202.350149) (xy 172.897186 -202.325497)
			(xy 172.853338 -202.294127) (xy 172.814525 -202.256706) (xy 172.781573 -202.214033) (xy 172.755187 -202.167016)
			(xy 172.735927 -202.116659) (xy 172.724204 -202.064035) (xy 172.720269 -202.010264) (xy 172.305472 -202.010264)
			(xy 172.305472 -202.056746) (xy 172.313092 -202.075288) (xy 172.320458 -202.082654) (xy 172.343354 -202.106008)
			(xy 172.383438 -202.157686) (xy 172.416375 -202.214189) (xy 172.441592 -202.274534) (xy 172.45865 -202.337672)
			(xy 172.467254 -202.402505) (xy 172.467778 -202.435206) (xy 174.318437 -202.435206) (xy 174.322372 -202.381435)
			(xy 174.334095 -202.328811) (xy 174.353355 -202.278454) (xy 174.379741 -202.231437) (xy 174.412693 -202.188764)
			(xy 174.451506 -202.151343) (xy 174.495354 -202.119973) (xy 174.543302 -202.095321) (xy 174.594329 -202.077913)
			(xy 174.647347 -202.06812) (xy 174.701226 -202.066151) (xy 174.754817 -202.072048) (xy 174.806978 -202.085684)
			(xy 174.856598 -202.106771) (xy 174.902619 -202.134857) (xy 174.944061 -202.169345) (xy 174.980039 -202.209499)
			(xy 175.009787 -202.254463) (xy 175.032672 -202.30328) (xy 175.048204 -202.354909) (xy 175.056054 -202.408249)
			(xy 175.056546 -202.435206) (xy 179.020216 -202.435206) (xy 179.020703 -202.402504) (xy 179.029317 -202.33767)
			(xy 179.046385 -202.274532) (xy 179.071608 -202.214188) (xy 179.10455 -202.157685) (xy 179.144637 -202.106006)
			(xy 179.167536 -202.082654) (xy 179.174902 -202.075288) (xy 179.182522 -202.056746) (xy 179.182522 -201.963782)
			(xy 179.174902 -201.94524) (xy 179.167536 -201.937874) (xy 179.144653 -201.914508) (xy 179.104567 -201.862832)
			(xy 179.071629 -201.806332) (xy 179.04641 -201.74599) (xy 179.029349 -201.682854) (xy 179.020742 -201.618022)
			(xy 179.020216 -201.585322) (xy 179.020705 -201.554159) (xy 179.028517 -201.492325) (xy 179.044017 -201.431957)
			(xy 179.06696 -201.374009) (xy 179.096986 -201.319392) (xy 179.13362 -201.26897) (xy 179.176285 -201.223536)
			(xy 179.224307 -201.183808) (xy 179.276931 -201.150413) (xy 179.333325 -201.123876) (xy 179.3926 -201.104616)
			(xy 179.453821 -201.092937) (xy 179.516024 -201.089024) (xy 179.578227 -201.092937) (xy 179.639448 -201.104616)
			(xy 179.698723 -201.123876) (xy 179.755117 -201.150413) (xy 179.807741 -201.183808) (xy 179.855763 -201.223536)
			(xy 179.898428 -201.26897) (xy 179.935062 -201.319392) (xy 179.965088 -201.374009) (xy 179.988031 -201.431957)
			(xy 180.003531 -201.492325) (xy 180.011343 -201.554159) (xy 180.011832 -201.585322) (xy 183.120284 -201.585322)
			(xy 183.12079 -201.552621) (xy 183.129402 -201.487788) (xy 183.146467 -201.424651) (xy 183.171687 -201.364306)
			(xy 183.204624 -201.307803) (xy 183.244707 -201.256123) (xy 183.267604 -201.23277) (xy 183.27497 -201.225404)
			(xy 183.28259 -201.206862) (xy 183.28259 -201.113898) (xy 183.27497 -201.095356) (xy 183.267604 -201.08799)
			(xy 183.244692 -201.064651) (xy 183.204608 -201.01297) (xy 183.171672 -200.956465) (xy 183.146457 -200.896117)
			(xy 183.129403 -200.832976) (xy 183.120805 -200.76814) (xy 183.120284 -200.735438) (xy 183.120773 -200.704275)
			(xy 183.128585 -200.642441) (xy 183.144085 -200.582073) (xy 183.167028 -200.524125) (xy 183.197054 -200.469508)
			(xy 183.233688 -200.419086) (xy 183.276353 -200.373652) (xy 183.324375 -200.333924) (xy 183.376999 -200.300529)
			(xy 183.433393 -200.273992) (xy 183.492668 -200.254732) (xy 183.553889 -200.243053) (xy 183.616092 -200.23914)
			(xy 183.678295 -200.243053) (xy 183.739516 -200.254732) (xy 183.798791 -200.273992) (xy 183.855185 -200.300529)
			(xy 183.907809 -200.333924) (xy 183.955831 -200.373652) (xy 183.998496 -200.419086) (xy 184.03513 -200.469508)
			(xy 184.065156 -200.524125) (xy 184.088099 -200.582073) (xy 184.103599 -200.642441) (xy 184.111411 -200.704275)
			(xy 184.1119 -200.735438) (xy 188.075077 -200.735438) (xy 188.079012 -200.681667) (xy 188.090735 -200.629043)
			(xy 188.109995 -200.578686) (xy 188.136381 -200.531669) (xy 188.169333 -200.488996) (xy 188.208146 -200.451575)
			(xy 188.251994 -200.420205) (xy 188.299942 -200.395553) (xy 188.350969 -200.378145) (xy 188.403987 -200.368352)
			(xy 188.457866 -200.366383) (xy 188.511457 -200.37228) (xy 188.563618 -200.385916) (xy 188.613238 -200.407003)
			(xy 188.659259 -200.435089) (xy 188.700701 -200.469577) (xy 188.736679 -200.509731) (xy 188.766427 -200.554695)
			(xy 188.789312 -200.603512) (xy 188.804844 -200.655141) (xy 188.812694 -200.708481) (xy 188.813186 -200.735438)
			(xy 188.812694 -200.762395) (xy 188.804844 -200.815735) (xy 188.789312 -200.867364) (xy 188.766427 -200.916181)
			(xy 188.736679 -200.961145) (xy 188.700701 -201.001299) (xy 188.659259 -201.035787) (xy 188.613238 -201.063873)
			(xy 188.563618 -201.08496) (xy 188.511457 -201.098596) (xy 188.457866 -201.104493) (xy 188.403987 -201.102524)
			(xy 188.350969 -201.092731) (xy 188.299942 -201.075323) (xy 188.251994 -201.050671) (xy 188.208146 -201.019301)
			(xy 188.169333 -200.98188) (xy 188.136381 -200.939207) (xy 188.109995 -200.89219) (xy 188.090735 -200.841833)
			(xy 188.079012 -200.789209) (xy 188.075077 -200.735438) (xy 184.1119 -200.735438) (xy 184.111373 -200.768139)
			(xy 184.102765 -200.832971) (xy 184.085706 -200.896108) (xy 184.06049 -200.956452) (xy 184.027556 -201.012956)
			(xy 183.987476 -201.064637) (xy 183.96458 -201.08799) (xy 183.957214 -201.095356) (xy 183.949594 -201.113898)
			(xy 183.949594 -201.16038) (xy 184.364391 -201.16038) (xy 184.368326 -201.106609) (xy 184.380049 -201.053985)
			(xy 184.399309 -201.003628) (xy 184.425695 -200.956611) (xy 184.458647 -200.913938) (xy 184.49746 -200.876517)
			(xy 184.541308 -200.845147) (xy 184.589256 -200.820495) (xy 184.640283 -200.803087) (xy 184.693301 -200.793294)
			(xy 184.74718 -200.791325) (xy 184.800771 -200.797222) (xy 184.852932 -200.810858) (xy 184.902552 -200.831945)
			(xy 184.948573 -200.860031) (xy 184.990015 -200.894519) (xy 185.025993 -200.934673) (xy 185.055741 -200.979637)
			(xy 185.078626 -201.028454) (xy 185.094158 -201.080083) (xy 185.102008 -201.133423) (xy 185.1025 -201.16038)
			(xy 185.102008 -201.187337) (xy 185.094158 -201.240677) (xy 185.078626 -201.292306) (xy 185.055741 -201.341123)
			(xy 185.025993 -201.386087) (xy 184.990015 -201.426241) (xy 184.948573 -201.460729) (xy 184.902552 -201.488815)
			(xy 184.852932 -201.509902) (xy 184.800771 -201.523538) (xy 184.74718 -201.529435) (xy 184.693301 -201.527466)
			(xy 184.640283 -201.517673) (xy 184.589256 -201.500265) (xy 184.541308 -201.475613) (xy 184.49746 -201.444243)
			(xy 184.458647 -201.406822) (xy 184.425695 -201.364149) (xy 184.399309 -201.317132) (xy 184.380049 -201.266775)
			(xy 184.368326 -201.214151) (xy 184.364391 -201.16038) (xy 183.949594 -201.16038) (xy 183.949594 -201.206862)
			(xy 183.957214 -201.225404) (xy 183.96458 -201.23277) (xy 183.987487 -201.256113) (xy 184.02757 -201.307794)
			(xy 184.060504 -201.364299) (xy 184.085719 -201.424646) (xy 184.102775 -201.487786) (xy 184.111377 -201.552621)
			(xy 184.1119 -201.585322) (xy 184.111411 -201.616485) (xy 184.103599 -201.678319) (xy 184.088099 -201.738687)
			(xy 184.065156 -201.796635) (xy 184.03513 -201.851252) (xy 183.998496 -201.901674) (xy 183.955831 -201.947108)
			(xy 183.907809 -201.986836) (xy 183.855185 -202.020231) (xy 183.798791 -202.046768) (xy 183.739516 -202.066028)
			(xy 183.678295 -202.077707) (xy 183.616092 -202.08162) (xy 183.553889 -202.077707) (xy 183.492668 -202.066028)
			(xy 183.433393 -202.046768) (xy 183.376999 -202.020231) (xy 183.324375 -201.986836) (xy 183.276353 -201.947108)
			(xy 183.233688 -201.901674) (xy 183.197054 -201.851252) (xy 183.167028 -201.796635) (xy 183.144085 -201.738687)
			(xy 183.128585 -201.678319) (xy 183.120773 -201.616485) (xy 183.120284 -201.585322) (xy 180.011832 -201.585322)
			(xy 180.011285 -201.618022) (xy 180.00268 -201.682853) (xy 179.985624 -201.745989) (xy 179.960411 -201.806333)
			(xy 179.927482 -201.862838) (xy 179.887406 -201.91452) (xy 179.864512 -201.937874) (xy 179.857146 -201.94524)
			(xy 179.849526 -201.963782) (xy 179.849526 -202.010264) (xy 180.264323 -202.010264) (xy 180.268258 -201.956493)
			(xy 180.279981 -201.903869) (xy 180.299241 -201.853512) (xy 180.325627 -201.806495) (xy 180.358579 -201.763822)
			(xy 180.397392 -201.726401) (xy 180.44124 -201.695031) (xy 180.489188 -201.670379) (xy 180.540215 -201.652971)
			(xy 180.593233 -201.643178) (xy 180.647112 -201.641209) (xy 180.700703 -201.647106) (xy 180.752864 -201.660742)
			(xy 180.802484 -201.681829) (xy 180.848505 -201.709915) (xy 180.889947 -201.744403) (xy 180.925925 -201.784557)
			(xy 180.955673 -201.829521) (xy 180.978558 -201.878338) (xy 180.99409 -201.929967) (xy 181.00194 -201.983307)
			(xy 181.002432 -202.010264) (xy 181.00194 -202.037221) (xy 180.99409 -202.090561) (xy 180.978558 -202.14219)
			(xy 180.955673 -202.191007) (xy 180.925925 -202.235971) (xy 180.889947 -202.276125) (xy 180.848505 -202.310613)
			(xy 180.802484 -202.338699) (xy 180.752864 -202.359786) (xy 180.700703 -202.373422) (xy 180.647112 -202.379319)
			(xy 180.593233 -202.37735) (xy 180.540215 -202.367557) (xy 180.489188 -202.350149) (xy 180.44124 -202.325497)
			(xy 180.397392 -202.294127) (xy 180.358579 -202.256706) (xy 180.325627 -202.214033) (xy 180.299241 -202.167016)
			(xy 180.279981 -202.116659) (xy 180.268258 -202.064035) (xy 180.264323 -202.010264) (xy 179.849526 -202.010264)
			(xy 179.849526 -202.056746) (xy 179.857146 -202.075288) (xy 179.864512 -202.082654) (xy 179.887399 -202.106016)
			(xy 179.927486 -202.157692) (xy 179.960425 -202.214192) (xy 179.985644 -202.274536) (xy 180.002703 -202.337673)
			(xy 180.011308 -202.402505) (xy 180.011832 -202.435206) (xy 181.862491 -202.435206) (xy 181.866426 -202.381435)
			(xy 181.878149 -202.328811) (xy 181.897409 -202.278454) (xy 181.923795 -202.231437) (xy 181.956747 -202.188764)
			(xy 181.99556 -202.151343) (xy 182.039408 -202.119973) (xy 182.087356 -202.095321) (xy 182.138383 -202.077913)
			(xy 182.191401 -202.06812) (xy 182.24528 -202.066151) (xy 182.298871 -202.072048) (xy 182.351032 -202.085684)
			(xy 182.400652 -202.106771) (xy 182.446673 -202.134857) (xy 182.488115 -202.169345) (xy 182.524093 -202.209499)
			(xy 182.553841 -202.254463) (xy 182.576726 -202.30328) (xy 182.592258 -202.354909) (xy 182.600108 -202.408249)
			(xy 182.6006 -202.435206) (xy 186.56427 -202.435206) (xy 186.56477 -202.402505) (xy 186.573384 -202.337672)
			(xy 186.59045 -202.274535) (xy 186.615671 -202.21419) (xy 186.648609 -202.157687) (xy 186.688692 -202.106007)
			(xy 186.71159 -202.082654) (xy 186.718956 -202.075288) (xy 186.726576 -202.056746) (xy 186.726576 -201.963782)
			(xy 186.718956 -201.94524) (xy 186.71159 -201.937874) (xy 186.688716 -201.914499) (xy 186.648628 -201.862826)
			(xy 186.615687 -201.806328) (xy 186.590466 -201.745987) (xy 186.573404 -201.682853) (xy 186.564796 -201.618022)
			(xy 186.56427 -201.585322) (xy 186.564759 -201.554159) (xy 186.572571 -201.492325) (xy 186.588071 -201.431957)
			(xy 186.611014 -201.374009) (xy 186.64104 -201.319392) (xy 186.677674 -201.26897) (xy 186.720339 -201.223536)
			(xy 186.768361 -201.183808) (xy 186.820985 -201.150413) (xy 186.877379 -201.123876) (xy 186.936654 -201.104616)
			(xy 186.997875 -201.092937) (xy 187.060078 -201.089024) (xy 187.122281 -201.092937) (xy 187.183502 -201.104616)
			(xy 187.242777 -201.123876) (xy 187.299171 -201.150413) (xy 187.351795 -201.183808) (xy 187.399817 -201.223536)
			(xy 187.442482 -201.26897) (xy 187.479116 -201.319392) (xy 187.509142 -201.374009) (xy 187.532085 -201.431957)
			(xy 187.547585 -201.492325) (xy 187.555397 -201.554159) (xy 187.555886 -201.585322) (xy 190.664338 -201.585322)
			(xy 190.664858 -201.552621) (xy 190.673469 -201.48779) (xy 190.690532 -201.424653) (xy 190.715749 -201.364309)
			(xy 190.748683 -201.307805) (xy 190.788762 -201.256124) (xy 190.811658 -201.23277) (xy 190.819024 -201.225404)
			(xy 190.826644 -201.206862) (xy 190.826644 -201.113898) (xy 190.819024 -201.095356) (xy 190.811658 -201.08799)
			(xy 190.788738 -201.064659) (xy 190.748656 -201.012976) (xy 190.715722 -200.956468) (xy 190.690509 -200.896119)
			(xy 190.673456 -200.832977) (xy 190.664859 -200.76814) (xy 190.664338 -200.735438) (xy 190.664827 -200.704275)
			(xy 190.672639 -200.642441) (xy 190.688139 -200.582073) (xy 190.711082 -200.524125) (xy 190.741108 -200.469508)
			(xy 190.777742 -200.419086) (xy 190.820407 -200.373652) (xy 190.868429 -200.333924) (xy 190.921053 -200.300529)
			(xy 190.977447 -200.273992) (xy 191.036722 -200.254732) (xy 191.097943 -200.243053) (xy 191.160146 -200.23914)
			(xy 191.222349 -200.243053) (xy 191.28357 -200.254732) (xy 191.342845 -200.273992) (xy 191.399239 -200.300529)
			(xy 191.451863 -200.333924) (xy 191.499885 -200.373652) (xy 191.54255 -200.419086) (xy 191.579184 -200.469508)
			(xy 191.60921 -200.524125) (xy 191.632153 -200.582073) (xy 191.647653 -200.642441) (xy 191.655465 -200.704275)
			(xy 191.655954 -200.735438) (xy 195.619131 -200.735438) (xy 195.623066 -200.681667) (xy 195.634789 -200.629043)
			(xy 195.654049 -200.578686) (xy 195.680435 -200.531669) (xy 195.713387 -200.488996) (xy 195.7522 -200.451575)
			(xy 195.796048 -200.420205) (xy 195.843996 -200.395553) (xy 195.895023 -200.378145) (xy 195.948041 -200.368352)
			(xy 196.00192 -200.366383) (xy 196.055511 -200.37228) (xy 196.107672 -200.385916) (xy 196.157292 -200.407003)
			(xy 196.203313 -200.435089) (xy 196.244755 -200.469577) (xy 196.280733 -200.509731) (xy 196.310481 -200.554695)
			(xy 196.333366 -200.603512) (xy 196.348898 -200.655141) (xy 196.356748 -200.708481) (xy 196.35724 -200.735438)
			(xy 196.356748 -200.762395) (xy 196.348898 -200.815735) (xy 196.333366 -200.867364) (xy 196.310481 -200.916181)
			(xy 196.280733 -200.961145) (xy 196.244755 -201.001299) (xy 196.203313 -201.035787) (xy 196.157292 -201.063873)
			(xy 196.107672 -201.08496) (xy 196.055511 -201.098596) (xy 196.00192 -201.104493) (xy 195.948041 -201.102524)
			(xy 195.895023 -201.092731) (xy 195.843996 -201.075323) (xy 195.796048 -201.050671) (xy 195.7522 -201.019301)
			(xy 195.713387 -200.98188) (xy 195.680435 -200.939207) (xy 195.654049 -200.89219) (xy 195.634789 -200.841833)
			(xy 195.623066 -200.789209) (xy 195.619131 -200.735438) (xy 191.655954 -200.735438) (xy 191.655411 -200.768138)
			(xy 191.646804 -200.832969) (xy 191.629747 -200.896105) (xy 191.604534 -200.956449) (xy 191.571603 -201.012953)
			(xy 191.531528 -201.064636) (xy 191.508634 -201.08799) (xy 191.501268 -201.095356) (xy 191.493648 -201.113898)
			(xy 191.493648 -201.16038) (xy 191.908445 -201.16038) (xy 191.91238 -201.106609) (xy 191.924103 -201.053985)
			(xy 191.943363 -201.003628) (xy 191.969749 -200.956611) (xy 192.002701 -200.913938) (xy 192.041514 -200.876517)
			(xy 192.085362 -200.845147) (xy 192.13331 -200.820495) (xy 192.184337 -200.803087) (xy 192.237355 -200.793294)
			(xy 192.291234 -200.791325) (xy 192.344825 -200.797222) (xy 192.396986 -200.810858) (xy 192.446606 -200.831945)
			(xy 192.492627 -200.860031) (xy 192.534069 -200.894519) (xy 192.570047 -200.934673) (xy 192.599795 -200.979637)
			(xy 192.62268 -201.028454) (xy 192.638212 -201.080083) (xy 192.646062 -201.133423) (xy 192.646554 -201.16038)
			(xy 192.646062 -201.187337) (xy 192.638212 -201.240677) (xy 192.62268 -201.292306) (xy 192.599795 -201.341123)
			(xy 192.570047 -201.386087) (xy 192.534069 -201.426241) (xy 192.492627 -201.460729) (xy 192.446606 -201.488815)
			(xy 192.396986 -201.509902) (xy 192.344825 -201.523538) (xy 192.291234 -201.529435) (xy 192.237355 -201.527466)
			(xy 192.184337 -201.517673) (xy 192.13331 -201.500265) (xy 192.085362 -201.475613) (xy 192.041514 -201.444243)
			(xy 192.002701 -201.406822) (xy 191.969749 -201.364149) (xy 191.943363 -201.317132) (xy 191.924103 -201.266775)
			(xy 191.91238 -201.214151) (xy 191.908445 -201.16038) (xy 191.493648 -201.16038) (xy 191.493648 -201.206862)
			(xy 191.501268 -201.225404) (xy 191.508634 -201.23277) (xy 191.531533 -201.256121) (xy 191.571618 -201.307799)
			(xy 191.604555 -201.364303) (xy 191.629771 -201.424648) (xy 191.646829 -201.487787) (xy 191.655431 -201.552621)
			(xy 191.655954 -201.585322) (xy 191.655465 -201.616485) (xy 191.647653 -201.678319) (xy 191.632153 -201.738687)
			(xy 191.60921 -201.796635) (xy 191.579184 -201.851252) (xy 191.54255 -201.901674) (xy 191.499885 -201.947108)
			(xy 191.451863 -201.986836) (xy 191.399239 -202.020231) (xy 191.342845 -202.046768) (xy 191.28357 -202.066028)
			(xy 191.222349 -202.077707) (xy 191.160146 -202.08162) (xy 191.097943 -202.077707) (xy 191.036722 -202.066028)
			(xy 190.977447 -202.046768) (xy 190.921053 -202.020231) (xy 190.868429 -201.986836) (xy 190.820407 -201.947108)
			(xy 190.777742 -201.901674) (xy 190.741108 -201.851252) (xy 190.711082 -201.796635) (xy 190.688139 -201.738687)
			(xy 190.672639 -201.678319) (xy 190.664827 -201.616485) (xy 190.664338 -201.585322) (xy 187.555886 -201.585322)
			(xy 187.555352 -201.618022) (xy 187.546747 -201.682855) (xy 187.529689 -201.745991) (xy 187.504474 -201.806336)
			(xy 187.471541 -201.86284) (xy 187.431462 -201.914521) (xy 187.408566 -201.937874) (xy 187.4012 -201.94524)
			(xy 187.39358 -201.963782) (xy 187.39358 -202.010264) (xy 187.808377 -202.010264) (xy 187.812312 -201.956493)
			(xy 187.824035 -201.903869) (xy 187.843295 -201.853512) (xy 187.869681 -201.806495) (xy 187.902633 -201.763822)
			(xy 187.941446 -201.726401) (xy 187.985294 -201.695031) (xy 188.033242 -201.670379) (xy 188.084269 -201.652971)
			(xy 188.137287 -201.643178) (xy 188.191166 -201.641209) (xy 188.244757 -201.647106) (xy 188.296918 -201.660742)
			(xy 188.346538 -201.681829) (xy 188.392559 -201.709915) (xy 188.434001 -201.744403) (xy 188.469979 -201.784557)
			(xy 188.499727 -201.829521) (xy 188.522612 -201.878338) (xy 188.538144 -201.929967) (xy 188.545994 -201.983307)
			(xy 188.546486 -202.010264) (xy 188.545994 -202.037221) (xy 188.538144 -202.090561) (xy 188.522612 -202.14219)
			(xy 188.499727 -202.191007) (xy 188.469979 -202.235971) (xy 188.434001 -202.276125) (xy 188.392559 -202.310613)
			(xy 188.346538 -202.338699) (xy 188.296918 -202.359786) (xy 188.244757 -202.373422) (xy 188.191166 -202.379319)
			(xy 188.137287 -202.37735) (xy 188.084269 -202.367557) (xy 188.033242 -202.350149) (xy 187.985294 -202.325497)
			(xy 187.941446 -202.294127) (xy 187.902633 -202.256706) (xy 187.869681 -202.214033) (xy 187.843295 -202.167016)
			(xy 187.824035 -202.116659) (xy 187.812312 -202.064035) (xy 187.808377 -202.010264) (xy 187.39358 -202.010264)
			(xy 187.39358 -202.056746) (xy 187.4012 -202.075288) (xy 187.408566 -202.082654) (xy 187.431463 -202.106007)
			(xy 187.471547 -202.157685) (xy 187.504483 -202.214188) (xy 187.5297 -202.274534) (xy 187.546758 -202.337672)
			(xy 187.555362 -202.402505) (xy 187.555886 -202.435206) (xy 189.406545 -202.435206) (xy 189.41048 -202.381435)
			(xy 189.422203 -202.328811) (xy 189.441463 -202.278454) (xy 189.467849 -202.231437) (xy 189.500801 -202.188764)
			(xy 189.539614 -202.151343) (xy 189.583462 -202.119973) (xy 189.63141 -202.095321) (xy 189.682437 -202.077913)
			(xy 189.735455 -202.06812) (xy 189.789334 -202.066151) (xy 189.842925 -202.072048) (xy 189.895086 -202.085684)
			(xy 189.944706 -202.106771) (xy 189.990727 -202.134857) (xy 190.032169 -202.169345) (xy 190.068147 -202.209499)
			(xy 190.097895 -202.254463) (xy 190.12078 -202.30328) (xy 190.136312 -202.354909) (xy 190.144162 -202.408249)
			(xy 190.144654 -202.435206) (xy 194.108324 -202.435206) (xy 194.108838 -202.402505) (xy 194.117451 -202.337673)
			(xy 194.134515 -202.274537) (xy 194.159733 -202.214193) (xy 194.192669 -202.15769) (xy 194.232748 -202.106008)
			(xy 194.255644 -202.082654) (xy 194.26301 -202.075288) (xy 194.27063 -202.056746) (xy 194.27063 -201.963782)
			(xy 194.26301 -201.94524) (xy 194.255644 -201.937874) (xy 194.232762 -201.914507) (xy 194.192676 -201.862831)
			(xy 194.159738 -201.806332) (xy 194.134518 -201.745989) (xy 194.117457 -201.682854) (xy 194.10885 -201.618022)
			(xy 194.108324 -201.585322) (xy 194.108813 -201.554159) (xy 194.116625 -201.492325) (xy 194.132125 -201.431957)
			(xy 194.155068 -201.374009) (xy 194.185094 -201.319392) (xy 194.221728 -201.26897) (xy 194.264393 -201.223536)
			(xy 194.312415 -201.183808) (xy 194.365039 -201.150413) (xy 194.421433 -201.123876) (xy 194.480708 -201.104616)
			(xy 194.541929 -201.092937) (xy 194.604132 -201.089024) (xy 194.666335 -201.092937) (xy 194.727556 -201.104616)
			(xy 194.786831 -201.123876) (xy 194.843225 -201.150413) (xy 194.895849 -201.183808) (xy 194.943871 -201.223536)
			(xy 194.986536 -201.26897) (xy 195.02317 -201.319392) (xy 195.053196 -201.374009) (xy 195.076139 -201.431957)
			(xy 195.091639 -201.492325) (xy 195.099451 -201.554159) (xy 195.09994 -201.585322) (xy 198.208392 -201.585322)
			(xy 198.208896 -201.552621) (xy 198.217508 -201.487788) (xy 198.234573 -201.42465) (xy 198.259793 -201.364306)
			(xy 198.292731 -201.307803) (xy 198.332814 -201.256123) (xy 198.355712 -201.23277) (xy 198.363078 -201.225404)
			(xy 198.370698 -201.206862) (xy 198.370698 -201.113898) (xy 198.363078 -201.095356) (xy 198.355712 -201.08799)
			(xy 198.332784 -201.064667) (xy 198.292704 -201.012981) (xy 198.259772 -200.956472) (xy 198.234561 -200.896121)
			(xy 198.217509 -200.832978) (xy 198.208913 -200.768141) (xy 198.208392 -200.735438) (xy 198.208881 -200.704275)
			(xy 198.216693 -200.642441) (xy 198.232193 -200.582073) (xy 198.255136 -200.524125) (xy 198.285162 -200.469508)
			(xy 198.321796 -200.419086) (xy 198.364461 -200.373652) (xy 198.412483 -200.333924) (xy 198.465107 -200.300529)
			(xy 198.521501 -200.273992) (xy 198.580776 -200.254732) (xy 198.641997 -200.243053) (xy 198.7042 -200.23914)
			(xy 198.766403 -200.243053) (xy 198.827624 -200.254732) (xy 198.886899 -200.273992) (xy 198.943293 -200.300529)
			(xy 198.995917 -200.333924) (xy 199.043939 -200.373652) (xy 199.086604 -200.419086) (xy 199.123238 -200.469508)
			(xy 199.153264 -200.524125) (xy 199.176207 -200.582073) (xy 199.191707 -200.642441) (xy 199.199519 -200.704275)
			(xy 199.200008 -200.735438) (xy 203.162931 -200.735438) (xy 203.166866 -200.681667) (xy 203.178589 -200.629043)
			(xy 203.197849 -200.578686) (xy 203.224235 -200.531669) (xy 203.257187 -200.488996) (xy 203.296 -200.451575)
			(xy 203.339848 -200.420205) (xy 203.387796 -200.395553) (xy 203.438823 -200.378145) (xy 203.491841 -200.368352)
			(xy 203.54572 -200.366383) (xy 203.599311 -200.37228) (xy 203.651472 -200.385916) (xy 203.701092 -200.407003)
			(xy 203.747113 -200.435089) (xy 203.788555 -200.469577) (xy 203.824533 -200.509731) (xy 203.854281 -200.554695)
			(xy 203.877166 -200.603512) (xy 203.892698 -200.655141) (xy 203.900548 -200.708481) (xy 203.90104 -200.735438)
			(xy 203.900548 -200.762395) (xy 203.892698 -200.815735) (xy 203.877166 -200.867364) (xy 203.854281 -200.916181)
			(xy 203.824533 -200.961145) (xy 203.788555 -201.001299) (xy 203.747113 -201.035787) (xy 203.701092 -201.063873)
			(xy 203.651472 -201.08496) (xy 203.599311 -201.098596) (xy 203.54572 -201.104493) (xy 203.491841 -201.102524)
			(xy 203.438823 -201.092731) (xy 203.387796 -201.075323) (xy 203.339848 -201.050671) (xy 203.296 -201.019301)
			(xy 203.257187 -200.98188) (xy 203.224235 -200.939207) (xy 203.197849 -200.89219) (xy 203.178589 -200.841833)
			(xy 203.166866 -200.789209) (xy 203.162931 -200.735438) (xy 199.200008 -200.735438) (xy 199.199478 -200.768138)
			(xy 199.190871 -200.83297) (xy 199.173812 -200.896107) (xy 199.148596 -200.956452) (xy 199.115663 -201.012955)
			(xy 199.075584 -201.064637) (xy 199.052688 -201.08799) (xy 199.045322 -201.095356) (xy 199.037702 -201.113898)
			(xy 199.037702 -201.16038) (xy 199.452499 -201.16038) (xy 199.456434 -201.106609) (xy 199.468157 -201.053985)
			(xy 199.487417 -201.003628) (xy 199.513803 -200.956611) (xy 199.546755 -200.913938) (xy 199.585568 -200.876517)
			(xy 199.629416 -200.845147) (xy 199.677364 -200.820495) (xy 199.728391 -200.803087) (xy 199.781409 -200.793294)
			(xy 199.835288 -200.791325) (xy 199.888879 -200.797222) (xy 199.94104 -200.810858) (xy 199.99066 -200.831945)
			(xy 200.036681 -200.860031) (xy 200.078123 -200.894519) (xy 200.114101 -200.934673) (xy 200.143849 -200.979637)
			(xy 200.166734 -201.028454) (xy 200.182266 -201.080083) (xy 200.190116 -201.133423) (xy 200.190608 -201.16038)
			(xy 200.190116 -201.187337) (xy 200.182266 -201.240677) (xy 200.166734 -201.292306) (xy 200.143849 -201.341123)
			(xy 200.114101 -201.386087) (xy 200.078123 -201.426241) (xy 200.036681 -201.460729) (xy 199.99066 -201.488815)
			(xy 199.94104 -201.509902) (xy 199.888879 -201.523538) (xy 199.835288 -201.529435) (xy 199.781409 -201.527466)
			(xy 199.728391 -201.517673) (xy 199.677364 -201.500265) (xy 199.629416 -201.475613) (xy 199.585568 -201.444243)
			(xy 199.546755 -201.406822) (xy 199.513803 -201.364149) (xy 199.487417 -201.317132) (xy 199.468157 -201.266775)
			(xy 199.456434 -201.214151) (xy 199.452499 -201.16038) (xy 199.037702 -201.16038) (xy 199.037702 -201.206862)
			(xy 199.045322 -201.225404) (xy 199.052688 -201.23277) (xy 199.075597 -201.256111) (xy 199.115679 -201.307793)
			(xy 199.148613 -201.364299) (xy 199.173827 -201.424646) (xy 199.190884 -201.487786) (xy 199.199485 -201.552621)
			(xy 199.200008 -201.585322) (xy 199.199519 -201.616485) (xy 199.191707 -201.678319) (xy 199.176207 -201.738687)
			(xy 199.153264 -201.796635) (xy 199.123238 -201.851252) (xy 199.086604 -201.901674) (xy 199.043939 -201.947108)
			(xy 198.995917 -201.986836) (xy 198.943293 -202.020231) (xy 198.886899 -202.046768) (xy 198.827624 -202.066028)
			(xy 198.766403 -202.077707) (xy 198.7042 -202.08162) (xy 198.641997 -202.077707) (xy 198.580776 -202.066028)
			(xy 198.521501 -202.046768) (xy 198.465107 -202.020231) (xy 198.412483 -201.986836) (xy 198.364461 -201.947108)
			(xy 198.321796 -201.901674) (xy 198.285162 -201.851252) (xy 198.255136 -201.796635) (xy 198.232193 -201.738687)
			(xy 198.216693 -201.678319) (xy 198.208881 -201.616485) (xy 198.208392 -201.585322) (xy 195.09994 -201.585322)
			(xy 195.09939 -201.618022) (xy 195.090786 -201.682853) (xy 195.07373 -201.745989) (xy 195.048518 -201.806333)
			(xy 195.015589 -201.862837) (xy 194.975514 -201.91452) (xy 194.95262 -201.937874) (xy 194.945254 -201.94524)
			(xy 194.937634 -201.963782) (xy 194.937634 -202.010264) (xy 195.352431 -202.010264) (xy 195.356366 -201.956493)
			(xy 195.368089 -201.903869) (xy 195.387349 -201.853512) (xy 195.413735 -201.806495) (xy 195.446687 -201.763822)
			(xy 195.4855 -201.726401) (xy 195.529348 -201.695031) (xy 195.577296 -201.670379) (xy 195.628323 -201.652971)
			(xy 195.681341 -201.643178) (xy 195.73522 -201.641209) (xy 195.788811 -201.647106) (xy 195.840972 -201.660742)
			(xy 195.890592 -201.681829) (xy 195.936613 -201.709915) (xy 195.978055 -201.744403) (xy 196.014033 -201.784557)
			(xy 196.043781 -201.829521) (xy 196.066666 -201.878338) (xy 196.082198 -201.929967) (xy 196.090048 -201.983307)
			(xy 196.09054 -202.010264) (xy 196.090048 -202.037221) (xy 196.082198 -202.090561) (xy 196.066666 -202.14219)
			(xy 196.043781 -202.191007) (xy 196.014033 -202.235971) (xy 195.978055 -202.276125) (xy 195.936613 -202.310613)
			(xy 195.890592 -202.338699) (xy 195.840972 -202.359786) (xy 195.788811 -202.373422) (xy 195.73522 -202.379319)
			(xy 195.681341 -202.37735) (xy 195.628323 -202.367557) (xy 195.577296 -202.350149) (xy 195.529348 -202.325497)
			(xy 195.4855 -202.294127) (xy 195.446687 -202.256706) (xy 195.413735 -202.214033) (xy 195.387349 -202.167016)
			(xy 195.368089 -202.116659) (xy 195.356366 -202.064035) (xy 195.352431 -202.010264) (xy 194.937634 -202.010264)
			(xy 194.937634 -202.056746) (xy 194.945254 -202.075288) (xy 194.95262 -202.082654) (xy 194.975509 -202.106015)
			(xy 195.015595 -202.157691) (xy 195.048534 -202.214192) (xy 195.073752 -202.274535) (xy 195.090812 -202.337673)
			(xy 195.099416 -202.402505) (xy 195.09994 -202.435206) (xy 196.950599 -202.435206) (xy 196.954534 -202.381435)
			(xy 196.966257 -202.328811) (xy 196.985517 -202.278454) (xy 197.011903 -202.231437) (xy 197.044855 -202.188764)
			(xy 197.083668 -202.151343) (xy 197.127516 -202.119973) (xy 197.175464 -202.095321) (xy 197.226491 -202.077913)
			(xy 197.279509 -202.06812) (xy 197.333388 -202.066151) (xy 197.386979 -202.072048) (xy 197.43914 -202.085684)
			(xy 197.48876 -202.106771) (xy 197.534781 -202.134857) (xy 197.576223 -202.169345) (xy 197.612201 -202.209499)
			(xy 197.641949 -202.254463) (xy 197.664834 -202.30328) (xy 197.680366 -202.354909) (xy 197.688216 -202.408249)
			(xy 197.688708 -202.435206) (xy 201.652124 -202.435206) (xy 201.652638 -202.402505) (xy 201.661251 -202.337673)
			(xy 201.678315 -202.274537) (xy 201.703533 -202.214193) (xy 201.736469 -202.15769) (xy 201.776548 -202.106008)
			(xy 201.799444 -202.082654) (xy 201.80681 -202.075288) (xy 201.81443 -202.056746) (xy 201.81443 -201.963782)
			(xy 201.80681 -201.94524) (xy 201.799444 -201.937874) (xy 201.776562 -201.914507) (xy 201.736476 -201.862831)
			(xy 201.703538 -201.806332) (xy 201.678318 -201.745989) (xy 201.661257 -201.682854) (xy 201.65265 -201.618022)
			(xy 201.652124 -201.585322) (xy 201.652613 -201.554159) (xy 201.660425 -201.492325) (xy 201.675925 -201.431957)
			(xy 201.698868 -201.374009) (xy 201.728894 -201.319392) (xy 201.765528 -201.26897) (xy 201.808193 -201.223536)
			(xy 201.856215 -201.183808) (xy 201.908839 -201.150413) (xy 201.965233 -201.123876) (xy 202.024508 -201.104616)
			(xy 202.085729 -201.092937) (xy 202.147932 -201.089024) (xy 202.210135 -201.092937) (xy 202.271356 -201.104616)
			(xy 202.330631 -201.123876) (xy 202.387025 -201.150413) (xy 202.439649 -201.183808) (xy 202.487671 -201.223536)
			(xy 202.530336 -201.26897) (xy 202.56697 -201.319392) (xy 202.596996 -201.374009) (xy 202.619939 -201.431957)
			(xy 202.635439 -201.492325) (xy 202.643251 -201.554159) (xy 202.64374 -201.585322) (xy 205.752192 -201.585322)
			(xy 205.752696 -201.552621) (xy 205.761308 -201.487788) (xy 205.778373 -201.42465) (xy 205.803593 -201.364306)
			(xy 205.836531 -201.307803) (xy 205.876614 -201.256123) (xy 205.899512 -201.23277) (xy 205.906878 -201.225404)
			(xy 205.914498 -201.206862) (xy 205.914498 -201.113898) (xy 205.906878 -201.095356) (xy 205.899512 -201.08799)
			(xy 205.876584 -201.064667) (xy 205.836504 -201.012981) (xy 205.803572 -200.956472) (xy 205.778361 -200.896121)
			(xy 205.761309 -200.832978) (xy 205.752713 -200.768141) (xy 205.752192 -200.735438) (xy 205.752681 -200.704275)
			(xy 205.760493 -200.642441) (xy 205.775993 -200.582073) (xy 205.798936 -200.524125) (xy 205.828962 -200.469508)
			(xy 205.865596 -200.419086) (xy 205.908261 -200.373652) (xy 205.956283 -200.333924) (xy 206.008907 -200.300529)
			(xy 206.065301 -200.273992) (xy 206.124576 -200.254732) (xy 206.185797 -200.243053) (xy 206.248 -200.23914)
			(xy 206.310203 -200.243053) (xy 206.371424 -200.254732) (xy 206.430699 -200.273992) (xy 206.487093 -200.300529)
			(xy 206.539717 -200.333924) (xy 206.587739 -200.373652) (xy 206.630404 -200.419086) (xy 206.667038 -200.469508)
			(xy 206.697064 -200.524125) (xy 206.720007 -200.582073) (xy 206.735507 -200.642441) (xy 206.743319 -200.704275)
			(xy 206.743808 -200.735438) (xy 206.743278 -200.768138) (xy 206.734671 -200.83297) (xy 206.717612 -200.896107)
			(xy 206.692396 -200.956452) (xy 206.659463 -201.012955) (xy 206.619384 -201.064637) (xy 206.596488 -201.08799)
			(xy 206.589122 -201.095356) (xy 206.581502 -201.113898) (xy 206.581502 -201.206862) (xy 206.589122 -201.225404)
			(xy 206.596488 -201.23277) (xy 206.619397 -201.256111) (xy 206.659479 -201.307793) (xy 206.692413 -201.364299)
			(xy 206.717627 -201.424646) (xy 206.734684 -201.487786) (xy 206.743285 -201.552621) (xy 206.743808 -201.585322)
			(xy 206.743319 -201.616485) (xy 206.735507 -201.678319) (xy 206.720007 -201.738687) (xy 206.697064 -201.796635)
			(xy 206.667038 -201.851252) (xy 206.630404 -201.901674) (xy 206.587739 -201.947108) (xy 206.539717 -201.986836)
			(xy 206.487093 -202.020231) (xy 206.430699 -202.046768) (xy 206.371424 -202.066028) (xy 206.310203 -202.077707)
			(xy 206.248 -202.08162) (xy 206.185797 -202.077707) (xy 206.124576 -202.066028) (xy 206.065301 -202.046768)
			(xy 206.008907 -202.020231) (xy 205.956283 -201.986836) (xy 205.908261 -201.947108) (xy 205.865596 -201.901674)
			(xy 205.828962 -201.851252) (xy 205.798936 -201.796635) (xy 205.775993 -201.738687) (xy 205.760493 -201.678319)
			(xy 205.752681 -201.616485) (xy 205.752192 -201.585322) (xy 202.64374 -201.585322) (xy 202.64319 -201.618022)
			(xy 202.634586 -201.682853) (xy 202.61753 -201.745989) (xy 202.592318 -201.806333) (xy 202.559389 -201.862837)
			(xy 202.519314 -201.91452) (xy 202.49642 -201.937874) (xy 202.489054 -201.94524) (xy 202.481434 -201.963782)
			(xy 202.481434 -202.010264) (xy 202.896231 -202.010264) (xy 202.900166 -201.956493) (xy 202.911889 -201.903869)
			(xy 202.931149 -201.853512) (xy 202.957535 -201.806495) (xy 202.990487 -201.763822) (xy 203.0293 -201.726401)
			(xy 203.073148 -201.695031) (xy 203.121096 -201.670379) (xy 203.172123 -201.652971) (xy 203.225141 -201.643178)
			(xy 203.27902 -201.641209) (xy 203.332611 -201.647106) (xy 203.384772 -201.660742) (xy 203.434392 -201.681829)
			(xy 203.480413 -201.709915) (xy 203.521855 -201.744403) (xy 203.557833 -201.784557) (xy 203.587581 -201.829521)
			(xy 203.610466 -201.878338) (xy 203.625998 -201.929967) (xy 203.633848 -201.983307) (xy 203.63434 -202.010264)
			(xy 203.633848 -202.037221) (xy 203.625998 -202.090561) (xy 203.610466 -202.14219) (xy 203.587581 -202.191007)
			(xy 203.557833 -202.235971) (xy 203.521855 -202.276125) (xy 203.480413 -202.310613) (xy 203.434392 -202.338699)
			(xy 203.384772 -202.359786) (xy 203.332611 -202.373422) (xy 203.27902 -202.379319) (xy 203.225141 -202.37735)
			(xy 203.172123 -202.367557) (xy 203.121096 -202.350149) (xy 203.073148 -202.325497) (xy 203.0293 -202.294127)
			(xy 202.990487 -202.256706) (xy 202.957535 -202.214033) (xy 202.931149 -202.167016) (xy 202.911889 -202.116659)
			(xy 202.900166 -202.064035) (xy 202.896231 -202.010264) (xy 202.481434 -202.010264) (xy 202.481434 -202.056746)
			(xy 202.489054 -202.075288) (xy 202.49642 -202.082654) (xy 202.519309 -202.106015) (xy 202.559395 -202.157691)
			(xy 202.592334 -202.214192) (xy 202.617552 -202.274535) (xy 202.634612 -202.337673) (xy 202.643216 -202.402505)
			(xy 202.64374 -202.435206) (xy 204.494399 -202.435206) (xy 204.498334 -202.381435) (xy 204.510057 -202.328811)
			(xy 204.529317 -202.278454) (xy 204.555703 -202.231437) (xy 204.588655 -202.188764) (xy 204.627468 -202.151343)
			(xy 204.671316 -202.119973) (xy 204.719264 -202.095321) (xy 204.770291 -202.077913) (xy 204.823309 -202.06812)
			(xy 204.877188 -202.066151) (xy 204.930779 -202.072048) (xy 204.98294 -202.085684) (xy 205.03256 -202.106771)
			(xy 205.078581 -202.134857) (xy 205.120023 -202.169345) (xy 205.156001 -202.209499) (xy 205.185749 -202.254463)
			(xy 205.208634 -202.30328) (xy 205.224166 -202.354909) (xy 205.232016 -202.408249) (xy 205.232508 -202.435206)
			(xy 205.232016 -202.462163) (xy 205.224166 -202.515503) (xy 205.208634 -202.567132) (xy 205.185749 -202.615949)
			(xy 205.156001 -202.660913) (xy 205.120023 -202.701067) (xy 205.078581 -202.735555) (xy 205.03256 -202.763641)
			(xy 204.98294 -202.784728) (xy 204.930779 -202.798364) (xy 204.877188 -202.804261) (xy 204.823309 -202.802292)
			(xy 204.770291 -202.792499) (xy 204.719264 -202.775091) (xy 204.671316 -202.750439) (xy 204.627468 -202.719069)
			(xy 204.588655 -202.681648) (xy 204.555703 -202.638975) (xy 204.529317 -202.591958) (xy 204.510057 -202.541601)
			(xy 204.498334 -202.488977) (xy 204.494399 -202.435206) (xy 202.64374 -202.435206) (xy 202.643251 -202.466369)
			(xy 202.635439 -202.528203) (xy 202.619939 -202.588571) (xy 202.596996 -202.646519) (xy 202.56697 -202.701136)
			(xy 202.530336 -202.751558) (xy 202.487671 -202.796992) (xy 202.439649 -202.83672) (xy 202.387025 -202.870115)
			(xy 202.330631 -202.896652) (xy 202.271356 -202.915912) (xy 202.210135 -202.927591) (xy 202.147932 -202.931504)
			(xy 202.085729 -202.927591) (xy 202.024508 -202.915912) (xy 201.965233 -202.896652) (xy 201.908839 -202.870115)
			(xy 201.856215 -202.83672) (xy 201.808193 -202.796992) (xy 201.765528 -202.751558) (xy 201.728894 -202.701136)
			(xy 201.698868 -202.646519) (xy 201.675925 -202.588571) (xy 201.660425 -202.528203) (xy 201.652613 -202.466369)
			(xy 201.652124 -202.435206) (xy 197.688708 -202.435206) (xy 197.688216 -202.462163) (xy 197.680366 -202.515503)
			(xy 197.664834 -202.567132) (xy 197.641949 -202.615949) (xy 197.612201 -202.660913) (xy 197.576223 -202.701067)
			(xy 197.534781 -202.735555) (xy 197.48876 -202.763641) (xy 197.43914 -202.784728) (xy 197.386979 -202.798364)
			(xy 197.333388 -202.804261) (xy 197.279509 -202.802292) (xy 197.226491 -202.792499) (xy 197.175464 -202.775091)
			(xy 197.127516 -202.750439) (xy 197.083668 -202.719069) (xy 197.044855 -202.681648) (xy 197.011903 -202.638975)
			(xy 196.985517 -202.591958) (xy 196.966257 -202.541601) (xy 196.954534 -202.488977) (xy 196.950599 -202.435206)
			(xy 195.09994 -202.435206) (xy 195.099451 -202.466369) (xy 195.091639 -202.528203) (xy 195.076139 -202.588571)
			(xy 195.053196 -202.646519) (xy 195.02317 -202.701136) (xy 194.986536 -202.751558) (xy 194.943871 -202.796992)
			(xy 194.895849 -202.83672) (xy 194.843225 -202.870115) (xy 194.786831 -202.896652) (xy 194.727556 -202.915912)
			(xy 194.666335 -202.927591) (xy 194.604132 -202.931504) (xy 194.541929 -202.927591) (xy 194.480708 -202.915912)
			(xy 194.421433 -202.896652) (xy 194.365039 -202.870115) (xy 194.312415 -202.83672) (xy 194.264393 -202.796992)
			(xy 194.221728 -202.751558) (xy 194.185094 -202.701136) (xy 194.155068 -202.646519) (xy 194.132125 -202.588571)
			(xy 194.116625 -202.528203) (xy 194.108813 -202.466369) (xy 194.108324 -202.435206) (xy 190.144654 -202.435206)
			(xy 190.144162 -202.462163) (xy 190.136312 -202.515503) (xy 190.12078 -202.567132) (xy 190.097895 -202.615949)
			(xy 190.068147 -202.660913) (xy 190.032169 -202.701067) (xy 189.990727 -202.735555) (xy 189.944706 -202.763641)
			(xy 189.895086 -202.784728) (xy 189.842925 -202.798364) (xy 189.789334 -202.804261) (xy 189.735455 -202.802292)
			(xy 189.682437 -202.792499) (xy 189.63141 -202.775091) (xy 189.583462 -202.750439) (xy 189.539614 -202.719069)
			(xy 189.500801 -202.681648) (xy 189.467849 -202.638975) (xy 189.441463 -202.591958) (xy 189.422203 -202.541601)
			(xy 189.41048 -202.488977) (xy 189.406545 -202.435206) (xy 187.555886 -202.435206) (xy 187.555397 -202.466369)
			(xy 187.547585 -202.528203) (xy 187.532085 -202.588571) (xy 187.509142 -202.646519) (xy 187.479116 -202.701136)
			(xy 187.442482 -202.751558) (xy 187.399817 -202.796992) (xy 187.351795 -202.83672) (xy 187.299171 -202.870115)
			(xy 187.242777 -202.896652) (xy 187.183502 -202.915912) (xy 187.122281 -202.927591) (xy 187.060078 -202.931504)
			(xy 186.997875 -202.927591) (xy 186.936654 -202.915912) (xy 186.877379 -202.896652) (xy 186.820985 -202.870115)
			(xy 186.768361 -202.83672) (xy 186.720339 -202.796992) (xy 186.677674 -202.751558) (xy 186.64104 -202.701136)
			(xy 186.611014 -202.646519) (xy 186.588071 -202.588571) (xy 186.572571 -202.528203) (xy 186.564759 -202.466369)
			(xy 186.56427 -202.435206) (xy 182.6006 -202.435206) (xy 182.600108 -202.462163) (xy 182.592258 -202.515503)
			(xy 182.576726 -202.567132) (xy 182.553841 -202.615949) (xy 182.524093 -202.660913) (xy 182.488115 -202.701067)
			(xy 182.446673 -202.735555) (xy 182.400652 -202.763641) (xy 182.351032 -202.784728) (xy 182.298871 -202.798364)
			(xy 182.24528 -202.804261) (xy 182.191401 -202.802292) (xy 182.138383 -202.792499) (xy 182.087356 -202.775091)
			(xy 182.039408 -202.750439) (xy 181.99556 -202.719069) (xy 181.956747 -202.681648) (xy 181.923795 -202.638975)
			(xy 181.897409 -202.591958) (xy 181.878149 -202.541601) (xy 181.866426 -202.488977) (xy 181.862491 -202.435206)
			(xy 180.011832 -202.435206) (xy 180.011343 -202.466369) (xy 180.003531 -202.528203) (xy 179.988031 -202.588571)
			(xy 179.965088 -202.646519) (xy 179.935062 -202.701136) (xy 179.898428 -202.751558) (xy 179.855763 -202.796992)
			(xy 179.807741 -202.83672) (xy 179.755117 -202.870115) (xy 179.698723 -202.896652) (xy 179.639448 -202.915912)
			(xy 179.578227 -202.927591) (xy 179.516024 -202.931504) (xy 179.453821 -202.927591) (xy 179.3926 -202.915912)
			(xy 179.333325 -202.896652) (xy 179.276931 -202.870115) (xy 179.224307 -202.83672) (xy 179.176285 -202.796992)
			(xy 179.13362 -202.751558) (xy 179.096986 -202.701136) (xy 179.06696 -202.646519) (xy 179.044017 -202.588571)
			(xy 179.028517 -202.528203) (xy 179.020705 -202.466369) (xy 179.020216 -202.435206) (xy 175.056546 -202.435206)
			(xy 175.056054 -202.462163) (xy 175.048204 -202.515503) (xy 175.032672 -202.567132) (xy 175.009787 -202.615949)
			(xy 174.980039 -202.660913) (xy 174.944061 -202.701067) (xy 174.902619 -202.735555) (xy 174.856598 -202.763641)
			(xy 174.806978 -202.784728) (xy 174.754817 -202.798364) (xy 174.701226 -202.804261) (xy 174.647347 -202.802292)
			(xy 174.594329 -202.792499) (xy 174.543302 -202.775091) (xy 174.495354 -202.750439) (xy 174.451506 -202.719069)
			(xy 174.412693 -202.681648) (xy 174.379741 -202.638975) (xy 174.353355 -202.591958) (xy 174.334095 -202.541601)
			(xy 174.322372 -202.488977) (xy 174.318437 -202.435206) (xy 172.467778 -202.435206) (xy 172.467289 -202.466369)
			(xy 172.459477 -202.528203) (xy 172.443977 -202.588571) (xy 172.421034 -202.646519) (xy 172.391008 -202.701136)
			(xy 172.354374 -202.751558) (xy 172.311709 -202.796992) (xy 172.263687 -202.83672) (xy 172.211063 -202.870115)
			(xy 172.154669 -202.896652) (xy 172.095394 -202.915912) (xy 172.034173 -202.927591) (xy 171.97197 -202.931504)
			(xy 171.909767 -202.927591) (xy 171.848546 -202.915912) (xy 171.789271 -202.896652) (xy 171.732877 -202.870115)
			(xy 171.680253 -202.83672) (xy 171.632231 -202.796992) (xy 171.589566 -202.751558) (xy 171.552932 -202.701136)
			(xy 171.522906 -202.646519) (xy 171.499963 -202.588571) (xy 171.484463 -202.528203) (xy 171.476651 -202.466369)
			(xy 171.476162 -202.435206) (xy 167.512492 -202.435206) (xy 167.512 -202.462163) (xy 167.50415 -202.515503)
			(xy 167.488618 -202.567132) (xy 167.465733 -202.615949) (xy 167.435985 -202.660913) (xy 167.400007 -202.701067)
			(xy 167.358565 -202.735555) (xy 167.312544 -202.763641) (xy 167.262924 -202.784728) (xy 167.210763 -202.798364)
			(xy 167.157172 -202.804261) (xy 167.103293 -202.802292) (xy 167.050275 -202.792499) (xy 166.999248 -202.775091)
			(xy 166.9513 -202.750439) (xy 166.907452 -202.719069) (xy 166.868639 -202.681648) (xy 166.835687 -202.638975)
			(xy 166.809301 -202.591958) (xy 166.790041 -202.541601) (xy 166.778318 -202.488977) (xy 166.774383 -202.435206)
			(xy 161.612834 -202.435206) (xy 161.612834 -203.285344) (xy 165.442915 -203.285344) (xy 165.44685 -203.231573)
			(xy 165.458573 -203.178949) (xy 165.477833 -203.128592) (xy 165.504219 -203.081575) (xy 165.537171 -203.038902)
			(xy 165.575984 -203.001481) (xy 165.619832 -202.970111) (xy 165.66778 -202.945459) (xy 165.718807 -202.928051)
			(xy 165.771825 -202.918258) (xy 165.825704 -202.916289) (xy 165.879295 -202.922186) (xy 165.931456 -202.935822)
			(xy 165.981076 -202.956909) (xy 166.027097 -202.984995) (xy 166.068539 -203.019483) (xy 166.104517 -203.059637)
			(xy 166.134265 -203.104601) (xy 166.15715 -203.153418) (xy 166.172682 -203.205047) (xy 166.180532 -203.258387)
			(xy 166.181024 -203.285344) (xy 172.986969 -203.285344) (xy 172.990904 -203.231573) (xy 173.002627 -203.178949)
			(xy 173.021887 -203.128592) (xy 173.048273 -203.081575) (xy 173.081225 -203.038902) (xy 173.120038 -203.001481)
			(xy 173.163886 -202.970111) (xy 173.211834 -202.945459) (xy 173.262861 -202.928051) (xy 173.315879 -202.918258)
			(xy 173.369758 -202.916289) (xy 173.423349 -202.922186) (xy 173.47551 -202.935822) (xy 173.52513 -202.956909)
			(xy 173.571151 -202.984995) (xy 173.612593 -203.019483) (xy 173.648571 -203.059637) (xy 173.678319 -203.104601)
			(xy 173.701204 -203.153418) (xy 173.716736 -203.205047) (xy 173.724586 -203.258387) (xy 173.725078 -203.285344)
			(xy 173.724586 -203.312301) (xy 173.716736 -203.365641) (xy 173.701204 -203.41727) (xy 173.678319 -203.466087)
			(xy 173.648571 -203.511051) (xy 173.612593 -203.551205) (xy 173.571151 -203.585693) (xy 173.52513 -203.613779)
			(xy 173.47551 -203.634866) (xy 173.423349 -203.648502) (xy 173.369758 -203.654399) (xy 173.315879 -203.65243)
			(xy 173.262861 -203.642637) (xy 173.211834 -203.625229) (xy 173.163886 -203.600577) (xy 173.120038 -203.569207)
			(xy 173.081225 -203.531786) (xy 173.048273 -203.489113) (xy 173.021887 -203.442096) (xy 173.002627 -203.391739)
			(xy 172.990904 -203.339115) (xy 172.986969 -203.285344) (xy 166.181024 -203.285344) (xy 166.180532 -203.312301)
			(xy 166.172682 -203.365641) (xy 166.15715 -203.41727) (xy 166.134265 -203.466087) (xy 166.104517 -203.511051)
			(xy 166.068539 -203.551205) (xy 166.027097 -203.585693) (xy 165.981076 -203.613779) (xy 165.931456 -203.634866)
			(xy 165.879295 -203.648502) (xy 165.825704 -203.654399) (xy 165.771825 -203.65243) (xy 165.718807 -203.642637)
			(xy 165.66778 -203.625229) (xy 165.619832 -203.600577) (xy 165.575984 -203.569207) (xy 165.537171 -203.531786)
			(xy 165.504219 -203.489113) (xy 165.477833 -203.442096) (xy 165.458573 -203.391739) (xy 165.44685 -203.339115)
			(xy 165.442915 -203.285344) (xy 161.612834 -203.285344) (xy 161.612834 -204.135228) (xy 168.158683 -204.135228)
			(xy 168.162618 -204.081457) (xy 168.174341 -204.028833) (xy 168.193601 -203.978476) (xy 168.219987 -203.931459)
			(xy 168.252939 -203.888786) (xy 168.291752 -203.851365) (xy 168.3356 -203.819995) (xy 168.383548 -203.795343)
			(xy 168.434575 -203.777935) (xy 168.487593 -203.768142) (xy 168.541472 -203.766173) (xy 168.595063 -203.77207)
			(xy 168.647224 -203.785706) (xy 168.696844 -203.806793) (xy 168.742865 -203.834879) (xy 168.784307 -203.869367)
			(xy 168.820285 -203.909521) (xy 168.850033 -203.954485) (xy 168.872918 -204.003302) (xy 168.88845 -204.054931)
			(xy 168.8963 -204.108271) (xy 168.896792 -204.135228) (xy 168.8963 -204.162185) (xy 168.88845 -204.215525)
			(xy 168.872918 -204.267154) (xy 168.850033 -204.315971) (xy 168.820285 -204.360935) (xy 168.784307 -204.401089)
			(xy 168.742865 -204.435577) (xy 168.696844 -204.463663) (xy 168.647224 -204.48475) (xy 168.595063 -204.498386)
			(xy 168.541472 -204.504283) (xy 168.487593 -204.502314) (xy 168.434575 -204.492521) (xy 168.383548 -204.475113)
			(xy 168.3356 -204.450461) (xy 168.291752 -204.419091) (xy 168.252939 -204.38167) (xy 168.219987 -204.338997)
			(xy 168.193601 -204.29198) (xy 168.174341 -204.241623) (xy 168.162618 -204.188999) (xy 168.158683 -204.135228)
			(xy 161.612834 -204.135228) (xy 161.612834 -204.985366) (xy 164.058615 -204.985366) (xy 164.06255 -204.931595)
			(xy 164.074273 -204.878971) (xy 164.093533 -204.828614) (xy 164.119919 -204.781597) (xy 164.152871 -204.738924)
			(xy 164.191684 -204.701503) (xy 164.235532 -204.670133) (xy 164.28348 -204.645481) (xy 164.334507 -204.628073)
			(xy 164.387525 -204.61828) (xy 164.441404 -204.616311) (xy 164.494995 -204.622208) (xy 164.547156 -204.635844)
			(xy 164.596776 -204.656931) (xy 164.642797 -204.685017) (xy 164.684239 -204.719505) (xy 164.720217 -204.759659)
			(xy 164.749965 -204.804623) (xy 164.77285 -204.85344) (xy 164.788382 -204.905069) (xy 164.796232 -204.958409)
			(xy 164.796724 -204.985366) (xy 164.796232 -205.012323) (xy 164.788382 -205.065663) (xy 164.77285 -205.117292)
			(xy 164.749965 -205.166109) (xy 164.720217 -205.211073) (xy 164.684239 -205.251227) (xy 164.642797 -205.285715)
			(xy 164.596776 -205.313801) (xy 164.547156 -205.334888) (xy 164.494995 -205.348524) (xy 164.441404 -205.354421)
			(xy 164.387525 -205.352452) (xy 164.334507 -205.342659) (xy 164.28348 -205.325251) (xy 164.235532 -205.300599)
			(xy 164.191684 -205.269229) (xy 164.152871 -205.231808) (xy 164.119919 -205.189135) (xy 164.093533 -205.142118)
			(xy 164.074273 -205.091761) (xy 164.06255 -205.039137) (xy 164.058615 -204.985366) (xy 161.612834 -204.985366)
			(xy 161.612834 -205.83525) (xy 168.158683 -205.83525) (xy 168.162618 -205.781479) (xy 168.174341 -205.728855)
			(xy 168.193601 -205.678498) (xy 168.219987 -205.631481) (xy 168.252939 -205.588808) (xy 168.291752 -205.551387)
			(xy 168.3356 -205.520017) (xy 168.383548 -205.495365) (xy 168.434575 -205.477957) (xy 168.487593 -205.468164)
			(xy 168.541472 -205.466195) (xy 168.595063 -205.472092) (xy 168.647224 -205.485728) (xy 168.696844 -205.506815)
			(xy 168.742865 -205.534901) (xy 168.784307 -205.569389) (xy 168.820285 -205.609543) (xy 168.850033 -205.654507)
			(xy 168.872918 -205.703324) (xy 168.88845 -205.754953) (xy 168.8963 -205.808293) (xy 168.896792 -205.83525)
			(xy 168.8963 -205.862207) (xy 168.88845 -205.915547) (xy 168.872918 -205.967176) (xy 168.850033 -206.015993)
			(xy 168.820285 -206.060957) (xy 168.784307 -206.101111) (xy 168.742865 -206.135599) (xy 168.696844 -206.163685)
			(xy 168.647224 -206.184772) (xy 168.595063 -206.198408) (xy 168.541472 -206.204305) (xy 168.487593 -206.202336)
			(xy 168.434575 -206.192543) (xy 168.383548 -206.175135) (xy 168.3356 -206.150483) (xy 168.291752 -206.119113)
			(xy 168.252939 -206.081692) (xy 168.219987 -206.039019) (xy 168.193601 -205.992002) (xy 168.174341 -205.941645)
			(xy 168.162618 -205.889021) (xy 168.158683 -205.83525) (xy 161.612834 -205.83525) (xy 161.612834 -206.685388)
			(xy 164.058615 -206.685388) (xy 164.06255 -206.631617) (xy 164.074273 -206.578993) (xy 164.093533 -206.528636)
			(xy 164.119919 -206.481619) (xy 164.152871 -206.438946) (xy 164.191684 -206.401525) (xy 164.235532 -206.370155)
			(xy 164.28348 -206.345503) (xy 164.334507 -206.328095) (xy 164.387525 -206.318302) (xy 164.441404 -206.316333)
			(xy 164.494995 -206.32223) (xy 164.547156 -206.335866) (xy 164.596776 -206.356953) (xy 164.642797 -206.385039)
			(xy 164.684239 -206.419527) (xy 164.720217 -206.459681) (xy 164.749965 -206.504645) (xy 164.77285 -206.553462)
			(xy 164.788382 -206.605091) (xy 164.796232 -206.658431) (xy 164.796724 -206.685388) (xy 164.796232 -206.712345)
			(xy 164.788382 -206.765685) (xy 164.77285 -206.817314) (xy 164.749965 -206.866131) (xy 164.720217 -206.911095)
			(xy 164.684239 -206.951249) (xy 164.642797 -206.985737) (xy 164.596776 -207.013823) (xy 164.547156 -207.03491)
			(xy 164.494995 -207.048546) (xy 164.441404 -207.054443) (xy 164.387525 -207.052474) (xy 164.334507 -207.042681)
			(xy 164.28348 -207.025273) (xy 164.235532 -207.000621) (xy 164.191684 -206.969251) (xy 164.152871 -206.93183)
			(xy 164.119919 -206.889157) (xy 164.093533 -206.84214) (xy 164.074273 -206.791783) (xy 164.06255 -206.739159)
			(xy 164.058615 -206.685388) (xy 161.612834 -206.685388) (xy 161.612834 -207.535272) (xy 168.158683 -207.535272)
			(xy 168.162618 -207.481501) (xy 168.174341 -207.428877) (xy 168.193601 -207.37852) (xy 168.219987 -207.331503)
			(xy 168.252939 -207.28883) (xy 168.291752 -207.251409) (xy 168.3356 -207.220039) (xy 168.383548 -207.195387)
			(xy 168.434575 -207.177979) (xy 168.487593 -207.168186) (xy 168.541472 -207.166217) (xy 168.595063 -207.172114)
			(xy 168.647224 -207.18575) (xy 168.696844 -207.206837) (xy 168.742865 -207.234923) (xy 168.784307 -207.269411)
			(xy 168.820285 -207.309565) (xy 168.850033 -207.354529) (xy 168.872918 -207.403346) (xy 168.88845 -207.454975)
			(xy 168.8963 -207.508315) (xy 168.896792 -207.535272) (xy 168.8963 -207.562229) (xy 168.88845 -207.615569)
			(xy 168.872918 -207.667198) (xy 168.850033 -207.716015) (xy 168.820285 -207.760979) (xy 168.784307 -207.801133)
			(xy 168.742865 -207.835621) (xy 168.696844 -207.863707) (xy 168.647224 -207.884794) (xy 168.595063 -207.89843)
			(xy 168.541472 -207.904327) (xy 168.487593 -207.902358) (xy 168.434575 -207.892565) (xy 168.383548 -207.875157)
			(xy 168.3356 -207.850505) (xy 168.291752 -207.819135) (xy 168.252939 -207.781714) (xy 168.219987 -207.739041)
			(xy 168.193601 -207.692024) (xy 168.174341 -207.641667) (xy 168.162618 -207.589043) (xy 168.158683 -207.535272)
			(xy 161.612834 -207.535272) (xy 161.612834 -208.38541) (xy 164.058615 -208.38541) (xy 164.06255 -208.331639)
			(xy 164.074273 -208.279015) (xy 164.093533 -208.228658) (xy 164.119919 -208.181641) (xy 164.152871 -208.138968)
			(xy 164.191684 -208.101547) (xy 164.235532 -208.070177) (xy 164.28348 -208.045525) (xy 164.334507 -208.028117)
			(xy 164.387525 -208.018324) (xy 164.441404 -208.016355) (xy 164.494995 -208.022252) (xy 164.547156 -208.035888)
			(xy 164.596776 -208.056975) (xy 164.642797 -208.085061) (xy 164.684239 -208.119549) (xy 164.720217 -208.159703)
			(xy 164.749965 -208.204667) (xy 164.77285 -208.253484) (xy 164.788382 -208.305113) (xy 164.796232 -208.358453)
			(xy 164.796724 -208.38541) (xy 164.796232 -208.412367) (xy 164.788382 -208.465707) (xy 164.77285 -208.517336)
			(xy 164.749965 -208.566153) (xy 164.720217 -208.611117) (xy 164.684239 -208.651271) (xy 164.642797 -208.685759)
			(xy 164.596776 -208.713845) (xy 164.547156 -208.734932) (xy 164.494995 -208.748568) (xy 164.441404 -208.754465)
			(xy 164.387525 -208.752496) (xy 164.334507 -208.742703) (xy 164.28348 -208.725295) (xy 164.235532 -208.700643)
			(xy 164.191684 -208.669273) (xy 164.152871 -208.631852) (xy 164.119919 -208.589179) (xy 164.093533 -208.542162)
			(xy 164.074273 -208.491805) (xy 164.06255 -208.439181) (xy 164.058615 -208.38541) (xy 161.612834 -208.38541)
			(xy 161.612834 -209.235294) (xy 166.774383 -209.235294) (xy 166.778318 -209.181523) (xy 166.790041 -209.128899)
			(xy 166.809301 -209.078542) (xy 166.835687 -209.031525) (xy 166.868639 -208.988852) (xy 166.907452 -208.951431)
			(xy 166.9513 -208.920061) (xy 166.999248 -208.895409) (xy 167.050275 -208.878001) (xy 167.103293 -208.868208)
			(xy 167.157172 -208.866239) (xy 167.210763 -208.872136) (xy 167.262924 -208.885772) (xy 167.312544 -208.906859)
			(xy 167.358565 -208.934945) (xy 167.400007 -208.969433) (xy 167.435985 -209.009587) (xy 167.465733 -209.054551)
			(xy 167.488618 -209.103368) (xy 167.50415 -209.154997) (xy 167.512 -209.208337) (xy 167.512492 -209.235294)
			(xy 171.476162 -209.235294) (xy 171.476611 -209.204096) (xy 171.484434 -209.142194) (xy 171.499966 -209.081763)
			(xy 171.522964 -209.023761) (xy 171.553061 -208.969105) (xy 171.589783 -208.918661) (xy 171.632548 -208.873227)
			(xy 171.680679 -208.833521) (xy 171.706794 -208.816448) (xy 171.716954 -208.809844) (xy 171.729146 -208.790032)
			(xy 171.738544 -208.685892) (xy 171.730162 -208.664302) (xy 171.721272 -208.65592) (xy 171.702992 -208.638399)
			(xy 171.670913 -208.599223) (xy 171.644494 -208.556028) (xy 171.624232 -208.509624) (xy 171.610509 -208.460885)
			(xy 171.603581 -208.410727) (xy 171.603162 -208.38541) (xy 171.603612 -208.360063) (xy 171.610542 -208.309845)
			(xy 171.624287 -208.26105) (xy 171.644587 -208.214598) (xy 171.67106 -208.171366) (xy 171.703206 -208.132168)
			(xy 171.721526 -208.114646) (xy 171.730416 -208.106518) (xy 171.738798 -208.084674) (xy 171.729146 -207.980534)
			(xy 171.716954 -207.960722) (xy 171.706794 -207.954372) (xy 171.680661 -207.937303) (xy 171.63254 -207.897547)
			(xy 171.589785 -207.852068) (xy 171.553073 -207.801586) (xy 171.522982 -207.746897) (xy 171.49999 -207.688866)
			(xy 171.484457 -207.62841) (xy 171.476631 -207.566482) (xy 171.476162 -207.535272) (xy 171.476594 -207.504074)
			(xy 171.484419 -207.442171) (xy 171.499955 -207.38174) (xy 171.522954 -207.323737) (xy 171.553054 -207.269082)
			(xy 171.589778 -207.218638) (xy 171.632545 -207.173204) (xy 171.680678 -207.133499) (xy 171.706794 -207.116426)
			(xy 171.716954 -207.109822) (xy 171.729146 -207.09001) (xy 171.738544 -206.98587) (xy 171.730162 -206.96428)
			(xy 171.721272 -206.955898) (xy 171.702981 -206.938388) (xy 171.670903 -206.89921) (xy 171.644486 -206.856012)
			(xy 171.624226 -206.809606) (xy 171.610505 -206.760865) (xy 171.60358 -206.710706) (xy 171.603162 -206.685388)
			(xy 171.603598 -206.66004) (xy 171.610531 -206.609822) (xy 171.624278 -206.561027) (xy 171.644581 -206.514575)
			(xy 171.671056 -206.471343) (xy 171.703204 -206.432145) (xy 171.721526 -206.414624) (xy 171.730416 -206.406496)
			(xy 171.738798 -206.384652) (xy 171.729146 -206.280512) (xy 171.716954 -206.2607) (xy 171.706794 -206.25435)
			(xy 171.680697 -206.237229) (xy 171.632575 -206.19748) (xy 171.589819 -206.152009) (xy 171.553104 -206.101535)
			(xy 171.523009 -206.046854) (xy 171.50001 -205.98883) (xy 171.484471 -205.92838) (xy 171.476636 -205.866458)
			(xy 171.476162 -205.83525) (xy 171.476655 -205.804054) (xy 171.484471 -205.742153) (xy 171.499997 -205.681724)
			(xy 171.522987 -205.623722) (xy 171.553079 -205.569066) (xy 171.589795 -205.518621) (xy 171.632555 -205.473185)
			(xy 171.680681 -205.433478) (xy 171.706794 -205.416404) (xy 171.716954 -205.4098) (xy 171.729146 -205.389988)
			(xy 171.738544 -205.285848) (xy 171.730162 -205.264258) (xy 171.721272 -205.255876) (xy 171.702971 -205.238377)
			(xy 171.670893 -205.199196) (xy 171.644477 -205.155996) (xy 171.624219 -205.109588) (xy 171.6105 -205.060845)
			(xy 171.603578 -205.010684) (xy 171.603162 -204.985366) (xy 171.603583 -204.960018) (xy 171.610519 -204.909799)
			(xy 171.62427 -204.861003) (xy 171.644575 -204.814552) (xy 171.671053 -204.77132) (xy 171.703203 -204.732123)
			(xy 171.721526 -204.714602) (xy 171.730416 -204.706474) (xy 171.738798 -204.68463) (xy 171.729146 -204.58049)
			(xy 171.716954 -204.560678) (xy 171.706794 -204.554328) (xy 171.680687 -204.537222) (xy 171.632565 -204.497471)
			(xy 171.589809 -204.451998) (xy 171.553095 -204.401521) (xy 171.523001 -204.346838) (xy 171.500004 -204.288812)
			(xy 171.484467 -204.22836) (xy 171.476635 -204.166436) (xy 171.476162 -204.135228) (xy 171.476651 -204.104065)
			(xy 171.484463 -204.042231) (xy 171.499963 -203.981863) (xy 171.522906 -203.923915) (xy 171.552932 -203.869298)
			(xy 171.589566 -203.818876) (xy 171.632231 -203.773442) (xy 171.680253 -203.733714) (xy 171.732877 -203.700319)
			(xy 171.789271 -203.673782) (xy 171.848546 -203.654522) (xy 171.909767 -203.642843) (xy 171.97197 -203.63893)
			(xy 172.034173 -203.642843) (xy 172.095394 -203.654522) (xy 172.154669 -203.673782) (xy 172.211063 -203.700319)
			(xy 172.263687 -203.733714) (xy 172.311709 -203.773442) (xy 172.354374 -203.818876) (xy 172.391008 -203.869298)
			(xy 172.421034 -203.923915) (xy 172.443977 -203.981863) (xy 172.459477 -204.042231) (xy 172.467289 -204.104065)
			(xy 172.467778 -204.135228) (xy 172.46731 -204.166438) (xy 172.459487 -204.228365) (xy 172.443956 -204.288821)
			(xy 172.420961 -204.34685) (xy 172.390868 -204.401536) (xy 172.35415 -204.452014) (xy 172.31139 -204.497486)
			(xy 172.263261 -204.537233) (xy 172.237146 -204.554328) (xy 172.226986 -204.560678) (xy 172.214794 -204.58049)
			(xy 172.205142 -204.68463) (xy 172.213524 -204.706474) (xy 172.222414 -204.714602) (xy 172.240737 -204.732121)
			(xy 172.272879 -204.771324) (xy 172.299352 -204.814558) (xy 172.319657 -204.861008) (xy 172.333411 -204.909802)
			(xy 172.340356 -204.960019) (xy 172.340778 -204.985366) (xy 172.340354 -205.010683) (xy 172.333431 -205.060842)
			(xy 172.31971 -205.109583) (xy 172.29945 -205.155987) (xy 172.273032 -205.199184) (xy 172.240952 -205.23836)
			(xy 172.222668 -205.255876) (xy 172.213778 -205.264258) (xy 172.205396 -205.285848) (xy 172.214794 -205.389988)
			(xy 172.226986 -205.4098) (xy 172.237146 -205.416404) (xy 172.263241 -205.433504) (xy 172.31136 -205.473215)
			(xy 172.354116 -205.51865) (xy 172.390832 -205.569092) (xy 172.420928 -205.623742) (xy 172.443928 -205.681737)
			(xy 172.459468 -205.74216) (xy 172.467304 -205.804055) (xy 172.467778 -205.83525) (xy 172.467327 -205.86646)
			(xy 172.459501 -205.928388) (xy 172.443968 -205.988845) (xy 172.420971 -206.046874) (xy 172.390875 -206.10156)
			(xy 172.354155 -206.152037) (xy 172.311392 -206.197509) (xy 172.263262 -206.237255) (xy 172.237146 -206.25435)
			(xy 172.226986 -206.2607) (xy 172.214794 -206.280512) (xy 172.205142 -206.384652) (xy 172.213524 -206.406496)
			(xy 172.222414 -206.414624) (xy 172.240748 -206.432132) (xy 172.272889 -206.471337) (xy 172.29936 -206.514573)
			(xy 172.319663 -206.561026) (xy 172.333415 -206.609822) (xy 172.340357 -206.66004) (xy 172.340778 -206.685388)
			(xy 172.340369 -206.710706) (xy 172.333443 -206.760866) (xy 172.31972 -206.809606) (xy 172.299457 -206.856011)
			(xy 172.273036 -206.899207) (xy 172.240954 -206.938382) (xy 172.222668 -206.955898) (xy 172.213778 -206.96428)
			(xy 172.205396 -206.98587) (xy 172.214794 -207.09001) (xy 172.226986 -207.109822) (xy 172.237146 -207.116426)
			(xy 172.263251 -207.133511) (xy 172.31137 -207.173224) (xy 172.354125 -207.218662) (xy 172.390841 -207.269106)
			(xy 172.420935 -207.323758) (xy 172.443934 -207.381755) (xy 172.459472 -207.44218) (xy 172.467305 -207.504077)
			(xy 172.467778 -207.535272) (xy 172.467344 -207.566483) (xy 172.459516 -207.628411) (xy 172.443979 -207.688868)
			(xy 172.42098 -207.746898) (xy 172.390882 -207.801584) (xy 172.35416 -207.852061) (xy 172.311395 -207.897532)
			(xy 172.263263 -207.937277) (xy 172.237146 -207.954372) (xy 172.226986 -207.960722) (xy 172.214794 -207.980534)
			(xy 172.205142 -208.084674) (xy 172.213524 -208.106518) (xy 172.222414 -208.114646) (xy 172.240759 -208.132144)
			(xy 172.272899 -208.171351) (xy 172.299369 -208.214589) (xy 172.319669 -208.261044) (xy 172.333419 -208.309841)
			(xy 172.340359 -208.360061) (xy 172.340778 -208.38541) (xy 175.57623 -208.38541) (xy 175.576646 -208.354199)
			(xy 175.584477 -208.292269) (xy 175.600016 -208.231812) (xy 175.623017 -208.173782) (xy 175.653118 -208.119096)
			(xy 175.689842 -208.068619) (xy 175.73261 -208.023149) (xy 175.780744 -207.983404) (xy 175.806862 -207.96631)
			(xy 175.817022 -207.95996) (xy 175.829214 -207.940148) (xy 175.838866 -207.836008) (xy 175.830484 -207.814164)
			(xy 175.821594 -207.806036) (xy 175.803291 -207.788497) (xy 175.771146 -207.749299) (xy 175.744671 -207.706069)
			(xy 175.724363 -207.659622) (xy 175.710605 -207.610832) (xy 175.703655 -207.560618) (xy 175.70323 -207.535272)
			(xy 175.703677 -207.509955) (xy 175.710595 -207.459797) (xy 175.724311 -207.411057) (xy 175.744566 -207.364652)
			(xy 175.770981 -207.321456) (xy 175.803057 -207.282279) (xy 175.82134 -207.264762) (xy 175.83023 -207.25638)
			(xy 175.838612 -207.23479) (xy 175.829214 -207.13065) (xy 175.817022 -207.110838) (xy 175.806862 -207.104234)
			(xy 175.780763 -207.08714) (xy 175.732648 -207.047425) (xy 175.689896 -207.001987) (xy 175.653182 -206.951544)
			(xy 175.623087 -206.896894) (xy 175.600087 -206.838899) (xy 175.584545 -206.778477) (xy 175.576706 -206.716582)
			(xy 175.57623 -206.685388) (xy 175.576707 -206.654179) (xy 175.584528 -206.592252) (xy 175.600058 -206.531796)
			(xy 175.62305 -206.473766) (xy 175.653143 -206.41908) (xy 175.689859 -206.368602) (xy 175.732619 -206.32313)
			(xy 175.780747 -206.283383) (xy 175.806862 -206.266288) (xy 175.817022 -206.259938) (xy 175.829214 -206.240126)
			(xy 175.838866 -206.135986) (xy 175.830484 -206.114142) (xy 175.821594 -206.106014) (xy 175.80328 -206.088486)
			(xy 175.771137 -206.049285) (xy 175.744663 -206.006053) (xy 175.724356 -205.959604) (xy 175.7106 -205.910812)
			(xy 175.703654 -205.860597) (xy 175.70323 -205.83525) (xy 175.703662 -205.809933) (xy 175.710583 -205.759774)
			(xy 175.724302 -205.711034) (xy 175.74456 -205.664629) (xy 175.770977 -205.621433) (xy 175.803056 -205.582257)
			(xy 175.82134 -205.56474) (xy 175.83023 -205.556358) (xy 175.838612 -205.534768) (xy 175.829214 -205.430628)
			(xy 175.817022 -205.410816) (xy 175.806862 -205.404212) (xy 175.780753 -205.387133) (xy 175.732638 -205.347416)
			(xy 175.689886 -205.301976) (xy 175.653173 -205.25153) (xy 175.62308 -205.196878) (xy 175.600081 -205.138881)
			(xy 175.584541 -205.078457) (xy 175.576705 -205.016561) (xy 175.57623 -204.985366) (xy 175.57669 -204.954156)
			(xy 175.584514 -204.892228) (xy 175.600046 -204.831772) (xy 175.623041 -204.773742) (xy 175.653136 -204.719056)
			(xy 175.689854 -204.668579) (xy 175.732616 -204.623107) (xy 175.780746 -204.583361) (xy 175.806862 -204.566266)
			(xy 175.817022 -204.559916) (xy 175.829214 -204.540104) (xy 175.838866 -204.435964) (xy 175.830484 -204.41412)
			(xy 175.821594 -204.405992) (xy 175.803269 -204.388474) (xy 175.771127 -204.349271) (xy 175.744654 -204.306037)
			(xy 175.72435 -204.259586) (xy 175.710596 -204.210793) (xy 175.703652 -204.160575) (xy 175.70323 -204.135228)
			(xy 175.703648 -204.10991) (xy 175.710572 -204.059751) (xy 175.724293 -204.011011) (xy 175.744554 -203.964606)
			(xy 175.770974 -203.92141) (xy 175.803055 -203.882234) (xy 175.82134 -203.864718) (xy 175.83023 -203.856336)
			(xy 175.838612 -203.834746) (xy 175.829214 -203.730606) (xy 175.817022 -203.710794) (xy 175.806862 -203.70419)
			(xy 175.780743 -203.687126) (xy 175.732628 -203.647406) (xy 175.689877 -203.601964) (xy 175.653165 -203.551517)
			(xy 175.623072 -203.496862) (xy 175.600076 -203.438863) (xy 175.584537 -203.378437) (xy 175.576704 -203.31654)
			(xy 175.57623 -203.285344) (xy 175.576719 -203.254181) (xy 175.584531 -203.192347) (xy 175.600031 -203.131979)
			(xy 175.622974 -203.074031) (xy 175.653 -203.019414) (xy 175.689634 -202.968992) (xy 175.732299 -202.923558)
			(xy 175.780321 -202.88383) (xy 175.832945 -202.850435) (xy 175.889339 -202.823898) (xy 175.948614 -202.804638)
			(xy 176.009835 -202.792959) (xy 176.072038 -202.789046) (xy 176.134241 -202.792959) (xy 176.195462 -202.804638)
			(xy 176.254737 -202.823898) (xy 176.311131 -202.850435) (xy 176.363755 -202.88383) (xy 176.411777 -202.923558)
			(xy 176.454442 -202.968992) (xy 176.491076 -203.019414) (xy 176.521102 -203.074031) (xy 176.544045 -203.131979)
			(xy 176.559545 -203.192347) (xy 176.567357 -203.254181) (xy 176.567846 -203.285344) (xy 180.531023 -203.285344)
			(xy 180.534958 -203.231573) (xy 180.546681 -203.178949) (xy 180.565941 -203.128592) (xy 180.592327 -203.081575)
			(xy 180.625279 -203.038902) (xy 180.664092 -203.001481) (xy 180.70794 -202.970111) (xy 180.755888 -202.945459)
			(xy 180.806915 -202.928051) (xy 180.859933 -202.918258) (xy 180.913812 -202.916289) (xy 180.967403 -202.922186)
			(xy 181.019564 -202.935822) (xy 181.069184 -202.956909) (xy 181.115205 -202.984995) (xy 181.156647 -203.019483)
			(xy 181.192625 -203.059637) (xy 181.222373 -203.104601) (xy 181.245258 -203.153418) (xy 181.26079 -203.205047)
			(xy 181.26864 -203.258387) (xy 181.269132 -203.285344) (xy 181.26864 -203.312301) (xy 181.26079 -203.365641)
			(xy 181.245258 -203.41727) (xy 181.222373 -203.466087) (xy 181.192625 -203.511051) (xy 181.156647 -203.551205)
			(xy 181.115205 -203.585693) (xy 181.069184 -203.613779) (xy 181.019564 -203.634866) (xy 180.967403 -203.648502)
			(xy 180.913812 -203.654399) (xy 180.859933 -203.65243) (xy 180.806915 -203.642637) (xy 180.755888 -203.625229)
			(xy 180.70794 -203.600577) (xy 180.664092 -203.569207) (xy 180.625279 -203.531786) (xy 180.592327 -203.489113)
			(xy 180.565941 -203.442096) (xy 180.546681 -203.391739) (xy 180.534958 -203.339115) (xy 180.531023 -203.285344)
			(xy 176.567846 -203.285344) (xy 176.567344 -203.31654) (xy 176.55953 -203.37844) (xy 176.544005 -203.438869)
			(xy 176.521015 -203.496871) (xy 176.490925 -203.551527) (xy 176.45421 -203.601972) (xy 176.411452 -203.647408)
			(xy 176.363327 -203.687116) (xy 176.337214 -203.70419) (xy 176.327054 -203.710794) (xy 176.314862 -203.730606)
			(xy 176.305464 -203.834746) (xy 176.313846 -203.856336) (xy 176.322736 -203.864718) (xy 176.341036 -203.882219)
			(xy 176.373113 -203.921399) (xy 176.399529 -203.964599) (xy 176.419787 -204.011007) (xy 176.433507 -204.059749)
			(xy 176.44043 -204.10991) (xy 176.440846 -204.135228) (xy 176.440418 -204.160576) (xy 176.433483 -204.210795)
			(xy 176.419734 -204.25959) (xy 176.39943 -204.306041) (xy 176.372953 -204.349274) (xy 176.340804 -204.388471)
			(xy 176.322482 -204.405992) (xy 176.313592 -204.41412) (xy 176.30521 -204.435964) (xy 176.314862 -204.540104)
			(xy 176.327054 -204.559916) (xy 176.337214 -204.566266) (xy 176.36332 -204.583373) (xy 176.411441 -204.623125)
			(xy 176.454197 -204.668598) (xy 176.490912 -204.719074) (xy 176.521005 -204.773757) (xy 176.544002 -204.831783)
			(xy 176.55954 -204.892235) (xy 176.567373 -204.954158) (xy 176.567846 -204.985366) (xy 176.567362 -205.016562)
			(xy 176.559544 -205.078463) (xy 176.544017 -205.138893) (xy 176.521025 -205.196895) (xy 176.490932 -205.251551)
			(xy 176.454215 -205.301995) (xy 176.411454 -205.347431) (xy 176.363327 -205.387138) (xy 176.337214 -205.404212)
			(xy 176.327054 -205.410816) (xy 176.314862 -205.430628) (xy 176.305464 -205.534768) (xy 176.313846 -205.556358)
			(xy 176.322736 -205.56474) (xy 176.340998 -205.582279) (xy 176.373079 -205.621451) (xy 176.3995 -205.664643)
			(xy 176.419764 -205.711043) (xy 176.433492 -205.759779) (xy 176.440424 -205.809934) (xy 176.440846 -205.83525)
			(xy 176.440433 -205.860598) (xy 176.433495 -205.910818) (xy 176.419743 -205.959613) (xy 176.399436 -206.006065)
			(xy 176.372957 -206.049296) (xy 176.340805 -206.088493) (xy 176.322482 -206.106014) (xy 176.313592 -206.114142)
			(xy 176.30521 -206.135986) (xy 176.314862 -206.240126) (xy 176.327054 -206.259938) (xy 176.337214 -206.266288)
			(xy 176.36333 -206.283381) (xy 176.411451 -206.323134) (xy 176.454207 -206.368609) (xy 176.49092 -206.419088)
			(xy 176.521013 -206.473773) (xy 176.544008 -206.531801) (xy 176.559544 -206.592254) (xy 176.567374 -206.654179)
			(xy 176.567846 -206.685388) (xy 176.567379 -206.716585) (xy 176.559559 -206.778487) (xy 176.544029 -206.838917)
			(xy 176.521034 -206.896918) (xy 176.490939 -206.951574) (xy 176.454219 -207.002019) (xy 176.411457 -207.047454)
			(xy 176.363328 -207.08716) (xy 176.337214 -207.104234) (xy 176.327054 -207.110838) (xy 176.314862 -207.13065)
			(xy 176.305464 -207.23479) (xy 176.313846 -207.25638) (xy 176.322736 -207.264762) (xy 176.341009 -207.28229)
			(xy 176.373088 -207.321464) (xy 176.399508 -207.364659) (xy 176.419771 -207.411061) (xy 176.433496 -207.459798)
			(xy 176.440426 -207.509955) (xy 176.440846 -207.535272) (xy 176.440381 -207.560619) (xy 176.433454 -207.610836)
			(xy 176.419712 -207.65963) (xy 176.399414 -207.706082) (xy 176.372944 -207.749315) (xy 176.340801 -207.788514)
			(xy 176.322482 -207.806036) (xy 176.313592 -207.814164) (xy 176.30521 -207.836008) (xy 176.314862 -207.940148)
			(xy 176.327054 -207.95996) (xy 176.337214 -207.96631) (xy 176.36334 -207.983388) (xy 176.411461 -208.023143)
			(xy 176.454216 -208.068621) (xy 176.490929 -208.119102) (xy 176.52102 -208.173789) (xy 176.544014 -208.231819)
			(xy 176.559548 -208.292274) (xy 176.567376 -208.3542) (xy 176.567846 -208.38541) (xy 176.567357 -208.416573)
			(xy 176.559545 -208.478407) (xy 176.544045 -208.538775) (xy 176.521102 -208.596723) (xy 176.491076 -208.65134)
			(xy 176.454442 -208.701762) (xy 176.411777 -208.747196) (xy 176.363755 -208.786924) (xy 176.311131 -208.820319)
			(xy 176.254737 -208.846856) (xy 176.195462 -208.866116) (xy 176.134241 -208.877795) (xy 176.072038 -208.881708)
			(xy 176.009835 -208.877795) (xy 175.948614 -208.866116) (xy 175.889339 -208.846856) (xy 175.832945 -208.820319)
			(xy 175.780321 -208.786924) (xy 175.732299 -208.747196) (xy 175.689634 -208.701762) (xy 175.653 -208.65134)
			(xy 175.622974 -208.596723) (xy 175.600031 -208.538775) (xy 175.584531 -208.478407) (xy 175.576719 -208.416573)
			(xy 175.57623 -208.38541) (xy 172.340778 -208.38541) (xy 172.340384 -208.410728) (xy 172.333455 -208.460889)
			(xy 172.319728 -208.50963) (xy 172.299463 -208.556034) (xy 172.273039 -208.59923) (xy 172.240955 -208.638405)
			(xy 172.222668 -208.65592) (xy 172.213778 -208.664302) (xy 172.205396 -208.685892) (xy 172.214794 -208.790032)
			(xy 172.226986 -208.809844) (xy 172.237146 -208.816448) (xy 172.263261 -208.833519) (xy 172.31138 -208.873234)
			(xy 172.354135 -208.918673) (xy 172.390849 -208.969119) (xy 172.420943 -209.023774) (xy 172.44394 -209.081773)
			(xy 172.459476 -209.1422) (xy 172.467306 -209.204098) (xy 172.467778 -209.235294) (xy 174.318437 -209.235294)
			(xy 174.322372 -209.181523) (xy 174.334095 -209.128899) (xy 174.353355 -209.078542) (xy 174.379741 -209.031525)
			(xy 174.412693 -208.988852) (xy 174.451506 -208.951431) (xy 174.495354 -208.920061) (xy 174.543302 -208.895409)
			(xy 174.594329 -208.878001) (xy 174.647347 -208.868208) (xy 174.701226 -208.866239) (xy 174.754817 -208.872136)
			(xy 174.806978 -208.885772) (xy 174.856598 -208.906859) (xy 174.902619 -208.934945) (xy 174.944061 -208.969433)
			(xy 174.980039 -209.009587) (xy 175.009787 -209.054551) (xy 175.032672 -209.103368) (xy 175.048204 -209.154997)
			(xy 175.056054 -209.208337) (xy 175.056546 -209.235294) (xy 179.020216 -209.235294) (xy 179.02064 -209.204095)
			(xy 179.028464 -209.142191) (xy 179.043998 -209.081759) (xy 179.066998 -209.023755) (xy 179.097099 -208.969099)
			(xy 179.133825 -208.918655) (xy 179.176595 -208.873222) (xy 179.22473 -208.833519) (xy 179.250848 -208.816448)
			(xy 179.261008 -208.809844) (xy 179.2732 -208.790032) (xy 179.282598 -208.685892) (xy 179.274216 -208.664302)
			(xy 179.265326 -208.65592) (xy 179.247037 -208.638408) (xy 179.214961 -208.599229) (xy 179.188544 -208.556031)
			(xy 179.168284 -208.509626) (xy 179.154562 -208.460886) (xy 179.147635 -208.410727) (xy 179.147216 -208.38541)
			(xy 179.147649 -208.360062) (xy 179.15458 -208.309843) (xy 179.168327 -208.261047) (xy 179.18863 -208.214595)
			(xy 179.215107 -208.171363) (xy 179.247257 -208.132166) (xy 179.26558 -208.114646) (xy 179.27447 -208.106518)
			(xy 179.282852 -208.084674) (xy 179.2732 -207.980534) (xy 179.261008 -207.960722) (xy 179.250848 -207.954372)
			(xy 179.224705 -207.93732) (xy 179.176585 -207.897559) (xy 179.133832 -207.852077) (xy 179.097122 -207.801592)
			(xy 179.067033 -207.746902) (xy 179.044042 -207.688869) (xy 179.02851 -207.628411) (xy 179.020685 -207.566483)
			(xy 179.020216 -207.535272) (xy 179.020623 -207.504073) (xy 179.028449 -207.442168) (xy 179.043986 -207.381735)
			(xy 179.066989 -207.323732) (xy 179.097092 -207.269076) (xy 179.13382 -207.218632) (xy 179.176592 -207.173199)
			(xy 179.224729 -207.133497) (xy 179.250848 -207.116426) (xy 179.261008 -207.109822) (xy 179.2732 -207.09001)
			(xy 179.282598 -206.98587) (xy 179.274216 -206.96428) (xy 179.265326 -206.955898) (xy 179.247027 -206.938397)
			(xy 179.214951 -206.899216) (xy 179.188536 -206.856016) (xy 179.168278 -206.809608) (xy 179.154558 -206.760866)
			(xy 179.147633 -206.710706) (xy 179.147216 -206.685388) (xy 179.147634 -206.66004) (xy 179.154569 -206.60982)
			(xy 179.168318 -206.561024) (xy 179.188624 -206.514572) (xy 179.215103 -206.47134) (xy 179.247256 -206.432144)
			(xy 179.26558 -206.414624) (xy 179.27447 -206.406496) (xy 179.282852 -206.384652) (xy 179.2732 -206.280512)
			(xy 179.261008 -206.2607) (xy 179.250848 -206.25435) (xy 179.22474 -206.237245) (xy 179.17662 -206.197492)
			(xy 179.133866 -206.152018) (xy 179.097153 -206.101541) (xy 179.06706 -206.046858) (xy 179.044062 -205.988833)
			(xy 179.028524 -205.928381) (xy 179.02069 -205.866458) (xy 179.020216 -205.83525) (xy 179.020684 -205.804053)
			(xy 179.028501 -205.74215) (xy 179.044028 -205.681719) (xy 179.067022 -205.623716) (xy 179.097117 -205.56906)
			(xy 179.133837 -205.518615) (xy 179.176601 -205.473181) (xy 179.224732 -205.433476) (xy 179.250848 -205.416404)
			(xy 179.261008 -205.4098) (xy 179.2732 -205.389988) (xy 179.282598 -205.285848) (xy 179.274216 -205.264258)
			(xy 179.265326 -205.255876) (xy 179.247016 -205.238386) (xy 179.214941 -205.199202) (xy 179.188528 -205.156)
			(xy 179.168271 -205.10959) (xy 179.154554 -205.060847) (xy 179.147632 -205.010685) (xy 179.147216 -204.985366)
			(xy 179.14762 -204.960017) (xy 179.154557 -204.909797) (xy 179.16831 -204.861) (xy 179.188618 -204.814548)
			(xy 179.2151 -204.771317) (xy 179.247255 -204.732121) (xy 179.26558 -204.714602) (xy 179.27447 -204.706474)
			(xy 179.282852 -204.68463) (xy 179.2732 -204.58049) (xy 179.261008 -204.560678) (xy 179.250848 -204.554328)
			(xy 179.22473 -204.537238) (xy 179.17661 -204.497483) (xy 179.133857 -204.452007) (xy 179.097144 -204.401527)
			(xy 179.067052 -204.346842) (xy 179.044056 -204.288815) (xy 179.02852 -204.228361) (xy 179.020688 -204.166437)
			(xy 179.020216 -204.135228) (xy 179.020705 -204.104065) (xy 179.028517 -204.042231) (xy 179.044017 -203.981863)
			(xy 179.06696 -203.923915) (xy 179.096986 -203.869298) (xy 179.13362 -203.818876) (xy 179.176285 -203.773442)
			(xy 179.224307 -203.733714) (xy 179.276931 -203.700319) (xy 179.333325 -203.673782) (xy 179.3926 -203.654522)
			(xy 179.453821 -203.642843) (xy 179.516024 -203.63893) (xy 179.578227 -203.642843) (xy 179.639448 -203.654522)
			(xy 179.698723 -203.673782) (xy 179.755117 -203.700319) (xy 179.807741 -203.733714) (xy 179.855763 -203.773442)
			(xy 179.898428 -203.818876) (xy 179.935062 -203.869298) (xy 179.965088 -203.923915) (xy 179.988031 -203.981863)
			(xy 180.003531 -204.042231) (xy 180.011343 -204.104065) (xy 180.011832 -204.135228) (xy 180.011339 -204.166437)
			(xy 180.003517 -204.228362) (xy 179.987988 -204.288816) (xy 179.964996 -204.346845) (xy 179.934906 -204.40153)
			(xy 179.898193 -204.452008) (xy 179.855437 -204.497481) (xy 179.807313 -204.537231) (xy 179.7812 -204.554328)
			(xy 179.77104 -204.560678) (xy 179.758848 -204.58049) (xy 179.749196 -204.68463) (xy 179.757578 -204.706474)
			(xy 179.766468 -204.714602) (xy 179.784782 -204.73213) (xy 179.816927 -204.77133) (xy 179.843402 -204.814561)
			(xy 179.863708 -204.861011) (xy 179.877464 -204.909803) (xy 179.884409 -204.960019) (xy 179.884832 -204.985366)
			(xy 179.884422 -205.010684) (xy 179.877499 -205.060844) (xy 179.863776 -205.109585) (xy 179.843514 -205.15599)
			(xy 179.817092 -205.199186) (xy 179.785008 -205.238361) (xy 179.766722 -205.255876) (xy 179.757832 -205.264258)
			(xy 179.74945 -205.285848) (xy 179.758848 -205.389988) (xy 179.77104 -205.4098) (xy 179.7812 -205.416404)
			(xy 179.807307 -205.433485) (xy 179.855424 -205.473201) (xy 179.898177 -205.51864) (xy 179.934891 -205.569085)
			(xy 179.964985 -205.623737) (xy 179.987984 -205.681734) (xy 180.003523 -205.742158) (xy 180.011358 -205.804055)
			(xy 180.011832 -205.83525) (xy 180.011356 -205.866459) (xy 180.003531 -205.928385) (xy 179.987999 -205.98884)
			(xy 179.965005 -206.046868) (xy 179.934913 -206.101554) (xy 179.898198 -206.152032) (xy 179.855439 -206.197504)
			(xy 179.807314 -206.237253) (xy 179.7812 -206.25435) (xy 179.77104 -206.2607) (xy 179.758848 -206.280512)
			(xy 179.749196 -206.384652) (xy 179.757578 -206.406496) (xy 179.766468 -206.414624) (xy 179.784793 -206.432141)
			(xy 179.816937 -206.471343) (xy 179.84341 -206.514577) (xy 179.863715 -206.561029) (xy 179.877468 -206.609823)
			(xy 179.884411 -206.66004) (xy 179.884832 -206.685388) (xy 179.884437 -206.710706) (xy 179.87751 -206.760867)
			(xy 179.863785 -206.809609) (xy 179.84352 -206.856014) (xy 179.817095 -206.899209) (xy 179.785009 -206.938383)
			(xy 179.766722 -206.955898) (xy 179.757832 -206.96428) (xy 179.74945 -206.98587) (xy 179.758848 -207.09001)
			(xy 179.77104 -207.109822) (xy 179.7812 -207.116426) (xy 179.807317 -207.133493) (xy 179.855434 -207.17321)
			(xy 179.898187 -207.218652) (xy 179.9349 -207.269098) (xy 179.964993 -207.323753) (xy 179.987989 -207.381752)
			(xy 180.003527 -207.442178) (xy 180.011359 -207.504076) (xy 180.011832 -207.535272) (xy 180.011373 -207.566482)
			(xy 180.003546 -207.628408) (xy 179.988011 -207.688864) (xy 179.965015 -207.746892) (xy 179.93492 -207.801577)
			(xy 179.898202 -207.852055) (xy 179.855442 -207.897527) (xy 179.807315 -207.937276) (xy 179.7812 -207.954372)
			(xy 179.77104 -207.960722) (xy 179.758848 -207.980534) (xy 179.749196 -208.084674) (xy 179.757578 -208.106518)
			(xy 179.766468 -208.114646) (xy 179.784804 -208.132153) (xy 179.816947 -208.171357) (xy 179.843419 -208.214593)
			(xy 179.863721 -208.261047) (xy 179.877472 -208.309843) (xy 179.884412 -208.360062) (xy 179.884832 -208.38541)
			(xy 183.120284 -208.38541) (xy 183.120721 -208.3542) (xy 183.128551 -208.292272) (xy 183.144089 -208.231816)
			(xy 183.167088 -208.173787) (xy 183.197186 -208.119101) (xy 183.233906 -208.068624) (xy 183.27667 -208.023153)
			(xy 183.3248 -207.983406) (xy 183.350916 -207.96631) (xy 183.361076 -207.95996) (xy 183.373268 -207.940148)
			(xy 183.38292 -207.836008) (xy 183.374538 -207.814164) (xy 183.365648 -207.806036) (xy 183.347355 -207.788486)
			(xy 183.315208 -207.749292) (xy 183.28873 -207.706065) (xy 183.268419 -207.65962) (xy 183.254659 -207.610831)
			(xy 183.247709 -207.560618) (xy 183.247284 -207.535272) (xy 183.247745 -207.509956) (xy 183.254663 -207.459799)
			(xy 183.268377 -207.41106) (xy 183.28863 -207.364656) (xy 183.315041 -207.321458) (xy 183.347113 -207.28228)
			(xy 183.365394 -207.264762) (xy 183.374284 -207.25638) (xy 183.382666 -207.23479) (xy 183.373268 -207.13065)
			(xy 183.361076 -207.110838) (xy 183.350916 -207.104234) (xy 183.32483 -207.087122) (xy 183.276712 -207.047411)
			(xy 183.233957 -207.001977) (xy 183.197241 -206.951537) (xy 183.167145 -206.896889) (xy 183.144143 -206.838896)
			(xy 183.1286 -206.778475) (xy 183.12076 -206.716582) (xy 183.120284 -206.685388) (xy 183.120782 -206.654179)
			(xy 183.128602 -206.592254) (xy 183.144131 -206.5318) (xy 183.167121 -206.473771) (xy 183.19721 -206.419085)
			(xy 183.233923 -206.368607) (xy 183.276679 -206.323134) (xy 183.324803 -206.283385) (xy 183.350916 -206.266288)
			(xy 183.361076 -206.259938) (xy 183.373268 -206.240126) (xy 183.38292 -206.135986) (xy 183.374538 -206.114142)
			(xy 183.365648 -206.106014) (xy 183.347344 -206.088475) (xy 183.315198 -206.049278) (xy 183.288721 -206.006049)
			(xy 183.268413 -205.959602) (xy 183.254655 -205.910811) (xy 183.247708 -205.860596) (xy 183.247284 -205.83525)
			(xy 183.24773 -205.809934) (xy 183.25465 -205.759776) (xy 183.268367 -205.711037) (xy 183.288623 -205.664632)
			(xy 183.315037 -205.621435) (xy 183.347112 -205.582257) (xy 183.365394 -205.56474) (xy 183.374284 -205.556358)
			(xy 183.382666 -205.534768) (xy 183.373268 -205.430628) (xy 183.361076 -205.410816) (xy 183.350916 -205.404212)
			(xy 183.32482 -205.387114) (xy 183.276702 -205.347402) (xy 183.233948 -205.301965) (xy 183.197233 -205.251523)
			(xy 183.167137 -205.196873) (xy 183.144137 -205.138878) (xy 183.128596 -205.078455) (xy 183.120759 -205.01656)
			(xy 183.120284 -204.985366) (xy 183.120765 -204.954157) (xy 183.128588 -204.892231) (xy 183.144119 -204.831776)
			(xy 183.167112 -204.773747) (xy 183.197203 -204.719062) (xy 183.233918 -204.668584) (xy 183.276677 -204.623111)
			(xy 183.324802 -204.583362) (xy 183.350916 -204.566266) (xy 183.361076 -204.559916) (xy 183.373268 -204.540104)
			(xy 183.38292 -204.435964) (xy 183.374538 -204.41412) (xy 183.365648 -204.405992) (xy 183.347334 -204.388464)
			(xy 183.315188 -204.349264) (xy 183.288713 -204.306033) (xy 183.268406 -204.259584) (xy 183.254651 -204.210791)
			(xy 183.247706 -204.160575) (xy 183.247284 -204.135228) (xy 183.247716 -204.109911) (xy 183.254639 -204.059753)
			(xy 183.268359 -204.011013) (xy 183.288617 -203.964609) (xy 183.315033 -203.921412) (xy 183.347111 -203.882235)
			(xy 183.365394 -203.864718) (xy 183.374284 -203.856336) (xy 183.382666 -203.834746) (xy 183.373268 -203.730606)
			(xy 183.361076 -203.710794) (xy 183.350916 -203.70419) (xy 183.32481 -203.687107) (xy 183.276692 -203.647392)
			(xy 183.233938 -203.601954) (xy 183.197224 -203.551509) (xy 183.16713 -203.496857) (xy 183.144131 -203.43886)
			(xy 183.128592 -203.378436) (xy 183.120758 -203.316539) (xy 183.120284 -203.285344) (xy 183.120773 -203.254181)
			(xy 183.128585 -203.192347) (xy 183.144085 -203.131979) (xy 183.167028 -203.074031) (xy 183.197054 -203.019414)
			(xy 183.233688 -202.968992) (xy 183.276353 -202.923558) (xy 183.324375 -202.88383) (xy 183.376999 -202.850435)
			(xy 183.433393 -202.823898) (xy 183.492668 -202.804638) (xy 183.553889 -202.792959) (xy 183.616092 -202.789046)
			(xy 183.678295 -202.792959) (xy 183.739516 -202.804638) (xy 183.798791 -202.823898) (xy 183.855185 -202.850435)
			(xy 183.907809 -202.88383) (xy 183.955831 -202.923558) (xy 183.998496 -202.968992) (xy 184.03513 -203.019414)
			(xy 184.065156 -203.074031) (xy 184.088099 -203.131979) (xy 184.103599 -203.192347) (xy 184.111411 -203.254181)
			(xy 184.1119 -203.285344) (xy 188.075077 -203.285344) (xy 188.079012 -203.231573) (xy 188.090735 -203.178949)
			(xy 188.109995 -203.128592) (xy 188.136381 -203.081575) (xy 188.169333 -203.038902) (xy 188.208146 -203.001481)
			(xy 188.251994 -202.970111) (xy 188.299942 -202.945459) (xy 188.350969 -202.928051) (xy 188.403987 -202.918258)
			(xy 188.457866 -202.916289) (xy 188.511457 -202.922186) (xy 188.563618 -202.935822) (xy 188.613238 -202.956909)
			(xy 188.659259 -202.984995) (xy 188.700701 -203.019483) (xy 188.736679 -203.059637) (xy 188.766427 -203.104601)
			(xy 188.789312 -203.153418) (xy 188.804844 -203.205047) (xy 188.812694 -203.258387) (xy 188.813186 -203.285344)
			(xy 188.812694 -203.312301) (xy 188.804844 -203.365641) (xy 188.789312 -203.41727) (xy 188.766427 -203.466087)
			(xy 188.736679 -203.511051) (xy 188.700701 -203.551205) (xy 188.659259 -203.585693) (xy 188.613238 -203.613779)
			(xy 188.563618 -203.634866) (xy 188.511457 -203.648502) (xy 188.457866 -203.654399) (xy 188.403987 -203.65243)
			(xy 188.350969 -203.642637) (xy 188.299942 -203.625229) (xy 188.251994 -203.600577) (xy 188.208146 -203.569207)
			(xy 188.169333 -203.531786) (xy 188.136381 -203.489113) (xy 188.109995 -203.442096) (xy 188.090735 -203.391739)
			(xy 188.079012 -203.339115) (xy 188.075077 -203.285344) (xy 184.1119 -203.285344) (xy 184.11142 -203.316541)
			(xy 184.103604 -203.378443) (xy 184.088078 -203.438873) (xy 184.065086 -203.496876) (xy 184.034992 -203.551532)
			(xy 183.998274 -203.601977) (xy 183.955512 -203.647412) (xy 183.907383 -203.687117) (xy 183.881268 -203.70419)
			(xy 183.871108 -203.710794) (xy 183.858916 -203.730606) (xy 183.849518 -203.834746) (xy 183.8579 -203.856336)
			(xy 183.86679 -203.864718) (xy 183.8851 -203.882208) (xy 183.917174 -203.921392) (xy 183.943588 -203.964595)
			(xy 183.963844 -204.011004) (xy 183.977562 -204.059748) (xy 183.984484 -204.109909) (xy 183.9849 -204.135228)
			(xy 183.984487 -204.160576) (xy 183.977551 -204.210796) (xy 183.9638 -204.259592) (xy 183.943493 -204.306044)
			(xy 183.917013 -204.349276) (xy 183.88486 -204.388472) (xy 183.866536 -204.405992) (xy 183.857646 -204.41412)
			(xy 183.849264 -204.435964) (xy 183.858916 -204.540104) (xy 183.871108 -204.559916) (xy 183.881268 -204.566266)
			(xy 183.907364 -204.583389) (xy 183.955487 -204.623137) (xy 183.998245 -204.668606) (xy 184.034961 -204.719081)
			(xy 184.065056 -204.773761) (xy 184.088055 -204.831785) (xy 184.103593 -204.892236) (xy 184.111427 -204.954158)
			(xy 184.1119 -204.985366) (xy 184.111437 -205.016563) (xy 184.103619 -205.078466) (xy 184.08809 -205.138897)
			(xy 184.065095 -205.1969) (xy 184.034999 -205.251556) (xy 183.998279 -205.302) (xy 183.955514 -205.347435)
			(xy 183.907383 -205.387139) (xy 183.881268 -205.404212) (xy 183.871108 -205.410816) (xy 183.858916 -205.430628)
			(xy 183.849518 -205.534768) (xy 183.8579 -205.556358) (xy 183.86679 -205.56474) (xy 183.885062 -205.582268)
			(xy 183.91714 -205.621444) (xy 183.943558 -205.664638) (xy 183.963821 -205.71104) (xy 183.977547 -205.759777)
			(xy 183.984478 -205.809934) (xy 183.9849 -205.83525) (xy 183.984502 -205.860599) (xy 183.977563 -205.91082)
			(xy 183.963809 -205.959616) (xy 183.943499 -206.006068) (xy 183.917017 -206.049299) (xy 183.884861 -206.088494)
			(xy 183.866536 -206.106014) (xy 183.857646 -206.114142) (xy 183.849264 -206.135986) (xy 183.858916 -206.240126)
			(xy 183.871108 -206.259938) (xy 183.881268 -206.266288) (xy 183.907374 -206.283397) (xy 183.955497 -206.323146)
			(xy 183.998254 -206.368618) (xy 184.03497 -206.419094) (xy 184.065064 -206.473777) (xy 184.088061 -206.531803)
			(xy 184.103597 -206.592256) (xy 184.111428 -206.65418) (xy 184.1119 -206.685388) (xy 184.111454 -206.716586)
			(xy 184.103633 -206.778489) (xy 184.088101 -206.838921) (xy 184.065104 -206.896923) (xy 184.035006 -206.95158)
			(xy 183.998283 -207.002024) (xy 183.955517 -207.047458) (xy 183.907384 -207.087162) (xy 183.881268 -207.104234)
			(xy 183.871108 -207.110838) (xy 183.858916 -207.13065) (xy 183.849518 -207.23479) (xy 183.8579 -207.25638)
			(xy 183.86679 -207.264762) (xy 183.885073 -207.282279) (xy 183.91715 -207.321457) (xy 183.943567 -207.364654)
			(xy 183.963827 -207.411058) (xy 183.977551 -207.459797) (xy 183.98448 -207.509955) (xy 183.9849 -207.535272)
			(xy 183.98445 -207.560619) (xy 183.977521 -207.610838) (xy 183.963778 -207.659633) (xy 183.943478 -207.706085)
			(xy 183.917004 -207.749318) (xy 183.884857 -207.788515) (xy 183.866536 -207.806036) (xy 183.857646 -207.814164)
			(xy 183.849264 -207.836008) (xy 183.858916 -207.940148) (xy 183.871108 -207.95996) (xy 183.881268 -207.96631)
			(xy 183.907384 -207.983404) (xy 183.955507 -208.023155) (xy 183.998264 -208.06863) (xy 184.034978 -208.119108)
			(xy 184.065071 -208.173793) (xy 184.088066 -208.231821) (xy 184.103601 -208.292275) (xy 184.11143 -208.354201)
			(xy 184.1119 -208.38541) (xy 184.111411 -208.416573) (xy 184.103599 -208.478407) (xy 184.088099 -208.538775)
			(xy 184.065156 -208.596723) (xy 184.03513 -208.65134) (xy 183.998496 -208.701762) (xy 183.955831 -208.747196)
			(xy 183.907809 -208.786924) (xy 183.855185 -208.820319) (xy 183.798791 -208.846856) (xy 183.739516 -208.866116)
			(xy 183.678295 -208.877795) (xy 183.616092 -208.881708) (xy 183.553889 -208.877795) (xy 183.492668 -208.866116)
			(xy 183.433393 -208.846856) (xy 183.376999 -208.820319) (xy 183.324375 -208.786924) (xy 183.276353 -208.747196)
			(xy 183.233688 -208.701762) (xy 183.197054 -208.65134) (xy 183.167028 -208.596723) (xy 183.144085 -208.538775)
			(xy 183.128585 -208.478407) (xy 183.120773 -208.416573) (xy 183.120284 -208.38541) (xy 179.884832 -208.38541)
			(xy 179.884452 -208.410729) (xy 179.877522 -208.460891) (xy 179.863794 -208.509632) (xy 179.843526 -208.556037)
			(xy 179.817099 -208.599233) (xy 179.785011 -208.638406) (xy 179.766722 -208.65592) (xy 179.757832 -208.664302)
			(xy 179.74945 -208.685892) (xy 179.758848 -208.790032) (xy 179.77104 -208.809844) (xy 179.7812 -208.816448)
			(xy 179.807327 -208.8335) (xy 179.855444 -208.87322) (xy 179.898197 -208.918663) (xy 179.934909 -208.969112)
			(xy 179.965 -209.023769) (xy 179.987995 -209.08177) (xy 180.003531 -209.142198) (xy 180.011361 -209.204098)
			(xy 180.011832 -209.235294) (xy 181.862491 -209.235294) (xy 181.866426 -209.181523) (xy 181.878149 -209.128899)
			(xy 181.897409 -209.078542) (xy 181.923795 -209.031525) (xy 181.956747 -208.988852) (xy 181.99556 -208.951431)
			(xy 182.039408 -208.920061) (xy 182.087356 -208.895409) (xy 182.138383 -208.878001) (xy 182.191401 -208.868208)
			(xy 182.24528 -208.866239) (xy 182.298871 -208.872136) (xy 182.351032 -208.885772) (xy 182.400652 -208.906859)
			(xy 182.446673 -208.934945) (xy 182.488115 -208.969433) (xy 182.524093 -209.009587) (xy 182.553841 -209.054551)
			(xy 182.576726 -209.103368) (xy 182.592258 -209.154997) (xy 182.600108 -209.208337) (xy 182.6006 -209.235294)
			(xy 186.56427 -209.235294) (xy 186.564716 -209.204096) (xy 186.572538 -209.142193) (xy 186.588071 -209.081763)
			(xy 186.611069 -209.02376) (xy 186.641167 -208.969105) (xy 186.677889 -208.91866) (xy 186.720655 -208.873226)
			(xy 186.768786 -208.833521) (xy 186.794902 -208.816448) (xy 186.805062 -208.809844) (xy 186.817254 -208.790032)
			(xy 186.826652 -208.685892) (xy 186.81827 -208.664302) (xy 186.80938 -208.65592) (xy 186.791101 -208.638398)
			(xy 186.759022 -208.599222) (xy 186.732603 -208.556027) (xy 186.712341 -208.509624) (xy 186.698617 -208.460885)
			(xy 186.691689 -208.410727) (xy 186.69127 -208.38541) (xy 186.691718 -208.360063) (xy 186.698648 -208.309845)
			(xy 186.712393 -208.26105) (xy 186.732694 -208.214598) (xy 186.759167 -208.171365) (xy 186.791313 -208.132167)
			(xy 186.809634 -208.114646) (xy 186.818524 -208.106518) (xy 186.826906 -208.084674) (xy 186.817254 -207.980534)
			(xy 186.805062 -207.960722) (xy 186.794902 -207.954372) (xy 186.768771 -207.937301) (xy 186.720649 -207.897545)
			(xy 186.677894 -207.852067) (xy 186.641181 -207.801585) (xy 186.611091 -207.746897) (xy 186.588098 -207.688866)
			(xy 186.572566 -207.628409) (xy 186.564739 -207.566482) (xy 186.56427 -207.535272) (xy 186.564699 -207.504074)
			(xy 186.572524 -207.44217) (xy 186.588059 -207.381739) (xy 186.611059 -207.323737) (xy 186.64116 -207.269081)
			(xy 186.677884 -207.218637) (xy 186.720652 -207.173203) (xy 186.768785 -207.133499) (xy 186.794902 -207.116426)
			(xy 186.805062 -207.109822) (xy 186.817254 -207.09001) (xy 186.826652 -206.98587) (xy 186.81827 -206.96428)
			(xy 186.80938 -206.955898) (xy 186.791091 -206.938386) (xy 186.759012 -206.899209) (xy 186.732594 -206.856011)
			(xy 186.712334 -206.809606) (xy 186.698613 -206.760865) (xy 186.691688 -206.710706) (xy 186.69127 -206.685388)
			(xy 186.691703 -206.66004) (xy 186.698636 -206.609822) (xy 186.712384 -206.561026) (xy 186.732687 -206.514575)
			(xy 186.759163 -206.471342) (xy 186.791312 -206.432145) (xy 186.809634 -206.414624) (xy 186.818524 -206.406496)
			(xy 186.826906 -206.384652) (xy 186.817254 -206.280512) (xy 186.805062 -206.2607) (xy 186.794902 -206.25435)
			(xy 186.768807 -206.237226) (xy 186.720685 -206.197478) (xy 186.677928 -206.152008) (xy 186.641212 -206.101534)
			(xy 186.611117 -206.046853) (xy 186.588118 -205.988829) (xy 186.572579 -205.928379) (xy 186.564744 -205.866458)
			(xy 186.56427 -205.83525) (xy 186.56476 -205.804054) (xy 186.572575 -205.742153) (xy 186.588101 -205.681723)
			(xy 186.611092 -205.623721) (xy 186.641185 -205.569065) (xy 186.677901 -205.51862) (xy 186.720662 -205.473184)
			(xy 186.768789 -205.433478) (xy 186.794902 -205.416404) (xy 186.805062 -205.4098) (xy 186.817254 -205.389988)
			(xy 186.826652 -205.285848) (xy 186.81827 -205.264258) (xy 186.80938 -205.255876) (xy 186.79108 -205.238375)
			(xy 186.759002 -205.199195) (xy 186.732586 -205.155995) (xy 186.712328 -205.109588) (xy 186.698609 -205.060845)
			(xy 186.691686 -205.010684) (xy 186.69127 -204.985366) (xy 186.691688 -204.960018) (xy 186.698625 -204.909799)
			(xy 186.712375 -204.861003) (xy 186.732681 -204.814551) (xy 186.75916 -204.771319) (xy 186.791311 -204.732123)
			(xy 186.809634 -204.714602) (xy 186.818524 -204.706474) (xy 186.826906 -204.68463) (xy 186.817254 -204.58049)
			(xy 186.805062 -204.560678) (xy 186.794902 -204.554328) (xy 186.768797 -204.537219) (xy 186.720675 -204.497469)
			(xy 186.677919 -204.451996) (xy 186.641204 -204.40152) (xy 186.61111 -204.346837) (xy 186.588113 -204.288811)
			(xy 186.572575 -204.22836) (xy 186.564743 -204.166436) (xy 186.56427 -204.135228) (xy 186.564759 -204.104065)
			(xy 186.572571 -204.042231) (xy 186.588071 -203.981863) (xy 186.611014 -203.923915) (xy 186.64104 -203.869298)
			(xy 186.677674 -203.818876) (xy 186.720339 -203.773442) (xy 186.768361 -203.733714) (xy 186.820985 -203.700319)
			(xy 186.877379 -203.673782) (xy 186.936654 -203.654522) (xy 186.997875 -203.642843) (xy 187.060078 -203.63893)
			(xy 187.122281 -203.642843) (xy 187.183502 -203.654522) (xy 187.242777 -203.673782) (xy 187.299171 -203.700319)
			(xy 187.351795 -203.733714) (xy 187.399817 -203.773442) (xy 187.442482 -203.818876) (xy 187.479116 -203.869298)
			(xy 187.509142 -203.923915) (xy 187.532085 -203.981863) (xy 187.547585 -204.042231) (xy 187.555397 -204.104065)
			(xy 187.555886 -204.135228) (xy 187.555414 -204.166438) (xy 187.547591 -204.228364) (xy 187.53206 -204.28882)
			(xy 187.509067 -204.34685) (xy 187.478974 -204.401535) (xy 187.442257 -204.452013) (xy 187.399497 -204.497485)
			(xy 187.351369 -204.537232) (xy 187.325254 -204.554328) (xy 187.315094 -204.560678) (xy 187.302902 -204.58049)
			(xy 187.29325 -204.68463) (xy 187.301632 -204.706474) (xy 187.310522 -204.714602) (xy 187.328847 -204.73212)
			(xy 187.360988 -204.771323) (xy 187.387461 -204.814557) (xy 187.407765 -204.861008) (xy 187.421519 -204.909802)
			(xy 187.428464 -204.960019) (xy 187.428886 -204.985366) (xy 187.42846 -205.010683) (xy 187.421537 -205.060842)
			(xy 187.407817 -205.109582) (xy 187.387557 -205.155987) (xy 187.361139 -205.199184) (xy 187.32906 -205.23836)
			(xy 187.310776 -205.255876) (xy 187.301886 -205.264258) (xy 187.293504 -205.285848) (xy 187.302902 -205.389988)
			(xy 187.315094 -205.4098) (xy 187.325254 -205.416404) (xy 187.351351 -205.433501) (xy 187.39947 -205.473213)
			(xy 187.442225 -205.518649) (xy 187.478941 -205.569091) (xy 187.509036 -205.623742) (xy 187.532036 -205.681737)
			(xy 187.547577 -205.74216) (xy 187.555412 -205.804055) (xy 187.555886 -205.83525) (xy 187.555431 -205.86646)
			(xy 187.547606 -205.928388) (xy 187.532072 -205.988844) (xy 187.509076 -206.046873) (xy 187.47898 -206.101559)
			(xy 187.442262 -206.152036) (xy 187.399499 -206.197508) (xy 187.35137 -206.237255) (xy 187.325254 -206.25435)
			(xy 187.315094 -206.2607) (xy 187.302902 -206.280512) (xy 187.29325 -206.384652) (xy 187.301632 -206.406496)
			(xy 187.310522 -206.414624) (xy 187.328857 -206.432131) (xy 187.360998 -206.471336) (xy 187.387469 -206.514573)
			(xy 187.407771 -206.561026) (xy 187.421523 -206.609821) (xy 187.428465 -206.66004) (xy 187.428886 -206.685388)
			(xy 187.428474 -206.710706) (xy 187.421549 -206.760865) (xy 187.407826 -206.809606) (xy 187.387563 -206.85601)
			(xy 187.361143 -206.899207) (xy 187.329061 -206.938382) (xy 187.310776 -206.955898) (xy 187.301886 -206.96428)
			(xy 187.293504 -206.98587) (xy 187.302902 -207.09001) (xy 187.315094 -207.109822) (xy 187.325254 -207.116426)
			(xy 187.351361 -207.133509) (xy 187.39948 -207.173222) (xy 187.442234 -207.21866) (xy 187.478949 -207.269105)
			(xy 187.509044 -207.323757) (xy 187.532042 -207.381755) (xy 187.54758 -207.44218) (xy 187.555413 -207.504077)
			(xy 187.555886 -207.535272) (xy 187.555449 -207.566483) (xy 187.54762 -207.628411) (xy 187.532084 -207.688867)
			(xy 187.509085 -207.746897) (xy 187.478987 -207.801583) (xy 187.442266 -207.85206) (xy 187.399502 -207.897531)
			(xy 187.351371 -207.937277) (xy 187.325254 -207.954372) (xy 187.315094 -207.960722) (xy 187.302902 -207.980534)
			(xy 187.29325 -208.084674) (xy 187.301632 -208.106518) (xy 187.310522 -208.114646) (xy 187.328868 -208.132142)
			(xy 187.361008 -208.17135) (xy 187.387477 -208.214589) (xy 187.407778 -208.261044) (xy 187.421527 -208.309841)
			(xy 187.428467 -208.360061) (xy 187.428886 -208.38541) (xy 190.664338 -208.38541) (xy 190.66475 -208.354199)
			(xy 190.672581 -208.292269) (xy 190.68812 -208.231811) (xy 190.711122 -208.173781) (xy 190.741224 -208.119095)
			(xy 190.777949 -208.068618) (xy 190.820717 -208.023148) (xy 190.868852 -207.983404) (xy 190.89497 -207.96631)
			(xy 190.90513 -207.95996) (xy 190.917322 -207.940148) (xy 190.926974 -207.836008) (xy 190.918592 -207.814164)
			(xy 190.909702 -207.806036) (xy 190.8914 -207.788495) (xy 190.859256 -207.749298) (xy 190.83278 -207.706069)
			(xy 190.812471 -207.659622) (xy 190.798713 -207.610832) (xy 190.791763 -207.560618) (xy 190.791338 -207.535272)
			(xy 190.791782 -207.509955) (xy 190.798701 -207.459797) (xy 190.812417 -207.411057) (xy 190.832673 -207.364652)
			(xy 190.859088 -207.321455) (xy 190.891165 -207.282279) (xy 190.909448 -207.264762) (xy 190.918338 -207.25638)
			(xy 190.92672 -207.23479) (xy 190.917322 -207.13065) (xy 190.90513 -207.110838) (xy 190.89497 -207.104234)
			(xy 190.868873 -207.087138) (xy 190.820758 -207.047423) (xy 190.778005 -207.001986) (xy 190.741291 -206.951543)
			(xy 190.711196 -206.896893) (xy 190.688195 -206.838898) (xy 190.672653 -206.778477) (xy 190.664814 -206.716582)
			(xy 190.664338 -206.685388) (xy 190.664811 -206.654178) (xy 190.672632 -206.592251) (xy 190.688162 -206.531795)
			(xy 190.711156 -206.473765) (xy 190.741249 -206.419079) (xy 190.777965 -206.368601) (xy 190.820726 -206.32313)
			(xy 190.868855 -206.283383) (xy 190.89497 -206.266288) (xy 190.90513 -206.259938) (xy 190.917322 -206.240126)
			(xy 190.926974 -206.135986) (xy 190.918592 -206.114142) (xy 190.909702 -206.106014) (xy 190.89139 -206.088484)
			(xy 190.859246 -206.049284) (xy 190.832771 -206.006053) (xy 190.812465 -205.959604) (xy 190.798709 -205.910812)
			(xy 190.791762 -205.860597) (xy 190.791338 -205.83525) (xy 190.791768 -205.809933) (xy 190.798689 -205.759774)
			(xy 190.812408 -205.711033) (xy 190.832667 -205.664629) (xy 190.859084 -205.621432) (xy 190.891164 -205.582256)
			(xy 190.909448 -205.56474) (xy 190.918338 -205.556358) (xy 190.92672 -205.534768) (xy 190.917322 -205.430628)
			(xy 190.90513 -205.410816) (xy 190.89497 -205.404212) (xy 190.868863 -205.38713) (xy 190.820748 -205.347414)
			(xy 190.777995 -205.301974) (xy 190.741282 -205.251529) (xy 190.711188 -205.196877) (xy 190.68819 -205.138881)
			(xy 190.672649 -205.078457) (xy 190.664813 -205.016561) (xy 190.664338 -204.985366) (xy 190.664794 -204.954156)
			(xy 190.672618 -204.892228) (xy 190.688151 -204.831771) (xy 190.711146 -204.773741) (xy 190.741242 -204.719055)
			(xy 190.777961 -204.668578) (xy 190.820723 -204.623107) (xy 190.868854 -204.583361) (xy 190.89497 -204.566266)
			(xy 190.90513 -204.559916) (xy 190.917322 -204.540104) (xy 190.926974 -204.435964) (xy 190.918592 -204.41412)
			(xy 190.909702 -204.405992) (xy 190.891379 -204.388473) (xy 190.859236 -204.34927) (xy 190.832763 -204.306037)
			(xy 190.812458 -204.259586) (xy 190.798704 -204.210792) (xy 190.79176 -204.160575) (xy 190.791338 -204.135228)
			(xy 190.791753 -204.10991) (xy 190.798677 -204.059751) (xy 190.812399 -204.01101) (xy 190.832661 -203.964605)
			(xy 190.859081 -203.921409) (xy 190.891163 -203.882234) (xy 190.909448 -203.864718) (xy 190.918338 -203.856336)
			(xy 190.92672 -203.834746) (xy 190.917322 -203.730606) (xy 190.90513 -203.710794) (xy 190.89497 -203.70419)
			(xy 190.868853 -203.687123) (xy 190.820738 -203.647404) (xy 190.777986 -203.601962) (xy 190.741273 -203.551516)
			(xy 190.711181 -203.496861) (xy 190.688184 -203.438863) (xy 190.672646 -203.378437) (xy 190.664812 -203.31654)
			(xy 190.664338 -203.285344) (xy 190.664827 -203.254181) (xy 190.672639 -203.192347) (xy 190.688139 -203.131979)
			(xy 190.711082 -203.074031) (xy 190.741108 -203.019414) (xy 190.777742 -202.968992) (xy 190.820407 -202.923558)
			(xy 190.868429 -202.88383) (xy 190.921053 -202.850435) (xy 190.977447 -202.823898) (xy 191.036722 -202.804638)
			(xy 191.097943 -202.792959) (xy 191.160146 -202.789046) (xy 191.222349 -202.792959) (xy 191.28357 -202.804638)
			(xy 191.342845 -202.823898) (xy 191.399239 -202.850435) (xy 191.451863 -202.88383) (xy 191.499885 -202.923558)
			(xy 191.54255 -202.968992) (xy 191.579184 -203.019414) (xy 191.60921 -203.074031) (xy 191.632153 -203.131979)
			(xy 191.647653 -203.192347) (xy 191.655465 -203.254181) (xy 191.655954 -203.285344) (xy 195.619131 -203.285344)
			(xy 195.623066 -203.231573) (xy 195.634789 -203.178949) (xy 195.654049 -203.128592) (xy 195.680435 -203.081575)
			(xy 195.713387 -203.038902) (xy 195.7522 -203.001481) (xy 195.796048 -202.970111) (xy 195.843996 -202.945459)
			(xy 195.895023 -202.928051) (xy 195.948041 -202.918258) (xy 196.00192 -202.916289) (xy 196.055511 -202.922186)
			(xy 196.107672 -202.935822) (xy 196.157292 -202.956909) (xy 196.203313 -202.984995) (xy 196.244755 -203.019483)
			(xy 196.280733 -203.059637) (xy 196.310481 -203.104601) (xy 196.333366 -203.153418) (xy 196.348898 -203.205047)
			(xy 196.356748 -203.258387) (xy 196.35724 -203.285344) (xy 196.356748 -203.312301) (xy 196.348898 -203.365641)
			(xy 196.333366 -203.41727) (xy 196.310481 -203.466087) (xy 196.280733 -203.511051) (xy 196.244755 -203.551205)
			(xy 196.203313 -203.585693) (xy 196.157292 -203.613779) (xy 196.107672 -203.634866) (xy 196.055511 -203.648502)
			(xy 196.00192 -203.654399) (xy 195.948041 -203.65243) (xy 195.895023 -203.642637) (xy 195.843996 -203.625229)
			(xy 195.796048 -203.600577) (xy 195.7522 -203.569207) (xy 195.713387 -203.531786) (xy 195.680435 -203.489113)
			(xy 195.654049 -203.442096) (xy 195.634789 -203.391739) (xy 195.623066 -203.339115) (xy 195.619131 -203.285344)
			(xy 191.655954 -203.285344) (xy 191.655449 -203.31654) (xy 191.647634 -203.37844) (xy 191.63211 -203.438869)
			(xy 191.60912 -203.49687) (xy 191.579031 -203.551526) (xy 191.542316 -203.601971) (xy 191.499558 -203.647407)
			(xy 191.451434 -203.687115) (xy 191.425322 -203.70419) (xy 191.415162 -203.710794) (xy 191.40297 -203.730606)
			(xy 191.393572 -203.834746) (xy 191.401954 -203.856336) (xy 191.410844 -203.864718) (xy 191.429146 -203.882217)
			(xy 191.461222 -203.921398) (xy 191.487638 -203.964598) (xy 191.507895 -204.011006) (xy 191.521615 -204.059749)
			(xy 191.528538 -204.10991) (xy 191.528954 -204.135228) (xy 191.528556 -204.160577) (xy 191.521619 -204.210798)
			(xy 191.507866 -204.259595) (xy 191.487556 -204.306047) (xy 191.461073 -204.349279) (xy 191.428916 -204.388473)
			(xy 191.41059 -204.405992) (xy 191.4017 -204.41412) (xy 191.393318 -204.435964) (xy 191.40297 -204.540104)
			(xy 191.415162 -204.559916) (xy 191.425322 -204.566266) (xy 191.45143 -204.58337) (xy 191.499551 -204.623122)
			(xy 191.542307 -204.668596) (xy 191.579021 -204.719073) (xy 191.609114 -204.773756) (xy 191.632111 -204.831782)
			(xy 191.647649 -204.892234) (xy 191.655481 -204.954158) (xy 191.655954 -204.985366) (xy 191.655466 -205.016562)
			(xy 191.647649 -205.078463) (xy 191.632121 -205.138892) (xy 191.60913 -205.196894) (xy 191.579037 -205.25155)
			(xy 191.542321 -205.301995) (xy 191.499561 -205.34743) (xy 191.451435 -205.387138) (xy 191.425322 -205.404212)
			(xy 191.415162 -205.410816) (xy 191.40297 -205.430628) (xy 191.393572 -205.534768) (xy 191.401954 -205.556358)
			(xy 191.410844 -205.56474) (xy 191.429108 -205.582277) (xy 191.461188 -205.62145) (xy 191.487608 -205.664642)
			(xy 191.507873 -205.711042) (xy 191.5216 -205.759778) (xy 191.528532 -205.809934) (xy 191.528954 -205.83525)
			(xy 191.52857 -205.8606) (xy 191.52163 -205.910821) (xy 191.507875 -205.959619) (xy 191.487562 -206.006071)
			(xy 191.461076 -206.049302) (xy 191.428917 -206.088496) (xy 191.41059 -206.106014) (xy 191.4017 -206.114142)
			(xy 191.393318 -206.135986) (xy 191.40297 -206.240126) (xy 191.415162 -206.259938) (xy 191.425322 -206.266288)
			(xy 191.45144 -206.283378) (xy 191.499561 -206.323132) (xy 191.542316 -206.368607) (xy 191.579029 -206.419087)
			(xy 191.609121 -206.473772) (xy 191.632117 -206.5318) (xy 191.647652 -206.592254) (xy 191.655483 -206.654179)
			(xy 191.655954 -206.685388) (xy 191.655483 -206.716585) (xy 191.647663 -206.778486) (xy 191.632133 -206.838916)
			(xy 191.609139 -206.896918) (xy 191.579044 -206.951573) (xy 191.542326 -207.002018) (xy 191.499564 -207.047453)
			(xy 191.451436 -207.08716) (xy 191.425322 -207.104234) (xy 191.415162 -207.110838) (xy 191.40297 -207.13065)
			(xy 191.393572 -207.23479) (xy 191.401954 -207.25638) (xy 191.410844 -207.264762) (xy 191.429118 -207.282288)
			(xy 191.461197 -207.321463) (xy 191.487617 -207.364658) (xy 191.507879 -207.41106) (xy 191.521604 -207.459798)
			(xy 191.528534 -207.509955) (xy 191.528954 -207.535272) (xy 191.528518 -207.56062) (xy 191.521589 -207.610839)
			(xy 191.507843 -207.659636) (xy 191.487541 -207.706088) (xy 191.461064 -207.74932) (xy 191.428913 -207.788516)
			(xy 191.41059 -207.806036) (xy 191.4017 -207.814164) (xy 191.393318 -207.836008) (xy 191.40297 -207.940148)
			(xy 191.415162 -207.95996) (xy 191.425322 -207.96631) (xy 191.45145 -207.983385) (xy 191.499571 -208.023141)
			(xy 191.542326 -208.068619) (xy 191.579038 -208.1191) (xy 191.609129 -208.173788) (xy 191.632123 -208.231818)
			(xy 191.647656 -208.292274) (xy 191.655484 -208.3542) (xy 191.655954 -208.38541) (xy 191.655465 -208.416573)
			(xy 191.647653 -208.478407) (xy 191.632153 -208.538775) (xy 191.60921 -208.596723) (xy 191.579184 -208.65134)
			(xy 191.54255 -208.701762) (xy 191.499885 -208.747196) (xy 191.451863 -208.786924) (xy 191.399239 -208.820319)
			(xy 191.342845 -208.846856) (xy 191.28357 -208.866116) (xy 191.222349 -208.877795) (xy 191.160146 -208.881708)
			(xy 191.097943 -208.877795) (xy 191.036722 -208.866116) (xy 190.977447 -208.846856) (xy 190.921053 -208.820319)
			(xy 190.868429 -208.786924) (xy 190.820407 -208.747196) (xy 190.777742 -208.701762) (xy 190.741108 -208.65134)
			(xy 190.711082 -208.596723) (xy 190.688139 -208.538775) (xy 190.672639 -208.478407) (xy 190.664827 -208.416573)
			(xy 190.664338 -208.38541) (xy 187.428886 -208.38541) (xy 187.428489 -208.410728) (xy 187.42156 -208.460888)
			(xy 187.407834 -208.509629) (xy 187.387569 -208.556034) (xy 187.361146 -208.59923) (xy 187.329062 -208.638404)
			(xy 187.310776 -208.65592) (xy 187.301886 -208.664302) (xy 187.293504 -208.685892) (xy 187.302902 -208.790032)
			(xy 187.315094 -208.809844) (xy 187.325254 -208.816448) (xy 187.351371 -208.833516) (xy 187.39949 -208.873232)
			(xy 187.442244 -208.918672) (xy 187.478958 -208.969118) (xy 187.509051 -209.023773) (xy 187.532048 -209.081773)
			(xy 187.547584 -209.142199) (xy 187.555415 -209.204098) (xy 187.555886 -209.235294) (xy 189.406545 -209.235294)
			(xy 189.41048 -209.181523) (xy 189.422203 -209.128899) (xy 189.441463 -209.078542) (xy 189.467849 -209.031525)
			(xy 189.500801 -208.988852) (xy 189.539614 -208.951431) (xy 189.583462 -208.920061) (xy 189.63141 -208.895409)
			(xy 189.682437 -208.878001) (xy 189.735455 -208.868208) (xy 189.789334 -208.866239) (xy 189.842925 -208.872136)
			(xy 189.895086 -208.885772) (xy 189.944706 -208.906859) (xy 189.990727 -208.934945) (xy 190.032169 -208.969433)
			(xy 190.068147 -209.009587) (xy 190.097895 -209.054551) (xy 190.12078 -209.103368) (xy 190.136312 -209.154997)
			(xy 190.144162 -209.208337) (xy 190.144654 -209.235294) (xy 194.108324 -209.235294) (xy 194.108745 -209.204095)
			(xy 194.116568 -209.14219) (xy 194.132103 -209.081758) (xy 194.155103 -209.023755) (xy 194.185205 -208.969098)
			(xy 194.221931 -208.918655) (xy 194.264702 -208.873222) (xy 194.312838 -208.833519) (xy 194.338956 -208.816448)
			(xy 194.349116 -208.809844) (xy 194.361308 -208.790032) (xy 194.370706 -208.685892) (xy 194.362324 -208.664302)
			(xy 194.353434 -208.65592) (xy 194.335147 -208.638407) (xy 194.30307 -208.599228) (xy 194.276653 -208.556031)
			(xy 194.256393 -208.509626) (xy 194.24267 -208.460886) (xy 194.235743 -208.410727) (xy 194.235324 -208.38541)
			(xy 194.235755 -208.360062) (xy 194.242686 -208.309843) (xy 194.256433 -208.261047) (xy 194.276737 -208.214594)
			(xy 194.303214 -208.171362) (xy 194.335365 -208.132166) (xy 194.353688 -208.114646) (xy 194.362578 -208.106518)
			(xy 194.37096 -208.084674) (xy 194.361308 -207.980534) (xy 194.349116 -207.960722) (xy 194.338956 -207.954372)
			(xy 194.312814 -207.937317) (xy 194.264694 -207.897557) (xy 194.221941 -207.852076) (xy 194.18523 -207.801591)
			(xy 194.155142 -207.746901) (xy 194.13215 -207.688869) (xy 194.116619 -207.628411) (xy 194.108793 -207.566482)
			(xy 194.108324 -207.535272) (xy 194.108728 -207.504073) (xy 194.116554 -207.442167) (xy 194.132091 -207.381734)
			(xy 194.155094 -207.323731) (xy 194.185198 -207.269075) (xy 194.221927 -207.218631) (xy 194.264699 -207.173199)
			(xy 194.312837 -207.133497) (xy 194.338956 -207.116426) (xy 194.349116 -207.109822) (xy 194.361308 -207.09001)
			(xy 194.370706 -206.98587) (xy 194.362324 -206.96428) (xy 194.353434 -206.955898) (xy 194.335136 -206.938395)
			(xy 194.30306 -206.899215) (xy 194.276644 -206.856015) (xy 194.256386 -206.809608) (xy 194.242666 -206.760866)
			(xy 194.235741 -206.710706) (xy 194.235324 -206.685388) (xy 194.23574 -206.66004) (xy 194.242674 -206.609819)
			(xy 194.256424 -206.561023) (xy 194.276731 -206.514571) (xy 194.30321 -206.471339) (xy 194.335364 -206.432144)
			(xy 194.353688 -206.414624) (xy 194.362578 -206.406496) (xy 194.37096 -206.384652) (xy 194.361308 -206.280512)
			(xy 194.349116 -206.2607) (xy 194.338956 -206.25435) (xy 194.31285 -206.237243) (xy 194.26473 -206.19749)
			(xy 194.221975 -206.152017) (xy 194.185261 -206.10154) (xy 194.155168 -206.046857) (xy 194.132171 -205.988832)
			(xy 194.116632 -205.928381) (xy 194.108798 -205.866458) (xy 194.108324 -205.83525) (xy 194.108789 -205.804053)
			(xy 194.116605 -205.74215) (xy 194.132133 -205.681718) (xy 194.155127 -205.623715) (xy 194.185223 -205.569059)
			(xy 194.221944 -205.518614) (xy 194.264708 -205.47318) (xy 194.31284 -205.433476) (xy 194.338956 -205.416404)
			(xy 194.349116 -205.4098) (xy 194.361308 -205.389988) (xy 194.370706 -205.285848) (xy 194.362324 -205.264258)
			(xy 194.353434 -205.255876) (xy 194.335125 -205.238384) (xy 194.30305 -205.199201) (xy 194.276636 -205.155999)
			(xy 194.25638 -205.10959) (xy 194.242662 -205.060846) (xy 194.23574 -205.010685) (xy 194.235324 -204.985366)
			(xy 194.235725 -204.960017) (xy 194.242663 -204.909796) (xy 194.256416 -204.861) (xy 194.276725 -204.814548)
			(xy 194.303207 -204.771316) (xy 194.335363 -204.732121) (xy 194.353688 -204.714602) (xy 194.362578 -204.706474)
			(xy 194.37096 -204.68463) (xy 194.361308 -204.58049) (xy 194.349116 -204.560678) (xy 194.338956 -204.554328)
			(xy 194.31284 -204.537235) (xy 194.26472 -204.497481) (xy 194.221966 -204.452005) (xy 194.185253 -204.401526)
			(xy 194.155161 -204.346841) (xy 194.132165 -204.288814) (xy 194.116628 -204.228361) (xy 194.108796 -204.166437)
			(xy 194.108324 -204.135228) (xy 194.108813 -204.104065) (xy 194.116625 -204.042231) (xy 194.132125 -203.981863)
			(xy 194.155068 -203.923915) (xy 194.185094 -203.869298) (xy 194.221728 -203.818876) (xy 194.264393 -203.773442)
			(xy 194.312415 -203.733714) (xy 194.365039 -203.700319) (xy 194.421433 -203.673782) (xy 194.480708 -203.654522)
			(xy 194.541929 -203.642843) (xy 194.604132 -203.63893) (xy 194.666335 -203.642843) (xy 194.727556 -203.654522)
			(xy 194.786831 -203.673782) (xy 194.843225 -203.700319) (xy 194.895849 -203.733714) (xy 194.943871 -203.773442)
			(xy 194.986536 -203.818876) (xy 195.02317 -203.869298) (xy 195.053196 -203.923915) (xy 195.076139 -203.981863)
			(xy 195.091639 -204.042231) (xy 195.099451 -204.104065) (xy 195.09994 -204.135228) (xy 195.099443 -204.166437)
			(xy 195.091621 -204.228361) (xy 195.076092 -204.288816) (xy 195.053101 -204.346844) (xy 195.023012 -204.401529)
			(xy 194.986299 -204.452007) (xy 194.943543 -204.497481) (xy 194.895421 -204.537231) (xy 194.869308 -204.554328)
			(xy 194.859148 -204.560678) (xy 194.846956 -204.58049) (xy 194.837304 -204.68463) (xy 194.845686 -204.706474)
			(xy 194.854576 -204.714602) (xy 194.872892 -204.732129) (xy 194.905036 -204.771329) (xy 194.931511 -204.814561)
			(xy 194.951817 -204.86101) (xy 194.965572 -204.909803) (xy 194.972517 -204.960019) (xy 194.97294 -204.985366)
			(xy 194.972528 -205.010684) (xy 194.965604 -205.060844) (xy 194.951882 -205.109585) (xy 194.93162 -205.15599)
			(xy 194.905199 -205.199186) (xy 194.873116 -205.23836) (xy 194.85483 -205.255876) (xy 194.84594 -205.264258)
			(xy 194.837558 -205.285848) (xy 194.846956 -205.389988) (xy 194.859148 -205.4098) (xy 194.869308 -205.416404)
			(xy 194.895417 -205.433483) (xy 194.943534 -205.473199) (xy 194.986287 -205.518639) (xy 195.023 -205.569084)
			(xy 195.053094 -205.623737) (xy 195.076092 -205.681734) (xy 195.091631 -205.742158) (xy 195.099466 -205.804055)
			(xy 195.09994 -205.83525) (xy 195.09946 -205.866459) (xy 195.091636 -205.928385) (xy 195.076104 -205.988839)
			(xy 195.053111 -206.046868) (xy 195.023019 -206.101553) (xy 194.986304 -206.152031) (xy 194.943546 -206.197504)
			(xy 194.895422 -206.237253) (xy 194.869308 -206.25435) (xy 194.859148 -206.2607) (xy 194.846956 -206.280512)
			(xy 194.837304 -206.384652) (xy 194.845686 -206.406496) (xy 194.854576 -206.414624) (xy 194.872903 -206.43214)
			(xy 194.905046 -206.471342) (xy 194.931519 -206.514577) (xy 194.951823 -206.561028) (xy 194.965576 -206.609823)
			(xy 194.972519 -206.66004) (xy 194.97294 -206.685388) (xy 194.972543 -206.710706) (xy 194.965616 -206.760867)
			(xy 194.951891 -206.809608) (xy 194.931626 -206.856013) (xy 194.905202 -206.899209) (xy 194.873117 -206.938383)
			(xy 194.85483 -206.955898) (xy 194.84594 -206.96428) (xy 194.837558 -206.98587) (xy 194.846956 -207.09001)
			(xy 194.859148 -207.109822) (xy 194.869308 -207.116426) (xy 194.895427 -207.13349) (xy 194.943544 -207.173208)
			(xy 194.986296 -207.21865) (xy 195.023009 -207.269097) (xy 195.053101 -207.323753) (xy 195.076098 -207.381752)
			(xy 195.091635 -207.442178) (xy 195.099467 -207.504076) (xy 195.09994 -207.535272) (xy 195.099478 -207.566482)
			(xy 195.09165 -207.628408) (xy 195.076116 -207.688863) (xy 195.05312 -207.746891) (xy 195.023026 -207.801577)
			(xy 194.986309 -207.852054) (xy 194.943549 -207.897527) (xy 194.895422 -207.937275) (xy 194.869308 -207.954372)
			(xy 194.859148 -207.960722) (xy 194.846956 -207.980534) (xy 194.837304 -208.084674) (xy 194.845686 -208.106518)
			(xy 194.854576 -208.114646) (xy 194.872913 -208.132151) (xy 194.905056 -208.171356) (xy 194.931527 -208.214592)
			(xy 194.95183 -208.261046) (xy 194.96558 -208.309842) (xy 194.97252 -208.360062) (xy 194.97294 -208.38541)
			(xy 198.208392 -208.38541) (xy 198.208825 -208.354199) (xy 198.216656 -208.292271) (xy 198.232193 -208.231815)
			(xy 198.255193 -208.173786) (xy 198.285291 -208.1191) (xy 198.322013 -208.068623) (xy 198.364777 -208.023152)
			(xy 198.412908 -207.983405) (xy 198.439024 -207.96631) (xy 198.449184 -207.95996) (xy 198.461376 -207.940148)
			(xy 198.471028 -207.836008) (xy 198.462646 -207.814164) (xy 198.453756 -207.806036) (xy 198.435464 -207.788485)
			(xy 198.403317 -207.749291) (xy 198.376838 -207.706064) (xy 198.356528 -207.659619) (xy 198.342768 -207.610831)
			(xy 198.335817 -207.560618) (xy 198.335392 -207.535272) (xy 198.335851 -207.509956) (xy 198.342768 -207.459799)
			(xy 198.356483 -207.41106) (xy 198.376736 -207.364655) (xy 198.403148 -207.321458) (xy 198.435221 -207.28228)
			(xy 198.453502 -207.264762) (xy 198.462392 -207.25638) (xy 198.470774 -207.23479) (xy 198.461376 -207.13065)
			(xy 198.449184 -207.110838) (xy 198.439024 -207.104234) (xy 198.41294 -207.087119) (xy 198.364822 -207.047409)
			(xy 198.322066 -207.001975) (xy 198.28535 -206.951536) (xy 198.255253 -206.896888) (xy 198.232251 -206.838895)
			(xy 198.216708 -206.778475) (xy 198.208868 -206.716582) (xy 198.208392 -206.685388) (xy 198.208886 -206.654179)
			(xy 198.216707 -206.592254) (xy 198.232235 -206.531799) (xy 198.255226 -206.47377) (xy 198.285316 -206.419084)
			(xy 198.322029 -206.368606) (xy 198.364786 -206.323133) (xy 198.412911 -206.283385) (xy 198.439024 -206.266288)
			(xy 198.449184 -206.259938) (xy 198.461376 -206.240126) (xy 198.471028 -206.135986) (xy 198.462646 -206.114142)
			(xy 198.453756 -206.106014) (xy 198.435454 -206.088473) (xy 198.403307 -206.049277) (xy 198.37683 -206.006048)
			(xy 198.356521 -205.959601) (xy 198.342763 -205.910811) (xy 198.335816 -205.860596) (xy 198.335392 -205.83525)
			(xy 198.335836 -205.809933) (xy 198.342756 -205.759776) (xy 198.356473 -205.711036) (xy 198.376729 -205.664631)
			(xy 198.403144 -205.621434) (xy 198.43522 -205.582257) (xy 198.453502 -205.56474) (xy 198.462392 -205.556358)
			(xy 198.470774 -205.534768) (xy 198.461376 -205.430628) (xy 198.449184 -205.410816) (xy 198.439024 -205.404212)
			(xy 198.41293 -205.387112) (xy 198.364812 -205.3474) (xy 198.322057 -205.301964) (xy 198.285342 -205.251522)
			(xy 198.255246 -205.196872) (xy 198.232245 -205.138877) (xy 198.216704 -205.078455) (xy 198.208867 -205.01656)
			(xy 198.208392 -204.985366) (xy 198.208869 -204.954157) (xy 198.216692 -204.892231) (xy 198.232223 -204.831775)
			(xy 198.255217 -204.773746) (xy 198.285309 -204.719061) (xy 198.322025 -204.668583) (xy 198.364784 -204.62311)
			(xy 198.41291 -204.583362) (xy 198.439024 -204.566266) (xy 198.449184 -204.559916) (xy 198.461376 -204.540104)
			(xy 198.471028 -204.435964) (xy 198.462646 -204.41412) (xy 198.453756 -204.405992) (xy 198.435443 -204.388462)
			(xy 198.403297 -204.349263) (xy 198.376822 -204.306032) (xy 198.356515 -204.259583) (xy 198.342759 -204.210791)
			(xy 198.335814 -204.160575) (xy 198.335392 -204.135228) (xy 198.335821 -204.109911) (xy 198.342744 -204.059752)
			(xy 198.356464 -204.011013) (xy 198.376723 -203.964608) (xy 198.40314 -203.921411) (xy 198.435218 -203.882235)
			(xy 198.453502 -203.864718) (xy 198.462392 -203.856336) (xy 198.470774 -203.834746) (xy 198.461376 -203.730606)
			(xy 198.449184 -203.710794) (xy 198.439024 -203.70419) (xy 198.41292 -203.687104) (xy 198.364802 -203.64739)
			(xy 198.322047 -203.601952) (xy 198.285333 -203.551508) (xy 198.255238 -203.496856) (xy 198.23224 -203.43886)
			(xy 198.2167 -203.378435) (xy 198.208866 -203.316539) (xy 198.208392 -203.285344) (xy 198.208881 -203.254181)
			(xy 198.216693 -203.192347) (xy 198.232193 -203.131979) (xy 198.255136 -203.074031) (xy 198.285162 -203.019414)
			(xy 198.321796 -202.968992) (xy 198.364461 -202.923558) (xy 198.412483 -202.88383) (xy 198.465107 -202.850435)
			(xy 198.521501 -202.823898) (xy 198.580776 -202.804638) (xy 198.641997 -202.792959) (xy 198.7042 -202.789046)
			(xy 198.766403 -202.792959) (xy 198.827624 -202.804638) (xy 198.886899 -202.823898) (xy 198.943293 -202.850435)
			(xy 198.995917 -202.88383) (xy 199.043939 -202.923558) (xy 199.086604 -202.968992) (xy 199.123238 -203.019414)
			(xy 199.153264 -203.074031) (xy 199.176207 -203.131979) (xy 199.191707 -203.192347) (xy 199.199519 -203.254181)
			(xy 199.200008 -203.285344) (xy 203.162931 -203.285344) (xy 203.166866 -203.231573) (xy 203.178589 -203.178949)
			(xy 203.197849 -203.128592) (xy 203.224235 -203.081575) (xy 203.257187 -203.038902) (xy 203.296 -203.001481)
			(xy 203.339848 -202.970111) (xy 203.387796 -202.945459) (xy 203.438823 -202.928051) (xy 203.491841 -202.918258)
			(xy 203.54572 -202.916289) (xy 203.599311 -202.922186) (xy 203.651472 -202.935822) (xy 203.701092 -202.956909)
			(xy 203.747113 -202.984995) (xy 203.788555 -203.019483) (xy 203.824533 -203.059637) (xy 203.854281 -203.104601)
			(xy 203.877166 -203.153418) (xy 203.892698 -203.205047) (xy 203.900548 -203.258387) (xy 203.90104 -203.285344)
			(xy 203.900548 -203.312301) (xy 203.892698 -203.365641) (xy 203.877166 -203.41727) (xy 203.854281 -203.466087)
			(xy 203.824533 -203.511051) (xy 203.788555 -203.551205) (xy 203.747113 -203.585693) (xy 203.701092 -203.613779)
			(xy 203.651472 -203.634866) (xy 203.599311 -203.648502) (xy 203.54572 -203.654399) (xy 203.491841 -203.65243)
			(xy 203.438823 -203.642637) (xy 203.387796 -203.625229) (xy 203.339848 -203.600577) (xy 203.296 -203.569207)
			(xy 203.257187 -203.531786) (xy 203.224235 -203.489113) (xy 203.197849 -203.442096) (xy 203.178589 -203.391739)
			(xy 203.166866 -203.339115) (xy 203.162931 -203.285344) (xy 199.200008 -203.285344) (xy 199.199524 -203.316541)
			(xy 199.191709 -203.378442) (xy 199.176182 -203.438873) (xy 199.153191 -203.496875) (xy 199.123098 -203.551531)
			(xy 199.08638 -203.601976) (xy 199.043619 -203.647411) (xy 198.99549 -203.687117) (xy 198.969376 -203.70419)
			(xy 198.959216 -203.710794) (xy 198.947024 -203.730606) (xy 198.937626 -203.834746) (xy 198.946008 -203.856336)
			(xy 198.954898 -203.864718) (xy 198.973191 -203.882226) (xy 199.00527 -203.921404) (xy 199.031688 -203.964602)
			(xy 199.051947 -204.011008) (xy 199.065668 -204.05975) (xy 199.072591 -204.10991) (xy 199.073008 -204.135228)
			(xy 199.072593 -204.160576) (xy 199.065657 -204.210796) (xy 199.051906 -204.259592) (xy 199.031599 -204.306044)
			(xy 199.00512 -204.349276) (xy 198.972968 -204.388472) (xy 198.954644 -204.405992) (xy 198.945754 -204.41412)
			(xy 198.937372 -204.435964) (xy 198.947024 -204.540104) (xy 198.959216 -204.559916) (xy 198.969376 -204.566266)
			(xy 198.995473 -204.583386) (xy 199.043596 -204.623135) (xy 199.086354 -204.668605) (xy 199.12307 -204.719079)
			(xy 199.153165 -204.773761) (xy 199.176163 -204.831785) (xy 199.191702 -204.892236) (xy 199.199535 -204.954158)
			(xy 199.200008 -204.985366) (xy 199.199541 -205.016563) (xy 199.191723 -205.078466) (xy 199.176194 -205.138896)
			(xy 199.1532 -205.196899) (xy 199.123105 -205.251555) (xy 199.086385 -205.301999) (xy 199.043621 -205.347434)
			(xy 198.995491 -205.387139) (xy 198.969376 -205.404212) (xy 198.959216 -205.410816) (xy 198.947024 -205.430628)
			(xy 198.937626 -205.534768) (xy 198.946008 -205.556358) (xy 198.954898 -205.56474) (xy 198.973153 -205.582286)
			(xy 199.005236 -205.621456) (xy 199.031658 -205.664646) (xy 199.051925 -205.711045) (xy 199.065653 -205.75978)
			(xy 199.072586 -205.809934) (xy 199.073008 -205.83525) (xy 199.072607 -205.860599) (xy 199.065668 -205.910819)
			(xy 199.051915 -205.959615) (xy 199.031605 -206.006067) (xy 199.005124 -206.049299) (xy 198.972969 -206.088494)
			(xy 198.954644 -206.106014) (xy 198.945754 -206.114142) (xy 198.937372 -206.135986) (xy 198.947024 -206.240126)
			(xy 198.959216 -206.259938) (xy 198.969376 -206.266288) (xy 198.995483 -206.283394) (xy 199.043606 -206.323144)
			(xy 199.086363 -206.368617) (xy 199.123078 -206.419093) (xy 199.153172 -206.473777) (xy 199.176169 -206.531803)
			(xy 199.191705 -206.592255) (xy 199.199536 -206.654179) (xy 199.200008 -206.685388) (xy 199.199558 -206.716586)
			(xy 199.191738 -206.778489) (xy 199.176206 -206.83892) (xy 199.15321 -206.896923) (xy 199.123112 -206.951579)
			(xy 199.08639 -207.002023) (xy 199.043624 -207.047457) (xy 198.995492 -207.087162) (xy 198.969376 -207.104234)
			(xy 198.959216 -207.110838) (xy 198.947024 -207.13065) (xy 198.937626 -207.23479) (xy 198.946008 -207.25638)
			(xy 198.954898 -207.264762) (xy 198.973164 -207.282297) (xy 199.005245 -207.321469) (xy 199.031667 -207.364662)
			(xy 199.051931 -207.411063) (xy 199.065657 -207.459799) (xy 199.072588 -207.509956) (xy 199.073008 -207.535272)
			(xy 199.072555 -207.560619) (xy 199.065627 -207.610837) (xy 199.051883 -207.659632) (xy 199.031584 -207.706084)
			(xy 199.005111 -207.749317) (xy 198.972965 -207.788515) (xy 198.954644 -207.806036) (xy 198.945754 -207.814164)
			(xy 198.937372 -207.836008) (xy 198.947024 -207.940148) (xy 198.959216 -207.95996) (xy 198.969376 -207.96631)
			(xy 198.995494 -207.983401) (xy 199.043616 -208.023153) (xy 199.086373 -208.068628) (xy 199.123087 -208.119107)
			(xy 199.15318 -208.173792) (xy 199.176175 -208.231821) (xy 199.191709 -208.292275) (xy 199.199538 -208.354201)
			(xy 199.200008 -208.38541) (xy 199.199519 -208.416573) (xy 199.191707 -208.478407) (xy 199.176207 -208.538775)
			(xy 199.153264 -208.596723) (xy 199.123238 -208.65134) (xy 199.086604 -208.701762) (xy 199.043939 -208.747196)
			(xy 198.995917 -208.786924) (xy 198.943293 -208.820319) (xy 198.886899 -208.846856) (xy 198.827624 -208.866116)
			(xy 198.766403 -208.877795) (xy 198.7042 -208.881708) (xy 198.641997 -208.877795) (xy 198.580776 -208.866116)
			(xy 198.521501 -208.846856) (xy 198.465107 -208.820319) (xy 198.412483 -208.786924) (xy 198.364461 -208.747196)
			(xy 198.321796 -208.701762) (xy 198.285162 -208.65134) (xy 198.255136 -208.596723) (xy 198.232193 -208.538775)
			(xy 198.216693 -208.478407) (xy 198.208881 -208.416573) (xy 198.208392 -208.38541) (xy 194.97294 -208.38541)
			(xy 194.972558 -208.410729) (xy 194.965628 -208.46089) (xy 194.9519 -208.509632) (xy 194.931633 -208.556037)
			(xy 194.905206 -208.599232) (xy 194.873118 -208.638406) (xy 194.85483 -208.65592) (xy 194.84594 -208.664302)
			(xy 194.837558 -208.685892) (xy 194.846956 -208.790032) (xy 194.859148 -208.809844) (xy 194.869308 -208.816448)
			(xy 194.895437 -208.833497) (xy 194.943554 -208.873218) (xy 194.986306 -208.918662) (xy 195.023017 -208.969111)
			(xy 195.053109 -209.023768) (xy 195.076104 -209.081769) (xy 195.091639 -209.142198) (xy 195.099469 -209.204097)
			(xy 195.09994 -209.235294) (xy 196.950599 -209.235294) (xy 196.954534 -209.181523) (xy 196.966257 -209.128899)
			(xy 196.985517 -209.078542) (xy 197.011903 -209.031525) (xy 197.044855 -208.988852) (xy 197.083668 -208.951431)
			(xy 197.127516 -208.920061) (xy 197.175464 -208.895409) (xy 197.226491 -208.878001) (xy 197.279509 -208.868208)
			(xy 197.333388 -208.866239) (xy 197.386979 -208.872136) (xy 197.43914 -208.885772) (xy 197.48876 -208.906859)
			(xy 197.534781 -208.934945) (xy 197.576223 -208.969433) (xy 197.612201 -209.009587) (xy 197.641949 -209.054551)
			(xy 197.664834 -209.103368) (xy 197.680366 -209.154997) (xy 197.688216 -209.208337) (xy 197.688708 -209.235294)
			(xy 201.652124 -209.235294) (xy 201.652545 -209.204095) (xy 201.660368 -209.14219) (xy 201.675903 -209.081758)
			(xy 201.698903 -209.023755) (xy 201.729005 -208.969098) (xy 201.765731 -208.918655) (xy 201.808502 -208.873222)
			(xy 201.856638 -208.833519) (xy 201.882756 -208.816448) (xy 201.892916 -208.809844) (xy 201.905108 -208.790032)
			(xy 201.914506 -208.685892) (xy 201.906124 -208.664302) (xy 201.897234 -208.65592) (xy 201.878947 -208.638407)
			(xy 201.84687 -208.599228) (xy 201.820453 -208.556031) (xy 201.800193 -208.509626) (xy 201.78647 -208.460886)
			(xy 201.779543 -208.410727) (xy 201.779124 -208.38541) (xy 201.779555 -208.360062) (xy 201.786486 -208.309843)
			(xy 201.800233 -208.261047) (xy 201.820537 -208.214594) (xy 201.847014 -208.171362) (xy 201.879165 -208.132166)
			(xy 201.897488 -208.114646) (xy 201.906378 -208.106518) (xy 201.91476 -208.084674) (xy 201.905108 -207.980534)
			(xy 201.892916 -207.960722) (xy 201.882756 -207.954372) (xy 201.856614 -207.937317) (xy 201.808494 -207.897557)
			(xy 201.765741 -207.852076) (xy 201.72903 -207.801591) (xy 201.698942 -207.746901) (xy 201.67595 -207.688869)
			(xy 201.660419 -207.628411) (xy 201.652593 -207.566482) (xy 201.652124 -207.535272) (xy 201.652528 -207.504073)
			(xy 201.660354 -207.442167) (xy 201.675891 -207.381734) (xy 201.698894 -207.323731) (xy 201.728998 -207.269075)
			(xy 201.765727 -207.218631) (xy 201.808499 -207.173199) (xy 201.856637 -207.133497) (xy 201.882756 -207.116426)
			(xy 201.892916 -207.109822) (xy 201.905108 -207.09001) (xy 201.914506 -206.98587) (xy 201.906124 -206.96428)
			(xy 201.897234 -206.955898) (xy 201.878936 -206.938395) (xy 201.84686 -206.899215) (xy 201.820444 -206.856015)
			(xy 201.800186 -206.809608) (xy 201.786466 -206.760866) (xy 201.779541 -206.710706) (xy 201.779124 -206.685388)
			(xy 201.77954 -206.66004) (xy 201.786474 -206.609819) (xy 201.800224 -206.561023) (xy 201.820531 -206.514571)
			(xy 201.84701 -206.471339) (xy 201.879164 -206.432144) (xy 201.897488 -206.414624) (xy 201.906378 -206.406496)
			(xy 201.91476 -206.384652) (xy 201.905108 -206.280512) (xy 201.892916 -206.2607) (xy 201.882756 -206.25435)
			(xy 201.85665 -206.237243) (xy 201.80853 -206.19749) (xy 201.765775 -206.152017) (xy 201.729061 -206.10154)
			(xy 201.698968 -206.046857) (xy 201.675971 -205.988832) (xy 201.660432 -205.928381) (xy 201.652598 -205.866458)
			(xy 201.652124 -205.83525) (xy 201.652589 -205.804053) (xy 201.660405 -205.74215) (xy 201.675933 -205.681718)
			(xy 201.698927 -205.623715) (xy 201.729023 -205.569059) (xy 201.765744 -205.518614) (xy 201.808508 -205.47318)
			(xy 201.85664 -205.433476) (xy 201.882756 -205.416404) (xy 201.892916 -205.4098) (xy 201.905108 -205.389988)
			(xy 201.914506 -205.285848) (xy 201.906124 -205.264258) (xy 201.897234 -205.255876) (xy 201.878925 -205.238384)
			(xy 201.84685 -205.199201) (xy 201.820436 -205.155999) (xy 201.80018 -205.10959) (xy 201.786462 -205.060846)
			(xy 201.77954 -205.010685) (xy 201.779124 -204.985366) (xy 201.779525 -204.960017) (xy 201.786463 -204.909796)
			(xy 201.800216 -204.861) (xy 201.820525 -204.814548) (xy 201.847007 -204.771316) (xy 201.879163 -204.732121)
			(xy 201.897488 -204.714602) (xy 201.906378 -204.706474) (xy 201.91476 -204.68463) (xy 201.905108 -204.58049)
			(xy 201.892916 -204.560678) (xy 201.882756 -204.554328) (xy 201.85664 -204.537235) (xy 201.80852 -204.497481)
			(xy 201.765766 -204.452005) (xy 201.729053 -204.401526) (xy 201.698961 -204.346841) (xy 201.675965 -204.288814)
			(xy 201.660428 -204.228361) (xy 201.652596 -204.166437) (xy 201.652124 -204.135228) (xy 201.652613 -204.104065)
			(xy 201.660425 -204.042231) (xy 201.675925 -203.981863) (xy 201.698868 -203.923915) (xy 201.728894 -203.869298)
			(xy 201.765528 -203.818876) (xy 201.808193 -203.773442) (xy 201.856215 -203.733714) (xy 201.908839 -203.700319)
			(xy 201.965233 -203.673782) (xy 202.024508 -203.654522) (xy 202.085729 -203.642843) (xy 202.147932 -203.63893)
			(xy 202.210135 -203.642843) (xy 202.271356 -203.654522) (xy 202.330631 -203.673782) (xy 202.387025 -203.700319)
			(xy 202.439649 -203.733714) (xy 202.487671 -203.773442) (xy 202.530336 -203.818876) (xy 202.56697 -203.869298)
			(xy 202.596996 -203.923915) (xy 202.619939 -203.981863) (xy 202.635439 -204.042231) (xy 202.643251 -204.104065)
			(xy 202.64374 -204.135228) (xy 202.643243 -204.166437) (xy 202.635421 -204.228361) (xy 202.619892 -204.288816)
			(xy 202.596901 -204.346844) (xy 202.566812 -204.401529) (xy 202.530099 -204.452007) (xy 202.487343 -204.497481)
			(xy 202.439221 -204.537231) (xy 202.413108 -204.554328) (xy 202.402948 -204.560678) (xy 202.390756 -204.58049)
			(xy 202.381104 -204.68463) (xy 202.389486 -204.706474) (xy 202.398376 -204.714602) (xy 202.416692 -204.732129)
			(xy 202.448836 -204.771329) (xy 202.475311 -204.814561) (xy 202.495617 -204.86101) (xy 202.509372 -204.909803)
			(xy 202.516317 -204.960019) (xy 202.51674 -204.985366) (xy 202.516328 -205.010684) (xy 202.509404 -205.060844)
			(xy 202.495682 -205.109585) (xy 202.47542 -205.15599) (xy 202.448999 -205.199186) (xy 202.416916 -205.23836)
			(xy 202.39863 -205.255876) (xy 202.38974 -205.264258) (xy 202.381358 -205.285848) (xy 202.390756 -205.389988)
			(xy 202.402948 -205.4098) (xy 202.413108 -205.416404) (xy 202.439217 -205.433483) (xy 202.487334 -205.473199)
			(xy 202.530087 -205.518639) (xy 202.5668 -205.569084) (xy 202.596894 -205.623737) (xy 202.619892 -205.681734)
			(xy 202.635431 -205.742158) (xy 202.643266 -205.804055) (xy 202.64374 -205.83525) (xy 202.64326 -205.866459)
			(xy 202.635436 -205.928385) (xy 202.619904 -205.988839) (xy 202.596911 -206.046868) (xy 202.566819 -206.101553)
			(xy 202.530104 -206.152031) (xy 202.487346 -206.197504) (xy 202.439222 -206.237253) (xy 202.413108 -206.25435)
			(xy 202.402948 -206.2607) (xy 202.390756 -206.280512) (xy 202.381104 -206.384652) (xy 202.389486 -206.406496)
			(xy 202.398376 -206.414624) (xy 202.416703 -206.43214) (xy 202.448846 -206.471342) (xy 202.475319 -206.514577)
			(xy 202.495623 -206.561028) (xy 202.509376 -206.609823) (xy 202.516319 -206.66004) (xy 202.51674 -206.685388)
			(xy 202.516343 -206.710706) (xy 202.509416 -206.760867) (xy 202.495691 -206.809608) (xy 202.475426 -206.856013)
			(xy 202.449002 -206.899209) (xy 202.416917 -206.938383) (xy 202.39863 -206.955898) (xy 202.38974 -206.96428)
			(xy 202.381358 -206.98587) (xy 202.390756 -207.09001) (xy 202.402948 -207.109822) (xy 202.413108 -207.116426)
			(xy 202.439227 -207.13349) (xy 202.487344 -207.173208) (xy 202.530096 -207.21865) (xy 202.566809 -207.269097)
			(xy 202.596901 -207.323753) (xy 202.619898 -207.381752) (xy 202.635435 -207.442178) (xy 202.643267 -207.504076)
			(xy 202.64374 -207.535272) (xy 202.643278 -207.566482) (xy 202.63545 -207.628408) (xy 202.619916 -207.688863)
			(xy 202.59692 -207.746891) (xy 202.566826 -207.801577) (xy 202.530109 -207.852054) (xy 202.487349 -207.897527)
			(xy 202.439222 -207.937275) (xy 202.413108 -207.954372) (xy 202.402948 -207.960722) (xy 202.390756 -207.980534)
			(xy 202.381104 -208.084674) (xy 202.389486 -208.106518) (xy 202.398376 -208.114646) (xy 202.416713 -208.132151)
			(xy 202.448856 -208.171356) (xy 202.475327 -208.214592) (xy 202.49563 -208.261046) (xy 202.50938 -208.309842)
			(xy 202.51632 -208.360062) (xy 202.51674 -208.38541) (xy 205.752192 -208.38541) (xy 205.752625 -208.354199)
			(xy 205.760456 -208.292271) (xy 205.775993 -208.231815) (xy 205.798993 -208.173786) (xy 205.829091 -208.1191)
			(xy 205.865813 -208.068623) (xy 205.908577 -208.023152) (xy 205.956708 -207.983405) (xy 205.982824 -207.96631)
			(xy 205.992984 -207.95996) (xy 206.005176 -207.940148) (xy 206.014828 -207.836008) (xy 206.006446 -207.814164)
			(xy 205.997556 -207.806036) (xy 205.979264 -207.788485) (xy 205.947117 -207.749291) (xy 205.920638 -207.706064)
			(xy 205.900328 -207.659619) (xy 205.886568 -207.610831) (xy 205.879617 -207.560618) (xy 205.879192 -207.535272)
			(xy 205.879651 -207.509956) (xy 205.886568 -207.459799) (xy 205.900283 -207.41106) (xy 205.920536 -207.364655)
			(xy 205.946948 -207.321458) (xy 205.979021 -207.28228) (xy 205.997302 -207.264762) (xy 206.006192 -207.25638)
			(xy 206.014574 -207.23479) (xy 206.005176 -207.13065) (xy 205.992984 -207.110838) (xy 205.982824 -207.104234)
			(xy 205.95674 -207.087119) (xy 205.908622 -207.047409) (xy 205.865866 -207.001975) (xy 205.82915 -206.951536)
			(xy 205.799053 -206.896888) (xy 205.776051 -206.838895) (xy 205.760508 -206.778475) (xy 205.752668 -206.716582)
			(xy 205.752192 -206.685388) (xy 205.752686 -206.654179) (xy 205.760507 -206.592254) (xy 205.776035 -206.531799)
			(xy 205.799026 -206.47377) (xy 205.829116 -206.419084) (xy 205.865829 -206.368606) (xy 205.908586 -206.323133)
			(xy 205.956711 -206.283385) (xy 205.982824 -206.266288) (xy 205.992984 -206.259938) (xy 206.005176 -206.240126)
			(xy 206.014828 -206.135986) (xy 206.006446 -206.114142) (xy 205.997556 -206.106014) (xy 205.979254 -206.088473)
			(xy 205.947107 -206.049277) (xy 205.92063 -206.006048) (xy 205.900321 -205.959601) (xy 205.886563 -205.910811)
			(xy 205.879616 -205.860596) (xy 205.879192 -205.83525) (xy 205.879636 -205.809933) (xy 205.886556 -205.759776)
			(xy 205.900273 -205.711036) (xy 205.920529 -205.664631) (xy 205.946944 -205.621434) (xy 205.97902 -205.582257)
			(xy 205.997302 -205.56474) (xy 206.006192 -205.556358) (xy 206.014574 -205.534768) (xy 206.005176 -205.430628)
			(xy 205.992984 -205.410816) (xy 205.982824 -205.404212) (xy 205.95673 -205.387112) (xy 205.908612 -205.3474)
			(xy 205.865857 -205.301964) (xy 205.829142 -205.251522) (xy 205.799046 -205.196872) (xy 205.776045 -205.138877)
			(xy 205.760504 -205.078455) (xy 205.752667 -205.01656) (xy 205.752192 -204.985366) (xy 205.752669 -204.954157)
			(xy 205.760492 -204.892231) (xy 205.776023 -204.831775) (xy 205.799017 -204.773746) (xy 205.829109 -204.719061)
			(xy 205.865825 -204.668583) (xy 205.908584 -204.62311) (xy 205.95671 -204.583362) (xy 205.982824 -204.566266)
			(xy 205.992984 -204.559916) (xy 206.005176 -204.540104) (xy 206.014828 -204.435964) (xy 206.006446 -204.41412)
			(xy 205.997556 -204.405992) (xy 205.979243 -204.388462) (xy 205.947097 -204.349263) (xy 205.920622 -204.306032)
			(xy 205.900315 -204.259583) (xy 205.886559 -204.210791) (xy 205.879614 -204.160575) (xy 205.879192 -204.135228)
			(xy 205.879621 -204.109911) (xy 205.886544 -204.059752) (xy 205.900264 -204.011013) (xy 205.920523 -203.964608)
			(xy 205.94694 -203.921411) (xy 205.979018 -203.882235) (xy 205.997302 -203.864718) (xy 206.006192 -203.856336)
			(xy 206.014574 -203.834746) (xy 206.005176 -203.730606) (xy 205.992984 -203.710794) (xy 205.982824 -203.70419)
			(xy 205.95672 -203.687104) (xy 205.908602 -203.64739) (xy 205.865847 -203.601952) (xy 205.829133 -203.551508)
			(xy 205.799038 -203.496856) (xy 205.77604 -203.43886) (xy 205.7605 -203.378435) (xy 205.752666 -203.316539)
			(xy 205.752192 -203.285344) (xy 205.752681 -203.254181) (xy 205.760493 -203.192347) (xy 205.775993 -203.131979)
			(xy 205.798936 -203.074031) (xy 205.828962 -203.019414) (xy 205.865596 -202.968992) (xy 205.908261 -202.923558)
			(xy 205.956283 -202.88383) (xy 206.008907 -202.850435) (xy 206.065301 -202.823898) (xy 206.124576 -202.804638)
			(xy 206.185797 -202.792959) (xy 206.248 -202.789046) (xy 206.310203 -202.792959) (xy 206.371424 -202.804638)
			(xy 206.430699 -202.823898) (xy 206.487093 -202.850435) (xy 206.539717 -202.88383) (xy 206.587739 -202.923558)
			(xy 206.630404 -202.968992) (xy 206.667038 -203.019414) (xy 206.697064 -203.074031) (xy 206.720007 -203.131979)
			(xy 206.735507 -203.192347) (xy 206.743319 -203.254181) (xy 206.743808 -203.285344) (xy 206.743324 -203.316541)
			(xy 206.735509 -203.378442) (xy 206.719982 -203.438873) (xy 206.696991 -203.496875) (xy 206.666898 -203.551531)
			(xy 206.63018 -203.601976) (xy 206.587419 -203.647411) (xy 206.53929 -203.687117) (xy 206.513176 -203.70419)
			(xy 206.503016 -203.710794) (xy 206.490824 -203.730606) (xy 206.481426 -203.834746) (xy 206.489808 -203.856336)
			(xy 206.498698 -203.864718) (xy 206.516991 -203.882226) (xy 206.54907 -203.921404) (xy 206.575488 -203.964602)
			(xy 206.595747 -204.011008) (xy 206.609468 -204.05975) (xy 206.616391 -204.10991) (xy 206.616808 -204.135228)
			(xy 206.616393 -204.160576) (xy 206.609457 -204.210796) (xy 206.595706 -204.259592) (xy 206.575399 -204.306044)
			(xy 206.54892 -204.349276) (xy 206.516768 -204.388472) (xy 206.498444 -204.405992) (xy 206.489554 -204.41412)
			(xy 206.481172 -204.435964) (xy 206.490824 -204.540104) (xy 206.503016 -204.559916) (xy 206.513176 -204.566266)
			(xy 206.539273 -204.583386) (xy 206.587396 -204.623135) (xy 206.630154 -204.668605) (xy 206.66687 -204.719079)
			(xy 206.696965 -204.773761) (xy 206.719963 -204.831785) (xy 206.735502 -204.892236) (xy 206.743335 -204.954158)
			(xy 206.743808 -204.985366) (xy 206.743341 -205.016563) (xy 206.735523 -205.078466) (xy 206.719994 -205.138896)
			(xy 206.697 -205.196899) (xy 206.666905 -205.251555) (xy 206.630185 -205.301999) (xy 206.587421 -205.347434)
			(xy 206.539291 -205.387139) (xy 206.513176 -205.404212) (xy 206.503016 -205.410816) (xy 206.490824 -205.430628)
			(xy 206.481426 -205.534768) (xy 206.489808 -205.556358) (xy 206.498698 -205.56474) (xy 206.516953 -205.582286)
			(xy 206.549036 -205.621456) (xy 206.575458 -205.664646) (xy 206.595725 -205.711045) (xy 206.609453 -205.75978)
			(xy 206.616386 -205.809934) (xy 206.616808 -205.83525) (xy 206.616407 -205.860599) (xy 206.609468 -205.910819)
			(xy 206.595715 -205.959615) (xy 206.575405 -206.006067) (xy 206.548924 -206.049299) (xy 206.516769 -206.088494)
			(xy 206.498444 -206.106014) (xy 206.489554 -206.114142) (xy 206.481172 -206.135986) (xy 206.490824 -206.240126)
			(xy 206.503016 -206.259938) (xy 206.513176 -206.266288) (xy 206.539283 -206.283394) (xy 206.587406 -206.323144)
			(xy 206.630163 -206.368617) (xy 206.666878 -206.419093) (xy 206.696972 -206.473777) (xy 206.719969 -206.531803)
			(xy 206.735505 -206.592255) (xy 206.743336 -206.654179) (xy 206.743808 -206.685388) (xy 206.743358 -206.716586)
			(xy 206.735538 -206.778489) (xy 206.720006 -206.83892) (xy 206.69701 -206.896923) (xy 206.666912 -206.951579)
			(xy 206.63019 -207.002023) (xy 206.587424 -207.047457) (xy 206.539292 -207.087162) (xy 206.513176 -207.104234)
			(xy 206.503016 -207.110838) (xy 206.490824 -207.13065) (xy 206.481426 -207.23479) (xy 206.489808 -207.25638)
			(xy 206.498698 -207.264762) (xy 206.516964 -207.282297) (xy 206.549045 -207.321469) (xy 206.575467 -207.364662)
			(xy 206.595731 -207.411063) (xy 206.609457 -207.459799) (xy 206.616388 -207.509956) (xy 206.616808 -207.535272)
			(xy 206.616355 -207.560619) (xy 206.609427 -207.610837) (xy 206.595683 -207.659632) (xy 206.575384 -207.706084)
			(xy 206.548911 -207.749317) (xy 206.516765 -207.788515) (xy 206.498444 -207.806036) (xy 206.489554 -207.814164)
			(xy 206.481172 -207.836008) (xy 206.490824 -207.940148) (xy 206.503016 -207.95996) (xy 206.513176 -207.96631)
			(xy 206.539294 -207.983401) (xy 206.587416 -208.023153) (xy 206.630173 -208.068628) (xy 206.666887 -208.119107)
			(xy 206.69698 -208.173792) (xy 206.719975 -208.231821) (xy 206.735509 -208.292275) (xy 206.743338 -208.354201)
			(xy 206.743808 -208.38541) (xy 206.743319 -208.416573) (xy 206.735507 -208.478407) (xy 206.720007 -208.538775)
			(xy 206.697064 -208.596723) (xy 206.667038 -208.65134) (xy 206.630404 -208.701762) (xy 206.587739 -208.747196)
			(xy 206.539717 -208.786924) (xy 206.487093 -208.820319) (xy 206.430699 -208.846856) (xy 206.371424 -208.866116)
			(xy 206.310203 -208.877795) (xy 206.248 -208.881708) (xy 206.185797 -208.877795) (xy 206.124576 -208.866116)
			(xy 206.065301 -208.846856) (xy 206.008907 -208.820319) (xy 205.956283 -208.786924) (xy 205.908261 -208.747196)
			(xy 205.865596 -208.701762) (xy 205.828962 -208.65134) (xy 205.798936 -208.596723) (xy 205.775993 -208.538775)
			(xy 205.760493 -208.478407) (xy 205.752681 -208.416573) (xy 205.752192 -208.38541) (xy 202.51674 -208.38541)
			(xy 202.516358 -208.410729) (xy 202.509428 -208.46089) (xy 202.4957 -208.509632) (xy 202.475433 -208.556037)
			(xy 202.449006 -208.599232) (xy 202.416918 -208.638406) (xy 202.39863 -208.65592) (xy 202.38974 -208.664302)
			(xy 202.381358 -208.685892) (xy 202.390756 -208.790032) (xy 202.402948 -208.809844) (xy 202.413108 -208.816448)
			(xy 202.439237 -208.833497) (xy 202.487354 -208.873218) (xy 202.530106 -208.918662) (xy 202.566817 -208.969111)
			(xy 202.596909 -209.023768) (xy 202.619904 -209.081769) (xy 202.635439 -209.142198) (xy 202.643269 -209.204097)
			(xy 202.64374 -209.235294) (xy 204.494399 -209.235294) (xy 204.498334 -209.181523) (xy 204.510057 -209.128899)
			(xy 204.529317 -209.078542) (xy 204.555703 -209.031525) (xy 204.588655 -208.988852) (xy 204.627468 -208.951431)
			(xy 204.671316 -208.920061) (xy 204.719264 -208.895409) (xy 204.770291 -208.878001) (xy 204.823309 -208.868208)
			(xy 204.877188 -208.866239) (xy 204.930779 -208.872136) (xy 204.98294 -208.885772) (xy 205.03256 -208.906859)
			(xy 205.078581 -208.934945) (xy 205.120023 -208.969433) (xy 205.156001 -209.009587) (xy 205.185749 -209.054551)
			(xy 205.208634 -209.103368) (xy 205.224166 -209.154997) (xy 205.232016 -209.208337) (xy 205.232508 -209.235294)
			(xy 205.232016 -209.262251) (xy 205.224166 -209.315591) (xy 205.208634 -209.36722) (xy 205.185749 -209.416037)
			(xy 205.156001 -209.461001) (xy 205.120023 -209.501155) (xy 205.078581 -209.535643) (xy 205.03256 -209.563729)
			(xy 204.98294 -209.584816) (xy 204.930779 -209.598452) (xy 204.877188 -209.604349) (xy 204.823309 -209.60238)
			(xy 204.770291 -209.592587) (xy 204.719264 -209.575179) (xy 204.671316 -209.550527) (xy 204.627468 -209.519157)
			(xy 204.588655 -209.481736) (xy 204.555703 -209.439063) (xy 204.529317 -209.392046) (xy 204.510057 -209.341689)
			(xy 204.498334 -209.289065) (xy 204.494399 -209.235294) (xy 202.64374 -209.235294) (xy 202.643251 -209.266457)
			(xy 202.635439 -209.328291) (xy 202.619939 -209.388659) (xy 202.596996 -209.446607) (xy 202.56697 -209.501224)
			(xy 202.530336 -209.551646) (xy 202.487671 -209.59708) (xy 202.439649 -209.636808) (xy 202.387025 -209.670203)
			(xy 202.330631 -209.69674) (xy 202.271356 -209.716) (xy 202.210135 -209.727679) (xy 202.147932 -209.731592)
			(xy 202.085729 -209.727679) (xy 202.024508 -209.716) (xy 201.965233 -209.69674) (xy 201.908839 -209.670203)
			(xy 201.856215 -209.636808) (xy 201.808193 -209.59708) (xy 201.765528 -209.551646) (xy 201.728894 -209.501224)
			(xy 201.698868 -209.446607) (xy 201.675925 -209.388659) (xy 201.660425 -209.328291) (xy 201.652613 -209.266457)
			(xy 201.652124 -209.235294) (xy 197.688708 -209.235294) (xy 197.688216 -209.262251) (xy 197.680366 -209.315591)
			(xy 197.664834 -209.36722) (xy 197.641949 -209.416037) (xy 197.612201 -209.461001) (xy 197.576223 -209.501155)
			(xy 197.534781 -209.535643) (xy 197.48876 -209.563729) (xy 197.43914 -209.584816) (xy 197.386979 -209.598452)
			(xy 197.333388 -209.604349) (xy 197.279509 -209.60238) (xy 197.226491 -209.592587) (xy 197.175464 -209.575179)
			(xy 197.127516 -209.550527) (xy 197.083668 -209.519157) (xy 197.044855 -209.481736) (xy 197.011903 -209.439063)
			(xy 196.985517 -209.392046) (xy 196.966257 -209.341689) (xy 196.954534 -209.289065) (xy 196.950599 -209.235294)
			(xy 195.09994 -209.235294) (xy 195.099451 -209.266457) (xy 195.091639 -209.328291) (xy 195.076139 -209.388659)
			(xy 195.053196 -209.446607) (xy 195.02317 -209.501224) (xy 194.986536 -209.551646) (xy 194.943871 -209.59708)
			(xy 194.895849 -209.636808) (xy 194.843225 -209.670203) (xy 194.786831 -209.69674) (xy 194.727556 -209.716)
			(xy 194.666335 -209.727679) (xy 194.604132 -209.731592) (xy 194.541929 -209.727679) (xy 194.480708 -209.716)
			(xy 194.421433 -209.69674) (xy 194.365039 -209.670203) (xy 194.312415 -209.636808) (xy 194.264393 -209.59708)
			(xy 194.221728 -209.551646) (xy 194.185094 -209.501224) (xy 194.155068 -209.446607) (xy 194.132125 -209.388659)
			(xy 194.116625 -209.328291) (xy 194.108813 -209.266457) (xy 194.108324 -209.235294) (xy 190.144654 -209.235294)
			(xy 190.144162 -209.262251) (xy 190.136312 -209.315591) (xy 190.12078 -209.36722) (xy 190.097895 -209.416037)
			(xy 190.068147 -209.461001) (xy 190.032169 -209.501155) (xy 189.990727 -209.535643) (xy 189.944706 -209.563729)
			(xy 189.895086 -209.584816) (xy 189.842925 -209.598452) (xy 189.789334 -209.604349) (xy 189.735455 -209.60238)
			(xy 189.682437 -209.592587) (xy 189.63141 -209.575179) (xy 189.583462 -209.550527) (xy 189.539614 -209.519157)
			(xy 189.500801 -209.481736) (xy 189.467849 -209.439063) (xy 189.441463 -209.392046) (xy 189.422203 -209.341689)
			(xy 189.41048 -209.289065) (xy 189.406545 -209.235294) (xy 187.555886 -209.235294) (xy 187.555397 -209.266457)
			(xy 187.547585 -209.328291) (xy 187.532085 -209.388659) (xy 187.509142 -209.446607) (xy 187.479116 -209.501224)
			(xy 187.442482 -209.551646) (xy 187.399817 -209.59708) (xy 187.351795 -209.636808) (xy 187.299171 -209.670203)
			(xy 187.242777 -209.69674) (xy 187.183502 -209.716) (xy 187.122281 -209.727679) (xy 187.060078 -209.731592)
			(xy 186.997875 -209.727679) (xy 186.936654 -209.716) (xy 186.877379 -209.69674) (xy 186.820985 -209.670203)
			(xy 186.768361 -209.636808) (xy 186.720339 -209.59708) (xy 186.677674 -209.551646) (xy 186.64104 -209.501224)
			(xy 186.611014 -209.446607) (xy 186.588071 -209.388659) (xy 186.572571 -209.328291) (xy 186.564759 -209.266457)
			(xy 186.56427 -209.235294) (xy 182.6006 -209.235294) (xy 182.600108 -209.262251) (xy 182.592258 -209.315591)
			(xy 182.576726 -209.36722) (xy 182.553841 -209.416037) (xy 182.524093 -209.461001) (xy 182.488115 -209.501155)
			(xy 182.446673 -209.535643) (xy 182.400652 -209.563729) (xy 182.351032 -209.584816) (xy 182.298871 -209.598452)
			(xy 182.24528 -209.604349) (xy 182.191401 -209.60238) (xy 182.138383 -209.592587) (xy 182.087356 -209.575179)
			(xy 182.039408 -209.550527) (xy 181.99556 -209.519157) (xy 181.956747 -209.481736) (xy 181.923795 -209.439063)
			(xy 181.897409 -209.392046) (xy 181.878149 -209.341689) (xy 181.866426 -209.289065) (xy 181.862491 -209.235294)
			(xy 180.011832 -209.235294) (xy 180.011343 -209.266457) (xy 180.003531 -209.328291) (xy 179.988031 -209.388659)
			(xy 179.965088 -209.446607) (xy 179.935062 -209.501224) (xy 179.898428 -209.551646) (xy 179.855763 -209.59708)
			(xy 179.807741 -209.636808) (xy 179.755117 -209.670203) (xy 179.698723 -209.69674) (xy 179.639448 -209.716)
			(xy 179.578227 -209.727679) (xy 179.516024 -209.731592) (xy 179.453821 -209.727679) (xy 179.3926 -209.716)
			(xy 179.333325 -209.69674) (xy 179.276931 -209.670203) (xy 179.224307 -209.636808) (xy 179.176285 -209.59708)
			(xy 179.13362 -209.551646) (xy 179.096986 -209.501224) (xy 179.06696 -209.446607) (xy 179.044017 -209.388659)
			(xy 179.028517 -209.328291) (xy 179.020705 -209.266457) (xy 179.020216 -209.235294) (xy 175.056546 -209.235294)
			(xy 175.056054 -209.262251) (xy 175.048204 -209.315591) (xy 175.032672 -209.36722) (xy 175.009787 -209.416037)
			(xy 174.980039 -209.461001) (xy 174.944061 -209.501155) (xy 174.902619 -209.535643) (xy 174.856598 -209.563729)
			(xy 174.806978 -209.584816) (xy 174.754817 -209.598452) (xy 174.701226 -209.604349) (xy 174.647347 -209.60238)
			(xy 174.594329 -209.592587) (xy 174.543302 -209.575179) (xy 174.495354 -209.550527) (xy 174.451506 -209.519157)
			(xy 174.412693 -209.481736) (xy 174.379741 -209.439063) (xy 174.353355 -209.392046) (xy 174.334095 -209.341689)
			(xy 174.322372 -209.289065) (xy 174.318437 -209.235294) (xy 172.467778 -209.235294) (xy 172.467289 -209.266457)
			(xy 172.459477 -209.328291) (xy 172.443977 -209.388659) (xy 172.421034 -209.446607) (xy 172.391008 -209.501224)
			(xy 172.354374 -209.551646) (xy 172.311709 -209.59708) (xy 172.263687 -209.636808) (xy 172.211063 -209.670203)
			(xy 172.154669 -209.69674) (xy 172.095394 -209.716) (xy 172.034173 -209.727679) (xy 171.97197 -209.731592)
			(xy 171.909767 -209.727679) (xy 171.848546 -209.716) (xy 171.789271 -209.69674) (xy 171.732877 -209.670203)
			(xy 171.680253 -209.636808) (xy 171.632231 -209.59708) (xy 171.589566 -209.551646) (xy 171.552932 -209.501224)
			(xy 171.522906 -209.446607) (xy 171.499963 -209.388659) (xy 171.484463 -209.328291) (xy 171.476651 -209.266457)
			(xy 171.476162 -209.235294) (xy 167.512492 -209.235294) (xy 167.512 -209.262251) (xy 167.50415 -209.315591)
			(xy 167.488618 -209.36722) (xy 167.465733 -209.416037) (xy 167.435985 -209.461001) (xy 167.400007 -209.501155)
			(xy 167.358565 -209.535643) (xy 167.312544 -209.563729) (xy 167.262924 -209.584816) (xy 167.210763 -209.598452)
			(xy 167.157172 -209.604349) (xy 167.103293 -209.60238) (xy 167.050275 -209.592587) (xy 166.999248 -209.575179)
			(xy 166.9513 -209.550527) (xy 166.907452 -209.519157) (xy 166.868639 -209.481736) (xy 166.835687 -209.439063)
			(xy 166.809301 -209.392046) (xy 166.790041 -209.341689) (xy 166.778318 -209.289065) (xy 166.774383 -209.235294)
			(xy 161.612834 -209.235294) (xy 161.612834 -210.085432) (xy 165.442915 -210.085432) (xy 165.44685 -210.031661)
			(xy 165.458573 -209.979037) (xy 165.477833 -209.92868) (xy 165.504219 -209.881663) (xy 165.537171 -209.83899)
			(xy 165.575984 -209.801569) (xy 165.619832 -209.770199) (xy 165.66778 -209.745547) (xy 165.718807 -209.728139)
			(xy 165.771825 -209.718346) (xy 165.825704 -209.716377) (xy 165.879295 -209.722274) (xy 165.931456 -209.73591)
			(xy 165.981076 -209.756997) (xy 166.027097 -209.785083) (xy 166.068539 -209.819571) (xy 166.104517 -209.859725)
			(xy 166.134265 -209.904689) (xy 166.15715 -209.953506) (xy 166.172682 -210.005135) (xy 166.180532 -210.058475)
			(xy 166.181024 -210.085432) (xy 172.986969 -210.085432) (xy 172.990904 -210.031661) (xy 173.002627 -209.979037)
			(xy 173.021887 -209.92868) (xy 173.048273 -209.881663) (xy 173.081225 -209.83899) (xy 173.120038 -209.801569)
			(xy 173.163886 -209.770199) (xy 173.211834 -209.745547) (xy 173.262861 -209.728139) (xy 173.315879 -209.718346)
			(xy 173.369758 -209.716377) (xy 173.423349 -209.722274) (xy 173.47551 -209.73591) (xy 173.52513 -209.756997)
			(xy 173.571151 -209.785083) (xy 173.612593 -209.819571) (xy 173.648571 -209.859725) (xy 173.678319 -209.904689)
			(xy 173.701204 -209.953506) (xy 173.716736 -210.005135) (xy 173.724586 -210.058475) (xy 173.725078 -210.085432)
			(xy 173.724586 -210.112389) (xy 173.716736 -210.165729) (xy 173.701204 -210.217358) (xy 173.678319 -210.266175)
			(xy 173.648571 -210.311139) (xy 173.612593 -210.351293) (xy 173.571151 -210.385781) (xy 173.52513 -210.413867)
			(xy 173.47551 -210.434954) (xy 173.423349 -210.44859) (xy 173.369758 -210.454487) (xy 173.315879 -210.452518)
			(xy 173.262861 -210.442725) (xy 173.211834 -210.425317) (xy 173.163886 -210.400665) (xy 173.120038 -210.369295)
			(xy 173.081225 -210.331874) (xy 173.048273 -210.289201) (xy 173.021887 -210.242184) (xy 173.002627 -210.191827)
			(xy 172.990904 -210.139203) (xy 172.986969 -210.085432) (xy 166.181024 -210.085432) (xy 166.180532 -210.112389)
			(xy 166.172682 -210.165729) (xy 166.15715 -210.217358) (xy 166.134265 -210.266175) (xy 166.104517 -210.311139)
			(xy 166.068539 -210.351293) (xy 166.027097 -210.385781) (xy 165.981076 -210.413867) (xy 165.931456 -210.434954)
			(xy 165.879295 -210.44859) (xy 165.825704 -210.454487) (xy 165.771825 -210.452518) (xy 165.718807 -210.442725)
			(xy 165.66778 -210.425317) (xy 165.619832 -210.400665) (xy 165.575984 -210.369295) (xy 165.537171 -210.331874)
			(xy 165.504219 -210.289201) (xy 165.477833 -210.242184) (xy 165.458573 -210.191827) (xy 165.44685 -210.139203)
			(xy 165.442915 -210.085432) (xy 161.612834 -210.085432) (xy 161.612834 -210.510374) (xy 169.276283 -210.510374)
			(xy 169.280218 -210.456603) (xy 169.291941 -210.403979) (xy 169.311201 -210.353622) (xy 169.337587 -210.306605)
			(xy 169.370539 -210.263932) (xy 169.409352 -210.226511) (xy 169.4532 -210.195141) (xy 169.501148 -210.170489)
			(xy 169.552175 -210.153081) (xy 169.605193 -210.143288) (xy 169.659072 -210.141319) (xy 169.712663 -210.147216)
			(xy 169.764824 -210.160852) (xy 169.814444 -210.181939) (xy 169.860465 -210.210025) (xy 169.901907 -210.244513)
			(xy 169.937885 -210.284667) (xy 169.967633 -210.329631) (xy 169.990518 -210.378448) (xy 170.00605 -210.430077)
			(xy 170.0139 -210.483417) (xy 170.014392 -210.510374) (xy 170.0139 -210.537331) (xy 170.00605 -210.590671)
			(xy 169.990518 -210.6423) (xy 169.967633 -210.691117) (xy 169.937885 -210.736081) (xy 169.901907 -210.776235)
			(xy 169.860465 -210.810723) (xy 169.814444 -210.838809) (xy 169.764824 -210.859896) (xy 169.712663 -210.873532)
			(xy 169.659072 -210.879429) (xy 169.605193 -210.87746) (xy 169.552175 -210.867667) (xy 169.501148 -210.850259)
			(xy 169.4532 -210.825607) (xy 169.409352 -210.794237) (xy 169.370539 -210.756816) (xy 169.337587 -210.714143)
			(xy 169.311201 -210.667126) (xy 169.291941 -210.616769) (xy 169.280218 -210.564145) (xy 169.276283 -210.510374)
			(xy 161.612834 -210.510374) (xy 161.612834 -211.360258) (xy 165.176215 -211.360258) (xy 165.18015 -211.306487)
			(xy 165.191873 -211.253863) (xy 165.211133 -211.203506) (xy 165.237519 -211.156489) (xy 165.270471 -211.113816)
			(xy 165.309284 -211.076395) (xy 165.353132 -211.045025) (xy 165.40108 -211.020373) (xy 165.452107 -211.002965)
			(xy 165.505125 -210.993172) (xy 165.559004 -210.991203) (xy 165.612595 -210.9971) (xy 165.664756 -211.010736)
			(xy 165.714376 -211.031823) (xy 165.760397 -211.059909) (xy 165.801839 -211.094397) (xy 165.837817 -211.134551)
			(xy 165.867565 -211.179515) (xy 165.89045 -211.228332) (xy 165.905982 -211.279961) (xy 165.913832 -211.333301)
			(xy 165.914324 -211.360258) (xy 165.913832 -211.387215) (xy 165.905982 -211.440555) (xy 165.89045 -211.492184)
			(xy 165.867565 -211.541001) (xy 165.837817 -211.585965) (xy 165.801839 -211.626119) (xy 165.760397 -211.660607)
			(xy 165.714376 -211.688693) (xy 165.664756 -211.70978) (xy 165.612595 -211.723416) (xy 165.559004 -211.729313)
			(xy 165.505125 -211.727344) (xy 165.452107 -211.717551) (xy 165.40108 -211.700143) (xy 165.353132 -211.675491)
			(xy 165.309284 -211.644121) (xy 165.270471 -211.6067) (xy 165.237519 -211.564027) (xy 165.211133 -211.51701)
			(xy 165.191873 -211.466653) (xy 165.18015 -211.414029) (xy 165.176215 -211.360258) (xy 161.612834 -211.360258)
			(xy 161.612834 -211.7852) (xy 166.774383 -211.7852) (xy 166.778318 -211.731429) (xy 166.790041 -211.678805)
			(xy 166.809301 -211.628448) (xy 166.835687 -211.581431) (xy 166.868639 -211.538758) (xy 166.907452 -211.501337)
			(xy 166.9513 -211.469967) (xy 166.999248 -211.445315) (xy 167.050275 -211.427907) (xy 167.103293 -211.418114)
			(xy 167.157172 -211.416145) (xy 167.210763 -211.422042) (xy 167.262924 -211.435678) (xy 167.312544 -211.456765)
			(xy 167.358565 -211.484851) (xy 167.400007 -211.519339) (xy 167.435985 -211.559493) (xy 167.465733 -211.604457)
			(xy 167.488618 -211.653274) (xy 167.50415 -211.704903) (xy 167.512 -211.758243) (xy 167.512492 -211.7852)
			(xy 171.476162 -211.7852) (xy 171.476661 -211.752499) (xy 171.485275 -211.687666) (xy 171.502341 -211.624529)
			(xy 171.527563 -211.564184) (xy 171.560501 -211.507681) (xy 171.600584 -211.456001) (xy 171.623482 -211.432648)
			(xy 171.630848 -211.425282) (xy 171.638468 -211.40674) (xy 171.638468 -211.313776) (xy 171.630848 -211.295234)
			(xy 171.623482 -211.287868) (xy 171.600604 -211.264497) (xy 171.560517 -211.212823) (xy 171.527577 -211.156324)
			(xy 171.502356 -211.095983) (xy 171.485294 -211.032847) (xy 171.476688 -210.968016) (xy 171.476162 -210.935316)
			(xy 171.476651 -210.904153) (xy 171.484463 -210.842319) (xy 171.499963 -210.781951) (xy 171.522906 -210.724003)
			(xy 171.552932 -210.669386) (xy 171.589566 -210.618964) (xy 171.632231 -210.57353) (xy 171.680253 -210.533802)
			(xy 171.732877 -210.500407) (xy 171.789271 -210.47387) (xy 171.848546 -210.45461) (xy 171.909767 -210.442931)
			(xy 171.97197 -210.439018) (xy 172.034173 -210.442931) (xy 172.095394 -210.45461) (xy 172.154669 -210.47387)
			(xy 172.211063 -210.500407) (xy 172.263687 -210.533802) (xy 172.311709 -210.57353) (xy 172.354374 -210.618964)
			(xy 172.391008 -210.669386) (xy 172.421034 -210.724003) (xy 172.443977 -210.781951) (xy 172.459477 -210.842319)
			(xy 172.467289 -210.904153) (xy 172.467778 -210.935316) (xy 175.57623 -210.935316) (xy 175.576748 -210.902615)
			(xy 175.58536 -210.837784) (xy 175.602423 -210.774647) (xy 175.627641 -210.714303) (xy 175.660575 -210.6578)
			(xy 175.700655 -210.606118) (xy 175.72355 -210.582764) (xy 175.730916 -210.575398) (xy 175.738536 -210.556856)
			(xy 175.738536 -210.463892) (xy 175.730916 -210.44535) (xy 175.72355 -210.437984) (xy 175.700626 -210.414657)
			(xy 175.660544 -210.362973) (xy 175.627611 -210.306464) (xy 175.602399 -210.246114) (xy 175.585347 -210.182972)
			(xy 175.57675 -210.118134) (xy 175.57623 -210.085432) (xy 175.576719 -210.054269) (xy 175.584531 -209.992435)
			(xy 175.600031 -209.932067) (xy 175.622974 -209.874119) (xy 175.653 -209.819502) (xy 175.689634 -209.76908)
			(xy 175.732299 -209.723646) (xy 175.780321 -209.683918) (xy 175.832945 -209.650523) (xy 175.889339 -209.623986)
			(xy 175.948614 -209.604726) (xy 176.009835 -209.593047) (xy 176.072038 -209.589134) (xy 176.134241 -209.593047)
			(xy 176.195462 -209.604726) (xy 176.254737 -209.623986) (xy 176.311131 -209.650523) (xy 176.363755 -209.683918)
			(xy 176.411777 -209.723646) (xy 176.454442 -209.76908) (xy 176.491076 -209.819502) (xy 176.521102 -209.874119)
			(xy 176.544045 -209.932067) (xy 176.559545 -209.992435) (xy 176.567357 -210.054269) (xy 176.567846 -210.085432)
			(xy 180.531023 -210.085432) (xy 180.534958 -210.031661) (xy 180.546681 -209.979037) (xy 180.565941 -209.92868)
			(xy 180.592327 -209.881663) (xy 180.625279 -209.83899) (xy 180.664092 -209.801569) (xy 180.70794 -209.770199)
			(xy 180.755888 -209.745547) (xy 180.806915 -209.728139) (xy 180.859933 -209.718346) (xy 180.913812 -209.716377)
			(xy 180.967403 -209.722274) (xy 181.019564 -209.73591) (xy 181.069184 -209.756997) (xy 181.115205 -209.785083)
			(xy 181.156647 -209.819571) (xy 181.192625 -209.859725) (xy 181.222373 -209.904689) (xy 181.245258 -209.953506)
			(xy 181.26079 -210.005135) (xy 181.26864 -210.058475) (xy 181.269132 -210.085432) (xy 181.26864 -210.112389)
			(xy 181.26079 -210.165729) (xy 181.245258 -210.217358) (xy 181.222373 -210.266175) (xy 181.192625 -210.311139)
			(xy 181.156647 -210.351293) (xy 181.115205 -210.385781) (xy 181.069184 -210.413867) (xy 181.019564 -210.434954)
			(xy 180.967403 -210.44859) (xy 180.913812 -210.454487) (xy 180.859933 -210.452518) (xy 180.806915 -210.442725)
			(xy 180.755888 -210.425317) (xy 180.70794 -210.400665) (xy 180.664092 -210.369295) (xy 180.625279 -210.331874)
			(xy 180.592327 -210.289201) (xy 180.565941 -210.242184) (xy 180.546681 -210.191827) (xy 180.534958 -210.139203)
			(xy 180.531023 -210.085432) (xy 176.567846 -210.085432) (xy 176.567301 -210.118132) (xy 176.558696 -210.182963)
			(xy 176.541638 -210.246099) (xy 176.516426 -210.306443) (xy 176.483495 -210.362947) (xy 176.44342 -210.41463)
			(xy 176.420526 -210.437984) (xy 176.41316 -210.44535) (xy 176.40554 -210.463892) (xy 176.40554 -210.510374)
			(xy 176.820337 -210.510374) (xy 176.824272 -210.456603) (xy 176.835995 -210.403979) (xy 176.855255 -210.353622)
			(xy 176.881641 -210.306605) (xy 176.914593 -210.263932) (xy 176.953406 -210.226511) (xy 176.997254 -210.195141)
			(xy 177.045202 -210.170489) (xy 177.096229 -210.153081) (xy 177.149247 -210.143288) (xy 177.203126 -210.141319)
			(xy 177.256717 -210.147216) (xy 177.308878 -210.160852) (xy 177.358498 -210.181939) (xy 177.404519 -210.210025)
			(xy 177.445961 -210.244513) (xy 177.481939 -210.284667) (xy 177.511687 -210.329631) (xy 177.534572 -210.378448)
			(xy 177.550104 -210.430077) (xy 177.557954 -210.483417) (xy 177.558446 -210.510374) (xy 177.557954 -210.537331)
			(xy 177.550104 -210.590671) (xy 177.534572 -210.6423) (xy 177.511687 -210.691117) (xy 177.481939 -210.736081)
			(xy 177.445961 -210.776235) (xy 177.404519 -210.810723) (xy 177.358498 -210.838809) (xy 177.308878 -210.859896)
			(xy 177.256717 -210.873532) (xy 177.203126 -210.879429) (xy 177.149247 -210.87746) (xy 177.096229 -210.867667)
			(xy 177.045202 -210.850259) (xy 176.997254 -210.825607) (xy 176.953406 -210.794237) (xy 176.914593 -210.756816)
			(xy 176.881641 -210.714143) (xy 176.855255 -210.667126) (xy 176.835995 -210.616769) (xy 176.824272 -210.564145)
			(xy 176.820337 -210.510374) (xy 176.40554 -210.510374) (xy 176.40554 -210.556856) (xy 176.41316 -210.575398)
			(xy 176.420526 -210.582764) (xy 176.443421 -210.606119) (xy 176.483506 -210.657797) (xy 176.516444 -210.714299)
			(xy 176.541661 -210.774644) (xy 176.558719 -210.837782) (xy 176.567322 -210.902615) (xy 176.567846 -210.935316)
			(xy 176.567357 -210.966479) (xy 176.559545 -211.028313) (xy 176.544045 -211.088681) (xy 176.521102 -211.146629)
			(xy 176.491076 -211.201246) (xy 176.454442 -211.251668) (xy 176.411777 -211.297102) (xy 176.363755 -211.33683)
			(xy 176.311131 -211.370225) (xy 176.254737 -211.396762) (xy 176.195462 -211.416022) (xy 176.134241 -211.427701)
			(xy 176.072038 -211.431614) (xy 176.009835 -211.427701) (xy 175.948614 -211.416022) (xy 175.889339 -211.396762)
			(xy 175.832945 -211.370225) (xy 175.780321 -211.33683) (xy 175.732299 -211.297102) (xy 175.689634 -211.251668)
			(xy 175.653 -211.201246) (xy 175.622974 -211.146629) (xy 175.600031 -211.088681) (xy 175.584531 -211.028313)
			(xy 175.576719 -210.966479) (xy 175.57623 -210.935316) (xy 172.467778 -210.935316) (xy 172.467213 -210.968015)
			(xy 172.45861 -211.032845) (xy 172.441556 -211.09598) (xy 172.416347 -211.156324) (xy 172.383421 -211.212829)
			(xy 172.34335 -211.264513) (xy 172.320458 -211.287868) (xy 172.313092 -211.295234) (xy 172.305472 -211.313776)
			(xy 172.305472 -211.360258) (xy 172.720269 -211.360258) (xy 172.724204 -211.306487) (xy 172.735927 -211.253863)
			(xy 172.755187 -211.203506) (xy 172.781573 -211.156489) (xy 172.814525 -211.113816) (xy 172.853338 -211.076395)
			(xy 172.897186 -211.045025) (xy 172.945134 -211.020373) (xy 172.996161 -211.002965) (xy 173.049179 -210.993172)
			(xy 173.103058 -210.991203) (xy 173.156649 -210.9971) (xy 173.20881 -211.010736) (xy 173.25843 -211.031823)
			(xy 173.304451 -211.059909) (xy 173.345893 -211.094397) (xy 173.381871 -211.134551) (xy 173.411619 -211.179515)
			(xy 173.434504 -211.228332) (xy 173.450036 -211.279961) (xy 173.457886 -211.333301) (xy 173.458378 -211.360258)
			(xy 173.457886 -211.387215) (xy 173.450036 -211.440555) (xy 173.434504 -211.492184) (xy 173.411619 -211.541001)
			(xy 173.381871 -211.585965) (xy 173.345893 -211.626119) (xy 173.304451 -211.660607) (xy 173.25843 -211.688693)
			(xy 173.20881 -211.70978) (xy 173.156649 -211.723416) (xy 173.103058 -211.729313) (xy 173.049179 -211.727344)
			(xy 172.996161 -211.717551) (xy 172.945134 -211.700143) (xy 172.897186 -211.675491) (xy 172.853338 -211.644121)
			(xy 172.814525 -211.6067) (xy 172.781573 -211.564027) (xy 172.755187 -211.51701) (xy 172.735927 -211.466653)
			(xy 172.724204 -211.414029) (xy 172.720269 -211.360258) (xy 172.305472 -211.360258) (xy 172.305472 -211.40674)
			(xy 172.313092 -211.425282) (xy 172.320458 -211.432648) (xy 172.343351 -211.456005) (xy 172.383435 -211.507682)
			(xy 172.416373 -211.564185) (xy 172.44159 -211.624529) (xy 172.458649 -211.687666) (xy 172.467253 -211.752499)
			(xy 172.467778 -211.7852) (xy 174.318437 -211.7852) (xy 174.322372 -211.731429) (xy 174.334095 -211.678805)
			(xy 174.353355 -211.628448) (xy 174.379741 -211.581431) (xy 174.412693 -211.538758) (xy 174.451506 -211.501337)
			(xy 174.495354 -211.469967) (xy 174.543302 -211.445315) (xy 174.594329 -211.427907) (xy 174.647347 -211.418114)
			(xy 174.701226 -211.416145) (xy 174.754817 -211.422042) (xy 174.806978 -211.435678) (xy 174.856598 -211.456765)
			(xy 174.902619 -211.484851) (xy 174.944061 -211.519339) (xy 174.980039 -211.559493) (xy 175.009787 -211.604457)
			(xy 175.032672 -211.653274) (xy 175.048204 -211.704903) (xy 175.056054 -211.758243) (xy 175.056546 -211.7852)
			(xy 179.020216 -211.7852) (xy 179.020699 -211.752498) (xy 179.029314 -211.687664) (xy 179.046382 -211.624526)
			(xy 179.071607 -211.564181) (xy 179.104549 -211.507679) (xy 179.144636 -211.456) (xy 179.167536 -211.432648)
			(xy 179.174902 -211.425282) (xy 179.182522 -211.40674) (xy 179.182522 -211.313776) (xy 179.174902 -211.295234)
			(xy 179.167536 -211.287868) (xy 179.14465 -211.264505) (xy 179.104565 -211.212829) (xy 179.071627 -211.156328)
			(xy 179.046408 -211.095985) (xy 179.029348 -211.032848) (xy 179.020742 -210.968016) (xy 179.020216 -210.935316)
			(xy 179.020705 -210.904153) (xy 179.028517 -210.842319) (xy 179.044017 -210.781951) (xy 179.06696 -210.724003)
			(xy 179.096986 -210.669386) (xy 179.13362 -210.618964) (xy 179.176285 -210.57353) (xy 179.224307 -210.533802)
			(xy 179.276931 -210.500407) (xy 179.333325 -210.47387) (xy 179.3926 -210.45461) (xy 179.453821 -210.442931)
			(xy 179.516024 -210.439018) (xy 179.578227 -210.442931) (xy 179.639448 -210.45461) (xy 179.698723 -210.47387)
			(xy 179.755117 -210.500407) (xy 179.807741 -210.533802) (xy 179.855763 -210.57353) (xy 179.898428 -210.618964)
			(xy 179.935062 -210.669386) (xy 179.965088 -210.724003) (xy 179.988031 -210.781951) (xy 180.003531 -210.842319)
			(xy 180.011343 -210.904153) (xy 180.011832 -210.935316) (xy 183.120284 -210.935316) (xy 183.120787 -210.902615)
			(xy 183.129399 -210.837782) (xy 183.146464 -210.774644) (xy 183.171685 -210.7143) (xy 183.204623 -210.657797)
			(xy 183.244706 -210.606117) (xy 183.267604 -210.582764) (xy 183.27497 -210.575398) (xy 183.28259 -210.556856)
			(xy 183.28259 -210.463892) (xy 183.27497 -210.44535) (xy 183.267604 -210.437984) (xy 183.24469 -210.414647)
			(xy 183.204605 -210.362966) (xy 183.171669 -210.30646) (xy 183.146455 -210.246112) (xy 183.129401 -210.182971)
			(xy 183.120804 -210.118134) (xy 183.120284 -210.085432) (xy 183.120773 -210.054269) (xy 183.128585 -209.992435)
			(xy 183.144085 -209.932067) (xy 183.167028 -209.874119) (xy 183.197054 -209.819502) (xy 183.233688 -209.76908)
			(xy 183.276353 -209.723646) (xy 183.324375 -209.683918) (xy 183.376999 -209.650523) (xy 183.433393 -209.623986)
			(xy 183.492668 -209.604726) (xy 183.553889 -209.593047) (xy 183.616092 -209.589134) (xy 183.678295 -209.593047)
			(xy 183.739516 -209.604726) (xy 183.798791 -209.623986) (xy 183.855185 -209.650523) (xy 183.907809 -209.683918)
			(xy 183.955831 -209.723646) (xy 183.998496 -209.76908) (xy 184.03513 -209.819502) (xy 184.065156 -209.874119)
			(xy 184.088099 -209.932067) (xy 184.103599 -209.992435) (xy 184.111411 -210.054269) (xy 184.1119 -210.085432)
			(xy 188.075077 -210.085432) (xy 188.079012 -210.031661) (xy 188.090735 -209.979037) (xy 188.109995 -209.92868)
			(xy 188.136381 -209.881663) (xy 188.169333 -209.83899) (xy 188.208146 -209.801569) (xy 188.251994 -209.770199)
			(xy 188.299942 -209.745547) (xy 188.350969 -209.728139) (xy 188.403987 -209.718346) (xy 188.457866 -209.716377)
			(xy 188.511457 -209.722274) (xy 188.563618 -209.73591) (xy 188.613238 -209.756997) (xy 188.659259 -209.785083)
			(xy 188.700701 -209.819571) (xy 188.736679 -209.859725) (xy 188.766427 -209.904689) (xy 188.789312 -209.953506)
			(xy 188.804844 -210.005135) (xy 188.812694 -210.058475) (xy 188.813186 -210.085432) (xy 188.812694 -210.112389)
			(xy 188.804844 -210.165729) (xy 188.789312 -210.217358) (xy 188.766427 -210.266175) (xy 188.736679 -210.311139)
			(xy 188.700701 -210.351293) (xy 188.659259 -210.385781) (xy 188.613238 -210.413867) (xy 188.563618 -210.434954)
			(xy 188.511457 -210.44859) (xy 188.457866 -210.454487) (xy 188.403987 -210.452518) (xy 188.350969 -210.442725)
			(xy 188.299942 -210.425317) (xy 188.251994 -210.400665) (xy 188.208146 -210.369295) (xy 188.169333 -210.331874)
			(xy 188.136381 -210.289201) (xy 188.109995 -210.242184) (xy 188.090735 -210.191827) (xy 188.079012 -210.139203)
			(xy 188.075077 -210.085432) (xy 184.1119 -210.085432) (xy 184.111369 -210.118132) (xy 184.102762 -210.182964)
			(xy 184.085703 -210.246101) (xy 184.060488 -210.306446) (xy 184.027555 -210.36295) (xy 183.987476 -210.414631)
			(xy 183.96458 -210.437984) (xy 183.957214 -210.44535) (xy 183.949594 -210.463892) (xy 183.949594 -210.510374)
			(xy 184.364391 -210.510374) (xy 184.368326 -210.456603) (xy 184.380049 -210.403979) (xy 184.399309 -210.353622)
			(xy 184.425695 -210.306605) (xy 184.458647 -210.263932) (xy 184.49746 -210.226511) (xy 184.541308 -210.195141)
			(xy 184.589256 -210.170489) (xy 184.640283 -210.153081) (xy 184.693301 -210.143288) (xy 184.74718 -210.141319)
			(xy 184.800771 -210.147216) (xy 184.852932 -210.160852) (xy 184.902552 -210.181939) (xy 184.948573 -210.210025)
			(xy 184.990015 -210.244513) (xy 185.025993 -210.284667) (xy 185.055741 -210.329631) (xy 185.078626 -210.378448)
			(xy 185.094158 -210.430077) (xy 185.102008 -210.483417) (xy 185.1025 -210.510374) (xy 185.102008 -210.537331)
			(xy 185.094158 -210.590671) (xy 185.078626 -210.6423) (xy 185.055741 -210.691117) (xy 185.025993 -210.736081)
			(xy 184.990015 -210.776235) (xy 184.948573 -210.810723) (xy 184.902552 -210.838809) (xy 184.852932 -210.859896)
			(xy 184.800771 -210.873532) (xy 184.74718 -210.879429) (xy 184.693301 -210.87746) (xy 184.640283 -210.867667)
			(xy 184.589256 -210.850259) (xy 184.541308 -210.825607) (xy 184.49746 -210.794237) (xy 184.458647 -210.756816)
			(xy 184.425695 -210.714143) (xy 184.399309 -210.667126) (xy 184.380049 -210.616769) (xy 184.368326 -210.564145)
			(xy 184.364391 -210.510374) (xy 183.949594 -210.510374) (xy 183.949594 -210.556856) (xy 183.957214 -210.575398)
			(xy 183.96458 -210.582764) (xy 183.987485 -210.60611) (xy 184.027567 -210.65779) (xy 184.060502 -210.714295)
			(xy 184.085717 -210.774641) (xy 184.102774 -210.83778) (xy 184.111377 -210.902615) (xy 184.1119 -210.935316)
			(xy 184.111411 -210.966479) (xy 184.103599 -211.028313) (xy 184.088099 -211.088681) (xy 184.065156 -211.146629)
			(xy 184.03513 -211.201246) (xy 183.998496 -211.251668) (xy 183.955831 -211.297102) (xy 183.907809 -211.33683)
			(xy 183.855185 -211.370225) (xy 183.798791 -211.396762) (xy 183.739516 -211.416022) (xy 183.678295 -211.427701)
			(xy 183.616092 -211.431614) (xy 183.553889 -211.427701) (xy 183.492668 -211.416022) (xy 183.433393 -211.396762)
			(xy 183.376999 -211.370225) (xy 183.324375 -211.33683) (xy 183.276353 -211.297102) (xy 183.233688 -211.251668)
			(xy 183.197054 -211.201246) (xy 183.167028 -211.146629) (xy 183.144085 -211.088681) (xy 183.128585 -211.028313)
			(xy 183.120773 -210.966479) (xy 183.120284 -210.935316) (xy 180.011832 -210.935316) (xy 180.011281 -210.968016)
			(xy 180.002677 -211.032847) (xy 179.985621 -211.095983) (xy 179.96041 -211.156327) (xy 179.927481 -211.212831)
			(xy 179.887406 -211.264514) (xy 179.864512 -211.287868) (xy 179.857146 -211.295234) (xy 179.849526 -211.313776)
			(xy 179.849526 -211.360258) (xy 180.264323 -211.360258) (xy 180.268258 -211.306487) (xy 180.279981 -211.253863)
			(xy 180.299241 -211.203506) (xy 180.325627 -211.156489) (xy 180.358579 -211.113816) (xy 180.397392 -211.076395)
			(xy 180.44124 -211.045025) (xy 180.489188 -211.020373) (xy 180.540215 -211.002965) (xy 180.593233 -210.993172)
			(xy 180.647112 -210.991203) (xy 180.700703 -210.9971) (xy 180.752864 -211.010736) (xy 180.802484 -211.031823)
			(xy 180.848505 -211.059909) (xy 180.889947 -211.094397) (xy 180.925925 -211.134551) (xy 180.955673 -211.179515)
			(xy 180.978558 -211.228332) (xy 180.99409 -211.279961) (xy 181.00194 -211.333301) (xy 181.002432 -211.360258)
			(xy 181.00194 -211.387215) (xy 180.99409 -211.440555) (xy 180.978558 -211.492184) (xy 180.955673 -211.541001)
			(xy 180.925925 -211.585965) (xy 180.889947 -211.626119) (xy 180.848505 -211.660607) (xy 180.802484 -211.688693)
			(xy 180.752864 -211.70978) (xy 180.700703 -211.723416) (xy 180.647112 -211.729313) (xy 180.593233 -211.727344)
			(xy 180.540215 -211.717551) (xy 180.489188 -211.700143) (xy 180.44124 -211.675491) (xy 180.397392 -211.644121)
			(xy 180.358579 -211.6067) (xy 180.325627 -211.564027) (xy 180.299241 -211.51701) (xy 180.279981 -211.466653)
			(xy 180.268258 -211.414029) (xy 180.264323 -211.360258) (xy 179.849526 -211.360258) (xy 179.849526 -211.40674)
			(xy 179.857146 -211.425282) (xy 179.864512 -211.432648) (xy 179.887397 -211.456013) (xy 179.927483 -211.507688)
			(xy 179.960423 -211.564188) (xy 179.985642 -211.624531) (xy 180.002702 -211.687667) (xy 180.011307 -211.7525)
			(xy 180.011832 -211.7852) (xy 181.862491 -211.7852) (xy 181.866426 -211.731429) (xy 181.878149 -211.678805)
			(xy 181.897409 -211.628448) (xy 181.923795 -211.581431) (xy 181.956747 -211.538758) (xy 181.99556 -211.501337)
			(xy 182.039408 -211.469967) (xy 182.087356 -211.445315) (xy 182.138383 -211.427907) (xy 182.191401 -211.418114)
			(xy 182.24528 -211.416145) (xy 182.298871 -211.422042) (xy 182.351032 -211.435678) (xy 182.400652 -211.456765)
			(xy 182.446673 -211.484851) (xy 182.488115 -211.519339) (xy 182.524093 -211.559493) (xy 182.553841 -211.604457)
			(xy 182.576726 -211.653274) (xy 182.592258 -211.704903) (xy 182.600108 -211.758243) (xy 182.6006 -211.7852)
			(xy 186.56427 -211.7852) (xy 186.564766 -211.752499) (xy 186.573381 -211.687665) (xy 186.590447 -211.624528)
			(xy 186.615669 -211.564184) (xy 186.648608 -211.507681) (xy 186.688692 -211.456001) (xy 186.71159 -211.432648)
			(xy 186.718956 -211.425282) (xy 186.726576 -211.40674) (xy 186.726576 -211.313776) (xy 186.718956 -211.295234)
			(xy 186.71159 -211.287868) (xy 186.688714 -211.264496) (xy 186.648626 -211.212822) (xy 186.615685 -211.156324)
			(xy 186.590465 -211.095982) (xy 186.573403 -211.032847) (xy 186.564796 -210.968016) (xy 186.56427 -210.935316)
			(xy 186.564759 -210.904153) (xy 186.572571 -210.842319) (xy 186.588071 -210.781951) (xy 186.611014 -210.724003)
			(xy 186.64104 -210.669386) (xy 186.677674 -210.618964) (xy 186.720339 -210.57353) (xy 186.768361 -210.533802)
			(xy 186.820985 -210.500407) (xy 186.877379 -210.47387) (xy 186.936654 -210.45461) (xy 186.997875 -210.442931)
			(xy 187.060078 -210.439018) (xy 187.122281 -210.442931) (xy 187.183502 -210.45461) (xy 187.242777 -210.47387)
			(xy 187.299171 -210.500407) (xy 187.351795 -210.533802) (xy 187.399817 -210.57353) (xy 187.442482 -210.618964)
			(xy 187.479116 -210.669386) (xy 187.509142 -210.724003) (xy 187.532085 -210.781951) (xy 187.547585 -210.842319)
			(xy 187.555397 -210.904153) (xy 187.555886 -210.935316) (xy 190.664338 -210.935316) (xy 190.664854 -210.902615)
			(xy 190.673466 -210.837783) (xy 190.690529 -210.774647) (xy 190.715747 -210.714303) (xy 190.748682 -210.657799)
			(xy 190.788762 -210.606118) (xy 190.811658 -210.582764) (xy 190.819024 -210.575398) (xy 190.826644 -210.556856)
			(xy 190.826644 -210.463892) (xy 190.819024 -210.44535) (xy 190.811658 -210.437984) (xy 190.788735 -210.414655)
			(xy 190.748653 -210.362972) (xy 190.71572 -210.306464) (xy 190.690507 -210.246114) (xy 190.673455 -210.182972)
			(xy 190.664858 -210.118134) (xy 190.664338 -210.085432) (xy 190.664827 -210.054269) (xy 190.672639 -209.992435)
			(xy 190.688139 -209.932067) (xy 190.711082 -209.874119) (xy 190.741108 -209.819502) (xy 190.777742 -209.76908)
			(xy 190.820407 -209.723646) (xy 190.868429 -209.683918) (xy 190.921053 -209.650523) (xy 190.977447 -209.623986)
			(xy 191.036722 -209.604726) (xy 191.097943 -209.593047) (xy 191.160146 -209.589134) (xy 191.222349 -209.593047)
			(xy 191.28357 -209.604726) (xy 191.342845 -209.623986) (xy 191.399239 -209.650523) (xy 191.451863 -209.683918)
			(xy 191.499885 -209.723646) (xy 191.54255 -209.76908) (xy 191.579184 -209.819502) (xy 191.60921 -209.874119)
			(xy 191.632153 -209.932067) (xy 191.647653 -209.992435) (xy 191.655465 -210.054269) (xy 191.655954 -210.085432)
			(xy 195.619131 -210.085432) (xy 195.623066 -210.031661) (xy 195.634789 -209.979037) (xy 195.654049 -209.92868)
			(xy 195.680435 -209.881663) (xy 195.713387 -209.83899) (xy 195.7522 -209.801569) (xy 195.796048 -209.770199)
			(xy 195.843996 -209.745547) (xy 195.895023 -209.728139) (xy 195.948041 -209.718346) (xy 196.00192 -209.716377)
			(xy 196.055511 -209.722274) (xy 196.107672 -209.73591) (xy 196.157292 -209.756997) (xy 196.203313 -209.785083)
			(xy 196.244755 -209.819571) (xy 196.280733 -209.859725) (xy 196.310481 -209.904689) (xy 196.333366 -209.953506)
			(xy 196.348898 -210.005135) (xy 196.356748 -210.058475) (xy 196.35724 -210.085432) (xy 196.356748 -210.112389)
			(xy 196.348898 -210.165729) (xy 196.333366 -210.217358) (xy 196.310481 -210.266175) (xy 196.280733 -210.311139)
			(xy 196.244755 -210.351293) (xy 196.203313 -210.385781) (xy 196.157292 -210.413867) (xy 196.107672 -210.434954)
			(xy 196.055511 -210.44859) (xy 196.00192 -210.454487) (xy 195.948041 -210.452518) (xy 195.895023 -210.442725)
			(xy 195.843996 -210.425317) (xy 195.796048 -210.400665) (xy 195.7522 -210.369295) (xy 195.713387 -210.331874)
			(xy 195.680435 -210.289201) (xy 195.654049 -210.242184) (xy 195.634789 -210.191827) (xy 195.623066 -210.139203)
			(xy 195.619131 -210.085432) (xy 191.655954 -210.085432) (xy 191.655407 -210.118132) (xy 191.646801 -210.182963)
			(xy 191.629744 -210.246098) (xy 191.604532 -210.306443) (xy 191.571602 -210.362947) (xy 191.531528 -210.41463)
			(xy 191.508634 -210.437984) (xy 191.501268 -210.44535) (xy 191.493648 -210.463892) (xy 191.493648 -210.510374)
			(xy 191.908445 -210.510374) (xy 191.91238 -210.456603) (xy 191.924103 -210.403979) (xy 191.943363 -210.353622)
			(xy 191.969749 -210.306605) (xy 192.002701 -210.263932) (xy 192.041514 -210.226511) (xy 192.085362 -210.195141)
			(xy 192.13331 -210.170489) (xy 192.184337 -210.153081) (xy 192.237355 -210.143288) (xy 192.291234 -210.141319)
			(xy 192.344825 -210.147216) (xy 192.396986 -210.160852) (xy 192.446606 -210.181939) (xy 192.492627 -210.210025)
			(xy 192.534069 -210.244513) (xy 192.570047 -210.284667) (xy 192.599795 -210.329631) (xy 192.62268 -210.378448)
			(xy 192.638212 -210.430077) (xy 192.646062 -210.483417) (xy 192.646554 -210.510374) (xy 192.646062 -210.537331)
			(xy 192.638212 -210.590671) (xy 192.62268 -210.6423) (xy 192.599795 -210.691117) (xy 192.570047 -210.736081)
			(xy 192.534069 -210.776235) (xy 192.492627 -210.810723) (xy 192.446606 -210.838809) (xy 192.396986 -210.859896)
			(xy 192.344825 -210.873532) (xy 192.291234 -210.879429) (xy 192.237355 -210.87746) (xy 192.184337 -210.867667)
			(xy 192.13331 -210.850259) (xy 192.085362 -210.825607) (xy 192.041514 -210.794237) (xy 192.002701 -210.756816)
			(xy 191.969749 -210.714143) (xy 191.943363 -210.667126) (xy 191.924103 -210.616769) (xy 191.91238 -210.564145)
			(xy 191.908445 -210.510374) (xy 191.493648 -210.510374) (xy 191.493648 -210.556856) (xy 191.501268 -210.575398)
			(xy 191.508634 -210.582764) (xy 191.53153 -210.606118) (xy 191.571615 -210.657796) (xy 191.604553 -210.714298)
			(xy 191.629769 -210.774643) (xy 191.646828 -210.837781) (xy 191.65543 -210.902615) (xy 191.655954 -210.935316)
			(xy 191.655465 -210.966479) (xy 191.647653 -211.028313) (xy 191.632153 -211.088681) (xy 191.60921 -211.146629)
			(xy 191.579184 -211.201246) (xy 191.54255 -211.251668) (xy 191.499885 -211.297102) (xy 191.451863 -211.33683)
			(xy 191.399239 -211.370225) (xy 191.342845 -211.396762) (xy 191.28357 -211.416022) (xy 191.222349 -211.427701)
			(xy 191.160146 -211.431614) (xy 191.097943 -211.427701) (xy 191.036722 -211.416022) (xy 190.977447 -211.396762)
			(xy 190.921053 -211.370225) (xy 190.868429 -211.33683) (xy 190.820407 -211.297102) (xy 190.777742 -211.251668)
			(xy 190.741108 -211.201246) (xy 190.711082 -211.146629) (xy 190.688139 -211.088681) (xy 190.672639 -211.028313)
			(xy 190.664827 -210.966479) (xy 190.664338 -210.935316) (xy 187.555886 -210.935316) (xy 187.555348 -210.968016)
			(xy 187.546744 -211.032848) (xy 187.529686 -211.095985) (xy 187.504472 -211.15633) (xy 187.47154 -211.212834)
			(xy 187.431462 -211.264515) (xy 187.408566 -211.287868) (xy 187.4012 -211.295234) (xy 187.39358 -211.313776)
			(xy 187.39358 -211.360258) (xy 187.808377 -211.360258) (xy 187.812312 -211.306487) (xy 187.824035 -211.253863)
			(xy 187.843295 -211.203506) (xy 187.869681 -211.156489) (xy 187.902633 -211.113816) (xy 187.941446 -211.076395)
			(xy 187.985294 -211.045025) (xy 188.033242 -211.020373) (xy 188.084269 -211.002965) (xy 188.137287 -210.993172)
			(xy 188.191166 -210.991203) (xy 188.244757 -210.9971) (xy 188.296918 -211.010736) (xy 188.346538 -211.031823)
			(xy 188.392559 -211.059909) (xy 188.434001 -211.094397) (xy 188.469979 -211.134551) (xy 188.499727 -211.179515)
			(xy 188.522612 -211.228332) (xy 188.538144 -211.279961) (xy 188.545994 -211.333301) (xy 188.546486 -211.360258)
			(xy 188.545994 -211.387215) (xy 188.538144 -211.440555) (xy 188.522612 -211.492184) (xy 188.499727 -211.541001)
			(xy 188.469979 -211.585965) (xy 188.434001 -211.626119) (xy 188.392559 -211.660607) (xy 188.346538 -211.688693)
			(xy 188.296918 -211.70978) (xy 188.244757 -211.723416) (xy 188.191166 -211.729313) (xy 188.137287 -211.727344)
			(xy 188.084269 -211.717551) (xy 188.033242 -211.700143) (xy 187.985294 -211.675491) (xy 187.941446 -211.644121)
			(xy 187.902633 -211.6067) (xy 187.869681 -211.564027) (xy 187.843295 -211.51701) (xy 187.824035 -211.466653)
			(xy 187.812312 -211.414029) (xy 187.808377 -211.360258) (xy 187.39358 -211.360258) (xy 187.39358 -211.40674)
			(xy 187.4012 -211.425282) (xy 187.408566 -211.432648) (xy 187.43146 -211.456003) (xy 187.471544 -211.507682)
			(xy 187.504481 -211.564184) (xy 187.529698 -211.624529) (xy 187.546757 -211.687666) (xy 187.555361 -211.752499)
			(xy 187.555886 -211.7852) (xy 189.406545 -211.7852) (xy 189.41048 -211.731429) (xy 189.422203 -211.678805)
			(xy 189.441463 -211.628448) (xy 189.467849 -211.581431) (xy 189.500801 -211.538758) (xy 189.539614 -211.501337)
			(xy 189.583462 -211.469967) (xy 189.63141 -211.445315) (xy 189.682437 -211.427907) (xy 189.735455 -211.418114)
			(xy 189.789334 -211.416145) (xy 189.842925 -211.422042) (xy 189.895086 -211.435678) (xy 189.944706 -211.456765)
			(xy 189.990727 -211.484851) (xy 190.032169 -211.519339) (xy 190.068147 -211.559493) (xy 190.097895 -211.604457)
			(xy 190.12078 -211.653274) (xy 190.136312 -211.704903) (xy 190.144162 -211.758243) (xy 190.144654 -211.7852)
			(xy 194.108324 -211.7852) (xy 194.108834 -211.752499) (xy 194.117448 -211.687667) (xy 194.134512 -211.624531)
			(xy 194.159732 -211.564187) (xy 194.192668 -211.507683) (xy 194.232748 -211.456002) (xy 194.255644 -211.432648)
			(xy 194.26301 -211.425282) (xy 194.27063 -211.40674) (xy 194.27063 -211.313776) (xy 194.26301 -211.295234)
			(xy 194.255644 -211.287868) (xy 194.232759 -211.264504) (xy 194.192674 -211.212828) (xy 194.159736 -211.156327)
			(xy 194.134517 -211.095984) (xy 194.117456 -211.032848) (xy 194.10885 -210.968016) (xy 194.108324 -210.935316)
			(xy 194.108813 -210.904153) (xy 194.116625 -210.842319) (xy 194.132125 -210.781951) (xy 194.155068 -210.724003)
			(xy 194.185094 -210.669386) (xy 194.221728 -210.618964) (xy 194.264393 -210.57353) (xy 194.312415 -210.533802)
			(xy 194.365039 -210.500407) (xy 194.421433 -210.47387) (xy 194.480708 -210.45461) (xy 194.541929 -210.442931)
			(xy 194.604132 -210.439018) (xy 194.666335 -210.442931) (xy 194.727556 -210.45461) (xy 194.786831 -210.47387)
			(xy 194.843225 -210.500407) (xy 194.895849 -210.533802) (xy 194.943871 -210.57353) (xy 194.986536 -210.618964)
			(xy 195.02317 -210.669386) (xy 195.053196 -210.724003) (xy 195.076139 -210.781951) (xy 195.091639 -210.842319)
			(xy 195.099451 -210.904153) (xy 195.09994 -210.935316) (xy 198.208392 -210.935316) (xy 198.208892 -210.902615)
			(xy 198.217505 -210.837781) (xy 198.23457 -210.774644) (xy 198.259791 -210.7143) (xy 198.29273 -210.657797)
			(xy 198.332814 -210.606117) (xy 198.355712 -210.582764) (xy 198.363078 -210.575398) (xy 198.370698 -210.556856)
			(xy 198.370698 -210.463892) (xy 198.363078 -210.44535) (xy 198.355712 -210.437984) (xy 198.332781 -210.414663)
			(xy 198.292701 -210.362977) (xy 198.25977 -210.306467) (xy 198.234559 -210.246116) (xy 198.217508 -210.182973)
			(xy 198.208912 -210.118135) (xy 198.208392 -210.085432) (xy 198.208881 -210.054269) (xy 198.216693 -209.992435)
			(xy 198.232193 -209.932067) (xy 198.255136 -209.874119) (xy 198.285162 -209.819502) (xy 198.321796 -209.76908)
			(xy 198.364461 -209.723646) (xy 198.412483 -209.683918) (xy 198.465107 -209.650523) (xy 198.521501 -209.623986)
			(xy 198.580776 -209.604726) (xy 198.641997 -209.593047) (xy 198.7042 -209.589134) (xy 198.766403 -209.593047)
			(xy 198.827624 -209.604726) (xy 198.886899 -209.623986) (xy 198.943293 -209.650523) (xy 198.995917 -209.683918)
			(xy 199.043939 -209.723646) (xy 199.086604 -209.76908) (xy 199.123238 -209.819502) (xy 199.153264 -209.874119)
			(xy 199.176207 -209.932067) (xy 199.191707 -209.992435) (xy 199.199519 -210.054269) (xy 199.200008 -210.085432)
			(xy 203.162931 -210.085432) (xy 203.166866 -210.031661) (xy 203.178589 -209.979037) (xy 203.197849 -209.92868)
			(xy 203.224235 -209.881663) (xy 203.257187 -209.83899) (xy 203.296 -209.801569) (xy 203.339848 -209.770199)
			(xy 203.387796 -209.745547) (xy 203.438823 -209.728139) (xy 203.491841 -209.718346) (xy 203.54572 -209.716377)
			(xy 203.599311 -209.722274) (xy 203.651472 -209.73591) (xy 203.701092 -209.756997) (xy 203.747113 -209.785083)
			(xy 203.788555 -209.819571) (xy 203.824533 -209.859725) (xy 203.854281 -209.904689) (xy 203.877166 -209.953506)
			(xy 203.892698 -210.005135) (xy 203.900548 -210.058475) (xy 203.90104 -210.085432) (xy 203.900548 -210.112389)
			(xy 203.892698 -210.165729) (xy 203.877166 -210.217358) (xy 203.854281 -210.266175) (xy 203.824533 -210.311139)
			(xy 203.788555 -210.351293) (xy 203.747113 -210.385781) (xy 203.701092 -210.413867) (xy 203.651472 -210.434954)
			(xy 203.599311 -210.44859) (xy 203.54572 -210.454487) (xy 203.491841 -210.452518) (xy 203.438823 -210.442725)
			(xy 203.387796 -210.425317) (xy 203.339848 -210.400665) (xy 203.296 -210.369295) (xy 203.257187 -210.331874)
			(xy 203.224235 -210.289201) (xy 203.197849 -210.242184) (xy 203.178589 -210.191827) (xy 203.166866 -210.139203)
			(xy 203.162931 -210.085432) (xy 199.200008 -210.085432) (xy 199.199474 -210.118132) (xy 199.190868 -210.182964)
			(xy 199.173809 -210.246101) (xy 199.148595 -210.306445) (xy 199.115662 -210.362949) (xy 199.075583 -210.414631)
			(xy 199.052688 -210.437984) (xy 199.045322 -210.44535) (xy 199.037702 -210.463892) (xy 199.037702 -210.510374)
			(xy 199.452499 -210.510374) (xy 199.456434 -210.456603) (xy 199.468157 -210.403979) (xy 199.487417 -210.353622)
			(xy 199.513803 -210.306605) (xy 199.546755 -210.263932) (xy 199.585568 -210.226511) (xy 199.629416 -210.195141)
			(xy 199.677364 -210.170489) (xy 199.728391 -210.153081) (xy 199.781409 -210.143288) (xy 199.835288 -210.141319)
			(xy 199.888879 -210.147216) (xy 199.94104 -210.160852) (xy 199.99066 -210.181939) (xy 200.036681 -210.210025)
			(xy 200.078123 -210.244513) (xy 200.114101 -210.284667) (xy 200.143849 -210.329631) (xy 200.166734 -210.378448)
			(xy 200.182266 -210.430077) (xy 200.190116 -210.483417) (xy 200.190608 -210.510374) (xy 200.190116 -210.537331)
			(xy 200.182266 -210.590671) (xy 200.166734 -210.6423) (xy 200.143849 -210.691117) (xy 200.114101 -210.736081)
			(xy 200.078123 -210.776235) (xy 200.036681 -210.810723) (xy 199.99066 -210.838809) (xy 199.94104 -210.859896)
			(xy 199.888879 -210.873532) (xy 199.835288 -210.879429) (xy 199.781409 -210.87746) (xy 199.728391 -210.867667)
			(xy 199.677364 -210.850259) (xy 199.629416 -210.825607) (xy 199.585568 -210.794237) (xy 199.546755 -210.756816)
			(xy 199.513803 -210.714143) (xy 199.487417 -210.667126) (xy 199.468157 -210.616769) (xy 199.456434 -210.564145)
			(xy 199.452499 -210.510374) (xy 199.037702 -210.510374) (xy 199.037702 -210.556856) (xy 199.045322 -210.575398)
			(xy 199.052688 -210.582764) (xy 199.075594 -210.606108) (xy 199.115676 -210.657789) (xy 199.148611 -210.714294)
			(xy 199.173826 -210.774641) (xy 199.190882 -210.83778) (xy 199.199485 -210.902615) (xy 199.200008 -210.935316)
			(xy 199.199519 -210.966479) (xy 199.191707 -211.028313) (xy 199.176207 -211.088681) (xy 199.153264 -211.146629)
			(xy 199.123238 -211.201246) (xy 199.086604 -211.251668) (xy 199.043939 -211.297102) (xy 198.995917 -211.33683)
			(xy 198.943293 -211.370225) (xy 198.886899 -211.396762) (xy 198.827624 -211.416022) (xy 198.766403 -211.427701)
			(xy 198.7042 -211.431614) (xy 198.641997 -211.427701) (xy 198.580776 -211.416022) (xy 198.521501 -211.396762)
			(xy 198.465107 -211.370225) (xy 198.412483 -211.33683) (xy 198.364461 -211.297102) (xy 198.321796 -211.251668)
			(xy 198.285162 -211.201246) (xy 198.255136 -211.146629) (xy 198.232193 -211.088681) (xy 198.216693 -211.028313)
			(xy 198.208881 -210.966479) (xy 198.208392 -210.935316) (xy 195.09994 -210.935316) (xy 195.099387 -210.968016)
			(xy 195.090783 -211.032846) (xy 195.073727 -211.095982) (xy 195.048516 -211.156327) (xy 195.015588 -211.212831)
			(xy 194.975513 -211.264514) (xy 194.95262 -211.287868) (xy 194.945254 -211.295234) (xy 194.937634 -211.313776)
			(xy 194.937634 -211.360258) (xy 195.352431 -211.360258) (xy 195.356366 -211.306487) (xy 195.368089 -211.253863)
			(xy 195.387349 -211.203506) (xy 195.413735 -211.156489) (xy 195.446687 -211.113816) (xy 195.4855 -211.076395)
			(xy 195.529348 -211.045025) (xy 195.577296 -211.020373) (xy 195.628323 -211.002965) (xy 195.681341 -210.993172)
			(xy 195.73522 -210.991203) (xy 195.788811 -210.9971) (xy 195.840972 -211.010736) (xy 195.890592 -211.031823)
			(xy 195.936613 -211.059909) (xy 195.978055 -211.094397) (xy 196.014033 -211.134551) (xy 196.043781 -211.179515)
			(xy 196.066666 -211.228332) (xy 196.082198 -211.279961) (xy 196.090048 -211.333301) (xy 196.09054 -211.360258)
			(xy 196.090048 -211.387215) (xy 196.082198 -211.440555) (xy 196.066666 -211.492184) (xy 196.043781 -211.541001)
			(xy 196.014033 -211.585965) (xy 195.978055 -211.626119) (xy 195.936613 -211.660607) (xy 195.890592 -211.688693)
			(xy 195.840972 -211.70978) (xy 195.788811 -211.723416) (xy 195.73522 -211.729313) (xy 195.681341 -211.727344)
			(xy 195.628323 -211.717551) (xy 195.577296 -211.700143) (xy 195.529348 -211.675491) (xy 195.4855 -211.644121)
			(xy 195.446687 -211.6067) (xy 195.413735 -211.564027) (xy 195.387349 -211.51701) (xy 195.368089 -211.466653)
			(xy 195.356366 -211.414029) (xy 195.352431 -211.360258) (xy 194.937634 -211.360258) (xy 194.937634 -211.40674)
			(xy 194.945254 -211.425282) (xy 194.95262 -211.432648) (xy 194.975506 -211.456011) (xy 195.015592 -211.507687)
			(xy 195.048531 -211.564187) (xy 195.07375 -211.624531) (xy 195.09081 -211.687667) (xy 195.099415 -211.7525)
			(xy 195.09994 -211.7852) (xy 196.950599 -211.7852) (xy 196.954534 -211.731429) (xy 196.966257 -211.678805)
			(xy 196.985517 -211.628448) (xy 197.011903 -211.581431) (xy 197.044855 -211.538758) (xy 197.083668 -211.501337)
			(xy 197.127516 -211.469967) (xy 197.175464 -211.445315) (xy 197.226491 -211.427907) (xy 197.279509 -211.418114)
			(xy 197.333388 -211.416145) (xy 197.386979 -211.422042) (xy 197.43914 -211.435678) (xy 197.48876 -211.456765)
			(xy 197.534781 -211.484851) (xy 197.576223 -211.519339) (xy 197.612201 -211.559493) (xy 197.641949 -211.604457)
			(xy 197.664834 -211.653274) (xy 197.680366 -211.704903) (xy 197.688216 -211.758243) (xy 197.688708 -211.7852)
			(xy 201.652124 -211.7852) (xy 201.652634 -211.752499) (xy 201.661248 -211.687667) (xy 201.678312 -211.624531)
			(xy 201.703532 -211.564187) (xy 201.736468 -211.507683) (xy 201.776548 -211.456002) (xy 201.799444 -211.432648)
			(xy 201.80681 -211.425282) (xy 201.81443 -211.40674) (xy 201.81443 -211.313776) (xy 201.80681 -211.295234)
			(xy 201.799444 -211.287868) (xy 201.776559 -211.264504) (xy 201.736474 -211.212828) (xy 201.703536 -211.156327)
			(xy 201.678317 -211.095984) (xy 201.661256 -211.032848) (xy 201.65265 -210.968016) (xy 201.652124 -210.935316)
			(xy 201.652613 -210.904153) (xy 201.660425 -210.842319) (xy 201.675925 -210.781951) (xy 201.698868 -210.724003)
			(xy 201.728894 -210.669386) (xy 201.765528 -210.618964) (xy 201.808193 -210.57353) (xy 201.856215 -210.533802)
			(xy 201.908839 -210.500407) (xy 201.965233 -210.47387) (xy 202.024508 -210.45461) (xy 202.085729 -210.442931)
			(xy 202.147932 -210.439018) (xy 202.210135 -210.442931) (xy 202.271356 -210.45461) (xy 202.330631 -210.47387)
			(xy 202.387025 -210.500407) (xy 202.439649 -210.533802) (xy 202.487671 -210.57353) (xy 202.530336 -210.618964)
			(xy 202.56697 -210.669386) (xy 202.596996 -210.724003) (xy 202.619939 -210.781951) (xy 202.635439 -210.842319)
			(xy 202.643251 -210.904153) (xy 202.64374 -210.935316) (xy 205.752192 -210.935316) (xy 205.752692 -210.902615)
			(xy 205.761305 -210.837781) (xy 205.77837 -210.774644) (xy 205.803591 -210.7143) (xy 205.83653 -210.657797)
			(xy 205.876614 -210.606117) (xy 205.899512 -210.582764) (xy 205.906878 -210.575398) (xy 205.914498 -210.556856)
			(xy 205.914498 -210.463892) (xy 205.906878 -210.44535) (xy 205.899512 -210.437984) (xy 205.876581 -210.414663)
			(xy 205.836501 -210.362977) (xy 205.80357 -210.306467) (xy 205.778359 -210.246116) (xy 205.761308 -210.182973)
			(xy 205.752712 -210.118135) (xy 205.752192 -210.085432) (xy 205.752681 -210.054269) (xy 205.760493 -209.992435)
			(xy 205.775993 -209.932067) (xy 205.798936 -209.874119) (xy 205.828962 -209.819502) (xy 205.865596 -209.76908)
			(xy 205.908261 -209.723646) (xy 205.956283 -209.683918) (xy 206.008907 -209.650523) (xy 206.065301 -209.623986)
			(xy 206.124576 -209.604726) (xy 206.185797 -209.593047) (xy 206.248 -209.589134) (xy 206.310203 -209.593047)
			(xy 206.371424 -209.604726) (xy 206.430699 -209.623986) (xy 206.487093 -209.650523) (xy 206.539717 -209.683918)
			(xy 206.587739 -209.723646) (xy 206.630404 -209.76908) (xy 206.667038 -209.819502) (xy 206.697064 -209.874119)
			(xy 206.720007 -209.932067) (xy 206.735507 -209.992435) (xy 206.743319 -210.054269) (xy 206.743808 -210.085432)
			(xy 206.743274 -210.118132) (xy 206.734668 -210.182964) (xy 206.717609 -210.246101) (xy 206.692395 -210.306445)
			(xy 206.659462 -210.362949) (xy 206.619383 -210.414631) (xy 206.596488 -210.437984) (xy 206.589122 -210.44535)
			(xy 206.581502 -210.463892) (xy 206.581502 -210.510374) (xy 206.996299 -210.510374) (xy 207.000234 -210.456603)
			(xy 207.011957 -210.403979) (xy 207.031217 -210.353622) (xy 207.057603 -210.306605) (xy 207.090555 -210.263932)
			(xy 207.129368 -210.226511) (xy 207.173216 -210.195141) (xy 207.221164 -210.170489) (xy 207.272191 -210.153081)
			(xy 207.325209 -210.143288) (xy 207.379088 -210.141319) (xy 207.432679 -210.147216) (xy 207.48484 -210.160852)
			(xy 207.53446 -210.181939) (xy 207.580481 -210.210025) (xy 207.621923 -210.244513) (xy 207.657901 -210.284667)
			(xy 207.687649 -210.329631) (xy 207.710534 -210.378448) (xy 207.726066 -210.430077) (xy 207.733916 -210.483417)
			(xy 207.734408 -210.510374) (xy 207.733916 -210.537331) (xy 207.726066 -210.590671) (xy 207.710534 -210.6423)
			(xy 207.687649 -210.691117) (xy 207.657901 -210.736081) (xy 207.621923 -210.776235) (xy 207.580481 -210.810723)
			(xy 207.53446 -210.838809) (xy 207.48484 -210.859896) (xy 207.432679 -210.873532) (xy 207.379088 -210.879429)
			(xy 207.325209 -210.87746) (xy 207.272191 -210.867667) (xy 207.221164 -210.850259) (xy 207.173216 -210.825607)
			(xy 207.129368 -210.794237) (xy 207.090555 -210.756816) (xy 207.057603 -210.714143) (xy 207.031217 -210.667126)
			(xy 207.011957 -210.616769) (xy 207.000234 -210.564145) (xy 206.996299 -210.510374) (xy 206.581502 -210.510374)
			(xy 206.581502 -210.556856) (xy 206.589122 -210.575398) (xy 206.596488 -210.582764) (xy 206.619394 -210.606108)
			(xy 206.659476 -210.657789) (xy 206.692411 -210.714294) (xy 206.717626 -210.774641) (xy 206.734682 -210.83778)
			(xy 206.743285 -210.902615) (xy 206.743808 -210.935316) (xy 206.743319 -210.966479) (xy 206.735507 -211.028313)
			(xy 206.720007 -211.088681) (xy 206.697064 -211.146629) (xy 206.667038 -211.201246) (xy 206.630404 -211.251668)
			(xy 206.587739 -211.297102) (xy 206.539717 -211.33683) (xy 206.487093 -211.370225) (xy 206.430699 -211.396762)
			(xy 206.371424 -211.416022) (xy 206.310203 -211.427701) (xy 206.248 -211.431614) (xy 206.185797 -211.427701)
			(xy 206.124576 -211.416022) (xy 206.065301 -211.396762) (xy 206.008907 -211.370225) (xy 205.956283 -211.33683)
			(xy 205.908261 -211.297102) (xy 205.865596 -211.251668) (xy 205.828962 -211.201246) (xy 205.798936 -211.146629)
			(xy 205.775993 -211.088681) (xy 205.760493 -211.028313) (xy 205.752681 -210.966479) (xy 205.752192 -210.935316)
			(xy 202.64374 -210.935316) (xy 202.643187 -210.968016) (xy 202.634583 -211.032846) (xy 202.617527 -211.095982)
			(xy 202.592316 -211.156327) (xy 202.559388 -211.212831) (xy 202.519313 -211.264514) (xy 202.49642 -211.287868)
			(xy 202.489054 -211.295234) (xy 202.481434 -211.313776) (xy 202.481434 -211.360258) (xy 202.896231 -211.360258)
			(xy 202.900166 -211.306487) (xy 202.911889 -211.253863) (xy 202.931149 -211.203506) (xy 202.957535 -211.156489)
			(xy 202.990487 -211.113816) (xy 203.0293 -211.076395) (xy 203.073148 -211.045025) (xy 203.121096 -211.020373)
			(xy 203.172123 -211.002965) (xy 203.225141 -210.993172) (xy 203.27902 -210.991203) (xy 203.332611 -210.9971)
			(xy 203.384772 -211.010736) (xy 203.434392 -211.031823) (xy 203.480413 -211.059909) (xy 203.521855 -211.094397)
			(xy 203.557833 -211.134551) (xy 203.587581 -211.179515) (xy 203.610466 -211.228332) (xy 203.625998 -211.279961)
			(xy 203.633848 -211.333301) (xy 203.63434 -211.360258) (xy 203.633848 -211.387215) (xy 203.625998 -211.440555)
			(xy 203.610466 -211.492184) (xy 203.587581 -211.541001) (xy 203.557833 -211.585965) (xy 203.521855 -211.626119)
			(xy 203.480413 -211.660607) (xy 203.434392 -211.688693) (xy 203.384772 -211.70978) (xy 203.332611 -211.723416)
			(xy 203.27902 -211.729313) (xy 203.225141 -211.727344) (xy 203.172123 -211.717551) (xy 203.121096 -211.700143)
			(xy 203.073148 -211.675491) (xy 203.0293 -211.644121) (xy 202.990487 -211.6067) (xy 202.957535 -211.564027)
			(xy 202.931149 -211.51701) (xy 202.911889 -211.466653) (xy 202.900166 -211.414029) (xy 202.896231 -211.360258)
			(xy 202.481434 -211.360258) (xy 202.481434 -211.40674) (xy 202.489054 -211.425282) (xy 202.49642 -211.432648)
			(xy 202.519306 -211.456011) (xy 202.559392 -211.507687) (xy 202.592331 -211.564187) (xy 202.61755 -211.624531)
			(xy 202.63461 -211.687667) (xy 202.643215 -211.7525) (xy 202.64374 -211.7852) (xy 204.494399 -211.7852)
			(xy 204.498334 -211.731429) (xy 204.510057 -211.678805) (xy 204.529317 -211.628448) (xy 204.555703 -211.581431)
			(xy 204.588655 -211.538758) (xy 204.627468 -211.501337) (xy 204.671316 -211.469967) (xy 204.719264 -211.445315)
			(xy 204.770291 -211.427907) (xy 204.823309 -211.418114) (xy 204.877188 -211.416145) (xy 204.930779 -211.422042)
			(xy 204.98294 -211.435678) (xy 205.03256 -211.456765) (xy 205.078581 -211.484851) (xy 205.120023 -211.519339)
			(xy 205.156001 -211.559493) (xy 205.185749 -211.604457) (xy 205.208634 -211.653274) (xy 205.224166 -211.704903)
			(xy 205.232016 -211.758243) (xy 205.232508 -211.7852) (xy 205.232016 -211.812157) (xy 205.224166 -211.865497)
			(xy 205.208634 -211.917126) (xy 205.185749 -211.965943) (xy 205.156001 -212.010907) (xy 205.120023 -212.051061)
			(xy 205.078581 -212.085549) (xy 205.03256 -212.113635) (xy 204.98294 -212.134722) (xy 204.930779 -212.148358)
			(xy 204.877188 -212.154255) (xy 204.823309 -212.152286) (xy 204.770291 -212.142493) (xy 204.719264 -212.125085)
			(xy 204.671316 -212.100433) (xy 204.627468 -212.069063) (xy 204.588655 -212.031642) (xy 204.555703 -211.988969)
			(xy 204.529317 -211.941952) (xy 204.510057 -211.891595) (xy 204.498334 -211.838971) (xy 204.494399 -211.7852)
			(xy 202.64374 -211.7852) (xy 202.643251 -211.816363) (xy 202.635439 -211.878197) (xy 202.619939 -211.938565)
			(xy 202.596996 -211.996513) (xy 202.56697 -212.05113) (xy 202.530336 -212.101552) (xy 202.487671 -212.146986)
			(xy 202.439649 -212.186714) (xy 202.387025 -212.220109) (xy 202.330631 -212.246646) (xy 202.271356 -212.265906)
			(xy 202.210135 -212.277585) (xy 202.147932 -212.281498) (xy 202.085729 -212.277585) (xy 202.024508 -212.265906)
			(xy 201.965233 -212.246646) (xy 201.908839 -212.220109) (xy 201.856215 -212.186714) (xy 201.808193 -212.146986)
			(xy 201.765528 -212.101552) (xy 201.728894 -212.05113) (xy 201.698868 -211.996513) (xy 201.675925 -211.938565)
			(xy 201.660425 -211.878197) (xy 201.652613 -211.816363) (xy 201.652124 -211.7852) (xy 197.688708 -211.7852)
			(xy 197.688216 -211.812157) (xy 197.680366 -211.865497) (xy 197.664834 -211.917126) (xy 197.641949 -211.965943)
			(xy 197.612201 -212.010907) (xy 197.576223 -212.051061) (xy 197.534781 -212.085549) (xy 197.48876 -212.113635)
			(xy 197.43914 -212.134722) (xy 197.386979 -212.148358) (xy 197.333388 -212.154255) (xy 197.279509 -212.152286)
			(xy 197.226491 -212.142493) (xy 197.175464 -212.125085) (xy 197.127516 -212.100433) (xy 197.083668 -212.069063)
			(xy 197.044855 -212.031642) (xy 197.011903 -211.988969) (xy 196.985517 -211.941952) (xy 196.966257 -211.891595)
			(xy 196.954534 -211.838971) (xy 196.950599 -211.7852) (xy 195.09994 -211.7852) (xy 195.099451 -211.816363)
			(xy 195.091639 -211.878197) (xy 195.076139 -211.938565) (xy 195.053196 -211.996513) (xy 195.02317 -212.05113)
			(xy 194.986536 -212.101552) (xy 194.943871 -212.146986) (xy 194.895849 -212.186714) (xy 194.843225 -212.220109)
			(xy 194.786831 -212.246646) (xy 194.727556 -212.265906) (xy 194.666335 -212.277585) (xy 194.604132 -212.281498)
			(xy 194.541929 -212.277585) (xy 194.480708 -212.265906) (xy 194.421433 -212.246646) (xy 194.365039 -212.220109)
			(xy 194.312415 -212.186714) (xy 194.264393 -212.146986) (xy 194.221728 -212.101552) (xy 194.185094 -212.05113)
			(xy 194.155068 -211.996513) (xy 194.132125 -211.938565) (xy 194.116625 -211.878197) (xy 194.108813 -211.816363)
			(xy 194.108324 -211.7852) (xy 190.144654 -211.7852) (xy 190.144162 -211.812157) (xy 190.136312 -211.865497)
			(xy 190.12078 -211.917126) (xy 190.097895 -211.965943) (xy 190.068147 -212.010907) (xy 190.032169 -212.051061)
			(xy 189.990727 -212.085549) (xy 189.944706 -212.113635) (xy 189.895086 -212.134722) (xy 189.842925 -212.148358)
			(xy 189.789334 -212.154255) (xy 189.735455 -212.152286) (xy 189.682437 -212.142493) (xy 189.63141 -212.125085)
			(xy 189.583462 -212.100433) (xy 189.539614 -212.069063) (xy 189.500801 -212.031642) (xy 189.467849 -211.988969)
			(xy 189.441463 -211.941952) (xy 189.422203 -211.891595) (xy 189.41048 -211.838971) (xy 189.406545 -211.7852)
			(xy 187.555886 -211.7852) (xy 187.555397 -211.816363) (xy 187.547585 -211.878197) (xy 187.532085 -211.938565)
			(xy 187.509142 -211.996513) (xy 187.479116 -212.05113) (xy 187.442482 -212.101552) (xy 187.399817 -212.146986)
			(xy 187.351795 -212.186714) (xy 187.299171 -212.220109) (xy 187.242777 -212.246646) (xy 187.183502 -212.265906)
			(xy 187.122281 -212.277585) (xy 187.060078 -212.281498) (xy 186.997875 -212.277585) (xy 186.936654 -212.265906)
			(xy 186.877379 -212.246646) (xy 186.820985 -212.220109) (xy 186.768361 -212.186714) (xy 186.720339 -212.146986)
			(xy 186.677674 -212.101552) (xy 186.64104 -212.05113) (xy 186.611014 -211.996513) (xy 186.588071 -211.938565)
			(xy 186.572571 -211.878197) (xy 186.564759 -211.816363) (xy 186.56427 -211.7852) (xy 182.6006 -211.7852)
			(xy 182.600108 -211.812157) (xy 182.592258 -211.865497) (xy 182.576726 -211.917126) (xy 182.553841 -211.965943)
			(xy 182.524093 -212.010907) (xy 182.488115 -212.051061) (xy 182.446673 -212.085549) (xy 182.400652 -212.113635)
			(xy 182.351032 -212.134722) (xy 182.298871 -212.148358) (xy 182.24528 -212.154255) (xy 182.191401 -212.152286)
			(xy 182.138383 -212.142493) (xy 182.087356 -212.125085) (xy 182.039408 -212.100433) (xy 181.99556 -212.069063)
			(xy 181.956747 -212.031642) (xy 181.923795 -211.988969) (xy 181.897409 -211.941952) (xy 181.878149 -211.891595)
			(xy 181.866426 -211.838971) (xy 181.862491 -211.7852) (xy 180.011832 -211.7852) (xy 180.011343 -211.816363)
			(xy 180.003531 -211.878197) (xy 179.988031 -211.938565) (xy 179.965088 -211.996513) (xy 179.935062 -212.05113)
			(xy 179.898428 -212.101552) (xy 179.855763 -212.146986) (xy 179.807741 -212.186714) (xy 179.755117 -212.220109)
			(xy 179.698723 -212.246646) (xy 179.639448 -212.265906) (xy 179.578227 -212.277585) (xy 179.516024 -212.281498)
			(xy 179.453821 -212.277585) (xy 179.3926 -212.265906) (xy 179.333325 -212.246646) (xy 179.276931 -212.220109)
			(xy 179.224307 -212.186714) (xy 179.176285 -212.146986) (xy 179.13362 -212.101552) (xy 179.096986 -212.05113)
			(xy 179.06696 -211.996513) (xy 179.044017 -211.938565) (xy 179.028517 -211.878197) (xy 179.020705 -211.816363)
			(xy 179.020216 -211.7852) (xy 175.056546 -211.7852) (xy 175.056054 -211.812157) (xy 175.048204 -211.865497)
			(xy 175.032672 -211.917126) (xy 175.009787 -211.965943) (xy 174.980039 -212.010907) (xy 174.944061 -212.051061)
			(xy 174.902619 -212.085549) (xy 174.856598 -212.113635) (xy 174.806978 -212.134722) (xy 174.754817 -212.148358)
			(xy 174.701226 -212.154255) (xy 174.647347 -212.152286) (xy 174.594329 -212.142493) (xy 174.543302 -212.125085)
			(xy 174.495354 -212.100433) (xy 174.451506 -212.069063) (xy 174.412693 -212.031642) (xy 174.379741 -211.988969)
			(xy 174.353355 -211.941952) (xy 174.334095 -211.891595) (xy 174.322372 -211.838971) (xy 174.318437 -211.7852)
			(xy 172.467778 -211.7852) (xy 172.467289 -211.816363) (xy 172.459477 -211.878197) (xy 172.443977 -211.938565)
			(xy 172.421034 -211.996513) (xy 172.391008 -212.05113) (xy 172.354374 -212.101552) (xy 172.311709 -212.146986)
			(xy 172.263687 -212.186714) (xy 172.211063 -212.220109) (xy 172.154669 -212.246646) (xy 172.095394 -212.265906)
			(xy 172.034173 -212.277585) (xy 171.97197 -212.281498) (xy 171.909767 -212.277585) (xy 171.848546 -212.265906)
			(xy 171.789271 -212.246646) (xy 171.732877 -212.220109) (xy 171.680253 -212.186714) (xy 171.632231 -212.146986)
			(xy 171.589566 -212.101552) (xy 171.552932 -212.05113) (xy 171.522906 -211.996513) (xy 171.499963 -211.938565)
			(xy 171.484463 -211.878197) (xy 171.476651 -211.816363) (xy 171.476162 -211.7852) (xy 167.512492 -211.7852)
			(xy 167.512 -211.812157) (xy 167.50415 -211.865497) (xy 167.488618 -211.917126) (xy 167.465733 -211.965943)
			(xy 167.435985 -212.010907) (xy 167.400007 -212.051061) (xy 167.358565 -212.085549) (xy 167.312544 -212.113635)
			(xy 167.262924 -212.134722) (xy 167.210763 -212.148358) (xy 167.157172 -212.154255) (xy 167.103293 -212.152286)
			(xy 167.050275 -212.142493) (xy 166.999248 -212.125085) (xy 166.9513 -212.100433) (xy 166.907452 -212.069063)
			(xy 166.868639 -212.031642) (xy 166.835687 -211.988969) (xy 166.809301 -211.941952) (xy 166.790041 -211.891595)
			(xy 166.778318 -211.838971) (xy 166.774383 -211.7852) (xy 161.612834 -211.7852) (xy 161.612834 -212.635338)
			(xy 165.442915 -212.635338) (xy 165.44685 -212.581567) (xy 165.458573 -212.528943) (xy 165.477833 -212.478586)
			(xy 165.504219 -212.431569) (xy 165.537171 -212.388896) (xy 165.575984 -212.351475) (xy 165.619832 -212.320105)
			(xy 165.66778 -212.295453) (xy 165.718807 -212.278045) (xy 165.771825 -212.268252) (xy 165.825704 -212.266283)
			(xy 165.879295 -212.27218) (xy 165.931456 -212.285816) (xy 165.981076 -212.306903) (xy 166.027097 -212.334989)
			(xy 166.068539 -212.369477) (xy 166.104517 -212.409631) (xy 166.134265 -212.454595) (xy 166.15715 -212.503412)
			(xy 166.172682 -212.555041) (xy 166.180532 -212.608381) (xy 166.181024 -212.635338) (xy 172.986969 -212.635338)
			(xy 172.990904 -212.581567) (xy 173.002627 -212.528943) (xy 173.021887 -212.478586) (xy 173.048273 -212.431569)
			(xy 173.081225 -212.388896) (xy 173.120038 -212.351475) (xy 173.163886 -212.320105) (xy 173.211834 -212.295453)
			(xy 173.262861 -212.278045) (xy 173.315879 -212.268252) (xy 173.369758 -212.266283) (xy 173.423349 -212.27218)
			(xy 173.47551 -212.285816) (xy 173.52513 -212.306903) (xy 173.571151 -212.334989) (xy 173.612593 -212.369477)
			(xy 173.648571 -212.409631) (xy 173.678319 -212.454595) (xy 173.701204 -212.503412) (xy 173.716736 -212.555041)
			(xy 173.724586 -212.608381) (xy 173.725078 -212.635338) (xy 173.724586 -212.662295) (xy 173.716736 -212.715635)
			(xy 173.701204 -212.767264) (xy 173.678319 -212.816081) (xy 173.648571 -212.861045) (xy 173.612593 -212.901199)
			(xy 173.571151 -212.935687) (xy 173.52513 -212.963773) (xy 173.47551 -212.98486) (xy 173.423349 -212.998496)
			(xy 173.369758 -213.004393) (xy 173.315879 -213.002424) (xy 173.262861 -212.992631) (xy 173.211834 -212.975223)
			(xy 173.163886 -212.950571) (xy 173.120038 -212.919201) (xy 173.081225 -212.88178) (xy 173.048273 -212.839107)
			(xy 173.021887 -212.79209) (xy 173.002627 -212.741733) (xy 172.990904 -212.689109) (xy 172.986969 -212.635338)
			(xy 166.181024 -212.635338) (xy 166.180532 -212.662295) (xy 166.172682 -212.715635) (xy 166.15715 -212.767264)
			(xy 166.134265 -212.816081) (xy 166.104517 -212.861045) (xy 166.068539 -212.901199) (xy 166.027097 -212.935687)
			(xy 165.981076 -212.963773) (xy 165.931456 -212.98486) (xy 165.879295 -212.998496) (xy 165.825704 -213.004393)
			(xy 165.771825 -213.002424) (xy 165.718807 -212.992631) (xy 165.66778 -212.975223) (xy 165.619832 -212.950571)
			(xy 165.575984 -212.919201) (xy 165.537171 -212.88178) (xy 165.504219 -212.839107) (xy 165.477833 -212.79209)
			(xy 165.458573 -212.741733) (xy 165.44685 -212.689109) (xy 165.442915 -212.635338) (xy 161.612834 -212.635338)
			(xy 161.612834 -213.485222) (xy 168.158683 -213.485222) (xy 168.162618 -213.431451) (xy 168.174341 -213.378827)
			(xy 168.193601 -213.32847) (xy 168.219987 -213.281453) (xy 168.252939 -213.23878) (xy 168.291752 -213.201359)
			(xy 168.3356 -213.169989) (xy 168.383548 -213.145337) (xy 168.434575 -213.127929) (xy 168.487593 -213.118136)
			(xy 168.541472 -213.116167) (xy 168.595063 -213.122064) (xy 168.647224 -213.1357) (xy 168.696844 -213.156787)
			(xy 168.742865 -213.184873) (xy 168.784307 -213.219361) (xy 168.820285 -213.259515) (xy 168.850033 -213.304479)
			(xy 168.872918 -213.353296) (xy 168.88845 -213.404925) (xy 168.8963 -213.458265) (xy 168.896792 -213.485222)
			(xy 168.8963 -213.512179) (xy 168.88845 -213.565519) (xy 168.872918 -213.617148) (xy 168.850033 -213.665965)
			(xy 168.820285 -213.710929) (xy 168.784307 -213.751083) (xy 168.742865 -213.785571) (xy 168.696844 -213.813657)
			(xy 168.647224 -213.834744) (xy 168.595063 -213.84838) (xy 168.541472 -213.854277) (xy 168.487593 -213.852308)
			(xy 168.434575 -213.842515) (xy 168.383548 -213.825107) (xy 168.3356 -213.800455) (xy 168.291752 -213.769085)
			(xy 168.252939 -213.731664) (xy 168.219987 -213.688991) (xy 168.193601 -213.641974) (xy 168.174341 -213.591617)
			(xy 168.162618 -213.538993) (xy 168.158683 -213.485222) (xy 161.612834 -213.485222) (xy 161.612834 -214.33536)
			(xy 164.058615 -214.33536) (xy 164.06255 -214.281589) (xy 164.074273 -214.228965) (xy 164.093533 -214.178608)
			(xy 164.119919 -214.131591) (xy 164.152871 -214.088918) (xy 164.191684 -214.051497) (xy 164.235532 -214.020127)
			(xy 164.28348 -213.995475) (xy 164.334507 -213.978067) (xy 164.387525 -213.968274) (xy 164.441404 -213.966305)
			(xy 164.494995 -213.972202) (xy 164.547156 -213.985838) (xy 164.596776 -214.006925) (xy 164.642797 -214.035011)
			(xy 164.684239 -214.069499) (xy 164.720217 -214.109653) (xy 164.749965 -214.154617) (xy 164.77285 -214.203434)
			(xy 164.788382 -214.255063) (xy 164.796232 -214.308403) (xy 164.796724 -214.33536) (xy 164.796232 -214.362317)
			(xy 164.788382 -214.415657) (xy 164.77285 -214.467286) (xy 164.749965 -214.516103) (xy 164.720217 -214.561067)
			(xy 164.684239 -214.601221) (xy 164.642797 -214.635709) (xy 164.596776 -214.663795) (xy 164.547156 -214.684882)
			(xy 164.494995 -214.698518) (xy 164.441404 -214.704415) (xy 164.387525 -214.702446) (xy 164.334507 -214.692653)
			(xy 164.28348 -214.675245) (xy 164.235532 -214.650593) (xy 164.191684 -214.619223) (xy 164.152871 -214.581802)
			(xy 164.119919 -214.539129) (xy 164.093533 -214.492112) (xy 164.074273 -214.441755) (xy 164.06255 -214.389131)
			(xy 164.058615 -214.33536) (xy 161.612834 -214.33536) (xy 161.612834 -215.185244) (xy 168.158683 -215.185244)
			(xy 168.162618 -215.131473) (xy 168.174341 -215.078849) (xy 168.193601 -215.028492) (xy 168.219987 -214.981475)
			(xy 168.252939 -214.938802) (xy 168.291752 -214.901381) (xy 168.3356 -214.870011) (xy 168.383548 -214.845359)
			(xy 168.434575 -214.827951) (xy 168.487593 -214.818158) (xy 168.541472 -214.816189) (xy 168.595063 -214.822086)
			(xy 168.647224 -214.835722) (xy 168.696844 -214.856809) (xy 168.742865 -214.884895) (xy 168.784307 -214.919383)
			(xy 168.820285 -214.959537) (xy 168.850033 -215.004501) (xy 168.872918 -215.053318) (xy 168.88845 -215.104947)
			(xy 168.8963 -215.158287) (xy 168.896792 -215.185244) (xy 168.8963 -215.212201) (xy 168.88845 -215.265541)
			(xy 168.872918 -215.31717) (xy 168.850033 -215.365987) (xy 168.820285 -215.410951) (xy 168.784307 -215.451105)
			(xy 168.742865 -215.485593) (xy 168.696844 -215.513679) (xy 168.647224 -215.534766) (xy 168.595063 -215.548402)
			(xy 168.541472 -215.554299) (xy 168.487593 -215.55233) (xy 168.434575 -215.542537) (xy 168.383548 -215.525129)
			(xy 168.3356 -215.500477) (xy 168.291752 -215.469107) (xy 168.252939 -215.431686) (xy 168.219987 -215.389013)
			(xy 168.193601 -215.341996) (xy 168.174341 -215.291639) (xy 168.162618 -215.239015) (xy 168.158683 -215.185244)
			(xy 161.612834 -215.185244) (xy 161.612834 -216.035382) (xy 164.058615 -216.035382) (xy 164.06255 -215.981611)
			(xy 164.074273 -215.928987) (xy 164.093533 -215.87863) (xy 164.119919 -215.831613) (xy 164.152871 -215.78894)
			(xy 164.191684 -215.751519) (xy 164.235532 -215.720149) (xy 164.28348 -215.695497) (xy 164.334507 -215.678089)
			(xy 164.387525 -215.668296) (xy 164.441404 -215.666327) (xy 164.494995 -215.672224) (xy 164.547156 -215.68586)
			(xy 164.596776 -215.706947) (xy 164.642797 -215.735033) (xy 164.684239 -215.769521) (xy 164.720217 -215.809675)
			(xy 164.749965 -215.854639) (xy 164.77285 -215.903456) (xy 164.788382 -215.955085) (xy 164.796232 -216.008425)
			(xy 164.796724 -216.035382) (xy 164.796232 -216.062339) (xy 164.788382 -216.115679) (xy 164.77285 -216.167308)
			(xy 164.749965 -216.216125) (xy 164.720217 -216.261089) (xy 164.684239 -216.301243) (xy 164.642797 -216.335731)
			(xy 164.596776 -216.363817) (xy 164.547156 -216.384904) (xy 164.494995 -216.39854) (xy 164.441404 -216.404437)
			(xy 164.387525 -216.402468) (xy 164.334507 -216.392675) (xy 164.28348 -216.375267) (xy 164.235532 -216.350615)
			(xy 164.191684 -216.319245) (xy 164.152871 -216.281824) (xy 164.119919 -216.239151) (xy 164.093533 -216.192134)
			(xy 164.074273 -216.141777) (xy 164.06255 -216.089153) (xy 164.058615 -216.035382) (xy 161.612834 -216.035382)
			(xy 161.612834 -216.885266) (xy 168.158683 -216.885266) (xy 168.162618 -216.831495) (xy 168.174341 -216.778871)
			(xy 168.193601 -216.728514) (xy 168.219987 -216.681497) (xy 168.252939 -216.638824) (xy 168.291752 -216.601403)
			(xy 168.3356 -216.570033) (xy 168.383548 -216.545381) (xy 168.434575 -216.527973) (xy 168.487593 -216.51818)
			(xy 168.541472 -216.516211) (xy 168.595063 -216.522108) (xy 168.647224 -216.535744) (xy 168.696844 -216.556831)
			(xy 168.742865 -216.584917) (xy 168.784307 -216.619405) (xy 168.820285 -216.659559) (xy 168.850033 -216.704523)
			(xy 168.872918 -216.75334) (xy 168.88845 -216.804969) (xy 168.8963 -216.858309) (xy 168.896792 -216.885266)
			(xy 168.8963 -216.912223) (xy 168.88845 -216.965563) (xy 168.872918 -217.017192) (xy 168.850033 -217.066009)
			(xy 168.820285 -217.110973) (xy 168.784307 -217.151127) (xy 168.742865 -217.185615) (xy 168.696844 -217.213701)
			(xy 168.647224 -217.234788) (xy 168.595063 -217.248424) (xy 168.541472 -217.254321) (xy 168.487593 -217.252352)
			(xy 168.434575 -217.242559) (xy 168.383548 -217.225151) (xy 168.3356 -217.200499) (xy 168.291752 -217.169129)
			(xy 168.252939 -217.131708) (xy 168.219987 -217.089035) (xy 168.193601 -217.042018) (xy 168.174341 -216.991661)
			(xy 168.162618 -216.939037) (xy 168.158683 -216.885266) (xy 161.612834 -216.885266) (xy 161.612834 -217.735404)
			(xy 164.058615 -217.735404) (xy 164.06255 -217.681633) (xy 164.074273 -217.629009) (xy 164.093533 -217.578652)
			(xy 164.119919 -217.531635) (xy 164.152871 -217.488962) (xy 164.191684 -217.451541) (xy 164.235532 -217.420171)
			(xy 164.28348 -217.395519) (xy 164.334507 -217.378111) (xy 164.387525 -217.368318) (xy 164.441404 -217.366349)
			(xy 164.494995 -217.372246) (xy 164.547156 -217.385882) (xy 164.596776 -217.406969) (xy 164.642797 -217.435055)
			(xy 164.684239 -217.469543) (xy 164.720217 -217.509697) (xy 164.749965 -217.554661) (xy 164.77285 -217.603478)
			(xy 164.788382 -217.655107) (xy 164.796232 -217.708447) (xy 164.796724 -217.735404) (xy 164.796232 -217.762361)
			(xy 164.788382 -217.815701) (xy 164.77285 -217.86733) (xy 164.749965 -217.916147) (xy 164.720217 -217.961111)
			(xy 164.684239 -218.001265) (xy 164.642797 -218.035753) (xy 164.596776 -218.063839) (xy 164.547156 -218.084926)
			(xy 164.494995 -218.098562) (xy 164.441404 -218.104459) (xy 164.387525 -218.10249) (xy 164.334507 -218.092697)
			(xy 164.28348 -218.075289) (xy 164.235532 -218.050637) (xy 164.191684 -218.019267) (xy 164.152871 -217.981846)
			(xy 164.119919 -217.939173) (xy 164.093533 -217.892156) (xy 164.074273 -217.841799) (xy 164.06255 -217.789175)
			(xy 164.058615 -217.735404) (xy 161.612834 -217.735404) (xy 161.612834 -218.585288) (xy 166.774383 -218.585288)
			(xy 166.778318 -218.531517) (xy 166.790041 -218.478893) (xy 166.809301 -218.428536) (xy 166.835687 -218.381519)
			(xy 166.868639 -218.338846) (xy 166.907452 -218.301425) (xy 166.9513 -218.270055) (xy 166.999248 -218.245403)
			(xy 167.050275 -218.227995) (xy 167.103293 -218.218202) (xy 167.157172 -218.216233) (xy 167.210763 -218.22213)
			(xy 167.262924 -218.235766) (xy 167.312544 -218.256853) (xy 167.358565 -218.284939) (xy 167.400007 -218.319427)
			(xy 167.435985 -218.359581) (xy 167.465733 -218.404545) (xy 167.488618 -218.453362) (xy 167.50415 -218.504991)
			(xy 167.512 -218.558331) (xy 167.512492 -218.585288) (xy 171.476162 -218.585288) (xy 171.476607 -218.55409)
			(xy 171.48443 -218.492188) (xy 171.499963 -218.431757) (xy 171.522961 -218.373755) (xy 171.553059 -218.319099)
			(xy 171.589782 -218.268655) (xy 171.632547 -218.22322) (xy 171.680678 -218.183515) (xy 171.706794 -218.166442)
			(xy 171.716954 -218.159838) (xy 171.729146 -218.140026) (xy 171.738544 -218.035886) (xy 171.730162 -218.014296)
			(xy 171.721272 -218.005914) (xy 171.702989 -217.988396) (xy 171.67091 -217.94922) (xy 171.644492 -217.906023)
			(xy 171.624231 -217.859619) (xy 171.610508 -217.81088) (xy 171.603581 -217.760721) (xy 171.603162 -217.735404)
			(xy 171.603608 -217.710057) (xy 171.610539 -217.659839) (xy 171.624285 -217.611044) (xy 171.644585 -217.564592)
			(xy 171.671059 -217.521359) (xy 171.703205 -217.482161) (xy 171.721526 -217.46464) (xy 171.730416 -217.456512)
			(xy 171.738798 -217.434668) (xy 171.729146 -217.330528) (xy 171.716954 -217.310716) (xy 171.706794 -217.304366)
			(xy 171.680704 -217.287234) (xy 171.632583 -217.247487) (xy 171.589826 -217.202018) (xy 171.55311 -217.151545)
			(xy 171.523014 -217.096865) (xy 171.500014 -217.038843) (xy 171.484474 -216.978394) (xy 171.476637 -216.916473)
			(xy 171.476162 -216.885266) (xy 171.476668 -216.85407) (xy 171.484481 -216.79217) (xy 171.500005 -216.731741)
			(xy 171.522994 -216.673739) (xy 171.553084 -216.619083) (xy 171.589799 -216.568638) (xy 171.632557 -216.523202)
			(xy 171.680681 -216.483494) (xy 171.706794 -216.46642) (xy 171.716954 -216.459816) (xy 171.729146 -216.440004)
			(xy 171.738544 -216.335864) (xy 171.730162 -216.314274) (xy 171.721272 -216.305892) (xy 171.702978 -216.288385)
			(xy 171.6709 -216.249206) (xy 171.644483 -216.206007) (xy 171.624224 -216.159601) (xy 171.610503 -216.11086)
			(xy 171.603579 -216.0607) (xy 171.603162 -216.035382) (xy 171.603594 -216.010034) (xy 171.610528 -215.959816)
			(xy 171.624276 -215.91102) (xy 171.644579 -215.864569) (xy 171.671055 -215.821337) (xy 171.703204 -215.782139)
			(xy 171.721526 -215.764618) (xy 171.730416 -215.75649) (xy 171.738798 -215.734646) (xy 171.729146 -215.630506)
			(xy 171.716954 -215.610694) (xy 171.706794 -215.604344) (xy 171.680694 -215.587227) (xy 171.632573 -215.547477)
			(xy 171.589816 -215.502006) (xy 171.553101 -215.451531) (xy 171.523007 -215.396849) (xy 171.500009 -215.338825)
			(xy 171.48447 -215.278374) (xy 171.476636 -215.216452) (xy 171.476162 -215.185244) (xy 171.476651 -215.154048)
			(xy 171.484467 -215.092147) (xy 171.499993 -215.031717) (xy 171.522985 -214.973715) (xy 171.553077 -214.919059)
			(xy 171.589794 -214.868614) (xy 171.632554 -214.823179) (xy 171.680681 -214.783472) (xy 171.706794 -214.766398)
			(xy 171.716954 -214.759794) (xy 171.729146 -214.739982) (xy 171.738544 -214.635842) (xy 171.730162 -214.614252)
			(xy 171.721272 -214.60587) (xy 171.702968 -214.588374) (xy 171.670891 -214.549192) (xy 171.644475 -214.505992)
			(xy 171.624218 -214.459583) (xy 171.610499 -214.41084) (xy 171.603578 -214.360678) (xy 171.603162 -214.33536)
			(xy 171.603579 -214.310012) (xy 171.610516 -214.259793) (xy 171.624267 -214.210997) (xy 171.644573 -214.164545)
			(xy 171.671052 -214.121314) (xy 171.703203 -214.082117) (xy 171.721526 -214.064596) (xy 171.730416 -214.056468)
			(xy 171.738798 -214.034624) (xy 171.729146 -213.930484) (xy 171.716954 -213.910672) (xy 171.706794 -213.904322)
			(xy 171.680684 -213.88722) (xy 171.632563 -213.847468) (xy 171.589807 -213.801994) (xy 171.553093 -213.751517)
			(xy 171.522999 -213.696833) (xy 171.500003 -213.638807) (xy 171.484466 -213.578354) (xy 171.476634 -213.516431)
			(xy 171.476162 -213.485222) (xy 171.476651 -213.454059) (xy 171.484463 -213.392225) (xy 171.499963 -213.331857)
			(xy 171.522906 -213.273909) (xy 171.552932 -213.219292) (xy 171.589566 -213.16887) (xy 171.632231 -213.123436)
			(xy 171.680253 -213.083708) (xy 171.732877 -213.050313) (xy 171.789271 -213.023776) (xy 171.848546 -213.004516)
			(xy 171.909767 -212.992837) (xy 171.97197 -212.988924) (xy 172.034173 -212.992837) (xy 172.095394 -213.004516)
			(xy 172.154669 -213.023776) (xy 172.211063 -213.050313) (xy 172.263687 -213.083708) (xy 172.311709 -213.123436)
			(xy 172.354374 -213.16887) (xy 172.391008 -213.219292) (xy 172.421034 -213.273909) (xy 172.443977 -213.331857)
			(xy 172.459477 -213.392225) (xy 172.467289 -213.454059) (xy 172.467778 -213.485222) (xy 172.467305 -213.516432)
			(xy 172.459483 -213.578358) (xy 172.443952 -213.638814) (xy 172.420959 -213.696844) (xy 172.390866 -213.75153)
			(xy 172.354149 -213.802008) (xy 172.311389 -213.847479) (xy 172.263261 -213.887227) (xy 172.237146 -213.904322)
			(xy 172.226986 -213.910672) (xy 172.214794 -213.930484) (xy 172.205142 -214.034624) (xy 172.213524 -214.056468)
			(xy 172.222414 -214.064596) (xy 172.240734 -214.082118) (xy 172.272877 -214.12132) (xy 172.29935 -214.164553)
			(xy 172.319655 -214.211004) (xy 172.33341 -214.259796) (xy 172.340355 -214.310013) (xy 172.340778 -214.33536)
			(xy 172.34035 -214.360677) (xy 172.333428 -214.410836) (xy 172.319708 -214.459576) (xy 172.299449 -214.505981)
			(xy 172.273031 -214.549177) (xy 172.240952 -214.588353) (xy 172.222668 -214.60587) (xy 172.213778 -214.614252)
			(xy 172.205396 -214.635842) (xy 172.214794 -214.739982) (xy 172.226986 -214.759794) (xy 172.237146 -214.766398)
			(xy 172.263238 -214.783502) (xy 172.311357 -214.823212) (xy 172.354113 -214.868647) (xy 172.390829 -214.919088)
			(xy 172.420926 -214.973738) (xy 172.443926 -215.031732) (xy 172.459467 -215.092155) (xy 172.467303 -215.15405)
			(xy 172.467778 -215.185244) (xy 172.467322 -215.216454) (xy 172.459497 -215.278382) (xy 172.443964 -215.338838)
			(xy 172.420968 -215.396868) (xy 172.390873 -215.451553) (xy 172.354154 -215.502031) (xy 172.311392 -215.547502)
			(xy 172.263262 -215.587249) (xy 172.237146 -215.604344) (xy 172.226986 -215.610694) (xy 172.214794 -215.630506)
			(xy 172.205142 -215.734646) (xy 172.213524 -215.75649) (xy 172.222414 -215.764618) (xy 172.240745 -215.782129)
			(xy 172.272886 -215.821334) (xy 172.299358 -215.864569) (xy 172.319661 -215.911022) (xy 172.333414 -215.959816)
			(xy 172.340357 -216.010034) (xy 172.340778 -216.035382) (xy 172.340365 -216.0607) (xy 172.33344 -216.110859)
			(xy 172.319717 -216.1596) (xy 172.299455 -216.206004) (xy 172.273035 -216.249201) (xy 172.240953 -216.288376)
			(xy 172.222668 -216.305892) (xy 172.213778 -216.314274) (xy 172.205396 -216.335864) (xy 172.214794 -216.440004)
			(xy 172.226986 -216.459816) (xy 172.237146 -216.46642) (xy 172.263248 -216.483509) (xy 172.311367 -216.523222)
			(xy 172.354123 -216.568659) (xy 172.390838 -216.619102) (xy 172.420933 -216.673754) (xy 172.443932 -216.73175)
			(xy 172.459471 -216.792174) (xy 172.467305 -216.854071) (xy 172.467778 -216.885266) (xy 172.46734 -216.916477)
			(xy 172.459512 -216.978405) (xy 172.443976 -217.038862) (xy 172.420978 -217.096892) (xy 172.39088 -217.151577)
			(xy 172.354159 -217.202054) (xy 172.311394 -217.247525) (xy 172.263263 -217.287271) (xy 172.237146 -217.304366)
			(xy 172.226986 -217.310716) (xy 172.214794 -217.330528) (xy 172.205142 -217.434668) (xy 172.213524 -217.456512)
			(xy 172.222414 -217.46464) (xy 172.240756 -217.482141) (xy 172.272896 -217.521347) (xy 172.299366 -217.564585)
			(xy 172.319668 -217.61104) (xy 172.333418 -217.659836) (xy 172.340358 -217.710056) (xy 172.340778 -217.735404)
			(xy 175.57623 -217.735404) (xy 175.576719 -217.704195) (xy 175.584539 -217.642269) (xy 175.600066 -217.581813)
			(xy 175.623057 -217.523783) (xy 175.653148 -217.469097) (xy 175.689863 -217.418619) (xy 175.732621 -217.373147)
			(xy 175.780748 -217.3334) (xy 175.806862 -217.316304) (xy 175.817022 -217.309954) (xy 175.829214 -217.290142)
			(xy 175.838866 -217.186002) (xy 175.830484 -217.164158) (xy 175.821594 -217.15603) (xy 175.803288 -217.138494)
			(xy 175.771144 -217.099295) (xy 175.744669 -217.056065) (xy 175.724361 -217.009617) (xy 175.710603 -216.960827)
			(xy 175.703655 -216.910612) (xy 175.70323 -216.885266) (xy 175.703673 -216.859949) (xy 175.710592 -216.809791)
			(xy 175.724308 -216.761051) (xy 175.744565 -216.714646) (xy 175.77098 -216.671449) (xy 175.803057 -216.632273)
			(xy 175.82134 -216.614756) (xy 175.83023 -216.606374) (xy 175.838612 -216.584784) (xy 175.829214 -216.480644)
			(xy 175.817022 -216.460832) (xy 175.806862 -216.454228) (xy 175.780761 -216.437138) (xy 175.732645 -216.397423)
			(xy 175.689893 -216.351984) (xy 175.65318 -216.30154) (xy 175.623085 -216.246889) (xy 175.600086 -216.188894)
			(xy 175.584544 -216.128472) (xy 175.576706 -216.066577) (xy 175.57623 -216.035382) (xy 175.576702 -216.004172)
			(xy 175.584524 -215.942245) (xy 175.600054 -215.881789) (xy 175.623048 -215.82376) (xy 175.653141 -215.769074)
			(xy 175.689858 -215.718596) (xy 175.732618 -215.673124) (xy 175.780747 -215.633377) (xy 175.806862 -215.616282)
			(xy 175.817022 -215.609932) (xy 175.829214 -215.59012) (xy 175.838866 -215.48598) (xy 175.830484 -215.464136)
			(xy 175.821594 -215.456008) (xy 175.803277 -215.438482) (xy 175.771134 -215.399281) (xy 175.74466 -215.356049)
			(xy 175.724355 -215.309599) (xy 175.710599 -215.260807) (xy 175.703653 -215.210591) (xy 175.70323 -215.185244)
			(xy 175.703658 -215.159927) (xy 175.71058 -215.109768) (xy 175.7243 -215.061028) (xy 175.744559 -215.014623)
			(xy 175.770976 -214.971426) (xy 175.803056 -214.93225) (xy 175.82134 -214.914734) (xy 175.83023 -214.906352)
			(xy 175.838612 -214.884762) (xy 175.829214 -214.780622) (xy 175.817022 -214.76081) (xy 175.806862 -214.754206)
			(xy 175.780751 -214.737131) (xy 175.732635 -214.697413) (xy 175.689884 -214.651972) (xy 175.653171 -214.601527)
			(xy 175.623078 -214.546873) (xy 175.60008 -214.488876) (xy 175.58454 -214.428452) (xy 175.576705 -214.366555)
			(xy 175.57623 -214.33536) (xy 175.576685 -214.30415) (xy 175.58451 -214.242222) (xy 175.600043 -214.181766)
			(xy 175.623039 -214.123736) (xy 175.653134 -214.06905) (xy 175.689853 -214.018572) (xy 175.732616 -213.973101)
			(xy 175.780746 -213.933355) (xy 175.806862 -213.91626) (xy 175.817022 -213.90991) (xy 175.829214 -213.890098)
			(xy 175.838866 -213.785958) (xy 175.830484 -213.764114) (xy 175.821594 -213.755986) (xy 175.803266 -213.738471)
			(xy 175.771124 -213.699268) (xy 175.744652 -213.656033) (xy 175.724348 -213.609581) (xy 175.710595 -213.560787)
			(xy 175.703652 -213.51057) (xy 175.70323 -213.485222) (xy 175.703643 -213.459904) (xy 175.710568 -213.409745)
			(xy 175.72429 -213.361004) (xy 175.744552 -213.314599) (xy 175.770973 -213.271403) (xy 175.803054 -213.232228)
			(xy 175.82134 -213.214712) (xy 175.83023 -213.20633) (xy 175.838612 -213.18474) (xy 175.829214 -213.0806)
			(xy 175.817022 -213.060788) (xy 175.806862 -213.054184) (xy 175.780741 -213.037124) (xy 175.732625 -212.997404)
			(xy 175.689874 -212.951961) (xy 175.653162 -212.901513) (xy 175.62307 -212.846857) (xy 175.600074 -212.788858)
			(xy 175.584536 -212.728432) (xy 175.576703 -212.666534) (xy 175.57623 -212.635338) (xy 175.576719 -212.604175)
			(xy 175.584531 -212.542341) (xy 175.600031 -212.481973) (xy 175.622974 -212.424025) (xy 175.653 -212.369408)
			(xy 175.689634 -212.318986) (xy 175.732299 -212.273552) (xy 175.780321 -212.233824) (xy 175.832945 -212.200429)
			(xy 175.889339 -212.173892) (xy 175.948614 -212.154632) (xy 176.009835 -212.142953) (xy 176.072038 -212.13904)
			(xy 176.134241 -212.142953) (xy 176.195462 -212.154632) (xy 176.254737 -212.173892) (xy 176.311131 -212.200429)
			(xy 176.363755 -212.233824) (xy 176.411777 -212.273552) (xy 176.454442 -212.318986) (xy 176.491076 -212.369408)
			(xy 176.521102 -212.424025) (xy 176.544045 -212.481973) (xy 176.559545 -212.542341) (xy 176.567357 -212.604175)
			(xy 176.567846 -212.635338) (xy 180.531023 -212.635338) (xy 180.534958 -212.581567) (xy 180.546681 -212.528943)
			(xy 180.565941 -212.478586) (xy 180.592327 -212.431569) (xy 180.625279 -212.388896) (xy 180.664092 -212.351475)
			(xy 180.70794 -212.320105) (xy 180.755888 -212.295453) (xy 180.806915 -212.278045) (xy 180.859933 -212.268252)
			(xy 180.913812 -212.266283) (xy 180.967403 -212.27218) (xy 181.019564 -212.285816) (xy 181.069184 -212.306903)
			(xy 181.115205 -212.334989) (xy 181.156647 -212.369477) (xy 181.192625 -212.409631) (xy 181.222373 -212.454595)
			(xy 181.245258 -212.503412) (xy 181.26079 -212.555041) (xy 181.26864 -212.608381) (xy 181.269132 -212.635338)
			(xy 181.26864 -212.662295) (xy 181.26079 -212.715635) (xy 181.245258 -212.767264) (xy 181.222373 -212.816081)
			(xy 181.192625 -212.861045) (xy 181.156647 -212.901199) (xy 181.115205 -212.935687) (xy 181.069184 -212.963773)
			(xy 181.019564 -212.98486) (xy 180.967403 -212.998496) (xy 180.913812 -213.004393) (xy 180.859933 -213.002424)
			(xy 180.806915 -212.992631) (xy 180.755888 -212.975223) (xy 180.70794 -212.950571) (xy 180.664092 -212.919201)
			(xy 180.625279 -212.88178) (xy 180.592327 -212.839107) (xy 180.565941 -212.79209) (xy 180.546681 -212.741733)
			(xy 180.534958 -212.689109) (xy 180.531023 -212.635338) (xy 176.567846 -212.635338) (xy 176.56734 -212.666534)
			(xy 176.559526 -212.728434) (xy 176.544002 -212.788863) (xy 176.521013 -212.846864) (xy 176.490923 -212.90152)
			(xy 176.454209 -212.951966) (xy 176.411451 -212.997402) (xy 176.363326 -213.03711) (xy 176.337214 -213.054184)
			(xy 176.327054 -213.060788) (xy 176.314862 -213.0806) (xy 176.305464 -213.18474) (xy 176.313846 -213.20633)
			(xy 176.322736 -213.214712) (xy 176.341033 -213.232216) (xy 176.37311 -213.271395) (xy 176.399527 -213.314595)
			(xy 176.419785 -213.361002) (xy 176.433505 -213.409743) (xy 176.440429 -213.459904) (xy 176.440846 -213.485222)
			(xy 176.440414 -213.51057) (xy 176.43348 -213.560788) (xy 176.419732 -213.609583) (xy 176.399428 -213.656035)
			(xy 176.372952 -213.699267) (xy 176.340804 -213.738465) (xy 176.322482 -213.755986) (xy 176.313592 -213.764114)
			(xy 176.30521 -213.785958) (xy 176.314862 -213.890098) (xy 176.327054 -213.90991) (xy 176.337214 -213.91626)
			(xy 176.363317 -213.933371) (xy 176.411439 -213.973122) (xy 176.454194 -214.018595) (xy 176.490909 -214.069071)
			(xy 176.521003 -214.123753) (xy 176.544001 -214.181778) (xy 176.559539 -214.242229) (xy 176.567373 -214.304152)
			(xy 176.567846 -214.33536) (xy 176.567357 -214.366556) (xy 176.55954 -214.428457) (xy 176.544014 -214.488887)
			(xy 176.521022 -214.546888) (xy 176.49093 -214.601544) (xy 176.454213 -214.651989) (xy 176.411453 -214.697425)
			(xy 176.363327 -214.737132) (xy 176.337214 -214.754206) (xy 176.327054 -214.76081) (xy 176.314862 -214.780622)
			(xy 176.305464 -214.884762) (xy 176.313846 -214.906352) (xy 176.322736 -214.914734) (xy 176.340995 -214.932275)
			(xy 176.373076 -214.971447) (xy 176.399497 -215.014638) (xy 176.419763 -215.061038) (xy 176.433491 -215.109773)
			(xy 176.440424 -215.159928) (xy 176.440846 -215.185244) (xy 176.440429 -215.210592) (xy 176.433492 -215.260811)
			(xy 176.41974 -215.309607) (xy 176.399434 -215.356058) (xy 176.372956 -215.39929) (xy 176.340805 -215.438487)
			(xy 176.322482 -215.456008) (xy 176.313592 -215.464136) (xy 176.30521 -215.48598) (xy 176.314862 -215.59012)
			(xy 176.327054 -215.609932) (xy 176.337214 -215.616282) (xy 176.363327 -215.633379) (xy 176.411449 -215.673132)
			(xy 176.454204 -215.718606) (xy 176.490918 -215.769084) (xy 176.52101 -215.823769) (xy 176.544006 -215.881796)
			(xy 176.559543 -215.942249) (xy 176.567374 -216.004173) (xy 176.567846 -216.035382) (xy 176.567374 -216.066579)
			(xy 176.559555 -216.12848) (xy 176.544025 -216.18891) (xy 176.521031 -216.246912) (xy 176.490937 -216.301568)
			(xy 176.454218 -216.352012) (xy 176.411456 -216.397448) (xy 176.363328 -216.437154) (xy 176.337214 -216.454228)
			(xy 176.327054 -216.460832) (xy 176.314862 -216.480644) (xy 176.305464 -216.584784) (xy 176.313846 -216.606374)
			(xy 176.322736 -216.614756) (xy 176.341006 -216.632287) (xy 176.373086 -216.671461) (xy 176.399506 -216.714654)
			(xy 176.419769 -216.761056) (xy 176.433495 -216.809793) (xy 176.440425 -216.85995) (xy 176.440846 -216.885266)
			(xy 176.440444 -216.910615) (xy 176.433504 -216.960834) (xy 176.419749 -217.00963) (xy 176.39944 -217.056082)
			(xy 176.372959 -217.099313) (xy 176.340806 -217.13851) (xy 176.322482 -217.15603) (xy 176.313592 -217.164158)
			(xy 176.30521 -217.186002) (xy 176.314862 -217.290142) (xy 176.327054 -217.309954) (xy 176.337214 -217.316304)
			(xy 176.363337 -217.333386) (xy 176.411459 -217.373141) (xy 176.454214 -217.418618) (xy 176.490927 -217.469098)
			(xy 176.521018 -217.523785) (xy 176.544012 -217.581814) (xy 176.559547 -217.642269) (xy 176.567375 -217.704195)
			(xy 176.567846 -217.735404) (xy 176.567357 -217.766567) (xy 176.559545 -217.828401) (xy 176.544045 -217.888769)
			(xy 176.521102 -217.946717) (xy 176.491076 -218.001334) (xy 176.454442 -218.051756) (xy 176.411777 -218.09719)
			(xy 176.363755 -218.136918) (xy 176.311131 -218.170313) (xy 176.254737 -218.19685) (xy 176.195462 -218.21611)
			(xy 176.134241 -218.227789) (xy 176.072038 -218.231702) (xy 176.009835 -218.227789) (xy 175.948614 -218.21611)
			(xy 175.889339 -218.19685) (xy 175.832945 -218.170313) (xy 175.780321 -218.136918) (xy 175.732299 -218.09719)
			(xy 175.689634 -218.051756) (xy 175.653 -218.001334) (xy 175.622974 -217.946717) (xy 175.600031 -217.888769)
			(xy 175.584531 -217.828401) (xy 175.576719 -217.766567) (xy 175.57623 -217.735404) (xy 172.340778 -217.735404)
			(xy 172.34038 -217.760722) (xy 172.333451 -217.810882) (xy 172.319726 -217.859623) (xy 172.299461 -217.906028)
			(xy 172.273038 -217.949224) (xy 172.240954 -217.988399) (xy 172.222668 -218.005914) (xy 172.213778 -218.014296)
			(xy 172.205396 -218.035886) (xy 172.214794 -218.140026) (xy 172.226986 -218.159838) (xy 172.237146 -218.166442)
			(xy 172.263258 -218.183517) (xy 172.311377 -218.223231) (xy 172.354132 -218.26867) (xy 172.390847 -218.319116)
			(xy 172.420941 -218.37377) (xy 172.443938 -218.431768) (xy 172.459475 -218.492194) (xy 172.467306 -218.554092)
			(xy 172.467778 -218.585288) (xy 174.318437 -218.585288) (xy 174.322372 -218.531517) (xy 174.334095 -218.478893)
			(xy 174.353355 -218.428536) (xy 174.379741 -218.381519) (xy 174.412693 -218.338846) (xy 174.451506 -218.301425)
			(xy 174.495354 -218.270055) (xy 174.543302 -218.245403) (xy 174.594329 -218.227995) (xy 174.647347 -218.218202)
			(xy 174.701226 -218.216233) (xy 174.754817 -218.22213) (xy 174.806978 -218.235766) (xy 174.856598 -218.256853)
			(xy 174.902619 -218.284939) (xy 174.944061 -218.319427) (xy 174.980039 -218.359581) (xy 175.009787 -218.404545)
			(xy 175.032672 -218.453362) (xy 175.048204 -218.504991) (xy 175.056054 -218.558331) (xy 175.056546 -218.585288)
			(xy 179.020216 -218.585288) (xy 179.020636 -218.554089) (xy 179.02846 -218.492185) (xy 179.043995 -218.431752)
			(xy 179.066996 -218.373749) (xy 179.097097 -218.319093) (xy 179.133824 -218.268649) (xy 179.176594 -218.223216)
			(xy 179.22473 -218.183513) (xy 179.250848 -218.166442) (xy 179.261008 -218.159838) (xy 179.2732 -218.140026)
			(xy 179.282598 -218.035886) (xy 179.274216 -218.014296) (xy 179.265326 -218.005914) (xy 179.247034 -217.988405)
			(xy 179.214958 -217.949226) (xy 179.188542 -217.906027) (xy 179.168283 -217.859621) (xy 179.154561 -217.810881)
			(xy 179.147635 -217.760722) (xy 179.147216 -217.735404) (xy 179.147645 -217.710056) (xy 179.154577 -217.659837)
			(xy 179.168325 -217.611041) (xy 179.188629 -217.564588) (xy 179.215106 -217.521356) (xy 179.247257 -217.48216)
			(xy 179.26558 -217.46464) (xy 179.27447 -217.456512) (xy 179.282852 -217.434668) (xy 179.2732 -217.330528)
			(xy 179.261008 -217.310716) (xy 179.250848 -217.304366) (xy 179.224748 -217.287251) (xy 179.176628 -217.247499)
			(xy 179.133873 -217.202027) (xy 179.097159 -217.151551) (xy 179.067065 -217.09687) (xy 179.044066 -217.038846)
			(xy 179.028527 -216.978396) (xy 179.020691 -216.916474) (xy 179.020216 -216.885266) (xy 179.020697 -216.854069)
			(xy 179.028511 -216.792167) (xy 179.044037 -216.731736) (xy 179.067029 -216.673733) (xy 179.097122 -216.619077)
			(xy 179.133841 -216.568632) (xy 179.176603 -216.523197) (xy 179.224733 -216.483493) (xy 179.250848 -216.46642)
			(xy 179.261008 -216.459816) (xy 179.2732 -216.440004) (xy 179.282598 -216.335864) (xy 179.274216 -216.314274)
			(xy 179.265326 -216.305892) (xy 179.247024 -216.288394) (xy 179.214948 -216.249212) (xy 179.188534 -216.206011)
			(xy 179.168276 -216.159603) (xy 179.154557 -216.110861) (xy 179.147633 -216.0607) (xy 179.147216 -216.035382)
			(xy 179.14763 -216.010034) (xy 179.154565 -215.959813) (xy 179.168316 -215.911017) (xy 179.188623 -215.864565)
			(xy 179.215102 -215.821333) (xy 179.247256 -215.782138) (xy 179.26558 -215.764618) (xy 179.27447 -215.75649)
			(xy 179.282852 -215.734646) (xy 179.2732 -215.630506) (xy 179.261008 -215.610694) (xy 179.250848 -215.604344)
			(xy 179.224737 -215.587243) (xy 179.176618 -215.54749) (xy 179.133864 -215.502015) (xy 179.09715 -215.451537)
			(xy 179.067058 -215.396854) (xy 179.044061 -215.338828) (xy 179.028523 -215.278376) (xy 179.020689 -215.216452)
			(xy 179.020216 -215.185244) (xy 179.02068 -215.154047) (xy 179.028497 -215.092144) (xy 179.044025 -215.031712)
			(xy 179.067019 -214.973709) (xy 179.097115 -214.919053) (xy 179.133836 -214.868609) (xy 179.176601 -214.823175)
			(xy 179.224732 -214.78347) (xy 179.250848 -214.766398) (xy 179.261008 -214.759794) (xy 179.2732 -214.739982)
			(xy 179.282598 -214.635842) (xy 179.274216 -214.614252) (xy 179.265326 -214.60587) (xy 179.247013 -214.588382)
			(xy 179.214939 -214.549198) (xy 179.188525 -214.505995) (xy 179.16827 -214.459585) (xy 179.154552 -214.410841)
			(xy 179.147632 -214.360679) (xy 179.147216 -214.33536) (xy 179.147616 -214.310011) (xy 179.154554 -214.25979)
			(xy 179.168307 -214.210994) (xy 179.188617 -214.164542) (xy 179.215099 -214.121311) (xy 179.247255 -214.082115)
			(xy 179.26558 -214.064596) (xy 179.27447 -214.056468) (xy 179.282852 -214.034624) (xy 179.2732 -213.930484)
			(xy 179.261008 -213.910672) (xy 179.250848 -213.904322) (xy 179.224727 -213.887236) (xy 179.176608 -213.84748)
			(xy 179.133854 -213.802004) (xy 179.097142 -213.751524) (xy 179.06705 -213.696838) (xy 179.044055 -213.63881)
			(xy 179.028519 -213.578356) (xy 179.020688 -213.516431) (xy 179.020216 -213.485222) (xy 179.020705 -213.454059)
			(xy 179.028517 -213.392225) (xy 179.044017 -213.331857) (xy 179.06696 -213.273909) (xy 179.096986 -213.219292)
			(xy 179.13362 -213.16887) (xy 179.176285 -213.123436) (xy 179.224307 -213.083708) (xy 179.276931 -213.050313)
			(xy 179.333325 -213.023776) (xy 179.3926 -213.004516) (xy 179.453821 -212.992837) (xy 179.516024 -212.988924)
			(xy 179.578227 -212.992837) (xy 179.639448 -213.004516) (xy 179.698723 -213.023776) (xy 179.755117 -213.050313)
			(xy 179.807741 -213.083708) (xy 179.855763 -213.123436) (xy 179.898428 -213.16887) (xy 179.935062 -213.219292)
			(xy 179.965088 -213.273909) (xy 179.988031 -213.331857) (xy 180.003531 -213.392225) (xy 180.011343 -213.454059)
			(xy 180.011832 -213.485222) (xy 180.011334 -213.516431) (xy 180.003513 -213.578355) (xy 179.987984 -213.63881)
			(xy 179.964994 -213.696838) (xy 179.934904 -213.751524) (xy 179.898191 -213.802002) (xy 179.855436 -213.847475)
			(xy 179.807313 -213.887225) (xy 179.7812 -213.904322) (xy 179.77104 -213.910672) (xy 179.758848 -213.930484)
			(xy 179.749196 -214.034624) (xy 179.757578 -214.056468) (xy 179.766468 -214.064596) (xy 179.78478 -214.082127)
			(xy 179.816925 -214.121326) (xy 179.8434 -214.164557) (xy 179.863707 -214.211006) (xy 179.877463 -214.259798)
			(xy 179.884409 -214.310013) (xy 179.884832 -214.33536) (xy 179.884418 -214.360678) (xy 179.877495 -214.410838)
			(xy 179.863774 -214.459579) (xy 179.843512 -214.505984) (xy 179.817091 -214.54918) (xy 179.785008 -214.588355)
			(xy 179.766722 -214.60587) (xy 179.757832 -214.614252) (xy 179.74945 -214.635842) (xy 179.758848 -214.739982)
			(xy 179.77104 -214.759794) (xy 179.7812 -214.766398) (xy 179.807305 -214.783483) (xy 179.855421 -214.823198)
			(xy 179.898175 -214.868637) (xy 179.934889 -214.919081) (xy 179.964983 -214.973733) (xy 179.987982 -215.031729)
			(xy 180.003522 -215.092153) (xy 180.011358 -215.154049) (xy 180.011832 -215.185244) (xy 180.011351 -215.216453)
			(xy 180.003527 -215.278379) (xy 179.987996 -215.338833) (xy 179.965003 -215.396862) (xy 179.934911 -215.451547)
			(xy 179.898196 -215.502025) (xy 179.855439 -215.547498) (xy 179.807314 -215.587247) (xy 179.7812 -215.604344)
			(xy 179.77104 -215.610694) (xy 179.758848 -215.630506) (xy 179.749196 -215.734646) (xy 179.757578 -215.75649)
			(xy 179.766468 -215.764618) (xy 179.78479 -215.782138) (xy 179.816934 -215.82134) (xy 179.843408 -215.864573)
			(xy 179.863713 -215.911024) (xy 179.877467 -215.959817) (xy 179.884411 -216.010035) (xy 179.884832 -216.035382)
			(xy 179.884433 -216.0607) (xy 179.877507 -216.110861) (xy 179.863783 -216.159602) (xy 179.843518 -216.206007)
			(xy 179.817094 -216.249203) (xy 179.785009 -216.288377) (xy 179.766722 -216.305892) (xy 179.757832 -216.314274)
			(xy 179.74945 -216.335864) (xy 179.758848 -216.440004) (xy 179.77104 -216.459816) (xy 179.7812 -216.46642)
			(xy 179.807315 -216.483491) (xy 179.855431 -216.523208) (xy 179.898184 -216.568649) (xy 179.934898 -216.619095)
			(xy 179.964991 -216.673749) (xy 179.987988 -216.731747) (xy 180.003526 -216.792173) (xy 180.011359 -216.85407)
			(xy 180.011832 -216.885266) (xy 180.011369 -216.916476) (xy 180.003542 -216.978402) (xy 179.988008 -217.038857)
			(xy 179.965012 -217.096886) (xy 179.934918 -217.151571) (xy 179.898201 -217.202049) (xy 179.855441 -217.247521)
			(xy 179.807314 -217.28727) (xy 179.7812 -217.304366) (xy 179.77104 -217.310716) (xy 179.758848 -217.330528)
			(xy 179.749196 -217.434668) (xy 179.757578 -217.456512) (xy 179.766468 -217.46464) (xy 179.784801 -217.48215)
			(xy 179.816944 -217.521353) (xy 179.843416 -217.564589) (xy 179.86372 -217.611042) (xy 179.877471 -217.659837)
			(xy 179.884412 -217.710056) (xy 179.884832 -217.735404) (xy 183.120284 -217.735404) (xy 183.120795 -217.704196)
			(xy 183.128613 -217.642271) (xy 183.144139 -217.581817) (xy 183.167128 -217.523788) (xy 183.197215 -217.469103)
			(xy 183.233927 -217.418624) (xy 183.276681 -217.373151) (xy 183.324804 -217.333401) (xy 183.350916 -217.316304)
			(xy 183.361076 -217.309954) (xy 183.373268 -217.290142) (xy 183.38292 -217.186002) (xy 183.374538 -217.164158)
			(xy 183.365648 -217.15603) (xy 183.347352 -217.138483) (xy 183.315205 -217.099288) (xy 183.288727 -217.05606)
			(xy 183.268418 -217.009615) (xy 183.254658 -216.960826) (xy 183.247709 -216.910612) (xy 183.247284 -216.885266)
			(xy 183.247741 -216.85995) (xy 183.254659 -216.809793) (xy 183.268374 -216.761054) (xy 183.288627 -216.714649)
			(xy 183.315039 -216.671452) (xy 183.347113 -216.632274) (xy 183.365394 -216.614756) (xy 183.374284 -216.606374)
			(xy 183.382666 -216.584784) (xy 183.373268 -216.480644) (xy 183.361076 -216.460832) (xy 183.350916 -216.454228)
			(xy 183.324827 -216.43712) (xy 183.276709 -216.397409) (xy 183.233955 -216.351974) (xy 183.197239 -216.301533)
			(xy 183.167143 -216.246884) (xy 183.144141 -216.188891) (xy 183.128599 -216.12847) (xy 183.12076 -216.066576)
			(xy 183.120284 -216.035382) (xy 183.120778 -216.004173) (xy 183.128599 -215.942248) (xy 183.144127 -215.881793)
			(xy 183.167118 -215.823764) (xy 183.197208 -215.769079) (xy 183.233922 -215.718601) (xy 183.276679 -215.673128)
			(xy 183.324803 -215.633379) (xy 183.350916 -215.616282) (xy 183.361076 -215.609932) (xy 183.373268 -215.59012)
			(xy 183.38292 -215.48598) (xy 183.374538 -215.464136) (xy 183.365648 -215.456008) (xy 183.347341 -215.438472)
			(xy 183.315195 -215.399274) (xy 183.288719 -215.356045) (xy 183.268411 -215.309597) (xy 183.254654 -215.260806)
			(xy 183.247707 -215.210591) (xy 183.247284 -215.185244) (xy 183.247726 -215.159927) (xy 183.254647 -215.10977)
			(xy 183.268365 -215.06103) (xy 183.288621 -215.014626) (xy 183.315036 -214.971429) (xy 183.347112 -214.932251)
			(xy 183.365394 -214.914734) (xy 183.374284 -214.906352) (xy 183.382666 -214.884762) (xy 183.373268 -214.780622)
			(xy 183.361076 -214.76081) (xy 183.350916 -214.754206) (xy 183.324817 -214.737112) (xy 183.276699 -214.697399)
			(xy 183.233945 -214.651962) (xy 183.19723 -214.601519) (xy 183.167135 -214.546868) (xy 183.144136 -214.488873)
			(xy 183.128595 -214.42845) (xy 183.120759 -214.366555) (xy 183.120284 -214.33536) (xy 183.12076 -214.304151)
			(xy 183.128584 -214.242225) (xy 183.144115 -214.181769) (xy 183.167109 -214.123741) (xy 183.197201 -214.069055)
			(xy 183.233917 -214.018577) (xy 183.276676 -213.973105) (xy 183.324802 -213.933356) (xy 183.350916 -213.91626)
			(xy 183.361076 -213.90991) (xy 183.373268 -213.890098) (xy 183.38292 -213.785958) (xy 183.374538 -213.764114)
			(xy 183.365648 -213.755986) (xy 183.347331 -213.738461) (xy 183.315186 -213.699261) (xy 183.288711 -213.656029)
			(xy 183.268405 -213.609579) (xy 183.25465 -213.560786) (xy 183.247706 -213.510569) (xy 183.247284 -213.485222)
			(xy 183.247712 -213.459905) (xy 183.254636 -213.409746) (xy 183.268356 -213.361007) (xy 183.288615 -213.314602)
			(xy 183.315032 -213.271406) (xy 183.34711 -213.232229) (xy 183.365394 -213.214712) (xy 183.374284 -213.20633)
			(xy 183.382666 -213.18474) (xy 183.373268 -213.0806) (xy 183.361076 -213.060788) (xy 183.350916 -213.054184)
			(xy 183.324807 -213.037105) (xy 183.276689 -212.99739) (xy 183.233936 -212.951951) (xy 183.197222 -212.901506)
			(xy 183.167128 -212.846853) (xy 183.14413 -212.788855) (xy 183.128591 -212.72843) (xy 183.120757 -212.666533)
			(xy 183.120284 -212.635338) (xy 183.120773 -212.604175) (xy 183.128585 -212.542341) (xy 183.144085 -212.481973)
			(xy 183.167028 -212.424025) (xy 183.197054 -212.369408) (xy 183.233688 -212.318986) (xy 183.276353 -212.273552)
			(xy 183.324375 -212.233824) (xy 183.376999 -212.200429) (xy 183.433393 -212.173892) (xy 183.492668 -212.154632)
			(xy 183.553889 -212.142953) (xy 183.616092 -212.13904) (xy 183.678295 -212.142953) (xy 183.739516 -212.154632)
			(xy 183.798791 -212.173892) (xy 183.855185 -212.200429) (xy 183.907809 -212.233824) (xy 183.955831 -212.273552)
			(xy 183.998496 -212.318986) (xy 184.03513 -212.369408) (xy 184.065156 -212.424025) (xy 184.088099 -212.481973)
			(xy 184.103599 -212.542341) (xy 184.111411 -212.604175) (xy 184.1119 -212.635338) (xy 188.075077 -212.635338)
			(xy 188.079012 -212.581567) (xy 188.090735 -212.528943) (xy 188.109995 -212.478586) (xy 188.136381 -212.431569)
			(xy 188.169333 -212.388896) (xy 188.208146 -212.351475) (xy 188.251994 -212.320105) (xy 188.299942 -212.295453)
			(xy 188.350969 -212.278045) (xy 188.403987 -212.268252) (xy 188.457866 -212.266283) (xy 188.511457 -212.27218)
			(xy 188.563618 -212.285816) (xy 188.613238 -212.306903) (xy 188.659259 -212.334989) (xy 188.700701 -212.369477)
			(xy 188.736679 -212.409631) (xy 188.766427 -212.454595) (xy 188.789312 -212.503412) (xy 188.804844 -212.555041)
			(xy 188.812694 -212.608381) (xy 188.813186 -212.635338) (xy 188.812694 -212.662295) (xy 188.804844 -212.715635)
			(xy 188.789312 -212.767264) (xy 188.766427 -212.816081) (xy 188.736679 -212.861045) (xy 188.700701 -212.901199)
			(xy 188.659259 -212.935687) (xy 188.613238 -212.963773) (xy 188.563618 -212.98486) (xy 188.511457 -212.998496)
			(xy 188.457866 -213.004393) (xy 188.403987 -213.002424) (xy 188.350969 -212.992631) (xy 188.299942 -212.975223)
			(xy 188.251994 -212.950571) (xy 188.208146 -212.919201) (xy 188.169333 -212.88178) (xy 188.136381 -212.839107)
			(xy 188.109995 -212.79209) (xy 188.090735 -212.741733) (xy 188.079012 -212.689109) (xy 188.075077 -212.635338)
			(xy 184.1119 -212.635338) (xy 184.111415 -212.666535) (xy 184.1036 -212.728436) (xy 184.088075 -212.788867)
			(xy 184.065083 -212.846869) (xy 184.03499 -212.901526) (xy 183.998273 -212.951971) (xy 183.955511 -212.997405)
			(xy 183.907382 -213.037111) (xy 183.881268 -213.054184) (xy 183.871108 -213.060788) (xy 183.858916 -213.0806)
			(xy 183.849518 -213.18474) (xy 183.8579 -213.20633) (xy 183.86679 -213.214712) (xy 183.885097 -213.232205)
			(xy 183.917172 -213.271388) (xy 183.943585 -213.31459) (xy 183.963842 -213.360999) (xy 183.97756 -213.409742)
			(xy 183.984483 -213.459904) (xy 183.9849 -213.485222) (xy 183.984483 -213.51057) (xy 183.977548 -213.56079)
			(xy 183.963797 -213.609586) (xy 183.943491 -213.656038) (xy 183.917012 -213.69927) (xy 183.88486 -213.738466)
			(xy 183.866536 -213.755986) (xy 183.857646 -213.764114) (xy 183.849264 -213.785958) (xy 183.858916 -213.890098)
			(xy 183.871108 -213.90991) (xy 183.881268 -213.91626) (xy 183.907361 -213.933387) (xy 183.955484 -213.973134)
			(xy 183.998242 -214.018603) (xy 184.034959 -214.069077) (xy 184.065054 -214.123757) (xy 184.088053 -214.181781)
			(xy 184.103592 -214.242231) (xy 184.111426 -214.304152) (xy 184.1119 -214.33536) (xy 184.111432 -214.366557)
			(xy 184.103615 -214.42846) (xy 184.088086 -214.48889) (xy 184.065093 -214.546893) (xy 184.034997 -214.601549)
			(xy 183.998277 -214.651994) (xy 183.955514 -214.697428) (xy 183.907383 -214.737133) (xy 183.881268 -214.754206)
			(xy 183.871108 -214.76081) (xy 183.858916 -214.780622) (xy 183.849518 -214.884762) (xy 183.8579 -214.906352)
			(xy 183.86679 -214.914734) (xy 183.88506 -214.932265) (xy 183.917137 -214.97144) (xy 183.943556 -215.014634)
			(xy 183.963819 -215.061035) (xy 183.977546 -215.109772) (xy 183.984478 -215.159928) (xy 183.9849 -215.185244)
			(xy 183.984498 -215.210593) (xy 183.97756 -215.260813) (xy 183.963806 -215.30961) (xy 183.943497 -215.356061)
			(xy 183.917016 -215.399293) (xy 183.884861 -215.438488) (xy 183.866536 -215.456008) (xy 183.857646 -215.464136)
			(xy 183.849264 -215.48598) (xy 183.858916 -215.59012) (xy 183.871108 -215.609932) (xy 183.881268 -215.616282)
			(xy 183.907371 -215.633395) (xy 183.955494 -215.673143) (xy 183.998252 -215.718615) (xy 184.034967 -215.769091)
			(xy 184.065062 -215.823773) (xy 184.088059 -215.881798) (xy 184.103596 -215.94225) (xy 184.111428 -216.004174)
			(xy 184.1119 -216.035382) (xy 184.111449 -216.06658) (xy 184.103629 -216.128483) (xy 184.088098 -216.188914)
			(xy 184.065102 -216.246917) (xy 184.035004 -216.301573) (xy 183.998282 -216.352017) (xy 183.955516 -216.397451)
			(xy 183.907384 -216.437156) (xy 183.881268 -216.454228) (xy 183.871108 -216.460832) (xy 183.858916 -216.480644)
			(xy 183.849518 -216.584784) (xy 183.8579 -216.606374) (xy 183.86679 -216.614756) (xy 183.88507 -216.632276)
			(xy 183.917147 -216.671454) (xy 183.943564 -216.71465) (xy 183.963825 -216.761053) (xy 183.97755 -216.809792)
			(xy 183.984479 -216.859949) (xy 183.9849 -216.885266) (xy 183.984512 -216.910615) (xy 183.977571 -216.960836)
			(xy 183.963815 -217.009633) (xy 183.943503 -217.056085) (xy 183.917019 -217.099316) (xy 183.884862 -217.138511)
			(xy 183.866536 -217.15603) (xy 183.857646 -217.164158) (xy 183.849264 -217.186002) (xy 183.858916 -217.290142)
			(xy 183.871108 -217.309954) (xy 183.881268 -217.316304) (xy 183.907381 -217.333402) (xy 183.955504 -217.373153)
			(xy 183.998261 -217.418626) (xy 184.034976 -217.469104) (xy 184.065069 -217.523789) (xy 184.088065 -217.581816)
			(xy 184.1036 -217.64227) (xy 184.111429 -217.704195) (xy 184.1119 -217.735404) (xy 184.111411 -217.766567)
			(xy 184.103599 -217.828401) (xy 184.088099 -217.888769) (xy 184.065156 -217.946717) (xy 184.03513 -218.001334)
			(xy 183.998496 -218.051756) (xy 183.955831 -218.09719) (xy 183.907809 -218.136918) (xy 183.855185 -218.170313)
			(xy 183.798791 -218.19685) (xy 183.739516 -218.21611) (xy 183.678295 -218.227789) (xy 183.616092 -218.231702)
			(xy 183.553889 -218.227789) (xy 183.492668 -218.21611) (xy 183.433393 -218.19685) (xy 183.376999 -218.170313)
			(xy 183.324375 -218.136918) (xy 183.276353 -218.09719) (xy 183.233688 -218.051756) (xy 183.197054 -218.001334)
			(xy 183.167028 -217.946717) (xy 183.144085 -217.888769) (xy 183.128585 -217.828401) (xy 183.120773 -217.766567)
			(xy 183.120284 -217.735404) (xy 179.884832 -217.735404) (xy 179.884448 -217.760723) (xy 179.877519 -217.810884)
			(xy 179.863791 -217.859626) (xy 179.843524 -217.906031) (xy 179.817098 -217.949226) (xy 179.78501 -217.988399)
			(xy 179.766722 -218.005914) (xy 179.757832 -218.014296) (xy 179.74945 -218.035886) (xy 179.758848 -218.140026)
			(xy 179.77104 -218.159838) (xy 179.7812 -218.166442) (xy 179.807325 -218.183498) (xy 179.855441 -218.223217)
			(xy 179.898194 -218.26866) (xy 179.934906 -218.319108) (xy 179.964998 -218.373765) (xy 179.987994 -218.431765)
			(xy 180.00353 -218.492192) (xy 180.01136 -218.554092) (xy 180.011832 -218.585288) (xy 181.862491 -218.585288)
			(xy 181.866426 -218.531517) (xy 181.878149 -218.478893) (xy 181.897409 -218.428536) (xy 181.923795 -218.381519)
			(xy 181.956747 -218.338846) (xy 181.99556 -218.301425) (xy 182.039408 -218.270055) (xy 182.087356 -218.245403)
			(xy 182.138383 -218.227995) (xy 182.191401 -218.218202) (xy 182.24528 -218.216233) (xy 182.298871 -218.22213)
			(xy 182.351032 -218.235766) (xy 182.400652 -218.256853) (xy 182.446673 -218.284939) (xy 182.488115 -218.319427)
			(xy 182.524093 -218.359581) (xy 182.553841 -218.404545) (xy 182.576726 -218.453362) (xy 182.592258 -218.504991)
			(xy 182.600108 -218.558331) (xy 182.6006 -218.585288) (xy 186.56427 -218.585288) (xy 186.564711 -218.55409)
			(xy 186.572534 -218.492187) (xy 186.588068 -218.431756) (xy 186.611066 -218.373754) (xy 186.641165 -218.319098)
			(xy 186.677888 -218.268654) (xy 186.720654 -218.22322) (xy 186.768786 -218.183515) (xy 186.794902 -218.166442)
			(xy 186.805062 -218.159838) (xy 186.817254 -218.140026) (xy 186.826652 -218.035886) (xy 186.81827 -218.014296)
			(xy 186.80938 -218.005914) (xy 186.791099 -217.988395) (xy 186.759019 -217.949219) (xy 186.7326 -217.906023)
			(xy 186.712339 -217.859619) (xy 186.698616 -217.81088) (xy 186.691689 -217.760721) (xy 186.69127 -217.735404)
			(xy 186.691714 -217.710057) (xy 186.698645 -217.659838) (xy 186.712391 -217.611043) (xy 186.732692 -217.564592)
			(xy 186.759166 -217.521359) (xy 186.791313 -217.482161) (xy 186.809634 -217.46464) (xy 186.818524 -217.456512)
			(xy 186.826906 -217.434668) (xy 186.817254 -217.330528) (xy 186.805062 -217.310716) (xy 186.794902 -217.304366)
			(xy 186.768814 -217.287232) (xy 186.720692 -217.247485) (xy 186.677935 -217.202016) (xy 186.641219 -217.151543)
			(xy 186.611123 -217.096864) (xy 186.588123 -217.038842) (xy 186.572582 -216.978394) (xy 186.564745 -216.916473)
			(xy 186.56427 -216.885266) (xy 186.564772 -216.85407) (xy 186.572586 -216.792169) (xy 186.58811 -216.73174)
			(xy 186.611099 -216.673738) (xy 186.64119 -216.619082) (xy 186.677905 -216.568637) (xy 186.720664 -216.523201)
			(xy 186.768789 -216.483494) (xy 186.794902 -216.46642) (xy 186.805062 -216.459816) (xy 186.817254 -216.440004)
			(xy 186.826652 -216.335864) (xy 186.81827 -216.314274) (xy 186.80938 -216.305892) (xy 186.791088 -216.288383)
			(xy 186.759009 -216.249205) (xy 186.732592 -216.206007) (xy 186.712332 -216.159601) (xy 186.698612 -216.11086)
			(xy 186.691687 -216.0607) (xy 186.69127 -216.035382) (xy 186.691699 -216.010034) (xy 186.698633 -215.959815)
			(xy 186.712382 -215.91102) (xy 186.732686 -215.864568) (xy 186.759162 -215.821336) (xy 186.791312 -215.782139)
			(xy 186.809634 -215.764618) (xy 186.818524 -215.75649) (xy 186.826906 -215.734646) (xy 186.817254 -215.630506)
			(xy 186.805062 -215.610694) (xy 186.794902 -215.604344) (xy 186.768804 -215.587224) (xy 186.720682 -215.547475)
			(xy 186.677926 -215.502004) (xy 186.64121 -215.45153) (xy 186.611115 -215.396849) (xy 186.588117 -215.338824)
			(xy 186.572578 -215.278374) (xy 186.564744 -215.216452) (xy 186.56427 -215.185244) (xy 186.564755 -215.154047)
			(xy 186.572571 -215.092146) (xy 186.588098 -215.031716) (xy 186.61109 -214.973714) (xy 186.641183 -214.919058)
			(xy 186.6779 -214.868613) (xy 186.720661 -214.823178) (xy 186.768788 -214.783472) (xy 186.794902 -214.766398)
			(xy 186.805062 -214.759794) (xy 186.817254 -214.739982) (xy 186.826652 -214.635842) (xy 186.81827 -214.614252)
			(xy 186.80938 -214.60587) (xy 186.791077 -214.588372) (xy 186.759 -214.549191) (xy 186.732584 -214.505991)
			(xy 186.712326 -214.459583) (xy 186.698607 -214.41084) (xy 186.691686 -214.360678) (xy 186.69127 -214.33536)
			(xy 186.691684 -214.310012) (xy 186.698621 -214.259792) (xy 186.712373 -214.210997) (xy 186.73268 -214.164545)
			(xy 186.759159 -214.121313) (xy 186.791311 -214.082116) (xy 186.809634 -214.064596) (xy 186.818524 -214.056468)
			(xy 186.826906 -214.034624) (xy 186.817254 -213.930484) (xy 186.805062 -213.910672) (xy 186.794902 -213.904322)
			(xy 186.768794 -213.887217) (xy 186.720672 -213.847466) (xy 186.677916 -213.801993) (xy 186.641201 -213.751516)
			(xy 186.611108 -213.696833) (xy 186.588111 -213.638807) (xy 186.572574 -213.578354) (xy 186.564742 -213.51643)
			(xy 186.56427 -213.485222) (xy 186.564759 -213.454059) (xy 186.572571 -213.392225) (xy 186.588071 -213.331857)
			(xy 186.611014 -213.273909) (xy 186.64104 -213.219292) (xy 186.677674 -213.16887) (xy 186.720339 -213.123436)
			(xy 186.768361 -213.083708) (xy 186.820985 -213.050313) (xy 186.877379 -213.023776) (xy 186.936654 -213.004516)
			(xy 186.997875 -212.992837) (xy 187.060078 -212.988924) (xy 187.122281 -212.992837) (xy 187.183502 -213.004516)
			(xy 187.242777 -213.023776) (xy 187.299171 -213.050313) (xy 187.351795 -213.083708) (xy 187.399817 -213.123436)
			(xy 187.442482 -213.16887) (xy 187.479116 -213.219292) (xy 187.509142 -213.273909) (xy 187.532085 -213.331857)
			(xy 187.547585 -213.392225) (xy 187.555397 -213.454059) (xy 187.555886 -213.485222) (xy 187.55541 -213.516431)
			(xy 187.547587 -213.578358) (xy 187.532057 -213.638814) (xy 187.509064 -213.696843) (xy 187.478972 -213.751529)
			(xy 187.442255 -213.802007) (xy 187.399496 -213.847479) (xy 187.351369 -213.887226) (xy 187.325254 -213.904322)
			(xy 187.315094 -213.910672) (xy 187.302902 -213.930484) (xy 187.29325 -214.034624) (xy 187.301632 -214.056468)
			(xy 187.310522 -214.064596) (xy 187.328844 -214.082116) (xy 187.360986 -214.121319) (xy 187.387458 -214.164553)
			(xy 187.407763 -214.211003) (xy 187.421518 -214.259796) (xy 187.428463 -214.310013) (xy 187.428886 -214.33536)
			(xy 187.428456 -214.360677) (xy 187.421534 -214.410836) (xy 187.407814 -214.459576) (xy 187.387556 -214.505981)
			(xy 187.361139 -214.549177) (xy 187.32906 -214.588354) (xy 187.310776 -214.60587) (xy 187.301886 -214.614252)
			(xy 187.293504 -214.635842) (xy 187.302902 -214.739982) (xy 187.315094 -214.759794) (xy 187.325254 -214.766398)
			(xy 187.351348 -214.783499) (xy 187.399467 -214.82321) (xy 187.442222 -214.868646) (xy 187.478938 -214.919087)
			(xy 187.509034 -214.973737) (xy 187.532035 -215.031732) (xy 187.547575 -215.092154) (xy 187.555411 -215.15405)
			(xy 187.555886 -215.185244) (xy 187.555427 -215.216454) (xy 187.547602 -215.278381) (xy 187.532069 -215.338837)
			(xy 187.509073 -215.396867) (xy 187.478979 -215.451553) (xy 187.44226 -215.50203) (xy 187.399499 -215.547502)
			(xy 187.35137 -215.587249) (xy 187.325254 -215.604344) (xy 187.315094 -215.610694) (xy 187.302902 -215.630506)
			(xy 187.29325 -215.734646) (xy 187.301632 -215.75649) (xy 187.310522 -215.764618) (xy 187.328854 -215.782128)
			(xy 187.360995 -215.821333) (xy 187.387467 -215.864568) (xy 187.40777 -215.911021) (xy 187.421522 -215.959816)
			(xy 187.428465 -216.010034) (xy 187.428886 -216.035382) (xy 187.42847 -216.0607) (xy 187.421545 -216.110859)
			(xy 187.407823 -216.159599) (xy 187.387562 -216.206004) (xy 187.361142 -216.2492) (xy 187.329061 -216.288376)
			(xy 187.310776 -216.305892) (xy 187.301886 -216.314274) (xy 187.293504 -216.335864) (xy 187.302902 -216.440004)
			(xy 187.315094 -216.459816) (xy 187.325254 -216.46642) (xy 187.351358 -216.483507) (xy 187.399477 -216.52322)
			(xy 187.442232 -216.568657) (xy 187.478947 -216.619101) (xy 187.509042 -216.673753) (xy 187.53204 -216.73175)
			(xy 187.547579 -216.792174) (xy 187.555413 -216.854071) (xy 187.555886 -216.885266) (xy 187.555444 -216.916476)
			(xy 187.547616 -216.978404) (xy 187.532081 -217.038861) (xy 187.509083 -217.096891) (xy 187.478986 -217.151576)
			(xy 187.442265 -217.202053) (xy 187.399501 -217.247525) (xy 187.351371 -217.287271) (xy 187.325254 -217.304366)
			(xy 187.315094 -217.310716) (xy 187.302902 -217.330528) (xy 187.29325 -217.434668) (xy 187.301632 -217.456512)
			(xy 187.310522 -217.46464) (xy 187.328865 -217.482139) (xy 187.361005 -217.521346) (xy 187.387475 -217.564584)
			(xy 187.407776 -217.611039) (xy 187.421526 -217.659836) (xy 187.428466 -217.710056) (xy 187.428886 -217.735404)
			(xy 190.664338 -217.735404) (xy 190.664824 -217.704195) (xy 190.672643 -217.642268) (xy 190.688171 -217.581812)
			(xy 190.711162 -217.523782) (xy 190.741254 -217.469096) (xy 190.777969 -217.418618) (xy 190.820728 -217.373146)
			(xy 190.868855 -217.333399) (xy 190.89497 -217.316304) (xy 190.90513 -217.309954) (xy 190.917322 -217.290142)
			(xy 190.926974 -217.186002) (xy 190.918592 -217.164158) (xy 190.909702 -217.15603) (xy 190.891397 -217.138492)
			(xy 190.859253 -217.099294) (xy 190.832777 -217.056064) (xy 190.81247 -217.009617) (xy 190.798712 -216.960827)
			(xy 190.791763 -216.910612) (xy 190.791338 -216.885266) (xy 190.791778 -216.859949) (xy 190.798697 -216.809791)
			(xy 190.812414 -216.76105) (xy 190.832671 -216.714646) (xy 190.859087 -216.671449) (xy 190.891165 -216.632273)
			(xy 190.909448 -216.614756) (xy 190.918338 -216.606374) (xy 190.92672 -216.584784) (xy 190.917322 -216.480644)
			(xy 190.90513 -216.460832) (xy 190.89497 -216.454228) (xy 190.868871 -216.437136) (xy 190.820755 -216.39742)
			(xy 190.778002 -216.351982) (xy 190.741289 -216.301539) (xy 190.711194 -216.246888) (xy 190.688194 -216.188894)
			(xy 190.672652 -216.128471) (xy 190.664814 -216.066576) (xy 190.664338 -216.035382) (xy 190.664807 -216.004172)
			(xy 190.672629 -215.942245) (xy 190.688159 -215.881788) (xy 190.711153 -215.823759) (xy 190.741247 -215.769073)
			(xy 190.777964 -215.718595) (xy 190.820725 -215.673123) (xy 190.868854 -215.633377) (xy 190.89497 -215.616282)
			(xy 190.90513 -215.609932) (xy 190.917322 -215.59012) (xy 190.926974 -215.48598) (xy 190.918592 -215.464136)
			(xy 190.909702 -215.456008) (xy 190.891387 -215.438481) (xy 190.859243 -215.39928) (xy 190.832769 -215.356048)
			(xy 190.812463 -215.309599) (xy 190.798707 -215.260807) (xy 190.791761 -215.210591) (xy 190.791338 -215.185244)
			(xy 190.791764 -215.159927) (xy 190.798686 -215.109767) (xy 190.812406 -215.061027) (xy 190.832665 -215.014622)
			(xy 190.859083 -214.971426) (xy 190.891164 -214.93225) (xy 190.909448 -214.914734) (xy 190.918338 -214.906352)
			(xy 190.92672 -214.884762) (xy 190.917322 -214.780622) (xy 190.90513 -214.76081) (xy 190.89497 -214.754206)
			(xy 190.86886 -214.737128) (xy 190.820745 -214.697411) (xy 190.777993 -214.651971) (xy 190.74128 -214.601526)
			(xy 190.711186 -214.546873) (xy 190.688188 -214.488876) (xy 190.672648 -214.428452) (xy 190.664813 -214.366555)
			(xy 190.664338 -214.33536) (xy 190.664789 -214.30415) (xy 190.672614 -214.242222) (xy 190.688147 -214.181765)
			(xy 190.711144 -214.123735) (xy 190.74124 -214.069049) (xy 190.777959 -214.018572) (xy 190.820723 -213.973101)
			(xy 190.868853 -213.933355) (xy 190.89497 -213.91626) (xy 190.90513 -213.90991) (xy 190.917322 -213.890098)
			(xy 190.926974 -213.785958) (xy 190.918592 -213.764114) (xy 190.909702 -213.755986) (xy 190.891376 -213.73847)
			(xy 190.859234 -213.699267) (xy 190.832761 -213.656032) (xy 190.812457 -213.609581) (xy 190.798703 -213.560787)
			(xy 190.79176 -213.51057) (xy 190.791338 -213.485222) (xy 190.791749 -213.459904) (xy 190.798674 -213.409744)
			(xy 190.812397 -213.361004) (xy 190.832659 -213.314599) (xy 190.85908 -213.271403) (xy 190.891162 -213.232228)
			(xy 190.909448 -213.214712) (xy 190.918338 -213.20633) (xy 190.92672 -213.18474) (xy 190.917322 -213.0806)
			(xy 190.90513 -213.060788) (xy 190.89497 -213.054184) (xy 190.86885 -213.037121) (xy 190.820735 -212.997402)
			(xy 190.777983 -212.951959) (xy 190.741271 -212.901512) (xy 190.711179 -212.846857) (xy 190.688182 -212.788858)
			(xy 190.672645 -212.728432) (xy 190.664811 -212.666534) (xy 190.664338 -212.635338) (xy 190.664827 -212.604175)
			(xy 190.672639 -212.542341) (xy 190.688139 -212.481973) (xy 190.711082 -212.424025) (xy 190.741108 -212.369408)
			(xy 190.777742 -212.318986) (xy 190.820407 -212.273552) (xy 190.868429 -212.233824) (xy 190.921053 -212.200429)
			(xy 190.977447 -212.173892) (xy 191.036722 -212.154632) (xy 191.097943 -212.142953) (xy 191.160146 -212.13904)
			(xy 191.222349 -212.142953) (xy 191.28357 -212.154632) (xy 191.342845 -212.173892) (xy 191.399239 -212.200429)
			(xy 191.451863 -212.233824) (xy 191.499885 -212.273552) (xy 191.54255 -212.318986) (xy 191.579184 -212.369408)
			(xy 191.60921 -212.424025) (xy 191.632153 -212.481973) (xy 191.647653 -212.542341) (xy 191.655465 -212.604175)
			(xy 191.655954 -212.635338) (xy 195.619131 -212.635338) (xy 195.623066 -212.581567) (xy 195.634789 -212.528943)
			(xy 195.654049 -212.478586) (xy 195.680435 -212.431569) (xy 195.713387 -212.388896) (xy 195.7522 -212.351475)
			(xy 195.796048 -212.320105) (xy 195.843996 -212.295453) (xy 195.895023 -212.278045) (xy 195.948041 -212.268252)
			(xy 196.00192 -212.266283) (xy 196.055511 -212.27218) (xy 196.107672 -212.285816) (xy 196.157292 -212.306903)
			(xy 196.203313 -212.334989) (xy 196.244755 -212.369477) (xy 196.280733 -212.409631) (xy 196.310481 -212.454595)
			(xy 196.333366 -212.503412) (xy 196.348898 -212.555041) (xy 196.356748 -212.608381) (xy 196.35724 -212.635338)
			(xy 196.356748 -212.662295) (xy 196.348898 -212.715635) (xy 196.333366 -212.767264) (xy 196.310481 -212.816081)
			(xy 196.280733 -212.861045) (xy 196.244755 -212.901199) (xy 196.203313 -212.935687) (xy 196.157292 -212.963773)
			(xy 196.107672 -212.98486) (xy 196.055511 -212.998496) (xy 196.00192 -213.004393) (xy 195.948041 -213.002424)
			(xy 195.895023 -212.992631) (xy 195.843996 -212.975223) (xy 195.796048 -212.950571) (xy 195.7522 -212.919201)
			(xy 195.713387 -212.88178) (xy 195.680435 -212.839107) (xy 195.654049 -212.79209) (xy 195.634789 -212.741733)
			(xy 195.623066 -212.689109) (xy 195.619131 -212.635338) (xy 191.655954 -212.635338) (xy 191.655444 -212.666534)
			(xy 191.64763 -212.728433) (xy 191.632106 -212.788862) (xy 191.609118 -212.846864) (xy 191.579029 -212.901519)
			(xy 191.542315 -212.951965) (xy 191.499558 -212.997401) (xy 191.451434 -213.037109) (xy 191.425322 -213.054184)
			(xy 191.415162 -213.060788) (xy 191.40297 -213.0806) (xy 191.393572 -213.18474) (xy 191.401954 -213.20633)
			(xy 191.410844 -213.214712) (xy 191.429143 -213.232214) (xy 191.46122 -213.271394) (xy 191.487635 -213.314594)
			(xy 191.507894 -213.361001) (xy 191.521614 -213.409743) (xy 191.528537 -213.459904) (xy 191.528954 -213.485222)
			(xy 191.528552 -213.510571) (xy 191.521616 -213.560792) (xy 191.507863 -213.609589) (xy 191.487554 -213.656041)
			(xy 191.461072 -213.699272) (xy 191.428916 -213.738467) (xy 191.41059 -213.755986) (xy 191.4017 -213.764114)
			(xy 191.393318 -213.785958) (xy 191.40297 -213.890098) (xy 191.415162 -213.90991) (xy 191.425322 -213.91626)
			(xy 191.451427 -213.933368) (xy 191.499549 -213.97312) (xy 191.542304 -214.018593) (xy 191.579018 -214.069069)
			(xy 191.609112 -214.123752) (xy 191.632109 -214.181777) (xy 191.647648 -214.242229) (xy 191.655481 -214.304152)
			(xy 191.655954 -214.33536) (xy 191.655461 -214.366556) (xy 191.647645 -214.428457) (xy 191.632118 -214.488886)
			(xy 191.609127 -214.546887) (xy 191.579036 -214.601543) (xy 191.54232 -214.651988) (xy 191.49956 -214.697424)
			(xy 191.451435 -214.737132) (xy 191.425322 -214.754206) (xy 191.415162 -214.76081) (xy 191.40297 -214.780622)
			(xy 191.393572 -214.884762) (xy 191.401954 -214.906352) (xy 191.410844 -214.914734) (xy 191.429105 -214.932274)
			(xy 191.461185 -214.971446) (xy 191.487606 -215.014638) (xy 191.507871 -215.061038) (xy 191.521599 -215.109773)
			(xy 191.528532 -215.159928) (xy 191.528954 -215.185244) (xy 191.528566 -215.210593) (xy 191.521627 -215.260815)
			(xy 191.507872 -215.309612) (xy 191.48756 -215.356064) (xy 191.461076 -215.399295) (xy 191.428917 -215.43849)
			(xy 191.41059 -215.456008) (xy 191.4017 -215.464136) (xy 191.393318 -215.48598) (xy 191.40297 -215.59012)
			(xy 191.415162 -215.609932) (xy 191.425322 -215.616282) (xy 191.451438 -215.633376) (xy 191.499559 -215.673129)
			(xy 191.542314 -215.718604) (xy 191.579027 -215.769083) (xy 191.609119 -215.823768) (xy 191.632115 -215.881795)
			(xy 191.647651 -215.942249) (xy 191.655482 -216.004173) (xy 191.655954 -216.035382) (xy 191.655478 -216.066579)
			(xy 191.647659 -216.12848) (xy 191.63213 -216.188909) (xy 191.609137 -216.246911) (xy 191.579043 -216.301567)
			(xy 191.542324 -216.352012) (xy 191.499563 -216.397447) (xy 191.451436 -216.437154) (xy 191.425322 -216.454228)
			(xy 191.415162 -216.460832) (xy 191.40297 -216.480644) (xy 191.393572 -216.584784) (xy 191.401954 -216.606374)
			(xy 191.410844 -216.614756) (xy 191.429115 -216.632285) (xy 191.461195 -216.67146) (xy 191.487614 -216.714654)
			(xy 191.507877 -216.761055) (xy 191.521603 -216.809793) (xy 191.528533 -216.859949) (xy 191.528954 -216.885266)
			(xy 191.528581 -216.910616) (xy 191.521639 -216.960838) (xy 191.507881 -217.009636) (xy 191.487567 -217.056088)
			(xy 191.461079 -217.099318) (xy 191.428918 -217.138512) (xy 191.41059 -217.15603) (xy 191.4017 -217.164158)
			(xy 191.393318 -217.186002) (xy 191.40297 -217.290142) (xy 191.415162 -217.309954) (xy 191.425322 -217.316304)
			(xy 191.451448 -217.333383) (xy 191.499569 -217.373138) (xy 191.542323 -217.418616) (xy 191.579036 -217.469097)
			(xy 191.609127 -217.523784) (xy 191.632121 -217.581813) (xy 191.647655 -217.642268) (xy 191.655484 -217.704194)
			(xy 191.655954 -217.735404) (xy 191.655465 -217.766567) (xy 191.647653 -217.828401) (xy 191.632153 -217.888769)
			(xy 191.60921 -217.946717) (xy 191.579184 -218.001334) (xy 191.54255 -218.051756) (xy 191.499885 -218.09719)
			(xy 191.451863 -218.136918) (xy 191.399239 -218.170313) (xy 191.342845 -218.19685) (xy 191.28357 -218.21611)
			(xy 191.222349 -218.227789) (xy 191.160146 -218.231702) (xy 191.097943 -218.227789) (xy 191.036722 -218.21611)
			(xy 190.977447 -218.19685) (xy 190.921053 -218.170313) (xy 190.868429 -218.136918) (xy 190.820407 -218.09719)
			(xy 190.777742 -218.051756) (xy 190.741108 -218.001334) (xy 190.711082 -217.946717) (xy 190.688139 -217.888769)
			(xy 190.672639 -217.828401) (xy 190.664827 -217.766567) (xy 190.664338 -217.735404) (xy 187.428886 -217.735404)
			(xy 187.428485 -217.760722) (xy 187.421557 -217.810882) (xy 187.407832 -217.859623) (xy 187.387568 -217.906027)
			(xy 187.361145 -217.949223) (xy 187.329062 -217.988398) (xy 187.310776 -218.005914) (xy 187.301886 -218.014296)
			(xy 187.293504 -218.035886) (xy 187.302902 -218.140026) (xy 187.315094 -218.159838) (xy 187.325254 -218.166442)
			(xy 187.351368 -218.183514) (xy 187.399487 -218.223229) (xy 187.442241 -218.268669) (xy 187.478956 -218.319115)
			(xy 187.509049 -218.373769) (xy 187.532046 -218.431768) (xy 187.547583 -218.492194) (xy 187.555414 -218.554092)
			(xy 187.555886 -218.585288) (xy 189.406545 -218.585288) (xy 189.41048 -218.531517) (xy 189.422203 -218.478893)
			(xy 189.441463 -218.428536) (xy 189.467849 -218.381519) (xy 189.500801 -218.338846) (xy 189.539614 -218.301425)
			(xy 189.583462 -218.270055) (xy 189.63141 -218.245403) (xy 189.682437 -218.227995) (xy 189.735455 -218.218202)
			(xy 189.789334 -218.216233) (xy 189.842925 -218.22213) (xy 189.895086 -218.235766) (xy 189.944706 -218.256853)
			(xy 189.990727 -218.284939) (xy 190.032169 -218.319427) (xy 190.068147 -218.359581) (xy 190.097895 -218.404545)
			(xy 190.12078 -218.453362) (xy 190.136312 -218.504991) (xy 190.144162 -218.558331) (xy 190.144654 -218.585288)
			(xy 194.108324 -218.585288) (xy 194.10874 -218.554089) (xy 194.116564 -218.492184) (xy 194.1321 -218.431752)
			(xy 194.155101 -218.373748) (xy 194.185203 -218.319092) (xy 194.22193 -218.268648) (xy 194.264701 -218.223216)
			(xy 194.312838 -218.183513) (xy 194.338956 -218.166442) (xy 194.349116 -218.159838) (xy 194.361308 -218.140026)
			(xy 194.370706 -218.035886) (xy 194.362324 -218.014296) (xy 194.353434 -218.005914) (xy 194.335144 -217.988404)
			(xy 194.303067 -217.949225) (xy 194.27665 -217.906026) (xy 194.256391 -217.859621) (xy 194.242669 -217.810881)
			(xy 194.235743 -217.760722) (xy 194.235324 -217.735404) (xy 194.235751 -217.710056) (xy 194.242683 -217.659836)
			(xy 194.256431 -217.61104) (xy 194.276735 -217.564588) (xy 194.303213 -217.521356) (xy 194.335365 -217.48216)
			(xy 194.353688 -217.46464) (xy 194.362578 -217.456512) (xy 194.37096 -217.434668) (xy 194.361308 -217.330528)
			(xy 194.349116 -217.310716) (xy 194.338956 -217.304366) (xy 194.312857 -217.287248) (xy 194.264737 -217.247497)
			(xy 194.221982 -217.202025) (xy 194.185268 -217.15155) (xy 194.155174 -217.096869) (xy 194.132175 -217.038845)
			(xy 194.116635 -216.978395) (xy 194.108799 -216.916474) (xy 194.108324 -216.885266) (xy 194.108801 -216.854069)
			(xy 194.116616 -216.792167) (xy 194.132142 -216.731735) (xy 194.155134 -216.673732) (xy 194.185228 -216.619076)
			(xy 194.221947 -216.568631) (xy 194.26471 -216.523197) (xy 194.312841 -216.483492) (xy 194.338956 -216.46642)
			(xy 194.349116 -216.459816) (xy 194.361308 -216.440004) (xy 194.370706 -216.335864) (xy 194.362324 -216.314274)
			(xy 194.353434 -216.305892) (xy 194.335133 -216.288392) (xy 194.303057 -216.249211) (xy 194.276642 -216.206011)
			(xy 194.256384 -216.159603) (xy 194.242665 -216.110861) (xy 194.235741 -216.0607) (xy 194.235324 -216.035382)
			(xy 194.235736 -216.010033) (xy 194.242671 -215.959813) (xy 194.256422 -215.911017) (xy 194.276729 -215.864565)
			(xy 194.303209 -215.821333) (xy 194.335363 -215.782137) (xy 194.353688 -215.764618) (xy 194.362578 -215.75649)
			(xy 194.37096 -215.734646) (xy 194.361308 -215.630506) (xy 194.349116 -215.610694) (xy 194.338956 -215.604344)
			(xy 194.312847 -215.587241) (xy 194.264727 -215.547488) (xy 194.221973 -215.502014) (xy 194.185259 -215.451536)
			(xy 194.155166 -215.396853) (xy 194.132169 -215.338827) (xy 194.116631 -215.278376) (xy 194.108797 -215.216452)
			(xy 194.108324 -215.185244) (xy 194.108784 -215.154046) (xy 194.116601 -215.092143) (xy 194.13213 -215.031712)
			(xy 194.155124 -214.973709) (xy 194.185221 -214.919052) (xy 194.221942 -214.868608) (xy 194.264708 -214.823174)
			(xy 194.31284 -214.78347) (xy 194.338956 -214.766398) (xy 194.349116 -214.759794) (xy 194.361308 -214.739982)
			(xy 194.370706 -214.635842) (xy 194.362324 -214.614252) (xy 194.353434 -214.60587) (xy 194.335122 -214.588381)
			(xy 194.303048 -214.549197) (xy 194.276634 -214.505995) (xy 194.256378 -214.459585) (xy 194.242661 -214.410841)
			(xy 194.23574 -214.360679) (xy 194.235324 -214.33536) (xy 194.235721 -214.310011) (xy 194.242659 -214.25979)
			(xy 194.256413 -214.210993) (xy 194.276723 -214.164541) (xy 194.303206 -214.12131) (xy 194.335362 -214.082115)
			(xy 194.353688 -214.064596) (xy 194.362578 -214.056468) (xy 194.37096 -214.034624) (xy 194.361308 -213.930484)
			(xy 194.349116 -213.910672) (xy 194.338956 -213.904322) (xy 194.312837 -213.887233) (xy 194.264717 -213.847478)
			(xy 194.221963 -213.802002) (xy 194.18525 -213.751523) (xy 194.155159 -213.696837) (xy 194.132163 -213.638809)
			(xy 194.116627 -213.578356) (xy 194.108796 -213.516431) (xy 194.108324 -213.485222) (xy 194.108813 -213.454059)
			(xy 194.116625 -213.392225) (xy 194.132125 -213.331857) (xy 194.155068 -213.273909) (xy 194.185094 -213.219292)
			(xy 194.221728 -213.16887) (xy 194.264393 -213.123436) (xy 194.312415 -213.083708) (xy 194.365039 -213.050313)
			(xy 194.421433 -213.023776) (xy 194.480708 -213.004516) (xy 194.541929 -212.992837) (xy 194.604132 -212.988924)
			(xy 194.666335 -212.992837) (xy 194.727556 -213.004516) (xy 194.786831 -213.023776) (xy 194.843225 -213.050313)
			(xy 194.895849 -213.083708) (xy 194.943871 -213.123436) (xy 194.986536 -213.16887) (xy 195.02317 -213.219292)
			(xy 195.053196 -213.273909) (xy 195.076139 -213.331857) (xy 195.091639 -213.392225) (xy 195.099451 -213.454059)
			(xy 195.09994 -213.485222) (xy 195.099439 -213.51643) (xy 195.091617 -213.578355) (xy 195.076089 -213.638809)
			(xy 195.053099 -213.696837) (xy 195.02301 -213.751523) (xy 194.986298 -213.802001) (xy 194.943543 -213.847474)
			(xy 194.89542 -213.887225) (xy 194.869308 -213.904322) (xy 194.859148 -213.910672) (xy 194.846956 -213.930484)
			(xy 194.837304 -214.034624) (xy 194.845686 -214.056468) (xy 194.854576 -214.064596) (xy 194.872889 -214.082125)
			(xy 194.905034 -214.121325) (xy 194.931508 -214.164556) (xy 194.951815 -214.211005) (xy 194.965571 -214.259797)
			(xy 194.972517 -214.310013) (xy 194.97294 -214.33536) (xy 194.972524 -214.360678) (xy 194.965601 -214.410838)
			(xy 194.95188 -214.459578) (xy 194.931618 -214.505983) (xy 194.905198 -214.54918) (xy 194.873116 -214.588354)
			(xy 194.85483 -214.60587) (xy 194.84594 -214.614252) (xy 194.837558 -214.635842) (xy 194.846956 -214.739982)
			(xy 194.859148 -214.759794) (xy 194.869308 -214.766398) (xy 194.895414 -214.783481) (xy 194.943531 -214.823196)
			(xy 194.986284 -214.868635) (xy 195.022998 -214.91908) (xy 195.053092 -214.973732) (xy 195.07609 -215.031729)
			(xy 195.09163 -215.092153) (xy 195.099466 -215.154049) (xy 195.09994 -215.185244) (xy 195.099456 -215.216453)
			(xy 195.091632 -215.278378) (xy 195.076101 -215.338833) (xy 195.053108 -215.396861) (xy 195.023017 -215.451546)
			(xy 194.986302 -215.502024) (xy 194.943545 -215.547497) (xy 194.895421 -215.587247) (xy 194.869308 -215.604344)
			(xy 194.859148 -215.610694) (xy 194.846956 -215.630506) (xy 194.837304 -215.734646) (xy 194.845686 -215.75649)
			(xy 194.854576 -215.764618) (xy 194.8729 -215.782137) (xy 194.905043 -215.821339) (xy 194.931517 -215.864572)
			(xy 194.951822 -215.911023) (xy 194.965575 -215.959817) (xy 194.972519 -216.010034) (xy 194.97294 -216.035382)
			(xy 194.972539 -216.0607) (xy 194.965613 -216.110861) (xy 194.951889 -216.159602) (xy 194.931624 -216.206007)
			(xy 194.905201 -216.249203) (xy 194.873117 -216.288377) (xy 194.85483 -216.305892) (xy 194.84594 -216.314274)
			(xy 194.837558 -216.335864) (xy 194.846956 -216.440004) (xy 194.859148 -216.459816) (xy 194.869308 -216.46642)
			(xy 194.895424 -216.483488) (xy 194.943541 -216.523206) (xy 194.986293 -216.568647) (xy 195.023006 -216.619094)
			(xy 195.053099 -216.673748) (xy 195.076096 -216.731747) (xy 195.091634 -216.792172) (xy 195.099467 -216.85407)
			(xy 195.09994 -216.885266) (xy 195.099473 -216.916475) (xy 195.091646 -216.978401) (xy 195.076113 -217.038856)
			(xy 195.053117 -217.096885) (xy 195.023024 -217.15157) (xy 194.986307 -217.202048) (xy 194.943548 -217.24752)
			(xy 194.895422 -217.287269) (xy 194.869308 -217.304366) (xy 194.859148 -217.310716) (xy 194.846956 -217.330528)
			(xy 194.837304 -217.434668) (xy 194.845686 -217.456512) (xy 194.854576 -217.46464) (xy 194.87291 -217.482148)
			(xy 194.905053 -217.521352) (xy 194.931525 -217.564588) (xy 194.951828 -217.611041) (xy 194.965579 -217.659837)
			(xy 194.97252 -217.710056) (xy 194.97294 -217.735404) (xy 198.208392 -217.735404) (xy 198.208899 -217.704196)
			(xy 198.216717 -217.642271) (xy 198.232244 -217.581816) (xy 198.255233 -217.523787) (xy 198.285321 -217.469102)
			(xy 198.322033 -217.418623) (xy 198.364788 -217.37315) (xy 198.412911 -217.333401) (xy 198.439024 -217.316304)
			(xy 198.449184 -217.309954) (xy 198.461376 -217.290142) (xy 198.471028 -217.186002) (xy 198.462646 -217.164158)
			(xy 198.453756 -217.15603) (xy 198.435462 -217.138482) (xy 198.403314 -217.099287) (xy 198.376836 -217.05606)
			(xy 198.356526 -217.009614) (xy 198.342766 -216.960825) (xy 198.335817 -216.910612) (xy 198.335392 -216.885266)
			(xy 198.335847 -216.85995) (xy 198.342765 -216.809792) (xy 198.35648 -216.761053) (xy 198.376734 -216.714649)
			(xy 198.403147 -216.671451) (xy 198.435221 -216.632274) (xy 198.453502 -216.614756) (xy 198.462392 -216.606374)
			(xy 198.470774 -216.584784) (xy 198.461376 -216.480644) (xy 198.449184 -216.460832) (xy 198.439024 -216.454228)
			(xy 198.412937 -216.437117) (xy 198.364819 -216.397406) (xy 198.322064 -216.351972) (xy 198.285348 -216.301532)
			(xy 198.255251 -216.246884) (xy 198.23225 -216.18889) (xy 198.216707 -216.12847) (xy 198.208868 -216.066576)
			(xy 198.208392 -216.035382) (xy 198.208882 -216.004173) (xy 198.216703 -215.942247) (xy 198.232232 -215.881792)
			(xy 198.255224 -215.823764) (xy 198.285314 -215.769078) (xy 198.322028 -215.7186) (xy 198.364786 -215.673127)
			(xy 198.41291 -215.633378) (xy 198.439024 -215.616282) (xy 198.449184 -215.609932) (xy 198.461376 -215.59012)
			(xy 198.471028 -215.48598) (xy 198.462646 -215.464136) (xy 198.453756 -215.456008) (xy 198.435451 -215.43847)
			(xy 198.403304 -215.399273) (xy 198.376828 -215.356044) (xy 198.35652 -215.309596) (xy 198.342762 -215.260805)
			(xy 198.335815 -215.210591) (xy 198.335392 -215.185244) (xy 198.335832 -215.159927) (xy 198.342753 -215.109769)
			(xy 198.356471 -215.06103) (xy 198.376728 -215.014625) (xy 198.403143 -214.971428) (xy 198.435219 -214.932251)
			(xy 198.453502 -214.914734) (xy 198.462392 -214.906352) (xy 198.470774 -214.884762) (xy 198.461376 -214.780622)
			(xy 198.449184 -214.76081) (xy 198.439024 -214.754206) (xy 198.412927 -214.73711) (xy 198.364809 -214.697397)
			(xy 198.322054 -214.651961) (xy 198.285339 -214.601518) (xy 198.255244 -214.546868) (xy 198.232244 -214.488873)
			(xy 198.216703 -214.42845) (xy 198.208867 -214.366555) (xy 198.208392 -214.33536) (xy 198.208865 -214.304151)
			(xy 198.216688 -214.242224) (xy 198.23222 -214.181769) (xy 198.255214 -214.12374) (xy 198.285307 -214.069054)
			(xy 198.322023 -214.018576) (xy 198.364783 -213.973104) (xy 198.412909 -213.933356) (xy 198.439024 -213.91626)
			(xy 198.449184 -213.90991) (xy 198.461376 -213.890098) (xy 198.471028 -213.785958) (xy 198.462646 -213.764114)
			(xy 198.453756 -213.755986) (xy 198.43544 -213.738459) (xy 198.403295 -213.69926) (xy 198.376819 -213.656028)
			(xy 198.356513 -213.609578) (xy 198.342758 -213.560786) (xy 198.335814 -213.510569) (xy 198.335392 -213.485222)
			(xy 198.335817 -213.459905) (xy 198.342741 -213.409746) (xy 198.356462 -213.361006) (xy 198.376722 -213.314602)
			(xy 198.403139 -213.271405) (xy 198.435218 -213.232229) (xy 198.453502 -213.214712) (xy 198.462392 -213.20633)
			(xy 198.470774 -213.18474) (xy 198.461376 -213.0806) (xy 198.449184 -213.060788) (xy 198.439024 -213.054184)
			(xy 198.412917 -213.037102) (xy 198.364799 -212.997388) (xy 198.322045 -212.951949) (xy 198.28533 -212.901505)
			(xy 198.255236 -212.846852) (xy 198.232238 -212.788855) (xy 198.216699 -212.72843) (xy 198.208865 -212.666533)
			(xy 198.208392 -212.635338) (xy 198.208881 -212.604175) (xy 198.216693 -212.542341) (xy 198.232193 -212.481973)
			(xy 198.255136 -212.424025) (xy 198.285162 -212.369408) (xy 198.321796 -212.318986) (xy 198.364461 -212.273552)
			(xy 198.412483 -212.233824) (xy 198.465107 -212.200429) (xy 198.521501 -212.173892) (xy 198.580776 -212.154632)
			(xy 198.641997 -212.142953) (xy 198.7042 -212.13904) (xy 198.766403 -212.142953) (xy 198.827624 -212.154632)
			(xy 198.886899 -212.173892) (xy 198.943293 -212.200429) (xy 198.995917 -212.233824) (xy 199.043939 -212.273552)
			(xy 199.086604 -212.318986) (xy 199.123238 -212.369408) (xy 199.153264 -212.424025) (xy 199.176207 -212.481973)
			(xy 199.191707 -212.542341) (xy 199.199519 -212.604175) (xy 199.200008 -212.635338) (xy 203.162931 -212.635338)
			(xy 203.166866 -212.581567) (xy 203.178589 -212.528943) (xy 203.197849 -212.478586) (xy 203.224235 -212.431569)
			(xy 203.257187 -212.388896) (xy 203.296 -212.351475) (xy 203.339848 -212.320105) (xy 203.387796 -212.295453)
			(xy 203.438823 -212.278045) (xy 203.491841 -212.268252) (xy 203.54572 -212.266283) (xy 203.599311 -212.27218)
			(xy 203.651472 -212.285816) (xy 203.701092 -212.306903) (xy 203.747113 -212.334989) (xy 203.788555 -212.369477)
			(xy 203.824533 -212.409631) (xy 203.854281 -212.454595) (xy 203.877166 -212.503412) (xy 203.892698 -212.555041)
			(xy 203.900548 -212.608381) (xy 203.90104 -212.635338) (xy 203.900548 -212.662295) (xy 203.892698 -212.715635)
			(xy 203.877166 -212.767264) (xy 203.854281 -212.816081) (xy 203.824533 -212.861045) (xy 203.788555 -212.901199)
			(xy 203.747113 -212.935687) (xy 203.701092 -212.963773) (xy 203.651472 -212.98486) (xy 203.599311 -212.998496)
			(xy 203.54572 -213.004393) (xy 203.491841 -213.002424) (xy 203.438823 -212.992631) (xy 203.387796 -212.975223)
			(xy 203.339848 -212.950571) (xy 203.296 -212.919201) (xy 203.257187 -212.88178) (xy 203.224235 -212.839107)
			(xy 203.197849 -212.79209) (xy 203.178589 -212.741733) (xy 203.166866 -212.689109) (xy 203.162931 -212.635338)
			(xy 199.200008 -212.635338) (xy 199.199519 -212.666535) (xy 199.191705 -212.728436) (xy 199.176179 -212.788866)
			(xy 199.153188 -212.846868) (xy 199.123096 -212.901525) (xy 199.086379 -212.95197) (xy 199.043618 -212.997405)
			(xy 198.99549 -213.037111) (xy 198.969376 -213.054184) (xy 198.959216 -213.060788) (xy 198.947024 -213.0806)
			(xy 198.937626 -213.18474) (xy 198.946008 -213.20633) (xy 198.954898 -213.214712) (xy 198.973188 -213.232223)
			(xy 199.005267 -213.2714) (xy 199.031686 -213.314598) (xy 199.051946 -213.361003) (xy 199.065667 -213.409744)
			(xy 199.072591 -213.459904) (xy 199.073008 -213.485222) (xy 199.072589 -213.51057) (xy 199.065654 -213.56079)
			(xy 199.051903 -213.609586) (xy 199.031598 -213.656038) (xy 199.005119 -213.699269) (xy 198.972967 -213.738466)
			(xy 198.954644 -213.755986) (xy 198.945754 -213.764114) (xy 198.937372 -213.785958) (xy 198.947024 -213.890098)
			(xy 198.959216 -213.90991) (xy 198.969376 -213.91626) (xy 198.995471 -213.933384) (xy 199.043594 -213.973132)
			(xy 199.086351 -214.018602) (xy 199.123067 -214.069076) (xy 199.153163 -214.123756) (xy 199.176161 -214.18178)
			(xy 199.191701 -214.24223) (xy 199.199534 -214.304152) (xy 199.200008 -214.33536) (xy 199.199536 -214.366557)
			(xy 199.191719 -214.428459) (xy 199.176191 -214.48889) (xy 199.153198 -214.546892) (xy 199.123103 -214.601548)
			(xy 199.086384 -214.651993) (xy 199.043621 -214.697428) (xy 198.995491 -214.737133) (xy 198.969376 -214.754206)
			(xy 198.959216 -214.76081) (xy 198.947024 -214.780622) (xy 198.937626 -214.884762) (xy 198.946008 -214.906352)
			(xy 198.954898 -214.914734) (xy 198.97315 -214.932283) (xy 199.005233 -214.971452) (xy 199.031656 -215.014642)
			(xy 199.051923 -215.06104) (xy 199.065652 -215.109774) (xy 199.072586 -215.159928) (xy 199.073008 -215.185244)
			(xy 199.072603 -215.210593) (xy 199.065665 -215.260813) (xy 199.051912 -215.309609) (xy 199.031604 -215.356061)
			(xy 199.005123 -215.399292) (xy 198.972968 -215.438488) (xy 198.954644 -215.456008) (xy 198.945754 -215.464136)
			(xy 198.937372 -215.48598) (xy 198.947024 -215.59012) (xy 198.959216 -215.609932) (xy 198.969376 -215.616282)
			(xy 198.995481 -215.633392) (xy 199.043604 -215.673141) (xy 199.086361 -215.718613) (xy 199.123076 -215.769089)
			(xy 199.15317 -215.823772) (xy 199.176167 -215.881798) (xy 199.191704 -215.94225) (xy 199.199536 -216.004174)
			(xy 199.200008 -216.035382) (xy 199.199554 -216.06658) (xy 199.191734 -216.128482) (xy 199.176203 -216.188913)
			(xy 199.153207 -216.246916) (xy 199.12311 -216.301572) (xy 199.086388 -216.352017) (xy 199.043623 -216.397451)
			(xy 198.995492 -216.437155) (xy 198.969376 -216.454228) (xy 198.959216 -216.460832) (xy 198.947024 -216.480644)
			(xy 198.937626 -216.584784) (xy 198.946008 -216.606374) (xy 198.954898 -216.614756) (xy 198.973161 -216.632294)
			(xy 199.005243 -216.671466) (xy 199.031664 -216.714657) (xy 199.051929 -216.761058) (xy 199.065656 -216.809794)
			(xy 199.072587 -216.85995) (xy 199.073008 -216.885266) (xy 199.072618 -216.910615) (xy 199.065677 -216.960836)
			(xy 199.051921 -217.009632) (xy 199.03161 -217.056084) (xy 199.005126 -217.099315) (xy 198.97297 -217.138511)
			(xy 198.954644 -217.15603) (xy 198.945754 -217.164158) (xy 198.937372 -217.186002) (xy 198.947024 -217.290142)
			(xy 198.959216 -217.309954) (xy 198.969376 -217.316304) (xy 198.995491 -217.333399) (xy 199.043614 -217.373151)
			(xy 199.08637 -217.418625) (xy 199.123085 -217.469103) (xy 199.153178 -217.523788) (xy 199.176173 -217.581816)
			(xy 199.191708 -217.64227) (xy 199.199537 -217.704195) (xy 199.200008 -217.735404) (xy 199.199519 -217.766567)
			(xy 199.191707 -217.828401) (xy 199.176207 -217.888769) (xy 199.153264 -217.946717) (xy 199.123238 -218.001334)
			(xy 199.086604 -218.051756) (xy 199.043939 -218.09719) (xy 198.995917 -218.136918) (xy 198.943293 -218.170313)
			(xy 198.886899 -218.19685) (xy 198.827624 -218.21611) (xy 198.766403 -218.227789) (xy 198.7042 -218.231702)
			(xy 198.641997 -218.227789) (xy 198.580776 -218.21611) (xy 198.521501 -218.19685) (xy 198.465107 -218.170313)
			(xy 198.412483 -218.136918) (xy 198.364461 -218.09719) (xy 198.321796 -218.051756) (xy 198.285162 -218.001334)
			(xy 198.255136 -217.946717) (xy 198.232193 -217.888769) (xy 198.216693 -217.828401) (xy 198.208881 -217.766567)
			(xy 198.208392 -217.735404) (xy 194.97294 -217.735404) (xy 194.972554 -217.760723) (xy 194.965625 -217.810884)
			(xy 194.951898 -217.859625) (xy 194.931631 -217.90603) (xy 194.905205 -217.949226) (xy 194.873118 -217.988399)
			(xy 194.85483 -218.005914) (xy 194.84594 -218.014296) (xy 194.837558 -218.035886) (xy 194.846956 -218.140026)
			(xy 194.859148 -218.159838) (xy 194.869308 -218.166442) (xy 194.895434 -218.183495) (xy 194.943551 -218.223215)
			(xy 194.986303 -218.268659) (xy 195.023015 -218.319107) (xy 195.053107 -218.373764) (xy 195.076102 -218.431765)
			(xy 195.091638 -218.492192) (xy 195.099468 -218.554092) (xy 195.09994 -218.585288) (xy 196.950599 -218.585288)
			(xy 196.954534 -218.531517) (xy 196.966257 -218.478893) (xy 196.985517 -218.428536) (xy 197.011903 -218.381519)
			(xy 197.044855 -218.338846) (xy 197.083668 -218.301425) (xy 197.127516 -218.270055) (xy 197.175464 -218.245403)
			(xy 197.226491 -218.227995) (xy 197.279509 -218.218202) (xy 197.333388 -218.216233) (xy 197.386979 -218.22213)
			(xy 197.43914 -218.235766) (xy 197.48876 -218.256853) (xy 197.534781 -218.284939) (xy 197.576223 -218.319427)
			(xy 197.612201 -218.359581) (xy 197.641949 -218.404545) (xy 197.664834 -218.453362) (xy 197.680366 -218.504991)
			(xy 197.688216 -218.558331) (xy 197.688708 -218.585288) (xy 201.652124 -218.585288) (xy 201.65254 -218.554089)
			(xy 201.660364 -218.492184) (xy 201.6759 -218.431752) (xy 201.698901 -218.373748) (xy 201.729003 -218.319092)
			(xy 201.76573 -218.268648) (xy 201.808501 -218.223216) (xy 201.856638 -218.183513) (xy 201.882756 -218.166442)
			(xy 201.892916 -218.159838) (xy 201.905108 -218.140026) (xy 201.914506 -218.035886) (xy 201.906124 -218.014296)
			(xy 201.897234 -218.005914) (xy 201.878944 -217.988404) (xy 201.846867 -217.949225) (xy 201.82045 -217.906026)
			(xy 201.800191 -217.859621) (xy 201.786469 -217.810881) (xy 201.779543 -217.760722) (xy 201.779124 -217.735404)
			(xy 201.779551 -217.710056) (xy 201.786483 -217.659836) (xy 201.800231 -217.61104) (xy 201.820535 -217.564588)
			(xy 201.847013 -217.521356) (xy 201.879165 -217.48216) (xy 201.897488 -217.46464) (xy 201.906378 -217.456512)
			(xy 201.91476 -217.434668) (xy 201.905108 -217.330528) (xy 201.892916 -217.310716) (xy 201.882756 -217.304366)
			(xy 201.856657 -217.287248) (xy 201.808537 -217.247497) (xy 201.765782 -217.202025) (xy 201.729068 -217.15155)
			(xy 201.698974 -217.096869) (xy 201.675975 -217.038845) (xy 201.660435 -216.978395) (xy 201.652599 -216.916474)
			(xy 201.652124 -216.885266) (xy 201.652601 -216.854069) (xy 201.660416 -216.792167) (xy 201.675942 -216.731735)
			(xy 201.698934 -216.673732) (xy 201.729028 -216.619076) (xy 201.765747 -216.568631) (xy 201.80851 -216.523197)
			(xy 201.856641 -216.483492) (xy 201.882756 -216.46642) (xy 201.892916 -216.459816) (xy 201.905108 -216.440004)
			(xy 201.914506 -216.335864) (xy 201.906124 -216.314274) (xy 201.897234 -216.305892) (xy 201.878933 -216.288392)
			(xy 201.846857 -216.249211) (xy 201.820442 -216.206011) (xy 201.800184 -216.159603) (xy 201.786465 -216.110861)
			(xy 201.779541 -216.0607) (xy 201.779124 -216.035382) (xy 201.779536 -216.010033) (xy 201.786471 -215.959813)
			(xy 201.800222 -215.911017) (xy 201.820529 -215.864565) (xy 201.847009 -215.821333) (xy 201.879163 -215.782137)
			(xy 201.897488 -215.764618) (xy 201.906378 -215.75649) (xy 201.91476 -215.734646) (xy 201.905108 -215.630506)
			(xy 201.892916 -215.610694) (xy 201.882756 -215.604344) (xy 201.856647 -215.587241) (xy 201.808527 -215.547488)
			(xy 201.765773 -215.502014) (xy 201.729059 -215.451536) (xy 201.698966 -215.396853) (xy 201.675969 -215.338827)
			(xy 201.660431 -215.278376) (xy 201.652597 -215.216452) (xy 201.652124 -215.185244) (xy 201.652584 -215.154046)
			(xy 201.660401 -215.092143) (xy 201.67593 -215.031712) (xy 201.698924 -214.973709) (xy 201.729021 -214.919052)
			(xy 201.765742 -214.868608) (xy 201.808508 -214.823174) (xy 201.85664 -214.78347) (xy 201.882756 -214.766398)
			(xy 201.892916 -214.759794) (xy 201.905108 -214.739982) (xy 201.914506 -214.635842) (xy 201.906124 -214.614252)
			(xy 201.897234 -214.60587) (xy 201.878922 -214.588381) (xy 201.846848 -214.549197) (xy 201.820434 -214.505995)
			(xy 201.800178 -214.459585) (xy 201.786461 -214.410841) (xy 201.77954 -214.360679) (xy 201.779124 -214.33536)
			(xy 201.779521 -214.310011) (xy 201.786459 -214.25979) (xy 201.800213 -214.210993) (xy 201.820523 -214.164541)
			(xy 201.847006 -214.12131) (xy 201.879162 -214.082115) (xy 201.897488 -214.064596) (xy 201.906378 -214.056468)
			(xy 201.91476 -214.034624) (xy 201.905108 -213.930484) (xy 201.892916 -213.910672) (xy 201.882756 -213.904322)
			(xy 201.856637 -213.887233) (xy 201.808517 -213.847478) (xy 201.765763 -213.802002) (xy 201.72905 -213.751523)
			(xy 201.698959 -213.696837) (xy 201.675963 -213.638809) (xy 201.660427 -213.578356) (xy 201.652596 -213.516431)
			(xy 201.652124 -213.485222) (xy 201.652613 -213.454059) (xy 201.660425 -213.392225) (xy 201.675925 -213.331857)
			(xy 201.698868 -213.273909) (xy 201.728894 -213.219292) (xy 201.765528 -213.16887) (xy 201.808193 -213.123436)
			(xy 201.856215 -213.083708) (xy 201.908839 -213.050313) (xy 201.965233 -213.023776) (xy 202.024508 -213.004516)
			(xy 202.085729 -212.992837) (xy 202.147932 -212.988924) (xy 202.210135 -212.992837) (xy 202.271356 -213.004516)
			(xy 202.330631 -213.023776) (xy 202.387025 -213.050313) (xy 202.439649 -213.083708) (xy 202.487671 -213.123436)
			(xy 202.530336 -213.16887) (xy 202.56697 -213.219292) (xy 202.596996 -213.273909) (xy 202.619939 -213.331857)
			(xy 202.635439 -213.392225) (xy 202.643251 -213.454059) (xy 202.64374 -213.485222) (xy 202.643239 -213.51643)
			(xy 202.635417 -213.578355) (xy 202.619889 -213.638809) (xy 202.596899 -213.696837) (xy 202.56681 -213.751523)
			(xy 202.530098 -213.802001) (xy 202.487343 -213.847474) (xy 202.43922 -213.887225) (xy 202.413108 -213.904322)
			(xy 202.402948 -213.910672) (xy 202.390756 -213.930484) (xy 202.381104 -214.034624) (xy 202.389486 -214.056468)
			(xy 202.398376 -214.064596) (xy 202.416689 -214.082125) (xy 202.448834 -214.121325) (xy 202.475308 -214.164556)
			(xy 202.495615 -214.211005) (xy 202.509371 -214.259797) (xy 202.516317 -214.310013) (xy 202.51674 -214.33536)
			(xy 202.516324 -214.360678) (xy 202.509401 -214.410838) (xy 202.49568 -214.459578) (xy 202.475418 -214.505983)
			(xy 202.448998 -214.54918) (xy 202.416916 -214.588354) (xy 202.39863 -214.60587) (xy 202.38974 -214.614252)
			(xy 202.381358 -214.635842) (xy 202.390756 -214.739982) (xy 202.402948 -214.759794) (xy 202.413108 -214.766398)
			(xy 202.439214 -214.783481) (xy 202.487331 -214.823196) (xy 202.530084 -214.868635) (xy 202.566798 -214.91908)
			(xy 202.596892 -214.973732) (xy 202.61989 -215.031729) (xy 202.63543 -215.092153) (xy 202.643266 -215.154049)
			(xy 202.64374 -215.185244) (xy 202.643256 -215.216453) (xy 202.635432 -215.278378) (xy 202.619901 -215.338833)
			(xy 202.596908 -215.396861) (xy 202.566817 -215.451546) (xy 202.530102 -215.502024) (xy 202.487345 -215.547497)
			(xy 202.439221 -215.587247) (xy 202.413108 -215.604344) (xy 202.402948 -215.610694) (xy 202.390756 -215.630506)
			(xy 202.381104 -215.734646) (xy 202.389486 -215.75649) (xy 202.398376 -215.764618) (xy 202.4167 -215.782137)
			(xy 202.448843 -215.821339) (xy 202.475317 -215.864572) (xy 202.495622 -215.911023) (xy 202.509375 -215.959817)
			(xy 202.516319 -216.010034) (xy 202.51674 -216.035382) (xy 202.516339 -216.0607) (xy 202.509413 -216.110861)
			(xy 202.495689 -216.159602) (xy 202.475424 -216.206007) (xy 202.449001 -216.249203) (xy 202.416917 -216.288377)
			(xy 202.39863 -216.305892) (xy 202.38974 -216.314274) (xy 202.381358 -216.335864) (xy 202.390756 -216.440004)
			(xy 202.402948 -216.459816) (xy 202.413108 -216.46642) (xy 202.439224 -216.483488) (xy 202.487341 -216.523206)
			(xy 202.530093 -216.568647) (xy 202.566806 -216.619094) (xy 202.596899 -216.673748) (xy 202.619896 -216.731747)
			(xy 202.635434 -216.792172) (xy 202.643267 -216.85407) (xy 202.64374 -216.885266) (xy 202.643273 -216.916475)
			(xy 202.635446 -216.978401) (xy 202.619913 -217.038856) (xy 202.596917 -217.096885) (xy 202.566824 -217.15157)
			(xy 202.530107 -217.202048) (xy 202.487348 -217.24752) (xy 202.439222 -217.287269) (xy 202.413108 -217.304366)
			(xy 202.402948 -217.310716) (xy 202.390756 -217.330528) (xy 202.381104 -217.434668) (xy 202.389486 -217.456512)
			(xy 202.398376 -217.46464) (xy 202.41671 -217.482148) (xy 202.448853 -217.521352) (xy 202.475325 -217.564588)
			(xy 202.495628 -217.611041) (xy 202.509379 -217.659837) (xy 202.51632 -217.710056) (xy 202.51674 -217.735404)
			(xy 205.752192 -217.735404) (xy 205.752699 -217.704196) (xy 205.760517 -217.642271) (xy 205.776044 -217.581816)
			(xy 205.799033 -217.523787) (xy 205.829121 -217.469102) (xy 205.865833 -217.418623) (xy 205.908588 -217.37315)
			(xy 205.956711 -217.333401) (xy 205.982824 -217.316304) (xy 205.992984 -217.309954) (xy 206.005176 -217.290142)
			(xy 206.014828 -217.186002) (xy 206.006446 -217.164158) (xy 205.997556 -217.15603) (xy 205.979262 -217.138482)
			(xy 205.947114 -217.099287) (xy 205.920636 -217.05606) (xy 205.900326 -217.009614) (xy 205.886566 -216.960825)
			(xy 205.879617 -216.910612) (xy 205.879192 -216.885266) (xy 205.879647 -216.85995) (xy 205.886565 -216.809792)
			(xy 205.90028 -216.761053) (xy 205.920534 -216.714649) (xy 205.946947 -216.671451) (xy 205.979021 -216.632274)
			(xy 205.997302 -216.614756) (xy 206.006192 -216.606374) (xy 206.014574 -216.584784) (xy 206.005176 -216.480644)
			(xy 205.992984 -216.460832) (xy 205.982824 -216.454228) (xy 205.956737 -216.437117) (xy 205.908619 -216.397406)
			(xy 205.865864 -216.351972) (xy 205.829148 -216.301532) (xy 205.799051 -216.246884) (xy 205.77605 -216.18889)
			(xy 205.760507 -216.12847) (xy 205.752668 -216.066576) (xy 205.752192 -216.035382) (xy 205.752682 -216.004173)
			(xy 205.760503 -215.942247) (xy 205.776032 -215.881792) (xy 205.799024 -215.823764) (xy 205.829114 -215.769078)
			(xy 205.865828 -215.7186) (xy 205.908586 -215.673127) (xy 205.95671 -215.633378) (xy 205.982824 -215.616282)
			(xy 205.992984 -215.609932) (xy 206.005176 -215.59012) (xy 206.014828 -215.48598) (xy 206.006446 -215.464136)
			(xy 205.997556 -215.456008) (xy 205.979251 -215.43847) (xy 205.947104 -215.399273) (xy 205.920628 -215.356044)
			(xy 205.90032 -215.309596) (xy 205.886562 -215.260805) (xy 205.879615 -215.210591) (xy 205.879192 -215.185244)
			(xy 205.879632 -215.159927) (xy 205.886553 -215.109769) (xy 205.900271 -215.06103) (xy 205.920528 -215.014625)
			(xy 205.946943 -214.971428) (xy 205.979019 -214.932251) (xy 205.997302 -214.914734) (xy 206.006192 -214.906352)
			(xy 206.014574 -214.884762) (xy 206.005176 -214.780622) (xy 205.992984 -214.76081) (xy 205.982824 -214.754206)
			(xy 205.956727 -214.73711) (xy 205.908609 -214.697397) (xy 205.865854 -214.651961) (xy 205.829139 -214.601518)
			(xy 205.799044 -214.546868) (xy 205.776044 -214.488873) (xy 205.760503 -214.42845) (xy 205.752667 -214.366555)
			(xy 205.752192 -214.33536) (xy 205.752665 -214.304151) (xy 205.760488 -214.242224) (xy 205.77602 -214.181769)
			(xy 205.799014 -214.12374) (xy 205.829107 -214.069054) (xy 205.865823 -214.018576) (xy 205.908583 -213.973104)
			(xy 205.956709 -213.933356) (xy 205.982824 -213.91626) (xy 205.992984 -213.90991) (xy 206.005176 -213.890098)
			(xy 206.014828 -213.785958) (xy 206.006446 -213.764114) (xy 205.997556 -213.755986) (xy 205.97924 -213.738459)
			(xy 205.947095 -213.69926) (xy 205.920619 -213.656028) (xy 205.900313 -213.609578) (xy 205.886558 -213.560786)
			(xy 205.879614 -213.510569) (xy 205.879192 -213.485222) (xy 205.879617 -213.459905) (xy 205.886541 -213.409746)
			(xy 205.900262 -213.361006) (xy 205.920522 -213.314602) (xy 205.946939 -213.271405) (xy 205.979018 -213.232229)
			(xy 205.997302 -213.214712) (xy 206.006192 -213.20633) (xy 206.014574 -213.18474) (xy 206.005176 -213.0806)
			(xy 205.992984 -213.060788) (xy 205.982824 -213.054184) (xy 205.956717 -213.037102) (xy 205.908599 -212.997388)
			(xy 205.865845 -212.951949) (xy 205.82913 -212.901505) (xy 205.799036 -212.846852) (xy 205.776038 -212.788855)
			(xy 205.760499 -212.72843) (xy 205.752665 -212.666533) (xy 205.752192 -212.635338) (xy 205.752681 -212.604175)
			(xy 205.760493 -212.542341) (xy 205.775993 -212.481973) (xy 205.798936 -212.424025) (xy 205.828962 -212.369408)
			(xy 205.865596 -212.318986) (xy 205.908261 -212.273552) (xy 205.956283 -212.233824) (xy 206.008907 -212.200429)
			(xy 206.065301 -212.173892) (xy 206.124576 -212.154632) (xy 206.185797 -212.142953) (xy 206.248 -212.13904)
			(xy 206.310203 -212.142953) (xy 206.371424 -212.154632) (xy 206.430699 -212.173892) (xy 206.487093 -212.200429)
			(xy 206.539717 -212.233824) (xy 206.587739 -212.273552) (xy 206.630404 -212.318986) (xy 206.667038 -212.369408)
			(xy 206.697064 -212.424025) (xy 206.720007 -212.481973) (xy 206.735507 -212.542341) (xy 206.743319 -212.604175)
			(xy 206.743808 -212.635338) (xy 206.743319 -212.666535) (xy 206.735505 -212.728436) (xy 206.719979 -212.788866)
			(xy 206.696988 -212.846868) (xy 206.666896 -212.901525) (xy 206.630179 -212.95197) (xy 206.587418 -212.997405)
			(xy 206.53929 -213.037111) (xy 206.513176 -213.054184) (xy 206.503016 -213.060788) (xy 206.490824 -213.0806)
			(xy 206.481426 -213.18474) (xy 206.489808 -213.20633) (xy 206.498698 -213.214712) (xy 206.516988 -213.232223)
			(xy 206.549067 -213.2714) (xy 206.575486 -213.314598) (xy 206.595746 -213.361003) (xy 206.609467 -213.409744)
			(xy 206.616391 -213.459904) (xy 206.616808 -213.485222) (xy 206.616389 -213.51057) (xy 206.609454 -213.56079)
			(xy 206.595703 -213.609586) (xy 206.575398 -213.656038) (xy 206.548919 -213.699269) (xy 206.516767 -213.738466)
			(xy 206.498444 -213.755986) (xy 206.489554 -213.764114) (xy 206.481172 -213.785958) (xy 206.490824 -213.890098)
			(xy 206.503016 -213.90991) (xy 206.513176 -213.91626) (xy 206.539271 -213.933384) (xy 206.587394 -213.973132)
			(xy 206.630151 -214.018602) (xy 206.666867 -214.069076) (xy 206.696963 -214.123756) (xy 206.719961 -214.18178)
			(xy 206.735501 -214.24223) (xy 206.743334 -214.304152) (xy 206.743808 -214.33536) (xy 206.743336 -214.366557)
			(xy 206.735519 -214.428459) (xy 206.719991 -214.48889) (xy 206.696998 -214.546892) (xy 206.666903 -214.601548)
			(xy 206.630184 -214.651993) (xy 206.587421 -214.697428) (xy 206.539291 -214.737133) (xy 206.513176 -214.754206)
			(xy 206.503016 -214.76081) (xy 206.490824 -214.780622) (xy 206.481426 -214.884762) (xy 206.489808 -214.906352)
			(xy 206.498698 -214.914734) (xy 206.51695 -214.932283) (xy 206.549033 -214.971452) (xy 206.575456 -215.014642)
			(xy 206.595723 -215.06104) (xy 206.609452 -215.109774) (xy 206.616386 -215.159928) (xy 206.616808 -215.185244)
			(xy 206.616403 -215.210593) (xy 206.609465 -215.260813) (xy 206.595712 -215.309609) (xy 206.575404 -215.356061)
			(xy 206.548923 -215.399292) (xy 206.516768 -215.438488) (xy 206.498444 -215.456008) (xy 206.489554 -215.464136)
			(xy 206.481172 -215.48598) (xy 206.490824 -215.59012) (xy 206.503016 -215.609932) (xy 206.513176 -215.616282)
			(xy 206.539281 -215.633392) (xy 206.587404 -215.673141) (xy 206.630161 -215.718613) (xy 206.666876 -215.769089)
			(xy 206.69697 -215.823772) (xy 206.719967 -215.881798) (xy 206.735504 -215.94225) (xy 206.743336 -216.004174)
			(xy 206.743808 -216.035382) (xy 206.743354 -216.06658) (xy 206.735534 -216.128482) (xy 206.720003 -216.188913)
			(xy 206.697007 -216.246916) (xy 206.66691 -216.301572) (xy 206.630188 -216.352017) (xy 206.587423 -216.397451)
			(xy 206.539292 -216.437155) (xy 206.513176 -216.454228) (xy 206.503016 -216.460832) (xy 206.490824 -216.480644)
			(xy 206.481426 -216.584784) (xy 206.489808 -216.606374) (xy 206.498698 -216.614756) (xy 206.516961 -216.632294)
			(xy 206.549043 -216.671466) (xy 206.575464 -216.714657) (xy 206.595729 -216.761058) (xy 206.609456 -216.809794)
			(xy 206.616387 -216.85995) (xy 206.616808 -216.885266) (xy 206.616418 -216.910615) (xy 206.609477 -216.960836)
			(xy 206.595721 -217.009632) (xy 206.57541 -217.056084) (xy 206.548926 -217.099315) (xy 206.51677 -217.138511)
			(xy 206.498444 -217.15603) (xy 206.489554 -217.164158) (xy 206.481172 -217.186002) (xy 206.490824 -217.290142)
			(xy 206.503016 -217.309954) (xy 206.513176 -217.316304) (xy 206.539291 -217.333399) (xy 206.587414 -217.373151)
			(xy 206.63017 -217.418625) (xy 206.666885 -217.469103) (xy 206.696978 -217.523788) (xy 206.719973 -217.581816)
			(xy 206.735508 -217.64227) (xy 206.743337 -217.704195) (xy 206.743808 -217.735404) (xy 206.743319 -217.766567)
			(xy 206.735507 -217.828401) (xy 206.720007 -217.888769) (xy 206.697064 -217.946717) (xy 206.667038 -218.001334)
			(xy 206.630404 -218.051756) (xy 206.587739 -218.09719) (xy 206.539717 -218.136918) (xy 206.487093 -218.170313)
			(xy 206.430699 -218.19685) (xy 206.371424 -218.21611) (xy 206.310203 -218.227789) (xy 206.248 -218.231702)
			(xy 206.185797 -218.227789) (xy 206.124576 -218.21611) (xy 206.065301 -218.19685) (xy 206.008907 -218.170313)
			(xy 205.956283 -218.136918) (xy 205.908261 -218.09719) (xy 205.865596 -218.051756) (xy 205.828962 -218.001334)
			(xy 205.798936 -217.946717) (xy 205.775993 -217.888769) (xy 205.760493 -217.828401) (xy 205.752681 -217.766567)
			(xy 205.752192 -217.735404) (xy 202.51674 -217.735404) (xy 202.516354 -217.760723) (xy 202.509425 -217.810884)
			(xy 202.495698 -217.859625) (xy 202.475431 -217.90603) (xy 202.449005 -217.949226) (xy 202.416918 -217.988399)
			(xy 202.39863 -218.005914) (xy 202.38974 -218.014296) (xy 202.381358 -218.035886) (xy 202.390756 -218.140026)
			(xy 202.402948 -218.159838) (xy 202.413108 -218.166442) (xy 202.439234 -218.183495) (xy 202.487351 -218.223215)
			(xy 202.530103 -218.268659) (xy 202.566815 -218.319107) (xy 202.596907 -218.373764) (xy 202.619902 -218.431765)
			(xy 202.635438 -218.492192) (xy 202.643268 -218.554092) (xy 202.64374 -218.585288) (xy 204.494399 -218.585288)
			(xy 204.498334 -218.531517) (xy 204.510057 -218.478893) (xy 204.529317 -218.428536) (xy 204.555703 -218.381519)
			(xy 204.588655 -218.338846) (xy 204.627468 -218.301425) (xy 204.671316 -218.270055) (xy 204.719264 -218.245403)
			(xy 204.770291 -218.227995) (xy 204.823309 -218.218202) (xy 204.877188 -218.216233) (xy 204.930779 -218.22213)
			(xy 204.98294 -218.235766) (xy 205.03256 -218.256853) (xy 205.078581 -218.284939) (xy 205.120023 -218.319427)
			(xy 205.156001 -218.359581) (xy 205.185749 -218.404545) (xy 205.208634 -218.453362) (xy 205.224166 -218.504991)
			(xy 205.232016 -218.558331) (xy 205.232508 -218.585288) (xy 205.232016 -218.612245) (xy 205.224166 -218.665585)
			(xy 205.208634 -218.717214) (xy 205.185749 -218.766031) (xy 205.156001 -218.810995) (xy 205.120023 -218.851149)
			(xy 205.078581 -218.885637) (xy 205.03256 -218.913723) (xy 204.98294 -218.93481) (xy 204.930779 -218.948446)
			(xy 204.877188 -218.954343) (xy 204.823309 -218.952374) (xy 204.770291 -218.942581) (xy 204.719264 -218.925173)
			(xy 204.671316 -218.900521) (xy 204.627468 -218.869151) (xy 204.588655 -218.83173) (xy 204.555703 -218.789057)
			(xy 204.529317 -218.74204) (xy 204.510057 -218.691683) (xy 204.498334 -218.639059) (xy 204.494399 -218.585288)
			(xy 202.64374 -218.585288) (xy 202.643251 -218.616451) (xy 202.635439 -218.678285) (xy 202.619939 -218.738653)
			(xy 202.596996 -218.796601) (xy 202.56697 -218.851218) (xy 202.530336 -218.90164) (xy 202.487671 -218.947074)
			(xy 202.439649 -218.986802) (xy 202.387025 -219.020197) (xy 202.330631 -219.046734) (xy 202.271356 -219.065994)
			(xy 202.210135 -219.077673) (xy 202.147932 -219.081586) (xy 202.085729 -219.077673) (xy 202.024508 -219.065994)
			(xy 201.965233 -219.046734) (xy 201.908839 -219.020197) (xy 201.856215 -218.986802) (xy 201.808193 -218.947074)
			(xy 201.765528 -218.90164) (xy 201.728894 -218.851218) (xy 201.698868 -218.796601) (xy 201.675925 -218.738653)
			(xy 201.660425 -218.678285) (xy 201.652613 -218.616451) (xy 201.652124 -218.585288) (xy 197.688708 -218.585288)
			(xy 197.688216 -218.612245) (xy 197.680366 -218.665585) (xy 197.664834 -218.717214) (xy 197.641949 -218.766031)
			(xy 197.612201 -218.810995) (xy 197.576223 -218.851149) (xy 197.534781 -218.885637) (xy 197.48876 -218.913723)
			(xy 197.43914 -218.93481) (xy 197.386979 -218.948446) (xy 197.333388 -218.954343) (xy 197.279509 -218.952374)
			(xy 197.226491 -218.942581) (xy 197.175464 -218.925173) (xy 197.127516 -218.900521) (xy 197.083668 -218.869151)
			(xy 197.044855 -218.83173) (xy 197.011903 -218.789057) (xy 196.985517 -218.74204) (xy 196.966257 -218.691683)
			(xy 196.954534 -218.639059) (xy 196.950599 -218.585288) (xy 195.09994 -218.585288) (xy 195.099451 -218.616451)
			(xy 195.091639 -218.678285) (xy 195.076139 -218.738653) (xy 195.053196 -218.796601) (xy 195.02317 -218.851218)
			(xy 194.986536 -218.90164) (xy 194.943871 -218.947074) (xy 194.895849 -218.986802) (xy 194.843225 -219.020197)
			(xy 194.786831 -219.046734) (xy 194.727556 -219.065994) (xy 194.666335 -219.077673) (xy 194.604132 -219.081586)
			(xy 194.541929 -219.077673) (xy 194.480708 -219.065994) (xy 194.421433 -219.046734) (xy 194.365039 -219.020197)
			(xy 194.312415 -218.986802) (xy 194.264393 -218.947074) (xy 194.221728 -218.90164) (xy 194.185094 -218.851218)
			(xy 194.155068 -218.796601) (xy 194.132125 -218.738653) (xy 194.116625 -218.678285) (xy 194.108813 -218.616451)
			(xy 194.108324 -218.585288) (xy 190.144654 -218.585288) (xy 190.144162 -218.612245) (xy 190.136312 -218.665585)
			(xy 190.12078 -218.717214) (xy 190.097895 -218.766031) (xy 190.068147 -218.810995) (xy 190.032169 -218.851149)
			(xy 189.990727 -218.885637) (xy 189.944706 -218.913723) (xy 189.895086 -218.93481) (xy 189.842925 -218.948446)
			(xy 189.789334 -218.954343) (xy 189.735455 -218.952374) (xy 189.682437 -218.942581) (xy 189.63141 -218.925173)
			(xy 189.583462 -218.900521) (xy 189.539614 -218.869151) (xy 189.500801 -218.83173) (xy 189.467849 -218.789057)
			(xy 189.441463 -218.74204) (xy 189.422203 -218.691683) (xy 189.41048 -218.639059) (xy 189.406545 -218.585288)
			(xy 187.555886 -218.585288) (xy 187.555397 -218.616451) (xy 187.547585 -218.678285) (xy 187.532085 -218.738653)
			(xy 187.509142 -218.796601) (xy 187.479116 -218.851218) (xy 187.442482 -218.90164) (xy 187.399817 -218.947074)
			(xy 187.351795 -218.986802) (xy 187.299171 -219.020197) (xy 187.242777 -219.046734) (xy 187.183502 -219.065994)
			(xy 187.122281 -219.077673) (xy 187.060078 -219.081586) (xy 186.997875 -219.077673) (xy 186.936654 -219.065994)
			(xy 186.877379 -219.046734) (xy 186.820985 -219.020197) (xy 186.768361 -218.986802) (xy 186.720339 -218.947074)
			(xy 186.677674 -218.90164) (xy 186.64104 -218.851218) (xy 186.611014 -218.796601) (xy 186.588071 -218.738653)
			(xy 186.572571 -218.678285) (xy 186.564759 -218.616451) (xy 186.56427 -218.585288) (xy 182.6006 -218.585288)
			(xy 182.600108 -218.612245) (xy 182.592258 -218.665585) (xy 182.576726 -218.717214) (xy 182.553841 -218.766031)
			(xy 182.524093 -218.810995) (xy 182.488115 -218.851149) (xy 182.446673 -218.885637) (xy 182.400652 -218.913723)
			(xy 182.351032 -218.93481) (xy 182.298871 -218.948446) (xy 182.24528 -218.954343) (xy 182.191401 -218.952374)
			(xy 182.138383 -218.942581) (xy 182.087356 -218.925173) (xy 182.039408 -218.900521) (xy 181.99556 -218.869151)
			(xy 181.956747 -218.83173) (xy 181.923795 -218.789057) (xy 181.897409 -218.74204) (xy 181.878149 -218.691683)
			(xy 181.866426 -218.639059) (xy 181.862491 -218.585288) (xy 180.011832 -218.585288) (xy 180.011343 -218.616451)
			(xy 180.003531 -218.678285) (xy 179.988031 -218.738653) (xy 179.965088 -218.796601) (xy 179.935062 -218.851218)
			(xy 179.898428 -218.90164) (xy 179.855763 -218.947074) (xy 179.807741 -218.986802) (xy 179.755117 -219.020197)
			(xy 179.698723 -219.046734) (xy 179.639448 -219.065994) (xy 179.578227 -219.077673) (xy 179.516024 -219.081586)
			(xy 179.453821 -219.077673) (xy 179.3926 -219.065994) (xy 179.333325 -219.046734) (xy 179.276931 -219.020197)
			(xy 179.224307 -218.986802) (xy 179.176285 -218.947074) (xy 179.13362 -218.90164) (xy 179.096986 -218.851218)
			(xy 179.06696 -218.796601) (xy 179.044017 -218.738653) (xy 179.028517 -218.678285) (xy 179.020705 -218.616451)
			(xy 179.020216 -218.585288) (xy 175.056546 -218.585288) (xy 175.056054 -218.612245) (xy 175.048204 -218.665585)
			(xy 175.032672 -218.717214) (xy 175.009787 -218.766031) (xy 174.980039 -218.810995) (xy 174.944061 -218.851149)
			(xy 174.902619 -218.885637) (xy 174.856598 -218.913723) (xy 174.806978 -218.93481) (xy 174.754817 -218.948446)
			(xy 174.701226 -218.954343) (xy 174.647347 -218.952374) (xy 174.594329 -218.942581) (xy 174.543302 -218.925173)
			(xy 174.495354 -218.900521) (xy 174.451506 -218.869151) (xy 174.412693 -218.83173) (xy 174.379741 -218.789057)
			(xy 174.353355 -218.74204) (xy 174.334095 -218.691683) (xy 174.322372 -218.639059) (xy 174.318437 -218.585288)
			(xy 172.467778 -218.585288) (xy 172.467289 -218.616451) (xy 172.459477 -218.678285) (xy 172.443977 -218.738653)
			(xy 172.421034 -218.796601) (xy 172.391008 -218.851218) (xy 172.354374 -218.90164) (xy 172.311709 -218.947074)
			(xy 172.263687 -218.986802) (xy 172.211063 -219.020197) (xy 172.154669 -219.046734) (xy 172.095394 -219.065994)
			(xy 172.034173 -219.077673) (xy 171.97197 -219.081586) (xy 171.909767 -219.077673) (xy 171.848546 -219.065994)
			(xy 171.789271 -219.046734) (xy 171.732877 -219.020197) (xy 171.680253 -218.986802) (xy 171.632231 -218.947074)
			(xy 171.589566 -218.90164) (xy 171.552932 -218.851218) (xy 171.522906 -218.796601) (xy 171.499963 -218.738653)
			(xy 171.484463 -218.678285) (xy 171.476651 -218.616451) (xy 171.476162 -218.585288) (xy 167.512492 -218.585288)
			(xy 167.512 -218.612245) (xy 167.50415 -218.665585) (xy 167.488618 -218.717214) (xy 167.465733 -218.766031)
			(xy 167.435985 -218.810995) (xy 167.400007 -218.851149) (xy 167.358565 -218.885637) (xy 167.312544 -218.913723)
			(xy 167.262924 -218.93481) (xy 167.210763 -218.948446) (xy 167.157172 -218.954343) (xy 167.103293 -218.952374)
			(xy 167.050275 -218.942581) (xy 166.999248 -218.925173) (xy 166.9513 -218.900521) (xy 166.907452 -218.869151)
			(xy 166.868639 -218.83173) (xy 166.835687 -218.789057) (xy 166.809301 -218.74204) (xy 166.790041 -218.691683)
			(xy 166.778318 -218.639059) (xy 166.774383 -218.585288) (xy 161.612834 -218.585288) (xy 161.612834 -219.435426)
			(xy 165.442915 -219.435426) (xy 165.44685 -219.381655) (xy 165.458573 -219.329031) (xy 165.477833 -219.278674)
			(xy 165.504219 -219.231657) (xy 165.537171 -219.188984) (xy 165.575984 -219.151563) (xy 165.619832 -219.120193)
			(xy 165.66778 -219.095541) (xy 165.718807 -219.078133) (xy 165.771825 -219.06834) (xy 165.825704 -219.066371)
			(xy 165.879295 -219.072268) (xy 165.931456 -219.085904) (xy 165.981076 -219.106991) (xy 166.027097 -219.135077)
			(xy 166.068539 -219.169565) (xy 166.104517 -219.209719) (xy 166.134265 -219.254683) (xy 166.15715 -219.3035)
			(xy 166.172682 -219.355129) (xy 166.180532 -219.408469) (xy 166.181024 -219.435426) (xy 172.986969 -219.435426)
			(xy 172.990904 -219.381655) (xy 173.002627 -219.329031) (xy 173.021887 -219.278674) (xy 173.048273 -219.231657)
			(xy 173.081225 -219.188984) (xy 173.120038 -219.151563) (xy 173.163886 -219.120193) (xy 173.211834 -219.095541)
			(xy 173.262861 -219.078133) (xy 173.315879 -219.06834) (xy 173.369758 -219.066371) (xy 173.423349 -219.072268)
			(xy 173.47551 -219.085904) (xy 173.52513 -219.106991) (xy 173.571151 -219.135077) (xy 173.612593 -219.169565)
			(xy 173.648571 -219.209719) (xy 173.678319 -219.254683) (xy 173.701204 -219.3035) (xy 173.716736 -219.355129)
			(xy 173.724586 -219.408469) (xy 173.725078 -219.435426) (xy 173.724586 -219.462383) (xy 173.716736 -219.515723)
			(xy 173.701204 -219.567352) (xy 173.678319 -219.616169) (xy 173.648571 -219.661133) (xy 173.612593 -219.701287)
			(xy 173.571151 -219.735775) (xy 173.52513 -219.763861) (xy 173.47551 -219.784948) (xy 173.423349 -219.798584)
			(xy 173.369758 -219.804481) (xy 173.315879 -219.802512) (xy 173.262861 -219.792719) (xy 173.211834 -219.775311)
			(xy 173.163886 -219.750659) (xy 173.120038 -219.719289) (xy 173.081225 -219.681868) (xy 173.048273 -219.639195)
			(xy 173.021887 -219.592178) (xy 173.002627 -219.541821) (xy 172.990904 -219.489197) (xy 172.986969 -219.435426)
			(xy 166.181024 -219.435426) (xy 166.180532 -219.462383) (xy 166.172682 -219.515723) (xy 166.15715 -219.567352)
			(xy 166.134265 -219.616169) (xy 166.104517 -219.661133) (xy 166.068539 -219.701287) (xy 166.027097 -219.735775)
			(xy 165.981076 -219.763861) (xy 165.931456 -219.784948) (xy 165.879295 -219.798584) (xy 165.825704 -219.804481)
			(xy 165.771825 -219.802512) (xy 165.718807 -219.792719) (xy 165.66778 -219.775311) (xy 165.619832 -219.750659)
			(xy 165.575984 -219.719289) (xy 165.537171 -219.681868) (xy 165.504219 -219.639195) (xy 165.477833 -219.592178)
			(xy 165.458573 -219.541821) (xy 165.44685 -219.489197) (xy 165.442915 -219.435426) (xy 161.612834 -219.435426)
			(xy 161.612834 -219.860368) (xy 169.276283 -219.860368) (xy 169.280218 -219.806597) (xy 169.291941 -219.753973)
			(xy 169.311201 -219.703616) (xy 169.337587 -219.656599) (xy 169.370539 -219.613926) (xy 169.409352 -219.576505)
			(xy 169.4532 -219.545135) (xy 169.501148 -219.520483) (xy 169.552175 -219.503075) (xy 169.605193 -219.493282)
			(xy 169.659072 -219.491313) (xy 169.712663 -219.49721) (xy 169.764824 -219.510846) (xy 169.814444 -219.531933)
			(xy 169.860465 -219.560019) (xy 169.901907 -219.594507) (xy 169.937885 -219.634661) (xy 169.967633 -219.679625)
			(xy 169.990518 -219.728442) (xy 170.00605 -219.780071) (xy 170.0139 -219.833411) (xy 170.014392 -219.860368)
			(xy 170.0139 -219.887325) (xy 170.00605 -219.940665) (xy 169.990518 -219.992294) (xy 169.967633 -220.041111)
			(xy 169.937885 -220.086075) (xy 169.901907 -220.126229) (xy 169.860465 -220.160717) (xy 169.814444 -220.188803)
			(xy 169.764824 -220.20989) (xy 169.712663 -220.223526) (xy 169.659072 -220.229423) (xy 169.605193 -220.227454)
			(xy 169.552175 -220.217661) (xy 169.501148 -220.200253) (xy 169.4532 -220.175601) (xy 169.409352 -220.144231)
			(xy 169.370539 -220.10681) (xy 169.337587 -220.064137) (xy 169.311201 -220.01712) (xy 169.291941 -219.966763)
			(xy 169.280218 -219.914139) (xy 169.276283 -219.860368) (xy 161.612834 -219.860368) (xy 161.612834 -220.710252)
			(xy 165.176215 -220.710252) (xy 165.18015 -220.656481) (xy 165.191873 -220.603857) (xy 165.211133 -220.5535)
			(xy 165.237519 -220.506483) (xy 165.270471 -220.46381) (xy 165.309284 -220.426389) (xy 165.353132 -220.395019)
			(xy 165.40108 -220.370367) (xy 165.452107 -220.352959) (xy 165.505125 -220.343166) (xy 165.559004 -220.341197)
			(xy 165.612595 -220.347094) (xy 165.664756 -220.36073) (xy 165.714376 -220.381817) (xy 165.760397 -220.409903)
			(xy 165.801839 -220.444391) (xy 165.837817 -220.484545) (xy 165.867565 -220.529509) (xy 165.89045 -220.578326)
			(xy 165.905982 -220.629955) (xy 165.913832 -220.683295) (xy 165.914324 -220.710252) (xy 165.913832 -220.737209)
			(xy 165.905982 -220.790549) (xy 165.89045 -220.842178) (xy 165.867565 -220.890995) (xy 165.837817 -220.935959)
			(xy 165.801839 -220.976113) (xy 165.760397 -221.010601) (xy 165.714376 -221.038687) (xy 165.664756 -221.059774)
			(xy 165.612595 -221.07341) (xy 165.559004 -221.079307) (xy 165.505125 -221.077338) (xy 165.452107 -221.067545)
			(xy 165.40108 -221.050137) (xy 165.353132 -221.025485) (xy 165.309284 -220.994115) (xy 165.270471 -220.956694)
			(xy 165.237519 -220.914021) (xy 165.211133 -220.867004) (xy 165.191873 -220.816647) (xy 165.18015 -220.764023)
			(xy 165.176215 -220.710252) (xy 161.612834 -220.710252) (xy 161.612834 -221.135194) (xy 166.774383 -221.135194)
			(xy 166.778318 -221.081423) (xy 166.790041 -221.028799) (xy 166.809301 -220.978442) (xy 166.835687 -220.931425)
			(xy 166.868639 -220.888752) (xy 166.907452 -220.851331) (xy 166.9513 -220.819961) (xy 166.999248 -220.795309)
			(xy 167.050275 -220.777901) (xy 167.103293 -220.768108) (xy 167.157172 -220.766139) (xy 167.210763 -220.772036)
			(xy 167.262924 -220.785672) (xy 167.312544 -220.806759) (xy 167.358565 -220.834845) (xy 167.400007 -220.869333)
			(xy 167.435985 -220.909487) (xy 167.465733 -220.954451) (xy 167.488618 -221.003268) (xy 167.50415 -221.054897)
			(xy 167.512 -221.108237) (xy 167.512492 -221.135194) (xy 171.476162 -221.135194) (xy 171.476721 -221.102495)
			(xy 171.485324 -221.037664) (xy 171.502378 -220.974528) (xy 171.527588 -220.914184) (xy 171.560516 -220.857679)
			(xy 171.600589 -220.805997) (xy 171.623482 -220.782642) (xy 171.630848 -220.775276) (xy 171.638468 -220.756734)
			(xy 171.638468 -220.66377) (xy 171.630848 -220.645228) (xy 171.623482 -220.637862) (xy 171.600601 -220.614494)
			(xy 171.560514 -220.562819) (xy 171.527574 -220.50632) (xy 171.502355 -220.445978) (xy 171.485293 -220.382842)
			(xy 171.476687 -220.31801) (xy 171.476162 -220.28531) (xy 171.476651 -220.254147) (xy 171.484463 -220.192313)
			(xy 171.499963 -220.131945) (xy 171.522906 -220.073997) (xy 171.552932 -220.01938) (xy 171.589566 -219.968958)
			(xy 171.632231 -219.923524) (xy 171.680253 -219.883796) (xy 171.732877 -219.850401) (xy 171.789271 -219.823864)
			(xy 171.848546 -219.804604) (xy 171.909767 -219.792925) (xy 171.97197 -219.789012) (xy 172.034173 -219.792925)
			(xy 172.095394 -219.804604) (xy 172.154669 -219.823864) (xy 172.211063 -219.850401) (xy 172.263687 -219.883796)
			(xy 172.311709 -219.923524) (xy 172.354374 -219.968958) (xy 172.391008 -220.01938) (xy 172.421034 -220.073997)
			(xy 172.443977 -220.131945) (xy 172.459477 -220.192313) (xy 172.467289 -220.254147) (xy 172.467778 -220.28531)
			(xy 175.57623 -220.28531) (xy 175.576745 -220.252609) (xy 175.585357 -220.187777) (xy 175.602421 -220.124641)
			(xy 175.627639 -220.064297) (xy 175.660574 -220.007793) (xy 175.700654 -219.956112) (xy 175.72355 -219.932758)
			(xy 175.730916 -219.925392) (xy 175.738536 -219.90685) (xy 175.738536 -219.813886) (xy 175.730916 -219.795344)
			(xy 175.72355 -219.787978) (xy 175.700671 -219.764608) (xy 175.660585 -219.712933) (xy 175.627646 -219.656434)
			(xy 175.602426 -219.596092) (xy 175.585364 -219.532957) (xy 175.576756 -219.468126) (xy 175.57623 -219.435426)
			(xy 175.576719 -219.404263) (xy 175.584531 -219.342429) (xy 175.600031 -219.282061) (xy 175.622974 -219.224113)
			(xy 175.653 -219.169496) (xy 175.689634 -219.119074) (xy 175.732299 -219.07364) (xy 175.780321 -219.033912)
			(xy 175.832945 -219.000517) (xy 175.889339 -218.97398) (xy 175.948614 -218.95472) (xy 176.009835 -218.943041)
			(xy 176.072038 -218.939128) (xy 176.134241 -218.943041) (xy 176.195462 -218.95472) (xy 176.254737 -218.97398)
			(xy 176.311131 -219.000517) (xy 176.363755 -219.033912) (xy 176.411777 -219.07364) (xy 176.454442 -219.119074)
			(xy 176.491076 -219.169496) (xy 176.521102 -219.224113) (xy 176.544045 -219.282061) (xy 176.559545 -219.342429)
			(xy 176.567357 -219.404263) (xy 176.567846 -219.435426) (xy 180.531023 -219.435426) (xy 180.534958 -219.381655)
			(xy 180.546681 -219.329031) (xy 180.565941 -219.278674) (xy 180.592327 -219.231657) (xy 180.625279 -219.188984)
			(xy 180.664092 -219.151563) (xy 180.70794 -219.120193) (xy 180.755888 -219.095541) (xy 180.806915 -219.078133)
			(xy 180.859933 -219.06834) (xy 180.913812 -219.066371) (xy 180.967403 -219.072268) (xy 181.019564 -219.085904)
			(xy 181.069184 -219.106991) (xy 181.115205 -219.135077) (xy 181.156647 -219.169565) (xy 181.192625 -219.209719)
			(xy 181.222373 -219.254683) (xy 181.245258 -219.3035) (xy 181.26079 -219.355129) (xy 181.26864 -219.408469)
			(xy 181.269132 -219.435426) (xy 181.26864 -219.462383) (xy 181.26079 -219.515723) (xy 181.245258 -219.567352)
			(xy 181.222373 -219.616169) (xy 181.192625 -219.661133) (xy 181.156647 -219.701287) (xy 181.115205 -219.735775)
			(xy 181.069184 -219.763861) (xy 181.019564 -219.784948) (xy 180.967403 -219.798584) (xy 180.913812 -219.804481)
			(xy 180.859933 -219.802512) (xy 180.806915 -219.792719) (xy 180.755888 -219.775311) (xy 180.70794 -219.750659)
			(xy 180.664092 -219.719289) (xy 180.625279 -219.681868) (xy 180.592327 -219.639195) (xy 180.565941 -219.592178)
			(xy 180.546681 -219.541821) (xy 180.534958 -219.489197) (xy 180.531023 -219.435426) (xy 176.567846 -219.435426)
			(xy 176.567297 -219.468126) (xy 176.558692 -219.532957) (xy 176.541636 -219.596093) (xy 176.516424 -219.656437)
			(xy 176.483494 -219.712941) (xy 176.44342 -219.764624) (xy 176.420526 -219.787978) (xy 176.41316 -219.795344)
			(xy 176.40554 -219.813886) (xy 176.40554 -219.860368) (xy 176.820337 -219.860368) (xy 176.824272 -219.806597)
			(xy 176.835995 -219.753973) (xy 176.855255 -219.703616) (xy 176.881641 -219.656599) (xy 176.914593 -219.613926)
			(xy 176.953406 -219.576505) (xy 176.997254 -219.545135) (xy 177.045202 -219.520483) (xy 177.096229 -219.503075)
			(xy 177.149247 -219.493282) (xy 177.203126 -219.491313) (xy 177.256717 -219.49721) (xy 177.308878 -219.510846)
			(xy 177.358498 -219.531933) (xy 177.404519 -219.560019) (xy 177.445961 -219.594507) (xy 177.481939 -219.634661)
			(xy 177.511687 -219.679625) (xy 177.534572 -219.728442) (xy 177.550104 -219.780071) (xy 177.557954 -219.833411)
			(xy 177.558446 -219.860368) (xy 177.557954 -219.887325) (xy 177.550104 -219.940665) (xy 177.534572 -219.992294)
			(xy 177.511687 -220.041111) (xy 177.481939 -220.086075) (xy 177.445961 -220.126229) (xy 177.404519 -220.160717)
			(xy 177.358498 -220.188803) (xy 177.308878 -220.20989) (xy 177.256717 -220.223526) (xy 177.203126 -220.229423)
			(xy 177.149247 -220.227454) (xy 177.096229 -220.217661) (xy 177.045202 -220.200253) (xy 176.997254 -220.175601)
			(xy 176.953406 -220.144231) (xy 176.914593 -220.10681) (xy 176.881641 -220.064137) (xy 176.855255 -220.01712)
			(xy 176.835995 -219.966763) (xy 176.824272 -219.914139) (xy 176.820337 -219.860368) (xy 176.40554 -219.860368)
			(xy 176.40554 -219.90685) (xy 176.41316 -219.925392) (xy 176.420526 -219.932758) (xy 176.443418 -219.956116)
			(xy 176.483504 -220.007793) (xy 176.516442 -220.064294) (xy 176.541659 -220.124639) (xy 176.558718 -220.187776)
			(xy 176.567322 -220.252609) (xy 176.567846 -220.28531) (xy 176.567357 -220.316473) (xy 176.559545 -220.378307)
			(xy 176.544045 -220.438675) (xy 176.521102 -220.496623) (xy 176.491076 -220.55124) (xy 176.454442 -220.601662)
			(xy 176.411777 -220.647096) (xy 176.363755 -220.686824) (xy 176.311131 -220.720219) (xy 176.254737 -220.746756)
			(xy 176.195462 -220.766016) (xy 176.134241 -220.777695) (xy 176.072038 -220.781608) (xy 176.009835 -220.777695)
			(xy 175.948614 -220.766016) (xy 175.889339 -220.746756) (xy 175.832945 -220.720219) (xy 175.780321 -220.686824)
			(xy 175.732299 -220.647096) (xy 175.689634 -220.601662) (xy 175.653 -220.55124) (xy 175.622974 -220.496623)
			(xy 175.600031 -220.438675) (xy 175.584531 -220.378307) (xy 175.576719 -220.316473) (xy 175.57623 -220.28531)
			(xy 172.467778 -220.28531) (xy 172.467209 -220.318009) (xy 172.458607 -220.382839) (xy 172.441554 -220.445974)
			(xy 172.416346 -220.506318) (xy 172.38342 -220.562823) (xy 172.34335 -220.614507) (xy 172.320458 -220.637862)
			(xy 172.313092 -220.645228) (xy 172.305472 -220.66377) (xy 172.305472 -220.710252) (xy 172.720269 -220.710252)
			(xy 172.724204 -220.656481) (xy 172.735927 -220.603857) (xy 172.755187 -220.5535) (xy 172.781573 -220.506483)
			(xy 172.814525 -220.46381) (xy 172.853338 -220.426389) (xy 172.897186 -220.395019) (xy 172.945134 -220.370367)
			(xy 172.996161 -220.352959) (xy 173.049179 -220.343166) (xy 173.103058 -220.341197) (xy 173.156649 -220.347094)
			(xy 173.20881 -220.36073) (xy 173.25843 -220.381817) (xy 173.304451 -220.409903) (xy 173.345893 -220.444391)
			(xy 173.381871 -220.484545) (xy 173.411619 -220.529509) (xy 173.434504 -220.578326) (xy 173.450036 -220.629955)
			(xy 173.457886 -220.683295) (xy 173.458378 -220.710252) (xy 173.457886 -220.737209) (xy 173.450036 -220.790549)
			(xy 173.434504 -220.842178) (xy 173.411619 -220.890995) (xy 173.381871 -220.935959) (xy 173.345893 -220.976113)
			(xy 173.304451 -221.010601) (xy 173.25843 -221.038687) (xy 173.20881 -221.059774) (xy 173.156649 -221.07341)
			(xy 173.103058 -221.079307) (xy 173.049179 -221.077338) (xy 172.996161 -221.067545) (xy 172.945134 -221.050137)
			(xy 172.897186 -221.025485) (xy 172.853338 -220.994115) (xy 172.814525 -220.956694) (xy 172.781573 -220.914021)
			(xy 172.755187 -220.867004) (xy 172.735927 -220.816647) (xy 172.724204 -220.764023) (xy 172.720269 -220.710252)
			(xy 172.305472 -220.710252) (xy 172.305472 -220.756734) (xy 172.313092 -220.775276) (xy 172.320458 -220.782642)
			(xy 172.343348 -220.806001) (xy 172.383433 -220.857679) (xy 172.41637 -220.91418) (xy 172.441588 -220.974524)
			(xy 172.458648 -221.037661) (xy 172.467253 -221.102493) (xy 172.467778 -221.135194) (xy 174.318437 -221.135194)
			(xy 174.322372 -221.081423) (xy 174.334095 -221.028799) (xy 174.353355 -220.978442) (xy 174.379741 -220.931425)
			(xy 174.412693 -220.888752) (xy 174.451506 -220.851331) (xy 174.495354 -220.819961) (xy 174.543302 -220.795309)
			(xy 174.594329 -220.777901) (xy 174.647347 -220.768108) (xy 174.701226 -220.766139) (xy 174.754817 -220.772036)
			(xy 174.806978 -220.785672) (xy 174.856598 -220.806759) (xy 174.902619 -220.834845) (xy 174.944061 -220.869333)
			(xy 174.980039 -220.909487) (xy 175.009787 -220.954451) (xy 175.032672 -221.003268) (xy 175.048204 -221.054897)
			(xy 175.056054 -221.108237) (xy 175.056546 -221.135194) (xy 179.020216 -221.135194) (xy 179.020759 -221.102494)
			(xy 179.029363 -221.037662) (xy 179.046419 -220.974525) (xy 179.071632 -220.914181) (xy 179.104563 -220.857677)
			(xy 179.144641 -220.805995) (xy 179.167536 -220.782642) (xy 179.174902 -220.775276) (xy 179.182522 -220.756734)
			(xy 179.182522 -220.66377) (xy 179.174902 -220.645228) (xy 179.167536 -220.637862) (xy 179.144647 -220.614502)
			(xy 179.104562 -220.562825) (xy 179.071625 -220.506323) (xy 179.046407 -220.44598) (xy 179.029347 -220.382843)
			(xy 179.020741 -220.318011) (xy 179.020216 -220.28531) (xy 179.020705 -220.254147) (xy 179.028517 -220.192313)
			(xy 179.044017 -220.131945) (xy 179.06696 -220.073997) (xy 179.096986 -220.01938) (xy 179.13362 -219.968958)
			(xy 179.176285 -219.923524) (xy 179.224307 -219.883796) (xy 179.276931 -219.850401) (xy 179.333325 -219.823864)
			(xy 179.3926 -219.804604) (xy 179.453821 -219.792925) (xy 179.516024 -219.789012) (xy 179.578227 -219.792925)
			(xy 179.639448 -219.804604) (xy 179.698723 -219.823864) (xy 179.755117 -219.850401) (xy 179.807741 -219.883796)
			(xy 179.855763 -219.923524) (xy 179.898428 -219.968958) (xy 179.935062 -220.01938) (xy 179.965088 -220.073997)
			(xy 179.988031 -220.131945) (xy 180.003531 -220.192313) (xy 180.011343 -220.254147) (xy 180.011832 -220.28531)
			(xy 183.120284 -220.28531) (xy 183.120783 -220.252609) (xy 183.129396 -220.187775) (xy 183.146462 -220.124638)
			(xy 183.171683 -220.064294) (xy 183.204622 -220.007791) (xy 183.244706 -219.956111) (xy 183.267604 -219.932758)
			(xy 183.27497 -219.925392) (xy 183.28259 -219.90685) (xy 183.28259 -219.813886) (xy 183.27497 -219.795344)
			(xy 183.267604 -219.787978) (xy 183.244735 -219.764599) (xy 183.204646 -219.712927) (xy 183.171704 -219.65643)
			(xy 183.146482 -219.59609) (xy 183.129419 -219.532956) (xy 183.12081 -219.468126) (xy 183.120284 -219.435426)
			(xy 183.120773 -219.404263) (xy 183.128585 -219.342429) (xy 183.144085 -219.282061) (xy 183.167028 -219.224113)
			(xy 183.197054 -219.169496) (xy 183.233688 -219.119074) (xy 183.276353 -219.07364) (xy 183.324375 -219.033912)
			(xy 183.376999 -219.000517) (xy 183.433393 -218.97398) (xy 183.492668 -218.95472) (xy 183.553889 -218.943041)
			(xy 183.616092 -218.939128) (xy 183.678295 -218.943041) (xy 183.739516 -218.95472) (xy 183.798791 -218.97398)
			(xy 183.855185 -219.000517) (xy 183.907809 -219.033912) (xy 183.955831 -219.07364) (xy 183.998496 -219.119074)
			(xy 184.03513 -219.169496) (xy 184.065156 -219.224113) (xy 184.088099 -219.282061) (xy 184.103599 -219.342429)
			(xy 184.111411 -219.404263) (xy 184.1119 -219.435426) (xy 188.075077 -219.435426) (xy 188.079012 -219.381655)
			(xy 188.090735 -219.329031) (xy 188.109995 -219.278674) (xy 188.136381 -219.231657) (xy 188.169333 -219.188984)
			(xy 188.208146 -219.151563) (xy 188.251994 -219.120193) (xy 188.299942 -219.095541) (xy 188.350969 -219.078133)
			(xy 188.403987 -219.06834) (xy 188.457866 -219.066371) (xy 188.511457 -219.072268) (xy 188.563618 -219.085904)
			(xy 188.613238 -219.106991) (xy 188.659259 -219.135077) (xy 188.700701 -219.169565) (xy 188.736679 -219.209719)
			(xy 188.766427 -219.254683) (xy 188.789312 -219.3035) (xy 188.804844 -219.355129) (xy 188.812694 -219.408469)
			(xy 188.813186 -219.435426) (xy 188.812694 -219.462383) (xy 188.804844 -219.515723) (xy 188.789312 -219.567352)
			(xy 188.766427 -219.616169) (xy 188.736679 -219.661133) (xy 188.700701 -219.701287) (xy 188.659259 -219.735775)
			(xy 188.613238 -219.763861) (xy 188.563618 -219.784948) (xy 188.511457 -219.798584) (xy 188.457866 -219.804481)
			(xy 188.403987 -219.802512) (xy 188.350969 -219.792719) (xy 188.299942 -219.775311) (xy 188.251994 -219.750659)
			(xy 188.208146 -219.719289) (xy 188.169333 -219.681868) (xy 188.136381 -219.639195) (xy 188.109995 -219.592178)
			(xy 188.090735 -219.541821) (xy 188.079012 -219.489197) (xy 188.075077 -219.435426) (xy 184.1119 -219.435426)
			(xy 184.111365 -219.468126) (xy 184.102759 -219.532958) (xy 184.085701 -219.596095) (xy 184.060486 -219.65644)
			(xy 184.027554 -219.712943) (xy 183.987476 -219.764625) (xy 183.96458 -219.787978) (xy 183.957214 -219.795344)
			(xy 183.949594 -219.813886) (xy 183.949594 -219.860368) (xy 184.364391 -219.860368) (xy 184.368326 -219.806597)
			(xy 184.380049 -219.753973) (xy 184.399309 -219.703616) (xy 184.425695 -219.656599) (xy 184.458647 -219.613926)
			(xy 184.49746 -219.576505) (xy 184.541308 -219.545135) (xy 184.589256 -219.520483) (xy 184.640283 -219.503075)
			(xy 184.693301 -219.493282) (xy 184.74718 -219.491313) (xy 184.800771 -219.49721) (xy 184.852932 -219.510846)
			(xy 184.902552 -219.531933) (xy 184.948573 -219.560019) (xy 184.990015 -219.594507) (xy 185.025993 -219.634661)
			(xy 185.055741 -219.679625) (xy 185.078626 -219.728442) (xy 185.094158 -219.780071) (xy 185.102008 -219.833411)
			(xy 185.1025 -219.860368) (xy 185.102008 -219.887325) (xy 185.094158 -219.940665) (xy 185.078626 -219.992294)
			(xy 185.055741 -220.041111) (xy 185.025993 -220.086075) (xy 184.990015 -220.126229) (xy 184.948573 -220.160717)
			(xy 184.902552 -220.188803) (xy 184.852932 -220.20989) (xy 184.800771 -220.223526) (xy 184.74718 -220.229423)
			(xy 184.693301 -220.227454) (xy 184.640283 -220.217661) (xy 184.589256 -220.200253) (xy 184.541308 -220.175601)
			(xy 184.49746 -220.144231) (xy 184.458647 -220.10681) (xy 184.425695 -220.064137) (xy 184.399309 -220.01712)
			(xy 184.380049 -219.966763) (xy 184.368326 -219.914139) (xy 184.364391 -219.860368) (xy 183.949594 -219.860368)
			(xy 183.949594 -219.90685) (xy 183.957214 -219.925392) (xy 183.96458 -219.932758) (xy 183.987482 -219.956106)
			(xy 184.027564 -220.007786) (xy 184.0605 -220.06429) (xy 184.085716 -220.124636) (xy 184.102773 -220.187775)
			(xy 184.111376 -220.252609) (xy 184.1119 -220.28531) (xy 184.111411 -220.316473) (xy 184.103599 -220.378307)
			(xy 184.088099 -220.438675) (xy 184.065156 -220.496623) (xy 184.03513 -220.55124) (xy 183.998496 -220.601662)
			(xy 183.955831 -220.647096) (xy 183.907809 -220.686824) (xy 183.855185 -220.720219) (xy 183.798791 -220.746756)
			(xy 183.739516 -220.766016) (xy 183.678295 -220.777695) (xy 183.616092 -220.781608) (xy 183.553889 -220.777695)
			(xy 183.492668 -220.766016) (xy 183.433393 -220.746756) (xy 183.376999 -220.720219) (xy 183.324375 -220.686824)
			(xy 183.276353 -220.647096) (xy 183.233688 -220.601662) (xy 183.197054 -220.55124) (xy 183.167028 -220.496623)
			(xy 183.144085 -220.438675) (xy 183.128585 -220.378307) (xy 183.120773 -220.316473) (xy 183.120284 -220.28531)
			(xy 180.011832 -220.28531) (xy 180.011277 -220.31801) (xy 180.002674 -220.38284) (xy 179.985619 -220.445976)
			(xy 179.960408 -220.506321) (xy 179.92748 -220.562825) (xy 179.887405 -220.614508) (xy 179.864512 -220.637862)
			(xy 179.857146 -220.645228) (xy 179.849526 -220.66377) (xy 179.849526 -220.710252) (xy 180.264323 -220.710252)
			(xy 180.268258 -220.656481) (xy 180.279981 -220.603857) (xy 180.299241 -220.5535) (xy 180.325627 -220.506483)
			(xy 180.358579 -220.46381) (xy 180.397392 -220.426389) (xy 180.44124 -220.395019) (xy 180.489188 -220.370367)
			(xy 180.540215 -220.352959) (xy 180.593233 -220.343166) (xy 180.647112 -220.341197) (xy 180.700703 -220.347094)
			(xy 180.752864 -220.36073) (xy 180.802484 -220.381817) (xy 180.848505 -220.409903) (xy 180.889947 -220.444391)
			(xy 180.925925 -220.484545) (xy 180.955673 -220.529509) (xy 180.978558 -220.578326) (xy 180.99409 -220.629955)
			(xy 181.00194 -220.683295) (xy 181.002432 -220.710252) (xy 181.00194 -220.737209) (xy 180.99409 -220.790549)
			(xy 180.978558 -220.842178) (xy 180.955673 -220.890995) (xy 180.925925 -220.935959) (xy 180.889947 -220.976113)
			(xy 180.848505 -221.010601) (xy 180.802484 -221.038687) (xy 180.752864 -221.059774) (xy 180.700703 -221.07341)
			(xy 180.647112 -221.079307) (xy 180.593233 -221.077338) (xy 180.540215 -221.067545) (xy 180.489188 -221.050137)
			(xy 180.44124 -221.025485) (xy 180.397392 -220.994115) (xy 180.358579 -220.956694) (xy 180.325627 -220.914021)
			(xy 180.299241 -220.867004) (xy 180.279981 -220.816647) (xy 180.268258 -220.764023) (xy 180.264323 -220.710252)
			(xy 179.849526 -220.710252) (xy 179.849526 -220.756734) (xy 179.857146 -220.775276) (xy 179.864512 -220.782642)
			(xy 179.887394 -220.80601) (xy 179.927481 -220.857684) (xy 179.960421 -220.914184) (xy 179.98564 -220.974526)
			(xy 180.002701 -221.037662) (xy 180.011307 -221.102494) (xy 180.011832 -221.135194) (xy 181.862491 -221.135194)
			(xy 181.866426 -221.081423) (xy 181.878149 -221.028799) (xy 181.897409 -220.978442) (xy 181.923795 -220.931425)
			(xy 181.956747 -220.888752) (xy 181.99556 -220.851331) (xy 182.039408 -220.819961) (xy 182.087356 -220.795309)
			(xy 182.138383 -220.777901) (xy 182.191401 -220.768108) (xy 182.24528 -220.766139) (xy 182.298871 -220.772036)
			(xy 182.351032 -220.785672) (xy 182.400652 -220.806759) (xy 182.446673 -220.834845) (xy 182.488115 -220.869333)
			(xy 182.524093 -220.909487) (xy 182.553841 -220.954451) (xy 182.576726 -221.003268) (xy 182.592258 -221.054897)
			(xy 182.600108 -221.108237) (xy 182.6006 -221.135194) (xy 186.56427 -221.135194) (xy 186.564827 -221.102495)
			(xy 186.573429 -221.037664) (xy 186.590484 -220.974528) (xy 186.615694 -220.914183) (xy 186.648623 -220.857679)
			(xy 186.688697 -220.805996) (xy 186.71159 -220.782642) (xy 186.718956 -220.775276) (xy 186.726576 -220.756734)
			(xy 186.726576 -220.66377) (xy 186.718956 -220.645228) (xy 186.71159 -220.637862) (xy 186.688711 -220.614492)
			(xy 186.648623 -220.562818) (xy 186.615683 -220.506319) (xy 186.590463 -220.445977) (xy 186.573401 -220.382842)
			(xy 186.564795 -220.31801) (xy 186.56427 -220.28531) (xy 186.564759 -220.254147) (xy 186.572571 -220.192313)
			(xy 186.588071 -220.131945) (xy 186.611014 -220.073997) (xy 186.64104 -220.01938) (xy 186.677674 -219.968958)
			(xy 186.720339 -219.923524) (xy 186.768361 -219.883796) (xy 186.820985 -219.850401) (xy 186.877379 -219.823864)
			(xy 186.936654 -219.804604) (xy 186.997875 -219.792925) (xy 187.060078 -219.789012) (xy 187.122281 -219.792925)
			(xy 187.183502 -219.804604) (xy 187.242777 -219.823864) (xy 187.299171 -219.850401) (xy 187.351795 -219.883796)
			(xy 187.399817 -219.923524) (xy 187.442482 -219.968958) (xy 187.479116 -220.01938) (xy 187.509142 -220.073997)
			(xy 187.532085 -220.131945) (xy 187.547585 -220.192313) (xy 187.555397 -220.254147) (xy 187.555886 -220.28531)
			(xy 190.664338 -220.28531) (xy 190.66485 -220.252609) (xy 190.673463 -220.187777) (xy 190.690527 -220.12464)
			(xy 190.715746 -220.064296) (xy 190.748682 -220.007793) (xy 190.788762 -219.956112) (xy 190.811658 -219.932758)
			(xy 190.819024 -219.925392) (xy 190.826644 -219.90685) (xy 190.826644 -219.813886) (xy 190.819024 -219.795344)
			(xy 190.811658 -219.787978) (xy 190.788781 -219.764607) (xy 190.748694 -219.712932) (xy 190.715754 -219.656433)
			(xy 190.690534 -219.596092) (xy 190.673472 -219.532957) (xy 190.664864 -219.468126) (xy 190.664338 -219.435426)
			(xy 190.664827 -219.404263) (xy 190.672639 -219.342429) (xy 190.688139 -219.282061) (xy 190.711082 -219.224113)
			(xy 190.741108 -219.169496) (xy 190.777742 -219.119074) (xy 190.820407 -219.07364) (xy 190.868429 -219.033912)
			(xy 190.921053 -219.000517) (xy 190.977447 -218.97398) (xy 191.036722 -218.95472) (xy 191.097943 -218.943041)
			(xy 191.160146 -218.939128) (xy 191.222349 -218.943041) (xy 191.28357 -218.95472) (xy 191.342845 -218.97398)
			(xy 191.399239 -219.000517) (xy 191.451863 -219.033912) (xy 191.499885 -219.07364) (xy 191.54255 -219.119074)
			(xy 191.579184 -219.169496) (xy 191.60921 -219.224113) (xy 191.632153 -219.282061) (xy 191.647653 -219.342429)
			(xy 191.655465 -219.404263) (xy 191.655954 -219.435426) (xy 195.619131 -219.435426) (xy 195.623066 -219.381655)
			(xy 195.634789 -219.329031) (xy 195.654049 -219.278674) (xy 195.680435 -219.231657) (xy 195.713387 -219.188984)
			(xy 195.7522 -219.151563) (xy 195.796048 -219.120193) (xy 195.843996 -219.095541) (xy 195.895023 -219.078133)
			(xy 195.948041 -219.06834) (xy 196.00192 -219.066371) (xy 196.055511 -219.072268) (xy 196.107672 -219.085904)
			(xy 196.157292 -219.106991) (xy 196.203313 -219.135077) (xy 196.244755 -219.169565) (xy 196.280733 -219.209719)
			(xy 196.310481 -219.254683) (xy 196.333366 -219.3035) (xy 196.348898 -219.355129) (xy 196.356748 -219.408469)
			(xy 196.35724 -219.435426) (xy 196.356748 -219.462383) (xy 196.348898 -219.515723) (xy 196.333366 -219.567352)
			(xy 196.310481 -219.616169) (xy 196.280733 -219.661133) (xy 196.244755 -219.701287) (xy 196.203313 -219.735775)
			(xy 196.157292 -219.763861) (xy 196.107672 -219.784948) (xy 196.055511 -219.798584) (xy 196.00192 -219.804481)
			(xy 195.948041 -219.802512) (xy 195.895023 -219.792719) (xy 195.843996 -219.775311) (xy 195.796048 -219.750659)
			(xy 195.7522 -219.719289) (xy 195.713387 -219.681868) (xy 195.680435 -219.639195) (xy 195.654049 -219.592178)
			(xy 195.634789 -219.541821) (xy 195.623066 -219.489197) (xy 195.619131 -219.435426) (xy 191.655954 -219.435426)
			(xy 191.655403 -219.468126) (xy 191.646798 -219.532956) (xy 191.629742 -219.596092) (xy 191.60453 -219.656436)
			(xy 191.571602 -219.712941) (xy 191.531527 -219.764623) (xy 191.508634 -219.787978) (xy 191.501268 -219.795344)
			(xy 191.493648 -219.813886) (xy 191.493648 -219.860368) (xy 191.908445 -219.860368) (xy 191.91238 -219.806597)
			(xy 191.924103 -219.753973) (xy 191.943363 -219.703616) (xy 191.969749 -219.656599) (xy 192.002701 -219.613926)
			(xy 192.041514 -219.576505) (xy 192.085362 -219.545135) (xy 192.13331 -219.520483) (xy 192.184337 -219.503075)
			(xy 192.237355 -219.493282) (xy 192.291234 -219.491313) (xy 192.344825 -219.49721) (xy 192.396986 -219.510846)
			(xy 192.446606 -219.531933) (xy 192.492627 -219.560019) (xy 192.534069 -219.594507) (xy 192.570047 -219.634661)
			(xy 192.599795 -219.679625) (xy 192.62268 -219.728442) (xy 192.638212 -219.780071) (xy 192.646062 -219.833411)
			(xy 192.646554 -219.860368) (xy 192.646062 -219.887325) (xy 192.638212 -219.940665) (xy 192.62268 -219.992294)
			(xy 192.599795 -220.041111) (xy 192.570047 -220.086075) (xy 192.534069 -220.126229) (xy 192.492627 -220.160717)
			(xy 192.446606 -220.188803) (xy 192.396986 -220.20989) (xy 192.344825 -220.223526) (xy 192.291234 -220.229423)
			(xy 192.237355 -220.227454) (xy 192.184337 -220.217661) (xy 192.13331 -220.200253) (xy 192.085362 -220.175601)
			(xy 192.041514 -220.144231) (xy 192.002701 -220.10681) (xy 191.969749 -220.064137) (xy 191.943363 -220.01712)
			(xy 191.924103 -219.966763) (xy 191.91238 -219.914139) (xy 191.908445 -219.860368) (xy 191.493648 -219.860368)
			(xy 191.493648 -219.90685) (xy 191.501268 -219.925392) (xy 191.508634 -219.932758) (xy 191.531527 -219.956114)
			(xy 191.571613 -220.007792) (xy 191.60455 -220.064294) (xy 191.629768 -220.124638) (xy 191.646827 -220.187776)
			(xy 191.65543 -220.252609) (xy 191.655954 -220.28531) (xy 191.655465 -220.316473) (xy 191.647653 -220.378307)
			(xy 191.632153 -220.438675) (xy 191.60921 -220.496623) (xy 191.579184 -220.55124) (xy 191.54255 -220.601662)
			(xy 191.499885 -220.647096) (xy 191.451863 -220.686824) (xy 191.399239 -220.720219) (xy 191.342845 -220.746756)
			(xy 191.28357 -220.766016) (xy 191.222349 -220.777695) (xy 191.160146 -220.781608) (xy 191.097943 -220.777695)
			(xy 191.036722 -220.766016) (xy 190.977447 -220.746756) (xy 190.921053 -220.720219) (xy 190.868429 -220.686824)
			(xy 190.820407 -220.647096) (xy 190.777742 -220.601662) (xy 190.741108 -220.55124) (xy 190.711082 -220.496623)
			(xy 190.688139 -220.438675) (xy 190.672639 -220.378307) (xy 190.664827 -220.316473) (xy 190.664338 -220.28531)
			(xy 187.555886 -220.28531) (xy 187.555345 -220.31801) (xy 187.546741 -220.382842) (xy 187.529684 -220.445979)
			(xy 187.504471 -220.506323) (xy 187.471539 -220.562827) (xy 187.431461 -220.614509) (xy 187.408566 -220.637862)
			(xy 187.4012 -220.645228) (xy 187.39358 -220.66377) (xy 187.39358 -220.710252) (xy 187.808377 -220.710252)
			(xy 187.812312 -220.656481) (xy 187.824035 -220.603857) (xy 187.843295 -220.5535) (xy 187.869681 -220.506483)
			(xy 187.902633 -220.46381) (xy 187.941446 -220.426389) (xy 187.985294 -220.395019) (xy 188.033242 -220.370367)
			(xy 188.084269 -220.352959) (xy 188.137287 -220.343166) (xy 188.191166 -220.341197) (xy 188.244757 -220.347094)
			(xy 188.296918 -220.36073) (xy 188.346538 -220.381817) (xy 188.392559 -220.409903) (xy 188.434001 -220.444391)
			(xy 188.469979 -220.484545) (xy 188.499727 -220.529509) (xy 188.522612 -220.578326) (xy 188.538144 -220.629955)
			(xy 188.545994 -220.683295) (xy 188.546486 -220.710252) (xy 188.545994 -220.737209) (xy 188.538144 -220.790549)
			(xy 188.522612 -220.842178) (xy 188.499727 -220.890995) (xy 188.469979 -220.935959) (xy 188.434001 -220.976113)
			(xy 188.392559 -221.010601) (xy 188.346538 -221.038687) (xy 188.296918 -221.059774) (xy 188.244757 -221.07341)
			(xy 188.191166 -221.079307) (xy 188.137287 -221.077338) (xy 188.084269 -221.067545) (xy 188.033242 -221.050137)
			(xy 187.985294 -221.025485) (xy 187.941446 -220.994115) (xy 187.902633 -220.956694) (xy 187.869681 -220.914021)
			(xy 187.843295 -220.867004) (xy 187.824035 -220.816647) (xy 187.812312 -220.764023) (xy 187.808377 -220.710252)
			(xy 187.39358 -220.710252) (xy 187.39358 -220.756734) (xy 187.4012 -220.775276) (xy 187.408566 -220.782642)
			(xy 187.431457 -220.806) (xy 187.471542 -220.857678) (xy 187.504479 -220.91418) (xy 187.529697 -220.974524)
			(xy 187.546756 -221.037661) (xy 187.555361 -221.102493) (xy 187.555886 -221.135194) (xy 189.406545 -221.135194)
			(xy 189.41048 -221.081423) (xy 189.422203 -221.028799) (xy 189.441463 -220.978442) (xy 189.467849 -220.931425)
			(xy 189.500801 -220.888752) (xy 189.539614 -220.851331) (xy 189.583462 -220.819961) (xy 189.63141 -220.795309)
			(xy 189.682437 -220.777901) (xy 189.735455 -220.768108) (xy 189.789334 -220.766139) (xy 189.842925 -220.772036)
			(xy 189.895086 -220.785672) (xy 189.944706 -220.806759) (xy 189.990727 -220.834845) (xy 190.032169 -220.869333)
			(xy 190.068147 -220.909487) (xy 190.097895 -220.954451) (xy 190.12078 -221.003268) (xy 190.136312 -221.054897)
			(xy 190.144162 -221.108237) (xy 190.144654 -221.135194) (xy 194.108324 -221.135194) (xy 194.108895 -221.102495)
			(xy 194.117496 -221.037666) (xy 194.134549 -220.97453) (xy 194.159757 -220.914186) (xy 194.192682 -220.857681)
			(xy 194.232753 -220.805997) (xy 194.255644 -220.782642) (xy 194.26301 -220.775276) (xy 194.27063 -220.756734)
			(xy 194.27063 -220.66377) (xy 194.26301 -220.645228) (xy 194.255644 -220.637862) (xy 194.232756 -220.6145)
			(xy 194.192671 -220.562824) (xy 194.159733 -220.506323) (xy 194.134515 -220.445979) (xy 194.117455 -220.382843)
			(xy 194.108849 -220.31801) (xy 194.108324 -220.28531) (xy 194.108813 -220.254147) (xy 194.116625 -220.192313)
			(xy 194.132125 -220.131945) (xy 194.155068 -220.073997) (xy 194.185094 -220.01938) (xy 194.221728 -219.968958)
			(xy 194.264393 -219.923524) (xy 194.312415 -219.883796) (xy 194.365039 -219.850401) (xy 194.421433 -219.823864)
			(xy 194.480708 -219.804604) (xy 194.541929 -219.792925) (xy 194.604132 -219.789012) (xy 194.666335 -219.792925)
			(xy 194.727556 -219.804604) (xy 194.786831 -219.823864) (xy 194.843225 -219.850401) (xy 194.895849 -219.883796)
			(xy 194.943871 -219.923524) (xy 194.986536 -219.968958) (xy 195.02317 -220.01938) (xy 195.053196 -220.073997)
			(xy 195.076139 -220.131945) (xy 195.091639 -220.192313) (xy 195.099451 -220.254147) (xy 195.09994 -220.28531)
			(xy 198.208392 -220.28531) (xy 198.208888 -220.252608) (xy 198.217502 -220.187775) (xy 198.234568 -220.124638)
			(xy 198.25979 -220.064293) (xy 198.292729 -220.00779) (xy 198.332814 -219.95611) (xy 198.355712 -219.932758)
			(xy 198.363078 -219.925392) (xy 198.370698 -219.90685) (xy 198.370698 -219.813886) (xy 198.363078 -219.795344)
			(xy 198.355712 -219.787978) (xy 198.332826 -219.764615) (xy 198.292742 -219.712938) (xy 198.259805 -219.656437)
			(xy 198.234586 -219.596094) (xy 198.217525 -219.532958) (xy 198.208918 -219.468126) (xy 198.208392 -219.435426)
			(xy 198.208881 -219.404263) (xy 198.216693 -219.342429) (xy 198.232193 -219.282061) (xy 198.255136 -219.224113)
			(xy 198.285162 -219.169496) (xy 198.321796 -219.119074) (xy 198.364461 -219.07364) (xy 198.412483 -219.033912)
			(xy 198.465107 -219.000517) (xy 198.521501 -218.97398) (xy 198.580776 -218.95472) (xy 198.641997 -218.943041)
			(xy 198.7042 -218.939128) (xy 198.766403 -218.943041) (xy 198.827624 -218.95472) (xy 198.886899 -218.97398)
			(xy 198.943293 -219.000517) (xy 198.995917 -219.033912) (xy 199.043939 -219.07364) (xy 199.086604 -219.119074)
			(xy 199.123238 -219.169496) (xy 199.153264 -219.224113) (xy 199.176207 -219.282061) (xy 199.191707 -219.342429)
			(xy 199.199519 -219.404263) (xy 199.200008 -219.435426) (xy 203.162931 -219.435426) (xy 203.166866 -219.381655)
			(xy 203.178589 -219.329031) (xy 203.197849 -219.278674) (xy 203.224235 -219.231657) (xy 203.257187 -219.188984)
			(xy 203.296 -219.151563) (xy 203.339848 -219.120193) (xy 203.387796 -219.095541) (xy 203.438823 -219.078133)
			(xy 203.491841 -219.06834) (xy 203.54572 -219.066371) (xy 203.599311 -219.072268) (xy 203.651472 -219.085904)
			(xy 203.701092 -219.106991) (xy 203.747113 -219.135077) (xy 203.788555 -219.169565) (xy 203.824533 -219.209719)
			(xy 203.854281 -219.254683) (xy 203.877166 -219.3035) (xy 203.892698 -219.355129) (xy 203.900548 -219.408469)
			(xy 203.90104 -219.435426) (xy 203.900548 -219.462383) (xy 203.892698 -219.515723) (xy 203.877166 -219.567352)
			(xy 203.854281 -219.616169) (xy 203.824533 -219.661133) (xy 203.788555 -219.701287) (xy 203.747113 -219.735775)
			(xy 203.701092 -219.763861) (xy 203.651472 -219.784948) (xy 203.599311 -219.798584) (xy 203.54572 -219.804481)
			(xy 203.491841 -219.802512) (xy 203.438823 -219.792719) (xy 203.387796 -219.775311) (xy 203.339848 -219.750659)
			(xy 203.296 -219.719289) (xy 203.257187 -219.681868) (xy 203.224235 -219.639195) (xy 203.197849 -219.592178)
			(xy 203.178589 -219.541821) (xy 203.166866 -219.489197) (xy 203.162931 -219.435426) (xy 199.200008 -219.435426)
			(xy 199.19947 -219.468126) (xy 199.190865 -219.532958) (xy 199.173807 -219.596095) (xy 199.148593 -219.656439)
			(xy 199.115661 -219.712943) (xy 199.075583 -219.764624) (xy 199.052688 -219.787978) (xy 199.045322 -219.795344)
			(xy 199.037702 -219.813886) (xy 199.037702 -219.860368) (xy 199.452499 -219.860368) (xy 199.456434 -219.806597)
			(xy 199.468157 -219.753973) (xy 199.487417 -219.703616) (xy 199.513803 -219.656599) (xy 199.546755 -219.613926)
			(xy 199.585568 -219.576505) (xy 199.629416 -219.545135) (xy 199.677364 -219.520483) (xy 199.728391 -219.503075)
			(xy 199.781409 -219.493282) (xy 199.835288 -219.491313) (xy 199.888879 -219.49721) (xy 199.94104 -219.510846)
			(xy 199.99066 -219.531933) (xy 200.036681 -219.560019) (xy 200.078123 -219.594507) (xy 200.114101 -219.634661)
			(xy 200.143849 -219.679625) (xy 200.166734 -219.728442) (xy 200.182266 -219.780071) (xy 200.190116 -219.833411)
			(xy 200.190608 -219.860368) (xy 200.190116 -219.887325) (xy 200.182266 -219.940665) (xy 200.166734 -219.992294)
			(xy 200.143849 -220.041111) (xy 200.114101 -220.086075) (xy 200.078123 -220.126229) (xy 200.036681 -220.160717)
			(xy 199.99066 -220.188803) (xy 199.94104 -220.20989) (xy 199.888879 -220.223526) (xy 199.835288 -220.229423)
			(xy 199.781409 -220.227454) (xy 199.728391 -220.217661) (xy 199.677364 -220.200253) (xy 199.629416 -220.175601)
			(xy 199.585568 -220.144231) (xy 199.546755 -220.10681) (xy 199.513803 -220.064137) (xy 199.487417 -220.01712)
			(xy 199.468157 -219.966763) (xy 199.456434 -219.914139) (xy 199.452499 -219.860368) (xy 199.037702 -219.860368)
			(xy 199.037702 -219.90685) (xy 199.045322 -219.925392) (xy 199.052688 -219.932758) (xy 199.075591 -219.956105)
			(xy 199.115674 -220.007785) (xy 199.148609 -220.06429) (xy 199.173824 -220.124636) (xy 199.190881 -220.187775)
			(xy 199.199484 -220.252609) (xy 199.200008 -220.28531) (xy 199.199519 -220.316473) (xy 199.191707 -220.378307)
			(xy 199.176207 -220.438675) (xy 199.153264 -220.496623) (xy 199.123238 -220.55124) (xy 199.086604 -220.601662)
			(xy 199.043939 -220.647096) (xy 198.995917 -220.686824) (xy 198.943293 -220.720219) (xy 198.886899 -220.746756)
			(xy 198.827624 -220.766016) (xy 198.766403 -220.777695) (xy 198.7042 -220.781608) (xy 198.641997 -220.777695)
			(xy 198.580776 -220.766016) (xy 198.521501 -220.746756) (xy 198.465107 -220.720219) (xy 198.412483 -220.686824)
			(xy 198.364461 -220.647096) (xy 198.321796 -220.601662) (xy 198.285162 -220.55124) (xy 198.255136 -220.496623)
			(xy 198.232193 -220.438675) (xy 198.216693 -220.378307) (xy 198.208881 -220.316473) (xy 198.208392 -220.28531)
			(xy 195.09994 -220.28531) (xy 195.099383 -220.318009) (xy 195.09078 -220.38284) (xy 195.073725 -220.445976)
			(xy 195.048515 -220.50632) (xy 195.015587 -220.562825) (xy 194.975513 -220.614507) (xy 194.95262 -220.637862)
			(xy 194.945254 -220.645228) (xy 194.937634 -220.66377) (xy 194.937634 -220.710252) (xy 195.352431 -220.710252)
			(xy 195.356366 -220.656481) (xy 195.368089 -220.603857) (xy 195.387349 -220.5535) (xy 195.413735 -220.506483)
			(xy 195.446687 -220.46381) (xy 195.4855 -220.426389) (xy 195.529348 -220.395019) (xy 195.577296 -220.370367)
			(xy 195.628323 -220.352959) (xy 195.681341 -220.343166) (xy 195.73522 -220.341197) (xy 195.788811 -220.347094)
			(xy 195.840972 -220.36073) (xy 195.890592 -220.381817) (xy 195.936613 -220.409903) (xy 195.978055 -220.444391)
			(xy 196.014033 -220.484545) (xy 196.043781 -220.529509) (xy 196.066666 -220.578326) (xy 196.082198 -220.629955)
			(xy 196.090048 -220.683295) (xy 196.09054 -220.710252) (xy 196.090048 -220.737209) (xy 196.082198 -220.790549)
			(xy 196.066666 -220.842178) (xy 196.043781 -220.890995) (xy 196.014033 -220.935959) (xy 195.978055 -220.976113)
			(xy 195.936613 -221.010601) (xy 195.890592 -221.038687) (xy 195.840972 -221.059774) (xy 195.788811 -221.07341)
			(xy 195.73522 -221.079307) (xy 195.681341 -221.077338) (xy 195.628323 -221.067545) (xy 195.577296 -221.050137)
			(xy 195.529348 -221.025485) (xy 195.4855 -220.994115) (xy 195.446687 -220.956694) (xy 195.413735 -220.914021)
			(xy 195.387349 -220.867004) (xy 195.368089 -220.816647) (xy 195.356366 -220.764023) (xy 195.352431 -220.710252)
			(xy 194.937634 -220.710252) (xy 194.937634 -220.756734) (xy 194.945254 -220.775276) (xy 194.95262 -220.782642)
			(xy 194.975503 -220.806008) (xy 195.01559 -220.857683) (xy 195.048529 -220.914183) (xy 195.073749 -220.974526)
			(xy 195.090809 -221.037662) (xy 195.099415 -221.102494) (xy 195.09994 -221.135194) (xy 196.950599 -221.135194)
			(xy 196.954534 -221.081423) (xy 196.966257 -221.028799) (xy 196.985517 -220.978442) (xy 197.011903 -220.931425)
			(xy 197.044855 -220.888752) (xy 197.083668 -220.851331) (xy 197.127516 -220.819961) (xy 197.175464 -220.795309)
			(xy 197.226491 -220.777901) (xy 197.279509 -220.768108) (xy 197.333388 -220.766139) (xy 197.386979 -220.772036)
			(xy 197.43914 -220.785672) (xy 197.48876 -220.806759) (xy 197.534781 -220.834845) (xy 197.576223 -220.869333)
			(xy 197.612201 -220.909487) (xy 197.641949 -220.954451) (xy 197.664834 -221.003268) (xy 197.680366 -221.054897)
			(xy 197.688216 -221.108237) (xy 197.688708 -221.135194) (xy 201.652124 -221.135194) (xy 201.652695 -221.102495)
			(xy 201.661296 -221.037666) (xy 201.678349 -220.97453) (xy 201.703557 -220.914186) (xy 201.736482 -220.857681)
			(xy 201.776553 -220.805997) (xy 201.799444 -220.782642) (xy 201.80681 -220.775276) (xy 201.81443 -220.756734)
			(xy 201.81443 -220.66377) (xy 201.80681 -220.645228) (xy 201.799444 -220.637862) (xy 201.776556 -220.6145)
			(xy 201.736471 -220.562824) (xy 201.703533 -220.506323) (xy 201.678315 -220.445979) (xy 201.661255 -220.382843)
			(xy 201.652649 -220.31801) (xy 201.652124 -220.28531) (xy 201.652613 -220.254147) (xy 201.660425 -220.192313)
			(xy 201.675925 -220.131945) (xy 201.698868 -220.073997) (xy 201.728894 -220.01938) (xy 201.765528 -219.968958)
			(xy 201.808193 -219.923524) (xy 201.856215 -219.883796) (xy 201.908839 -219.850401) (xy 201.965233 -219.823864)
			(xy 202.024508 -219.804604) (xy 202.085729 -219.792925) (xy 202.147932 -219.789012) (xy 202.210135 -219.792925)
			(xy 202.271356 -219.804604) (xy 202.330631 -219.823864) (xy 202.387025 -219.850401) (xy 202.439649 -219.883796)
			(xy 202.487671 -219.923524) (xy 202.530336 -219.968958) (xy 202.56697 -220.01938) (xy 202.596996 -220.073997)
			(xy 202.619939 -220.131945) (xy 202.635439 -220.192313) (xy 202.643251 -220.254147) (xy 202.64374 -220.28531)
			(xy 205.752192 -220.28531) (xy 205.752688 -220.252608) (xy 205.761302 -220.187775) (xy 205.778368 -220.124638)
			(xy 205.80359 -220.064293) (xy 205.836529 -220.00779) (xy 205.876614 -219.95611) (xy 205.899512 -219.932758)
			(xy 205.906878 -219.925392) (xy 205.914498 -219.90685) (xy 205.914498 -219.813886) (xy 205.906878 -219.795344)
			(xy 205.899512 -219.787978) (xy 205.876626 -219.764615) (xy 205.836542 -219.712938) (xy 205.803605 -219.656437)
			(xy 205.778386 -219.596094) (xy 205.761325 -219.532958) (xy 205.752718 -219.468126) (xy 205.752192 -219.435426)
			(xy 205.752681 -219.404263) (xy 205.760493 -219.342429) (xy 205.775993 -219.282061) (xy 205.798936 -219.224113)
			(xy 205.828962 -219.169496) (xy 205.865596 -219.119074) (xy 205.908261 -219.07364) (xy 205.956283 -219.033912)
			(xy 206.008907 -219.000517) (xy 206.065301 -218.97398) (xy 206.124576 -218.95472) (xy 206.185797 -218.943041)
			(xy 206.248 -218.939128) (xy 206.310203 -218.943041) (xy 206.371424 -218.95472) (xy 206.430699 -218.97398)
			(xy 206.487093 -219.000517) (xy 206.539717 -219.033912) (xy 206.587739 -219.07364) (xy 206.630404 -219.119074)
			(xy 206.667038 -219.169496) (xy 206.697064 -219.224113) (xy 206.720007 -219.282061) (xy 206.735507 -219.342429)
			(xy 206.743319 -219.404263) (xy 206.743808 -219.435426) (xy 206.74327 -219.468126) (xy 206.734665 -219.532958)
			(xy 206.717607 -219.596095) (xy 206.692393 -219.656439) (xy 206.659461 -219.712943) (xy 206.619383 -219.764624)
			(xy 206.596488 -219.787978) (xy 206.589122 -219.795344) (xy 206.581502 -219.813886) (xy 206.581502 -219.860368)
			(xy 206.996299 -219.860368) (xy 207.000234 -219.806597) (xy 207.011957 -219.753973) (xy 207.031217 -219.703616)
			(xy 207.057603 -219.656599) (xy 207.090555 -219.613926) (xy 207.129368 -219.576505) (xy 207.173216 -219.545135)
			(xy 207.221164 -219.520483) (xy 207.272191 -219.503075) (xy 207.325209 -219.493282) (xy 207.379088 -219.491313)
			(xy 207.432679 -219.49721) (xy 207.48484 -219.510846) (xy 207.53446 -219.531933) (xy 207.580481 -219.560019)
			(xy 207.621923 -219.594507) (xy 207.657901 -219.634661) (xy 207.687649 -219.679625) (xy 207.710534 -219.728442)
			(xy 207.726066 -219.780071) (xy 207.733916 -219.833411) (xy 207.734408 -219.860368) (xy 207.733916 -219.887325)
			(xy 207.726066 -219.940665) (xy 207.710534 -219.992294) (xy 207.687649 -220.041111) (xy 207.657901 -220.086075)
			(xy 207.621923 -220.126229) (xy 207.580481 -220.160717) (xy 207.53446 -220.188803) (xy 207.48484 -220.20989)
			(xy 207.432679 -220.223526) (xy 207.379088 -220.229423) (xy 207.325209 -220.227454) (xy 207.272191 -220.217661)
			(xy 207.221164 -220.200253) (xy 207.173216 -220.175601) (xy 207.129368 -220.144231) (xy 207.090555 -220.10681)
			(xy 207.057603 -220.064137) (xy 207.031217 -220.01712) (xy 207.011957 -219.966763) (xy 207.000234 -219.914139)
			(xy 206.996299 -219.860368) (xy 206.581502 -219.860368) (xy 206.581502 -219.90685) (xy 206.589122 -219.925392)
			(xy 206.596488 -219.932758) (xy 206.619391 -219.956105) (xy 206.659474 -220.007785) (xy 206.692409 -220.06429)
			(xy 206.717624 -220.124636) (xy 206.734681 -220.187775) (xy 206.743284 -220.252609) (xy 206.743808 -220.28531)
			(xy 206.743319 -220.316473) (xy 206.735507 -220.378307) (xy 206.720007 -220.438675) (xy 206.697064 -220.496623)
			(xy 206.667038 -220.55124) (xy 206.630404 -220.601662) (xy 206.587739 -220.647096) (xy 206.539717 -220.686824)
			(xy 206.487093 -220.720219) (xy 206.430699 -220.746756) (xy 206.371424 -220.766016) (xy 206.310203 -220.777695)
			(xy 206.248 -220.781608) (xy 206.185797 -220.777695) (xy 206.124576 -220.766016) (xy 206.065301 -220.746756)
			(xy 206.008907 -220.720219) (xy 205.956283 -220.686824) (xy 205.908261 -220.647096) (xy 205.865596 -220.601662)
			(xy 205.828962 -220.55124) (xy 205.798936 -220.496623) (xy 205.775993 -220.438675) (xy 205.760493 -220.378307)
			(xy 205.752681 -220.316473) (xy 205.752192 -220.28531) (xy 202.64374 -220.28531) (xy 202.643183 -220.318009)
			(xy 202.63458 -220.38284) (xy 202.617525 -220.445976) (xy 202.592315 -220.50632) (xy 202.559387 -220.562825)
			(xy 202.519313 -220.614507) (xy 202.49642 -220.637862) (xy 202.489054 -220.645228) (xy 202.481434 -220.66377)
			(xy 202.481434 -220.710252) (xy 202.896231 -220.710252) (xy 202.900166 -220.656481) (xy 202.911889 -220.603857)
			(xy 202.931149 -220.5535) (xy 202.957535 -220.506483) (xy 202.990487 -220.46381) (xy 203.0293 -220.426389)
			(xy 203.073148 -220.395019) (xy 203.121096 -220.370367) (xy 203.172123 -220.352959) (xy 203.225141 -220.343166)
			(xy 203.27902 -220.341197) (xy 203.332611 -220.347094) (xy 203.384772 -220.36073) (xy 203.434392 -220.381817)
			(xy 203.480413 -220.409903) (xy 203.521855 -220.444391) (xy 203.557833 -220.484545) (xy 203.587581 -220.529509)
			(xy 203.610466 -220.578326) (xy 203.625998 -220.629955) (xy 203.633848 -220.683295) (xy 203.63434 -220.710252)
			(xy 203.633848 -220.737209) (xy 203.625998 -220.790549) (xy 203.610466 -220.842178) (xy 203.587581 -220.890995)
			(xy 203.557833 -220.935959) (xy 203.521855 -220.976113) (xy 203.480413 -221.010601) (xy 203.434392 -221.038687)
			(xy 203.384772 -221.059774) (xy 203.332611 -221.07341) (xy 203.27902 -221.079307) (xy 203.225141 -221.077338)
			(xy 203.172123 -221.067545) (xy 203.121096 -221.050137) (xy 203.073148 -221.025485) (xy 203.0293 -220.994115)
			(xy 202.990487 -220.956694) (xy 202.957535 -220.914021) (xy 202.931149 -220.867004) (xy 202.911889 -220.816647)
			(xy 202.900166 -220.764023) (xy 202.896231 -220.710252) (xy 202.481434 -220.710252) (xy 202.481434 -220.756734)
			(xy 202.489054 -220.775276) (xy 202.49642 -220.782642) (xy 202.519303 -220.806008) (xy 202.55939 -220.857683)
			(xy 202.592329 -220.914183) (xy 202.617549 -220.974526) (xy 202.634609 -221.037662) (xy 202.643215 -221.102494)
			(xy 202.64374 -221.135194) (xy 204.494399 -221.135194) (xy 204.498334 -221.081423) (xy 204.510057 -221.028799)
			(xy 204.529317 -220.978442) (xy 204.555703 -220.931425) (xy 204.588655 -220.888752) (xy 204.627468 -220.851331)
			(xy 204.671316 -220.819961) (xy 204.719264 -220.795309) (xy 204.770291 -220.777901) (xy 204.823309 -220.768108)
			(xy 204.877188 -220.766139) (xy 204.930779 -220.772036) (xy 204.98294 -220.785672) (xy 205.03256 -220.806759)
			(xy 205.078581 -220.834845) (xy 205.120023 -220.869333) (xy 205.156001 -220.909487) (xy 205.185749 -220.954451)
			(xy 205.208634 -221.003268) (xy 205.224166 -221.054897) (xy 205.232016 -221.108237) (xy 205.232508 -221.135194)
			(xy 205.232016 -221.162151) (xy 205.224166 -221.215491) (xy 205.208634 -221.26712) (xy 205.185749 -221.315937)
			(xy 205.156001 -221.360901) (xy 205.120023 -221.401055) (xy 205.078581 -221.435543) (xy 205.03256 -221.463629)
			(xy 204.98294 -221.484716) (xy 204.930779 -221.498352) (xy 204.877188 -221.504249) (xy 204.823309 -221.50228)
			(xy 204.770291 -221.492487) (xy 204.719264 -221.475079) (xy 204.671316 -221.450427) (xy 204.627468 -221.419057)
			(xy 204.588655 -221.381636) (xy 204.555703 -221.338963) (xy 204.529317 -221.291946) (xy 204.510057 -221.241589)
			(xy 204.498334 -221.188965) (xy 204.494399 -221.135194) (xy 202.64374 -221.135194) (xy 202.643251 -221.166357)
			(xy 202.635439 -221.228191) (xy 202.619939 -221.288559) (xy 202.596996 -221.346507) (xy 202.56697 -221.401124)
			(xy 202.530336 -221.451546) (xy 202.487671 -221.49698) (xy 202.439649 -221.536708) (xy 202.387025 -221.570103)
			(xy 202.330631 -221.59664) (xy 202.271356 -221.6159) (xy 202.210135 -221.627579) (xy 202.147932 -221.631492)
			(xy 202.085729 -221.627579) (xy 202.024508 -221.6159) (xy 201.965233 -221.59664) (xy 201.908839 -221.570103)
			(xy 201.856215 -221.536708) (xy 201.808193 -221.49698) (xy 201.765528 -221.451546) (xy 201.728894 -221.401124)
			(xy 201.698868 -221.346507) (xy 201.675925 -221.288559) (xy 201.660425 -221.228191) (xy 201.652613 -221.166357)
			(xy 201.652124 -221.135194) (xy 197.688708 -221.135194) (xy 197.688216 -221.162151) (xy 197.680366 -221.215491)
			(xy 197.664834 -221.26712) (xy 197.641949 -221.315937) (xy 197.612201 -221.360901) (xy 197.576223 -221.401055)
			(xy 197.534781 -221.435543) (xy 197.48876 -221.463629) (xy 197.43914 -221.484716) (xy 197.386979 -221.498352)
			(xy 197.333388 -221.504249) (xy 197.279509 -221.50228) (xy 197.226491 -221.492487) (xy 197.175464 -221.475079)
			(xy 197.127516 -221.450427) (xy 197.083668 -221.419057) (xy 197.044855 -221.381636) (xy 197.011903 -221.338963)
			(xy 196.985517 -221.291946) (xy 196.966257 -221.241589) (xy 196.954534 -221.188965) (xy 196.950599 -221.135194)
			(xy 195.09994 -221.135194) (xy 195.099451 -221.166357) (xy 195.091639 -221.228191) (xy 195.076139 -221.288559)
			(xy 195.053196 -221.346507) (xy 195.02317 -221.401124) (xy 194.986536 -221.451546) (xy 194.943871 -221.49698)
			(xy 194.895849 -221.536708) (xy 194.843225 -221.570103) (xy 194.786831 -221.59664) (xy 194.727556 -221.6159)
			(xy 194.666335 -221.627579) (xy 194.604132 -221.631492) (xy 194.541929 -221.627579) (xy 194.480708 -221.6159)
			(xy 194.421433 -221.59664) (xy 194.365039 -221.570103) (xy 194.312415 -221.536708) (xy 194.264393 -221.49698)
			(xy 194.221728 -221.451546) (xy 194.185094 -221.401124) (xy 194.155068 -221.346507) (xy 194.132125 -221.288559)
			(xy 194.116625 -221.228191) (xy 194.108813 -221.166357) (xy 194.108324 -221.135194) (xy 190.144654 -221.135194)
			(xy 190.144162 -221.162151) (xy 190.136312 -221.215491) (xy 190.12078 -221.26712) (xy 190.097895 -221.315937)
			(xy 190.068147 -221.360901) (xy 190.032169 -221.401055) (xy 189.990727 -221.435543) (xy 189.944706 -221.463629)
			(xy 189.895086 -221.484716) (xy 189.842925 -221.498352) (xy 189.789334 -221.504249) (xy 189.735455 -221.50228)
			(xy 189.682437 -221.492487) (xy 189.63141 -221.475079) (xy 189.583462 -221.450427) (xy 189.539614 -221.419057)
			(xy 189.500801 -221.381636) (xy 189.467849 -221.338963) (xy 189.441463 -221.291946) (xy 189.422203 -221.241589)
			(xy 189.41048 -221.188965) (xy 189.406545 -221.135194) (xy 187.555886 -221.135194) (xy 187.555397 -221.166357)
			(xy 187.547585 -221.228191) (xy 187.532085 -221.288559) (xy 187.509142 -221.346507) (xy 187.479116 -221.401124)
			(xy 187.442482 -221.451546) (xy 187.399817 -221.49698) (xy 187.351795 -221.536708) (xy 187.299171 -221.570103)
			(xy 187.242777 -221.59664) (xy 187.183502 -221.6159) (xy 187.122281 -221.627579) (xy 187.060078 -221.631492)
			(xy 186.997875 -221.627579) (xy 186.936654 -221.6159) (xy 186.877379 -221.59664) (xy 186.820985 -221.570103)
			(xy 186.768361 -221.536708) (xy 186.720339 -221.49698) (xy 186.677674 -221.451546) (xy 186.64104 -221.401124)
			(xy 186.611014 -221.346507) (xy 186.588071 -221.288559) (xy 186.572571 -221.228191) (xy 186.564759 -221.166357)
			(xy 186.56427 -221.135194) (xy 182.6006 -221.135194) (xy 182.600108 -221.162151) (xy 182.592258 -221.215491)
			(xy 182.576726 -221.26712) (xy 182.553841 -221.315937) (xy 182.524093 -221.360901) (xy 182.488115 -221.401055)
			(xy 182.446673 -221.435543) (xy 182.400652 -221.463629) (xy 182.351032 -221.484716) (xy 182.298871 -221.498352)
			(xy 182.24528 -221.504249) (xy 182.191401 -221.50228) (xy 182.138383 -221.492487) (xy 182.087356 -221.475079)
			(xy 182.039408 -221.450427) (xy 181.99556 -221.419057) (xy 181.956747 -221.381636) (xy 181.923795 -221.338963)
			(xy 181.897409 -221.291946) (xy 181.878149 -221.241589) (xy 181.866426 -221.188965) (xy 181.862491 -221.135194)
			(xy 180.011832 -221.135194) (xy 180.011343 -221.166357) (xy 180.003531 -221.228191) (xy 179.988031 -221.288559)
			(xy 179.965088 -221.346507) (xy 179.935062 -221.401124) (xy 179.898428 -221.451546) (xy 179.855763 -221.49698)
			(xy 179.807741 -221.536708) (xy 179.755117 -221.570103) (xy 179.698723 -221.59664) (xy 179.639448 -221.6159)
			(xy 179.578227 -221.627579) (xy 179.516024 -221.631492) (xy 179.453821 -221.627579) (xy 179.3926 -221.6159)
			(xy 179.333325 -221.59664) (xy 179.276931 -221.570103) (xy 179.224307 -221.536708) (xy 179.176285 -221.49698)
			(xy 179.13362 -221.451546) (xy 179.096986 -221.401124) (xy 179.06696 -221.346507) (xy 179.044017 -221.288559)
			(xy 179.028517 -221.228191) (xy 179.020705 -221.166357) (xy 179.020216 -221.135194) (xy 175.056546 -221.135194)
			(xy 175.056054 -221.162151) (xy 175.048204 -221.215491) (xy 175.032672 -221.26712) (xy 175.009787 -221.315937)
			(xy 174.980039 -221.360901) (xy 174.944061 -221.401055) (xy 174.902619 -221.435543) (xy 174.856598 -221.463629)
			(xy 174.806978 -221.484716) (xy 174.754817 -221.498352) (xy 174.701226 -221.504249) (xy 174.647347 -221.50228)
			(xy 174.594329 -221.492487) (xy 174.543302 -221.475079) (xy 174.495354 -221.450427) (xy 174.451506 -221.419057)
			(xy 174.412693 -221.381636) (xy 174.379741 -221.338963) (xy 174.353355 -221.291946) (xy 174.334095 -221.241589)
			(xy 174.322372 -221.188965) (xy 174.318437 -221.135194) (xy 172.467778 -221.135194) (xy 172.467289 -221.166357)
			(xy 172.459477 -221.228191) (xy 172.443977 -221.288559) (xy 172.421034 -221.346507) (xy 172.391008 -221.401124)
			(xy 172.354374 -221.451546) (xy 172.311709 -221.49698) (xy 172.263687 -221.536708) (xy 172.211063 -221.570103)
			(xy 172.154669 -221.59664) (xy 172.095394 -221.6159) (xy 172.034173 -221.627579) (xy 171.97197 -221.631492)
			(xy 171.909767 -221.627579) (xy 171.848546 -221.6159) (xy 171.789271 -221.59664) (xy 171.732877 -221.570103)
			(xy 171.680253 -221.536708) (xy 171.632231 -221.49698) (xy 171.589566 -221.451546) (xy 171.552932 -221.401124)
			(xy 171.522906 -221.346507) (xy 171.499963 -221.288559) (xy 171.484463 -221.228191) (xy 171.476651 -221.166357)
			(xy 171.476162 -221.135194) (xy 167.512492 -221.135194) (xy 167.512 -221.162151) (xy 167.50415 -221.215491)
			(xy 167.488618 -221.26712) (xy 167.465733 -221.315937) (xy 167.435985 -221.360901) (xy 167.400007 -221.401055)
			(xy 167.358565 -221.435543) (xy 167.312544 -221.463629) (xy 167.262924 -221.484716) (xy 167.210763 -221.498352)
			(xy 167.157172 -221.504249) (xy 167.103293 -221.50228) (xy 167.050275 -221.492487) (xy 166.999248 -221.475079)
			(xy 166.9513 -221.450427) (xy 166.907452 -221.419057) (xy 166.868639 -221.381636) (xy 166.835687 -221.338963)
			(xy 166.809301 -221.291946) (xy 166.790041 -221.241589) (xy 166.778318 -221.188965) (xy 166.774383 -221.135194)
			(xy 161.612834 -221.135194) (xy 161.612834 -221.985332) (xy 165.442915 -221.985332) (xy 165.44685 -221.931561)
			(xy 165.458573 -221.878937) (xy 165.477833 -221.82858) (xy 165.504219 -221.781563) (xy 165.537171 -221.73889)
			(xy 165.575984 -221.701469) (xy 165.619832 -221.670099) (xy 165.66778 -221.645447) (xy 165.718807 -221.628039)
			(xy 165.771825 -221.618246) (xy 165.825704 -221.616277) (xy 165.879295 -221.622174) (xy 165.931456 -221.63581)
			(xy 165.981076 -221.656897) (xy 166.027097 -221.684983) (xy 166.068539 -221.719471) (xy 166.104517 -221.759625)
			(xy 166.134265 -221.804589) (xy 166.15715 -221.853406) (xy 166.172682 -221.905035) (xy 166.180532 -221.958375)
			(xy 166.181024 -221.985332) (xy 172.986969 -221.985332) (xy 172.990904 -221.931561) (xy 173.002627 -221.878937)
			(xy 173.021887 -221.82858) (xy 173.048273 -221.781563) (xy 173.081225 -221.73889) (xy 173.120038 -221.701469)
			(xy 173.163886 -221.670099) (xy 173.211834 -221.645447) (xy 173.262861 -221.628039) (xy 173.315879 -221.618246)
			(xy 173.369758 -221.616277) (xy 173.423349 -221.622174) (xy 173.47551 -221.63581) (xy 173.52513 -221.656897)
			(xy 173.571151 -221.684983) (xy 173.612593 -221.719471) (xy 173.648571 -221.759625) (xy 173.678319 -221.804589)
			(xy 173.701204 -221.853406) (xy 173.716736 -221.905035) (xy 173.724586 -221.958375) (xy 173.725078 -221.985332)
			(xy 173.724586 -222.012289) (xy 173.716736 -222.065629) (xy 173.701204 -222.117258) (xy 173.678319 -222.166075)
			(xy 173.648571 -222.211039) (xy 173.612593 -222.251193) (xy 173.571151 -222.285681) (xy 173.52513 -222.313767)
			(xy 173.47551 -222.334854) (xy 173.423349 -222.34849) (xy 173.369758 -222.354387) (xy 173.315879 -222.352418)
			(xy 173.262861 -222.342625) (xy 173.211834 -222.325217) (xy 173.163886 -222.300565) (xy 173.120038 -222.269195)
			(xy 173.081225 -222.231774) (xy 173.048273 -222.189101) (xy 173.021887 -222.142084) (xy 173.002627 -222.091727)
			(xy 172.990904 -222.039103) (xy 172.986969 -221.985332) (xy 166.181024 -221.985332) (xy 166.180532 -222.012289)
			(xy 166.172682 -222.065629) (xy 166.15715 -222.117258) (xy 166.134265 -222.166075) (xy 166.104517 -222.211039)
			(xy 166.068539 -222.251193) (xy 166.027097 -222.285681) (xy 165.981076 -222.313767) (xy 165.931456 -222.334854)
			(xy 165.879295 -222.34849) (xy 165.825704 -222.354387) (xy 165.771825 -222.352418) (xy 165.718807 -222.342625)
			(xy 165.66778 -222.325217) (xy 165.619832 -222.300565) (xy 165.575984 -222.269195) (xy 165.537171 -222.231774)
			(xy 165.504219 -222.189101) (xy 165.477833 -222.142084) (xy 165.458573 -222.091727) (xy 165.44685 -222.039103)
			(xy 165.442915 -221.985332) (xy 161.612834 -221.985332) (xy 161.612834 -222.835216) (xy 168.158683 -222.835216)
			(xy 168.162618 -222.781445) (xy 168.174341 -222.728821) (xy 168.193601 -222.678464) (xy 168.219987 -222.631447)
			(xy 168.252939 -222.588774) (xy 168.291752 -222.551353) (xy 168.3356 -222.519983) (xy 168.383548 -222.495331)
			(xy 168.434575 -222.477923) (xy 168.487593 -222.46813) (xy 168.541472 -222.466161) (xy 168.595063 -222.472058)
			(xy 168.647224 -222.485694) (xy 168.696844 -222.506781) (xy 168.742865 -222.534867) (xy 168.784307 -222.569355)
			(xy 168.820285 -222.609509) (xy 168.850033 -222.654473) (xy 168.872918 -222.70329) (xy 168.88845 -222.754919)
			(xy 168.8963 -222.808259) (xy 168.896792 -222.835216) (xy 168.8963 -222.862173) (xy 168.88845 -222.915513)
			(xy 168.872918 -222.967142) (xy 168.850033 -223.015959) (xy 168.820285 -223.060923) (xy 168.784307 -223.101077)
			(xy 168.742865 -223.135565) (xy 168.696844 -223.163651) (xy 168.647224 -223.184738) (xy 168.595063 -223.198374)
			(xy 168.541472 -223.204271) (xy 168.487593 -223.202302) (xy 168.434575 -223.192509) (xy 168.383548 -223.175101)
			(xy 168.3356 -223.150449) (xy 168.291752 -223.119079) (xy 168.252939 -223.081658) (xy 168.219987 -223.038985)
			(xy 168.193601 -222.991968) (xy 168.174341 -222.941611) (xy 168.162618 -222.888987) (xy 168.158683 -222.835216)
			(xy 161.612834 -222.835216) (xy 161.612834 -223.685354) (xy 164.058615 -223.685354) (xy 164.06255 -223.631583)
			(xy 164.074273 -223.578959) (xy 164.093533 -223.528602) (xy 164.119919 -223.481585) (xy 164.152871 -223.438912)
			(xy 164.191684 -223.401491) (xy 164.235532 -223.370121) (xy 164.28348 -223.345469) (xy 164.334507 -223.328061)
			(xy 164.387525 -223.318268) (xy 164.441404 -223.316299) (xy 164.494995 -223.322196) (xy 164.547156 -223.335832)
			(xy 164.596776 -223.356919) (xy 164.642797 -223.385005) (xy 164.684239 -223.419493) (xy 164.720217 -223.459647)
			(xy 164.749965 -223.504611) (xy 164.77285 -223.553428) (xy 164.788382 -223.605057) (xy 164.796232 -223.658397)
			(xy 164.796724 -223.685354) (xy 164.796232 -223.712311) (xy 164.788382 -223.765651) (xy 164.77285 -223.81728)
			(xy 164.749965 -223.866097) (xy 164.720217 -223.911061) (xy 164.684239 -223.951215) (xy 164.642797 -223.985703)
			(xy 164.596776 -224.013789) (xy 164.547156 -224.034876) (xy 164.494995 -224.048512) (xy 164.441404 -224.054409)
			(xy 164.387525 -224.05244) (xy 164.334507 -224.042647) (xy 164.28348 -224.025239) (xy 164.235532 -224.000587)
			(xy 164.191684 -223.969217) (xy 164.152871 -223.931796) (xy 164.119919 -223.889123) (xy 164.093533 -223.842106)
			(xy 164.074273 -223.791749) (xy 164.06255 -223.739125) (xy 164.058615 -223.685354) (xy 161.612834 -223.685354)
			(xy 161.612834 -224.535238) (xy 168.158683 -224.535238) (xy 168.162618 -224.481467) (xy 168.174341 -224.428843)
			(xy 168.193601 -224.378486) (xy 168.219987 -224.331469) (xy 168.252939 -224.288796) (xy 168.291752 -224.251375)
			(xy 168.3356 -224.220005) (xy 168.383548 -224.195353) (xy 168.434575 -224.177945) (xy 168.487593 -224.168152)
			(xy 168.541472 -224.166183) (xy 168.595063 -224.17208) (xy 168.647224 -224.185716) (xy 168.696844 -224.206803)
			(xy 168.742865 -224.234889) (xy 168.784307 -224.269377) (xy 168.820285 -224.309531) (xy 168.850033 -224.354495)
			(xy 168.872918 -224.403312) (xy 168.88845 -224.454941) (xy 168.8963 -224.508281) (xy 168.896792 -224.535238)
			(xy 168.8963 -224.562195) (xy 168.88845 -224.615535) (xy 168.872918 -224.667164) (xy 168.850033 -224.715981)
			(xy 168.820285 -224.760945) (xy 168.784307 -224.801099) (xy 168.742865 -224.835587) (xy 168.696844 -224.863673)
			(xy 168.647224 -224.88476) (xy 168.595063 -224.898396) (xy 168.541472 -224.904293) (xy 168.487593 -224.902324)
			(xy 168.434575 -224.892531) (xy 168.383548 -224.875123) (xy 168.3356 -224.850471) (xy 168.291752 -224.819101)
			(xy 168.252939 -224.78168) (xy 168.219987 -224.739007) (xy 168.193601 -224.69199) (xy 168.174341 -224.641633)
			(xy 168.162618 -224.589009) (xy 168.158683 -224.535238) (xy 161.612834 -224.535238) (xy 161.612834 -225.385376)
			(xy 164.058615 -225.385376) (xy 164.06255 -225.331605) (xy 164.074273 -225.278981) (xy 164.093533 -225.228624)
			(xy 164.119919 -225.181607) (xy 164.152871 -225.138934) (xy 164.191684 -225.101513) (xy 164.235532 -225.070143)
			(xy 164.28348 -225.045491) (xy 164.334507 -225.028083) (xy 164.387525 -225.01829) (xy 164.441404 -225.016321)
			(xy 164.494995 -225.022218) (xy 164.547156 -225.035854) (xy 164.596776 -225.056941) (xy 164.642797 -225.085027)
			(xy 164.684239 -225.119515) (xy 164.720217 -225.159669) (xy 164.749965 -225.204633) (xy 164.77285 -225.25345)
			(xy 164.788382 -225.305079) (xy 164.796232 -225.358419) (xy 164.796724 -225.385376) (xy 164.796232 -225.412333)
			(xy 164.788382 -225.465673) (xy 164.77285 -225.517302) (xy 164.749965 -225.566119) (xy 164.720217 -225.611083)
			(xy 164.684239 -225.651237) (xy 164.642797 -225.685725) (xy 164.596776 -225.713811) (xy 164.547156 -225.734898)
			(xy 164.494995 -225.748534) (xy 164.441404 -225.754431) (xy 164.387525 -225.752462) (xy 164.334507 -225.742669)
			(xy 164.28348 -225.725261) (xy 164.235532 -225.700609) (xy 164.191684 -225.669239) (xy 164.152871 -225.631818)
			(xy 164.119919 -225.589145) (xy 164.093533 -225.542128) (xy 164.074273 -225.491771) (xy 164.06255 -225.439147)
			(xy 164.058615 -225.385376) (xy 161.612834 -225.385376) (xy 161.612834 -226.23526) (xy 168.158683 -226.23526)
			(xy 168.162618 -226.181489) (xy 168.174341 -226.128865) (xy 168.193601 -226.078508) (xy 168.219987 -226.031491)
			(xy 168.252939 -225.988818) (xy 168.291752 -225.951397) (xy 168.3356 -225.920027) (xy 168.383548 -225.895375)
			(xy 168.434575 -225.877967) (xy 168.487593 -225.868174) (xy 168.541472 -225.866205) (xy 168.595063 -225.872102)
			(xy 168.647224 -225.885738) (xy 168.696844 -225.906825) (xy 168.742865 -225.934911) (xy 168.784307 -225.969399)
			(xy 168.820285 -226.009553) (xy 168.850033 -226.054517) (xy 168.872918 -226.103334) (xy 168.88845 -226.154963)
			(xy 168.8963 -226.208303) (xy 168.896792 -226.23526) (xy 168.8963 -226.262217) (xy 168.88845 -226.315557)
			(xy 168.872918 -226.367186) (xy 168.850033 -226.416003) (xy 168.820285 -226.460967) (xy 168.784307 -226.501121)
			(xy 168.742865 -226.535609) (xy 168.696844 -226.563695) (xy 168.647224 -226.584782) (xy 168.595063 -226.598418)
			(xy 168.541472 -226.604315) (xy 168.487593 -226.602346) (xy 168.434575 -226.592553) (xy 168.383548 -226.575145)
			(xy 168.3356 -226.550493) (xy 168.291752 -226.519123) (xy 168.252939 -226.481702) (xy 168.219987 -226.439029)
			(xy 168.193601 -226.392012) (xy 168.174341 -226.341655) (xy 168.162618 -226.289031) (xy 168.158683 -226.23526)
			(xy 161.612834 -226.23526) (xy 161.612834 -227.085398) (xy 164.058615 -227.085398) (xy 164.06255 -227.031627)
			(xy 164.074273 -226.979003) (xy 164.093533 -226.928646) (xy 164.119919 -226.881629) (xy 164.152871 -226.838956)
			(xy 164.191684 -226.801535) (xy 164.235532 -226.770165) (xy 164.28348 -226.745513) (xy 164.334507 -226.728105)
			(xy 164.387525 -226.718312) (xy 164.441404 -226.716343) (xy 164.494995 -226.72224) (xy 164.547156 -226.735876)
			(xy 164.596776 -226.756963) (xy 164.642797 -226.785049) (xy 164.684239 -226.819537) (xy 164.720217 -226.859691)
			(xy 164.749965 -226.904655) (xy 164.77285 -226.953472) (xy 164.788382 -227.005101) (xy 164.796232 -227.058441)
			(xy 164.796724 -227.085398) (xy 164.796232 -227.112355) (xy 164.788382 -227.165695) (xy 164.77285 -227.217324)
			(xy 164.749965 -227.266141) (xy 164.720217 -227.311105) (xy 164.684239 -227.351259) (xy 164.642797 -227.385747)
			(xy 164.596776 -227.413833) (xy 164.547156 -227.43492) (xy 164.494995 -227.448556) (xy 164.441404 -227.454453)
			(xy 164.387525 -227.452484) (xy 164.334507 -227.442691) (xy 164.28348 -227.425283) (xy 164.235532 -227.400631)
			(xy 164.191684 -227.369261) (xy 164.152871 -227.33184) (xy 164.119919 -227.289167) (xy 164.093533 -227.24215)
			(xy 164.074273 -227.191793) (xy 164.06255 -227.139169) (xy 164.058615 -227.085398) (xy 161.612834 -227.085398)
			(xy 161.612834 -227.935282) (xy 166.774383 -227.935282) (xy 166.778318 -227.881511) (xy 166.790041 -227.828887)
			(xy 166.809301 -227.77853) (xy 166.835687 -227.731513) (xy 166.868639 -227.68884) (xy 166.907452 -227.651419)
			(xy 166.9513 -227.620049) (xy 166.999248 -227.595397) (xy 167.050275 -227.577989) (xy 167.103293 -227.568196)
			(xy 167.157172 -227.566227) (xy 167.210763 -227.572124) (xy 167.262924 -227.58576) (xy 167.312544 -227.606847)
			(xy 167.358565 -227.634933) (xy 167.400007 -227.669421) (xy 167.435985 -227.709575) (xy 167.465733 -227.754539)
			(xy 167.488618 -227.803356) (xy 167.50415 -227.854985) (xy 167.512 -227.908325) (xy 167.512492 -227.935282)
			(xy 171.476162 -227.935282) (xy 171.476602 -227.904084) (xy 171.484426 -227.842181) (xy 171.49996 -227.78175)
			(xy 171.522958 -227.723748) (xy 171.553057 -227.669093) (xy 171.58978 -227.618648) (xy 171.632546 -227.573214)
			(xy 171.680678 -227.533509) (xy 171.706794 -227.516436) (xy 171.716954 -227.509832) (xy 171.729146 -227.49002)
			(xy 171.738544 -227.38588) (xy 171.730162 -227.36429) (xy 171.721272 -227.355908) (xy 171.702986 -227.338393)
			(xy 171.670907 -227.299216) (xy 171.644489 -227.256019) (xy 171.624229 -227.209614) (xy 171.610506 -227.160874)
			(xy 171.60358 -227.110715) (xy 171.603162 -227.085398) (xy 171.603604 -227.060051) (xy 171.610536 -227.009832)
			(xy 171.624282 -226.961037) (xy 171.644584 -226.914586) (xy 171.671058 -226.871353) (xy 171.703205 -226.832155)
			(xy 171.721526 -226.814634) (xy 171.730416 -226.806506) (xy 171.738798 -226.784662) (xy 171.729146 -226.680522)
			(xy 171.716954 -226.66071) (xy 171.706794 -226.65436) (xy 171.680702 -226.637232) (xy 171.63258 -226.597484)
			(xy 171.589823 -226.552014) (xy 171.553108 -226.501541) (xy 171.523012 -226.446861) (xy 171.500013 -226.388838)
			(xy 171.484473 -226.328389) (xy 171.476637 -226.266467) (xy 171.476162 -226.23526) (xy 171.476663 -226.204064)
			(xy 171.484477 -226.142164) (xy 171.500002 -226.081734) (xy 171.522992 -226.023733) (xy 171.553082 -225.969077)
			(xy 171.589797 -225.918631) (xy 171.632556 -225.873196) (xy 171.680681 -225.833488) (xy 171.706794 -225.816414)
			(xy 171.716954 -225.80981) (xy 171.729146 -225.789998) (xy 171.738544 -225.685858) (xy 171.730162 -225.664268)
			(xy 171.721272 -225.655886) (xy 171.702975 -225.638382) (xy 171.670898 -225.599202) (xy 171.644481 -225.556003)
			(xy 171.624222 -225.509596) (xy 171.610502 -225.460855) (xy 171.603579 -225.410694) (xy 171.603162 -225.385376)
			(xy 171.60359 -225.360028) (xy 171.610524 -225.309809) (xy 171.624273 -225.261014) (xy 171.644578 -225.214562)
			(xy 171.671054 -225.17133) (xy 171.703204 -225.132133) (xy 171.721526 -225.114612) (xy 171.730416 -225.106484)
			(xy 171.738798 -225.08464) (xy 171.729146 -224.9805) (xy 171.716954 -224.960688) (xy 171.706794 -224.954338)
			(xy 171.680692 -224.937225) (xy 171.63257 -224.897475) (xy 171.589814 -224.852003) (xy 171.553099 -224.801527)
			(xy 171.523005 -224.746845) (xy 171.500007 -224.68882) (xy 171.484469 -224.628369) (xy 171.476635 -224.566446)
			(xy 171.476162 -224.535238) (xy 171.476646 -224.504041) (xy 171.484463 -224.44214) (xy 171.49999 -224.381711)
			(xy 171.522982 -224.323709) (xy 171.553075 -224.269053) (xy 171.589792 -224.218608) (xy 171.632553 -224.173173)
			(xy 171.68068 -224.133466) (xy 171.706794 -224.116392) (xy 171.716954 -224.109788) (xy 171.729146 -224.089976)
			(xy 171.738544 -223.985836) (xy 171.730162 -223.964246) (xy 171.721272 -223.955864) (xy 171.703013 -223.938322)
			(xy 171.670932 -223.899151) (xy 171.644511 -223.855959) (xy 171.624245 -223.80956) (xy 171.610517 -223.760825)
			(xy 171.603584 -223.71067) (xy 171.603162 -223.685354) (xy 171.603575 -223.660006) (xy 171.610513 -223.609786)
			(xy 171.624265 -223.560991) (xy 171.644572 -223.514539) (xy 171.671051 -223.471307) (xy 171.703203 -223.432111)
			(xy 171.721526 -223.41459) (xy 171.730416 -223.406462) (xy 171.738798 -223.384618) (xy 171.729146 -223.280478)
			(xy 171.716954 -223.260666) (xy 171.706794 -223.254316) (xy 171.680682 -223.237218) (xy 171.63256 -223.197466)
			(xy 171.589804 -223.151991) (xy 171.55309 -223.101513) (xy 171.522997 -223.046829) (xy 171.500001 -222.988802)
			(xy 171.484465 -222.928349) (xy 171.476634 -222.866425) (xy 171.476162 -222.835216) (xy 171.476651 -222.804053)
			(xy 171.484463 -222.742219) (xy 171.499963 -222.681851) (xy 171.522906 -222.623903) (xy 171.552932 -222.569286)
			(xy 171.589566 -222.518864) (xy 171.632231 -222.47343) (xy 171.680253 -222.433702) (xy 171.732877 -222.400307)
			(xy 171.789271 -222.37377) (xy 171.848546 -222.35451) (xy 171.909767 -222.342831) (xy 171.97197 -222.338918)
			(xy 172.034173 -222.342831) (xy 172.095394 -222.35451) (xy 172.154669 -222.37377) (xy 172.211063 -222.400307)
			(xy 172.263687 -222.433702) (xy 172.311709 -222.47343) (xy 172.354374 -222.518864) (xy 172.391008 -222.569286)
			(xy 172.421034 -222.623903) (xy 172.443977 -222.681851) (xy 172.459477 -222.742219) (xy 172.467289 -222.804053)
			(xy 172.467778 -222.835216) (xy 172.467301 -222.866425) (xy 172.459479 -222.928352) (xy 172.443949 -222.988808)
			(xy 172.420956 -223.046837) (xy 172.390864 -223.101523) (xy 172.354148 -223.152001) (xy 172.311388 -223.197473)
			(xy 172.263261 -223.23722) (xy 172.237146 -223.254316) (xy 172.226986 -223.260666) (xy 172.214794 -223.280478)
			(xy 172.205142 -223.384618) (xy 172.213524 -223.406462) (xy 172.222414 -223.41459) (xy 172.240731 -223.432115)
			(xy 172.272874 -223.471316) (xy 172.299347 -223.514549) (xy 172.319653 -223.560999) (xy 172.333408 -223.609791)
			(xy 172.340355 -223.660007) (xy 172.340778 -223.685354) (xy 172.340346 -223.710671) (xy 172.333424 -223.76083)
			(xy 172.319706 -223.80957) (xy 172.299447 -223.855975) (xy 172.27303 -223.899171) (xy 172.240952 -223.938347)
			(xy 172.222668 -223.955864) (xy 172.213778 -223.964246) (xy 172.205396 -223.985836) (xy 172.214794 -224.089976)
			(xy 172.226986 -224.109788) (xy 172.237146 -224.116392) (xy 172.263235 -224.1335) (xy 172.311355 -224.17321)
			(xy 172.354111 -224.218644) (xy 172.390827 -224.269085) (xy 172.420924 -224.323734) (xy 172.443925 -224.381728)
			(xy 172.459466 -224.442149) (xy 172.467303 -224.504044) (xy 172.467778 -224.535238) (xy 172.467318 -224.566448)
			(xy 172.459494 -224.628375) (xy 172.443961 -224.688832) (xy 172.420966 -224.746861) (xy 172.390871 -224.801547)
			(xy 172.354153 -224.852025) (xy 172.311391 -224.897496) (xy 172.263262 -224.937243) (xy 172.237146 -224.954338)
			(xy 172.226986 -224.960688) (xy 172.214794 -224.9805) (xy 172.205142 -225.08464) (xy 172.213524 -225.106484)
			(xy 172.222414 -225.114612) (xy 172.240742 -225.132126) (xy 172.272884 -225.17133) (xy 172.299356 -225.214565)
			(xy 172.319659 -225.261017) (xy 172.333413 -225.309811) (xy 172.340356 -225.360028) (xy 172.340778 -225.385376)
			(xy 172.340361 -225.410694) (xy 172.333437 -225.460853) (xy 172.319715 -225.509593) (xy 172.299454 -225.555998)
			(xy 172.273034 -225.599194) (xy 172.240953 -225.63837) (xy 172.222668 -225.655886) (xy 172.213778 -225.664268)
			(xy 172.205396 -225.685858) (xy 172.214794 -225.789998) (xy 172.226986 -225.80981) (xy 172.237146 -225.816414)
			(xy 172.263245 -225.833507) (xy 172.311365 -225.873219) (xy 172.35412 -225.918656) (xy 172.390836 -225.969098)
			(xy 172.420931 -226.02375) (xy 172.443931 -226.081745) (xy 172.45947 -226.142169) (xy 172.467304 -226.204065)
			(xy 172.467778 -226.23526) (xy 172.467335 -226.26647) (xy 172.459508 -226.328399) (xy 172.443973 -226.388855)
			(xy 172.420975 -226.446885) (xy 172.390878 -226.501571) (xy 172.354157 -226.552048) (xy 172.311394 -226.597519)
			(xy 172.263263 -226.637265) (xy 172.237146 -226.65436) (xy 172.226986 -226.66071) (xy 172.214794 -226.680522)
			(xy 172.205142 -226.784662) (xy 172.213524 -226.806506) (xy 172.222414 -226.814634) (xy 172.240753 -226.832138)
			(xy 172.272893 -226.871344) (xy 172.299364 -226.914581) (xy 172.319666 -226.961035) (xy 172.333417 -227.009831)
			(xy 172.340358 -227.06005) (xy 172.340778 -227.085398) (xy 175.57623 -227.085398) (xy 175.576715 -227.054189)
			(xy 175.584535 -226.992262) (xy 175.600063 -226.931806) (xy 175.623055 -226.873777) (xy 175.653146 -226.819091)
			(xy 175.689861 -226.768613) (xy 175.73262 -226.723141) (xy 175.780747 -226.683393) (xy 175.806862 -226.666298)
			(xy 175.817022 -226.659948) (xy 175.829214 -226.640136) (xy 175.838866 -226.535996) (xy 175.830484 -226.514152)
			(xy 175.821594 -226.506024) (xy 175.803285 -226.488491) (xy 175.771141 -226.449291) (xy 175.744666 -226.406061)
			(xy 175.724359 -226.359612) (xy 175.710602 -226.310821) (xy 175.703654 -226.260607) (xy 175.70323 -226.23526)
			(xy 175.703669 -226.209943) (xy 175.710589 -226.159785) (xy 175.724306 -226.111045) (xy 175.744563 -226.06464)
			(xy 175.770979 -226.021443) (xy 175.803057 -225.982267) (xy 175.82134 -225.96475) (xy 175.83023 -225.956368)
			(xy 175.838612 -225.934778) (xy 175.829214 -225.830638) (xy 175.817022 -225.810826) (xy 175.806862 -225.804222)
			(xy 175.780758 -225.787136) (xy 175.732643 -225.74742) (xy 175.689891 -225.701981) (xy 175.653177 -225.651537)
			(xy 175.623083 -225.596885) (xy 175.600084 -225.538889) (xy 175.584543 -225.478466) (xy 175.576706 -225.416571)
			(xy 175.57623 -225.385376) (xy 175.576698 -225.354166) (xy 175.58452 -225.292239) (xy 175.600051 -225.231783)
			(xy 175.623045 -225.173753) (xy 175.653139 -225.119067) (xy 175.689857 -225.068589) (xy 175.732618 -225.023118)
			(xy 175.780746 -224.983371) (xy 175.806862 -224.966276) (xy 175.817022 -224.959926) (xy 175.829214 -224.940114)
			(xy 175.838866 -224.835974) (xy 175.830484 -224.81413) (xy 175.821594 -224.806002) (xy 175.803274 -224.788479)
			(xy 175.771131 -224.749278) (xy 175.744658 -224.706045) (xy 175.724353 -224.659594) (xy 175.710598 -224.610802)
			(xy 175.703653 -224.560585) (xy 175.70323 -224.535238) (xy 175.703654 -224.509921) (xy 175.710577 -224.459761)
			(xy 175.724297 -224.411021) (xy 175.744557 -224.364616) (xy 175.770976 -224.32142) (xy 175.803056 -224.282244)
			(xy 175.82134 -224.264728) (xy 175.83023 -224.256346) (xy 175.838612 -224.234756) (xy 175.829214 -224.130616)
			(xy 175.817022 -224.110804) (xy 175.806862 -224.1042) (xy 175.780748 -224.087129) (xy 175.732633 -224.047411)
			(xy 175.689881 -224.001969) (xy 175.653169 -223.951523) (xy 175.623076 -223.896869) (xy 175.600078 -223.838871)
			(xy 175.584539 -223.778446) (xy 175.576704 -223.716549) (xy 175.57623 -223.685354) (xy 175.57668 -223.654144)
			(xy 175.584506 -223.592216) (xy 175.600039 -223.531759) (xy 175.623036 -223.473729) (xy 175.653132 -223.419043)
			(xy 175.689852 -223.368566) (xy 175.732615 -223.323095) (xy 175.780746 -223.283349) (xy 175.806862 -223.266254)
			(xy 175.817022 -223.259904) (xy 175.829214 -223.240092) (xy 175.838866 -223.135952) (xy 175.830484 -223.114108)
			(xy 175.821594 -223.10598) (xy 175.803264 -223.088468) (xy 175.771122 -223.049264) (xy 175.74465 -223.006029)
			(xy 175.724347 -222.959576) (xy 175.710594 -222.910782) (xy 175.703651 -222.860564) (xy 175.70323 -222.835216)
			(xy 175.703639 -222.809898) (xy 175.710565 -222.759738) (xy 175.724288 -222.710998) (xy 175.744551 -222.664593)
			(xy 175.770972 -222.621397) (xy 175.803054 -222.582222) (xy 175.82134 -222.564706) (xy 175.83023 -222.556324)
			(xy 175.838612 -222.534734) (xy 175.829214 -222.430594) (xy 175.817022 -222.410782) (xy 175.806862 -222.404178)
			(xy 175.780738 -222.387122) (xy 175.732623 -222.347401) (xy 175.689871 -222.301958) (xy 175.65316 -222.251509)
			(xy 175.623068 -222.196853) (xy 175.600072 -222.138853) (xy 175.584535 -222.078427) (xy 175.576703 -222.016528)
			(xy 175.57623 -221.985332) (xy 175.576719 -221.954169) (xy 175.584531 -221.892335) (xy 175.600031 -221.831967)
			(xy 175.622974 -221.774019) (xy 175.653 -221.719402) (xy 175.689634 -221.66898) (xy 175.732299 -221.623546)
			(xy 175.780321 -221.583818) (xy 175.832945 -221.550423) (xy 175.889339 -221.523886) (xy 175.948614 -221.504626)
			(xy 176.009835 -221.492947) (xy 176.072038 -221.489034) (xy 176.134241 -221.492947) (xy 176.195462 -221.504626)
			(xy 176.254737 -221.523886) (xy 176.311131 -221.550423) (xy 176.363755 -221.583818) (xy 176.411777 -221.623546)
			(xy 176.454442 -221.66898) (xy 176.491076 -221.719402) (xy 176.521102 -221.774019) (xy 176.544045 -221.831967)
			(xy 176.559545 -221.892335) (xy 176.567357 -221.954169) (xy 176.567846 -221.985332) (xy 180.531023 -221.985332)
			(xy 180.534958 -221.931561) (xy 180.546681 -221.878937) (xy 180.565941 -221.82858) (xy 180.592327 -221.781563)
			(xy 180.625279 -221.73889) (xy 180.664092 -221.701469) (xy 180.70794 -221.670099) (xy 180.755888 -221.645447)
			(xy 180.806915 -221.628039) (xy 180.859933 -221.618246) (xy 180.913812 -221.616277) (xy 180.967403 -221.622174)
			(xy 181.019564 -221.63581) (xy 181.069184 -221.656897) (xy 181.115205 -221.684983) (xy 181.156647 -221.719471)
			(xy 181.192625 -221.759625) (xy 181.222373 -221.804589) (xy 181.245258 -221.853406) (xy 181.26079 -221.905035)
			(xy 181.26864 -221.958375) (xy 181.269132 -221.985332) (xy 181.26864 -222.012289) (xy 181.26079 -222.065629)
			(xy 181.245258 -222.117258) (xy 181.222373 -222.166075) (xy 181.192625 -222.211039) (xy 181.156647 -222.251193)
			(xy 181.115205 -222.285681) (xy 181.069184 -222.313767) (xy 181.019564 -222.334854) (xy 180.967403 -222.34849)
			(xy 180.913812 -222.354387) (xy 180.859933 -222.352418) (xy 180.806915 -222.342625) (xy 180.755888 -222.325217)
			(xy 180.70794 -222.300565) (xy 180.664092 -222.269195) (xy 180.625279 -222.231774) (xy 180.592327 -222.189101)
			(xy 180.565941 -222.142084) (xy 180.546681 -222.091727) (xy 180.534958 -222.039103) (xy 180.531023 -221.985332)
			(xy 176.567846 -221.985332) (xy 176.567335 -222.016528) (xy 176.559522 -222.078428) (xy 176.543998 -222.138856)
			(xy 176.52101 -222.196858) (xy 176.490921 -222.251514) (xy 176.454207 -222.301959) (xy 176.41145 -222.347396)
			(xy 176.363326 -222.387103) (xy 176.337214 -222.404178) (xy 176.327054 -222.410782) (xy 176.314862 -222.430594)
			(xy 176.305464 -222.534734) (xy 176.313846 -222.556324) (xy 176.322736 -222.564706) (xy 176.34103 -222.582213)
			(xy 176.373108 -222.621392) (xy 176.399524 -222.66459) (xy 176.419784 -222.710997) (xy 176.433504 -222.759738)
			(xy 176.440429 -222.809898) (xy 176.440846 -222.835216) (xy 176.44041 -222.860563) (xy 176.433477 -222.910782)
			(xy 176.419729 -222.959577) (xy 176.399426 -223.006029) (xy 176.372951 -223.049261) (xy 176.340803 -223.088459)
			(xy 176.322482 -223.10598) (xy 176.313592 -223.114108) (xy 176.30521 -223.135952) (xy 176.314862 -223.240092)
			(xy 176.327054 -223.259904) (xy 176.337214 -223.266254) (xy 176.363315 -223.283369) (xy 176.411436 -223.32312)
			(xy 176.454192 -223.368591) (xy 176.490907 -223.419067) (xy 176.521001 -223.473749) (xy 176.543999 -223.531773)
			(xy 176.559538 -223.592224) (xy 176.567372 -223.654146) (xy 176.567846 -223.685354) (xy 176.567352 -223.71655)
			(xy 176.559536 -223.778451) (xy 176.54401 -223.83888) (xy 176.52102 -223.896882) (xy 176.490928 -223.951538)
			(xy 176.454212 -224.001983) (xy 176.411453 -224.047418) (xy 176.363327 -224.087126) (xy 176.337214 -224.1042)
			(xy 176.327054 -224.110804) (xy 176.314862 -224.130616) (xy 176.305464 -224.234756) (xy 176.313846 -224.256346)
			(xy 176.322736 -224.264728) (xy 176.341041 -224.282224) (xy 176.373117 -224.321405) (xy 176.399533 -224.364606)
			(xy 176.41979 -224.411015) (xy 176.433509 -224.459758) (xy 176.44043 -224.50992) (xy 176.440846 -224.535238)
			(xy 176.440425 -224.560586) (xy 176.433489 -224.610805) (xy 176.419738 -224.6596) (xy 176.399432 -224.706052)
			(xy 176.372955 -224.749284) (xy 176.340804 -224.788481) (xy 176.322482 -224.806002) (xy 176.313592 -224.81413)
			(xy 176.30521 -224.835974) (xy 176.314862 -224.940114) (xy 176.327054 -224.959926) (xy 176.337214 -224.966276)
			(xy 176.363325 -224.983377) (xy 176.411446 -225.023129) (xy 176.454201 -225.068603) (xy 176.490915 -225.119081)
			(xy 176.521008 -225.173764) (xy 176.544005 -225.231791) (xy 176.559542 -225.292243) (xy 176.567373 -225.354167)
			(xy 176.567846 -225.385376) (xy 176.567369 -225.416573) (xy 176.559551 -225.478474) (xy 176.544022 -225.538904)
			(xy 176.521029 -225.596906) (xy 176.490935 -225.651561) (xy 176.454217 -225.702006) (xy 176.411455 -225.747441)
			(xy 176.363328 -225.787148) (xy 176.337214 -225.804222) (xy 176.327054 -225.810826) (xy 176.314862 -225.830638)
			(xy 176.305464 -225.934778) (xy 176.313846 -225.956368) (xy 176.322736 -225.96475) (xy 176.341003 -225.982284)
			(xy 176.373083 -226.021457) (xy 176.399503 -226.06465) (xy 176.419767 -226.111051) (xy 176.433494 -226.159788)
			(xy 176.440425 -226.209944) (xy 176.440846 -226.23526) (xy 176.44044 -226.260608) (xy 176.4335 -226.310828)
			(xy 176.419747 -226.359624) (xy 176.399439 -226.406075) (xy 176.372958 -226.449307) (xy 176.340806 -226.488504)
			(xy 176.322482 -226.506024) (xy 176.313592 -226.514152) (xy 176.30521 -226.535996) (xy 176.314862 -226.640136)
			(xy 176.327054 -226.659948) (xy 176.337214 -226.666298) (xy 176.363335 -226.683384) (xy 176.411456 -226.723138)
			(xy 176.454211 -226.768615) (xy 176.490924 -226.819094) (xy 176.521016 -226.87378) (xy 176.544011 -226.931809)
			(xy 176.559545 -226.992263) (xy 176.567375 -227.054189) (xy 176.567846 -227.085398) (xy 176.567357 -227.116561)
			(xy 176.559545 -227.178395) (xy 176.544045 -227.238763) (xy 176.521102 -227.296711) (xy 176.491076 -227.351328)
			(xy 176.454442 -227.40175) (xy 176.411777 -227.447184) (xy 176.363755 -227.486912) (xy 176.311131 -227.520307)
			(xy 176.254737 -227.546844) (xy 176.195462 -227.566104) (xy 176.134241 -227.577783) (xy 176.072038 -227.581696)
			(xy 176.009835 -227.577783) (xy 175.948614 -227.566104) (xy 175.889339 -227.546844) (xy 175.832945 -227.520307)
			(xy 175.780321 -227.486912) (xy 175.732299 -227.447184) (xy 175.689634 -227.40175) (xy 175.653 -227.351328)
			(xy 175.622974 -227.296711) (xy 175.600031 -227.238763) (xy 175.584531 -227.178395) (xy 175.576719 -227.116561)
			(xy 175.57623 -227.085398) (xy 172.340778 -227.085398) (xy 172.340376 -227.110716) (xy 172.333448 -227.160876)
			(xy 172.319724 -227.209617) (xy 172.29946 -227.256021) (xy 172.273038 -227.299217) (xy 172.240954 -227.338392)
			(xy 172.222668 -227.355908) (xy 172.213778 -227.36429) (xy 172.205396 -227.38588) (xy 172.214794 -227.49002)
			(xy 172.226986 -227.509832) (xy 172.237146 -227.516436) (xy 172.263256 -227.533515) (xy 172.311375 -227.573229)
			(xy 172.35413 -227.618667) (xy 172.390845 -227.669112) (xy 172.420939 -227.723765) (xy 172.443936 -227.781763)
			(xy 172.459474 -227.842189) (xy 172.467306 -227.904086) (xy 172.467778 -227.935282) (xy 174.318437 -227.935282)
			(xy 174.322372 -227.881511) (xy 174.334095 -227.828887) (xy 174.353355 -227.77853) (xy 174.379741 -227.731513)
			(xy 174.412693 -227.68884) (xy 174.451506 -227.651419) (xy 174.495354 -227.620049) (xy 174.543302 -227.595397)
			(xy 174.594329 -227.577989) (xy 174.647347 -227.568196) (xy 174.701226 -227.566227) (xy 174.754817 -227.572124)
			(xy 174.806978 -227.58576) (xy 174.856598 -227.606847) (xy 174.902619 -227.634933) (xy 174.944061 -227.669421)
			(xy 174.980039 -227.709575) (xy 175.009787 -227.754539) (xy 175.032672 -227.803356) (xy 175.048204 -227.854985)
			(xy 175.056054 -227.908325) (xy 175.056546 -227.935282) (xy 179.020216 -227.935282) (xy 179.020631 -227.904083)
			(xy 179.028456 -227.842178) (xy 179.043992 -227.781746) (xy 179.066993 -227.723742) (xy 179.097095 -227.669086)
			(xy 179.133823 -227.618643) (xy 179.176593 -227.57321) (xy 179.22473 -227.533507) (xy 179.250848 -227.516436)
			(xy 179.261008 -227.509832) (xy 179.2732 -227.49002) (xy 179.282598 -227.38588) (xy 179.274216 -227.36429)
			(xy 179.265326 -227.355908) (xy 179.247031 -227.338402) (xy 179.214955 -227.299222) (xy 179.18854 -227.256023)
			(xy 179.168281 -227.209617) (xy 179.15456 -227.160875) (xy 179.147634 -227.110716) (xy 179.147216 -227.085398)
			(xy 179.147641 -227.06005) (xy 179.154574 -227.00983) (xy 179.168322 -226.961034) (xy 179.188627 -226.914582)
			(xy 179.215105 -226.87135) (xy 179.247257 -226.832154) (xy 179.26558 -226.814634) (xy 179.27447 -226.806506)
			(xy 179.282852 -226.784662) (xy 179.2732 -226.680522) (xy 179.261008 -226.66071) (xy 179.250848 -226.65436)
			(xy 179.224745 -226.637249) (xy 179.176625 -226.597497) (xy 179.13387 -226.552023) (xy 179.097157 -226.501547)
			(xy 179.067063 -226.446865) (xy 179.044065 -226.388841) (xy 179.028526 -226.32839) (xy 179.02069 -226.266468)
			(xy 179.020216 -226.23526) (xy 179.020692 -226.204063) (xy 179.028507 -226.142161) (xy 179.044034 -226.08173)
			(xy 179.067026 -226.023727) (xy 179.09712 -225.96907) (xy 179.13384 -225.918626) (xy 179.176603 -225.873191)
			(xy 179.224733 -225.833486) (xy 179.250848 -225.816414) (xy 179.261008 -225.80981) (xy 179.2732 -225.789998)
			(xy 179.282598 -225.685858) (xy 179.274216 -225.664268) (xy 179.265326 -225.655886) (xy 179.247021 -225.638391)
			(xy 179.214946 -225.599208) (xy 179.188531 -225.556007) (xy 179.168274 -225.509599) (xy 179.154556 -225.460856)
			(xy 179.147633 -225.410694) (xy 179.147216 -225.385376) (xy 179.147626 -225.360027) (xy 179.154562 -225.309807)
			(xy 179.168314 -225.261011) (xy 179.188621 -225.214559) (xy 179.215101 -225.171327) (xy 179.247255 -225.132132)
			(xy 179.26558 -225.114612) (xy 179.27447 -225.106484) (xy 179.282852 -225.08464) (xy 179.2732 -224.9805)
			(xy 179.261008 -224.960688) (xy 179.250848 -224.954338) (xy 179.224735 -224.937241) (xy 179.176615 -224.897487)
			(xy 179.133861 -224.852012) (xy 179.097148 -224.801534) (xy 179.067056 -224.746849) (xy 179.044059 -224.688823)
			(xy 179.028522 -224.62837) (xy 179.020689 -224.566447) (xy 179.020216 -224.535238) (xy 179.020675 -224.50404)
			(xy 179.028493 -224.442137) (xy 179.044022 -224.381706) (xy 179.067017 -224.323703) (xy 179.097113 -224.269047)
			(xy 179.133835 -224.218602) (xy 179.1766 -224.173168) (xy 179.224732 -224.133464) (xy 179.250848 -224.116392)
			(xy 179.261008 -224.109788) (xy 179.2732 -224.089976) (xy 179.282598 -223.985836) (xy 179.274216 -223.964246)
			(xy 179.265326 -223.955864) (xy 179.247059 -223.938331) (xy 179.21498 -223.899157) (xy 179.188561 -223.855963)
			(xy 179.168297 -223.809562) (xy 179.15457 -223.760826) (xy 179.147638 -223.71067) (xy 179.147216 -223.685354)
			(xy 179.147612 -223.660005) (xy 179.154551 -223.609784) (xy 179.168305 -223.560987) (xy 179.188615 -223.514535)
			(xy 179.215098 -223.471304) (xy 179.247254 -223.432109) (xy 179.26558 -223.41459) (xy 179.27447 -223.406462)
			(xy 179.282852 -223.384618) (xy 179.2732 -223.280478) (xy 179.261008 -223.260666) (xy 179.250848 -223.254316)
			(xy 179.224725 -223.237234) (xy 179.176605 -223.197478) (xy 179.133851 -223.152) (xy 179.097139 -223.10152)
			(xy 179.067048 -223.046833) (xy 179.044053 -222.988805) (xy 179.028518 -222.928351) (xy 179.020687 -222.866425)
			(xy 179.020216 -222.835216) (xy 179.020705 -222.804053) (xy 179.028517 -222.742219) (xy 179.044017 -222.681851)
			(xy 179.06696 -222.623903) (xy 179.096986 -222.569286) (xy 179.13362 -222.518864) (xy 179.176285 -222.47343)
			(xy 179.224307 -222.433702) (xy 179.276931 -222.400307) (xy 179.333325 -222.37377) (xy 179.3926 -222.35451)
			(xy 179.453821 -222.342831) (xy 179.516024 -222.338918) (xy 179.578227 -222.342831) (xy 179.639448 -222.35451)
			(xy 179.698723 -222.37377) (xy 179.755117 -222.400307) (xy 179.807741 -222.433702) (xy 179.855763 -222.47343)
			(xy 179.898428 -222.518864) (xy 179.935062 -222.569286) (xy 179.965088 -222.623903) (xy 179.988031 -222.681851)
			(xy 180.003531 -222.742219) (xy 180.011343 -222.804053) (xy 180.011832 -222.835216) (xy 180.01133 -222.866424)
			(xy 180.003509 -222.928349) (xy 179.987981 -222.988803) (xy 179.964991 -223.046832) (xy 179.934902 -223.101517)
			(xy 179.89819 -223.151995) (xy 179.855435 -223.197469) (xy 179.807313 -223.237219) (xy 179.7812 -223.254316)
			(xy 179.77104 -223.260666) (xy 179.758848 -223.280478) (xy 179.749196 -223.384618) (xy 179.757578 -223.406462)
			(xy 179.766468 -223.41459) (xy 179.784777 -223.432124) (xy 179.816922 -223.471322) (xy 179.843398 -223.514553)
			(xy 179.863705 -223.561001) (xy 179.877462 -223.609792) (xy 179.884409 -223.660007) (xy 179.884832 -223.685354)
			(xy 179.884414 -223.710672) (xy 179.877492 -223.760832) (xy 179.863771 -223.809573) (xy 179.84351 -223.855978)
			(xy 179.81709 -223.899174) (xy 179.785008 -223.938348) (xy 179.766722 -223.955864) (xy 179.757832 -223.964246)
			(xy 179.74945 -223.985836) (xy 179.758848 -224.089976) (xy 179.77104 -224.109788) (xy 179.7812 -224.116392)
			(xy 179.807302 -224.133481) (xy 179.855419 -224.173196) (xy 179.898172 -224.218634) (xy 179.934886 -224.269077)
			(xy 179.964981 -224.323729) (xy 179.98798 -224.381724) (xy 180.003521 -224.442148) (xy 180.011357 -224.504043)
			(xy 180.011832 -224.535238) (xy 180.011347 -224.566447) (xy 180.003524 -224.628372) (xy 179.987993 -224.688827)
			(xy 179.965 -224.746855) (xy 179.934909 -224.801541) (xy 179.898195 -224.852019) (xy 179.855438 -224.897492)
			(xy 179.807313 -224.937241) (xy 179.7812 -224.954338) (xy 179.77104 -224.960688) (xy 179.758848 -224.9805)
			(xy 179.749196 -225.08464) (xy 179.757578 -225.106484) (xy 179.766468 -225.114612) (xy 179.784787 -225.132135)
			(xy 179.816932 -225.171336) (xy 179.843406 -225.214569) (xy 179.863711 -225.261019) (xy 179.877466 -225.309812)
			(xy 179.88441 -225.360029) (xy 179.884832 -225.385376) (xy 179.884429 -225.410694) (xy 179.877504 -225.460855)
			(xy 179.86378 -225.509596) (xy 179.843516 -225.556001) (xy 179.817094 -225.599197) (xy 179.785009 -225.638371)
			(xy 179.766722 -225.655886) (xy 179.757832 -225.664268) (xy 179.74945 -225.685858) (xy 179.758848 -225.789998)
			(xy 179.77104 -225.80981) (xy 179.7812 -225.816414) (xy 179.807312 -225.833489) (xy 179.855429 -225.873205)
			(xy 179.898182 -225.918645) (xy 179.934895 -225.969091) (xy 179.964989 -226.023745) (xy 179.987986 -226.081742)
			(xy 180.003525 -226.142167) (xy 180.011358 -226.204065) (xy 180.011832 -226.23526) (xy 180.011364 -226.266469)
			(xy 180.003538 -226.328396) (xy 179.988005 -226.388851) (xy 179.96501 -226.446879) (xy 179.934916 -226.501565)
			(xy 179.8982 -226.552042) (xy 179.85544 -226.597515) (xy 179.807314 -226.637263) (xy 179.7812 -226.65436)
			(xy 179.77104 -226.66071) (xy 179.758848 -226.680522) (xy 179.749196 -226.784662) (xy 179.757578 -226.806506)
			(xy 179.766468 -226.814634) (xy 179.784798 -226.832147) (xy 179.816941 -226.87135) (xy 179.843414 -226.914584)
			(xy 179.863718 -226.961037) (xy 179.87747 -227.009832) (xy 179.884412 -227.06005) (xy 179.884832 -227.085398)
			(xy 183.120284 -227.085398) (xy 183.12079 -227.05419) (xy 183.128609 -226.992265) (xy 183.144136 -226.93181)
			(xy 183.167125 -226.873782) (xy 183.197214 -226.819096) (xy 183.233925 -226.768618) (xy 183.276681 -226.723144)
			(xy 183.324803 -226.683395) (xy 183.350916 -226.666298) (xy 183.361076 -226.659948) (xy 183.373268 -226.640136)
			(xy 183.38292 -226.535996) (xy 183.374538 -226.514152) (xy 183.365648 -226.506024) (xy 183.347349 -226.48848)
			(xy 183.315202 -226.449284) (xy 183.288725 -226.406056) (xy 183.268416 -226.35961) (xy 183.254657 -226.31082)
			(xy 183.247708 -226.260606) (xy 183.247284 -226.23526) (xy 183.247737 -226.209944) (xy 183.254656 -226.159786)
			(xy 183.268371 -226.111047) (xy 183.288626 -226.064643) (xy 183.315038 -226.021445) (xy 183.347112 -225.982268)
			(xy 183.365394 -225.96475) (xy 183.374284 -225.956368) (xy 183.382666 -225.934778) (xy 183.373268 -225.830638)
			(xy 183.361076 -225.810826) (xy 183.350916 -225.804222) (xy 183.324824 -225.787118) (xy 183.276707 -225.747406)
			(xy 183.233952 -225.70197) (xy 183.197237 -225.651529) (xy 183.167141 -225.59688) (xy 183.14414 -225.538886)
			(xy 183.128598 -225.478464) (xy 183.12076 -225.41657) (xy 183.120284 -225.385376) (xy 183.120773 -225.354167)
			(xy 183.128595 -225.292242) (xy 183.144124 -225.231787) (xy 183.167116 -225.173758) (xy 183.197207 -225.119072)
			(xy 183.233921 -225.068594) (xy 183.276678 -225.023122) (xy 183.324802 -224.983373) (xy 183.350916 -224.966276)
			(xy 183.361076 -224.959926) (xy 183.373268 -224.940114) (xy 183.38292 -224.835974) (xy 183.374538 -224.81413)
			(xy 183.365648 -224.806002) (xy 183.347338 -224.788469) (xy 183.315193 -224.749271) (xy 183.288717 -224.70604)
			(xy 183.268409 -224.659592) (xy 183.254653 -224.6108) (xy 183.247707 -224.560585) (xy 183.247284 -224.535238)
			(xy 183.247722 -224.509921) (xy 183.254644 -224.459763) (xy 183.268363 -224.411024) (xy 183.28862 -224.364619)
			(xy 183.315035 -224.321422) (xy 183.347111 -224.282245) (xy 183.365394 -224.264728) (xy 183.374284 -224.256346)
			(xy 183.382666 -224.234756) (xy 183.373268 -224.130616) (xy 183.361076 -224.110804) (xy 183.350916 -224.1042)
			(xy 183.324814 -224.08711) (xy 183.276697 -224.047397) (xy 183.233943 -224.001959) (xy 183.197228 -223.951516)
			(xy 183.167133 -223.896864) (xy 183.144134 -223.838868) (xy 183.128594 -223.778445) (xy 183.120758 -223.716549)
			(xy 183.120284 -223.685354) (xy 183.120756 -223.654145) (xy 183.12858 -223.592218) (xy 183.144112 -223.531763)
			(xy 183.167107 -223.473734) (xy 183.1972 -223.419049) (xy 183.233916 -223.368571) (xy 183.276675 -223.323099)
			(xy 183.324802 -223.28335) (xy 183.350916 -223.266254) (xy 183.361076 -223.259904) (xy 183.373268 -223.240092)
			(xy 183.38292 -223.135952) (xy 183.374538 -223.114108) (xy 183.365648 -223.10598) (xy 183.347328 -223.088458)
			(xy 183.315183 -223.049257) (xy 183.288709 -223.006024) (xy 183.268403 -222.959574) (xy 183.254649 -222.91078)
			(xy 183.247705 -222.860563) (xy 183.247284 -222.835216) (xy 183.247708 -222.809899) (xy 183.254632 -222.75974)
			(xy 183.268354 -222.711) (xy 183.288614 -222.664596) (xy 183.315031 -222.621399) (xy 183.34711 -222.582223)
			(xy 183.365394 -222.564706) (xy 183.374284 -222.556324) (xy 183.382666 -222.534734) (xy 183.373268 -222.430594)
			(xy 183.361076 -222.410782) (xy 183.350916 -222.404178) (xy 183.324804 -222.387103) (xy 183.276687 -222.347387)
			(xy 183.233933 -222.301947) (xy 183.197219 -222.251502) (xy 183.167126 -222.196848) (xy 183.144128 -222.13885)
			(xy 183.12859 -222.078425) (xy 183.120757 -222.016528) (xy 183.120284 -221.985332) (xy 183.120773 -221.954169)
			(xy 183.128585 -221.892335) (xy 183.144085 -221.831967) (xy 183.167028 -221.774019) (xy 183.197054 -221.719402)
			(xy 183.233688 -221.66898) (xy 183.276353 -221.623546) (xy 183.324375 -221.583818) (xy 183.376999 -221.550423)
			(xy 183.433393 -221.523886) (xy 183.492668 -221.504626) (xy 183.553889 -221.492947) (xy 183.616092 -221.489034)
			(xy 183.678295 -221.492947) (xy 183.739516 -221.504626) (xy 183.798791 -221.523886) (xy 183.855185 -221.550423)
			(xy 183.907809 -221.583818) (xy 183.955831 -221.623546) (xy 183.998496 -221.66898) (xy 184.03513 -221.719402)
			(xy 184.065156 -221.774019) (xy 184.088099 -221.831967) (xy 184.103599 -221.892335) (xy 184.111411 -221.954169)
			(xy 184.1119 -221.985332) (xy 188.075077 -221.985332) (xy 188.079012 -221.931561) (xy 188.090735 -221.878937)
			(xy 188.109995 -221.82858) (xy 188.136381 -221.781563) (xy 188.169333 -221.73889) (xy 188.208146 -221.701469)
			(xy 188.251994 -221.670099) (xy 188.299942 -221.645447) (xy 188.350969 -221.628039) (xy 188.403987 -221.618246)
			(xy 188.457866 -221.616277) (xy 188.511457 -221.622174) (xy 188.563618 -221.63581) (xy 188.613238 -221.656897)
			(xy 188.659259 -221.684983) (xy 188.700701 -221.719471) (xy 188.736679 -221.759625) (xy 188.766427 -221.804589)
			(xy 188.789312 -221.853406) (xy 188.804844 -221.905035) (xy 188.812694 -221.958375) (xy 188.813186 -221.985332)
			(xy 188.812694 -222.012289) (xy 188.804844 -222.065629) (xy 188.789312 -222.117258) (xy 188.766427 -222.166075)
			(xy 188.736679 -222.211039) (xy 188.700701 -222.251193) (xy 188.659259 -222.285681) (xy 188.613238 -222.313767)
			(xy 188.563618 -222.334854) (xy 188.511457 -222.34849) (xy 188.457866 -222.354387) (xy 188.403987 -222.352418)
			(xy 188.350969 -222.342625) (xy 188.299942 -222.325217) (xy 188.251994 -222.300565) (xy 188.208146 -222.269195)
			(xy 188.169333 -222.231774) (xy 188.136381 -222.189101) (xy 188.109995 -222.142084) (xy 188.090735 -222.091727)
			(xy 188.079012 -222.039103) (xy 188.075077 -221.985332) (xy 184.1119 -221.985332) (xy 184.11141 -222.016529)
			(xy 184.103596 -222.07843) (xy 184.088071 -222.13886) (xy 184.065081 -222.196863) (xy 184.034989 -222.251519)
			(xy 183.998271 -222.301964) (xy 183.95551 -222.347399) (xy 183.907382 -222.387105) (xy 183.881268 -222.404178)
			(xy 183.871108 -222.410782) (xy 183.858916 -222.430594) (xy 183.849518 -222.534734) (xy 183.8579 -222.556324)
			(xy 183.86679 -222.564706) (xy 183.885094 -222.582202) (xy 183.917169 -222.621385) (xy 183.943583 -222.664586)
			(xy 183.96384 -222.710994) (xy 183.977559 -222.759737) (xy 183.984483 -222.809898) (xy 183.9849 -222.835216)
			(xy 183.984479 -222.860564) (xy 183.977545 -222.910784) (xy 183.963795 -222.95958) (xy 183.94349 -223.006032)
			(xy 183.917011 -223.049264) (xy 183.884859 -223.08846) (xy 183.866536 -223.10598) (xy 183.857646 -223.114108)
			(xy 183.849264 -223.135952) (xy 183.858916 -223.240092) (xy 183.871108 -223.259904) (xy 183.881268 -223.266254)
			(xy 183.907358 -223.283385) (xy 183.955482 -223.323132) (xy 183.998239 -223.3686) (xy 184.034956 -223.419073)
			(xy 184.065052 -223.473753) (xy 184.088052 -223.531776) (xy 184.103591 -223.592225) (xy 184.111426 -223.654147)
			(xy 184.1119 -223.685354) (xy 184.111427 -223.716551) (xy 184.103611 -223.778453) (xy 184.088083 -223.838884)
			(xy 184.06509 -223.896887) (xy 184.034996 -223.951543) (xy 183.998276 -224.001988) (xy 183.955513 -224.047422)
			(xy 183.907383 -224.087127) (xy 183.881268 -224.1042) (xy 183.871108 -224.110804) (xy 183.858916 -224.130616)
			(xy 183.849518 -224.234756) (xy 183.8579 -224.256346) (xy 183.86679 -224.264728) (xy 183.885105 -224.282213)
			(xy 183.917179 -224.321398) (xy 183.943591 -224.364602) (xy 183.963846 -224.411012) (xy 183.977563 -224.459757)
			(xy 183.984484 -224.509919) (xy 183.9849 -224.535238) (xy 183.984494 -224.560587) (xy 183.977556 -224.610807)
			(xy 183.963804 -224.659603) (xy 183.943496 -224.706055) (xy 183.917015 -224.749287) (xy 183.88486 -224.788482)
			(xy 183.866536 -224.806002) (xy 183.857646 -224.81413) (xy 183.849264 -224.835974) (xy 183.858916 -224.940114)
			(xy 183.871108 -224.959926) (xy 183.881268 -224.966276) (xy 183.907368 -224.983393) (xy 183.955492 -225.023141)
			(xy 183.998249 -225.068612) (xy 184.034965 -225.119087) (xy 184.06506 -225.173769) (xy 184.088057 -225.231794)
			(xy 184.103595 -225.292245) (xy 184.111427 -225.354168) (xy 184.1119 -225.385376) (xy 184.111445 -225.416574)
			(xy 184.103625 -225.478477) (xy 184.088095 -225.538908) (xy 184.065099 -225.59691) (xy 184.035003 -225.651567)
			(xy 183.998281 -225.702011) (xy 183.955516 -225.747445) (xy 183.907384 -225.78715) (xy 183.881268 -225.804222)
			(xy 183.871108 -225.810826) (xy 183.858916 -225.830638) (xy 183.849518 -225.934778) (xy 183.8579 -225.956368)
			(xy 183.86679 -225.96475) (xy 183.885067 -225.982273) (xy 183.917144 -226.02145) (xy 183.943562 -226.064646)
			(xy 183.963824 -226.111048) (xy 183.977549 -226.159786) (xy 183.984479 -226.209943) (xy 183.9849 -226.23526)
			(xy 183.984508 -226.260609) (xy 183.977568 -226.31083) (xy 183.963813 -226.359627) (xy 183.943502 -226.406078)
			(xy 183.917018 -226.44931) (xy 183.884862 -226.488505) (xy 183.866536 -226.506024) (xy 183.857646 -226.514152)
			(xy 183.849264 -226.535996) (xy 183.858916 -226.640136) (xy 183.871108 -226.659948) (xy 183.881268 -226.666298)
			(xy 183.907378 -226.6834) (xy 183.955502 -226.72315) (xy 183.998258 -226.768623) (xy 184.034974 -226.8191)
			(xy 184.065067 -226.873784) (xy 184.088063 -226.931811) (xy 184.103599 -226.992265) (xy 184.111429 -227.054189)
			(xy 184.1119 -227.085398) (xy 184.111411 -227.116561) (xy 184.103599 -227.178395) (xy 184.088099 -227.238763)
			(xy 184.065156 -227.296711) (xy 184.03513 -227.351328) (xy 183.998496 -227.40175) (xy 183.955831 -227.447184)
			(xy 183.907809 -227.486912) (xy 183.855185 -227.520307) (xy 183.798791 -227.546844) (xy 183.739516 -227.566104)
			(xy 183.678295 -227.577783) (xy 183.616092 -227.581696) (xy 183.553889 -227.577783) (xy 183.492668 -227.566104)
			(xy 183.433393 -227.546844) (xy 183.376999 -227.520307) (xy 183.324375 -227.486912) (xy 183.276353 -227.447184)
			(xy 183.233688 -227.40175) (xy 183.197054 -227.351328) (xy 183.167028 -227.296711) (xy 183.144085 -227.238763)
			(xy 183.128585 -227.178395) (xy 183.120773 -227.116561) (xy 183.120284 -227.085398) (xy 179.884832 -227.085398)
			(xy 179.884444 -227.110717) (xy 179.877515 -227.160878) (xy 179.863789 -227.209619) (xy 179.843522 -227.256024)
			(xy 179.817097 -227.29922) (xy 179.78501 -227.338393) (xy 179.766722 -227.355908) (xy 179.757832 -227.36429)
			(xy 179.74945 -227.38588) (xy 179.758848 -227.49002) (xy 179.77104 -227.509832) (xy 179.7812 -227.516436)
			(xy 179.807322 -227.533496) (xy 179.855439 -227.573215) (xy 179.898191 -227.618657) (xy 179.934904 -227.669105)
			(xy 179.964996 -227.72376) (xy 179.987992 -227.78176) (xy 180.003529 -227.842187) (xy 180.01136 -227.904086)
			(xy 180.011832 -227.935282) (xy 181.862491 -227.935282) (xy 181.866426 -227.881511) (xy 181.878149 -227.828887)
			(xy 181.897409 -227.77853) (xy 181.923795 -227.731513) (xy 181.956747 -227.68884) (xy 181.99556 -227.651419)
			(xy 182.039408 -227.620049) (xy 182.087356 -227.595397) (xy 182.138383 -227.577989) (xy 182.191401 -227.568196)
			(xy 182.24528 -227.566227) (xy 182.298871 -227.572124) (xy 182.351032 -227.58576) (xy 182.400652 -227.606847)
			(xy 182.446673 -227.634933) (xy 182.488115 -227.669421) (xy 182.524093 -227.709575) (xy 182.553841 -227.754539)
			(xy 182.576726 -227.803356) (xy 182.592258 -227.854985) (xy 182.600108 -227.908325) (xy 182.6006 -227.935282)
			(xy 186.56427 -227.935282) (xy 186.564706 -227.904084) (xy 186.57253 -227.842181) (xy 186.588065 -227.78175)
			(xy 186.611064 -227.723747) (xy 186.641163 -227.669092) (xy 186.677887 -227.618648) (xy 186.720653 -227.573214)
			(xy 186.768786 -227.533509) (xy 186.794902 -227.516436) (xy 186.805062 -227.509832) (xy 186.817254 -227.49002)
			(xy 186.826652 -227.38588) (xy 186.81827 -227.36429) (xy 186.80938 -227.355908) (xy 186.791096 -227.338392)
			(xy 186.759017 -227.299215) (xy 186.732598 -227.256018) (xy 186.712337 -227.209614) (xy 186.698615 -227.160874)
			(xy 186.691688 -227.110715) (xy 186.69127 -227.085398) (xy 186.69171 -227.060051) (xy 186.698642 -227.009832)
			(xy 186.712388 -226.961037) (xy 186.73269 -226.914585) (xy 186.759165 -226.871353) (xy 186.791313 -226.832155)
			(xy 186.809634 -226.814634) (xy 186.818524 -226.806506) (xy 186.826906 -226.784662) (xy 186.817254 -226.680522)
			(xy 186.805062 -226.66071) (xy 186.794902 -226.65436) (xy 186.768811 -226.63723) (xy 186.720689 -226.597482)
			(xy 186.677932 -226.552013) (xy 186.641216 -226.50154) (xy 186.611121 -226.44686) (xy 186.588121 -226.388837)
			(xy 186.572581 -226.328388) (xy 186.564745 -226.266467) (xy 186.56427 -226.23526) (xy 186.564767 -226.204064)
			(xy 186.572582 -226.142163) (xy 186.588107 -226.081734) (xy 186.611097 -226.023732) (xy 186.641188 -225.969076)
			(xy 186.677904 -225.918631) (xy 186.720663 -225.873195) (xy 186.768789 -225.833488) (xy 186.794902 -225.816414)
			(xy 186.805062 -225.80981) (xy 186.817254 -225.789998) (xy 186.826652 -225.685858) (xy 186.81827 -225.664268)
			(xy 186.80938 -225.655886) (xy 186.791085 -225.63838) (xy 186.759007 -225.599201) (xy 186.73259 -225.556002)
			(xy 186.712331 -225.509596) (xy 186.69861 -225.460854) (xy 186.691687 -225.410694) (xy 186.69127 -225.385376)
			(xy 186.691695 -225.360028) (xy 186.69863 -225.309809) (xy 186.712379 -225.261014) (xy 186.732684 -225.214562)
			(xy 186.759161 -225.17133) (xy 186.791312 -225.132133) (xy 186.809634 -225.114612) (xy 186.818524 -225.106484)
			(xy 186.826906 -225.08464) (xy 186.817254 -224.9805) (xy 186.805062 -224.960688) (xy 186.794902 -224.954338)
			(xy 186.768801 -224.937222) (xy 186.720679 -224.897473) (xy 186.677923 -224.852001) (xy 186.641208 -224.801526)
			(xy 186.611113 -224.746844) (xy 186.588115 -224.68882) (xy 186.572577 -224.628369) (xy 186.564743 -224.566446)
			(xy 186.56427 -224.535238) (xy 186.56475 -224.504041) (xy 186.572567 -224.44214) (xy 186.588095 -224.38171)
			(xy 186.611087 -224.323708) (xy 186.641181 -224.269052) (xy 186.677899 -224.218607) (xy 186.72066 -224.173172)
			(xy 186.768788 -224.133466) (xy 186.794902 -224.116392) (xy 186.805062 -224.109788) (xy 186.817254 -224.089976)
			(xy 186.826652 -223.985836) (xy 186.81827 -223.964246) (xy 186.80938 -223.955864) (xy 186.791123 -223.93832)
			(xy 186.759041 -223.89915) (xy 186.732619 -223.855959) (xy 186.712354 -223.80956) (xy 186.698625 -223.760825)
			(xy 186.691692 -223.71067) (xy 186.69127 -223.685354) (xy 186.69168 -223.660006) (xy 186.698618 -223.609786)
			(xy 186.712371 -223.56099) (xy 186.732678 -223.514538) (xy 186.759158 -223.471307) (xy 186.79131 -223.43211)
			(xy 186.809634 -223.41459) (xy 186.818524 -223.406462) (xy 186.826906 -223.384618) (xy 186.817254 -223.280478)
			(xy 186.805062 -223.260666) (xy 186.794902 -223.254316) (xy 186.768791 -223.237215) (xy 186.720669 -223.197463)
			(xy 186.677913 -223.15199) (xy 186.641199 -223.101512) (xy 186.611106 -223.046828) (xy 186.58811 -222.988802)
			(xy 186.572573 -222.928349) (xy 186.564742 -222.866425) (xy 186.56427 -222.835216) (xy 186.564759 -222.804053)
			(xy 186.572571 -222.742219) (xy 186.588071 -222.681851) (xy 186.611014 -222.623903) (xy 186.64104 -222.569286)
			(xy 186.677674 -222.518864) (xy 186.720339 -222.47343) (xy 186.768361 -222.433702) (xy 186.820985 -222.400307)
			(xy 186.877379 -222.37377) (xy 186.936654 -222.35451) (xy 186.997875 -222.342831) (xy 187.060078 -222.338918)
			(xy 187.122281 -222.342831) (xy 187.183502 -222.35451) (xy 187.242777 -222.37377) (xy 187.299171 -222.400307)
			(xy 187.351795 -222.433702) (xy 187.399817 -222.47343) (xy 187.442482 -222.518864) (xy 187.479116 -222.569286)
			(xy 187.509142 -222.623903) (xy 187.532085 -222.681851) (xy 187.547585 -222.742219) (xy 187.555397 -222.804053)
			(xy 187.555886 -222.835216) (xy 187.555405 -222.866425) (xy 187.547583 -222.928352) (xy 187.532054 -222.988807)
			(xy 187.509062 -223.046837) (xy 187.47897 -223.101522) (xy 187.442254 -223.152) (xy 187.399495 -223.197473)
			(xy 187.351369 -223.23722) (xy 187.325254 -223.254316) (xy 187.315094 -223.260666) (xy 187.302902 -223.280478)
			(xy 187.29325 -223.384618) (xy 187.301632 -223.406462) (xy 187.310522 -223.41459) (xy 187.328841 -223.432113)
			(xy 187.360983 -223.471315) (xy 187.387456 -223.514548) (xy 187.407761 -223.560998) (xy 187.421517 -223.609791)
			(xy 187.428463 -223.660007) (xy 187.428886 -223.685354) (xy 187.428451 -223.710671) (xy 187.42153 -223.760829)
			(xy 187.407812 -223.809569) (xy 187.387554 -223.855974) (xy 187.361137 -223.899171) (xy 187.329059 -223.938347)
			(xy 187.310776 -223.955864) (xy 187.301886 -223.964246) (xy 187.293504 -223.985836) (xy 187.302902 -224.089976)
			(xy 187.315094 -224.109788) (xy 187.325254 -224.116392) (xy 187.351345 -224.133497) (xy 187.399464 -224.173208)
			(xy 187.44222 -224.218643) (xy 187.478936 -224.269083) (xy 187.509032 -224.323733) (xy 187.532033 -224.381727)
			(xy 187.547574 -224.442149) (xy 187.555411 -224.504044) (xy 187.555886 -224.535238) (xy 187.555422 -224.566448)
			(xy 187.547598 -224.628375) (xy 187.532066 -224.688831) (xy 187.509071 -224.74686) (xy 187.478977 -224.801546)
			(xy 187.442259 -224.852024) (xy 187.399498 -224.897495) (xy 187.351369 -224.937243) (xy 187.325254 -224.954338)
			(xy 187.315094 -224.960688) (xy 187.302902 -224.9805) (xy 187.29325 -225.08464) (xy 187.301632 -225.106484)
			(xy 187.310522 -225.114612) (xy 187.328852 -225.132125) (xy 187.360993 -225.171329) (xy 187.387464 -225.214564)
			(xy 187.407768 -225.261016) (xy 187.421521 -225.309811) (xy 187.428464 -225.360028) (xy 187.428886 -225.385376)
			(xy 187.428466 -225.410693) (xy 187.421542 -225.460853) (xy 187.407821 -225.509593) (xy 187.38756 -225.555998)
			(xy 187.361141 -225.599194) (xy 187.329061 -225.63837) (xy 187.310776 -225.655886) (xy 187.301886 -225.664268)
			(xy 187.293504 -225.685858) (xy 187.302902 -225.789998) (xy 187.315094 -225.80981) (xy 187.325254 -225.816414)
			(xy 187.351355 -225.833505) (xy 187.399474 -225.873217) (xy 187.442229 -225.918654) (xy 187.478945 -225.969097)
			(xy 187.50904 -226.023749) (xy 187.532039 -226.081745) (xy 187.547578 -226.142169) (xy 187.555412 -226.204065)
			(xy 187.555886 -226.23526) (xy 187.555439 -226.26647) (xy 187.547612 -226.328398) (xy 187.532078 -226.388855)
			(xy 187.50908 -226.446884) (xy 187.478984 -226.50157) (xy 187.442264 -226.552047) (xy 187.399501 -226.597518)
			(xy 187.35137 -226.637265) (xy 187.325254 -226.65436) (xy 187.315094 -226.66071) (xy 187.302902 -226.680522)
			(xy 187.29325 -226.784662) (xy 187.301632 -226.806506) (xy 187.310522 -226.814634) (xy 187.328862 -226.832136)
			(xy 187.361003 -226.871343) (xy 187.387473 -226.91458) (xy 187.407774 -226.961034) (xy 187.421525 -227.00983)
			(xy 187.428466 -227.06005) (xy 187.428886 -227.085398) (xy 190.664338 -227.085398) (xy 190.664819 -227.054189)
			(xy 190.672639 -226.992262) (xy 190.688168 -226.931806) (xy 190.71116 -226.873776) (xy 190.741252 -226.81909)
			(xy 190.777968 -226.768612) (xy 190.820727 -226.72314) (xy 190.868855 -226.683393) (xy 190.89497 -226.666298)
			(xy 190.90513 -226.659948) (xy 190.917322 -226.640136) (xy 190.926974 -226.535996) (xy 190.918592 -226.514152)
			(xy 190.909702 -226.506024) (xy 190.891394 -226.488489) (xy 190.85925 -226.44929) (xy 190.832775 -226.40606)
			(xy 190.812468 -226.359612) (xy 190.79871 -226.310821) (xy 190.791762 -226.260607) (xy 190.791338 -226.23526)
			(xy 190.791774 -226.209943) (xy 190.798694 -226.159784) (xy 190.812412 -226.111044) (xy 190.83267 -226.064639)
			(xy 190.859086 -226.021443) (xy 190.891164 -225.982267) (xy 190.909448 -225.96475) (xy 190.918338 -225.956368)
			(xy 190.92672 -225.934778) (xy 190.917322 -225.830638) (xy 190.90513 -225.810826) (xy 190.89497 -225.804222)
			(xy 190.868868 -225.787134) (xy 190.820752 -225.747418) (xy 190.778 -225.701979) (xy 190.741286 -225.651536)
			(xy 190.711192 -225.596884) (xy 190.688192 -225.538889) (xy 190.672651 -225.478466) (xy 190.664814 -225.416571)
			(xy 190.664338 -225.385376) (xy 190.664802 -225.354166) (xy 190.672625 -225.292239) (xy 190.688156 -225.231782)
			(xy 190.71115 -225.173752) (xy 190.741245 -225.119066) (xy 190.777963 -225.068589) (xy 190.820725 -225.023117)
			(xy 190.868854 -224.983371) (xy 190.89497 -224.966276) (xy 190.90513 -224.959926) (xy 190.917322 -224.940114)
			(xy 190.926974 -224.835974) (xy 190.918592 -224.81413) (xy 190.909702 -224.806002) (xy 190.891384 -224.788478)
			(xy 190.859241 -224.749277) (xy 190.832767 -224.706044) (xy 190.812461 -224.659594) (xy 190.798706 -224.610801)
			(xy 190.791761 -224.560585) (xy 190.791338 -224.535238) (xy 190.79176 -224.509921) (xy 190.798683 -224.459761)
			(xy 190.812403 -224.411021) (xy 190.832663 -224.364616) (xy 190.859082 -224.32142) (xy 190.891163 -224.282244)
			(xy 190.909448 -224.264728) (xy 190.918338 -224.256346) (xy 190.92672 -224.234756) (xy 190.917322 -224.130616)
			(xy 190.90513 -224.110804) (xy 190.89497 -224.1042) (xy 190.868858 -224.087126) (xy 190.820742 -224.047409)
			(xy 190.77799 -224.001968) (xy 190.741277 -223.951522) (xy 190.711184 -223.896868) (xy 190.688186 -223.838871)
			(xy 190.672647 -223.778446) (xy 190.664812 -223.716549) (xy 190.664338 -223.685354) (xy 190.664785 -223.654144)
			(xy 190.67261 -223.592215) (xy 190.688144 -223.531758) (xy 190.711141 -223.473728) (xy 190.741238 -223.419043)
			(xy 190.777958 -223.368565) (xy 190.820722 -223.323094) (xy 190.868853 -223.283349) (xy 190.89497 -223.266254)
			(xy 190.90513 -223.259904) (xy 190.917322 -223.240092) (xy 190.926974 -223.135952) (xy 190.918592 -223.114108)
			(xy 190.909702 -223.10598) (xy 190.891373 -223.088466) (xy 190.859231 -223.049263) (xy 190.832759 -223.006028)
			(xy 190.812455 -222.959576) (xy 190.798702 -222.910782) (xy 190.791759 -222.860564) (xy 190.791338 -222.835216)
			(xy 190.791745 -222.809898) (xy 190.79867 -222.759738) (xy 190.812394 -222.710997) (xy 190.832657 -222.664592)
			(xy 190.859079 -222.621396) (xy 190.891162 -222.582221) (xy 190.909448 -222.564706) (xy 190.918338 -222.556324)
			(xy 190.92672 -222.534734) (xy 190.917322 -222.430594) (xy 190.90513 -222.410782) (xy 190.89497 -222.404178)
			(xy 190.868848 -222.387119) (xy 190.820732 -222.347399) (xy 190.777981 -222.301956) (xy 190.741269 -222.251508)
			(xy 190.711177 -222.196852) (xy 190.688181 -222.138853) (xy 190.672643 -222.078426) (xy 190.664811 -222.016528)
			(xy 190.664338 -221.985332) (xy 190.664827 -221.954169) (xy 190.672639 -221.892335) (xy 190.688139 -221.831967)
			(xy 190.711082 -221.774019) (xy 190.741108 -221.719402) (xy 190.777742 -221.66898) (xy 190.820407 -221.623546)
			(xy 190.868429 -221.583818) (xy 190.921053 -221.550423) (xy 190.977447 -221.523886) (xy 191.036722 -221.504626)
			(xy 191.097943 -221.492947) (xy 191.160146 -221.489034) (xy 191.222349 -221.492947) (xy 191.28357 -221.504626)
			(xy 191.342845 -221.523886) (xy 191.399239 -221.550423) (xy 191.451863 -221.583818) (xy 191.499885 -221.623546)
			(xy 191.54255 -221.66898) (xy 191.579184 -221.719402) (xy 191.60921 -221.774019) (xy 191.632153 -221.831967)
			(xy 191.647653 -221.892335) (xy 191.655465 -221.954169) (xy 191.655954 -221.985332) (xy 195.619131 -221.985332)
			(xy 195.623066 -221.931561) (xy 195.634789 -221.878937) (xy 195.654049 -221.82858) (xy 195.680435 -221.781563)
			(xy 195.713387 -221.73889) (xy 195.7522 -221.701469) (xy 195.796048 -221.670099) (xy 195.843996 -221.645447)
			(xy 195.895023 -221.628039) (xy 195.948041 -221.618246) (xy 196.00192 -221.616277) (xy 196.055511 -221.622174)
			(xy 196.107672 -221.63581) (xy 196.157292 -221.656897) (xy 196.203313 -221.684983) (xy 196.244755 -221.719471)
			(xy 196.280733 -221.759625) (xy 196.310481 -221.804589) (xy 196.333366 -221.853406) (xy 196.348898 -221.905035)
			(xy 196.356748 -221.958375) (xy 196.35724 -221.985332) (xy 196.356748 -222.012289) (xy 196.348898 -222.065629)
			(xy 196.333366 -222.117258) (xy 196.310481 -222.166075) (xy 196.280733 -222.211039) (xy 196.244755 -222.251193)
			(xy 196.203313 -222.285681) (xy 196.157292 -222.313767) (xy 196.107672 -222.334854) (xy 196.055511 -222.34849)
			(xy 196.00192 -222.354387) (xy 195.948041 -222.352418) (xy 195.895023 -222.342625) (xy 195.843996 -222.325217)
			(xy 195.796048 -222.300565) (xy 195.7522 -222.269195) (xy 195.713387 -222.231774) (xy 195.680435 -222.189101)
			(xy 195.654049 -222.142084) (xy 195.634789 -222.091727) (xy 195.623066 -222.039103) (xy 195.619131 -221.985332)
			(xy 191.655954 -221.985332) (xy 191.655439 -222.016528) (xy 191.647626 -222.078427) (xy 191.632103 -222.138856)
			(xy 191.609115 -222.196857) (xy 191.579027 -222.251513) (xy 191.542314 -222.301958) (xy 191.499557 -222.347395)
			(xy 191.451434 -222.387103) (xy 191.425322 -222.404178) (xy 191.415162 -222.410782) (xy 191.40297 -222.430594)
			(xy 191.393572 -222.534734) (xy 191.401954 -222.556324) (xy 191.410844 -222.564706) (xy 191.42914 -222.582211)
			(xy 191.461217 -222.621391) (xy 191.487633 -222.66459) (xy 191.507892 -222.710996) (xy 191.521612 -222.759738)
			(xy 191.528537 -222.809898) (xy 191.528954 -222.835216) (xy 191.528548 -222.860565) (xy 191.521612 -222.910786)
			(xy 191.507861 -222.959582) (xy 191.487553 -223.006035) (xy 191.461071 -223.049266) (xy 191.428915 -223.088461)
			(xy 191.41059 -223.10598) (xy 191.4017 -223.114108) (xy 191.393318 -223.135952) (xy 191.40297 -223.240092)
			(xy 191.415162 -223.259904) (xy 191.425322 -223.266254) (xy 191.451425 -223.283366) (xy 191.499546 -223.323117)
			(xy 191.542301 -223.36859) (xy 191.579016 -223.419065) (xy 191.60911 -223.473748) (xy 191.632108 -223.531772)
			(xy 191.647647 -223.592223) (xy 191.655481 -223.654146) (xy 191.655954 -223.685354) (xy 191.655456 -223.71655)
			(xy 191.647641 -223.77845) (xy 191.632115 -223.838879) (xy 191.609125 -223.896881) (xy 191.579034 -223.951537)
			(xy 191.542318 -224.001982) (xy 191.49956 -224.047418) (xy 191.451435 -224.087126) (xy 191.425322 -224.1042)
			(xy 191.415162 -224.110804) (xy 191.40297 -224.130616) (xy 191.393572 -224.234756) (xy 191.401954 -224.256346)
			(xy 191.410844 -224.264728) (xy 191.42915 -224.282222) (xy 191.461227 -224.321404) (xy 191.487641 -224.364606)
			(xy 191.507898 -224.411014) (xy 191.521617 -224.459758) (xy 191.528538 -224.509919) (xy 191.528954 -224.535238)
			(xy 191.528562 -224.560587) (xy 191.521624 -224.610809) (xy 191.50787 -224.659606) (xy 191.487559 -224.706058)
			(xy 191.461075 -224.749289) (xy 191.428917 -224.788483) (xy 191.41059 -224.806002) (xy 191.4017 -224.81413)
			(xy 191.393318 -224.835974) (xy 191.40297 -224.940114) (xy 191.415162 -224.959926) (xy 191.425322 -224.966276)
			(xy 191.451435 -224.983374) (xy 191.499556 -225.023127) (xy 191.542311 -225.068601) (xy 191.579025 -225.119079)
			(xy 191.609117 -225.173763) (xy 191.632114 -225.23179) (xy 191.64765 -225.292243) (xy 191.655482 -225.354167)
			(xy 191.655954 -225.385376) (xy 191.655474 -225.416573) (xy 191.647655 -225.478474) (xy 191.632127 -225.538903)
			(xy 191.609134 -225.596905) (xy 191.579041 -225.65156) (xy 191.542323 -225.702005) (xy 191.499562 -225.747441)
			(xy 191.451435 -225.787148) (xy 191.425322 -225.804222) (xy 191.415162 -225.810826) (xy 191.40297 -225.830638)
			(xy 191.393572 -225.934778) (xy 191.401954 -225.956368) (xy 191.410844 -225.96475) (xy 191.429113 -225.982282)
			(xy 191.461192 -226.021456) (xy 191.487612 -226.064649) (xy 191.507876 -226.111051) (xy 191.521602 -226.159787)
			(xy 191.528533 -226.209944) (xy 191.528954 -226.23526) (xy 191.528577 -226.26061) (xy 191.521636 -226.310832)
			(xy 191.507879 -226.359629) (xy 191.487565 -226.406081) (xy 191.461078 -226.449312) (xy 191.428918 -226.488506)
			(xy 191.41059 -226.506024) (xy 191.4017 -226.514152) (xy 191.393318 -226.535996) (xy 191.40297 -226.640136)
			(xy 191.415162 -226.659948) (xy 191.425322 -226.666298) (xy 191.451445 -226.683381) (xy 191.499566 -226.723136)
			(xy 191.54232 -226.768613) (xy 191.579033 -226.819093) (xy 191.609125 -226.873779) (xy 191.632119 -226.931808)
			(xy 191.647654 -226.992263) (xy 191.655483 -227.054189) (xy 191.655954 -227.085398) (xy 191.655465 -227.116561)
			(xy 191.647653 -227.178395) (xy 191.632153 -227.238763) (xy 191.60921 -227.296711) (xy 191.579184 -227.351328)
			(xy 191.54255 -227.40175) (xy 191.499885 -227.447184) (xy 191.451863 -227.486912) (xy 191.399239 -227.520307)
			(xy 191.342845 -227.546844) (xy 191.28357 -227.566104) (xy 191.222349 -227.577783) (xy 191.160146 -227.581696)
			(xy 191.097943 -227.577783) (xy 191.036722 -227.566104) (xy 190.977447 -227.546844) (xy 190.921053 -227.520307)
			(xy 190.868429 -227.486912) (xy 190.820407 -227.447184) (xy 190.777742 -227.40175) (xy 190.741108 -227.351328)
			(xy 190.711082 -227.296711) (xy 190.688139 -227.238763) (xy 190.672639 -227.178395) (xy 190.664827 -227.116561)
			(xy 190.664338 -227.085398) (xy 187.428886 -227.085398) (xy 187.428481 -227.110716) (xy 187.421554 -227.160876)
			(xy 187.40783 -227.209616) (xy 187.387566 -227.256021) (xy 187.361145 -227.299217) (xy 187.329062 -227.338392)
			(xy 187.310776 -227.355908) (xy 187.301886 -227.36429) (xy 187.293504 -227.38588) (xy 187.302902 -227.49002)
			(xy 187.315094 -227.509832) (xy 187.325254 -227.516436) (xy 187.351365 -227.533512) (xy 187.399484 -227.573227)
			(xy 187.442239 -227.618666) (xy 187.478953 -227.669111) (xy 187.509047 -227.723765) (xy 187.532045 -227.781763)
			(xy 187.547582 -227.842189) (xy 187.555414 -227.904086) (xy 187.555886 -227.935282) (xy 189.406545 -227.935282)
			(xy 189.41048 -227.881511) (xy 189.422203 -227.828887) (xy 189.441463 -227.77853) (xy 189.467849 -227.731513)
			(xy 189.500801 -227.68884) (xy 189.539614 -227.651419) (xy 189.583462 -227.620049) (xy 189.63141 -227.595397)
			(xy 189.682437 -227.577989) (xy 189.735455 -227.568196) (xy 189.789334 -227.566227) (xy 189.842925 -227.572124)
			(xy 189.895086 -227.58576) (xy 189.944706 -227.606847) (xy 189.990727 -227.634933) (xy 190.032169 -227.669421)
			(xy 190.068147 -227.709575) (xy 190.097895 -227.754539) (xy 190.12078 -227.803356) (xy 190.136312 -227.854985)
			(xy 190.144162 -227.908325) (xy 190.144654 -227.935282) (xy 194.108324 -227.935282) (xy 194.108735 -227.904083)
			(xy 194.11656 -227.842178) (xy 194.132096 -227.781745) (xy 194.155098 -227.723742) (xy 194.185201 -227.669085)
			(xy 194.221929 -227.618642) (xy 194.2647 -227.573209) (xy 194.312837 -227.533507) (xy 194.338956 -227.516436)
			(xy 194.349116 -227.509832) (xy 194.361308 -227.49002) (xy 194.370706 -227.38588) (xy 194.362324 -227.36429)
			(xy 194.353434 -227.355908) (xy 194.335141 -227.338401) (xy 194.303064 -227.299221) (xy 194.276648 -227.256022)
			(xy 194.256389 -227.209616) (xy 194.242668 -227.160875) (xy 194.235742 -227.110716) (xy 194.235324 -227.085398)
			(xy 194.235747 -227.06005) (xy 194.24268 -227.00983) (xy 194.256428 -226.961034) (xy 194.276733 -226.914582)
			(xy 194.303212 -226.87135) (xy 194.335364 -226.832154) (xy 194.353688 -226.814634) (xy 194.362578 -226.806506)
			(xy 194.37096 -226.784662) (xy 194.361308 -226.680522) (xy 194.349116 -226.66071) (xy 194.338956 -226.65436)
			(xy 194.312855 -226.637246) (xy 194.264734 -226.597495) (xy 194.22198 -226.552022) (xy 194.185265 -226.501546)
			(xy 194.155171 -226.446865) (xy 194.132173 -226.38884) (xy 194.116634 -226.32839) (xy 194.108798 -226.266468)
			(xy 194.108324 -226.23526) (xy 194.108796 -226.204063) (xy 194.116612 -226.14216) (xy 194.132139 -226.081729)
			(xy 194.155131 -226.023726) (xy 194.185226 -225.969069) (xy 194.221946 -225.918625) (xy 194.26471 -225.873191)
			(xy 194.312841 -225.833486) (xy 194.338956 -225.816414) (xy 194.349116 -225.80981) (xy 194.361308 -225.789998)
			(xy 194.370706 -225.685858) (xy 194.362324 -225.664268) (xy 194.353434 -225.655886) (xy 194.33513 -225.638389)
			(xy 194.303055 -225.599207) (xy 194.27664 -225.556006) (xy 194.256383 -225.509598) (xy 194.242664 -225.460855)
			(xy 194.235741 -225.410694) (xy 194.235324 -225.385376) (xy 194.235732 -225.360027) (xy 194.242668 -225.309807)
			(xy 194.25642 -225.26101) (xy 194.276727 -225.214558) (xy 194.303208 -225.171327) (xy 194.335363 -225.132131)
			(xy 194.353688 -225.114612) (xy 194.362578 -225.106484) (xy 194.37096 -225.08464) (xy 194.361308 -224.9805)
			(xy 194.349116 -224.960688) (xy 194.338956 -224.954338) (xy 194.312845 -224.937239) (xy 194.264724 -224.897485)
			(xy 194.22197 -224.85201) (xy 194.185257 -224.801532) (xy 194.155164 -224.746849) (xy 194.132167 -224.688822)
			(xy 194.11663 -224.62837) (xy 194.108797 -224.566447) (xy 194.108324 -224.535238) (xy 194.108779 -224.50404)
			(xy 194.116597 -224.442137) (xy 194.132127 -224.381705) (xy 194.155122 -224.323702) (xy 194.185219 -224.269046)
			(xy 194.221941 -224.218601) (xy 194.264707 -224.173168) (xy 194.31284 -224.133464) (xy 194.338956 -224.116392)
			(xy 194.349116 -224.109788) (xy 194.361308 -224.089976) (xy 194.370706 -223.985836) (xy 194.362324 -223.964246)
			(xy 194.353434 -223.955864) (xy 194.335168 -223.938329) (xy 194.303089 -223.899156) (xy 194.276669 -223.855963)
			(xy 194.256405 -223.809562) (xy 194.242678 -223.760826) (xy 194.235746 -223.71067) (xy 194.235324 -223.685354)
			(xy 194.235717 -223.660005) (xy 194.242656 -223.609784) (xy 194.256411 -223.560987) (xy 194.276721 -223.514535)
			(xy 194.303205 -223.471304) (xy 194.335362 -223.432109) (xy 194.353688 -223.41459) (xy 194.362578 -223.406462)
			(xy 194.37096 -223.384618) (xy 194.361308 -223.280478) (xy 194.349116 -223.260666) (xy 194.338956 -223.254316)
			(xy 194.312835 -223.237231) (xy 194.264714 -223.197476) (xy 194.22196 -223.151999) (xy 194.185248 -223.101519)
			(xy 194.155157 -223.046833) (xy 194.132162 -222.988804) (xy 194.116626 -222.92835) (xy 194.108795 -222.866425)
			(xy 194.108324 -222.835216) (xy 194.108813 -222.804053) (xy 194.116625 -222.742219) (xy 194.132125 -222.681851)
			(xy 194.155068 -222.623903) (xy 194.185094 -222.569286) (xy 194.221728 -222.518864) (xy 194.264393 -222.47343)
			(xy 194.312415 -222.433702) (xy 194.365039 -222.400307) (xy 194.421433 -222.37377) (xy 194.480708 -222.35451)
			(xy 194.541929 -222.342831) (xy 194.604132 -222.338918) (xy 194.666335 -222.342831) (xy 194.727556 -222.35451)
			(xy 194.786831 -222.37377) (xy 194.843225 -222.400307) (xy 194.895849 -222.433702) (xy 194.943871 -222.47343)
			(xy 194.986536 -222.518864) (xy 195.02317 -222.569286) (xy 195.053196 -222.623903) (xy 195.076139 -222.681851)
			(xy 195.091639 -222.742219) (xy 195.099451 -222.804053) (xy 195.09994 -222.835216) (xy 195.099434 -222.866424)
			(xy 195.091613 -222.928349) (xy 195.076086 -222.988803) (xy 195.053096 -223.046831) (xy 195.023008 -223.101516)
			(xy 194.986296 -223.151995) (xy 194.943542 -223.197468) (xy 194.89542 -223.237218) (xy 194.869308 -223.254316)
			(xy 194.859148 -223.260666) (xy 194.846956 -223.280478) (xy 194.837304 -223.384618) (xy 194.845686 -223.406462)
			(xy 194.854576 -223.41459) (xy 194.872886 -223.432122) (xy 194.905031 -223.471321) (xy 194.931506 -223.514552)
			(xy 194.951813 -223.561001) (xy 194.96557 -223.609792) (xy 194.972517 -223.660007) (xy 194.97294 -223.685354)
			(xy 194.97252 -223.710672) (xy 194.965598 -223.760831) (xy 194.951877 -223.809572) (xy 194.931617 -223.855977)
			(xy 194.905197 -223.899173) (xy 194.873115 -223.938348) (xy 194.85483 -223.955864) (xy 194.84594 -223.964246)
			(xy 194.837558 -223.985836) (xy 194.846956 -224.089976) (xy 194.859148 -224.109788) (xy 194.869308 -224.116392)
			(xy 194.895412 -224.133479) (xy 194.943528 -224.173194) (xy 194.986281 -224.218632) (xy 195.022995 -224.269076)
			(xy 195.05309 -224.323728) (xy 195.076089 -224.381724) (xy 195.091629 -224.442147) (xy 195.099465 -224.504043)
			(xy 195.09994 -224.535238) (xy 195.099451 -224.566447) (xy 195.091628 -224.628372) (xy 195.076098 -224.688826)
			(xy 195.053105 -224.746855) (xy 195.023015 -224.80154) (xy 194.986301 -224.852018) (xy 194.943545 -224.897491)
			(xy 194.895421 -224.937241) (xy 194.869308 -224.954338) (xy 194.859148 -224.960688) (xy 194.846956 -224.9805)
			(xy 194.837304 -225.08464) (xy 194.845686 -225.106484) (xy 194.854576 -225.114612) (xy 194.872897 -225.132134)
			(xy 194.905041 -225.171335) (xy 194.931515 -225.214568) (xy 194.95182 -225.261019) (xy 194.965574 -225.309812)
			(xy 194.972518 -225.360029) (xy 194.97294 -225.385376) (xy 194.972535 -225.410694) (xy 194.965609 -225.460854)
			(xy 194.951886 -225.509595) (xy 194.931623 -225.556) (xy 194.905201 -225.599196) (xy 194.873116 -225.638371)
			(xy 194.85483 -225.655886) (xy 194.84594 -225.664268) (xy 194.837558 -225.685858) (xy 194.846956 -225.789998)
			(xy 194.859148 -225.80981) (xy 194.869308 -225.816414) (xy 194.895422 -225.833486) (xy 194.943538 -225.873203)
			(xy 194.986291 -225.918644) (xy 195.023004 -225.96909) (xy 195.053097 -226.023744) (xy 195.076095 -226.081742)
			(xy 195.091633 -226.142167) (xy 195.099466 -226.204064) (xy 195.09994 -226.23526) (xy 195.099468 -226.266469)
			(xy 195.091642 -226.328395) (xy 195.07611 -226.38885) (xy 195.053115 -226.446878) (xy 195.023022 -226.501564)
			(xy 194.986306 -226.552041) (xy 194.943547 -226.597514) (xy 194.895422 -226.637263) (xy 194.869308 -226.65436)
			(xy 194.859148 -226.66071) (xy 194.846956 -226.680522) (xy 194.837304 -226.784662) (xy 194.845686 -226.806506)
			(xy 194.854576 -226.814634) (xy 194.872908 -226.832145) (xy 194.90505 -226.871349) (xy 194.931523 -226.914584)
			(xy 194.951826 -226.961036) (xy 194.965578 -227.009832) (xy 194.97252 -227.06005) (xy 194.97294 -227.085398)
			(xy 198.208392 -227.085398) (xy 198.208894 -227.054189) (xy 198.216714 -226.992264) (xy 198.232241 -226.93181)
			(xy 198.25523 -226.873781) (xy 198.285319 -226.819095) (xy 198.322032 -226.768617) (xy 198.364787 -226.723144)
			(xy 198.412911 -226.683395) (xy 198.439024 -226.666298) (xy 198.449184 -226.659948) (xy 198.461376 -226.640136)
			(xy 198.471028 -226.535996) (xy 198.462646 -226.514152) (xy 198.453756 -226.506024) (xy 198.435459 -226.488479)
			(xy 198.403311 -226.449283) (xy 198.376834 -226.406055) (xy 198.356524 -226.359609) (xy 198.342765 -226.31082)
			(xy 198.335816 -226.260606) (xy 198.335392 -226.23526) (xy 198.335842 -226.209944) (xy 198.342761 -226.159786)
			(xy 198.356477 -226.111047) (xy 198.376732 -226.064642) (xy 198.403145 -226.021445) (xy 198.43522 -225.982267)
			(xy 198.453502 -225.96475) (xy 198.462392 -225.956368) (xy 198.470774 -225.934778) (xy 198.461376 -225.830638)
			(xy 198.449184 -225.810826) (xy 198.439024 -225.804222) (xy 198.412934 -225.787115) (xy 198.364816 -225.747404)
			(xy 198.322061 -225.701969) (xy 198.285346 -225.651528) (xy 198.255249 -225.596879) (xy 198.232248 -225.538886)
			(xy 198.216706 -225.478464) (xy 198.208868 -225.41657) (xy 198.208392 -225.385376) (xy 198.208877 -225.354167)
			(xy 198.216699 -225.292241) (xy 198.232229 -225.231786) (xy 198.255221 -225.173757) (xy 198.285312 -225.119071)
			(xy 198.322027 -225.068594) (xy 198.364785 -225.023121) (xy 198.41291 -224.983372) (xy 198.439024 -224.966276)
			(xy 198.449184 -224.959926) (xy 198.461376 -224.940114) (xy 198.471028 -224.835974) (xy 198.462646 -224.81413)
			(xy 198.453756 -224.806002) (xy 198.435448 -224.788467) (xy 198.403302 -224.74927) (xy 198.376825 -224.70604)
			(xy 198.356518 -224.659591) (xy 198.342761 -224.6108) (xy 198.335815 -224.560585) (xy 198.335392 -224.535238)
			(xy 198.335828 -224.509921) (xy 198.34275 -224.459763) (xy 198.356468 -224.411023) (xy 198.376726 -224.364619)
			(xy 198.403142 -224.321422) (xy 198.435219 -224.282245) (xy 198.453502 -224.264728) (xy 198.462392 -224.256346)
			(xy 198.470774 -224.234756) (xy 198.461376 -224.130616) (xy 198.449184 -224.110804) (xy 198.439024 -224.1042)
			(xy 198.412924 -224.087108) (xy 198.364806 -224.047395) (xy 198.322052 -224.001957) (xy 198.285337 -223.951515)
			(xy 198.255242 -223.896863) (xy 198.232242 -223.838868) (xy 198.216702 -223.778444) (xy 198.208866 -223.716549)
			(xy 198.208392 -223.685354) (xy 198.20886 -223.654144) (xy 198.216685 -223.592218) (xy 198.232217 -223.531762)
			(xy 198.255212 -223.473733) (xy 198.285305 -223.419048) (xy 198.322022 -223.36857) (xy 198.364782 -223.323098)
			(xy 198.412909 -223.28335) (xy 198.439024 -223.266254) (xy 198.449184 -223.259904) (xy 198.461376 -223.240092)
			(xy 198.471028 -223.135952) (xy 198.462646 -223.114108) (xy 198.453756 -223.10598) (xy 198.435437 -223.088456)
			(xy 198.403292 -223.049256) (xy 198.376817 -223.006024) (xy 198.356511 -222.959573) (xy 198.342757 -222.91078)
			(xy 198.335813 -222.860563) (xy 198.335392 -222.835216) (xy 198.335813 -222.809899) (xy 198.342738 -222.75974)
			(xy 198.35646 -222.711) (xy 198.37672 -222.664595) (xy 198.403138 -222.621399) (xy 198.435218 -222.582223)
			(xy 198.453502 -222.564706) (xy 198.462392 -222.556324) (xy 198.470774 -222.534734) (xy 198.461376 -222.430594)
			(xy 198.449184 -222.410782) (xy 198.439024 -222.404178) (xy 198.412914 -222.3871) (xy 198.364796 -222.347385)
			(xy 198.322042 -222.301946) (xy 198.285328 -222.251501) (xy 198.255234 -222.196847) (xy 198.232236 -222.13885)
			(xy 198.216698 -222.078425) (xy 198.208865 -222.016527) (xy 198.208392 -221.985332) (xy 198.208881 -221.954169)
			(xy 198.216693 -221.892335) (xy 198.232193 -221.831967) (xy 198.255136 -221.774019) (xy 198.285162 -221.719402)
			(xy 198.321796 -221.66898) (xy 198.364461 -221.623546) (xy 198.412483 -221.583818) (xy 198.465107 -221.550423)
			(xy 198.521501 -221.523886) (xy 198.580776 -221.504626) (xy 198.641997 -221.492947) (xy 198.7042 -221.489034)
			(xy 198.766403 -221.492947) (xy 198.827624 -221.504626) (xy 198.886899 -221.523886) (xy 198.943293 -221.550423)
			(xy 198.995917 -221.583818) (xy 199.043939 -221.623546) (xy 199.086604 -221.66898) (xy 199.123238 -221.719402)
			(xy 199.153264 -221.774019) (xy 199.176207 -221.831967) (xy 199.191707 -221.892335) (xy 199.199519 -221.954169)
			(xy 199.200008 -221.985332) (xy 203.162931 -221.985332) (xy 203.166866 -221.931561) (xy 203.178589 -221.878937)
			(xy 203.197849 -221.82858) (xy 203.224235 -221.781563) (xy 203.257187 -221.73889) (xy 203.296 -221.701469)
			(xy 203.339848 -221.670099) (xy 203.387796 -221.645447) (xy 203.438823 -221.628039) (xy 203.491841 -221.618246)
			(xy 203.54572 -221.616277) (xy 203.599311 -221.622174) (xy 203.651472 -221.63581) (xy 203.701092 -221.656897)
			(xy 203.747113 -221.684983) (xy 203.788555 -221.719471) (xy 203.824533 -221.759625) (xy 203.854281 -221.804589)
			(xy 203.877166 -221.853406) (xy 203.892698 -221.905035) (xy 203.900548 -221.958375) (xy 203.90104 -221.985332)
			(xy 203.900548 -222.012289) (xy 203.892698 -222.065629) (xy 203.877166 -222.117258) (xy 203.854281 -222.166075)
			(xy 203.824533 -222.211039) (xy 203.788555 -222.251193) (xy 203.747113 -222.285681) (xy 203.701092 -222.313767)
			(xy 203.651472 -222.334854) (xy 203.599311 -222.34849) (xy 203.54572 -222.354387) (xy 203.491841 -222.352418)
			(xy 203.438823 -222.342625) (xy 203.387796 -222.325217) (xy 203.339848 -222.300565) (xy 203.296 -222.269195)
			(xy 203.257187 -222.231774) (xy 203.224235 -222.189101) (xy 203.197849 -222.142084) (xy 203.178589 -222.091727)
			(xy 203.166866 -222.039103) (xy 203.162931 -221.985332) (xy 199.200008 -221.985332) (xy 199.199515 -222.016528)
			(xy 199.191701 -222.07843) (xy 199.176176 -222.13886) (xy 199.153186 -222.196862) (xy 199.123094 -222.251518)
			(xy 199.086378 -222.301963) (xy 199.043617 -222.347399) (xy 198.99549 -222.387105) (xy 198.969376 -222.404178)
			(xy 198.959216 -222.410782) (xy 198.947024 -222.430594) (xy 198.937626 -222.534734) (xy 198.946008 -222.556324)
			(xy 198.954898 -222.564706) (xy 198.973185 -222.58222) (xy 199.005265 -222.621397) (xy 199.031683 -222.664594)
			(xy 199.051944 -222.710999) (xy 199.065666 -222.759739) (xy 199.072591 -222.809898) (xy 199.073008 -222.835216)
			(xy 199.072585 -222.860564) (xy 199.06565 -222.910783) (xy 199.051901 -222.959579) (xy 199.031596 -223.006031)
			(xy 199.005118 -223.049263) (xy 198.972967 -223.08846) (xy 198.954644 -223.10598) (xy 198.945754 -223.114108)
			(xy 198.937372 -223.135952) (xy 198.947024 -223.240092) (xy 198.959216 -223.259904) (xy 198.969376 -223.266254)
			(xy 198.995468 -223.283382) (xy 199.043591 -223.323129) (xy 199.086349 -223.368599) (xy 199.123065 -223.419072)
			(xy 199.153161 -223.473752) (xy 199.17616 -223.531775) (xy 199.191699 -223.592225) (xy 199.199534 -223.654146)
			(xy 199.200008 -223.685354) (xy 199.199532 -223.716551) (xy 199.191715 -223.778453) (xy 199.176188 -223.838883)
			(xy 199.153195 -223.896886) (xy 199.123101 -223.951542) (xy 199.086382 -224.001987) (xy 199.04362 -224.047421)
			(xy 198.995491 -224.087127) (xy 198.969376 -224.1042) (xy 198.959216 -224.110804) (xy 198.947024 -224.130616)
			(xy 198.937626 -224.234756) (xy 198.946008 -224.256346) (xy 198.954898 -224.264728) (xy 198.973196 -224.282231)
			(xy 199.005274 -224.32141) (xy 199.031692 -224.364609) (xy 199.05195 -224.411017) (xy 199.06567 -224.459759)
			(xy 199.072592 -224.50992) (xy 199.073008 -224.535238) (xy 199.072599 -224.560587) (xy 199.065662 -224.610807)
			(xy 199.05191 -224.659603) (xy 199.031602 -224.706054) (xy 199.005122 -224.749286) (xy 198.972968 -224.788482)
			(xy 198.954644 -224.806002) (xy 198.945754 -224.81413) (xy 198.937372 -224.835974) (xy 198.947024 -224.940114)
			(xy 198.959216 -224.959926) (xy 198.969376 -224.966276) (xy 198.995478 -224.98339) (xy 199.043601 -225.023139)
			(xy 199.086358 -225.06861) (xy 199.123074 -225.119086) (xy 199.153168 -225.173768) (xy 199.176166 -225.231793)
			(xy 199.191703 -225.292245) (xy 199.199535 -225.354168) (xy 199.200008 -225.385376) (xy 199.199549 -225.416573)
			(xy 199.19173 -225.478476) (xy 199.1762 -225.538907) (xy 199.153205 -225.59691) (xy 199.123108 -225.651566)
			(xy 199.086387 -225.70201) (xy 199.043623 -225.747444) (xy 198.995491 -225.787149) (xy 198.969376 -225.804222)
			(xy 198.959216 -225.810826) (xy 198.947024 -225.830638) (xy 198.937626 -225.934778) (xy 198.946008 -225.956368)
			(xy 198.954898 -225.96475) (xy 198.973158 -225.982291) (xy 199.00524 -226.021462) (xy 199.031662 -226.064653)
			(xy 199.051928 -226.111053) (xy 199.065655 -226.159789) (xy 199.072587 -226.209944) (xy 199.073008 -226.23526)
			(xy 199.072614 -226.260609) (xy 199.065674 -226.31083) (xy 199.051919 -226.359626) (xy 199.031608 -226.406078)
			(xy 199.005125 -226.449309) (xy 198.972969 -226.488504) (xy 198.954644 -226.506024) (xy 198.945754 -226.514152)
			(xy 198.937372 -226.535996) (xy 198.947024 -226.640136) (xy 198.959216 -226.659948) (xy 198.969376 -226.666298)
			(xy 198.995488 -226.683397) (xy 199.043611 -226.723148) (xy 199.086368 -226.768622) (xy 199.123082 -226.819099)
			(xy 199.153176 -226.873784) (xy 199.176171 -226.931811) (xy 199.191707 -226.992264) (xy 199.199537 -227.054189)
			(xy 199.200008 -227.085398) (xy 199.199519 -227.116561) (xy 199.191707 -227.178395) (xy 199.176207 -227.238763)
			(xy 199.153264 -227.296711) (xy 199.123238 -227.351328) (xy 199.086604 -227.40175) (xy 199.043939 -227.447184)
			(xy 198.995917 -227.486912) (xy 198.943293 -227.520307) (xy 198.886899 -227.546844) (xy 198.827624 -227.566104)
			(xy 198.766403 -227.577783) (xy 198.7042 -227.581696) (xy 198.641997 -227.577783) (xy 198.580776 -227.566104)
			(xy 198.521501 -227.546844) (xy 198.465107 -227.520307) (xy 198.412483 -227.486912) (xy 198.364461 -227.447184)
			(xy 198.321796 -227.40175) (xy 198.285162 -227.351328) (xy 198.255136 -227.296711) (xy 198.232193 -227.238763)
			(xy 198.216693 -227.178395) (xy 198.208881 -227.116561) (xy 198.208392 -227.085398) (xy 194.97294 -227.085398)
			(xy 194.972549 -227.110717) (xy 194.965621 -227.160878) (xy 194.951895 -227.209619) (xy 194.931629 -227.256024)
			(xy 194.905204 -227.299219) (xy 194.873117 -227.338393) (xy 194.85483 -227.355908) (xy 194.84594 -227.36429)
			(xy 194.837558 -227.38588) (xy 194.846956 -227.49002) (xy 194.859148 -227.509832) (xy 194.869308 -227.516436)
			(xy 194.895432 -227.533493) (xy 194.943548 -227.573212) (xy 194.9863 -227.618655) (xy 195.023013 -227.669104)
			(xy 195.053105 -227.72376) (xy 195.0761 -227.78176) (xy 195.091637 -227.842187) (xy 195.099468 -227.904086)
			(xy 195.09994 -227.935282) (xy 196.950599 -227.935282) (xy 196.954534 -227.881511) (xy 196.966257 -227.828887)
			(xy 196.985517 -227.77853) (xy 197.011903 -227.731513) (xy 197.044855 -227.68884) (xy 197.083668 -227.651419)
			(xy 197.127516 -227.620049) (xy 197.175464 -227.595397) (xy 197.226491 -227.577989) (xy 197.279509 -227.568196)
			(xy 197.333388 -227.566227) (xy 197.386979 -227.572124) (xy 197.43914 -227.58576) (xy 197.48876 -227.606847)
			(xy 197.534781 -227.634933) (xy 197.576223 -227.669421) (xy 197.612201 -227.709575) (xy 197.641949 -227.754539)
			(xy 197.664834 -227.803356) (xy 197.680366 -227.854985) (xy 197.688216 -227.908325) (xy 197.688708 -227.935282)
			(xy 201.652124 -227.935282) (xy 201.652535 -227.904083) (xy 201.66036 -227.842178) (xy 201.675896 -227.781745)
			(xy 201.698898 -227.723742) (xy 201.729001 -227.669085) (xy 201.765729 -227.618642) (xy 201.8085 -227.573209)
			(xy 201.856637 -227.533507) (xy 201.882756 -227.516436) (xy 201.892916 -227.509832) (xy 201.905108 -227.49002)
			(xy 201.914506 -227.38588) (xy 201.906124 -227.36429) (xy 201.897234 -227.355908) (xy 201.878941 -227.338401)
			(xy 201.846864 -227.299221) (xy 201.820448 -227.256022) (xy 201.800189 -227.209616) (xy 201.786468 -227.160875)
			(xy 201.779542 -227.110716) (xy 201.779124 -227.085398) (xy 201.779547 -227.06005) (xy 201.78648 -227.00983)
			(xy 201.800228 -226.961034) (xy 201.820533 -226.914582) (xy 201.847012 -226.87135) (xy 201.879164 -226.832154)
			(xy 201.897488 -226.814634) (xy 201.906378 -226.806506) (xy 201.91476 -226.784662) (xy 201.905108 -226.680522)
			(xy 201.892916 -226.66071) (xy 201.882756 -226.65436) (xy 201.856655 -226.637246) (xy 201.808534 -226.597495)
			(xy 201.76578 -226.552022) (xy 201.729065 -226.501546) (xy 201.698971 -226.446865) (xy 201.675973 -226.38884)
			(xy 201.660434 -226.32839) (xy 201.652598 -226.266468) (xy 201.652124 -226.23526) (xy 201.652596 -226.204063)
			(xy 201.660412 -226.14216) (xy 201.675939 -226.081729) (xy 201.698931 -226.023726) (xy 201.729026 -225.969069)
			(xy 201.765746 -225.918625) (xy 201.80851 -225.873191) (xy 201.856641 -225.833486) (xy 201.882756 -225.816414)
			(xy 201.892916 -225.80981) (xy 201.905108 -225.789998) (xy 201.914506 -225.685858) (xy 201.906124 -225.664268)
			(xy 201.897234 -225.655886) (xy 201.87893 -225.638389) (xy 201.846855 -225.599207) (xy 201.82044 -225.556006)
			(xy 201.800183 -225.509598) (xy 201.786464 -225.460855) (xy 201.779541 -225.410694) (xy 201.779124 -225.385376)
			(xy 201.779532 -225.360027) (xy 201.786468 -225.309807) (xy 201.80022 -225.26101) (xy 201.820527 -225.214558)
			(xy 201.847008 -225.171327) (xy 201.879163 -225.132131) (xy 201.897488 -225.114612) (xy 201.906378 -225.106484)
			(xy 201.91476 -225.08464) (xy 201.905108 -224.9805) (xy 201.892916 -224.960688) (xy 201.882756 -224.954338)
			(xy 201.856645 -224.937239) (xy 201.808524 -224.897485) (xy 201.76577 -224.85201) (xy 201.729057 -224.801532)
			(xy 201.698964 -224.746849) (xy 201.675967 -224.688822) (xy 201.66043 -224.62837) (xy 201.652597 -224.566447)
			(xy 201.652124 -224.535238) (xy 201.652579 -224.50404) (xy 201.660397 -224.442137) (xy 201.675927 -224.381705)
			(xy 201.698922 -224.323702) (xy 201.729019 -224.269046) (xy 201.765741 -224.218601) (xy 201.808507 -224.173168)
			(xy 201.85664 -224.133464) (xy 201.882756 -224.116392) (xy 201.892916 -224.109788) (xy 201.905108 -224.089976)
			(xy 201.914506 -223.985836) (xy 201.906124 -223.964246) (xy 201.897234 -223.955864) (xy 201.878968 -223.938329)
			(xy 201.846889 -223.899156) (xy 201.820469 -223.855963) (xy 201.800205 -223.809562) (xy 201.786478 -223.760826)
			(xy 201.779546 -223.71067) (xy 201.779124 -223.685354) (xy 201.779517 -223.660005) (xy 201.786456 -223.609784)
			(xy 201.800211 -223.560987) (xy 201.820521 -223.514535) (xy 201.847005 -223.471304) (xy 201.879162 -223.432109)
			(xy 201.897488 -223.41459) (xy 201.906378 -223.406462) (xy 201.91476 -223.384618) (xy 201.905108 -223.280478)
			(xy 201.892916 -223.260666) (xy 201.882756 -223.254316) (xy 201.856635 -223.237231) (xy 201.808514 -223.197476)
			(xy 201.76576 -223.151999) (xy 201.729048 -223.101519) (xy 201.698957 -223.046833) (xy 201.675962 -222.988804)
			(xy 201.660426 -222.92835) (xy 201.652595 -222.866425) (xy 201.652124 -222.835216) (xy 201.652613 -222.804053)
			(xy 201.660425 -222.742219) (xy 201.675925 -222.681851) (xy 201.698868 -222.623903) (xy 201.728894 -222.569286)
			(xy 201.765528 -222.518864) (xy 201.808193 -222.47343) (xy 201.856215 -222.433702) (xy 201.908839 -222.400307)
			(xy 201.965233 -222.37377) (xy 202.024508 -222.35451) (xy 202.085729 -222.342831) (xy 202.147932 -222.338918)
			(xy 202.210135 -222.342831) (xy 202.271356 -222.35451) (xy 202.330631 -222.37377) (xy 202.387025 -222.400307)
			(xy 202.439649 -222.433702) (xy 202.487671 -222.47343) (xy 202.530336 -222.518864) (xy 202.56697 -222.569286)
			(xy 202.596996 -222.623903) (xy 202.619939 -222.681851) (xy 202.635439 -222.742219) (xy 202.643251 -222.804053)
			(xy 202.64374 -222.835216) (xy 202.643234 -222.866424) (xy 202.635413 -222.928349) (xy 202.619886 -222.988803)
			(xy 202.596896 -223.046831) (xy 202.566808 -223.101516) (xy 202.530096 -223.151995) (xy 202.487342 -223.197468)
			(xy 202.43922 -223.237218) (xy 202.413108 -223.254316) (xy 202.402948 -223.260666) (xy 202.390756 -223.280478)
			(xy 202.381104 -223.384618) (xy 202.389486 -223.406462) (xy 202.398376 -223.41459) (xy 202.416686 -223.432122)
			(xy 202.448831 -223.471321) (xy 202.475306 -223.514552) (xy 202.495613 -223.561001) (xy 202.50937 -223.609792)
			(xy 202.516317 -223.660007) (xy 202.51674 -223.685354) (xy 202.51632 -223.710672) (xy 202.509398 -223.760831)
			(xy 202.495677 -223.809572) (xy 202.475417 -223.855977) (xy 202.448997 -223.899173) (xy 202.416915 -223.938348)
			(xy 202.39863 -223.955864) (xy 202.38974 -223.964246) (xy 202.381358 -223.985836) (xy 202.390756 -224.089976)
			(xy 202.402948 -224.109788) (xy 202.413108 -224.116392) (xy 202.439212 -224.133479) (xy 202.487328 -224.173194)
			(xy 202.530081 -224.218632) (xy 202.566795 -224.269076) (xy 202.59689 -224.323728) (xy 202.619889 -224.381724)
			(xy 202.635429 -224.442147) (xy 202.643265 -224.504043) (xy 202.64374 -224.535238) (xy 202.643251 -224.566447)
			(xy 202.635428 -224.628372) (xy 202.619898 -224.688826) (xy 202.596905 -224.746855) (xy 202.566815 -224.80154)
			(xy 202.530101 -224.852018) (xy 202.487345 -224.897491) (xy 202.439221 -224.937241) (xy 202.413108 -224.954338)
			(xy 202.402948 -224.960688) (xy 202.390756 -224.9805) (xy 202.381104 -225.08464) (xy 202.389486 -225.106484)
			(xy 202.398376 -225.114612) (xy 202.416697 -225.132134) (xy 202.448841 -225.171335) (xy 202.475315 -225.214568)
			(xy 202.49562 -225.261019) (xy 202.509374 -225.309812) (xy 202.516318 -225.360029) (xy 202.51674 -225.385376)
			(xy 202.516335 -225.410694) (xy 202.509409 -225.460854) (xy 202.495686 -225.509595) (xy 202.475423 -225.556)
			(xy 202.449001 -225.599196) (xy 202.416916 -225.638371) (xy 202.39863 -225.655886) (xy 202.38974 -225.664268)
			(xy 202.381358 -225.685858) (xy 202.390756 -225.789998) (xy 202.402948 -225.80981) (xy 202.413108 -225.816414)
			(xy 202.439222 -225.833486) (xy 202.487338 -225.873203) (xy 202.530091 -225.918644) (xy 202.566804 -225.96909)
			(xy 202.596897 -226.023744) (xy 202.619895 -226.081742) (xy 202.635433 -226.142167) (xy 202.643266 -226.204064)
			(xy 202.64374 -226.23526) (xy 202.643268 -226.266469) (xy 202.635442 -226.328395) (xy 202.61991 -226.38885)
			(xy 202.596915 -226.446878) (xy 202.566822 -226.501564) (xy 202.530106 -226.552041) (xy 202.487347 -226.597514)
			(xy 202.439222 -226.637263) (xy 202.413108 -226.65436) (xy 202.402948 -226.66071) (xy 202.390756 -226.680522)
			(xy 202.381104 -226.784662) (xy 202.389486 -226.806506) (xy 202.398376 -226.814634) (xy 202.416708 -226.832145)
			(xy 202.44885 -226.871349) (xy 202.475323 -226.914584) (xy 202.495626 -226.961036) (xy 202.509378 -227.009832)
			(xy 202.51632 -227.06005) (xy 202.51674 -227.085398) (xy 205.752192 -227.085398) (xy 205.752694 -227.054189)
			(xy 205.760514 -226.992264) (xy 205.776041 -226.93181) (xy 205.79903 -226.873781) (xy 205.829119 -226.819095)
			(xy 205.865832 -226.768617) (xy 205.908587 -226.723144) (xy 205.956711 -226.683395) (xy 205.982824 -226.666298)
			(xy 205.992984 -226.659948) (xy 206.005176 -226.640136) (xy 206.014828 -226.535996) (xy 206.006446 -226.514152)
			(xy 205.997556 -226.506024) (xy 205.979259 -226.488479) (xy 205.947111 -226.449283) (xy 205.920634 -226.406055)
			(xy 205.900324 -226.359609) (xy 205.886565 -226.31082) (xy 205.879616 -226.260606) (xy 205.879192 -226.23526)
			(xy 205.879642 -226.209944) (xy 205.886561 -226.159786) (xy 205.900277 -226.111047) (xy 205.920532 -226.064642)
			(xy 205.946945 -226.021445) (xy 205.97902 -225.982267) (xy 205.997302 -225.96475) (xy 206.006192 -225.956368)
			(xy 206.014574 -225.934778) (xy 206.005176 -225.830638) (xy 205.992984 -225.810826) (xy 205.982824 -225.804222)
			(xy 205.956734 -225.787115) (xy 205.908616 -225.747404) (xy 205.865861 -225.701969) (xy 205.829146 -225.651528)
			(xy 205.799049 -225.596879) (xy 205.776048 -225.538886) (xy 205.760506 -225.478464) (xy 205.752668 -225.41657)
			(xy 205.752192 -225.385376) (xy 205.752677 -225.354167) (xy 205.760499 -225.292241) (xy 205.776029 -225.231786)
			(xy 205.799021 -225.173757) (xy 205.829112 -225.119071) (xy 205.865827 -225.068594) (xy 205.908585 -225.023121)
			(xy 205.95671 -224.983372) (xy 205.982824 -224.966276) (xy 205.992984 -224.959926) (xy 206.005176 -224.940114)
			(xy 206.014828 -224.835974) (xy 206.006446 -224.81413) (xy 205.997556 -224.806002) (xy 205.979248 -224.788467)
			(xy 205.947102 -224.74927) (xy 205.920625 -224.70604) (xy 205.900318 -224.659591) (xy 205.886561 -224.6108)
			(xy 205.879615 -224.560585) (xy 205.879192 -224.535238) (xy 205.879628 -224.509921) (xy 205.88655 -224.459763)
			(xy 205.900268 -224.411023) (xy 205.920526 -224.364619) (xy 205.946942 -224.321422) (xy 205.979019 -224.282245)
			(xy 205.997302 -224.264728) (xy 206.006192 -224.256346) (xy 206.014574 -224.234756) (xy 206.005176 -224.130616)
			(xy 205.992984 -224.110804) (xy 205.982824 -224.1042) (xy 205.956724 -224.087108) (xy 205.908606 -224.047395)
			(xy 205.865852 -224.001957) (xy 205.829137 -223.951515) (xy 205.799042 -223.896863) (xy 205.776042 -223.838868)
			(xy 205.760502 -223.778444) (xy 205.752666 -223.716549) (xy 205.752192 -223.685354) (xy 205.75266 -223.654144)
			(xy 205.760485 -223.592218) (xy 205.776017 -223.531762) (xy 205.799012 -223.473733) (xy 205.829105 -223.419048)
			(xy 205.865822 -223.36857) (xy 205.908582 -223.323098) (xy 205.956709 -223.28335) (xy 205.982824 -223.266254)
			(xy 205.992984 -223.259904) (xy 206.005176 -223.240092) (xy 206.014828 -223.135952) (xy 206.006446 -223.114108)
			(xy 205.997556 -223.10598) (xy 205.979237 -223.088456) (xy 205.947092 -223.049256) (xy 205.920617 -223.006024)
			(xy 205.900311 -222.959573) (xy 205.886557 -222.91078) (xy 205.879613 -222.860563) (xy 205.879192 -222.835216)
			(xy 205.879613 -222.809899) (xy 205.886538 -222.75974) (xy 205.90026 -222.711) (xy 205.92052 -222.664595)
			(xy 205.946938 -222.621399) (xy 205.979018 -222.582223) (xy 205.997302 -222.564706) (xy 206.006192 -222.556324)
			(xy 206.014574 -222.534734) (xy 206.005176 -222.430594) (xy 205.992984 -222.410782) (xy 205.982824 -222.404178)
			(xy 205.956714 -222.3871) (xy 205.908596 -222.347385) (xy 205.865842 -222.301946) (xy 205.829128 -222.251501)
			(xy 205.799034 -222.196847) (xy 205.776036 -222.13885) (xy 205.760498 -222.078425) (xy 205.752665 -222.016527)
			(xy 205.752192 -221.985332) (xy 205.752681 -221.954169) (xy 205.760493 -221.892335) (xy 205.775993 -221.831967)
			(xy 205.798936 -221.774019) (xy 205.828962 -221.719402) (xy 205.865596 -221.66898) (xy 205.908261 -221.623546)
			(xy 205.956283 -221.583818) (xy 206.008907 -221.550423) (xy 206.065301 -221.523886) (xy 206.124576 -221.504626)
			(xy 206.185797 -221.492947) (xy 206.248 -221.489034) (xy 206.310203 -221.492947) (xy 206.371424 -221.504626)
			(xy 206.430699 -221.523886) (xy 206.487093 -221.550423) (xy 206.539717 -221.583818) (xy 206.587739 -221.623546)
			(xy 206.630404 -221.66898) (xy 206.667038 -221.719402) (xy 206.697064 -221.774019) (xy 206.720007 -221.831967)
			(xy 206.735507 -221.892335) (xy 206.743319 -221.954169) (xy 206.743808 -221.985332) (xy 206.743315 -222.016528)
			(xy 206.735501 -222.07843) (xy 206.719976 -222.13886) (xy 206.696986 -222.196862) (xy 206.666894 -222.251518)
			(xy 206.630178 -222.301963) (xy 206.587417 -222.347399) (xy 206.53929 -222.387105) (xy 206.513176 -222.404178)
			(xy 206.503016 -222.410782) (xy 206.490824 -222.430594) (xy 206.481426 -222.534734) (xy 206.489808 -222.556324)
			(xy 206.498698 -222.564706) (xy 206.516985 -222.58222) (xy 206.549065 -222.621397) (xy 206.575483 -222.664594)
			(xy 206.595744 -222.710999) (xy 206.609466 -222.759739) (xy 206.616391 -222.809898) (xy 206.616808 -222.835216)
			(xy 206.616385 -222.860564) (xy 206.60945 -222.910783) (xy 206.595701 -222.959579) (xy 206.575396 -223.006031)
			(xy 206.548918 -223.049263) (xy 206.516767 -223.08846) (xy 206.498444 -223.10598) (xy 206.489554 -223.114108)
			(xy 206.481172 -223.135952) (xy 206.490824 -223.240092) (xy 206.503016 -223.259904) (xy 206.513176 -223.266254)
			(xy 206.539268 -223.283382) (xy 206.587391 -223.323129) (xy 206.630149 -223.368599) (xy 206.666865 -223.419072)
			(xy 206.696961 -223.473752) (xy 206.71996 -223.531775) (xy 206.735499 -223.592225) (xy 206.743334 -223.654146)
			(xy 206.743808 -223.685354) (xy 206.743332 -223.716551) (xy 206.735515 -223.778453) (xy 206.719988 -223.838883)
			(xy 206.696995 -223.896886) (xy 206.666901 -223.951542) (xy 206.630182 -224.001987) (xy 206.58742 -224.047421)
			(xy 206.539291 -224.087127) (xy 206.513176 -224.1042) (xy 206.503016 -224.110804) (xy 206.490824 -224.130616)
			(xy 206.481426 -224.234756) (xy 206.489808 -224.256346) (xy 206.498698 -224.264728) (xy 206.516996 -224.282231)
			(xy 206.549074 -224.32141) (xy 206.575492 -224.364609) (xy 206.59575 -224.411017) (xy 206.60947 -224.459759)
			(xy 206.616392 -224.50992) (xy 206.616808 -224.535238) (xy 206.616399 -224.560587) (xy 206.609462 -224.610807)
			(xy 206.59571 -224.659603) (xy 206.575402 -224.706054) (xy 206.548922 -224.749286) (xy 206.516768 -224.788482)
			(xy 206.498444 -224.806002) (xy 206.489554 -224.81413) (xy 206.481172 -224.835974) (xy 206.490824 -224.940114)
			(xy 206.503016 -224.959926) (xy 206.513176 -224.966276) (xy 206.539278 -224.98339) (xy 206.587401 -225.023139)
			(xy 206.630158 -225.06861) (xy 206.666874 -225.119086) (xy 206.696968 -225.173768) (xy 206.719966 -225.231793)
			(xy 206.735503 -225.292245) (xy 206.743335 -225.354168) (xy 206.743808 -225.385376) (xy 206.743349 -225.416573)
			(xy 206.73553 -225.478476) (xy 206.72 -225.538907) (xy 206.697005 -225.59691) (xy 206.666908 -225.651566)
			(xy 206.630187 -225.70201) (xy 206.587423 -225.747444) (xy 206.539291 -225.787149) (xy 206.513176 -225.804222)
			(xy 206.503016 -225.810826) (xy 206.490824 -225.830638) (xy 206.481426 -225.934778) (xy 206.489808 -225.956368)
			(xy 206.498698 -225.96475) (xy 206.516958 -225.982291) (xy 206.54904 -226.021462) (xy 206.575462 -226.064653)
			(xy 206.595728 -226.111053) (xy 206.609455 -226.159789) (xy 206.616387 -226.209944) (xy 206.616808 -226.23526)
			(xy 206.616414 -226.260609) (xy 206.609474 -226.31083) (xy 206.595719 -226.359626) (xy 206.575408 -226.406078)
			(xy 206.548925 -226.449309) (xy 206.516769 -226.488504) (xy 206.498444 -226.506024) (xy 206.489554 -226.514152)
			(xy 206.481172 -226.535996) (xy 206.490824 -226.640136) (xy 206.503016 -226.659948) (xy 206.513176 -226.666298)
			(xy 206.539288 -226.683397) (xy 206.587411 -226.723148) (xy 206.630168 -226.768622) (xy 206.666882 -226.819099)
			(xy 206.696976 -226.873784) (xy 206.719971 -226.931811) (xy 206.735507 -226.992264) (xy 206.743337 -227.054189)
			(xy 206.743808 -227.085398) (xy 206.743319 -227.116561) (xy 206.735507 -227.178395) (xy 206.720007 -227.238763)
			(xy 206.697064 -227.296711) (xy 206.667038 -227.351328) (xy 206.630404 -227.40175) (xy 206.587739 -227.447184)
			(xy 206.539717 -227.486912) (xy 206.487093 -227.520307) (xy 206.430699 -227.546844) (xy 206.371424 -227.566104)
			(xy 206.310203 -227.577783) (xy 206.248 -227.581696) (xy 206.185797 -227.577783) (xy 206.124576 -227.566104)
			(xy 206.065301 -227.546844) (xy 206.008907 -227.520307) (xy 205.956283 -227.486912) (xy 205.908261 -227.447184)
			(xy 205.865596 -227.40175) (xy 205.828962 -227.351328) (xy 205.798936 -227.296711) (xy 205.775993 -227.238763)
			(xy 205.760493 -227.178395) (xy 205.752681 -227.116561) (xy 205.752192 -227.085398) (xy 202.51674 -227.085398)
			(xy 202.516349 -227.110717) (xy 202.509421 -227.160878) (xy 202.495695 -227.209619) (xy 202.475429 -227.256024)
			(xy 202.449004 -227.299219) (xy 202.416917 -227.338393) (xy 202.39863 -227.355908) (xy 202.38974 -227.36429)
			(xy 202.381358 -227.38588) (xy 202.390756 -227.49002) (xy 202.402948 -227.509832) (xy 202.413108 -227.516436)
			(xy 202.439232 -227.533493) (xy 202.487348 -227.573212) (xy 202.5301 -227.618655) (xy 202.566813 -227.669104)
			(xy 202.596905 -227.72376) (xy 202.6199 -227.78176) (xy 202.635437 -227.842187) (xy 202.643268 -227.904086)
			(xy 202.64374 -227.935282) (xy 204.494399 -227.935282) (xy 204.498334 -227.881511) (xy 204.510057 -227.828887)
			(xy 204.529317 -227.77853) (xy 204.555703 -227.731513) (xy 204.588655 -227.68884) (xy 204.627468 -227.651419)
			(xy 204.671316 -227.620049) (xy 204.719264 -227.595397) (xy 204.770291 -227.577989) (xy 204.823309 -227.568196)
			(xy 204.877188 -227.566227) (xy 204.930779 -227.572124) (xy 204.98294 -227.58576) (xy 205.03256 -227.606847)
			(xy 205.078581 -227.634933) (xy 205.120023 -227.669421) (xy 205.156001 -227.709575) (xy 205.185749 -227.754539)
			(xy 205.208634 -227.803356) (xy 205.224166 -227.854985) (xy 205.232016 -227.908325) (xy 205.232508 -227.935282)
			(xy 205.232016 -227.962239) (xy 205.224166 -228.015579) (xy 205.208634 -228.067208) (xy 205.185749 -228.116025)
			(xy 205.156001 -228.160989) (xy 205.120023 -228.201143) (xy 205.078581 -228.235631) (xy 205.03256 -228.263717)
			(xy 204.98294 -228.284804) (xy 204.930779 -228.29844) (xy 204.877188 -228.304337) (xy 204.823309 -228.302368)
			(xy 204.770291 -228.292575) (xy 204.719264 -228.275167) (xy 204.671316 -228.250515) (xy 204.627468 -228.219145)
			(xy 204.588655 -228.181724) (xy 204.555703 -228.139051) (xy 204.529317 -228.092034) (xy 204.510057 -228.041677)
			(xy 204.498334 -227.989053) (xy 204.494399 -227.935282) (xy 202.64374 -227.935282) (xy 202.643251 -227.966445)
			(xy 202.635439 -228.028279) (xy 202.619939 -228.088647) (xy 202.596996 -228.146595) (xy 202.56697 -228.201212)
			(xy 202.530336 -228.251634) (xy 202.487671 -228.297068) (xy 202.439649 -228.336796) (xy 202.387025 -228.370191)
			(xy 202.330631 -228.396728) (xy 202.271356 -228.415988) (xy 202.210135 -228.427667) (xy 202.147932 -228.43158)
			(xy 202.085729 -228.427667) (xy 202.024508 -228.415988) (xy 201.965233 -228.396728) (xy 201.908839 -228.370191)
			(xy 201.856215 -228.336796) (xy 201.808193 -228.297068) (xy 201.765528 -228.251634) (xy 201.728894 -228.201212)
			(xy 201.698868 -228.146595) (xy 201.675925 -228.088647) (xy 201.660425 -228.028279) (xy 201.652613 -227.966445)
			(xy 201.652124 -227.935282) (xy 197.688708 -227.935282) (xy 197.688216 -227.962239) (xy 197.680366 -228.015579)
			(xy 197.664834 -228.067208) (xy 197.641949 -228.116025) (xy 197.612201 -228.160989) (xy 197.576223 -228.201143)
			(xy 197.534781 -228.235631) (xy 197.48876 -228.263717) (xy 197.43914 -228.284804) (xy 197.386979 -228.29844)
			(xy 197.333388 -228.304337) (xy 197.279509 -228.302368) (xy 197.226491 -228.292575) (xy 197.175464 -228.275167)
			(xy 197.127516 -228.250515) (xy 197.083668 -228.219145) (xy 197.044855 -228.181724) (xy 197.011903 -228.139051)
			(xy 196.985517 -228.092034) (xy 196.966257 -228.041677) (xy 196.954534 -227.989053) (xy 196.950599 -227.935282)
			(xy 195.09994 -227.935282) (xy 195.099451 -227.966445) (xy 195.091639 -228.028279) (xy 195.076139 -228.088647)
			(xy 195.053196 -228.146595) (xy 195.02317 -228.201212) (xy 194.986536 -228.251634) (xy 194.943871 -228.297068)
			(xy 194.895849 -228.336796) (xy 194.843225 -228.370191) (xy 194.786831 -228.396728) (xy 194.727556 -228.415988)
			(xy 194.666335 -228.427667) (xy 194.604132 -228.43158) (xy 194.541929 -228.427667) (xy 194.480708 -228.415988)
			(xy 194.421433 -228.396728) (xy 194.365039 -228.370191) (xy 194.312415 -228.336796) (xy 194.264393 -228.297068)
			(xy 194.221728 -228.251634) (xy 194.185094 -228.201212) (xy 194.155068 -228.146595) (xy 194.132125 -228.088647)
			(xy 194.116625 -228.028279) (xy 194.108813 -227.966445) (xy 194.108324 -227.935282) (xy 190.144654 -227.935282)
			(xy 190.144162 -227.962239) (xy 190.136312 -228.015579) (xy 190.12078 -228.067208) (xy 190.097895 -228.116025)
			(xy 190.068147 -228.160989) (xy 190.032169 -228.201143) (xy 189.990727 -228.235631) (xy 189.944706 -228.263717)
			(xy 189.895086 -228.284804) (xy 189.842925 -228.29844) (xy 189.789334 -228.304337) (xy 189.735455 -228.302368)
			(xy 189.682437 -228.292575) (xy 189.63141 -228.275167) (xy 189.583462 -228.250515) (xy 189.539614 -228.219145)
			(xy 189.500801 -228.181724) (xy 189.467849 -228.139051) (xy 189.441463 -228.092034) (xy 189.422203 -228.041677)
			(xy 189.41048 -227.989053) (xy 189.406545 -227.935282) (xy 187.555886 -227.935282) (xy 187.555397 -227.966445)
			(xy 187.547585 -228.028279) (xy 187.532085 -228.088647) (xy 187.509142 -228.146595) (xy 187.479116 -228.201212)
			(xy 187.442482 -228.251634) (xy 187.399817 -228.297068) (xy 187.351795 -228.336796) (xy 187.299171 -228.370191)
			(xy 187.242777 -228.396728) (xy 187.183502 -228.415988) (xy 187.122281 -228.427667) (xy 187.060078 -228.43158)
			(xy 186.997875 -228.427667) (xy 186.936654 -228.415988) (xy 186.877379 -228.396728) (xy 186.820985 -228.370191)
			(xy 186.768361 -228.336796) (xy 186.720339 -228.297068) (xy 186.677674 -228.251634) (xy 186.64104 -228.201212)
			(xy 186.611014 -228.146595) (xy 186.588071 -228.088647) (xy 186.572571 -228.028279) (xy 186.564759 -227.966445)
			(xy 186.56427 -227.935282) (xy 182.6006 -227.935282) (xy 182.600108 -227.962239) (xy 182.592258 -228.015579)
			(xy 182.576726 -228.067208) (xy 182.553841 -228.116025) (xy 182.524093 -228.160989) (xy 182.488115 -228.201143)
			(xy 182.446673 -228.235631) (xy 182.400652 -228.263717) (xy 182.351032 -228.284804) (xy 182.298871 -228.29844)
			(xy 182.24528 -228.304337) (xy 182.191401 -228.302368) (xy 182.138383 -228.292575) (xy 182.087356 -228.275167)
			(xy 182.039408 -228.250515) (xy 181.99556 -228.219145) (xy 181.956747 -228.181724) (xy 181.923795 -228.139051)
			(xy 181.897409 -228.092034) (xy 181.878149 -228.041677) (xy 181.866426 -227.989053) (xy 181.862491 -227.935282)
			(xy 180.011832 -227.935282) (xy 180.011343 -227.966445) (xy 180.003531 -228.028279) (xy 179.988031 -228.088647)
			(xy 179.965088 -228.146595) (xy 179.935062 -228.201212) (xy 179.898428 -228.251634) (xy 179.855763 -228.297068)
			(xy 179.807741 -228.336796) (xy 179.755117 -228.370191) (xy 179.698723 -228.396728) (xy 179.639448 -228.415988)
			(xy 179.578227 -228.427667) (xy 179.516024 -228.43158) (xy 179.453821 -228.427667) (xy 179.3926 -228.415988)
			(xy 179.333325 -228.396728) (xy 179.276931 -228.370191) (xy 179.224307 -228.336796) (xy 179.176285 -228.297068)
			(xy 179.13362 -228.251634) (xy 179.096986 -228.201212) (xy 179.06696 -228.146595) (xy 179.044017 -228.088647)
			(xy 179.028517 -228.028279) (xy 179.020705 -227.966445) (xy 179.020216 -227.935282) (xy 175.056546 -227.935282)
			(xy 175.056054 -227.962239) (xy 175.048204 -228.015579) (xy 175.032672 -228.067208) (xy 175.009787 -228.116025)
			(xy 174.980039 -228.160989) (xy 174.944061 -228.201143) (xy 174.902619 -228.235631) (xy 174.856598 -228.263717)
			(xy 174.806978 -228.284804) (xy 174.754817 -228.29844) (xy 174.701226 -228.304337) (xy 174.647347 -228.302368)
			(xy 174.594329 -228.292575) (xy 174.543302 -228.275167) (xy 174.495354 -228.250515) (xy 174.451506 -228.219145)
			(xy 174.412693 -228.181724) (xy 174.379741 -228.139051) (xy 174.353355 -228.092034) (xy 174.334095 -228.041677)
			(xy 174.322372 -227.989053) (xy 174.318437 -227.935282) (xy 172.467778 -227.935282) (xy 172.467289 -227.966445)
			(xy 172.459477 -228.028279) (xy 172.443977 -228.088647) (xy 172.421034 -228.146595) (xy 172.391008 -228.201212)
			(xy 172.354374 -228.251634) (xy 172.311709 -228.297068) (xy 172.263687 -228.336796) (xy 172.211063 -228.370191)
			(xy 172.154669 -228.396728) (xy 172.095394 -228.415988) (xy 172.034173 -228.427667) (xy 171.97197 -228.43158)
			(xy 171.909767 -228.427667) (xy 171.848546 -228.415988) (xy 171.789271 -228.396728) (xy 171.732877 -228.370191)
			(xy 171.680253 -228.336796) (xy 171.632231 -228.297068) (xy 171.589566 -228.251634) (xy 171.552932 -228.201212)
			(xy 171.522906 -228.146595) (xy 171.499963 -228.088647) (xy 171.484463 -228.028279) (xy 171.476651 -227.966445)
			(xy 171.476162 -227.935282) (xy 167.512492 -227.935282) (xy 167.512 -227.962239) (xy 167.50415 -228.015579)
			(xy 167.488618 -228.067208) (xy 167.465733 -228.116025) (xy 167.435985 -228.160989) (xy 167.400007 -228.201143)
			(xy 167.358565 -228.235631) (xy 167.312544 -228.263717) (xy 167.262924 -228.284804) (xy 167.210763 -228.29844)
			(xy 167.157172 -228.304337) (xy 167.103293 -228.302368) (xy 167.050275 -228.292575) (xy 166.999248 -228.275167)
			(xy 166.9513 -228.250515) (xy 166.907452 -228.219145) (xy 166.868639 -228.181724) (xy 166.835687 -228.139051)
			(xy 166.809301 -228.092034) (xy 166.790041 -228.041677) (xy 166.778318 -227.989053) (xy 166.774383 -227.935282)
			(xy 161.612834 -227.935282) (xy 161.612834 -228.78542) (xy 165.442915 -228.78542) (xy 165.44685 -228.731649)
			(xy 165.458573 -228.679025) (xy 165.477833 -228.628668) (xy 165.504219 -228.581651) (xy 165.537171 -228.538978)
			(xy 165.575984 -228.501557) (xy 165.619832 -228.470187) (xy 165.66778 -228.445535) (xy 165.718807 -228.428127)
			(xy 165.771825 -228.418334) (xy 165.825704 -228.416365) (xy 165.879295 -228.422262) (xy 165.931456 -228.435898)
			(xy 165.981076 -228.456985) (xy 166.027097 -228.485071) (xy 166.068539 -228.519559) (xy 166.104517 -228.559713)
			(xy 166.134265 -228.604677) (xy 166.15715 -228.653494) (xy 166.172682 -228.705123) (xy 166.180532 -228.758463)
			(xy 166.181024 -228.78542) (xy 172.986969 -228.78542) (xy 172.990904 -228.731649) (xy 173.002627 -228.679025)
			(xy 173.021887 -228.628668) (xy 173.048273 -228.581651) (xy 173.081225 -228.538978) (xy 173.120038 -228.501557)
			(xy 173.163886 -228.470187) (xy 173.211834 -228.445535) (xy 173.262861 -228.428127) (xy 173.315879 -228.418334)
			(xy 173.369758 -228.416365) (xy 173.423349 -228.422262) (xy 173.47551 -228.435898) (xy 173.52513 -228.456985)
			(xy 173.571151 -228.485071) (xy 173.612593 -228.519559) (xy 173.648571 -228.559713) (xy 173.678319 -228.604677)
			(xy 173.701204 -228.653494) (xy 173.716736 -228.705123) (xy 173.724586 -228.758463) (xy 173.725078 -228.78542)
			(xy 173.724586 -228.812377) (xy 173.716736 -228.865717) (xy 173.701204 -228.917346) (xy 173.678319 -228.966163)
			(xy 173.648571 -229.011127) (xy 173.612593 -229.051281) (xy 173.571151 -229.085769) (xy 173.52513 -229.113855)
			(xy 173.47551 -229.134942) (xy 173.423349 -229.148578) (xy 173.369758 -229.154475) (xy 173.315879 -229.152506)
			(xy 173.262861 -229.142713) (xy 173.211834 -229.125305) (xy 173.163886 -229.100653) (xy 173.120038 -229.069283)
			(xy 173.081225 -229.031862) (xy 173.048273 -228.989189) (xy 173.021887 -228.942172) (xy 173.002627 -228.891815)
			(xy 172.990904 -228.839191) (xy 172.986969 -228.78542) (xy 166.181024 -228.78542) (xy 166.180532 -228.812377)
			(xy 166.172682 -228.865717) (xy 166.15715 -228.917346) (xy 166.134265 -228.966163) (xy 166.104517 -229.011127)
			(xy 166.068539 -229.051281) (xy 166.027097 -229.085769) (xy 165.981076 -229.113855) (xy 165.931456 -229.134942)
			(xy 165.879295 -229.148578) (xy 165.825704 -229.154475) (xy 165.771825 -229.152506) (xy 165.718807 -229.142713)
			(xy 165.66778 -229.125305) (xy 165.619832 -229.100653) (xy 165.575984 -229.069283) (xy 165.537171 -229.031862)
			(xy 165.504219 -228.989189) (xy 165.477833 -228.942172) (xy 165.458573 -228.891815) (xy 165.44685 -228.839191)
			(xy 165.442915 -228.78542) (xy 161.612834 -228.78542) (xy 161.612834 -229.210362) (xy 169.276283 -229.210362)
			(xy 169.280218 -229.156591) (xy 169.291941 -229.103967) (xy 169.311201 -229.05361) (xy 169.337587 -229.006593)
			(xy 169.370539 -228.96392) (xy 169.409352 -228.926499) (xy 169.4532 -228.895129) (xy 169.501148 -228.870477)
			(xy 169.552175 -228.853069) (xy 169.605193 -228.843276) (xy 169.659072 -228.841307) (xy 169.712663 -228.847204)
			(xy 169.764824 -228.86084) (xy 169.814444 -228.881927) (xy 169.860465 -228.910013) (xy 169.901907 -228.944501)
			(xy 169.937885 -228.984655) (xy 169.967633 -229.029619) (xy 169.990518 -229.078436) (xy 170.00605 -229.130065)
			(xy 170.0139 -229.183405) (xy 170.014392 -229.210362) (xy 170.0139 -229.237319) (xy 170.00605 -229.290659)
			(xy 169.990518 -229.342288) (xy 169.967633 -229.391105) (xy 169.937885 -229.436069) (xy 169.901907 -229.476223)
			(xy 169.860465 -229.510711) (xy 169.814444 -229.538797) (xy 169.764824 -229.559884) (xy 169.712663 -229.57352)
			(xy 169.659072 -229.579417) (xy 169.605193 -229.577448) (xy 169.552175 -229.567655) (xy 169.501148 -229.550247)
			(xy 169.4532 -229.525595) (xy 169.409352 -229.494225) (xy 169.370539 -229.456804) (xy 169.337587 -229.414131)
			(xy 169.311201 -229.367114) (xy 169.291941 -229.316757) (xy 169.280218 -229.264133) (xy 169.276283 -229.210362)
			(xy 161.612834 -229.210362) (xy 161.612834 -230.0605) (xy 165.176215 -230.0605) (xy 165.18015 -230.006729)
			(xy 165.191873 -229.954105) (xy 165.211133 -229.903748) (xy 165.237519 -229.856731) (xy 165.270471 -229.814058)
			(xy 165.309284 -229.776637) (xy 165.353132 -229.745267) (xy 165.40108 -229.720615) (xy 165.452107 -229.703207)
			(xy 165.505125 -229.693414) (xy 165.559004 -229.691445) (xy 165.612595 -229.697342) (xy 165.664756 -229.710978)
			(xy 165.714376 -229.732065) (xy 165.760397 -229.760151) (xy 165.801839 -229.794639) (xy 165.837817 -229.834793)
			(xy 165.867565 -229.879757) (xy 165.89045 -229.928574) (xy 165.905982 -229.980203) (xy 165.913832 -230.033543)
			(xy 165.914324 -230.0605) (xy 165.913832 -230.087457) (xy 165.905982 -230.140797) (xy 165.89045 -230.192426)
			(xy 165.867565 -230.241243) (xy 165.837817 -230.286207) (xy 165.801839 -230.326361) (xy 165.760397 -230.360849)
			(xy 165.714376 -230.388935) (xy 165.664756 -230.410022) (xy 165.612595 -230.423658) (xy 165.559004 -230.429555)
			(xy 165.505125 -230.427586) (xy 165.452107 -230.417793) (xy 165.40108 -230.400385) (xy 165.353132 -230.375733)
			(xy 165.309284 -230.344363) (xy 165.270471 -230.306942) (xy 165.237519 -230.264269) (xy 165.211133 -230.217252)
			(xy 165.191873 -230.166895) (xy 165.18015 -230.114271) (xy 165.176215 -230.0605) (xy 161.612834 -230.0605)
			(xy 161.612834 -230.485442) (xy 166.774383 -230.485442) (xy 166.778318 -230.431671) (xy 166.790041 -230.379047)
			(xy 166.809301 -230.32869) (xy 166.835687 -230.281673) (xy 166.868639 -230.239) (xy 166.907452 -230.201579)
			(xy 166.9513 -230.170209) (xy 166.999248 -230.145557) (xy 167.050275 -230.128149) (xy 167.103293 -230.118356)
			(xy 167.157172 -230.116387) (xy 167.210763 -230.122284) (xy 167.262924 -230.13592) (xy 167.312544 -230.157007)
			(xy 167.358565 -230.185093) (xy 167.400007 -230.219581) (xy 167.435985 -230.259735) (xy 167.465733 -230.304699)
			(xy 167.488618 -230.353516) (xy 167.50415 -230.405145) (xy 167.512 -230.458485) (xy 167.512492 -230.485442)
			(xy 171.476162 -230.485442) (xy 171.476661 -230.452721) (xy 171.485262 -230.387846) (xy 171.502321 -230.324666)
			(xy 171.527541 -230.264278) (xy 171.560483 -230.207732) (xy 171.600577 -230.156009) (xy 171.623482 -230.132636)
			(xy 171.630848 -230.125524) (xy 171.638722 -230.106728) (xy 171.638722 -230.014018) (xy 171.630848 -229.995222)
			(xy 171.623482 -229.98811) (xy 171.60058 -229.964736) (xy 171.560497 -229.913008) (xy 171.527562 -229.85646)
			(xy 171.502347 -229.796073) (xy 171.48529 -229.732896) (xy 171.476686 -229.668024) (xy 171.476162 -229.635304)
			(xy 171.476651 -229.604141) (xy 171.484463 -229.542307) (xy 171.499963 -229.481939) (xy 171.522906 -229.423991)
			(xy 171.552932 -229.369374) (xy 171.589566 -229.318952) (xy 171.632231 -229.273518) (xy 171.680253 -229.23379)
			(xy 171.732877 -229.200395) (xy 171.789271 -229.173858) (xy 171.848546 -229.154598) (xy 171.909767 -229.142919)
			(xy 171.97197 -229.139006) (xy 172.034173 -229.142919) (xy 172.095394 -229.154598) (xy 172.154669 -229.173858)
			(xy 172.211063 -229.200395) (xy 172.263687 -229.23379) (xy 172.311709 -229.273518) (xy 172.354374 -229.318952)
			(xy 172.391008 -229.369374) (xy 172.421034 -229.423991) (xy 172.443977 -229.481939) (xy 172.459477 -229.542307)
			(xy 172.467289 -229.604141) (xy 172.467778 -229.635304) (xy 175.57623 -229.635304) (xy 175.576741 -229.602603)
			(xy 175.585354 -229.537771) (xy 175.602419 -229.474635) (xy 175.627638 -229.414291) (xy 175.660574 -229.357787)
			(xy 175.700654 -229.306106) (xy 175.72355 -229.282752) (xy 175.730916 -229.275386) (xy 175.738536 -229.256844)
			(xy 175.738536 -229.16388) (xy 175.730916 -229.145338) (xy 175.72355 -229.137972) (xy 175.700668 -229.114605)
			(xy 175.660582 -229.062929) (xy 175.627643 -229.00643) (xy 175.602424 -228.946087) (xy 175.585363 -228.882952)
			(xy 175.576756 -228.81812) (xy 175.57623 -228.78542) (xy 175.576719 -228.754257) (xy 175.584531 -228.692423)
			(xy 175.600031 -228.632055) (xy 175.622974 -228.574107) (xy 175.653 -228.51949) (xy 175.689634 -228.469068)
			(xy 175.732299 -228.423634) (xy 175.780321 -228.383906) (xy 175.832945 -228.350511) (xy 175.889339 -228.323974)
			(xy 175.948614 -228.304714) (xy 176.009835 -228.293035) (xy 176.072038 -228.289122) (xy 176.134241 -228.293035)
			(xy 176.195462 -228.304714) (xy 176.254737 -228.323974) (xy 176.311131 -228.350511) (xy 176.363755 -228.383906)
			(xy 176.411777 -228.423634) (xy 176.454442 -228.469068) (xy 176.491076 -228.51949) (xy 176.521102 -228.574107)
			(xy 176.544045 -228.632055) (xy 176.559545 -228.692423) (xy 176.567357 -228.754257) (xy 176.567846 -228.78542)
			(xy 180.531023 -228.78542) (xy 180.534958 -228.731649) (xy 180.546681 -228.679025) (xy 180.565941 -228.628668)
			(xy 180.592327 -228.581651) (xy 180.625279 -228.538978) (xy 180.664092 -228.501557) (xy 180.70794 -228.470187)
			(xy 180.755888 -228.445535) (xy 180.806915 -228.428127) (xy 180.859933 -228.418334) (xy 180.913812 -228.416365)
			(xy 180.967403 -228.422262) (xy 181.019564 -228.435898) (xy 181.069184 -228.456985) (xy 181.115205 -228.485071)
			(xy 181.156647 -228.519559) (xy 181.192625 -228.559713) (xy 181.222373 -228.604677) (xy 181.245258 -228.653494)
			(xy 181.26079 -228.705123) (xy 181.26864 -228.758463) (xy 181.269132 -228.78542) (xy 181.26864 -228.812377)
			(xy 181.26079 -228.865717) (xy 181.245258 -228.917346) (xy 181.222373 -228.966163) (xy 181.192625 -229.011127)
			(xy 181.156647 -229.051281) (xy 181.115205 -229.085769) (xy 181.069184 -229.113855) (xy 181.019564 -229.134942)
			(xy 180.967403 -229.148578) (xy 180.913812 -229.154475) (xy 180.859933 -229.152506) (xy 180.806915 -229.142713)
			(xy 180.755888 -229.125305) (xy 180.70794 -229.100653) (xy 180.664092 -229.069283) (xy 180.625279 -229.031862)
			(xy 180.592327 -228.989189) (xy 180.565941 -228.942172) (xy 180.546681 -228.891815) (xy 180.534958 -228.839191)
			(xy 180.531023 -228.78542) (xy 176.567846 -228.78542) (xy 176.567293 -228.81812) (xy 176.558689 -228.88295)
			(xy 176.541634 -228.946086) (xy 176.516422 -229.00643) (xy 176.483494 -229.062935) (xy 176.443419 -229.114618)
			(xy 176.420526 -229.137972) (xy 176.41316 -229.145338) (xy 176.40554 -229.16388) (xy 176.40554 -229.210362)
			(xy 176.820337 -229.210362) (xy 176.824272 -229.156591) (xy 176.835995 -229.103967) (xy 176.855255 -229.05361)
			(xy 176.881641 -229.006593) (xy 176.914593 -228.96392) (xy 176.953406 -228.926499) (xy 176.997254 -228.895129)
			(xy 177.045202 -228.870477) (xy 177.096229 -228.853069) (xy 177.149247 -228.843276) (xy 177.203126 -228.841307)
			(xy 177.256717 -228.847204) (xy 177.308878 -228.86084) (xy 177.358498 -228.881927) (xy 177.404519 -228.910013)
			(xy 177.445961 -228.944501) (xy 177.481939 -228.984655) (xy 177.511687 -229.029619) (xy 177.534572 -229.078436)
			(xy 177.550104 -229.130065) (xy 177.557954 -229.183405) (xy 177.558446 -229.210362) (xy 177.557954 -229.237319)
			(xy 177.550104 -229.290659) (xy 177.534572 -229.342288) (xy 177.511687 -229.391105) (xy 177.481939 -229.436069)
			(xy 177.445961 -229.476223) (xy 177.404519 -229.510711) (xy 177.358498 -229.538797) (xy 177.308878 -229.559884)
			(xy 177.256717 -229.57352) (xy 177.203126 -229.579417) (xy 177.149247 -229.577448) (xy 177.096229 -229.567655)
			(xy 177.045202 -229.550247) (xy 176.997254 -229.525595) (xy 176.953406 -229.494225) (xy 176.914593 -229.456804)
			(xy 176.881641 -229.414131) (xy 176.855255 -229.367114) (xy 176.835995 -229.316757) (xy 176.824272 -229.264133)
			(xy 176.820337 -229.210362) (xy 176.40554 -229.210362) (xy 176.40554 -229.256844) (xy 176.41316 -229.275386)
			(xy 176.420526 -229.282752) (xy 176.443415 -229.306113) (xy 176.483501 -229.357789) (xy 176.516439 -229.41429)
			(xy 176.541658 -229.474634) (xy 176.558717 -229.537771) (xy 176.567322 -229.602603) (xy 176.567846 -229.635304)
			(xy 176.567357 -229.666467) (xy 176.559545 -229.728301) (xy 176.544045 -229.788669) (xy 176.521102 -229.846617)
			(xy 176.491076 -229.901234) (xy 176.454442 -229.951656) (xy 176.411777 -229.99709) (xy 176.363755 -230.036818)
			(xy 176.311131 -230.070213) (xy 176.254737 -230.09675) (xy 176.195462 -230.11601) (xy 176.134241 -230.127689)
			(xy 176.072038 -230.131602) (xy 176.009835 -230.127689) (xy 175.948614 -230.11601) (xy 175.889339 -230.09675)
			(xy 175.832945 -230.070213) (xy 175.780321 -230.036818) (xy 175.732299 -229.99709) (xy 175.689634 -229.951656)
			(xy 175.653 -229.901234) (xy 175.622974 -229.846617) (xy 175.600031 -229.788669) (xy 175.584531 -229.728301)
			(xy 175.576719 -229.666467) (xy 175.57623 -229.635304) (xy 172.467778 -229.635304) (xy 172.467232 -229.668024)
			(xy 172.458639 -229.732896) (xy 172.441588 -229.796075) (xy 172.416377 -229.856462) (xy 172.383443 -229.91301)
			(xy 172.343359 -229.964735) (xy 172.320458 -229.98811) (xy 172.313092 -229.995222) (xy 172.305218 -230.014018)
			(xy 172.305218 -230.0605) (xy 172.720269 -230.0605) (xy 172.724204 -230.006729) (xy 172.735927 -229.954105)
			(xy 172.755187 -229.903748) (xy 172.781573 -229.856731) (xy 172.814525 -229.814058) (xy 172.853338 -229.776637)
			(xy 172.897186 -229.745267) (xy 172.945134 -229.720615) (xy 172.996161 -229.703207) (xy 173.049179 -229.693414)
			(xy 173.103058 -229.691445) (xy 173.156649 -229.697342) (xy 173.20881 -229.710978) (xy 173.25843 -229.732065)
			(xy 173.304451 -229.760151) (xy 173.345893 -229.794639) (xy 173.381871 -229.834793) (xy 173.411619 -229.879757)
			(xy 173.434504 -229.928574) (xy 173.450036 -229.980203) (xy 173.457886 -230.033543) (xy 173.458378 -230.0605)
			(xy 173.457886 -230.087457) (xy 173.450036 -230.140797) (xy 173.434504 -230.192426) (xy 173.411619 -230.241243)
			(xy 173.381871 -230.286207) (xy 173.345893 -230.326361) (xy 173.304451 -230.360849) (xy 173.25843 -230.388935)
			(xy 173.20881 -230.410022) (xy 173.156649 -230.423658) (xy 173.103058 -230.429555) (xy 173.049179 -230.427586)
			(xy 172.996161 -230.417793) (xy 172.945134 -230.400385) (xy 172.897186 -230.375733) (xy 172.853338 -230.344363)
			(xy 172.814525 -230.306942) (xy 172.781573 -230.264269) (xy 172.755187 -230.217252) (xy 172.735927 -230.166895)
			(xy 172.724204 -230.114271) (xy 172.720269 -230.0605) (xy 172.305218 -230.0605) (xy 172.305218 -230.106728)
			(xy 172.313092 -230.125524) (xy 172.320458 -230.132636) (xy 172.343342 -230.156027) (xy 172.383425 -230.207752)
			(xy 172.416362 -230.264296) (xy 172.44158 -230.32468) (xy 172.458642 -230.387854) (xy 172.467251 -230.452723)
			(xy 172.467778 -230.485442) (xy 174.318437 -230.485442) (xy 174.322372 -230.431671) (xy 174.334095 -230.379047)
			(xy 174.353355 -230.32869) (xy 174.379741 -230.281673) (xy 174.412693 -230.239) (xy 174.451506 -230.201579)
			(xy 174.495354 -230.170209) (xy 174.543302 -230.145557) (xy 174.594329 -230.128149) (xy 174.647347 -230.118356)
			(xy 174.701226 -230.116387) (xy 174.754817 -230.122284) (xy 174.806978 -230.13592) (xy 174.856598 -230.157007)
			(xy 174.902619 -230.185093) (xy 174.944061 -230.219581) (xy 174.980039 -230.259735) (xy 175.009787 -230.304699)
			(xy 175.032672 -230.353516) (xy 175.048204 -230.405145) (xy 175.056054 -230.458485) (xy 175.056546 -230.485442)
			(xy 179.020216 -230.485442) (xy 179.020729 -230.452721) (xy 179.029329 -230.387848) (xy 179.046386 -230.324668)
			(xy 179.071603 -230.264281) (xy 179.104543 -230.207734) (xy 179.144633 -230.15601) (xy 179.167536 -230.132636)
			(xy 179.174902 -230.125524) (xy 179.182776 -230.106728) (xy 179.182776 -230.014018) (xy 179.174902 -229.995222)
			(xy 179.167536 -229.98811) (xy 179.144625 -229.964744) (xy 179.104544 -229.913014) (xy 179.071612 -229.856464)
			(xy 179.046399 -229.796076) (xy 179.029343 -229.732897) (xy 179.02074 -229.668024) (xy 179.020216 -229.635304)
			(xy 179.020705 -229.604141) (xy 179.028517 -229.542307) (xy 179.044017 -229.481939) (xy 179.06696 -229.423991)
			(xy 179.096986 -229.369374) (xy 179.13362 -229.318952) (xy 179.176285 -229.273518) (xy 179.224307 -229.23379)
			(xy 179.276931 -229.200395) (xy 179.333325 -229.173858) (xy 179.3926 -229.154598) (xy 179.453821 -229.142919)
			(xy 179.516024 -229.139006) (xy 179.578227 -229.142919) (xy 179.639448 -229.154598) (xy 179.698723 -229.173858)
			(xy 179.755117 -229.200395) (xy 179.807741 -229.23379) (xy 179.855763 -229.273518) (xy 179.898428 -229.318952)
			(xy 179.935062 -229.369374) (xy 179.965088 -229.423991) (xy 179.988031 -229.481939) (xy 180.003531 -229.542307)
			(xy 180.011343 -229.604141) (xy 180.011832 -229.635304) (xy 183.120284 -229.635304) (xy 183.120779 -229.602602)
			(xy 183.129393 -229.537769) (xy 183.14646 -229.474632) (xy 183.171682 -229.414287) (xy 183.204621 -229.357784)
			(xy 183.244706 -229.306105) (xy 183.267604 -229.282752) (xy 183.27497 -229.275386) (xy 183.28259 -229.256844)
			(xy 183.28259 -229.16388) (xy 183.27497 -229.145338) (xy 183.267604 -229.137972) (xy 183.244732 -229.114595)
			(xy 183.204643 -229.062923) (xy 183.171702 -229.006426) (xy 183.14648 -228.946085) (xy 183.129418 -228.882951)
			(xy 183.12081 -228.81812) (xy 183.120284 -228.78542) (xy 183.120773 -228.754257) (xy 183.128585 -228.692423)
			(xy 183.144085 -228.632055) (xy 183.167028 -228.574107) (xy 183.197054 -228.51949) (xy 183.233688 -228.469068)
			(xy 183.276353 -228.423634) (xy 183.324375 -228.383906) (xy 183.376999 -228.350511) (xy 183.433393 -228.323974)
			(xy 183.492668 -228.304714) (xy 183.553889 -228.293035) (xy 183.616092 -228.289122) (xy 183.678295 -228.293035)
			(xy 183.739516 -228.304714) (xy 183.798791 -228.323974) (xy 183.855185 -228.350511) (xy 183.907809 -228.383906)
			(xy 183.955831 -228.423634) (xy 183.998496 -228.469068) (xy 184.03513 -228.51949) (xy 184.065156 -228.574107)
			(xy 184.088099 -228.632055) (xy 184.103599 -228.692423) (xy 184.111411 -228.754257) (xy 184.1119 -228.78542)
			(xy 188.075077 -228.78542) (xy 188.079012 -228.731649) (xy 188.090735 -228.679025) (xy 188.109995 -228.628668)
			(xy 188.136381 -228.581651) (xy 188.169333 -228.538978) (xy 188.208146 -228.501557) (xy 188.251994 -228.470187)
			(xy 188.299942 -228.445535) (xy 188.350969 -228.428127) (xy 188.403987 -228.418334) (xy 188.457866 -228.416365)
			(xy 188.511457 -228.422262) (xy 188.563618 -228.435898) (xy 188.613238 -228.456985) (xy 188.659259 -228.485071)
			(xy 188.700701 -228.519559) (xy 188.736679 -228.559713) (xy 188.766427 -228.604677) (xy 188.789312 -228.653494)
			(xy 188.804844 -228.705123) (xy 188.812694 -228.758463) (xy 188.813186 -228.78542) (xy 188.812694 -228.812377)
			(xy 188.804844 -228.865717) (xy 188.789312 -228.917346) (xy 188.766427 -228.966163) (xy 188.736679 -229.011127)
			(xy 188.700701 -229.051281) (xy 188.659259 -229.085769) (xy 188.613238 -229.113855) (xy 188.563618 -229.134942)
			(xy 188.511457 -229.148578) (xy 188.457866 -229.154475) (xy 188.403987 -229.152506) (xy 188.350969 -229.142713)
			(xy 188.299942 -229.125305) (xy 188.251994 -229.100653) (xy 188.208146 -229.069283) (xy 188.169333 -229.031862)
			(xy 188.136381 -228.989189) (xy 188.109995 -228.942172) (xy 188.090735 -228.891815) (xy 188.079012 -228.839191)
			(xy 188.075077 -228.78542) (xy 184.1119 -228.78542) (xy 184.111361 -228.81812) (xy 184.102756 -228.882952)
			(xy 184.085699 -228.946089) (xy 184.060485 -229.006433) (xy 184.027553 -229.062937) (xy 183.987475 -229.114619)
			(xy 183.96458 -229.137972) (xy 183.957214 -229.145338) (xy 183.949594 -229.16388) (xy 183.949594 -229.210362)
			(xy 184.364391 -229.210362) (xy 184.368326 -229.156591) (xy 184.380049 -229.103967) (xy 184.399309 -229.05361)
			(xy 184.425695 -229.006593) (xy 184.458647 -228.96392) (xy 184.49746 -228.926499) (xy 184.541308 -228.895129)
			(xy 184.589256 -228.870477) (xy 184.640283 -228.853069) (xy 184.693301 -228.843276) (xy 184.74718 -228.841307)
			(xy 184.800771 -228.847204) (xy 184.852932 -228.86084) (xy 184.902552 -228.881927) (xy 184.948573 -228.910013)
			(xy 184.990015 -228.944501) (xy 185.025993 -228.984655) (xy 185.055741 -229.029619) (xy 185.078626 -229.078436)
			(xy 185.094158 -229.130065) (xy 185.102008 -229.183405) (xy 185.1025 -229.210362) (xy 185.102008 -229.237319)
			(xy 185.094158 -229.290659) (xy 185.078626 -229.342288) (xy 185.055741 -229.391105) (xy 185.025993 -229.436069)
			(xy 184.990015 -229.476223) (xy 184.948573 -229.510711) (xy 184.902552 -229.538797) (xy 184.852932 -229.559884)
			(xy 184.800771 -229.57352) (xy 184.74718 -229.579417) (xy 184.693301 -229.577448) (xy 184.640283 -229.567655)
			(xy 184.589256 -229.550247) (xy 184.541308 -229.525595) (xy 184.49746 -229.494225) (xy 184.458647 -229.456804)
			(xy 184.425695 -229.414131) (xy 184.399309 -229.367114) (xy 184.380049 -229.316757) (xy 184.368326 -229.264133)
			(xy 184.364391 -229.210362) (xy 183.949594 -229.210362) (xy 183.949594 -229.256844) (xy 183.957214 -229.275386)
			(xy 183.96458 -229.282752) (xy 183.987479 -229.306103) (xy 184.027562 -229.357782) (xy 184.060498 -229.414286)
			(xy 184.085714 -229.474631) (xy 184.102772 -229.537769) (xy 184.111376 -229.602603) (xy 184.1119 -229.635304)
			(xy 184.111411 -229.666467) (xy 184.103599 -229.728301) (xy 184.088099 -229.788669) (xy 184.065156 -229.846617)
			(xy 184.03513 -229.901234) (xy 183.998496 -229.951656) (xy 183.955831 -229.99709) (xy 183.907809 -230.036818)
			(xy 183.855185 -230.070213) (xy 183.798791 -230.09675) (xy 183.739516 -230.11601) (xy 183.678295 -230.127689)
			(xy 183.616092 -230.131602) (xy 183.553889 -230.127689) (xy 183.492668 -230.11601) (xy 183.433393 -230.09675)
			(xy 183.376999 -230.070213) (xy 183.324375 -230.036818) (xy 183.276353 -229.99709) (xy 183.233688 -229.951656)
			(xy 183.197054 -229.901234) (xy 183.167028 -229.846617) (xy 183.144085 -229.788669) (xy 183.128585 -229.728301)
			(xy 183.120773 -229.666467) (xy 183.120284 -229.635304) (xy 180.011832 -229.635304) (xy 180.0113 -229.668024)
			(xy 180.002706 -229.732898) (xy 179.985653 -229.796077) (xy 179.96044 -229.856465) (xy 179.927503 -229.913012)
			(xy 179.887415 -229.964736) (xy 179.864512 -229.98811) (xy 179.857146 -229.995222) (xy 179.849272 -230.014018)
			(xy 179.849272 -230.0605) (xy 180.264323 -230.0605) (xy 180.268258 -230.006729) (xy 180.279981 -229.954105)
			(xy 180.299241 -229.903748) (xy 180.325627 -229.856731) (xy 180.358579 -229.814058) (xy 180.397392 -229.776637)
			(xy 180.44124 -229.745267) (xy 180.489188 -229.720615) (xy 180.540215 -229.703207) (xy 180.593233 -229.693414)
			(xy 180.647112 -229.691445) (xy 180.700703 -229.697342) (xy 180.752864 -229.710978) (xy 180.802484 -229.732065)
			(xy 180.848505 -229.760151) (xy 180.889947 -229.794639) (xy 180.925925 -229.834793) (xy 180.955673 -229.879757)
			(xy 180.978558 -229.928574) (xy 180.99409 -229.980203) (xy 181.00194 -230.033543) (xy 181.002432 -230.0605)
			(xy 181.00194 -230.087457) (xy 180.99409 -230.140797) (xy 180.978558 -230.192426) (xy 180.955673 -230.241243)
			(xy 180.925925 -230.286207) (xy 180.889947 -230.326361) (xy 180.848505 -230.360849) (xy 180.802484 -230.388935)
			(xy 180.752864 -230.410022) (xy 180.700703 -230.423658) (xy 180.647112 -230.429555) (xy 180.593233 -230.427586)
			(xy 180.540215 -230.417793) (xy 180.489188 -230.400385) (xy 180.44124 -230.375733) (xy 180.397392 -230.344363)
			(xy 180.358579 -230.306942) (xy 180.325627 -230.264269) (xy 180.299241 -230.217252) (xy 180.279981 -230.166895)
			(xy 180.268258 -230.114271) (xy 180.264323 -230.0605) (xy 179.849272 -230.0605) (xy 179.849272 -230.106728)
			(xy 179.857146 -230.125524) (xy 179.864512 -230.132636) (xy 179.887387 -230.156036) (xy 179.927473 -230.207757)
			(xy 179.960412 -230.2643) (xy 179.985631 -230.324682) (xy 180.002694 -230.387855) (xy 180.011304 -230.452724)
			(xy 180.011832 -230.485442) (xy 181.862491 -230.485442) (xy 181.866426 -230.431671) (xy 181.878149 -230.379047)
			(xy 181.897409 -230.32869) (xy 181.923795 -230.281673) (xy 181.956747 -230.239) (xy 181.99556 -230.201579)
			(xy 182.039408 -230.170209) (xy 182.087356 -230.145557) (xy 182.138383 -230.128149) (xy 182.191401 -230.118356)
			(xy 182.24528 -230.116387) (xy 182.298871 -230.122284) (xy 182.351032 -230.13592) (xy 182.400652 -230.157007)
			(xy 182.446673 -230.185093) (xy 182.488115 -230.219581) (xy 182.524093 -230.259735) (xy 182.553841 -230.304699)
			(xy 182.576726 -230.353516) (xy 182.592258 -230.405145) (xy 182.600108 -230.458485) (xy 182.6006 -230.485442)
			(xy 186.56427 -230.485442) (xy 186.564796 -230.452722) (xy 186.573396 -230.387849) (xy 186.590451 -230.324671)
			(xy 186.615666 -230.264284) (xy 186.648602 -230.207736) (xy 186.688689 -230.156011) (xy 186.71159 -230.132636)
			(xy 186.718956 -230.125524) (xy 186.72683 -230.106728) (xy 186.72683 -230.014018) (xy 186.718956 -229.995222)
			(xy 186.71159 -229.98811) (xy 186.688689 -229.964734) (xy 186.648606 -229.913008) (xy 186.615671 -229.85646)
			(xy 186.590455 -229.796073) (xy 186.573398 -229.732896) (xy 186.564794 -229.668024) (xy 186.56427 -229.635304)
			(xy 186.564759 -229.604141) (xy 186.572571 -229.542307) (xy 186.588071 -229.481939) (xy 186.611014 -229.423991)
			(xy 186.64104 -229.369374) (xy 186.677674 -229.318952) (xy 186.720339 -229.273518) (xy 186.768361 -229.23379)
			(xy 186.820985 -229.200395) (xy 186.877379 -229.173858) (xy 186.936654 -229.154598) (xy 186.997875 -229.142919)
			(xy 187.060078 -229.139006) (xy 187.122281 -229.142919) (xy 187.183502 -229.154598) (xy 187.242777 -229.173858)
			(xy 187.299171 -229.200395) (xy 187.351795 -229.23379) (xy 187.399817 -229.273518) (xy 187.442482 -229.318952)
			(xy 187.479116 -229.369374) (xy 187.509142 -229.423991) (xy 187.532085 -229.481939) (xy 187.547585 -229.542307)
			(xy 187.555397 -229.604141) (xy 187.555886 -229.635304) (xy 190.664338 -229.635304) (xy 190.664846 -229.602603)
			(xy 190.67346 -229.537771) (xy 190.690525 -229.474634) (xy 190.715744 -229.41429) (xy 190.748681 -229.357787)
			(xy 190.788762 -229.306106) (xy 190.811658 -229.282752) (xy 190.819024 -229.275386) (xy 190.826644 -229.256844)
			(xy 190.826644 -229.16388) (xy 190.819024 -229.145338) (xy 190.811658 -229.137972) (xy 190.788778 -229.114603)
			(xy 190.748691 -229.062929) (xy 190.715752 -229.006429) (xy 190.690532 -228.946087) (xy 190.673471 -228.882952)
			(xy 190.664864 -228.81812) (xy 190.664338 -228.78542) (xy 190.664827 -228.754257) (xy 190.672639 -228.692423)
			(xy 190.688139 -228.632055) (xy 190.711082 -228.574107) (xy 190.741108 -228.51949) (xy 190.777742 -228.469068)
			(xy 190.820407 -228.423634) (xy 190.868429 -228.383906) (xy 190.921053 -228.350511) (xy 190.977447 -228.323974)
			(xy 191.036722 -228.304714) (xy 191.097943 -228.293035) (xy 191.160146 -228.289122) (xy 191.222349 -228.293035)
			(xy 191.28357 -228.304714) (xy 191.342845 -228.323974) (xy 191.399239 -228.350511) (xy 191.451863 -228.383906)
			(xy 191.499885 -228.423634) (xy 191.54255 -228.469068) (xy 191.579184 -228.51949) (xy 191.60921 -228.574107)
			(xy 191.632153 -228.632055) (xy 191.647653 -228.692423) (xy 191.655465 -228.754257) (xy 191.655954 -228.78542)
			(xy 195.619131 -228.78542) (xy 195.623066 -228.731649) (xy 195.634789 -228.679025) (xy 195.654049 -228.628668)
			(xy 195.680435 -228.581651) (xy 195.713387 -228.538978) (xy 195.7522 -228.501557) (xy 195.796048 -228.470187)
			(xy 195.843996 -228.445535) (xy 195.895023 -228.428127) (xy 195.948041 -228.418334) (xy 196.00192 -228.416365)
			(xy 196.055511 -228.422262) (xy 196.107672 -228.435898) (xy 196.157292 -228.456985) (xy 196.203313 -228.485071)
			(xy 196.244755 -228.519559) (xy 196.280733 -228.559713) (xy 196.310481 -228.604677) (xy 196.333366 -228.653494)
			(xy 196.348898 -228.705123) (xy 196.356748 -228.758463) (xy 196.35724 -228.78542) (xy 196.356748 -228.812377)
			(xy 196.348898 -228.865717) (xy 196.333366 -228.917346) (xy 196.310481 -228.966163) (xy 196.280733 -229.011127)
			(xy 196.244755 -229.051281) (xy 196.203313 -229.085769) (xy 196.157292 -229.113855) (xy 196.107672 -229.134942)
			(xy 196.055511 -229.148578) (xy 196.00192 -229.154475) (xy 195.948041 -229.152506) (xy 195.895023 -229.142713)
			(xy 195.843996 -229.125305) (xy 195.796048 -229.100653) (xy 195.7522 -229.069283) (xy 195.713387 -229.031862)
			(xy 195.680435 -228.989189) (xy 195.654049 -228.942172) (xy 195.634789 -228.891815) (xy 195.623066 -228.839191)
			(xy 195.619131 -228.78542) (xy 191.655954 -228.78542) (xy 191.655399 -228.818119) (xy 191.646795 -228.88295)
			(xy 191.62974 -228.946086) (xy 191.604529 -229.00643) (xy 191.571601 -229.062934) (xy 191.531527 -229.114617)
			(xy 191.508634 -229.137972) (xy 191.501268 -229.145338) (xy 191.493648 -229.16388) (xy 191.493648 -229.210362)
			(xy 191.908445 -229.210362) (xy 191.91238 -229.156591) (xy 191.924103 -229.103967) (xy 191.943363 -229.05361)
			(xy 191.969749 -229.006593) (xy 192.002701 -228.96392) (xy 192.041514 -228.926499) (xy 192.085362 -228.895129)
			(xy 192.13331 -228.870477) (xy 192.184337 -228.853069) (xy 192.237355 -228.843276) (xy 192.291234 -228.841307)
			(xy 192.344825 -228.847204) (xy 192.396986 -228.86084) (xy 192.446606 -228.881927) (xy 192.492627 -228.910013)
			(xy 192.534069 -228.944501) (xy 192.570047 -228.984655) (xy 192.599795 -229.029619) (xy 192.62268 -229.078436)
			(xy 192.638212 -229.130065) (xy 192.646062 -229.183405) (xy 192.646554 -229.210362) (xy 192.646062 -229.237319)
			(xy 192.638212 -229.290659) (xy 192.62268 -229.342288) (xy 192.599795 -229.391105) (xy 192.570047 -229.436069)
			(xy 192.534069 -229.476223) (xy 192.492627 -229.510711) (xy 192.446606 -229.538797) (xy 192.396986 -229.559884)
			(xy 192.344825 -229.57352) (xy 192.291234 -229.579417) (xy 192.237355 -229.577448) (xy 192.184337 -229.567655)
			(xy 192.13331 -229.550247) (xy 192.085362 -229.525595) (xy 192.041514 -229.494225) (xy 192.002701 -229.456804)
			(xy 191.969749 -229.414131) (xy 191.943363 -229.367114) (xy 191.924103 -229.316757) (xy 191.91238 -229.264133)
			(xy 191.908445 -229.210362) (xy 191.493648 -229.210362) (xy 191.493648 -229.256844) (xy 191.501268 -229.275386)
			(xy 191.508634 -229.282752) (xy 191.531524 -229.306111) (xy 191.57161 -229.357788) (xy 191.604548 -229.414289)
			(xy 191.629766 -229.474633) (xy 191.646825 -229.53777) (xy 191.65543 -229.602603) (xy 191.655954 -229.635304)
			(xy 191.655465 -229.666467) (xy 191.647653 -229.728301) (xy 191.632153 -229.788669) (xy 191.60921 -229.846617)
			(xy 191.579184 -229.901234) (xy 191.54255 -229.951656) (xy 191.499885 -229.99709) (xy 191.451863 -230.036818)
			(xy 191.399239 -230.070213) (xy 191.342845 -230.09675) (xy 191.28357 -230.11601) (xy 191.222349 -230.127689)
			(xy 191.160146 -230.131602) (xy 191.097943 -230.127689) (xy 191.036722 -230.11601) (xy 190.977447 -230.09675)
			(xy 190.921053 -230.070213) (xy 190.868429 -230.036818) (xy 190.820407 -229.99709) (xy 190.777742 -229.951656)
			(xy 190.741108 -229.901234) (xy 190.711082 -229.846617) (xy 190.688139 -229.788669) (xy 190.672639 -229.728301)
			(xy 190.664827 -229.666467) (xy 190.664338 -229.635304) (xy 187.555886 -229.635304) (xy 187.555338 -229.668024)
			(xy 187.546745 -229.732896) (xy 187.529695 -229.796074) (xy 187.504484 -229.856462) (xy 187.471551 -229.913009)
			(xy 187.431467 -229.964735) (xy 187.408566 -229.98811) (xy 187.4012 -229.995222) (xy 187.393326 -230.014018)
			(xy 187.393326 -230.0605) (xy 187.808377 -230.0605) (xy 187.812312 -230.006729) (xy 187.824035 -229.954105)
			(xy 187.843295 -229.903748) (xy 187.869681 -229.856731) (xy 187.902633 -229.814058) (xy 187.941446 -229.776637)
			(xy 187.985294 -229.745267) (xy 188.033242 -229.720615) (xy 188.084269 -229.703207) (xy 188.137287 -229.693414)
			(xy 188.191166 -229.691445) (xy 188.244757 -229.697342) (xy 188.296918 -229.710978) (xy 188.346538 -229.732065)
			(xy 188.392559 -229.760151) (xy 188.434001 -229.794639) (xy 188.469979 -229.834793) (xy 188.499727 -229.879757)
			(xy 188.522612 -229.928574) (xy 188.538144 -229.980203) (xy 188.545994 -230.033543) (xy 188.546486 -230.0605)
			(xy 188.545994 -230.087457) (xy 188.538144 -230.140797) (xy 188.522612 -230.192426) (xy 188.499727 -230.241243)
			(xy 188.469979 -230.286207) (xy 188.434001 -230.326361) (xy 188.392559 -230.360849) (xy 188.346538 -230.388935)
			(xy 188.296918 -230.410022) (xy 188.244757 -230.423658) (xy 188.191166 -230.429555) (xy 188.137287 -230.427586)
			(xy 188.084269 -230.417793) (xy 188.033242 -230.400385) (xy 187.985294 -230.375733) (xy 187.941446 -230.344363)
			(xy 187.902633 -230.306942) (xy 187.869681 -230.264269) (xy 187.843295 -230.217252) (xy 187.824035 -230.166895)
			(xy 187.812312 -230.114271) (xy 187.808377 -230.0605) (xy 187.393326 -230.0605) (xy 187.393326 -230.106728)
			(xy 187.4012 -230.125524) (xy 187.408566 -230.132636) (xy 187.431451 -230.156026) (xy 187.471534 -230.207751)
			(xy 187.504471 -230.264296) (xy 187.529688 -230.324679) (xy 187.54675 -230.387854) (xy 187.555359 -230.452723)
			(xy 187.555886 -230.485442) (xy 189.406545 -230.485442) (xy 189.41048 -230.431671) (xy 189.422203 -230.379047)
			(xy 189.441463 -230.32869) (xy 189.467849 -230.281673) (xy 189.500801 -230.239) (xy 189.539614 -230.201579)
			(xy 189.583462 -230.170209) (xy 189.63141 -230.145557) (xy 189.682437 -230.128149) (xy 189.735455 -230.118356)
			(xy 189.789334 -230.116387) (xy 189.842925 -230.122284) (xy 189.895086 -230.13592) (xy 189.944706 -230.157007)
			(xy 189.990727 -230.185093) (xy 190.032169 -230.219581) (xy 190.068147 -230.259735) (xy 190.097895 -230.304699)
			(xy 190.12078 -230.353516) (xy 190.136312 -230.405145) (xy 190.144162 -230.458485) (xy 190.144654 -230.485442)
			(xy 194.108324 -230.485442) (xy 194.108834 -230.452721) (xy 194.117435 -230.387847) (xy 194.134492 -230.324668)
			(xy 194.15971 -230.26428) (xy 194.19265 -230.207734) (xy 194.23274 -230.15601) (xy 194.255644 -230.132636)
			(xy 194.26301 -230.125524) (xy 194.270884 -230.106728) (xy 194.270884 -230.014018) (xy 194.26301 -229.995222)
			(xy 194.255644 -229.98811) (xy 194.232734 -229.964743) (xy 194.192653 -229.913013) (xy 194.15972 -229.856463)
			(xy 194.134507 -229.796075) (xy 194.117451 -229.732897) (xy 194.108848 -229.668024) (xy 194.108324 -229.635304)
			(xy 194.108813 -229.604141) (xy 194.116625 -229.542307) (xy 194.132125 -229.481939) (xy 194.155068 -229.423991)
			(xy 194.185094 -229.369374) (xy 194.221728 -229.318952) (xy 194.264393 -229.273518) (xy 194.312415 -229.23379)
			(xy 194.365039 -229.200395) (xy 194.421433 -229.173858) (xy 194.480708 -229.154598) (xy 194.541929 -229.142919)
			(xy 194.604132 -229.139006) (xy 194.666335 -229.142919) (xy 194.727556 -229.154598) (xy 194.786831 -229.173858)
			(xy 194.843225 -229.200395) (xy 194.895849 -229.23379) (xy 194.943871 -229.273518) (xy 194.986536 -229.318952)
			(xy 195.02317 -229.369374) (xy 195.053196 -229.423991) (xy 195.076139 -229.481939) (xy 195.091639 -229.542307)
			(xy 195.099451 -229.604141) (xy 195.09994 -229.635304) (xy 198.208392 -229.635304) (xy 198.208884 -229.602602)
			(xy 198.217499 -229.537769) (xy 198.234566 -229.474631) (xy 198.259788 -229.414287) (xy 198.292728 -229.357784)
			(xy 198.332813 -229.306104) (xy 198.355712 -229.282752) (xy 198.363078 -229.275386) (xy 198.370698 -229.256844)
			(xy 198.370698 -229.16388) (xy 198.363078 -229.145338) (xy 198.355712 -229.137972) (xy 198.332823 -229.114611)
			(xy 198.29274 -229.062934) (xy 198.259802 -229.006432) (xy 198.234584 -228.946089) (xy 198.217524 -228.882953)
			(xy 198.208918 -228.81812) (xy 198.208392 -228.78542) (xy 198.208881 -228.754257) (xy 198.216693 -228.692423)
			(xy 198.232193 -228.632055) (xy 198.255136 -228.574107) (xy 198.285162 -228.51949) (xy 198.321796 -228.469068)
			(xy 198.364461 -228.423634) (xy 198.412483 -228.383906) (xy 198.465107 -228.350511) (xy 198.521501 -228.323974)
			(xy 198.580776 -228.304714) (xy 198.641997 -228.293035) (xy 198.7042 -228.289122) (xy 198.766403 -228.293035)
			(xy 198.827624 -228.304714) (xy 198.886899 -228.323974) (xy 198.943293 -228.350511) (xy 198.995917 -228.383906)
			(xy 199.043939 -228.423634) (xy 199.086604 -228.469068) (xy 199.123238 -228.51949) (xy 199.153264 -228.574107)
			(xy 199.176207 -228.632055) (xy 199.191707 -228.692423) (xy 199.199519 -228.754257) (xy 199.200008 -228.78542)
			(xy 203.162931 -228.78542) (xy 203.166866 -228.731649) (xy 203.178589 -228.679025) (xy 203.197849 -228.628668)
			(xy 203.224235 -228.581651) (xy 203.257187 -228.538978) (xy 203.296 -228.501557) (xy 203.339848 -228.470187)
			(xy 203.387796 -228.445535) (xy 203.438823 -228.428127) (xy 203.491841 -228.418334) (xy 203.54572 -228.416365)
			(xy 203.599311 -228.422262) (xy 203.651472 -228.435898) (xy 203.701092 -228.456985) (xy 203.747113 -228.485071)
			(xy 203.788555 -228.519559) (xy 203.824533 -228.559713) (xy 203.854281 -228.604677) (xy 203.877166 -228.653494)
			(xy 203.892698 -228.705123) (xy 203.900548 -228.758463) (xy 203.90104 -228.78542) (xy 203.900548 -228.812377)
			(xy 203.892698 -228.865717) (xy 203.877166 -228.917346) (xy 203.854281 -228.966163) (xy 203.824533 -229.011127)
			(xy 203.788555 -229.051281) (xy 203.747113 -229.085769) (xy 203.701092 -229.113855) (xy 203.651472 -229.134942)
			(xy 203.599311 -229.148578) (xy 203.54572 -229.154475) (xy 203.491841 -229.152506) (xy 203.438823 -229.142713)
			(xy 203.387796 -229.125305) (xy 203.339848 -229.100653) (xy 203.296 -229.069283) (xy 203.257187 -229.031862)
			(xy 203.224235 -228.989189) (xy 203.197849 -228.942172) (xy 203.178589 -228.891815) (xy 203.166866 -228.839191)
			(xy 203.162931 -228.78542) (xy 199.200008 -228.78542) (xy 199.199467 -228.81812) (xy 199.190862 -228.882952)
			(xy 199.173805 -228.946088) (xy 199.148591 -229.006433) (xy 199.11566 -229.062937) (xy 199.075583 -229.114618)
			(xy 199.052688 -229.137972) (xy 199.045322 -229.145338) (xy 199.037702 -229.16388) (xy 199.037702 -229.210362)
			(xy 199.452499 -229.210362) (xy 199.456434 -229.156591) (xy 199.468157 -229.103967) (xy 199.487417 -229.05361)
			(xy 199.513803 -229.006593) (xy 199.546755 -228.96392) (xy 199.585568 -228.926499) (xy 199.629416 -228.895129)
			(xy 199.677364 -228.870477) (xy 199.728391 -228.853069) (xy 199.781409 -228.843276) (xy 199.835288 -228.841307)
			(xy 199.888879 -228.847204) (xy 199.94104 -228.86084) (xy 199.99066 -228.881927) (xy 200.036681 -228.910013)
			(xy 200.078123 -228.944501) (xy 200.114101 -228.984655) (xy 200.143849 -229.029619) (xy 200.166734 -229.078436)
			(xy 200.182266 -229.130065) (xy 200.190116 -229.183405) (xy 200.190608 -229.210362) (xy 200.190116 -229.237319)
			(xy 200.182266 -229.290659) (xy 200.166734 -229.342288) (xy 200.143849 -229.391105) (xy 200.114101 -229.436069)
			(xy 200.078123 -229.476223) (xy 200.036681 -229.510711) (xy 199.99066 -229.538797) (xy 199.94104 -229.559884)
			(xy 199.888879 -229.57352) (xy 199.835288 -229.579417) (xy 199.781409 -229.577448) (xy 199.728391 -229.567655)
			(xy 199.677364 -229.550247) (xy 199.629416 -229.525595) (xy 199.585568 -229.494225) (xy 199.546755 -229.456804)
			(xy 199.513803 -229.414131) (xy 199.487417 -229.367114) (xy 199.468157 -229.316757) (xy 199.456434 -229.264133)
			(xy 199.452499 -229.210362) (xy 199.037702 -229.210362) (xy 199.037702 -229.256844) (xy 199.045322 -229.275386)
			(xy 199.052688 -229.282752) (xy 199.075588 -229.306102) (xy 199.115671 -229.357782) (xy 199.148606 -229.414285)
			(xy 199.173822 -229.474631) (xy 199.19088 -229.537769) (xy 199.199484 -229.602603) (xy 199.200008 -229.635304)
			(xy 199.199519 -229.666467) (xy 199.191707 -229.728301) (xy 199.176207 -229.788669) (xy 199.153264 -229.846617)
			(xy 199.123238 -229.901234) (xy 199.086604 -229.951656) (xy 199.043939 -229.99709) (xy 198.995917 -230.036818)
			(xy 198.943293 -230.070213) (xy 198.886899 -230.09675) (xy 198.827624 -230.11601) (xy 198.766403 -230.127689)
			(xy 198.7042 -230.131602) (xy 198.641997 -230.127689) (xy 198.580776 -230.11601) (xy 198.521501 -230.09675)
			(xy 198.465107 -230.070213) (xy 198.412483 -230.036818) (xy 198.364461 -229.99709) (xy 198.321796 -229.951656)
			(xy 198.285162 -229.901234) (xy 198.255136 -229.846617) (xy 198.232193 -229.788669) (xy 198.216693 -229.728301)
			(xy 198.208881 -229.666467) (xy 198.208392 -229.635304) (xy 195.09994 -229.635304) (xy 195.099406 -229.668024)
			(xy 195.090811 -229.732897) (xy 195.07376 -229.796077) (xy 195.048546 -229.856465) (xy 195.01561 -229.913012)
			(xy 194.975522 -229.964736) (xy 194.95262 -229.98811) (xy 194.945254 -229.995222) (xy 194.93738 -230.014018)
			(xy 194.93738 -230.0605) (xy 195.352431 -230.0605) (xy 195.356366 -230.006729) (xy 195.368089 -229.954105)
			(xy 195.387349 -229.903748) (xy 195.413735 -229.856731) (xy 195.446687 -229.814058) (xy 195.4855 -229.776637)
			(xy 195.529348 -229.745267) (xy 195.577296 -229.720615) (xy 195.628323 -229.703207) (xy 195.681341 -229.693414)
			(xy 195.73522 -229.691445) (xy 195.788811 -229.697342) (xy 195.840972 -229.710978) (xy 195.890592 -229.732065)
			(xy 195.936613 -229.760151) (xy 195.978055 -229.794639) (xy 196.014033 -229.834793) (xy 196.043781 -229.879757)
			(xy 196.066666 -229.928574) (xy 196.082198 -229.980203) (xy 196.090048 -230.033543) (xy 196.09054 -230.0605)
			(xy 196.090048 -230.087457) (xy 196.082198 -230.140797) (xy 196.066666 -230.192426) (xy 196.043781 -230.241243)
			(xy 196.014033 -230.286207) (xy 195.978055 -230.326361) (xy 195.936613 -230.360849) (xy 195.890592 -230.388935)
			(xy 195.840972 -230.410022) (xy 195.788811 -230.423658) (xy 195.73522 -230.429555) (xy 195.681341 -230.427586)
			(xy 195.628323 -230.417793) (xy 195.577296 -230.400385) (xy 195.529348 -230.375733) (xy 195.4855 -230.344363)
			(xy 195.446687 -230.306942) (xy 195.413735 -230.264269) (xy 195.387349 -230.217252) (xy 195.368089 -230.166895)
			(xy 195.356366 -230.114271) (xy 195.352431 -230.0605) (xy 194.93738 -230.0605) (xy 194.93738 -230.106728)
			(xy 194.945254 -230.125524) (xy 194.95262 -230.132636) (xy 194.975497 -230.156034) (xy 195.015582 -230.207756)
			(xy 195.04852 -230.264299) (xy 195.07374 -230.324682) (xy 195.090802 -230.387855) (xy 195.099412 -230.452723)
			(xy 195.09994 -230.485442) (xy 196.950599 -230.485442) (xy 196.954534 -230.431671) (xy 196.966257 -230.379047)
			(xy 196.985517 -230.32869) (xy 197.011903 -230.281673) (xy 197.044855 -230.239) (xy 197.083668 -230.201579)
			(xy 197.127516 -230.170209) (xy 197.175464 -230.145557) (xy 197.226491 -230.128149) (xy 197.279509 -230.118356)
			(xy 197.333388 -230.116387) (xy 197.386979 -230.122284) (xy 197.43914 -230.13592) (xy 197.48876 -230.157007)
			(xy 197.534781 -230.185093) (xy 197.576223 -230.219581) (xy 197.612201 -230.259735) (xy 197.641949 -230.304699)
			(xy 197.664834 -230.353516) (xy 197.680366 -230.405145) (xy 197.688216 -230.458485) (xy 197.688708 -230.485442)
			(xy 201.652124 -230.485442) (xy 201.652634 -230.452721) (xy 201.661235 -230.387847) (xy 201.678292 -230.324668)
			(xy 201.70351 -230.26428) (xy 201.73645 -230.207734) (xy 201.77654 -230.15601) (xy 201.799444 -230.132636)
			(xy 201.80681 -230.125524) (xy 201.814684 -230.106728) (xy 201.814684 -230.014018) (xy 201.80681 -229.995222)
			(xy 201.799444 -229.98811) (xy 201.776534 -229.964743) (xy 201.736453 -229.913013) (xy 201.70352 -229.856463)
			(xy 201.678307 -229.796075) (xy 201.661251 -229.732897) (xy 201.652648 -229.668024) (xy 201.652124 -229.635304)
			(xy 201.652613 -229.604141) (xy 201.660425 -229.542307) (xy 201.675925 -229.481939) (xy 201.698868 -229.423991)
			(xy 201.728894 -229.369374) (xy 201.765528 -229.318952) (xy 201.808193 -229.273518) (xy 201.856215 -229.23379)
			(xy 201.908839 -229.200395) (xy 201.965233 -229.173858) (xy 202.024508 -229.154598) (xy 202.085729 -229.142919)
			(xy 202.147932 -229.139006) (xy 202.210135 -229.142919) (xy 202.271356 -229.154598) (xy 202.330631 -229.173858)
			(xy 202.387025 -229.200395) (xy 202.439649 -229.23379) (xy 202.487671 -229.273518) (xy 202.530336 -229.318952)
			(xy 202.56697 -229.369374) (xy 202.596996 -229.423991) (xy 202.619939 -229.481939) (xy 202.635439 -229.542307)
			(xy 202.643251 -229.604141) (xy 202.64374 -229.635304) (xy 205.752192 -229.635304) (xy 205.752684 -229.602602)
			(xy 205.761299 -229.537769) (xy 205.778366 -229.474631) (xy 205.803588 -229.414287) (xy 205.836528 -229.357784)
			(xy 205.876613 -229.306104) (xy 205.899512 -229.282752) (xy 205.906878 -229.275386) (xy 205.914498 -229.256844)
			(xy 205.914498 -229.16388) (xy 205.906878 -229.145338) (xy 205.899512 -229.137972) (xy 205.876623 -229.114611)
			(xy 205.83654 -229.062934) (xy 205.803602 -229.006432) (xy 205.778384 -228.946089) (xy 205.761324 -228.882953)
			(xy 205.752718 -228.81812) (xy 205.752192 -228.78542) (xy 205.752681 -228.754257) (xy 205.760493 -228.692423)
			(xy 205.775993 -228.632055) (xy 205.798936 -228.574107) (xy 205.828962 -228.51949) (xy 205.865596 -228.469068)
			(xy 205.908261 -228.423634) (xy 205.956283 -228.383906) (xy 206.008907 -228.350511) (xy 206.065301 -228.323974)
			(xy 206.124576 -228.304714) (xy 206.185797 -228.293035) (xy 206.248 -228.289122) (xy 206.310203 -228.293035)
			(xy 206.371424 -228.304714) (xy 206.430699 -228.323974) (xy 206.487093 -228.350511) (xy 206.539717 -228.383906)
			(xy 206.587739 -228.423634) (xy 206.630404 -228.469068) (xy 206.667038 -228.51949) (xy 206.697064 -228.574107)
			(xy 206.720007 -228.632055) (xy 206.735507 -228.692423) (xy 206.743319 -228.754257) (xy 206.743808 -228.78542)
			(xy 206.743267 -228.81812) (xy 206.734662 -228.882952) (xy 206.717605 -228.946088) (xy 206.692391 -229.006433)
			(xy 206.65946 -229.062937) (xy 206.619383 -229.114618) (xy 206.596488 -229.137972) (xy 206.589122 -229.145338)
			(xy 206.581502 -229.16388) (xy 206.581502 -229.210362) (xy 206.996299 -229.210362) (xy 207.000234 -229.156591)
			(xy 207.011957 -229.103967) (xy 207.031217 -229.05361) (xy 207.057603 -229.006593) (xy 207.090555 -228.96392)
			(xy 207.129368 -228.926499) (xy 207.173216 -228.895129) (xy 207.221164 -228.870477) (xy 207.272191 -228.853069)
			(xy 207.325209 -228.843276) (xy 207.379088 -228.841307) (xy 207.432679 -228.847204) (xy 207.48484 -228.86084)
			(xy 207.53446 -228.881927) (xy 207.580481 -228.910013) (xy 207.621923 -228.944501) (xy 207.657901 -228.984655)
			(xy 207.687649 -229.029619) (xy 207.710534 -229.078436) (xy 207.726066 -229.130065) (xy 207.733916 -229.183405)
			(xy 207.734408 -229.210362) (xy 207.733916 -229.237319) (xy 207.726066 -229.290659) (xy 207.710534 -229.342288)
			(xy 207.687649 -229.391105) (xy 207.657901 -229.436069) (xy 207.621923 -229.476223) (xy 207.580481 -229.510711)
			(xy 207.53446 -229.538797) (xy 207.48484 -229.559884) (xy 207.432679 -229.57352) (xy 207.379088 -229.579417)
			(xy 207.325209 -229.577448) (xy 207.272191 -229.567655) (xy 207.221164 -229.550247) (xy 207.173216 -229.525595)
			(xy 207.129368 -229.494225) (xy 207.090555 -229.456804) (xy 207.057603 -229.414131) (xy 207.031217 -229.367114)
			(xy 207.011957 -229.316757) (xy 207.000234 -229.264133) (xy 206.996299 -229.210362) (xy 206.581502 -229.210362)
			(xy 206.581502 -229.256844) (xy 206.589122 -229.275386) (xy 206.596488 -229.282752) (xy 206.619388 -229.306102)
			(xy 206.659471 -229.357782) (xy 206.692406 -229.414285) (xy 206.717622 -229.474631) (xy 206.73468 -229.537769)
			(xy 206.743284 -229.602603) (xy 206.743808 -229.635304) (xy 206.743319 -229.666467) (xy 206.735507 -229.728301)
			(xy 206.720007 -229.788669) (xy 206.697064 -229.846617) (xy 206.667038 -229.901234) (xy 206.630404 -229.951656)
			(xy 206.587739 -229.99709) (xy 206.539717 -230.036818) (xy 206.487093 -230.070213) (xy 206.430699 -230.09675)
			(xy 206.371424 -230.11601) (xy 206.310203 -230.127689) (xy 206.248 -230.131602) (xy 206.185797 -230.127689)
			(xy 206.124576 -230.11601) (xy 206.065301 -230.09675) (xy 206.008907 -230.070213) (xy 205.956283 -230.036818)
			(xy 205.908261 -229.99709) (xy 205.865596 -229.951656) (xy 205.828962 -229.901234) (xy 205.798936 -229.846617)
			(xy 205.775993 -229.788669) (xy 205.760493 -229.728301) (xy 205.752681 -229.666467) (xy 205.752192 -229.635304)
			(xy 202.64374 -229.635304) (xy 202.643206 -229.668024) (xy 202.634611 -229.732897) (xy 202.61756 -229.796077)
			(xy 202.592346 -229.856465) (xy 202.55941 -229.913012) (xy 202.519322 -229.964736) (xy 202.49642 -229.98811)
			(xy 202.489054 -229.995222) (xy 202.48118 -230.014018) (xy 202.48118 -230.0605) (xy 202.896231 -230.0605)
			(xy 202.900166 -230.006729) (xy 202.911889 -229.954105) (xy 202.931149 -229.903748) (xy 202.957535 -229.856731)
			(xy 202.990487 -229.814058) (xy 203.0293 -229.776637) (xy 203.073148 -229.745267) (xy 203.121096 -229.720615)
			(xy 203.172123 -229.703207) (xy 203.225141 -229.693414) (xy 203.27902 -229.691445) (xy 203.332611 -229.697342)
			(xy 203.384772 -229.710978) (xy 203.434392 -229.732065) (xy 203.480413 -229.760151) (xy 203.521855 -229.794639)
			(xy 203.557833 -229.834793) (xy 203.587581 -229.879757) (xy 203.610466 -229.928574) (xy 203.625998 -229.980203)
			(xy 203.633848 -230.033543) (xy 203.63434 -230.0605) (xy 203.633848 -230.087457) (xy 203.625998 -230.140797)
			(xy 203.610466 -230.192426) (xy 203.587581 -230.241243) (xy 203.557833 -230.286207) (xy 203.521855 -230.326361)
			(xy 203.480413 -230.360849) (xy 203.434392 -230.388935) (xy 203.384772 -230.410022) (xy 203.332611 -230.423658)
			(xy 203.27902 -230.429555) (xy 203.225141 -230.427586) (xy 203.172123 -230.417793) (xy 203.121096 -230.400385)
			(xy 203.073148 -230.375733) (xy 203.0293 -230.344363) (xy 202.990487 -230.306942) (xy 202.957535 -230.264269)
			(xy 202.931149 -230.217252) (xy 202.911889 -230.166895) (xy 202.900166 -230.114271) (xy 202.896231 -230.0605)
			(xy 202.48118 -230.0605) (xy 202.48118 -230.106728) (xy 202.489054 -230.125524) (xy 202.49642 -230.132636)
			(xy 202.519297 -230.156034) (xy 202.559382 -230.207756) (xy 202.59232 -230.264299) (xy 202.61754 -230.324682)
			(xy 202.634602 -230.387855) (xy 202.643212 -230.452723) (xy 202.64374 -230.485442) (xy 204.494399 -230.485442)
			(xy 204.498334 -230.431671) (xy 204.510057 -230.379047) (xy 204.529317 -230.32869) (xy 204.555703 -230.281673)
			(xy 204.588655 -230.239) (xy 204.627468 -230.201579) (xy 204.671316 -230.170209) (xy 204.719264 -230.145557)
			(xy 204.770291 -230.128149) (xy 204.823309 -230.118356) (xy 204.877188 -230.116387) (xy 204.930779 -230.122284)
			(xy 204.98294 -230.13592) (xy 205.03256 -230.157007) (xy 205.078581 -230.185093) (xy 205.120023 -230.219581)
			(xy 205.156001 -230.259735) (xy 205.185749 -230.304699) (xy 205.208634 -230.353516) (xy 205.224166 -230.405145)
			(xy 205.232016 -230.458485) (xy 205.232508 -230.485442) (xy 205.232016 -230.512399) (xy 205.224166 -230.565739)
			(xy 205.219375 -230.581665) (xy 208.769452 -230.581665) (xy 208.769452 -230.517743) (xy 208.777463 -230.454325)
			(xy 208.79336 -230.392411) (xy 208.816892 -230.332978) (xy 208.847686 -230.276963) (xy 208.885259 -230.225248)
			(xy 208.929016 -230.178651) (xy 208.978269 -230.137906) (xy 209.03224 -230.103655) (xy 209.090079 -230.076438)
			(xy 209.150872 -230.056685) (xy 209.213662 -230.044707) (xy 209.277458 -230.040694) (xy 209.341254 -230.044707)
			(xy 209.404044 -230.056685) (xy 209.464837 -230.076438) (xy 209.522676 -230.103655) (xy 209.576647 -230.137906)
			(xy 209.6259 -230.178651) (xy 209.669657 -230.225248) (xy 209.70723 -230.276963) (xy 209.738024 -230.332978)
			(xy 209.761556 -230.392411) (xy 209.777453 -230.454325) (xy 209.785464 -230.517743) (xy 209.785966 -230.549704)
			(xy 209.785464 -230.581665) (xy 209.777453 -230.645083) (xy 209.761556 -230.706997) (xy 209.738024 -230.76643)
			(xy 209.70723 -230.822445) (xy 209.669657 -230.87416) (xy 209.6259 -230.920757) (xy 209.576647 -230.961502)
			(xy 209.522676 -230.995753) (xy 209.464837 -231.02297) (xy 209.404044 -231.042723) (xy 209.341254 -231.054701)
			(xy 209.277458 -231.058715) (xy 209.213662 -231.054701) (xy 209.150872 -231.042723) (xy 209.090079 -231.02297)
			(xy 209.03224 -230.995753) (xy 208.978269 -230.961502) (xy 208.929016 -230.920757) (xy 208.885259 -230.87416)
			(xy 208.847686 -230.822445) (xy 208.816892 -230.76643) (xy 208.79336 -230.706997) (xy 208.777463 -230.645083)
			(xy 208.769452 -230.581665) (xy 205.219375 -230.581665) (xy 205.208634 -230.617368) (xy 205.185749 -230.666185)
			(xy 205.156001 -230.711149) (xy 205.120023 -230.751303) (xy 205.078581 -230.785791) (xy 205.03256 -230.813877)
			(xy 204.98294 -230.834964) (xy 204.930779 -230.8486) (xy 204.877188 -230.854497) (xy 204.823309 -230.852528)
			(xy 204.770291 -230.842735) (xy 204.719264 -230.825327) (xy 204.671316 -230.800675) (xy 204.627468 -230.769305)
			(xy 204.588655 -230.731884) (xy 204.555703 -230.689211) (xy 204.529317 -230.642194) (xy 204.510057 -230.591837)
			(xy 204.498334 -230.539213) (xy 204.494399 -230.485442) (xy 202.64374 -230.485442) (xy 202.643251 -230.516605)
			(xy 202.635439 -230.578439) (xy 202.619939 -230.638807) (xy 202.596996 -230.696755) (xy 202.56697 -230.751372)
			(xy 202.530336 -230.801794) (xy 202.487671 -230.847228) (xy 202.439649 -230.886956) (xy 202.387025 -230.920351)
			(xy 202.330631 -230.946888) (xy 202.271356 -230.966148) (xy 202.210135 -230.977827) (xy 202.147932 -230.98174)
			(xy 202.085729 -230.977827) (xy 202.024508 -230.966148) (xy 201.965233 -230.946888) (xy 201.908839 -230.920351)
			(xy 201.856215 -230.886956) (xy 201.808193 -230.847228) (xy 201.765528 -230.801794) (xy 201.728894 -230.751372)
			(xy 201.698868 -230.696755) (xy 201.675925 -230.638807) (xy 201.660425 -230.578439) (xy 201.652613 -230.516605)
			(xy 201.652124 -230.485442) (xy 197.688708 -230.485442) (xy 197.688216 -230.512399) (xy 197.680366 -230.565739)
			(xy 197.664834 -230.617368) (xy 197.641949 -230.666185) (xy 197.612201 -230.711149) (xy 197.576223 -230.751303)
			(xy 197.534781 -230.785791) (xy 197.48876 -230.813877) (xy 197.43914 -230.834964) (xy 197.386979 -230.8486)
			(xy 197.333388 -230.854497) (xy 197.279509 -230.852528) (xy 197.226491 -230.842735) (xy 197.175464 -230.825327)
			(xy 197.127516 -230.800675) (xy 197.083668 -230.769305) (xy 197.044855 -230.731884) (xy 197.011903 -230.689211)
			(xy 196.985517 -230.642194) (xy 196.966257 -230.591837) (xy 196.954534 -230.539213) (xy 196.950599 -230.485442)
			(xy 195.09994 -230.485442) (xy 195.099451 -230.516605) (xy 195.091639 -230.578439) (xy 195.076139 -230.638807)
			(xy 195.053196 -230.696755) (xy 195.02317 -230.751372) (xy 194.986536 -230.801794) (xy 194.943871 -230.847228)
			(xy 194.895849 -230.886956) (xy 194.843225 -230.920351) (xy 194.786831 -230.946888) (xy 194.727556 -230.966148)
			(xy 194.666335 -230.977827) (xy 194.604132 -230.98174) (xy 194.541929 -230.977827) (xy 194.480708 -230.966148)
			(xy 194.421433 -230.946888) (xy 194.365039 -230.920351) (xy 194.312415 -230.886956) (xy 194.264393 -230.847228)
			(xy 194.221728 -230.801794) (xy 194.185094 -230.751372) (xy 194.155068 -230.696755) (xy 194.132125 -230.638807)
			(xy 194.116625 -230.578439) (xy 194.108813 -230.516605) (xy 194.108324 -230.485442) (xy 190.144654 -230.485442)
			(xy 190.144162 -230.512399) (xy 190.136312 -230.565739) (xy 190.12078 -230.617368) (xy 190.097895 -230.666185)
			(xy 190.068147 -230.711149) (xy 190.032169 -230.751303) (xy 189.990727 -230.785791) (xy 189.944706 -230.813877)
			(xy 189.895086 -230.834964) (xy 189.842925 -230.8486) (xy 189.789334 -230.854497) (xy 189.735455 -230.852528)
			(xy 189.682437 -230.842735) (xy 189.63141 -230.825327) (xy 189.583462 -230.800675) (xy 189.539614 -230.769305)
			(xy 189.500801 -230.731884) (xy 189.467849 -230.689211) (xy 189.441463 -230.642194) (xy 189.422203 -230.591837)
			(xy 189.41048 -230.539213) (xy 189.406545 -230.485442) (xy 187.555886 -230.485442) (xy 187.555397 -230.516605)
			(xy 187.547585 -230.578439) (xy 187.532085 -230.638807) (xy 187.509142 -230.696755) (xy 187.479116 -230.751372)
			(xy 187.442482 -230.801794) (xy 187.399817 -230.847228) (xy 187.351795 -230.886956) (xy 187.299171 -230.920351)
			(xy 187.242777 -230.946888) (xy 187.183502 -230.966148) (xy 187.122281 -230.977827) (xy 187.060078 -230.98174)
			(xy 186.997875 -230.977827) (xy 186.936654 -230.966148) (xy 186.877379 -230.946888) (xy 186.820985 -230.920351)
			(xy 186.768361 -230.886956) (xy 186.720339 -230.847228) (xy 186.677674 -230.801794) (xy 186.64104 -230.751372)
			(xy 186.611014 -230.696755) (xy 186.588071 -230.638807) (xy 186.572571 -230.578439) (xy 186.564759 -230.516605)
			(xy 186.56427 -230.485442) (xy 182.6006 -230.485442) (xy 182.600108 -230.512399) (xy 182.592258 -230.565739)
			(xy 182.576726 -230.617368) (xy 182.553841 -230.666185) (xy 182.524093 -230.711149) (xy 182.488115 -230.751303)
			(xy 182.446673 -230.785791) (xy 182.400652 -230.813877) (xy 182.351032 -230.834964) (xy 182.298871 -230.8486)
			(xy 182.24528 -230.854497) (xy 182.191401 -230.852528) (xy 182.138383 -230.842735) (xy 182.087356 -230.825327)
			(xy 182.039408 -230.800675) (xy 181.99556 -230.769305) (xy 181.956747 -230.731884) (xy 181.923795 -230.689211)
			(xy 181.897409 -230.642194) (xy 181.878149 -230.591837) (xy 181.866426 -230.539213) (xy 181.862491 -230.485442)
			(xy 180.011832 -230.485442) (xy 180.011343 -230.516605) (xy 180.003531 -230.578439) (xy 179.988031 -230.638807)
			(xy 179.965088 -230.696755) (xy 179.935062 -230.751372) (xy 179.898428 -230.801794) (xy 179.855763 -230.847228)
			(xy 179.807741 -230.886956) (xy 179.755117 -230.920351) (xy 179.698723 -230.946888) (xy 179.639448 -230.966148)
			(xy 179.578227 -230.977827) (xy 179.516024 -230.98174) (xy 179.453821 -230.977827) (xy 179.3926 -230.966148)
			(xy 179.333325 -230.946888) (xy 179.276931 -230.920351) (xy 179.224307 -230.886956) (xy 179.176285 -230.847228)
			(xy 179.13362 -230.801794) (xy 179.096986 -230.751372) (xy 179.06696 -230.696755) (xy 179.044017 -230.638807)
			(xy 179.028517 -230.578439) (xy 179.020705 -230.516605) (xy 179.020216 -230.485442) (xy 175.056546 -230.485442)
			(xy 175.056054 -230.512399) (xy 175.048204 -230.565739) (xy 175.032672 -230.617368) (xy 175.009787 -230.666185)
			(xy 174.980039 -230.711149) (xy 174.944061 -230.751303) (xy 174.902619 -230.785791) (xy 174.856598 -230.813877)
			(xy 174.806978 -230.834964) (xy 174.754817 -230.8486) (xy 174.701226 -230.854497) (xy 174.647347 -230.852528)
			(xy 174.594329 -230.842735) (xy 174.543302 -230.825327) (xy 174.495354 -230.800675) (xy 174.451506 -230.769305)
			(xy 174.412693 -230.731884) (xy 174.379741 -230.689211) (xy 174.353355 -230.642194) (xy 174.334095 -230.591837)
			(xy 174.322372 -230.539213) (xy 174.318437 -230.485442) (xy 172.467778 -230.485442) (xy 172.467289 -230.516605)
			(xy 172.459477 -230.578439) (xy 172.443977 -230.638807) (xy 172.421034 -230.696755) (xy 172.391008 -230.751372)
			(xy 172.354374 -230.801794) (xy 172.311709 -230.847228) (xy 172.263687 -230.886956) (xy 172.211063 -230.920351)
			(xy 172.154669 -230.946888) (xy 172.095394 -230.966148) (xy 172.034173 -230.977827) (xy 171.97197 -230.98174)
			(xy 171.909767 -230.977827) (xy 171.848546 -230.966148) (xy 171.789271 -230.946888) (xy 171.732877 -230.920351)
			(xy 171.680253 -230.886956) (xy 171.632231 -230.847228) (xy 171.589566 -230.801794) (xy 171.552932 -230.751372)
			(xy 171.522906 -230.696755) (xy 171.499963 -230.638807) (xy 171.484463 -230.578439) (xy 171.476651 -230.516605)
			(xy 171.476162 -230.485442) (xy 167.512492 -230.485442) (xy 167.512 -230.512399) (xy 167.50415 -230.565739)
			(xy 167.488618 -230.617368) (xy 167.465733 -230.666185) (xy 167.435985 -230.711149) (xy 167.400007 -230.751303)
			(xy 167.358565 -230.785791) (xy 167.312544 -230.813877) (xy 167.262924 -230.834964) (xy 167.210763 -230.8486)
			(xy 167.157172 -230.854497) (xy 167.103293 -230.852528) (xy 167.050275 -230.842735) (xy 166.999248 -230.825327)
			(xy 166.9513 -230.800675) (xy 166.907452 -230.769305) (xy 166.868639 -230.731884) (xy 166.835687 -230.689211)
			(xy 166.809301 -230.642194) (xy 166.790041 -230.591837) (xy 166.778318 -230.539213) (xy 166.774383 -230.485442)
			(xy 161.612834 -230.485442) (xy 161.612834 -231.335326) (xy 165.442915 -231.335326) (xy 165.44685 -231.281555)
			(xy 165.458573 -231.228931) (xy 165.477833 -231.178574) (xy 165.504219 -231.131557) (xy 165.537171 -231.088884)
			(xy 165.575984 -231.051463) (xy 165.619832 -231.020093) (xy 165.66778 -230.995441) (xy 165.718807 -230.978033)
			(xy 165.771825 -230.96824) (xy 165.825704 -230.966271) (xy 165.879295 -230.972168) (xy 165.931456 -230.985804)
			(xy 165.981076 -231.006891) (xy 166.027097 -231.034977) (xy 166.068539 -231.069465) (xy 166.104517 -231.109619)
			(xy 166.134265 -231.154583) (xy 166.15715 -231.2034) (xy 166.172682 -231.255029) (xy 166.180532 -231.308369)
			(xy 166.181024 -231.335326) (xy 172.986969 -231.335326) (xy 172.990904 -231.281555) (xy 173.002627 -231.228931)
			(xy 173.021887 -231.178574) (xy 173.048273 -231.131557) (xy 173.081225 -231.088884) (xy 173.120038 -231.051463)
			(xy 173.163886 -231.020093) (xy 173.211834 -230.995441) (xy 173.262861 -230.978033) (xy 173.315879 -230.96824)
			(xy 173.369758 -230.966271) (xy 173.423349 -230.972168) (xy 173.47551 -230.985804) (xy 173.52513 -231.006891)
			(xy 173.571151 -231.034977) (xy 173.612593 -231.069465) (xy 173.648571 -231.109619) (xy 173.678319 -231.154583)
			(xy 173.701204 -231.2034) (xy 173.716736 -231.255029) (xy 173.724586 -231.308369) (xy 173.725078 -231.335326)
			(xy 173.724586 -231.362283) (xy 173.716736 -231.415623) (xy 173.701204 -231.467252) (xy 173.678319 -231.516069)
			(xy 173.648571 -231.561033) (xy 173.612593 -231.601187) (xy 173.571151 -231.635675) (xy 173.52513 -231.663761)
			(xy 173.47551 -231.684848) (xy 173.423349 -231.698484) (xy 173.369758 -231.704381) (xy 173.315879 -231.702412)
			(xy 173.262861 -231.692619) (xy 173.211834 -231.675211) (xy 173.163886 -231.650559) (xy 173.120038 -231.619189)
			(xy 173.081225 -231.581768) (xy 173.048273 -231.539095) (xy 173.021887 -231.492078) (xy 173.002627 -231.441721)
			(xy 172.990904 -231.389097) (xy 172.986969 -231.335326) (xy 166.181024 -231.335326) (xy 166.180532 -231.362283)
			(xy 166.172682 -231.415623) (xy 166.15715 -231.467252) (xy 166.134265 -231.516069) (xy 166.104517 -231.561033)
			(xy 166.068539 -231.601187) (xy 166.027097 -231.635675) (xy 165.981076 -231.663761) (xy 165.931456 -231.684848)
			(xy 165.879295 -231.698484) (xy 165.825704 -231.704381) (xy 165.771825 -231.702412) (xy 165.718807 -231.692619)
			(xy 165.66778 -231.675211) (xy 165.619832 -231.650559) (xy 165.575984 -231.619189) (xy 165.537171 -231.581768)
			(xy 165.504219 -231.539095) (xy 165.477833 -231.492078) (xy 165.458573 -231.441721) (xy 165.44685 -231.389097)
			(xy 165.442915 -231.335326) (xy 161.612834 -231.335326) (xy 161.612834 -232.18521) (xy 168.158683 -232.18521)
			(xy 168.162618 -232.131439) (xy 168.174341 -232.078815) (xy 168.193601 -232.028458) (xy 168.219987 -231.981441)
			(xy 168.252939 -231.938768) (xy 168.291752 -231.901347) (xy 168.3356 -231.869977) (xy 168.383548 -231.845325)
			(xy 168.434575 -231.827917) (xy 168.487593 -231.818124) (xy 168.541472 -231.816155) (xy 168.595063 -231.822052)
			(xy 168.647224 -231.835688) (xy 168.696844 -231.856775) (xy 168.742865 -231.884861) (xy 168.784307 -231.919349)
			(xy 168.820285 -231.959503) (xy 168.850033 -232.004467) (xy 168.872918 -232.053284) (xy 168.88845 -232.104913)
			(xy 168.8963 -232.158253) (xy 168.896792 -232.18521) (xy 168.8963 -232.212167) (xy 168.88845 -232.265507)
			(xy 168.872918 -232.317136) (xy 168.850033 -232.365953) (xy 168.820285 -232.410917) (xy 168.784307 -232.451071)
			(xy 168.742865 -232.485559) (xy 168.696844 -232.513645) (xy 168.647224 -232.534732) (xy 168.595063 -232.548368)
			(xy 168.541472 -232.554265) (xy 168.487593 -232.552296) (xy 168.434575 -232.542503) (xy 168.383548 -232.525095)
			(xy 168.3356 -232.500443) (xy 168.291752 -232.469073) (xy 168.252939 -232.431652) (xy 168.219987 -232.388979)
			(xy 168.193601 -232.341962) (xy 168.174341 -232.291605) (xy 168.162618 -232.238981) (xy 168.158683 -232.18521)
			(xy 161.612834 -232.18521) (xy 161.612834 -233.035348) (xy 164.058615 -233.035348) (xy 164.06255 -232.981577)
			(xy 164.074273 -232.928953) (xy 164.093533 -232.878596) (xy 164.119919 -232.831579) (xy 164.152871 -232.788906)
			(xy 164.191684 -232.751485) (xy 164.235532 -232.720115) (xy 164.28348 -232.695463) (xy 164.334507 -232.678055)
			(xy 164.387525 -232.668262) (xy 164.441404 -232.666293) (xy 164.494995 -232.67219) (xy 164.547156 -232.685826)
			(xy 164.596776 -232.706913) (xy 164.642797 -232.734999) (xy 164.684239 -232.769487) (xy 164.720217 -232.809641)
			(xy 164.749965 -232.854605) (xy 164.77285 -232.903422) (xy 164.788382 -232.955051) (xy 164.796232 -233.008391)
			(xy 164.796724 -233.035348) (xy 164.796232 -233.062305) (xy 164.788382 -233.115645) (xy 164.77285 -233.167274)
			(xy 164.749965 -233.216091) (xy 164.720217 -233.261055) (xy 164.684239 -233.301209) (xy 164.642797 -233.335697)
			(xy 164.596776 -233.363783) (xy 164.547156 -233.38487) (xy 164.494995 -233.398506) (xy 164.441404 -233.404403)
			(xy 164.387525 -233.402434) (xy 164.334507 -233.392641) (xy 164.28348 -233.375233) (xy 164.235532 -233.350581)
			(xy 164.191684 -233.319211) (xy 164.152871 -233.28179) (xy 164.119919 -233.239117) (xy 164.093533 -233.1921)
			(xy 164.074273 -233.141743) (xy 164.06255 -233.089119) (xy 164.058615 -233.035348) (xy 161.612834 -233.035348)
			(xy 161.612834 -233.885232) (xy 168.158683 -233.885232) (xy 168.162618 -233.831461) (xy 168.174341 -233.778837)
			(xy 168.193601 -233.72848) (xy 168.219987 -233.681463) (xy 168.252939 -233.63879) (xy 168.291752 -233.601369)
			(xy 168.3356 -233.569999) (xy 168.383548 -233.545347) (xy 168.434575 -233.527939) (xy 168.487593 -233.518146)
			(xy 168.541472 -233.516177) (xy 168.595063 -233.522074) (xy 168.647224 -233.53571) (xy 168.696844 -233.556797)
			(xy 168.742865 -233.584883) (xy 168.784307 -233.619371) (xy 168.820285 -233.659525) (xy 168.850033 -233.704489)
			(xy 168.872918 -233.753306) (xy 168.88845 -233.804935) (xy 168.8963 -233.858275) (xy 168.896792 -233.885232)
			(xy 168.8963 -233.912189) (xy 168.88845 -233.965529) (xy 168.872918 -234.017158) (xy 168.850033 -234.065975)
			(xy 168.820285 -234.110939) (xy 168.784307 -234.151093) (xy 168.742865 -234.185581) (xy 168.696844 -234.213667)
			(xy 168.647224 -234.234754) (xy 168.595063 -234.24839) (xy 168.541472 -234.254287) (xy 168.487593 -234.252318)
			(xy 168.434575 -234.242525) (xy 168.383548 -234.225117) (xy 168.3356 -234.200465) (xy 168.291752 -234.169095)
			(xy 168.252939 -234.131674) (xy 168.219987 -234.089001) (xy 168.193601 -234.041984) (xy 168.174341 -233.991627)
			(xy 168.162618 -233.939003) (xy 168.158683 -233.885232) (xy 161.612834 -233.885232) (xy 161.612834 -234.73537)
			(xy 164.058615 -234.73537) (xy 164.06255 -234.681599) (xy 164.074273 -234.628975) (xy 164.093533 -234.578618)
			(xy 164.119919 -234.531601) (xy 164.152871 -234.488928) (xy 164.191684 -234.451507) (xy 164.235532 -234.420137)
			(xy 164.28348 -234.395485) (xy 164.334507 -234.378077) (xy 164.387525 -234.368284) (xy 164.441404 -234.366315)
			(xy 164.494995 -234.372212) (xy 164.547156 -234.385848) (xy 164.596776 -234.406935) (xy 164.642797 -234.435021)
			(xy 164.684239 -234.469509) (xy 164.720217 -234.509663) (xy 164.749965 -234.554627) (xy 164.77285 -234.603444)
			(xy 164.788382 -234.655073) (xy 164.796232 -234.708413) (xy 164.796724 -234.73537) (xy 164.796232 -234.762327)
			(xy 164.788382 -234.815667) (xy 164.77285 -234.867296) (xy 164.749965 -234.916113) (xy 164.720217 -234.961077)
			(xy 164.684239 -235.001231) (xy 164.642797 -235.035719) (xy 164.596776 -235.063805) (xy 164.547156 -235.084892)
			(xy 164.494995 -235.098528) (xy 164.441404 -235.104425) (xy 164.387525 -235.102456) (xy 164.334507 -235.092663)
			(xy 164.28348 -235.075255) (xy 164.235532 -235.050603) (xy 164.191684 -235.019233) (xy 164.152871 -234.981812)
			(xy 164.119919 -234.939139) (xy 164.093533 -234.892122) (xy 164.074273 -234.841765) (xy 164.06255 -234.789141)
			(xy 164.058615 -234.73537) (xy 161.612834 -234.73537) (xy 161.612834 -235.585254) (xy 168.158683 -235.585254)
			(xy 168.162618 -235.531483) (xy 168.174341 -235.478859) (xy 168.193601 -235.428502) (xy 168.219987 -235.381485)
			(xy 168.252939 -235.338812) (xy 168.291752 -235.301391) (xy 168.3356 -235.270021) (xy 168.383548 -235.245369)
			(xy 168.434575 -235.227961) (xy 168.487593 -235.218168) (xy 168.541472 -235.216199) (xy 168.595063 -235.222096)
			(xy 168.647224 -235.235732) (xy 168.696844 -235.256819) (xy 168.742865 -235.284905) (xy 168.784307 -235.319393)
			(xy 168.820285 -235.359547) (xy 168.850033 -235.404511) (xy 168.872918 -235.453328) (xy 168.88845 -235.504957)
			(xy 168.8963 -235.558297) (xy 168.896792 -235.585254) (xy 168.8963 -235.612211) (xy 168.88845 -235.665551)
			(xy 168.872918 -235.71718) (xy 168.850033 -235.765997) (xy 168.820285 -235.810961) (xy 168.784307 -235.851115)
			(xy 168.742865 -235.885603) (xy 168.696844 -235.913689) (xy 168.647224 -235.934776) (xy 168.595063 -235.948412)
			(xy 168.541472 -235.954309) (xy 168.487593 -235.95234) (xy 168.434575 -235.942547) (xy 168.383548 -235.925139)
			(xy 168.3356 -235.900487) (xy 168.291752 -235.869117) (xy 168.252939 -235.831696) (xy 168.219987 -235.789023)
			(xy 168.193601 -235.742006) (xy 168.174341 -235.691649) (xy 168.162618 -235.639025) (xy 168.158683 -235.585254)
			(xy 161.612834 -235.585254) (xy 161.612834 -236.435392) (xy 164.058615 -236.435392) (xy 164.06255 -236.381621)
			(xy 164.074273 -236.328997) (xy 164.093533 -236.27864) (xy 164.119919 -236.231623) (xy 164.152871 -236.18895)
			(xy 164.191684 -236.151529) (xy 164.235532 -236.120159) (xy 164.28348 -236.095507) (xy 164.334507 -236.078099)
			(xy 164.387525 -236.068306) (xy 164.441404 -236.066337) (xy 164.494995 -236.072234) (xy 164.547156 -236.08587)
			(xy 164.596776 -236.106957) (xy 164.642797 -236.135043) (xy 164.684239 -236.169531) (xy 164.720217 -236.209685)
			(xy 164.749965 -236.254649) (xy 164.77285 -236.303466) (xy 164.788382 -236.355095) (xy 164.796232 -236.408435)
			(xy 164.796724 -236.435392) (xy 164.796232 -236.462349) (xy 164.788382 -236.515689) (xy 164.77285 -236.567318)
			(xy 164.749965 -236.616135) (xy 164.720217 -236.661099) (xy 164.684239 -236.701253) (xy 164.642797 -236.735741)
			(xy 164.596776 -236.763827) (xy 164.547156 -236.784914) (xy 164.494995 -236.79855) (xy 164.441404 -236.804447)
			(xy 164.387525 -236.802478) (xy 164.334507 -236.792685) (xy 164.28348 -236.775277) (xy 164.235532 -236.750625)
			(xy 164.191684 -236.719255) (xy 164.152871 -236.681834) (xy 164.119919 -236.639161) (xy 164.093533 -236.592144)
			(xy 164.074273 -236.541787) (xy 164.06255 -236.489163) (xy 164.058615 -236.435392) (xy 161.612834 -236.435392)
			(xy 161.612834 -237.285276) (xy 166.774383 -237.285276) (xy 166.778318 -237.231505) (xy 166.790041 -237.178881)
			(xy 166.809301 -237.128524) (xy 166.835687 -237.081507) (xy 166.868639 -237.038834) (xy 166.907452 -237.001413)
			(xy 166.9513 -236.970043) (xy 166.999248 -236.945391) (xy 167.050275 -236.927983) (xy 167.103293 -236.91819)
			(xy 167.157172 -236.916221) (xy 167.210763 -236.922118) (xy 167.262924 -236.935754) (xy 167.312544 -236.956841)
			(xy 167.358565 -236.984927) (xy 167.400007 -237.019415) (xy 167.435985 -237.059569) (xy 167.465733 -237.104533)
			(xy 167.488618 -237.15335) (xy 167.50415 -237.204979) (xy 167.512 -237.258319) (xy 167.512492 -237.285276)
			(xy 171.476162 -237.285276) (xy 171.476597 -237.254078) (xy 171.484422 -237.192175) (xy 171.499957 -237.131744)
			(xy 171.522956 -237.073742) (xy 171.553055 -237.019086) (xy 171.589779 -236.968642) (xy 171.632546 -236.923208)
			(xy 171.680678 -236.883503) (xy 171.706794 -236.86643) (xy 171.716954 -236.859826) (xy 171.729146 -236.840014)
			(xy 171.738544 -236.735874) (xy 171.730162 -236.714284) (xy 171.721272 -236.705902) (xy 171.702983 -236.68839)
			(xy 171.670905 -236.649212) (xy 171.644487 -236.606015) (xy 171.624227 -236.559609) (xy 171.610505 -236.510869)
			(xy 171.60358 -236.46071) (xy 171.603162 -236.435392) (xy 171.6036 -236.410045) (xy 171.610533 -236.359826)
			(xy 171.62428 -236.311031) (xy 171.644582 -236.264579) (xy 171.671057 -236.221347) (xy 171.703205 -236.182149)
			(xy 171.721526 -236.164628) (xy 171.730416 -236.1565) (xy 171.738798 -236.134656) (xy 171.729146 -236.030516)
			(xy 171.716954 -236.010704) (xy 171.706794 -236.004354) (xy 171.680699 -235.98723) (xy 171.632577 -235.947482)
			(xy 171.589821 -235.902011) (xy 171.553105 -235.851537) (xy 171.52301 -235.796856) (xy 171.500011 -235.738833)
			(xy 171.484472 -235.678383) (xy 171.476636 -235.616462) (xy 171.476162 -235.585254) (xy 171.476658 -235.554058)
			(xy 171.484473 -235.492157) (xy 171.499999 -235.431728) (xy 171.522989 -235.373726) (xy 171.55308 -235.31907)
			(xy 171.589796 -235.268625) (xy 171.632555 -235.223189) (xy 171.680681 -235.183482) (xy 171.706794 -235.166408)
			(xy 171.716954 -235.159804) (xy 171.729146 -235.139992) (xy 171.738544 -235.035852) (xy 171.730162 -235.014262)
			(xy 171.721272 -235.00588) (xy 171.702973 -234.988379) (xy 171.670895 -234.949199) (xy 171.644479 -234.905999)
			(xy 171.624221 -234.859591) (xy 171.610501 -234.810849) (xy 171.603578 -234.760688) (xy 171.603162 -234.73537)
			(xy 171.603586 -234.710022) (xy 171.610521 -234.659803) (xy 171.624271 -234.611008) (xy 171.644576 -234.564556)
			(xy 171.671053 -234.521324) (xy 171.703204 -234.482127) (xy 171.721526 -234.464606) (xy 171.730416 -234.456478)
			(xy 171.738798 -234.434634) (xy 171.729146 -234.330494) (xy 171.716954 -234.310682) (xy 171.706794 -234.304332)
			(xy 171.680689 -234.287223) (xy 171.632567 -234.247472) (xy 171.589811 -234.202) (xy 171.553096 -234.151523)
			(xy 171.523003 -234.096841) (xy 171.500005 -234.038815) (xy 171.484468 -233.978363) (xy 171.476635 -233.91644)
			(xy 171.476162 -233.885232) (xy 171.476641 -233.854035) (xy 171.484459 -233.792134) (xy 171.499987 -233.731704)
			(xy 171.52298 -233.673702) (xy 171.553073 -233.619046) (xy 171.589791 -233.568602) (xy 171.632552 -233.523166)
			(xy 171.68068 -233.48346) (xy 171.706794 -233.466386) (xy 171.716954 -233.459782) (xy 171.729146 -233.43997)
			(xy 171.738544 -233.33583) (xy 171.730162 -233.31424) (xy 171.721272 -233.305858) (xy 171.70301 -233.288319)
			(xy 171.670929 -233.249147) (xy 171.644508 -233.205955) (xy 171.624243 -233.159555) (xy 171.610516 -233.110819)
			(xy 171.603584 -233.060664) (xy 171.603162 -233.035348) (xy 171.603571 -233.01) (xy 171.61051 -232.95978)
			(xy 171.624262 -232.910984) (xy 171.64457 -232.864533) (xy 171.67105 -232.821301) (xy 171.703202 -232.782104)
			(xy 171.721526 -232.764584) (xy 171.730416 -232.756456) (xy 171.738798 -232.734612) (xy 171.729146 -232.630472)
			(xy 171.716954 -232.61066) (xy 171.706794 -232.60431) (xy 171.680679 -232.587216) (xy 171.632557 -232.547463)
			(xy 171.589802 -232.501988) (xy 171.553088 -232.45151) (xy 171.522995 -232.396825) (xy 171.5 -232.338797)
			(xy 171.484464 -232.278344) (xy 171.476634 -232.216419) (xy 171.476162 -232.18521) (xy 171.476651 -232.154047)
			(xy 171.484463 -232.092213) (xy 171.499963 -232.031845) (xy 171.522906 -231.973897) (xy 171.552932 -231.91928)
			(xy 171.589566 -231.868858) (xy 171.632231 -231.823424) (xy 171.680253 -231.783696) (xy 171.732877 -231.750301)
			(xy 171.789271 -231.723764) (xy 171.848546 -231.704504) (xy 171.909767 -231.692825) (xy 171.97197 -231.688912)
			(xy 172.034173 -231.692825) (xy 172.095394 -231.704504) (xy 172.154669 -231.723764) (xy 172.211063 -231.750301)
			(xy 172.263687 -231.783696) (xy 172.311709 -231.823424) (xy 172.354374 -231.868858) (xy 172.391008 -231.91928)
			(xy 172.421034 -231.973897) (xy 172.443977 -232.031845) (xy 172.459477 -232.092213) (xy 172.467289 -232.154047)
			(xy 172.467778 -232.18521) (xy 172.467296 -232.216419) (xy 172.459475 -232.278346) (xy 172.443946 -232.338802)
			(xy 172.420954 -232.396831) (xy 172.390862 -232.451517) (xy 172.354147 -232.501995) (xy 172.311387 -232.547467)
			(xy 172.263261 -232.587214) (xy 172.237146 -232.60431) (xy 172.226986 -232.61066) (xy 172.214794 -232.630472)
			(xy 172.205142 -232.734612) (xy 172.213524 -232.756456) (xy 172.222414 -232.764584) (xy 172.240729 -232.782112)
			(xy 172.272871 -232.821313) (xy 172.299345 -232.864545) (xy 172.319651 -232.910994) (xy 172.333407 -232.959786)
			(xy 172.340354 -233.010001) (xy 172.340778 -233.035348) (xy 172.340342 -233.060665) (xy 172.333421 -233.110823)
			(xy 172.319703 -233.159563) (xy 172.299445 -233.205968) (xy 172.273029 -233.249165) (xy 172.240951 -233.288341)
			(xy 172.222668 -233.305858) (xy 172.213778 -233.31424) (xy 172.205396 -233.33583) (xy 172.214794 -233.43997)
			(xy 172.226986 -233.459782) (xy 172.237146 -233.466386) (xy 172.263233 -233.483498) (xy 172.311352 -233.523207)
			(xy 172.354108 -233.568641) (xy 172.390825 -233.619081) (xy 172.420922 -233.673729) (xy 172.443923 -233.731723)
			(xy 172.459465 -233.792144) (xy 172.467303 -233.854038) (xy 172.467778 -233.885232) (xy 172.467313 -233.916442)
			(xy 172.45949 -233.978369) (xy 172.443958 -234.038825) (xy 172.420963 -234.096855) (xy 172.390869 -234.151541)
			(xy 172.354151 -234.202018) (xy 172.31139 -234.24749) (xy 172.263262 -234.287237) (xy 172.237146 -234.304332)
			(xy 172.226986 -234.310682) (xy 172.214794 -234.330494) (xy 172.205142 -234.434634) (xy 172.213524 -234.456478)
			(xy 172.222414 -234.464606) (xy 172.240739 -234.482123) (xy 172.272881 -234.521326) (xy 172.299353 -234.56456)
			(xy 172.319658 -234.611012) (xy 172.333411 -234.659805) (xy 172.340356 -234.710023) (xy 172.340778 -234.73537)
			(xy 172.340357 -234.760687) (xy 172.333433 -234.810847) (xy 172.319712 -234.859587) (xy 172.299452 -234.905992)
			(xy 172.273033 -234.949188) (xy 172.240953 -234.988364) (xy 172.222668 -235.00588) (xy 172.213778 -235.014262)
			(xy 172.205396 -235.035852) (xy 172.214794 -235.139992) (xy 172.226986 -235.159804) (xy 172.237146 -235.166408)
			(xy 172.263243 -235.183505) (xy 172.311362 -235.223217) (xy 172.354118 -235.268652) (xy 172.390833 -235.319094)
			(xy 172.420929 -235.373745) (xy 172.443929 -235.431741) (xy 172.459469 -235.492164) (xy 172.467304 -235.554059)
			(xy 172.467778 -235.585254) (xy 172.46733 -235.616464) (xy 172.459504 -235.678392) (xy 172.44397 -235.738849)
			(xy 172.420973 -235.796879) (xy 172.390876 -235.851564) (xy 172.354156 -235.902042) (xy 172.311393 -235.947513)
			(xy 172.263262 -235.987259) (xy 172.237146 -236.004354) (xy 172.226986 -236.010704) (xy 172.214794 -236.030516)
			(xy 172.205142 -236.134656) (xy 172.213524 -236.1565) (xy 172.222414 -236.164628) (xy 172.24075 -236.182135)
			(xy 172.272891 -236.22134) (xy 172.299362 -236.264576) (xy 172.319664 -236.31103) (xy 172.333416 -236.359825)
			(xy 172.340357 -236.410044) (xy 172.340778 -236.435392) (xy 175.57623 -236.435392) (xy 175.57671 -236.404183)
			(xy 175.584531 -236.342256) (xy 175.60006 -236.2818) (xy 175.623052 -236.22377) (xy 175.653144 -236.169084)
			(xy 175.68986 -236.118606) (xy 175.73262 -236.073135) (xy 175.780747 -236.033387) (xy 175.806862 -236.016292)
			(xy 175.817022 -236.009942) (xy 175.829214 -235.99013) (xy 175.838866 -235.88599) (xy 175.830484 -235.864146)
			(xy 175.821594 -235.856018) (xy 175.803282 -235.838488) (xy 175.771139 -235.799288) (xy 175.744664 -235.756056)
			(xy 175.724358 -235.709607) (xy 175.710601 -235.660816) (xy 175.703654 -235.610601) (xy 175.70323 -235.585254)
			(xy 175.703665 -235.559937) (xy 175.710585 -235.509778) (xy 175.724304 -235.461038) (xy 175.744561 -235.414633)
			(xy 175.770978 -235.371437) (xy 175.803056 -235.332261) (xy 175.82134 -235.314744) (xy 175.83023 -235.306362)
			(xy 175.838612 -235.284772) (xy 175.829214 -235.180632) (xy 175.817022 -235.16082) (xy 175.806862 -235.154216)
			(xy 175.780755 -235.137134) (xy 175.73264 -235.097417) (xy 175.689888 -235.051978) (xy 175.653175 -235.001533)
			(xy 175.623081 -234.946881) (xy 175.600082 -234.888884) (xy 175.584542 -234.828461) (xy 175.576705 -234.766565)
			(xy 175.57623 -234.73537) (xy 175.576693 -234.70416) (xy 175.584516 -234.642233) (xy 175.600048 -234.581776)
			(xy 175.623043 -234.523747) (xy 175.653137 -234.469061) (xy 175.689855 -234.418583) (xy 175.732617 -234.373112)
			(xy 175.780746 -234.333365) (xy 175.806862 -234.31627) (xy 175.817022 -234.30992) (xy 175.829214 -234.290108)
			(xy 175.838866 -234.185968) (xy 175.830484 -234.164124) (xy 175.821594 -234.155996) (xy 175.803271 -234.138476)
			(xy 175.771129 -234.099274) (xy 175.744656 -234.05604) (xy 175.724351 -234.009589) (xy 175.710597 -233.960796)
			(xy 175.703652 -233.910579) (xy 175.70323 -233.885232) (xy 175.70365 -233.859915) (xy 175.710574 -233.809755)
			(xy 175.724295 -233.761015) (xy 175.744555 -233.71461) (xy 175.770975 -233.671414) (xy 175.803055 -233.632238)
			(xy 175.82134 -233.614722) (xy 175.83023 -233.60634) (xy 175.838612 -233.58475) (xy 175.829214 -233.48061)
			(xy 175.817022 -233.460798) (xy 175.806862 -233.454194) (xy 175.780745 -233.437127) (xy 175.73263 -233.397408)
			(xy 175.689878 -233.351966) (xy 175.653166 -233.301519) (xy 175.623074 -233.246865) (xy 175.600077 -233.188866)
			(xy 175.584538 -233.128441) (xy 175.576704 -233.066544) (xy 175.57623 -233.035348) (xy 175.576676 -233.004138)
			(xy 175.584502 -232.942209) (xy 175.600036 -232.881753) (xy 175.623033 -232.823723) (xy 175.65313 -232.769037)
			(xy 175.689851 -232.71856) (xy 175.732614 -232.673089) (xy 175.780745 -232.633343) (xy 175.806862 -232.616248)
			(xy 175.817022 -232.609898) (xy 175.829214 -232.590086) (xy 175.838866 -232.485946) (xy 175.830484 -232.464102)
			(xy 175.821594 -232.455974) (xy 175.803261 -232.438465) (xy 175.771119 -232.39926) (xy 175.744648 -232.356024)
			(xy 175.724345 -232.309572) (xy 175.710593 -232.260776) (xy 175.703651 -232.210558) (xy 175.70323 -232.18521)
			(xy 175.703635 -232.159892) (xy 175.710562 -232.109732) (xy 175.724286 -232.060991) (xy 175.744549 -232.014586)
			(xy 175.770971 -231.97139) (xy 175.803054 -231.932216) (xy 175.82134 -231.9147) (xy 175.83023 -231.906318)
			(xy 175.838612 -231.884728) (xy 175.829214 -231.780588) (xy 175.817022 -231.760776) (xy 175.806862 -231.754172)
			(xy 175.780735 -231.73712) (xy 175.73262 -231.697399) (xy 175.689869 -231.651955) (xy 175.653158 -231.601505)
			(xy 175.623066 -231.546849) (xy 175.600071 -231.488849) (xy 175.584534 -231.428421) (xy 175.576703 -231.366522)
			(xy 175.57623 -231.335326) (xy 175.576719 -231.304163) (xy 175.584531 -231.242329) (xy 175.600031 -231.181961)
			(xy 175.622974 -231.124013) (xy 175.653 -231.069396) (xy 175.689634 -231.018974) (xy 175.732299 -230.97354)
			(xy 175.780321 -230.933812) (xy 175.832945 -230.900417) (xy 175.889339 -230.87388) (xy 175.948614 -230.85462)
			(xy 176.009835 -230.842941) (xy 176.072038 -230.839028) (xy 176.134241 -230.842941) (xy 176.195462 -230.85462)
			(xy 176.254737 -230.87388) (xy 176.311131 -230.900417) (xy 176.363755 -230.933812) (xy 176.411777 -230.97354)
			(xy 176.454442 -231.018974) (xy 176.491076 -231.069396) (xy 176.521102 -231.124013) (xy 176.544045 -231.181961)
			(xy 176.559545 -231.242329) (xy 176.567357 -231.304163) (xy 176.567846 -231.335326) (xy 180.531023 -231.335326)
			(xy 180.534958 -231.281555) (xy 180.546681 -231.228931) (xy 180.565941 -231.178574) (xy 180.592327 -231.131557)
			(xy 180.625279 -231.088884) (xy 180.664092 -231.051463) (xy 180.70794 -231.020093) (xy 180.755888 -230.995441)
			(xy 180.806915 -230.978033) (xy 180.859933 -230.96824) (xy 180.913812 -230.966271) (xy 180.967403 -230.972168)
			(xy 181.019564 -230.985804) (xy 181.069184 -231.006891) (xy 181.115205 -231.034977) (xy 181.156647 -231.069465)
			(xy 181.192625 -231.109619) (xy 181.222373 -231.154583) (xy 181.245258 -231.2034) (xy 181.26079 -231.255029)
			(xy 181.26864 -231.308369) (xy 181.269132 -231.335326) (xy 181.26864 -231.362283) (xy 181.26079 -231.415623)
			(xy 181.245258 -231.467252) (xy 181.222373 -231.516069) (xy 181.192625 -231.561033) (xy 181.156647 -231.601187)
			(xy 181.115205 -231.635675) (xy 181.069184 -231.663761) (xy 181.019564 -231.684848) (xy 180.967403 -231.698484)
			(xy 180.913812 -231.704381) (xy 180.859933 -231.702412) (xy 180.806915 -231.692619) (xy 180.755888 -231.675211)
			(xy 180.70794 -231.650559) (xy 180.664092 -231.619189) (xy 180.625279 -231.581768) (xy 180.592327 -231.539095)
			(xy 180.565941 -231.492078) (xy 180.546681 -231.441721) (xy 180.534958 -231.389097) (xy 180.531023 -231.335326)
			(xy 176.567846 -231.335326) (xy 176.567408 -231.366524) (xy 176.559584 -231.428427) (xy 176.544049 -231.488857)
			(xy 176.52105 -231.54686) (xy 176.490951 -231.601515) (xy 176.454228 -231.651959) (xy 176.411462 -231.697393)
			(xy 176.36333 -231.737099) (xy 176.337214 -231.754172) (xy 176.327054 -231.760776) (xy 176.314862 -231.780588)
			(xy 176.305464 -231.884728) (xy 176.313846 -231.906318) (xy 176.322736 -231.9147) (xy 176.341027 -231.932209)
			(xy 176.373105 -231.971388) (xy 176.399522 -232.014586) (xy 176.419782 -232.060992) (xy 176.433503 -232.109733)
			(xy 176.440428 -232.159892) (xy 176.440846 -232.18521) (xy 176.440406 -232.210557) (xy 176.433474 -232.260776)
			(xy 176.419727 -232.309571) (xy 176.399425 -232.356022) (xy 176.37295 -232.399255) (xy 176.340803 -232.438453)
			(xy 176.322482 -232.455974) (xy 176.313592 -232.464102) (xy 176.30521 -232.485946) (xy 176.314862 -232.590086)
			(xy 176.327054 -232.609898) (xy 176.337214 -232.616248) (xy 176.363312 -232.633367) (xy 176.411433 -232.673117)
			(xy 176.454189 -232.718588) (xy 176.490904 -232.769063) (xy 176.520999 -232.823744) (xy 176.543997 -232.881768)
			(xy 176.559537 -232.942218) (xy 176.567372 -233.00414) (xy 176.567846 -233.035348) (xy 176.567347 -233.066544)
			(xy 176.559532 -233.128444) (xy 176.544007 -233.188874) (xy 176.521017 -233.246875) (xy 176.490926 -233.301531)
			(xy 176.454211 -233.351976) (xy 176.411452 -233.397412) (xy 176.363327 -233.43712) (xy 176.337214 -233.454194)
			(xy 176.327054 -233.460798) (xy 176.314862 -233.48061) (xy 176.305464 -233.58475) (xy 176.313846 -233.60634)
			(xy 176.322736 -233.614722) (xy 176.341038 -233.632221) (xy 176.373115 -233.671402) (xy 176.399531 -233.714602)
			(xy 176.419788 -233.76101) (xy 176.433507 -233.809753) (xy 176.44043 -233.859914) (xy 176.440846 -233.885232)
			(xy 176.440421 -233.91058) (xy 176.433486 -233.960799) (xy 176.419736 -234.009594) (xy 176.399431 -234.056046)
			(xy 176.372954 -234.099278) (xy 176.340804 -234.138475) (xy 176.322482 -234.155996) (xy 176.313592 -234.164124)
			(xy 176.30521 -234.185968) (xy 176.314862 -234.290108) (xy 176.327054 -234.30992) (xy 176.337214 -234.31627)
			(xy 176.363322 -234.333375) (xy 176.411443 -234.373126) (xy 176.454199 -234.4186) (xy 176.490913 -234.469077)
			(xy 176.521006 -234.52376) (xy 176.544003 -234.581786) (xy 176.559541 -234.642238) (xy 176.567373 -234.704162)
			(xy 176.567846 -234.73537) (xy 176.567365 -234.766567) (xy 176.559547 -234.828468) (xy 176.544019 -234.888897)
			(xy 176.521026 -234.946899) (xy 176.490933 -235.001555) (xy 176.454216 -235.052) (xy 176.411455 -235.097435)
			(xy 176.363328 -235.137142) (xy 176.337214 -235.154216) (xy 176.327054 -235.16082) (xy 176.314862 -235.180632)
			(xy 176.305464 -235.284772) (xy 176.313846 -235.306362) (xy 176.322736 -235.314744) (xy 176.341 -235.332281)
			(xy 176.37308 -235.371453) (xy 176.399501 -235.414646) (xy 176.419766 -235.461046) (xy 176.433493 -235.509782)
			(xy 176.440425 -235.559938) (xy 176.440846 -235.585254) (xy 176.440436 -235.610602) (xy 176.433497 -235.660822)
			(xy 176.419744 -235.709617) (xy 176.399437 -235.756069) (xy 176.372957 -235.799301) (xy 176.340805 -235.838497)
			(xy 176.322482 -235.856018) (xy 176.313592 -235.864146) (xy 176.30521 -235.88599) (xy 176.314862 -235.99013)
			(xy 176.327054 -236.009942) (xy 176.337214 -236.016292) (xy 176.363332 -236.033382) (xy 176.411453 -236.073136)
			(xy 176.454208 -236.118611) (xy 176.490922 -236.169091) (xy 176.521014 -236.223776) (xy 176.544009 -236.281804)
			(xy 176.559544 -236.342258) (xy 176.567374 -236.404183) (xy 176.567846 -236.435392) (xy 176.567357 -236.466555)
			(xy 176.559545 -236.528389) (xy 176.544045 -236.588757) (xy 176.521102 -236.646705) (xy 176.491076 -236.701322)
			(xy 176.454442 -236.751744) (xy 176.411777 -236.797178) (xy 176.363755 -236.836906) (xy 176.311131 -236.870301)
			(xy 176.254737 -236.896838) (xy 176.195462 -236.916098) (xy 176.134241 -236.927777) (xy 176.072038 -236.93169)
			(xy 176.009835 -236.927777) (xy 175.948614 -236.916098) (xy 175.889339 -236.896838) (xy 175.832945 -236.870301)
			(xy 175.780321 -236.836906) (xy 175.732299 -236.797178) (xy 175.689634 -236.751744) (xy 175.653 -236.701322)
			(xy 175.622974 -236.646705) (xy 175.600031 -236.588757) (xy 175.584531 -236.528389) (xy 175.576719 -236.466555)
			(xy 175.57623 -236.435392) (xy 172.340778 -236.435392) (xy 172.340372 -236.46071) (xy 172.333445 -236.51087)
			(xy 172.319721 -236.55961) (xy 172.299458 -236.606015) (xy 172.273037 -236.649211) (xy 172.240954 -236.688386)
			(xy 172.222668 -236.705902) (xy 172.213778 -236.714284) (xy 172.205396 -236.735874) (xy 172.214794 -236.840014)
			(xy 172.226986 -236.859826) (xy 172.237146 -236.86643) (xy 172.263253 -236.883513) (xy 172.311372 -236.923226)
			(xy 172.354127 -236.968664) (xy 172.390842 -237.019108) (xy 172.420937 -237.073761) (xy 172.443935 -237.131758)
			(xy 172.459473 -237.192183) (xy 172.467305 -237.254081) (xy 172.467778 -237.285276) (xy 174.318437 -237.285276)
			(xy 174.322372 -237.231505) (xy 174.334095 -237.178881) (xy 174.353355 -237.128524) (xy 174.379741 -237.081507)
			(xy 174.412693 -237.038834) (xy 174.451506 -237.001413) (xy 174.495354 -236.970043) (xy 174.543302 -236.945391)
			(xy 174.594329 -236.927983) (xy 174.647347 -236.91819) (xy 174.701226 -236.916221) (xy 174.754817 -236.922118)
			(xy 174.806978 -236.935754) (xy 174.856598 -236.956841) (xy 174.902619 -236.984927) (xy 174.944061 -237.019415)
			(xy 174.980039 -237.059569) (xy 175.009787 -237.104533) (xy 175.032672 -237.15335) (xy 175.048204 -237.204979)
			(xy 175.056054 -237.258319) (xy 175.056546 -237.285276) (xy 179.020216 -237.285276) (xy 179.020626 -237.254077)
			(xy 179.028452 -237.192172) (xy 179.043989 -237.131739) (xy 179.06699 -237.073736) (xy 179.097094 -237.01908)
			(xy 179.133821 -236.968636) (xy 179.176592 -236.923204) (xy 179.22473 -236.883501) (xy 179.250848 -236.86643)
			(xy 179.261008 -236.859826) (xy 179.2732 -236.840014) (xy 179.282598 -236.735874) (xy 179.274216 -236.714284)
			(xy 179.265326 -236.705902) (xy 179.247028 -236.688399) (xy 179.214953 -236.649218) (xy 179.188537 -236.606018)
			(xy 179.168279 -236.559612) (xy 179.154559 -236.51087) (xy 179.147634 -236.46071) (xy 179.147216 -236.435392)
			(xy 179.147637 -236.410044) (xy 179.154571 -236.359824) (xy 179.16832 -236.311028) (xy 179.188625 -236.264576)
			(xy 179.215104 -236.221344) (xy 179.247256 -236.182148) (xy 179.26558 -236.164628) (xy 179.27447 -236.1565)
			(xy 179.282852 -236.134656) (xy 179.2732 -236.030516) (xy 179.261008 -236.010704) (xy 179.250848 -236.004354)
			(xy 179.224742 -235.987247) (xy 179.176622 -235.947494) (xy 179.133868 -235.90202) (xy 179.097154 -235.851544)
			(xy 179.067061 -235.796861) (xy 179.044063 -235.738836) (xy 179.028524 -235.678385) (xy 179.02069 -235.616462)
			(xy 179.020216 -235.585254) (xy 179.020687 -235.554057) (xy 179.028503 -235.492154) (xy 179.044031 -235.431723)
			(xy 179.067024 -235.37372) (xy 179.097118 -235.319064) (xy 179.133838 -235.268619) (xy 179.176602 -235.223185)
			(xy 179.224733 -235.18348) (xy 179.250848 -235.166408) (xy 179.261008 -235.159804) (xy 179.2732 -235.139992)
			(xy 179.282598 -235.035852) (xy 179.274216 -235.014262) (xy 179.265326 -235.00588) (xy 179.247018 -234.988388)
			(xy 179.214943 -234.949205) (xy 179.188529 -234.906003) (xy 179.168273 -234.859594) (xy 179.154554 -234.81085)
			(xy 179.147632 -234.760689) (xy 179.147216 -234.73537) (xy 179.147622 -234.710021) (xy 179.154559 -234.659801)
			(xy 179.168311 -234.611004) (xy 179.188619 -234.564552) (xy 179.2151 -234.521321) (xy 179.247255 -234.482125)
			(xy 179.26558 -234.464606) (xy 179.27447 -234.456478) (xy 179.282852 -234.434634) (xy 179.2732 -234.330494)
			(xy 179.261008 -234.310682) (xy 179.250848 -234.304332) (xy 179.224732 -234.287239) (xy 179.176612 -234.247485)
			(xy 179.133858 -234.202009) (xy 179.097145 -234.15153) (xy 179.067053 -234.096845) (xy 179.044057 -234.038818)
			(xy 179.028521 -233.978365) (xy 179.020688 -233.916441) (xy 179.020216 -233.885232) (xy 179.02067 -233.854034)
			(xy 179.028489 -233.792131) (xy 179.044019 -233.7317) (xy 179.067014 -233.673697) (xy 179.097111 -233.61904)
			(xy 179.133833 -233.568596) (xy 179.176599 -233.523162) (xy 179.224732 -233.483458) (xy 179.250848 -233.466386)
			(xy 179.261008 -233.459782) (xy 179.2732 -233.43997) (xy 179.282598 -233.33583) (xy 179.274216 -233.31424)
			(xy 179.265326 -233.305858) (xy 179.247056 -233.288328) (xy 179.214977 -233.249153) (xy 179.188558 -233.205959)
			(xy 179.168295 -233.159557) (xy 179.154569 -233.110821) (xy 179.147637 -233.060664) (xy 179.147216 -233.035348)
			(xy 179.147608 -233.009999) (xy 179.154547 -232.959778) (xy 179.168302 -232.910981) (xy 179.188613 -232.864529)
			(xy 179.215097 -232.821298) (xy 179.247254 -232.782103) (xy 179.26558 -232.764584) (xy 179.27447 -232.756456)
			(xy 179.282852 -232.734612) (xy 179.2732 -232.630472) (xy 179.261008 -232.61066) (xy 179.250848 -232.60431)
			(xy 179.224722 -232.587232) (xy 179.176602 -232.547475) (xy 179.133849 -232.501997) (xy 179.097137 -232.451516)
			(xy 179.067046 -232.396829) (xy 179.044052 -232.3388) (xy 179.028517 -232.278345) (xy 179.020687 -232.216419)
			(xy 179.020216 -232.18521) (xy 179.020705 -232.154047) (xy 179.028517 -232.092213) (xy 179.044017 -232.031845)
			(xy 179.06696 -231.973897) (xy 179.096986 -231.91928) (xy 179.13362 -231.868858) (xy 179.176285 -231.823424)
			(xy 179.224307 -231.783696) (xy 179.276931 -231.750301) (xy 179.333325 -231.723764) (xy 179.3926 -231.704504)
			(xy 179.453821 -231.692825) (xy 179.516024 -231.688912) (xy 179.578227 -231.692825) (xy 179.639448 -231.704504)
			(xy 179.698723 -231.723764) (xy 179.755117 -231.750301) (xy 179.807741 -231.783696) (xy 179.855763 -231.823424)
			(xy 179.898428 -231.868858) (xy 179.935062 -231.91928) (xy 179.965088 -231.973897) (xy 179.988031 -232.031845)
			(xy 180.003531 -232.092213) (xy 180.011343 -232.154047) (xy 180.011832 -232.18521) (xy 180.011325 -232.216418)
			(xy 180.003505 -232.278343) (xy 179.987978 -232.338797) (xy 179.964988 -232.396825) (xy 179.9349 -232.451511)
			(xy 179.898189 -232.501989) (xy 179.855434 -232.547463) (xy 179.807312 -232.587213) (xy 179.7812 -232.60431)
			(xy 179.77104 -232.61066) (xy 179.758848 -232.630472) (xy 179.749196 -232.734612) (xy 179.757578 -232.756456)
			(xy 179.766468 -232.764584) (xy 179.784774 -232.782121) (xy 179.816919 -232.821319) (xy 179.843395 -232.864548)
			(xy 179.863703 -232.910996) (xy 179.877461 -232.959787) (xy 179.884408 -233.010001) (xy 179.884832 -233.035348)
			(xy 179.88441 -233.060666) (xy 179.877489 -233.110825) (xy 179.863769 -233.159566) (xy 179.843509 -233.205971)
			(xy 179.817089 -233.249167) (xy 179.785007 -233.288342) (xy 179.766722 -233.305858) (xy 179.757832 -233.31424)
			(xy 179.74945 -233.33583) (xy 179.758848 -233.43997) (xy 179.77104 -233.459782) (xy 179.7812 -233.466386)
			(xy 179.807299 -233.483479) (xy 179.855416 -233.523193) (xy 179.89817 -233.568631) (xy 179.934884 -233.619073)
			(xy 179.964979 -233.673724) (xy 179.987979 -233.73172) (xy 180.00352 -233.792142) (xy 180.011357 -233.854037)
			(xy 180.011832 -233.885232) (xy 180.011342 -233.916441) (xy 180.00352 -233.978366) (xy 179.98799 -234.038821)
			(xy 179.964998 -234.096849) (xy 179.934907 -234.151534) (xy 179.898194 -234.202012) (xy 179.855437 -234.247486)
			(xy 179.807313 -234.287235) (xy 179.7812 -234.304332) (xy 179.77104 -234.310682) (xy 179.758848 -234.330494)
			(xy 179.749196 -234.434634) (xy 179.757578 -234.456478) (xy 179.766468 -234.464606) (xy 179.784784 -234.482132)
			(xy 179.816929 -234.521332) (xy 179.843404 -234.564564) (xy 179.86371 -234.611014) (xy 179.877465 -234.659807)
			(xy 179.88441 -234.710023) (xy 179.884832 -234.73537) (xy 179.884425 -234.760688) (xy 179.877501 -234.810848)
			(xy 179.863778 -234.85959) (xy 179.843515 -234.905995) (xy 179.817093 -234.94919) (xy 179.785008 -234.988365)
			(xy 179.766722 -235.00588) (xy 179.757832 -235.014262) (xy 179.74945 -235.035852) (xy 179.758848 -235.139992)
			(xy 179.77104 -235.159804) (xy 179.7812 -235.166408) (xy 179.807309 -235.183487) (xy 179.855426 -235.223203)
			(xy 179.898179 -235.268642) (xy 179.934893 -235.319087) (xy 179.964987 -235.37374) (xy 179.987985 -235.431737)
			(xy 180.003524 -235.492162) (xy 180.011358 -235.554059) (xy 180.011832 -235.585254) (xy 180.011359 -235.616463)
			(xy 180.003534 -235.678389) (xy 179.988002 -235.738844) (xy 179.965007 -235.796873) (xy 179.934914 -235.851558)
			(xy 179.898198 -235.902036) (xy 179.85544 -235.947508) (xy 179.807314 -235.987257) (xy 179.7812 -236.004354)
			(xy 179.77104 -236.010704) (xy 179.758848 -236.030516) (xy 179.749196 -236.134656) (xy 179.757578 -236.1565)
			(xy 179.766468 -236.164628) (xy 179.784795 -236.182143) (xy 179.816939 -236.221346) (xy 179.843412 -236.26458)
			(xy 179.863716 -236.311032) (xy 179.877469 -236.359826) (xy 179.884411 -236.410044) (xy 179.884832 -236.435392)
			(xy 183.120284 -236.435392) (xy 183.120785 -236.404183) (xy 183.128605 -236.342258) (xy 183.144133 -236.281804)
			(xy 183.167123 -236.223775) (xy 183.197212 -236.16909) (xy 183.233924 -236.118611) (xy 183.27668 -236.073138)
			(xy 183.324803 -236.033389) (xy 183.350916 -236.016292) (xy 183.361076 -236.009942) (xy 183.373268 -235.99013)
			(xy 183.38292 -235.88599) (xy 183.374538 -235.864146) (xy 183.365648 -235.856018) (xy 183.347346 -235.838477)
			(xy 183.3152 -235.799281) (xy 183.288723 -235.756052) (xy 183.268414 -235.709605) (xy 183.254656 -235.660815)
			(xy 183.247708 -235.6106) (xy 183.247284 -235.585254) (xy 183.247733 -235.559938) (xy 183.254653 -235.50978)
			(xy 183.268369 -235.461041) (xy 183.288624 -235.414636) (xy 183.315037 -235.371439) (xy 183.347112 -235.332261)
			(xy 183.365394 -235.314744) (xy 183.374284 -235.306362) (xy 183.382666 -235.284772) (xy 183.373268 -235.180632)
			(xy 183.361076 -235.16082) (xy 183.350916 -235.154216) (xy 183.324822 -235.137116) (xy 183.276704 -235.097403)
			(xy 183.23395 -235.051967) (xy 183.197234 -235.001526) (xy 183.167139 -234.946876) (xy 183.144138 -234.888881)
			(xy 183.128597 -234.828459) (xy 183.120759 -234.766564) (xy 183.120284 -234.73537) (xy 183.120768 -234.704161)
			(xy 183.128591 -234.642235) (xy 183.144121 -234.58178) (xy 183.167113 -234.523751) (xy 183.197205 -234.469066)
			(xy 183.233919 -234.418588) (xy 183.276677 -234.373115) (xy 183.324802 -234.333367) (xy 183.350916 -234.31627)
			(xy 183.361076 -234.30992) (xy 183.373268 -234.290108) (xy 183.38292 -234.185968) (xy 183.374538 -234.164124)
			(xy 183.365648 -234.155996) (xy 183.347336 -234.138466) (xy 183.31519 -234.099267) (xy 183.288715 -234.056036)
			(xy 183.268408 -234.009587) (xy 183.254652 -233.960795) (xy 183.247706 -233.910579) (xy 183.247284 -233.885232)
			(xy 183.247718 -233.859915) (xy 183.254641 -233.809757) (xy 183.26836 -233.761017) (xy 183.288618 -233.714613)
			(xy 183.315034 -233.671416) (xy 183.347111 -233.632239) (xy 183.365394 -233.614722) (xy 183.374284 -233.60634)
			(xy 183.382666 -233.58475) (xy 183.373268 -233.48061) (xy 183.361076 -233.460798) (xy 183.350916 -233.454194)
			(xy 183.324812 -233.437108) (xy 183.276694 -233.397394) (xy 183.23394 -233.351956) (xy 183.197226 -233.301512)
			(xy 183.167131 -233.24686) (xy 183.144132 -233.188863) (xy 183.128593 -233.128439) (xy 183.120758 -233.066543)
			(xy 183.120284 -233.035348) (xy 183.120751 -233.004138) (xy 183.128576 -232.942212) (xy 183.144109 -232.881757)
			(xy 183.167104 -232.823728) (xy 183.197198 -232.769042) (xy 183.233915 -232.718565) (xy 183.276674 -232.673092)
			(xy 183.324801 -232.633344) (xy 183.350916 -232.616248) (xy 183.361076 -232.609898) (xy 183.373268 -232.590086)
			(xy 183.38292 -232.485946) (xy 183.374538 -232.464102) (xy 183.365648 -232.455974) (xy 183.347325 -232.438454)
			(xy 183.31518 -232.399253) (xy 183.288706 -232.35602) (xy 183.268401 -232.309569) (xy 183.254648 -232.260775)
			(xy 183.247705 -232.210558) (xy 183.247284 -232.18521) (xy 183.247704 -232.159893) (xy 183.254629 -232.109734)
			(xy 183.268351 -232.060994) (xy 183.288612 -232.01459) (xy 183.315031 -231.971393) (xy 183.34711 -231.932217)
			(xy 183.365394 -231.9147) (xy 183.374284 -231.906318) (xy 183.382666 -231.884728) (xy 183.373268 -231.780588)
			(xy 183.361076 -231.760776) (xy 183.350916 -231.754172) (xy 183.324801 -231.737101) (xy 183.276684 -231.697385)
			(xy 183.23393 -231.651944) (xy 183.197217 -231.601498) (xy 183.167124 -231.546844) (xy 183.144127 -231.488845)
			(xy 183.128589 -231.42842) (xy 183.120757 -231.366522) (xy 183.120284 -231.335326) (xy 183.120773 -231.304163)
			(xy 183.128585 -231.242329) (xy 183.144085 -231.181961) (xy 183.167028 -231.124013) (xy 183.197054 -231.069396)
			(xy 183.233688 -231.018974) (xy 183.276353 -230.97354) (xy 183.324375 -230.933812) (xy 183.376999 -230.900417)
			(xy 183.433393 -230.87388) (xy 183.492668 -230.85462) (xy 183.553889 -230.842941) (xy 183.616092 -230.839028)
			(xy 183.678295 -230.842941) (xy 183.739516 -230.85462) (xy 183.798791 -230.87388) (xy 183.855185 -230.900417)
			(xy 183.907809 -230.933812) (xy 183.955831 -230.97354) (xy 183.998496 -231.018974) (xy 184.03513 -231.069396)
			(xy 184.065156 -231.124013) (xy 184.088099 -231.181961) (xy 184.103599 -231.242329) (xy 184.111411 -231.304163)
			(xy 184.1119 -231.335326) (xy 188.075077 -231.335326) (xy 188.079012 -231.281555) (xy 188.090735 -231.228931)
			(xy 188.109995 -231.178574) (xy 188.136381 -231.131557) (xy 188.169333 -231.088884) (xy 188.208146 -231.051463)
			(xy 188.251994 -231.020093) (xy 188.299942 -230.995441) (xy 188.350969 -230.978033) (xy 188.403987 -230.96824)
			(xy 188.457866 -230.966271) (xy 188.511457 -230.972168) (xy 188.563618 -230.985804) (xy 188.613238 -231.006891)
			(xy 188.659259 -231.034977) (xy 188.700701 -231.069465) (xy 188.736679 -231.109619) (xy 188.766427 -231.154583)
			(xy 188.789312 -231.2034) (xy 188.804844 -231.255029) (xy 188.812694 -231.308369) (xy 188.813186 -231.335326)
			(xy 188.812694 -231.362283) (xy 188.804844 -231.415623) (xy 188.789312 -231.467252) (xy 188.766427 -231.516069)
			(xy 188.736679 -231.561033) (xy 188.700701 -231.601187) (xy 188.659259 -231.635675) (xy 188.613238 -231.663761)
			(xy 188.563618 -231.684848) (xy 188.511457 -231.698484) (xy 188.457866 -231.704381) (xy 188.403987 -231.702412)
			(xy 188.350969 -231.692619) (xy 188.299942 -231.675211) (xy 188.251994 -231.650559) (xy 188.208146 -231.619189)
			(xy 188.169333 -231.581768) (xy 188.136381 -231.539095) (xy 188.109995 -231.492078) (xy 188.090735 -231.441721)
			(xy 188.079012 -231.389097) (xy 188.075077 -231.335326) (xy 184.1119 -231.335326) (xy 184.111484 -231.366525)
			(xy 184.103658 -231.428429) (xy 184.088122 -231.488861) (xy 184.065121 -231.546865) (xy 184.035018 -231.60152)
			(xy 183.998292 -231.651964) (xy 183.955522 -231.697397) (xy 183.907386 -231.7371) (xy 183.881268 -231.754172)
			(xy 183.871108 -231.760776) (xy 183.858916 -231.780588) (xy 183.849518 -231.884728) (xy 183.8579 -231.906318)
			(xy 183.86679 -231.9147) (xy 183.885092 -231.932199) (xy 183.917166 -231.971381) (xy 183.943581 -232.014582)
			(xy 183.963838 -232.060989) (xy 183.977558 -232.109731) (xy 183.984482 -232.159892) (xy 183.9849 -232.18521)
			(xy 183.984475 -232.210558) (xy 183.977542 -232.260777) (xy 183.963793 -232.309573) (xy 183.943488 -232.356025)
			(xy 183.91701 -232.399257) (xy 183.884859 -232.438454) (xy 183.866536 -232.455974) (xy 183.857646 -232.464102)
			(xy 183.849264 -232.485946) (xy 183.858916 -232.590086) (xy 183.871108 -232.609898) (xy 183.881268 -232.616248)
			(xy 183.907355 -232.633383) (xy 183.955479 -232.673129) (xy 183.998237 -232.718597) (xy 184.034954 -232.769069)
			(xy 184.06505 -232.823748) (xy 184.08805 -232.881771) (xy 184.10359 -232.94222) (xy 184.111426 -233.004141)
			(xy 184.1119 -233.035348) (xy 184.111423 -233.066545) (xy 184.103607 -233.128447) (xy 184.08808 -233.188878)
			(xy 184.065087 -233.24688) (xy 184.034994 -233.301536) (xy 183.998275 -233.351981) (xy 183.955512 -233.397416)
			(xy 183.907383 -233.437121) (xy 183.881268 -233.454194) (xy 183.871108 -233.460798) (xy 183.858916 -233.48061)
			(xy 183.849518 -233.58475) (xy 183.8579 -233.60634) (xy 183.86679 -233.614722) (xy 183.885102 -233.63221)
			(xy 183.917176 -233.671395) (xy 183.943589 -233.714598) (xy 183.963845 -233.761007) (xy 183.977562 -233.809751)
			(xy 183.984484 -233.859913) (xy 183.9849 -233.885232) (xy 183.98449 -233.910581) (xy 183.977553 -233.960801)
			(xy 183.963801 -234.009597) (xy 183.943494 -234.056049) (xy 183.917014 -234.09928) (xy 183.88486 -234.138476)
			(xy 183.866536 -234.155996) (xy 183.857646 -234.164124) (xy 183.849264 -234.185968) (xy 183.858916 -234.290108)
			(xy 183.871108 -234.30992) (xy 183.881268 -234.31627) (xy 183.907365 -234.333391) (xy 183.955489 -234.373138)
			(xy 183.998246 -234.418609) (xy 184.034963 -234.469083) (xy 184.065058 -234.523764) (xy 184.088056 -234.581789)
			(xy 184.103594 -234.64224) (xy 184.111427 -234.704162) (xy 184.1119 -234.73537) (xy 184.11144 -234.766567)
			(xy 184.103621 -234.82847) (xy 184.088092 -234.888901) (xy 184.065097 -234.946904) (xy 184.035001 -235.00156)
			(xy 183.99828 -235.052005) (xy 183.955515 -235.097439) (xy 183.907384 -235.137143) (xy 183.881268 -235.154216)
			(xy 183.871108 -235.16082) (xy 183.858916 -235.180632) (xy 183.849518 -235.284772) (xy 183.8579 -235.306362)
			(xy 183.86679 -235.314744) (xy 183.885064 -235.33227) (xy 183.917142 -235.371446) (xy 183.94356 -235.414641)
			(xy 183.963822 -235.461043) (xy 183.977548 -235.509781) (xy 183.984479 -235.559937) (xy 183.9849 -235.585254)
			(xy 183.984504 -235.610603) (xy 183.977565 -235.660824) (xy 183.96381 -235.70962) (xy 183.9435 -235.756072)
			(xy 183.917017 -235.799303) (xy 183.884861 -235.838499) (xy 183.866536 -235.856018) (xy 183.857646 -235.864146)
			(xy 183.849264 -235.88599) (xy 183.858916 -235.99013) (xy 183.871108 -236.009942) (xy 183.881268 -236.016292)
			(xy 183.907375 -236.033398) (xy 183.955499 -236.073148) (xy 183.998256 -236.11862) (xy 184.034971 -236.169097)
			(xy 184.065065 -236.22378) (xy 184.088062 -236.281807) (xy 184.103598 -236.342259) (xy 184.111428 -236.404183)
			(xy 184.1119 -236.435392) (xy 184.111411 -236.466555) (xy 184.103599 -236.528389) (xy 184.088099 -236.588757)
			(xy 184.065156 -236.646705) (xy 184.03513 -236.701322) (xy 183.998496 -236.751744) (xy 183.955831 -236.797178)
			(xy 183.907809 -236.836906) (xy 183.855185 -236.870301) (xy 183.798791 -236.896838) (xy 183.739516 -236.916098)
			(xy 183.678295 -236.927777) (xy 183.616092 -236.93169) (xy 183.553889 -236.927777) (xy 183.492668 -236.916098)
			(xy 183.433393 -236.896838) (xy 183.376999 -236.870301) (xy 183.324375 -236.836906) (xy 183.276353 -236.797178)
			(xy 183.233688 -236.751744) (xy 183.197054 -236.701322) (xy 183.167028 -236.646705) (xy 183.144085 -236.588757)
			(xy 183.128585 -236.528389) (xy 183.120773 -236.466555) (xy 183.120284 -236.435392) (xy 179.884832 -236.435392)
			(xy 179.88444 -236.460711) (xy 179.877512 -236.510872) (xy 179.863787 -236.559613) (xy 179.843521 -236.606018)
			(xy 179.817096 -236.649213) (xy 179.78501 -236.688387) (xy 179.766722 -236.705902) (xy 179.757832 -236.714284)
			(xy 179.74945 -236.735874) (xy 179.758848 -236.840014) (xy 179.77104 -236.859826) (xy 179.7812 -236.86643)
			(xy 179.807319 -236.883494) (xy 179.855436 -236.923212) (xy 179.898189 -236.968654) (xy 179.934901 -237.019101)
			(xy 179.964994 -237.073756) (xy 179.987991 -237.131755) (xy 180.003528 -237.192182) (xy 180.011359 -237.25408)
			(xy 180.011832 -237.285276) (xy 181.862491 -237.285276) (xy 181.866426 -237.231505) (xy 181.878149 -237.178881)
			(xy 181.897409 -237.128524) (xy 181.923795 -237.081507) (xy 181.956747 -237.038834) (xy 181.99556 -237.001413)
			(xy 182.039408 -236.970043) (xy 182.087356 -236.945391) (xy 182.138383 -236.927983) (xy 182.191401 -236.91819)
			(xy 182.24528 -236.916221) (xy 182.298871 -236.922118) (xy 182.351032 -236.935754) (xy 182.400652 -236.956841)
			(xy 182.446673 -236.984927) (xy 182.488115 -237.019415) (xy 182.524093 -237.059569) (xy 182.553841 -237.104533)
			(xy 182.576726 -237.15335) (xy 182.592258 -237.204979) (xy 182.600108 -237.258319) (xy 182.6006 -237.285276)
			(xy 186.56427 -237.285276) (xy 186.564702 -237.254078) (xy 186.572526 -237.192174) (xy 186.588061 -237.131743)
			(xy 186.611061 -237.073741) (xy 186.641161 -237.019085) (xy 186.677885 -236.968641) (xy 186.720652 -236.923207)
			(xy 186.768786 -236.883503) (xy 186.794902 -236.86643) (xy 186.805062 -236.859826) (xy 186.817254 -236.840014)
			(xy 186.826652 -236.735874) (xy 186.81827 -236.714284) (xy 186.80938 -236.705902) (xy 186.791093 -236.688388)
			(xy 186.759014 -236.649211) (xy 186.732596 -236.606014) (xy 186.712335 -236.559609) (xy 186.698613 -236.510869)
			(xy 186.691688 -236.46071) (xy 186.69127 -236.435392) (xy 186.691706 -236.410044) (xy 186.698638 -236.359826)
			(xy 186.712386 -236.311031) (xy 186.732689 -236.264579) (xy 186.759164 -236.221347) (xy 186.791312 -236.182149)
			(xy 186.809634 -236.164628) (xy 186.818524 -236.1565) (xy 186.826906 -236.134656) (xy 186.817254 -236.030516)
			(xy 186.805062 -236.010704) (xy 186.794902 -236.004354) (xy 186.768809 -235.987228) (xy 186.720687 -235.94748)
			(xy 186.67793 -235.90201) (xy 186.641214 -235.851536) (xy 186.611119 -235.796856) (xy 186.58812 -235.738833)
			(xy 186.57258 -235.678383) (xy 186.564744 -235.616462) (xy 186.56427 -235.585254) (xy 186.564763 -235.554058)
			(xy 186.572578 -235.492157) (xy 186.588103 -235.431727) (xy 186.611094 -235.373725) (xy 186.641186 -235.319069)
			(xy 186.677902 -235.268624) (xy 186.720662 -235.223189) (xy 186.768789 -235.183482) (xy 186.794902 -235.166408)
			(xy 186.805062 -235.159804) (xy 186.817254 -235.139992) (xy 186.826652 -235.035852) (xy 186.81827 -235.014262)
			(xy 186.80938 -235.00588) (xy 186.791082 -234.988377) (xy 186.759004 -234.949198) (xy 186.732588 -234.905998)
			(xy 186.712329 -234.859591) (xy 186.698609 -234.810849) (xy 186.691686 -234.760688) (xy 186.69127 -234.73537)
			(xy 186.691691 -234.710022) (xy 186.698627 -234.659803) (xy 186.712377 -234.611007) (xy 186.732683 -234.564555)
			(xy 186.75916 -234.521324) (xy 186.791311 -234.482127) (xy 186.809634 -234.464606) (xy 186.818524 -234.456478)
			(xy 186.826906 -234.434634) (xy 186.817254 -234.330494) (xy 186.805062 -234.310682) (xy 186.794902 -234.304332)
			(xy 186.768799 -234.28722) (xy 186.720677 -234.24747) (xy 186.67792 -234.201998) (xy 186.641205 -234.151522)
			(xy 186.611111 -234.09684) (xy 186.588114 -234.038815) (xy 186.572576 -233.978363) (xy 186.564743 -233.91644)
			(xy 186.56427 -233.885232) (xy 186.564745 -233.854035) (xy 186.572563 -233.792134) (xy 186.588092 -233.731703)
			(xy 186.611085 -233.673701) (xy 186.641179 -233.619045) (xy 186.677897 -233.568601) (xy 186.720659 -233.523166)
			(xy 186.768788 -233.48346) (xy 186.794902 -233.466386) (xy 186.805062 -233.459782) (xy 186.817254 -233.43997)
			(xy 186.826652 -233.33583) (xy 186.81827 -233.31424) (xy 186.80938 -233.305858) (xy 186.79112 -233.288317)
			(xy 186.759039 -233.249146) (xy 186.732617 -233.205954) (xy 186.712352 -233.159555) (xy 186.698624 -233.110819)
			(xy 186.691692 -233.060664) (xy 186.69127 -233.035348) (xy 186.691676 -233.009999) (xy 186.698615 -232.95978)
			(xy 186.712368 -232.910984) (xy 186.732676 -232.864532) (xy 186.759157 -232.821301) (xy 186.79131 -232.782104)
			(xy 186.809634 -232.764584) (xy 186.818524 -232.756456) (xy 186.826906 -232.734612) (xy 186.817254 -232.630472)
			(xy 186.805062 -232.61066) (xy 186.794902 -232.60431) (xy 186.768789 -232.587213) (xy 186.720667 -232.547461)
			(xy 186.677911 -232.501987) (xy 186.641197 -232.451509) (xy 186.611104 -232.396824) (xy 186.588108 -232.338797)
			(xy 186.572572 -232.278343) (xy 186.564742 -232.216419) (xy 186.56427 -232.18521) (xy 186.564759 -232.154047)
			(xy 186.572571 -232.092213) (xy 186.588071 -232.031845) (xy 186.611014 -231.973897) (xy 186.64104 -231.91928)
			(xy 186.677674 -231.868858) (xy 186.720339 -231.823424) (xy 186.768361 -231.783696) (xy 186.820985 -231.750301)
			(xy 186.877379 -231.723764) (xy 186.936654 -231.704504) (xy 186.997875 -231.692825) (xy 187.060078 -231.688912)
			(xy 187.122281 -231.692825) (xy 187.183502 -231.704504) (xy 187.242777 -231.723764) (xy 187.299171 -231.750301)
			(xy 187.351795 -231.783696) (xy 187.399817 -231.823424) (xy 187.442482 -231.868858) (xy 187.479116 -231.91928)
			(xy 187.509142 -231.973897) (xy 187.532085 -232.031845) (xy 187.547585 -232.092213) (xy 187.555397 -232.154047)
			(xy 187.555886 -232.18521) (xy 187.5554 -232.216419) (xy 187.54758 -232.278345) (xy 187.532051 -232.338801)
			(xy 187.509059 -232.39683) (xy 187.478968 -232.451516) (xy 187.442253 -232.501994) (xy 187.399494 -232.547466)
			(xy 187.351368 -232.587214) (xy 187.325254 -232.60431) (xy 187.315094 -232.61066) (xy 187.302902 -232.630472)
			(xy 187.29325 -232.734612) (xy 187.301632 -232.756456) (xy 187.310522 -232.764584) (xy 187.328838 -232.78211)
			(xy 187.360981 -232.821312) (xy 187.387454 -232.864544) (xy 187.40776 -232.910993) (xy 187.421515 -232.959785)
			(xy 187.428462 -233.010001) (xy 187.428886 -233.035348) (xy 187.428447 -233.060665) (xy 187.421527 -233.110823)
			(xy 187.407809 -233.159563) (xy 187.387552 -233.205968) (xy 187.361136 -233.249164) (xy 187.329059 -233.288341)
			(xy 187.310776 -233.305858) (xy 187.301886 -233.31424) (xy 187.293504 -233.33583) (xy 187.302902 -233.43997)
			(xy 187.315094 -233.459782) (xy 187.325254 -233.466386) (xy 187.351342 -233.483495) (xy 187.399461 -233.523205)
			(xy 187.442217 -233.568639) (xy 187.478933 -233.61908) (xy 187.50903 -233.673729) (xy 187.532031 -233.731722)
			(xy 187.547573 -233.792144) (xy 187.555411 -233.854038) (xy 187.555886 -233.885232) (xy 187.555417 -233.916442)
			(xy 187.547594 -233.978369) (xy 187.532063 -234.038824) (xy 187.509068 -234.096854) (xy 187.478975 -234.15154)
			(xy 187.442258 -234.202017) (xy 187.399497 -234.247489) (xy 187.351369 -234.287236) (xy 187.325254 -234.304332)
			(xy 187.315094 -234.310682) (xy 187.302902 -234.330494) (xy 187.29325 -234.434634) (xy 187.301632 -234.456478)
			(xy 187.310522 -234.464606) (xy 187.328849 -234.482122) (xy 187.36099 -234.521325) (xy 187.387462 -234.56456)
			(xy 187.407766 -234.611011) (xy 187.42152 -234.659805) (xy 187.428464 -234.710022) (xy 187.428886 -234.73537)
			(xy 187.428462 -234.760687) (xy 187.421539 -234.810846) (xy 187.407818 -234.859587) (xy 187.387558 -234.905991)
			(xy 187.36114 -234.949188) (xy 187.32906 -234.988364) (xy 187.310776 -235.00588) (xy 187.301886 -235.014262)
			(xy 187.293504 -235.035852) (xy 187.302902 -235.139992) (xy 187.315094 -235.159804) (xy 187.325254 -235.166408)
			(xy 187.351353 -235.183503) (xy 187.399471 -235.223215) (xy 187.442227 -235.268651) (xy 187.478942 -235.319093)
			(xy 187.509038 -235.373744) (xy 187.532037 -235.43174) (xy 187.547577 -235.492163) (xy 187.555412 -235.554059)
			(xy 187.555886 -235.585254) (xy 187.555435 -235.616464) (xy 187.547609 -235.678392) (xy 187.532074 -235.738848)
			(xy 187.509078 -235.796878) (xy 187.478982 -235.851563) (xy 187.442262 -235.902041) (xy 187.3995 -235.947512)
			(xy 187.35137 -235.987259) (xy 187.325254 -236.004354) (xy 187.315094 -236.010704) (xy 187.302902 -236.030516)
			(xy 187.29325 -236.134656) (xy 187.301632 -236.1565) (xy 187.310522 -236.164628) (xy 187.328859 -236.182133)
			(xy 187.361 -236.221339) (xy 187.38747 -236.264576) (xy 187.407772 -236.311029) (xy 187.421524 -236.359825)
			(xy 187.428465 -236.410044) (xy 187.428886 -236.435392) (xy 190.664338 -236.435392) (xy 190.664814 -236.404182)
			(xy 190.672635 -236.342255) (xy 190.688165 -236.281799) (xy 190.711157 -236.223769) (xy 190.74125 -236.169083)
			(xy 190.777966 -236.118606) (xy 190.820727 -236.073134) (xy 190.868855 -236.033387) (xy 190.89497 -236.016292)
			(xy 190.90513 -236.009942) (xy 190.917322 -235.99013) (xy 190.926974 -235.88599) (xy 190.918592 -235.864146)
			(xy 190.909702 -235.856018) (xy 190.891391 -235.838486) (xy 190.859248 -235.799287) (xy 190.832773 -235.756056)
			(xy 190.812466 -235.709607) (xy 190.798709 -235.660816) (xy 190.791762 -235.610601) (xy 190.791338 -235.585254)
			(xy 190.79177 -235.559937) (xy 190.798691 -235.509778) (xy 190.81241 -235.461038) (xy 190.832668 -235.414633)
			(xy 190.859085 -235.371436) (xy 190.891164 -235.33226) (xy 190.909448 -235.314744) (xy 190.918338 -235.306362)
			(xy 190.92672 -235.284772) (xy 190.917322 -235.180632) (xy 190.90513 -235.16082) (xy 190.89497 -235.154216)
			(xy 190.868865 -235.137132) (xy 190.820749 -235.097415) (xy 190.777997 -235.051976) (xy 190.741284 -235.001532)
			(xy 190.71119 -234.94688) (xy 190.688191 -234.888884) (xy 190.67265 -234.828461) (xy 190.664813 -234.766565)
			(xy 190.664338 -234.73537) (xy 190.664797 -234.70416) (xy 190.672621 -234.642232) (xy 190.688153 -234.581776)
			(xy 190.711148 -234.523746) (xy 190.741243 -234.46906) (xy 190.777962 -234.418582) (xy 190.820724 -234.373111)
			(xy 190.868854 -234.333365) (xy 190.89497 -234.31627) (xy 190.90513 -234.30992) (xy 190.917322 -234.290108)
			(xy 190.926974 -234.185968) (xy 190.918592 -234.164124) (xy 190.909702 -234.155996) (xy 190.891381 -234.138475)
			(xy 190.859238 -234.099273) (xy 190.832765 -234.05604) (xy 190.81246 -234.009589) (xy 190.798705 -233.960796)
			(xy 190.79176 -233.910579) (xy 190.791338 -233.885232) (xy 190.791756 -233.859914) (xy 190.798679 -233.809755)
			(xy 190.812401 -233.761014) (xy 190.832662 -233.71461) (xy 190.859082 -233.671413) (xy 190.891163 -233.632238)
			(xy 190.909448 -233.614722) (xy 190.918338 -233.60634) (xy 190.92672 -233.58475) (xy 190.917322 -233.48061)
			(xy 190.90513 -233.460798) (xy 190.89497 -233.454194) (xy 190.868855 -233.437124) (xy 190.820739 -233.397406)
			(xy 190.777988 -233.351965) (xy 190.741275 -233.301518) (xy 190.711182 -233.246864) (xy 190.688185 -233.188866)
			(xy 190.672646 -233.128441) (xy 190.664812 -233.066544) (xy 190.664338 -233.035348) (xy 190.66478 -233.004137)
			(xy 190.672606 -232.942209) (xy 190.688141 -232.881752) (xy 190.711139 -232.823722) (xy 190.741236 -232.769036)
			(xy 190.777957 -232.718559) (xy 190.820721 -232.673088) (xy 190.868853 -232.633342) (xy 190.89497 -232.616248)
			(xy 190.90513 -232.609898) (xy 190.917322 -232.590086) (xy 190.926974 -232.485946) (xy 190.918592 -232.464102)
			(xy 190.909702 -232.455974) (xy 190.89137 -232.438463) (xy 190.859228 -232.399259) (xy 190.832756 -232.356024)
			(xy 190.812453 -232.309571) (xy 190.798701 -232.260776) (xy 190.791759 -232.210558) (xy 190.791338 -232.18521)
			(xy 190.791741 -232.159892) (xy 190.798667 -232.109732) (xy 190.812391 -232.060991) (xy 190.832655 -232.014586)
			(xy 190.859078 -231.97139) (xy 190.891162 -231.932215) (xy 190.909448 -231.9147) (xy 190.918338 -231.906318)
			(xy 190.92672 -231.884728) (xy 190.917322 -231.780588) (xy 190.90513 -231.760776) (xy 190.89497 -231.754172)
			(xy 190.868845 -231.737117) (xy 190.820729 -231.697397) (xy 190.777978 -231.651953) (xy 190.741266 -231.601504)
			(xy 190.711175 -231.546848) (xy 190.688179 -231.488848) (xy 190.672642 -231.428421) (xy 190.664811 -231.366522)
			(xy 190.664338 -231.335326) (xy 190.664827 -231.304163) (xy 190.672639 -231.242329) (xy 190.688139 -231.181961)
			(xy 190.711082 -231.124013) (xy 190.741108 -231.069396) (xy 190.777742 -231.018974) (xy 190.820407 -230.97354)
			(xy 190.868429 -230.933812) (xy 190.921053 -230.900417) (xy 190.977447 -230.87388) (xy 191.036722 -230.85462)
			(xy 191.097943 -230.842941) (xy 191.160146 -230.839028) (xy 191.222349 -230.842941) (xy 191.28357 -230.85462)
			(xy 191.342845 -230.87388) (xy 191.399239 -230.900417) (xy 191.451863 -230.933812) (xy 191.499885 -230.97354)
			(xy 191.54255 -231.018974) (xy 191.579184 -231.069396) (xy 191.60921 -231.124013) (xy 191.632153 -231.181961)
			(xy 191.647653 -231.242329) (xy 191.655465 -231.304163) (xy 191.655954 -231.335326) (xy 195.619131 -231.335326)
			(xy 195.623066 -231.281555) (xy 195.634789 -231.228931) (xy 195.654049 -231.178574) (xy 195.680435 -231.131557)
			(xy 195.713387 -231.088884) (xy 195.7522 -231.051463) (xy 195.796048 -231.020093) (xy 195.843996 -230.995441)
			(xy 195.895023 -230.978033) (xy 195.948041 -230.96824) (xy 196.00192 -230.966271) (xy 196.055511 -230.972168)
			(xy 196.107672 -230.985804) (xy 196.157292 -231.006891) (xy 196.203313 -231.034977) (xy 196.244755 -231.069465)
			(xy 196.280733 -231.109619) (xy 196.310481 -231.154583) (xy 196.333366 -231.2034) (xy 196.348898 -231.255029)
			(xy 196.356748 -231.308369) (xy 196.35724 -231.335326) (xy 196.356748 -231.362283) (xy 196.348898 -231.415623)
			(xy 196.333366 -231.467252) (xy 196.310481 -231.516069) (xy 196.280733 -231.561033) (xy 196.244755 -231.601187)
			(xy 196.203313 -231.635675) (xy 196.157292 -231.663761) (xy 196.107672 -231.684848) (xy 196.055511 -231.698484)
			(xy 196.00192 -231.704381) (xy 195.948041 -231.702412) (xy 195.895023 -231.692619) (xy 195.843996 -231.675211)
			(xy 195.796048 -231.650559) (xy 195.7522 -231.619189) (xy 195.713387 -231.581768) (xy 195.680435 -231.539095)
			(xy 195.654049 -231.492078) (xy 195.634789 -231.441721) (xy 195.623066 -231.389097) (xy 195.619131 -231.335326)
			(xy 191.655954 -231.335326) (xy 191.655513 -231.366524) (xy 191.647688 -231.428426) (xy 191.632154 -231.488857)
			(xy 191.609155 -231.546859) (xy 191.579056 -231.601514) (xy 191.542334 -231.651958) (xy 191.499569 -231.697393)
			(xy 191.451437 -231.737099) (xy 191.425322 -231.754172) (xy 191.415162 -231.760776) (xy 191.40297 -231.780588)
			(xy 191.393572 -231.884728) (xy 191.401954 -231.906318) (xy 191.410844 -231.9147) (xy 191.429137 -231.932208)
			(xy 191.461214 -231.971387) (xy 191.487631 -232.014585) (xy 191.50789 -232.060991) (xy 191.521611 -232.109732)
			(xy 191.528536 -232.159892) (xy 191.528954 -232.18521) (xy 191.528544 -232.210559) (xy 191.521609 -232.260779)
			(xy 191.507859 -232.309576) (xy 191.487551 -232.356028) (xy 191.46107 -232.39926) (xy 191.428915 -232.438455)
			(xy 191.41059 -232.455974) (xy 191.4017 -232.464102) (xy 191.393318 -232.485946) (xy 191.40297 -232.590086)
			(xy 191.415162 -232.609898) (xy 191.425322 -232.616248) (xy 191.451422 -232.633364) (xy 191.499543 -232.673115)
			(xy 191.542299 -232.718586) (xy 191.579014 -232.769062) (xy 191.609108 -232.823743) (xy 191.632106 -232.881767)
			(xy 191.647646 -232.942218) (xy 191.65548 -233.00414) (xy 191.655954 -233.035348) (xy 191.655452 -233.066544)
			(xy 191.647637 -233.128444) (xy 191.632112 -233.188873) (xy 191.609122 -233.246874) (xy 191.579032 -233.30153)
			(xy 191.542317 -233.351975) (xy 191.499559 -233.397412) (xy 191.451434 -233.437119) (xy 191.425322 -233.454194)
			(xy 191.415162 -233.460798) (xy 191.40297 -233.48061) (xy 191.393572 -233.58475) (xy 191.401954 -233.60634)
			(xy 191.410844 -233.614722) (xy 191.429147 -233.632219) (xy 191.461224 -233.671401) (xy 191.487639 -233.714601)
			(xy 191.507897 -233.761009) (xy 191.521616 -233.809752) (xy 191.528538 -233.859914) (xy 191.528954 -233.885232)
			(xy 191.528558 -233.910581) (xy 191.521621 -233.960802) (xy 191.507867 -234.009599) (xy 191.487557 -234.056052)
			(xy 191.461074 -234.099283) (xy 191.428916 -234.138477) (xy 191.41059 -234.155996) (xy 191.4017 -234.164124)
			(xy 191.393318 -234.185968) (xy 191.40297 -234.290108) (xy 191.415162 -234.30992) (xy 191.425322 -234.31627)
			(xy 191.451432 -234.333372) (xy 191.499553 -234.373124) (xy 191.542308 -234.418598) (xy 191.579022 -234.469075)
			(xy 191.609115 -234.523759) (xy 191.632112 -234.581785) (xy 191.647649 -234.642238) (xy 191.655482 -234.704161)
			(xy 191.655954 -234.73537) (xy 191.655469 -234.766566) (xy 191.647651 -234.828467) (xy 191.632124 -234.888897)
			(xy 191.609131 -234.946898) (xy 191.579039 -235.001554) (xy 191.542322 -235.051999) (xy 191.499562 -235.097434)
			(xy 191.451435 -235.137142) (xy 191.425322 -235.154216) (xy 191.415162 -235.16082) (xy 191.40297 -235.180632)
			(xy 191.393572 -235.284772) (xy 191.401954 -235.306362) (xy 191.410844 -235.314744) (xy 191.42911 -235.332279)
			(xy 191.46119 -235.371452) (xy 191.48761 -235.414645) (xy 191.507874 -235.461046) (xy 191.521601 -235.509782)
			(xy 191.528533 -235.559938) (xy 191.528954 -235.585254) (xy 191.528573 -235.610604) (xy 191.521633 -235.660826)
			(xy 191.507876 -235.709623) (xy 191.487563 -235.756075) (xy 191.461077 -235.799306) (xy 191.428917 -235.8385)
			(xy 191.41059 -235.856018) (xy 191.4017 -235.864146) (xy 191.393318 -235.88599) (xy 191.40297 -235.99013)
			(xy 191.415162 -236.009942) (xy 191.425322 -236.016292) (xy 191.451442 -236.033379) (xy 191.499563 -236.073133)
			(xy 191.542318 -236.11861) (xy 191.579031 -236.169089) (xy 191.609123 -236.223775) (xy 191.632118 -236.281803)
			(xy 191.647653 -236.342258) (xy 191.655483 -236.404183) (xy 191.655954 -236.435392) (xy 191.655465 -236.466555)
			(xy 191.647653 -236.528389) (xy 191.632153 -236.588757) (xy 191.60921 -236.646705) (xy 191.579184 -236.701322)
			(xy 191.54255 -236.751744) (xy 191.499885 -236.797178) (xy 191.451863 -236.836906) (xy 191.399239 -236.870301)
			(xy 191.342845 -236.896838) (xy 191.28357 -236.916098) (xy 191.222349 -236.927777) (xy 191.160146 -236.93169)
			(xy 191.097943 -236.927777) (xy 191.036722 -236.916098) (xy 190.977447 -236.896838) (xy 190.921053 -236.870301)
			(xy 190.868429 -236.836906) (xy 190.820407 -236.797178) (xy 190.777742 -236.751744) (xy 190.741108 -236.701322)
			(xy 190.711082 -236.646705) (xy 190.688139 -236.588757) (xy 190.672639 -236.528389) (xy 190.664827 -236.466555)
			(xy 190.664338 -236.435392) (xy 187.428886 -236.435392) (xy 187.428477 -236.46071) (xy 187.421551 -236.51087)
			(xy 187.407827 -236.55961) (xy 187.387564 -236.606015) (xy 187.361144 -236.649211) (xy 187.329062 -236.688386)
			(xy 187.310776 -236.705902) (xy 187.301886 -236.714284) (xy 187.293504 -236.735874) (xy 187.302902 -236.840014)
			(xy 187.315094 -236.859826) (xy 187.325254 -236.86643) (xy 187.351363 -236.88351) (xy 187.399481 -236.923224)
			(xy 187.442236 -236.968663) (xy 187.478951 -237.019107) (xy 187.509045 -237.07376) (xy 187.532043 -237.131758)
			(xy 187.547581 -237.192183) (xy 187.555413 -237.254081) (xy 187.555886 -237.285276) (xy 189.406545 -237.285276)
			(xy 189.41048 -237.231505) (xy 189.422203 -237.178881) (xy 189.441463 -237.128524) (xy 189.467849 -237.081507)
			(xy 189.500801 -237.038834) (xy 189.539614 -237.001413) (xy 189.583462 -236.970043) (xy 189.63141 -236.945391)
			(xy 189.682437 -236.927983) (xy 189.735455 -236.91819) (xy 189.789334 -236.916221) (xy 189.842925 -236.922118)
			(xy 189.895086 -236.935754) (xy 189.944706 -236.956841) (xy 189.990727 -236.984927) (xy 190.032169 -237.019415)
			(xy 190.068147 -237.059569) (xy 190.097895 -237.104533) (xy 190.12078 -237.15335) (xy 190.136312 -237.204979)
			(xy 190.144162 -237.258319) (xy 190.144654 -237.285276) (xy 194.108324 -237.285276) (xy 194.108731 -237.254077)
			(xy 194.116556 -237.192171) (xy 194.132093 -237.131739) (xy 194.155096 -237.073735) (xy 194.185199 -237.019079)
			(xy 194.221928 -236.968635) (xy 194.264699 -236.923203) (xy 194.312837 -236.883501) (xy 194.338956 -236.86643)
			(xy 194.349116 -236.859826) (xy 194.361308 -236.840014) (xy 194.370706 -236.735874) (xy 194.362324 -236.714284)
			(xy 194.353434 -236.705902) (xy 194.335138 -236.688397) (xy 194.303062 -236.649217) (xy 194.276646 -236.606018)
			(xy 194.256387 -236.559611) (xy 194.242667 -236.51087) (xy 194.235742 -236.46071) (xy 194.235324 -236.435392)
			(xy 194.235743 -236.410044) (xy 194.242676 -236.359824) (xy 194.256426 -236.311027) (xy 194.276732 -236.264575)
			(xy 194.303211 -236.221344) (xy 194.335364 -236.182148) (xy 194.353688 -236.164628) (xy 194.362578 -236.1565)
			(xy 194.37096 -236.134656) (xy 194.361308 -236.030516) (xy 194.349116 -236.010704) (xy 194.338956 -236.004354)
			(xy 194.312852 -235.987244) (xy 194.264732 -235.947492) (xy 194.221977 -235.902019) (xy 194.185263 -235.851542)
			(xy 194.155169 -235.79686) (xy 194.132172 -235.738835) (xy 194.116633 -235.678384) (xy 194.108798 -235.616462)
			(xy 194.108324 -235.585254) (xy 194.108792 -235.554057) (xy 194.116608 -235.492154) (xy 194.132135 -235.431723)
			(xy 194.155129 -235.373719) (xy 194.185224 -235.319063) (xy 194.221944 -235.268618) (xy 194.264709 -235.223184)
			(xy 194.31284 -235.18348) (xy 194.338956 -235.166408) (xy 194.349116 -235.159804) (xy 194.361308 -235.139992)
			(xy 194.370706 -235.035852) (xy 194.362324 -235.014262) (xy 194.353434 -235.00588) (xy 194.335127 -234.988386)
			(xy 194.303052 -234.949204) (xy 194.276638 -234.906002) (xy 194.256381 -234.859593) (xy 194.242663 -234.81085)
			(xy 194.23574 -234.760688) (xy 194.235324 -234.73537) (xy 194.235728 -234.710021) (xy 194.242665 -234.659801)
			(xy 194.256417 -234.611004) (xy 194.276726 -234.564552) (xy 194.303207 -234.521321) (xy 194.335363 -234.482125)
			(xy 194.353688 -234.464606) (xy 194.362578 -234.456478) (xy 194.37096 -234.434634) (xy 194.361308 -234.330494)
			(xy 194.349116 -234.310682) (xy 194.338956 -234.304332) (xy 194.312842 -234.287237) (xy 194.264722 -234.247483)
			(xy 194.221967 -234.202007) (xy 194.185254 -234.151529) (xy 194.155162 -234.096844) (xy 194.132166 -234.038818)
			(xy 194.116629 -233.978365) (xy 194.108796 -233.916441) (xy 194.108324 -233.885232) (xy 194.108774 -233.854034)
			(xy 194.116593 -233.792131) (xy 194.132123 -233.731699) (xy 194.155119 -233.673696) (xy 194.185217 -233.619039)
			(xy 194.22194 -233.568595) (xy 194.264706 -233.523161) (xy 194.312839 -233.483458) (xy 194.338956 -233.466386)
			(xy 194.349116 -233.459782) (xy 194.361308 -233.43997) (xy 194.370706 -233.33583) (xy 194.362324 -233.31424)
			(xy 194.353434 -233.305858) (xy 194.335165 -233.288326) (xy 194.303086 -233.249152) (xy 194.276667 -233.205958)
			(xy 194.256404 -233.159557) (xy 194.242677 -233.11082) (xy 194.235746 -233.060664) (xy 194.235324 -233.035348)
			(xy 194.235713 -233.009999) (xy 194.242653 -232.959777) (xy 194.256408 -232.910981) (xy 194.27672 -232.864529)
			(xy 194.303204 -232.821298) (xy 194.335362 -232.782103) (xy 194.353688 -232.764584) (xy 194.362578 -232.756456)
			(xy 194.37096 -232.734612) (xy 194.361308 -232.630472) (xy 194.349116 -232.61066) (xy 194.338956 -232.60431)
			(xy 194.312832 -232.587229) (xy 194.264712 -232.547473) (xy 194.221958 -232.501996) (xy 194.185246 -232.451515)
			(xy 194.155154 -232.396828) (xy 194.13216 -232.3388) (xy 194.116625 -232.278345) (xy 194.108795 -232.216419)
			(xy 194.108324 -232.18521) (xy 194.108813 -232.154047) (xy 194.116625 -232.092213) (xy 194.132125 -232.031845)
			(xy 194.155068 -231.973897) (xy 194.185094 -231.91928) (xy 194.221728 -231.868858) (xy 194.264393 -231.823424)
			(xy 194.312415 -231.783696) (xy 194.365039 -231.750301) (xy 194.421433 -231.723764) (xy 194.480708 -231.704504)
			(xy 194.541929 -231.692825) (xy 194.604132 -231.688912) (xy 194.666335 -231.692825) (xy 194.727556 -231.704504)
			(xy 194.786831 -231.723764) (xy 194.843225 -231.750301) (xy 194.895849 -231.783696) (xy 194.943871 -231.823424)
			(xy 194.986536 -231.868858) (xy 195.02317 -231.91928) (xy 195.053196 -231.973897) (xy 195.076139 -232.031845)
			(xy 195.091639 -232.092213) (xy 195.099451 -232.154047) (xy 195.09994 -232.18521) (xy 195.099429 -232.216418)
			(xy 195.09161 -232.278342) (xy 195.076083 -232.338796) (xy 195.053094 -232.396824) (xy 195.023006 -232.45151)
			(xy 194.986295 -232.501988) (xy 194.943541 -232.547462) (xy 194.89542 -232.587212) (xy 194.869308 -232.60431)
			(xy 194.859148 -232.61066) (xy 194.846956 -232.630472) (xy 194.837304 -232.734612) (xy 194.845686 -232.756456)
			(xy 194.854576 -232.764584) (xy 194.872883 -232.782119) (xy 194.905028 -232.821318) (xy 194.931504 -232.864548)
			(xy 194.951812 -232.910996) (xy 194.965569 -232.959787) (xy 194.972516 -233.010001) (xy 194.97294 -233.035348)
			(xy 194.972516 -233.060665) (xy 194.965595 -233.110825) (xy 194.951875 -233.159566) (xy 194.931615 -233.205971)
			(xy 194.905196 -233.249167) (xy 194.873115 -233.288342) (xy 194.85483 -233.305858) (xy 194.84594 -233.31424)
			(xy 194.837558 -233.33583) (xy 194.846956 -233.43997) (xy 194.859148 -233.459782) (xy 194.869308 -233.466386)
			(xy 194.895409 -233.483477) (xy 194.943525 -233.523191) (xy 194.986279 -233.568629) (xy 195.022993 -233.619072)
			(xy 195.053088 -233.673724) (xy 195.076087 -233.731719) (xy 195.091628 -233.792142) (xy 195.099465 -233.854037)
			(xy 195.09994 -233.885232) (xy 195.099446 -233.916441) (xy 195.091624 -233.978366) (xy 195.076094 -234.03882)
			(xy 195.053103 -234.096848) (xy 195.023013 -234.151533) (xy 194.9863 -234.202012) (xy 194.943544 -234.247485)
			(xy 194.895421 -234.287235) (xy 194.869308 -234.304332) (xy 194.859148 -234.310682) (xy 194.846956 -234.330494)
			(xy 194.837304 -234.434634) (xy 194.845686 -234.456478) (xy 194.854576 -234.464606) (xy 194.872894 -234.482131)
			(xy 194.905038 -234.521331) (xy 194.931512 -234.564564) (xy 194.951818 -234.611014) (xy 194.965573 -234.659806)
			(xy 194.972518 -234.710023) (xy 194.97294 -234.73537) (xy 194.972531 -234.760688) (xy 194.965606 -234.810848)
			(xy 194.951884 -234.859589) (xy 194.931621 -234.905994) (xy 194.9052 -234.94919) (xy 194.873116 -234.988365)
			(xy 194.85483 -235.00588) (xy 194.84594 -235.014262) (xy 194.837558 -235.035852) (xy 194.846956 -235.139992)
			(xy 194.859148 -235.159804) (xy 194.869308 -235.166408) (xy 194.895419 -235.183484) (xy 194.943535 -235.223201)
			(xy 194.986288 -235.268641) (xy 195.023002 -235.319086) (xy 195.053095 -235.37374) (xy 195.076093 -235.431737)
			(xy 195.091632 -235.492162) (xy 195.099466 -235.554059) (xy 195.09994 -235.585254) (xy 195.099464 -235.616463)
			(xy 195.091639 -235.678389) (xy 195.076106 -235.738844) (xy 195.053112 -235.796872) (xy 195.02302 -235.851557)
			(xy 194.986305 -235.902035) (xy 194.943547 -235.947508) (xy 194.895422 -235.987257) (xy 194.869308 -236.004354)
			(xy 194.859148 -236.010704) (xy 194.846956 -236.030516) (xy 194.837304 -236.134656) (xy 194.845686 -236.1565)
			(xy 194.854576 -236.164628) (xy 194.872905 -236.182142) (xy 194.905048 -236.221345) (xy 194.931521 -236.264579)
			(xy 194.951824 -236.311032) (xy 194.965577 -236.359826) (xy 194.972519 -236.410044) (xy 194.97294 -236.435392)
			(xy 198.208392 -236.435392) (xy 198.20889 -236.404183) (xy 198.21671 -236.342258) (xy 198.232237 -236.281803)
			(xy 198.255228 -236.223774) (xy 198.285317 -236.169089) (xy 198.32203 -236.118611) (xy 198.364787 -236.073138)
			(xy 198.412911 -236.033389) (xy 198.439024 -236.016292) (xy 198.449184 -236.009942) (xy 198.461376 -235.99013)
			(xy 198.471028 -235.88599) (xy 198.462646 -235.864146) (xy 198.453756 -235.856018) (xy 198.435456 -235.838475)
			(xy 198.403309 -235.79928) (xy 198.376832 -235.756051) (xy 198.356522 -235.709604) (xy 198.342764 -235.660815)
			(xy 198.335816 -235.6106) (xy 198.335392 -235.585254) (xy 198.335838 -235.559938) (xy 198.342758 -235.50978)
			(xy 198.356475 -235.46104) (xy 198.376731 -235.414636) (xy 198.403144 -235.371439) (xy 198.43522 -235.332261)
			(xy 198.453502 -235.314744) (xy 198.462392 -235.306362) (xy 198.470774 -235.284772) (xy 198.461376 -235.180632)
			(xy 198.449184 -235.16082) (xy 198.439024 -235.154216) (xy 198.412931 -235.137113) (xy 198.364813 -235.097401)
			(xy 198.322059 -235.051966) (xy 198.285343 -235.001525) (xy 198.255247 -234.946875) (xy 198.232246 -234.888881)
			(xy 198.216705 -234.828459) (xy 198.208867 -234.766564) (xy 198.208392 -234.73537) (xy 198.208872 -234.704161)
			(xy 198.216695 -234.642235) (xy 198.232226 -234.58178) (xy 198.255218 -234.523751) (xy 198.28531 -234.469065)
			(xy 198.322026 -234.418587) (xy 198.364784 -234.373115) (xy 198.41291 -234.333366) (xy 198.439024 -234.31627)
			(xy 198.449184 -234.30992) (xy 198.461376 -234.290108) (xy 198.471028 -234.185968) (xy 198.462646 -234.164124)
			(xy 198.453756 -234.155996) (xy 198.435445 -234.138464) (xy 198.403299 -234.099266) (xy 198.376823 -234.056035)
			(xy 198.356516 -234.009586) (xy 198.34276 -233.960795) (xy 198.335814 -233.910579) (xy 198.335392 -233.885232)
			(xy 198.335824 -233.859915) (xy 198.342747 -233.809757) (xy 198.356466 -233.761017) (xy 198.376725 -233.714612)
			(xy 198.403141 -233.671416) (xy 198.435219 -233.632239) (xy 198.453502 -233.614722) (xy 198.462392 -233.60634)
			(xy 198.470774 -233.58475) (xy 198.461376 -233.48061) (xy 198.449184 -233.460798) (xy 198.439024 -233.454194)
			(xy 198.412921 -233.437106) (xy 198.364803 -233.397392) (xy 198.322049 -233.351954) (xy 198.285334 -233.301511)
			(xy 198.25524 -233.246859) (xy 198.232241 -233.188863) (xy 198.216701 -233.128439) (xy 198.208866 -233.066543)
			(xy 198.208392 -233.035348) (xy 198.208855 -233.004138) (xy 198.216681 -232.942212) (xy 198.232214 -232.881756)
			(xy 198.255209 -232.823727) (xy 198.285303 -232.769041) (xy 198.322021 -232.718564) (xy 198.364781 -232.673092)
			(xy 198.412909 -232.633344) (xy 198.439024 -232.616248) (xy 198.449184 -232.609898) (xy 198.461376 -232.590086)
			(xy 198.471028 -232.485946) (xy 198.462646 -232.464102) (xy 198.453756 -232.455974) (xy 198.435434 -232.438453)
			(xy 198.403289 -232.399252) (xy 198.376815 -232.356019) (xy 198.35651 -232.309569) (xy 198.342756 -232.260775)
			(xy 198.335813 -232.210558) (xy 198.335392 -232.18521) (xy 198.335809 -232.159893) (xy 198.342735 -232.109733)
			(xy 198.356457 -232.060993) (xy 198.376719 -232.014589) (xy 198.403138 -231.971393) (xy 198.435218 -231.932216)
			(xy 198.453502 -231.9147) (xy 198.462392 -231.906318) (xy 198.470774 -231.884728) (xy 198.461376 -231.780588)
			(xy 198.449184 -231.760776) (xy 198.439024 -231.754172) (xy 198.412911 -231.737098) (xy 198.364793 -231.697383)
			(xy 198.32204 -231.651943) (xy 198.285326 -231.601497) (xy 198.255232 -231.546843) (xy 198.232235 -231.488845)
			(xy 198.216697 -231.428419) (xy 198.208865 -231.366522) (xy 198.208392 -231.335326) (xy 198.208881 -231.304163)
			(xy 198.216693 -231.242329) (xy 198.232193 -231.181961) (xy 198.255136 -231.124013) (xy 198.285162 -231.069396)
			(xy 198.321796 -231.018974) (xy 198.364461 -230.97354) (xy 198.412483 -230.933812) (xy 198.465107 -230.900417)
			(xy 198.521501 -230.87388) (xy 198.580776 -230.85462) (xy 198.641997 -230.842941) (xy 198.7042 -230.839028)
			(xy 198.766403 -230.842941) (xy 198.827624 -230.85462) (xy 198.886899 -230.87388) (xy 198.943293 -230.900417)
			(xy 198.995917 -230.933812) (xy 199.043939 -230.97354) (xy 199.086604 -231.018974) (xy 199.123238 -231.069396)
			(xy 199.153264 -231.124013) (xy 199.176207 -231.181961) (xy 199.191707 -231.242329) (xy 199.199519 -231.304163)
			(xy 199.200008 -231.335326) (xy 203.162931 -231.335326) (xy 203.166866 -231.281555) (xy 203.178589 -231.228931)
			(xy 203.197849 -231.178574) (xy 203.224235 -231.131557) (xy 203.257187 -231.088884) (xy 203.296 -231.051463)
			(xy 203.339848 -231.020093) (xy 203.387796 -230.995441) (xy 203.438823 -230.978033) (xy 203.491841 -230.96824)
			(xy 203.54572 -230.966271) (xy 203.599311 -230.972168) (xy 203.651472 -230.985804) (xy 203.701092 -231.006891)
			(xy 203.747113 -231.034977) (xy 203.788555 -231.069465) (xy 203.824533 -231.109619) (xy 203.854281 -231.154583)
			(xy 203.877166 -231.2034) (xy 203.892698 -231.255029) (xy 203.900548 -231.308369) (xy 203.90104 -231.335326)
			(xy 203.900548 -231.362283) (xy 203.892698 -231.415623) (xy 203.877166 -231.467252) (xy 203.854281 -231.516069)
			(xy 203.824533 -231.561033) (xy 203.788555 -231.601187) (xy 203.747113 -231.635675) (xy 203.701092 -231.663761)
			(xy 203.651472 -231.684848) (xy 203.599311 -231.698484) (xy 203.54572 -231.704381) (xy 203.491841 -231.702412)
			(xy 203.438823 -231.692619) (xy 203.387796 -231.675211) (xy 203.339848 -231.650559) (xy 203.296 -231.619189)
			(xy 203.257187 -231.581768) (xy 203.224235 -231.539095) (xy 203.197849 -231.492078) (xy 203.178589 -231.441721)
			(xy 203.166866 -231.389097) (xy 203.162931 -231.335326) (xy 199.200008 -231.335326) (xy 199.199588 -231.366525)
			(xy 199.191763 -231.428429) (xy 199.176227 -231.488861) (xy 199.153226 -231.546864) (xy 199.123124 -231.60152)
			(xy 199.086398 -231.651963) (xy 199.043629 -231.697397) (xy 198.995493 -231.7371) (xy 198.969376 -231.754172)
			(xy 198.959216 -231.760776) (xy 198.947024 -231.780588) (xy 198.937626 -231.884728) (xy 198.946008 -231.906318)
			(xy 198.954898 -231.9147) (xy 198.973182 -231.932217) (xy 199.005262 -231.971393) (xy 199.031681 -232.014589)
			(xy 199.051942 -232.060994) (xy 199.065665 -232.109734) (xy 199.07259 -232.159893) (xy 199.073008 -232.18521)
			(xy 199.072581 -232.210558) (xy 199.065647 -232.260777) (xy 199.051899 -232.309573) (xy 199.031594 -232.356025)
			(xy 199.005117 -232.399257) (xy 198.972967 -232.438454) (xy 198.954644 -232.455974) (xy 198.945754 -232.464102)
			(xy 198.937372 -232.485946) (xy 198.947024 -232.590086) (xy 198.959216 -232.609898) (xy 198.969376 -232.616248)
			(xy 198.995465 -232.63338) (xy 199.043588 -232.673127) (xy 199.086346 -232.718596) (xy 199.123063 -232.769068)
			(xy 199.153159 -232.823748) (xy 199.176158 -232.88177) (xy 199.191698 -232.94222) (xy 199.199534 -233.004141)
			(xy 199.200008 -233.035348) (xy 199.199527 -233.066545) (xy 199.191711 -233.128447) (xy 199.176185 -233.188877)
			(xy 199.153193 -233.246879) (xy 199.123099 -233.301536) (xy 199.086381 -233.35198) (xy 199.043619 -233.397415)
			(xy 198.99549 -233.437121) (xy 198.969376 -233.454194) (xy 198.959216 -233.460798) (xy 198.947024 -233.48061)
			(xy 198.937626 -233.58475) (xy 198.946008 -233.60634) (xy 198.954898 -233.614722) (xy 198.973193 -233.632228)
			(xy 199.005272 -233.671407) (xy 199.031689 -233.714605) (xy 199.051949 -233.761012) (xy 199.065669 -233.809753)
			(xy 199.072592 -233.859914) (xy 199.073008 -233.885232) (xy 199.072595 -233.91058) (xy 199.065659 -233.9608)
			(xy 199.051907 -234.009596) (xy 199.0316 -234.056048) (xy 199.005121 -234.09928) (xy 198.972968 -234.138476)
			(xy 198.954644 -234.155996) (xy 198.945754 -234.164124) (xy 198.937372 -234.185968) (xy 198.947024 -234.290108)
			(xy 198.959216 -234.30992) (xy 198.969376 -234.31627) (xy 198.995475 -234.333388) (xy 199.043598 -234.373136)
			(xy 199.086355 -234.418607) (xy 199.123071 -234.469082) (xy 199.153166 -234.523764) (xy 199.176164 -234.581788)
			(xy 199.191702 -234.642239) (xy 199.199535 -234.704162) (xy 199.200008 -234.73537) (xy 199.199544 -234.766567)
			(xy 199.191726 -234.82847) (xy 199.176197 -234.888901) (xy 199.153202 -234.946903) (xy 199.123106 -235.001559)
			(xy 199.086386 -235.052004) (xy 199.043622 -235.097438) (xy 198.995491 -235.137143) (xy 198.969376 -235.154216)
			(xy 198.959216 -235.16082) (xy 198.947024 -235.180632) (xy 198.937626 -235.284772) (xy 198.946008 -235.306362)
			(xy 198.954898 -235.314744) (xy 198.973155 -235.332288) (xy 199.005237 -235.371458) (xy 199.03166 -235.414649)
			(xy 199.051926 -235.461048) (xy 199.065654 -235.509783) (xy 199.072587 -235.559938) (xy 199.073008 -235.585254)
			(xy 199.07261 -235.610603) (xy 199.06567 -235.660823) (xy 199.051916 -235.70962) (xy 199.031606 -235.756071)
			(xy 199.005124 -235.799303) (xy 198.972969 -235.838498) (xy 198.954644 -235.856018) (xy 198.945754 -235.864146)
			(xy 198.937372 -235.88599) (xy 198.947024 -235.99013) (xy 198.959216 -236.009942) (xy 198.969376 -236.016292)
			(xy 198.995485 -236.033395) (xy 199.043608 -236.073146) (xy 199.086365 -236.118619) (xy 199.12308 -236.169096)
			(xy 199.153173 -236.223779) (xy 199.17617 -236.281806) (xy 199.191706 -236.342259) (xy 199.199536 -236.404183)
			(xy 199.200008 -236.435392) (xy 199.199519 -236.466555) (xy 199.191707 -236.528389) (xy 199.176207 -236.588757)
			(xy 199.153264 -236.646705) (xy 199.123238 -236.701322) (xy 199.086604 -236.751744) (xy 199.043939 -236.797178)
			(xy 198.995917 -236.836906) (xy 198.943293 -236.870301) (xy 198.886899 -236.896838) (xy 198.827624 -236.916098)
			(xy 198.766403 -236.927777) (xy 198.7042 -236.93169) (xy 198.641997 -236.927777) (xy 198.580776 -236.916098)
			(xy 198.521501 -236.896838) (xy 198.465107 -236.870301) (xy 198.412483 -236.836906) (xy 198.364461 -236.797178)
			(xy 198.321796 -236.751744) (xy 198.285162 -236.701322) (xy 198.255136 -236.646705) (xy 198.232193 -236.588757)
			(xy 198.216693 -236.528389) (xy 198.208881 -236.466555) (xy 198.208392 -236.435392) (xy 194.97294 -236.435392)
			(xy 194.972545 -236.46071) (xy 194.965618 -236.510871) (xy 194.951892 -236.559613) (xy 194.931627 -236.606017)
			(xy 194.905203 -236.649213) (xy 194.873117 -236.688387) (xy 194.85483 -236.705902) (xy 194.84594 -236.714284)
			(xy 194.837558 -236.735874) (xy 194.846956 -236.840014) (xy 194.859148 -236.859826) (xy 194.869308 -236.86643)
			(xy 194.895429 -236.883491) (xy 194.943545 -236.92321) (xy 194.986298 -236.968652) (xy 195.02301 -237.0191)
			(xy 195.053102 -237.073755) (xy 195.076099 -237.131755) (xy 195.091636 -237.192181) (xy 195.099467 -237.25408)
			(xy 195.09994 -237.285276) (xy 196.950599 -237.285276) (xy 196.954534 -237.231505) (xy 196.966257 -237.178881)
			(xy 196.985517 -237.128524) (xy 197.011903 -237.081507) (xy 197.044855 -237.038834) (xy 197.083668 -237.001413)
			(xy 197.127516 -236.970043) (xy 197.175464 -236.945391) (xy 197.226491 -236.927983) (xy 197.279509 -236.91819)
			(xy 197.333388 -236.916221) (xy 197.386979 -236.922118) (xy 197.43914 -236.935754) (xy 197.48876 -236.956841)
			(xy 197.534781 -236.984927) (xy 197.576223 -237.019415) (xy 197.612201 -237.059569) (xy 197.641949 -237.104533)
			(xy 197.664834 -237.15335) (xy 197.680366 -237.204979) (xy 197.688216 -237.258319) (xy 197.688708 -237.285276)
			(xy 201.652124 -237.285276) (xy 201.652531 -237.254077) (xy 201.660356 -237.192171) (xy 201.675893 -237.131739)
			(xy 201.698896 -237.073735) (xy 201.728999 -237.019079) (xy 201.765728 -236.968635) (xy 201.808499 -236.923203)
			(xy 201.856637 -236.883501) (xy 201.882756 -236.86643) (xy 201.892916 -236.859826) (xy 201.905108 -236.840014)
			(xy 201.914506 -236.735874) (xy 201.906124 -236.714284) (xy 201.897234 -236.705902) (xy 201.878938 -236.688397)
			(xy 201.846862 -236.649217) (xy 201.820446 -236.606018) (xy 201.800187 -236.559611) (xy 201.786467 -236.51087)
			(xy 201.779542 -236.46071) (xy 201.779124 -236.435392) (xy 201.779543 -236.410044) (xy 201.786476 -236.359824)
			(xy 201.800226 -236.311027) (xy 201.820532 -236.264575) (xy 201.847011 -236.221344) (xy 201.879164 -236.182148)
			(xy 201.897488 -236.164628) (xy 201.906378 -236.1565) (xy 201.91476 -236.134656) (xy 201.905108 -236.030516)
			(xy 201.892916 -236.010704) (xy 201.882756 -236.004354) (xy 201.856652 -235.987244) (xy 201.808532 -235.947492)
			(xy 201.765777 -235.902019) (xy 201.729063 -235.851542) (xy 201.698969 -235.79686) (xy 201.675972 -235.738835)
			(xy 201.660433 -235.678384) (xy 201.652598 -235.616462) (xy 201.652124 -235.585254) (xy 201.652592 -235.554057)
			(xy 201.660408 -235.492154) (xy 201.675935 -235.431723) (xy 201.698929 -235.373719) (xy 201.729024 -235.319063)
			(xy 201.765744 -235.268618) (xy 201.808509 -235.223184) (xy 201.85664 -235.18348) (xy 201.882756 -235.166408)
			(xy 201.892916 -235.159804) (xy 201.905108 -235.139992) (xy 201.914506 -235.035852) (xy 201.906124 -235.014262)
			(xy 201.897234 -235.00588) (xy 201.878927 -234.988386) (xy 201.846852 -234.949204) (xy 201.820438 -234.906002)
			(xy 201.800181 -234.859593) (xy 201.786463 -234.81085) (xy 201.77954 -234.760688) (xy 201.779124 -234.73537)
			(xy 201.779528 -234.710021) (xy 201.786465 -234.659801) (xy 201.800217 -234.611004) (xy 201.820526 -234.564552)
			(xy 201.847007 -234.521321) (xy 201.879163 -234.482125) (xy 201.897488 -234.464606) (xy 201.906378 -234.456478)
			(xy 201.91476 -234.434634) (xy 201.905108 -234.330494) (xy 201.892916 -234.310682) (xy 201.882756 -234.304332)
			(xy 201.856642 -234.287237) (xy 201.808522 -234.247483) (xy 201.765767 -234.202007) (xy 201.729054 -234.151529)
			(xy 201.698962 -234.096844) (xy 201.675966 -234.038818) (xy 201.660429 -233.978365) (xy 201.652596 -233.916441)
			(xy 201.652124 -233.885232) (xy 201.652574 -233.854034) (xy 201.660393 -233.792131) (xy 201.675923 -233.731699)
			(xy 201.698919 -233.673696) (xy 201.729017 -233.619039) (xy 201.76574 -233.568595) (xy 201.808506 -233.523161)
			(xy 201.856639 -233.483458) (xy 201.882756 -233.466386) (xy 201.892916 -233.459782) (xy 201.905108 -233.43997)
			(xy 201.914506 -233.33583) (xy 201.906124 -233.31424) (xy 201.897234 -233.305858) (xy 201.878965 -233.288326)
			(xy 201.846886 -233.249152) (xy 201.820467 -233.205958) (xy 201.800204 -233.159557) (xy 201.786477 -233.11082)
			(xy 201.779546 -233.060664) (xy 201.779124 -233.035348) (xy 201.779513 -233.009999) (xy 201.786453 -232.959777)
			(xy 201.800208 -232.910981) (xy 201.82052 -232.864529) (xy 201.847004 -232.821298) (xy 201.879162 -232.782103)
			(xy 201.897488 -232.764584) (xy 201.906378 -232.756456) (xy 201.91476 -232.734612) (xy 201.905108 -232.630472)
			(xy 201.892916 -232.61066) (xy 201.882756 -232.60431) (xy 201.856632 -232.587229) (xy 201.808512 -232.547473)
			(xy 201.765758 -232.501996) (xy 201.729046 -232.451515) (xy 201.698954 -232.396828) (xy 201.67596 -232.3388)
			(xy 201.660425 -232.278345) (xy 201.652595 -232.216419) (xy 201.652124 -232.18521) (xy 201.652613 -232.154047)
			(xy 201.660425 -232.092213) (xy 201.675925 -232.031845) (xy 201.698868 -231.973897) (xy 201.728894 -231.91928)
			(xy 201.765528 -231.868858) (xy 201.808193 -231.823424) (xy 201.856215 -231.783696) (xy 201.908839 -231.750301)
			(xy 201.965233 -231.723764) (xy 202.024508 -231.704504) (xy 202.085729 -231.692825) (xy 202.147932 -231.688912)
			(xy 202.210135 -231.692825) (xy 202.271356 -231.704504) (xy 202.330631 -231.723764) (xy 202.387025 -231.750301)
			(xy 202.439649 -231.783696) (xy 202.487671 -231.823424) (xy 202.530336 -231.868858) (xy 202.56697 -231.91928)
			(xy 202.596996 -231.973897) (xy 202.619939 -232.031845) (xy 202.635439 -232.092213) (xy 202.643251 -232.154047)
			(xy 202.64374 -232.18521) (xy 202.643229 -232.216418) (xy 202.63541 -232.278342) (xy 202.619883 -232.338796)
			(xy 202.596894 -232.396824) (xy 202.566806 -232.45151) (xy 202.530095 -232.501988) (xy 202.487341 -232.547462)
			(xy 202.43922 -232.587212) (xy 202.413108 -232.60431) (xy 202.402948 -232.61066) (xy 202.390756 -232.630472)
			(xy 202.381104 -232.734612) (xy 202.389486 -232.756456) (xy 202.398376 -232.764584) (xy 202.416683 -232.782119)
			(xy 202.448828 -232.821318) (xy 202.475304 -232.864548) (xy 202.495612 -232.910996) (xy 202.509369 -232.959787)
			(xy 202.516316 -233.010001) (xy 202.51674 -233.035348) (xy 202.516316 -233.060665) (xy 202.509395 -233.110825)
			(xy 202.495675 -233.159566) (xy 202.475415 -233.205971) (xy 202.448996 -233.249167) (xy 202.416915 -233.288342)
			(xy 202.39863 -233.305858) (xy 202.38974 -233.31424) (xy 202.381358 -233.33583) (xy 202.390756 -233.43997)
			(xy 202.402948 -233.459782) (xy 202.413108 -233.466386) (xy 202.439209 -233.483477) (xy 202.487325 -233.523191)
			(xy 202.530079 -233.568629) (xy 202.566793 -233.619072) (xy 202.596888 -233.673724) (xy 202.619887 -233.731719)
			(xy 202.635428 -233.792142) (xy 202.643265 -233.854037) (xy 202.64374 -233.885232) (xy 202.643246 -233.916441)
			(xy 202.635424 -233.978366) (xy 202.619894 -234.03882) (xy 202.596903 -234.096848) (xy 202.566813 -234.151533)
			(xy 202.5301 -234.202012) (xy 202.487344 -234.247485) (xy 202.439221 -234.287235) (xy 202.413108 -234.304332)
			(xy 202.402948 -234.310682) (xy 202.390756 -234.330494) (xy 202.381104 -234.434634) (xy 202.389486 -234.456478)
			(xy 202.398376 -234.464606) (xy 202.416694 -234.482131) (xy 202.448838 -234.521331) (xy 202.475312 -234.564564)
			(xy 202.495618 -234.611014) (xy 202.509373 -234.659806) (xy 202.516318 -234.710023) (xy 202.51674 -234.73537)
			(xy 202.516331 -234.760688) (xy 202.509406 -234.810848) (xy 202.495684 -234.859589) (xy 202.475421 -234.905994)
			(xy 202.449 -234.94919) (xy 202.416916 -234.988365) (xy 202.39863 -235.00588) (xy 202.38974 -235.014262)
			(xy 202.381358 -235.035852) (xy 202.390756 -235.139992) (xy 202.402948 -235.159804) (xy 202.413108 -235.166408)
			(xy 202.439219 -235.183484) (xy 202.487335 -235.223201) (xy 202.530088 -235.268641) (xy 202.566802 -235.319086)
			(xy 202.596895 -235.37374) (xy 202.619893 -235.431737) (xy 202.635432 -235.492162) (xy 202.643266 -235.554059)
			(xy 202.64374 -235.585254) (xy 202.643264 -235.616463) (xy 202.635439 -235.678389) (xy 202.619906 -235.738844)
			(xy 202.596912 -235.796872) (xy 202.56682 -235.851557) (xy 202.530105 -235.902035) (xy 202.487347 -235.947508)
			(xy 202.439222 -235.987257) (xy 202.413108 -236.004354) (xy 202.402948 -236.010704) (xy 202.390756 -236.030516)
			(xy 202.381104 -236.134656) (xy 202.389486 -236.1565) (xy 202.398376 -236.164628) (xy 202.416705 -236.182142)
			(xy 202.448848 -236.221345) (xy 202.475321 -236.264579) (xy 202.495624 -236.311032) (xy 202.509377 -236.359826)
			(xy 202.516319 -236.410044) (xy 202.51674 -236.435392) (xy 205.752192 -236.435392) (xy 205.75269 -236.404183)
			(xy 205.76051 -236.342258) (xy 205.776037 -236.281803) (xy 205.799028 -236.223774) (xy 205.829117 -236.169089)
			(xy 205.86583 -236.118611) (xy 205.908587 -236.073138) (xy 205.956711 -236.033389) (xy 205.982824 -236.016292)
			(xy 205.992984 -236.009942) (xy 206.005176 -235.99013) (xy 206.014828 -235.88599) (xy 206.006446 -235.864146)
			(xy 205.997556 -235.856018) (xy 205.979256 -235.838475) (xy 205.947109 -235.79928) (xy 205.920632 -235.756051)
			(xy 205.900322 -235.709604) (xy 205.886564 -235.660815) (xy 205.879616 -235.6106) (xy 205.879192 -235.585254)
			(xy 205.879638 -235.559938) (xy 205.886558 -235.50978) (xy 205.900275 -235.46104) (xy 205.920531 -235.414636)
			(xy 205.946944 -235.371439) (xy 205.97902 -235.332261) (xy 205.997302 -235.314744) (xy 206.006192 -235.306362)
			(xy 206.014574 -235.284772) (xy 206.005176 -235.180632) (xy 205.992984 -235.16082) (xy 205.982824 -235.154216)
			(xy 205.956731 -235.137113) (xy 205.908613 -235.097401) (xy 205.865859 -235.051966) (xy 205.829143 -235.001525)
			(xy 205.799047 -234.946875) (xy 205.776046 -234.888881) (xy 205.760505 -234.828459) (xy 205.752667 -234.766564)
			(xy 205.752192 -234.73537) (xy 205.752672 -234.704161) (xy 205.760495 -234.642235) (xy 205.776026 -234.58178)
			(xy 205.799018 -234.523751) (xy 205.82911 -234.469065) (xy 205.865826 -234.418587) (xy 205.908584 -234.373115)
			(xy 205.95671 -234.333366) (xy 205.982824 -234.31627) (xy 205.992984 -234.30992) (xy 206.005176 -234.290108)
			(xy 206.014828 -234.185968) (xy 206.006446 -234.164124) (xy 205.997556 -234.155996) (xy 205.979245 -234.138464)
			(xy 205.947099 -234.099266) (xy 205.920623 -234.056035) (xy 205.900316 -234.009586) (xy 205.88656 -233.960795)
			(xy 205.879614 -233.910579) (xy 205.879192 -233.885232) (xy 205.879624 -233.859915) (xy 205.886547 -233.809757)
			(xy 205.900266 -233.761017) (xy 205.920525 -233.714612) (xy 205.946941 -233.671416) (xy 205.979019 -233.632239)
			(xy 205.997302 -233.614722) (xy 206.006192 -233.60634) (xy 206.014574 -233.58475) (xy 206.005176 -233.48061)
			(xy 205.992984 -233.460798) (xy 205.982824 -233.454194) (xy 205.956721 -233.437106) (xy 205.908603 -233.397392)
			(xy 205.865849 -233.351954) (xy 205.829134 -233.301511) (xy 205.79904 -233.246859) (xy 205.776041 -233.188863)
			(xy 205.760501 -233.128439) (xy 205.752666 -233.066543) (xy 205.752192 -233.035348) (xy 205.752655 -233.004138)
			(xy 205.760481 -232.942212) (xy 205.776014 -232.881756) (xy 205.799009 -232.823727) (xy 205.829103 -232.769041)
			(xy 205.865821 -232.718564) (xy 205.908581 -232.673092) (xy 205.956709 -232.633344) (xy 205.982824 -232.616248)
			(xy 205.992984 -232.609898) (xy 206.005176 -232.590086) (xy 206.014828 -232.485946) (xy 206.006446 -232.464102)
			(xy 205.997556 -232.455974) (xy 205.979234 -232.438453) (xy 205.947089 -232.399252) (xy 205.920615 -232.356019)
			(xy 205.90031 -232.309569) (xy 205.886556 -232.260775) (xy 205.879613 -232.210558) (xy 205.879192 -232.18521)
			(xy 205.879609 -232.159893) (xy 205.886535 -232.109733) (xy 205.900257 -232.060993) (xy 205.920519 -232.014589)
			(xy 205.946938 -231.971393) (xy 205.979018 -231.932216) (xy 205.997302 -231.9147) (xy 206.006192 -231.906318)
			(xy 206.014574 -231.884728) (xy 206.005176 -231.780588) (xy 205.992984 -231.760776) (xy 205.982824 -231.754172)
			(xy 205.956711 -231.737098) (xy 205.908593 -231.697383) (xy 205.86584 -231.651943) (xy 205.829126 -231.601497)
			(xy 205.799032 -231.546843) (xy 205.776035 -231.488845) (xy 205.760497 -231.428419) (xy 205.752665 -231.366522)
			(xy 205.752192 -231.335326) (xy 205.752681 -231.304163) (xy 205.760493 -231.242329) (xy 205.775993 -231.181961)
			(xy 205.798936 -231.124013) (xy 205.828962 -231.069396) (xy 205.865596 -231.018974) (xy 205.908261 -230.97354)
			(xy 205.956283 -230.933812) (xy 206.008907 -230.900417) (xy 206.065301 -230.87388) (xy 206.124576 -230.85462)
			(xy 206.185797 -230.842941) (xy 206.248 -230.839028) (xy 206.310203 -230.842941) (xy 206.371424 -230.85462)
			(xy 206.430699 -230.87388) (xy 206.487093 -230.900417) (xy 206.539717 -230.933812) (xy 206.587739 -230.97354)
			(xy 206.630404 -231.018974) (xy 206.667038 -231.069396) (xy 206.697064 -231.124013) (xy 206.720007 -231.181961)
			(xy 206.735507 -231.242329) (xy 206.743319 -231.304163) (xy 206.743808 -231.335326) (xy 206.743388 -231.366525)
			(xy 206.735563 -231.428429) (xy 206.720027 -231.488861) (xy 206.697026 -231.546864) (xy 206.666924 -231.60152)
			(xy 206.630198 -231.651963) (xy 206.587429 -231.697397) (xy 206.539293 -231.7371) (xy 206.513176 -231.754172)
			(xy 206.503016 -231.760776) (xy 206.490824 -231.780588) (xy 206.481426 -231.884728) (xy 206.489808 -231.906318)
			(xy 206.498698 -231.9147) (xy 206.516982 -231.932217) (xy 206.549062 -231.971393) (xy 206.575481 -232.014589)
			(xy 206.595742 -232.060994) (xy 206.609465 -232.109734) (xy 206.61639 -232.159893) (xy 206.616808 -232.18521)
			(xy 206.616381 -232.210558) (xy 206.609447 -232.260777) (xy 206.595699 -232.309573) (xy 206.575394 -232.356025)
			(xy 206.548917 -232.399257) (xy 206.516767 -232.438454) (xy 206.498444 -232.455974) (xy 206.489554 -232.464102)
			(xy 206.481172 -232.485946) (xy 206.490824 -232.590086) (xy 206.503016 -232.609898) (xy 206.513176 -232.616248)
			(xy 206.539265 -232.63338) (xy 206.587388 -232.673127) (xy 206.630146 -232.718596) (xy 206.666863 -232.769068)
			(xy 206.696959 -232.823748) (xy 206.719958 -232.88177) (xy 206.735498 -232.94222) (xy 206.743334 -233.004141)
			(xy 206.743808 -233.035348) (xy 206.743327 -233.066545) (xy 206.735511 -233.128447) (xy 206.719985 -233.188877)
			(xy 206.696993 -233.246879) (xy 206.666899 -233.301536) (xy 206.630181 -233.35198) (xy 206.587419 -233.397415)
			(xy 206.53929 -233.437121) (xy 206.513176 -233.454194) (xy 206.503016 -233.460798) (xy 206.490824 -233.48061)
			(xy 206.481426 -233.58475) (xy 206.489808 -233.60634) (xy 206.498698 -233.614722) (xy 206.516993 -233.632228)
			(xy 206.549072 -233.671407) (xy 206.575489 -233.714605) (xy 206.595749 -233.761012) (xy 206.609469 -233.809753)
			(xy 206.616392 -233.859914) (xy 206.616808 -233.885232) (xy 206.616395 -233.91058) (xy 206.609459 -233.9608)
			(xy 206.595707 -234.009596) (xy 206.5754 -234.056048) (xy 206.548921 -234.09928) (xy 206.516768 -234.138476)
			(xy 206.498444 -234.155996) (xy 206.489554 -234.164124) (xy 206.481172 -234.185968) (xy 206.490824 -234.290108)
			(xy 206.503016 -234.30992) (xy 206.513176 -234.31627) (xy 206.539275 -234.333388) (xy 206.587398 -234.373136)
			(xy 206.630155 -234.418607) (xy 206.666871 -234.469082) (xy 206.696966 -234.523764) (xy 206.719964 -234.581788)
			(xy 206.735502 -234.642239) (xy 206.743335 -234.704162) (xy 206.743808 -234.73537) (xy 206.743344 -234.766567)
			(xy 206.735526 -234.82847) (xy 206.719997 -234.888901) (xy 206.697002 -234.946903) (xy 206.666906 -235.001559)
			(xy 206.630186 -235.052004) (xy 206.587422 -235.097438) (xy 206.539291 -235.137143) (xy 206.513176 -235.154216)
			(xy 206.503016 -235.16082) (xy 206.490824 -235.180632) (xy 206.481426 -235.284772) (xy 206.489808 -235.306362)
			(xy 206.498698 -235.314744) (xy 206.516955 -235.332288) (xy 206.549037 -235.371458) (xy 206.57546 -235.414649)
			(xy 206.595726 -235.461048) (xy 206.609454 -235.509783) (xy 206.616387 -235.559938) (xy 206.616808 -235.585254)
			(xy 206.61641 -235.610603) (xy 206.60947 -235.660823) (xy 206.595716 -235.70962) (xy 206.575406 -235.756071)
			(xy 206.548924 -235.799303) (xy 206.516769 -235.838498) (xy 206.498444 -235.856018) (xy 206.489554 -235.864146)
			(xy 206.481172 -235.88599) (xy 206.490824 -235.99013) (xy 206.503016 -236.009942) (xy 206.513176 -236.016292)
			(xy 206.539285 -236.033395) (xy 206.587408 -236.073146) (xy 206.630165 -236.118619) (xy 206.66688 -236.169096)
			(xy 206.696973 -236.223779) (xy 206.71997 -236.281806) (xy 206.735506 -236.342259) (xy 206.743336 -236.404183)
			(xy 206.743808 -236.435392) (xy 206.743319 -236.466555) (xy 206.735507 -236.528389) (xy 206.720007 -236.588757)
			(xy 206.697064 -236.646705) (xy 206.667038 -236.701322) (xy 206.630404 -236.751744) (xy 206.587739 -236.797178)
			(xy 206.539717 -236.836906) (xy 206.487093 -236.870301) (xy 206.430699 -236.896838) (xy 206.371424 -236.916098)
			(xy 206.310203 -236.927777) (xy 206.248 -236.93169) (xy 206.185797 -236.927777) (xy 206.124576 -236.916098)
			(xy 206.065301 -236.896838) (xy 206.008907 -236.870301) (xy 205.956283 -236.836906) (xy 205.908261 -236.797178)
			(xy 205.865596 -236.751744) (xy 205.828962 -236.701322) (xy 205.798936 -236.646705) (xy 205.775993 -236.588757)
			(xy 205.760493 -236.528389) (xy 205.752681 -236.466555) (xy 205.752192 -236.435392) (xy 202.51674 -236.435392)
			(xy 202.516345 -236.46071) (xy 202.509418 -236.510871) (xy 202.495692 -236.559613) (xy 202.475427 -236.606017)
			(xy 202.449003 -236.649213) (xy 202.416917 -236.688387) (xy 202.39863 -236.705902) (xy 202.38974 -236.714284)
			(xy 202.381358 -236.735874) (xy 202.390756 -236.840014) (xy 202.402948 -236.859826) (xy 202.413108 -236.86643)
			(xy 202.439229 -236.883491) (xy 202.487345 -236.92321) (xy 202.530098 -236.968652) (xy 202.56681 -237.0191)
			(xy 202.596902 -237.073755) (xy 202.619899 -237.131755) (xy 202.635436 -237.192181) (xy 202.643267 -237.25408)
			(xy 202.64374 -237.285276) (xy 204.494399 -237.285276) (xy 204.498334 -237.231505) (xy 204.510057 -237.178881)
			(xy 204.529317 -237.128524) (xy 204.555703 -237.081507) (xy 204.588655 -237.038834) (xy 204.627468 -237.001413)
			(xy 204.671316 -236.970043) (xy 204.719264 -236.945391) (xy 204.770291 -236.927983) (xy 204.823309 -236.91819)
			(xy 204.877188 -236.916221) (xy 204.930779 -236.922118) (xy 204.98294 -236.935754) (xy 205.03256 -236.956841)
			(xy 205.078581 -236.984927) (xy 205.120023 -237.019415) (xy 205.156001 -237.059569) (xy 205.185749 -237.104533)
			(xy 205.208634 -237.15335) (xy 205.224166 -237.204979) (xy 205.232016 -237.258319) (xy 205.232508 -237.285276)
			(xy 205.232016 -237.312233) (xy 205.224166 -237.365573) (xy 205.208634 -237.417202) (xy 205.185749 -237.466019)
			(xy 205.156001 -237.510983) (xy 205.120023 -237.551137) (xy 205.078581 -237.585625) (xy 205.03256 -237.613711)
			(xy 204.98294 -237.634798) (xy 204.930779 -237.648434) (xy 204.877188 -237.654331) (xy 204.823309 -237.652362)
			(xy 204.770291 -237.642569) (xy 204.719264 -237.625161) (xy 204.671316 -237.600509) (xy 204.627468 -237.569139)
			(xy 204.588655 -237.531718) (xy 204.555703 -237.489045) (xy 204.529317 -237.442028) (xy 204.510057 -237.391671)
			(xy 204.498334 -237.339047) (xy 204.494399 -237.285276) (xy 202.64374 -237.285276) (xy 202.643251 -237.316439)
			(xy 202.635439 -237.378273) (xy 202.619939 -237.438641) (xy 202.596996 -237.496589) (xy 202.56697 -237.551206)
			(xy 202.530336 -237.601628) (xy 202.487671 -237.647062) (xy 202.439649 -237.68679) (xy 202.387025 -237.720185)
			(xy 202.330631 -237.746722) (xy 202.271356 -237.765982) (xy 202.210135 -237.777661) (xy 202.147932 -237.781574)
			(xy 202.085729 -237.777661) (xy 202.024508 -237.765982) (xy 201.965233 -237.746722) (xy 201.908839 -237.720185)
			(xy 201.856215 -237.68679) (xy 201.808193 -237.647062) (xy 201.765528 -237.601628) (xy 201.728894 -237.551206)
			(xy 201.698868 -237.496589) (xy 201.675925 -237.438641) (xy 201.660425 -237.378273) (xy 201.652613 -237.316439)
			(xy 201.652124 -237.285276) (xy 197.688708 -237.285276) (xy 197.688216 -237.312233) (xy 197.680366 -237.365573)
			(xy 197.664834 -237.417202) (xy 197.641949 -237.466019) (xy 197.612201 -237.510983) (xy 197.576223 -237.551137)
			(xy 197.534781 -237.585625) (xy 197.48876 -237.613711) (xy 197.43914 -237.634798) (xy 197.386979 -237.648434)
			(xy 197.333388 -237.654331) (xy 197.279509 -237.652362) (xy 197.226491 -237.642569) (xy 197.175464 -237.625161)
			(xy 197.127516 -237.600509) (xy 197.083668 -237.569139) (xy 197.044855 -237.531718) (xy 197.011903 -237.489045)
			(xy 196.985517 -237.442028) (xy 196.966257 -237.391671) (xy 196.954534 -237.339047) (xy 196.950599 -237.285276)
			(xy 195.09994 -237.285276) (xy 195.099451 -237.316439) (xy 195.091639 -237.378273) (xy 195.076139 -237.438641)
			(xy 195.053196 -237.496589) (xy 195.02317 -237.551206) (xy 194.986536 -237.601628) (xy 194.943871 -237.647062)
			(xy 194.895849 -237.68679) (xy 194.843225 -237.720185) (xy 194.786831 -237.746722) (xy 194.727556 -237.765982)
			(xy 194.666335 -237.777661) (xy 194.604132 -237.781574) (xy 194.541929 -237.777661) (xy 194.480708 -237.765982)
			(xy 194.421433 -237.746722) (xy 194.365039 -237.720185) (xy 194.312415 -237.68679) (xy 194.264393 -237.647062)
			(xy 194.221728 -237.601628) (xy 194.185094 -237.551206) (xy 194.155068 -237.496589) (xy 194.132125 -237.438641)
			(xy 194.116625 -237.378273) (xy 194.108813 -237.316439) (xy 194.108324 -237.285276) (xy 190.144654 -237.285276)
			(xy 190.144162 -237.312233) (xy 190.136312 -237.365573) (xy 190.12078 -237.417202) (xy 190.097895 -237.466019)
			(xy 190.068147 -237.510983) (xy 190.032169 -237.551137) (xy 189.990727 -237.585625) (xy 189.944706 -237.613711)
			(xy 189.895086 -237.634798) (xy 189.842925 -237.648434) (xy 189.789334 -237.654331) (xy 189.735455 -237.652362)
			(xy 189.682437 -237.642569) (xy 189.63141 -237.625161) (xy 189.583462 -237.600509) (xy 189.539614 -237.569139)
			(xy 189.500801 -237.531718) (xy 189.467849 -237.489045) (xy 189.441463 -237.442028) (xy 189.422203 -237.391671)
			(xy 189.41048 -237.339047) (xy 189.406545 -237.285276) (xy 187.555886 -237.285276) (xy 187.555397 -237.316439)
			(xy 187.547585 -237.378273) (xy 187.532085 -237.438641) (xy 187.509142 -237.496589) (xy 187.479116 -237.551206)
			(xy 187.442482 -237.601628) (xy 187.399817 -237.647062) (xy 187.351795 -237.68679) (xy 187.299171 -237.720185)
			(xy 187.242777 -237.746722) (xy 187.183502 -237.765982) (xy 187.122281 -237.777661) (xy 187.060078 -237.781574)
			(xy 186.997875 -237.777661) (xy 186.936654 -237.765982) (xy 186.877379 -237.746722) (xy 186.820985 -237.720185)
			(xy 186.768361 -237.68679) (xy 186.720339 -237.647062) (xy 186.677674 -237.601628) (xy 186.64104 -237.551206)
			(xy 186.611014 -237.496589) (xy 186.588071 -237.438641) (xy 186.572571 -237.378273) (xy 186.564759 -237.316439)
			(xy 186.56427 -237.285276) (xy 182.6006 -237.285276) (xy 182.600108 -237.312233) (xy 182.592258 -237.365573)
			(xy 182.576726 -237.417202) (xy 182.553841 -237.466019) (xy 182.524093 -237.510983) (xy 182.488115 -237.551137)
			(xy 182.446673 -237.585625) (xy 182.400652 -237.613711) (xy 182.351032 -237.634798) (xy 182.298871 -237.648434)
			(xy 182.24528 -237.654331) (xy 182.191401 -237.652362) (xy 182.138383 -237.642569) (xy 182.087356 -237.625161)
			(xy 182.039408 -237.600509) (xy 181.99556 -237.569139) (xy 181.956747 -237.531718) (xy 181.923795 -237.489045)
			(xy 181.897409 -237.442028) (xy 181.878149 -237.391671) (xy 181.866426 -237.339047) (xy 181.862491 -237.285276)
			(xy 180.011832 -237.285276) (xy 180.011343 -237.316439) (xy 180.003531 -237.378273) (xy 179.988031 -237.438641)
			(xy 179.965088 -237.496589) (xy 179.935062 -237.551206) (xy 179.898428 -237.601628) (xy 179.855763 -237.647062)
			(xy 179.807741 -237.68679) (xy 179.755117 -237.720185) (xy 179.698723 -237.746722) (xy 179.639448 -237.765982)
			(xy 179.578227 -237.777661) (xy 179.516024 -237.781574) (xy 179.453821 -237.777661) (xy 179.3926 -237.765982)
			(xy 179.333325 -237.746722) (xy 179.276931 -237.720185) (xy 179.224307 -237.68679) (xy 179.176285 -237.647062)
			(xy 179.13362 -237.601628) (xy 179.096986 -237.551206) (xy 179.06696 -237.496589) (xy 179.044017 -237.438641)
			(xy 179.028517 -237.378273) (xy 179.020705 -237.316439) (xy 179.020216 -237.285276) (xy 175.056546 -237.285276)
			(xy 175.056054 -237.312233) (xy 175.048204 -237.365573) (xy 175.032672 -237.417202) (xy 175.009787 -237.466019)
			(xy 174.980039 -237.510983) (xy 174.944061 -237.551137) (xy 174.902619 -237.585625) (xy 174.856598 -237.613711)
			(xy 174.806978 -237.634798) (xy 174.754817 -237.648434) (xy 174.701226 -237.654331) (xy 174.647347 -237.652362)
			(xy 174.594329 -237.642569) (xy 174.543302 -237.625161) (xy 174.495354 -237.600509) (xy 174.451506 -237.569139)
			(xy 174.412693 -237.531718) (xy 174.379741 -237.489045) (xy 174.353355 -237.442028) (xy 174.334095 -237.391671)
			(xy 174.322372 -237.339047) (xy 174.318437 -237.285276) (xy 172.467778 -237.285276) (xy 172.467289 -237.316439)
			(xy 172.459477 -237.378273) (xy 172.443977 -237.438641) (xy 172.421034 -237.496589) (xy 172.391008 -237.551206)
			(xy 172.354374 -237.601628) (xy 172.311709 -237.647062) (xy 172.263687 -237.68679) (xy 172.211063 -237.720185)
			(xy 172.154669 -237.746722) (xy 172.095394 -237.765982) (xy 172.034173 -237.777661) (xy 171.97197 -237.781574)
			(xy 171.909767 -237.777661) (xy 171.848546 -237.765982) (xy 171.789271 -237.746722) (xy 171.732877 -237.720185)
			(xy 171.680253 -237.68679) (xy 171.632231 -237.647062) (xy 171.589566 -237.601628) (xy 171.552932 -237.551206)
			(xy 171.522906 -237.496589) (xy 171.499963 -237.438641) (xy 171.484463 -237.378273) (xy 171.476651 -237.316439)
			(xy 171.476162 -237.285276) (xy 167.512492 -237.285276) (xy 167.512 -237.312233) (xy 167.50415 -237.365573)
			(xy 167.488618 -237.417202) (xy 167.465733 -237.466019) (xy 167.435985 -237.510983) (xy 167.400007 -237.551137)
			(xy 167.358565 -237.585625) (xy 167.312544 -237.613711) (xy 167.262924 -237.634798) (xy 167.210763 -237.648434)
			(xy 167.157172 -237.654331) (xy 167.103293 -237.652362) (xy 167.050275 -237.642569) (xy 166.999248 -237.625161)
			(xy 166.9513 -237.600509) (xy 166.907452 -237.569139) (xy 166.868639 -237.531718) (xy 166.835687 -237.489045)
			(xy 166.809301 -237.442028) (xy 166.790041 -237.391671) (xy 166.778318 -237.339047) (xy 166.774383 -237.285276)
			(xy 161.612834 -237.285276) (xy 161.612834 -238.135414) (xy 165.442915 -238.135414) (xy 165.44685 -238.081643)
			(xy 165.458573 -238.029019) (xy 165.477833 -237.978662) (xy 165.504219 -237.931645) (xy 165.537171 -237.888972)
			(xy 165.575984 -237.851551) (xy 165.619832 -237.820181) (xy 165.66778 -237.795529) (xy 165.718807 -237.778121)
			(xy 165.771825 -237.768328) (xy 165.825704 -237.766359) (xy 165.879295 -237.772256) (xy 165.931456 -237.785892)
			(xy 165.981076 -237.806979) (xy 166.027097 -237.835065) (xy 166.068539 -237.869553) (xy 166.104517 -237.909707)
			(xy 166.134265 -237.954671) (xy 166.15715 -238.003488) (xy 166.172682 -238.055117) (xy 166.180532 -238.108457)
			(xy 166.181024 -238.135414) (xy 172.986969 -238.135414) (xy 172.990904 -238.081643) (xy 173.002627 -238.029019)
			(xy 173.021887 -237.978662) (xy 173.048273 -237.931645) (xy 173.081225 -237.888972) (xy 173.120038 -237.851551)
			(xy 173.163886 -237.820181) (xy 173.211834 -237.795529) (xy 173.262861 -237.778121) (xy 173.315879 -237.768328)
			(xy 173.369758 -237.766359) (xy 173.423349 -237.772256) (xy 173.47551 -237.785892) (xy 173.52513 -237.806979)
			(xy 173.571151 -237.835065) (xy 173.612593 -237.869553) (xy 173.648571 -237.909707) (xy 173.678319 -237.954671)
			(xy 173.701204 -238.003488) (xy 173.716736 -238.055117) (xy 173.724586 -238.108457) (xy 173.725078 -238.135414)
			(xy 173.724586 -238.162371) (xy 173.716736 -238.215711) (xy 173.701204 -238.26734) (xy 173.678319 -238.316157)
			(xy 173.648571 -238.361121) (xy 173.612593 -238.401275) (xy 173.571151 -238.435763) (xy 173.52513 -238.463849)
			(xy 173.47551 -238.484936) (xy 173.423349 -238.498572) (xy 173.369758 -238.504469) (xy 173.315879 -238.5025)
			(xy 173.262861 -238.492707) (xy 173.211834 -238.475299) (xy 173.163886 -238.450647) (xy 173.120038 -238.419277)
			(xy 173.081225 -238.381856) (xy 173.048273 -238.339183) (xy 173.021887 -238.292166) (xy 173.002627 -238.241809)
			(xy 172.990904 -238.189185) (xy 172.986969 -238.135414) (xy 166.181024 -238.135414) (xy 166.180532 -238.162371)
			(xy 166.172682 -238.215711) (xy 166.15715 -238.26734) (xy 166.134265 -238.316157) (xy 166.104517 -238.361121)
			(xy 166.068539 -238.401275) (xy 166.027097 -238.435763) (xy 165.981076 -238.463849) (xy 165.931456 -238.484936)
			(xy 165.879295 -238.498572) (xy 165.825704 -238.504469) (xy 165.771825 -238.5025) (xy 165.718807 -238.492707)
			(xy 165.66778 -238.475299) (xy 165.619832 -238.450647) (xy 165.575984 -238.419277) (xy 165.537171 -238.381856)
			(xy 165.504219 -238.339183) (xy 165.477833 -238.292166) (xy 165.458573 -238.241809) (xy 165.44685 -238.189185)
			(xy 165.442915 -238.135414) (xy 161.612834 -238.135414) (xy 161.612834 -238.560356) (xy 169.276283 -238.560356)
			(xy 169.280218 -238.506585) (xy 169.291941 -238.453961) (xy 169.311201 -238.403604) (xy 169.337587 -238.356587)
			(xy 169.370539 -238.313914) (xy 169.409352 -238.276493) (xy 169.4532 -238.245123) (xy 169.501148 -238.220471)
			(xy 169.552175 -238.203063) (xy 169.605193 -238.19327) (xy 169.659072 -238.191301) (xy 169.712663 -238.197198)
			(xy 169.764824 -238.210834) (xy 169.814444 -238.231921) (xy 169.860465 -238.260007) (xy 169.901907 -238.294495)
			(xy 169.937885 -238.334649) (xy 169.967633 -238.379613) (xy 169.990518 -238.42843) (xy 170.00605 -238.480059)
			(xy 170.0139 -238.533399) (xy 170.014392 -238.560356) (xy 170.0139 -238.587313) (xy 170.00605 -238.640653)
			(xy 169.990518 -238.692282) (xy 169.967633 -238.741099) (xy 169.937885 -238.786063) (xy 169.901907 -238.826217)
			(xy 169.860465 -238.860705) (xy 169.814444 -238.888791) (xy 169.764824 -238.909878) (xy 169.712663 -238.923514)
			(xy 169.659072 -238.929411) (xy 169.605193 -238.927442) (xy 169.552175 -238.917649) (xy 169.501148 -238.900241)
			(xy 169.4532 -238.875589) (xy 169.409352 -238.844219) (xy 169.370539 -238.806798) (xy 169.337587 -238.764125)
			(xy 169.311201 -238.717108) (xy 169.291941 -238.666751) (xy 169.280218 -238.614127) (xy 169.276283 -238.560356)
			(xy 161.612834 -238.560356) (xy 161.612834 -239.410494) (xy 165.176215 -239.410494) (xy 165.18015 -239.356723)
			(xy 165.191873 -239.304099) (xy 165.211133 -239.253742) (xy 165.237519 -239.206725) (xy 165.270471 -239.164052)
			(xy 165.309284 -239.126631) (xy 165.353132 -239.095261) (xy 165.40108 -239.070609) (xy 165.452107 -239.053201)
			(xy 165.505125 -239.043408) (xy 165.559004 -239.041439) (xy 165.612595 -239.047336) (xy 165.664756 -239.060972)
			(xy 165.714376 -239.082059) (xy 165.760397 -239.110145) (xy 165.801839 -239.144633) (xy 165.837817 -239.184787)
			(xy 165.867565 -239.229751) (xy 165.89045 -239.278568) (xy 165.905982 -239.330197) (xy 165.913832 -239.383537)
			(xy 165.914324 -239.410494) (xy 165.913832 -239.437451) (xy 165.905982 -239.490791) (xy 165.89045 -239.54242)
			(xy 165.867565 -239.591237) (xy 165.837817 -239.636201) (xy 165.801839 -239.676355) (xy 165.760397 -239.710843)
			(xy 165.714376 -239.738929) (xy 165.664756 -239.760016) (xy 165.612595 -239.773652) (xy 165.559004 -239.779549)
			(xy 165.505125 -239.77758) (xy 165.452107 -239.767787) (xy 165.40108 -239.750379) (xy 165.353132 -239.725727)
			(xy 165.309284 -239.694357) (xy 165.270471 -239.656936) (xy 165.237519 -239.614263) (xy 165.211133 -239.567246)
			(xy 165.191873 -239.516889) (xy 165.18015 -239.464265) (xy 165.176215 -239.410494) (xy 161.612834 -239.410494)
			(xy 161.612834 -239.835436) (xy 166.774383 -239.835436) (xy 166.778318 -239.781665) (xy 166.790041 -239.729041)
			(xy 166.809301 -239.678684) (xy 166.835687 -239.631667) (xy 166.868639 -239.588994) (xy 166.907452 -239.551573)
			(xy 166.9513 -239.520203) (xy 166.999248 -239.495551) (xy 167.050275 -239.478143) (xy 167.103293 -239.46835)
			(xy 167.157172 -239.466381) (xy 167.210763 -239.472278) (xy 167.262924 -239.485914) (xy 167.312544 -239.507001)
			(xy 167.358565 -239.535087) (xy 167.400007 -239.569575) (xy 167.435985 -239.609729) (xy 167.465733 -239.654693)
			(xy 167.488618 -239.70351) (xy 167.50415 -239.755139) (xy 167.512 -239.808479) (xy 167.512492 -239.835436)
			(xy 171.476162 -239.835436) (xy 171.476657 -239.802715) (xy 171.485259 -239.73784) (xy 171.502319 -239.67466)
			(xy 171.527539 -239.614272) (xy 171.560483 -239.557726) (xy 171.600577 -239.506003) (xy 171.623482 -239.48263)
			(xy 171.630848 -239.475518) (xy 171.638722 -239.456722) (xy 171.638722 -239.364012) (xy 171.630848 -239.345216)
			(xy 171.623482 -239.338104) (xy 171.600577 -239.314733) (xy 171.560494 -239.263005) (xy 171.52756 -239.206456)
			(xy 171.502345 -239.146069) (xy 171.485289 -239.08289) (xy 171.476686 -239.018018) (xy 171.476162 -238.985298)
			(xy 171.476651 -238.954135) (xy 171.484463 -238.892301) (xy 171.499963 -238.831933) (xy 171.522906 -238.773985)
			(xy 171.552932 -238.719368) (xy 171.589566 -238.668946) (xy 171.632231 -238.623512) (xy 171.680253 -238.583784)
			(xy 171.732877 -238.550389) (xy 171.789271 -238.523852) (xy 171.848546 -238.504592) (xy 171.909767 -238.492913)
			(xy 171.97197 -238.489) (xy 172.034173 -238.492913) (xy 172.095394 -238.504592) (xy 172.154669 -238.523852)
			(xy 172.211063 -238.550389) (xy 172.263687 -238.583784) (xy 172.311709 -238.623512) (xy 172.354374 -238.668946)
			(xy 172.391008 -238.719368) (xy 172.421034 -238.773985) (xy 172.443977 -238.831933) (xy 172.459477 -238.892301)
			(xy 172.467289 -238.954135) (xy 172.467778 -238.985298) (xy 175.57623 -238.985298) (xy 175.576801 -238.952599)
			(xy 175.585403 -238.88777) (xy 175.602455 -238.824634) (xy 175.627663 -238.76429) (xy 175.660588 -238.707785)
			(xy 175.700659 -238.656101) (xy 175.72355 -238.632746) (xy 175.730916 -238.62538) (xy 175.738536 -238.606838)
			(xy 175.738536 -238.513874) (xy 175.730916 -238.495332) (xy 175.72355 -238.487966) (xy 175.700665 -238.464601)
			(xy 175.66058 -238.412926) (xy 175.627641 -238.356425) (xy 175.602422 -238.296082) (xy 175.585362 -238.232946)
			(xy 175.576755 -238.168114) (xy 175.57623 -238.135414) (xy 175.576719 -238.104251) (xy 175.584531 -238.042417)
			(xy 175.600031 -237.982049) (xy 175.622974 -237.924101) (xy 175.653 -237.869484) (xy 175.689634 -237.819062)
			(xy 175.732299 -237.773628) (xy 175.780321 -237.7339) (xy 175.832945 -237.700505) (xy 175.889339 -237.673968)
			(xy 175.948614 -237.654708) (xy 176.009835 -237.643029) (xy 176.072038 -237.639116) (xy 176.134241 -237.643029)
			(xy 176.195462 -237.654708) (xy 176.254737 -237.673968) (xy 176.311131 -237.700505) (xy 176.363755 -237.7339)
			(xy 176.411777 -237.773628) (xy 176.454442 -237.819062) (xy 176.491076 -237.869484) (xy 176.521102 -237.924101)
			(xy 176.544045 -237.982049) (xy 176.559545 -238.042417) (xy 176.567357 -238.104251) (xy 176.567846 -238.135414)
			(xy 180.531023 -238.135414) (xy 180.534958 -238.081643) (xy 180.546681 -238.029019) (xy 180.565941 -237.978662)
			(xy 180.592327 -237.931645) (xy 180.625279 -237.888972) (xy 180.664092 -237.851551) (xy 180.70794 -237.820181)
			(xy 180.755888 -237.795529) (xy 180.806915 -237.778121) (xy 180.859933 -237.768328) (xy 180.913812 -237.766359)
			(xy 180.967403 -237.772256) (xy 181.019564 -237.785892) (xy 181.069184 -237.806979) (xy 181.115205 -237.835065)
			(xy 181.156647 -237.869553) (xy 181.192625 -237.909707) (xy 181.222373 -237.954671) (xy 181.245258 -238.003488)
			(xy 181.26079 -238.055117) (xy 181.26864 -238.108457) (xy 181.269132 -238.135414) (xy 181.26864 -238.162371)
			(xy 181.26079 -238.215711) (xy 181.245258 -238.26734) (xy 181.222373 -238.316157) (xy 181.192625 -238.361121)
			(xy 181.156647 -238.401275) (xy 181.115205 -238.435763) (xy 181.069184 -238.463849) (xy 181.019564 -238.484936)
			(xy 180.967403 -238.498572) (xy 180.913812 -238.504469) (xy 180.859933 -238.5025) (xy 180.806915 -238.492707)
			(xy 180.755888 -238.475299) (xy 180.70794 -238.450647) (xy 180.664092 -238.419277) (xy 180.625279 -238.381856)
			(xy 180.592327 -238.339183) (xy 180.565941 -238.292166) (xy 180.546681 -238.241809) (xy 180.534958 -238.189185)
			(xy 180.531023 -238.135414) (xy 176.567846 -238.135414) (xy 176.567289 -238.168113) (xy 176.558686 -238.232944)
			(xy 176.541631 -238.29608) (xy 176.516421 -238.356424) (xy 176.483493 -238.412929) (xy 176.443419 -238.464611)
			(xy 176.420526 -238.487966) (xy 176.41316 -238.495332) (xy 176.40554 -238.513874) (xy 176.40554 -238.560356)
			(xy 176.820337 -238.560356) (xy 176.824272 -238.506585) (xy 176.835995 -238.453961) (xy 176.855255 -238.403604)
			(xy 176.881641 -238.356587) (xy 176.914593 -238.313914) (xy 176.953406 -238.276493) (xy 176.997254 -238.245123)
			(xy 177.045202 -238.220471) (xy 177.096229 -238.203063) (xy 177.149247 -238.19327) (xy 177.203126 -238.191301)
			(xy 177.256717 -238.197198) (xy 177.308878 -238.210834) (xy 177.358498 -238.231921) (xy 177.404519 -238.260007)
			(xy 177.445961 -238.294495) (xy 177.481939 -238.334649) (xy 177.511687 -238.379613) (xy 177.534572 -238.42843)
			(xy 177.550104 -238.480059) (xy 177.557954 -238.533399) (xy 177.558446 -238.560356) (xy 177.557954 -238.587313)
			(xy 177.550104 -238.640653) (xy 177.534572 -238.692282) (xy 177.511687 -238.741099) (xy 177.481939 -238.786063)
			(xy 177.445961 -238.826217) (xy 177.404519 -238.860705) (xy 177.358498 -238.888791) (xy 177.308878 -238.909878)
			(xy 177.256717 -238.923514) (xy 177.203126 -238.929411) (xy 177.149247 -238.927442) (xy 177.096229 -238.917649)
			(xy 177.045202 -238.900241) (xy 176.997254 -238.875589) (xy 176.953406 -238.844219) (xy 176.914593 -238.806798)
			(xy 176.881641 -238.764125) (xy 176.855255 -238.717108) (xy 176.835995 -238.666751) (xy 176.824272 -238.614127)
			(xy 176.820337 -238.560356) (xy 176.40554 -238.560356) (xy 176.40554 -238.606838) (xy 176.41316 -238.62538)
			(xy 176.420526 -238.632746) (xy 176.443412 -238.656109) (xy 176.483498 -238.707785) (xy 176.516437 -238.764285)
			(xy 176.541656 -238.824629) (xy 176.558716 -238.887765) (xy 176.567321 -238.952598) (xy 176.567846 -238.985298)
			(xy 176.567357 -239.016461) (xy 176.559545 -239.078295) (xy 176.544045 -239.138663) (xy 176.521102 -239.196611)
			(xy 176.491076 -239.251228) (xy 176.454442 -239.30165) (xy 176.411777 -239.347084) (xy 176.363755 -239.386812)
			(xy 176.311131 -239.420207) (xy 176.254737 -239.446744) (xy 176.195462 -239.466004) (xy 176.134241 -239.477683)
			(xy 176.072038 -239.481596) (xy 176.009835 -239.477683) (xy 175.948614 -239.466004) (xy 175.889339 -239.446744)
			(xy 175.832945 -239.420207) (xy 175.780321 -239.386812) (xy 175.732299 -239.347084) (xy 175.689634 -239.30165)
			(xy 175.653 -239.251228) (xy 175.622974 -239.196611) (xy 175.600031 -239.138663) (xy 175.584531 -239.078295)
			(xy 175.576719 -239.016461) (xy 175.57623 -238.985298) (xy 172.467778 -238.985298) (xy 172.467229 -239.018017)
			(xy 172.458636 -239.08289) (xy 172.441586 -239.146068) (xy 172.416376 -239.206456) (xy 172.383443 -239.263004)
			(xy 172.343359 -239.314729) (xy 172.320458 -239.338104) (xy 172.313092 -239.345216) (xy 172.305218 -239.364012)
			(xy 172.305218 -239.410494) (xy 172.720269 -239.410494) (xy 172.724204 -239.356723) (xy 172.735927 -239.304099)
			(xy 172.755187 -239.253742) (xy 172.781573 -239.206725) (xy 172.814525 -239.164052) (xy 172.853338 -239.126631)
			(xy 172.897186 -239.095261) (xy 172.945134 -239.070609) (xy 172.996161 -239.053201) (xy 173.049179 -239.043408)
			(xy 173.103058 -239.041439) (xy 173.156649 -239.047336) (xy 173.20881 -239.060972) (xy 173.25843 -239.082059)
			(xy 173.304451 -239.110145) (xy 173.345893 -239.144633) (xy 173.381871 -239.184787) (xy 173.411619 -239.229751)
			(xy 173.434504 -239.278568) (xy 173.450036 -239.330197) (xy 173.457886 -239.383537) (xy 173.458378 -239.410494)
			(xy 173.457886 -239.437451) (xy 173.450036 -239.490791) (xy 173.434504 -239.54242) (xy 173.411619 -239.591237)
			(xy 173.381871 -239.636201) (xy 173.345893 -239.676355) (xy 173.304451 -239.710843) (xy 173.25843 -239.738929)
			(xy 173.20881 -239.760016) (xy 173.156649 -239.773652) (xy 173.103058 -239.779549) (xy 173.049179 -239.77758)
			(xy 172.996161 -239.767787) (xy 172.945134 -239.750379) (xy 172.897186 -239.725727) (xy 172.853338 -239.694357)
			(xy 172.814525 -239.656936) (xy 172.781573 -239.614263) (xy 172.755187 -239.567246) (xy 172.735927 -239.516889)
			(xy 172.724204 -239.464265) (xy 172.720269 -239.410494) (xy 172.305218 -239.410494) (xy 172.305218 -239.456722)
			(xy 172.313092 -239.475518) (xy 172.320458 -239.48263) (xy 172.343339 -239.506024) (xy 172.383423 -239.557748)
			(xy 172.41636 -239.614292) (xy 172.441578 -239.674675) (xy 172.45864 -239.737849) (xy 172.467251 -239.802717)
			(xy 172.467778 -239.835436) (xy 174.318437 -239.835436) (xy 174.322372 -239.781665) (xy 174.334095 -239.729041)
			(xy 174.353355 -239.678684) (xy 174.379741 -239.631667) (xy 174.412693 -239.588994) (xy 174.451506 -239.551573)
			(xy 174.495354 -239.520203) (xy 174.543302 -239.495551) (xy 174.594329 -239.478143) (xy 174.647347 -239.46835)
			(xy 174.701226 -239.466381) (xy 174.754817 -239.472278) (xy 174.806978 -239.485914) (xy 174.856598 -239.507001)
			(xy 174.902619 -239.535087) (xy 174.944061 -239.569575) (xy 174.980039 -239.609729) (xy 175.009787 -239.654693)
			(xy 175.032672 -239.70351) (xy 175.048204 -239.755139) (xy 175.056054 -239.808479) (xy 175.056546 -239.835436)
			(xy 179.020216 -239.835436) (xy 179.020725 -239.802715) (xy 179.029326 -239.737841) (xy 179.046384 -239.674662)
			(xy 179.071602 -239.614275) (xy 179.104542 -239.557728) (xy 179.144632 -239.506004) (xy 179.167536 -239.48263)
			(xy 179.174902 -239.475518) (xy 179.182776 -239.456722) (xy 179.182776 -239.364012) (xy 179.174902 -239.345216)
			(xy 179.167536 -239.338104) (xy 179.144622 -239.314741) (xy 179.104542 -239.26301) (xy 179.07161 -239.20646)
			(xy 179.046397 -239.146071) (xy 179.029341 -239.082891) (xy 179.020739 -239.018018) (xy 179.020216 -238.985298)
			(xy 179.020705 -238.954135) (xy 179.028517 -238.892301) (xy 179.044017 -238.831933) (xy 179.06696 -238.773985)
			(xy 179.096986 -238.719368) (xy 179.13362 -238.668946) (xy 179.176285 -238.623512) (xy 179.224307 -238.583784)
			(xy 179.276931 -238.550389) (xy 179.333325 -238.523852) (xy 179.3926 -238.504592) (xy 179.453821 -238.492913)
			(xy 179.516024 -238.489) (xy 179.578227 -238.492913) (xy 179.639448 -238.504592) (xy 179.698723 -238.523852)
			(xy 179.755117 -238.550389) (xy 179.807741 -238.583784) (xy 179.855763 -238.623512) (xy 179.898428 -238.668946)
			(xy 179.935062 -238.719368) (xy 179.965088 -238.773985) (xy 179.988031 -238.831933) (xy 180.003531 -238.892301)
			(xy 180.011343 -238.954135) (xy 180.011832 -238.985298) (xy 183.120284 -238.985298) (xy 183.120839 -238.952598)
			(xy 183.129442 -238.887768) (xy 183.146496 -238.824631) (xy 183.171707 -238.764287) (xy 183.204636 -238.707782)
			(xy 183.24471 -238.6561) (xy 183.267604 -238.632746) (xy 183.27497 -238.62538) (xy 183.28259 -238.606838)
			(xy 183.28259 -238.513874) (xy 183.27497 -238.495332) (xy 183.267604 -238.487966) (xy 183.244729 -238.464592)
			(xy 183.204641 -238.412919) (xy 183.1717 -238.356421) (xy 183.146479 -238.29608) (xy 183.129416 -238.232945)
			(xy 183.12081 -238.168114) (xy 183.120284 -238.135414) (xy 183.120773 -238.104251) (xy 183.128585 -238.042417)
			(xy 183.144085 -237.982049) (xy 183.167028 -237.924101) (xy 183.197054 -237.869484) (xy 183.233688 -237.819062)
			(xy 183.276353 -237.773628) (xy 183.324375 -237.7339) (xy 183.376999 -237.700505) (xy 183.433393 -237.673968)
			(xy 183.492668 -237.654708) (xy 183.553889 -237.643029) (xy 183.616092 -237.639116) (xy 183.678295 -237.643029)
			(xy 183.739516 -237.654708) (xy 183.798791 -237.673968) (xy 183.855185 -237.700505) (xy 183.907809 -237.7339)
			(xy 183.955831 -237.773628) (xy 183.998496 -237.819062) (xy 184.03513 -237.869484) (xy 184.065156 -237.924101)
			(xy 184.088099 -237.982049) (xy 184.103599 -238.042417) (xy 184.111411 -238.104251) (xy 184.1119 -238.135414)
			(xy 188.075077 -238.135414) (xy 188.079012 -238.081643) (xy 188.090735 -238.029019) (xy 188.109995 -237.978662)
			(xy 188.136381 -237.931645) (xy 188.169333 -237.888972) (xy 188.208146 -237.851551) (xy 188.251994 -237.820181)
			(xy 188.299942 -237.795529) (xy 188.350969 -237.778121) (xy 188.403987 -237.768328) (xy 188.457866 -237.766359)
			(xy 188.511457 -237.772256) (xy 188.563618 -237.785892) (xy 188.613238 -237.806979) (xy 188.659259 -237.835065)
			(xy 188.700701 -237.869553) (xy 188.736679 -237.909707) (xy 188.766427 -237.954671) (xy 188.789312 -238.003488)
			(xy 188.804844 -238.055117) (xy 188.812694 -238.108457) (xy 188.813186 -238.135414) (xy 188.812694 -238.162371)
			(xy 188.804844 -238.215711) (xy 188.789312 -238.26734) (xy 188.766427 -238.316157) (xy 188.736679 -238.361121)
			(xy 188.700701 -238.401275) (xy 188.659259 -238.435763) (xy 188.613238 -238.463849) (xy 188.563618 -238.484936)
			(xy 188.511457 -238.498572) (xy 188.457866 -238.504469) (xy 188.403987 -238.5025) (xy 188.350969 -238.492707)
			(xy 188.299942 -238.475299) (xy 188.251994 -238.450647) (xy 188.208146 -238.419277) (xy 188.169333 -238.381856)
			(xy 188.136381 -238.339183) (xy 188.109995 -238.292166) (xy 188.090735 -238.241809) (xy 188.079012 -238.189185)
			(xy 188.075077 -238.135414) (xy 184.1119 -238.135414) (xy 184.111357 -238.168114) (xy 184.102753 -238.232946)
			(xy 184.085696 -238.296082) (xy 184.060483 -238.356427) (xy 184.027552 -238.412931) (xy 183.987475 -238.464612)
			(xy 183.96458 -238.487966) (xy 183.957214 -238.495332) (xy 183.949594 -238.513874) (xy 183.949594 -238.560356)
			(xy 184.364391 -238.560356) (xy 184.368326 -238.506585) (xy 184.380049 -238.453961) (xy 184.399309 -238.403604)
			(xy 184.425695 -238.356587) (xy 184.458647 -238.313914) (xy 184.49746 -238.276493) (xy 184.541308 -238.245123)
			(xy 184.589256 -238.220471) (xy 184.640283 -238.203063) (xy 184.693301 -238.19327) (xy 184.74718 -238.191301)
			(xy 184.800771 -238.197198) (xy 184.852932 -238.210834) (xy 184.902552 -238.231921) (xy 184.948573 -238.260007)
			(xy 184.990015 -238.294495) (xy 185.025993 -238.334649) (xy 185.055741 -238.379613) (xy 185.078626 -238.42843)
			(xy 185.094158 -238.480059) (xy 185.102008 -238.533399) (xy 185.1025 -238.560356) (xy 185.102008 -238.587313)
			(xy 185.094158 -238.640653) (xy 185.078626 -238.692282) (xy 185.055741 -238.741099) (xy 185.025993 -238.786063)
			(xy 184.990015 -238.826217) (xy 184.948573 -238.860705) (xy 184.902552 -238.888791) (xy 184.852932 -238.909878)
			(xy 184.800771 -238.923514) (xy 184.74718 -238.929411) (xy 184.693301 -238.927442) (xy 184.640283 -238.917649)
			(xy 184.589256 -238.900241) (xy 184.541308 -238.875589) (xy 184.49746 -238.844219) (xy 184.458647 -238.806798)
			(xy 184.425695 -238.764125) (xy 184.399309 -238.717108) (xy 184.380049 -238.666751) (xy 184.368326 -238.614127)
			(xy 184.364391 -238.560356) (xy 183.949594 -238.560356) (xy 183.949594 -238.606838) (xy 183.957214 -238.62538)
			(xy 183.96458 -238.632746) (xy 183.987476 -238.6561) (xy 184.027559 -238.707779) (xy 184.060496 -238.764281)
			(xy 184.085712 -238.824626) (xy 184.102771 -238.887764) (xy 184.111375 -238.952597) (xy 184.1119 -238.985298)
			(xy 184.111411 -239.016461) (xy 184.103599 -239.078295) (xy 184.088099 -239.138663) (xy 184.065156 -239.196611)
			(xy 184.03513 -239.251228) (xy 183.998496 -239.30165) (xy 183.955831 -239.347084) (xy 183.907809 -239.386812)
			(xy 183.855185 -239.420207) (xy 183.798791 -239.446744) (xy 183.739516 -239.466004) (xy 183.678295 -239.477683)
			(xy 183.616092 -239.481596) (xy 183.553889 -239.477683) (xy 183.492668 -239.466004) (xy 183.433393 -239.446744)
			(xy 183.376999 -239.420207) (xy 183.324375 -239.386812) (xy 183.276353 -239.347084) (xy 183.233688 -239.30165)
			(xy 183.197054 -239.251228) (xy 183.167028 -239.196611) (xy 183.144085 -239.138663) (xy 183.128585 -239.078295)
			(xy 183.120773 -239.016461) (xy 183.120284 -238.985298) (xy 180.011832 -238.985298) (xy 180.011296 -239.018018)
			(xy 180.002702 -239.082891) (xy 179.985651 -239.146071) (xy 179.960438 -239.206459) (xy 179.927502 -239.263006)
			(xy 179.887414 -239.31473) (xy 179.864512 -239.338104) (xy 179.857146 -239.345216) (xy 179.849272 -239.364012)
			(xy 179.849272 -239.410494) (xy 180.264323 -239.410494) (xy 180.268258 -239.356723) (xy 180.279981 -239.304099)
			(xy 180.299241 -239.253742) (xy 180.325627 -239.206725) (xy 180.358579 -239.164052) (xy 180.397392 -239.126631)
			(xy 180.44124 -239.095261) (xy 180.489188 -239.070609) (xy 180.540215 -239.053201) (xy 180.593233 -239.043408)
			(xy 180.647112 -239.041439) (xy 180.700703 -239.047336) (xy 180.752864 -239.060972) (xy 180.802484 -239.082059)
			(xy 180.848505 -239.110145) (xy 180.889947 -239.144633) (xy 180.925925 -239.184787) (xy 180.955673 -239.229751)
			(xy 180.978558 -239.278568) (xy 180.99409 -239.330197) (xy 181.00194 -239.383537) (xy 181.002432 -239.410494)
			(xy 181.00194 -239.437451) (xy 180.99409 -239.490791) (xy 180.978558 -239.54242) (xy 180.955673 -239.591237)
			(xy 180.925925 -239.636201) (xy 180.889947 -239.676355) (xy 180.848505 -239.710843) (xy 180.802484 -239.738929)
			(xy 180.752864 -239.760016) (xy 180.700703 -239.773652) (xy 180.647112 -239.779549) (xy 180.593233 -239.77758)
			(xy 180.540215 -239.767787) (xy 180.489188 -239.750379) (xy 180.44124 -239.725727) (xy 180.397392 -239.694357)
			(xy 180.358579 -239.656936) (xy 180.325627 -239.614263) (xy 180.299241 -239.567246) (xy 180.279981 -239.516889)
			(xy 180.268258 -239.464265) (xy 180.264323 -239.410494) (xy 179.849272 -239.410494) (xy 179.849272 -239.456722)
			(xy 179.857146 -239.475518) (xy 179.864512 -239.48263) (xy 179.887384 -239.506032) (xy 179.92747 -239.557754)
			(xy 179.96041 -239.614296) (xy 179.98563 -239.674677) (xy 180.002693 -239.73785) (xy 180.011304 -239.802718)
			(xy 180.011832 -239.835436) (xy 181.862491 -239.835436) (xy 181.866426 -239.781665) (xy 181.878149 -239.729041)
			(xy 181.897409 -239.678684) (xy 181.923795 -239.631667) (xy 181.956747 -239.588994) (xy 181.99556 -239.551573)
			(xy 182.039408 -239.520203) (xy 182.087356 -239.495551) (xy 182.138383 -239.478143) (xy 182.191401 -239.46835)
			(xy 182.24528 -239.466381) (xy 182.298871 -239.472278) (xy 182.351032 -239.485914) (xy 182.400652 -239.507001)
			(xy 182.446673 -239.535087) (xy 182.488115 -239.569575) (xy 182.524093 -239.609729) (xy 182.553841 -239.654693)
			(xy 182.576726 -239.70351) (xy 182.592258 -239.755139) (xy 182.600108 -239.808479) (xy 182.6006 -239.835436)
			(xy 186.56427 -239.835436) (xy 186.564792 -239.802716) (xy 186.573393 -239.737843) (xy 186.590449 -239.674664)
			(xy 186.615664 -239.614277) (xy 186.648601 -239.55773) (xy 186.688688 -239.506005) (xy 186.71159 -239.48263)
			(xy 186.718956 -239.475518) (xy 186.72683 -239.456722) (xy 186.72683 -239.364012) (xy 186.718956 -239.345216)
			(xy 186.71159 -239.338104) (xy 186.688686 -239.314731) (xy 186.648603 -239.263004) (xy 186.615668 -239.206455)
			(xy 186.590454 -239.146068) (xy 186.573397 -239.08289) (xy 186.564794 -239.018018) (xy 186.56427 -238.985298)
			(xy 186.564759 -238.954135) (xy 186.572571 -238.892301) (xy 186.588071 -238.831933) (xy 186.611014 -238.773985)
			(xy 186.64104 -238.719368) (xy 186.677674 -238.668946) (xy 186.720339 -238.623512) (xy 186.768361 -238.583784)
			(xy 186.820985 -238.550389) (xy 186.877379 -238.523852) (xy 186.936654 -238.504592) (xy 186.997875 -238.492913)
			(xy 187.060078 -238.489) (xy 187.122281 -238.492913) (xy 187.183502 -238.504592) (xy 187.242777 -238.523852)
			(xy 187.299171 -238.550389) (xy 187.351795 -238.583784) (xy 187.399817 -238.623512) (xy 187.442482 -238.668946)
			(xy 187.479116 -238.719368) (xy 187.509142 -238.773985) (xy 187.532085 -238.831933) (xy 187.547585 -238.892301)
			(xy 187.555397 -238.954135) (xy 187.555886 -238.985298) (xy 190.664338 -238.985298) (xy 190.664907 -238.952599)
			(xy 190.673508 -238.887769) (xy 190.690561 -238.824634) (xy 190.715769 -238.76429) (xy 190.748695 -238.707785)
			(xy 190.788766 -238.656101) (xy 190.811658 -238.632746) (xy 190.819024 -238.62538) (xy 190.826644 -238.606838)
			(xy 190.826644 -238.513874) (xy 190.819024 -238.495332) (xy 190.811658 -238.487966) (xy 190.788775 -238.4646)
			(xy 190.748689 -238.412925) (xy 190.71575 -238.356425) (xy 190.690531 -238.296082) (xy 190.67347 -238.232946)
			(xy 190.664863 -238.168114) (xy 190.664338 -238.135414) (xy 190.664827 -238.104251) (xy 190.672639 -238.042417)
			(xy 190.688139 -237.982049) (xy 190.711082 -237.924101) (xy 190.741108 -237.869484) (xy 190.777742 -237.819062)
			(xy 190.820407 -237.773628) (xy 190.868429 -237.7339) (xy 190.921053 -237.700505) (xy 190.977447 -237.673968)
			(xy 191.036722 -237.654708) (xy 191.097943 -237.643029) (xy 191.160146 -237.639116) (xy 191.222349 -237.643029)
			(xy 191.28357 -237.654708) (xy 191.342845 -237.673968) (xy 191.399239 -237.700505) (xy 191.451863 -237.7339)
			(xy 191.499885 -237.773628) (xy 191.54255 -237.819062) (xy 191.579184 -237.869484) (xy 191.60921 -237.924101)
			(xy 191.632153 -237.982049) (xy 191.647653 -238.042417) (xy 191.655465 -238.104251) (xy 191.655954 -238.135414)
			(xy 195.619131 -238.135414) (xy 195.623066 -238.081643) (xy 195.634789 -238.029019) (xy 195.654049 -237.978662)
			(xy 195.680435 -237.931645) (xy 195.713387 -237.888972) (xy 195.7522 -237.851551) (xy 195.796048 -237.820181)
			(xy 195.843996 -237.795529) (xy 195.895023 -237.778121) (xy 195.948041 -237.768328) (xy 196.00192 -237.766359)
			(xy 196.055511 -237.772256) (xy 196.107672 -237.785892) (xy 196.157292 -237.806979) (xy 196.203313 -237.835065)
			(xy 196.244755 -237.869553) (xy 196.280733 -237.909707) (xy 196.310481 -237.954671) (xy 196.333366 -238.003488)
			(xy 196.348898 -238.055117) (xy 196.356748 -238.108457) (xy 196.35724 -238.135414) (xy 196.356748 -238.162371)
			(xy 196.348898 -238.215711) (xy 196.333366 -238.26734) (xy 196.310481 -238.316157) (xy 196.280733 -238.361121)
			(xy 196.244755 -238.401275) (xy 196.203313 -238.435763) (xy 196.157292 -238.463849) (xy 196.107672 -238.484936)
			(xy 196.055511 -238.498572) (xy 196.00192 -238.504469) (xy 195.948041 -238.5025) (xy 195.895023 -238.492707)
			(xy 195.843996 -238.475299) (xy 195.796048 -238.450647) (xy 195.7522 -238.419277) (xy 195.713387 -238.381856)
			(xy 195.680435 -238.339183) (xy 195.654049 -238.292166) (xy 195.634789 -238.241809) (xy 195.623066 -238.189185)
			(xy 195.619131 -238.135414) (xy 191.655954 -238.135414) (xy 191.655395 -238.168113) (xy 191.646792 -238.232944)
			(xy 191.629737 -238.296079) (xy 191.604527 -238.356424) (xy 191.5716 -238.412928) (xy 191.531527 -238.464611)
			(xy 191.508634 -238.487966) (xy 191.501268 -238.495332) (xy 191.493648 -238.513874) (xy 191.493648 -238.560356)
			(xy 191.908445 -238.560356) (xy 191.91238 -238.506585) (xy 191.924103 -238.453961) (xy 191.943363 -238.403604)
			(xy 191.969749 -238.356587) (xy 192.002701 -238.313914) (xy 192.041514 -238.276493) (xy 192.085362 -238.245123)
			(xy 192.13331 -238.220471) (xy 192.184337 -238.203063) (xy 192.237355 -238.19327) (xy 192.291234 -238.191301)
			(xy 192.344825 -238.197198) (xy 192.396986 -238.210834) (xy 192.446606 -238.231921) (xy 192.492627 -238.260007)
			(xy 192.534069 -238.294495) (xy 192.570047 -238.334649) (xy 192.599795 -238.379613) (xy 192.62268 -238.42843)
			(xy 192.638212 -238.480059) (xy 192.646062 -238.533399) (xy 192.646554 -238.560356) (xy 192.646062 -238.587313)
			(xy 192.638212 -238.640653) (xy 192.62268 -238.692282) (xy 192.599795 -238.741099) (xy 192.570047 -238.786063)
			(xy 192.534069 -238.826217) (xy 192.492627 -238.860705) (xy 192.446606 -238.888791) (xy 192.396986 -238.909878)
			(xy 192.344825 -238.923514) (xy 192.291234 -238.929411) (xy 192.237355 -238.927442) (xy 192.184337 -238.917649)
			(xy 192.13331 -238.900241) (xy 192.085362 -238.875589) (xy 192.041514 -238.844219) (xy 192.002701 -238.806798)
			(xy 191.969749 -238.764125) (xy 191.943363 -238.717108) (xy 191.924103 -238.666751) (xy 191.91238 -238.614127)
			(xy 191.908445 -238.560356) (xy 191.493648 -238.560356) (xy 191.493648 -238.606838) (xy 191.501268 -238.62538)
			(xy 191.508634 -238.632746) (xy 191.531522 -238.656108) (xy 191.571607 -238.707784) (xy 191.604546 -238.764285)
			(xy 191.629764 -238.824628) (xy 191.646824 -238.887765) (xy 191.655429 -238.952597) (xy 191.655954 -238.985298)
			(xy 191.655465 -239.016461) (xy 191.647653 -239.078295) (xy 191.632153 -239.138663) (xy 191.60921 -239.196611)
			(xy 191.579184 -239.251228) (xy 191.54255 -239.30165) (xy 191.499885 -239.347084) (xy 191.451863 -239.386812)
			(xy 191.399239 -239.420207) (xy 191.342845 -239.446744) (xy 191.28357 -239.466004) (xy 191.222349 -239.477683)
			(xy 191.160146 -239.481596) (xy 191.097943 -239.477683) (xy 191.036722 -239.466004) (xy 190.977447 -239.446744)
			(xy 190.921053 -239.420207) (xy 190.868429 -239.386812) (xy 190.820407 -239.347084) (xy 190.777742 -239.30165)
			(xy 190.741108 -239.251228) (xy 190.711082 -239.196611) (xy 190.688139 -239.138663) (xy 190.672639 -239.078295)
			(xy 190.664827 -239.016461) (xy 190.664338 -238.985298) (xy 187.555886 -238.985298) (xy 187.555334 -239.018017)
			(xy 187.546742 -239.082889) (xy 187.529692 -239.146068) (xy 187.504482 -239.206455) (xy 187.47155 -239.263003)
			(xy 187.431466 -239.314729) (xy 187.408566 -239.338104) (xy 187.4012 -239.345216) (xy 187.393326 -239.364012)
			(xy 187.393326 -239.410494) (xy 187.808377 -239.410494) (xy 187.812312 -239.356723) (xy 187.824035 -239.304099)
			(xy 187.843295 -239.253742) (xy 187.869681 -239.206725) (xy 187.902633 -239.164052) (xy 187.941446 -239.126631)
			(xy 187.985294 -239.095261) (xy 188.033242 -239.070609) (xy 188.084269 -239.053201) (xy 188.137287 -239.043408)
			(xy 188.191166 -239.041439) (xy 188.244757 -239.047336) (xy 188.296918 -239.060972) (xy 188.346538 -239.082059)
			(xy 188.392559 -239.110145) (xy 188.434001 -239.144633) (xy 188.469979 -239.184787) (xy 188.499727 -239.229751)
			(xy 188.522612 -239.278568) (xy 188.538144 -239.330197) (xy 188.545994 -239.383537) (xy 188.546486 -239.410494)
			(xy 188.545994 -239.437451) (xy 188.538144 -239.490791) (xy 188.522612 -239.54242) (xy 188.499727 -239.591237)
			(xy 188.469979 -239.636201) (xy 188.434001 -239.676355) (xy 188.392559 -239.710843) (xy 188.346538 -239.738929)
			(xy 188.296918 -239.760016) (xy 188.244757 -239.773652) (xy 188.191166 -239.779549) (xy 188.137287 -239.77758)
			(xy 188.084269 -239.767787) (xy 188.033242 -239.750379) (xy 187.985294 -239.725727) (xy 187.941446 -239.694357)
			(xy 187.902633 -239.656936) (xy 187.869681 -239.614263) (xy 187.843295 -239.567246) (xy 187.824035 -239.516889)
			(xy 187.812312 -239.464265) (xy 187.808377 -239.410494) (xy 187.393326 -239.410494) (xy 187.393326 -239.456722)
			(xy 187.4012 -239.475518) (xy 187.408566 -239.48263) (xy 187.431448 -239.506023) (xy 187.471532 -239.557747)
			(xy 187.504468 -239.614291) (xy 187.529686 -239.674674) (xy 187.546749 -239.737849) (xy 187.555359 -239.802717)
			(xy 187.555886 -239.835436) (xy 189.406545 -239.835436) (xy 189.41048 -239.781665) (xy 189.422203 -239.729041)
			(xy 189.441463 -239.678684) (xy 189.467849 -239.631667) (xy 189.500801 -239.588994) (xy 189.539614 -239.551573)
			(xy 189.583462 -239.520203) (xy 189.63141 -239.495551) (xy 189.682437 -239.478143) (xy 189.735455 -239.46835)
			(xy 189.789334 -239.466381) (xy 189.842925 -239.472278) (xy 189.895086 -239.485914) (xy 189.944706 -239.507001)
			(xy 189.990727 -239.535087) (xy 190.032169 -239.569575) (xy 190.068147 -239.609729) (xy 190.097895 -239.654693)
			(xy 190.12078 -239.70351) (xy 190.136312 -239.755139) (xy 190.144162 -239.808479) (xy 190.144654 -239.835436)
			(xy 194.108324 -239.835436) (xy 194.10883 -239.802715) (xy 194.117432 -239.737841) (xy 194.13449 -239.674662)
			(xy 194.159708 -239.614274) (xy 194.192649 -239.557728) (xy 194.23274 -239.506004) (xy 194.255644 -239.48263)
			(xy 194.26301 -239.475518) (xy 194.270884 -239.456722) (xy 194.270884 -239.364012) (xy 194.26301 -239.345216)
			(xy 194.255644 -239.338104) (xy 194.232732 -239.31474) (xy 194.192651 -239.263009) (xy 194.159718 -239.206459)
			(xy 194.134505 -239.14607) (xy 194.11745 -239.082891) (xy 194.108847 -239.018018) (xy 194.108324 -238.985298)
			(xy 194.108813 -238.954135) (xy 194.116625 -238.892301) (xy 194.132125 -238.831933) (xy 194.155068 -238.773985)
			(xy 194.185094 -238.719368) (xy 194.221728 -238.668946) (xy 194.264393 -238.623512) (xy 194.312415 -238.583784)
			(xy 194.365039 -238.550389) (xy 194.421433 -238.523852) (xy 194.480708 -238.504592) (xy 194.541929 -238.492913)
			(xy 194.604132 -238.489) (xy 194.666335 -238.492913) (xy 194.727556 -238.504592) (xy 194.786831 -238.523852)
			(xy 194.843225 -238.550389) (xy 194.895849 -238.583784) (xy 194.943871 -238.623512) (xy 194.986536 -238.668946)
			(xy 195.02317 -238.719368) (xy 195.053196 -238.773985) (xy 195.076139 -238.831933) (xy 195.091639 -238.892301)
			(xy 195.099451 -238.954135) (xy 195.09994 -238.985298) (xy 198.208392 -238.985298) (xy 198.208945 -238.952598)
			(xy 198.217547 -238.887767) (xy 198.234602 -238.824631) (xy 198.259813 -238.764286) (xy 198.292743 -238.707782)
			(xy 198.332818 -238.6561) (xy 198.355712 -238.632746) (xy 198.363078 -238.62538) (xy 198.370698 -238.606838)
			(xy 198.370698 -238.513874) (xy 198.363078 -238.495332) (xy 198.355712 -238.487966) (xy 198.33282 -238.464608)
			(xy 198.292737 -238.41293) (xy 198.2598 -238.356428) (xy 198.234583 -238.296084) (xy 198.217523 -238.232947)
			(xy 198.208917 -238.168115) (xy 198.208392 -238.135414) (xy 198.208881 -238.104251) (xy 198.216693 -238.042417)
			(xy 198.232193 -237.982049) (xy 198.255136 -237.924101) (xy 198.285162 -237.869484) (xy 198.321796 -237.819062)
			(xy 198.364461 -237.773628) (xy 198.412483 -237.7339) (xy 198.465107 -237.700505) (xy 198.521501 -237.673968)
			(xy 198.580776 -237.654708) (xy 198.641997 -237.643029) (xy 198.7042 -237.639116) (xy 198.766403 -237.643029)
			(xy 198.827624 -237.654708) (xy 198.886899 -237.673968) (xy 198.943293 -237.700505) (xy 198.995917 -237.7339)
			(xy 199.043939 -237.773628) (xy 199.086604 -237.819062) (xy 199.123238 -237.869484) (xy 199.153264 -237.924101)
			(xy 199.176207 -237.982049) (xy 199.191707 -238.042417) (xy 199.199519 -238.104251) (xy 199.200008 -238.135414)
			(xy 203.162931 -238.135414) (xy 203.166866 -238.081643) (xy 203.178589 -238.029019) (xy 203.197849 -237.978662)
			(xy 203.224235 -237.931645) (xy 203.257187 -237.888972) (xy 203.296 -237.851551) (xy 203.339848 -237.820181)
			(xy 203.387796 -237.795529) (xy 203.438823 -237.778121) (xy 203.491841 -237.768328) (xy 203.54572 -237.766359)
			(xy 203.599311 -237.772256) (xy 203.651472 -237.785892) (xy 203.701092 -237.806979) (xy 203.747113 -237.835065)
			(xy 203.788555 -237.869553) (xy 203.824533 -237.909707) (xy 203.854281 -237.954671) (xy 203.877166 -238.003488)
			(xy 203.892698 -238.055117) (xy 203.900548 -238.108457) (xy 203.90104 -238.135414) (xy 203.900548 -238.162371)
			(xy 203.892698 -238.215711) (xy 203.877166 -238.26734) (xy 203.854281 -238.316157) (xy 203.824533 -238.361121)
			(xy 203.788555 -238.401275) (xy 203.747113 -238.435763) (xy 203.701092 -238.463849) (xy 203.651472 -238.484936)
			(xy 203.599311 -238.498572) (xy 203.54572 -238.504469) (xy 203.491841 -238.5025) (xy 203.438823 -238.492707)
			(xy 203.387796 -238.475299) (xy 203.339848 -238.450647) (xy 203.296 -238.419277) (xy 203.257187 -238.381856)
			(xy 203.224235 -238.339183) (xy 203.197849 -238.292166) (xy 203.178589 -238.241809) (xy 203.166866 -238.189185)
			(xy 203.162931 -238.135414) (xy 199.200008 -238.135414) (xy 199.199463 -238.168114) (xy 199.190859 -238.232945)
			(xy 199.173802 -238.296082) (xy 199.14859 -238.356426) (xy 199.115659 -238.41293) (xy 199.075583 -238.464612)
			(xy 199.052688 -238.487966) (xy 199.045322 -238.495332) (xy 199.037702 -238.513874) (xy 199.037702 -238.560356)
			(xy 199.452499 -238.560356) (xy 199.456434 -238.506585) (xy 199.468157 -238.453961) (xy 199.487417 -238.403604)
			(xy 199.513803 -238.356587) (xy 199.546755 -238.313914) (xy 199.585568 -238.276493) (xy 199.629416 -238.245123)
			(xy 199.677364 -238.220471) (xy 199.728391 -238.203063) (xy 199.781409 -238.19327) (xy 199.835288 -238.191301)
			(xy 199.888879 -238.197198) (xy 199.94104 -238.210834) (xy 199.99066 -238.231921) (xy 200.036681 -238.260007)
			(xy 200.078123 -238.294495) (xy 200.114101 -238.334649) (xy 200.143849 -238.379613) (xy 200.166734 -238.42843)
			(xy 200.182266 -238.480059) (xy 200.190116 -238.533399) (xy 200.190608 -238.560356) (xy 200.190116 -238.587313)
			(xy 200.182266 -238.640653) (xy 200.166734 -238.692282) (xy 200.143849 -238.741099) (xy 200.114101 -238.786063)
			(xy 200.078123 -238.826217) (xy 200.036681 -238.860705) (xy 199.99066 -238.888791) (xy 199.94104 -238.909878)
			(xy 199.888879 -238.923514) (xy 199.835288 -238.929411) (xy 199.781409 -238.927442) (xy 199.728391 -238.917649)
			(xy 199.677364 -238.900241) (xy 199.629416 -238.875589) (xy 199.585568 -238.844219) (xy 199.546755 -238.806798)
			(xy 199.513803 -238.764125) (xy 199.487417 -238.717108) (xy 199.468157 -238.666751) (xy 199.456434 -238.614127)
			(xy 199.452499 -238.560356) (xy 199.037702 -238.560356) (xy 199.037702 -238.606838) (xy 199.045322 -238.62538)
			(xy 199.052688 -238.632746) (xy 199.075585 -238.656098) (xy 199.115668 -238.707778) (xy 199.148604 -238.764281)
			(xy 199.173821 -238.824626) (xy 199.190879 -238.887764) (xy 199.199483 -238.952597) (xy 199.200008 -238.985298)
			(xy 199.199519 -239.016461) (xy 199.191707 -239.078295) (xy 199.176207 -239.138663) (xy 199.153264 -239.196611)
			(xy 199.123238 -239.251228) (xy 199.086604 -239.30165) (xy 199.043939 -239.347084) (xy 198.995917 -239.386812)
			(xy 198.943293 -239.420207) (xy 198.886899 -239.446744) (xy 198.827624 -239.466004) (xy 198.766403 -239.477683)
			(xy 198.7042 -239.481596) (xy 198.641997 -239.477683) (xy 198.580776 -239.466004) (xy 198.521501 -239.446744)
			(xy 198.465107 -239.420207) (xy 198.412483 -239.386812) (xy 198.364461 -239.347084) (xy 198.321796 -239.30165)
			(xy 198.285162 -239.251228) (xy 198.255136 -239.196611) (xy 198.232193 -239.138663) (xy 198.216693 -239.078295)
			(xy 198.208881 -239.016461) (xy 198.208392 -238.985298) (xy 195.09994 -238.985298) (xy 195.099402 -239.018018)
			(xy 195.090808 -239.082891) (xy 195.073757 -239.14607) (xy 195.048545 -239.206458) (xy 195.015609 -239.263005)
			(xy 194.975522 -239.31473) (xy 194.95262 -239.338104) (xy 194.945254 -239.345216) (xy 194.93738 -239.364012)
			(xy 194.93738 -239.410494) (xy 195.352431 -239.410494) (xy 195.356366 -239.356723) (xy 195.368089 -239.304099)
			(xy 195.387349 -239.253742) (xy 195.413735 -239.206725) (xy 195.446687 -239.164052) (xy 195.4855 -239.126631)
			(xy 195.529348 -239.095261) (xy 195.577296 -239.070609) (xy 195.628323 -239.053201) (xy 195.681341 -239.043408)
			(xy 195.73522 -239.041439) (xy 195.788811 -239.047336) (xy 195.840972 -239.060972) (xy 195.890592 -239.082059)
			(xy 195.936613 -239.110145) (xy 195.978055 -239.144633) (xy 196.014033 -239.184787) (xy 196.043781 -239.229751)
			(xy 196.066666 -239.278568) (xy 196.082198 -239.330197) (xy 196.090048 -239.383537) (xy 196.09054 -239.410494)
			(xy 196.090048 -239.437451) (xy 196.082198 -239.490791) (xy 196.066666 -239.54242) (xy 196.043781 -239.591237)
			(xy 196.014033 -239.636201) (xy 195.978055 -239.676355) (xy 195.936613 -239.710843) (xy 195.890592 -239.738929)
			(xy 195.840972 -239.760016) (xy 195.788811 -239.773652) (xy 195.73522 -239.779549) (xy 195.681341 -239.77758)
			(xy 195.628323 -239.767787) (xy 195.577296 -239.750379) (xy 195.529348 -239.725727) (xy 195.4855 -239.694357)
			(xy 195.446687 -239.656936) (xy 195.413735 -239.614263) (xy 195.387349 -239.567246) (xy 195.368089 -239.516889)
			(xy 195.356366 -239.464265) (xy 195.352431 -239.410494) (xy 194.93738 -239.410494) (xy 194.93738 -239.456722)
			(xy 194.945254 -239.475518) (xy 194.95262 -239.48263) (xy 194.975494 -239.506031) (xy 195.015579 -239.557753)
			(xy 195.048518 -239.614295) (xy 195.073738 -239.674677) (xy 195.090801 -239.73785) (xy 195.099412 -239.802718)
			(xy 195.09994 -239.835436) (xy 196.950599 -239.835436) (xy 196.954534 -239.781665) (xy 196.966257 -239.729041)
			(xy 196.985517 -239.678684) (xy 197.011903 -239.631667) (xy 197.044855 -239.588994) (xy 197.083668 -239.551573)
			(xy 197.127516 -239.520203) (xy 197.175464 -239.495551) (xy 197.226491 -239.478143) (xy 197.279509 -239.46835)
			(xy 197.333388 -239.466381) (xy 197.386979 -239.472278) (xy 197.43914 -239.485914) (xy 197.48876 -239.507001)
			(xy 197.534781 -239.535087) (xy 197.576223 -239.569575) (xy 197.612201 -239.609729) (xy 197.641949 -239.654693)
			(xy 197.664834 -239.70351) (xy 197.680366 -239.755139) (xy 197.688216 -239.808479) (xy 197.688708 -239.835436)
			(xy 201.652124 -239.835436) (xy 201.65263 -239.802715) (xy 201.661232 -239.737841) (xy 201.67829 -239.674662)
			(xy 201.703508 -239.614274) (xy 201.736449 -239.557728) (xy 201.77654 -239.506004) (xy 201.799444 -239.48263)
			(xy 201.80681 -239.475518) (xy 201.814684 -239.456722) (xy 201.814684 -239.364012) (xy 201.80681 -239.345216)
			(xy 201.799444 -239.338104) (xy 201.776532 -239.31474) (xy 201.736451 -239.263009) (xy 201.703518 -239.206459)
			(xy 201.678305 -239.14607) (xy 201.66125 -239.082891) (xy 201.652647 -239.018018) (xy 201.652124 -238.985298)
			(xy 201.652613 -238.954135) (xy 201.660425 -238.892301) (xy 201.675925 -238.831933) (xy 201.698868 -238.773985)
			(xy 201.728894 -238.719368) (xy 201.765528 -238.668946) (xy 201.808193 -238.623512) (xy 201.856215 -238.583784)
			(xy 201.908839 -238.550389) (xy 201.965233 -238.523852) (xy 202.024508 -238.504592) (xy 202.085729 -238.492913)
			(xy 202.147932 -238.489) (xy 202.210135 -238.492913) (xy 202.271356 -238.504592) (xy 202.330631 -238.523852)
			(xy 202.387025 -238.550389) (xy 202.439649 -238.583784) (xy 202.487671 -238.623512) (xy 202.530336 -238.668946)
			(xy 202.56697 -238.719368) (xy 202.596996 -238.773985) (xy 202.619939 -238.831933) (xy 202.635439 -238.892301)
			(xy 202.643251 -238.954135) (xy 202.64374 -238.985298) (xy 205.752192 -238.985298) (xy 205.752745 -238.952598)
			(xy 205.761347 -238.887767) (xy 205.778402 -238.824631) (xy 205.803613 -238.764286) (xy 205.836543 -238.707782)
			(xy 205.876618 -238.6561) (xy 205.899512 -238.632746) (xy 205.906878 -238.62538) (xy 205.914498 -238.606838)
			(xy 205.914498 -238.513874) (xy 205.906878 -238.495332) (xy 205.899512 -238.487966) (xy 205.87662 -238.464608)
			(xy 205.836537 -238.41293) (xy 205.8036 -238.356428) (xy 205.778383 -238.296084) (xy 205.761323 -238.232947)
			(xy 205.752717 -238.168115) (xy 205.752192 -238.135414) (xy 205.752681 -238.104251) (xy 205.760493 -238.042417)
			(xy 205.775993 -237.982049) (xy 205.798936 -237.924101) (xy 205.828962 -237.869484) (xy 205.865596 -237.819062)
			(xy 205.908261 -237.773628) (xy 205.956283 -237.7339) (xy 206.008907 -237.700505) (xy 206.065301 -237.673968)
			(xy 206.124576 -237.654708) (xy 206.185797 -237.643029) (xy 206.248 -237.639116) (xy 206.310203 -237.643029)
			(xy 206.371424 -237.654708) (xy 206.430699 -237.673968) (xy 206.487093 -237.700505) (xy 206.539717 -237.7339)
			(xy 206.587739 -237.773628) (xy 206.630404 -237.819062) (xy 206.667038 -237.869484) (xy 206.697064 -237.924101)
			(xy 206.720007 -237.982049) (xy 206.735507 -238.042417) (xy 206.743319 -238.104251) (xy 206.743808 -238.135414)
			(xy 206.743263 -238.168114) (xy 206.734659 -238.232945) (xy 206.717602 -238.296082) (xy 206.69239 -238.356426)
			(xy 206.659459 -238.41293) (xy 206.619383 -238.464612) (xy 206.596488 -238.487966) (xy 206.589122 -238.495332)
			(xy 206.581502 -238.513874) (xy 206.581502 -238.560356) (xy 206.996299 -238.560356) (xy 207.000234 -238.506585)
			(xy 207.011957 -238.453961) (xy 207.031217 -238.403604) (xy 207.057603 -238.356587) (xy 207.090555 -238.313914)
			(xy 207.129368 -238.276493) (xy 207.173216 -238.245123) (xy 207.221164 -238.220471) (xy 207.272191 -238.203063)
			(xy 207.325209 -238.19327) (xy 207.379088 -238.191301) (xy 207.432679 -238.197198) (xy 207.48484 -238.210834)
			(xy 207.53446 -238.231921) (xy 207.580481 -238.260007) (xy 207.621923 -238.294495) (xy 207.657901 -238.334649)
			(xy 207.687649 -238.379613) (xy 207.710534 -238.42843) (xy 207.726066 -238.480059) (xy 207.733916 -238.533399)
			(xy 207.734408 -238.560356) (xy 207.733916 -238.587313) (xy 207.726066 -238.640653) (xy 207.710534 -238.692282)
			(xy 207.687649 -238.741099) (xy 207.657901 -238.786063) (xy 207.621923 -238.826217) (xy 207.580481 -238.860705)
			(xy 207.53446 -238.888791) (xy 207.48484 -238.909878) (xy 207.432679 -238.923514) (xy 207.379088 -238.929411)
			(xy 207.325209 -238.927442) (xy 207.272191 -238.917649) (xy 207.221164 -238.900241) (xy 207.173216 -238.875589)
			(xy 207.129368 -238.844219) (xy 207.090555 -238.806798) (xy 207.057603 -238.764125) (xy 207.031217 -238.717108)
			(xy 207.011957 -238.666751) (xy 207.000234 -238.614127) (xy 206.996299 -238.560356) (xy 206.581502 -238.560356)
			(xy 206.581502 -238.606838) (xy 206.589122 -238.62538) (xy 206.596488 -238.632746) (xy 206.619385 -238.656098)
			(xy 206.659468 -238.707778) (xy 206.692404 -238.764281) (xy 206.717621 -238.824626) (xy 206.734679 -238.887764)
			(xy 206.743283 -238.952597) (xy 206.743808 -238.985298) (xy 206.743319 -239.016461) (xy 206.735507 -239.078295)
			(xy 206.720007 -239.138663) (xy 206.697064 -239.196611) (xy 206.667038 -239.251228) (xy 206.630404 -239.30165)
			(xy 206.587739 -239.347084) (xy 206.539717 -239.386812) (xy 206.487093 -239.420207) (xy 206.430699 -239.446744)
			(xy 206.371424 -239.466004) (xy 206.310203 -239.477683) (xy 206.248 -239.481596) (xy 206.185797 -239.477683)
			(xy 206.124576 -239.466004) (xy 206.065301 -239.446744) (xy 206.008907 -239.420207) (xy 205.956283 -239.386812)
			(xy 205.908261 -239.347084) (xy 205.865596 -239.30165) (xy 205.828962 -239.251228) (xy 205.798936 -239.196611)
			(xy 205.775993 -239.138663) (xy 205.760493 -239.078295) (xy 205.752681 -239.016461) (xy 205.752192 -238.985298)
			(xy 202.64374 -238.985298) (xy 202.643202 -239.018018) (xy 202.634608 -239.082891) (xy 202.617557 -239.14607)
			(xy 202.592345 -239.206458) (xy 202.559409 -239.263005) (xy 202.519322 -239.31473) (xy 202.49642 -239.338104)
			(xy 202.489054 -239.345216) (xy 202.48118 -239.364012) (xy 202.48118 -239.410494) (xy 202.896231 -239.410494)
			(xy 202.900166 -239.356723) (xy 202.911889 -239.304099) (xy 202.931149 -239.253742) (xy 202.957535 -239.206725)
			(xy 202.990487 -239.164052) (xy 203.0293 -239.126631) (xy 203.073148 -239.095261) (xy 203.121096 -239.070609)
			(xy 203.172123 -239.053201) (xy 203.225141 -239.043408) (xy 203.27902 -239.041439) (xy 203.332611 -239.047336)
			(xy 203.384772 -239.060972) (xy 203.434392 -239.082059) (xy 203.480413 -239.110145) (xy 203.521855 -239.144633)
			(xy 203.557833 -239.184787) (xy 203.587581 -239.229751) (xy 203.610466 -239.278568) (xy 203.625998 -239.330197)
			(xy 203.633848 -239.383537) (xy 203.63434 -239.410494) (xy 203.633848 -239.437451) (xy 203.625998 -239.490791)
			(xy 203.610466 -239.54242) (xy 203.587581 -239.591237) (xy 203.557833 -239.636201) (xy 203.521855 -239.676355)
			(xy 203.480413 -239.710843) (xy 203.434392 -239.738929) (xy 203.384772 -239.760016) (xy 203.332611 -239.773652)
			(xy 203.27902 -239.779549) (xy 203.225141 -239.77758) (xy 203.172123 -239.767787) (xy 203.121096 -239.750379)
			(xy 203.073148 -239.725727) (xy 203.0293 -239.694357) (xy 202.990487 -239.656936) (xy 202.957535 -239.614263)
			(xy 202.931149 -239.567246) (xy 202.911889 -239.516889) (xy 202.900166 -239.464265) (xy 202.896231 -239.410494)
			(xy 202.48118 -239.410494) (xy 202.48118 -239.456722) (xy 202.489054 -239.475518) (xy 202.49642 -239.48263)
			(xy 202.519294 -239.506031) (xy 202.559379 -239.557753) (xy 202.592318 -239.614295) (xy 202.617538 -239.674677)
			(xy 202.634601 -239.73785) (xy 202.643212 -239.802718) (xy 202.64374 -239.835436) (xy 204.494399 -239.835436)
			(xy 204.498334 -239.781665) (xy 204.510057 -239.729041) (xy 204.529317 -239.678684) (xy 204.555703 -239.631667)
			(xy 204.588655 -239.588994) (xy 204.627468 -239.551573) (xy 204.671316 -239.520203) (xy 204.719264 -239.495551)
			(xy 204.770291 -239.478143) (xy 204.823309 -239.46835) (xy 204.877188 -239.466381) (xy 204.930779 -239.472278)
			(xy 204.98294 -239.485914) (xy 205.03256 -239.507001) (xy 205.078581 -239.535087) (xy 205.120023 -239.569575)
			(xy 205.156001 -239.609729) (xy 205.185749 -239.654693) (xy 205.208634 -239.70351) (xy 205.224166 -239.755139)
			(xy 205.232016 -239.808479) (xy 205.232508 -239.835436) (xy 205.232016 -239.862393) (xy 205.224166 -239.915733)
			(xy 205.208634 -239.967362) (xy 205.185749 -240.016179) (xy 205.156001 -240.061143) (xy 205.120023 -240.101297)
			(xy 205.078581 -240.135785) (xy 205.03256 -240.163871) (xy 204.98294 -240.184958) (xy 204.930779 -240.198594)
			(xy 204.877188 -240.204491) (xy 204.823309 -240.202522) (xy 204.770291 -240.192729) (xy 204.719264 -240.175321)
			(xy 204.671316 -240.150669) (xy 204.627468 -240.119299) (xy 204.588655 -240.081878) (xy 204.555703 -240.039205)
			(xy 204.529317 -239.992188) (xy 204.510057 -239.941831) (xy 204.498334 -239.889207) (xy 204.494399 -239.835436)
			(xy 202.64374 -239.835436) (xy 202.643251 -239.866599) (xy 202.635439 -239.928433) (xy 202.619939 -239.988801)
			(xy 202.596996 -240.046749) (xy 202.56697 -240.101366) (xy 202.530336 -240.151788) (xy 202.487671 -240.197222)
			(xy 202.439649 -240.23695) (xy 202.387025 -240.270345) (xy 202.330631 -240.296882) (xy 202.271356 -240.316142)
			(xy 202.210135 -240.327821) (xy 202.147932 -240.331734) (xy 202.085729 -240.327821) (xy 202.024508 -240.316142)
			(xy 201.965233 -240.296882) (xy 201.908839 -240.270345) (xy 201.856215 -240.23695) (xy 201.808193 -240.197222)
			(xy 201.765528 -240.151788) (xy 201.728894 -240.101366) (xy 201.698868 -240.046749) (xy 201.675925 -239.988801)
			(xy 201.660425 -239.928433) (xy 201.652613 -239.866599) (xy 201.652124 -239.835436) (xy 197.688708 -239.835436)
			(xy 197.688216 -239.862393) (xy 197.680366 -239.915733) (xy 197.664834 -239.967362) (xy 197.641949 -240.016179)
			(xy 197.612201 -240.061143) (xy 197.576223 -240.101297) (xy 197.534781 -240.135785) (xy 197.48876 -240.163871)
			(xy 197.43914 -240.184958) (xy 197.386979 -240.198594) (xy 197.333388 -240.204491) (xy 197.279509 -240.202522)
			(xy 197.226491 -240.192729) (xy 197.175464 -240.175321) (xy 197.127516 -240.150669) (xy 197.083668 -240.119299)
			(xy 197.044855 -240.081878) (xy 197.011903 -240.039205) (xy 196.985517 -239.992188) (xy 196.966257 -239.941831)
			(xy 196.954534 -239.889207) (xy 196.950599 -239.835436) (xy 195.09994 -239.835436) (xy 195.099451 -239.866599)
			(xy 195.091639 -239.928433) (xy 195.076139 -239.988801) (xy 195.053196 -240.046749) (xy 195.02317 -240.101366)
			(xy 194.986536 -240.151788) (xy 194.943871 -240.197222) (xy 194.895849 -240.23695) (xy 194.843225 -240.270345)
			(xy 194.786831 -240.296882) (xy 194.727556 -240.316142) (xy 194.666335 -240.327821) (xy 194.604132 -240.331734)
			(xy 194.541929 -240.327821) (xy 194.480708 -240.316142) (xy 194.421433 -240.296882) (xy 194.365039 -240.270345)
			(xy 194.312415 -240.23695) (xy 194.264393 -240.197222) (xy 194.221728 -240.151788) (xy 194.185094 -240.101366)
			(xy 194.155068 -240.046749) (xy 194.132125 -239.988801) (xy 194.116625 -239.928433) (xy 194.108813 -239.866599)
			(xy 194.108324 -239.835436) (xy 190.144654 -239.835436) (xy 190.144162 -239.862393) (xy 190.136312 -239.915733)
			(xy 190.12078 -239.967362) (xy 190.097895 -240.016179) (xy 190.068147 -240.061143) (xy 190.032169 -240.101297)
			(xy 189.990727 -240.135785) (xy 189.944706 -240.163871) (xy 189.895086 -240.184958) (xy 189.842925 -240.198594)
			(xy 189.789334 -240.204491) (xy 189.735455 -240.202522) (xy 189.682437 -240.192729) (xy 189.63141 -240.175321)
			(xy 189.583462 -240.150669) (xy 189.539614 -240.119299) (xy 189.500801 -240.081878) (xy 189.467849 -240.039205)
			(xy 189.441463 -239.992188) (xy 189.422203 -239.941831) (xy 189.41048 -239.889207) (xy 189.406545 -239.835436)
			(xy 187.555886 -239.835436) (xy 187.555397 -239.866599) (xy 187.547585 -239.928433) (xy 187.532085 -239.988801)
			(xy 187.509142 -240.046749) (xy 187.479116 -240.101366) (xy 187.442482 -240.151788) (xy 187.399817 -240.197222)
			(xy 187.351795 -240.23695) (xy 187.299171 -240.270345) (xy 187.242777 -240.296882) (xy 187.183502 -240.316142)
			(xy 187.122281 -240.327821) (xy 187.060078 -240.331734) (xy 186.997875 -240.327821) (xy 186.936654 -240.316142)
			(xy 186.877379 -240.296882) (xy 186.820985 -240.270345) (xy 186.768361 -240.23695) (xy 186.720339 -240.197222)
			(xy 186.677674 -240.151788) (xy 186.64104 -240.101366) (xy 186.611014 -240.046749) (xy 186.588071 -239.988801)
			(xy 186.572571 -239.928433) (xy 186.564759 -239.866599) (xy 186.56427 -239.835436) (xy 182.6006 -239.835436)
			(xy 182.600108 -239.862393) (xy 182.592258 -239.915733) (xy 182.576726 -239.967362) (xy 182.553841 -240.016179)
			(xy 182.524093 -240.061143) (xy 182.488115 -240.101297) (xy 182.446673 -240.135785) (xy 182.400652 -240.163871)
			(xy 182.351032 -240.184958) (xy 182.298871 -240.198594) (xy 182.24528 -240.204491) (xy 182.191401 -240.202522)
			(xy 182.138383 -240.192729) (xy 182.087356 -240.175321) (xy 182.039408 -240.150669) (xy 181.99556 -240.119299)
			(xy 181.956747 -240.081878) (xy 181.923795 -240.039205) (xy 181.897409 -239.992188) (xy 181.878149 -239.941831)
			(xy 181.866426 -239.889207) (xy 181.862491 -239.835436) (xy 180.011832 -239.835436) (xy 180.011343 -239.866599)
			(xy 180.003531 -239.928433) (xy 179.988031 -239.988801) (xy 179.965088 -240.046749) (xy 179.935062 -240.101366)
			(xy 179.898428 -240.151788) (xy 179.855763 -240.197222) (xy 179.807741 -240.23695) (xy 179.755117 -240.270345)
			(xy 179.698723 -240.296882) (xy 179.639448 -240.316142) (xy 179.578227 -240.327821) (xy 179.516024 -240.331734)
			(xy 179.453821 -240.327821) (xy 179.3926 -240.316142) (xy 179.333325 -240.296882) (xy 179.276931 -240.270345)
			(xy 179.224307 -240.23695) (xy 179.176285 -240.197222) (xy 179.13362 -240.151788) (xy 179.096986 -240.101366)
			(xy 179.06696 -240.046749) (xy 179.044017 -239.988801) (xy 179.028517 -239.928433) (xy 179.020705 -239.866599)
			(xy 179.020216 -239.835436) (xy 175.056546 -239.835436) (xy 175.056054 -239.862393) (xy 175.048204 -239.915733)
			(xy 175.032672 -239.967362) (xy 175.009787 -240.016179) (xy 174.980039 -240.061143) (xy 174.944061 -240.101297)
			(xy 174.902619 -240.135785) (xy 174.856598 -240.163871) (xy 174.806978 -240.184958) (xy 174.754817 -240.198594)
			(xy 174.701226 -240.204491) (xy 174.647347 -240.202522) (xy 174.594329 -240.192729) (xy 174.543302 -240.175321)
			(xy 174.495354 -240.150669) (xy 174.451506 -240.119299) (xy 174.412693 -240.081878) (xy 174.379741 -240.039205)
			(xy 174.353355 -239.992188) (xy 174.334095 -239.941831) (xy 174.322372 -239.889207) (xy 174.318437 -239.835436)
			(xy 172.467778 -239.835436) (xy 172.467289 -239.866599) (xy 172.459477 -239.928433) (xy 172.443977 -239.988801)
			(xy 172.421034 -240.046749) (xy 172.391008 -240.101366) (xy 172.354374 -240.151788) (xy 172.311709 -240.197222)
			(xy 172.263687 -240.23695) (xy 172.211063 -240.270345) (xy 172.154669 -240.296882) (xy 172.095394 -240.316142)
			(xy 172.034173 -240.327821) (xy 171.97197 -240.331734) (xy 171.909767 -240.327821) (xy 171.848546 -240.316142)
			(xy 171.789271 -240.296882) (xy 171.732877 -240.270345) (xy 171.680253 -240.23695) (xy 171.632231 -240.197222)
			(xy 171.589566 -240.151788) (xy 171.552932 -240.101366) (xy 171.522906 -240.046749) (xy 171.499963 -239.988801)
			(xy 171.484463 -239.928433) (xy 171.476651 -239.866599) (xy 171.476162 -239.835436) (xy 167.512492 -239.835436)
			(xy 167.512 -239.862393) (xy 167.50415 -239.915733) (xy 167.488618 -239.967362) (xy 167.465733 -240.016179)
			(xy 167.435985 -240.061143) (xy 167.400007 -240.101297) (xy 167.358565 -240.135785) (xy 167.312544 -240.163871)
			(xy 167.262924 -240.184958) (xy 167.210763 -240.198594) (xy 167.157172 -240.204491) (xy 167.103293 -240.202522)
			(xy 167.050275 -240.192729) (xy 166.999248 -240.175321) (xy 166.9513 -240.150669) (xy 166.907452 -240.119299)
			(xy 166.868639 -240.081878) (xy 166.835687 -240.039205) (xy 166.809301 -239.992188) (xy 166.790041 -239.941831)
			(xy 166.778318 -239.889207) (xy 166.774383 -239.835436) (xy 161.612834 -239.835436) (xy 161.612834 -240.68532)
			(xy 165.442915 -240.68532) (xy 165.44685 -240.631549) (xy 165.458573 -240.578925) (xy 165.477833 -240.528568)
			(xy 165.504219 -240.481551) (xy 165.537171 -240.438878) (xy 165.575984 -240.401457) (xy 165.619832 -240.370087)
			(xy 165.66778 -240.345435) (xy 165.718807 -240.328027) (xy 165.771825 -240.318234) (xy 165.825704 -240.316265)
			(xy 165.879295 -240.322162) (xy 165.931456 -240.335798) (xy 165.981076 -240.356885) (xy 166.027097 -240.384971)
			(xy 166.068539 -240.419459) (xy 166.104517 -240.459613) (xy 166.134265 -240.504577) (xy 166.15715 -240.553394)
			(xy 166.172682 -240.605023) (xy 166.180532 -240.658363) (xy 166.181024 -240.68532) (xy 172.986969 -240.68532)
			(xy 172.990904 -240.631549) (xy 173.002627 -240.578925) (xy 173.021887 -240.528568) (xy 173.048273 -240.481551)
			(xy 173.081225 -240.438878) (xy 173.120038 -240.401457) (xy 173.163886 -240.370087) (xy 173.211834 -240.345435)
			(xy 173.262861 -240.328027) (xy 173.315879 -240.318234) (xy 173.369758 -240.316265) (xy 173.423349 -240.322162)
			(xy 173.47551 -240.335798) (xy 173.52513 -240.356885) (xy 173.571151 -240.384971) (xy 173.612593 -240.419459)
			(xy 173.648571 -240.459613) (xy 173.678319 -240.504577) (xy 173.701204 -240.553394) (xy 173.716736 -240.605023)
			(xy 173.724586 -240.658363) (xy 173.725078 -240.68532) (xy 173.724586 -240.712277) (xy 173.716736 -240.765617)
			(xy 173.701204 -240.817246) (xy 173.678319 -240.866063) (xy 173.648571 -240.911027) (xy 173.612593 -240.951181)
			(xy 173.571151 -240.985669) (xy 173.52513 -241.013755) (xy 173.47551 -241.034842) (xy 173.423349 -241.048478)
			(xy 173.369758 -241.054375) (xy 173.315879 -241.052406) (xy 173.262861 -241.042613) (xy 173.211834 -241.025205)
			(xy 173.163886 -241.000553) (xy 173.120038 -240.969183) (xy 173.081225 -240.931762) (xy 173.048273 -240.889089)
			(xy 173.021887 -240.842072) (xy 173.002627 -240.791715) (xy 172.990904 -240.739091) (xy 172.986969 -240.68532)
			(xy 166.181024 -240.68532) (xy 166.180532 -240.712277) (xy 166.172682 -240.765617) (xy 166.15715 -240.817246)
			(xy 166.134265 -240.866063) (xy 166.104517 -240.911027) (xy 166.068539 -240.951181) (xy 166.027097 -240.985669)
			(xy 165.981076 -241.013755) (xy 165.931456 -241.034842) (xy 165.879295 -241.048478) (xy 165.825704 -241.054375)
			(xy 165.771825 -241.052406) (xy 165.718807 -241.042613) (xy 165.66778 -241.025205) (xy 165.619832 -241.000553)
			(xy 165.575984 -240.969183) (xy 165.537171 -240.931762) (xy 165.504219 -240.889089) (xy 165.477833 -240.842072)
			(xy 165.458573 -240.791715) (xy 165.44685 -240.739091) (xy 165.442915 -240.68532) (xy 161.612834 -240.68532)
			(xy 161.612834 -241.535204) (xy 168.158683 -241.535204) (xy 168.162618 -241.481433) (xy 168.174341 -241.428809)
			(xy 168.193601 -241.378452) (xy 168.219987 -241.331435) (xy 168.252939 -241.288762) (xy 168.291752 -241.251341)
			(xy 168.3356 -241.219971) (xy 168.383548 -241.195319) (xy 168.434575 -241.177911) (xy 168.487593 -241.168118)
			(xy 168.541472 -241.166149) (xy 168.595063 -241.172046) (xy 168.647224 -241.185682) (xy 168.696844 -241.206769)
			(xy 168.742865 -241.234855) (xy 168.784307 -241.269343) (xy 168.820285 -241.309497) (xy 168.850033 -241.354461)
			(xy 168.872918 -241.403278) (xy 168.88845 -241.454907) (xy 168.8963 -241.508247) (xy 168.896792 -241.535204)
			(xy 168.8963 -241.562161) (xy 168.88845 -241.615501) (xy 168.872918 -241.66713) (xy 168.850033 -241.715947)
			(xy 168.820285 -241.760911) (xy 168.784307 -241.801065) (xy 168.742865 -241.835553) (xy 168.696844 -241.863639)
			(xy 168.647224 -241.884726) (xy 168.595063 -241.898362) (xy 168.541472 -241.904259) (xy 168.487593 -241.90229)
			(xy 168.434575 -241.892497) (xy 168.383548 -241.875089) (xy 168.3356 -241.850437) (xy 168.291752 -241.819067)
			(xy 168.252939 -241.781646) (xy 168.219987 -241.738973) (xy 168.193601 -241.691956) (xy 168.174341 -241.641599)
			(xy 168.162618 -241.588975) (xy 168.158683 -241.535204) (xy 161.612834 -241.535204) (xy 161.612834 -242.385342)
			(xy 164.058615 -242.385342) (xy 164.06255 -242.331571) (xy 164.074273 -242.278947) (xy 164.093533 -242.22859)
			(xy 164.119919 -242.181573) (xy 164.152871 -242.1389) (xy 164.191684 -242.101479) (xy 164.235532 -242.070109)
			(xy 164.28348 -242.045457) (xy 164.334507 -242.028049) (xy 164.387525 -242.018256) (xy 164.441404 -242.016287)
			(xy 164.494995 -242.022184) (xy 164.547156 -242.03582) (xy 164.596776 -242.056907) (xy 164.642797 -242.084993)
			(xy 164.684239 -242.119481) (xy 164.720217 -242.159635) (xy 164.749965 -242.204599) (xy 164.77285 -242.253416)
			(xy 164.788382 -242.305045) (xy 164.796232 -242.358385) (xy 164.796724 -242.385342) (xy 164.796232 -242.412299)
			(xy 164.788382 -242.465639) (xy 164.77285 -242.517268) (xy 164.749965 -242.566085) (xy 164.720217 -242.611049)
			(xy 164.684239 -242.651203) (xy 164.642797 -242.685691) (xy 164.596776 -242.713777) (xy 164.547156 -242.734864)
			(xy 164.494995 -242.7485) (xy 164.441404 -242.754397) (xy 164.387525 -242.752428) (xy 164.334507 -242.742635)
			(xy 164.28348 -242.725227) (xy 164.235532 -242.700575) (xy 164.191684 -242.669205) (xy 164.152871 -242.631784)
			(xy 164.119919 -242.589111) (xy 164.093533 -242.542094) (xy 164.074273 -242.491737) (xy 164.06255 -242.439113)
			(xy 164.058615 -242.385342) (xy 161.612834 -242.385342) (xy 161.612834 -244.085364) (xy 164.058615 -244.085364)
			(xy 164.06255 -244.031593) (xy 164.074273 -243.978969) (xy 164.093533 -243.928612) (xy 164.119919 -243.881595)
			(xy 164.152871 -243.838922) (xy 164.191684 -243.801501) (xy 164.235532 -243.770131) (xy 164.28348 -243.745479)
			(xy 164.334507 -243.728071) (xy 164.387525 -243.718278) (xy 164.441404 -243.716309) (xy 164.494995 -243.722206)
			(xy 164.547156 -243.735842) (xy 164.596776 -243.756929) (xy 164.642797 -243.785015) (xy 164.684239 -243.819503)
			(xy 164.720217 -243.859657) (xy 164.749965 -243.904621) (xy 164.77285 -243.953438) (xy 164.788382 -244.005067)
			(xy 164.796232 -244.058407) (xy 164.796724 -244.085364) (xy 166.634666 -244.085364) (xy 166.63874 -244.021896)
			(xy 166.650898 -243.959471) (xy 166.670938 -243.899112) (xy 166.698532 -243.841812) (xy 166.733228 -243.788511)
			(xy 166.774454 -243.740084) (xy 166.821534 -243.697327) (xy 166.873696 -243.660941) (xy 166.930083 -243.631524)
			(xy 166.989768 -243.609559) (xy 167.051772 -243.595407) (xy 167.115076 -243.589301) (xy 167.178642 -243.591339)
			(xy 167.241425 -243.601489) (xy 167.302395 -243.619585) (xy 167.36055 -243.645328) (xy 167.414936 -243.678297)
			(xy 167.464659 -243.71795) (xy 167.508904 -243.763636) (xy 167.546943 -243.814605) (xy 167.578152 -243.870019)
			(xy 167.602018 -243.92897) (xy 167.61815 -243.990488) (xy 167.626283 -244.053565) (xy 167.626792 -244.085364)
			(xy 168.032176 -244.085364) (xy 168.032659 -244.054155) (xy 168.040482 -243.992229) (xy 168.056013 -243.931774)
			(xy 168.079006 -243.873746) (xy 168.109097 -243.81906) (xy 168.145812 -243.768582) (xy 168.188569 -243.72311)
			(xy 168.236694 -243.683361) (xy 168.262808 -243.666264) (xy 168.272968 -243.659914) (xy 168.28516 -243.640102)
			(xy 168.294812 -243.535962) (xy 168.28643 -243.514118) (xy 168.27754 -243.50599) (xy 168.259223 -243.488464)
			(xy 168.227078 -243.449264) (xy 168.200604 -243.406032) (xy 168.180298 -243.359582) (xy 168.166543 -243.31079)
			(xy 168.159598 -243.260573) (xy 168.159176 -243.235226) (xy 168.159692 -243.207626) (xy 168.167919 -243.153043)
			(xy 168.184189 -243.100296) (xy 168.208139 -243.050564) (xy 168.239234 -243.004956) (xy 168.276779 -242.964492)
			(xy 168.319936 -242.930075) (xy 168.36774 -242.902476) (xy 168.419124 -242.882309) (xy 168.472939 -242.870026)
			(xy 168.527984 -242.865901) (xy 168.583029 -242.870026) (xy 168.636844 -242.882309) (xy 168.688228 -242.902476)
			(xy 168.736032 -242.930075) (xy 168.779189 -242.964492) (xy 168.816734 -243.004956) (xy 168.847829 -243.050564)
			(xy 168.871779 -243.100296) (xy 168.888049 -243.153043) (xy 168.896276 -243.207626) (xy 168.896792 -243.235226)
			(xy 168.89638 -243.260574) (xy 168.889444 -243.310795) (xy 168.875693 -243.359591) (xy 168.855386 -243.406043)
			(xy 168.828906 -243.449274) (xy 168.796752 -243.48847) (xy 168.778428 -243.50599) (xy 168.769538 -243.514118)
			(xy 168.761156 -243.535962) (xy 168.770808 -243.640102) (xy 168.783 -243.659914) (xy 168.79316 -243.666264)
			(xy 168.819276 -243.683356) (xy 168.867395 -243.723112) (xy 168.910149 -243.768588) (xy 168.946862 -243.819067)
			(xy 168.976954 -243.873751) (xy 168.99995 -243.931778) (xy 169.015487 -243.992231) (xy 169.023319 -244.054155)
			(xy 169.023792 -244.085364) (xy 169.023331 -244.116561) (xy 169.015513 -244.178464) (xy 168.999984 -244.238895)
			(xy 168.976989 -244.296898) (xy 168.946893 -244.351555) (xy 168.910172 -244.401999) (xy 168.867407 -244.447433)
			(xy 168.819276 -244.487138) (xy 168.79316 -244.50421) (xy 168.783 -244.510814) (xy 168.770808 -244.530626)
			(xy 168.76141 -244.634766) (xy 168.769792 -244.656356) (xy 168.778682 -244.664738) (xy 168.796952 -244.682269)
			(xy 168.82903 -244.721444) (xy 168.855449 -244.764638) (xy 168.875712 -244.811039) (xy 168.889438 -244.859776)
			(xy 168.89637 -244.909932) (xy 168.896792 -244.935248) (xy 168.896276 -244.962848) (xy 168.888049 -245.017431)
			(xy 168.871779 -245.070178) (xy 168.847829 -245.119911) (xy 168.816734 -245.165518) (xy 168.779189 -245.205982)
			(xy 168.736032 -245.240399) (xy 168.688228 -245.267998) (xy 168.636844 -245.288165) (xy 168.583029 -245.300448)
			(xy 168.527984 -245.304573) (xy 168.472939 -245.300448) (xy 168.419124 -245.288165) (xy 168.36774 -245.267998)
			(xy 168.319936 -245.240399) (xy 168.276779 -245.205982) (xy 168.239234 -245.165518) (xy 168.208139 -245.119911)
			(xy 168.184189 -245.070178) (xy 168.167919 -245.017431) (xy 168.159692 -244.962848) (xy 168.159176 -244.935248)
			(xy 168.159592 -244.90993) (xy 168.166515 -244.85977) (xy 168.180235 -244.811029) (xy 168.200497 -244.764624)
			(xy 168.226917 -244.721428) (xy 168.259 -244.682253) (xy 168.277286 -244.664738) (xy 168.286176 -244.656356)
			(xy 168.294558 -244.634766) (xy 168.28516 -244.530626) (xy 168.272968 -244.510814) (xy 168.262808 -244.50421)
			(xy 168.236709 -244.487116) (xy 168.188592 -244.447403) (xy 168.145838 -244.401966) (xy 168.109123 -244.351523)
			(xy 168.079028 -244.296872) (xy 168.056028 -244.238877) (xy 168.040487 -244.178454) (xy 168.032651 -244.116559)
			(xy 168.032176 -244.085364) (xy 167.626792 -244.085364) (xy 167.626283 -244.117163) (xy 167.61815 -244.18024)
			(xy 167.602018 -244.241758) (xy 167.578152 -244.300709) (xy 167.546943 -244.356123) (xy 167.508904 -244.407092)
			(xy 167.464659 -244.452778) (xy 167.414936 -244.492431) (xy 167.36055 -244.5254) (xy 167.302395 -244.551143)
			(xy 167.241425 -244.569239) (xy 167.178642 -244.579389) (xy 167.115076 -244.581427) (xy 167.051772 -244.575321)
			(xy 166.989768 -244.561169) (xy 166.930083 -244.539204) (xy 166.873696 -244.509787) (xy 166.821534 -244.473401)
			(xy 166.774454 -244.430644) (xy 166.733228 -244.382217) (xy 166.698532 -244.328916) (xy 166.670938 -244.271616)
			(xy 166.650898 -244.211257) (xy 166.63874 -244.148832) (xy 166.634666 -244.085364) (xy 164.796724 -244.085364)
			(xy 164.796232 -244.112321) (xy 164.788382 -244.165661) (xy 164.77285 -244.21729) (xy 164.749965 -244.266107)
			(xy 164.720217 -244.311071) (xy 164.684239 -244.351225) (xy 164.642797 -244.385713) (xy 164.596776 -244.413799)
			(xy 164.547156 -244.434886) (xy 164.494995 -244.448522) (xy 164.441404 -244.454419) (xy 164.387525 -244.45245)
			(xy 164.334507 -244.442657) (xy 164.28348 -244.425249) (xy 164.235532 -244.400597) (xy 164.191684 -244.369227)
			(xy 164.152871 -244.331806) (xy 164.119919 -244.289133) (xy 164.093533 -244.242116) (xy 164.074273 -244.191759)
			(xy 164.06255 -244.139135) (xy 164.058615 -244.085364) (xy 161.612834 -244.085364) (xy 161.612834 -245.785386)
			(xy 164.058615 -245.785386) (xy 164.06255 -245.731615) (xy 164.074273 -245.678991) (xy 164.093533 -245.628634)
			(xy 164.119919 -245.581617) (xy 164.152871 -245.538944) (xy 164.191684 -245.501523) (xy 164.235532 -245.470153)
			(xy 164.28348 -245.445501) (xy 164.334507 -245.428093) (xy 164.387525 -245.4183) (xy 164.441404 -245.416331)
			(xy 164.494995 -245.422228) (xy 164.547156 -245.435864) (xy 164.596776 -245.456951) (xy 164.642797 -245.485037)
			(xy 164.684239 -245.519525) (xy 164.720217 -245.559679) (xy 164.749965 -245.604643) (xy 164.77285 -245.65346)
			(xy 164.788382 -245.705089) (xy 164.796232 -245.758429) (xy 164.796724 -245.785386) (xy 164.796232 -245.812343)
			(xy 164.788382 -245.865683) (xy 164.77285 -245.917312) (xy 164.749965 -245.966129) (xy 164.720217 -246.011093)
			(xy 164.684239 -246.051247) (xy 164.642797 -246.085735) (xy 164.596776 -246.113821) (xy 164.547156 -246.134908)
			(xy 164.494995 -246.148544) (xy 164.441404 -246.154441) (xy 164.387525 -246.152472) (xy 164.334507 -246.142679)
			(xy 164.28348 -246.125271) (xy 164.235532 -246.100619) (xy 164.191684 -246.069249) (xy 164.152871 -246.031828)
			(xy 164.119919 -245.989155) (xy 164.093533 -245.942138) (xy 164.074273 -245.891781) (xy 164.06255 -245.839157)
			(xy 164.058615 -245.785386) (xy 161.612834 -245.785386) (xy 161.612834 -246.63527) (xy 168.158683 -246.63527)
			(xy 168.162618 -246.581499) (xy 168.174341 -246.528875) (xy 168.193601 -246.478518) (xy 168.219987 -246.431501)
			(xy 168.252939 -246.388828) (xy 168.291752 -246.351407) (xy 168.3356 -246.320037) (xy 168.383548 -246.295385)
			(xy 168.434575 -246.277977) (xy 168.487593 -246.268184) (xy 168.541472 -246.266215) (xy 168.595063 -246.272112)
			(xy 168.647224 -246.285748) (xy 168.696844 -246.306835) (xy 168.742865 -246.334921) (xy 168.784307 -246.369409)
			(xy 168.820285 -246.409563) (xy 168.850033 -246.454527) (xy 168.872918 -246.503344) (xy 168.88845 -246.554973)
			(xy 168.8963 -246.608313) (xy 168.896792 -246.63527) (xy 168.8963 -246.662227) (xy 168.88845 -246.715567)
			(xy 168.872918 -246.767196) (xy 168.850033 -246.816013) (xy 168.820285 -246.860977) (xy 168.784307 -246.901131)
			(xy 168.742865 -246.935619) (xy 168.696844 -246.963705) (xy 168.647224 -246.984792) (xy 168.595063 -246.998428)
			(xy 168.541472 -247.004325) (xy 168.487593 -247.002356) (xy 168.434575 -246.992563) (xy 168.383548 -246.975155)
			(xy 168.3356 -246.950503) (xy 168.291752 -246.919133) (xy 168.252939 -246.881712) (xy 168.219987 -246.839039)
			(xy 168.193601 -246.792022) (xy 168.174341 -246.741665) (xy 168.162618 -246.689041) (xy 168.158683 -246.63527)
			(xy 161.612834 -246.63527) (xy 161.612834 -247.485408) (xy 164.058615 -247.485408) (xy 164.06255 -247.431637)
			(xy 164.074273 -247.379013) (xy 164.093533 -247.328656) (xy 164.119919 -247.281639) (xy 164.152871 -247.238966)
			(xy 164.191684 -247.201545) (xy 164.235532 -247.170175) (xy 164.28348 -247.145523) (xy 164.334507 -247.128115)
			(xy 164.387525 -247.118322) (xy 164.441404 -247.116353) (xy 164.494995 -247.12225) (xy 164.547156 -247.135886)
			(xy 164.596776 -247.156973) (xy 164.642797 -247.185059) (xy 164.684239 -247.219547) (xy 164.720217 -247.259701)
			(xy 164.749965 -247.304665) (xy 164.77285 -247.353482) (xy 164.788382 -247.405111) (xy 164.796232 -247.458451)
			(xy 164.796724 -247.485408) (xy 164.796232 -247.512365) (xy 164.788382 -247.565705) (xy 164.77285 -247.617334)
			(xy 164.749965 -247.666151) (xy 164.720217 -247.711115) (xy 164.684239 -247.751269) (xy 164.642797 -247.785757)
			(xy 164.596776 -247.813843) (xy 164.547156 -247.83493) (xy 164.494995 -247.848566) (xy 164.441404 -247.854463)
			(xy 164.387525 -247.852494) (xy 164.334507 -247.842701) (xy 164.28348 -247.825293) (xy 164.235532 -247.800641)
			(xy 164.191684 -247.769271) (xy 164.152871 -247.73185) (xy 164.119919 -247.689177) (xy 164.093533 -247.64216)
			(xy 164.074273 -247.591803) (xy 164.06255 -247.539179) (xy 164.058615 -247.485408) (xy 161.612834 -247.485408)
			(xy 161.612834 -248.335292) (xy 168.158683 -248.335292) (xy 168.162618 -248.281521) (xy 168.174341 -248.228897)
			(xy 168.193601 -248.17854) (xy 168.219987 -248.131523) (xy 168.252939 -248.08885) (xy 168.291752 -248.051429)
			(xy 168.3356 -248.020059) (xy 168.383548 -247.995407) (xy 168.434575 -247.977999) (xy 168.487593 -247.968206)
			(xy 168.541472 -247.966237) (xy 168.595063 -247.972134) (xy 168.647224 -247.98577) (xy 168.696844 -248.006857)
			(xy 168.742865 -248.034943) (xy 168.784307 -248.069431) (xy 168.820285 -248.109585) (xy 168.850033 -248.154549)
			(xy 168.872918 -248.203366) (xy 168.88845 -248.254995) (xy 168.8963 -248.308335) (xy 168.896792 -248.335292)
			(xy 168.8963 -248.362249) (xy 168.88845 -248.415589) (xy 168.872918 -248.467218) (xy 168.850033 -248.516035)
			(xy 168.820285 -248.560999) (xy 168.784307 -248.601153) (xy 168.742865 -248.635641) (xy 168.696844 -248.663727)
			(xy 168.647224 -248.684814) (xy 168.595063 -248.69845) (xy 168.541472 -248.704347) (xy 168.487593 -248.702378)
			(xy 168.434575 -248.692585) (xy 168.383548 -248.675177) (xy 168.3356 -248.650525) (xy 168.291752 -248.619155)
			(xy 168.252939 -248.581734) (xy 168.219987 -248.539061) (xy 168.193601 -248.492044) (xy 168.174341 -248.441687)
			(xy 168.162618 -248.389063) (xy 168.158683 -248.335292) (xy 161.612834 -248.335292) (xy 161.612834 -249.18543)
			(xy 164.058615 -249.18543) (xy 164.06255 -249.131659) (xy 164.074273 -249.079035) (xy 164.093533 -249.028678)
			(xy 164.119919 -248.981661) (xy 164.152871 -248.938988) (xy 164.191684 -248.901567) (xy 164.235532 -248.870197)
			(xy 164.28348 -248.845545) (xy 164.334507 -248.828137) (xy 164.387525 -248.818344) (xy 164.441404 -248.816375)
			(xy 164.494995 -248.822272) (xy 164.547156 -248.835908) (xy 164.596776 -248.856995) (xy 164.642797 -248.885081)
			(xy 164.684239 -248.919569) (xy 164.720217 -248.959723) (xy 164.749965 -249.004687) (xy 164.77285 -249.053504)
			(xy 164.788382 -249.105133) (xy 164.796232 -249.158473) (xy 164.796724 -249.18543) (xy 164.796232 -249.212387)
			(xy 164.788382 -249.265727) (xy 164.77285 -249.317356) (xy 164.749965 -249.366173) (xy 164.720217 -249.411137)
			(xy 164.684239 -249.451291) (xy 164.642797 -249.485779) (xy 164.596776 -249.513865) (xy 164.547156 -249.534952)
			(xy 164.494995 -249.548588) (xy 164.441404 -249.554485) (xy 164.387525 -249.552516) (xy 164.334507 -249.542723)
			(xy 164.28348 -249.525315) (xy 164.235532 -249.500663) (xy 164.191684 -249.469293) (xy 164.152871 -249.431872)
			(xy 164.119919 -249.389199) (xy 164.093533 -249.342182) (xy 164.074273 -249.291825) (xy 164.06255 -249.239201)
			(xy 164.058615 -249.18543) (xy 161.612834 -249.18543) (xy 161.612834 -250.035314) (xy 168.158683 -250.035314)
			(xy 168.162618 -249.981543) (xy 168.174341 -249.928919) (xy 168.193601 -249.878562) (xy 168.219987 -249.831545)
			(xy 168.252939 -249.788872) (xy 168.291752 -249.751451) (xy 168.3356 -249.720081) (xy 168.383548 -249.695429)
			(xy 168.434575 -249.678021) (xy 168.487593 -249.668228) (xy 168.541472 -249.666259) (xy 168.595063 -249.672156)
			(xy 168.647224 -249.685792) (xy 168.696844 -249.706879) (xy 168.742865 -249.734965) (xy 168.784307 -249.769453)
			(xy 168.820285 -249.809607) (xy 168.850033 -249.854571) (xy 168.872918 -249.903388) (xy 168.88845 -249.955017)
			(xy 168.8963 -250.008357) (xy 168.896792 -250.035314) (xy 168.8963 -250.062271) (xy 168.88845 -250.115611)
			(xy 168.872918 -250.16724) (xy 168.850033 -250.216057) (xy 168.820285 -250.261021) (xy 168.784307 -250.301175)
			(xy 168.742865 -250.335663) (xy 168.696844 -250.363749) (xy 168.647224 -250.384836) (xy 168.595063 -250.398472)
			(xy 168.541472 -250.404369) (xy 168.487593 -250.4024) (xy 168.434575 -250.392607) (xy 168.383548 -250.375199)
			(xy 168.3356 -250.350547) (xy 168.291752 -250.319177) (xy 168.252939 -250.281756) (xy 168.219987 -250.239083)
			(xy 168.193601 -250.192066) (xy 168.174341 -250.141709) (xy 168.162618 -250.089085) (xy 168.158683 -250.035314)
			(xy 161.612834 -250.035314) (xy 161.612834 -250.885198) (xy 164.058615 -250.885198) (xy 164.06255 -250.831427)
			(xy 164.074273 -250.778803) (xy 164.093533 -250.728446) (xy 164.119919 -250.681429) (xy 164.152871 -250.638756)
			(xy 164.191684 -250.601335) (xy 164.235532 -250.569965) (xy 164.28348 -250.545313) (xy 164.334507 -250.527905)
			(xy 164.387525 -250.518112) (xy 164.441404 -250.516143) (xy 164.494995 -250.52204) (xy 164.547156 -250.535676)
			(xy 164.596776 -250.556763) (xy 164.642797 -250.584849) (xy 164.684239 -250.619337) (xy 164.720217 -250.659491)
			(xy 164.749965 -250.704455) (xy 164.77285 -250.753272) (xy 164.788382 -250.804901) (xy 164.796232 -250.858241)
			(xy 164.796724 -250.885198) (xy 164.796232 -250.912155) (xy 164.788382 -250.965495) (xy 164.77285 -251.017124)
			(xy 164.749965 -251.065941) (xy 164.720217 -251.110905) (xy 164.684239 -251.151059) (xy 164.642797 -251.185547)
			(xy 164.596776 -251.213633) (xy 164.547156 -251.23472) (xy 164.494995 -251.248356) (xy 164.441404 -251.254253)
			(xy 164.387525 -251.252284) (xy 164.334507 -251.242491) (xy 164.28348 -251.225083) (xy 164.235532 -251.200431)
			(xy 164.191684 -251.169061) (xy 164.152871 -251.13164) (xy 164.119919 -251.088967) (xy 164.093533 -251.04195)
			(xy 164.074273 -250.991593) (xy 164.06255 -250.938969) (xy 164.058615 -250.885198) (xy 161.612834 -250.885198)
			(xy 161.612834 -251.735336) (xy 168.158683 -251.735336) (xy 168.162618 -251.681565) (xy 168.174341 -251.628941)
			(xy 168.193601 -251.578584) (xy 168.219987 -251.531567) (xy 168.252939 -251.488894) (xy 168.291752 -251.451473)
			(xy 168.3356 -251.420103) (xy 168.383548 -251.395451) (xy 168.434575 -251.378043) (xy 168.487593 -251.36825)
			(xy 168.541472 -251.366281) (xy 168.595063 -251.372178) (xy 168.647224 -251.385814) (xy 168.696844 -251.406901)
			(xy 168.742865 -251.434987) (xy 168.784307 -251.469475) (xy 168.820285 -251.509629) (xy 168.850033 -251.554593)
			(xy 168.872918 -251.60341) (xy 168.88845 -251.655039) (xy 168.8963 -251.708379) (xy 168.896792 -251.735336)
			(xy 168.8963 -251.762293) (xy 168.88845 -251.815633) (xy 168.872918 -251.867262) (xy 168.850033 -251.916079)
			(xy 168.820285 -251.961043) (xy 168.784307 -252.001197) (xy 168.742865 -252.035685) (xy 168.696844 -252.063771)
			(xy 168.647224 -252.084858) (xy 168.595063 -252.098494) (xy 168.541472 -252.104391) (xy 168.487593 -252.102422)
			(xy 168.434575 -252.092629) (xy 168.383548 -252.075221) (xy 168.3356 -252.050569) (xy 168.291752 -252.019199)
			(xy 168.252939 -251.981778) (xy 168.219987 -251.939105) (xy 168.193601 -251.892088) (xy 168.174341 -251.841731)
			(xy 168.162618 -251.789107) (xy 168.158683 -251.735336) (xy 161.612834 -251.735336) (xy 161.612834 -252.58522)
			(xy 164.058615 -252.58522) (xy 164.06255 -252.531449) (xy 164.074273 -252.478825) (xy 164.093533 -252.428468)
			(xy 164.119919 -252.381451) (xy 164.152871 -252.338778) (xy 164.191684 -252.301357) (xy 164.235532 -252.269987)
			(xy 164.28348 -252.245335) (xy 164.334507 -252.227927) (xy 164.387525 -252.218134) (xy 164.441404 -252.216165)
			(xy 164.494995 -252.222062) (xy 164.547156 -252.235698) (xy 164.596776 -252.256785) (xy 164.642797 -252.284871)
			(xy 164.684239 -252.319359) (xy 164.720217 -252.359513) (xy 164.749965 -252.404477) (xy 164.77285 -252.453294)
			(xy 164.788382 -252.504923) (xy 164.796232 -252.558263) (xy 164.796724 -252.58522) (xy 164.796232 -252.612177)
			(xy 164.788382 -252.665517) (xy 164.77285 -252.717146) (xy 164.749965 -252.765963) (xy 164.720217 -252.810927)
			(xy 164.684239 -252.851081) (xy 164.642797 -252.885569) (xy 164.596776 -252.913655) (xy 164.547156 -252.934742)
			(xy 164.494995 -252.948378) (xy 164.441404 -252.954275) (xy 164.387525 -252.952306) (xy 164.334507 -252.942513)
			(xy 164.28348 -252.925105) (xy 164.235532 -252.900453) (xy 164.191684 -252.869083) (xy 164.152871 -252.831662)
			(xy 164.119919 -252.788989) (xy 164.093533 -252.741972) (xy 164.074273 -252.691615) (xy 164.06255 -252.638991)
			(xy 164.058615 -252.58522) (xy 161.612834 -252.58522) (xy 161.612834 -253.435358) (xy 168.158683 -253.435358)
			(xy 168.162618 -253.381587) (xy 168.174341 -253.328963) (xy 168.193601 -253.278606) (xy 168.219987 -253.231589)
			(xy 168.252939 -253.188916) (xy 168.291752 -253.151495) (xy 168.3356 -253.120125) (xy 168.383548 -253.095473)
			(xy 168.434575 -253.078065) (xy 168.487593 -253.068272) (xy 168.541472 -253.066303) (xy 168.595063 -253.0722)
			(xy 168.647224 -253.085836) (xy 168.696844 -253.106923) (xy 168.742865 -253.135009) (xy 168.784307 -253.169497)
			(xy 168.820285 -253.209651) (xy 168.850033 -253.254615) (xy 168.872918 -253.303432) (xy 168.88845 -253.355061)
			(xy 168.8963 -253.408401) (xy 168.896792 -253.435358) (xy 168.8963 -253.462315) (xy 168.88845 -253.515655)
			(xy 168.872918 -253.567284) (xy 168.850033 -253.616101) (xy 168.820285 -253.661065) (xy 168.784307 -253.701219)
			(xy 168.742865 -253.735707) (xy 168.696844 -253.763793) (xy 168.647224 -253.78488) (xy 168.595063 -253.798516)
			(xy 168.541472 -253.804413) (xy 168.487593 -253.802444) (xy 168.434575 -253.792651) (xy 168.383548 -253.775243)
			(xy 168.3356 -253.750591) (xy 168.291752 -253.719221) (xy 168.252939 -253.6818) (xy 168.219987 -253.639127)
			(xy 168.193601 -253.59211) (xy 168.174341 -253.541753) (xy 168.162618 -253.489129) (xy 168.158683 -253.435358)
			(xy 161.612834 -253.435358) (xy 161.612834 -254.285242) (xy 171.476162 -254.285242) (xy 171.476688 -254.252542)
			(xy 171.485297 -254.18771) (xy 171.502358 -254.124573) (xy 171.527574 -254.064229) (xy 171.560508 -254.007725)
			(xy 171.600586 -253.956044) (xy 171.623482 -253.93269) (xy 171.630848 -253.925324) (xy 171.638468 -253.906782)
			(xy 171.638468 -253.813818) (xy 171.630848 -253.795276) (xy 171.623482 -253.78791) (xy 171.600576 -253.764565)
			(xy 171.560491 -253.712886) (xy 171.527555 -253.656381) (xy 171.50234 -253.596035) (xy 171.485284 -253.532895)
			(xy 171.476684 -253.46806) (xy 171.476162 -253.435358) (xy 171.476647 -253.404149) (xy 171.484471 -253.342224)
			(xy 171.500001 -253.281769) (xy 171.522994 -253.223741) (xy 171.553085 -253.169056) (xy 171.5898 -253.118578)
			(xy 171.632557 -253.073105) (xy 171.680681 -253.033355) (xy 171.706794 -253.016258) (xy 171.716954 -253.009908)
			(xy 171.729146 -252.990096) (xy 171.738798 -252.885956) (xy 171.730416 -252.864112) (xy 171.721526 -252.855984)
			(xy 171.703204 -252.838464) (xy 171.67106 -252.799262) (xy 171.644586 -252.756029) (xy 171.624281 -252.709578)
			(xy 171.610527 -252.660785) (xy 171.603584 -252.610567) (xy 171.603162 -252.58522) (xy 171.603564 -252.559902)
			(xy 171.61049 -252.509741) (xy 171.624214 -252.461) (xy 171.644478 -252.414595) (xy 171.670901 -252.371399)
			(xy 171.702985 -252.332225) (xy 171.721272 -252.31471) (xy 171.730162 -252.306328) (xy 171.738544 -252.284738)
			(xy 171.729146 -252.180598) (xy 171.716954 -252.160786) (xy 171.706794 -252.154182) (xy 171.680679 -252.137112)
			(xy 171.632562 -252.097395) (xy 171.58981 -252.051954) (xy 171.553097 -252.001507) (xy 171.523004 -251.946853)
			(xy 171.500006 -251.888855) (xy 171.484468 -251.828429) (xy 171.476635 -251.766532) (xy 171.476162 -251.735336)
			(xy 171.47663 -251.704127) (xy 171.484456 -251.642201) (xy 171.49999 -251.581746) (xy 171.522985 -251.523717)
			(xy 171.553078 -251.469032) (xy 171.589795 -251.418554) (xy 171.632554 -251.373082) (xy 171.68068 -251.333333)
			(xy 171.706794 -251.316236) (xy 171.716954 -251.309886) (xy 171.729146 -251.290074) (xy 171.738798 -251.185934)
			(xy 171.730416 -251.16409) (xy 171.721526 -251.155962) (xy 171.703193 -251.138453) (xy 171.67105 -251.099249)
			(xy 171.644578 -251.056013) (xy 171.624275 -251.00956) (xy 171.610523 -250.960765) (xy 171.603582 -250.910546)
			(xy 171.603162 -250.885198) (xy 171.603549 -250.859879) (xy 171.610478 -250.809718) (xy 171.624205 -250.760977)
			(xy 171.644472 -250.714572) (xy 171.670897 -250.671376) (xy 171.702984 -250.632203) (xy 171.721272 -250.614688)
			(xy 171.730162 -250.606306) (xy 171.738544 -250.584716) (xy 171.729146 -250.480576) (xy 171.716954 -250.460764)
			(xy 171.706794 -250.45416) (xy 171.680692 -250.437066) (xy 171.632563 -250.39736) (xy 171.589798 -250.351926)
			(xy 171.553075 -250.301484) (xy 171.522973 -250.246832) (xy 171.49997 -250.188833) (xy 171.484429 -250.128405)
			(xy 171.476597 -250.066505) (xy 171.476596 -250.00411) (xy 171.484427 -249.94221) (xy 171.499966 -249.881782)
			(xy 171.522967 -249.823782) (xy 171.553067 -249.769128) (xy 171.589789 -249.718685) (xy 171.632552 -249.67325)
			(xy 171.68068 -249.633543) (xy 171.706794 -249.616468) (xy 171.716954 -249.609864) (xy 171.729146 -249.590052)
			(xy 171.738544 -249.485912) (xy 171.730162 -249.464322) (xy 171.721272 -249.45594) (xy 171.703002 -249.43841)
			(xy 171.670922 -249.399236) (xy 171.644502 -249.356042) (xy 171.624238 -249.30964) (xy 171.610512 -249.260903)
			(xy 171.603582 -249.210747) (xy 171.603162 -249.18543) (xy 171.603559 -249.160081) (xy 171.6105 -249.109861)
			(xy 171.624255 -249.061065) (xy 171.644565 -249.014614) (xy 171.671047 -248.971382) (xy 171.703202 -248.932186)
			(xy 171.721526 -248.914666) (xy 171.730416 -248.906538) (xy 171.738798 -248.884694) (xy 171.729146 -248.780554)
			(xy 171.716954 -248.760742) (xy 171.706794 -248.754392) (xy 171.680671 -248.73731) (xy 171.632549 -248.697555)
			(xy 171.589794 -248.652079) (xy 171.553081 -248.601598) (xy 171.522989 -248.546912) (xy 171.499995 -248.488883)
			(xy 171.484461 -248.428428) (xy 171.476633 -248.366501) (xy 171.476162 -248.335292) (xy 171.47661 -248.304094)
			(xy 171.484432 -248.242192) (xy 171.499965 -248.181761) (xy 171.522963 -248.123759) (xy 171.553061 -248.069103)
			(xy 171.589783 -248.018659) (xy 171.632548 -247.973225) (xy 171.680679 -247.933519) (xy 171.706794 -247.916446)
			(xy 171.716954 -247.909842) (xy 171.729146 -247.89003) (xy 171.738544 -247.78589) (xy 171.730162 -247.7643)
			(xy 171.721272 -247.755918) (xy 171.702991 -247.738398) (xy 171.670912 -247.699222) (xy 171.644493 -247.656026)
			(xy 171.624232 -247.609622) (xy 171.610508 -247.560883) (xy 171.603581 -247.510725) (xy 171.603162 -247.485408)
			(xy 171.603611 -247.460061) (xy 171.610541 -247.409843) (xy 171.624286 -247.361048) (xy 171.644587 -247.314596)
			(xy 171.671059 -247.271364) (xy 171.703205 -247.232165) (xy 171.721526 -247.214644) (xy 171.730416 -247.206516)
			(xy 171.738798 -247.184672) (xy 171.729146 -247.080532) (xy 171.716954 -247.06072) (xy 171.706794 -247.05437)
			(xy 171.680706 -247.037236) (xy 171.632584 -246.997489) (xy 171.589828 -246.95202) (xy 171.553112 -246.901547)
			(xy 171.523016 -246.846868) (xy 171.500016 -246.788846) (xy 171.484474 -246.728398) (xy 171.476637 -246.666477)
			(xy 171.476162 -246.63527) (xy 171.476671 -246.604074) (xy 171.484484 -246.542174) (xy 171.500007 -246.481745)
			(xy 171.522996 -246.423743) (xy 171.553085 -246.369087) (xy 171.589799 -246.318642) (xy 171.632557 -246.273206)
			(xy 171.680682 -246.233498) (xy 171.706794 -246.216424) (xy 171.716954 -246.20982) (xy 171.729146 -246.190008)
			(xy 171.738544 -246.085868) (xy 171.730162 -246.064278) (xy 171.721272 -246.055896) (xy 171.70298 -246.038387)
			(xy 171.670902 -245.999209) (xy 171.644485 -245.95601) (xy 171.624225 -245.909605) (xy 171.610504 -245.860864)
			(xy 171.603579 -245.810704) (xy 171.603162 -245.785386) (xy 171.603596 -245.760038) (xy 171.61053 -245.70982)
			(xy 171.624277 -245.661025) (xy 171.644581 -245.614573) (xy 171.671056 -245.571341) (xy 171.703204 -245.532143)
			(xy 171.721526 -245.514622) (xy 171.730416 -245.506494) (xy 171.738798 -245.48465) (xy 171.729146 -245.38051)
			(xy 171.716954 -245.360698) (xy 171.706794 -245.354348) (xy 171.680696 -245.337229) (xy 171.632574 -245.297479)
			(xy 171.589818 -245.252008) (xy 171.553103 -245.201533) (xy 171.523008 -245.146852) (xy 171.50001 -245.088828)
			(xy 171.48447 -245.028378) (xy 171.476636 -244.966456) (xy 171.476162 -244.935248) (xy 171.476654 -244.904052)
			(xy 171.484469 -244.842151) (xy 171.499995 -244.781721) (xy 171.522986 -244.72372) (xy 171.553078 -244.669064)
			(xy 171.589795 -244.618619) (xy 171.632554 -244.573183) (xy 171.680681 -244.533476) (xy 171.706794 -244.516402)
			(xy 171.716954 -244.509798) (xy 171.729146 -244.489986) (xy 171.738544 -244.385846) (xy 171.730162 -244.364256)
			(xy 171.721272 -244.355874) (xy 171.70297 -244.338376) (xy 171.670892 -244.299195) (xy 171.644477 -244.255994)
			(xy 171.624219 -244.209587) (xy 171.6105 -244.160844) (xy 171.603578 -244.110682) (xy 171.603162 -244.085364)
			(xy 171.603582 -244.060016) (xy 171.610518 -244.009797) (xy 171.624269 -243.961001) (xy 171.644574 -243.91455)
			(xy 171.671052 -243.871318) (xy 171.703203 -243.832121) (xy 171.721526 -243.8146) (xy 171.730416 -243.806472)
			(xy 171.738798 -243.784628) (xy 171.729146 -243.680488) (xy 171.716954 -243.660676) (xy 171.706794 -243.654326)
			(xy 171.680686 -243.637221) (xy 171.632564 -243.59747) (xy 171.589809 -243.551997) (xy 171.553094 -243.50152)
			(xy 171.523001 -243.446836) (xy 171.500004 -243.38881) (xy 171.484467 -243.328358) (xy 171.476635 -243.266434)
			(xy 171.476162 -243.235226) (xy 171.476637 -243.204029) (xy 171.484455 -243.142128) (xy 171.499984 -243.081698)
			(xy 171.522977 -243.023696) (xy 171.553071 -242.96904) (xy 171.58979 -242.918595) (xy 171.632552 -242.87316)
			(xy 171.68068 -242.833454) (xy 171.706794 -242.81638) (xy 171.716954 -242.809776) (xy 171.729146 -242.789964)
			(xy 171.738544 -242.685824) (xy 171.730162 -242.664234) (xy 171.721272 -242.655852) (xy 171.703007 -242.638316)
			(xy 171.670927 -242.599143) (xy 171.644506 -242.555951) (xy 171.624242 -242.50955) (xy 171.610515 -242.460814)
			(xy 171.603583 -242.410658) (xy 171.603162 -242.385342) (xy 171.603567 -242.359993) (xy 171.610506 -242.309774)
			(xy 171.62426 -242.260978) (xy 171.644568 -242.214526) (xy 171.671049 -242.171295) (xy 171.703202 -242.132098)
			(xy 171.721526 -242.114578) (xy 171.730416 -242.10645) (xy 171.738798 -242.084606) (xy 171.729146 -241.980466)
			(xy 171.716954 -241.960654) (xy 171.706794 -241.954304) (xy 171.680676 -241.937214) (xy 171.632554 -241.89746)
			(xy 171.589799 -241.851985) (xy 171.553085 -241.801506) (xy 171.522993 -241.74682) (xy 171.499998 -241.688792)
			(xy 171.484463 -241.628338) (xy 171.476633 -241.566413) (xy 171.476162 -241.535204) (xy 171.476651 -241.504041)
			(xy 171.484463 -241.442207) (xy 171.499963 -241.381839) (xy 171.522906 -241.323891) (xy 171.552932 -241.269274)
			(xy 171.589566 -241.218852) (xy 171.632231 -241.173418) (xy 171.680253 -241.13369) (xy 171.732877 -241.100295)
			(xy 171.789271 -241.073758) (xy 171.848546 -241.054498) (xy 171.909767 -241.042819) (xy 171.97197 -241.038906)
			(xy 172.034173 -241.042819) (xy 172.095394 -241.054498) (xy 172.154669 -241.073758) (xy 172.211063 -241.100295)
			(xy 172.263687 -241.13369) (xy 172.311709 -241.173418) (xy 172.354374 -241.218852) (xy 172.391008 -241.269274)
			(xy 172.421034 -241.323891) (xy 172.443977 -241.381839) (xy 172.459477 -241.442207) (xy 172.467289 -241.504041)
			(xy 172.467778 -241.535204) (xy 172.467291 -241.566413) (xy 172.459471 -241.628339) (xy 172.443943 -241.688795)
			(xy 172.420951 -241.746824) (xy 172.39086 -241.80151) (xy 172.354145 -241.851988) (xy 172.311387 -241.897461)
			(xy 172.26326 -241.937208) (xy 172.237146 -241.954304) (xy 172.226986 -241.960654) (xy 172.214794 -241.980466)
			(xy 172.205142 -242.084606) (xy 172.213524 -242.10645) (xy 172.222414 -242.114578) (xy 172.240726 -242.132109)
			(xy 172.272869 -242.171309) (xy 172.299343 -242.21454) (xy 172.31965 -242.260989) (xy 172.333406 -242.30978)
			(xy 172.340354 -242.359995) (xy 172.340778 -242.385342) (xy 172.340338 -242.410659) (xy 172.333418 -242.460817)
			(xy 172.319701 -242.509557) (xy 172.299444 -242.555962) (xy 172.273028 -242.599159) (xy 172.240951 -242.638335)
			(xy 172.222668 -242.655852) (xy 172.213778 -242.664234) (xy 172.205396 -242.685824) (xy 172.214794 -242.789964)
			(xy 172.226986 -242.809776) (xy 172.237146 -242.81638) (xy 172.26323 -242.833496) (xy 172.311349 -242.873205)
			(xy 172.354105 -242.918638) (xy 172.390822 -242.969077) (xy 172.42092 -243.023725) (xy 172.443922 -243.081718)
			(xy 172.459464 -243.142139) (xy 172.467302 -243.204032) (xy 172.467778 -243.235226) (xy 172.467308 -243.266436)
			(xy 172.459486 -243.328363) (xy 172.443955 -243.388819) (xy 172.420961 -243.446848) (xy 172.390867 -243.501534)
			(xy 172.35415 -243.552012) (xy 172.311389 -243.597484) (xy 172.263261 -243.637231) (xy 172.237146 -243.654326)
			(xy 172.226986 -243.660676) (xy 172.214794 -243.680488) (xy 172.205142 -243.784628) (xy 172.213524 -243.806472)
			(xy 172.222414 -243.8146) (xy 172.240736 -243.83212) (xy 172.272878 -243.871323) (xy 172.299351 -243.914556)
			(xy 172.319656 -243.961007) (xy 172.33341 -244.0098) (xy 172.340355 -244.060017) (xy 172.340778 -244.085364)
			(xy 174.17872 -244.085364) (xy 174.182794 -244.021896) (xy 174.194952 -243.959471) (xy 174.214992 -243.899112)
			(xy 174.242586 -243.841812) (xy 174.277282 -243.788511) (xy 174.318508 -243.740084) (xy 174.365588 -243.697327)
			(xy 174.41775 -243.660941) (xy 174.474137 -243.631524) (xy 174.533822 -243.609559) (xy 174.595826 -243.595407)
			(xy 174.65913 -243.589301) (xy 174.722696 -243.591339) (xy 174.785479 -243.601489) (xy 174.846449 -243.619585)
			(xy 174.904604 -243.645328) (xy 174.95899 -243.678297) (xy 175.008713 -243.71795) (xy 175.052958 -243.763636)
			(xy 175.090997 -243.814605) (xy 175.122206 -243.870019) (xy 175.146072 -243.92897) (xy 175.162204 -243.990488)
			(xy 175.170337 -244.053565) (xy 175.170846 -244.085364) (xy 175.170337 -244.117163) (xy 175.162204 -244.18024)
			(xy 175.146072 -244.241758) (xy 175.122206 -244.300709) (xy 175.090997 -244.356123) (xy 175.052958 -244.407092)
			(xy 175.008713 -244.452778) (xy 174.95899 -244.492431) (xy 174.904604 -244.5254) (xy 174.846449 -244.551143)
			(xy 174.785479 -244.569239) (xy 174.722696 -244.579389) (xy 174.65913 -244.581427) (xy 174.595826 -244.575321)
			(xy 174.533822 -244.561169) (xy 174.474137 -244.539204) (xy 174.41775 -244.509787) (xy 174.365588 -244.473401)
			(xy 174.318508 -244.430644) (xy 174.277282 -244.382217) (xy 174.242586 -244.328916) (xy 174.214992 -244.271616)
			(xy 174.194952 -244.211257) (xy 174.182794 -244.148832) (xy 174.17872 -244.085364) (xy 172.340778 -244.085364)
			(xy 172.340353 -244.110681) (xy 172.33343 -244.16084) (xy 172.31971 -244.20958) (xy 172.29945 -244.255985)
			(xy 172.273032 -244.299182) (xy 172.240952 -244.338357) (xy 172.222668 -244.355874) (xy 172.213778 -244.364256)
			(xy 172.205396 -244.385846) (xy 172.214794 -244.489986) (xy 172.226986 -244.509798) (xy 172.237146 -244.516402)
			(xy 172.26324 -244.533503) (xy 172.311359 -244.573214) (xy 172.354115 -244.618649) (xy 172.390831 -244.669091)
			(xy 172.420927 -244.723741) (xy 172.443927 -244.781736) (xy 172.459468 -244.842158) (xy 172.467304 -244.904053)
			(xy 172.467778 -244.935248) (xy 172.467326 -244.966458) (xy 172.4595 -245.028386) (xy 172.443966 -245.088842)
			(xy 172.42097 -245.146872) (xy 172.390874 -245.201558) (xy 172.354155 -245.252035) (xy 172.311392 -245.297507)
			(xy 172.263262 -245.337253) (xy 172.237146 -245.354348) (xy 172.226986 -245.360698) (xy 172.214794 -245.38051)
			(xy 172.205142 -245.48465) (xy 172.213524 -245.506494) (xy 172.222414 -245.514622) (xy 172.240747 -245.532131)
			(xy 172.272888 -245.571336) (xy 172.299359 -245.614572) (xy 172.319662 -245.661025) (xy 172.333415 -245.70982)
			(xy 172.340357 -245.760038) (xy 172.340778 -245.785386) (xy 172.340368 -245.810704) (xy 172.333442 -245.860864)
			(xy 172.319719 -245.909604) (xy 172.299456 -245.956009) (xy 172.273036 -245.999205) (xy 172.240954 -246.03838)
			(xy 172.222668 -246.055896) (xy 172.213778 -246.064278) (xy 172.205396 -246.085868) (xy 172.214794 -246.190008)
			(xy 172.226986 -246.20982) (xy 172.237146 -246.216424) (xy 172.26325 -246.233511) (xy 172.311369 -246.273223)
			(xy 172.354124 -246.318661) (xy 172.39084 -246.369104) (xy 172.420935 -246.423757) (xy 172.443933 -246.481754)
			(xy 172.459472 -246.542178) (xy 172.467305 -246.604075) (xy 172.467778 -246.63527) (xy 172.467343 -246.666481)
			(xy 172.459515 -246.728409) (xy 172.443978 -246.788866) (xy 172.420979 -246.846896) (xy 172.390881 -246.901581)
			(xy 172.35416 -246.952059) (xy 172.311395 -246.997529) (xy 172.263263 -247.037275) (xy 172.237146 -247.05437)
			(xy 172.226986 -247.06072) (xy 172.214794 -247.080532) (xy 172.205142 -247.184672) (xy 172.213524 -247.206516)
			(xy 172.222414 -247.214644) (xy 172.240758 -247.232143) (xy 172.272898 -247.27135) (xy 172.299368 -247.314588)
			(xy 172.319669 -247.361043) (xy 172.333419 -247.40984) (xy 172.340358 -247.460059) (xy 172.340778 -247.485408)
			(xy 172.340382 -247.510726) (xy 172.333454 -247.560887) (xy 172.319728 -247.609627) (xy 172.299462 -247.656032)
			(xy 172.273039 -247.699228) (xy 172.240955 -247.738403) (xy 172.222668 -247.755918) (xy 172.213778 -247.7643)
			(xy 172.205396 -247.78589) (xy 172.214794 -247.89003) (xy 172.226986 -247.909842) (xy 172.237146 -247.916446)
			(xy 172.26326 -247.933518) (xy 172.311379 -247.973233) (xy 172.354134 -248.018672) (xy 172.390848 -248.069118)
			(xy 172.420942 -248.123773) (xy 172.443939 -248.181771) (xy 172.459476 -248.242198) (xy 172.467306 -248.304096)
			(xy 172.467778 -248.335292) (xy 172.467282 -248.366501) (xy 172.459463 -248.428427) (xy 172.443936 -248.488882)
			(xy 172.420946 -248.546912) (xy 172.390856 -248.601597) (xy 172.354143 -248.652076) (xy 172.311385 -248.697548)
			(xy 172.26326 -248.737296) (xy 172.237146 -248.754392) (xy 172.226986 -248.760742) (xy 172.214794 -248.780554)
			(xy 172.205142 -248.884694) (xy 172.213524 -248.906538) (xy 172.222414 -248.914666) (xy 172.24072 -248.932203)
			(xy 172.272864 -248.971401) (xy 172.299338 -249.014632) (xy 172.319646 -249.061079) (xy 172.333404 -249.109869)
			(xy 172.340353 -249.160084) (xy 172.340778 -249.18543) (xy 172.34033 -249.210747) (xy 172.333412 -249.260905)
			(xy 172.319696 -249.309644) (xy 172.299441 -249.356049) (xy 172.273026 -249.399246) (xy 172.24095 -249.438423)
			(xy 172.222668 -249.45594) (xy 172.213778 -249.464322) (xy 172.205396 -249.485912) (xy 172.214794 -249.590052)
			(xy 172.226986 -249.609864) (xy 172.237146 -249.616468) (xy 172.263272 -249.633525) (xy 172.311399 -249.673236)
			(xy 172.354161 -249.718674) (xy 172.390882 -249.76912) (xy 172.42098 -249.823776) (xy 172.44398 -249.881778)
			(xy 172.459519 -249.942208) (xy 172.46735 -250.00411) (xy 172.467349 -250.066505) (xy 172.459516 -250.128407)
			(xy 172.443976 -250.188836) (xy 172.420974 -250.246837) (xy 172.390873 -250.301492) (xy 172.354151 -250.351937)
			(xy 172.311388 -250.397374) (xy 172.26326 -250.437084) (xy 172.237146 -250.45416) (xy 172.226986 -250.460764)
			(xy 172.214794 -250.480576) (xy 172.205396 -250.584716) (xy 172.213778 -250.606306) (xy 172.222668 -250.614688)
			(xy 172.24096 -250.632197) (xy 172.273036 -250.671376) (xy 172.299452 -250.714575) (xy 172.319712 -250.76098)
			(xy 172.333433 -250.809721) (xy 172.34036 -250.85988) (xy 172.340778 -250.885198) (xy 172.340352 -250.910546)
			(xy 172.33342 -250.960766) (xy 172.319672 -251.009562) (xy 172.299367 -251.056014) (xy 172.272889 -251.099246)
			(xy 172.240737 -251.138442) (xy 172.222414 -251.155962) (xy 172.213524 -251.16409) (xy 172.205142 -251.185934)
			(xy 172.214794 -251.290074) (xy 172.226986 -251.309886) (xy 172.237146 -251.316236) (xy 172.263246 -251.333352)
			(xy 172.311366 -251.373103) (xy 172.354121 -251.418576) (xy 172.390835 -251.469051) (xy 172.420929 -251.523732)
			(xy 172.443928 -251.581756) (xy 172.459468 -251.642206) (xy 172.467304 -251.704128) (xy 172.467778 -251.735336)
			(xy 172.467302 -251.766533) (xy 172.459487 -251.828435) (xy 172.44396 -251.888867) (xy 172.420968 -251.94687)
			(xy 172.390874 -252.001526) (xy 172.354155 -252.051971) (xy 172.311392 -252.097405) (xy 172.263261 -252.13711)
			(xy 172.237146 -252.154182) (xy 172.226986 -252.160786) (xy 172.214794 -252.180598) (xy 172.205396 -252.284738)
			(xy 172.213778 -252.306328) (xy 172.222668 -252.31471) (xy 172.24097 -252.332208) (xy 172.273046 -252.37139)
			(xy 172.299461 -252.414591) (xy 172.319718 -252.460998) (xy 172.333438 -252.509741) (xy 172.340361 -252.559902)
			(xy 172.340778 -252.58522) (xy 172.340367 -252.610569) (xy 172.333431 -252.660789) (xy 172.31968 -252.709585)
			(xy 172.299373 -252.756037) (xy 172.272893 -252.799269) (xy 172.240739 -252.838464) (xy 172.222414 -252.855984)
			(xy 172.213524 -252.864112) (xy 172.205142 -252.885956) (xy 172.214794 -252.990096) (xy 172.226986 -253.009908)
			(xy 172.237146 -253.016258) (xy 172.263256 -253.033359) (xy 172.311376 -253.073113) (xy 172.35413 -253.118587)
			(xy 172.390844 -253.169065) (xy 172.420937 -253.223748) (xy 172.443934 -253.281774) (xy 172.459472 -253.342226)
			(xy 172.467305 -253.40415) (xy 172.467778 -253.435358) (xy 172.46724 -253.468058) (xy 172.458632 -253.532889)
			(xy 172.441573 -253.596025) (xy 172.416359 -253.656369) (xy 172.383428 -253.712873) (xy 172.343352 -253.764555)
			(xy 172.320458 -253.78791) (xy 172.313092 -253.795276) (xy 172.305472 -253.813818) (xy 172.305472 -253.906782)
			(xy 172.313092 -253.925324) (xy 172.320458 -253.93269) (xy 172.343371 -253.956028) (xy 172.383454 -254.00771)
			(xy 172.416388 -254.064216) (xy 172.441602 -254.124564) (xy 172.458657 -254.187704) (xy 172.467256 -254.25254)
			(xy 172.467778 -254.285242) (xy 175.57623 -254.285242) (xy 175.576732 -254.254046) (xy 175.584548 -254.192146)
			(xy 175.600073 -254.131718) (xy 175.623063 -254.073717) (xy 175.653154 -254.019061) (xy 175.689868 -253.968616)
			(xy 175.732626 -253.923179) (xy 175.78075 -253.883471) (xy 175.806862 -253.866396) (xy 175.817022 -253.859792)
			(xy 175.829214 -253.83998) (xy 175.838612 -253.73584) (xy 175.83023 -253.71425) (xy 175.82134 -253.705868)
			(xy 175.803029 -253.688379) (xy 175.770954 -253.649195) (xy 175.74454 -253.605993) (xy 175.724284 -253.559583)
			(xy 175.710566 -253.510839) (xy 175.703646 -253.460677) (xy 175.70323 -253.435358) (xy 175.703624 -253.410009)
			(xy 175.710563 -253.359788) (xy 175.724317 -253.310991) (xy 175.744627 -253.264539) (xy 175.771111 -253.221308)
			(xy 175.803268 -253.182113) (xy 175.821594 -253.164594) (xy 175.830484 -253.156466) (xy 175.838866 -253.134622)
			(xy 175.829214 -253.030482) (xy 175.817022 -253.01067) (xy 175.806862 -253.00432) (xy 175.780744 -252.987231)
			(xy 175.732623 -252.947476) (xy 175.689869 -252.902) (xy 175.653156 -252.85152) (xy 175.623064 -252.796835)
			(xy 175.600069 -252.738807) (xy 175.584533 -252.678354) (xy 175.576702 -252.616429) (xy 175.57623 -252.58522)
			(xy 175.576715 -252.554024) (xy 175.584533 -252.492123) (xy 175.600062 -252.431694) (xy 175.623054 -252.373693)
			(xy 175.653147 -252.319037) (xy 175.689864 -252.268592) (xy 175.732623 -252.223156) (xy 175.780749 -252.183449)
			(xy 175.806862 -252.166374) (xy 175.817022 -252.15977) (xy 175.829214 -252.139958) (xy 175.838612 -252.035818)
			(xy 175.83023 -252.014228) (xy 175.82134 -252.005846) (xy 175.803066 -251.988319) (xy 175.770988 -251.949144)
			(xy 175.744569 -251.905949) (xy 175.724306 -251.859547) (xy 175.710581 -251.810809) (xy 175.703651 -251.760653)
			(xy 175.70323 -251.735336) (xy 175.703609 -251.709986) (xy 175.710551 -251.659765) (xy 175.724308 -251.610967)
			(xy 175.744621 -251.564515) (xy 175.771107 -251.521285) (xy 175.803267 -251.482091) (xy 175.821594 -251.464572)
			(xy 175.830484 -251.456444) (xy 175.838866 -251.4346) (xy 175.829214 -251.33046) (xy 175.817022 -251.310648)
			(xy 175.806862 -251.304298) (xy 175.780734 -251.287223) (xy 175.732613 -251.247467) (xy 175.68986 -251.201988)
			(xy 175.653147 -251.151507) (xy 175.623057 -251.096819) (xy 175.600063 -251.038789) (xy 175.584529 -250.978334)
			(xy 175.5767 -250.916408) (xy 175.57623 -250.885198) (xy 175.576697 -250.854001) (xy 175.584519 -250.7921)
			(xy 175.60005 -250.73167) (xy 175.623045 -250.673669) (xy 175.65314 -250.619013) (xy 175.689859 -250.568569)
			(xy 175.732621 -250.523133) (xy 175.780748 -250.483426) (xy 175.806862 -250.466352) (xy 175.817022 -250.459748)
			(xy 175.829214 -250.439936) (xy 175.838612 -250.335796) (xy 175.83023 -250.314206) (xy 175.82134 -250.305824)
			(xy 175.801427 -250.286675) (xy 175.766958 -250.243503) (xy 175.739315 -250.195673) (xy 175.719115 -250.144255)
			(xy 175.706811 -250.090398) (xy 175.702678 -250.03531) (xy 175.706808 -249.98022) (xy 175.719109 -249.926364)
			(xy 175.739306 -249.874944) (xy 175.766948 -249.827113) (xy 175.801414 -249.783939) (xy 175.82134 -249.764804)
			(xy 175.83023 -249.756422) (xy 175.838612 -249.734832) (xy 175.829214 -249.630692) (xy 175.817022 -249.61088)
			(xy 175.806862 -249.604276) (xy 175.780737 -249.587221) (xy 175.732622 -249.5475) (xy 175.689871 -249.502057)
			(xy 175.653159 -249.451608) (xy 175.623068 -249.396952) (xy 175.600072 -249.338952) (xy 175.584535 -249.278525)
			(xy 175.576703 -249.216626) (xy 175.57623 -249.18543) (xy 175.576662 -249.154219) (xy 175.58449 -249.09229)
			(xy 175.600026 -249.031833) (xy 175.623026 -248.973803) (xy 175.653124 -248.919118) (xy 175.689847 -248.868641)
			(xy 175.732612 -248.82317) (xy 175.780745 -248.783424) (xy 175.806862 -248.76633) (xy 175.817022 -248.75998)
			(xy 175.829214 -248.740168) (xy 175.838866 -248.636028) (xy 175.830484 -248.614184) (xy 175.821594 -248.606056)
			(xy 175.803252 -248.588556) (xy 175.771111 -248.549349) (xy 175.744641 -248.506111) (xy 175.72434 -248.459657)
			(xy 175.710589 -248.41086) (xy 175.70365 -248.36064) (xy 175.70323 -248.335292) (xy 175.703623 -248.309974)
			(xy 175.710552 -248.259813) (xy 175.724278 -248.211072) (xy 175.744544 -248.164667) (xy 175.770968 -248.121472)
			(xy 175.803053 -248.082297) (xy 175.82134 -248.064782) (xy 175.83023 -248.0564) (xy 175.838612 -248.03481)
			(xy 175.829214 -247.93067) (xy 175.817022 -247.910858) (xy 175.806862 -247.904254) (xy 175.780727 -247.887214)
			(xy 175.732612 -247.847491) (xy 175.689861 -247.802045) (xy 175.65315 -247.751594) (xy 175.62306 -247.696936)
			(xy 175.600066 -247.638934) (xy 175.584531 -247.578505) (xy 175.576702 -247.516605) (xy 175.57623 -247.485408)
			(xy 175.576723 -247.454199) (xy 175.584541 -247.392273) (xy 175.600068 -247.331817) (xy 175.623059 -247.273788)
			(xy 175.653149 -247.219102) (xy 175.689864 -247.168623) (xy 175.732622 -247.123151) (xy 175.780748 -247.083404)
			(xy 175.806862 -247.066308) (xy 175.817022 -247.059958) (xy 175.829214 -247.040146) (xy 175.838866 -246.936006)
			(xy 175.830484 -246.914162) (xy 175.821594 -246.906034) (xy 175.80329 -246.888496) (xy 175.771146 -246.849298)
			(xy 175.74467 -246.806068) (xy 175.724362 -246.759621) (xy 175.710604 -246.71083) (xy 175.703655 -246.660616)
			(xy 175.70323 -246.63527) (xy 175.703676 -246.609953) (xy 175.710594 -246.559795) (xy 175.72431 -246.511055)
			(xy 175.744566 -246.46465) (xy 175.770981 -246.421453) (xy 175.803057 -246.382277) (xy 175.82134 -246.36476)
			(xy 175.83023 -246.356378) (xy 175.838612 -246.334788) (xy 175.829214 -246.230648) (xy 175.817022 -246.210836)
			(xy 175.806862 -246.204232) (xy 175.780763 -246.18714) (xy 175.732647 -246.147424) (xy 175.689895 -246.101986)
			(xy 175.653181 -246.051543) (xy 175.623087 -245.996892) (xy 175.600087 -245.938897) (xy 175.584545 -245.878475)
			(xy 175.576706 -245.81658) (xy 175.57623 -245.785386) (xy 175.576705 -245.754176) (xy 175.584527 -245.69225)
			(xy 175.600057 -245.631793) (xy 175.62305 -245.573764) (xy 175.653142 -245.519078) (xy 175.689859 -245.4686)
			(xy 175.732619 -245.423128) (xy 175.780747 -245.383381) (xy 175.806862 -245.366286) (xy 175.817022 -245.359936)
			(xy 175.829214 -245.340124) (xy 175.838866 -245.235984) (xy 175.830484 -245.21414) (xy 175.821594 -245.206012)
			(xy 175.803279 -245.188485) (xy 175.771136 -245.149284) (xy 175.744662 -245.106052) (xy 175.724356 -245.059603)
			(xy 175.7106 -245.010811) (xy 175.703653 -244.960595) (xy 175.70323 -244.935248) (xy 175.703661 -244.909931)
			(xy 175.710582 -244.859772) (xy 175.724301 -244.811032) (xy 175.74456 -244.764627) (xy 175.770977 -244.72143)
			(xy 175.803056 -244.682255) (xy 175.82134 -244.664738) (xy 175.83023 -244.656356) (xy 175.838612 -244.634766)
			(xy 175.829214 -244.530626) (xy 175.817022 -244.510814) (xy 175.806862 -244.50421) (xy 175.780752 -244.487132)
			(xy 175.732637 -244.447415) (xy 175.689885 -244.401974) (xy 175.653173 -244.351529) (xy 175.623079 -244.296876)
			(xy 175.600081 -244.238879) (xy 175.584541 -244.178455) (xy 175.576705 -244.116559) (xy 175.57623 -244.085364)
			(xy 175.576688 -244.054154) (xy 175.584512 -243.992226) (xy 175.600045 -243.93177) (xy 175.62304 -243.87374)
			(xy 175.653135 -243.819054) (xy 175.689854 -243.768577) (xy 175.732616 -243.723105) (xy 175.780746 -243.683359)
			(xy 175.806862 -243.666264) (xy 175.817022 -243.659914) (xy 175.829214 -243.640102) (xy 175.838866 -243.535962)
			(xy 175.830484 -243.514118) (xy 175.821594 -243.50599) (xy 175.803268 -243.488473) (xy 175.771126 -243.44927)
			(xy 175.744654 -243.406036) (xy 175.724349 -243.359585) (xy 175.710596 -243.310791) (xy 175.703652 -243.260574)
			(xy 175.70323 -243.235226) (xy 175.703646 -243.209908) (xy 175.710571 -243.159749) (xy 175.724292 -243.111008)
			(xy 175.744554 -243.064604) (xy 175.770974 -243.021407) (xy 175.803055 -242.982232) (xy 175.82134 -242.964716)
			(xy 175.83023 -242.956334) (xy 175.838612 -242.934744) (xy 175.829214 -242.830604) (xy 175.817022 -242.810792)
			(xy 175.806862 -242.804188) (xy 175.780742 -242.787125) (xy 175.732627 -242.747406) (xy 175.689876 -242.701963)
			(xy 175.653164 -242.651515) (xy 175.623072 -242.59686) (xy 175.600075 -242.538862) (xy 175.584537 -242.478436)
			(xy 175.576704 -242.416538) (xy 175.57623 -242.385342) (xy 175.576671 -242.354131) (xy 175.584498 -242.292203)
			(xy 175.600033 -242.231746) (xy 175.623031 -242.173716) (xy 175.653128 -242.119031) (xy 175.689849 -242.068553)
			(xy 175.732614 -242.023082) (xy 175.780745 -241.983337) (xy 175.806862 -241.966242) (xy 175.817022 -241.959892)
			(xy 175.829214 -241.94008) (xy 175.838866 -241.83594) (xy 175.830484 -241.814096) (xy 175.821594 -241.805968)
			(xy 175.803258 -241.788462) (xy 175.771116 -241.749257) (xy 175.744645 -241.70602) (xy 175.724343 -241.659567)
			(xy 175.710592 -241.610771) (xy 175.70365 -241.560552) (xy 175.70323 -241.535204) (xy 175.703631 -241.509886)
			(xy 175.710558 -241.459726) (xy 175.724283 -241.410985) (xy 175.744547 -241.36458) (xy 175.77097 -241.321384)
			(xy 175.803054 -241.282209) (xy 175.82134 -241.264694) (xy 175.83023 -241.256312) (xy 175.838612 -241.234722)
			(xy 175.829214 -241.130582) (xy 175.817022 -241.11077) (xy 175.806862 -241.104166) (xy 175.780732 -241.087118)
			(xy 175.732617 -241.047396) (xy 175.689866 -241.001951) (xy 175.653155 -240.951502) (xy 175.623064 -240.896844)
			(xy 175.600069 -240.838844) (xy 175.584533 -240.778416) (xy 175.576702 -240.716516) (xy 175.57623 -240.68532)
			(xy 175.576719 -240.654157) (xy 175.584531 -240.592323) (xy 175.600031 -240.531955) (xy 175.622974 -240.474007)
			(xy 175.653 -240.41939) (xy 175.689634 -240.368968) (xy 175.732299 -240.323534) (xy 175.780321 -240.283806)
			(xy 175.832945 -240.250411) (xy 175.889339 -240.223874) (xy 175.948614 -240.204614) (xy 176.009835 -240.192935)
			(xy 176.072038 -240.189022) (xy 176.134241 -240.192935) (xy 176.195462 -240.204614) (xy 176.254737 -240.223874)
			(xy 176.311131 -240.250411) (xy 176.363755 -240.283806) (xy 176.411777 -240.323534) (xy 176.454442 -240.368968)
			(xy 176.491076 -240.41939) (xy 176.521102 -240.474007) (xy 176.544045 -240.531955) (xy 176.559545 -240.592323)
			(xy 176.567357 -240.654157) (xy 176.567846 -240.68532) (xy 180.531023 -240.68532) (xy 180.534958 -240.631549)
			(xy 180.546681 -240.578925) (xy 180.565941 -240.528568) (xy 180.592327 -240.481551) (xy 180.625279 -240.438878)
			(xy 180.664092 -240.401457) (xy 180.70794 -240.370087) (xy 180.755888 -240.345435) (xy 180.806915 -240.328027)
			(xy 180.859933 -240.318234) (xy 180.913812 -240.316265) (xy 180.967403 -240.322162) (xy 181.019564 -240.335798)
			(xy 181.069184 -240.356885) (xy 181.115205 -240.384971) (xy 181.156647 -240.419459) (xy 181.192625 -240.459613)
			(xy 181.222373 -240.504577) (xy 181.245258 -240.553394) (xy 181.26079 -240.605023) (xy 181.26864 -240.658363)
			(xy 181.269132 -240.68532) (xy 181.26864 -240.712277) (xy 181.26079 -240.765617) (xy 181.245258 -240.817246)
			(xy 181.222373 -240.866063) (xy 181.192625 -240.911027) (xy 181.156647 -240.951181) (xy 181.115205 -240.985669)
			(xy 181.069184 -241.013755) (xy 181.019564 -241.034842) (xy 180.967403 -241.048478) (xy 180.913812 -241.054375)
			(xy 180.859933 -241.052406) (xy 180.806915 -241.042613) (xy 180.755888 -241.025205) (xy 180.70794 -241.000553)
			(xy 180.664092 -240.969183) (xy 180.625279 -240.931762) (xy 180.592327 -240.889089) (xy 180.565941 -240.842072)
			(xy 180.546681 -240.791715) (xy 180.534958 -240.739091) (xy 180.531023 -240.68532) (xy 176.567846 -240.68532)
			(xy 176.567404 -240.716518) (xy 176.55958 -240.77842) (xy 176.544046 -240.838851) (xy 176.521048 -240.896853)
			(xy 176.490949 -240.951509) (xy 176.454226 -241.001953) (xy 176.411461 -241.047387) (xy 176.363329 -241.087093)
			(xy 176.337214 -241.104166) (xy 176.327054 -241.11077) (xy 176.314862 -241.130582) (xy 176.305464 -241.234722)
			(xy 176.313846 -241.256312) (xy 176.322736 -241.264694) (xy 176.341024 -241.282206) (xy 176.373103 -241.321384)
			(xy 176.39952 -241.364582) (xy 176.41978 -241.410987) (xy 176.433502 -241.459727) (xy 176.440428 -241.509886)
			(xy 176.440846 -241.535204) (xy 176.440403 -241.560551) (xy 176.433471 -241.610769) (xy 176.419724 -241.659564)
			(xy 176.399423 -241.706016) (xy 176.37295 -241.749248) (xy 176.340803 -241.788447) (xy 176.322482 -241.805968)
			(xy 176.313592 -241.814096) (xy 176.30521 -241.83594) (xy 176.314862 -241.94008) (xy 176.327054 -241.959892)
			(xy 176.337214 -241.966242) (xy 176.363309 -241.983365) (xy 176.411431 -242.023114) (xy 176.454187 -242.068585)
			(xy 176.490902 -242.119059) (xy 176.520997 -242.17374) (xy 176.543996 -242.231763) (xy 176.559536 -242.292213)
			(xy 176.567371 -242.354134) (xy 176.567846 -242.385342) (xy 176.567343 -242.416538) (xy 176.559529 -242.478438)
			(xy 176.544004 -242.538867) (xy 176.521014 -242.596869) (xy 176.490924 -242.651525) (xy 176.454209 -242.70197)
			(xy 176.411451 -242.747406) (xy 176.363326 -242.787114) (xy 176.337214 -242.804188) (xy 176.327054 -242.810792)
			(xy 176.314862 -242.830604) (xy 176.305464 -242.934744) (xy 176.313846 -242.956334) (xy 176.322736 -242.964716)
			(xy 176.341035 -242.982218) (xy 176.373112 -243.021398) (xy 176.399528 -243.064598) (xy 176.419787 -243.111005)
			(xy 176.433506 -243.159747) (xy 176.440429 -243.209908) (xy 176.440846 -243.235226) (xy 176.440417 -243.260574)
			(xy 176.433482 -243.310792) (xy 176.419733 -243.359588) (xy 176.399429 -243.406039) (xy 176.372953 -243.449271)
			(xy 176.340804 -243.488469) (xy 176.322482 -243.50599) (xy 176.313592 -243.514118) (xy 176.30521 -243.535962)
			(xy 176.314862 -243.640102) (xy 176.327054 -243.659914) (xy 176.337214 -243.666264) (xy 176.363319 -243.683373)
			(xy 176.411441 -243.723124) (xy 176.454196 -243.768597) (xy 176.490911 -243.819073) (xy 176.521004 -243.873756)
			(xy 176.544002 -243.931781) (xy 176.55954 -243.992233) (xy 176.567373 -244.054156) (xy 176.567846 -244.085364)
			(xy 176.56736 -244.11656) (xy 176.559543 -244.178461) (xy 176.544016 -244.238891) (xy 176.521024 -244.296893)
			(xy 176.490931 -244.351548) (xy 176.454214 -244.401993) (xy 176.411454 -244.447429) (xy 176.363327 -244.487136)
			(xy 176.337214 -244.50421) (xy 176.327054 -244.510814) (xy 176.314862 -244.530626) (xy 176.305464 -244.634766)
			(xy 176.313846 -244.656356) (xy 176.322736 -244.664738) (xy 176.340997 -244.682277) (xy 176.373078 -244.721449)
			(xy 176.399499 -244.764641) (xy 176.419764 -244.811041) (xy 176.433492 -244.859777) (xy 176.440424 -244.909932)
			(xy 176.440846 -244.935248) (xy 176.440432 -244.960596) (xy 176.433494 -245.010816) (xy 176.419742 -245.059611)
			(xy 176.399435 -245.106063) (xy 176.372956 -245.149294) (xy 176.340805 -245.188491) (xy 176.322482 -245.206012)
			(xy 176.313592 -245.21414) (xy 176.30521 -245.235984) (xy 176.314862 -245.340124) (xy 176.327054 -245.359936)
			(xy 176.337214 -245.366286) (xy 176.363329 -245.38338) (xy 176.411451 -245.423133) (xy 176.454206 -245.468608)
			(xy 176.490919 -245.519087) (xy 176.521012 -245.573772) (xy 176.544008 -245.631799) (xy 176.559543 -245.692252)
			(xy 176.567374 -245.754177) (xy 176.567846 -245.785386) (xy 176.567377 -245.816583) (xy 176.559558 -245.878485)
			(xy 176.544028 -245.938914) (xy 176.521033 -245.996916) (xy 176.490938 -246.051572) (xy 176.454219 -246.102017)
			(xy 176.411457 -246.147452) (xy 176.363328 -246.187158) (xy 176.337214 -246.204232) (xy 176.327054 -246.210836)
			(xy 176.314862 -246.230648) (xy 176.305464 -246.334788) (xy 176.313846 -246.356378) (xy 176.322736 -246.36476)
			(xy 176.341008 -246.382289) (xy 176.373088 -246.421463) (xy 176.399507 -246.464657) (xy 176.41977 -246.511059)
			(xy 176.433496 -246.559797) (xy 176.440426 -246.609953) (xy 176.440846 -246.63527) (xy 176.440446 -246.660619)
			(xy 176.433506 -246.710839) (xy 176.419751 -246.759634) (xy 176.399441 -246.806086) (xy 176.37296 -246.849317)
			(xy 176.340806 -246.888514) (xy 176.322482 -246.906034) (xy 176.313592 -246.914162) (xy 176.30521 -246.936006)
			(xy 176.314862 -247.040146) (xy 176.327054 -247.059958) (xy 176.337214 -247.066308) (xy 176.363339 -247.083387)
			(xy 176.411461 -247.123143) (xy 176.454215 -247.16862) (xy 176.490928 -247.219101) (xy 176.521019 -247.273788)
			(xy 176.544013 -247.331817) (xy 176.559547 -247.392272) (xy 176.567375 -247.454198) (xy 176.567846 -247.485408)
			(xy 176.567394 -247.516605) (xy 176.559572 -247.578508) (xy 176.544039 -247.638938) (xy 176.521042 -247.69694)
			(xy 176.490945 -247.751596) (xy 176.454224 -247.80204) (xy 176.411459 -247.847475) (xy 176.363329 -247.887181)
			(xy 176.337214 -247.904254) (xy 176.327054 -247.910858) (xy 176.314862 -247.93067) (xy 176.305464 -248.03481)
			(xy 176.313846 -248.0564) (xy 176.322736 -248.064782) (xy 176.341019 -248.0823) (xy 176.373097 -248.121477)
			(xy 176.399515 -248.164673) (xy 176.419777 -248.211077) (xy 176.4335 -248.259816) (xy 176.440427 -248.309975)
			(xy 176.440846 -248.335292) (xy 176.440395 -248.360639) (xy 176.433464 -248.410857) (xy 176.41972 -248.459651)
			(xy 176.39942 -248.506103) (xy 176.372948 -248.549336) (xy 176.340802 -248.588534) (xy 176.322482 -248.606056)
			(xy 176.313592 -248.614184) (xy 176.30521 -248.636028) (xy 176.314862 -248.740168) (xy 176.327054 -248.75998)
			(xy 176.337214 -248.76633) (xy 176.363304 -248.783461) (xy 176.411425 -248.823209) (xy 176.454181 -248.868679)
			(xy 176.490897 -248.919152) (xy 176.520993 -248.973831) (xy 176.543993 -249.031853) (xy 176.559534 -249.092302)
			(xy 176.567371 -249.154223) (xy 176.567846 -249.18543) (xy 176.567333 -249.216626) (xy 176.559521 -249.278525)
			(xy 176.543997 -249.338954) (xy 176.521009 -249.396956) (xy 176.49092 -249.451612) (xy 176.454207 -249.502057)
			(xy 176.41145 -249.547493) (xy 176.363326 -249.587201) (xy 176.337214 -249.604276) (xy 176.327054 -249.61088)
			(xy 176.314862 -249.630692) (xy 176.305464 -249.734832) (xy 176.313846 -249.756422) (xy 176.322736 -249.764804)
			(xy 176.342673 -249.783927) (xy 176.377135 -249.827106) (xy 176.404772 -249.87494) (xy 176.424966 -249.926362)
			(xy 176.437265 -249.98022) (xy 176.441394 -250.03531) (xy 176.437262 -250.090399) (xy 176.42496 -250.144257)
			(xy 176.404763 -250.195677) (xy 176.377124 -250.24351) (xy 176.34266 -250.286687) (xy 176.322736 -250.305824)
			(xy 176.313846 -250.314206) (xy 176.305464 -250.335796) (xy 176.314862 -250.439936) (xy 176.327054 -250.459748)
			(xy 176.337214 -250.466352) (xy 176.363346 -250.483396) (xy 176.411463 -250.523118) (xy 176.454214 -250.568563)
			(xy 176.490926 -250.619013) (xy 176.521016 -250.673671) (xy 176.544011 -250.731672) (xy 176.559545 -250.792101)
			(xy 176.567375 -250.854001) (xy 176.567846 -250.885198) (xy 176.567323 -250.916406) (xy 176.559505 -250.978329)
			(xy 176.54398 -251.038783) (xy 176.520992 -251.096811) (xy 176.490906 -251.151496) (xy 176.454197 -251.201975)
			(xy 176.411445 -251.247449) (xy 176.363325 -251.2872) (xy 176.337214 -251.304298) (xy 176.327054 -251.310648)
			(xy 176.314862 -251.33046) (xy 176.30521 -251.4346) (xy 176.313592 -251.456444) (xy 176.322482 -251.464572)
			(xy 176.340785 -251.482112) (xy 176.37293 -251.521309) (xy 176.399406 -251.564539) (xy 176.419714 -251.610986)
			(xy 176.433473 -251.659776) (xy 176.440421 -251.70999) (xy 176.440846 -251.735336) (xy 176.440412 -251.760653)
			(xy 176.433492 -251.810812) (xy 176.419775 -251.859553) (xy 176.399517 -251.905958) (xy 176.373099 -251.949154)
			(xy 176.34102 -251.98833) (xy 176.322736 -252.005846) (xy 176.313846 -252.014228) (xy 176.305464 -252.035818)
			(xy 176.314862 -252.139958) (xy 176.327054 -252.15977) (xy 176.337214 -252.166374) (xy 176.363311 -252.183471)
			(xy 176.411427 -252.223185) (xy 176.45418 -252.268622) (xy 176.490895 -252.319064) (xy 176.52099 -252.373714)
			(xy 176.54399 -252.431709) (xy 176.559532 -252.492131) (xy 176.56737 -252.554026) (xy 176.567846 -252.58522)
			(xy 176.56734 -252.616428) (xy 176.559519 -252.678353) (xy 176.543991 -252.738806) (xy 176.521002 -252.796835)
			(xy 176.490913 -252.85152) (xy 176.454202 -252.901998) (xy 176.411448 -252.947472) (xy 176.363326 -252.987222)
			(xy 176.337214 -253.00432) (xy 176.327054 -253.01067) (xy 176.314862 -253.030482) (xy 176.30521 -253.134622)
			(xy 176.313592 -253.156466) (xy 176.322482 -253.164594) (xy 176.340795 -253.182123) (xy 176.37294 -253.221323)
			(xy 176.399414 -253.264554) (xy 176.419721 -253.311004) (xy 176.433477 -253.359795) (xy 176.440423 -253.410011)
			(xy 176.440846 -253.435358) (xy 176.440427 -253.460676) (xy 176.433504 -253.510835) (xy 176.419783 -253.559576)
			(xy 176.399523 -253.605981) (xy 176.373103 -253.649177) (xy 176.341021 -253.688352) (xy 176.322736 -253.705868)
			(xy 176.313846 -253.71425) (xy 176.305464 -253.73584) (xy 176.314862 -253.83998) (xy 176.327054 -253.859792)
			(xy 176.337214 -253.866396) (xy 176.363321 -253.883478) (xy 176.411437 -253.923194) (xy 176.45419 -253.968633)
			(xy 176.490903 -254.019078) (xy 176.520997 -254.07373) (xy 176.543996 -254.131727) (xy 176.559536 -254.192151)
			(xy 176.567371 -254.254047) (xy 176.567846 -254.285242) (xy 179.020216 -254.285242) (xy 179.020726 -254.252541)
			(xy 179.029336 -254.187708) (xy 179.046399 -254.12457) (xy 179.071618 -254.064226) (xy 179.104555 -254.007722)
			(xy 179.144638 -253.956042) (xy 179.167536 -253.93269) (xy 179.174902 -253.925324) (xy 179.182522 -253.906782)
			(xy 179.182522 -253.813818) (xy 179.174902 -253.795276) (xy 179.167536 -253.78791) (xy 179.144622 -253.764573)
			(xy 179.10454 -253.712891) (xy 179.071605 -253.656385) (xy 179.046392 -253.596037) (xy 179.029337 -253.532896)
			(xy 179.020738 -253.46806) (xy 179.020216 -253.435358) (xy 179.020676 -253.404148) (xy 179.0285 -253.342221)
			(xy 179.044033 -253.281765) (xy 179.067029 -253.223735) (xy 179.097123 -253.169049) (xy 179.133842 -253.118572)
			(xy 179.176603 -253.0731) (xy 179.224732 -253.033353) (xy 179.250848 -253.016258) (xy 179.261008 -253.009908)
			(xy 179.2732 -252.990096) (xy 179.282852 -252.885956) (xy 179.27447 -252.864112) (xy 179.26558 -252.855984)
			(xy 179.247249 -252.838473) (xy 179.215108 -252.799268) (xy 179.188636 -252.756033) (xy 179.168333 -252.70958)
			(xy 179.154581 -252.660786) (xy 179.147637 -252.610568) (xy 179.147216 -252.58522) (xy 179.147632 -252.559902)
			(xy 179.154557 -252.509743) (xy 179.168279 -252.461003) (xy 179.18854 -252.414598) (xy 179.21496 -252.371402)
			(xy 179.247041 -252.332226) (xy 179.265326 -252.31471) (xy 179.274216 -252.306328) (xy 179.282598 -252.284738)
			(xy 179.2732 -252.180598) (xy 179.261008 -252.160786) (xy 179.250848 -252.154182) (xy 179.224745 -252.137093)
			(xy 179.176626 -252.097381) (xy 179.133871 -252.051943) (xy 179.097156 -252.0015) (xy 179.067061 -251.946848)
			(xy 179.044062 -251.888852) (xy 179.028523 -251.828428) (xy 179.020689 -251.766531) (xy 179.020216 -251.735336)
			(xy 179.020659 -251.704126) (xy 179.028486 -251.642198) (xy 179.044021 -251.581741) (xy 179.067019 -251.523711)
			(xy 179.097116 -251.469026) (xy 179.133837 -251.418548) (xy 179.176601 -251.373077) (xy 179.224731 -251.333331)
			(xy 179.250848 -251.316236) (xy 179.261008 -251.309886) (xy 179.2732 -251.290074) (xy 179.282852 -251.185934)
			(xy 179.27447 -251.16409) (xy 179.26558 -251.155962) (xy 179.247238 -251.138462) (xy 179.215098 -251.099255)
			(xy 179.188628 -251.056017) (xy 179.168327 -251.009562) (xy 179.154576 -250.960766) (xy 179.147636 -250.910546)
			(xy 179.147216 -250.885198) (xy 179.147618 -250.85988) (xy 179.154545 -250.80972) (xy 179.16827 -250.760979)
			(xy 179.188534 -250.714575) (xy 179.214957 -250.671379) (xy 179.24704 -250.632204) (xy 179.265326 -250.614688)
			(xy 179.274216 -250.606306) (xy 179.282598 -250.584716) (xy 179.2732 -250.480576) (xy 179.261008 -250.460764)
			(xy 179.250848 -250.45416) (xy 179.224748 -250.437064) (xy 179.176623 -250.397356) (xy 179.133862 -250.351921)
			(xy 179.097142 -250.301479) (xy 179.067044 -250.246827) (xy 179.044043 -250.188829) (xy 179.028504 -250.128402)
			(xy 179.020672 -250.066504) (xy 179.020671 -250.004111) (xy 179.028501 -249.942212) (xy 179.044038 -249.881786)
			(xy 179.067037 -249.823787) (xy 179.097134 -249.769134) (xy 179.133853 -249.71869) (xy 179.176612 -249.673254)
			(xy 179.224736 -249.633544) (xy 179.250848 -249.616468) (xy 179.261008 -249.609864) (xy 179.2732 -249.590052)
			(xy 179.282598 -249.485912) (xy 179.274216 -249.464322) (xy 179.265326 -249.45594) (xy 179.247047 -249.438419)
			(xy 179.214969 -249.399242) (xy 179.188552 -249.356046) (xy 179.16829 -249.309643) (xy 179.154566 -249.260904)
			(xy 179.147636 -249.210747) (xy 179.147216 -249.18543) (xy 179.147596 -249.16008) (xy 179.154538 -249.109859)
			(xy 179.168295 -249.061062) (xy 179.188608 -249.01461) (xy 179.215094 -248.971379) (xy 179.247253 -248.932185)
			(xy 179.26558 -248.914666) (xy 179.27447 -248.906538) (xy 179.282852 -248.884694) (xy 179.2732 -248.780554)
			(xy 179.261008 -248.760742) (xy 179.250848 -248.754392) (xy 179.224714 -248.737326) (xy 179.176594 -248.697568)
			(xy 179.133841 -248.652088) (xy 179.09713 -248.601605) (xy 179.06704 -248.546916) (xy 179.044047 -248.488885)
			(xy 179.028514 -248.428429) (xy 179.020686 -248.366502) (xy 179.020216 -248.335292) (xy 179.020639 -248.304093)
			(xy 179.028462 -248.242189) (xy 179.043997 -248.181757) (xy 179.066997 -248.123753) (xy 179.097099 -248.069097)
			(xy 179.133825 -248.018653) (xy 179.176594 -247.97322) (xy 179.22473 -247.933517) (xy 179.250848 -247.916446)
			(xy 179.261008 -247.909842) (xy 179.2732 -247.89003) (xy 179.282598 -247.78589) (xy 179.274216 -247.7643)
			(xy 179.265326 -247.755918) (xy 179.247036 -247.738407) (xy 179.21496 -247.699228) (xy 179.188543 -247.65603)
			(xy 179.168284 -247.609625) (xy 179.154562 -247.560885) (xy 179.147635 -247.510725) (xy 179.147216 -247.485408)
			(xy 179.147648 -247.46006) (xy 179.154579 -247.409841) (xy 179.168326 -247.361045) (xy 179.18863 -247.314593)
			(xy 179.215106 -247.271361) (xy 179.247257 -247.232164) (xy 179.26558 -247.214644) (xy 179.27447 -247.206516)
			(xy 179.282852 -247.184672) (xy 179.2732 -247.080532) (xy 179.261008 -247.06072) (xy 179.250848 -247.05437)
			(xy 179.224749 -247.037252) (xy 179.176629 -246.997501) (xy 179.133875 -246.952029) (xy 179.097161 -246.901554)
			(xy 179.067066 -246.846872) (xy 179.044068 -246.788849) (xy 179.028527 -246.728399) (xy 179.020691 -246.666478)
			(xy 179.020216 -246.63527) (xy 179.0207 -246.604073) (xy 179.028514 -246.542171) (xy 179.044039 -246.48174)
			(xy 179.06703 -246.423738) (xy 179.097123 -246.369081) (xy 179.133842 -246.318636) (xy 179.176604 -246.273202)
			(xy 179.224733 -246.233497) (xy 179.250848 -246.216424) (xy 179.261008 -246.20982) (xy 179.2732 -246.190008)
			(xy 179.282598 -246.085868) (xy 179.274216 -246.064278) (xy 179.265326 -246.055896) (xy 179.247026 -246.038396)
			(xy 179.21495 -245.999215) (xy 179.188535 -245.956014) (xy 179.168277 -245.909607) (xy 179.154557 -245.860865)
			(xy 179.147633 -245.810704) (xy 179.147216 -245.785386) (xy 179.147633 -245.760038) (xy 179.154568 -245.709818)
			(xy 179.168318 -245.661021) (xy 179.188624 -245.614569) (xy 179.215103 -245.571338) (xy 179.247256 -245.532142)
			(xy 179.26558 -245.514622) (xy 179.27447 -245.506494) (xy 179.282852 -245.48465) (xy 179.2732 -245.38051)
			(xy 179.261008 -245.360698) (xy 179.250848 -245.354348) (xy 179.224739 -245.337245) (xy 179.176619 -245.297491)
			(xy 179.133865 -245.252017) (xy 179.097152 -245.20154) (xy 179.067059 -245.146857) (xy 179.044062 -245.088831)
			(xy 179.028523 -245.028379) (xy 179.020689 -244.966456) (xy 179.020216 -244.935248) (xy 179.020683 -244.904051)
			(xy 179.028499 -244.842148) (xy 179.044027 -244.781717) (xy 179.067021 -244.723714) (xy 179.097116 -244.669057)
			(xy 179.133837 -244.618613) (xy 179.176601 -244.573179) (xy 179.224732 -244.533474) (xy 179.250848 -244.516402)
			(xy 179.261008 -244.509798) (xy 179.2732 -244.489986) (xy 179.282598 -244.385846) (xy 179.274216 -244.364256)
			(xy 179.265326 -244.355874) (xy 179.247015 -244.338385) (xy 179.21494 -244.299201) (xy 179.188527 -244.255998)
			(xy 179.168271 -244.209589) (xy 179.154553 -244.160845) (xy 179.147632 -244.110683) (xy 179.147216 -244.085364)
			(xy 179.147618 -244.060015) (xy 179.154556 -244.009795) (xy 179.168309 -243.960998) (xy 179.188618 -243.914546)
			(xy 179.2151 -243.871315) (xy 179.247255 -243.832119) (xy 179.26558 -243.8146) (xy 179.27447 -243.806472)
			(xy 179.282852 -243.784628) (xy 179.2732 -243.680488) (xy 179.261008 -243.660676) (xy 179.250848 -243.654326)
			(xy 179.224729 -243.637237) (xy 179.176609 -243.597482) (xy 179.133856 -243.552006) (xy 179.097143 -243.501526)
			(xy 179.067051 -243.446841) (xy 179.044056 -243.388813) (xy 179.02852 -243.32836) (xy 179.020688 -243.266435)
			(xy 179.020216 -243.235226) (xy 179.020665 -243.204028) (xy 179.028485 -243.142125) (xy 179.044015 -243.081693)
			(xy 179.067012 -243.02369) (xy 179.097109 -242.969034) (xy 179.133832 -242.918589) (xy 179.176599 -242.873156)
			(xy 179.224732 -242.833452) (xy 179.250848 -242.81638) (xy 179.261008 -242.809776) (xy 179.2732 -242.789964)
			(xy 179.282598 -242.685824) (xy 179.274216 -242.664234) (xy 179.265326 -242.655852) (xy 179.247053 -242.638325)
			(xy 179.214975 -242.599149) (xy 179.188556 -242.555955) (xy 179.168294 -242.509552) (xy 179.154568 -242.460815)
			(xy 179.147637 -242.410659) (xy 179.147216 -242.385342) (xy 179.147604 -242.359993) (xy 179.154544 -242.309771)
			(xy 179.1683 -242.260975) (xy 179.188612 -242.214523) (xy 179.215096 -242.171292) (xy 179.247254 -242.132097)
			(xy 179.26558 -242.114578) (xy 179.27447 -242.10645) (xy 179.282852 -242.084606) (xy 179.2732 -241.980466)
			(xy 179.261008 -241.960654) (xy 179.250848 -241.954304) (xy 179.224719 -241.93723) (xy 179.176599 -241.897473)
			(xy 179.133846 -241.851994) (xy 179.097134 -241.801512) (xy 179.067044 -241.746825) (xy 179.04405 -241.688795)
			(xy 179.028516 -241.62834) (xy 179.020687 -241.566414) (xy 179.020216 -241.535204) (xy 179.020705 -241.504041)
			(xy 179.028517 -241.442207) (xy 179.044017 -241.381839) (xy 179.06696 -241.323891) (xy 179.096986 -241.269274)
			(xy 179.13362 -241.218852) (xy 179.176285 -241.173418) (xy 179.224307 -241.13369) (xy 179.276931 -241.100295)
			(xy 179.333325 -241.073758) (xy 179.3926 -241.054498) (xy 179.453821 -241.042819) (xy 179.516024 -241.038906)
			(xy 179.578227 -241.042819) (xy 179.639448 -241.054498) (xy 179.698723 -241.073758) (xy 179.755117 -241.100295)
			(xy 179.807741 -241.13369) (xy 179.855763 -241.173418) (xy 179.898428 -241.218852) (xy 179.935062 -241.269274)
			(xy 179.965088 -241.323891) (xy 179.988031 -241.381839) (xy 180.003531 -241.442207) (xy 180.011343 -241.504041)
			(xy 180.011832 -241.535204) (xy 180.01132 -241.566412) (xy 180.003501 -241.628336) (xy 179.987975 -241.68879)
			(xy 179.964986 -241.746819) (xy 179.934898 -241.801504) (xy 179.898188 -241.851983) (xy 179.855434 -241.897456)
			(xy 179.807312 -241.937207) (xy 179.7812 -241.954304) (xy 179.77104 -241.960654) (xy 179.758848 -241.980466)
			(xy 179.749196 -242.084606) (xy 179.757578 -242.10645) (xy 179.766468 -242.114578) (xy 179.784771 -242.132118)
			(xy 179.816917 -242.171315) (xy 179.843393 -242.214544) (xy 179.863701 -242.260991) (xy 179.877459 -242.309781)
			(xy 179.884408 -242.359996) (xy 179.884832 -242.385342) (xy 179.884407 -242.410659) (xy 179.877486 -242.460819)
			(xy 179.863767 -242.50956) (xy 179.843507 -242.555965) (xy 179.817088 -242.599161) (xy 179.785007 -242.638336)
			(xy 179.766722 -242.655852) (xy 179.757832 -242.664234) (xy 179.74945 -242.685824) (xy 179.758848 -242.789964)
			(xy 179.77104 -242.809776) (xy 179.7812 -242.81638) (xy 179.807296 -242.833477) (xy 179.855413 -242.873191)
			(xy 179.898167 -242.918628) (xy 179.934882 -242.96907) (xy 179.964977 -243.02372) (xy 179.987977 -243.081715)
			(xy 180.003519 -243.142137) (xy 180.011356 -243.204032) (xy 180.011832 -243.235226) (xy 180.011337 -243.266435)
			(xy 180.003516 -243.32836) (xy 179.987986 -243.388814) (xy 179.964995 -243.446843) (xy 179.934905 -243.501528)
			(xy 179.898192 -243.552006) (xy 179.855436 -243.597479) (xy 179.807313 -243.637229) (xy 179.7812 -243.654326)
			(xy 179.77104 -243.660676) (xy 179.758848 -243.680488) (xy 179.749196 -243.784628) (xy 179.757578 -243.806472)
			(xy 179.766468 -243.8146) (xy 179.784782 -243.832129) (xy 179.816926 -243.871329) (xy 179.843401 -243.91456)
			(xy 179.863708 -243.961009) (xy 179.877464 -244.009801) (xy 179.884409 -244.060017) (xy 179.884832 -244.085364)
			(xy 181.722774 -244.085364) (xy 181.726848 -244.021896) (xy 181.739006 -243.959471) (xy 181.759046 -243.899112)
			(xy 181.78664 -243.841812) (xy 181.821336 -243.788511) (xy 181.862562 -243.740084) (xy 181.909642 -243.697327)
			(xy 181.961804 -243.660941) (xy 182.018191 -243.631524) (xy 182.077876 -243.609559) (xy 182.13988 -243.595407)
			(xy 182.203184 -243.589301) (xy 182.26675 -243.591339) (xy 182.329533 -243.601489) (xy 182.390503 -243.619585)
			(xy 182.448658 -243.645328) (xy 182.503044 -243.678297) (xy 182.552767 -243.71795) (xy 182.597012 -243.763636)
			(xy 182.635051 -243.814605) (xy 182.66626 -243.870019) (xy 182.690126 -243.92897) (xy 182.706258 -243.990488)
			(xy 182.714391 -244.053565) (xy 182.7149 -244.085364) (xy 182.714391 -244.117163) (xy 182.706258 -244.18024)
			(xy 182.690126 -244.241758) (xy 182.66626 -244.300709) (xy 182.635051 -244.356123) (xy 182.597012 -244.407092)
			(xy 182.552767 -244.452778) (xy 182.503044 -244.492431) (xy 182.448658 -244.5254) (xy 182.390503 -244.551143)
			(xy 182.329533 -244.569239) (xy 182.26675 -244.579389) (xy 182.203184 -244.581427) (xy 182.13988 -244.575321)
			(xy 182.077876 -244.561169) (xy 182.018191 -244.539204) (xy 181.961804 -244.509787) (xy 181.909642 -244.473401)
			(xy 181.862562 -244.430644) (xy 181.821336 -244.382217) (xy 181.78664 -244.328916) (xy 181.759046 -244.271616)
			(xy 181.739006 -244.211257) (xy 181.726848 -244.148832) (xy 181.722774 -244.085364) (xy 179.884832 -244.085364)
			(xy 179.884421 -244.110682) (xy 179.877497 -244.160842) (xy 179.863775 -244.209583) (xy 179.843513 -244.255988)
			(xy 179.817092 -244.299184) (xy 179.785008 -244.338359) (xy 179.766722 -244.355874) (xy 179.757832 -244.364256)
			(xy 179.74945 -244.385846) (xy 179.758848 -244.489986) (xy 179.77104 -244.509798) (xy 179.7812 -244.516402)
			(xy 179.807306 -244.533485) (xy 179.855423 -244.5732) (xy 179.898177 -244.618639) (xy 179.93489 -244.669083)
			(xy 179.964984 -244.723736) (xy 179.987983 -244.781733) (xy 180.003523 -244.842157) (xy 180.011358 -244.904053)
			(xy 180.011832 -244.935248) (xy 180.011355 -244.966457) (xy 180.00353 -245.028383) (xy 179.987998 -245.088838)
			(xy 179.965005 -245.146866) (xy 179.934912 -245.201552) (xy 179.898197 -245.252029) (xy 179.855439 -245.297502)
			(xy 179.807314 -245.337251) (xy 179.7812 -245.354348) (xy 179.77104 -245.360698) (xy 179.758848 -245.38051)
			(xy 179.749196 -245.48465) (xy 179.757578 -245.506494) (xy 179.766468 -245.514622) (xy 179.784792 -245.53214)
			(xy 179.816936 -245.571342) (xy 179.84341 -245.614576) (xy 179.863714 -245.661027) (xy 179.877468 -245.709821)
			(xy 179.884411 -245.760038) (xy 179.884832 -245.785386) (xy 179.884436 -245.810704) (xy 179.877509 -245.860865)
			(xy 179.863784 -245.909607) (xy 179.843519 -245.956012) (xy 179.817095 -245.999207) (xy 179.785009 -246.038381)
			(xy 179.766722 -246.055896) (xy 179.757832 -246.064278) (xy 179.74945 -246.085868) (xy 179.758848 -246.190008)
			(xy 179.77104 -246.20982) (xy 179.7812 -246.216424) (xy 179.807316 -246.233492) (xy 179.855433 -246.273209)
			(xy 179.898186 -246.318651) (xy 179.934899 -246.369097) (xy 179.964992 -246.423752) (xy 179.987989 -246.48175)
			(xy 180.003527 -246.542176) (xy 180.011359 -246.604074) (xy 180.011832 -246.63527) (xy 180.011372 -246.66648)
			(xy 180.003545 -246.728406) (xy 179.98801 -246.788861) (xy 179.965014 -246.84689) (xy 179.934919 -246.901575)
			(xy 179.898202 -246.952053) (xy 179.855442 -246.997525) (xy 179.807315 -247.037274) (xy 179.7812 -247.05437)
			(xy 179.77104 -247.06072) (xy 179.758848 -247.080532) (xy 179.749196 -247.184672) (xy 179.757578 -247.206516)
			(xy 179.766468 -247.214644) (xy 179.784803 -247.232152) (xy 179.816946 -247.271356) (xy 179.843418 -247.314592)
			(xy 179.863721 -247.361045) (xy 179.877472 -247.409841) (xy 179.884412 -247.46006) (xy 179.884832 -247.485408)
			(xy 179.88445 -247.510727) (xy 179.877521 -247.560888) (xy 179.863793 -247.60963) (xy 179.843525 -247.656035)
			(xy 179.817099 -247.69923) (xy 179.78501 -247.738403) (xy 179.766722 -247.755918) (xy 179.757832 -247.7643)
			(xy 179.74945 -247.78589) (xy 179.758848 -247.89003) (xy 179.77104 -247.909842) (xy 179.7812 -247.916446)
			(xy 179.807326 -247.933499) (xy 179.855443 -247.973219) (xy 179.898196 -248.018662) (xy 179.934908 -248.069111)
			(xy 179.964999 -248.123768) (xy 179.987995 -248.181768) (xy 180.00353 -248.242196) (xy 180.01136 -248.304096)
			(xy 180.011832 -248.335292) (xy 180.011311 -248.3665) (xy 180.003493 -248.428424) (xy 179.987968 -248.488878)
			(xy 179.964981 -248.546906) (xy 179.934895 -248.601591) (xy 179.898185 -248.65207) (xy 179.855432 -248.697544)
			(xy 179.807312 -248.737294) (xy 179.7812 -248.754392) (xy 179.77104 -248.760742) (xy 179.758848 -248.780554)
			(xy 179.749196 -248.884694) (xy 179.757578 -248.906538) (xy 179.766468 -248.914666) (xy 179.784765 -248.932212)
			(xy 179.816911 -248.971407) (xy 179.843389 -249.014635) (xy 179.863698 -249.061081) (xy 179.877457 -249.10987)
			(xy 179.884407 -249.160084) (xy 179.884832 -249.18543) (xy 179.884399 -249.210747) (xy 179.877479 -249.260906)
			(xy 179.863762 -249.309647) (xy 179.843504 -249.356052) (xy 179.817086 -249.399249) (xy 179.785006 -249.438424)
			(xy 179.766722 -249.45594) (xy 179.757832 -249.464322) (xy 179.74945 -249.485912) (xy 179.758848 -249.590052)
			(xy 179.77104 -249.609864) (xy 179.7812 -249.616468) (xy 179.807328 -249.633524) (xy 179.855459 -249.673233)
			(xy 179.898225 -249.718669) (xy 179.934949 -249.769115) (xy 179.965051 -249.823771) (xy 179.988053 -249.881774)
			(xy 180.003593 -249.942205) (xy 180.011425 -250.004109) (xy 180.011424 -250.066506) (xy 180.003591 -250.12841)
			(xy 179.988049 -250.18884) (xy 179.965044 -250.246842) (xy 179.934941 -250.301498) (xy 179.898215 -250.351942)
			(xy 179.855448 -250.397378) (xy 179.807316 -250.437085) (xy 179.7812 -250.45416) (xy 179.77104 -250.460764)
			(xy 179.758848 -250.480576) (xy 179.74945 -250.584716) (xy 179.757832 -250.606306) (xy 179.766722 -250.614688)
			(xy 179.785005 -250.632206) (xy 179.817084 -250.671382) (xy 179.843503 -250.714579) (xy 179.863764 -250.760983)
			(xy 179.877487 -250.809722) (xy 179.884413 -250.859881) (xy 179.884832 -250.885198) (xy 179.884389 -250.910545)
			(xy 179.877458 -250.960764) (xy 179.863712 -251.009559) (xy 179.84341 -251.05601) (xy 179.816936 -251.099243)
			(xy 179.784789 -251.138441) (xy 179.766468 -251.155962) (xy 179.757578 -251.16409) (xy 179.749196 -251.185934)
			(xy 179.758848 -251.290074) (xy 179.77104 -251.309886) (xy 179.7812 -251.316236) (xy 179.807289 -251.333368)
			(xy 179.855411 -251.373116) (xy 179.898168 -251.418585) (xy 179.934884 -251.469057) (xy 179.96498 -251.523737)
			(xy 179.98798 -251.581759) (xy 180.003521 -251.642208) (xy 180.011357 -251.704129) (xy 180.011832 -251.735336)
			(xy 180.011331 -251.766532) (xy 180.003517 -251.828433) (xy 179.987992 -251.888862) (xy 179.965003 -251.946864)
			(xy 179.934912 -252.00152) (xy 179.898197 -252.051965) (xy 179.855438 -252.097401) (xy 179.807313 -252.137108)
			(xy 179.7812 -252.154182) (xy 179.77104 -252.160786) (xy 179.758848 -252.180598) (xy 179.74945 -252.284738)
			(xy 179.757832 -252.306328) (xy 179.766722 -252.31471) (xy 179.785015 -252.332217) (xy 179.817094 -252.371396)
			(xy 179.843511 -252.414594) (xy 179.86377 -252.461001) (xy 179.877491 -252.509742) (xy 179.884415 -252.559902)
			(xy 179.884832 -252.58522) (xy 179.884404 -252.610568) (xy 179.877469 -252.660787) (xy 179.86372 -252.709582)
			(xy 179.843416 -252.756034) (xy 179.81694 -252.799266) (xy 179.78479 -252.838463) (xy 179.766468 -252.855984)
			(xy 179.757578 -252.864112) (xy 179.749196 -252.885956) (xy 179.758848 -252.990096) (xy 179.77104 -253.009908)
			(xy 179.7812 -253.016258) (xy 179.807299 -253.033376) (xy 179.855421 -253.073125) (xy 179.898178 -253.118596)
			(xy 179.934893 -253.169071) (xy 179.964987 -253.223753) (xy 179.987986 -253.281777) (xy 180.003524 -253.342228)
			(xy 180.011358 -253.40415) (xy 180.011832 -253.435358) (xy 180.011308 -253.468059) (xy 180.002699 -253.532891)
			(xy 179.985638 -253.596027) (xy 179.960421 -253.656372) (xy 179.927487 -253.712875) (xy 179.887408 -253.764556)
			(xy 179.864512 -253.78791) (xy 179.857146 -253.795276) (xy 179.849526 -253.813818) (xy 179.849526 -253.906782)
			(xy 179.857146 -253.925324) (xy 179.864512 -253.93269) (xy 179.887417 -253.956036) (xy 179.927502 -254.007715)
			(xy 179.960438 -254.064219) (xy 179.985654 -254.124566) (xy 180.00271 -254.187705) (xy 180.01131 -254.25254)
			(xy 180.011832 -254.285242) (xy 183.120284 -254.285242) (xy 183.120761 -254.254045) (xy 183.128578 -254.192143)
			(xy 183.144105 -254.131713) (xy 183.167098 -254.073711) (xy 183.197192 -254.019055) (xy 183.233911 -253.96861)
			(xy 183.276673 -253.923175) (xy 183.324802 -253.883469) (xy 183.350916 -253.866396) (xy 183.361076 -253.859792)
			(xy 183.373268 -253.83998) (xy 183.382666 -253.73584) (xy 183.374284 -253.71425) (xy 183.365394 -253.705868)
			(xy 183.347093 -253.688368) (xy 183.315015 -253.649188) (xy 183.288598 -253.605988) (xy 183.26834 -253.559581)
			(xy 183.254621 -253.510838) (xy 183.2477 -253.460676) (xy 183.247284 -253.435358) (xy 183.247693 -253.410009)
			(xy 183.25463 -253.35979) (xy 183.268383 -253.310994) (xy 183.28869 -253.264542) (xy 183.315171 -253.22131)
			(xy 183.347324 -253.182114) (xy 183.365648 -253.164594) (xy 183.374538 -253.156466) (xy 183.38292 -253.134622)
			(xy 183.373268 -253.030482) (xy 183.361076 -253.01067) (xy 183.350916 -253.00432) (xy 183.32481 -252.987212)
			(xy 183.276688 -252.947462) (xy 183.233931 -252.901989) (xy 183.197216 -252.851513) (xy 183.167122 -252.79683)
			(xy 183.144125 -252.738804) (xy 183.128588 -252.678352) (xy 183.120756 -252.616428) (xy 183.120284 -252.58522)
			(xy 183.120744 -252.554023) (xy 183.128563 -252.49212) (xy 183.144093 -252.431689) (xy 183.167089 -252.373687)
			(xy 183.197185 -252.319031) (xy 183.233906 -252.268586) (xy 183.27667 -252.223152) (xy 183.324801 -252.183447)
			(xy 183.350916 -252.166374) (xy 183.361076 -252.15977) (xy 183.373268 -252.139958) (xy 183.382666 -252.035818)
			(xy 183.374284 -252.014228) (xy 183.365394 -252.005846) (xy 183.347131 -251.988308) (xy 183.315049 -251.949137)
			(xy 183.288628 -251.905945) (xy 183.268363 -251.859544) (xy 183.254636 -251.810808) (xy 183.247705 -251.760652)
			(xy 183.247284 -251.735336) (xy 183.247678 -251.709987) (xy 183.254619 -251.659766) (xy 183.268374 -251.61097)
			(xy 183.288684 -251.564518) (xy 183.315167 -251.521287) (xy 183.347323 -251.482092) (xy 183.365648 -251.464572)
			(xy 183.374538 -251.456444) (xy 183.38292 -251.4346) (xy 183.373268 -251.33046) (xy 183.361076 -251.310648)
			(xy 183.350916 -251.304298) (xy 183.3248 -251.287204) (xy 183.276678 -251.247452) (xy 183.233922 -251.201978)
			(xy 183.197207 -251.151499) (xy 183.167115 -251.096814) (xy 183.144119 -251.038786) (xy 183.128584 -250.978332)
			(xy 183.120755 -250.916407) (xy 183.120284 -250.885198) (xy 183.120726 -250.854) (xy 183.128549 -250.792097)
			(xy 183.144082 -250.731666) (xy 183.167079 -250.673663) (xy 183.197178 -250.619007) (xy 183.233901 -250.568563)
			(xy 183.276667 -250.523129) (xy 183.3248 -250.483425) (xy 183.350916 -250.466352) (xy 183.361076 -250.459748)
			(xy 183.373268 -250.439936) (xy 183.382666 -250.335796) (xy 183.374284 -250.314206) (xy 183.365394 -250.305824)
			(xy 183.345483 -250.286673) (xy 183.311019 -250.2435) (xy 183.283379 -250.19567) (xy 183.263181 -250.144252)
			(xy 183.250879 -250.090397) (xy 183.246746 -250.03531) (xy 183.250876 -249.980222) (xy 183.263176 -249.926366)
			(xy 183.28337 -249.874947) (xy 183.311008 -249.827115) (xy 183.34547 -249.783941) (xy 183.365394 -249.764804)
			(xy 183.374284 -249.756422) (xy 183.382666 -249.734832) (xy 183.373268 -249.630692) (xy 183.361076 -249.61088)
			(xy 183.350916 -249.604276) (xy 183.324803 -249.587202) (xy 183.276686 -249.547486) (xy 183.233932 -249.502046)
			(xy 183.197218 -249.451601) (xy 183.167125 -249.396947) (xy 183.144128 -249.338949) (xy 183.12859 -249.278523)
			(xy 183.120757 -249.216626) (xy 183.120284 -249.18543) (xy 183.120737 -249.15422) (xy 183.128564 -249.092293)
			(xy 183.144099 -249.031837) (xy 183.167096 -248.973808) (xy 183.197192 -248.919123) (xy 183.233911 -248.868645)
			(xy 183.276672 -248.823174) (xy 183.324801 -248.783426) (xy 183.350916 -248.76633) (xy 183.361076 -248.75998)
			(xy 183.373268 -248.740168) (xy 183.38292 -248.636028) (xy 183.374538 -248.614184) (xy 183.365648 -248.606056)
			(xy 183.347316 -248.588545) (xy 183.315172 -248.549342) (xy 183.288699 -248.506107) (xy 183.268396 -248.459654)
			(xy 183.254644 -248.410859) (xy 183.247704 -248.36064) (xy 183.247284 -248.335292) (xy 183.247692 -248.309974)
			(xy 183.25462 -248.259815) (xy 183.268344 -248.211075) (xy 183.288607 -248.16467) (xy 183.315028 -248.121474)
			(xy 183.347109 -248.082298) (xy 183.365394 -248.064782) (xy 183.374284 -248.0564) (xy 183.382666 -248.03481)
			(xy 183.373268 -247.93067) (xy 183.361076 -247.910858) (xy 183.350916 -247.904254) (xy 183.324793 -247.887195)
			(xy 183.276676 -247.847477) (xy 183.233923 -247.802035) (xy 183.19721 -247.751587) (xy 183.167118 -247.696931)
			(xy 183.144122 -247.638931) (xy 183.128586 -247.578503) (xy 183.120756 -247.516604) (xy 183.120284 -247.485408)
			(xy 183.120798 -247.4542) (xy 183.128616 -247.392275) (xy 183.144141 -247.331821) (xy 183.167129 -247.273793)
			(xy 183.197217 -247.219107) (xy 183.233928 -247.168628) (xy 183.276682 -247.123155) (xy 183.324804 -247.083405)
			(xy 183.350916 -247.066308) (xy 183.361076 -247.059958) (xy 183.373268 -247.040146) (xy 183.38292 -246.936006)
			(xy 183.374538 -246.914162) (xy 183.365648 -246.906034) (xy 183.347354 -246.888485) (xy 183.315207 -246.84929)
			(xy 183.288729 -246.806063) (xy 183.268419 -246.759618) (xy 183.254659 -246.710829) (xy 183.247709 -246.660616)
			(xy 183.247284 -246.63527) (xy 183.247744 -246.609954) (xy 183.254662 -246.559797) (xy 183.268376 -246.511058)
			(xy 183.288629 -246.464653) (xy 183.31504 -246.421456) (xy 183.347113 -246.382278) (xy 183.365394 -246.36476)
			(xy 183.374284 -246.356378) (xy 183.382666 -246.334788) (xy 183.373268 -246.230648) (xy 183.361076 -246.210836)
			(xy 183.350916 -246.204232) (xy 183.324829 -246.187121) (xy 183.276711 -246.14741) (xy 183.233956 -246.101976)
			(xy 183.197241 -246.051536) (xy 183.167144 -245.996887) (xy 183.144142 -245.938894) (xy 183.128599 -245.878473)
			(xy 183.12076 -245.81658) (xy 183.120284 -245.785386) (xy 183.120781 -245.754177) (xy 183.128601 -245.692252)
			(xy 183.144129 -245.631797) (xy 183.16712 -245.573769) (xy 183.19721 -245.519083) (xy 183.233923 -245.468605)
			(xy 183.276679 -245.423132) (xy 183.324803 -245.383383) (xy 183.350916 -245.366286) (xy 183.361076 -245.359936)
			(xy 183.373268 -245.340124) (xy 183.38292 -245.235984) (xy 183.374538 -245.21414) (xy 183.365648 -245.206012)
			(xy 183.347343 -245.188474) (xy 183.315197 -245.149277) (xy 183.288721 -245.106047) (xy 183.268412 -245.0596)
			(xy 183.254655 -245.010809) (xy 183.247707 -244.960595) (xy 183.247284 -244.935248) (xy 183.247729 -244.909932)
			(xy 183.254649 -244.859774) (xy 183.268367 -244.811034) (xy 183.288623 -244.76463) (xy 183.315037 -244.721433)
			(xy 183.347112 -244.682255) (xy 183.365394 -244.664738) (xy 183.374284 -244.656356) (xy 183.382666 -244.634766)
			(xy 183.373268 -244.530626) (xy 183.361076 -244.510814) (xy 183.350916 -244.50421) (xy 183.324819 -244.487114)
			(xy 183.276701 -244.447401) (xy 183.233947 -244.401964) (xy 183.197232 -244.351522) (xy 183.167137 -244.296871)
			(xy 183.144137 -244.238876) (xy 183.128596 -244.178454) (xy 183.120759 -244.116559) (xy 183.120284 -244.085364)
			(xy 183.120763 -244.054155) (xy 183.128587 -243.992229) (xy 183.144118 -243.931774) (xy 183.167111 -243.873745)
			(xy 183.197203 -243.819059) (xy 183.233918 -243.768582) (xy 183.276676 -243.723109) (xy 183.324802 -243.68336)
			(xy 183.350916 -243.666264) (xy 183.361076 -243.659914) (xy 183.373268 -243.640102) (xy 183.38292 -243.535962)
			(xy 183.374538 -243.514118) (xy 183.365648 -243.50599) (xy 183.347333 -243.488463) (xy 183.315187 -243.449263)
			(xy 183.288712 -243.406032) (xy 183.268406 -243.359582) (xy 183.254651 -243.310789) (xy 183.247706 -243.260573)
			(xy 183.247284 -243.235226) (xy 183.247714 -243.209909) (xy 183.254638 -243.159751) (xy 183.268358 -243.111011)
			(xy 183.288617 -243.064606) (xy 183.315033 -243.02141) (xy 183.347111 -242.982233) (xy 183.365394 -242.964716)
			(xy 183.374284 -242.956334) (xy 183.382666 -242.934744) (xy 183.373268 -242.830604) (xy 183.361076 -242.810792)
			(xy 183.350916 -242.804188) (xy 183.324809 -242.787106) (xy 183.276691 -242.747392) (xy 183.233937 -242.701953)
			(xy 183.197223 -242.651508) (xy 183.167129 -242.596855) (xy 183.144131 -242.538858) (xy 183.128592 -242.478434)
			(xy 183.120758 -242.416537) (xy 183.120284 -242.385342) (xy 183.120746 -242.354132) (xy 183.128572 -242.292206)
			(xy 183.144106 -242.23175) (xy 183.167101 -242.173721) (xy 183.197196 -242.119036) (xy 183.233913 -242.068558)
			(xy 183.276674 -242.023086) (xy 183.324801 -241.983338) (xy 183.350916 -241.966242) (xy 183.361076 -241.959892)
			(xy 183.373268 -241.94008) (xy 183.38292 -241.83594) (xy 183.374538 -241.814096) (xy 183.365648 -241.805968)
			(xy 183.347322 -241.788451) (xy 183.315178 -241.74925) (xy 183.288704 -241.706016) (xy 183.268399 -241.659564)
			(xy 183.254647 -241.61077) (xy 183.247705 -241.560552) (xy 183.247284 -241.535204) (xy 183.2477 -241.509887)
			(xy 183.254626 -241.459728) (xy 183.268349 -241.410988) (xy 183.28861 -241.364583) (xy 183.31503 -241.321387)
			(xy 183.34711 -241.282211) (xy 183.365394 -241.264694) (xy 183.374284 -241.256312) (xy 183.382666 -241.234722)
			(xy 183.373268 -241.130582) (xy 183.361076 -241.11077) (xy 183.350916 -241.104166) (xy 183.324799 -241.087099)
			(xy 183.276681 -241.047382) (xy 183.233928 -241.001941) (xy 183.197215 -240.951494) (xy 183.167122 -240.89684)
			(xy 183.144125 -240.83884) (xy 183.128588 -240.778414) (xy 183.120756 -240.716516) (xy 183.120284 -240.68532)
			(xy 183.120773 -240.654157) (xy 183.128585 -240.592323) (xy 183.144085 -240.531955) (xy 183.167028 -240.474007)
			(xy 183.197054 -240.41939) (xy 183.233688 -240.368968) (xy 183.276353 -240.323534) (xy 183.324375 -240.283806)
			(xy 183.376999 -240.250411) (xy 183.433393 -240.223874) (xy 183.492668 -240.204614) (xy 183.553889 -240.192935)
			(xy 183.616092 -240.189022) (xy 183.678295 -240.192935) (xy 183.739516 -240.204614) (xy 183.798791 -240.223874)
			(xy 183.855185 -240.250411) (xy 183.907809 -240.283806) (xy 183.955831 -240.323534) (xy 183.998496 -240.368968)
			(xy 184.03513 -240.41939) (xy 184.065156 -240.474007) (xy 184.088099 -240.531955) (xy 184.103599 -240.592323)
			(xy 184.111411 -240.654157) (xy 184.1119 -240.68532) (xy 188.075077 -240.68532) (xy 188.079012 -240.631549)
			(xy 188.090735 -240.578925) (xy 188.109995 -240.528568) (xy 188.136381 -240.481551) (xy 188.169333 -240.438878)
			(xy 188.208146 -240.401457) (xy 188.251994 -240.370087) (xy 188.299942 -240.345435) (xy 188.350969 -240.328027)
			(xy 188.403987 -240.318234) (xy 188.457866 -240.316265) (xy 188.511457 -240.322162) (xy 188.563618 -240.335798)
			(xy 188.613238 -240.356885) (xy 188.659259 -240.384971) (xy 188.700701 -240.419459) (xy 188.736679 -240.459613)
			(xy 188.766427 -240.504577) (xy 188.789312 -240.553394) (xy 188.804844 -240.605023) (xy 188.812694 -240.658363)
			(xy 188.813186 -240.68532) (xy 188.812694 -240.712277) (xy 188.804844 -240.765617) (xy 188.789312 -240.817246)
			(xy 188.766427 -240.866063) (xy 188.736679 -240.911027) (xy 188.700701 -240.951181) (xy 188.659259 -240.985669)
			(xy 188.613238 -241.013755) (xy 188.563618 -241.034842) (xy 188.511457 -241.048478) (xy 188.457866 -241.054375)
			(xy 188.403987 -241.052406) (xy 188.350969 -241.042613) (xy 188.299942 -241.025205) (xy 188.251994 -241.000553)
			(xy 188.208146 -240.969183) (xy 188.169333 -240.931762) (xy 188.136381 -240.889089) (xy 188.109995 -240.842072)
			(xy 188.090735 -240.791715) (xy 188.079012 -240.739091) (xy 188.075077 -240.68532) (xy 184.1119 -240.68532)
			(xy 184.111479 -240.716519) (xy 184.103654 -240.778423) (xy 184.088119 -240.838855) (xy 184.065118 -240.896858)
			(xy 184.035016 -240.951514) (xy 183.99829 -241.001958) (xy 183.955521 -241.047391) (xy 183.907386 -241.087094)
			(xy 183.881268 -241.104166) (xy 183.871108 -241.11077) (xy 183.858916 -241.130582) (xy 183.849518 -241.234722)
			(xy 183.8579 -241.256312) (xy 183.86679 -241.264694) (xy 183.885089 -241.282196) (xy 183.917164 -241.321377)
			(xy 183.943579 -241.364577) (xy 183.963837 -241.410984) (xy 183.977557 -241.459726) (xy 183.984482 -241.509886)
			(xy 183.9849 -241.535204) (xy 183.984471 -241.560552) (xy 183.977538 -241.610771) (xy 183.96379 -241.659567)
			(xy 183.943486 -241.706019) (xy 183.917009 -241.749251) (xy 183.884859 -241.788448) (xy 183.866536 -241.805968)
			(xy 183.857646 -241.814096) (xy 183.849264 -241.83594) (xy 183.858916 -241.94008) (xy 183.871108 -241.959892)
			(xy 183.881268 -241.966242) (xy 183.907353 -241.983381) (xy 183.955476 -242.023126) (xy 183.998234 -242.068594)
			(xy 184.034951 -242.119066) (xy 184.065048 -242.173744) (xy 184.088048 -242.231766) (xy 184.103589 -242.292214)
			(xy 184.111425 -242.354135) (xy 184.1119 -242.385342) (xy 184.111418 -242.416539) (xy 184.103603 -242.478441)
			(xy 184.088077 -242.538871) (xy 184.065085 -242.596874) (xy 184.034992 -242.65153) (xy 183.998273 -242.701975)
			(xy 183.955511 -242.74741) (xy 183.907382 -242.787115) (xy 183.881268 -242.804188) (xy 183.871108 -242.810792)
			(xy 183.858916 -242.830604) (xy 183.849518 -242.934744) (xy 183.8579 -242.956334) (xy 183.86679 -242.964716)
			(xy 183.885099 -242.982207) (xy 183.917173 -243.021391) (xy 183.943587 -243.064593) (xy 183.963843 -243.111002)
			(xy 183.977561 -243.159746) (xy 183.984483 -243.209907) (xy 183.9849 -243.235226) (xy 183.984486 -243.260574)
			(xy 183.97755 -243.310794) (xy 183.963799 -243.35959) (xy 183.943492 -243.406042) (xy 183.917013 -243.449274)
			(xy 183.88486 -243.48847) (xy 183.866536 -243.50599) (xy 183.857646 -243.514118) (xy 183.849264 -243.535962)
			(xy 183.858916 -243.640102) (xy 183.871108 -243.659914) (xy 183.881268 -243.666264) (xy 183.907363 -243.683389)
			(xy 183.955486 -243.723136) (xy 183.998244 -243.768605) (xy 184.03496 -243.819079) (xy 184.065055 -243.87376)
			(xy 184.088054 -243.931784) (xy 184.103593 -243.992234) (xy 184.111427 -244.054156) (xy 184.1119 -244.085364)
			(xy 184.111435 -244.116561) (xy 184.103617 -244.178464) (xy 184.088089 -244.238895) (xy 184.065094 -244.296897)
			(xy 184.034999 -244.351554) (xy 183.998278 -244.401998) (xy 183.955514 -244.447433) (xy 183.907383 -244.487137)
			(xy 183.881268 -244.50421) (xy 183.871108 -244.510814) (xy 183.858916 -244.530626) (xy 183.849518 -244.634766)
			(xy 183.8579 -244.656356) (xy 183.86679 -244.664738) (xy 183.885061 -244.682267) (xy 183.917139 -244.721442)
			(xy 183.943557 -244.764637) (xy 183.96382 -244.811039) (xy 183.977546 -244.859775) (xy 183.984478 -244.909932)
			(xy 183.9849 -244.935248) (xy 183.9845 -244.960597) (xy 183.977562 -245.010817) (xy 183.963808 -245.059614)
			(xy 183.943498 -245.106066) (xy 183.917016 -245.149297) (xy 183.884861 -245.188492) (xy 183.866536 -245.206012)
			(xy 183.857646 -245.21414) (xy 183.849264 -245.235984) (xy 183.858916 -245.340124) (xy 183.871108 -245.359936)
			(xy 183.881268 -245.366286) (xy 183.907373 -245.383396) (xy 183.955496 -245.423145) (xy 183.998253 -245.468617)
			(xy 184.034969 -245.519093) (xy 184.065063 -245.573776) (xy 184.08806 -245.631802) (xy 184.103597 -245.692254)
			(xy 184.111428 -245.754178) (xy 184.1119 -245.785386) (xy 184.111452 -245.816584) (xy 184.103632 -245.878487)
			(xy 184.0881 -245.938918) (xy 184.065104 -245.996921) (xy 184.035006 -246.051577) (xy 183.998283 -246.102022)
			(xy 183.955517 -246.147455) (xy 183.907384 -246.18716) (xy 183.881268 -246.204232) (xy 183.871108 -246.210836)
			(xy 183.858916 -246.230648) (xy 183.849518 -246.334788) (xy 183.8579 -246.356378) (xy 183.86679 -246.36476)
			(xy 183.885072 -246.382278) (xy 183.917149 -246.421456) (xy 183.943566 -246.464653) (xy 183.963827 -246.511057)
			(xy 183.977551 -246.559795) (xy 183.98448 -246.609953) (xy 183.9849 -246.63527) (xy 183.984515 -246.660619)
			(xy 183.977573 -246.710841) (xy 183.963817 -246.759637) (xy 183.943504 -246.806089) (xy 183.91702 -246.84932)
			(xy 183.884862 -246.888515) (xy 183.866536 -246.906034) (xy 183.857646 -246.914162) (xy 183.849264 -246.936006)
			(xy 183.858916 -247.040146) (xy 183.871108 -247.059958) (xy 183.881268 -247.066308) (xy 183.907383 -247.083403)
			(xy 183.955506 -247.123155) (xy 183.998263 -247.168629) (xy 184.034978 -247.219107) (xy 184.06507 -247.273792)
			(xy 184.088066 -247.33182) (xy 184.103601 -247.392274) (xy 184.111429 -247.454199) (xy 184.1119 -247.485408)
			(xy 184.11147 -247.516606) (xy 184.103646 -247.57851) (xy 184.088112 -247.638942) (xy 184.065113 -247.696945)
			(xy 184.035013 -247.751601) (xy 183.998288 -247.802045) (xy 183.95552 -247.847478) (xy 183.907385 -247.887182)
			(xy 183.881268 -247.904254) (xy 183.871108 -247.910858) (xy 183.858916 -247.93067) (xy 183.849518 -248.03481)
			(xy 183.8579 -248.0564) (xy 183.86679 -248.064782) (xy 183.885083 -248.08229) (xy 183.917158 -248.12147)
			(xy 183.943574 -248.164669) (xy 183.963833 -248.211075) (xy 183.977555 -248.259815) (xy 183.984481 -248.309974)
			(xy 183.9849 -248.335292) (xy 183.984463 -248.36064) (xy 183.977532 -248.410859) (xy 183.963786 -248.459654)
			(xy 183.943483 -248.506106) (xy 183.917007 -248.549338) (xy 183.884858 -248.588535) (xy 183.866536 -248.606056)
			(xy 183.857646 -248.614184) (xy 183.849264 -248.636028) (xy 183.858916 -248.740168) (xy 183.871108 -248.75998)
			(xy 183.881268 -248.76633) (xy 183.907347 -248.783477) (xy 183.955471 -248.823221) (xy 183.998229 -248.868688)
			(xy 184.034947 -248.919158) (xy 184.065044 -248.973835) (xy 184.088045 -249.031856) (xy 184.103587 -249.092304)
			(xy 184.111425 -249.154223) (xy 184.1119 -249.18543) (xy 184.111409 -249.216626) (xy 184.103595 -249.278528)
			(xy 184.08807 -249.338958) (xy 184.06508 -249.396961) (xy 184.034988 -249.451617) (xy 183.998271 -249.502062)
			(xy 183.95551 -249.547497) (xy 183.907382 -249.587203) (xy 183.881268 -249.604276) (xy 183.871108 -249.61088)
			(xy 183.858916 -249.630692) (xy 183.849518 -249.734832) (xy 183.8579 -249.756422) (xy 183.86679 -249.764804)
			(xy 183.88673 -249.783926) (xy 183.921195 -249.827103) (xy 183.948836 -249.874937) (xy 183.969032 -249.926359)
			(xy 183.981333 -249.980218) (xy 183.985463 -250.03531) (xy 183.98133 -250.090401) (xy 183.969026 -250.144259)
			(xy 183.948827 -250.19568) (xy 183.921185 -250.243513) (xy 183.886717 -250.286688) (xy 183.86679 -250.305824)
			(xy 183.8579 -250.314206) (xy 183.849518 -250.335796) (xy 183.858916 -250.439936) (xy 183.871108 -250.459748)
			(xy 183.881268 -250.466352) (xy 183.90739 -250.483412) (xy 183.955508 -250.52313) (xy 183.998262 -250.568571)
			(xy 184.034975 -250.619019) (xy 184.065067 -250.673675) (xy 184.088063 -250.731675) (xy 184.103599 -250.792102)
			(xy 184.111429 -250.854002) (xy 184.1119 -250.885198) (xy 184.111398 -250.916407) (xy 184.103579 -250.978332)
			(xy 184.088052 -251.038787) (xy 184.065063 -251.096816) (xy 184.034974 -251.151501) (xy 183.998261 -251.20198)
			(xy 183.955505 -251.247453) (xy 183.907381 -251.287202) (xy 183.881268 -251.304298) (xy 183.871108 -251.310648)
			(xy 183.858916 -251.33046) (xy 183.849264 -251.4346) (xy 183.857646 -251.456444) (xy 183.866536 -251.464572)
			(xy 183.88483 -251.482121) (xy 183.916978 -251.521315) (xy 183.943456 -251.564542) (xy 183.963766 -251.610988)
			(xy 183.977526 -251.659777) (xy 183.984475 -251.70999) (xy 183.9849 -251.735336) (xy 183.984449 -251.760652)
			(xy 183.97753 -251.81081) (xy 183.963815 -251.859549) (xy 183.94356 -251.905954) (xy 183.917147 -251.949151)
			(xy 183.885072 -251.988328) (xy 183.86679 -252.005846) (xy 183.8579 -252.014228) (xy 183.849518 -252.035818)
			(xy 183.858916 -252.139958) (xy 183.871108 -252.15977) (xy 183.881268 -252.166374) (xy 183.907354 -252.183486)
			(xy 183.955473 -252.223196) (xy 183.998228 -252.26863) (xy 184.034944 -252.31907) (xy 184.065041 -252.373719)
			(xy 184.088043 -252.431712) (xy 184.103586 -252.492132) (xy 184.111424 -252.554026) (xy 184.1119 -252.58522)
			(xy 184.111415 -252.616429) (xy 184.103594 -252.678355) (xy 184.088064 -252.73881) (xy 184.065072 -252.796839)
			(xy 184.034981 -252.851525) (xy 183.998266 -252.902003) (xy 183.955508 -252.947476) (xy 183.907382 -252.987224)
			(xy 183.881268 -253.00432) (xy 183.871108 -253.01067) (xy 183.858916 -253.030482) (xy 183.849264 -253.134622)
			(xy 183.857646 -253.156466) (xy 183.866536 -253.164594) (xy 183.884841 -253.182132) (xy 183.916987 -253.221329)
			(xy 183.943464 -253.264558) (xy 183.963773 -253.311006) (xy 183.97753 -253.359797) (xy 183.984477 -253.410011)
			(xy 183.9849 -253.435358) (xy 183.984464 -253.460675) (xy 183.977543 -253.510833) (xy 183.963824 -253.559573)
			(xy 183.943566 -253.605978) (xy 183.91715 -253.649174) (xy 183.885073 -253.688351) (xy 183.86679 -253.705868)
			(xy 183.8579 -253.71425) (xy 183.849518 -253.73584) (xy 183.858916 -253.83998) (xy 183.871108 -253.859792)
			(xy 183.881268 -253.866396) (xy 183.907364 -253.883494) (xy 183.955483 -253.923206) (xy 183.998237 -253.968642)
			(xy 184.034953 -254.019084) (xy 184.065048 -254.073735) (xy 184.088048 -254.13173) (xy 184.103589 -254.192152)
			(xy 184.111425 -254.254047) (xy 184.1119 -254.285242) (xy 186.56427 -254.285242) (xy 186.564793 -254.252541)
			(xy 186.573403 -254.187709) (xy 186.590464 -254.124573) (xy 186.61568 -254.064228) (xy 186.648615 -254.007725)
			(xy 186.688694 -253.956043) (xy 186.71159 -253.93269) (xy 186.718956 -253.925324) (xy 186.726576 -253.906782)
			(xy 186.726576 -253.813818) (xy 186.718956 -253.795276) (xy 186.71159 -253.78791) (xy 186.688686 -253.764564)
			(xy 186.648601 -253.712885) (xy 186.615664 -253.656381) (xy 186.590448 -253.596034) (xy 186.573392 -253.532894)
			(xy 186.564792 -253.468059) (xy 186.56427 -253.435358) (xy 186.564751 -253.404149) (xy 186.572575 -253.342223)
			(xy 186.588106 -253.281769) (xy 186.611099 -253.22374) (xy 186.641191 -253.169055) (xy 186.677906 -253.118577)
			(xy 186.720663 -253.073104) (xy 186.768788 -253.033355) (xy 186.794902 -253.016258) (xy 186.805062 -253.009908)
			(xy 186.817254 -252.990096) (xy 186.826906 -252.885956) (xy 186.818524 -252.864112) (xy 186.809634 -252.855984)
			(xy 186.791313 -252.838462) (xy 186.759169 -252.799261) (xy 186.732695 -252.756028) (xy 186.71239 -252.709578)
			(xy 186.698635 -252.660784) (xy 186.691692 -252.610567) (xy 186.69127 -252.58522) (xy 186.69167 -252.559902)
			(xy 186.698595 -252.509741) (xy 186.71232 -252.461) (xy 186.732584 -252.414595) (xy 186.759008 -252.371399)
			(xy 186.791093 -252.332225) (xy 186.80938 -252.31471) (xy 186.81827 -252.306328) (xy 186.826652 -252.284738)
			(xy 186.817254 -252.180598) (xy 186.805062 -252.160786) (xy 186.794902 -252.154182) (xy 186.768789 -252.137109)
			(xy 186.720672 -252.097393) (xy 186.677919 -252.051952) (xy 186.641205 -252.001506) (xy 186.611112 -251.946852)
			(xy 186.588115 -251.888854) (xy 186.572577 -251.828429) (xy 186.564743 -251.766532) (xy 186.56427 -251.735336)
			(xy 186.564734 -251.704126) (xy 186.57256 -251.6422) (xy 186.588094 -251.581745) (xy 186.61109 -251.523716)
			(xy 186.641184 -251.469031) (xy 186.677901 -251.418553) (xy 186.720661 -251.373081) (xy 186.768788 -251.333332)
			(xy 186.794902 -251.316236) (xy 186.805062 -251.309886) (xy 186.817254 -251.290074) (xy 186.826906 -251.185934)
			(xy 186.818524 -251.16409) (xy 186.809634 -251.155962) (xy 186.791302 -251.138451) (xy 186.759159 -251.099248)
			(xy 186.732687 -251.056012) (xy 186.712383 -251.00956) (xy 186.698631 -250.960765) (xy 186.69169 -250.910546)
			(xy 186.69127 -250.885198) (xy 186.691655 -250.859879) (xy 186.698584 -250.809718) (xy 186.712311 -250.760976)
			(xy 186.732578 -250.714571) (xy 186.759004 -250.671376) (xy 186.791092 -250.632203) (xy 186.80938 -250.614688)
			(xy 186.81827 -250.606306) (xy 186.826652 -250.584716) (xy 186.817254 -250.480576) (xy 186.805062 -250.460764)
			(xy 186.794902 -250.45416) (xy 186.7688 -250.437066) (xy 186.72067 -250.39736) (xy 186.677905 -250.351927)
			(xy 186.64118 -250.301485) (xy 186.611078 -250.246832) (xy 186.588075 -250.188833) (xy 186.572534 -250.128405)
			(xy 186.564701 -250.066505) (xy 186.5647 -250.00411) (xy 186.572531 -249.942209) (xy 186.58807 -249.881781)
			(xy 186.611072 -249.823781) (xy 186.641172 -249.769127) (xy 186.677895 -249.718684) (xy 186.720659 -249.67325)
			(xy 186.768788 -249.633543) (xy 186.794902 -249.616468) (xy 186.805062 -249.609864) (xy 186.817254 -249.590052)
			(xy 186.826652 -249.485912) (xy 186.81827 -249.464322) (xy 186.80938 -249.45594) (xy 186.791111 -249.438408)
			(xy 186.759031 -249.399235) (xy 186.73261 -249.356041) (xy 186.712347 -249.30964) (xy 186.698621 -249.260903)
			(xy 186.69169 -249.210746) (xy 186.69127 -249.18543) (xy 186.691664 -249.160081) (xy 186.698606 -249.109861)
			(xy 186.712361 -249.061065) (xy 186.732672 -249.014613) (xy 186.759154 -248.971382) (xy 186.791309 -248.932186)
			(xy 186.809634 -248.914666) (xy 186.818524 -248.906538) (xy 186.826906 -248.884694) (xy 186.817254 -248.780554)
			(xy 186.805062 -248.760742) (xy 186.794902 -248.754392) (xy 186.76878 -248.737307) (xy 186.720658 -248.697553)
			(xy 186.677903 -248.652077) (xy 186.641189 -248.601597) (xy 186.611098 -248.546911) (xy 186.588103 -248.488882)
			(xy 186.572569 -248.428427) (xy 186.564741 -248.366501) (xy 186.56427 -248.335292) (xy 186.564714 -248.304094)
			(xy 186.572537 -248.242191) (xy 186.58807 -248.18176) (xy 186.611068 -248.123758) (xy 186.641166 -248.069102)
			(xy 186.677889 -248.018658) (xy 186.720654 -247.973224) (xy 186.768786 -247.933519) (xy 186.794902 -247.916446)
			(xy 186.805062 -247.909842) (xy 186.817254 -247.89003) (xy 186.826652 -247.78589) (xy 186.81827 -247.7643)
			(xy 186.80938 -247.755918) (xy 186.7911 -247.738397) (xy 186.759021 -247.699221) (xy 186.732602 -247.656026)
			(xy 186.71234 -247.609622) (xy 186.698616 -247.560883) (xy 186.691689 -247.510725) (xy 186.69127 -247.485408)
			(xy 186.691716 -247.460061) (xy 186.698647 -247.409843) (xy 186.712392 -247.361048) (xy 186.732693 -247.314596)
			(xy 186.759166 -247.271363) (xy 186.791313 -247.232165) (xy 186.809634 -247.214644) (xy 186.818524 -247.206516)
			(xy 186.826906 -247.184672) (xy 186.817254 -247.080532) (xy 186.805062 -247.06072) (xy 186.794902 -247.05437)
			(xy 186.768816 -247.037233) (xy 186.720694 -246.997486) (xy 186.677937 -246.952018) (xy 186.64122 -246.901546)
			(xy 186.611124 -246.846867) (xy 186.588124 -246.788846) (xy 186.572582 -246.728397) (xy 186.564745 -246.666477)
			(xy 186.56427 -246.63527) (xy 186.564775 -246.604074) (xy 186.572588 -246.542174) (xy 186.588112 -246.481744)
			(xy 186.611101 -246.423743) (xy 186.641191 -246.369086) (xy 186.677906 -246.318641) (xy 186.720664 -246.273205)
			(xy 186.768789 -246.233498) (xy 186.794902 -246.216424) (xy 186.805062 -246.20982) (xy 186.817254 -246.190008)
			(xy 186.826652 -246.085868) (xy 186.81827 -246.064278) (xy 186.80938 -246.055896) (xy 186.79109 -246.038385)
			(xy 186.759011 -245.999207) (xy 186.732594 -245.95601) (xy 186.712334 -245.909604) (xy 186.698612 -245.860863)
			(xy 186.691687 -245.810704) (xy 186.69127 -245.785386) (xy 186.691702 -245.760038) (xy 186.698635 -245.70982)
			(xy 186.712383 -245.661024) (xy 186.732687 -245.614572) (xy 186.759163 -245.57134) (xy 186.791312 -245.532143)
			(xy 186.809634 -245.514622) (xy 186.818524 -245.506494) (xy 186.826906 -245.48465) (xy 186.817254 -245.38051)
			(xy 186.805062 -245.360698) (xy 186.794902 -245.354348) (xy 186.768806 -245.337226) (xy 186.720684 -245.297477)
			(xy 186.677927 -245.252007) (xy 186.641212 -245.201532) (xy 186.611117 -245.146851) (xy 186.588118 -245.088828)
			(xy 186.572579 -245.028378) (xy 186.564744 -244.966456) (xy 186.56427 -244.935248) (xy 186.564758 -244.904052)
			(xy 186.572574 -244.84215) (xy 186.5881 -244.781721) (xy 186.611092 -244.723719) (xy 186.641184 -244.669063)
			(xy 186.677901 -244.618618) (xy 186.720661 -244.573182) (xy 186.768788 -244.533476) (xy 186.794902 -244.516402)
			(xy 186.805062 -244.509798) (xy 186.817254 -244.489986) (xy 186.826652 -244.385846) (xy 186.81827 -244.364256)
			(xy 186.80938 -244.355874) (xy 186.791079 -244.338374) (xy 186.759002 -244.299194) (xy 186.732585 -244.255994)
			(xy 186.712327 -244.209586) (xy 186.698608 -244.160843) (xy 186.691686 -244.110682) (xy 186.69127 -244.085364)
			(xy 186.691687 -244.060016) (xy 186.698624 -244.009796) (xy 186.712375 -243.961001) (xy 186.732681 -243.914549)
			(xy 186.759159 -243.871317) (xy 186.791311 -243.832121) (xy 186.809634 -243.8146) (xy 186.818524 -243.806472)
			(xy 186.826906 -243.784628) (xy 186.817254 -243.680488) (xy 186.805062 -243.660676) (xy 186.794902 -243.654326)
			(xy 186.768796 -243.637218) (xy 186.720674 -243.597468) (xy 186.677918 -243.551995) (xy 186.641203 -243.501519)
			(xy 186.611109 -243.446836) (xy 186.588112 -243.38881) (xy 186.572575 -243.328358) (xy 186.564743 -243.266434)
			(xy 186.56427 -243.235226) (xy 186.564741 -243.204029) (xy 186.572559 -243.142127) (xy 186.588088 -243.081697)
			(xy 186.611082 -243.023695) (xy 186.641177 -242.969039) (xy 186.677896 -242.918594) (xy 186.720659 -242.873159)
			(xy 186.768788 -242.833453) (xy 186.794902 -242.81638) (xy 186.805062 -242.809776) (xy 186.817254 -242.789964)
			(xy 186.826652 -242.685824) (xy 186.81827 -242.664234) (xy 186.80938 -242.655852) (xy 186.791117 -242.638314)
			(xy 186.759036 -242.599142) (xy 186.732615 -242.55595) (xy 186.71235 -242.50955) (xy 186.698623 -242.460814)
			(xy 186.691691 -242.410658) (xy 186.69127 -242.385342) (xy 186.691672 -242.359993) (xy 186.698612 -242.309773)
			(xy 186.712366 -242.260977) (xy 186.732675 -242.214526) (xy 186.759156 -242.171294) (xy 186.79131 -242.132098)
			(xy 186.809634 -242.114578) (xy 186.818524 -242.10645) (xy 186.826906 -242.084606) (xy 186.817254 -241.980466)
			(xy 186.805062 -241.960654) (xy 186.794902 -241.954304) (xy 186.768786 -241.937211) (xy 186.720664 -241.897458)
			(xy 186.677908 -241.851983) (xy 186.641194 -241.801505) (xy 186.611102 -241.74682) (xy 186.588106 -241.688792)
			(xy 186.572571 -241.628338) (xy 186.564741 -241.566413) (xy 186.56427 -241.535204) (xy 186.564759 -241.504041)
			(xy 186.572571 -241.442207) (xy 186.588071 -241.381839) (xy 186.611014 -241.323891) (xy 186.64104 -241.269274)
			(xy 186.677674 -241.218852) (xy 186.720339 -241.173418) (xy 186.768361 -241.13369) (xy 186.820985 -241.100295)
			(xy 186.877379 -241.073758) (xy 186.936654 -241.054498) (xy 186.997875 -241.042819) (xy 187.060078 -241.038906)
			(xy 187.122281 -241.042819) (xy 187.183502 -241.054498) (xy 187.242777 -241.073758) (xy 187.299171 -241.100295)
			(xy 187.351795 -241.13369) (xy 187.399817 -241.173418) (xy 187.442482 -241.218852) (xy 187.479116 -241.269274)
			(xy 187.509142 -241.323891) (xy 187.532085 -241.381839) (xy 187.547585 -241.442207) (xy 187.555397 -241.504041)
			(xy 187.555886 -241.535204) (xy 187.555395 -241.566413) (xy 187.547576 -241.628339) (xy 187.532047 -241.688794)
			(xy 187.509056 -241.746824) (xy 187.478966 -241.801509) (xy 187.442252 -241.851988) (xy 187.399494 -241.89746)
			(xy 187.351368 -241.937208) (xy 187.325254 -241.954304) (xy 187.315094 -241.960654) (xy 187.302902 -241.980466)
			(xy 187.29325 -242.084606) (xy 187.301632 -242.10645) (xy 187.310522 -242.114578) (xy 187.328835 -242.132107)
			(xy 187.360978 -242.171308) (xy 187.387452 -242.21454) (xy 187.407758 -242.260989) (xy 187.421514 -242.30978)
			(xy 187.428462 -242.359995) (xy 187.428886 -242.385342) (xy 187.428443 -242.410659) (xy 187.421524 -242.460817)
			(xy 187.407807 -242.509557) (xy 187.38755 -242.555961) (xy 187.361135 -242.599158) (xy 187.329059 -242.638335)
			(xy 187.310776 -242.655852) (xy 187.301886 -242.664234) (xy 187.293504 -242.685824) (xy 187.302902 -242.789964)
			(xy 187.315094 -242.809776) (xy 187.325254 -242.81638) (xy 187.35134 -242.833493) (xy 187.399459 -242.873203)
			(xy 187.442214 -242.918636) (xy 187.478931 -242.969076) (xy 187.509028 -243.023724) (xy 187.53203 -243.081717)
			(xy 187.547572 -243.142138) (xy 187.55541 -243.204032) (xy 187.555886 -243.235226) (xy 187.555413 -243.266435)
			(xy 187.54759 -243.328362) (xy 187.532059 -243.388818) (xy 187.509066 -243.446847) (xy 187.478973 -243.501533)
			(xy 187.442256 -243.552011) (xy 187.399496 -243.597483) (xy 187.351369 -243.63723) (xy 187.325254 -243.654326)
			(xy 187.315094 -243.660676) (xy 187.302902 -243.680488) (xy 187.29325 -243.784628) (xy 187.301632 -243.806472)
			(xy 187.310522 -243.8146) (xy 187.328846 -243.832119) (xy 187.360988 -243.871321) (xy 187.38746 -243.914555)
			(xy 187.407764 -243.961006) (xy 187.421518 -244.0098) (xy 187.428463 -244.060017) (xy 187.428886 -244.085364)
			(xy 189.266828 -244.085364) (xy 189.270902 -244.021896) (xy 189.28306 -243.959471) (xy 189.3031 -243.899112)
			(xy 189.330694 -243.841812) (xy 189.36539 -243.788511) (xy 189.406616 -243.740084) (xy 189.453696 -243.697327)
			(xy 189.505858 -243.660941) (xy 189.562245 -243.631524) (xy 189.62193 -243.609559) (xy 189.683934 -243.595407)
			(xy 189.747238 -243.589301) (xy 189.810804 -243.591339) (xy 189.873587 -243.601489) (xy 189.934557 -243.619585)
			(xy 189.992712 -243.645328) (xy 190.047098 -243.678297) (xy 190.096821 -243.71795) (xy 190.141066 -243.763636)
			(xy 190.179105 -243.814605) (xy 190.210314 -243.870019) (xy 190.23418 -243.92897) (xy 190.250312 -243.990488)
			(xy 190.258445 -244.053565) (xy 190.258954 -244.085364) (xy 190.258445 -244.117163) (xy 190.250312 -244.18024)
			(xy 190.23418 -244.241758) (xy 190.210314 -244.300709) (xy 190.179105 -244.356123) (xy 190.141066 -244.407092)
			(xy 190.096821 -244.452778) (xy 190.047098 -244.492431) (xy 189.992712 -244.5254) (xy 189.934557 -244.551143)
			(xy 189.873587 -244.569239) (xy 189.810804 -244.579389) (xy 189.747238 -244.581427) (xy 189.683934 -244.575321)
			(xy 189.62193 -244.561169) (xy 189.562245 -244.539204) (xy 189.505858 -244.509787) (xy 189.453696 -244.473401)
			(xy 189.406616 -244.430644) (xy 189.36539 -244.382217) (xy 189.330694 -244.328916) (xy 189.3031 -244.271616)
			(xy 189.28306 -244.211257) (xy 189.270902 -244.148832) (xy 189.266828 -244.085364) (xy 187.428886 -244.085364)
			(xy 187.428458 -244.110681) (xy 187.421536 -244.16084) (xy 187.407816 -244.20958) (xy 187.387557 -244.255985)
			(xy 187.361139 -244.299181) (xy 187.32906 -244.338358) (xy 187.310776 -244.355874) (xy 187.301886 -244.364256)
			(xy 187.293504 -244.385846) (xy 187.302902 -244.489986) (xy 187.315094 -244.509798) (xy 187.325254 -244.516402)
			(xy 187.35135 -244.533501) (xy 187.399469 -244.573212) (xy 187.442224 -244.618648) (xy 187.47894 -244.66909)
			(xy 187.509036 -244.72374) (xy 187.532036 -244.781735) (xy 187.547576 -244.842158) (xy 187.555412 -244.904053)
			(xy 187.555886 -244.935248) (xy 187.55543 -244.966458) (xy 187.547605 -245.028385) (xy 187.532071 -245.088842)
			(xy 187.509075 -245.146871) (xy 187.47898 -245.201557) (xy 187.442261 -245.252034) (xy 187.399499 -245.297506)
			(xy 187.35137 -245.337253) (xy 187.325254 -245.354348) (xy 187.315094 -245.360698) (xy 187.302902 -245.38051)
			(xy 187.29325 -245.48465) (xy 187.301632 -245.506494) (xy 187.310522 -245.514622) (xy 187.328856 -245.53213)
			(xy 187.360997 -245.571335) (xy 187.387468 -245.614571) (xy 187.407771 -245.661024) (xy 187.421523 -245.70982)
			(xy 187.428465 -245.760038) (xy 187.428886 -245.785386) (xy 187.428473 -245.810704) (xy 187.421548 -245.860863)
			(xy 187.407825 -245.909604) (xy 187.387563 -245.956008) (xy 187.361143 -245.999204) (xy 187.329061 -246.03838)
			(xy 187.310776 -246.055896) (xy 187.301886 -246.064278) (xy 187.293504 -246.085868) (xy 187.302902 -246.190008)
			(xy 187.315094 -246.20982) (xy 187.325254 -246.216424) (xy 187.35136 -246.233508) (xy 187.399479 -246.273221)
			(xy 187.442234 -246.318659) (xy 187.478949 -246.369103) (xy 187.509043 -246.423756) (xy 187.532041 -246.481753)
			(xy 187.54758 -246.542178) (xy 187.555413 -246.604075) (xy 187.555886 -246.63527) (xy 187.555447 -246.666481)
			(xy 187.547619 -246.728409) (xy 187.532083 -246.788865) (xy 187.509084 -246.846895) (xy 187.478987 -246.901581)
			(xy 187.442266 -246.952058) (xy 187.399502 -246.997529) (xy 187.351371 -247.037275) (xy 187.325254 -247.05437)
			(xy 187.315094 -247.06072) (xy 187.302902 -247.080532) (xy 187.29325 -247.184672) (xy 187.301632 -247.206516)
			(xy 187.310522 -247.214644) (xy 187.328867 -247.232141) (xy 187.361007 -247.271349) (xy 187.387476 -247.314587)
			(xy 187.407777 -247.361042) (xy 187.421527 -247.409839) (xy 187.428466 -247.460059) (xy 187.428886 -247.485408)
			(xy 187.428488 -247.510726) (xy 187.421559 -247.560886) (xy 187.407834 -247.609627) (xy 187.387569 -247.656032)
			(xy 187.361146 -247.699227) (xy 187.329062 -247.738402) (xy 187.310776 -247.755918) (xy 187.301886 -247.7643)
			(xy 187.293504 -247.78589) (xy 187.302902 -247.89003) (xy 187.315094 -247.909842) (xy 187.325254 -247.916446)
			(xy 187.35137 -247.933515) (xy 187.399489 -247.973231) (xy 187.442243 -248.018671) (xy 187.478957 -248.069117)
			(xy 187.509051 -248.123772) (xy 187.532047 -248.181771) (xy 187.547584 -248.242198) (xy 187.555414 -248.304096)
			(xy 187.555886 -248.335292) (xy 187.555386 -248.366501) (xy 187.547568 -248.428426) (xy 187.532041 -248.488882)
			(xy 187.509051 -248.546911) (xy 187.478962 -248.601597) (xy 187.442249 -248.652075) (xy 187.399492 -248.697547)
			(xy 187.351368 -248.737296) (xy 187.325254 -248.754392) (xy 187.315094 -248.760742) (xy 187.302902 -248.780554)
			(xy 187.29325 -248.884694) (xy 187.301632 -248.906538) (xy 187.310522 -248.914666) (xy 187.328829 -248.932201)
			(xy 187.360973 -248.9714) (xy 187.387447 -249.014631) (xy 187.407754 -249.061079) (xy 187.421512 -249.109869)
			(xy 187.428461 -249.160084) (xy 187.428886 -249.18543) (xy 187.428435 -249.210746) (xy 187.421517 -249.260904)
			(xy 187.407802 -249.309644) (xy 187.387547 -249.356049) (xy 187.361133 -249.399246) (xy 187.329058 -249.438423)
			(xy 187.310776 -249.45594) (xy 187.301886 -249.464322) (xy 187.293504 -249.485912) (xy 187.302902 -249.590052)
			(xy 187.315094 -249.609864) (xy 187.325254 -249.616468) (xy 187.351379 -249.633525) (xy 187.399506 -249.673237)
			(xy 187.442267 -249.718675) (xy 187.478987 -249.769121) (xy 187.509085 -249.823777) (xy 187.532085 -249.881778)
			(xy 187.547623 -249.942208) (xy 187.555454 -250.00411) (xy 187.555453 -250.066505) (xy 187.54762 -250.128407)
			(xy 187.532081 -250.188836) (xy 187.509079 -250.246836) (xy 187.478979 -250.301491) (xy 187.442258 -250.351936)
			(xy 187.399495 -250.397373) (xy 187.351367 -250.437083) (xy 187.325254 -250.45416) (xy 187.315094 -250.460764)
			(xy 187.302902 -250.480576) (xy 187.293504 -250.584716) (xy 187.301886 -250.606306) (xy 187.310776 -250.614688)
			(xy 187.329069 -250.632195) (xy 187.361145 -250.671375) (xy 187.387561 -250.714574) (xy 187.40782 -250.76098)
			(xy 187.421542 -250.809721) (xy 187.428468 -250.85988) (xy 187.428886 -250.885198) (xy 187.428458 -250.910546)
			(xy 187.421525 -250.960765) (xy 187.407778 -251.009561) (xy 187.387473 -251.056014) (xy 187.360996 -251.099245)
			(xy 187.328845 -251.138442) (xy 187.310522 -251.155962) (xy 187.301632 -251.16409) (xy 187.29325 -251.185934)
			(xy 187.302902 -251.290074) (xy 187.315094 -251.309886) (xy 187.325254 -251.316236) (xy 187.351356 -251.333349)
			(xy 187.399476 -251.373101) (xy 187.44223 -251.418574) (xy 187.478944 -251.46905) (xy 187.509038 -251.523732)
			(xy 187.532036 -251.581756) (xy 187.547576 -251.642206) (xy 187.555412 -251.704128) (xy 187.555886 -251.735336)
			(xy 187.555406 -251.766533) (xy 187.547591 -251.828435) (xy 187.532065 -251.888866) (xy 187.509073 -251.946869)
			(xy 187.47898 -252.001525) (xy 187.442261 -252.05197) (xy 187.399499 -252.097404) (xy 187.351369 -252.137109)
			(xy 187.325254 -252.154182) (xy 187.315094 -252.160786) (xy 187.302902 -252.180598) (xy 187.293504 -252.284738)
			(xy 187.301886 -252.306328) (xy 187.310776 -252.31471) (xy 187.32908 -252.332207) (xy 187.361155 -252.371389)
			(xy 187.387569 -252.41459) (xy 187.407827 -252.460998) (xy 187.421546 -252.509741) (xy 187.428469 -252.559902)
			(xy 187.428886 -252.58522) (xy 187.428472 -252.610568) (xy 187.421537 -252.660789) (xy 187.407786 -252.709585)
			(xy 187.38748 -252.756037) (xy 187.361 -252.799268) (xy 187.328846 -252.838464) (xy 187.310522 -252.855984)
			(xy 187.301632 -252.864112) (xy 187.29325 -252.885956) (xy 187.302902 -252.990096) (xy 187.315094 -253.009908)
			(xy 187.325254 -253.016258) (xy 187.351366 -253.033357) (xy 187.399486 -253.073111) (xy 187.44224 -253.118586)
			(xy 187.478953 -253.169064) (xy 187.509045 -253.223748) (xy 187.532042 -253.281774) (xy 187.54758 -253.342226)
			(xy 187.555413 -253.40415) (xy 187.555886 -253.435358) (xy 187.555376 -253.468059) (xy 187.546766 -253.532892)
			(xy 187.529703 -253.59603) (xy 187.504484 -253.656374) (xy 187.471547 -253.712877) (xy 187.431464 -253.764557)
			(xy 187.408566 -253.78791) (xy 187.4012 -253.795276) (xy 187.39358 -253.813818) (xy 187.39358 -253.906782)
			(xy 187.4012 -253.925324) (xy 187.408566 -253.93269) (xy 187.431481 -253.956026) (xy 187.471563 -254.007709)
			(xy 187.504497 -254.064215) (xy 187.52971 -254.124563) (xy 187.546765 -254.187704) (xy 187.555364 -254.25254)
			(xy 187.555886 -254.285242) (xy 190.664338 -254.285242) (xy 190.664836 -254.254046) (xy 190.672652 -254.192146)
			(xy 190.688178 -254.131717) (xy 190.711169 -254.073716) (xy 190.741259 -254.01906) (xy 190.777975 -253.968615)
			(xy 190.820733 -253.923179) (xy 190.868858 -253.883471) (xy 190.89497 -253.866396) (xy 190.90513 -253.859792)
			(xy 190.917322 -253.83998) (xy 190.92672 -253.73584) (xy 190.918338 -253.71425) (xy 190.909448 -253.705868)
			(xy 190.891138 -253.688377) (xy 190.859063 -253.649194) (xy 190.832648 -253.605992) (xy 190.812392 -253.559583)
			(xy 190.798674 -253.510839) (xy 190.791754 -253.460677) (xy 190.791338 -253.435358) (xy 190.791729 -253.410009)
			(xy 190.798668 -253.359787) (xy 190.812423 -253.31099) (xy 190.832734 -253.264538) (xy 190.859218 -253.221307)
			(xy 190.891376 -253.182113) (xy 190.909702 -253.164594) (xy 190.918592 -253.156466) (xy 190.926974 -253.134622)
			(xy 190.917322 -253.030482) (xy 190.90513 -253.01067) (xy 190.89497 -253.00432) (xy 190.868854 -252.987228)
			(xy 190.820733 -252.947474) (xy 190.777978 -252.901998) (xy 190.741265 -252.851519) (xy 190.711173 -252.796834)
			(xy 190.688177 -252.738807) (xy 190.672641 -252.678354) (xy 190.66481 -252.616429) (xy 190.664338 -252.58522)
			(xy 190.664819 -252.554024) (xy 190.672638 -252.492123) (xy 190.688166 -252.431693) (xy 190.711159 -252.373692)
			(xy 190.741252 -252.319036) (xy 190.77797 -252.268591) (xy 190.82073 -252.223156) (xy 190.868857 -252.183448)
			(xy 190.89497 -252.166374) (xy 190.90513 -252.15977) (xy 190.917322 -252.139958) (xy 190.92672 -252.035818)
			(xy 190.918338 -252.014228) (xy 190.909448 -252.005846) (xy 190.891176 -251.988317) (xy 190.859097 -251.949143)
			(xy 190.832678 -251.905948) (xy 190.812415 -251.859547) (xy 190.798689 -251.810809) (xy 190.791759 -251.760653)
			(xy 190.791338 -251.735336) (xy 190.791715 -251.709986) (xy 190.798657 -251.659764) (xy 190.812414 -251.610967)
			(xy 190.832728 -251.564515) (xy 190.859214 -251.521284) (xy 190.891375 -251.48209) (xy 190.909702 -251.464572)
			(xy 190.918592 -251.456444) (xy 190.926974 -251.4346) (xy 190.917322 -251.33046) (xy 190.90513 -251.310648)
			(xy 190.89497 -251.304298) (xy 190.868843 -251.287221) (xy 190.820723 -251.247464) (xy 190.777969 -251.201987)
			(xy 190.741256 -251.151506) (xy 190.711165 -251.096818) (xy 190.688171 -251.038789) (xy 190.672637 -250.978334)
			(xy 190.664808 -250.916408) (xy 190.664338 -250.885198) (xy 190.664802 -250.854001) (xy 190.672623 -250.792099)
			(xy 190.688154 -250.73167) (xy 190.71115 -250.673668) (xy 190.741245 -250.619013) (xy 190.777965 -250.568568)
			(xy 190.820727 -250.523133) (xy 190.868856 -250.483426) (xy 190.89497 -250.466352) (xy 190.90513 -250.459748)
			(xy 190.917322 -250.439936) (xy 190.92672 -250.335796) (xy 190.918338 -250.314206) (xy 190.909448 -250.305824)
			(xy 190.889535 -250.286675) (xy 190.855065 -250.243503) (xy 190.827421 -250.195673) (xy 190.807221 -250.144255)
			(xy 190.794916 -250.090399) (xy 190.790783 -250.03531) (xy 190.794914 -249.98022) (xy 190.807215 -249.926363)
			(xy 190.827413 -249.874944) (xy 190.855054 -249.827112) (xy 190.889522 -249.783939) (xy 190.909448 -249.764804)
			(xy 190.918338 -249.756422) (xy 190.92672 -249.734832) (xy 190.917322 -249.630692) (xy 190.90513 -249.61088)
			(xy 190.89497 -249.604276) (xy 190.868847 -249.587218) (xy 190.820731 -249.547498) (xy 190.77798 -249.502055)
			(xy 190.741268 -249.451607) (xy 190.711176 -249.396951) (xy 190.68818 -249.338951) (xy 190.672643 -249.278525)
			(xy 190.664811 -249.216626) (xy 190.664338 -249.18543) (xy 190.664766 -249.154219) (xy 190.672594 -249.09229)
			(xy 190.688131 -249.031833) (xy 190.711131 -248.973802) (xy 190.74123 -248.919117) (xy 190.777953 -248.86864)
			(xy 190.820719 -248.823169) (xy 190.868852 -248.783424) (xy 190.89497 -248.76633) (xy 190.90513 -248.75998)
			(xy 190.917322 -248.740168) (xy 190.926974 -248.636028) (xy 190.918592 -248.614184) (xy 190.909702 -248.606056)
			(xy 190.891361 -248.588554) (xy 190.85922 -248.549348) (xy 190.83275 -248.506111) (xy 190.812448 -248.459656)
			(xy 190.798698 -248.41086) (xy 190.791758 -248.36064) (xy 190.791338 -248.335292) (xy 190.791729 -248.309973)
			(xy 190.798658 -248.259813) (xy 190.812384 -248.211072) (xy 190.83265 -248.164667) (xy 190.859075 -248.121471)
			(xy 190.891161 -248.082297) (xy 190.909448 -248.064782) (xy 190.918338 -248.0564) (xy 190.92672 -248.03481)
			(xy 190.917322 -247.93067) (xy 190.90513 -247.910858) (xy 190.89497 -247.904254) (xy 190.868837 -247.887211)
			(xy 190.820721 -247.847489) (xy 190.77797 -247.802044) (xy 190.741259 -247.751593) (xy 190.711169 -247.696935)
			(xy 190.688174 -247.638933) (xy 190.672639 -247.578505) (xy 190.66481 -247.516605) (xy 190.664338 -247.485408)
			(xy 190.664827 -247.454199) (xy 190.672646 -247.392272) (xy 190.688173 -247.331816) (xy 190.711164 -247.273787)
			(xy 190.741255 -247.219101) (xy 190.77797 -247.168623) (xy 190.820729 -247.123151) (xy 190.868855 -247.083403)
			(xy 190.89497 -247.066308) (xy 190.90513 -247.059958) (xy 190.917322 -247.040146) (xy 190.926974 -246.936006)
			(xy 190.918592 -246.914162) (xy 190.909702 -246.906034) (xy 190.891399 -246.888494) (xy 190.859255 -246.849296)
			(xy 190.832779 -246.806067) (xy 190.812471 -246.75962) (xy 190.798712 -246.71083) (xy 190.791763 -246.660616)
			(xy 190.791338 -246.63527) (xy 190.791781 -246.609953) (xy 190.798699 -246.559795) (xy 190.812416 -246.511055)
			(xy 190.832672 -246.46465) (xy 190.859088 -246.421453) (xy 190.891165 -246.382277) (xy 190.909448 -246.36476)
			(xy 190.918338 -246.356378) (xy 190.92672 -246.334788) (xy 190.917322 -246.230648) (xy 190.90513 -246.210836)
			(xy 190.89497 -246.204232) (xy 190.868872 -246.187137) (xy 190.820757 -246.147422) (xy 190.778004 -246.101984)
			(xy 190.74129 -246.051542) (xy 190.711195 -245.996891) (xy 190.688195 -245.938897) (xy 190.672653 -245.878475)
			(xy 190.664814 -245.81658) (xy 190.664338 -245.785386) (xy 190.66481 -245.754176) (xy 190.672631 -245.692249)
			(xy 190.688161 -245.631793) (xy 190.711155 -245.573763) (xy 190.741248 -245.519077) (xy 190.777965 -245.468599)
			(xy 190.820726 -245.423128) (xy 190.868854 -245.383381) (xy 190.89497 -245.366286) (xy 190.90513 -245.359936)
			(xy 190.917322 -245.340124) (xy 190.926974 -245.235984) (xy 190.918592 -245.21414) (xy 190.909702 -245.206012)
			(xy 190.891389 -245.188483) (xy 190.859245 -245.149283) (xy 190.832771 -245.106051) (xy 190.812464 -245.059602)
			(xy 190.798708 -245.01081) (xy 190.791761 -244.960595) (xy 190.791338 -244.935248) (xy 190.791766 -244.909931)
			(xy 190.798688 -244.859772) (xy 190.812407 -244.811031) (xy 190.832666 -244.764627) (xy 190.859084 -244.72143)
			(xy 190.891164 -244.682254) (xy 190.909448 -244.664738) (xy 190.918338 -244.656356) (xy 190.92672 -244.634766)
			(xy 190.917322 -244.530626) (xy 190.90513 -244.510814) (xy 190.89497 -244.50421) (xy 190.868862 -244.48713)
			(xy 190.820747 -244.447413) (xy 190.777994 -244.401973) (xy 190.741281 -244.351528) (xy 190.711188 -244.296875)
			(xy 190.688189 -244.238879) (xy 190.672649 -244.178455) (xy 190.664813 -244.116559) (xy 190.664338 -244.085364)
			(xy 190.664792 -244.054154) (xy 190.672617 -243.992226) (xy 190.688149 -243.931769) (xy 190.711145 -243.873739)
			(xy 190.741241 -243.819053) (xy 190.77796 -243.768576) (xy 190.820723 -243.723105) (xy 190.868854 -243.683359)
			(xy 190.89497 -243.666264) (xy 190.90513 -243.659914) (xy 190.917322 -243.640102) (xy 190.926974 -243.535962)
			(xy 190.918592 -243.514118) (xy 190.909702 -243.50599) (xy 190.891378 -243.488472) (xy 190.859235 -243.449269)
			(xy 190.832762 -243.406035) (xy 190.812458 -243.359584) (xy 190.798704 -243.310791) (xy 190.79176 -243.260573)
			(xy 190.791338 -243.235226) (xy 190.791752 -243.209908) (xy 190.798676 -243.159749) (xy 190.812398 -243.111008)
			(xy 190.83266 -243.064603) (xy 190.859081 -243.021407) (xy 190.891163 -242.982232) (xy 190.909448 -242.964716)
			(xy 190.918338 -242.956334) (xy 190.92672 -242.934744) (xy 190.917322 -242.830604) (xy 190.90513 -242.810792)
			(xy 190.89497 -242.804188) (xy 190.868852 -242.787122) (xy 190.820737 -242.747403) (xy 190.777985 -242.701961)
			(xy 190.741273 -242.651514) (xy 190.71118 -242.59686) (xy 190.688183 -242.538861) (xy 190.672645 -242.478435)
			(xy 190.664812 -242.416538) (xy 190.664338 -242.385342) (xy 190.664775 -242.354131) (xy 190.672602 -242.292203)
			(xy 190.688138 -242.231745) (xy 190.711136 -242.173715) (xy 190.741234 -242.11903) (xy 190.777956 -242.068552)
			(xy 190.82072 -242.023082) (xy 190.868853 -241.983336) (xy 190.89497 -241.966242) (xy 190.90513 -241.959892)
			(xy 190.917322 -241.94008) (xy 190.926974 -241.83594) (xy 190.918592 -241.814096) (xy 190.909702 -241.805968)
			(xy 190.891367 -241.78846) (xy 190.859226 -241.749256) (xy 190.832754 -241.706019) (xy 190.812451 -241.659566)
			(xy 190.7987 -241.610771) (xy 190.791758 -241.560552) (xy 190.791338 -241.535204) (xy 190.791737 -241.509886)
			(xy 190.798664 -241.459725) (xy 190.812389 -241.410984) (xy 190.832654 -241.36458) (xy 190.859077 -241.321384)
			(xy 190.891161 -241.282209) (xy 190.909448 -241.264694) (xy 190.918338 -241.256312) (xy 190.92672 -241.234722)
			(xy 190.917322 -241.130582) (xy 190.90513 -241.11077) (xy 190.89497 -241.104166) (xy 190.868842 -241.087115)
			(xy 190.820727 -241.047394) (xy 190.777975 -241.00195) (xy 190.741264 -240.951501) (xy 190.711173 -240.896844)
			(xy 190.688177 -240.838843) (xy 190.672641 -240.778416) (xy 190.66481 -240.716516) (xy 190.664338 -240.68532)
			(xy 190.664827 -240.654157) (xy 190.672639 -240.592323) (xy 190.688139 -240.531955) (xy 190.711082 -240.474007)
			(xy 190.741108 -240.41939) (xy 190.777742 -240.368968) (xy 190.820407 -240.323534) (xy 190.868429 -240.283806)
			(xy 190.921053 -240.250411) (xy 190.977447 -240.223874) (xy 191.036722 -240.204614) (xy 191.097943 -240.192935)
			(xy 191.160146 -240.189022) (xy 191.222349 -240.192935) (xy 191.28357 -240.204614) (xy 191.342845 -240.223874)
			(xy 191.399239 -240.250411) (xy 191.451863 -240.283806) (xy 191.499885 -240.323534) (xy 191.54255 -240.368968)
			(xy 191.579184 -240.41939) (xy 191.60921 -240.474007) (xy 191.632153 -240.531955) (xy 191.647653 -240.592323)
			(xy 191.655465 -240.654157) (xy 191.655954 -240.68532) (xy 195.619131 -240.68532) (xy 195.623066 -240.631549)
			(xy 195.634789 -240.578925) (xy 195.654049 -240.528568) (xy 195.680435 -240.481551) (xy 195.713387 -240.438878)
			(xy 195.7522 -240.401457) (xy 195.796048 -240.370087) (xy 195.843996 -240.345435) (xy 195.895023 -240.328027)
			(xy 195.948041 -240.318234) (xy 196.00192 -240.316265) (xy 196.055511 -240.322162) (xy 196.107672 -240.335798)
			(xy 196.157292 -240.356885) (xy 196.203313 -240.384971) (xy 196.244755 -240.419459) (xy 196.280733 -240.459613)
			(xy 196.310481 -240.504577) (xy 196.333366 -240.553394) (xy 196.348898 -240.605023) (xy 196.356748 -240.658363)
			(xy 196.35724 -240.68532) (xy 196.356748 -240.712277) (xy 196.348898 -240.765617) (xy 196.333366 -240.817246)
			(xy 196.310481 -240.866063) (xy 196.280733 -240.911027) (xy 196.244755 -240.951181) (xy 196.203313 -240.985669)
			(xy 196.157292 -241.013755) (xy 196.107672 -241.034842) (xy 196.055511 -241.048478) (xy 196.00192 -241.054375)
			(xy 195.948041 -241.052406) (xy 195.895023 -241.042613) (xy 195.843996 -241.025205) (xy 195.796048 -241.000553)
			(xy 195.7522 -240.969183) (xy 195.713387 -240.931762) (xy 195.680435 -240.889089) (xy 195.654049 -240.842072)
			(xy 195.634789 -240.791715) (xy 195.623066 -240.739091) (xy 195.619131 -240.68532) (xy 191.655954 -240.68532)
			(xy 191.655508 -240.716518) (xy 191.647684 -240.77842) (xy 191.632151 -240.83885) (xy 191.609153 -240.896852)
			(xy 191.579055 -240.951508) (xy 191.542333 -241.001952) (xy 191.499568 -241.047387) (xy 191.451437 -241.087093)
			(xy 191.425322 -241.104166) (xy 191.415162 -241.11077) (xy 191.40297 -241.130582) (xy 191.393572 -241.234722)
			(xy 191.401954 -241.256312) (xy 191.410844 -241.264694) (xy 191.429134 -241.282205) (xy 191.461212 -241.321383)
			(xy 191.487629 -241.364581) (xy 191.507888 -241.410987) (xy 191.52161 -241.459727) (xy 191.528536 -241.509886)
			(xy 191.528954 -241.535204) (xy 191.52854 -241.560553) (xy 191.521606 -241.610773) (xy 191.507856 -241.65957)
			(xy 191.48755 -241.706022) (xy 191.461069 -241.749254) (xy 191.428915 -241.788449) (xy 191.41059 -241.805968)
			(xy 191.4017 -241.814096) (xy 191.393318 -241.83594) (xy 191.40297 -241.94008) (xy 191.415162 -241.959892)
			(xy 191.425322 -241.966242) (xy 191.451419 -241.983362) (xy 191.49954 -242.023112) (xy 191.542296 -242.068583)
			(xy 191.579011 -242.119058) (xy 191.609106 -242.173739) (xy 191.632105 -242.231763) (xy 191.647644 -242.292213)
			(xy 191.65548 -242.354134) (xy 191.655954 -242.385342) (xy 191.655447 -242.416538) (xy 191.647633 -242.478438)
			(xy 191.632109 -242.538866) (xy 191.60912 -242.596868) (xy 191.57903 -242.651524) (xy 191.542316 -242.701969)
			(xy 191.499558 -242.747405) (xy 191.451434 -242.787113) (xy 191.425322 -242.804188) (xy 191.415162 -242.810792)
			(xy 191.40297 -242.830604) (xy 191.393572 -242.934744) (xy 191.401954 -242.956334) (xy 191.410844 -242.964716)
			(xy 191.429145 -242.982216) (xy 191.461221 -243.021397) (xy 191.487637 -243.064597) (xy 191.507895 -243.111005)
			(xy 191.521614 -243.159747) (xy 191.528537 -243.209908) (xy 191.528954 -243.235226) (xy 191.528554 -243.260575)
			(xy 191.521618 -243.310796) (xy 191.507865 -243.359593) (xy 191.487556 -243.406045) (xy 191.461073 -243.449277)
			(xy 191.428916 -243.488471) (xy 191.41059 -243.50599) (xy 191.4017 -243.514118) (xy 191.393318 -243.535962)
			(xy 191.40297 -243.640102) (xy 191.415162 -243.659914) (xy 191.425322 -243.666264) (xy 191.451429 -243.68337)
			(xy 191.49955 -243.723121) (xy 191.542306 -243.768595) (xy 191.57902 -243.819072) (xy 191.609113 -243.873755)
			(xy 191.63211 -243.931781) (xy 191.647648 -243.992232) (xy 191.655481 -244.054156) (xy 191.655954 -244.085364)
			(xy 191.655464 -244.11656) (xy 191.647647 -244.178461) (xy 191.63212 -244.23889) (xy 191.609129 -244.296892)
			(xy 191.579037 -244.351547) (xy 191.54232 -244.401992) (xy 191.499561 -244.447428) (xy 191.451435 -244.487136)
			(xy 191.425322 -244.50421) (xy 191.415162 -244.510814) (xy 191.40297 -244.530626) (xy 191.393572 -244.634766)
			(xy 191.401954 -244.656356) (xy 191.410844 -244.664738) (xy 191.429107 -244.682276) (xy 191.461187 -244.721448)
			(xy 191.487608 -244.764641) (xy 191.507872 -244.811041) (xy 191.5216 -244.859777) (xy 191.528532 -244.909932)
			(xy 191.528954 -244.935248) (xy 191.528569 -244.960598) (xy 191.521629 -245.010819) (xy 191.507874 -245.059617)
			(xy 191.487562 -245.106069) (xy 191.461076 -245.1493) (xy 191.428917 -245.188494) (xy 191.41059 -245.206012)
			(xy 191.4017 -245.21414) (xy 191.393318 -245.235984) (xy 191.40297 -245.340124) (xy 191.415162 -245.359936)
			(xy 191.425322 -245.366286) (xy 191.451439 -245.383377) (xy 191.49956 -245.423131) (xy 191.542315 -245.468606)
			(xy 191.579029 -245.519085) (xy 191.609121 -245.573771) (xy 191.632116 -245.631798) (xy 191.647652 -245.692252)
			(xy 191.655483 -245.754177) (xy 191.655954 -245.785386) (xy 191.655481 -245.816583) (xy 191.647662 -245.878484)
			(xy 191.632132 -245.938914) (xy 191.609138 -245.996915) (xy 191.579044 -246.051571) (xy 191.542325 -246.102016)
			(xy 191.499564 -246.147451) (xy 191.451436 -246.187158) (xy 191.425322 -246.204232) (xy 191.415162 -246.210836)
			(xy 191.40297 -246.230648) (xy 191.393572 -246.334788) (xy 191.401954 -246.356378) (xy 191.410844 -246.36476)
			(xy 191.429117 -246.382287) (xy 191.461197 -246.421462) (xy 191.487616 -246.464657) (xy 191.507879 -246.511059)
			(xy 191.521604 -246.559796) (xy 191.528534 -246.609953) (xy 191.528954 -246.63527) (xy 191.528584 -246.66062)
			(xy 191.521641 -246.710842) (xy 191.507883 -246.75964) (xy 191.487568 -246.806092) (xy 191.46108 -246.849323)
			(xy 191.428918 -246.888516) (xy 191.41059 -246.906034) (xy 191.4017 -246.914162) (xy 191.393318 -246.936006)
			(xy 191.40297 -247.040146) (xy 191.415162 -247.059958) (xy 191.425322 -247.066308) (xy 191.451449 -247.083384)
			(xy 191.49957 -247.12314) (xy 191.542325 -247.168618) (xy 191.579037 -247.219099) (xy 191.609128 -247.273787)
			(xy 191.632122 -247.331816) (xy 191.647656 -247.392272) (xy 191.655484 -247.454198) (xy 191.655954 -247.485408)
			(xy 191.655499 -247.516605) (xy 191.647676 -247.578507) (xy 191.632144 -247.638937) (xy 191.609148 -247.696939)
			(xy 191.579051 -247.751595) (xy 191.54233 -247.802039) (xy 191.499566 -247.847474) (xy 191.451437 -247.88718)
			(xy 191.425322 -247.904254) (xy 191.415162 -247.910858) (xy 191.40297 -247.93067) (xy 191.393572 -248.03481)
			(xy 191.401954 -248.0564) (xy 191.410844 -248.064782) (xy 191.429128 -248.082299) (xy 191.461206 -248.121476)
			(xy 191.487624 -248.164672) (xy 191.507885 -248.211077) (xy 191.521608 -248.259816) (xy 191.528535 -248.309975)
			(xy 191.528954 -248.335292) (xy 191.528532 -248.36064) (xy 191.5216 -248.41086) (xy 191.507851 -248.459657)
			(xy 191.487546 -248.506109) (xy 191.461067 -248.549341) (xy 191.428914 -248.588537) (xy 191.41059 -248.606056)
			(xy 191.4017 -248.614184) (xy 191.393318 -248.636028) (xy 191.40297 -248.740168) (xy 191.415162 -248.75998)
			(xy 191.425322 -248.76633) (xy 191.451414 -248.783458) (xy 191.499535 -248.823207) (xy 191.542291 -248.868677)
			(xy 191.579006 -248.919151) (xy 191.609102 -248.97383) (xy 191.632101 -249.031853) (xy 191.647642 -249.092302)
			(xy 191.655479 -249.154223) (xy 191.655954 -249.18543) (xy 191.655438 -249.216625) (xy 191.647625 -249.278525)
			(xy 191.632102 -249.338954) (xy 191.609114 -249.396955) (xy 191.579026 -249.451611) (xy 191.542313 -249.502056)
			(xy 191.499557 -249.547493) (xy 191.451434 -249.587201) (xy 191.425322 -249.604276) (xy 191.415162 -249.61088)
			(xy 191.40297 -249.630692) (xy 191.393572 -249.734832) (xy 191.401954 -249.756422) (xy 191.410844 -249.764804)
			(xy 191.430781 -249.783928) (xy 191.465242 -249.827106) (xy 191.492878 -249.874941) (xy 191.513071 -249.926362)
			(xy 191.52537 -249.98022) (xy 191.5295 -250.03531) (xy 191.525368 -250.090399) (xy 191.513066 -250.144256)
			(xy 191.49287 -250.195676) (xy 191.465231 -250.24351) (xy 191.430768 -250.286686) (xy 191.410844 -250.305824)
			(xy 191.401954 -250.314206) (xy 191.393572 -250.335796) (xy 191.40297 -250.439936) (xy 191.415162 -250.459748)
			(xy 191.425322 -250.466352) (xy 191.451456 -250.483394) (xy 191.499572 -250.523116) (xy 191.542323 -250.568561)
			(xy 191.579034 -250.619012) (xy 191.609125 -250.67367) (xy 191.632119 -250.731672) (xy 191.647654 -250.792101)
			(xy 191.655483 -250.854001) (xy 191.655954 -250.885198) (xy 191.655474 -250.916407) (xy 191.647654 -250.978334)
			(xy 191.632125 -251.038791) (xy 191.609133 -251.096821) (xy 191.579041 -251.151507) (xy 191.542325 -251.201985)
			(xy 191.499565 -251.247456) (xy 191.451437 -251.287203) (xy 191.425322 -251.304298) (xy 191.415162 -251.310648)
			(xy 191.40297 -251.33046) (xy 191.393318 -251.4346) (xy 191.4017 -251.456444) (xy 191.41059 -251.464572)
			(xy 191.428894 -251.48211) (xy 191.461039 -251.521308) (xy 191.487515 -251.564538) (xy 191.507823 -251.610985)
			(xy 191.521581 -251.659775) (xy 191.52853 -251.70999) (xy 191.528954 -251.735336) (xy 191.528518 -251.760653)
			(xy 191.521598 -251.810812) (xy 191.507881 -251.859552) (xy 191.487623 -251.905957) (xy 191.461206 -251.949154)
			(xy 191.429128 -251.98833) (xy 191.410844 -252.005846) (xy 191.401954 -252.014228) (xy 191.393572 -252.035818)
			(xy 191.40297 -252.139958) (xy 191.415162 -252.15977) (xy 191.425322 -252.166374) (xy 191.451421 -252.183468)
			(xy 191.499537 -252.223182) (xy 191.542289 -252.26862) (xy 191.579003 -252.319063) (xy 191.609098 -252.373714)
			(xy 191.632098 -252.431708) (xy 191.64764 -252.492131) (xy 191.655478 -252.554026) (xy 191.655954 -252.58522)
			(xy 191.655491 -252.61643) (xy 191.647668 -252.678358) (xy 191.632137 -252.738814) (xy 191.609143 -252.796844)
			(xy 191.579048 -252.85153) (xy 191.54233 -252.902008) (xy 191.499568 -252.947479) (xy 191.451438 -252.987225)
			(xy 191.425322 -253.00432) (xy 191.415162 -253.01067) (xy 191.40297 -253.030482) (xy 191.393318 -253.134622)
			(xy 191.4017 -253.156466) (xy 191.41059 -253.164594) (xy 191.428905 -253.182122) (xy 191.461049 -253.221322)
			(xy 191.487523 -253.264554) (xy 191.507829 -253.311003) (xy 191.521585 -253.359795) (xy 191.528531 -253.410011)
			(xy 191.528954 -253.435358) (xy 191.528532 -253.460675) (xy 191.52161 -253.510835) (xy 191.507889 -253.559576)
			(xy 191.487629 -253.60598) (xy 191.46121 -253.649177) (xy 191.429129 -253.688352) (xy 191.410844 -253.705868)
			(xy 191.401954 -253.71425) (xy 191.393572 -253.73584) (xy 191.40297 -253.83998) (xy 191.415162 -253.859792)
			(xy 191.425322 -253.866396) (xy 191.451431 -253.883475) (xy 191.499547 -253.923192) (xy 191.542299 -253.968632)
			(xy 191.579012 -254.019077) (xy 191.609106 -254.07373) (xy 191.632104 -254.131726) (xy 191.647644 -254.19215)
			(xy 191.655479 -254.254047) (xy 191.655954 -254.285242) (xy 194.108324 -254.285242) (xy 194.108861 -254.252542)
			(xy 194.117469 -254.187711) (xy 194.134529 -254.124575) (xy 194.159743 -254.064231) (xy 194.192674 -254.007727)
			(xy 194.23275 -253.956044) (xy 194.255644 -253.93269) (xy 194.26301 -253.925324) (xy 194.27063 -253.906782)
			(xy 194.27063 -253.813818) (xy 194.26301 -253.795276) (xy 194.255644 -253.78791) (xy 194.232731 -253.764572)
			(xy 194.192649 -253.71289) (xy 194.159714 -253.656384) (xy 194.1345 -253.596036) (xy 194.117445 -253.532895)
			(xy 194.108846 -253.46806) (xy 194.108324 -253.435358) (xy 194.10878 -253.404148) (xy 194.116605 -253.34222)
			(xy 194.132138 -253.281764) (xy 194.155134 -253.223734) (xy 194.185229 -253.169048) (xy 194.221948 -253.118571)
			(xy 194.26471 -253.0731) (xy 194.31284 -253.033353) (xy 194.338956 -253.016258) (xy 194.349116 -253.009908)
			(xy 194.361308 -252.990096) (xy 194.37096 -252.885956) (xy 194.362578 -252.864112) (xy 194.353688 -252.855984)
			(xy 194.335358 -252.838471) (xy 194.303217 -252.799267) (xy 194.276745 -252.756032) (xy 194.256441 -252.70958)
			(xy 194.242689 -252.660786) (xy 194.235746 -252.610568) (xy 194.235324 -252.58522) (xy 194.235738 -252.559902)
			(xy 194.242663 -252.509743) (xy 194.256385 -252.461002) (xy 194.276647 -252.414597) (xy 194.303067 -252.371401)
			(xy 194.335149 -252.332226) (xy 194.353434 -252.31471) (xy 194.362324 -252.306328) (xy 194.370706 -252.284738)
			(xy 194.361308 -252.180598) (xy 194.349116 -252.160786) (xy 194.338956 -252.154182) (xy 194.312855 -252.137091)
			(xy 194.264736 -252.097379) (xy 194.22198 -252.051942) (xy 194.185265 -252.001499) (xy 194.15517 -251.946847)
			(xy 194.132171 -251.888851) (xy 194.116631 -251.828427) (xy 194.108797 -251.766531) (xy 194.108324 -251.735336)
			(xy 194.108763 -251.704125) (xy 194.11659 -251.642197) (xy 194.132126 -251.58174) (xy 194.155125 -251.52371)
			(xy 194.185222 -251.469025) (xy 194.221943 -251.418548) (xy 194.264708 -251.373077) (xy 194.312839 -251.333331)
			(xy 194.338956 -251.316236) (xy 194.349116 -251.309886) (xy 194.361308 -251.290074) (xy 194.37096 -251.185934)
			(xy 194.362578 -251.16409) (xy 194.353688 -251.155962) (xy 194.335348 -251.13846) (xy 194.303207 -251.099254)
			(xy 194.276737 -251.056016) (xy 194.256435 -251.009562) (xy 194.242685 -250.960766) (xy 194.235744 -250.910546)
			(xy 194.235324 -250.885198) (xy 194.235723 -250.85988) (xy 194.242651 -250.80972) (xy 194.256376 -250.760979)
			(xy 194.276641 -250.714574) (xy 194.303064 -250.671378) (xy 194.335148 -250.632203) (xy 194.353434 -250.614688)
			(xy 194.362324 -250.606306) (xy 194.370706 -250.584716) (xy 194.361308 -250.480576) (xy 194.349116 -250.460764)
			(xy 194.338956 -250.45416) (xy 194.312856 -250.437065) (xy 194.26473 -250.397357) (xy 194.221969 -250.351922)
			(xy 194.185248 -250.30148) (xy 194.155149 -250.246827) (xy 194.132148 -250.188829) (xy 194.116608 -250.128403)
			(xy 194.108776 -250.066504) (xy 194.108775 -250.004111) (xy 194.116605 -249.942212) (xy 194.132143 -249.881785)
			(xy 194.155143 -249.823786) (xy 194.18524 -249.769133) (xy 194.221959 -249.718689) (xy 194.264719 -249.673254)
			(xy 194.312844 -249.633544) (xy 194.338956 -249.616468) (xy 194.349116 -249.609864) (xy 194.361308 -249.590052)
			(xy 194.370706 -249.485912) (xy 194.362324 -249.464322) (xy 194.353434 -249.45594) (xy 194.335156 -249.438417)
			(xy 194.303078 -249.399241) (xy 194.27666 -249.356045) (xy 194.256398 -249.309642) (xy 194.242674 -249.260904)
			(xy 194.235744 -249.210747) (xy 194.235324 -249.18543) (xy 194.235701 -249.16008) (xy 194.242643 -249.109858)
			(xy 194.256401 -249.061061) (xy 194.276715 -249.014609) (xy 194.303201 -248.971379) (xy 194.335361 -248.932185)
			(xy 194.353688 -248.914666) (xy 194.362578 -248.906538) (xy 194.37096 -248.884694) (xy 194.361308 -248.780554)
			(xy 194.349116 -248.760742) (xy 194.338956 -248.754392) (xy 194.312824 -248.737323) (xy 194.264704 -248.697566)
			(xy 194.22195 -248.652086) (xy 194.185238 -248.601604) (xy 194.155148 -248.546915) (xy 194.132155 -248.488885)
			(xy 194.116622 -248.428429) (xy 194.108794 -248.366502) (xy 194.108324 -248.335292) (xy 194.108743 -248.304093)
			(xy 194.116567 -248.242188) (xy 194.132102 -248.181756) (xy 194.155102 -248.123752) (xy 194.185204 -248.069096)
			(xy 194.221931 -248.018652) (xy 194.264701 -247.97322) (xy 194.312838 -247.933517) (xy 194.338956 -247.916446)
			(xy 194.349116 -247.909842) (xy 194.361308 -247.89003) (xy 194.370706 -247.78589) (xy 194.362324 -247.7643)
			(xy 194.353434 -247.755918) (xy 194.335146 -247.738406) (xy 194.303069 -247.699227) (xy 194.276652 -247.656029)
			(xy 194.256392 -247.609624) (xy 194.24267 -247.560884) (xy 194.235743 -247.510725) (xy 194.235324 -247.485408)
			(xy 194.235753 -247.46006) (xy 194.242685 -247.40984) (xy 194.256432 -247.361044) (xy 194.276736 -247.314592)
			(xy 194.303213 -247.27136) (xy 194.335365 -247.232164) (xy 194.353688 -247.214644) (xy 194.362578 -247.206516)
			(xy 194.37096 -247.184672) (xy 194.361308 -247.080532) (xy 194.349116 -247.06072) (xy 194.338956 -247.05437)
			(xy 194.312859 -247.037249) (xy 194.264739 -246.997499) (xy 194.221984 -246.952027) (xy 194.185269 -246.901552)
			(xy 194.155175 -246.846872) (xy 194.132176 -246.788848) (xy 194.116635 -246.728399) (xy 194.108799 -246.666478)
			(xy 194.108324 -246.63527) (xy 194.108804 -246.604073) (xy 194.116618 -246.542171) (xy 194.132144 -246.48174)
			(xy 194.155136 -246.423737) (xy 194.185229 -246.36908) (xy 194.221948 -246.318635) (xy 194.264711 -246.273201)
			(xy 194.312841 -246.233496) (xy 194.338956 -246.216424) (xy 194.349116 -246.20982) (xy 194.361308 -246.190008)
			(xy 194.370706 -246.085868) (xy 194.362324 -246.064278) (xy 194.353434 -246.055896) (xy 194.335135 -246.038394)
			(xy 194.303059 -245.999213) (xy 194.276644 -245.956013) (xy 194.256386 -245.909606) (xy 194.242666 -245.860864)
			(xy 194.235741 -245.810704) (xy 194.235324 -245.785386) (xy 194.235739 -245.760038) (xy 194.242673 -245.709817)
			(xy 194.256424 -245.661021) (xy 194.27673 -245.614569) (xy 194.30321 -245.571337) (xy 194.335364 -245.532142)
			(xy 194.353688 -245.514622) (xy 194.362578 -245.506494) (xy 194.37096 -245.48465) (xy 194.361308 -245.38051)
			(xy 194.349116 -245.360698) (xy 194.338956 -245.354348) (xy 194.312849 -245.337242) (xy 194.264729 -245.297489)
			(xy 194.221974 -245.252016) (xy 194.185261 -245.201539) (xy 194.155167 -245.146856) (xy 194.13217 -245.088831)
			(xy 194.116632 -245.028379) (xy 194.108797 -244.966456) (xy 194.108324 -244.935248) (xy 194.108787 -244.904051)
			(xy 194.116604 -244.842147) (xy 194.132132 -244.781716) (xy 194.155126 -244.723713) (xy 194.185222 -244.669056)
			(xy 194.221943 -244.618612) (xy 194.264708 -244.573178) (xy 194.31284 -244.533474) (xy 194.338956 -244.516402)
			(xy 194.349116 -244.509798) (xy 194.361308 -244.489986) (xy 194.370706 -244.385846) (xy 194.362324 -244.364256)
			(xy 194.353434 -244.355874) (xy 194.335124 -244.338383) (xy 194.303049 -244.2992) (xy 194.276635 -244.255998)
			(xy 194.256379 -244.209588) (xy 194.242661 -244.160845) (xy 194.23574 -244.110683) (xy 194.235324 -244.085364)
			(xy 194.235724 -244.060015) (xy 194.242662 -244.009794) (xy 194.256415 -243.960998) (xy 194.276724 -243.914546)
			(xy 194.303207 -243.871314) (xy 194.335363 -243.832119) (xy 194.353688 -243.8146) (xy 194.362578 -243.806472)
			(xy 194.37096 -243.784628) (xy 194.361308 -243.680488) (xy 194.349116 -243.660676) (xy 194.338956 -243.654326)
			(xy 194.312839 -243.637235) (xy 194.264719 -243.59748) (xy 194.221965 -243.552004) (xy 194.185252 -243.501525)
			(xy 194.15516 -243.44684) (xy 194.132164 -243.388813) (xy 194.116628 -243.328359) (xy 194.108796 -243.266435)
			(xy 194.108324 -243.235226) (xy 194.10877 -243.204028) (xy 194.116589 -243.142124) (xy 194.13212 -243.081692)
			(xy 194.155117 -243.023689) (xy 194.185215 -242.969033) (xy 194.221938 -242.918589) (xy 194.264705 -242.873155)
			(xy 194.312839 -242.833452) (xy 194.338956 -242.81638) (xy 194.349116 -242.809776) (xy 194.361308 -242.789964)
			(xy 194.370706 -242.685824) (xy 194.362324 -242.664234) (xy 194.353434 -242.655852) (xy 194.335162 -242.638323)
			(xy 194.303084 -242.599148) (xy 194.276665 -242.555954) (xy 194.256402 -242.509552) (xy 194.242676 -242.460815)
			(xy 194.235745 -242.410658) (xy 194.235324 -242.385342) (xy 194.235709 -242.359993) (xy 194.24265 -242.309771)
			(xy 194.256406 -242.260974) (xy 194.276718 -242.214522) (xy 194.303203 -242.171291) (xy 194.335361 -242.132097)
			(xy 194.353688 -242.114578) (xy 194.362578 -242.10645) (xy 194.37096 -242.084606) (xy 194.361308 -241.980466)
			(xy 194.349116 -241.960654) (xy 194.338956 -241.954304) (xy 194.312829 -241.937227) (xy 194.264709 -241.897471)
			(xy 194.221955 -241.851993) (xy 194.185243 -241.801511) (xy 194.155152 -241.746824) (xy 194.132158 -241.688795)
			(xy 194.116624 -241.62834) (xy 194.108795 -241.566414) (xy 194.108324 -241.535204) (xy 194.108813 -241.504041)
			(xy 194.116625 -241.442207) (xy 194.132125 -241.381839) (xy 194.155068 -241.323891) (xy 194.185094 -241.269274)
			(xy 194.221728 -241.218852) (xy 194.264393 -241.173418) (xy 194.312415 -241.13369) (xy 194.365039 -241.100295)
			(xy 194.421433 -241.073758) (xy 194.480708 -241.054498) (xy 194.541929 -241.042819) (xy 194.604132 -241.038906)
			(xy 194.666335 -241.042819) (xy 194.727556 -241.054498) (xy 194.786831 -241.073758) (xy 194.843225 -241.100295)
			(xy 194.895849 -241.13369) (xy 194.943871 -241.173418) (xy 194.986536 -241.218852) (xy 195.02317 -241.269274)
			(xy 195.053196 -241.323891) (xy 195.076139 -241.381839) (xy 195.091639 -241.442207) (xy 195.099451 -241.504041)
			(xy 195.09994 -241.535204) (xy 195.099424 -241.566412) (xy 195.091606 -241.628336) (xy 195.076079 -241.68879)
			(xy 195.053091 -241.746818) (xy 195.023004 -241.801503) (xy 194.986294 -241.851982) (xy 194.943541 -241.897456)
			(xy 194.89542 -241.937206) (xy 194.869308 -241.954304) (xy 194.859148 -241.960654) (xy 194.846956 -241.980466)
			(xy 194.837304 -242.084606) (xy 194.845686 -242.10645) (xy 194.854576 -242.114578) (xy 194.87288 -242.132116)
			(xy 194.905026 -242.171314) (xy 194.931502 -242.214543) (xy 194.95181 -242.260991) (xy 194.965568 -242.309781)
			(xy 194.972516 -242.359996) (xy 194.97294 -242.385342) (xy 194.972512 -242.410659) (xy 194.965591 -242.460819)
			(xy 194.951873 -242.509559) (xy 194.931613 -242.555964) (xy 194.905195 -242.599161) (xy 194.873115 -242.638336)
			(xy 194.85483 -242.655852) (xy 194.84594 -242.664234) (xy 194.837558 -242.685824) (xy 194.846956 -242.789964)
			(xy 194.859148 -242.809776) (xy 194.869308 -242.81638) (xy 194.895406 -242.833475) (xy 194.943523 -242.873189)
			(xy 194.986276 -242.918626) (xy 195.02299 -242.969069) (xy 195.053085 -243.023719) (xy 195.076086 -243.081714)
			(xy 195.091627 -243.142137) (xy 195.099464 -243.204031) (xy 195.09994 -243.235226) (xy 195.099442 -243.266434)
			(xy 195.09162 -243.328359) (xy 195.076091 -243.388813) (xy 195.0531 -243.446842) (xy 195.023011 -243.501527)
			(xy 194.986299 -243.552005) (xy 194.943543 -243.597479) (xy 194.895421 -243.637229) (xy 194.869308 -243.654326)
			(xy 194.859148 -243.660676) (xy 194.846956 -243.680488) (xy 194.837304 -243.784628) (xy 194.845686 -243.806472)
			(xy 194.854576 -243.8146) (xy 194.872891 -243.832128) (xy 194.905035 -243.871327) (xy 194.93151 -243.914559)
			(xy 194.951816 -243.961009) (xy 194.965572 -244.009801) (xy 194.972517 -244.060017) (xy 194.97294 -244.085364)
			(xy 196.810882 -244.085364) (xy 196.814956 -244.021896) (xy 196.827114 -243.959471) (xy 196.847154 -243.899112)
			(xy 196.874748 -243.841812) (xy 196.909444 -243.788511) (xy 196.95067 -243.740084) (xy 196.99775 -243.697327)
			(xy 197.049912 -243.660941) (xy 197.106299 -243.631524) (xy 197.165984 -243.609559) (xy 197.227988 -243.595407)
			(xy 197.291292 -243.589301) (xy 197.354858 -243.591339) (xy 197.417641 -243.601489) (xy 197.478611 -243.619585)
			(xy 197.536766 -243.645328) (xy 197.591152 -243.678297) (xy 197.640875 -243.71795) (xy 197.68512 -243.763636)
			(xy 197.723159 -243.814605) (xy 197.754368 -243.870019) (xy 197.778234 -243.92897) (xy 197.794366 -243.990488)
			(xy 197.802499 -244.053565) (xy 197.803008 -244.085364) (xy 197.802499 -244.117163) (xy 197.794366 -244.18024)
			(xy 197.778234 -244.241758) (xy 197.754368 -244.300709) (xy 197.723159 -244.356123) (xy 197.68512 -244.407092)
			(xy 197.640875 -244.452778) (xy 197.591152 -244.492431) (xy 197.536766 -244.5254) (xy 197.478611 -244.551143)
			(xy 197.417641 -244.569239) (xy 197.354858 -244.579389) (xy 197.291292 -244.581427) (xy 197.227988 -244.575321)
			(xy 197.165984 -244.561169) (xy 197.106299 -244.539204) (xy 197.049912 -244.509787) (xy 196.99775 -244.473401)
			(xy 196.95067 -244.430644) (xy 196.909444 -244.382217) (xy 196.874748 -244.328916) (xy 196.847154 -244.271616)
			(xy 196.827114 -244.211257) (xy 196.814956 -244.148832) (xy 196.810882 -244.085364) (xy 194.97294 -244.085364)
			(xy 194.972527 -244.110682) (xy 194.965603 -244.160842) (xy 194.951881 -244.209583) (xy 194.931619 -244.255988)
			(xy 194.905199 -244.299184) (xy 194.873116 -244.338358) (xy 194.85483 -244.355874) (xy 194.84594 -244.364256)
			(xy 194.837558 -244.385846) (xy 194.846956 -244.489986) (xy 194.859148 -244.509798) (xy 194.869308 -244.516402)
			(xy 194.895416 -244.533482) (xy 194.943533 -244.573198) (xy 194.986286 -244.618638) (xy 195.022999 -244.669082)
			(xy 195.053093 -244.723735) (xy 195.076091 -244.781732) (xy 195.091631 -244.842156) (xy 195.099466 -244.904053)
			(xy 195.09994 -244.935248) (xy 195.099459 -244.966457) (xy 195.091635 -245.028382) (xy 195.076103 -245.088837)
			(xy 195.05311 -245.146865) (xy 195.023018 -245.201551) (xy 194.986303 -245.252029) (xy 194.943546 -245.297502)
			(xy 194.895421 -245.337251) (xy 194.869308 -245.354348) (xy 194.859148 -245.360698) (xy 194.846956 -245.38051)
			(xy 194.837304 -245.48465) (xy 194.845686 -245.506494) (xy 194.854576 -245.514622) (xy 194.872902 -245.532139)
			(xy 194.905045 -245.571341) (xy 194.931518 -245.614575) (xy 194.951823 -245.661027) (xy 194.965576 -245.709821)
			(xy 194.972519 -245.760038) (xy 194.97294 -245.785386) (xy 194.972541 -245.810704) (xy 194.965615 -245.860865)
			(xy 194.95189 -245.909606) (xy 194.931625 -245.956011) (xy 194.905202 -245.999207) (xy 194.873117 -246.038381)
			(xy 194.85483 -246.055896) (xy 194.84594 -246.064278) (xy 194.837558 -246.085868) (xy 194.846956 -246.190008)
			(xy 194.859148 -246.20982) (xy 194.869308 -246.216424) (xy 194.895426 -246.233489) (xy 194.943543 -246.273207)
			(xy 194.986295 -246.318649) (xy 195.023008 -246.369096) (xy 195.0531 -246.423751) (xy 195.076097 -246.48175)
			(xy 195.091635 -246.542176) (xy 195.099467 -246.604074) (xy 195.09994 -246.63527) (xy 195.099476 -246.666479)
			(xy 195.091649 -246.728406) (xy 195.076115 -246.788861) (xy 195.053119 -246.846889) (xy 195.023025 -246.901574)
			(xy 194.986308 -246.952052) (xy 194.943549 -246.997524) (xy 194.895422 -247.037273) (xy 194.869308 -247.05437)
			(xy 194.859148 -247.06072) (xy 194.846956 -247.080532) (xy 194.837304 -247.184672) (xy 194.845686 -247.206516)
			(xy 194.854576 -247.214644) (xy 194.872912 -247.23215) (xy 194.905055 -247.271355) (xy 194.931527 -247.314591)
			(xy 194.951829 -247.361045) (xy 194.96558 -247.409841) (xy 194.97252 -247.46006) (xy 194.97294 -247.485408)
			(xy 194.972556 -247.510727) (xy 194.965627 -247.560888) (xy 194.951899 -247.60963) (xy 194.931632 -247.656035)
			(xy 194.905206 -247.69923) (xy 194.873118 -247.738404) (xy 194.85483 -247.755918) (xy 194.84594 -247.7643)
			(xy 194.837558 -247.78589) (xy 194.846956 -247.89003) (xy 194.859148 -247.909842) (xy 194.869308 -247.916446)
			(xy 194.895436 -247.933497) (xy 194.943553 -247.973217) (xy 194.986305 -248.018661) (xy 195.023017 -248.06911)
			(xy 195.053108 -248.123767) (xy 195.076103 -248.181768) (xy 195.091638 -248.242196) (xy 195.099468 -248.304096)
			(xy 195.09994 -248.335292) (xy 195.099415 -248.3665) (xy 195.091598 -248.428423) (xy 195.076073 -248.488877)
			(xy 195.053086 -248.546905) (xy 195.023 -248.60159) (xy 194.986291 -248.652069) (xy 194.943539 -248.697543)
			(xy 194.895419 -248.737294) (xy 194.869308 -248.754392) (xy 194.859148 -248.760742) (xy 194.846956 -248.780554)
			(xy 194.837304 -248.884694) (xy 194.845686 -248.906538) (xy 194.854576 -248.914666) (xy 194.872875 -248.93221)
			(xy 194.90502 -248.971406) (xy 194.931497 -249.014635) (xy 194.951806 -249.061081) (xy 194.965565 -249.10987)
			(xy 194.972515 -249.160084) (xy 194.97294 -249.18543) (xy 194.972504 -249.210747) (xy 194.965585 -249.260906)
			(xy 194.951868 -249.309647) (xy 194.93161 -249.356052) (xy 194.905193 -249.399248) (xy 194.873114 -249.438424)
			(xy 194.85483 -249.45594) (xy 194.84594 -249.464322) (xy 194.837558 -249.485912) (xy 194.846956 -249.590052)
			(xy 194.859148 -249.609864) (xy 194.869308 -249.616468) (xy 194.895435 -249.633524) (xy 194.943566 -249.673233)
			(xy 194.986331 -249.71867) (xy 195.023055 -249.769116) (xy 195.053156 -249.823772) (xy 195.076158 -249.881775)
			(xy 195.091698 -249.942205) (xy 195.099529 -250.004109) (xy 195.099528 -250.066506) (xy 195.091695 -250.128409)
			(xy 195.076153 -250.18884) (xy 195.053149 -250.246841) (xy 195.023047 -250.301497) (xy 194.986322 -250.351941)
			(xy 194.943555 -250.397377) (xy 194.895423 -250.437085) (xy 194.869308 -250.45416) (xy 194.859148 -250.460764)
			(xy 194.846956 -250.480576) (xy 194.837558 -250.584716) (xy 194.84594 -250.606306) (xy 194.85483 -250.614688)
			(xy 194.873114 -250.632204) (xy 194.905193 -250.671381) (xy 194.931611 -250.714578) (xy 194.951872 -250.760982)
			(xy 194.965595 -250.809722) (xy 194.972522 -250.859881) (xy 194.97294 -250.885198) (xy 194.972494 -250.910545)
			(xy 194.965563 -250.960763) (xy 194.951818 -251.009558) (xy 194.931517 -251.05601) (xy 194.905043 -251.099242)
			(xy 194.872897 -251.138441) (xy 194.854576 -251.155962) (xy 194.845686 -251.16409) (xy 194.837304 -251.185934)
			(xy 194.846956 -251.290074) (xy 194.859148 -251.309886) (xy 194.869308 -251.316236) (xy 194.895399 -251.333365)
			(xy 194.943521 -251.373113) (xy 194.986277 -251.418583) (xy 195.022993 -251.469056) (xy 195.053088 -251.523736)
			(xy 195.076088 -251.581759) (xy 195.091629 -251.642208) (xy 195.099465 -251.704129) (xy 195.09994 -251.735336)
			(xy 195.099435 -251.766532) (xy 195.091621 -251.828432) (xy 195.076097 -251.888861) (xy 195.053108 -251.946863)
			(xy 195.023018 -252.001519) (xy 194.986303 -252.051964) (xy 194.943545 -252.0974) (xy 194.89542 -252.137108)
			(xy 194.869308 -252.154182) (xy 194.859148 -252.160786) (xy 194.846956 -252.180598) (xy 194.837558 -252.284738)
			(xy 194.84594 -252.306328) (xy 194.85483 -252.31471) (xy 194.873125 -252.332216) (xy 194.905203 -252.371395)
			(xy 194.931619 -252.414594) (xy 194.951879 -252.461) (xy 194.965599 -252.509742) (xy 194.972523 -252.559902)
			(xy 194.97294 -252.58522) (xy 194.972509 -252.610568) (xy 194.965575 -252.660786) (xy 194.951826 -252.709582)
			(xy 194.931523 -252.756033) (xy 194.905047 -252.799265) (xy 194.872898 -252.838463) (xy 194.854576 -252.855984)
			(xy 194.845686 -252.864112) (xy 194.837304 -252.885956) (xy 194.846956 -252.990096) (xy 194.859148 -253.009908)
			(xy 194.869308 -253.016258) (xy 194.895409 -253.033373) (xy 194.943531 -253.073123) (xy 194.986287 -253.118595)
			(xy 195.023002 -253.16907) (xy 195.053096 -253.223752) (xy 195.076094 -253.281777) (xy 195.091633 -253.342228)
			(xy 195.099466 -253.40415) (xy 195.09994 -253.435358) (xy 195.099414 -253.468058) (xy 195.090805 -253.53289)
			(xy 195.073744 -253.596027) (xy 195.048528 -253.656371) (xy 195.015594 -253.712875) (xy 194.975515 -253.764556)
			(xy 194.95262 -253.78791) (xy 194.945254 -253.795276) (xy 194.937634 -253.813818) (xy 194.937634 -253.906782)
			(xy 194.945254 -253.925324) (xy 194.95262 -253.93269) (xy 194.975526 -253.956034) (xy 195.015611 -254.007714)
			(xy 195.048547 -254.064218) (xy 195.073762 -254.124565) (xy 195.090818 -254.187705) (xy 195.099418 -254.25254)
			(xy 195.09994 -254.285242) (xy 198.208392 -254.285242) (xy 198.208865 -254.254045) (xy 198.216682 -254.192143)
			(xy 198.23221 -254.131712) (xy 198.255203 -254.07371) (xy 198.285298 -254.019054) (xy 198.322017 -253.968609)
			(xy 198.36478 -253.923174) (xy 198.412909 -253.883469) (xy 198.439024 -253.866396) (xy 198.449184 -253.859792)
			(xy 198.461376 -253.83998) (xy 198.470774 -253.73584) (xy 198.462392 -253.71425) (xy 198.453502 -253.705868)
			(xy 198.435202 -253.688367) (xy 198.403124 -253.649187) (xy 198.376707 -253.605988) (xy 198.356448 -253.55958)
			(xy 198.342729 -253.510838) (xy 198.335808 -253.460676) (xy 198.335392 -253.435358) (xy 198.335798 -253.410009)
			(xy 198.342736 -253.359789) (xy 198.356489 -253.310993) (xy 198.376797 -253.264541) (xy 198.403278 -253.22131)
			(xy 198.435432 -253.182114) (xy 198.453756 -253.164594) (xy 198.462646 -253.156466) (xy 198.471028 -253.134622)
			(xy 198.461376 -253.030482) (xy 198.449184 -253.01067) (xy 198.439024 -253.00432) (xy 198.41292 -252.987209)
			(xy 198.364797 -252.947459) (xy 198.32204 -252.901988) (xy 198.285325 -252.851512) (xy 198.255231 -252.796829)
			(xy 198.232233 -252.738804) (xy 198.216696 -252.678352) (xy 198.208864 -252.616428) (xy 198.208392 -252.58522)
			(xy 198.208848 -252.554023) (xy 198.216668 -252.49212) (xy 198.232198 -252.431689) (xy 198.255194 -252.373686)
			(xy 198.285291 -252.31903) (xy 198.322012 -252.268586) (xy 198.364777 -252.223151) (xy 198.412908 -252.183447)
			(xy 198.439024 -252.166374) (xy 198.449184 -252.15977) (xy 198.461376 -252.139958) (xy 198.470774 -252.035818)
			(xy 198.462392 -252.014228) (xy 198.453502 -252.005846) (xy 198.43524 -251.988307) (xy 198.403158 -251.949136)
			(xy 198.376736 -251.905944) (xy 198.356471 -251.859544) (xy 198.342744 -251.810808) (xy 198.335813 -251.760652)
			(xy 198.335392 -251.735336) (xy 198.335783 -251.709987) (xy 198.342724 -251.659766) (xy 198.35648 -251.61097)
			(xy 198.376791 -251.564518) (xy 198.403274 -251.521287) (xy 198.435431 -251.482091) (xy 198.453756 -251.464572)
			(xy 198.462646 -251.456444) (xy 198.471028 -251.4346) (xy 198.461376 -251.33046) (xy 198.449184 -251.310648)
			(xy 198.439024 -251.304298) (xy 198.41291 -251.287202) (xy 198.364787 -251.24745) (xy 198.322031 -251.201976)
			(xy 198.285316 -251.151498) (xy 198.255223 -251.096813) (xy 198.232227 -251.038786) (xy 198.216692 -250.978332)
			(xy 198.208863 -250.916407) (xy 198.208392 -250.885198) (xy 198.208831 -250.854) (xy 198.216653 -250.792096)
			(xy 198.232186 -250.731665) (xy 198.255184 -250.673662) (xy 198.285284 -250.619006) (xy 198.322007 -250.568562)
			(xy 198.364774 -250.523128) (xy 198.412908 -250.483424) (xy 198.439024 -250.466352) (xy 198.449184 -250.459748)
			(xy 198.461376 -250.439936) (xy 198.470774 -250.335796) (xy 198.462392 -250.314206) (xy 198.453502 -250.305824)
			(xy 198.433591 -250.286674) (xy 198.399125 -250.243501) (xy 198.371485 -250.19567) (xy 198.351287 -250.144253)
			(xy 198.338985 -250.090397) (xy 198.334852 -250.03531) (xy 198.338982 -249.980222) (xy 198.351282 -249.926366)
			(xy 198.371477 -249.874947) (xy 198.399115 -249.827115) (xy 198.433578 -249.78394) (xy 198.453502 -249.764804)
			(xy 198.462392 -249.756422) (xy 198.470774 -249.734832) (xy 198.461376 -249.630692) (xy 198.449184 -249.61088)
			(xy 198.439024 -249.604276) (xy 198.412913 -249.5872) (xy 198.364795 -249.547484) (xy 198.322041 -249.502045)
			(xy 198.285327 -249.4516) (xy 198.255234 -249.396946) (xy 198.232236 -249.338948) (xy 198.216698 -249.278523)
			(xy 198.208865 -249.216625) (xy 198.208392 -249.18543) (xy 198.208841 -249.15422) (xy 198.216669 -249.092293)
			(xy 198.232204 -249.031837) (xy 198.255201 -248.973807) (xy 198.285298 -248.919122) (xy 198.322017 -248.868645)
			(xy 198.364779 -248.823173) (xy 198.412908 -248.783426) (xy 198.439024 -248.76633) (xy 198.449184 -248.75998)
			(xy 198.461376 -248.740168) (xy 198.471028 -248.636028) (xy 198.462646 -248.614184) (xy 198.453756 -248.606056)
			(xy 198.435426 -248.588544) (xy 198.403282 -248.549341) (xy 198.376808 -248.506106) (xy 198.356504 -248.459654)
			(xy 198.342752 -248.410859) (xy 198.335812 -248.36064) (xy 198.335392 -248.335292) (xy 198.335797 -248.309974)
			(xy 198.342725 -248.259815) (xy 198.35645 -248.211074) (xy 198.376714 -248.16467) (xy 198.403135 -248.121474)
			(xy 198.435217 -248.082298) (xy 198.453502 -248.064782) (xy 198.462392 -248.0564) (xy 198.470774 -248.03481)
			(xy 198.461376 -247.93067) (xy 198.449184 -247.910858) (xy 198.439024 -247.904254) (xy 198.412903 -247.887192)
			(xy 198.364785 -247.847475) (xy 198.322032 -247.802033) (xy 198.285319 -247.751586) (xy 198.255226 -247.69693)
			(xy 198.23223 -247.63893) (xy 198.216694 -247.578503) (xy 198.208864 -247.516604) (xy 198.208392 -247.485408)
			(xy 198.208902 -247.4542) (xy 198.21672 -247.392275) (xy 198.232246 -247.33182) (xy 198.255235 -247.273792)
			(xy 198.285322 -247.219106) (xy 198.322034 -247.168628) (xy 198.364789 -247.123154) (xy 198.412911 -247.083405)
			(xy 198.439024 -247.066308) (xy 198.449184 -247.059958) (xy 198.461376 -247.040146) (xy 198.471028 -246.936006)
			(xy 198.462646 -246.914162) (xy 198.453756 -246.906034) (xy 198.435464 -246.888484) (xy 198.403316 -246.849289)
			(xy 198.376838 -246.806063) (xy 198.356527 -246.759618) (xy 198.342767 -246.710829) (xy 198.335817 -246.660616)
			(xy 198.335392 -246.63527) (xy 198.33585 -246.609954) (xy 198.342767 -246.559797) (xy 198.356482 -246.511057)
			(xy 198.376735 -246.464653) (xy 198.403147 -246.421456) (xy 198.435221 -246.382278) (xy 198.453502 -246.36476)
			(xy 198.462392 -246.356378) (xy 198.470774 -246.334788) (xy 198.461376 -246.230648) (xy 198.449184 -246.210836)
			(xy 198.439024 -246.204232) (xy 198.412939 -246.187118) (xy 198.364821 -246.147408) (xy 198.322066 -246.101974)
			(xy 198.285349 -246.051534) (xy 198.255253 -245.996886) (xy 198.232251 -245.938894) (xy 198.216707 -245.878473)
			(xy 198.208868 -245.81658) (xy 198.208392 -245.785386) (xy 198.208885 -245.754177) (xy 198.216706 -245.692252)
			(xy 198.232234 -245.631797) (xy 198.255225 -245.573768) (xy 198.285315 -245.519082) (xy 198.322029 -245.468604)
			(xy 198.364786 -245.423131) (xy 198.41291 -245.383383) (xy 198.439024 -245.366286) (xy 198.449184 -245.359936)
			(xy 198.461376 -245.340124) (xy 198.471028 -245.235984) (xy 198.462646 -245.21414) (xy 198.453756 -245.206012)
			(xy 198.435453 -245.188472) (xy 198.403306 -245.149276) (xy 198.376829 -245.106047) (xy 198.356521 -245.0596)
			(xy 198.342763 -245.010809) (xy 198.335816 -244.960594) (xy 198.335392 -244.935248) (xy 198.335834 -244.909931)
			(xy 198.342755 -244.859773) (xy 198.356472 -244.811034) (xy 198.376729 -244.764629) (xy 198.403144 -244.721432)
			(xy 198.435219 -244.682255) (xy 198.453502 -244.664738) (xy 198.462392 -244.656356) (xy 198.470774 -244.634766)
			(xy 198.461376 -244.530626) (xy 198.449184 -244.510814) (xy 198.439024 -244.50421) (xy 198.412929 -244.487111)
			(xy 198.364811 -244.447399) (xy 198.322056 -244.401963) (xy 198.285341 -244.351521) (xy 198.255245 -244.296871)
			(xy 198.232245 -244.238876) (xy 198.216704 -244.178453) (xy 198.208867 -244.116558) (xy 198.208392 -244.085364)
			(xy 198.208868 -244.054155) (xy 198.216691 -243.992228) (xy 198.232222 -243.931773) (xy 198.255216 -243.873744)
			(xy 198.285308 -243.819059) (xy 198.322024 -243.768581) (xy 198.364783 -243.723108) (xy 198.41291 -243.68336)
			(xy 198.439024 -243.666264) (xy 198.449184 -243.659914) (xy 198.461376 -243.640102) (xy 198.471028 -243.535962)
			(xy 198.462646 -243.514118) (xy 198.453756 -243.50599) (xy 198.435442 -243.488461) (xy 198.403297 -243.449262)
			(xy 198.376821 -243.406031) (xy 198.356514 -243.359582) (xy 198.342759 -243.310789) (xy 198.335814 -243.260573)
			(xy 198.335392 -243.235226) (xy 198.33582 -243.209909) (xy 198.342743 -243.15975) (xy 198.356464 -243.111011)
			(xy 198.376723 -243.064606) (xy 198.40314 -243.021409) (xy 198.435218 -242.982233) (xy 198.453502 -242.964716)
			(xy 198.462392 -242.956334) (xy 198.470774 -242.934744) (xy 198.461376 -242.830604) (xy 198.449184 -242.810792)
			(xy 198.439024 -242.804188) (xy 198.412919 -242.787104) (xy 198.364801 -242.747389) (xy 198.322047 -242.701951)
			(xy 198.285332 -242.651507) (xy 198.255238 -242.596855) (xy 198.232239 -242.538858) (xy 198.2167 -242.478434)
			(xy 198.208866 -242.416537) (xy 198.208392 -242.385342) (xy 198.208851 -242.354132) (xy 198.216677 -242.292205)
			(xy 198.23221 -242.231749) (xy 198.255207 -242.17372) (xy 198.285301 -242.119035) (xy 198.32202 -242.068557)
			(xy 198.364781 -242.023085) (xy 198.412909 -241.983338) (xy 198.439024 -241.966242) (xy 198.449184 -241.959892)
			(xy 198.461376 -241.94008) (xy 198.471028 -241.83594) (xy 198.462646 -241.814096) (xy 198.453756 -241.805968)
			(xy 198.435432 -241.78845) (xy 198.403287 -241.749249) (xy 198.376813 -241.706015) (xy 198.356508 -241.659564)
			(xy 198.342755 -241.610769) (xy 198.335813 -241.560552) (xy 198.335392 -241.535204) (xy 198.335805 -241.509886)
			(xy 198.342732 -241.459727) (xy 198.356455 -241.410987) (xy 198.376717 -241.364583) (xy 198.403137 -241.321386)
			(xy 198.435217 -241.28221) (xy 198.453502 -241.264694) (xy 198.462392 -241.256312) (xy 198.470774 -241.234722)
			(xy 198.461376 -241.130582) (xy 198.449184 -241.11077) (xy 198.439024 -241.104166) (xy 198.412909 -241.087096)
			(xy 198.364791 -241.04738) (xy 198.322037 -241.00194) (xy 198.285323 -240.951493) (xy 198.25523 -240.896839)
			(xy 198.232233 -240.83884) (xy 198.216696 -240.778414) (xy 198.208864 -240.716516) (xy 198.208392 -240.68532)
			(xy 198.208881 -240.654157) (xy 198.216693 -240.592323) (xy 198.232193 -240.531955) (xy 198.255136 -240.474007)
			(xy 198.285162 -240.41939) (xy 198.321796 -240.368968) (xy 198.364461 -240.323534) (xy 198.412483 -240.283806)
			(xy 198.465107 -240.250411) (xy 198.521501 -240.223874) (xy 198.580776 -240.204614) (xy 198.641997 -240.192935)
			(xy 198.7042 -240.189022) (xy 198.766403 -240.192935) (xy 198.827624 -240.204614) (xy 198.886899 -240.223874)
			(xy 198.943293 -240.250411) (xy 198.995917 -240.283806) (xy 199.043939 -240.323534) (xy 199.086604 -240.368968)
			(xy 199.123238 -240.41939) (xy 199.153264 -240.474007) (xy 199.176207 -240.531955) (xy 199.191707 -240.592323)
			(xy 199.199519 -240.654157) (xy 199.200008 -240.68532) (xy 203.162931 -240.68532) (xy 203.166866 -240.631549)
			(xy 203.178589 -240.578925) (xy 203.197849 -240.528568) (xy 203.224235 -240.481551) (xy 203.257187 -240.438878)
			(xy 203.296 -240.401457) (xy 203.339848 -240.370087) (xy 203.387796 -240.345435) (xy 203.438823 -240.328027)
			(xy 203.491841 -240.318234) (xy 203.54572 -240.316265) (xy 203.599311 -240.322162) (xy 203.651472 -240.335798)
			(xy 203.701092 -240.356885) (xy 203.747113 -240.384971) (xy 203.788555 -240.419459) (xy 203.824533 -240.459613)
			(xy 203.854281 -240.504577) (xy 203.877166 -240.553394) (xy 203.892698 -240.605023) (xy 203.900548 -240.658363)
			(xy 203.90104 -240.68532) (xy 203.900548 -240.712277) (xy 203.892698 -240.765617) (xy 203.877166 -240.817246)
			(xy 203.854281 -240.866063) (xy 203.824533 -240.911027) (xy 203.788555 -240.951181) (xy 203.747113 -240.985669)
			(xy 203.701092 -241.013755) (xy 203.651472 -241.034842) (xy 203.599311 -241.048478) (xy 203.54572 -241.054375)
			(xy 203.491841 -241.052406) (xy 203.438823 -241.042613) (xy 203.387796 -241.025205) (xy 203.339848 -241.000553)
			(xy 203.296 -240.969183) (xy 203.257187 -240.931762) (xy 203.224235 -240.889089) (xy 203.197849 -240.842072)
			(xy 203.178589 -240.791715) (xy 203.166866 -240.739091) (xy 203.162931 -240.68532) (xy 199.200008 -240.68532)
			(xy 199.199583 -240.716518) (xy 199.191759 -240.778423) (xy 199.176223 -240.838854) (xy 199.153223 -240.896857)
			(xy 199.123122 -240.951513) (xy 199.086397 -241.001957) (xy 199.043628 -241.04739) (xy 198.995493 -241.087094)
			(xy 198.969376 -241.104166) (xy 198.959216 -241.11077) (xy 198.947024 -241.130582) (xy 198.937626 -241.234722)
			(xy 198.946008 -241.256312) (xy 198.954898 -241.264694) (xy 198.973179 -241.282214) (xy 199.005259 -241.321389)
			(xy 199.031679 -241.364585) (xy 199.05194 -241.410989) (xy 199.065663 -241.459728) (xy 199.07259 -241.509887)
			(xy 199.073008 -241.535204) (xy 199.072577 -241.560552) (xy 199.065644 -241.610771) (xy 199.051896 -241.659566)
			(xy 199.031593 -241.706018) (xy 199.005116 -241.749251) (xy 198.972966 -241.788447) (xy 198.954644 -241.805968)
			(xy 198.945754 -241.814096) (xy 198.937372 -241.83594) (xy 198.947024 -241.94008) (xy 198.959216 -241.959892)
			(xy 198.969376 -241.966242) (xy 198.995462 -241.983378) (xy 199.043586 -242.023124) (xy 199.086343 -242.068592)
			(xy 199.12306 -242.119064) (xy 199.153157 -242.173743) (xy 199.176157 -242.231765) (xy 199.191697 -242.292214)
			(xy 199.199533 -242.354135) (xy 199.200008 -242.385342) (xy 199.199522 -242.416539) (xy 199.191707 -242.47844)
			(xy 199.176181 -242.53887) (xy 199.15319 -242.596873) (xy 199.123097 -242.651529) (xy 199.08638 -242.701974)
			(xy 199.043618 -242.747409) (xy 198.99549 -242.787115) (xy 198.969376 -242.804188) (xy 198.959216 -242.810792)
			(xy 198.947024 -242.830604) (xy 198.937626 -242.934744) (xy 198.946008 -242.956334) (xy 198.954898 -242.964716)
			(xy 198.97319 -242.982225) (xy 199.005269 -243.021403) (xy 199.031687 -243.064601) (xy 199.051947 -243.111007)
			(xy 199.065668 -243.159748) (xy 199.072591 -243.209908) (xy 199.073008 -243.235226) (xy 199.072591 -243.260574)
			(xy 199.065656 -243.310794) (xy 199.051905 -243.35959) (xy 199.031599 -243.406042) (xy 199.00512 -243.449274)
			(xy 198.972968 -243.48847) (xy 198.954644 -243.50599) (xy 198.945754 -243.514118) (xy 198.937372 -243.535962)
			(xy 198.947024 -243.640102) (xy 198.959216 -243.659914) (xy 198.969376 -243.666264) (xy 198.995472 -243.683386)
			(xy 199.043596 -243.723134) (xy 199.086353 -243.768604) (xy 199.123069 -243.819078) (xy 199.153164 -243.873759)
			(xy 199.176162 -243.931783) (xy 199.191701 -243.992234) (xy 199.199535 -244.054156) (xy 199.200008 -244.085364)
			(xy 199.19954 -244.116561) (xy 199.191722 -244.178463) (xy 199.176193 -244.238894) (xy 199.153199 -244.296897)
			(xy 199.123104 -244.351553) (xy 199.086384 -244.401997) (xy 199.043621 -244.447432) (xy 198.995491 -244.487137)
			(xy 198.969376 -244.50421) (xy 198.959216 -244.510814) (xy 198.947024 -244.530626) (xy 198.937626 -244.634766)
			(xy 198.946008 -244.656356) (xy 198.954898 -244.664738) (xy 198.973152 -244.682285) (xy 199.005235 -244.721454)
			(xy 199.031658 -244.764644) (xy 199.051924 -244.811043) (xy 199.065653 -244.859778) (xy 199.072586 -244.909932)
			(xy 199.073008 -244.935248) (xy 199.072606 -244.960597) (xy 199.065667 -245.010817) (xy 199.051914 -245.059613)
			(xy 199.031605 -245.106065) (xy 199.005123 -245.149297) (xy 198.972969 -245.188492) (xy 198.954644 -245.206012)
			(xy 198.945754 -245.21414) (xy 198.937372 -245.235984) (xy 198.947024 -245.340124) (xy 198.959216 -245.359936)
			(xy 198.969376 -245.366286) (xy 198.995483 -245.383393) (xy 199.043606 -245.423143) (xy 199.086362 -245.468615)
			(xy 199.123078 -245.519092) (xy 199.153171 -245.573775) (xy 199.176168 -245.631801) (xy 199.191705 -245.692254)
			(xy 199.199536 -245.754177) (xy 199.200008 -245.785386) (xy 199.199557 -245.816584) (xy 199.191736 -245.878487)
			(xy 199.176205 -245.938918) (xy 199.153209 -245.99692) (xy 199.123111 -246.051576) (xy 199.086389 -246.102021)
			(xy 199.043624 -246.147455) (xy 198.995492 -246.187159) (xy 198.969376 -246.204232) (xy 198.959216 -246.210836)
			(xy 198.947024 -246.230648) (xy 198.937626 -246.334788) (xy 198.946008 -246.356378) (xy 198.954898 -246.36476)
			(xy 198.973163 -246.382296) (xy 199.005244 -246.421468) (xy 199.031666 -246.46466) (xy 199.051931 -246.511061)
			(xy 199.065657 -246.559798) (xy 199.072588 -246.609954) (xy 199.073008 -246.63527) (xy 199.072621 -246.660619)
			(xy 199.065679 -246.71084) (xy 199.051923 -246.759637) (xy 199.031611 -246.806088) (xy 199.005127 -246.84932)
			(xy 198.97297 -246.888515) (xy 198.954644 -246.906034) (xy 198.945754 -246.914162) (xy 198.937372 -246.936006)
			(xy 198.947024 -247.040146) (xy 198.959216 -247.059958) (xy 198.969376 -247.066308) (xy 198.995493 -247.0834)
			(xy 199.043616 -247.123152) (xy 199.086372 -247.168627) (xy 199.123086 -247.219106) (xy 199.153179 -247.273791)
			(xy 199.176174 -247.331819) (xy 199.191709 -247.392273) (xy 199.199537 -247.454199) (xy 199.200008 -247.485408)
			(xy 199.199574 -247.516606) (xy 199.191751 -247.57851) (xy 199.176217 -247.638941) (xy 199.153218 -247.696944)
			(xy 199.123118 -247.7516) (xy 199.086394 -247.802044) (xy 199.043626 -247.847478) (xy 198.995493 -247.887182)
			(xy 198.969376 -247.904254) (xy 198.959216 -247.910858) (xy 198.947024 -247.93067) (xy 198.937626 -248.03481)
			(xy 198.946008 -248.0564) (xy 198.954898 -248.064782) (xy 198.973173 -248.082308) (xy 199.005254 -248.121482)
			(xy 199.031674 -248.164676) (xy 199.051937 -248.211079) (xy 199.065661 -248.259817) (xy 199.072589 -248.309975)
			(xy 199.073008 -248.335292) (xy 199.072569 -248.36064) (xy 199.065638 -248.410858) (xy 199.051891 -248.459654)
			(xy 199.031589 -248.506106) (xy 199.005114 -248.549338) (xy 198.972966 -248.588535) (xy 198.954644 -248.606056)
			(xy 198.945754 -248.614184) (xy 198.937372 -248.636028) (xy 198.947024 -248.740168) (xy 198.959216 -248.75998)
			(xy 198.969376 -248.76633) (xy 198.995457 -248.783475) (xy 199.04358 -248.823219) (xy 199.086338 -248.868686)
			(xy 199.123055 -248.919157) (xy 199.153152 -248.973835) (xy 199.176153 -249.031856) (xy 199.191695 -249.092303)
			(xy 199.199533 -249.154223) (xy 199.200008 -249.18543) (xy 199.199513 -249.216626) (xy 199.1917 -249.278528)
			(xy 199.176175 -249.338958) (xy 199.153185 -249.39696) (xy 199.123094 -249.451616) (xy 199.086377 -249.502061)
			(xy 199.043617 -249.547496) (xy 198.99549 -249.587203) (xy 198.969376 -249.604276) (xy 198.959216 -249.61088)
			(xy 198.947024 -249.630692) (xy 198.937626 -249.734832) (xy 198.946008 -249.756422) (xy 198.954898 -249.764804)
			(xy 198.974837 -249.783926) (xy 199.009302 -249.827103) (xy 199.036942 -249.874938) (xy 199.057138 -249.92636)
			(xy 199.069439 -249.980218) (xy 199.073569 -250.03531) (xy 199.069436 -250.0904) (xy 199.057132 -250.144259)
			(xy 199.036934 -250.195679) (xy 199.009291 -250.243512) (xy 198.974824 -250.286688) (xy 198.954898 -250.305824)
			(xy 198.946008 -250.314206) (xy 198.937626 -250.335796) (xy 198.947024 -250.439936) (xy 198.959216 -250.459748)
			(xy 198.969376 -250.466352) (xy 198.9955 -250.48341) (xy 199.043618 -250.523128) (xy 199.086371 -250.56857)
			(xy 199.123084 -250.619018) (xy 199.153176 -250.673674) (xy 199.176172 -250.731675) (xy 199.191707 -250.792102)
			(xy 199.199537 -250.854002) (xy 199.200008 -250.885198) (xy 199.199503 -250.916406) (xy 199.191684 -250.978331)
			(xy 199.176157 -251.038786) (xy 199.153168 -251.096815) (xy 199.12308 -251.151501) (xy 199.086367 -251.201979)
			(xy 199.043612 -251.247452) (xy 198.995489 -251.287201) (xy 198.969376 -251.304298) (xy 198.959216 -251.310648)
			(xy 198.947024 -251.33046) (xy 198.937372 -251.4346) (xy 198.945754 -251.456444) (xy 198.954644 -251.464572)
			(xy 198.972939 -251.482119) (xy 199.005087 -251.521314) (xy 199.031565 -251.564542) (xy 199.051875 -251.610987)
			(xy 199.065634 -251.659776) (xy 199.072583 -251.70999) (xy 199.073008 -251.735336) (xy 199.072554 -251.760652)
			(xy 199.065636 -251.81081) (xy 199.051921 -251.859549) (xy 199.031666 -251.905953) (xy 199.005254 -251.949151)
			(xy 198.973179 -251.988328) (xy 198.954898 -252.005846) (xy 198.946008 -252.014228) (xy 198.937626 -252.035818)
			(xy 198.947024 -252.139958) (xy 198.959216 -252.15977) (xy 198.969376 -252.166374) (xy 198.995464 -252.183484)
			(xy 199.043582 -252.223194) (xy 199.086337 -252.268629) (xy 199.123053 -252.319069) (xy 199.153149 -252.373718)
			(xy 199.176151 -252.431711) (xy 199.191694 -252.492132) (xy 199.199532 -252.554026) (xy 199.200008 -252.58522)
			(xy 199.19952 -252.616429) (xy 199.191698 -252.678355) (xy 199.176169 -252.73881) (xy 199.153177 -252.796839)
			(xy 199.123087 -252.851524) (xy 199.086372 -252.902002) (xy 199.043615 -252.947475) (xy 198.99549 -252.987224)
			(xy 198.969376 -253.00432) (xy 198.959216 -253.01067) (xy 198.947024 -253.030482) (xy 198.937372 -253.134622)
			(xy 198.945754 -253.156466) (xy 198.954644 -253.164594) (xy 198.97295 -253.182131) (xy 199.005096 -253.221328)
			(xy 199.031573 -253.264558) (xy 199.051881 -253.311005) (xy 199.065638 -253.359796) (xy 199.072585 -253.410011)
			(xy 199.073008 -253.435358) (xy 199.07257 -253.460675) (xy 199.065648 -253.510833) (xy 199.05193 -253.559572)
			(xy 199.031673 -253.605977) (xy 199.005257 -253.649174) (xy 198.973181 -253.688351) (xy 198.954898 -253.705868)
			(xy 198.946008 -253.71425) (xy 198.937626 -253.73584) (xy 198.947024 -253.83998) (xy 198.959216 -253.859792)
			(xy 198.969376 -253.866396) (xy 198.995474 -253.883491) (xy 199.043592 -253.923204) (xy 199.086347 -253.96864)
			(xy 199.123062 -254.019083) (xy 199.153157 -254.073734) (xy 199.176157 -254.131729) (xy 199.191697 -254.192152)
			(xy 199.199533 -254.254047) (xy 199.200008 -254.285242) (xy 201.652124 -254.285242) (xy 201.652661 -254.252542)
			(xy 201.661269 -254.187711) (xy 201.678329 -254.124575) (xy 201.703543 -254.064231) (xy 201.736474 -254.007727)
			(xy 201.77655 -253.956044) (xy 201.799444 -253.93269) (xy 201.80681 -253.925324) (xy 201.81443 -253.906782)
			(xy 201.81443 -253.813818) (xy 201.80681 -253.795276) (xy 201.799444 -253.78791) (xy 201.776531 -253.764572)
			(xy 201.736449 -253.71289) (xy 201.703514 -253.656384) (xy 201.6783 -253.596036) (xy 201.661245 -253.532895)
			(xy 201.652646 -253.46806) (xy 201.652124 -253.435358) (xy 201.65258 -253.404148) (xy 201.660405 -253.34222)
			(xy 201.675938 -253.281764) (xy 201.698934 -253.223734) (xy 201.729029 -253.169048) (xy 201.765748 -253.118571)
			(xy 201.80851 -253.0731) (xy 201.85664 -253.033353) (xy 201.882756 -253.016258) (xy 201.892916 -253.009908)
			(xy 201.905108 -252.990096) (xy 201.91476 -252.885956) (xy 201.906378 -252.864112) (xy 201.897488 -252.855984)
			(xy 201.879158 -252.838471) (xy 201.847017 -252.799267) (xy 201.820545 -252.756032) (xy 201.800241 -252.70958)
			(xy 201.786489 -252.660786) (xy 201.779546 -252.610568) (xy 201.779124 -252.58522) (xy 201.779538 -252.559902)
			(xy 201.786463 -252.509743) (xy 201.800185 -252.461002) (xy 201.820447 -252.414597) (xy 201.846867 -252.371401)
			(xy 201.878949 -252.332226) (xy 201.897234 -252.31471) (xy 201.906124 -252.306328) (xy 201.914506 -252.284738)
			(xy 201.905108 -252.180598) (xy 201.892916 -252.160786) (xy 201.882756 -252.154182) (xy 201.856655 -252.137091)
			(xy 201.808536 -252.097379) (xy 201.76578 -252.051942) (xy 201.729065 -252.001499) (xy 201.69897 -251.946847)
			(xy 201.675971 -251.888851) (xy 201.660431 -251.828427) (xy 201.652597 -251.766531) (xy 201.652124 -251.735336)
			(xy 201.652563 -251.704125) (xy 201.66039 -251.642197) (xy 201.675926 -251.58174) (xy 201.698925 -251.52371)
			(xy 201.729022 -251.469025) (xy 201.765743 -251.418548) (xy 201.808508 -251.373077) (xy 201.856639 -251.333331)
			(xy 201.882756 -251.316236) (xy 201.892916 -251.309886) (xy 201.905108 -251.290074) (xy 201.91476 -251.185934)
			(xy 201.906378 -251.16409) (xy 201.897488 -251.155962) (xy 201.879148 -251.13846) (xy 201.847007 -251.099254)
			(xy 201.820537 -251.056016) (xy 201.800235 -251.009562) (xy 201.786485 -250.960766) (xy 201.779544 -250.910546)
			(xy 201.779124 -250.885198) (xy 201.779523 -250.85988) (xy 201.786451 -250.80972) (xy 201.800176 -250.760979)
			(xy 201.820441 -250.714574) (xy 201.846864 -250.671378) (xy 201.878948 -250.632203) (xy 201.897234 -250.614688)
			(xy 201.906124 -250.606306) (xy 201.914506 -250.584716) (xy 201.905108 -250.480576) (xy 201.892916 -250.460764)
			(xy 201.882756 -250.45416) (xy 201.856656 -250.437065) (xy 201.80853 -250.397357) (xy 201.765769 -250.351922)
			(xy 201.729048 -250.30148) (xy 201.698949 -250.246827) (xy 201.675948 -250.188829) (xy 201.660408 -250.128403)
			(xy 201.652576 -250.066504) (xy 201.652575 -250.004111) (xy 201.660405 -249.942212) (xy 201.675943 -249.881785)
			(xy 201.698943 -249.823786) (xy 201.72904 -249.769133) (xy 201.765759 -249.718689) (xy 201.808519 -249.673254)
			(xy 201.856644 -249.633544) (xy 201.882756 -249.616468) (xy 201.892916 -249.609864) (xy 201.905108 -249.590052)
			(xy 201.914506 -249.485912) (xy 201.906124 -249.464322) (xy 201.897234 -249.45594) (xy 201.878956 -249.438417)
			(xy 201.846878 -249.399241) (xy 201.82046 -249.356045) (xy 201.800198 -249.309642) (xy 201.786474 -249.260904)
			(xy 201.779544 -249.210747) (xy 201.779124 -249.18543) (xy 201.779501 -249.16008) (xy 201.786443 -249.109858)
			(xy 201.800201 -249.061061) (xy 201.820515 -249.014609) (xy 201.847001 -248.971379) (xy 201.879161 -248.932185)
			(xy 201.897488 -248.914666) (xy 201.906378 -248.906538) (xy 201.91476 -248.884694) (xy 201.905108 -248.780554)
			(xy 201.892916 -248.760742) (xy 201.882756 -248.754392) (xy 201.856624 -248.737323) (xy 201.808504 -248.697566)
			(xy 201.76575 -248.652086) (xy 201.729038 -248.601604) (xy 201.698948 -248.546915) (xy 201.675955 -248.488885)
			(xy 201.660422 -248.428429) (xy 201.652594 -248.366502) (xy 201.652124 -248.335292) (xy 201.652543 -248.304093)
			(xy 201.660367 -248.242188) (xy 201.675902 -248.181756) (xy 201.698902 -248.123752) (xy 201.729004 -248.069096)
			(xy 201.765731 -248.018652) (xy 201.808501 -247.97322) (xy 201.856638 -247.933517) (xy 201.882756 -247.916446)
			(xy 201.892916 -247.909842) (xy 201.905108 -247.89003) (xy 201.914506 -247.78589) (xy 201.906124 -247.7643)
			(xy 201.897234 -247.755918) (xy 201.878946 -247.738406) (xy 201.846869 -247.699227) (xy 201.820452 -247.656029)
			(xy 201.800192 -247.609624) (xy 201.78647 -247.560884) (xy 201.779543 -247.510725) (xy 201.779124 -247.485408)
			(xy 201.779553 -247.46006) (xy 201.786485 -247.40984) (xy 201.800232 -247.361044) (xy 201.820536 -247.314592)
			(xy 201.847013 -247.27136) (xy 201.879165 -247.232164) (xy 201.897488 -247.214644) (xy 201.906378 -247.206516)
			(xy 201.91476 -247.184672) (xy 201.905108 -247.080532) (xy 201.892916 -247.06072) (xy 201.882756 -247.05437)
			(xy 201.856659 -247.037249) (xy 201.808539 -246.997499) (xy 201.765784 -246.952027) (xy 201.729069 -246.901552)
			(xy 201.698975 -246.846872) (xy 201.675976 -246.788848) (xy 201.660435 -246.728399) (xy 201.652599 -246.666478)
			(xy 201.652124 -246.63527) (xy 201.652604 -246.604073) (xy 201.660418 -246.542171) (xy 201.675944 -246.48174)
			(xy 201.698936 -246.423737) (xy 201.729029 -246.36908) (xy 201.765748 -246.318635) (xy 201.808511 -246.273201)
			(xy 201.856641 -246.233496) (xy 201.882756 -246.216424) (xy 201.892916 -246.20982) (xy 201.905108 -246.190008)
			(xy 201.914506 -246.085868) (xy 201.906124 -246.064278) (xy 201.897234 -246.055896) (xy 201.878935 -246.038394)
			(xy 201.846859 -245.999213) (xy 201.820444 -245.956013) (xy 201.800186 -245.909606) (xy 201.786466 -245.860864)
			(xy 201.779541 -245.810704) (xy 201.779124 -245.785386) (xy 201.779539 -245.760038) (xy 201.786473 -245.709817)
			(xy 201.800224 -245.661021) (xy 201.82053 -245.614569) (xy 201.84701 -245.571337) (xy 201.879164 -245.532142)
			(xy 201.897488 -245.514622) (xy 201.906378 -245.506494) (xy 201.91476 -245.48465) (xy 201.905108 -245.38051)
			(xy 201.892916 -245.360698) (xy 201.882756 -245.354348) (xy 201.856649 -245.337242) (xy 201.808529 -245.297489)
			(xy 201.765774 -245.252016) (xy 201.729061 -245.201539) (xy 201.698967 -245.146856) (xy 201.67597 -245.088831)
			(xy 201.660432 -245.028379) (xy 201.652597 -244.966456) (xy 201.652124 -244.935248) (xy 201.652587 -244.904051)
			(xy 201.660404 -244.842147) (xy 201.675932 -244.781716) (xy 201.698926 -244.723713) (xy 201.729022 -244.669056)
			(xy 201.765743 -244.618612) (xy 201.808508 -244.573178) (xy 201.85664 -244.533474) (xy 201.882756 -244.516402)
			(xy 201.892916 -244.509798) (xy 201.905108 -244.489986) (xy 201.914506 -244.385846) (xy 201.906124 -244.364256)
			(xy 201.897234 -244.355874) (xy 201.878924 -244.338383) (xy 201.846849 -244.2992) (xy 201.820435 -244.255998)
			(xy 201.800179 -244.209588) (xy 201.786461 -244.160845) (xy 201.77954 -244.110683) (xy 201.779124 -244.085364)
			(xy 201.779524 -244.060015) (xy 201.786462 -244.009794) (xy 201.800215 -243.960998) (xy 201.820524 -243.914546)
			(xy 201.847007 -243.871314) (xy 201.879163 -243.832119) (xy 201.897488 -243.8146) (xy 201.906378 -243.806472)
			(xy 201.91476 -243.784628) (xy 201.905108 -243.680488) (xy 201.892916 -243.660676) (xy 201.882756 -243.654326)
			(xy 201.856639 -243.637235) (xy 201.808519 -243.59748) (xy 201.765765 -243.552004) (xy 201.729052 -243.501525)
			(xy 201.69896 -243.44684) (xy 201.675964 -243.388813) (xy 201.660428 -243.328359) (xy 201.652596 -243.266435)
			(xy 201.652124 -243.235226) (xy 201.65257 -243.204028) (xy 201.660389 -243.142124) (xy 201.67592 -243.081692)
			(xy 201.698917 -243.023689) (xy 201.729015 -242.969033) (xy 201.765738 -242.918589) (xy 201.808505 -242.873155)
			(xy 201.856639 -242.833452) (xy 201.882756 -242.81638) (xy 201.892916 -242.809776) (xy 201.905108 -242.789964)
			(xy 201.914506 -242.685824) (xy 201.906124 -242.664234) (xy 201.897234 -242.655852) (xy 201.878962 -242.638323)
			(xy 201.846884 -242.599148) (xy 201.820465 -242.555954) (xy 201.800202 -242.509552) (xy 201.786476 -242.460815)
			(xy 201.779545 -242.410658) (xy 201.779124 -242.385342) (xy 201.779509 -242.359993) (xy 201.78645 -242.309771)
			(xy 201.800206 -242.260974) (xy 201.820518 -242.214522) (xy 201.847003 -242.171291) (xy 201.879161 -242.132097)
			(xy 201.897488 -242.114578) (xy 201.906378 -242.10645) (xy 201.91476 -242.084606) (xy 201.905108 -241.980466)
			(xy 201.892916 -241.960654) (xy 201.882756 -241.954304) (xy 201.856629 -241.937227) (xy 201.808509 -241.897471)
			(xy 201.765755 -241.851993) (xy 201.729043 -241.801511) (xy 201.698952 -241.746824) (xy 201.675958 -241.688795)
			(xy 201.660424 -241.62834) (xy 201.652595 -241.566414) (xy 201.652124 -241.535204) (xy 201.652613 -241.504041)
			(xy 201.660425 -241.442207) (xy 201.675925 -241.381839) (xy 201.698868 -241.323891) (xy 201.728894 -241.269274)
			(xy 201.765528 -241.218852) (xy 201.808193 -241.173418) (xy 201.856215 -241.13369) (xy 201.908839 -241.100295)
			(xy 201.965233 -241.073758) (xy 202.024508 -241.054498) (xy 202.085729 -241.042819) (xy 202.147932 -241.038906)
			(xy 202.210135 -241.042819) (xy 202.271356 -241.054498) (xy 202.330631 -241.073758) (xy 202.387025 -241.100295)
			(xy 202.439649 -241.13369) (xy 202.487671 -241.173418) (xy 202.530336 -241.218852) (xy 202.56697 -241.269274)
			(xy 202.596996 -241.323891) (xy 202.619939 -241.381839) (xy 202.635439 -241.442207) (xy 202.643251 -241.504041)
			(xy 202.64374 -241.535204) (xy 202.643224 -241.566412) (xy 202.635406 -241.628336) (xy 202.619879 -241.68879)
			(xy 202.596891 -241.746818) (xy 202.566804 -241.801503) (xy 202.530094 -241.851982) (xy 202.487341 -241.897456)
			(xy 202.43922 -241.937206) (xy 202.413108 -241.954304) (xy 202.402948 -241.960654) (xy 202.390756 -241.980466)
			(xy 202.381104 -242.084606) (xy 202.389486 -242.10645) (xy 202.398376 -242.114578) (xy 202.41668 -242.132116)
			(xy 202.448826 -242.171314) (xy 202.475302 -242.214543) (xy 202.49561 -242.260991) (xy 202.509368 -242.309781)
			(xy 202.516316 -242.359996) (xy 202.51674 -242.385342) (xy 202.516312 -242.410659) (xy 202.509391 -242.460819)
			(xy 202.495673 -242.509559) (xy 202.475413 -242.555964) (xy 202.448995 -242.599161) (xy 202.416915 -242.638336)
			(xy 202.39863 -242.655852) (xy 202.38974 -242.664234) (xy 202.381358 -242.685824) (xy 202.390756 -242.789964)
			(xy 202.402948 -242.809776) (xy 202.413108 -242.81638) (xy 202.439206 -242.833475) (xy 202.487323 -242.873189)
			(xy 202.530076 -242.918626) (xy 202.56679 -242.969069) (xy 202.596885 -243.023719) (xy 202.619886 -243.081714)
			(xy 202.635427 -243.142137) (xy 202.643264 -243.204031) (xy 202.64374 -243.235226) (xy 202.643242 -243.266434)
			(xy 202.63542 -243.328359) (xy 202.619891 -243.388813) (xy 202.5969 -243.446842) (xy 202.566811 -243.501527)
			(xy 202.530099 -243.552005) (xy 202.487343 -243.597479) (xy 202.439221 -243.637229) (xy 202.413108 -243.654326)
			(xy 202.402948 -243.660676) (xy 202.390756 -243.680488) (xy 202.381104 -243.784628) (xy 202.389486 -243.806472)
			(xy 202.398376 -243.8146) (xy 202.416691 -243.832128) (xy 202.448835 -243.871327) (xy 202.47531 -243.914559)
			(xy 202.495616 -243.961009) (xy 202.509372 -244.009801) (xy 202.516317 -244.060017) (xy 202.51674 -244.085364)
			(xy 204.354682 -244.085364) (xy 204.358756 -244.021896) (xy 204.370914 -243.959471) (xy 204.390954 -243.899112)
			(xy 204.418548 -243.841812) (xy 204.453244 -243.788511) (xy 204.49447 -243.740084) (xy 204.54155 -243.697327)
			(xy 204.593712 -243.660941) (xy 204.650099 -243.631524) (xy 204.709784 -243.609559) (xy 204.771788 -243.595407)
			(xy 204.835092 -243.589301) (xy 204.898658 -243.591339) (xy 204.961441 -243.601489) (xy 205.022411 -243.619585)
			(xy 205.080566 -243.645328) (xy 205.134952 -243.678297) (xy 205.184675 -243.71795) (xy 205.22892 -243.763636)
			(xy 205.266959 -243.814605) (xy 205.298168 -243.870019) (xy 205.322034 -243.92897) (xy 205.338166 -243.990488)
			(xy 205.346299 -244.053565) (xy 205.346808 -244.085364) (xy 205.346299 -244.117163) (xy 205.338166 -244.18024)
			(xy 205.322034 -244.241758) (xy 205.298168 -244.300709) (xy 205.266959 -244.356123) (xy 205.22892 -244.407092)
			(xy 205.184675 -244.452778) (xy 205.134952 -244.492431) (xy 205.080566 -244.5254) (xy 205.022411 -244.551143)
			(xy 204.961441 -244.569239) (xy 204.898658 -244.579389) (xy 204.835092 -244.581427) (xy 204.771788 -244.575321)
			(xy 204.709784 -244.561169) (xy 204.650099 -244.539204) (xy 204.593712 -244.509787) (xy 204.54155 -244.473401)
			(xy 204.49447 -244.430644) (xy 204.453244 -244.382217) (xy 204.418548 -244.328916) (xy 204.390954 -244.271616)
			(xy 204.370914 -244.211257) (xy 204.358756 -244.148832) (xy 204.354682 -244.085364) (xy 202.51674 -244.085364)
			(xy 202.516327 -244.110682) (xy 202.509403 -244.160842) (xy 202.495681 -244.209583) (xy 202.475419 -244.255988)
			(xy 202.448999 -244.299184) (xy 202.416916 -244.338358) (xy 202.39863 -244.355874) (xy 202.38974 -244.364256)
			(xy 202.381358 -244.385846) (xy 202.390756 -244.489986) (xy 202.402948 -244.509798) (xy 202.413108 -244.516402)
			(xy 202.439216 -244.533482) (xy 202.487333 -244.573198) (xy 202.530086 -244.618638) (xy 202.566799 -244.669082)
			(xy 202.596893 -244.723735) (xy 202.619891 -244.781732) (xy 202.635431 -244.842156) (xy 202.643266 -244.904053)
			(xy 202.64374 -244.935248) (xy 202.643259 -244.966457) (xy 202.635435 -245.028382) (xy 202.619903 -245.088837)
			(xy 202.59691 -245.146865) (xy 202.566818 -245.201551) (xy 202.530103 -245.252029) (xy 202.487346 -245.297502)
			(xy 202.439221 -245.337251) (xy 202.413108 -245.354348) (xy 202.402948 -245.360698) (xy 202.390756 -245.38051)
			(xy 202.381104 -245.48465) (xy 202.389486 -245.506494) (xy 202.398376 -245.514622) (xy 202.416702 -245.532139)
			(xy 202.448845 -245.571341) (xy 202.475318 -245.614575) (xy 202.495623 -245.661027) (xy 202.509376 -245.709821)
			(xy 202.516319 -245.760038) (xy 202.51674 -245.785386) (xy 202.516341 -245.810704) (xy 202.509415 -245.860865)
			(xy 202.49569 -245.909606) (xy 202.475425 -245.956011) (xy 202.449002 -245.999207) (xy 202.416917 -246.038381)
			(xy 202.39863 -246.055896) (xy 202.38974 -246.064278) (xy 202.381358 -246.085868) (xy 202.390756 -246.190008)
			(xy 202.402948 -246.20982) (xy 202.413108 -246.216424) (xy 202.439226 -246.233489) (xy 202.487343 -246.273207)
			(xy 202.530095 -246.318649) (xy 202.566808 -246.369096) (xy 202.5969 -246.423751) (xy 202.619897 -246.48175)
			(xy 202.635435 -246.542176) (xy 202.643267 -246.604074) (xy 202.64374 -246.63527) (xy 202.643276 -246.666479)
			(xy 202.635449 -246.728406) (xy 202.619915 -246.788861) (xy 202.596919 -246.846889) (xy 202.566825 -246.901574)
			(xy 202.530108 -246.952052) (xy 202.487349 -246.997524) (xy 202.439222 -247.037273) (xy 202.413108 -247.05437)
			(xy 202.402948 -247.06072) (xy 202.390756 -247.080532) (xy 202.381104 -247.184672) (xy 202.389486 -247.206516)
			(xy 202.398376 -247.214644) (xy 202.416712 -247.23215) (xy 202.448855 -247.271355) (xy 202.475327 -247.314591)
			(xy 202.495629 -247.361045) (xy 202.50938 -247.409841) (xy 202.51632 -247.46006) (xy 202.51674 -247.485408)
			(xy 202.516356 -247.510727) (xy 202.509427 -247.560888) (xy 202.495699 -247.60963) (xy 202.475432 -247.656035)
			(xy 202.449006 -247.69923) (xy 202.416918 -247.738404) (xy 202.39863 -247.755918) (xy 202.38974 -247.7643)
			(xy 202.381358 -247.78589) (xy 202.390756 -247.89003) (xy 202.402948 -247.909842) (xy 202.413108 -247.916446)
			(xy 202.439236 -247.933497) (xy 202.487353 -247.973217) (xy 202.530105 -248.018661) (xy 202.566817 -248.06911)
			(xy 202.596908 -248.123767) (xy 202.619903 -248.181768) (xy 202.635438 -248.242196) (xy 202.643268 -248.304096)
			(xy 202.64374 -248.335292) (xy 202.643215 -248.3665) (xy 202.635398 -248.428423) (xy 202.619873 -248.488877)
			(xy 202.596886 -248.546905) (xy 202.5668 -248.60159) (xy 202.530091 -248.652069) (xy 202.487339 -248.697543)
			(xy 202.439219 -248.737294) (xy 202.413108 -248.754392) (xy 202.402948 -248.760742) (xy 202.390756 -248.780554)
			(xy 202.381104 -248.884694) (xy 202.389486 -248.906538) (xy 202.398376 -248.914666) (xy 202.416675 -248.93221)
			(xy 202.44882 -248.971406) (xy 202.475297 -249.014635) (xy 202.495606 -249.061081) (xy 202.509365 -249.10987)
			(xy 202.516315 -249.160084) (xy 202.51674 -249.18543) (xy 202.516304 -249.210747) (xy 202.509385 -249.260906)
			(xy 202.495668 -249.309647) (xy 202.47541 -249.356052) (xy 202.448993 -249.399248) (xy 202.416914 -249.438424)
			(xy 202.39863 -249.45594) (xy 202.38974 -249.464322) (xy 202.381358 -249.485912) (xy 202.390756 -249.590052)
			(xy 202.402948 -249.609864) (xy 202.413108 -249.616468) (xy 202.439235 -249.633524) (xy 202.487366 -249.673233)
			(xy 202.530131 -249.71867) (xy 202.566855 -249.769116) (xy 202.596956 -249.823772) (xy 202.619958 -249.881775)
			(xy 202.635498 -249.942205) (xy 202.643329 -250.004109) (xy 202.643328 -250.066506) (xy 202.635495 -250.128409)
			(xy 202.619953 -250.18884) (xy 202.596949 -250.246841) (xy 202.566847 -250.301497) (xy 202.530122 -250.351941)
			(xy 202.487355 -250.397377) (xy 202.439223 -250.437085) (xy 202.413108 -250.45416) (xy 202.402948 -250.460764)
			(xy 202.390756 -250.480576) (xy 202.381358 -250.584716) (xy 202.38974 -250.606306) (xy 202.39863 -250.614688)
			(xy 202.416914 -250.632204) (xy 202.448993 -250.671381) (xy 202.475411 -250.714578) (xy 202.495672 -250.760982)
			(xy 202.509395 -250.809722) (xy 202.516322 -250.859881) (xy 202.51674 -250.885198) (xy 202.516294 -250.910545)
			(xy 202.509363 -250.960763) (xy 202.495618 -251.009558) (xy 202.475317 -251.05601) (xy 202.448843 -251.099242)
			(xy 202.416697 -251.138441) (xy 202.398376 -251.155962) (xy 202.389486 -251.16409) (xy 202.381104 -251.185934)
			(xy 202.390756 -251.290074) (xy 202.402948 -251.309886) (xy 202.413108 -251.316236) (xy 202.439199 -251.333365)
			(xy 202.487321 -251.373113) (xy 202.530077 -251.418583) (xy 202.566793 -251.469056) (xy 202.596888 -251.523736)
			(xy 202.619888 -251.581759) (xy 202.635429 -251.642208) (xy 202.643265 -251.704129) (xy 202.64374 -251.735336)
			(xy 202.643235 -251.766532) (xy 202.635421 -251.828432) (xy 202.619897 -251.888861) (xy 202.596908 -251.946863)
			(xy 202.566818 -252.001519) (xy 202.530103 -252.051964) (xy 202.487345 -252.0974) (xy 202.43922 -252.137108)
			(xy 202.413108 -252.154182) (xy 202.402948 -252.160786) (xy 202.390756 -252.180598) (xy 202.381358 -252.284738)
			(xy 202.38974 -252.306328) (xy 202.39863 -252.31471) (xy 202.416925 -252.332216) (xy 202.449003 -252.371395)
			(xy 202.475419 -252.414594) (xy 202.495679 -252.461) (xy 202.509399 -252.509742) (xy 202.516323 -252.559902)
			(xy 202.51674 -252.58522) (xy 202.516309 -252.610568) (xy 202.509375 -252.660786) (xy 202.495626 -252.709582)
			(xy 202.475323 -252.756033) (xy 202.448847 -252.799265) (xy 202.416698 -252.838463) (xy 202.398376 -252.855984)
			(xy 202.389486 -252.864112) (xy 202.381104 -252.885956) (xy 202.390756 -252.990096) (xy 202.402948 -253.009908)
			(xy 202.413108 -253.016258) (xy 202.439209 -253.033373) (xy 202.487331 -253.073123) (xy 202.530087 -253.118595)
			(xy 202.566802 -253.16907) (xy 202.596896 -253.223752) (xy 202.619894 -253.281777) (xy 202.635433 -253.342228)
			(xy 202.643266 -253.40415) (xy 202.64374 -253.435358) (xy 202.643214 -253.468058) (xy 202.634605 -253.53289)
			(xy 202.617544 -253.596027) (xy 202.592328 -253.656371) (xy 202.559394 -253.712875) (xy 202.519315 -253.764556)
			(xy 202.49642 -253.78791) (xy 202.489054 -253.795276) (xy 202.481434 -253.813818) (xy 202.481434 -253.906782)
			(xy 202.489054 -253.925324) (xy 202.49642 -253.93269) (xy 202.519326 -253.956034) (xy 202.559411 -254.007714)
			(xy 202.592347 -254.064218) (xy 202.617562 -254.124565) (xy 202.634618 -254.187705) (xy 202.643218 -254.25254)
			(xy 202.64374 -254.285242) (xy 205.752192 -254.285242) (xy 205.752665 -254.254045) (xy 205.760482 -254.192143)
			(xy 205.77601 -254.131712) (xy 205.799003 -254.07371) (xy 205.829098 -254.019054) (xy 205.865817 -253.968609)
			(xy 205.90858 -253.923174) (xy 205.956709 -253.883469) (xy 205.982824 -253.866396) (xy 205.992984 -253.859792)
			(xy 206.005176 -253.83998) (xy 206.014574 -253.73584) (xy 206.006192 -253.71425) (xy 205.997302 -253.705868)
			(xy 205.979002 -253.688367) (xy 205.946924 -253.649187) (xy 205.920507 -253.605988) (xy 205.900248 -253.55958)
			(xy 205.886529 -253.510838) (xy 205.879608 -253.460676) (xy 205.879192 -253.435358) (xy 205.879598 -253.410009)
			(xy 205.886536 -253.359789) (xy 205.900289 -253.310993) (xy 205.920597 -253.264541) (xy 205.947078 -253.22131)
			(xy 205.979232 -253.182114) (xy 205.997556 -253.164594) (xy 206.006446 -253.156466) (xy 206.014828 -253.134622)
			(xy 206.005176 -253.030482) (xy 205.992984 -253.01067) (xy 205.982824 -253.00432) (xy 205.95672 -252.987209)
			(xy 205.908597 -252.947459) (xy 205.86584 -252.901988) (xy 205.829125 -252.851512) (xy 205.799031 -252.796829)
			(xy 205.776033 -252.738804) (xy 205.760496 -252.678352) (xy 205.752664 -252.616428) (xy 205.752192 -252.58522)
			(xy 205.752648 -252.554023) (xy 205.760468 -252.49212) (xy 205.775998 -252.431689) (xy 205.798994 -252.373686)
			(xy 205.829091 -252.31903) (xy 205.865812 -252.268586) (xy 205.908577 -252.223151) (xy 205.956708 -252.183447)
			(xy 205.982824 -252.166374) (xy 205.992984 -252.15977) (xy 206.005176 -252.139958) (xy 206.014574 -252.035818)
			(xy 206.006192 -252.014228) (xy 205.997302 -252.005846) (xy 205.97904 -251.988307) (xy 205.946958 -251.949136)
			(xy 205.920536 -251.905944) (xy 205.900271 -251.859544) (xy 205.886544 -251.810808) (xy 205.879613 -251.760652)
			(xy 205.879192 -251.735336) (xy 205.879583 -251.709987) (xy 205.886524 -251.659766) (xy 205.90028 -251.61097)
			(xy 205.920591 -251.564518) (xy 205.947074 -251.521287) (xy 205.979231 -251.482091) (xy 205.997556 -251.464572)
			(xy 206.006446 -251.456444) (xy 206.014828 -251.4346) (xy 206.005176 -251.33046) (xy 205.992984 -251.310648)
			(xy 205.982824 -251.304298) (xy 205.95671 -251.287202) (xy 205.908587 -251.24745) (xy 205.865831 -251.201976)
			(xy 205.829116 -251.151498) (xy 205.799023 -251.096813) (xy 205.776027 -251.038786) (xy 205.760492 -250.978332)
			(xy 205.752663 -250.916407) (xy 205.752192 -250.885198) (xy 205.752631 -250.854) (xy 205.760453 -250.792096)
			(xy 205.775986 -250.731665) (xy 205.798984 -250.673662) (xy 205.829084 -250.619006) (xy 205.865807 -250.568562)
			(xy 205.908574 -250.523128) (xy 205.956708 -250.483424) (xy 205.982824 -250.466352) (xy 205.992984 -250.459748)
			(xy 206.005176 -250.439936) (xy 206.014574 -250.335796) (xy 206.006192 -250.314206) (xy 205.997302 -250.305824)
			(xy 205.977391 -250.286674) (xy 205.942925 -250.243501) (xy 205.915285 -250.19567) (xy 205.895087 -250.144253)
			(xy 205.882785 -250.090397) (xy 205.878652 -250.03531) (xy 205.882782 -249.980222) (xy 205.895082 -249.926366)
			(xy 205.915277 -249.874947) (xy 205.942915 -249.827115) (xy 205.977378 -249.78394) (xy 205.997302 -249.764804)
			(xy 206.006192 -249.756422) (xy 206.014574 -249.734832) (xy 206.005176 -249.630692) (xy 205.992984 -249.61088)
			(xy 205.982824 -249.604276) (xy 205.956713 -249.5872) (xy 205.908595 -249.547484) (xy 205.865841 -249.502045)
			(xy 205.829127 -249.4516) (xy 205.799034 -249.396946) (xy 205.776036 -249.338948) (xy 205.760498 -249.278523)
			(xy 205.752665 -249.216625) (xy 205.752192 -249.18543) (xy 205.752641 -249.15422) (xy 205.760469 -249.092293)
			(xy 205.776004 -249.031837) (xy 205.799001 -248.973807) (xy 205.829098 -248.919122) (xy 205.865817 -248.868645)
			(xy 205.908579 -248.823173) (xy 205.956708 -248.783426) (xy 205.982824 -248.76633) (xy 205.992984 -248.75998)
			(xy 206.005176 -248.740168) (xy 206.014828 -248.636028) (xy 206.006446 -248.614184) (xy 205.997556 -248.606056)
			(xy 205.979226 -248.588544) (xy 205.947082 -248.549341) (xy 205.920608 -248.506106) (xy 205.900304 -248.459654)
			(xy 205.886552 -248.410859) (xy 205.879612 -248.36064) (xy 205.879192 -248.335292) (xy 205.879597 -248.309974)
			(xy 205.886525 -248.259815) (xy 205.90025 -248.211074) (xy 205.920514 -248.16467) (xy 205.946935 -248.121474)
			(xy 205.979017 -248.082298) (xy 205.997302 -248.064782) (xy 206.006192 -248.0564) (xy 206.014574 -248.03481)
			(xy 206.005176 -247.93067) (xy 205.992984 -247.910858) (xy 205.982824 -247.904254) (xy 205.956703 -247.887192)
			(xy 205.908585 -247.847475) (xy 205.865832 -247.802033) (xy 205.829119 -247.751586) (xy 205.799026 -247.69693)
			(xy 205.77603 -247.63893) (xy 205.760494 -247.578503) (xy 205.752664 -247.516604) (xy 205.752192 -247.485408)
			(xy 205.752702 -247.4542) (xy 205.76052 -247.392275) (xy 205.776046 -247.33182) (xy 205.799035 -247.273792)
			(xy 205.829122 -247.219106) (xy 205.865834 -247.168628) (xy 205.908589 -247.123154) (xy 205.956711 -247.083405)
			(xy 205.982824 -247.066308) (xy 205.992984 -247.059958) (xy 206.005176 -247.040146) (xy 206.014828 -246.936006)
			(xy 206.006446 -246.914162) (xy 205.997556 -246.906034) (xy 205.979264 -246.888484) (xy 205.947116 -246.849289)
			(xy 205.920638 -246.806063) (xy 205.900327 -246.759618) (xy 205.886567 -246.710829) (xy 205.879617 -246.660616)
			(xy 205.879192 -246.63527) (xy 205.87965 -246.609954) (xy 205.886567 -246.559797) (xy 205.900282 -246.511057)
			(xy 205.920535 -246.464653) (xy 205.946947 -246.421456) (xy 205.979021 -246.382278) (xy 205.997302 -246.36476)
			(xy 206.006192 -246.356378) (xy 206.014574 -246.334788) (xy 206.005176 -246.230648) (xy 205.992984 -246.210836)
			(xy 205.982824 -246.204232) (xy 205.956739 -246.187118) (xy 205.908621 -246.147408) (xy 205.865866 -246.101974)
			(xy 205.829149 -246.051534) (xy 205.799053 -245.996886) (xy 205.776051 -245.938894) (xy 205.760507 -245.878473)
			(xy 205.752668 -245.81658) (xy 205.752192 -245.785386) (xy 205.752685 -245.754177) (xy 205.760506 -245.692252)
			(xy 205.776034 -245.631797) (xy 205.799025 -245.573768) (xy 205.829115 -245.519082) (xy 205.865829 -245.468604)
			(xy 205.908586 -245.423131) (xy 205.95671 -245.383383) (xy 205.982824 -245.366286) (xy 205.992984 -245.359936)
			(xy 206.005176 -245.340124) (xy 206.014828 -245.235984) (xy 206.006446 -245.21414) (xy 205.997556 -245.206012)
			(xy 205.979253 -245.188472) (xy 205.947106 -245.149276) (xy 205.920629 -245.106047) (xy 205.900321 -245.0596)
			(xy 205.886563 -245.010809) (xy 205.879616 -244.960594) (xy 205.879192 -244.935248) (xy 205.879634 -244.909931)
			(xy 205.886555 -244.859773) (xy 205.900272 -244.811034) (xy 205.920529 -244.764629) (xy 205.946944 -244.721432)
			(xy 205.979019 -244.682255) (xy 205.997302 -244.664738) (xy 206.006192 -244.656356) (xy 206.014574 -244.634766)
			(xy 206.005176 -244.530626) (xy 205.992984 -244.510814) (xy 205.982824 -244.50421) (xy 205.956729 -244.487111)
			(xy 205.908611 -244.447399) (xy 205.865856 -244.401963) (xy 205.829141 -244.351521) (xy 205.799045 -244.296871)
			(xy 205.776045 -244.238876) (xy 205.760504 -244.178453) (xy 205.752667 -244.116558) (xy 205.752192 -244.085364)
			(xy 205.752668 -244.054155) (xy 205.760491 -243.992228) (xy 205.776022 -243.931773) (xy 205.799016 -243.873744)
			(xy 205.829108 -243.819059) (xy 205.865824 -243.768581) (xy 205.908583 -243.723108) (xy 205.95671 -243.68336)
			(xy 205.982824 -243.666264) (xy 205.992984 -243.659914) (xy 206.005176 -243.640102) (xy 206.014828 -243.535962)
			(xy 206.006446 -243.514118) (xy 205.997556 -243.50599) (xy 205.979242 -243.488461) (xy 205.947097 -243.449262)
			(xy 205.920621 -243.406031) (xy 205.900314 -243.359582) (xy 205.886559 -243.310789) (xy 205.879614 -243.260573)
			(xy 205.879192 -243.235226) (xy 205.87962 -243.209909) (xy 205.886543 -243.15975) (xy 205.900264 -243.111011)
			(xy 205.920523 -243.064606) (xy 205.94694 -243.021409) (xy 205.979018 -242.982233) (xy 205.997302 -242.964716)
			(xy 206.006192 -242.956334) (xy 206.014574 -242.934744) (xy 206.005176 -242.830604) (xy 205.992984 -242.810792)
			(xy 205.982824 -242.804188) (xy 205.956719 -242.787104) (xy 205.908601 -242.747389) (xy 205.865847 -242.701951)
			(xy 205.829132 -242.651507) (xy 205.799038 -242.596855) (xy 205.776039 -242.538858) (xy 205.7605 -242.478434)
			(xy 205.752666 -242.416537) (xy 205.752192 -242.385342) (xy 205.752651 -242.354132) (xy 205.760477 -242.292205)
			(xy 205.77601 -242.231749) (xy 205.799007 -242.17372) (xy 205.829101 -242.119035) (xy 205.86582 -242.068557)
			(xy 205.908581 -242.023085) (xy 205.956709 -241.983338) (xy 205.982824 -241.966242) (xy 205.992984 -241.959892)
			(xy 206.005176 -241.94008) (xy 206.014828 -241.83594) (xy 206.006446 -241.814096) (xy 205.997556 -241.805968)
			(xy 205.979232 -241.78845) (xy 205.947087 -241.749249) (xy 205.920613 -241.706015) (xy 205.900308 -241.659564)
			(xy 205.886555 -241.610769) (xy 205.879613 -241.560552) (xy 205.879192 -241.535204) (xy 205.879605 -241.509886)
			(xy 205.886532 -241.459727) (xy 205.900255 -241.410987) (xy 205.920517 -241.364583) (xy 205.946937 -241.321386)
			(xy 205.979017 -241.28221) (xy 205.997302 -241.264694) (xy 206.006192 -241.256312) (xy 206.014574 -241.234722)
			(xy 206.005176 -241.130582) (xy 205.992984 -241.11077) (xy 205.982824 -241.104166) (xy 205.956709 -241.087096)
			(xy 205.908591 -241.04738) (xy 205.865837 -241.00194) (xy 205.829123 -240.951493) (xy 205.79903 -240.896839)
			(xy 205.776033 -240.83884) (xy 205.760496 -240.778414) (xy 205.752664 -240.716516) (xy 205.752192 -240.68532)
			(xy 205.752681 -240.654157) (xy 205.760493 -240.592323) (xy 205.775993 -240.531955) (xy 205.798936 -240.474007)
			(xy 205.828962 -240.41939) (xy 205.865596 -240.368968) (xy 205.908261 -240.323534) (xy 205.956283 -240.283806)
			(xy 206.008907 -240.250411) (xy 206.065301 -240.223874) (xy 206.124576 -240.204614) (xy 206.185797 -240.192935)
			(xy 206.248 -240.189022) (xy 206.310203 -240.192935) (xy 206.371424 -240.204614) (xy 206.430699 -240.223874)
			(xy 206.487093 -240.250411) (xy 206.539717 -240.283806) (xy 206.587739 -240.323534) (xy 206.630404 -240.368968)
			(xy 206.667038 -240.41939) (xy 206.697064 -240.474007) (xy 206.720007 -240.531955) (xy 206.735507 -240.592323)
			(xy 206.743319 -240.654157) (xy 206.743808 -240.68532) (xy 206.743383 -240.716518) (xy 206.735559 -240.778423)
			(xy 206.720023 -240.838854) (xy 206.697023 -240.896857) (xy 206.666922 -240.951513) (xy 206.630197 -241.001957)
			(xy 206.587428 -241.04739) (xy 206.539293 -241.087094) (xy 206.513176 -241.104166) (xy 206.503016 -241.11077)
			(xy 206.490824 -241.130582) (xy 206.481426 -241.234722) (xy 206.489808 -241.256312) (xy 206.498698 -241.264694)
			(xy 206.516979 -241.282214) (xy 206.549059 -241.321389) (xy 206.575479 -241.364585) (xy 206.59574 -241.410989)
			(xy 206.609463 -241.459728) (xy 206.61639 -241.509887) (xy 206.616808 -241.535204) (xy 206.616377 -241.560552)
			(xy 206.609444 -241.610771) (xy 206.595696 -241.659566) (xy 206.575393 -241.706018) (xy 206.548916 -241.749251)
			(xy 206.516766 -241.788447) (xy 206.498444 -241.805968) (xy 206.489554 -241.814096) (xy 206.481172 -241.83594)
			(xy 206.490824 -241.94008) (xy 206.503016 -241.959892) (xy 206.513176 -241.966242) (xy 206.539262 -241.983378)
			(xy 206.587386 -242.023124) (xy 206.630143 -242.068592) (xy 206.66686 -242.119064) (xy 206.696957 -242.173743)
			(xy 206.719957 -242.231765) (xy 206.735497 -242.292214) (xy 206.743333 -242.354135) (xy 206.743808 -242.385342)
			(xy 206.743322 -242.416539) (xy 206.735507 -242.47844) (xy 206.719981 -242.53887) (xy 206.69699 -242.596873)
			(xy 206.666897 -242.651529) (xy 206.63018 -242.701974) (xy 206.587418 -242.747409) (xy 206.53929 -242.787115)
			(xy 206.513176 -242.804188) (xy 206.503016 -242.810792) (xy 206.490824 -242.830604) (xy 206.481426 -242.934744)
			(xy 206.489808 -242.956334) (xy 206.498698 -242.964716) (xy 206.51699 -242.982225) (xy 206.549069 -243.021403)
			(xy 206.575487 -243.064601) (xy 206.595747 -243.111007) (xy 206.609468 -243.159748) (xy 206.616391 -243.209908)
			(xy 206.616808 -243.235226) (xy 206.616391 -243.260574) (xy 206.609456 -243.310794) (xy 206.595705 -243.35959)
			(xy 206.575399 -243.406042) (xy 206.54892 -243.449274) (xy 206.516768 -243.48847) (xy 206.498444 -243.50599)
			(xy 206.489554 -243.514118) (xy 206.481172 -243.535962) (xy 206.490824 -243.640102) (xy 206.503016 -243.659914)
			(xy 206.513176 -243.666264) (xy 206.539272 -243.683386) (xy 206.587396 -243.723134) (xy 206.630153 -243.768604)
			(xy 206.666869 -243.819078) (xy 206.696964 -243.873759) (xy 206.719962 -243.931783) (xy 206.735501 -243.992234)
			(xy 206.743335 -244.054156) (xy 206.743808 -244.085364) (xy 206.74334 -244.116561) (xy 206.735522 -244.178463)
			(xy 206.719993 -244.238894) (xy 206.696999 -244.296897) (xy 206.666904 -244.351553) (xy 206.630184 -244.401997)
			(xy 206.587421 -244.447432) (xy 206.539291 -244.487137) (xy 206.513176 -244.50421) (xy 206.503016 -244.510814)
			(xy 206.490824 -244.530626) (xy 206.481426 -244.634766) (xy 206.489808 -244.656356) (xy 206.498698 -244.664738)
			(xy 206.516952 -244.682285) (xy 206.549035 -244.721454) (xy 206.575458 -244.764644) (xy 206.595724 -244.811043)
			(xy 206.609453 -244.859778) (xy 206.616386 -244.909932) (xy 206.616808 -244.935248) (xy 206.616406 -244.960597)
			(xy 206.609467 -245.010817) (xy 206.595714 -245.059613) (xy 206.575405 -245.106065) (xy 206.548923 -245.149297)
			(xy 206.516769 -245.188492) (xy 206.498444 -245.206012) (xy 206.489554 -245.21414) (xy 206.481172 -245.235984)
			(xy 206.490824 -245.340124) (xy 206.503016 -245.359936) (xy 206.513176 -245.366286) (xy 206.539283 -245.383393)
			(xy 206.587406 -245.423143) (xy 206.630162 -245.468615) (xy 206.666878 -245.519092) (xy 206.696971 -245.573775)
			(xy 206.719968 -245.631801) (xy 206.735505 -245.692254) (xy 206.743336 -245.754177) (xy 206.743808 -245.785386)
			(xy 206.743357 -245.816584) (xy 206.735536 -245.878487) (xy 206.720005 -245.938918) (xy 206.697009 -245.99692)
			(xy 206.666911 -246.051576) (xy 206.630189 -246.102021) (xy 206.587424 -246.147455) (xy 206.539292 -246.187159)
			(xy 206.513176 -246.204232) (xy 206.503016 -246.210836) (xy 206.490824 -246.230648) (xy 206.481426 -246.334788)
			(xy 206.489808 -246.356378) (xy 206.498698 -246.36476) (xy 206.516963 -246.382296) (xy 206.549044 -246.421468)
			(xy 206.575466 -246.46466) (xy 206.595731 -246.511061) (xy 206.609457 -246.559798) (xy 206.616388 -246.609954)
			(xy 206.616808 -246.63527) (xy 206.616421 -246.660619) (xy 206.609479 -246.71084) (xy 206.595723 -246.759637)
			(xy 206.575411 -246.806088) (xy 206.548927 -246.84932) (xy 206.51677 -246.888515) (xy 206.498444 -246.906034)
			(xy 206.489554 -246.914162) (xy 206.481172 -246.936006) (xy 206.490824 -247.040146) (xy 206.503016 -247.059958)
			(xy 206.513176 -247.066308) (xy 206.539293 -247.0834) (xy 206.587416 -247.123152) (xy 206.630172 -247.168627)
			(xy 206.666886 -247.219106) (xy 206.696979 -247.273791) (xy 206.719974 -247.331819) (xy 206.735509 -247.392273)
			(xy 206.743337 -247.454199) (xy 206.743808 -247.485408) (xy 206.743374 -247.516606) (xy 206.735551 -247.57851)
			(xy 206.720017 -247.638941) (xy 206.697018 -247.696944) (xy 206.666918 -247.7516) (xy 206.630194 -247.802044)
			(xy 206.587426 -247.847478) (xy 206.539293 -247.887182) (xy 206.513176 -247.904254) (xy 206.503016 -247.910858)
			(xy 206.490824 -247.93067) (xy 206.481426 -248.03481) (xy 206.489808 -248.0564) (xy 206.498698 -248.064782)
			(xy 206.516973 -248.082308) (xy 206.549054 -248.121482) (xy 206.575474 -248.164676) (xy 206.595737 -248.211079)
			(xy 206.609461 -248.259817) (xy 206.616389 -248.309975) (xy 206.616808 -248.335292) (xy 206.616369 -248.36064)
			(xy 206.609438 -248.410858) (xy 206.595691 -248.459654) (xy 206.575389 -248.506106) (xy 206.548914 -248.549338)
			(xy 206.516766 -248.588535) (xy 206.498444 -248.606056) (xy 206.489554 -248.614184) (xy 206.481172 -248.636028)
			(xy 206.490824 -248.740168) (xy 206.503016 -248.75998) (xy 206.513176 -248.76633) (xy 206.539257 -248.783475)
			(xy 206.58738 -248.823219) (xy 206.630138 -248.868686) (xy 206.666855 -248.919157) (xy 206.696952 -248.973835)
			(xy 206.719953 -249.031856) (xy 206.735495 -249.092303) (xy 206.743333 -249.154223) (xy 206.743808 -249.18543)
			(xy 206.743313 -249.216626) (xy 206.7355 -249.278528) (xy 206.719975 -249.338958) (xy 206.696985 -249.39696)
			(xy 206.666894 -249.451616) (xy 206.630177 -249.502061) (xy 206.587417 -249.547496) (xy 206.53929 -249.587203)
			(xy 206.513176 -249.604276) (xy 206.503016 -249.61088) (xy 206.490824 -249.630692) (xy 206.481426 -249.734832)
			(xy 206.489808 -249.756422) (xy 206.498698 -249.764804) (xy 206.518637 -249.783926) (xy 206.553102 -249.827103)
			(xy 206.580742 -249.874938) (xy 206.600938 -249.92636) (xy 206.613239 -249.980218) (xy 206.617369 -250.03531)
			(xy 206.613236 -250.0904) (xy 206.600932 -250.144259) (xy 206.580734 -250.195679) (xy 206.553091 -250.243512)
			(xy 206.518624 -250.286688) (xy 206.498698 -250.305824) (xy 206.489808 -250.314206) (xy 206.481426 -250.335796)
			(xy 206.490824 -250.439936) (xy 206.503016 -250.459748) (xy 206.513176 -250.466352) (xy 206.5393 -250.48341)
			(xy 206.587418 -250.523128) (xy 206.630171 -250.56857) (xy 206.666884 -250.619018) (xy 206.696976 -250.673674)
			(xy 206.719972 -250.731675) (xy 206.735507 -250.792102) (xy 206.743337 -250.854002) (xy 206.743808 -250.885198)
			(xy 206.743303 -250.916406) (xy 206.735484 -250.978331) (xy 206.719957 -251.038786) (xy 206.696968 -251.096815)
			(xy 206.66688 -251.151501) (xy 206.630167 -251.201979) (xy 206.587412 -251.247452) (xy 206.539289 -251.287201)
			(xy 206.513176 -251.304298) (xy 206.503016 -251.310648) (xy 206.490824 -251.33046) (xy 206.481172 -251.4346)
			(xy 206.489554 -251.456444) (xy 206.498444 -251.464572) (xy 206.516739 -251.482119) (xy 206.548887 -251.521314)
			(xy 206.575365 -251.564542) (xy 206.595675 -251.610987) (xy 206.609434 -251.659776) (xy 206.616383 -251.70999)
			(xy 206.616808 -251.735336) (xy 206.616354 -251.760652) (xy 206.609436 -251.81081) (xy 206.595721 -251.859549)
			(xy 206.575466 -251.905953) (xy 206.549054 -251.949151) (xy 206.516979 -251.988328) (xy 206.498698 -252.005846)
			(xy 206.489808 -252.014228) (xy 206.481426 -252.035818) (xy 206.490824 -252.139958) (xy 206.503016 -252.15977)
			(xy 206.513176 -252.166374) (xy 206.539264 -252.183484) (xy 206.587382 -252.223194) (xy 206.630137 -252.268629)
			(xy 206.666853 -252.319069) (xy 206.696949 -252.373718) (xy 206.719951 -252.431711) (xy 206.735494 -252.492132)
			(xy 206.743332 -252.554026) (xy 206.743808 -252.58522) (xy 206.74332 -252.616429) (xy 206.735498 -252.678355)
			(xy 206.719969 -252.73881) (xy 206.696977 -252.796839) (xy 206.666887 -252.851524) (xy 206.630172 -252.902002)
			(xy 206.587415 -252.947475) (xy 206.53929 -252.987224) (xy 206.513176 -253.00432) (xy 206.503016 -253.01067)
			(xy 206.490824 -253.030482) (xy 206.481172 -253.134622) (xy 206.489554 -253.156466) (xy 206.498444 -253.164594)
			(xy 206.51675 -253.182131) (xy 206.548896 -253.221328) (xy 206.575373 -253.264558) (xy 206.595681 -253.311005)
			(xy 206.609438 -253.359796) (xy 206.616385 -253.410011) (xy 206.616808 -253.435358) (xy 206.61637 -253.460675)
			(xy 206.609448 -253.510833) (xy 206.59573 -253.559572) (xy 206.575473 -253.605977) (xy 206.549057 -253.649174)
			(xy 206.516981 -253.688351) (xy 206.498698 -253.705868) (xy 206.489808 -253.71425) (xy 206.481426 -253.73584)
			(xy 206.490824 -253.83998) (xy 206.503016 -253.859792) (xy 206.513176 -253.866396) (xy 206.539274 -253.883491)
			(xy 206.587392 -253.923204) (xy 206.630147 -253.96864) (xy 206.666862 -254.019083) (xy 206.696957 -254.073734)
			(xy 206.719957 -254.131729) (xy 206.735497 -254.192152) (xy 206.743333 -254.254047) (xy 206.743808 -254.285242)
			(xy 206.743337 -254.316451) (xy 206.735513 -254.378378) (xy 206.719981 -254.438833) (xy 206.696987 -254.496862)
			(xy 206.666894 -254.551548) (xy 206.630177 -254.602026) (xy 206.587417 -254.647498) (xy 206.539291 -254.687246)
			(xy 206.513176 -254.704342) (xy 206.503016 -254.710692) (xy 206.490824 -254.730504) (xy 206.481172 -254.834644)
			(xy 206.489554 -254.856488) (xy 206.498444 -254.864616) (xy 206.516761 -254.882142) (xy 206.548906 -254.921342)
			(xy 206.575381 -254.964573) (xy 206.595687 -255.011023) (xy 206.609442 -255.059816) (xy 206.616386 -255.110033)
			(xy 206.616808 -255.13538) (xy 206.616292 -255.16298) (xy 206.608065 -255.217563) (xy 206.591795 -255.27031)
			(xy 206.567845 -255.320043) (xy 206.53675 -255.36565) (xy 206.499205 -255.406114) (xy 206.456048 -255.440531)
			(xy 206.408244 -255.46813) (xy 206.35686 -255.488297) (xy 206.303045 -255.50058) (xy 206.248 -255.504705)
			(xy 206.192955 -255.50058) (xy 206.13914 -255.488297) (xy 206.087756 -255.46813) (xy 206.039952 -255.440531)
			(xy 205.996795 -255.406114) (xy 205.95925 -255.36565) (xy 205.928155 -255.320043) (xy 205.904205 -255.27031)
			(xy 205.887935 -255.217563) (xy 205.879708 -255.16298) (xy 205.879192 -255.13538) (xy 205.879613 -255.110032)
			(xy 205.886548 -255.059812) (xy 205.900297 -255.011016) (xy 205.920603 -254.964565) (xy 205.947081 -254.921333)
			(xy 205.979233 -254.882136) (xy 205.997556 -254.864616) (xy 206.006446 -254.856488) (xy 206.014828 -254.834644)
			(xy 206.005176 -254.730504) (xy 205.992984 -254.710692) (xy 205.982824 -254.704342) (xy 205.95673 -254.687216)
			(xy 205.908607 -254.647469) (xy 205.86585 -254.601999) (xy 205.829133 -254.551526) (xy 205.799038 -254.496845)
			(xy 205.776039 -254.438822) (xy 205.7605 -254.378371) (xy 205.752666 -254.31645) (xy 205.752192 -254.285242)
			(xy 202.64374 -254.285242) (xy 202.643254 -254.316451) (xy 202.635431 -254.378376) (xy 202.6199 -254.438831)
			(xy 202.596907 -254.496859) (xy 202.566816 -254.551544) (xy 202.530102 -254.602022) (xy 202.487345 -254.647495)
			(xy 202.439221 -254.687245) (xy 202.413108 -254.704342) (xy 202.402948 -254.710692) (xy 202.390756 -254.730504)
			(xy 202.381104 -254.834644) (xy 202.389486 -254.856488) (xy 202.398376 -254.864616) (xy 202.416699 -254.882136)
			(xy 202.448842 -254.921337) (xy 202.475316 -254.964571) (xy 202.495621 -255.011022) (xy 202.509375 -255.059815)
			(xy 202.516318 -255.110033) (xy 202.51674 -255.13538) (xy 202.516224 -255.16298) (xy 202.507997 -255.217563)
			(xy 202.491727 -255.27031) (xy 202.467777 -255.320043) (xy 202.436682 -255.36565) (xy 202.399137 -255.406114)
			(xy 202.35598 -255.440531) (xy 202.308176 -255.46813) (xy 202.256792 -255.488297) (xy 202.202977 -255.50058)
			(xy 202.147932 -255.504705) (xy 202.092887 -255.50058) (xy 202.039072 -255.488297) (xy 201.987688 -255.46813)
			(xy 201.939884 -255.440531) (xy 201.896727 -255.406114) (xy 201.859182 -255.36565) (xy 201.828087 -255.320043)
			(xy 201.804137 -255.27031) (xy 201.787867 -255.217563) (xy 201.77964 -255.16298) (xy 201.779124 -255.13538)
			(xy 201.779535 -255.110031) (xy 201.78647 -255.059811) (xy 201.800221 -255.011015) (xy 201.820528 -254.964562)
			(xy 201.847009 -254.921331) (xy 201.879163 -254.882135) (xy 201.897488 -254.864616) (xy 201.906378 -254.856488)
			(xy 201.91476 -254.834644) (xy 201.905108 -254.730504) (xy 201.892916 -254.710692) (xy 201.882756 -254.704342)
			(xy 201.856646 -254.68724) (xy 201.808526 -254.647487) (xy 201.765772 -254.602012) (xy 201.729058 -254.551535)
			(xy 201.698965 -254.496852) (xy 201.675968 -254.438826) (xy 201.660431 -254.378374) (xy 201.652597 -254.31645)
			(xy 201.652124 -254.285242) (xy 199.200008 -254.285242) (xy 199.199537 -254.316451) (xy 199.191713 -254.378378)
			(xy 199.176181 -254.438833) (xy 199.153187 -254.496862) (xy 199.123094 -254.551548) (xy 199.086377 -254.602026)
			(xy 199.043617 -254.647498) (xy 198.995491 -254.687246) (xy 198.969376 -254.704342) (xy 198.959216 -254.710692)
			(xy 198.947024 -254.730504) (xy 198.937372 -254.834644) (xy 198.945754 -254.856488) (xy 198.954644 -254.864616)
			(xy 198.972961 -254.882142) (xy 199.005106 -254.921342) (xy 199.031581 -254.964573) (xy 199.051887 -255.011023)
			(xy 199.065642 -255.059816) (xy 199.072586 -255.110033) (xy 199.073008 -255.13538) (xy 199.072492 -255.16298)
			(xy 199.064265 -255.217563) (xy 199.047995 -255.27031) (xy 199.024045 -255.320043) (xy 198.99295 -255.36565)
			(xy 198.955405 -255.406114) (xy 198.912248 -255.440531) (xy 198.864444 -255.46813) (xy 198.81306 -255.488297)
			(xy 198.759245 -255.50058) (xy 198.7042 -255.504705) (xy 198.649155 -255.50058) (xy 198.59534 -255.488297)
			(xy 198.543956 -255.46813) (xy 198.496152 -255.440531) (xy 198.452995 -255.406114) (xy 198.41545 -255.36565)
			(xy 198.384355 -255.320043) (xy 198.360405 -255.27031) (xy 198.344135 -255.217563) (xy 198.335908 -255.16298)
			(xy 198.335392 -255.13538) (xy 198.335813 -255.110032) (xy 198.342748 -255.059812) (xy 198.356497 -255.011016)
			(xy 198.376803 -254.964565) (xy 198.403281 -254.921333) (xy 198.435433 -254.882136) (xy 198.453756 -254.864616)
			(xy 198.462646 -254.856488) (xy 198.471028 -254.834644) (xy 198.461376 -254.730504) (xy 198.449184 -254.710692)
			(xy 198.439024 -254.704342) (xy 198.41293 -254.687216) (xy 198.364807 -254.647469) (xy 198.32205 -254.601999)
			(xy 198.285333 -254.551526) (xy 198.255238 -254.496845) (xy 198.232239 -254.438822) (xy 198.2167 -254.378371)
			(xy 198.208866 -254.31645) (xy 198.208392 -254.285242) (xy 195.09994 -254.285242) (xy 195.099454 -254.316451)
			(xy 195.091631 -254.378376) (xy 195.0761 -254.438831) (xy 195.053107 -254.496859) (xy 195.023016 -254.551544)
			(xy 194.986302 -254.602022) (xy 194.943545 -254.647495) (xy 194.895421 -254.687245) (xy 194.869308 -254.704342)
			(xy 194.859148 -254.710692) (xy 194.846956 -254.730504) (xy 194.837304 -254.834644) (xy 194.845686 -254.856488)
			(xy 194.854576 -254.864616) (xy 194.872899 -254.882136) (xy 194.905042 -254.921337) (xy 194.931516 -254.964571)
			(xy 194.951821 -255.011022) (xy 194.965575 -255.059815) (xy 194.972518 -255.110033) (xy 194.97294 -255.13538)
			(xy 194.972424 -255.16298) (xy 194.964197 -255.217563) (xy 194.947927 -255.27031) (xy 194.923977 -255.320043)
			(xy 194.892882 -255.36565) (xy 194.855337 -255.406114) (xy 194.81218 -255.440531) (xy 194.764376 -255.46813)
			(xy 194.712992 -255.488297) (xy 194.659177 -255.50058) (xy 194.604132 -255.504705) (xy 194.549087 -255.50058)
			(xy 194.495272 -255.488297) (xy 194.443888 -255.46813) (xy 194.396084 -255.440531) (xy 194.352927 -255.406114)
			(xy 194.315382 -255.36565) (xy 194.284287 -255.320043) (xy 194.260337 -255.27031) (xy 194.244067 -255.217563)
			(xy 194.23584 -255.16298) (xy 194.235324 -255.13538) (xy 194.235735 -255.110031) (xy 194.24267 -255.059811)
			(xy 194.256421 -255.011015) (xy 194.276728 -254.964562) (xy 194.303209 -254.921331) (xy 194.335363 -254.882135)
			(xy 194.353688 -254.864616) (xy 194.362578 -254.856488) (xy 194.37096 -254.834644) (xy 194.361308 -254.730504)
			(xy 194.349116 -254.710692) (xy 194.338956 -254.704342) (xy 194.312846 -254.68724) (xy 194.264726 -254.647487)
			(xy 194.221972 -254.602012) (xy 194.185258 -254.551535) (xy 194.155165 -254.496852) (xy 194.132168 -254.438826)
			(xy 194.116631 -254.378374) (xy 194.108797 -254.31645) (xy 194.108324 -254.285242) (xy 191.655954 -254.285242)
			(xy 191.655508 -254.316452) (xy 191.647683 -254.378381) (xy 191.632149 -254.438838) (xy 191.609152 -254.496868)
			(xy 191.579055 -254.551554) (xy 191.542335 -254.602031) (xy 191.499571 -254.647502) (xy 191.451439 -254.687248)
			(xy 191.425322 -254.704342) (xy 191.415162 -254.710692) (xy 191.40297 -254.730504) (xy 191.393318 -254.834644)
			(xy 191.4017 -254.856488) (xy 191.41059 -254.864616) (xy 191.428915 -254.882133) (xy 191.461058 -254.921336)
			(xy 191.487531 -254.96457) (xy 191.507836 -255.011021) (xy 191.521589 -255.059815) (xy 191.528532 -255.110032)
			(xy 191.528954 -255.13538) (xy 191.528438 -255.16298) (xy 191.520211 -255.217563) (xy 191.503941 -255.27031)
			(xy 191.479991 -255.320043) (xy 191.448896 -255.36565) (xy 191.411351 -255.406114) (xy 191.368194 -255.440531)
			(xy 191.32039 -255.46813) (xy 191.269006 -255.488297) (xy 191.215191 -255.50058) (xy 191.160146 -255.504705)
			(xy 191.105101 -255.50058) (xy 191.051286 -255.488297) (xy 190.999902 -255.46813) (xy 190.952098 -255.440531)
			(xy 190.908941 -255.406114) (xy 190.871396 -255.36565) (xy 190.840301 -255.320043) (xy 190.816351 -255.27031)
			(xy 190.800081 -255.217563) (xy 190.791854 -255.16298) (xy 190.791338 -255.13538) (xy 190.791744 -255.110031)
			(xy 190.79868 -255.05981) (xy 190.812432 -255.011014) (xy 190.83274 -254.964562) (xy 190.859221 -254.92133)
			(xy 190.891377 -254.882135) (xy 190.909702 -254.864616) (xy 190.918592 -254.856488) (xy 190.926974 -254.834644)
			(xy 190.917322 -254.730504) (xy 190.90513 -254.710692) (xy 190.89497 -254.704342) (xy 190.868864 -254.687235)
			(xy 190.820743 -254.647483) (xy 190.777988 -254.60201) (xy 190.741274 -254.551533) (xy 190.71118 -254.49685)
			(xy 190.688183 -254.438825) (xy 190.672645 -254.378373) (xy 190.664811 -254.31645) (xy 190.664338 -254.285242)
			(xy 187.555886 -254.285242) (xy 187.555425 -254.316452) (xy 187.547601 -254.378379) (xy 187.532068 -254.438835)
			(xy 187.509073 -254.496865) (xy 187.478978 -254.55155) (xy 187.44226 -254.602028) (xy 187.399498 -254.6475)
			(xy 187.35137 -254.687247) (xy 187.325254 -254.704342) (xy 187.315094 -254.710692) (xy 187.302902 -254.730504)
			(xy 187.29325 -254.834644) (xy 187.301632 -254.856488) (xy 187.310522 -254.864616) (xy 187.328854 -254.882127)
			(xy 187.360995 -254.921331) (xy 187.387466 -254.964567) (xy 187.407769 -255.01102) (xy 187.421522 -255.059814)
			(xy 187.428465 -255.110032) (xy 187.428886 -255.13538) (xy 187.42837 -255.16298) (xy 187.420143 -255.217563)
			(xy 187.403873 -255.27031) (xy 187.379923 -255.320043) (xy 187.348828 -255.36565) (xy 187.311283 -255.406114)
			(xy 187.268126 -255.440531) (xy 187.220322 -255.46813) (xy 187.168938 -255.488297) (xy 187.115123 -255.50058)
			(xy 187.060078 -255.504705) (xy 187.005033 -255.50058) (xy 186.951218 -255.488297) (xy 186.899834 -255.46813)
			(xy 186.85203 -255.440531) (xy 186.808873 -255.406114) (xy 186.771328 -255.36565) (xy 186.740233 -255.320043)
			(xy 186.716283 -255.27031) (xy 186.700013 -255.217563) (xy 186.691786 -255.16298) (xy 186.69127 -255.13538)
			(xy 186.691698 -255.110032) (xy 186.698632 -255.059813) (xy 186.712381 -255.011018) (xy 186.732685 -254.964566)
			(xy 186.759162 -254.921334) (xy 186.791312 -254.882137) (xy 186.809634 -254.864616) (xy 186.818524 -254.856488)
			(xy 186.826906 -254.834644) (xy 186.817254 -254.730504) (xy 186.805062 -254.710692) (xy 186.794902 -254.704342)
			(xy 186.768803 -254.687224) (xy 186.720681 -254.647475) (xy 186.677925 -254.602003) (xy 186.641209 -254.551529)
			(xy 186.611115 -254.496847) (xy 186.588116 -254.438823) (xy 186.572578 -254.378372) (xy 186.564744 -254.31645)
			(xy 186.56427 -254.285242) (xy 184.1119 -254.285242) (xy 184.111433 -254.316452) (xy 184.103608 -254.378378)
			(xy 184.088076 -254.438834) (xy 184.065082 -254.496863) (xy 184.034988 -254.551549) (xy 183.998271 -254.602026)
			(xy 183.955511 -254.647498) (xy 183.907383 -254.687246) (xy 183.881268 -254.704342) (xy 183.871108 -254.710692)
			(xy 183.858916 -254.730504) (xy 183.849264 -254.834644) (xy 183.857646 -254.856488) (xy 183.866536 -254.864616)
			(xy 183.884851 -254.882144) (xy 183.916997 -254.921343) (xy 183.943473 -254.964574) (xy 183.963779 -255.011024)
			(xy 183.977534 -255.059816) (xy 183.984478 -255.110033) (xy 183.9849 -255.13538) (xy 183.984384 -255.16298)
			(xy 183.976157 -255.217563) (xy 183.959887 -255.27031) (xy 183.935937 -255.320043) (xy 183.904842 -255.36565)
			(xy 183.867297 -255.406114) (xy 183.82414 -255.440531) (xy 183.776336 -255.46813) (xy 183.724952 -255.488297)
			(xy 183.671137 -255.50058) (xy 183.616092 -255.504705) (xy 183.561047 -255.50058) (xy 183.507232 -255.488297)
			(xy 183.455848 -255.46813) (xy 183.408044 -255.440531) (xy 183.364887 -255.406114) (xy 183.327342 -255.36565)
			(xy 183.296247 -255.320043) (xy 183.272297 -255.27031) (xy 183.256027 -255.217563) (xy 183.2478 -255.16298)
			(xy 183.247284 -255.13538) (xy 183.247707 -255.110032) (xy 183.254642 -255.059813) (xy 183.268391 -255.011017)
			(xy 183.288696 -254.964565) (xy 183.315174 -254.921333) (xy 183.347325 -254.882136) (xy 183.365648 -254.864616)
			(xy 183.374538 -254.856488) (xy 183.38292 -254.834644) (xy 183.373268 -254.730504) (xy 183.361076 -254.710692)
			(xy 183.350916 -254.704342) (xy 183.32482 -254.687219) (xy 183.276698 -254.647471) (xy 183.233941 -254.602001)
			(xy 183.197225 -254.551527) (xy 183.16713 -254.496846) (xy 183.144131 -254.438822) (xy 183.128592 -254.378372)
			(xy 183.120758 -254.31645) (xy 183.120284 -254.285242) (xy 180.011832 -254.285242) (xy 180.01135 -254.316451)
			(xy 180.003526 -254.378377) (xy 179.987995 -254.438831) (xy 179.965002 -254.49686) (xy 179.93491 -254.551545)
			(xy 179.898196 -254.602023) (xy 179.855438 -254.647496) (xy 179.807314 -254.687245) (xy 179.7812 -254.704342)
			(xy 179.77104 -254.710692) (xy 179.758848 -254.730504) (xy 179.749196 -254.834644) (xy 179.757578 -254.856488)
			(xy 179.766468 -254.864616) (xy 179.784789 -254.882137) (xy 179.816933 -254.921338) (xy 179.843407 -254.964571)
			(xy 179.863713 -255.011022) (xy 179.877467 -255.059816) (xy 179.88441 -255.110033) (xy 179.884832 -255.13538)
			(xy 179.884316 -255.16298) (xy 179.876089 -255.217563) (xy 179.859819 -255.27031) (xy 179.835869 -255.320043)
			(xy 179.804774 -255.36565) (xy 179.767229 -255.406114) (xy 179.724072 -255.440531) (xy 179.676268 -255.46813)
			(xy 179.624884 -255.488297) (xy 179.571069 -255.50058) (xy 179.516024 -255.504705) (xy 179.460979 -255.50058)
			(xy 179.407164 -255.488297) (xy 179.35578 -255.46813) (xy 179.307976 -255.440531) (xy 179.264819 -255.406114)
			(xy 179.227274 -255.36565) (xy 179.196179 -255.320043) (xy 179.172229 -255.27031) (xy 179.155959 -255.217563)
			(xy 179.147732 -255.16298) (xy 179.147216 -255.13538) (xy 179.147629 -255.110032) (xy 179.154564 -255.059811)
			(xy 179.168315 -255.011015) (xy 179.188622 -254.964563) (xy 179.215102 -254.921331) (xy 179.247256 -254.882136)
			(xy 179.26558 -254.864616) (xy 179.27447 -254.856488) (xy 179.282852 -254.834644) (xy 179.2732 -254.730504)
			(xy 179.261008 -254.710692) (xy 179.250848 -254.704342) (xy 179.224737 -254.687243) (xy 179.176617 -254.647489)
			(xy 179.133863 -254.602014) (xy 179.097149 -254.551536) (xy 179.067057 -254.496852) (xy 179.04406 -254.438826)
			(xy 179.028522 -254.378374) (xy 179.020689 -254.31645) (xy 179.020216 -254.285242) (xy 176.567846 -254.285242)
			(xy 176.567357 -254.316451) (xy 176.559534 -254.378376) (xy 176.544003 -254.43883) (xy 176.521011 -254.496858)
			(xy 176.49092 -254.551544) (xy 176.454207 -254.602022) (xy 176.41145 -254.647495) (xy 176.363327 -254.687245)
			(xy 176.337214 -254.704342) (xy 176.327054 -254.710692) (xy 176.314862 -254.730504) (xy 176.30521 -254.834644)
			(xy 176.313592 -254.856488) (xy 176.322482 -254.864616) (xy 176.340806 -254.882135) (xy 176.372949 -254.921337)
			(xy 176.399423 -254.96457) (xy 176.419727 -255.011021) (xy 176.433481 -255.059815) (xy 176.440424 -255.110032)
			(xy 176.440846 -255.13538) (xy 176.44033 -255.16298) (xy 176.432103 -255.217563) (xy 176.415833 -255.27031)
			(xy 176.391883 -255.320043) (xy 176.360788 -255.36565) (xy 176.323243 -255.406114) (xy 176.280086 -255.440531)
			(xy 176.232282 -255.46813) (xy 176.180898 -255.488297) (xy 176.127083 -255.50058) (xy 176.072038 -255.504705)
			(xy 176.016993 -255.50058) (xy 175.963178 -255.488297) (xy 175.911794 -255.46813) (xy 175.86399 -255.440531)
			(xy 175.820833 -255.406114) (xy 175.783288 -255.36565) (xy 175.752193 -255.320043) (xy 175.728243 -255.27031)
			(xy 175.711973 -255.217563) (xy 175.703746 -255.16298) (xy 175.70323 -255.13538) (xy 175.703639 -255.110031)
			(xy 175.710574 -255.059811) (xy 175.724326 -255.011014) (xy 175.744633 -254.964562) (xy 175.771114 -254.921331)
			(xy 175.803269 -254.882135) (xy 175.821594 -254.864616) (xy 175.830484 -254.856488) (xy 175.838866 -254.834644)
			(xy 175.829214 -254.730504) (xy 175.817022 -254.710692) (xy 175.806862 -254.704342) (xy 175.780754 -254.687238)
			(xy 175.732633 -254.647485) (xy 175.689879 -254.602011) (xy 175.653165 -254.551534) (xy 175.623072 -254.496851)
			(xy 175.600075 -254.438825) (xy 175.584537 -254.378374) (xy 175.576703 -254.31645) (xy 175.57623 -254.285242)
			(xy 172.467778 -254.285242) (xy 172.467321 -254.316452) (xy 172.459496 -254.37838) (xy 172.443963 -254.438836)
			(xy 172.420967 -254.496866) (xy 172.390872 -254.551551) (xy 172.354154 -254.602029) (xy 172.311391 -254.6475)
			(xy 172.263262 -254.687247) (xy 172.237146 -254.704342) (xy 172.226986 -254.710692) (xy 172.214794 -254.730504)
			(xy 172.205142 -254.834644) (xy 172.213524 -254.856488) (xy 172.222414 -254.864616) (xy 172.240744 -254.882128)
			(xy 172.272886 -254.921332) (xy 172.299357 -254.964568) (xy 172.319661 -255.01102) (xy 172.333413 -255.059814)
			(xy 172.340357 -255.110032) (xy 172.340778 -255.13538) (xy 172.340262 -255.16298) (xy 172.332035 -255.217563)
			(xy 172.315765 -255.27031) (xy 172.291815 -255.320043) (xy 172.26072 -255.36565) (xy 172.223175 -255.406114)
			(xy 172.180018 -255.440531) (xy 172.132214 -255.46813) (xy 172.08083 -255.488297) (xy 172.027015 -255.50058)
			(xy 171.97197 -255.504705) (xy 171.916925 -255.50058) (xy 171.86311 -255.488297) (xy 171.811726 -255.46813)
			(xy 171.763922 -255.440531) (xy 171.720765 -255.406114) (xy 171.68322 -255.36565) (xy 171.652125 -255.320043)
			(xy 171.628175 -255.27031) (xy 171.611905 -255.217563) (xy 171.603678 -255.16298) (xy 171.603162 -255.13538)
			(xy 171.603592 -255.110032) (xy 171.610526 -255.059814) (xy 171.624275 -255.011018) (xy 171.644579 -254.964567)
			(xy 171.671055 -254.921334) (xy 171.703204 -254.882137) (xy 171.721526 -254.864616) (xy 171.730416 -254.856488)
			(xy 171.738798 -254.834644) (xy 171.729146 -254.730504) (xy 171.716954 -254.710692) (xy 171.706794 -254.704342)
			(xy 171.680693 -254.687227) (xy 171.632572 -254.647477) (xy 171.589816 -254.602005) (xy 171.5531 -254.55153)
			(xy 171.523006 -254.496848) (xy 171.500008 -254.438823) (xy 171.484469 -254.378372) (xy 171.476636 -254.31645)
			(xy 171.476162 -254.285242) (xy 161.612834 -254.285242) (xy 161.612834 -255.13538) (xy 164.058615 -255.13538)
			(xy 164.06255 -255.081609) (xy 164.074273 -255.028985) (xy 164.093533 -254.978628) (xy 164.119919 -254.931611)
			(xy 164.152871 -254.888938) (xy 164.191684 -254.851517) (xy 164.235532 -254.820147) (xy 164.28348 -254.795495)
			(xy 164.334507 -254.778087) (xy 164.387525 -254.768294) (xy 164.441404 -254.766325) (xy 164.494995 -254.772222)
			(xy 164.547156 -254.785858) (xy 164.596776 -254.806945) (xy 164.642797 -254.835031) (xy 164.684239 -254.869519)
			(xy 164.720217 -254.909673) (xy 164.749965 -254.954637) (xy 164.77285 -255.003454) (xy 164.788382 -255.055083)
			(xy 164.796232 -255.108423) (xy 164.796724 -255.13538) (xy 168.158683 -255.13538) (xy 168.162618 -255.081609)
			(xy 168.174341 -255.028985) (xy 168.193601 -254.978628) (xy 168.219987 -254.931611) (xy 168.252939 -254.888938)
			(xy 168.291752 -254.851517) (xy 168.3356 -254.820147) (xy 168.383548 -254.795495) (xy 168.434575 -254.778087)
			(xy 168.487593 -254.768294) (xy 168.541472 -254.766325) (xy 168.595063 -254.772222) (xy 168.647224 -254.785858)
			(xy 168.696844 -254.806945) (xy 168.742865 -254.835031) (xy 168.784307 -254.869519) (xy 168.820285 -254.909673)
			(xy 168.850033 -254.954637) (xy 168.872918 -255.003454) (xy 168.88845 -255.055083) (xy 168.8963 -255.108423)
			(xy 168.896792 -255.13538) (xy 168.8963 -255.162337) (xy 168.88845 -255.215677) (xy 168.872918 -255.267306)
			(xy 168.850033 -255.316123) (xy 168.820285 -255.361087) (xy 168.784307 -255.401241) (xy 168.742865 -255.435729)
			(xy 168.696844 -255.463815) (xy 168.647224 -255.484902) (xy 168.595063 -255.498538) (xy 168.541472 -255.504435)
			(xy 168.487593 -255.502466) (xy 168.434575 -255.492673) (xy 168.383548 -255.475265) (xy 168.3356 -255.450613)
			(xy 168.291752 -255.419243) (xy 168.252939 -255.381822) (xy 168.219987 -255.339149) (xy 168.193601 -255.292132)
			(xy 168.174341 -255.241775) (xy 168.162618 -255.189151) (xy 168.158683 -255.13538) (xy 164.796724 -255.13538)
			(xy 164.796232 -255.162337) (xy 164.788382 -255.215677) (xy 164.77285 -255.267306) (xy 164.749965 -255.316123)
			(xy 164.720217 -255.361087) (xy 164.684239 -255.401241) (xy 164.642797 -255.435729) (xy 164.596776 -255.463815)
			(xy 164.547156 -255.484902) (xy 164.494995 -255.498538) (xy 164.441404 -255.504435) (xy 164.387525 -255.502466)
			(xy 164.334507 -255.492673) (xy 164.28348 -255.475265) (xy 164.235532 -255.450613) (xy 164.191684 -255.419243)
			(xy 164.152871 -255.381822) (xy 164.119919 -255.339149) (xy 164.093533 -255.292132) (xy 164.074273 -255.241775)
			(xy 164.06255 -255.189151) (xy 164.058615 -255.13538) (xy 161.612834 -255.13538) (xy 161.612834 -255.556512)
			(xy 161.61326 -255.566581) (xy 161.620981 -255.585179) (xy 161.62782 -255.59258) (xy 162.545014 -256.509774)
			(xy 162.552412 -256.516621) (xy 162.57101 -256.524354) (xy 162.581082 -256.52476) (xy 185.266838 -256.52476)
			(xy 185.276904 -256.525192) (xy 185.295493 -256.532922) (xy 185.302906 -256.539746) (xy 185.953654 -257.190494)
			(xy 185.960506 -257.19789) (xy 185.96825 -257.216488) (xy 185.96864 -257.226562) (xy 185.96864 -259.4353)
			(xy 187.242478 -259.4353) (xy 187.246469 -259.346438) (xy 187.258409 -259.258291) (xy 187.278203 -259.17157)
			(xy 187.305691 -259.086972) (xy 187.340651 -259.005178) (xy 187.382803 -258.926848) (xy 187.431806 -258.852612)
			(xy 187.487267 -258.783067) (xy 187.548739 -258.718773) (xy 187.615726 -258.660249) (xy 187.68769 -258.607965)
			(xy 187.764051 -258.562342) (xy 187.844194 -258.523748) (xy 187.927474 -258.492494) (xy 188.01322 -258.46883)
			(xy 188.100742 -258.452948) (xy 188.189336 -258.444976) (xy 188.233812 -258.444492) (xy 189.986412 -258.444492)
			(xy 190.030891 -258.444899) (xy 190.11949 -258.452874) (xy 190.207017 -258.468759) (xy 190.292768 -258.492426)
			(xy 190.376053 -258.523684) (xy 190.4562 -258.562282) (xy 190.532565 -258.607909) (xy 190.604533 -258.660197)
			(xy 190.671524 -258.718726) (xy 190.732998 -258.783024) (xy 190.788462 -258.852574) (xy 190.837468 -258.926815)
			(xy 190.879622 -259.005151) (xy 190.914584 -259.08695) (xy 190.942073 -259.171553) (xy 190.961868 -259.25828)
			(xy 190.973808 -259.346432) (xy 190.9778 -259.4353) (xy 194.786592 -259.4353) (xy 194.790583 -259.346442)
			(xy 194.802523 -259.258299) (xy 194.822315 -259.171581) (xy 194.849801 -259.086987) (xy 194.884759 -259.005197)
			(xy 194.926907 -258.926869) (xy 194.975907 -258.852635) (xy 195.031364 -258.783092) (xy 195.092832 -258.7188)
			(xy 195.159815 -258.660277) (xy 195.231774 -258.607993) (xy 195.30813 -258.56237) (xy 195.388268 -258.523775)
			(xy 195.471543 -258.492519) (xy 195.557285 -258.468853) (xy 195.644803 -258.452968) (xy 195.733392 -258.444992)
			(xy 195.777866 -258.444492) (xy 197.530466 -258.444492) (xy 197.574947 -258.444883) (xy 197.66355 -258.452854)
			(xy 197.751082 -258.468736) (xy 197.836838 -258.492401) (xy 197.920127 -258.523657) (xy 198.000279 -258.562254)
			(xy 198.076649 -258.607881) (xy 198.148621 -258.660169) (xy 198.215617 -258.718699) (xy 198.277095 -258.782999)
			(xy 198.332563 -258.85255) (xy 198.381572 -258.926794) (xy 198.423729 -259.005133) (xy 198.458694 -259.086935)
			(xy 198.486185 -259.171542) (xy 198.505981 -259.258272) (xy 198.517923 -259.346428) (xy 198.521914 -259.4353)
			(xy 202.330392 -259.4353) (xy 202.334383 -259.346442) (xy 202.346323 -259.258299) (xy 202.366115 -259.171581)
			(xy 202.393601 -259.086987) (xy 202.428559 -259.005197) (xy 202.470707 -258.926869) (xy 202.519707 -258.852635)
			(xy 202.575164 -258.783092) (xy 202.636632 -258.7188) (xy 202.703615 -258.660277) (xy 202.775574 -258.607993)
			(xy 202.85193 -258.56237) (xy 202.932068 -258.523775) (xy 203.015343 -258.492519) (xy 203.101085 -258.468853)
			(xy 203.188603 -258.452968) (xy 203.277192 -258.444992) (xy 203.321666 -258.444492) (xy 205.074266 -258.444492)
			(xy 205.118747 -258.444883) (xy 205.20735 -258.452854) (xy 205.294882 -258.468736) (xy 205.380638 -258.492401)
			(xy 205.463927 -258.523657) (xy 205.544079 -258.562254) (xy 205.620449 -258.607881) (xy 205.692421 -258.660169)
			(xy 205.759417 -258.718699) (xy 205.820895 -258.782999) (xy 205.876363 -258.85255) (xy 205.925372 -258.926794)
			(xy 205.967529 -259.005133) (xy 206.002494 -259.086935) (xy 206.029985 -259.171542) (xy 206.049781 -259.258272)
			(xy 206.061723 -259.346428) (xy 206.065714 -259.4353) (xy 206.061723 -259.524172) (xy 206.049781 -259.612328)
			(xy 206.029985 -259.699058) (xy 206.002494 -259.783665) (xy 205.967529 -259.865467) (xy 205.925372 -259.943806)
			(xy 205.876363 -260.01805) (xy 205.820895 -260.087601) (xy 205.759417 -260.151901) (xy 205.692421 -260.210431)
			(xy 205.620449 -260.262719) (xy 205.544079 -260.308346) (xy 205.463927 -260.346943) (xy 205.380638 -260.378199)
			(xy 205.294882 -260.401864) (xy 205.20735 -260.417746) (xy 205.118747 -260.425717) (xy 205.074266 -260.4262)
			(xy 203.321666 -260.4262) (xy 203.277192 -260.425608) (xy 203.188603 -260.417632) (xy 203.101085 -260.401747)
			(xy 203.015343 -260.378081) (xy 202.932068 -260.346825) (xy 202.85193 -260.30823) (xy 202.775574 -260.262607)
			(xy 202.703615 -260.210323) (xy 202.636632 -260.1518) (xy 202.575164 -260.087508) (xy 202.519707 -260.017965)
			(xy 202.470707 -259.943731) (xy 202.428559 -259.865403) (xy 202.393601 -259.783613) (xy 202.366115 -259.699019)
			(xy 202.346323 -259.612301) (xy 202.334383 -259.524158) (xy 202.330392 -259.4353) (xy 198.521914 -259.4353)
			(xy 198.517923 -259.524172) (xy 198.505981 -259.612328) (xy 198.486185 -259.699058) (xy 198.458694 -259.783665)
			(xy 198.423729 -259.865467) (xy 198.381572 -259.943806) (xy 198.332563 -260.01805) (xy 198.277095 -260.087601)
			(xy 198.215617 -260.151901) (xy 198.148621 -260.210431) (xy 198.076649 -260.262719) (xy 198.000279 -260.308346)
			(xy 197.920127 -260.346943) (xy 197.836838 -260.378199) (xy 197.751082 -260.401864) (xy 197.66355 -260.417746)
			(xy 197.574947 -260.425717) (xy 197.530466 -260.4262) (xy 195.777866 -260.4262) (xy 195.733392 -260.425608)
			(xy 195.644803 -260.417632) (xy 195.557285 -260.401747) (xy 195.471543 -260.378081) (xy 195.388268 -260.346825)
			(xy 195.30813 -260.30823) (xy 195.231774 -260.262607) (xy 195.159815 -260.210323) (xy 195.092832 -260.1518)
			(xy 195.031364 -260.087508) (xy 194.975907 -260.017965) (xy 194.926907 -259.943731) (xy 194.884759 -259.865403)
			(xy 194.849801 -259.783613) (xy 194.822315 -259.699019) (xy 194.802523 -259.612301) (xy 194.790583 -259.524158)
			(xy 194.786592 -259.4353) (xy 190.9778 -259.4353) (xy 190.973808 -259.524168) (xy 190.961868 -259.61232)
			(xy 190.942073 -259.699047) (xy 190.914584 -259.78365) (xy 190.879622 -259.865449) (xy 190.837468 -259.943785)
			(xy 190.788462 -260.018026) (xy 190.732998 -260.087576) (xy 190.671524 -260.151874) (xy 190.604533 -260.210403)
			(xy 190.532565 -260.262691) (xy 190.4562 -260.308318) (xy 190.376053 -260.346916) (xy 190.292768 -260.378174)
			(xy 190.207017 -260.401841) (xy 190.11949 -260.417726) (xy 190.030891 -260.425701) (xy 189.986412 -260.4262)
			(xy 188.233812 -260.4262) (xy 188.189336 -260.425624) (xy 188.100742 -260.417652) (xy 188.01322 -260.40177)
			(xy 187.927474 -260.378106) (xy 187.844194 -260.346852) (xy 187.764051 -260.308258) (xy 187.68769 -260.262635)
			(xy 187.615726 -260.210351) (xy 187.548739 -260.151827) (xy 187.487267 -260.087533) (xy 187.431806 -260.017988)
			(xy 187.382803 -259.943752) (xy 187.340651 -259.865422) (xy 187.305691 -259.783628) (xy 187.278203 -259.69903)
			(xy 187.258409 -259.612309) (xy 187.246469 -259.524162) (xy 187.242478 -259.4353) (xy 185.96864 -259.4353)
			(xy 185.96864 -274.685252) (xy 186.56427 -274.685252) (xy 186.564761 -274.654056) (xy 186.572576 -274.592155)
			(xy 186.588102 -274.531725) (xy 186.611093 -274.473723) (xy 186.641185 -274.419067) (xy 186.677902 -274.368622)
			(xy 186.720662 -274.323187) (xy 186.768789 -274.28348) (xy 186.794902 -274.266406) (xy 186.805062 -274.259802)
			(xy 186.817254 -274.23999) (xy 186.826652 -274.13585) (xy 186.81827 -274.11426) (xy 186.80938 -274.105878)
			(xy 186.791081 -274.088376) (xy 186.759003 -274.049196) (xy 186.732587 -274.005997) (xy 186.712328 -273.959589)
			(xy 186.698609 -273.910847) (xy 186.691686 -273.860686) (xy 186.69127 -273.835368) (xy 186.69169 -273.81002)
			(xy 186.698626 -273.759801) (xy 186.712376 -273.711005) (xy 186.732682 -273.664553) (xy 186.75916 -273.621321)
			(xy 186.791311 -273.582125) (xy 186.809634 -273.564604) (xy 186.818524 -273.556476) (xy 186.826906 -273.534632)
			(xy 186.817254 -273.430492) (xy 186.805062 -273.41068) (xy 186.794902 -273.40433) (xy 186.768798 -273.38722)
			(xy 186.720676 -273.347469) (xy 186.677919 -273.301997) (xy 186.641204 -273.251521) (xy 186.611111 -273.196838)
			(xy 186.588113 -273.138813) (xy 186.572575 -273.078361) (xy 186.564743 -273.016438) (xy 186.56427 -272.98523)
			(xy 186.564744 -272.954033) (xy 186.572562 -272.892131) (xy 186.588091 -272.831701) (xy 186.611084 -272.773699)
			(xy 186.641178 -272.719043) (xy 186.677897 -272.668599) (xy 186.720659 -272.623164) (xy 186.768788 -272.583457)
			(xy 186.794902 -272.566384) (xy 186.805062 -272.55978) (xy 186.817254 -272.539968) (xy 186.826652 -272.435828)
			(xy 186.81827 -272.414238) (xy 186.80938 -272.405856) (xy 186.791119 -272.388316) (xy 186.759038 -272.349145)
			(xy 186.732616 -272.305953) (xy 186.712351 -272.259553) (xy 186.698624 -272.210817) (xy 186.691691 -272.160662)
			(xy 186.69127 -272.135346) (xy 186.691675 -272.109997) (xy 186.698614 -272.059777) (xy 186.712367 -272.010982)
			(xy 186.732676 -271.96453) (xy 186.759157 -271.921298) (xy 186.79131 -271.882102) (xy 186.809634 -271.864582)
			(xy 186.818524 -271.856454) (xy 186.826906 -271.83461) (xy 186.817254 -271.73047) (xy 186.805062 -271.710658)
			(xy 186.794902 -271.704308) (xy 186.768788 -271.687212) (xy 186.720666 -271.64746) (xy 186.67791 -271.601986)
			(xy 186.641196 -271.551507) (xy 186.611103 -271.496823) (xy 186.588107 -271.438795) (xy 186.572572 -271.378342)
			(xy 186.564742 -271.316417) (xy 186.56427 -271.285208) (xy 186.564771 -271.252507) (xy 186.573385 -271.187674)
			(xy 186.590451 -271.124537) (xy 186.615671 -271.064192) (xy 186.648609 -271.007689) (xy 186.688692 -270.956009)
			(xy 186.71159 -270.932656) (xy 186.718956 -270.92529) (xy 186.726576 -270.906748) (xy 186.726576 -270.813784)
			(xy 186.718956 -270.795242) (xy 186.71159 -270.787876) (xy 186.688717 -270.7645) (xy 186.648629 -270.712827)
			(xy 186.615688 -270.65633) (xy 186.590467 -270.595989) (xy 186.573404 -270.532854) (xy 186.564796 -270.468024)
			(xy 186.56427 -270.435324) (xy 186.564739 -270.404127) (xy 186.572558 -270.342225) (xy 186.588087 -270.281795)
			(xy 186.611081 -270.223793) (xy 186.641176 -270.169137) (xy 186.677896 -270.118692) (xy 186.720658 -270.073257)
			(xy 186.768788 -270.033551) (xy 186.794902 -270.016478) (xy 186.805062 -270.009874) (xy 186.817254 -269.990062)
			(xy 186.826652 -269.885922) (xy 186.81827 -269.864332) (xy 186.80938 -269.85595) (xy 186.791116 -269.838413)
			(xy 186.759035 -269.799241) (xy 186.732614 -269.756049) (xy 186.712349 -269.709648) (xy 186.698622 -269.660912)
			(xy 186.691691 -269.610756) (xy 186.69127 -269.58544) (xy 186.691671 -269.560091) (xy 186.698611 -269.509871)
			(xy 186.712365 -269.461075) (xy 186.732674 -269.414624) (xy 186.759156 -269.371392) (xy 186.79131 -269.332196)
			(xy 186.809634 -269.314676) (xy 186.818524 -269.306548) (xy 186.826906 -269.284704) (xy 186.817254 -269.180564)
			(xy 186.805062 -269.160752) (xy 186.794902 -269.154402) (xy 186.768785 -269.137311) (xy 186.720663 -269.097558)
			(xy 186.677907 -269.052082) (xy 186.641193 -269.001604) (xy 186.611101 -268.946918) (xy 186.588106 -268.88889)
			(xy 186.572571 -268.828436) (xy 186.564741 -268.766511) (xy 186.56427 -268.735302) (xy 186.564722 -268.704105)
			(xy 186.572543 -268.642202) (xy 186.588075 -268.581771) (xy 186.611072 -268.523769) (xy 186.641169 -268.469113)
			(xy 186.677891 -268.418669) (xy 186.720656 -268.373234) (xy 186.768787 -268.333529) (xy 186.794902 -268.316456)
			(xy 186.805062 -268.309852) (xy 186.817254 -268.29004) (xy 186.826652 -268.1859) (xy 186.81827 -268.16431)
			(xy 186.80938 -268.155928) (xy 186.791105 -268.138402) (xy 186.759025 -268.099227) (xy 186.732606 -268.056033)
			(xy 186.712343 -268.00963) (xy 186.698618 -267.960892) (xy 186.69169 -267.910735) (xy 186.69127 -267.885418)
			(xy 186.691723 -267.860071) (xy 186.698652 -267.809853) (xy 186.712396 -267.761058) (xy 186.732696 -267.714606)
			(xy 186.759168 -267.671374) (xy 186.791314 -267.632175) (xy 186.809634 -267.614654) (xy 186.818524 -267.606526)
			(xy 186.826906 -267.584682) (xy 186.817254 -267.480542) (xy 186.805062 -267.46073) (xy 186.794902 -267.45438)
			(xy 186.768775 -267.437303) (xy 186.720653 -267.397548) (xy 186.677898 -267.352071) (xy 186.641185 -267.30159)
			(xy 186.611094 -267.246902) (xy 186.5881 -267.188872) (xy 186.572567 -267.128417) (xy 186.56474 -267.06649)
			(xy 186.56427 -267.03528) (xy 186.564705 -267.004082) (xy 186.572529 -266.942179) (xy 186.588064 -266.881748)
			(xy 186.611063 -266.823745) (xy 186.641162 -266.769089) (xy 186.677886 -266.718645) (xy 186.720653 -266.673211)
			(xy 186.768786 -266.633507) (xy 186.794902 -266.616434) (xy 186.805062 -266.60983) (xy 186.817254 -266.590018)
			(xy 186.826652 -266.485878) (xy 186.81827 -266.464288) (xy 186.80938 -266.455906) (xy 186.791095 -266.438391)
			(xy 186.759016 -266.399214) (xy 186.732597 -266.356017) (xy 186.712337 -266.309612) (xy 186.698614 -266.260872)
			(xy 186.691688 -266.210713) (xy 186.69127 -266.185396) (xy 186.691708 -266.160049) (xy 186.698641 -266.10983)
			(xy 186.712387 -266.061035) (xy 186.73269 -266.014583) (xy 186.759164 -265.971351) (xy 186.791313 -265.932153)
			(xy 186.809634 -265.914632) (xy 186.818524 -265.906504) (xy 186.826906 -265.88466) (xy 186.817254 -265.78052)
			(xy 186.805062 -265.760708) (xy 186.794902 -265.754358) (xy 186.768811 -265.737229) (xy 186.720688 -265.697481)
			(xy 186.677932 -265.652012) (xy 186.641216 -265.601539) (xy 186.61112 -265.546859) (xy 186.588121 -265.488836)
			(xy 186.57258 -265.428387) (xy 186.564745 -265.366465) (xy 186.56427 -265.335258) (xy 186.564766 -265.304062)
			(xy 186.57258 -265.242161) (xy 186.588106 -265.181731) (xy 186.611096 -265.12373) (xy 186.641187 -265.069073)
			(xy 186.677903 -265.018628) (xy 186.720663 -264.973193) (xy 186.768789 -264.933486) (xy 186.794902 -264.916412)
			(xy 186.805062 -264.909808) (xy 186.817254 -264.889996) (xy 186.826652 -264.785856) (xy 186.81827 -264.764266)
			(xy 186.80938 -264.755884) (xy 186.791084 -264.738379) (xy 186.759006 -264.6992) (xy 186.732589 -264.656001)
			(xy 186.71233 -264.609594) (xy 186.69861 -264.560853) (xy 186.691687 -264.510692) (xy 186.69127 -264.485374)
			(xy 186.691694 -264.460026) (xy 186.698629 -264.409807) (xy 186.712379 -264.361011) (xy 186.732684 -264.31456)
			(xy 186.759161 -264.271328) (xy 186.791311 -264.232131) (xy 186.809634 -264.21461) (xy 186.818524 -264.206482)
			(xy 186.826906 -264.184638) (xy 186.817254 -264.080498) (xy 186.805062 -264.060686) (xy 186.794902 -264.054336)
			(xy 186.7688 -264.037222) (xy 186.720678 -263.997472) (xy 186.677922 -263.952) (xy 186.641207 -263.901525)
			(xy 186.611113 -263.846843) (xy 186.588115 -263.788818) (xy 186.572577 -263.728367) (xy 186.564743 -263.666444)
			(xy 186.56427 -263.635236) (xy 186.564749 -263.604039) (xy 186.572566 -263.542138) (xy 186.588094 -263.481708)
			(xy 186.611086 -263.423706) (xy 186.64118 -263.36905) (xy 186.677898 -263.318605) (xy 186.72066 -263.27317)
			(xy 186.768788 -263.233464) (xy 186.794902 -263.21639) (xy 186.805062 -263.209786) (xy 186.817254 -263.189974)
			(xy 186.826652 -263.085834) (xy 186.81827 -263.064244) (xy 186.80938 -263.055862) (xy 186.791122 -263.038319)
			(xy 186.75904 -262.999148) (xy 186.732618 -262.955957) (xy 186.712353 -262.909558) (xy 186.698625 -262.860823)
			(xy 186.691692 -262.810668) (xy 186.69127 -262.785352) (xy 186.691679 -262.760004) (xy 186.698617 -262.709784)
			(xy 186.71237 -262.660988) (xy 186.732678 -262.614536) (xy 186.759158 -262.571305) (xy 186.79131 -262.532108)
			(xy 186.809634 -262.514588) (xy 186.818524 -262.50646) (xy 186.826906 -262.484616) (xy 186.817254 -262.380476)
			(xy 186.805062 -262.360664) (xy 186.794902 -262.354314) (xy 186.76879 -262.337214) (xy 186.720668 -262.297463)
			(xy 186.677912 -262.251989) (xy 186.641198 -262.201511) (xy 186.611105 -262.146827) (xy 186.588109 -262.0888)
			(xy 186.572573 -262.028347) (xy 186.564742 -261.966423) (xy 186.56427 -261.935214) (xy 186.564759 -261.904051)
			(xy 186.572571 -261.842217) (xy 186.588071 -261.781849) (xy 186.611014 -261.723901) (xy 186.64104 -261.669284)
			(xy 186.677674 -261.618862) (xy 186.720339 -261.573428) (xy 186.768361 -261.5337) (xy 186.820985 -261.500305)
			(xy 186.877379 -261.473768) (xy 186.936654 -261.454508) (xy 186.997875 -261.442829) (xy 187.060078 -261.438916)
			(xy 187.122281 -261.442829) (xy 187.183502 -261.454508) (xy 187.242777 -261.473768) (xy 187.299171 -261.500305)
			(xy 187.351795 -261.5337) (xy 187.399817 -261.573428) (xy 187.442482 -261.618862) (xy 187.479116 -261.669284)
			(xy 187.509142 -261.723901) (xy 187.532085 -261.781849) (xy 187.547585 -261.842217) (xy 187.555397 -261.904051)
			(xy 187.555886 -261.935214) (xy 187.555403 -261.966423) (xy 187.547582 -262.02835) (xy 187.532053 -262.088805)
			(xy 187.509061 -262.146834) (xy 187.478969 -262.20152) (xy 187.442254 -262.251998) (xy 187.399495 -262.29747)
			(xy 187.351368 -262.337218) (xy 187.325254 -262.354314) (xy 187.315094 -262.360664) (xy 187.302902 -262.380476)
			(xy 187.29325 -262.484616) (xy 187.301632 -262.50646) (xy 187.310522 -262.514588) (xy 187.32884 -262.532112)
			(xy 187.360982 -262.571314) (xy 187.387455 -262.614547) (xy 187.407761 -262.660997) (xy 187.421516 -262.709789)
			(xy 187.428463 -262.760005) (xy 187.428886 -262.785352) (xy 187.42845 -262.810669) (xy 187.421529 -262.860827)
			(xy 187.407811 -262.909567) (xy 187.387553 -262.955972) (xy 187.361137 -262.999169) (xy 187.329059 -263.038345)
			(xy 187.310776 -263.055862) (xy 187.301886 -263.064244) (xy 187.293504 -263.085834) (xy 187.302902 -263.189974)
			(xy 187.315094 -263.209786) (xy 187.325254 -263.21639) (xy 187.351344 -263.233497) (xy 187.399463 -263.273207)
			(xy 187.442219 -263.318642) (xy 187.478935 -263.369082) (xy 187.509032 -263.423731) (xy 187.532032 -263.481725)
			(xy 187.547574 -263.542147) (xy 187.555411 -263.604042) (xy 187.555886 -263.635236) (xy 187.55542 -263.666446)
			(xy 187.547597 -263.728373) (xy 187.532065 -263.788829) (xy 187.50907 -263.846858) (xy 187.478976 -263.901544)
			(xy 187.442258 -263.952022) (xy 187.399498 -263.997493) (xy 187.351369 -264.037241) (xy 187.325254 -264.054336)
			(xy 187.315094 -264.060686) (xy 187.302902 -264.080498) (xy 187.29325 -264.184638) (xy 187.301632 -264.206482)
			(xy 187.310522 -264.21461) (xy 187.328851 -264.232124) (xy 187.360992 -264.271328) (xy 187.387464 -264.314563)
			(xy 187.407767 -264.361015) (xy 187.42152 -264.409809) (xy 187.428464 -264.460026) (xy 187.428886 -264.485374)
			(xy 187.428465 -264.510691) (xy 187.421541 -264.560851) (xy 187.40782 -264.609591) (xy 187.387559 -264.655995)
			(xy 187.361141 -264.699192) (xy 187.329061 -264.738368) (xy 187.310776 -264.755884) (xy 187.301886 -264.764266)
			(xy 187.293504 -264.785856) (xy 187.302902 -264.889996) (xy 187.315094 -264.909808) (xy 187.325254 -264.916412)
			(xy 187.351354 -264.933504) (xy 187.399473 -264.973216) (xy 187.442228 -265.018653) (xy 187.478944 -265.069096)
			(xy 187.509039 -265.123747) (xy 187.532038 -265.181743) (xy 187.547578 -265.242167) (xy 187.555412 -265.304063)
			(xy 187.555886 -265.335258) (xy 187.555438 -265.366468) (xy 187.547611 -265.428396) (xy 187.532077 -265.488852)
			(xy 187.509079 -265.546882) (xy 187.478983 -265.601568) (xy 187.442263 -265.652045) (xy 187.3995 -265.697516)
			(xy 187.35137 -265.737263) (xy 187.325254 -265.754358) (xy 187.315094 -265.760708) (xy 187.302902 -265.78052)
			(xy 187.29325 -265.88466) (xy 187.301632 -265.906504) (xy 187.310522 -265.914632) (xy 187.328861 -265.932135)
			(xy 187.361002 -265.971341) (xy 187.387472 -266.014579) (xy 187.407774 -266.061033) (xy 187.421525 -266.109829)
			(xy 187.428466 -266.160048) (xy 187.428886 -266.185396) (xy 187.42848 -266.210714) (xy 187.421553 -266.260874)
			(xy 187.407829 -266.309614) (xy 187.387566 -266.356019) (xy 187.361144 -266.399215) (xy 187.329062 -266.43839)
			(xy 187.310776 -266.455906) (xy 187.301886 -266.464288) (xy 187.293504 -266.485878) (xy 187.302902 -266.590018)
			(xy 187.315094 -266.60983) (xy 187.325254 -266.616434) (xy 187.351364 -266.633511) (xy 187.399483 -266.673226)
			(xy 187.442238 -266.718665) (xy 187.478953 -266.76911) (xy 187.509046 -266.823763) (xy 187.532044 -266.881761)
			(xy 187.547582 -266.942187) (xy 187.555414 -267.004084) (xy 187.555886 -267.03528) (xy 187.555455 -267.066491)
			(xy 187.547626 -267.128419) (xy 187.532088 -267.188876) (xy 187.509089 -267.246906) (xy 187.47899 -267.301591)
			(xy 187.442268 -267.352068) (xy 187.399503 -267.397539) (xy 187.351371 -267.437285) (xy 187.325254 -267.45438)
			(xy 187.315094 -267.46073) (xy 187.302902 -267.480542) (xy 187.29325 -267.584682) (xy 187.301632 -267.606526)
			(xy 187.310522 -267.614654) (xy 187.328872 -267.632146) (xy 187.361011 -267.671355) (xy 187.38748 -267.714594)
			(xy 187.40778 -267.761051) (xy 187.421529 -267.809848) (xy 187.428467 -267.860069) (xy 187.428886 -267.885418)
			(xy 187.428494 -267.910736) (xy 187.421565 -267.960897) (xy 187.407838 -268.009638) (xy 187.387572 -268.056042)
			(xy 187.361148 -268.099238) (xy 187.329063 -268.138413) (xy 187.310776 -268.155928) (xy 187.301886 -268.16431)
			(xy 187.293504 -268.1859) (xy 187.302902 -268.29004) (xy 187.315094 -268.309852) (xy 187.325254 -268.316456)
			(xy 187.351374 -268.333518) (xy 187.399493 -268.373235) (xy 187.442248 -268.418676) (xy 187.478961 -268.469123)
			(xy 187.509054 -268.523779) (xy 187.53205 -268.581779) (xy 187.547585 -268.642207) (xy 187.555415 -268.704106)
			(xy 187.555886 -268.735302) (xy 187.555394 -268.766511) (xy 187.547574 -268.828437) (xy 187.532046 -268.888892)
			(xy 187.509056 -268.946921) (xy 187.478965 -269.001607) (xy 187.442251 -269.052085) (xy 187.399493 -269.097558)
			(xy 187.351368 -269.137306) (xy 187.325254 -269.154402) (xy 187.315094 -269.160752) (xy 187.302902 -269.180564)
			(xy 187.29325 -269.284704) (xy 187.301632 -269.306548) (xy 187.310522 -269.314676) (xy 187.328834 -269.332206)
			(xy 187.360977 -269.371407) (xy 187.387451 -269.414638) (xy 187.407757 -269.461087) (xy 187.421514 -269.509878)
			(xy 187.428462 -269.560093) (xy 187.428886 -269.58544) (xy 187.428442 -269.610757) (xy 187.421523 -269.660915)
			(xy 187.407806 -269.709654) (xy 187.38755 -269.756059) (xy 187.361135 -269.799256) (xy 187.329059 -269.838433)
			(xy 187.310776 -269.85595) (xy 187.301886 -269.864332) (xy 187.293504 -269.885922) (xy 187.302902 -269.990062)
			(xy 187.315094 -270.009874) (xy 187.325254 -270.016478) (xy 187.351339 -270.033593) (xy 187.399458 -270.073302)
			(xy 187.442214 -270.118735) (xy 187.47893 -270.169175) (xy 187.509027 -270.223823) (xy 187.532029 -270.281816)
			(xy 187.547572 -270.342237) (xy 187.55541 -270.40413) (xy 187.555886 -270.435324) (xy 187.555354 -270.468024)
			(xy 187.546748 -270.532857) (xy 187.52969 -270.595994) (xy 187.504475 -270.656338) (xy 187.471541 -270.712842)
			(xy 187.431462 -270.764523) (xy 187.408566 -270.787876) (xy 187.4012 -270.795242) (xy 187.39358 -270.813784)
			(xy 187.39358 -270.906748) (xy 187.4012 -270.92529) (xy 187.408566 -270.932656) (xy 187.431464 -270.956008)
			(xy 187.471548 -271.007687) (xy 187.504484 -271.06419) (xy 187.529701 -271.124535) (xy 187.546759 -271.187673)
			(xy 187.555362 -271.252507) (xy 187.555886 -271.285208) (xy 187.555399 -271.316417) (xy 187.547578 -271.378343)
			(xy 187.53205 -271.438799) (xy 187.509058 -271.496828) (xy 187.478967 -271.551514) (xy 187.442252 -271.601992)
			(xy 187.399494 -271.647464) (xy 187.351368 -271.687212) (xy 187.325254 -271.704308) (xy 187.315094 -271.710658)
			(xy 187.302902 -271.73047) (xy 187.29325 -271.83461) (xy 187.301632 -271.856454) (xy 187.310522 -271.864582)
			(xy 187.328837 -271.882109) (xy 187.36098 -271.92131) (xy 187.387453 -271.964542) (xy 187.407759 -272.010992)
			(xy 187.421515 -272.059784) (xy 187.428462 -272.109999) (xy 187.428886 -272.135346) (xy 187.428446 -272.160663)
			(xy 187.421526 -272.210821) (xy 187.407808 -272.259561) (xy 187.387551 -272.305966) (xy 187.361136 -272.349162)
			(xy 187.329059 -272.388339) (xy 187.310776 -272.405856) (xy 187.301886 -272.414238) (xy 187.293504 -272.435828)
			(xy 187.302902 -272.539968) (xy 187.315094 -272.55978) (xy 187.325254 -272.566384) (xy 187.351342 -272.583495)
			(xy 187.399461 -272.623204) (xy 187.442216 -272.668638) (xy 187.478933 -272.719078) (xy 187.509029 -272.773727)
			(xy 187.532031 -272.831721) (xy 187.547573 -272.892142) (xy 187.555411 -272.954036) (xy 187.555886 -272.98523)
			(xy 187.555416 -273.01644) (xy 187.547593 -273.078366) (xy 187.532061 -273.138822) (xy 187.509067 -273.196852)
			(xy 187.478974 -273.251537) (xy 187.442257 -273.302015) (xy 187.399497 -273.347487) (xy 187.351369 -273.387234)
			(xy 187.325254 -273.40433) (xy 187.315094 -273.41068) (xy 187.302902 -273.430492) (xy 187.29325 -273.534632)
			(xy 187.301632 -273.556476) (xy 187.310522 -273.564604) (xy 187.328848 -273.582121) (xy 187.360989 -273.621324)
			(xy 187.387461 -273.664558) (xy 187.407765 -273.71101) (xy 187.421519 -273.759803) (xy 187.428464 -273.810021)
			(xy 187.428886 -273.835368) (xy 190.664338 -273.835368) (xy 190.664796 -273.804158) (xy 190.672619 -273.74223)
			(xy 190.688152 -273.681773) (xy 190.711147 -273.623744) (xy 190.741242 -273.569058) (xy 190.777961 -273.51858)
			(xy 190.820724 -273.473109) (xy 190.868854 -273.433363) (xy 190.89497 -273.416268) (xy 190.90513 -273.409918)
			(xy 190.917322 -273.390106) (xy 190.926974 -273.285966) (xy 190.918592 -273.264122) (xy 190.909702 -273.255994)
			(xy 190.89138 -273.238474) (xy 190.859237 -273.199272) (xy 190.832764 -273.156038) (xy 190.812459 -273.109587)
			(xy 190.798705 -273.060794) (xy 190.79176 -273.010577) (xy 190.791338 -272.98523) (xy 190.791754 -272.959912)
			(xy 190.798678 -272.909753) (xy 190.8124 -272.861012) (xy 190.832661 -272.814607) (xy 190.859081 -272.771411)
			(xy 190.891163 -272.732236) (xy 190.909448 -272.71472) (xy 190.918338 -272.706338) (xy 190.92672 -272.684748)
			(xy 190.917322 -272.580608) (xy 190.90513 -272.560796) (xy 190.89497 -272.554192) (xy 190.868854 -272.537124)
			(xy 190.820738 -272.497405) (xy 190.777987 -272.451963) (xy 190.741274 -272.401517) (xy 190.711182 -272.346862)
			(xy 190.688184 -272.288864) (xy 190.672646 -272.228439) (xy 190.664812 -272.166542) (xy 190.664338 -272.135346)
			(xy 190.664778 -272.104135) (xy 190.672605 -272.042207) (xy 190.68814 -271.98175) (xy 190.711138 -271.92372)
			(xy 190.741235 -271.869034) (xy 190.777956 -271.818557) (xy 190.820721 -271.773086) (xy 190.868853 -271.73334)
			(xy 190.89497 -271.716246) (xy 190.90513 -271.709896) (xy 190.917322 -271.690084) (xy 190.926974 -271.585944)
			(xy 190.918592 -271.5641) (xy 190.909702 -271.555972) (xy 190.891369 -271.538462) (xy 190.859227 -271.499258)
			(xy 190.832756 -271.456022) (xy 190.812453 -271.409569) (xy 190.798701 -271.360774) (xy 190.791759 -271.310556)
			(xy 190.791338 -271.285208) (xy 190.791739 -271.25989) (xy 190.798666 -271.20973) (xy 190.812391 -271.160989)
			(xy 190.832655 -271.114584) (xy 190.859077 -271.071388) (xy 190.891161 -271.032213) (xy 190.909448 -271.014698)
			(xy 190.918338 -271.006316) (xy 190.92672 -270.984726) (xy 190.917322 -270.880586) (xy 190.90513 -270.860774)
			(xy 190.89497 -270.85417) (xy 190.868844 -270.837116) (xy 190.820728 -270.797396) (xy 190.777977 -270.751952)
			(xy 190.741266 -270.701503) (xy 190.711174 -270.646847) (xy 190.688179 -270.588846) (xy 190.672642 -270.528419)
			(xy 190.66481 -270.46652) (xy 190.664338 -270.435324) (xy 190.664859 -270.402623) (xy 190.67347 -270.337792)
			(xy 190.690532 -270.274655) (xy 190.71575 -270.214311) (xy 190.748684 -270.157808) (xy 190.788763 -270.106126)
			(xy 190.811658 -270.082772) (xy 190.819024 -270.075406) (xy 190.826644 -270.056864) (xy 190.826644 -269.9639)
			(xy 190.819024 -269.945358) (xy 190.811658 -269.937992) (xy 190.788739 -269.91466) (xy 190.748657 -269.862977)
			(xy 190.715723 -269.80647) (xy 190.69051 -269.746121) (xy 190.673456 -269.682979) (xy 190.664859 -269.618142)
			(xy 190.664338 -269.58544) (xy 190.664774 -269.554229) (xy 190.672601 -269.492301) (xy 190.688137 -269.431843)
			(xy 190.711135 -269.373813) (xy 190.741233 -269.319127) (xy 190.777955 -269.26865) (xy 190.82072 -269.22318)
			(xy 190.868853 -269.183434) (xy 190.89497 -269.16634) (xy 190.90513 -269.15999) (xy 190.917322 -269.140178)
			(xy 190.926974 -269.036038) (xy 190.918592 -269.014194) (xy 190.909702 -269.006066) (xy 190.891366 -268.988559)
			(xy 190.859225 -268.949354) (xy 190.832753 -268.906118) (xy 190.812451 -268.859665) (xy 190.798699 -268.810869)
			(xy 190.791758 -268.76065) (xy 190.791338 -268.735302) (xy 190.791735 -268.709984) (xy 190.798663 -268.659823)
			(xy 190.812388 -268.611082) (xy 190.832653 -268.564677) (xy 190.859076 -268.521482) (xy 190.891161 -268.482307)
			(xy 190.909448 -268.464792) (xy 190.918338 -268.45641) (xy 190.92672 -268.43482) (xy 190.917322 -268.33068)
			(xy 190.90513 -268.310868) (xy 190.89497 -268.304264) (xy 190.868841 -268.287214) (xy 190.820726 -268.247493)
			(xy 190.777974 -268.202049) (xy 190.741263 -268.151599) (xy 190.711172 -268.096942) (xy 190.688177 -268.038942)
			(xy 190.672641 -267.978514) (xy 190.66481 -267.916614) (xy 190.664338 -267.885418) (xy 190.664756 -267.854207)
			(xy 190.672586 -267.792277) (xy 190.688125 -267.73182) (xy 190.711126 -267.673789) (xy 190.741226 -267.619104)
			(xy 190.77795 -267.568627) (xy 190.820717 -267.523157) (xy 190.868852 -267.483412) (xy 190.89497 -267.466318)
			(xy 190.90513 -267.459968) (xy 190.917322 -267.440156) (xy 190.926974 -267.336016) (xy 190.918592 -267.314172)
			(xy 190.909702 -267.306044) (xy 190.891356 -267.288548) (xy 190.859215 -267.249341) (xy 190.832745 -267.206102)
			(xy 190.812444 -267.159647) (xy 190.798695 -267.110849) (xy 190.791757 -267.060629) (xy 190.791338 -267.03528)
			(xy 190.791721 -267.009961) (xy 190.798651 -266.9598) (xy 190.81238 -266.911059) (xy 190.832647 -266.864654)
			(xy 190.859073 -266.821459) (xy 190.89116 -266.782285) (xy 190.909448 -266.76477) (xy 190.918338 -266.756388)
			(xy 190.92672 -266.734798) (xy 190.917322 -266.630658) (xy 190.90513 -266.610846) (xy 190.89497 -266.604242)
			(xy 190.868831 -266.587207) (xy 190.820716 -266.547484) (xy 190.777965 -266.502037) (xy 190.741254 -266.451586)
			(xy 190.711165 -266.396926) (xy 190.688171 -266.338924) (xy 190.672637 -266.278494) (xy 190.664809 -266.216593)
			(xy 190.664338 -266.185396) (xy 190.664817 -266.154187) (xy 190.672638 -266.09226) (xy 190.688167 -266.031804)
			(xy 190.711159 -265.973774) (xy 190.741251 -265.919088) (xy 190.777967 -265.86861) (xy 190.820727 -265.823138)
			(xy 190.868855 -265.783391) (xy 190.89497 -265.766296) (xy 190.90513 -265.759946) (xy 190.917322 -265.740134)
			(xy 190.926974 -265.635994) (xy 190.918592 -265.61415) (xy 190.909702 -265.606022) (xy 190.891393 -265.588488)
			(xy 190.859249 -265.549289) (xy 190.832774 -265.506058) (xy 190.812467 -265.45961) (xy 190.79871 -265.410819)
			(xy 190.791762 -265.360605) (xy 190.791338 -265.335258) (xy 190.791773 -265.309941) (xy 190.798693 -265.259782)
			(xy 190.812411 -265.211042) (xy 190.832669 -265.164637) (xy 190.859086 -265.12144) (xy 190.891164 -265.082265)
			(xy 190.909448 -265.064748) (xy 190.918338 -265.056366) (xy 190.92672 -265.034776) (xy 190.917322 -264.930636)
			(xy 190.90513 -264.910824) (xy 190.89497 -264.90422) (xy 190.868867 -264.887133) (xy 190.820751 -264.847417)
			(xy 190.777999 -264.801978) (xy 190.741285 -264.751534) (xy 190.711191 -264.696883) (xy 190.688192 -264.638887)
			(xy 190.672651 -264.578464) (xy 190.664814 -264.516569) (xy 190.664338 -264.485374) (xy 190.6648 -264.454164)
			(xy 190.672623 -264.392236) (xy 190.688155 -264.33178) (xy 190.71115 -264.27375) (xy 190.741244 -264.219064)
			(xy 190.777962 -264.168586) (xy 190.820724 -264.123115) (xy 190.868854 -264.083369) (xy 190.89497 -264.066274)
			(xy 190.90513 -264.059924) (xy 190.917322 -264.040112) (xy 190.926974 -263.935972) (xy 190.918592 -263.914128)
			(xy 190.909702 -263.906) (xy 190.891383 -263.888477) (xy 190.85924 -263.849275) (xy 190.832766 -263.806043)
			(xy 190.812461 -263.759592) (xy 190.798706 -263.7108) (xy 190.791761 -263.660583) (xy 190.791338 -263.635236)
			(xy 190.791758 -263.609918) (xy 190.798681 -263.559759) (xy 190.812402 -263.511019) (xy 190.832663 -263.464614)
			(xy 190.859082 -263.421417) (xy 190.891163 -263.382242) (xy 190.909448 -263.364726) (xy 190.918338 -263.356344)
			(xy 190.92672 -263.334754) (xy 190.917322 -263.230614) (xy 190.90513 -263.210802) (xy 190.89497 -263.204198)
			(xy 190.868857 -263.187126) (xy 190.820741 -263.147408) (xy 190.777989 -263.101967) (xy 190.741277 -263.051521)
			(xy 190.711184 -262.996867) (xy 190.688186 -262.938869) (xy 190.672647 -262.878444) (xy 190.664812 -262.816547)
			(xy 190.664338 -262.785352) (xy 190.664783 -262.754142) (xy 190.672609 -262.692213) (xy 190.688143 -262.631756)
			(xy 190.71114 -262.573726) (xy 190.741237 -262.51904) (xy 190.777958 -262.468563) (xy 190.820722 -262.423092)
			(xy 190.868853 -262.383346) (xy 190.89497 -262.366252) (xy 190.90513 -262.359902) (xy 190.917322 -262.34009)
			(xy 190.926974 -262.23595) (xy 190.918592 -262.214106) (xy 190.909702 -262.205978) (xy 190.891372 -262.188465)
			(xy 190.85923 -262.149262) (xy 190.832758 -262.106027) (xy 190.812454 -262.059574) (xy 190.798702 -262.01078)
			(xy 190.791759 -261.960562) (xy 190.791338 -261.935214) (xy 190.791743 -261.909896) (xy 190.798669 -261.859736)
			(xy 190.812393 -261.810995) (xy 190.832656 -261.76459) (xy 190.859078 -261.721394) (xy 190.891162 -261.682219)
			(xy 190.909448 -261.664704) (xy 190.918338 -261.656322) (xy 190.92672 -261.634732) (xy 190.917322 -261.530592)
			(xy 190.90513 -261.51078) (xy 190.89497 -261.504176) (xy 190.868847 -261.487118) (xy 190.820731 -261.447398)
			(xy 190.77798 -261.401955) (xy 190.741268 -261.351507) (xy 190.711176 -261.296851) (xy 190.68818 -261.238851)
			(xy 190.672643 -261.178425) (xy 190.664811 -261.116526) (xy 190.664338 -261.08533) (xy 190.664827 -261.054167)
			(xy 190.672639 -260.992333) (xy 190.688139 -260.931965) (xy 190.711082 -260.874017) (xy 190.741108 -260.8194)
			(xy 190.777742 -260.768978) (xy 190.820407 -260.723544) (xy 190.868429 -260.683816) (xy 190.921053 -260.650421)
			(xy 190.977447 -260.623884) (xy 191.036722 -260.604624) (xy 191.097943 -260.592945) (xy 191.160146 -260.589032)
			(xy 191.222349 -260.592945) (xy 191.28357 -260.604624) (xy 191.342845 -260.623884) (xy 191.399239 -260.650421)
			(xy 191.451863 -260.683816) (xy 191.499885 -260.723544) (xy 191.54255 -260.768978) (xy 191.579184 -260.8194)
			(xy 191.60921 -260.874017) (xy 191.632153 -260.931965) (xy 191.647653 -260.992333) (xy 191.655465 -261.054167)
			(xy 191.655954 -261.08533) (xy 191.655438 -261.116525) (xy 191.647625 -261.178425) (xy 191.632102 -261.238854)
			(xy 191.609114 -261.296855) (xy 191.579026 -261.351511) (xy 191.542313 -261.401956) (xy 191.499557 -261.447393)
			(xy 191.451434 -261.487101) (xy 191.425322 -261.504176) (xy 191.415162 -261.51078) (xy 191.40297 -261.530592)
			(xy 191.393572 -261.634732) (xy 191.401954 -261.656322) (xy 191.410844 -261.664704) (xy 191.429139 -261.68221)
			(xy 191.461216 -261.721389) (xy 191.487632 -261.764588) (xy 191.507891 -261.810995) (xy 191.521612 -261.859736)
			(xy 191.528537 -261.909896) (xy 191.528954 -261.935214) (xy 191.528546 -261.960563) (xy 191.521611 -262.010784)
			(xy 191.50786 -262.05958) (xy 191.487552 -262.106033) (xy 191.461071 -262.149264) (xy 191.428915 -262.188459)
			(xy 191.41059 -262.205978) (xy 191.4017 -262.214106) (xy 191.393318 -262.23595) (xy 191.40297 -262.34009)
			(xy 191.415162 -262.359902) (xy 191.425322 -262.366252) (xy 191.451424 -262.383366) (xy 191.499545 -262.423116)
			(xy 191.542301 -262.468589) (xy 191.579015 -262.519064) (xy 191.609109 -262.573746) (xy 191.632107 -262.631771)
			(xy 191.647646 -262.692222) (xy 191.655481 -262.754144) (xy 191.655954 -262.785352) (xy 191.655455 -262.816548)
			(xy 191.64764 -262.878448) (xy 191.632114 -262.938877) (xy 191.609124 -262.996879) (xy 191.579033 -263.051535)
			(xy 191.542318 -263.10198) (xy 191.499559 -263.147416) (xy 191.451434 -263.187123) (xy 191.425322 -263.204198)
			(xy 191.415162 -263.210802) (xy 191.40297 -263.230614) (xy 191.393572 -263.334754) (xy 191.401954 -263.356344)
			(xy 191.410844 -263.364726) (xy 191.429149 -263.382221) (xy 191.461226 -263.421403) (xy 191.487641 -263.464604)
			(xy 191.507898 -263.511013) (xy 191.521616 -263.559756) (xy 191.528538 -263.609918) (xy 191.528954 -263.635236)
			(xy 191.528561 -263.660585) (xy 191.521623 -263.710807) (xy 191.507869 -263.759604) (xy 191.487558 -263.806056)
			(xy 191.461074 -263.849287) (xy 191.428916 -263.888481) (xy 191.41059 -263.906) (xy 191.4017 -263.914128)
			(xy 191.393318 -263.935972) (xy 191.40297 -264.040112) (xy 191.415162 -264.059924) (xy 191.425322 -264.066274)
			(xy 191.451434 -264.083373) (xy 191.499555 -264.123126) (xy 191.54231 -264.1686) (xy 191.579024 -264.219078)
			(xy 191.609117 -264.273762) (xy 191.632113 -264.331789) (xy 191.64765 -264.392241) (xy 191.655482 -264.454165)
			(xy 191.655954 -264.485374) (xy 191.655472 -264.51657) (xy 191.647654 -264.578471) (xy 191.632126 -264.638901)
			(xy 191.609133 -264.696903) (xy 191.57904 -264.751558) (xy 191.542323 -264.802003) (xy 191.499562 -264.847439)
			(xy 191.451435 -264.887146) (xy 191.425322 -264.90422) (xy 191.415162 -264.910824) (xy 191.40297 -264.930636)
			(xy 191.393572 -265.034776) (xy 191.401954 -265.056366) (xy 191.410844 -265.064748) (xy 191.429112 -265.082281)
			(xy 191.461191 -265.121455) (xy 191.487611 -265.164648) (xy 191.507875 -265.211049) (xy 191.521602 -265.259786)
			(xy 191.528533 -265.309942) (xy 191.528954 -265.335258) (xy 191.528576 -265.360608) (xy 191.521635 -265.41083)
			(xy 191.507878 -265.459627) (xy 191.487564 -265.506079) (xy 191.461078 -265.54931) (xy 191.428918 -265.588504)
			(xy 191.41059 -265.606022) (xy 191.4017 -265.61415) (xy 191.393318 -265.635994) (xy 191.40297 -265.740134)
			(xy 191.415162 -265.759946) (xy 191.425322 -265.766296) (xy 191.451444 -265.78338) (xy 191.499565 -265.823135)
			(xy 191.54232 -265.868612) (xy 191.579033 -265.919092) (xy 191.609124 -265.973778) (xy 191.632119 -266.031807)
			(xy 191.647654 -266.092261) (xy 191.655483 -266.154187) (xy 191.655954 -266.185396) (xy 191.655489 -266.216593)
			(xy 191.647669 -266.278495) (xy 191.632138 -266.338925) (xy 191.609143 -266.396926) (xy 191.579047 -266.451582)
			(xy 191.542327 -266.502026) (xy 191.499565 -266.547462) (xy 191.451436 -266.587168) (xy 191.425322 -266.604242)
			(xy 191.415162 -266.610846) (xy 191.40297 -266.630658) (xy 191.393572 -266.734798) (xy 191.401954 -266.756388)
			(xy 191.410844 -266.76477) (xy 191.429122 -266.782292) (xy 191.461201 -266.821468) (xy 191.48762 -266.864664)
			(xy 191.507881 -266.911067) (xy 191.521606 -266.959805) (xy 191.528534 -267.009963) (xy 191.528954 -267.03528)
			(xy 191.528524 -267.060628) (xy 191.521593 -267.110848) (xy 191.507847 -267.159644) (xy 191.487543 -267.206097)
			(xy 191.461065 -267.249328) (xy 191.428914 -267.288524) (xy 191.41059 -267.306044) (xy 191.4017 -267.314172)
			(xy 191.393318 -267.336016) (xy 191.40297 -267.440156) (xy 191.415162 -267.459968) (xy 191.425322 -267.466318)
			(xy 191.451454 -267.483387) (xy 191.499575 -267.523144) (xy 191.542329 -267.568623) (xy 191.579041 -267.619105)
			(xy 191.609132 -267.673794) (xy 191.632125 -267.731824) (xy 191.647658 -267.792281) (xy 191.655485 -267.854208)
			(xy 191.655954 -267.885418) (xy 191.655507 -267.916615) (xy 191.647683 -267.978518) (xy 191.63215 -268.038948)
			(xy 191.609152 -268.09695) (xy 191.579054 -268.151606) (xy 191.542332 -268.20205) (xy 191.499568 -268.247485)
			(xy 191.451437 -268.28719) (xy 191.425322 -268.304264) (xy 191.415162 -268.310868) (xy 191.40297 -268.33068)
			(xy 191.393572 -268.43482) (xy 191.401954 -268.45641) (xy 191.410844 -268.464792) (xy 191.429133 -268.482304)
			(xy 191.461211 -268.521482) (xy 191.487628 -268.56468) (xy 191.507888 -268.611085) (xy 191.52161 -268.659825)
			(xy 191.528536 -268.709984) (xy 191.528954 -268.735302) (xy 191.528538 -268.760651) (xy 191.521605 -268.810871)
			(xy 191.507855 -268.859668) (xy 191.487549 -268.90612) (xy 191.461069 -268.949351) (xy 191.428915 -268.988547)
			(xy 191.41059 -269.006066) (xy 191.4017 -269.014194) (xy 191.393318 -269.036038) (xy 191.40297 -269.140178)
			(xy 191.415162 -269.15999) (xy 191.425322 -269.16634) (xy 191.451418 -269.183462) (xy 191.49954 -269.223211)
			(xy 191.542295 -269.268682) (xy 191.57901 -269.319157) (xy 191.609105 -269.373838) (xy 191.632104 -269.431861)
			(xy 191.647644 -269.492311) (xy 191.65548 -269.554232) (xy 191.655954 -269.58544) (xy 191.655412 -269.61814)
			(xy 191.646805 -269.682971) (xy 191.629747 -269.746107) (xy 191.604534 -269.806451) (xy 191.571604 -269.862955)
			(xy 191.531528 -269.914638) (xy 191.508634 -269.937992) (xy 191.501268 -269.945358) (xy 191.493648 -269.9639)
			(xy 191.493648 -270.056864) (xy 191.501268 -270.075406) (xy 191.508634 -270.082772) (xy 191.531534 -270.106122)
			(xy 191.571619 -270.157801) (xy 191.604555 -270.214304) (xy 191.629772 -270.27465) (xy 191.646829 -270.337789)
			(xy 191.655431 -270.402623) (xy 191.655954 -270.435324) (xy 191.655511 -270.466522) (xy 191.647687 -270.528424)
			(xy 191.632153 -270.588855) (xy 191.609154 -270.646857) (xy 191.579056 -270.701512) (xy 191.542333 -270.751956)
			(xy 191.499568 -270.797391) (xy 191.451437 -270.837097) (xy 191.425322 -270.85417) (xy 191.415162 -270.860774)
			(xy 191.40297 -270.880586) (xy 191.393572 -270.984726) (xy 191.401954 -271.006316) (xy 191.410844 -271.014698)
			(xy 191.429136 -271.032207) (xy 191.461213 -271.071386) (xy 191.48763 -271.114584) (xy 191.50789 -271.16099)
			(xy 191.521611 -271.209731) (xy 191.528536 -271.25989) (xy 191.528954 -271.285208) (xy 191.528542 -271.310557)
			(xy 191.521608 -271.360777) (xy 191.507858 -271.409574) (xy 191.487551 -271.456026) (xy 191.46107 -271.499258)
			(xy 191.428915 -271.538453) (xy 191.41059 -271.555972) (xy 191.4017 -271.5641) (xy 191.393318 -271.585944)
			(xy 191.40297 -271.690084) (xy 191.415162 -271.709896) (xy 191.425322 -271.716246) (xy 191.451421 -271.733364)
			(xy 191.499542 -271.773114) (xy 191.542298 -271.818585) (xy 191.579013 -271.86906) (xy 191.609107 -271.923742)
			(xy 191.632106 -271.981766) (xy 191.647645 -272.042216) (xy 191.65548 -272.104138) (xy 191.655954 -272.135346)
			(xy 191.65545 -272.166542) (xy 191.647636 -272.228442) (xy 191.632111 -272.288871) (xy 191.609121 -272.346872)
			(xy 191.579031 -272.401528) (xy 191.542317 -272.451973) (xy 191.499559 -272.497409) (xy 191.451434 -272.537117)
			(xy 191.425322 -272.554192) (xy 191.415162 -272.560796) (xy 191.40297 -272.580608) (xy 191.393572 -272.684748)
			(xy 191.401954 -272.706338) (xy 191.410844 -272.71472) (xy 191.429146 -272.732218) (xy 191.461223 -272.771399)
			(xy 191.487638 -272.8146) (xy 191.507896 -272.861008) (xy 191.521615 -272.909751) (xy 191.528538 -272.959912)
			(xy 191.528954 -272.98523) (xy 191.528557 -273.010579) (xy 191.52162 -273.0608) (xy 191.507867 -273.109597)
			(xy 191.487557 -273.15605) (xy 191.461073 -273.199281) (xy 191.428916 -273.238475) (xy 191.41059 -273.255994)
			(xy 191.4017 -273.264122) (xy 191.393318 -273.285966) (xy 191.40297 -273.390106) (xy 191.415162 -273.409918)
			(xy 191.425322 -273.416268) (xy 191.451431 -273.433371) (xy 191.499552 -273.473123) (xy 191.542307 -273.518597)
			(xy 191.579022 -273.569074) (xy 191.609115 -273.623758) (xy 191.632112 -273.681784) (xy 191.647649 -273.742236)
			(xy 191.655482 -273.80416) (xy 191.655954 -273.835368) (xy 191.655465 -273.866531) (xy 191.647653 -273.928365)
			(xy 191.632153 -273.988733) (xy 191.60921 -274.046681) (xy 191.579184 -274.101298) (xy 191.54255 -274.15172)
			(xy 191.499885 -274.197154) (xy 191.451863 -274.236882) (xy 191.399239 -274.270277) (xy 191.342845 -274.296814)
			(xy 191.28357 -274.316074) (xy 191.222349 -274.327753) (xy 191.160146 -274.331666) (xy 191.097943 -274.327753)
			(xy 191.036722 -274.316074) (xy 190.977447 -274.296814) (xy 190.921053 -274.270277) (xy 190.868429 -274.236882)
			(xy 190.820407 -274.197154) (xy 190.777742 -274.15172) (xy 190.741108 -274.101298) (xy 190.711082 -274.046681)
			(xy 190.688139 -273.988733) (xy 190.672639 -273.928365) (xy 190.664827 -273.866531) (xy 190.664338 -273.835368)
			(xy 187.428886 -273.835368) (xy 187.428461 -273.860685) (xy 187.421538 -273.910844) (xy 187.407818 -273.959584)
			(xy 187.387558 -274.005989) (xy 187.36114 -274.049186) (xy 187.32906 -274.088362) (xy 187.310776 -274.105878)
			(xy 187.301886 -274.11426) (xy 187.293504 -274.13585) (xy 187.302902 -274.23999) (xy 187.315094 -274.259802)
			(xy 187.325254 -274.266406) (xy 187.351352 -274.283502) (xy 187.399471 -274.323214) (xy 187.442226 -274.36865)
			(xy 187.478941 -274.419092) (xy 187.509037 -274.473743) (xy 187.532037 -274.531738) (xy 187.547577 -274.592162)
			(xy 187.555412 -274.654057) (xy 187.555886 -274.685252) (xy 189.406545 -274.685252) (xy 189.41048 -274.631481)
			(xy 189.422203 -274.578857) (xy 189.441463 -274.5285) (xy 189.467849 -274.481483) (xy 189.500801 -274.43881)
			(xy 189.539614 -274.401389) (xy 189.583462 -274.370019) (xy 189.63141 -274.345367) (xy 189.682437 -274.327959)
			(xy 189.735455 -274.318166) (xy 189.789334 -274.316197) (xy 189.842925 -274.322094) (xy 189.895086 -274.33573)
			(xy 189.944706 -274.356817) (xy 189.990727 -274.384903) (xy 190.032169 -274.419391) (xy 190.068147 -274.459545)
			(xy 190.097895 -274.504509) (xy 190.12078 -274.553326) (xy 190.136312 -274.604955) (xy 190.144162 -274.658295)
			(xy 190.144654 -274.685252) (xy 194.108324 -274.685252) (xy 194.10879 -274.654055) (xy 194.116606 -274.592152)
			(xy 194.132134 -274.53172) (xy 194.155128 -274.473717) (xy 194.185223 -274.419061) (xy 194.221944 -274.368616)
			(xy 194.264709 -274.323182) (xy 194.31284 -274.283478) (xy 194.338956 -274.266406) (xy 194.349116 -274.259802)
			(xy 194.361308 -274.23999) (xy 194.370706 -274.13585) (xy 194.362324 -274.11426) (xy 194.353434 -274.105878)
			(xy 194.335126 -274.088385) (xy 194.303051 -274.049202) (xy 194.276637 -274.006) (xy 194.25638 -273.959592)
			(xy 194.242662 -273.910848) (xy 194.23574 -273.860687) (xy 194.235324 -273.835368) (xy 194.235727 -273.810019)
			(xy 194.242664 -273.759798) (xy 194.256416 -273.711002) (xy 194.276725 -273.66455) (xy 194.303207 -273.621318)
			(xy 194.335363 -273.582123) (xy 194.353688 -273.564604) (xy 194.362578 -273.556476) (xy 194.37096 -273.534632)
			(xy 194.361308 -273.430492) (xy 194.349116 -273.41068) (xy 194.338956 -273.40433) (xy 194.312841 -273.387236)
			(xy 194.264721 -273.347482) (xy 194.221967 -273.302006) (xy 194.185253 -273.251527) (xy 194.155161 -273.196843)
			(xy 194.132165 -273.138816) (xy 194.116628 -273.078363) (xy 194.108796 -273.016439) (xy 194.108324 -272.98523)
			(xy 194.108773 -272.954032) (xy 194.116592 -272.892128) (xy 194.132122 -272.831697) (xy 194.155119 -272.773693)
			(xy 194.185216 -272.719037) (xy 194.221939 -272.668593) (xy 194.264706 -272.623159) (xy 194.312839 -272.583456)
			(xy 194.338956 -272.566384) (xy 194.349116 -272.55978) (xy 194.361308 -272.539968) (xy 194.370706 -272.435828)
			(xy 194.362324 -272.414238) (xy 194.353434 -272.405856) (xy 194.335164 -272.388325) (xy 194.303085 -272.349151)
			(xy 194.276666 -272.305957) (xy 194.256403 -272.259555) (xy 194.242677 -272.210819) (xy 194.235745 -272.160662)
			(xy 194.235324 -272.135346) (xy 194.235712 -272.109997) (xy 194.242652 -272.059775) (xy 194.256408 -272.010978)
			(xy 194.276719 -271.964526) (xy 194.303204 -271.921295) (xy 194.335362 -271.882101) (xy 194.353688 -271.864582)
			(xy 194.362578 -271.856454) (xy 194.37096 -271.83461) (xy 194.361308 -271.73047) (xy 194.349116 -271.710658)
			(xy 194.338956 -271.704308) (xy 194.312831 -271.687229) (xy 194.264711 -271.647472) (xy 194.221957 -271.601995)
			(xy 194.185245 -271.551514) (xy 194.155154 -271.496827) (xy 194.132159 -271.438798) (xy 194.116625 -271.378343)
			(xy 194.108795 -271.316417) (xy 194.108324 -271.285208) (xy 194.108839 -271.252507) (xy 194.117452 -271.187675)
			(xy 194.134516 -271.124539) (xy 194.159734 -271.064195) (xy 194.192669 -271.007692) (xy 194.232748 -270.95601)
			(xy 194.255644 -270.932656) (xy 194.26301 -270.92529) (xy 194.27063 -270.906748) (xy 194.27063 -270.813784)
			(xy 194.26301 -270.795242) (xy 194.255644 -270.787876) (xy 194.232763 -270.764508) (xy 194.192677 -270.712833)
			(xy 194.159738 -270.656333) (xy 194.134519 -270.595991) (xy 194.117457 -270.532855) (xy 194.10885 -270.468024)
			(xy 194.108324 -270.435324) (xy 194.108768 -270.404126) (xy 194.116588 -270.342222) (xy 194.132119 -270.28179)
			(xy 194.155116 -270.223787) (xy 194.185214 -270.169131) (xy 194.221938 -270.118686) (xy 194.264705 -270.073253)
			(xy 194.312839 -270.03355) (xy 194.338956 -270.016478) (xy 194.349116 -270.009874) (xy 194.361308 -269.990062)
			(xy 194.370706 -269.885922) (xy 194.362324 -269.864332) (xy 194.353434 -269.85595) (xy 194.335161 -269.838422)
			(xy 194.303083 -269.799247) (xy 194.276664 -269.756052) (xy 194.256401 -269.70965) (xy 194.242676 -269.660913)
			(xy 194.235745 -269.610757) (xy 194.235324 -269.58544) (xy 194.235708 -269.560091) (xy 194.242649 -269.509869)
			(xy 194.256405 -269.461072) (xy 194.276718 -269.41462) (xy 194.303203 -269.371389) (xy 194.335361 -269.332195)
			(xy 194.353688 -269.314676) (xy 194.362578 -269.306548) (xy 194.37096 -269.284704) (xy 194.361308 -269.180564)
			(xy 194.349116 -269.160752) (xy 194.338956 -269.154402) (xy 194.312828 -269.137327) (xy 194.264708 -269.09757)
			(xy 194.221954 -269.052091) (xy 194.185242 -269.00161) (xy 194.155152 -268.946923) (xy 194.132158 -268.888893)
			(xy 194.116624 -268.828438) (xy 194.108795 -268.766512) (xy 194.108324 -268.735302) (xy 194.108751 -268.704103)
			(xy 194.116573 -268.642199) (xy 194.132107 -268.581767) (xy 194.155107 -268.523763) (xy 194.185207 -268.469107)
			(xy 194.221933 -268.418663) (xy 194.264703 -268.37323) (xy 194.312838 -268.333527) (xy 194.338956 -268.316456)
			(xy 194.349116 -268.309852) (xy 194.361308 -268.29004) (xy 194.370706 -268.1859) (xy 194.362324 -268.16431)
			(xy 194.353434 -268.155928) (xy 194.335151 -268.138411) (xy 194.303073 -268.099233) (xy 194.276656 -268.056037)
			(xy 194.256395 -268.009632) (xy 194.242672 -267.960893) (xy 194.235743 -267.910735) (xy 194.235324 -267.885418)
			(xy 194.23576 -267.86007) (xy 194.24269 -267.809851) (xy 194.256436 -267.761055) (xy 194.276739 -267.714603)
			(xy 194.303215 -267.671371) (xy 194.335365 -267.632174) (xy 194.353688 -267.614654) (xy 194.362578 -267.606526)
			(xy 194.37096 -267.584682) (xy 194.361308 -267.480542) (xy 194.349116 -267.46073) (xy 194.338956 -267.45438)
			(xy 194.312818 -267.437319) (xy 194.264698 -267.39756) (xy 194.221945 -267.35208) (xy 194.185234 -267.301596)
			(xy 194.155144 -267.246907) (xy 194.132152 -267.188875) (xy 194.11662 -267.128418) (xy 194.108793 -267.06649)
			(xy 194.108324 -267.03528) (xy 194.108734 -267.004081) (xy 194.116559 -266.942176) (xy 194.132095 -266.881743)
			(xy 194.155097 -266.823739) (xy 194.185201 -266.769083) (xy 194.221928 -266.71864) (xy 194.2647 -266.673207)
			(xy 194.312837 -266.633505) (xy 194.338956 -266.616434) (xy 194.349116 -266.60983) (xy 194.361308 -266.590018)
			(xy 194.370706 -266.485878) (xy 194.362324 -266.464288) (xy 194.353434 -266.455906) (xy 194.33514 -266.438399)
			(xy 194.303063 -266.39922) (xy 194.276647 -266.356021) (xy 194.256389 -266.309615) (xy 194.242667 -266.260873)
			(xy 194.235742 -266.210714) (xy 194.235324 -266.185396) (xy 194.235745 -266.160048) (xy 194.242679 -266.109828)
			(xy 194.256428 -266.061032) (xy 194.276733 -266.014579) (xy 194.303212 -265.971348) (xy 194.335364 -265.932152)
			(xy 194.353688 -265.914632) (xy 194.362578 -265.906504) (xy 194.37096 -265.88466) (xy 194.361308 -265.78052)
			(xy 194.349116 -265.760708) (xy 194.338956 -265.754358) (xy 194.312854 -265.737245) (xy 194.264734 -265.697494)
			(xy 194.221979 -265.652021) (xy 194.185265 -265.601545) (xy 194.155171 -265.546863) (xy 194.132173 -265.488839)
			(xy 194.116633 -265.428388) (xy 194.108798 -265.366466) (xy 194.108324 -265.335258) (xy 194.108795 -265.304061)
			(xy 194.11661 -265.242158) (xy 194.132137 -265.181727) (xy 194.15513 -265.123724) (xy 194.185225 -265.069067)
			(xy 194.221945 -265.018623) (xy 194.264709 -264.973188) (xy 194.31284 -264.933484) (xy 194.338956 -264.916412)
			(xy 194.349116 -264.909808) (xy 194.361308 -264.889996) (xy 194.370706 -264.785856) (xy 194.362324 -264.764266)
			(xy 194.353434 -264.755884) (xy 194.335129 -264.738388) (xy 194.303054 -264.699206) (xy 194.276639 -264.656005)
			(xy 194.256382 -264.609597) (xy 194.242663 -264.560854) (xy 194.235741 -264.510692) (xy 194.235324 -264.485374)
			(xy 194.235731 -264.460025) (xy 194.242667 -264.409805) (xy 194.256419 -264.361008) (xy 194.276727 -264.314556)
			(xy 194.303208 -264.271325) (xy 194.335363 -264.232129) (xy 194.353688 -264.21461) (xy 194.362578 -264.206482)
			(xy 194.37096 -264.184638) (xy 194.361308 -264.080498) (xy 194.349116 -264.060686) (xy 194.338956 -264.054336)
			(xy 194.312844 -264.037238) (xy 194.264724 -263.997484) (xy 194.221969 -263.952009) (xy 194.185256 -263.901531)
			(xy 194.155163 -263.846847) (xy 194.132167 -263.788821) (xy 194.116629 -263.728368) (xy 194.108797 -263.666445)
			(xy 194.108324 -263.635236) (xy 194.108778 -263.604038) (xy 194.116596 -263.542135) (xy 194.132126 -263.481703)
			(xy 194.155121 -263.4237) (xy 194.185218 -263.369044) (xy 194.221941 -263.318599) (xy 194.264707 -263.273166)
			(xy 194.31284 -263.233462) (xy 194.338956 -263.21639) (xy 194.349116 -263.209786) (xy 194.361308 -263.189974)
			(xy 194.370706 -263.085834) (xy 194.362324 -263.064244) (xy 194.353434 -263.055862) (xy 194.335167 -263.038328)
			(xy 194.303088 -262.999154) (xy 194.276669 -262.955961) (xy 194.256405 -262.90956) (xy 194.242678 -262.860824)
			(xy 194.235746 -262.810668) (xy 194.235324 -262.785352) (xy 194.235716 -262.760003) (xy 194.242655 -262.709782)
			(xy 194.25641 -262.660985) (xy 194.276721 -262.614533) (xy 194.303205 -262.571302) (xy 194.335362 -262.532107)
			(xy 194.353688 -262.514588) (xy 194.362578 -262.50646) (xy 194.37096 -262.484616) (xy 194.361308 -262.380476)
			(xy 194.349116 -262.360664) (xy 194.338956 -262.354314) (xy 194.312834 -262.337231) (xy 194.264714 -262.297475)
			(xy 194.22196 -262.251998) (xy 194.185247 -262.201518) (xy 194.155156 -262.146831) (xy 194.132161 -262.088803)
			(xy 194.116626 -262.028349) (xy 194.108795 -261.966423) (xy 194.108324 -261.935214) (xy 194.108813 -261.904051)
			(xy 194.116625 -261.842217) (xy 194.132125 -261.781849) (xy 194.155068 -261.723901) (xy 194.185094 -261.669284)
			(xy 194.221728 -261.618862) (xy 194.264393 -261.573428) (xy 194.312415 -261.5337) (xy 194.365039 -261.500305)
			(xy 194.421433 -261.473768) (xy 194.480708 -261.454508) (xy 194.541929 -261.442829) (xy 194.604132 -261.438916)
			(xy 194.666335 -261.442829) (xy 194.727556 -261.454508) (xy 194.786831 -261.473768) (xy 194.843225 -261.500305)
			(xy 194.895849 -261.5337) (xy 194.943871 -261.573428) (xy 194.986536 -261.618862) (xy 195.02317 -261.669284)
			(xy 195.053196 -261.723901) (xy 195.076139 -261.781849) (xy 195.091639 -261.842217) (xy 195.099451 -261.904051)
			(xy 195.09994 -261.935214) (xy 195.099432 -261.966422) (xy 195.091612 -262.028347) (xy 195.076085 -262.088801)
			(xy 195.053095 -262.146829) (xy 195.023007 -262.201514) (xy 194.986296 -262.251992) (xy 194.943542 -262.297466)
			(xy 194.89542 -262.337216) (xy 194.869308 -262.354314) (xy 194.859148 -262.360664) (xy 194.846956 -262.380476)
			(xy 194.837304 -262.484616) (xy 194.845686 -262.50646) (xy 194.854576 -262.514588) (xy 194.872885 -262.532121)
			(xy 194.90503 -262.57132) (xy 194.931505 -262.614551) (xy 194.951813 -262.660999) (xy 194.965569 -262.70979)
			(xy 194.972517 -262.760005) (xy 194.97294 -262.785352) (xy 194.972519 -262.81067) (xy 194.965597 -262.860829)
			(xy 194.951877 -262.90957) (xy 194.931616 -262.955975) (xy 194.905197 -262.999171) (xy 194.873115 -263.038346)
			(xy 194.85483 -263.055862) (xy 194.84594 -263.064244) (xy 194.837558 -263.085834) (xy 194.846956 -263.189974)
			(xy 194.859148 -263.209786) (xy 194.869308 -263.21639) (xy 194.895411 -263.233478) (xy 194.943527 -263.273193)
			(xy 194.98628 -263.318631) (xy 195.022994 -263.369075) (xy 195.053089 -263.423727) (xy 195.076088 -263.481722)
			(xy 195.091629 -263.542146) (xy 195.099465 -263.604041) (xy 195.09994 -263.635236) (xy 195.099449 -263.666445)
			(xy 195.091627 -263.72837) (xy 195.076097 -263.788824) (xy 195.053105 -263.846852) (xy 195.023014 -263.901538)
			(xy 194.986301 -263.952016) (xy 194.943544 -263.997489) (xy 194.895421 -264.037239) (xy 194.869308 -264.054336)
			(xy 194.859148 -264.060686) (xy 194.846956 -264.080498) (xy 194.837304 -264.184638) (xy 194.845686 -264.206482)
			(xy 194.854576 -264.21461) (xy 194.872896 -264.232133) (xy 194.90504 -264.271334) (xy 194.931514 -264.314566)
			(xy 194.951819 -264.361017) (xy 194.965574 -264.40981) (xy 194.972518 -264.460027) (xy 194.97294 -264.485374)
			(xy 194.972533 -264.510692) (xy 194.965608 -264.560852) (xy 194.951885 -264.609593) (xy 194.931622 -264.655998)
			(xy 194.9052 -264.699194) (xy 194.873116 -264.738369) (xy 194.85483 -264.755884) (xy 194.84594 -264.764266)
			(xy 194.837558 -264.785856) (xy 194.846956 -264.889996) (xy 194.859148 -264.909808) (xy 194.869308 -264.916412)
			(xy 194.895421 -264.933485) (xy 194.943537 -264.973202) (xy 194.98629 -265.018643) (xy 195.023003 -265.069089)
			(xy 195.053096 -265.123742) (xy 195.076094 -265.18174) (xy 195.091633 -265.242165) (xy 195.099466 -265.304063)
			(xy 195.09994 -265.335258) (xy 195.099467 -265.366467) (xy 195.091641 -265.428393) (xy 195.076108 -265.488848)
			(xy 195.053114 -265.546876) (xy 195.023021 -265.601561) (xy 194.986306 -265.652039) (xy 194.943547 -265.697512)
			(xy 194.895422 -265.737261) (xy 194.869308 -265.754358) (xy 194.859148 -265.760708) (xy 194.846956 -265.78052)
			(xy 194.837304 -265.88466) (xy 194.845686 -265.906504) (xy 194.854576 -265.914632) (xy 194.872907 -265.932144)
			(xy 194.905049 -265.971347) (xy 194.931522 -266.014582) (xy 194.951826 -266.061035) (xy 194.965578 -266.10983)
			(xy 194.97252 -266.160048) (xy 194.97294 -266.185396) (xy 194.972548 -266.210715) (xy 194.96562 -266.260875)
			(xy 194.951894 -266.309617) (xy 194.931628 -266.356022) (xy 194.905204 -266.399217) (xy 194.873117 -266.438391)
			(xy 194.85483 -266.455906) (xy 194.84594 -266.464288) (xy 194.837558 -266.485878) (xy 194.846956 -266.590018)
			(xy 194.859148 -266.60983) (xy 194.869308 -266.616434) (xy 194.895431 -266.633493) (xy 194.943547 -266.673212)
			(xy 194.9863 -266.718654) (xy 195.023012 -266.769102) (xy 195.053104 -266.823758) (xy 195.0761 -266.881758)
			(xy 195.091636 -266.942185) (xy 195.099468 -267.004084) (xy 195.09994 -267.03528) (xy 195.099484 -267.06649)
			(xy 195.091656 -267.128416) (xy 195.07612 -267.188871) (xy 195.053123 -267.2469) (xy 195.023028 -267.301585)
			(xy 194.98631 -267.352063) (xy 194.94355 -267.397535) (xy 194.895423 -267.437283) (xy 194.869308 -267.45438)
			(xy 194.859148 -267.46073) (xy 194.846956 -267.480542) (xy 194.837304 -267.584682) (xy 194.845686 -267.606526)
			(xy 194.854576 -267.614654) (xy 194.872917 -267.632155) (xy 194.905059 -267.671361) (xy 194.93153 -267.714598)
			(xy 194.951832 -267.761053) (xy 194.965582 -267.80985) (xy 194.972521 -267.860069) (xy 194.97294 -267.885418)
			(xy 194.972563 -267.910737) (xy 194.965632 -267.960899) (xy 194.951903 -268.00964) (xy 194.931635 -268.056045)
			(xy 194.905208 -268.09924) (xy 194.873119 -268.138414) (xy 194.85483 -268.155928) (xy 194.84594 -268.16431)
			(xy 194.837558 -268.1859) (xy 194.846956 -268.29004) (xy 194.859148 -268.309852) (xy 194.869308 -268.316456)
			(xy 194.895441 -268.3335) (xy 194.943557 -268.373221) (xy 194.986309 -268.418666) (xy 195.023021 -268.469116)
			(xy 195.053111 -268.523774) (xy 195.076106 -268.581776) (xy 195.09164 -268.642205) (xy 195.099469 -268.704105)
			(xy 195.09994 -268.735302) (xy 195.099423 -268.76651) (xy 195.091604 -268.828434) (xy 195.076078 -268.888888)
			(xy 195.05309 -268.946916) (xy 195.023003 -269.001601) (xy 194.986293 -269.05208) (xy 194.94354 -269.097554)
			(xy 194.89542 -269.137304) (xy 194.869308 -269.154402) (xy 194.859148 -269.160752) (xy 194.846956 -269.180564)
			(xy 194.837304 -269.284704) (xy 194.845686 -269.306548) (xy 194.854576 -269.314676) (xy 194.872879 -269.332215)
			(xy 194.905025 -269.371413) (xy 194.931501 -269.414642) (xy 194.951809 -269.461089) (xy 194.965567 -269.509879)
			(xy 194.972516 -269.560094) (xy 194.97294 -269.58544) (xy 194.972511 -269.610757) (xy 194.96559 -269.660917)
			(xy 194.951872 -269.709657) (xy 194.931613 -269.756062) (xy 194.905195 -269.799259) (xy 194.873115 -269.838434)
			(xy 194.85483 -269.85595) (xy 194.84594 -269.864332) (xy 194.837558 -269.885922) (xy 194.846956 -269.990062)
			(xy 194.859148 -270.009874) (xy 194.869308 -270.016478) (xy 194.895405 -270.033574) (xy 194.943522 -270.073288)
			(xy 194.986275 -270.118725) (xy 195.02299 -270.169167) (xy 195.053085 -270.223818) (xy 195.076085 -270.281813)
			(xy 195.091627 -270.342235) (xy 195.099464 -270.40413) (xy 195.09994 -270.435324) (xy 195.099392 -270.468024)
			(xy 195.090787 -270.532855) (xy 195.073731 -270.595991) (xy 195.048519 -270.656335) (xy 195.015589 -270.712839)
			(xy 194.975514 -270.764522) (xy 194.95262 -270.787876) (xy 194.945254 -270.795242) (xy 194.937634 -270.813784)
			(xy 194.937634 -270.906748) (xy 194.945254 -270.92529) (xy 194.95262 -270.932656) (xy 194.97551 -270.956016)
			(xy 195.015596 -271.007692) (xy 195.048534 -271.064193) (xy 195.073753 -271.124537) (xy 195.090812 -271.187674)
			(xy 195.099416 -271.252507) (xy 195.09994 -271.285208) (xy 195.099428 -271.316416) (xy 195.091608 -271.37834)
			(xy 195.076081 -271.438794) (xy 195.053093 -271.496822) (xy 195.023005 -271.551508) (xy 194.986295 -271.601986)
			(xy 194.943541 -271.64746) (xy 194.89542 -271.68721) (xy 194.869308 -271.704308) (xy 194.859148 -271.710658)
			(xy 194.846956 -271.73047) (xy 194.837304 -271.83461) (xy 194.845686 -271.856454) (xy 194.854576 -271.864582)
			(xy 194.872882 -271.882118) (xy 194.905027 -271.921316) (xy 194.931503 -271.964546) (xy 194.951811 -272.010994)
			(xy 194.965568 -272.059785) (xy 194.972516 -272.109999) (xy 194.97294 -272.135346) (xy 194.972515 -272.160663)
			(xy 194.965594 -272.210823) (xy 194.951874 -272.259564) (xy 194.931615 -272.305969) (xy 194.905196 -272.349165)
			(xy 194.873115 -272.38834) (xy 194.85483 -272.405856) (xy 194.84594 -272.414238) (xy 194.837558 -272.435828)
			(xy 194.846956 -272.539968) (xy 194.859148 -272.55978) (xy 194.869308 -272.566384) (xy 194.895408 -272.583476)
			(xy 194.943525 -272.62319) (xy 194.986278 -272.668628) (xy 195.022992 -272.719071) (xy 195.053087 -272.773722)
			(xy 195.076087 -272.831717) (xy 195.091628 -272.89214) (xy 195.099465 -272.954035) (xy 195.09994 -272.98523)
			(xy 195.099445 -273.016439) (xy 195.091623 -273.078363) (xy 195.076093 -273.138818) (xy 195.053102 -273.196846)
			(xy 195.023012 -273.251531) (xy 194.986299 -273.302009) (xy 194.943544 -273.347483) (xy 194.895421 -273.387233)
			(xy 194.869308 -273.40433) (xy 194.859148 -273.41068) (xy 194.846956 -273.430492) (xy 194.837304 -273.534632)
			(xy 194.845686 -273.556476) (xy 194.854576 -273.564604) (xy 194.872893 -273.58213) (xy 194.905037 -273.62133)
			(xy 194.931511 -273.664562) (xy 194.951817 -273.711012) (xy 194.965572 -273.759805) (xy 194.972518 -273.810021)
			(xy 194.97294 -273.835368) (xy 198.208392 -273.835368) (xy 198.208871 -273.804159) (xy 198.216694 -273.742233)
			(xy 198.232224 -273.681777) (xy 198.255218 -273.623748) (xy 198.28531 -273.569063) (xy 198.322025 -273.518585)
			(xy 198.364784 -273.473113) (xy 198.41291 -273.433364) (xy 198.439024 -273.416268) (xy 198.449184 -273.409918)
			(xy 198.461376 -273.390106) (xy 198.471028 -273.285966) (xy 198.462646 -273.264122) (xy 198.453756 -273.255994)
			(xy 198.435444 -273.238463) (xy 198.403298 -273.199265) (xy 198.376822 -273.156034) (xy 198.356515 -273.109585)
			(xy 198.34276 -273.060793) (xy 198.335814 -273.010577) (xy 198.335392 -272.98523) (xy 198.335823 -272.959913)
			(xy 198.342745 -272.909755) (xy 198.356465 -272.861015) (xy 198.376724 -272.81461) (xy 198.403141 -272.771413)
			(xy 198.435219 -272.732237) (xy 198.453502 -272.71472) (xy 198.462392 -272.706338) (xy 198.470774 -272.684748)
			(xy 198.461376 -272.580608) (xy 198.449184 -272.560796) (xy 198.439024 -272.554192) (xy 198.41292 -272.537105)
			(xy 198.364802 -272.497391) (xy 198.322048 -272.451953) (xy 198.285334 -272.40151) (xy 198.255239 -272.346858)
			(xy 198.23224 -272.288861) (xy 198.216701 -272.228437) (xy 198.208866 -272.166541) (xy 198.208392 -272.135346)
			(xy 198.208854 -272.104136) (xy 198.216679 -272.042209) (xy 198.232213 -271.981754) (xy 198.255208 -271.923725)
			(xy 198.285303 -271.869039) (xy 198.32202 -271.818562) (xy 198.364781 -271.77309) (xy 198.412909 -271.733342)
			(xy 198.439024 -271.716246) (xy 198.449184 -271.709896) (xy 198.461376 -271.690084) (xy 198.471028 -271.585944)
			(xy 198.462646 -271.5641) (xy 198.453756 -271.555972) (xy 198.435433 -271.538452) (xy 198.403289 -271.499251)
			(xy 198.376814 -271.456018) (xy 198.356509 -271.409567) (xy 198.342756 -271.360773) (xy 198.335813 -271.310556)
			(xy 198.335392 -271.285208) (xy 198.335808 -271.25989) (xy 198.342734 -271.209731) (xy 198.356457 -271.160991)
			(xy 198.376718 -271.114587) (xy 198.403137 -271.07139) (xy 198.435217 -271.032214) (xy 198.453502 -271.014698)
			(xy 198.462392 -271.006316) (xy 198.470774 -270.984726) (xy 198.461376 -270.880586) (xy 198.449184 -270.860774)
			(xy 198.439024 -270.85417) (xy 198.41291 -270.837098) (xy 198.364792 -270.797382) (xy 198.322039 -270.751942)
			(xy 198.285325 -270.701496) (xy 198.255232 -270.646842) (xy 198.232234 -270.588843) (xy 198.216697 -270.528418)
			(xy 198.208865 -270.46652) (xy 198.208392 -270.435324) (xy 198.208897 -270.402623) (xy 198.217509 -270.33779)
			(xy 198.234574 -270.274652) (xy 198.259794 -270.214308) (xy 198.292731 -270.157805) (xy 198.332814 -270.106125)
			(xy 198.355712 -270.082772) (xy 198.363078 -270.075406) (xy 198.370698 -270.056864) (xy 198.370698 -269.9639)
			(xy 198.363078 -269.945358) (xy 198.355712 -269.937992) (xy 198.332785 -269.914668) (xy 198.292705 -269.862982)
			(xy 198.259773 -269.806473) (xy 198.234562 -269.746123) (xy 198.21751 -269.68298) (xy 198.208913 -269.618142)
			(xy 198.208392 -269.58544) (xy 198.208849 -269.55423) (xy 198.216675 -269.492303) (xy 198.232209 -269.431847)
			(xy 198.255206 -269.373818) (xy 198.285301 -269.319133) (xy 198.322019 -269.268655) (xy 198.36478 -269.223183)
			(xy 198.412909 -269.183436) (xy 198.439024 -269.16634) (xy 198.449184 -269.15999) (xy 198.461376 -269.140178)
			(xy 198.471028 -269.036038) (xy 198.462646 -269.014194) (xy 198.453756 -269.006066) (xy 198.435431 -268.988549)
			(xy 198.403286 -268.949347) (xy 198.376812 -268.906114) (xy 198.356507 -268.859662) (xy 198.342754 -268.810868)
			(xy 198.335812 -268.76065) (xy 198.335392 -268.735302) (xy 198.335804 -268.709984) (xy 198.342731 -268.659825)
			(xy 198.356454 -268.611085) (xy 198.376716 -268.564681) (xy 198.403136 -268.521484) (xy 198.435217 -268.482308)
			(xy 198.453502 -268.464792) (xy 198.462392 -268.45641) (xy 198.470774 -268.43482) (xy 198.461376 -268.33068)
			(xy 198.449184 -268.310868) (xy 198.439024 -268.304264) (xy 198.412908 -268.287196) (xy 198.36479 -268.247479)
			(xy 198.322036 -268.202039) (xy 198.285323 -268.151592) (xy 198.255229 -268.096937) (xy 198.232233 -268.038938)
			(xy 198.216696 -267.978512) (xy 198.208864 -267.916614) (xy 198.208392 -267.885418) (xy 198.208832 -267.854208)
			(xy 198.216661 -267.79228) (xy 198.232198 -267.731824) (xy 198.255196 -267.673794) (xy 198.285294 -267.619109)
			(xy 198.322014 -267.568632) (xy 198.364778 -267.52316) (xy 198.412908 -267.483413) (xy 198.439024 -267.466318)
			(xy 198.449184 -267.459968) (xy 198.461376 -267.440156) (xy 198.471028 -267.336016) (xy 198.462646 -267.314172)
			(xy 198.453756 -267.306044) (xy 198.43542 -267.288537) (xy 198.403276 -267.249334) (xy 198.376804 -267.206098)
			(xy 198.356501 -267.159644) (xy 198.34275 -267.110848) (xy 198.335811 -267.060628) (xy 198.335392 -267.03528)
			(xy 198.335789 -267.009962) (xy 198.342719 -266.959802) (xy 198.356445 -266.911062) (xy 198.37671 -266.864657)
			(xy 198.403133 -266.821461) (xy 198.435216 -266.782286) (xy 198.453502 -266.76477) (xy 198.462392 -266.756388)
			(xy 198.470774 -266.734798) (xy 198.461376 -266.630658) (xy 198.449184 -266.610846) (xy 198.439024 -266.604242)
			(xy 198.412898 -266.587188) (xy 198.36478 -266.54747) (xy 198.322027 -266.502027) (xy 198.285314 -266.451578)
			(xy 198.255222 -266.396921) (xy 198.232227 -266.338921) (xy 198.216692 -266.278492) (xy 198.208863 -266.216593)
			(xy 198.208392 -266.185396) (xy 198.208893 -266.154187) (xy 198.216712 -266.092262) (xy 198.23224 -266.031807)
			(xy 198.255229 -265.973779) (xy 198.285319 -265.919093) (xy 198.322031 -265.868615) (xy 198.364787 -265.823142)
			(xy 198.412911 -265.783393) (xy 198.439024 -265.766296) (xy 198.449184 -265.759946) (xy 198.461376 -265.740134)
			(xy 198.471028 -265.635994) (xy 198.462646 -265.61415) (xy 198.453756 -265.606022) (xy 198.435458 -265.588478)
			(xy 198.403311 -265.549282) (xy 198.376833 -265.506054) (xy 198.356524 -265.459608) (xy 198.342765 -265.410818)
			(xy 198.335816 -265.360604) (xy 198.335392 -265.335258) (xy 198.335841 -265.309942) (xy 198.34276 -265.259784)
			(xy 198.356476 -265.211045) (xy 198.376732 -265.16464) (xy 198.403145 -265.121443) (xy 198.43522 -265.082265)
			(xy 198.453502 -265.064748) (xy 198.462392 -265.056366) (xy 198.470774 -265.034776) (xy 198.461376 -264.930636)
			(xy 198.449184 -264.910824) (xy 198.439024 -264.90422) (xy 198.412933 -264.887114) (xy 198.364815 -264.847403)
			(xy 198.32206 -264.801968) (xy 198.285345 -264.751527) (xy 198.255249 -264.696878) (xy 198.232248 -264.638884)
			(xy 198.216705 -264.578462) (xy 198.208868 -264.516568) (xy 198.208392 -264.485374) (xy 198.208876 -264.454165)
			(xy 198.216698 -264.392239) (xy 198.232228 -264.331784) (xy 198.25522 -264.273755) (xy 198.285312 -264.219069)
			(xy 198.322026 -264.168591) (xy 198.364785 -264.123119) (xy 198.41291 -264.08337) (xy 198.439024 -264.066274)
			(xy 198.449184 -264.059924) (xy 198.461376 -264.040112) (xy 198.471028 -263.935972) (xy 198.462646 -263.914128)
			(xy 198.453756 -263.906) (xy 198.435447 -263.888466) (xy 198.403301 -263.849268) (xy 198.376825 -263.806038)
			(xy 198.356517 -263.75959) (xy 198.342761 -263.710798) (xy 198.335815 -263.660583) (xy 198.335392 -263.635236)
			(xy 198.335827 -263.609919) (xy 198.342749 -263.559761) (xy 198.356468 -263.511021) (xy 198.376726 -263.464617)
			(xy 198.403142 -263.42142) (xy 198.435219 -263.382243) (xy 198.453502 -263.364726) (xy 198.462392 -263.356344)
			(xy 198.470774 -263.334754) (xy 198.461376 -263.230614) (xy 198.449184 -263.210802) (xy 198.439024 -263.204198)
			(xy 198.412923 -263.187107) (xy 198.364805 -263.147394) (xy 198.322051 -263.101956) (xy 198.285336 -263.051513)
			(xy 198.255241 -262.996862) (xy 198.232242 -262.938866) (xy 198.216702 -262.878443) (xy 198.208866 -262.816547)
			(xy 198.208392 -262.785352) (xy 198.208858 -262.754142) (xy 198.216683 -262.692216) (xy 198.232216 -262.63176)
			(xy 198.255211 -262.573731) (xy 198.285305 -262.519046) (xy 198.322022 -262.468568) (xy 198.364782 -262.423096)
			(xy 198.412909 -262.383348) (xy 198.439024 -262.366252) (xy 198.449184 -262.359902) (xy 198.461376 -262.34009)
			(xy 198.471028 -262.23595) (xy 198.462646 -262.214106) (xy 198.453756 -262.205978) (xy 198.435436 -262.188455)
			(xy 198.403291 -262.149255) (xy 198.376816 -262.106022) (xy 198.356511 -262.059572) (xy 198.342757 -262.010778)
			(xy 198.335813 -261.960561) (xy 198.335392 -261.935214) (xy 198.335812 -261.909897) (xy 198.342737 -261.859738)
			(xy 198.356459 -261.810998) (xy 198.37672 -261.764593) (xy 198.403138 -261.721397) (xy 198.435218 -261.682221)
			(xy 198.453502 -261.664704) (xy 198.462392 -261.656322) (xy 198.470774 -261.634732) (xy 198.461376 -261.530592)
			(xy 198.449184 -261.51078) (xy 198.439024 -261.504176) (xy 198.412913 -261.4871) (xy 198.364795 -261.447384)
			(xy 198.322041 -261.401945) (xy 198.285327 -261.3515) (xy 198.255234 -261.296846) (xy 198.232236 -261.238848)
			(xy 198.216698 -261.178423) (xy 198.208865 -261.116525) (xy 198.208392 -261.08533) (xy 198.208881 -261.054167)
			(xy 198.216693 -260.992333) (xy 198.232193 -260.931965) (xy 198.255136 -260.874017) (xy 198.285162 -260.8194)
			(xy 198.321796 -260.768978) (xy 198.364461 -260.723544) (xy 198.412483 -260.683816) (xy 198.465107 -260.650421)
			(xy 198.521501 -260.623884) (xy 198.580776 -260.604624) (xy 198.641997 -260.592945) (xy 198.7042 -260.589032)
			(xy 198.766403 -260.592945) (xy 198.827624 -260.604624) (xy 198.886899 -260.623884) (xy 198.943293 -260.650421)
			(xy 198.995917 -260.683816) (xy 199.043939 -260.723544) (xy 199.086604 -260.768978) (xy 199.123238 -260.8194)
			(xy 199.153264 -260.874017) (xy 199.176207 -260.931965) (xy 199.191707 -260.992333) (xy 199.199519 -261.054167)
			(xy 199.200008 -261.08533) (xy 199.199513 -261.116526) (xy 199.1917 -261.178428) (xy 199.176175 -261.238858)
			(xy 199.153185 -261.29686) (xy 199.123094 -261.351516) (xy 199.086377 -261.401961) (xy 199.043617 -261.447396)
			(xy 198.99549 -261.487103) (xy 198.969376 -261.504176) (xy 198.959216 -261.51078) (xy 198.947024 -261.530592)
			(xy 198.937626 -261.634732) (xy 198.946008 -261.656322) (xy 198.954898 -261.664704) (xy 198.973184 -261.682219)
			(xy 199.005264 -261.721395) (xy 199.031683 -261.764592) (xy 199.051943 -261.810997) (xy 199.065665 -261.859737)
			(xy 199.072591 -261.909896) (xy 199.073008 -261.935214) (xy 199.072583 -261.960562) (xy 199.065649 -262.010781)
			(xy 199.0519 -262.059577) (xy 199.031595 -262.106029) (xy 199.005118 -262.149261) (xy 198.972967 -262.188458)
			(xy 198.954644 -262.205978) (xy 198.945754 -262.214106) (xy 198.937372 -262.23595) (xy 198.947024 -262.34009)
			(xy 198.959216 -262.359902) (xy 198.969376 -262.366252) (xy 198.995467 -262.383382) (xy 199.04359 -262.423129)
			(xy 199.086348 -262.468598) (xy 199.123064 -262.519071) (xy 199.15316 -262.573751) (xy 199.176159 -262.631774)
			(xy 199.191699 -262.692223) (xy 199.199534 -262.754145) (xy 199.200008 -262.785352) (xy 199.19953 -262.816549)
			(xy 199.191714 -262.878451) (xy 199.176187 -262.938881) (xy 199.153194 -262.996884) (xy 199.123101 -263.05154)
			(xy 199.086382 -263.101985) (xy 199.04362 -263.147419) (xy 198.995491 -263.187125) (xy 198.969376 -263.204198)
			(xy 198.959216 -263.210802) (xy 198.947024 -263.230614) (xy 198.937626 -263.334754) (xy 198.946008 -263.356344)
			(xy 198.954898 -263.364726) (xy 198.973195 -263.38223) (xy 199.005273 -263.421409) (xy 199.031691 -263.464608)
			(xy 199.05195 -263.511015) (xy 199.06567 -263.559757) (xy 199.072592 -263.609918) (xy 199.073008 -263.635236)
			(xy 199.072598 -263.660584) (xy 199.065661 -263.710804) (xy 199.051909 -263.759601) (xy 199.031602 -263.806052)
			(xy 199.005121 -263.849284) (xy 198.972968 -263.88848) (xy 198.954644 -263.906) (xy 198.945754 -263.914128)
			(xy 198.937372 -263.935972) (xy 198.947024 -264.040112) (xy 198.959216 -264.059924) (xy 198.969376 -264.066274)
			(xy 198.995477 -264.083389) (xy 199.0436 -264.123138) (xy 199.086357 -264.168609) (xy 199.123073 -264.219084)
			(xy 199.153167 -264.273766) (xy 199.176165 -264.331791) (xy 199.191703 -264.392243) (xy 199.199535 -264.454166)
			(xy 199.200008 -264.485374) (xy 199.199547 -264.516571) (xy 199.191729 -264.578474) (xy 199.176199 -264.638905)
			(xy 199.153204 -264.696907) (xy 199.123108 -264.751564) (xy 199.086387 -264.802008) (xy 199.043622 -264.847442)
			(xy 198.995491 -264.887147) (xy 198.969376 -264.90422) (xy 198.959216 -264.910824) (xy 198.947024 -264.930636)
			(xy 198.937626 -265.034776) (xy 198.946008 -265.056366) (xy 198.954898 -265.064748) (xy 198.973157 -265.08229)
			(xy 199.005239 -265.121461) (xy 199.031661 -265.164652) (xy 199.051927 -265.211051) (xy 199.065655 -265.259787)
			(xy 199.072587 -265.309942) (xy 199.073008 -265.335258) (xy 199.072613 -265.360607) (xy 199.065673 -265.410828)
			(xy 199.051918 -265.459624) (xy 199.031608 -265.506076) (xy 199.005125 -265.549307) (xy 198.972969 -265.588502)
			(xy 198.954644 -265.606022) (xy 198.945754 -265.61415) (xy 198.937372 -265.635994) (xy 198.947024 -265.740134)
			(xy 198.959216 -265.759946) (xy 198.969376 -265.766296) (xy 198.995487 -265.783396) (xy 199.04361 -265.823147)
			(xy 199.086367 -265.868621) (xy 199.123082 -265.919098) (xy 199.153175 -265.973782) (xy 199.176171 -266.031809)
			(xy 199.191707 -266.092263) (xy 199.199537 -266.154187) (xy 199.200008 -266.185396) (xy 199.199565 -266.216594)
			(xy 199.191743 -266.278497) (xy 199.176211 -266.338928) (xy 199.153213 -266.396931) (xy 199.123114 -266.451587)
			(xy 199.086391 -266.502031) (xy 199.043625 -266.547465) (xy 198.995492 -266.58717) (xy 198.969376 -266.604242)
			(xy 198.959216 -266.610846) (xy 198.947024 -266.630658) (xy 198.937626 -266.734798) (xy 198.946008 -266.756388)
			(xy 198.954898 -266.76477) (xy 198.973168 -266.782301) (xy 199.005249 -266.821474) (xy 199.03167 -266.864668)
			(xy 199.051933 -266.911069) (xy 199.065659 -266.959807) (xy 199.072588 -267.009963) (xy 199.073008 -267.03528)
			(xy 199.072561 -267.060627) (xy 199.065631 -267.110846) (xy 199.051887 -267.159641) (xy 199.031586 -267.206093)
			(xy 199.005113 -267.249325) (xy 198.972965 -267.288523) (xy 198.954644 -267.306044) (xy 198.945754 -267.314172)
			(xy 198.937372 -267.336016) (xy 198.947024 -267.440156) (xy 198.959216 -267.459968) (xy 198.969376 -267.466318)
			(xy 198.995497 -267.483404) (xy 199.04362 -267.523157) (xy 199.086376 -267.568632) (xy 199.12309 -267.619112)
			(xy 199.153182 -267.673798) (xy 199.176177 -267.731827) (xy 199.19171 -267.792282) (xy 199.199538 -267.854209)
			(xy 199.200008 -267.885418) (xy 199.199582 -267.916616) (xy 199.191758 -267.97852) (xy 199.176222 -268.038952)
			(xy 199.153222 -268.096955) (xy 199.123121 -268.151611) (xy 199.086396 -268.202055) (xy 199.043628 -268.247488)
			(xy 198.995493 -268.287192) (xy 198.969376 -268.304264) (xy 198.959216 -268.310868) (xy 198.947024 -268.33068)
			(xy 198.937626 -268.43482) (xy 198.946008 -268.45641) (xy 198.954898 -268.464792) (xy 198.973178 -268.482313)
			(xy 199.005259 -268.521488) (xy 199.031678 -268.564683) (xy 199.05194 -268.611087) (xy 199.065663 -268.659826)
			(xy 199.07259 -268.709985) (xy 199.073008 -268.735302) (xy 199.072575 -268.76065) (xy 199.065643 -268.810869)
			(xy 199.051895 -268.859664) (xy 199.031592 -268.906116) (xy 199.005116 -268.949348) (xy 198.972966 -268.988545)
			(xy 198.954644 -269.006066) (xy 198.945754 -269.014194) (xy 198.937372 -269.036038) (xy 198.947024 -269.140178)
			(xy 198.959216 -269.15999) (xy 198.969376 -269.16634) (xy 198.995462 -269.183478) (xy 199.043585 -269.223223)
			(xy 199.086342 -269.268691) (xy 199.123059 -269.319163) (xy 199.153156 -269.373842) (xy 199.176156 -269.431864)
			(xy 199.191697 -269.492312) (xy 199.199533 -269.554233) (xy 199.200008 -269.58544) (xy 199.199479 -269.61814)
			(xy 199.190872 -269.682973) (xy 199.173812 -269.746109) (xy 199.148597 -269.806454) (xy 199.115663 -269.862958)
			(xy 199.075584 -269.914639) (xy 199.052688 -269.937992) (xy 199.045322 -269.945358) (xy 199.037702 -269.9639)
			(xy 199.037702 -270.056864) (xy 199.045322 -270.075406) (xy 199.052688 -270.082772) (xy 199.075598 -270.106113)
			(xy 199.11568 -270.157794) (xy 199.148614 -270.2143) (xy 199.173828 -270.274647) (xy 199.190884 -270.337787)
			(xy 199.199485 -270.402622) (xy 199.200008 -270.435324) (xy 199.199587 -270.466522) (xy 199.191761 -270.528427)
			(xy 199.176226 -270.588859) (xy 199.153225 -270.646861) (xy 199.123123 -270.701517) (xy 199.086397 -270.751961)
			(xy 199.043628 -270.797394) (xy 198.995493 -270.837098) (xy 198.969376 -270.85417) (xy 198.959216 -270.860774)
			(xy 198.947024 -270.880586) (xy 198.937626 -270.984726) (xy 198.946008 -271.006316) (xy 198.954898 -271.014698)
			(xy 198.973181 -271.032216) (xy 199.005261 -271.071392) (xy 199.03168 -271.114588) (xy 199.051942 -271.160992)
			(xy 199.065664 -271.209732) (xy 199.07259 -271.259891) (xy 199.073008 -271.285208) (xy 199.072579 -271.310556)
			(xy 199.065646 -271.360775) (xy 199.051898 -271.409571) (xy 199.031594 -271.456023) (xy 199.005117 -271.499255)
			(xy 198.972967 -271.538452) (xy 198.954644 -271.555972) (xy 198.945754 -271.5641) (xy 198.937372 -271.585944)
			(xy 198.947024 -271.690084) (xy 198.959216 -271.709896) (xy 198.969376 -271.716246) (xy 198.995464 -271.73338)
			(xy 199.043587 -271.773126) (xy 199.086345 -271.818594) (xy 199.123062 -271.869067) (xy 199.153158 -271.923746)
			(xy 199.176158 -271.981769) (xy 199.191698 -272.042218) (xy 199.199534 -272.104139) (xy 199.200008 -272.135346)
			(xy 199.199525 -272.166543) (xy 199.19171 -272.228444) (xy 199.176184 -272.288875) (xy 199.153192 -272.346877)
			(xy 199.123099 -272.401533) (xy 199.086381 -272.451978) (xy 199.043619 -272.497413) (xy 198.99549 -272.537119)
			(xy 198.969376 -272.554192) (xy 198.959216 -272.560796) (xy 198.947024 -272.580608) (xy 198.937626 -272.684748)
			(xy 198.946008 -272.706338) (xy 198.954898 -272.71472) (xy 198.973192 -272.732227) (xy 199.005271 -272.771405)
			(xy 199.031689 -272.814604) (xy 199.051948 -272.86101) (xy 199.065668 -272.909752) (xy 199.072592 -272.959912)
			(xy 199.073008 -272.98523) (xy 199.072594 -273.010578) (xy 199.065658 -273.060798) (xy 199.051907 -273.109594)
			(xy 199.0316 -273.156046) (xy 199.00512 -273.199278) (xy 198.972968 -273.238474) (xy 198.954644 -273.255994)
			(xy 198.945754 -273.264122) (xy 198.937372 -273.285966) (xy 198.947024 -273.390106) (xy 198.959216 -273.409918)
			(xy 198.969376 -273.416268) (xy 198.995474 -273.433387) (xy 199.043597 -273.473135) (xy 199.086355 -273.518606)
			(xy 199.123071 -273.569081) (xy 199.153165 -273.623762) (xy 199.176164 -273.681787) (xy 199.191702 -273.742238)
			(xy 199.199535 -273.80416) (xy 199.200008 -273.835368) (xy 199.199519 -273.866531) (xy 199.191707 -273.928365)
			(xy 199.176207 -273.988733) (xy 199.153264 -274.046681) (xy 199.123238 -274.101298) (xy 199.086604 -274.15172)
			(xy 199.043939 -274.197154) (xy 198.995917 -274.236882) (xy 198.943293 -274.270277) (xy 198.886899 -274.296814)
			(xy 198.827624 -274.316074) (xy 198.766403 -274.327753) (xy 198.7042 -274.331666) (xy 198.641997 -274.327753)
			(xy 198.580776 -274.316074) (xy 198.521501 -274.296814) (xy 198.465107 -274.270277) (xy 198.412483 -274.236882)
			(xy 198.364461 -274.197154) (xy 198.321796 -274.15172) (xy 198.285162 -274.101298) (xy 198.255136 -274.046681)
			(xy 198.232193 -273.988733) (xy 198.216693 -273.928365) (xy 198.208881 -273.866531) (xy 198.208392 -273.835368)
			(xy 194.97294 -273.835368) (xy 194.972529 -273.860686) (xy 194.965605 -273.910846) (xy 194.951883 -273.959587)
			(xy 194.931621 -274.005992) (xy 194.905199 -274.049188) (xy 194.873116 -274.088362) (xy 194.85483 -274.105878)
			(xy 194.84594 -274.11426) (xy 194.837558 -274.13585) (xy 194.846956 -274.23999) (xy 194.859148 -274.259802)
			(xy 194.869308 -274.266406) (xy 194.895418 -274.283483) (xy 194.943535 -274.3232) (xy 194.986287 -274.36864)
			(xy 195.023001 -274.419085) (xy 195.053094 -274.473738) (xy 195.076092 -274.531735) (xy 195.091632 -274.59216)
			(xy 195.099466 -274.654057) (xy 195.09994 -274.685252) (xy 196.950599 -274.685252) (xy 196.954534 -274.631481)
			(xy 196.966257 -274.578857) (xy 196.985517 -274.5285) (xy 197.011903 -274.481483) (xy 197.044855 -274.43881)
			(xy 197.083668 -274.401389) (xy 197.127516 -274.370019) (xy 197.175464 -274.345367) (xy 197.226491 -274.327959)
			(xy 197.279509 -274.318166) (xy 197.333388 -274.316197) (xy 197.386979 -274.322094) (xy 197.43914 -274.33573)
			(xy 197.48876 -274.356817) (xy 197.534781 -274.384903) (xy 197.576223 -274.419391) (xy 197.612201 -274.459545)
			(xy 197.641949 -274.504509) (xy 197.664834 -274.553326) (xy 197.680366 -274.604955) (xy 197.688216 -274.658295)
			(xy 197.688708 -274.685252) (xy 201.652124 -274.685252) (xy 201.65259 -274.654055) (xy 201.660406 -274.592152)
			(xy 201.675934 -274.53172) (xy 201.698928 -274.473717) (xy 201.729023 -274.419061) (xy 201.765744 -274.368616)
			(xy 201.808509 -274.323182) (xy 201.85664 -274.283478) (xy 201.882756 -274.266406) (xy 201.892916 -274.259802)
			(xy 201.905108 -274.23999) (xy 201.914506 -274.13585) (xy 201.906124 -274.11426) (xy 201.897234 -274.105878)
			(xy 201.878926 -274.088385) (xy 201.846851 -274.049202) (xy 201.820437 -274.006) (xy 201.80018 -273.959592)
			(xy 201.786462 -273.910848) (xy 201.77954 -273.860687) (xy 201.779124 -273.835368) (xy 201.779527 -273.810019)
			(xy 201.786464 -273.759798) (xy 201.800216 -273.711002) (xy 201.820525 -273.66455) (xy 201.847007 -273.621318)
			(xy 201.879163 -273.582123) (xy 201.897488 -273.564604) (xy 201.906378 -273.556476) (xy 201.91476 -273.534632)
			(xy 201.905108 -273.430492) (xy 201.892916 -273.41068) (xy 201.882756 -273.40433) (xy 201.856641 -273.387236)
			(xy 201.808521 -273.347482) (xy 201.765767 -273.302006) (xy 201.729053 -273.251527) (xy 201.698961 -273.196843)
			(xy 201.675965 -273.138816) (xy 201.660428 -273.078363) (xy 201.652596 -273.016439) (xy 201.652124 -272.98523)
			(xy 201.652573 -272.954032) (xy 201.660392 -272.892128) (xy 201.675922 -272.831697) (xy 201.698919 -272.773693)
			(xy 201.729016 -272.719037) (xy 201.765739 -272.668593) (xy 201.808506 -272.623159) (xy 201.856639 -272.583456)
			(xy 201.882756 -272.566384) (xy 201.892916 -272.55978) (xy 201.905108 -272.539968) (xy 201.914506 -272.435828)
			(xy 201.906124 -272.414238) (xy 201.897234 -272.405856) (xy 201.878964 -272.388325) (xy 201.846885 -272.349151)
			(xy 201.820466 -272.305957) (xy 201.800203 -272.259555) (xy 201.786477 -272.210819) (xy 201.779545 -272.160662)
			(xy 201.779124 -272.135346) (xy 201.779512 -272.109997) (xy 201.786452 -272.059775) (xy 201.800208 -272.010978)
			(xy 201.820519 -271.964526) (xy 201.847004 -271.921295) (xy 201.879162 -271.882101) (xy 201.897488 -271.864582)
			(xy 201.906378 -271.856454) (xy 201.91476 -271.83461) (xy 201.905108 -271.73047) (xy 201.892916 -271.710658)
			(xy 201.882756 -271.704308) (xy 201.856631 -271.687229) (xy 201.808511 -271.647472) (xy 201.765757 -271.601995)
			(xy 201.729045 -271.551514) (xy 201.698954 -271.496827) (xy 201.675959 -271.438798) (xy 201.660425 -271.378343)
			(xy 201.652595 -271.316417) (xy 201.652124 -271.285208) (xy 201.652639 -271.252507) (xy 201.661252 -271.187675)
			(xy 201.678316 -271.124539) (xy 201.703534 -271.064195) (xy 201.736469 -271.007692) (xy 201.776548 -270.95601)
			(xy 201.799444 -270.932656) (xy 201.80681 -270.92529) (xy 201.81443 -270.906748) (xy 201.81443 -270.813784)
			(xy 201.80681 -270.795242) (xy 201.799444 -270.787876) (xy 201.776563 -270.764508) (xy 201.736477 -270.712833)
			(xy 201.703538 -270.656333) (xy 201.678319 -270.595991) (xy 201.661257 -270.532855) (xy 201.65265 -270.468024)
			(xy 201.652124 -270.435324) (xy 201.652568 -270.404126) (xy 201.660388 -270.342222) (xy 201.675919 -270.28179)
			(xy 201.698916 -270.223787) (xy 201.729014 -270.169131) (xy 201.765738 -270.118686) (xy 201.808505 -270.073253)
			(xy 201.856639 -270.03355) (xy 201.882756 -270.016478) (xy 201.892916 -270.009874) (xy 201.905108 -269.990062)
			(xy 201.914506 -269.885922) (xy 201.906124 -269.864332) (xy 201.897234 -269.85595) (xy 201.878961 -269.838422)
			(xy 201.846883 -269.799247) (xy 201.820464 -269.756052) (xy 201.800201 -269.70965) (xy 201.786476 -269.660913)
			(xy 201.779545 -269.610757) (xy 201.779124 -269.58544) (xy 201.779508 -269.560091) (xy 201.786449 -269.509869)
			(xy 201.800205 -269.461072) (xy 201.820518 -269.41462) (xy 201.847003 -269.371389) (xy 201.879161 -269.332195)
			(xy 201.897488 -269.314676) (xy 201.906378 -269.306548) (xy 201.91476 -269.284704) (xy 201.905108 -269.180564)
			(xy 201.892916 -269.160752) (xy 201.882756 -269.154402) (xy 201.856628 -269.137327) (xy 201.808508 -269.09757)
			(xy 201.765754 -269.052091) (xy 201.729042 -269.00161) (xy 201.698952 -268.946923) (xy 201.675958 -268.888893)
			(xy 201.660424 -268.828438) (xy 201.652595 -268.766512) (xy 201.652124 -268.735302) (xy 201.652551 -268.704103)
			(xy 201.660373 -268.642199) (xy 201.675907 -268.581767) (xy 201.698907 -268.523763) (xy 201.729007 -268.469107)
			(xy 201.765733 -268.418663) (xy 201.808503 -268.37323) (xy 201.856638 -268.333527) (xy 201.882756 -268.316456)
			(xy 201.892916 -268.309852) (xy 201.905108 -268.29004) (xy 201.914506 -268.1859) (xy 201.906124 -268.16431)
			(xy 201.897234 -268.155928) (xy 201.878951 -268.138411) (xy 201.846873 -268.099233) (xy 201.820456 -268.056037)
			(xy 201.800195 -268.009632) (xy 201.786472 -267.960893) (xy 201.779543 -267.910735) (xy 201.779124 -267.885418)
			(xy 201.77956 -267.86007) (xy 201.78649 -267.809851) (xy 201.800236 -267.761055) (xy 201.820539 -267.714603)
			(xy 201.847015 -267.671371) (xy 201.879165 -267.632174) (xy 201.897488 -267.614654) (xy 201.906378 -267.606526)
			(xy 201.91476 -267.584682) (xy 201.905108 -267.480542) (xy 201.892916 -267.46073) (xy 201.882756 -267.45438)
			(xy 201.856618 -267.437319) (xy 201.808498 -267.39756) (xy 201.765745 -267.35208) (xy 201.729034 -267.301596)
			(xy 201.698944 -267.246907) (xy 201.675952 -267.188875) (xy 201.66042 -267.128418) (xy 201.652593 -267.06649)
			(xy 201.652124 -267.03528) (xy 201.652534 -267.004081) (xy 201.660359 -266.942176) (xy 201.675895 -266.881743)
			(xy 201.698897 -266.823739) (xy 201.729001 -266.769083) (xy 201.765728 -266.71864) (xy 201.8085 -266.673207)
			(xy 201.856637 -266.633505) (xy 201.882756 -266.616434) (xy 201.892916 -266.60983) (xy 201.905108 -266.590018)
			(xy 201.914506 -266.485878) (xy 201.906124 -266.464288) (xy 201.897234 -266.455906) (xy 201.87894 -266.438399)
			(xy 201.846863 -266.39922) (xy 201.820447 -266.356021) (xy 201.800189 -266.309615) (xy 201.786467 -266.260873)
			(xy 201.779542 -266.210714) (xy 201.779124 -266.185396) (xy 201.779545 -266.160048) (xy 201.786479 -266.109828)
			(xy 201.800228 -266.061032) (xy 201.820533 -266.014579) (xy 201.847012 -265.971348) (xy 201.879164 -265.932152)
			(xy 201.897488 -265.914632) (xy 201.906378 -265.906504) (xy 201.91476 -265.88466) (xy 201.905108 -265.78052)
			(xy 201.892916 -265.760708) (xy 201.882756 -265.754358) (xy 201.856654 -265.737245) (xy 201.808534 -265.697494)
			(xy 201.765779 -265.652021) (xy 201.729065 -265.601545) (xy 201.698971 -265.546863) (xy 201.675973 -265.488839)
			(xy 201.660433 -265.428388) (xy 201.652598 -265.366466) (xy 201.652124 -265.335258) (xy 201.652595 -265.304061)
			(xy 201.66041 -265.242158) (xy 201.675937 -265.181727) (xy 201.69893 -265.123724) (xy 201.729025 -265.069067)
			(xy 201.765745 -265.018623) (xy 201.808509 -264.973188) (xy 201.85664 -264.933484) (xy 201.882756 -264.916412)
			(xy 201.892916 -264.909808) (xy 201.905108 -264.889996) (xy 201.914506 -264.785856) (xy 201.906124 -264.764266)
			(xy 201.897234 -264.755884) (xy 201.878929 -264.738388) (xy 201.846854 -264.699206) (xy 201.820439 -264.656005)
			(xy 201.800182 -264.609597) (xy 201.786463 -264.560854) (xy 201.779541 -264.510692) (xy 201.779124 -264.485374)
			(xy 201.779531 -264.460025) (xy 201.786467 -264.409805) (xy 201.800219 -264.361008) (xy 201.820527 -264.314556)
			(xy 201.847008 -264.271325) (xy 201.879163 -264.232129) (xy 201.897488 -264.21461) (xy 201.906378 -264.206482)
			(xy 201.91476 -264.184638) (xy 201.905108 -264.080498) (xy 201.892916 -264.060686) (xy 201.882756 -264.054336)
			(xy 201.856644 -264.037238) (xy 201.808524 -263.997484) (xy 201.765769 -263.952009) (xy 201.729056 -263.901531)
			(xy 201.698963 -263.846847) (xy 201.675967 -263.788821) (xy 201.660429 -263.728368) (xy 201.652597 -263.666445)
			(xy 201.652124 -263.635236) (xy 201.652578 -263.604038) (xy 201.660396 -263.542135) (xy 201.675926 -263.481703)
			(xy 201.698921 -263.4237) (xy 201.729018 -263.369044) (xy 201.765741 -263.318599) (xy 201.808507 -263.273166)
			(xy 201.85664 -263.233462) (xy 201.882756 -263.21639) (xy 201.892916 -263.209786) (xy 201.905108 -263.189974)
			(xy 201.914506 -263.085834) (xy 201.906124 -263.064244) (xy 201.897234 -263.055862) (xy 201.878967 -263.038328)
			(xy 201.846888 -262.999154) (xy 201.820469 -262.955961) (xy 201.800205 -262.90956) (xy 201.786478 -262.860824)
			(xy 201.779546 -262.810668) (xy 201.779124 -262.785352) (xy 201.779516 -262.760003) (xy 201.786455 -262.709782)
			(xy 201.80021 -262.660985) (xy 201.820521 -262.614533) (xy 201.847005 -262.571302) (xy 201.879162 -262.532107)
			(xy 201.897488 -262.514588) (xy 201.906378 -262.50646) (xy 201.91476 -262.484616) (xy 201.905108 -262.380476)
			(xy 201.892916 -262.360664) (xy 201.882756 -262.354314) (xy 201.856634 -262.337231) (xy 201.808514 -262.297475)
			(xy 201.76576 -262.251998) (xy 201.729047 -262.201518) (xy 201.698956 -262.146831) (xy 201.675961 -262.088803)
			(xy 201.660426 -262.028349) (xy 201.652595 -261.966423) (xy 201.652124 -261.935214) (xy 201.652613 -261.904051)
			(xy 201.660425 -261.842217) (xy 201.675925 -261.781849) (xy 201.698868 -261.723901) (xy 201.728894 -261.669284)
			(xy 201.765528 -261.618862) (xy 201.808193 -261.573428) (xy 201.856215 -261.5337) (xy 201.908839 -261.500305)
			(xy 201.965233 -261.473768) (xy 202.024508 -261.454508) (xy 202.085729 -261.442829) (xy 202.147932 -261.438916)
			(xy 202.210135 -261.442829) (xy 202.271356 -261.454508) (xy 202.330631 -261.473768) (xy 202.387025 -261.500305)
			(xy 202.439649 -261.5337) (xy 202.487671 -261.573428) (xy 202.530336 -261.618862) (xy 202.56697 -261.669284)
			(xy 202.596996 -261.723901) (xy 202.619939 -261.781849) (xy 202.635439 -261.842217) (xy 202.643251 -261.904051)
			(xy 202.64374 -261.935214) (xy 202.643232 -261.966422) (xy 202.635412 -262.028347) (xy 202.619885 -262.088801)
			(xy 202.596895 -262.146829) (xy 202.566807 -262.201514) (xy 202.530096 -262.251992) (xy 202.487342 -262.297466)
			(xy 202.43922 -262.337216) (xy 202.413108 -262.354314) (xy 202.402948 -262.360664) (xy 202.390756 -262.380476)
			(xy 202.381104 -262.484616) (xy 202.389486 -262.50646) (xy 202.398376 -262.514588) (xy 202.416685 -262.532121)
			(xy 202.44883 -262.57132) (xy 202.475305 -262.614551) (xy 202.495613 -262.660999) (xy 202.509369 -262.70979)
			(xy 202.516317 -262.760005) (xy 202.51674 -262.785352) (xy 202.516319 -262.81067) (xy 202.509397 -262.860829)
			(xy 202.495677 -262.90957) (xy 202.475416 -262.955975) (xy 202.448997 -262.999171) (xy 202.416915 -263.038346)
			(xy 202.39863 -263.055862) (xy 202.38974 -263.064244) (xy 202.381358 -263.085834) (xy 202.390756 -263.189974)
			(xy 202.402948 -263.209786) (xy 202.413108 -263.21639) (xy 202.439211 -263.233478) (xy 202.487327 -263.273193)
			(xy 202.53008 -263.318631) (xy 202.566794 -263.369075) (xy 202.596889 -263.423727) (xy 202.619888 -263.481722)
			(xy 202.635429 -263.542146) (xy 202.643265 -263.604041) (xy 202.64374 -263.635236) (xy 202.643249 -263.666445)
			(xy 202.635427 -263.72837) (xy 202.619897 -263.788824) (xy 202.596905 -263.846852) (xy 202.566814 -263.901538)
			(xy 202.530101 -263.952016) (xy 202.487344 -263.997489) (xy 202.439221 -264.037239) (xy 202.413108 -264.054336)
			(xy 202.402948 -264.060686) (xy 202.390756 -264.080498) (xy 202.381104 -264.184638) (xy 202.389486 -264.206482)
			(xy 202.398376 -264.21461) (xy 202.416696 -264.232133) (xy 202.44884 -264.271334) (xy 202.475314 -264.314566)
			(xy 202.495619 -264.361017) (xy 202.509374 -264.40981) (xy 202.516318 -264.460027) (xy 202.51674 -264.485374)
			(xy 202.516333 -264.510692) (xy 202.509408 -264.560852) (xy 202.495685 -264.609593) (xy 202.475422 -264.655998)
			(xy 202.449 -264.699194) (xy 202.416916 -264.738369) (xy 202.39863 -264.755884) (xy 202.38974 -264.764266)
			(xy 202.381358 -264.785856) (xy 202.390756 -264.889996) (xy 202.402948 -264.909808) (xy 202.413108 -264.916412)
			(xy 202.439221 -264.933485) (xy 202.487337 -264.973202) (xy 202.53009 -265.018643) (xy 202.566803 -265.069089)
			(xy 202.596896 -265.123742) (xy 202.619894 -265.18174) (xy 202.635433 -265.242165) (xy 202.643266 -265.304063)
			(xy 202.64374 -265.335258) (xy 202.643267 -265.366467) (xy 202.635441 -265.428393) (xy 202.619908 -265.488848)
			(xy 202.596914 -265.546876) (xy 202.566821 -265.601561) (xy 202.530106 -265.652039) (xy 202.487347 -265.697512)
			(xy 202.439222 -265.737261) (xy 202.413108 -265.754358) (xy 202.402948 -265.760708) (xy 202.390756 -265.78052)
			(xy 202.381104 -265.88466) (xy 202.389486 -265.906504) (xy 202.398376 -265.914632) (xy 202.416707 -265.932144)
			(xy 202.448849 -265.971347) (xy 202.475322 -266.014582) (xy 202.495626 -266.061035) (xy 202.509378 -266.10983)
			(xy 202.51632 -266.160048) (xy 202.51674 -266.185396) (xy 202.516348 -266.210715) (xy 202.50942 -266.260875)
			(xy 202.495694 -266.309617) (xy 202.475428 -266.356022) (xy 202.449004 -266.399217) (xy 202.416917 -266.438391)
			(xy 202.39863 -266.455906) (xy 202.38974 -266.464288) (xy 202.381358 -266.485878) (xy 202.390756 -266.590018)
			(xy 202.402948 -266.60983) (xy 202.413108 -266.616434) (xy 202.439231 -266.633493) (xy 202.487347 -266.673212)
			(xy 202.5301 -266.718654) (xy 202.566812 -266.769102) (xy 202.596904 -266.823758) (xy 202.6199 -266.881758)
			(xy 202.635436 -266.942185) (xy 202.643268 -267.004084) (xy 202.64374 -267.03528) (xy 202.643284 -267.06649)
			(xy 202.635456 -267.128416) (xy 202.61992 -267.188871) (xy 202.596923 -267.2469) (xy 202.566828 -267.301585)
			(xy 202.53011 -267.352063) (xy 202.48735 -267.397535) (xy 202.439223 -267.437283) (xy 202.413108 -267.45438)
			(xy 202.402948 -267.46073) (xy 202.390756 -267.480542) (xy 202.381104 -267.584682) (xy 202.389486 -267.606526)
			(xy 202.398376 -267.614654) (xy 202.416717 -267.632155) (xy 202.448859 -267.671361) (xy 202.47533 -267.714598)
			(xy 202.495632 -267.761053) (xy 202.509382 -267.80985) (xy 202.516321 -267.860069) (xy 202.51674 -267.885418)
			(xy 202.516363 -267.910737) (xy 202.509432 -267.960899) (xy 202.495703 -268.00964) (xy 202.475435 -268.056045)
			(xy 202.449008 -268.09924) (xy 202.416919 -268.138414) (xy 202.39863 -268.155928) (xy 202.38974 -268.16431)
			(xy 202.381358 -268.1859) (xy 202.390756 -268.29004) (xy 202.402948 -268.309852) (xy 202.413108 -268.316456)
			(xy 202.439241 -268.3335) (xy 202.487357 -268.373221) (xy 202.530109 -268.418666) (xy 202.566821 -268.469116)
			(xy 202.596911 -268.523774) (xy 202.619906 -268.581776) (xy 202.63544 -268.642205) (xy 202.643269 -268.704105)
			(xy 202.64374 -268.735302) (xy 202.643223 -268.76651) (xy 202.635404 -268.828434) (xy 202.619878 -268.888888)
			(xy 202.59689 -268.946916) (xy 202.566803 -269.001601) (xy 202.530093 -269.05208) (xy 202.48734 -269.097554)
			(xy 202.43922 -269.137304) (xy 202.413108 -269.154402) (xy 202.402948 -269.160752) (xy 202.390756 -269.180564)
			(xy 202.381104 -269.284704) (xy 202.389486 -269.306548) (xy 202.398376 -269.314676) (xy 202.416679 -269.332215)
			(xy 202.448825 -269.371413) (xy 202.475301 -269.414642) (xy 202.495609 -269.461089) (xy 202.509367 -269.509879)
			(xy 202.516316 -269.560094) (xy 202.51674 -269.58544) (xy 202.516311 -269.610757) (xy 202.50939 -269.660917)
			(xy 202.495672 -269.709657) (xy 202.475413 -269.756062) (xy 202.448995 -269.799259) (xy 202.416915 -269.838434)
			(xy 202.39863 -269.85595) (xy 202.38974 -269.864332) (xy 202.381358 -269.885922) (xy 202.390756 -269.990062)
			(xy 202.402948 -270.009874) (xy 202.413108 -270.016478) (xy 202.439205 -270.033574) (xy 202.487322 -270.073288)
			(xy 202.530075 -270.118725) (xy 202.56679 -270.169167) (xy 202.596885 -270.223818) (xy 202.619885 -270.281813)
			(xy 202.635427 -270.342235) (xy 202.643264 -270.40413) (xy 202.64374 -270.435324) (xy 202.643192 -270.468024)
			(xy 202.634587 -270.532855) (xy 202.617531 -270.595991) (xy 202.592319 -270.656335) (xy 202.559389 -270.712839)
			(xy 202.519314 -270.764522) (xy 202.49642 -270.787876) (xy 202.489054 -270.795242) (xy 202.481434 -270.813784)
			(xy 202.481434 -270.906748) (xy 202.489054 -270.92529) (xy 202.49642 -270.932656) (xy 202.51931 -270.956016)
			(xy 202.559396 -271.007692) (xy 202.592334 -271.064193) (xy 202.617553 -271.124537) (xy 202.634612 -271.187674)
			(xy 202.643216 -271.252507) (xy 202.64374 -271.285208) (xy 202.643228 -271.316416) (xy 202.635408 -271.37834)
			(xy 202.619881 -271.438794) (xy 202.596893 -271.496822) (xy 202.566805 -271.551508) (xy 202.530095 -271.601986)
			(xy 202.487341 -271.64746) (xy 202.43922 -271.68721) (xy 202.413108 -271.704308) (xy 202.402948 -271.710658)
			(xy 202.390756 -271.73047) (xy 202.381104 -271.83461) (xy 202.389486 -271.856454) (xy 202.398376 -271.864582)
			(xy 202.416682 -271.882118) (xy 202.448827 -271.921316) (xy 202.475303 -271.964546) (xy 202.495611 -272.010994)
			(xy 202.509368 -272.059785) (xy 202.516316 -272.109999) (xy 202.51674 -272.135346) (xy 202.516315 -272.160663)
			(xy 202.509394 -272.210823) (xy 202.495674 -272.259564) (xy 202.475415 -272.305969) (xy 202.448996 -272.349165)
			(xy 202.416915 -272.38834) (xy 202.39863 -272.405856) (xy 202.38974 -272.414238) (xy 202.381358 -272.435828)
			(xy 202.390756 -272.539968) (xy 202.402948 -272.55978) (xy 202.413108 -272.566384) (xy 202.439208 -272.583476)
			(xy 202.487325 -272.62319) (xy 202.530078 -272.668628) (xy 202.566792 -272.719071) (xy 202.596887 -272.773722)
			(xy 202.619887 -272.831717) (xy 202.635428 -272.89214) (xy 202.643265 -272.954035) (xy 202.64374 -272.98523)
			(xy 202.643245 -273.016439) (xy 202.635423 -273.078363) (xy 202.619893 -273.138818) (xy 202.596902 -273.196846)
			(xy 202.566812 -273.251531) (xy 202.530099 -273.302009) (xy 202.487344 -273.347483) (xy 202.439221 -273.387233)
			(xy 202.413108 -273.40433) (xy 202.402948 -273.41068) (xy 202.390756 -273.430492) (xy 202.381104 -273.534632)
			(xy 202.389486 -273.556476) (xy 202.398376 -273.564604) (xy 202.416693 -273.58213) (xy 202.448837 -273.62133)
			(xy 202.475311 -273.664562) (xy 202.495617 -273.711012) (xy 202.509372 -273.759805) (xy 202.516318 -273.810021)
			(xy 202.51674 -273.835368) (xy 205.752192 -273.835368) (xy 205.752671 -273.804159) (xy 205.760494 -273.742233)
			(xy 205.776024 -273.681777) (xy 205.799018 -273.623748) (xy 205.82911 -273.569063) (xy 205.865825 -273.518585)
			(xy 205.908584 -273.473113) (xy 205.95671 -273.433364) (xy 205.982824 -273.416268) (xy 205.992984 -273.409918)
			(xy 206.005176 -273.390106) (xy 206.014828 -273.285966) (xy 206.006446 -273.264122) (xy 205.997556 -273.255994)
			(xy 205.979244 -273.238463) (xy 205.947098 -273.199265) (xy 205.920622 -273.156034) (xy 205.900315 -273.109585)
			(xy 205.88656 -273.060793) (xy 205.879614 -273.010577) (xy 205.879192 -272.98523) (xy 205.879623 -272.959913)
			(xy 205.886545 -272.909755) (xy 205.900265 -272.861015) (xy 205.920524 -272.81461) (xy 205.946941 -272.771413)
			(xy 205.979019 -272.732237) (xy 205.997302 -272.71472) (xy 206.006192 -272.706338) (xy 206.014574 -272.684748)
			(xy 206.005176 -272.580608) (xy 205.992984 -272.560796) (xy 205.982824 -272.554192) (xy 205.95672 -272.537105)
			(xy 205.908602 -272.497391) (xy 205.865848 -272.451953) (xy 205.829134 -272.40151) (xy 205.799039 -272.346858)
			(xy 205.77604 -272.288861) (xy 205.760501 -272.228437) (xy 205.752666 -272.166541) (xy 205.752192 -272.135346)
			(xy 205.752654 -272.104136) (xy 205.760479 -272.042209) (xy 205.776013 -271.981754) (xy 205.799008 -271.923725)
			(xy 205.829103 -271.869039) (xy 205.86582 -271.818562) (xy 205.908581 -271.77309) (xy 205.956709 -271.733342)
			(xy 205.982824 -271.716246) (xy 205.992984 -271.709896) (xy 206.005176 -271.690084) (xy 206.014828 -271.585944)
			(xy 206.006446 -271.5641) (xy 205.997556 -271.555972) (xy 205.979233 -271.538452) (xy 205.947089 -271.499251)
			(xy 205.920614 -271.456018) (xy 205.900309 -271.409567) (xy 205.886556 -271.360773) (xy 205.879613 -271.310556)
			(xy 205.879192 -271.285208) (xy 205.879608 -271.25989) (xy 205.886534 -271.209731) (xy 205.900257 -271.160991)
			(xy 205.920518 -271.114587) (xy 205.946937 -271.07139) (xy 205.979017 -271.032214) (xy 205.997302 -271.014698)
			(xy 206.006192 -271.006316) (xy 206.014574 -270.984726) (xy 206.005176 -270.880586) (xy 205.992984 -270.860774)
			(xy 205.982824 -270.85417) (xy 205.95671 -270.837098) (xy 205.908592 -270.797382) (xy 205.865839 -270.751942)
			(xy 205.829125 -270.701496) (xy 205.799032 -270.646842) (xy 205.776034 -270.588843) (xy 205.760497 -270.528418)
			(xy 205.752665 -270.46652) (xy 205.752192 -270.435324) (xy 205.752697 -270.402623) (xy 205.761309 -270.33779)
			(xy 205.778374 -270.274652) (xy 205.803594 -270.214308) (xy 205.836531 -270.157805) (xy 205.876614 -270.106125)
			(xy 205.899512 -270.082772) (xy 205.906878 -270.075406) (xy 205.914498 -270.056864) (xy 205.914498 -269.9639)
			(xy 205.906878 -269.945358) (xy 205.899512 -269.937992) (xy 205.876585 -269.914668) (xy 205.836505 -269.862982)
			(xy 205.803573 -269.806473) (xy 205.778362 -269.746123) (xy 205.76131 -269.68298) (xy 205.752713 -269.618142)
			(xy 205.752192 -269.58544) (xy 205.752649 -269.55423) (xy 205.760475 -269.492303) (xy 205.776009 -269.431847)
			(xy 205.799006 -269.373818) (xy 205.829101 -269.319133) (xy 205.865819 -269.268655) (xy 205.90858 -269.223183)
			(xy 205.956709 -269.183436) (xy 205.982824 -269.16634) (xy 205.992984 -269.15999) (xy 206.005176 -269.140178)
			(xy 206.014828 -269.036038) (xy 206.006446 -269.014194) (xy 205.997556 -269.006066) (xy 205.979231 -268.988549)
			(xy 205.947086 -268.949347) (xy 205.920612 -268.906114) (xy 205.900307 -268.859662) (xy 205.886554 -268.810868)
			(xy 205.879612 -268.76065) (xy 205.879192 -268.735302) (xy 205.879604 -268.709984) (xy 205.886531 -268.659825)
			(xy 205.900254 -268.611085) (xy 205.920516 -268.564681) (xy 205.946936 -268.521484) (xy 205.979017 -268.482308)
			(xy 205.997302 -268.464792) (xy 206.006192 -268.45641) (xy 206.014574 -268.43482) (xy 206.005176 -268.33068)
			(xy 205.992984 -268.310868) (xy 205.982824 -268.304264) (xy 205.956708 -268.287196) (xy 205.90859 -268.247479)
			(xy 205.865836 -268.202039) (xy 205.829123 -268.151592) (xy 205.799029 -268.096937) (xy 205.776033 -268.038938)
			(xy 205.760496 -267.978512) (xy 205.752664 -267.916614) (xy 205.752192 -267.885418) (xy 205.752632 -267.854208)
			(xy 205.760461 -267.79228) (xy 205.775998 -267.731824) (xy 205.798996 -267.673794) (xy 205.829094 -267.619109)
			(xy 205.865814 -267.568632) (xy 205.908578 -267.52316) (xy 205.956708 -267.483413) (xy 205.982824 -267.466318)
			(xy 205.992984 -267.459968) (xy 206.005176 -267.440156) (xy 206.014828 -267.336016) (xy 206.006446 -267.314172)
			(xy 205.997556 -267.306044) (xy 205.97922 -267.288537) (xy 205.947076 -267.249334) (xy 205.920604 -267.206098)
			(xy 205.900301 -267.159644) (xy 205.88655 -267.110848) (xy 205.879611 -267.060628) (xy 205.879192 -267.03528)
			(xy 205.879589 -267.009962) (xy 205.886519 -266.959802) (xy 205.900245 -266.911062) (xy 205.92051 -266.864657)
			(xy 205.946933 -266.821461) (xy 205.979016 -266.782286) (xy 205.997302 -266.76477) (xy 206.006192 -266.756388)
			(xy 206.014574 -266.734798) (xy 206.005176 -266.630658) (xy 205.992984 -266.610846) (xy 205.982824 -266.604242)
			(xy 205.956698 -266.587188) (xy 205.90858 -266.54747) (xy 205.865827 -266.502027) (xy 205.829114 -266.451578)
			(xy 205.799022 -266.396921) (xy 205.776027 -266.338921) (xy 205.760492 -266.278492) (xy 205.752663 -266.216593)
			(xy 205.752192 -266.185396) (xy 205.752693 -266.154187) (xy 205.760512 -266.092262) (xy 205.77604 -266.031807)
			(xy 205.799029 -265.973779) (xy 205.829119 -265.919093) (xy 205.865831 -265.868615) (xy 205.908587 -265.823142)
			(xy 205.956711 -265.783393) (xy 205.982824 -265.766296) (xy 205.992984 -265.759946) (xy 206.005176 -265.740134)
			(xy 206.014828 -265.635994) (xy 206.006446 -265.61415) (xy 205.997556 -265.606022) (xy 205.979258 -265.588478)
			(xy 205.947111 -265.549282) (xy 205.920633 -265.506054) (xy 205.900324 -265.459608) (xy 205.886565 -265.410818)
			(xy 205.879616 -265.360604) (xy 205.879192 -265.335258) (xy 205.879641 -265.309942) (xy 205.88656 -265.259784)
			(xy 205.900276 -265.211045) (xy 205.920532 -265.16464) (xy 205.946945 -265.121443) (xy 205.97902 -265.082265)
			(xy 205.997302 -265.064748) (xy 206.006192 -265.056366) (xy 206.014574 -265.034776) (xy 206.005176 -264.930636)
			(xy 205.992984 -264.910824) (xy 205.982824 -264.90422) (xy 205.956733 -264.887114) (xy 205.908615 -264.847403)
			(xy 205.86586 -264.801968) (xy 205.829145 -264.751527) (xy 205.799049 -264.696878) (xy 205.776048 -264.638884)
			(xy 205.760505 -264.578462) (xy 205.752668 -264.516568) (xy 205.752192 -264.485374) (xy 205.752676 -264.454165)
			(xy 205.760498 -264.392239) (xy 205.776028 -264.331784) (xy 205.79902 -264.273755) (xy 205.829112 -264.219069)
			(xy 205.865826 -264.168591) (xy 205.908585 -264.123119) (xy 205.95671 -264.08337) (xy 205.982824 -264.066274)
			(xy 205.992984 -264.059924) (xy 206.005176 -264.040112) (xy 206.014828 -263.935972) (xy 206.006446 -263.914128)
			(xy 205.997556 -263.906) (xy 205.979247 -263.888466) (xy 205.947101 -263.849268) (xy 205.920625 -263.806038)
			(xy 205.900317 -263.75959) (xy 205.886561 -263.710798) (xy 205.879615 -263.660583) (xy 205.879192 -263.635236)
			(xy 205.879627 -263.609919) (xy 205.886549 -263.559761) (xy 205.900268 -263.511021) (xy 205.920526 -263.464617)
			(xy 205.946942 -263.42142) (xy 205.979019 -263.382243) (xy 205.997302 -263.364726) (xy 206.006192 -263.356344)
			(xy 206.014574 -263.334754) (xy 206.005176 -263.230614) (xy 205.992984 -263.210802) (xy 205.982824 -263.204198)
			(xy 205.956723 -263.187107) (xy 205.908605 -263.147394) (xy 205.865851 -263.101956) (xy 205.829136 -263.051513)
			(xy 205.799041 -262.996862) (xy 205.776042 -262.938866) (xy 205.760502 -262.878443) (xy 205.752666 -262.816547)
			(xy 205.752192 -262.785352) (xy 205.752658 -262.754142) (xy 205.760483 -262.692216) (xy 205.776016 -262.63176)
			(xy 205.799011 -262.573731) (xy 205.829105 -262.519046) (xy 205.865822 -262.468568) (xy 205.908582 -262.423096)
			(xy 205.956709 -262.383348) (xy 205.982824 -262.366252) (xy 205.992984 -262.359902) (xy 206.005176 -262.34009)
			(xy 206.014828 -262.23595) (xy 206.006446 -262.214106) (xy 205.997556 -262.205978) (xy 205.979236 -262.188455)
			(xy 205.947091 -262.149255) (xy 205.920616 -262.106022) (xy 205.900311 -262.059572) (xy 205.886557 -262.010778)
			(xy 205.879613 -261.960561) (xy 205.879192 -261.935214) (xy 205.879612 -261.909897) (xy 205.886537 -261.859738)
			(xy 205.900259 -261.810998) (xy 205.92052 -261.764593) (xy 205.946938 -261.721397) (xy 205.979018 -261.682221)
			(xy 205.997302 -261.664704) (xy 206.006192 -261.656322) (xy 206.014574 -261.634732) (xy 206.005176 -261.530592)
			(xy 205.992984 -261.51078) (xy 205.982824 -261.504176) (xy 205.956713 -261.4871) (xy 205.908595 -261.447384)
			(xy 205.865841 -261.401945) (xy 205.829127 -261.3515) (xy 205.799034 -261.296846) (xy 205.776036 -261.238848)
			(xy 205.760498 -261.178423) (xy 205.752665 -261.116525) (xy 205.752192 -261.08533) (xy 205.752681 -261.054167)
			(xy 205.760493 -260.992333) (xy 205.775993 -260.931965) (xy 205.798936 -260.874017) (xy 205.828962 -260.8194)
			(xy 205.865596 -260.768978) (xy 205.908261 -260.723544) (xy 205.956283 -260.683816) (xy 206.008907 -260.650421)
			(xy 206.065301 -260.623884) (xy 206.124576 -260.604624) (xy 206.185797 -260.592945) (xy 206.248 -260.589032)
			(xy 206.310203 -260.592945) (xy 206.371424 -260.604624) (xy 206.430699 -260.623884) (xy 206.487093 -260.650421)
			(xy 206.539717 -260.683816) (xy 206.587739 -260.723544) (xy 206.630404 -260.768978) (xy 206.667038 -260.8194)
			(xy 206.697064 -260.874017) (xy 206.720007 -260.931965) (xy 206.735507 -260.992333) (xy 206.743319 -261.054167)
			(xy 206.743808 -261.08533) (xy 206.743313 -261.116526) (xy 206.7355 -261.178428) (xy 206.719975 -261.238858)
			(xy 206.696985 -261.29686) (xy 206.666894 -261.351516) (xy 206.630177 -261.401961) (xy 206.587417 -261.447396)
			(xy 206.53929 -261.487103) (xy 206.513176 -261.504176) (xy 206.503016 -261.51078) (xy 206.490824 -261.530592)
			(xy 206.481426 -261.634732) (xy 206.489808 -261.656322) (xy 206.498698 -261.664704) (xy 206.516984 -261.682219)
			(xy 206.549064 -261.721395) (xy 206.575483 -261.764592) (xy 206.595743 -261.810997) (xy 206.609465 -261.859737)
			(xy 206.616391 -261.909896) (xy 206.616808 -261.935214) (xy 206.616383 -261.960562) (xy 206.609449 -262.010781)
			(xy 206.5957 -262.059577) (xy 206.575395 -262.106029) (xy 206.548918 -262.149261) (xy 206.516767 -262.188458)
			(xy 206.498444 -262.205978) (xy 206.489554 -262.214106) (xy 206.481172 -262.23595) (xy 206.490824 -262.34009)
			(xy 206.503016 -262.359902) (xy 206.513176 -262.366252) (xy 206.539267 -262.383382) (xy 206.58739 -262.423129)
			(xy 206.630148 -262.468598) (xy 206.666864 -262.519071) (xy 206.69696 -262.573751) (xy 206.719959 -262.631774)
			(xy 206.735499 -262.692223) (xy 206.743334 -262.754145) (xy 206.743808 -262.785352) (xy 206.74333 -262.816549)
			(xy 206.735514 -262.878451) (xy 206.719987 -262.938881) (xy 206.696994 -262.996884) (xy 206.666901 -263.05154)
			(xy 206.630182 -263.101985) (xy 206.58742 -263.147419) (xy 206.539291 -263.187125) (xy 206.513176 -263.204198)
			(xy 206.503016 -263.210802) (xy 206.490824 -263.230614) (xy 206.481426 -263.334754) (xy 206.489808 -263.356344)
			(xy 206.498698 -263.364726) (xy 206.516995 -263.38223) (xy 206.549073 -263.421409) (xy 206.575491 -263.464608)
			(xy 206.59575 -263.511015) (xy 206.60947 -263.559757) (xy 206.616392 -263.609918) (xy 206.616808 -263.635236)
			(xy 206.616398 -263.660584) (xy 206.609461 -263.710804) (xy 206.595709 -263.759601) (xy 206.575402 -263.806052)
			(xy 206.548921 -263.849284) (xy 206.516768 -263.88848) (xy 206.498444 -263.906) (xy 206.489554 -263.914128)
			(xy 206.481172 -263.935972) (xy 206.490824 -264.040112) (xy 206.503016 -264.059924) (xy 206.513176 -264.066274)
			(xy 206.539277 -264.083389) (xy 206.5874 -264.123138) (xy 206.630157 -264.168609) (xy 206.666873 -264.219084)
			(xy 206.696967 -264.273766) (xy 206.719965 -264.331791) (xy 206.735503 -264.392243) (xy 206.743335 -264.454166)
			(xy 206.743808 -264.485374) (xy 206.743347 -264.516571) (xy 206.735529 -264.578474) (xy 206.719999 -264.638905)
			(xy 206.697004 -264.696907) (xy 206.666908 -264.751564) (xy 206.630187 -264.802008) (xy 206.587422 -264.847442)
			(xy 206.539291 -264.887147) (xy 206.513176 -264.90422) (xy 206.503016 -264.910824) (xy 206.490824 -264.930636)
			(xy 206.481426 -265.034776) (xy 206.489808 -265.056366) (xy 206.498698 -265.064748) (xy 206.516957 -265.08229)
			(xy 206.549039 -265.121461) (xy 206.575461 -265.164652) (xy 206.595727 -265.211051) (xy 206.609455 -265.259787)
			(xy 206.616387 -265.309942) (xy 206.616808 -265.335258) (xy 206.616413 -265.360607) (xy 206.609473 -265.410828)
			(xy 206.595718 -265.459624) (xy 206.575408 -265.506076) (xy 206.548925 -265.549307) (xy 206.516769 -265.588502)
			(xy 206.498444 -265.606022) (xy 206.489554 -265.61415) (xy 206.481172 -265.635994) (xy 206.490824 -265.740134)
			(xy 206.503016 -265.759946) (xy 206.513176 -265.766296) (xy 206.539287 -265.783396) (xy 206.58741 -265.823147)
			(xy 206.630167 -265.868621) (xy 206.666882 -265.919098) (xy 206.696975 -265.973782) (xy 206.719971 -266.031809)
			(xy 206.735507 -266.092263) (xy 206.743337 -266.154187) (xy 206.743808 -266.185396) (xy 206.743365 -266.216594)
			(xy 206.735543 -266.278497) (xy 206.720011 -266.338928) (xy 206.697013 -266.396931) (xy 206.666914 -266.451587)
			(xy 206.630191 -266.502031) (xy 206.587425 -266.547465) (xy 206.539292 -266.58717) (xy 206.513176 -266.604242)
			(xy 206.503016 -266.610846) (xy 206.490824 -266.630658) (xy 206.481426 -266.734798) (xy 206.489808 -266.756388)
			(xy 206.498698 -266.76477) (xy 206.516968 -266.782301) (xy 206.549049 -266.821474) (xy 206.57547 -266.864668)
			(xy 206.595733 -266.911069) (xy 206.609459 -266.959807) (xy 206.616388 -267.009963) (xy 206.616808 -267.03528)
			(xy 206.616361 -267.060627) (xy 206.609431 -267.110846) (xy 206.595687 -267.159641) (xy 206.575386 -267.206093)
			(xy 206.548913 -267.249325) (xy 206.516765 -267.288523) (xy 206.498444 -267.306044) (xy 206.489554 -267.314172)
			(xy 206.481172 -267.336016) (xy 206.490824 -267.440156) (xy 206.503016 -267.459968) (xy 206.513176 -267.466318)
			(xy 206.539297 -267.483404) (xy 206.58742 -267.523157) (xy 206.630176 -267.568632) (xy 206.66689 -267.619112)
			(xy 206.696982 -267.673798) (xy 206.719977 -267.731827) (xy 206.73551 -267.792282) (xy 206.743338 -267.854209)
			(xy 206.743808 -267.885418) (xy 206.743382 -267.916616) (xy 206.735558 -267.97852) (xy 206.720022 -268.038952)
			(xy 206.697022 -268.096955) (xy 206.666921 -268.151611) (xy 206.630196 -268.202055) (xy 206.587428 -268.247488)
			(xy 206.539293 -268.287192) (xy 206.513176 -268.304264) (xy 206.503016 -268.310868) (xy 206.490824 -268.33068)
			(xy 206.481426 -268.43482) (xy 206.489808 -268.45641) (xy 206.498698 -268.464792) (xy 206.516978 -268.482313)
			(xy 206.549059 -268.521488) (xy 206.575478 -268.564683) (xy 206.59574 -268.611087) (xy 206.609463 -268.659826)
			(xy 206.61639 -268.709985) (xy 206.616808 -268.735302) (xy 206.616375 -268.76065) (xy 206.609443 -268.810869)
			(xy 206.595695 -268.859664) (xy 206.575392 -268.906116) (xy 206.548916 -268.949348) (xy 206.516766 -268.988545)
			(xy 206.498444 -269.006066) (xy 206.489554 -269.014194) (xy 206.481172 -269.036038) (xy 206.490824 -269.140178)
			(xy 206.503016 -269.15999) (xy 206.513176 -269.16634) (xy 206.539262 -269.183478) (xy 206.587385 -269.223223)
			(xy 206.630142 -269.268691) (xy 206.666859 -269.319163) (xy 206.696956 -269.373842) (xy 206.719956 -269.431864)
			(xy 206.735497 -269.492312) (xy 206.743333 -269.554233) (xy 206.743808 -269.58544) (xy 206.743279 -269.61814)
			(xy 206.734672 -269.682973) (xy 206.717612 -269.746109) (xy 206.692397 -269.806454) (xy 206.659463 -269.862958)
			(xy 206.619384 -269.914639) (xy 206.596488 -269.937992) (xy 206.589122 -269.945358) (xy 206.581502 -269.9639)
			(xy 206.581502 -270.056864) (xy 206.589122 -270.075406) (xy 206.596488 -270.082772) (xy 206.619398 -270.106113)
			(xy 206.65948 -270.157794) (xy 206.692414 -270.2143) (xy 206.717628 -270.274647) (xy 206.734684 -270.337787)
			(xy 206.743285 -270.402622) (xy 206.743808 -270.435324) (xy 206.743387 -270.466522) (xy 206.735561 -270.528427)
			(xy 206.720026 -270.588859) (xy 206.697025 -270.646861) (xy 206.666923 -270.701517) (xy 206.630197 -270.751961)
			(xy 206.587428 -270.797394) (xy 206.539293 -270.837098) (xy 206.513176 -270.85417) (xy 206.503016 -270.860774)
			(xy 206.490824 -270.880586) (xy 206.481426 -270.984726) (xy 206.489808 -271.006316) (xy 206.498698 -271.014698)
			(xy 206.516981 -271.032216) (xy 206.549061 -271.071392) (xy 206.57548 -271.114588) (xy 206.595742 -271.160992)
			(xy 206.609464 -271.209732) (xy 206.61639 -271.259891) (xy 206.616808 -271.285208) (xy 206.616379 -271.310556)
			(xy 206.609446 -271.360775) (xy 206.595698 -271.409571) (xy 206.575394 -271.456023) (xy 206.548917 -271.499255)
			(xy 206.516767 -271.538452) (xy 206.498444 -271.555972) (xy 206.489554 -271.5641) (xy 206.481172 -271.585944)
			(xy 206.490824 -271.690084) (xy 206.503016 -271.709896) (xy 206.513176 -271.716246) (xy 206.539264 -271.73338)
			(xy 206.587387 -271.773126) (xy 206.630145 -271.818594) (xy 206.666862 -271.869067) (xy 206.696958 -271.923746)
			(xy 206.719958 -271.981769) (xy 206.735498 -272.042218) (xy 206.743334 -272.104139) (xy 206.743808 -272.135346)
			(xy 206.743325 -272.166543) (xy 206.73551 -272.228444) (xy 206.719984 -272.288875) (xy 206.696992 -272.346877)
			(xy 206.666899 -272.401533) (xy 206.630181 -272.451978) (xy 206.587419 -272.497413) (xy 206.53929 -272.537119)
			(xy 206.513176 -272.554192) (xy 206.503016 -272.560796) (xy 206.490824 -272.580608) (xy 206.481426 -272.684748)
			(xy 206.489808 -272.706338) (xy 206.498698 -272.71472) (xy 206.516992 -272.732227) (xy 206.549071 -272.771405)
			(xy 206.575489 -272.814604) (xy 206.595748 -272.86101) (xy 206.609468 -272.909752) (xy 206.616392 -272.959912)
			(xy 206.616808 -272.98523) (xy 206.616394 -273.010578) (xy 206.609458 -273.060798) (xy 206.595707 -273.109594)
			(xy 206.5754 -273.156046) (xy 206.54892 -273.199278) (xy 206.516768 -273.238474) (xy 206.498444 -273.255994)
			(xy 206.489554 -273.264122) (xy 206.481172 -273.285966) (xy 206.490824 -273.390106) (xy 206.503016 -273.409918)
			(xy 206.513176 -273.416268) (xy 206.539274 -273.433387) (xy 206.587397 -273.473135) (xy 206.630155 -273.518606)
			(xy 206.666871 -273.569081) (xy 206.696965 -273.623762) (xy 206.719964 -273.681787) (xy 206.735502 -273.742238)
			(xy 206.743335 -273.80416) (xy 206.743808 -273.835368) (xy 206.743319 -273.866531) (xy 206.735507 -273.928365)
			(xy 206.720007 -273.988733) (xy 206.697064 -274.046681) (xy 206.667038 -274.101298) (xy 206.630404 -274.15172)
			(xy 206.587739 -274.197154) (xy 206.539717 -274.236882) (xy 206.487093 -274.270277) (xy 206.430699 -274.296814)
			(xy 206.371424 -274.316074) (xy 206.310203 -274.327753) (xy 206.248 -274.331666) (xy 206.185797 -274.327753)
			(xy 206.124576 -274.316074) (xy 206.065301 -274.296814) (xy 206.008907 -274.270277) (xy 205.956283 -274.236882)
			(xy 205.908261 -274.197154) (xy 205.865596 -274.15172) (xy 205.828962 -274.101298) (xy 205.798936 -274.046681)
			(xy 205.775993 -273.988733) (xy 205.760493 -273.928365) (xy 205.752681 -273.866531) (xy 205.752192 -273.835368)
			(xy 202.51674 -273.835368) (xy 202.516329 -273.860686) (xy 202.509405 -273.910846) (xy 202.495683 -273.959587)
			(xy 202.475421 -274.005992) (xy 202.448999 -274.049188) (xy 202.416916 -274.088362) (xy 202.39863 -274.105878)
			(xy 202.38974 -274.11426) (xy 202.381358 -274.13585) (xy 202.390756 -274.23999) (xy 202.402948 -274.259802)
			(xy 202.413108 -274.266406) (xy 202.439218 -274.283483) (xy 202.487335 -274.3232) (xy 202.530087 -274.36864)
			(xy 202.566801 -274.419085) (xy 202.596894 -274.473738) (xy 202.619892 -274.531735) (xy 202.635432 -274.59216)
			(xy 202.643266 -274.654057) (xy 202.64374 -274.685252) (xy 204.494399 -274.685252) (xy 204.498334 -274.631481)
			(xy 204.510057 -274.578857) (xy 204.529317 -274.5285) (xy 204.555703 -274.481483) (xy 204.588655 -274.43881)
			(xy 204.627468 -274.401389) (xy 204.671316 -274.370019) (xy 204.719264 -274.345367) (xy 204.770291 -274.327959)
			(xy 204.823309 -274.318166) (xy 204.877188 -274.316197) (xy 204.930779 -274.322094) (xy 204.98294 -274.33573)
			(xy 205.03256 -274.356817) (xy 205.078581 -274.384903) (xy 205.120023 -274.419391) (xy 205.156001 -274.459545)
			(xy 205.185749 -274.504509) (xy 205.208634 -274.553326) (xy 205.224166 -274.604955) (xy 205.232016 -274.658295)
			(xy 205.232508 -274.685252) (xy 205.232016 -274.712209) (xy 205.224166 -274.765549) (xy 205.208634 -274.817178)
			(xy 205.185749 -274.865995) (xy 205.156001 -274.910959) (xy 205.120023 -274.951113) (xy 205.078581 -274.985601)
			(xy 205.03256 -275.013687) (xy 204.98294 -275.034774) (xy 204.930779 -275.04841) (xy 204.877188 -275.054307)
			(xy 204.823309 -275.052338) (xy 204.770291 -275.042545) (xy 204.719264 -275.025137) (xy 204.671316 -275.000485)
			(xy 204.627468 -274.969115) (xy 204.588655 -274.931694) (xy 204.555703 -274.889021) (xy 204.529317 -274.842004)
			(xy 204.510057 -274.791647) (xy 204.498334 -274.739023) (xy 204.494399 -274.685252) (xy 202.64374 -274.685252)
			(xy 202.643251 -274.716415) (xy 202.635439 -274.778249) (xy 202.619939 -274.838617) (xy 202.596996 -274.896565)
			(xy 202.56697 -274.951182) (xy 202.530336 -275.001604) (xy 202.487671 -275.047038) (xy 202.439649 -275.086766)
			(xy 202.387025 -275.120161) (xy 202.330631 -275.146698) (xy 202.271356 -275.165958) (xy 202.210135 -275.177637)
			(xy 202.147932 -275.18155) (xy 202.085729 -275.177637) (xy 202.024508 -275.165958) (xy 201.965233 -275.146698)
			(xy 201.908839 -275.120161) (xy 201.856215 -275.086766) (xy 201.808193 -275.047038) (xy 201.765528 -275.001604)
			(xy 201.728894 -274.951182) (xy 201.698868 -274.896565) (xy 201.675925 -274.838617) (xy 201.660425 -274.778249)
			(xy 201.652613 -274.716415) (xy 201.652124 -274.685252) (xy 197.688708 -274.685252) (xy 197.688216 -274.712209)
			(xy 197.680366 -274.765549) (xy 197.664834 -274.817178) (xy 197.641949 -274.865995) (xy 197.612201 -274.910959)
			(xy 197.576223 -274.951113) (xy 197.534781 -274.985601) (xy 197.48876 -275.013687) (xy 197.43914 -275.034774)
			(xy 197.386979 -275.04841) (xy 197.333388 -275.054307) (xy 197.279509 -275.052338) (xy 197.226491 -275.042545)
			(xy 197.175464 -275.025137) (xy 197.127516 -275.000485) (xy 197.083668 -274.969115) (xy 197.044855 -274.931694)
			(xy 197.011903 -274.889021) (xy 196.985517 -274.842004) (xy 196.966257 -274.791647) (xy 196.954534 -274.739023)
			(xy 196.950599 -274.685252) (xy 195.09994 -274.685252) (xy 195.099451 -274.716415) (xy 195.091639 -274.778249)
			(xy 195.076139 -274.838617) (xy 195.053196 -274.896565) (xy 195.02317 -274.951182) (xy 194.986536 -275.001604)
			(xy 194.943871 -275.047038) (xy 194.895849 -275.086766) (xy 194.843225 -275.120161) (xy 194.786831 -275.146698)
			(xy 194.727556 -275.165958) (xy 194.666335 -275.177637) (xy 194.604132 -275.18155) (xy 194.541929 -275.177637)
			(xy 194.480708 -275.165958) (xy 194.421433 -275.146698) (xy 194.365039 -275.120161) (xy 194.312415 -275.086766)
			(xy 194.264393 -275.047038) (xy 194.221728 -275.001604) (xy 194.185094 -274.951182) (xy 194.155068 -274.896565)
			(xy 194.132125 -274.838617) (xy 194.116625 -274.778249) (xy 194.108813 -274.716415) (xy 194.108324 -274.685252)
			(xy 190.144654 -274.685252) (xy 190.144162 -274.712209) (xy 190.136312 -274.765549) (xy 190.12078 -274.817178)
			(xy 190.097895 -274.865995) (xy 190.068147 -274.910959) (xy 190.032169 -274.951113) (xy 189.990727 -274.985601)
			(xy 189.944706 -275.013687) (xy 189.895086 -275.034774) (xy 189.842925 -275.04841) (xy 189.789334 -275.054307)
			(xy 189.735455 -275.052338) (xy 189.682437 -275.042545) (xy 189.63141 -275.025137) (xy 189.583462 -275.000485)
			(xy 189.539614 -274.969115) (xy 189.500801 -274.931694) (xy 189.467849 -274.889021) (xy 189.441463 -274.842004)
			(xy 189.422203 -274.791647) (xy 189.41048 -274.739023) (xy 189.406545 -274.685252) (xy 187.555886 -274.685252)
			(xy 187.555397 -274.716415) (xy 187.547585 -274.778249) (xy 187.532085 -274.838617) (xy 187.509142 -274.896565)
			(xy 187.479116 -274.951182) (xy 187.442482 -275.001604) (xy 187.399817 -275.047038) (xy 187.351795 -275.086766)
			(xy 187.299171 -275.120161) (xy 187.242777 -275.146698) (xy 187.183502 -275.165958) (xy 187.122281 -275.177637)
			(xy 187.060078 -275.18155) (xy 186.997875 -275.177637) (xy 186.936654 -275.165958) (xy 186.877379 -275.146698)
			(xy 186.820985 -275.120161) (xy 186.768361 -275.086766) (xy 186.720339 -275.047038) (xy 186.677674 -275.001604)
			(xy 186.64104 -274.951182) (xy 186.611014 -274.896565) (xy 186.588071 -274.838617) (xy 186.572571 -274.778249)
			(xy 186.564759 -274.716415) (xy 186.56427 -274.685252) (xy 185.96864 -274.685252) (xy 185.96864 -275.53539)
			(xy 188.075077 -275.53539) (xy 188.079012 -275.481619) (xy 188.090735 -275.428995) (xy 188.109995 -275.378638)
			(xy 188.136381 -275.331621) (xy 188.169333 -275.288948) (xy 188.208146 -275.251527) (xy 188.251994 -275.220157)
			(xy 188.299942 -275.195505) (xy 188.350969 -275.178097) (xy 188.403987 -275.168304) (xy 188.457866 -275.166335)
			(xy 188.511457 -275.172232) (xy 188.563618 -275.185868) (xy 188.613238 -275.206955) (xy 188.659259 -275.235041)
			(xy 188.700701 -275.269529) (xy 188.736679 -275.309683) (xy 188.766427 -275.354647) (xy 188.789312 -275.403464)
			(xy 188.804844 -275.455093) (xy 188.812694 -275.508433) (xy 188.813186 -275.53539) (xy 188.812694 -275.562347)
			(xy 188.804844 -275.615687) (xy 188.789312 -275.667316) (xy 188.766427 -275.716133) (xy 188.736679 -275.761097)
			(xy 188.700701 -275.801251) (xy 188.659259 -275.835739) (xy 188.613238 -275.863825) (xy 188.563618 -275.884912)
			(xy 188.511457 -275.898548) (xy 188.457866 -275.904445) (xy 188.403987 -275.902476) (xy 188.350969 -275.892683)
			(xy 188.299942 -275.875275) (xy 188.251994 -275.850623) (xy 188.208146 -275.819253) (xy 188.169333 -275.781832)
			(xy 188.136381 -275.739159) (xy 188.109995 -275.692142) (xy 188.090735 -275.641785) (xy 188.079012 -275.589161)
			(xy 188.075077 -275.53539) (xy 185.96864 -275.53539) (xy 185.96864 -277.235412) (xy 186.56427 -277.235412)
			(xy 186.564777 -277.202691) (xy 186.57338 -277.137818) (xy 186.590439 -277.074639) (xy 186.615658 -277.014252)
			(xy 186.648598 -276.957705) (xy 186.688687 -276.905981) (xy 186.71159 -276.882606) (xy 186.718956 -276.875494)
			(xy 186.72683 -276.856698) (xy 186.72683 -276.763988) (xy 186.718956 -276.745192) (xy 186.71159 -276.73808)
			(xy 186.688675 -276.714718) (xy 186.648593 -276.662988) (xy 186.615659 -276.606438) (xy 186.590447 -276.546048)
			(xy 186.573392 -276.482868) (xy 186.564792 -276.417995) (xy 186.56427 -276.385274) (xy 186.564759 -276.354111)
			(xy 186.572571 -276.292277) (xy 186.588071 -276.231909) (xy 186.611014 -276.173961) (xy 186.64104 -276.119344)
			(xy 186.677674 -276.068922) (xy 186.720339 -276.023488) (xy 186.768361 -275.98376) (xy 186.820985 -275.950365)
			(xy 186.877379 -275.923828) (xy 186.936654 -275.904568) (xy 186.997875 -275.892889) (xy 187.060078 -275.888976)
			(xy 187.122281 -275.892889) (xy 187.183502 -275.904568) (xy 187.242777 -275.923828) (xy 187.299171 -275.950365)
			(xy 187.351795 -275.98376) (xy 187.399817 -276.023488) (xy 187.442482 -276.068922) (xy 187.479116 -276.119344)
			(xy 187.509142 -276.173961) (xy 187.532085 -276.231909) (xy 187.547585 -276.292277) (xy 187.555397 -276.354111)
			(xy 187.555886 -276.385274) (xy 190.664338 -276.385274) (xy 190.664892 -276.352575) (xy 190.673496 -276.287744)
			(xy 190.690552 -276.224608) (xy 190.715763 -276.164264) (xy 190.748691 -276.10776) (xy 190.788765 -276.056077)
			(xy 190.811658 -276.032722) (xy 190.819024 -276.025356) (xy 190.826644 -276.006814) (xy 190.826644 -275.91385)
			(xy 190.819024 -275.895308) (xy 190.811658 -275.887942) (xy 190.788763 -275.864587) (xy 190.748678 -275.812909)
			(xy 190.715741 -275.756407) (xy 190.690524 -275.696062) (xy 190.673465 -275.632924) (xy 190.664862 -275.568091)
			(xy 190.664338 -275.53539) (xy 190.664827 -275.504227) (xy 190.672639 -275.442393) (xy 190.688139 -275.382025)
			(xy 190.711082 -275.324077) (xy 190.741108 -275.26946) (xy 190.777742 -275.219038) (xy 190.820407 -275.173604)
			(xy 190.868429 -275.133876) (xy 190.921053 -275.100481) (xy 190.977447 -275.073944) (xy 191.036722 -275.054684)
			(xy 191.097943 -275.043005) (xy 191.160146 -275.039092) (xy 191.222349 -275.043005) (xy 191.28357 -275.054684)
			(xy 191.342845 -275.073944) (xy 191.399239 -275.100481) (xy 191.451863 -275.133876) (xy 191.499885 -275.173604)
			(xy 191.54255 -275.219038) (xy 191.579184 -275.26946) (xy 191.60921 -275.324077) (xy 191.632153 -275.382025)
			(xy 191.647653 -275.442393) (xy 191.655465 -275.504227) (xy 191.655954 -275.53539) (xy 195.619131 -275.53539)
			(xy 195.623066 -275.481619) (xy 195.634789 -275.428995) (xy 195.654049 -275.378638) (xy 195.680435 -275.331621)
			(xy 195.713387 -275.288948) (xy 195.7522 -275.251527) (xy 195.796048 -275.220157) (xy 195.843996 -275.195505)
			(xy 195.895023 -275.178097) (xy 195.948041 -275.168304) (xy 196.00192 -275.166335) (xy 196.055511 -275.172232)
			(xy 196.107672 -275.185868) (xy 196.157292 -275.206955) (xy 196.203313 -275.235041) (xy 196.244755 -275.269529)
			(xy 196.280733 -275.309683) (xy 196.310481 -275.354647) (xy 196.333366 -275.403464) (xy 196.348898 -275.455093)
			(xy 196.356748 -275.508433) (xy 196.35724 -275.53539) (xy 196.356748 -275.562347) (xy 196.348898 -275.615687)
			(xy 196.333366 -275.667316) (xy 196.310481 -275.716133) (xy 196.280733 -275.761097) (xy 196.244755 -275.801251)
			(xy 196.203313 -275.835739) (xy 196.157292 -275.863825) (xy 196.107672 -275.884912) (xy 196.055511 -275.898548)
			(xy 196.00192 -275.904445) (xy 195.948041 -275.902476) (xy 195.895023 -275.892683) (xy 195.843996 -275.875275)
			(xy 195.796048 -275.850623) (xy 195.7522 -275.819253) (xy 195.713387 -275.781832) (xy 195.680435 -275.739159)
			(xy 195.654049 -275.692142) (xy 195.634789 -275.641785) (xy 195.623066 -275.589161) (xy 195.619131 -275.53539)
			(xy 191.655954 -275.53539) (xy 191.655444 -275.568091) (xy 191.646831 -275.632923) (xy 191.629767 -275.69606)
			(xy 191.604548 -275.756404) (xy 191.571611 -275.812907) (xy 191.53153 -275.864589) (xy 191.508634 -275.887942)
			(xy 191.501268 -275.895308) (xy 191.493648 -275.91385) (xy 191.493648 -275.960332) (xy 191.908445 -275.960332)
			(xy 191.91238 -275.906561) (xy 191.924103 -275.853937) (xy 191.943363 -275.80358) (xy 191.969749 -275.756563)
			(xy 192.002701 -275.71389) (xy 192.041514 -275.676469) (xy 192.085362 -275.645099) (xy 192.13331 -275.620447)
			(xy 192.184337 -275.603039) (xy 192.237355 -275.593246) (xy 192.291234 -275.591277) (xy 192.344825 -275.597174)
			(xy 192.396986 -275.61081) (xy 192.446606 -275.631897) (xy 192.492627 -275.659983) (xy 192.534069 -275.694471)
			(xy 192.570047 -275.734625) (xy 192.599795 -275.779589) (xy 192.62268 -275.828406) (xy 192.638212 -275.880035)
			(xy 192.646062 -275.933375) (xy 192.646554 -275.960332) (xy 192.646062 -275.987289) (xy 192.638212 -276.040629)
			(xy 192.62268 -276.092258) (xy 192.599795 -276.141075) (xy 192.570047 -276.186039) (xy 192.534069 -276.226193)
			(xy 192.492627 -276.260681) (xy 192.446606 -276.288767) (xy 192.396986 -276.309854) (xy 192.344825 -276.32349)
			(xy 192.291234 -276.329387) (xy 192.237355 -276.327418) (xy 192.184337 -276.317625) (xy 192.13331 -276.300217)
			(xy 192.085362 -276.275565) (xy 192.041514 -276.244195) (xy 192.002701 -276.206774) (xy 191.969749 -276.164101)
			(xy 191.943363 -276.117084) (xy 191.924103 -276.066727) (xy 191.91238 -276.014103) (xy 191.908445 -275.960332)
			(xy 191.493648 -275.960332) (xy 191.493648 -276.006814) (xy 191.501268 -276.025356) (xy 191.508634 -276.032722)
			(xy 191.53151 -276.056095) (xy 191.571597 -276.107769) (xy 191.604537 -276.164267) (xy 191.629758 -276.224608)
			(xy 191.64682 -276.287743) (xy 191.655428 -276.352574) (xy 191.655954 -276.385274) (xy 191.655465 -276.416437)
			(xy 191.647653 -276.478271) (xy 191.632153 -276.538639) (xy 191.60921 -276.596587) (xy 191.579184 -276.651204)
			(xy 191.54255 -276.701626) (xy 191.499885 -276.74706) (xy 191.451863 -276.786788) (xy 191.399239 -276.820183)
			(xy 191.342845 -276.84672) (xy 191.28357 -276.86598) (xy 191.222349 -276.877659) (xy 191.160146 -276.881572)
			(xy 191.097943 -276.877659) (xy 191.036722 -276.86598) (xy 190.977447 -276.84672) (xy 190.921053 -276.820183)
			(xy 190.868429 -276.786788) (xy 190.820407 -276.74706) (xy 190.777742 -276.701626) (xy 190.741108 -276.651204)
			(xy 190.711082 -276.596587) (xy 190.688139 -276.538639) (xy 190.672639 -276.478271) (xy 190.664827 -276.416437)
			(xy 190.664338 -276.385274) (xy 187.555886 -276.385274) (xy 187.555383 -276.417995) (xy 187.546781 -276.482869)
			(xy 187.529722 -276.546048) (xy 187.504503 -276.606436) (xy 187.471561 -276.662982) (xy 187.43147 -276.714706)
			(xy 187.408566 -276.73808) (xy 187.4012 -276.745192) (xy 187.393326 -276.763988) (xy 187.393326 -276.81047)
			(xy 187.808377 -276.81047) (xy 187.812312 -276.756699) (xy 187.824035 -276.704075) (xy 187.843295 -276.653718)
			(xy 187.869681 -276.606701) (xy 187.902633 -276.564028) (xy 187.941446 -276.526607) (xy 187.985294 -276.495237)
			(xy 188.033242 -276.470585) (xy 188.084269 -276.453177) (xy 188.137287 -276.443384) (xy 188.191166 -276.441415)
			(xy 188.244757 -276.447312) (xy 188.296918 -276.460948) (xy 188.346538 -276.482035) (xy 188.392559 -276.510121)
			(xy 188.434001 -276.544609) (xy 188.469979 -276.584763) (xy 188.499727 -276.629727) (xy 188.522612 -276.678544)
			(xy 188.538144 -276.730173) (xy 188.545994 -276.783513) (xy 188.546486 -276.81047) (xy 188.545994 -276.837427)
			(xy 188.538144 -276.890767) (xy 188.522612 -276.942396) (xy 188.499727 -276.991213) (xy 188.469979 -277.036177)
			(xy 188.434001 -277.076331) (xy 188.392559 -277.110819) (xy 188.346538 -277.138905) (xy 188.296918 -277.159992)
			(xy 188.244757 -277.173628) (xy 188.191166 -277.179525) (xy 188.137287 -277.177556) (xy 188.084269 -277.167763)
			(xy 188.033242 -277.150355) (xy 187.985294 -277.125703) (xy 187.941446 -277.094333) (xy 187.902633 -277.056912)
			(xy 187.869681 -277.014239) (xy 187.843295 -276.967222) (xy 187.824035 -276.916865) (xy 187.812312 -276.864241)
			(xy 187.808377 -276.81047) (xy 187.393326 -276.81047) (xy 187.393326 -276.856698) (xy 187.4012 -276.875494)
			(xy 187.408566 -276.882606) (xy 187.431485 -276.905964) (xy 187.471565 -276.957696) (xy 187.504496 -277.014248)
			(xy 187.529708 -277.074638) (xy 187.546762 -277.137818) (xy 187.555363 -277.202691) (xy 187.555886 -277.235412)
			(xy 189.406545 -277.235412) (xy 189.41048 -277.181641) (xy 189.422203 -277.129017) (xy 189.441463 -277.07866)
			(xy 189.467849 -277.031643) (xy 189.500801 -276.98897) (xy 189.539614 -276.951549) (xy 189.583462 -276.920179)
			(xy 189.63141 -276.895527) (xy 189.682437 -276.878119) (xy 189.735455 -276.868326) (xy 189.789334 -276.866357)
			(xy 189.842925 -276.872254) (xy 189.895086 -276.88589) (xy 189.944706 -276.906977) (xy 189.990727 -276.935063)
			(xy 190.032169 -276.969551) (xy 190.068147 -277.009705) (xy 190.097895 -277.054669) (xy 190.12078 -277.103486)
			(xy 190.136312 -277.155115) (xy 190.144162 -277.208455) (xy 190.144654 -277.235412) (xy 194.108324 -277.235412)
			(xy 194.108815 -277.202691) (xy 194.117419 -277.137816) (xy 194.13448 -277.074636) (xy 194.159702 -277.014249)
			(xy 194.192645 -276.957702) (xy 194.232739 -276.90598) (xy 194.255644 -276.882606) (xy 194.26301 -276.875494)
			(xy 194.270884 -276.856698) (xy 194.270884 -276.763988) (xy 194.26301 -276.745192) (xy 194.255644 -276.73808)
			(xy 194.23272 -276.714726) (xy 194.19264 -276.662994) (xy 194.159709 -276.606441) (xy 194.134498 -276.54605)
			(xy 194.117445 -276.482869) (xy 194.108846 -276.417995) (xy 194.108324 -276.385274) (xy 194.108813 -276.354111)
			(xy 194.116625 -276.292277) (xy 194.132125 -276.231909) (xy 194.155068 -276.173961) (xy 194.185094 -276.119344)
			(xy 194.221728 -276.068922) (xy 194.264393 -276.023488) (xy 194.312415 -275.98376) (xy 194.365039 -275.950365)
			(xy 194.421433 -275.923828) (xy 194.480708 -275.904568) (xy 194.541929 -275.892889) (xy 194.604132 -275.888976)
			(xy 194.666335 -275.892889) (xy 194.727556 -275.904568) (xy 194.786831 -275.923828) (xy 194.843225 -275.950365)
			(xy 194.895849 -275.98376) (xy 194.943871 -276.023488) (xy 194.986536 -276.068922) (xy 195.02317 -276.119344)
			(xy 195.053196 -276.173961) (xy 195.076139 -276.231909) (xy 195.091639 -276.292277) (xy 195.099451 -276.354111)
			(xy 195.09994 -276.385274) (xy 198.208392 -276.385274) (xy 198.20893 -276.352574) (xy 198.217535 -276.287742)
			(xy 198.234593 -276.224605) (xy 198.259807 -276.164261) (xy 198.292739 -276.107757) (xy 198.332817 -276.056076)
			(xy 198.355712 -276.032722) (xy 198.363078 -276.025356) (xy 198.370698 -276.006814) (xy 198.370698 -275.91385)
			(xy 198.363078 -275.895308) (xy 198.355712 -275.887942) (xy 198.332809 -275.864595) (xy 198.292726 -275.812915)
			(xy 198.259791 -275.75641) (xy 198.234576 -275.696064) (xy 198.217519 -275.632925) (xy 198.208916 -275.568091)
			(xy 198.208392 -275.53539) (xy 198.208881 -275.504227) (xy 198.216693 -275.442393) (xy 198.232193 -275.382025)
			(xy 198.255136 -275.324077) (xy 198.285162 -275.26946) (xy 198.321796 -275.219038) (xy 198.364461 -275.173604)
			(xy 198.412483 -275.133876) (xy 198.465107 -275.100481) (xy 198.521501 -275.073944) (xy 198.580776 -275.054684)
			(xy 198.641997 -275.043005) (xy 198.7042 -275.039092) (xy 198.766403 -275.043005) (xy 198.827624 -275.054684)
			(xy 198.886899 -275.073944) (xy 198.943293 -275.100481) (xy 198.995917 -275.133876) (xy 199.043939 -275.173604)
			(xy 199.086604 -275.219038) (xy 199.123238 -275.26946) (xy 199.153264 -275.324077) (xy 199.176207 -275.382025)
			(xy 199.191707 -275.442393) (xy 199.199519 -275.504227) (xy 199.200008 -275.53539) (xy 203.162931 -275.53539)
			(xy 203.166866 -275.481619) (xy 203.178589 -275.428995) (xy 203.197849 -275.378638) (xy 203.224235 -275.331621)
			(xy 203.257187 -275.288948) (xy 203.296 -275.251527) (xy 203.339848 -275.220157) (xy 203.387796 -275.195505)
			(xy 203.438823 -275.178097) (xy 203.491841 -275.168304) (xy 203.54572 -275.166335) (xy 203.599311 -275.172232)
			(xy 203.651472 -275.185868) (xy 203.701092 -275.206955) (xy 203.747113 -275.235041) (xy 203.788555 -275.269529)
			(xy 203.824533 -275.309683) (xy 203.854281 -275.354647) (xy 203.877166 -275.403464) (xy 203.892698 -275.455093)
			(xy 203.900548 -275.508433) (xy 203.90104 -275.53539) (xy 203.900548 -275.562347) (xy 203.892698 -275.615687)
			(xy 203.877166 -275.667316) (xy 203.854281 -275.716133) (xy 203.824533 -275.761097) (xy 203.788555 -275.801251)
			(xy 203.747113 -275.835739) (xy 203.701092 -275.863825) (xy 203.651472 -275.884912) (xy 203.599311 -275.898548)
			(xy 203.54572 -275.904445) (xy 203.491841 -275.902476) (xy 203.438823 -275.892683) (xy 203.387796 -275.875275)
			(xy 203.339848 -275.850623) (xy 203.296 -275.819253) (xy 203.257187 -275.781832) (xy 203.224235 -275.739159)
			(xy 203.197849 -275.692142) (xy 203.178589 -275.641785) (xy 203.166866 -275.589161) (xy 203.162931 -275.53539)
			(xy 199.200008 -275.53539) (xy 199.199512 -275.568092) (xy 199.190898 -275.632925) (xy 199.173832 -275.696062)
			(xy 199.14861 -275.756407) (xy 199.115671 -275.81291) (xy 199.075586 -275.86459) (xy 199.052688 -275.887942)
			(xy 199.045322 -275.895308) (xy 199.037702 -275.91385) (xy 199.037702 -275.960332) (xy 199.452499 -275.960332)
			(xy 199.456434 -275.906561) (xy 199.468157 -275.853937) (xy 199.487417 -275.80358) (xy 199.513803 -275.756563)
			(xy 199.546755 -275.71389) (xy 199.585568 -275.676469) (xy 199.629416 -275.645099) (xy 199.677364 -275.620447)
			(xy 199.728391 -275.603039) (xy 199.781409 -275.593246) (xy 199.835288 -275.591277) (xy 199.888879 -275.597174)
			(xy 199.94104 -275.61081) (xy 199.99066 -275.631897) (xy 200.036681 -275.659983) (xy 200.078123 -275.694471)
			(xy 200.114101 -275.734625) (xy 200.143849 -275.779589) (xy 200.166734 -275.828406) (xy 200.182266 -275.880035)
			(xy 200.190116 -275.933375) (xy 200.190608 -275.960332) (xy 200.190116 -275.987289) (xy 200.182266 -276.040629)
			(xy 200.166734 -276.092258) (xy 200.143849 -276.141075) (xy 200.114101 -276.186039) (xy 200.078123 -276.226193)
			(xy 200.036681 -276.260681) (xy 199.99066 -276.288767) (xy 199.94104 -276.309854) (xy 199.888879 -276.32349)
			(xy 199.835288 -276.329387) (xy 199.781409 -276.327418) (xy 199.728391 -276.317625) (xy 199.677364 -276.300217)
			(xy 199.629416 -276.275565) (xy 199.585568 -276.244195) (xy 199.546755 -276.206774) (xy 199.513803 -276.164101)
			(xy 199.487417 -276.117084) (xy 199.468157 -276.066727) (xy 199.456434 -276.014103) (xy 199.452499 -275.960332)
			(xy 199.037702 -275.960332) (xy 199.037702 -276.006814) (xy 199.045322 -276.025356) (xy 199.052688 -276.032722)
			(xy 199.075574 -276.056085) (xy 199.115658 -276.107762) (xy 199.148595 -276.164263) (xy 199.173814 -276.224606)
			(xy 199.190875 -276.287742) (xy 199.199482 -276.352574) (xy 199.200008 -276.385274) (xy 199.199519 -276.416437)
			(xy 199.191707 -276.478271) (xy 199.176207 -276.538639) (xy 199.153264 -276.596587) (xy 199.123238 -276.651204)
			(xy 199.086604 -276.701626) (xy 199.043939 -276.74706) (xy 198.995917 -276.786788) (xy 198.943293 -276.820183)
			(xy 198.886899 -276.84672) (xy 198.827624 -276.86598) (xy 198.766403 -276.877659) (xy 198.7042 -276.881572)
			(xy 198.641997 -276.877659) (xy 198.580776 -276.86598) (xy 198.521501 -276.84672) (xy 198.465107 -276.820183)
			(xy 198.412483 -276.786788) (xy 198.364461 -276.74706) (xy 198.321796 -276.701626) (xy 198.285162 -276.651204)
			(xy 198.255136 -276.596587) (xy 198.232193 -276.538639) (xy 198.216693 -276.478271) (xy 198.208881 -276.416437)
			(xy 198.208392 -276.385274) (xy 195.09994 -276.385274) (xy 195.099451 -276.417996) (xy 195.090847 -276.482871)
			(xy 195.073787 -276.546051) (xy 195.048565 -276.606439) (xy 195.015621 -276.662985) (xy 194.975526 -276.714707)
			(xy 194.95262 -276.73808) (xy 194.945254 -276.745192) (xy 194.93738 -276.763988) (xy 194.93738 -276.81047)
			(xy 195.352431 -276.81047) (xy 195.356366 -276.756699) (xy 195.368089 -276.704075) (xy 195.387349 -276.653718)
			(xy 195.413735 -276.606701) (xy 195.446687 -276.564028) (xy 195.4855 -276.526607) (xy 195.529348 -276.495237)
			(xy 195.577296 -276.470585) (xy 195.628323 -276.453177) (xy 195.681341 -276.443384) (xy 195.73522 -276.441415)
			(xy 195.788811 -276.447312) (xy 195.840972 -276.460948) (xy 195.890592 -276.482035) (xy 195.936613 -276.510121)
			(xy 195.978055 -276.544609) (xy 196.014033 -276.584763) (xy 196.043781 -276.629727) (xy 196.066666 -276.678544)
			(xy 196.082198 -276.730173) (xy 196.090048 -276.783513) (xy 196.09054 -276.81047) (xy 196.090048 -276.837427)
			(xy 196.082198 -276.890767) (xy 196.066666 -276.942396) (xy 196.043781 -276.991213) (xy 196.014033 -277.036177)
			(xy 195.978055 -277.076331) (xy 195.936613 -277.110819) (xy 195.890592 -277.138905) (xy 195.840972 -277.159992)
			(xy 195.788811 -277.173628) (xy 195.73522 -277.179525) (xy 195.681341 -277.177556) (xy 195.628323 -277.167763)
			(xy 195.577296 -277.150355) (xy 195.529348 -277.125703) (xy 195.4855 -277.094333) (xy 195.446687 -277.056912)
			(xy 195.413735 -277.014239) (xy 195.387349 -276.967222) (xy 195.368089 -276.916865) (xy 195.356366 -276.864241)
			(xy 195.352431 -276.81047) (xy 194.93738 -276.81047) (xy 194.93738 -276.856698) (xy 194.945254 -276.875494)
			(xy 194.95262 -276.882606) (xy 194.97553 -276.905973) (xy 195.015613 -276.957702) (xy 195.048546 -277.014251)
			(xy 195.07376 -277.07464) (xy 195.090815 -277.137819) (xy 195.099417 -277.202692) (xy 195.09994 -277.235412)
			(xy 196.950599 -277.235412) (xy 196.954534 -277.181641) (xy 196.966257 -277.129017) (xy 196.985517 -277.07866)
			(xy 197.011903 -277.031643) (xy 197.044855 -276.98897) (xy 197.083668 -276.951549) (xy 197.127516 -276.920179)
			(xy 197.175464 -276.895527) (xy 197.226491 -276.878119) (xy 197.279509 -276.868326) (xy 197.333388 -276.866357)
			(xy 197.386979 -276.872254) (xy 197.43914 -276.88589) (xy 197.48876 -276.906977) (xy 197.534781 -276.935063)
			(xy 197.576223 -276.969551) (xy 197.612201 -277.009705) (xy 197.641949 -277.054669) (xy 197.664834 -277.103486)
			(xy 197.680366 -277.155115) (xy 197.688216 -277.208455) (xy 197.688708 -277.235412) (xy 201.652124 -277.235412)
			(xy 201.652615 -277.202691) (xy 201.661219 -277.137816) (xy 201.67828 -277.074636) (xy 201.703502 -277.014249)
			(xy 201.736445 -276.957702) (xy 201.776539 -276.90598) (xy 201.799444 -276.882606) (xy 201.80681 -276.875494)
			(xy 201.814684 -276.856698) (xy 201.814684 -276.763988) (xy 201.80681 -276.745192) (xy 201.799444 -276.73808)
			(xy 201.77652 -276.714726) (xy 201.73644 -276.662994) (xy 201.703509 -276.606441) (xy 201.678298 -276.54605)
			(xy 201.661245 -276.482869) (xy 201.652646 -276.417995) (xy 201.652124 -276.385274) (xy 201.652613 -276.354111)
			(xy 201.660425 -276.292277) (xy 201.675925 -276.231909) (xy 201.698868 -276.173961) (xy 201.728894 -276.119344)
			(xy 201.765528 -276.068922) (xy 201.808193 -276.023488) (xy 201.856215 -275.98376) (xy 201.908839 -275.950365)
			(xy 201.965233 -275.923828) (xy 202.024508 -275.904568) (xy 202.085729 -275.892889) (xy 202.147932 -275.888976)
			(xy 202.210135 -275.892889) (xy 202.271356 -275.904568) (xy 202.330631 -275.923828) (xy 202.387025 -275.950365)
			(xy 202.439649 -275.98376) (xy 202.487671 -276.023488) (xy 202.530336 -276.068922) (xy 202.56697 -276.119344)
			(xy 202.596996 -276.173961) (xy 202.619939 -276.231909) (xy 202.635439 -276.292277) (xy 202.643251 -276.354111)
			(xy 202.64374 -276.385274) (xy 205.752192 -276.385274) (xy 205.75273 -276.352574) (xy 205.761335 -276.287742)
			(xy 205.778393 -276.224605) (xy 205.803607 -276.164261) (xy 205.836539 -276.107757) (xy 205.876617 -276.056076)
			(xy 205.899512 -276.032722) (xy 205.906878 -276.025356) (xy 205.914498 -276.006814) (xy 205.914498 -275.91385)
			(xy 205.906878 -275.895308) (xy 205.899512 -275.887942) (xy 205.876609 -275.864595) (xy 205.836526 -275.812915)
			(xy 205.803591 -275.75641) (xy 205.778376 -275.696064) (xy 205.761319 -275.632925) (xy 205.752716 -275.568091)
			(xy 205.752192 -275.53539) (xy 205.752681 -275.504227) (xy 205.760493 -275.442393) (xy 205.775993 -275.382025)
			(xy 205.798936 -275.324077) (xy 205.828962 -275.26946) (xy 205.865596 -275.219038) (xy 205.908261 -275.173604)
			(xy 205.956283 -275.133876) (xy 206.008907 -275.100481) (xy 206.065301 -275.073944) (xy 206.124576 -275.054684)
			(xy 206.185797 -275.043005) (xy 206.248 -275.039092) (xy 206.310203 -275.043005) (xy 206.371424 -275.054684)
			(xy 206.430699 -275.073944) (xy 206.487093 -275.100481) (xy 206.539717 -275.133876) (xy 206.587739 -275.173604)
			(xy 206.630404 -275.219038) (xy 206.667038 -275.26946) (xy 206.697064 -275.324077) (xy 206.720007 -275.382025)
			(xy 206.735507 -275.442393) (xy 206.743319 -275.504227) (xy 206.743808 -275.53539) (xy 206.743312 -275.568092)
			(xy 206.734698 -275.632925) (xy 206.717632 -275.696062) (xy 206.69241 -275.756407) (xy 206.659471 -275.81291)
			(xy 206.619386 -275.86459) (xy 206.596488 -275.887942) (xy 206.589122 -275.895308) (xy 206.581502 -275.91385)
			(xy 206.581502 -275.960332) (xy 206.996299 -275.960332) (xy 207.000234 -275.906561) (xy 207.011957 -275.853937)
			(xy 207.031217 -275.80358) (xy 207.057603 -275.756563) (xy 207.090555 -275.71389) (xy 207.129368 -275.676469)
			(xy 207.173216 -275.645099) (xy 207.221164 -275.620447) (xy 207.272191 -275.603039) (xy 207.325209 -275.593246)
			(xy 207.379088 -275.591277) (xy 207.432679 -275.597174) (xy 207.48484 -275.61081) (xy 207.53446 -275.631897)
			(xy 207.580481 -275.659983) (xy 207.621923 -275.694471) (xy 207.657901 -275.734625) (xy 207.687649 -275.779589)
			(xy 207.710534 -275.828406) (xy 207.726066 -275.880035) (xy 207.733916 -275.933375) (xy 207.734408 -275.960332)
			(xy 207.733916 -275.987289) (xy 207.726066 -276.040629) (xy 207.710534 -276.092258) (xy 207.687649 -276.141075)
			(xy 207.657901 -276.186039) (xy 207.621923 -276.226193) (xy 207.580481 -276.260681) (xy 207.53446 -276.288767)
			(xy 207.48484 -276.309854) (xy 207.432679 -276.32349) (xy 207.379088 -276.329387) (xy 207.325209 -276.327418)
			(xy 207.272191 -276.317625) (xy 207.221164 -276.300217) (xy 207.173216 -276.275565) (xy 207.129368 -276.244195)
			(xy 207.090555 -276.206774) (xy 207.057603 -276.164101) (xy 207.031217 -276.117084) (xy 207.011957 -276.066727)
			(xy 207.000234 -276.014103) (xy 206.996299 -275.960332) (xy 206.581502 -275.960332) (xy 206.581502 -276.006814)
			(xy 206.589122 -276.025356) (xy 206.596488 -276.032722) (xy 206.619374 -276.056085) (xy 206.659458 -276.107762)
			(xy 206.692395 -276.164263) (xy 206.717614 -276.224606) (xy 206.734675 -276.287742) (xy 206.743282 -276.352574)
			(xy 206.743808 -276.385274) (xy 206.743319 -276.416437) (xy 206.735507 -276.478271) (xy 206.720007 -276.538639)
			(xy 206.697064 -276.596587) (xy 206.667038 -276.651204) (xy 206.630404 -276.701626) (xy 206.587739 -276.74706)
			(xy 206.539717 -276.786788) (xy 206.487093 -276.820183) (xy 206.430699 -276.84672) (xy 206.371424 -276.86598)
			(xy 206.310203 -276.877659) (xy 206.248 -276.881572) (xy 206.185797 -276.877659) (xy 206.124576 -276.86598)
			(xy 206.065301 -276.84672) (xy 206.008907 -276.820183) (xy 205.956283 -276.786788) (xy 205.908261 -276.74706)
			(xy 205.865596 -276.701626) (xy 205.828962 -276.651204) (xy 205.798936 -276.596587) (xy 205.775993 -276.538639)
			(xy 205.760493 -276.478271) (xy 205.752681 -276.416437) (xy 205.752192 -276.385274) (xy 202.64374 -276.385274)
			(xy 202.643251 -276.417996) (xy 202.634647 -276.482871) (xy 202.617587 -276.546051) (xy 202.592365 -276.606439)
			(xy 202.559421 -276.662985) (xy 202.519326 -276.714707) (xy 202.49642 -276.73808) (xy 202.489054 -276.745192)
			(xy 202.48118 -276.763988) (xy 202.48118 -276.81047) (xy 202.896231 -276.81047) (xy 202.900166 -276.756699)
			(xy 202.911889 -276.704075) (xy 202.931149 -276.653718) (xy 202.957535 -276.606701) (xy 202.990487 -276.564028)
			(xy 203.0293 -276.526607) (xy 203.073148 -276.495237) (xy 203.121096 -276.470585) (xy 203.172123 -276.453177)
			(xy 203.225141 -276.443384) (xy 203.27902 -276.441415) (xy 203.332611 -276.447312) (xy 203.384772 -276.460948)
			(xy 203.434392 -276.482035) (xy 203.480413 -276.510121) (xy 203.521855 -276.544609) (xy 203.557833 -276.584763)
			(xy 203.587581 -276.629727) (xy 203.610466 -276.678544) (xy 203.625998 -276.730173) (xy 203.633848 -276.783513)
			(xy 203.63434 -276.81047) (xy 203.633848 -276.837427) (xy 203.625998 -276.890767) (xy 203.610466 -276.942396)
			(xy 203.587581 -276.991213) (xy 203.557833 -277.036177) (xy 203.521855 -277.076331) (xy 203.480413 -277.110819)
			(xy 203.434392 -277.138905) (xy 203.384772 -277.159992) (xy 203.332611 -277.173628) (xy 203.27902 -277.179525)
			(xy 203.225141 -277.177556) (xy 203.172123 -277.167763) (xy 203.121096 -277.150355) (xy 203.073148 -277.125703)
			(xy 203.0293 -277.094333) (xy 202.990487 -277.056912) (xy 202.957535 -277.014239) (xy 202.931149 -276.967222)
			(xy 202.911889 -276.916865) (xy 202.900166 -276.864241) (xy 202.896231 -276.81047) (xy 202.48118 -276.81047)
			(xy 202.48118 -276.856698) (xy 202.489054 -276.875494) (xy 202.49642 -276.882606) (xy 202.51933 -276.905973)
			(xy 202.559413 -276.957702) (xy 202.592346 -277.014251) (xy 202.61756 -277.07464) (xy 202.634615 -277.137819)
			(xy 202.643217 -277.202692) (xy 202.64374 -277.235412) (xy 204.494399 -277.235412) (xy 204.498334 -277.181641)
			(xy 204.510057 -277.129017) (xy 204.529317 -277.07866) (xy 204.555703 -277.031643) (xy 204.588655 -276.98897)
			(xy 204.627468 -276.951549) (xy 204.671316 -276.920179) (xy 204.719264 -276.895527) (xy 204.770291 -276.878119)
			(xy 204.823309 -276.868326) (xy 204.877188 -276.866357) (xy 204.930779 -276.872254) (xy 204.98294 -276.88589)
			(xy 205.03256 -276.906977) (xy 205.078581 -276.935063) (xy 205.120023 -276.969551) (xy 205.156001 -277.009705)
			(xy 205.185749 -277.054669) (xy 205.208634 -277.103486) (xy 205.224166 -277.155115) (xy 205.232016 -277.208455)
			(xy 205.232508 -277.235412) (xy 205.232016 -277.262369) (xy 205.224166 -277.315709) (xy 205.208634 -277.367338)
			(xy 205.185749 -277.416155) (xy 205.156001 -277.461119) (xy 205.120023 -277.501273) (xy 205.078581 -277.535761)
			(xy 205.03256 -277.563847) (xy 204.98294 -277.584934) (xy 204.930779 -277.59857) (xy 204.877188 -277.604467)
			(xy 204.823309 -277.602498) (xy 204.770291 -277.592705) (xy 204.719264 -277.575297) (xy 204.671316 -277.550645)
			(xy 204.627468 -277.519275) (xy 204.588655 -277.481854) (xy 204.555703 -277.439181) (xy 204.529317 -277.392164)
			(xy 204.510057 -277.341807) (xy 204.498334 -277.289183) (xy 204.494399 -277.235412) (xy 202.64374 -277.235412)
			(xy 202.643251 -277.266575) (xy 202.635439 -277.328409) (xy 202.619939 -277.388777) (xy 202.596996 -277.446725)
			(xy 202.56697 -277.501342) (xy 202.530336 -277.551764) (xy 202.487671 -277.597198) (xy 202.439649 -277.636926)
			(xy 202.387025 -277.670321) (xy 202.330631 -277.696858) (xy 202.271356 -277.716118) (xy 202.210135 -277.727797)
			(xy 202.147932 -277.73171) (xy 202.085729 -277.727797) (xy 202.024508 -277.716118) (xy 201.965233 -277.696858)
			(xy 201.908839 -277.670321) (xy 201.856215 -277.636926) (xy 201.808193 -277.597198) (xy 201.765528 -277.551764)
			(xy 201.728894 -277.501342) (xy 201.698868 -277.446725) (xy 201.675925 -277.388777) (xy 201.660425 -277.328409)
			(xy 201.652613 -277.266575) (xy 201.652124 -277.235412) (xy 197.688708 -277.235412) (xy 197.688216 -277.262369)
			(xy 197.680366 -277.315709) (xy 197.664834 -277.367338) (xy 197.641949 -277.416155) (xy 197.612201 -277.461119)
			(xy 197.576223 -277.501273) (xy 197.534781 -277.535761) (xy 197.48876 -277.563847) (xy 197.43914 -277.584934)
			(xy 197.386979 -277.59857) (xy 197.333388 -277.604467) (xy 197.279509 -277.602498) (xy 197.226491 -277.592705)
			(xy 197.175464 -277.575297) (xy 197.127516 -277.550645) (xy 197.083668 -277.519275) (xy 197.044855 -277.481854)
			(xy 197.011903 -277.439181) (xy 196.985517 -277.392164) (xy 196.966257 -277.341807) (xy 196.954534 -277.289183)
			(xy 196.950599 -277.235412) (xy 195.09994 -277.235412) (xy 195.099451 -277.266575) (xy 195.091639 -277.328409)
			(xy 195.076139 -277.388777) (xy 195.053196 -277.446725) (xy 195.02317 -277.501342) (xy 194.986536 -277.551764)
			(xy 194.943871 -277.597198) (xy 194.895849 -277.636926) (xy 194.843225 -277.670321) (xy 194.786831 -277.696858)
			(xy 194.727556 -277.716118) (xy 194.666335 -277.727797) (xy 194.604132 -277.73171) (xy 194.541929 -277.727797)
			(xy 194.480708 -277.716118) (xy 194.421433 -277.696858) (xy 194.365039 -277.670321) (xy 194.312415 -277.636926)
			(xy 194.264393 -277.597198) (xy 194.221728 -277.551764) (xy 194.185094 -277.501342) (xy 194.155068 -277.446725)
			(xy 194.132125 -277.388777) (xy 194.116625 -277.328409) (xy 194.108813 -277.266575) (xy 194.108324 -277.235412)
			(xy 190.144654 -277.235412) (xy 190.144162 -277.262369) (xy 190.136312 -277.315709) (xy 190.12078 -277.367338)
			(xy 190.097895 -277.416155) (xy 190.068147 -277.461119) (xy 190.032169 -277.501273) (xy 189.990727 -277.535761)
			(xy 189.944706 -277.563847) (xy 189.895086 -277.584934) (xy 189.842925 -277.59857) (xy 189.789334 -277.604467)
			(xy 189.735455 -277.602498) (xy 189.682437 -277.592705) (xy 189.63141 -277.575297) (xy 189.583462 -277.550645)
			(xy 189.539614 -277.519275) (xy 189.500801 -277.481854) (xy 189.467849 -277.439181) (xy 189.441463 -277.392164)
			(xy 189.422203 -277.341807) (xy 189.41048 -277.289183) (xy 189.406545 -277.235412) (xy 187.555886 -277.235412)
			(xy 187.555397 -277.266575) (xy 187.547585 -277.328409) (xy 187.532085 -277.388777) (xy 187.509142 -277.446725)
			(xy 187.479116 -277.501342) (xy 187.442482 -277.551764) (xy 187.399817 -277.597198) (xy 187.351795 -277.636926)
			(xy 187.299171 -277.670321) (xy 187.242777 -277.696858) (xy 187.183502 -277.716118) (xy 187.122281 -277.727797)
			(xy 187.060078 -277.73171) (xy 186.997875 -277.727797) (xy 186.936654 -277.716118) (xy 186.877379 -277.696858)
			(xy 186.820985 -277.670321) (xy 186.768361 -277.636926) (xy 186.720339 -277.597198) (xy 186.677674 -277.551764)
			(xy 186.64104 -277.501342) (xy 186.611014 -277.446725) (xy 186.588071 -277.388777) (xy 186.572571 -277.328409)
			(xy 186.564759 -277.266575) (xy 186.56427 -277.235412) (xy 185.96864 -277.235412) (xy 185.96864 -278.085296)
			(xy 188.075077 -278.085296) (xy 188.079012 -278.031525) (xy 188.090735 -277.978901) (xy 188.109995 -277.928544)
			(xy 188.136381 -277.881527) (xy 188.169333 -277.838854) (xy 188.208146 -277.801433) (xy 188.251994 -277.770063)
			(xy 188.299942 -277.745411) (xy 188.350969 -277.728003) (xy 188.403987 -277.71821) (xy 188.457866 -277.716241)
			(xy 188.511457 -277.722138) (xy 188.563618 -277.735774) (xy 188.613238 -277.756861) (xy 188.659259 -277.784947)
			(xy 188.700701 -277.819435) (xy 188.736679 -277.859589) (xy 188.766427 -277.904553) (xy 188.789312 -277.95337)
			(xy 188.804844 -278.004999) (xy 188.812694 -278.058339) (xy 188.813186 -278.085296) (xy 188.812694 -278.112253)
			(xy 188.804844 -278.165593) (xy 188.789312 -278.217222) (xy 188.766427 -278.266039) (xy 188.736679 -278.311003)
			(xy 188.700701 -278.351157) (xy 188.659259 -278.385645) (xy 188.613238 -278.413731) (xy 188.563618 -278.434818)
			(xy 188.511457 -278.448454) (xy 188.457866 -278.454351) (xy 188.403987 -278.452382) (xy 188.350969 -278.442589)
			(xy 188.299942 -278.425181) (xy 188.251994 -278.400529) (xy 188.208146 -278.369159) (xy 188.169333 -278.331738)
			(xy 188.136381 -278.289065) (xy 188.109995 -278.242048) (xy 188.090735 -278.191691) (xy 188.079012 -278.139067)
			(xy 188.075077 -278.085296) (xy 185.96864 -278.085296) (xy 185.96864 -284.035246) (xy 186.56427 -284.035246)
			(xy 186.564756 -284.00405) (xy 186.572572 -283.942148) (xy 186.588099 -283.881719) (xy 186.611091 -283.823717)
			(xy 186.641183 -283.769061) (xy 186.6779 -283.718616) (xy 186.720661 -283.67318) (xy 186.768788 -283.633474)
			(xy 186.794902 -283.6164) (xy 186.805062 -283.609796) (xy 186.817254 -283.589984) (xy 186.826652 -283.485844)
			(xy 186.81827 -283.464254) (xy 186.80938 -283.455872) (xy 186.791078 -283.438373) (xy 186.759001 -283.399193)
			(xy 186.732585 -283.355992) (xy 186.712327 -283.309585) (xy 186.698608 -283.260842) (xy 186.691686 -283.21068)
			(xy 186.69127 -283.185362) (xy 186.691686 -283.160014) (xy 186.698623 -283.109794) (xy 186.712374 -283.060999)
			(xy 186.73268 -283.014547) (xy 186.759159 -282.971315) (xy 186.791311 -282.932118) (xy 186.809634 -282.914598)
			(xy 186.818524 -282.90647) (xy 186.826906 -282.884626) (xy 186.817254 -282.780486) (xy 186.805062 -282.760674)
			(xy 186.794902 -282.754324) (xy 186.768795 -282.737218) (xy 186.720673 -282.697467) (xy 186.677917 -282.651994)
			(xy 186.641202 -282.601517) (xy 186.611109 -282.546834) (xy 186.588112 -282.488808) (xy 186.572574 -282.428356)
			(xy 186.564743 -282.366432) (xy 186.56427 -282.335224) (xy 186.564739 -282.304027) (xy 186.572558 -282.242125)
			(xy 186.588087 -282.181695) (xy 186.611081 -282.123693) (xy 186.641176 -282.069037) (xy 186.677896 -282.018592)
			(xy 186.720658 -281.973157) (xy 186.768788 -281.933451) (xy 186.794902 -281.916378) (xy 186.805062 -281.909774)
			(xy 186.817254 -281.889962) (xy 186.826652 -281.785822) (xy 186.81827 -281.764232) (xy 186.80938 -281.75585)
			(xy 186.791116 -281.738313) (xy 186.759035 -281.699141) (xy 186.732614 -281.655949) (xy 186.712349 -281.609548)
			(xy 186.698622 -281.560812) (xy 186.691691 -281.510656) (xy 186.69127 -281.48534) (xy 186.691671 -281.459991)
			(xy 186.698611 -281.409771) (xy 186.712365 -281.360975) (xy 186.732674 -281.314524) (xy 186.759156 -281.271292)
			(xy 186.79131 -281.232096) (xy 186.809634 -281.214576) (xy 186.818524 -281.206448) (xy 186.826906 -281.184604)
			(xy 186.817254 -281.080464) (xy 186.805062 -281.060652) (xy 186.794902 -281.054302) (xy 186.768785 -281.037211)
			(xy 186.720663 -280.997458) (xy 186.677907 -280.951982) (xy 186.641193 -280.901504) (xy 186.611101 -280.846818)
			(xy 186.588106 -280.78879) (xy 186.572571 -280.728336) (xy 186.564741 -280.666411) (xy 186.56427 -280.635202)
			(xy 186.564722 -280.604005) (xy 186.572543 -280.542102) (xy 186.588075 -280.481671) (xy 186.611072 -280.423669)
			(xy 186.641169 -280.369013) (xy 186.677891 -280.318569) (xy 186.720656 -280.273134) (xy 186.768787 -280.233429)
			(xy 186.794902 -280.216356) (xy 186.805062 -280.209752) (xy 186.817254 -280.18994) (xy 186.826652 -280.0858)
			(xy 186.81827 -280.06421) (xy 186.80938 -280.055828) (xy 186.789474 -280.036673) (xy 186.75501 -279.9935)
			(xy 186.727371 -279.94567) (xy 186.707175 -279.894253) (xy 186.694873 -279.840399) (xy 186.69074 -279.785312)
			(xy 186.694869 -279.730225) (xy 186.707168 -279.67637) (xy 186.727361 -279.624952) (xy 186.754997 -279.57712)
			(xy 186.789457 -279.533945) (xy 186.80938 -279.514808) (xy 186.81827 -279.506426) (xy 186.826652 -279.484836)
			(xy 186.817254 -279.380696) (xy 186.805062 -279.360884) (xy 186.794902 -279.35428) (xy 186.768788 -279.337209)
			(xy 186.720671 -279.297492) (xy 186.677918 -279.252051) (xy 186.641205 -279.201605) (xy 186.611112 -279.146951)
			(xy 186.588114 -279.088953) (xy 186.572576 -279.028527) (xy 186.564743 -278.96663) (xy 186.56427 -278.935434)
			(xy 186.564759 -278.904271) (xy 186.572571 -278.842437) (xy 186.588071 -278.782069) (xy 186.611014 -278.724121)
			(xy 186.64104 -278.669504) (xy 186.677674 -278.619082) (xy 186.720339 -278.573648) (xy 186.768361 -278.53392)
			(xy 186.820985 -278.500525) (xy 186.877379 -278.473988) (xy 186.936654 -278.454728) (xy 186.997875 -278.443049)
			(xy 187.060078 -278.439136) (xy 187.122281 -278.443049) (xy 187.183502 -278.454728) (xy 187.242777 -278.473988)
			(xy 187.299171 -278.500525) (xy 187.351795 -278.53392) (xy 187.399817 -278.573648) (xy 187.442482 -278.619082)
			(xy 187.479116 -278.669504) (xy 187.509142 -278.724121) (xy 187.532085 -278.782069) (xy 187.547585 -278.842437)
			(xy 187.555397 -278.904271) (xy 187.555886 -278.935434) (xy 187.555404 -278.966631) (xy 187.54759 -279.028533)
			(xy 187.532064 -279.088964) (xy 187.509073 -279.146967) (xy 187.478979 -279.201623) (xy 187.442261 -279.252068)
			(xy 187.399498 -279.297502) (xy 187.351369 -279.337207) (xy 187.325254 -279.35428) (xy 187.315094 -279.360884)
			(xy 187.302902 -279.380696) (xy 187.293504 -279.484836) (xy 187.301886 -279.506426) (xy 187.310776 -279.514808)
			(xy 187.33072 -279.533926) (xy 187.365187 -279.577103) (xy 187.392828 -279.624938) (xy 187.413026 -279.67636)
			(xy 187.425327 -279.73022) (xy 187.429457 -279.785312) (xy 187.425323 -279.840404) (xy 187.413018 -279.894263)
			(xy 187.392818 -279.945685) (xy 187.365173 -279.993518) (xy 187.330704 -280.036692) (xy 187.310776 -280.055828)
			(xy 187.301886 -280.06421) (xy 187.293504 -280.0858) (xy 187.302902 -280.18994) (xy 187.315094 -280.209752)
			(xy 187.325254 -280.216356) (xy 187.351374 -280.233418) (xy 187.399493 -280.273135) (xy 187.442248 -280.318576)
			(xy 187.478961 -280.369023) (xy 187.509054 -280.423679) (xy 187.53205 -280.481679) (xy 187.547585 -280.542107)
			(xy 187.555415 -280.604006) (xy 187.555886 -280.635202) (xy 187.555394 -280.666411) (xy 187.547574 -280.728337)
			(xy 187.532046 -280.788792) (xy 187.509056 -280.846821) (xy 187.478965 -280.901507) (xy 187.442251 -280.951985)
			(xy 187.399493 -280.997458) (xy 187.351368 -281.037206) (xy 187.325254 -281.054302) (xy 187.315094 -281.060652)
			(xy 187.302902 -281.080464) (xy 187.29325 -281.184604) (xy 187.301632 -281.206448) (xy 187.310522 -281.214576)
			(xy 187.328834 -281.232106) (xy 187.360977 -281.271307) (xy 187.387451 -281.314538) (xy 187.407757 -281.360987)
			(xy 187.421514 -281.409778) (xy 187.428462 -281.459993) (xy 187.428886 -281.48534) (xy 187.428442 -281.510657)
			(xy 187.421523 -281.560815) (xy 187.407806 -281.609554) (xy 187.38755 -281.655959) (xy 187.361135 -281.699156)
			(xy 187.329059 -281.738333) (xy 187.310776 -281.75585) (xy 187.301886 -281.764232) (xy 187.293504 -281.785822)
			(xy 187.302902 -281.889962) (xy 187.315094 -281.909774) (xy 187.325254 -281.916378) (xy 187.351339 -281.933493)
			(xy 187.399458 -281.973202) (xy 187.442214 -282.018635) (xy 187.47893 -282.069075) (xy 187.509027 -282.123723)
			(xy 187.532029 -282.181716) (xy 187.547572 -282.242137) (xy 187.55541 -282.30403) (xy 187.555886 -282.335224)
			(xy 187.555411 -282.366433) (xy 187.547589 -282.42836) (xy 187.532058 -282.488816) (xy 187.509065 -282.546845)
			(xy 187.478972 -282.601531) (xy 187.442256 -282.652009) (xy 187.399496 -282.697481) (xy 187.351369 -282.737228)
			(xy 187.325254 -282.754324) (xy 187.315094 -282.760674) (xy 187.302902 -282.780486) (xy 187.29325 -282.884626)
			(xy 187.301632 -282.90647) (xy 187.310522 -282.914598) (xy 187.328845 -282.932118) (xy 187.360987 -282.97132)
			(xy 187.387459 -283.014554) (xy 187.407764 -283.061005) (xy 187.421518 -283.109798) (xy 187.428463 -283.160015)
			(xy 187.428886 -283.185362) (xy 190.664338 -283.185362) (xy 190.664791 -283.154152) (xy 190.672615 -283.092224)
			(xy 190.688148 -283.031767) (xy 190.711145 -282.973737) (xy 190.74124 -282.919051) (xy 190.77796 -282.868574)
			(xy 190.820723 -282.823103) (xy 190.868854 -282.783357) (xy 190.89497 -282.766262) (xy 190.90513 -282.759912)
			(xy 190.917322 -282.7401) (xy 190.926974 -282.63596) (xy 190.918592 -282.614116) (xy 190.909702 -282.605988)
			(xy 190.891377 -282.588471) (xy 190.859234 -282.549268) (xy 190.832762 -282.506034) (xy 190.812457 -282.459583)
			(xy 190.798704 -282.410789) (xy 190.79176 -282.360572) (xy 190.791338 -282.335224) (xy 190.79175 -282.309906)
			(xy 190.798675 -282.259746) (xy 190.812398 -282.211006) (xy 190.83266 -282.164601) (xy 190.85908 -282.121405)
			(xy 190.891163 -282.08223) (xy 190.909448 -282.064714) (xy 190.918338 -282.056332) (xy 190.92672 -282.034742)
			(xy 190.917322 -281.930602) (xy 190.90513 -281.91079) (xy 190.89497 -281.904186) (xy 190.868851 -281.887122)
			(xy 190.820736 -281.847403) (xy 190.777984 -281.80196) (xy 190.741272 -281.751513) (xy 190.71118 -281.696858)
			(xy 190.688183 -281.638859) (xy 190.672645 -281.578434) (xy 190.664811 -281.516536) (xy 190.664338 -281.48534)
			(xy 190.664774 -281.454129) (xy 190.672601 -281.392201) (xy 190.688137 -281.331743) (xy 190.711135 -281.273713)
			(xy 190.741233 -281.219027) (xy 190.777955 -281.16855) (xy 190.82072 -281.12308) (xy 190.868853 -281.083334)
			(xy 190.89497 -281.06624) (xy 190.90513 -281.05989) (xy 190.917322 -281.040078) (xy 190.926974 -280.935938)
			(xy 190.918592 -280.914094) (xy 190.909702 -280.905966) (xy 190.891366 -280.888459) (xy 190.859225 -280.849254)
			(xy 190.832753 -280.806018) (xy 190.812451 -280.759565) (xy 190.798699 -280.710769) (xy 190.791758 -280.66055)
			(xy 190.791338 -280.635202) (xy 190.791735 -280.609884) (xy 190.798663 -280.559723) (xy 190.812388 -280.510982)
			(xy 190.832653 -280.464577) (xy 190.859076 -280.421382) (xy 190.891161 -280.382207) (xy 190.909448 -280.364692)
			(xy 190.918338 -280.35631) (xy 190.92672 -280.33472) (xy 190.917322 -280.23058) (xy 190.90513 -280.210768)
			(xy 190.89497 -280.204164) (xy 190.868873 -280.187064) (xy 190.820746 -280.147357) (xy 190.777983 -280.101923)
			(xy 190.741262 -280.051482) (xy 190.711162 -279.996829) (xy 190.68816 -279.938832) (xy 190.67262 -279.878405)
			(xy 190.664787 -279.816506) (xy 190.664786 -279.754113) (xy 190.672616 -279.692214) (xy 190.688154 -279.631787)
			(xy 190.711154 -279.573788) (xy 190.741251 -279.519135) (xy 190.777971 -279.468692) (xy 190.820732 -279.423256)
			(xy 190.868858 -279.383548) (xy 190.89497 -279.366472) (xy 190.90513 -279.359868) (xy 190.917322 -279.340056)
			(xy 190.92672 -279.235916) (xy 190.918338 -279.214326) (xy 190.909448 -279.205944) (xy 190.891175 -279.188416)
			(xy 190.859096 -279.149241) (xy 190.832677 -279.106047) (xy 190.812414 -279.059645) (xy 190.798689 -279.010907)
			(xy 190.791759 -278.960751) (xy 190.791338 -278.935434) (xy 190.791713 -278.910084) (xy 190.798655 -278.859862)
			(xy 190.812413 -278.811065) (xy 190.832727 -278.764613) (xy 190.859214 -278.721382) (xy 190.891374 -278.682188)
			(xy 190.909702 -278.66467) (xy 190.918592 -278.656542) (xy 190.926974 -278.634698) (xy 190.917322 -278.530558)
			(xy 190.90513 -278.510746) (xy 190.89497 -278.504396) (xy 190.868843 -278.48732) (xy 190.820722 -278.447564)
			(xy 190.777968 -278.402086) (xy 190.741255 -278.351604) (xy 190.711165 -278.296917) (xy 190.688171 -278.238887)
			(xy 190.672637 -278.178432) (xy 190.664808 -278.116506) (xy 190.664338 -278.085296) (xy 190.664827 -278.054133)
			(xy 190.672639 -277.992299) (xy 190.688139 -277.931931) (xy 190.711082 -277.873983) (xy 190.741108 -277.819366)
			(xy 190.777742 -277.768944) (xy 190.820407 -277.72351) (xy 190.868429 -277.683782) (xy 190.921053 -277.650387)
			(xy 190.977447 -277.62385) (xy 191.036722 -277.60459) (xy 191.097943 -277.592911) (xy 191.160146 -277.588998)
			(xy 191.222349 -277.592911) (xy 191.28357 -277.60459) (xy 191.342845 -277.62385) (xy 191.399239 -277.650387)
			(xy 191.451863 -277.683782) (xy 191.499885 -277.72351) (xy 191.54255 -277.768944) (xy 191.579184 -277.819366)
			(xy 191.60921 -277.873983) (xy 191.632153 -277.931931) (xy 191.647653 -277.992299) (xy 191.655465 -278.054133)
			(xy 191.655954 -278.085296) (xy 195.619131 -278.085296) (xy 195.623066 -278.031525) (xy 195.634789 -277.978901)
			(xy 195.654049 -277.928544) (xy 195.680435 -277.881527) (xy 195.713387 -277.838854) (xy 195.7522 -277.801433)
			(xy 195.796048 -277.770063) (xy 195.843996 -277.745411) (xy 195.895023 -277.728003) (xy 195.948041 -277.71821)
			(xy 196.00192 -277.716241) (xy 196.055511 -277.722138) (xy 196.107672 -277.735774) (xy 196.157292 -277.756861)
			(xy 196.203313 -277.784947) (xy 196.244755 -277.819435) (xy 196.280733 -277.859589) (xy 196.310481 -277.904553)
			(xy 196.333366 -277.95337) (xy 196.348898 -278.004999) (xy 196.356748 -278.058339) (xy 196.35724 -278.085296)
			(xy 196.356748 -278.112253) (xy 196.348898 -278.165593) (xy 196.333366 -278.217222) (xy 196.310481 -278.266039)
			(xy 196.280733 -278.311003) (xy 196.244755 -278.351157) (xy 196.203313 -278.385645) (xy 196.157292 -278.413731)
			(xy 196.107672 -278.434818) (xy 196.055511 -278.448454) (xy 196.00192 -278.454351) (xy 195.948041 -278.452382)
			(xy 195.895023 -278.442589) (xy 195.843996 -278.425181) (xy 195.796048 -278.400529) (xy 195.7522 -278.369159)
			(xy 195.713387 -278.331738) (xy 195.680435 -278.289065) (xy 195.654049 -278.242048) (xy 195.634789 -278.191691)
			(xy 195.623066 -278.139067) (xy 195.619131 -278.085296) (xy 191.655954 -278.085296) (xy 191.655472 -278.116505)
			(xy 191.647653 -278.178432) (xy 191.632124 -278.238889) (xy 191.609132 -278.296918) (xy 191.579041 -278.351605)
			(xy 191.542325 -278.402082) (xy 191.499565 -278.447554) (xy 191.451437 -278.487301) (xy 191.425322 -278.504396)
			(xy 191.415162 -278.510746) (xy 191.40297 -278.530558) (xy 191.393318 -278.634698) (xy 191.4017 -278.656542)
			(xy 191.41059 -278.66467) (xy 191.428893 -278.682209) (xy 191.461038 -278.721407) (xy 191.487514 -278.764636)
			(xy 191.507822 -278.811084) (xy 191.52158 -278.859874) (xy 191.528529 -278.910088) (xy 191.528954 -278.935434)
			(xy 191.528516 -278.960751) (xy 191.521597 -279.01091) (xy 191.50788 -279.05965) (xy 191.487622 -279.106055)
			(xy 191.461206 -279.149252) (xy 191.429128 -279.188428) (xy 191.410844 -279.205944) (xy 191.401954 -279.214326)
			(xy 191.393572 -279.235916) (xy 191.40297 -279.340056) (xy 191.415162 -279.359868) (xy 191.425322 -279.366472)
			(xy 191.451453 -279.383523) (xy 191.499582 -279.423233) (xy 191.542346 -279.468671) (xy 191.579069 -279.519117)
			(xy 191.609169 -279.573774) (xy 191.63217 -279.631777) (xy 191.647709 -279.692208) (xy 191.65554 -279.754111)
			(xy 191.655539 -279.816508) (xy 191.647706 -279.878411) (xy 191.632164 -279.938842) (xy 191.60916 -279.996843)
			(xy 191.579058 -280.051499) (xy 191.542334 -280.101944) (xy 191.499568 -280.14738) (xy 191.451437 -280.187088)
			(xy 191.425322 -280.204164) (xy 191.415162 -280.210768) (xy 191.40297 -280.23058) (xy 191.393572 -280.33472)
			(xy 191.401954 -280.35631) (xy 191.410844 -280.364692) (xy 191.429133 -280.382204) (xy 191.461211 -280.421382)
			(xy 191.487628 -280.46458) (xy 191.507888 -280.510985) (xy 191.52161 -280.559725) (xy 191.528536 -280.609884)
			(xy 191.528954 -280.635202) (xy 191.528538 -280.660551) (xy 191.521605 -280.710771) (xy 191.507855 -280.759568)
			(xy 191.487549 -280.80602) (xy 191.461069 -280.849251) (xy 191.428915 -280.888447) (xy 191.41059 -280.905966)
			(xy 191.4017 -280.914094) (xy 191.393318 -280.935938) (xy 191.40297 -281.040078) (xy 191.415162 -281.05989)
			(xy 191.425322 -281.06624) (xy 191.451418 -281.083362) (xy 191.49954 -281.123111) (xy 191.542295 -281.168582)
			(xy 191.57901 -281.219057) (xy 191.609105 -281.273738) (xy 191.632104 -281.331761) (xy 191.647644 -281.392211)
			(xy 191.65548 -281.454132) (xy 191.655954 -281.48534) (xy 191.655445 -281.516536) (xy 191.647632 -281.578436)
			(xy 191.632107 -281.638864) (xy 191.609119 -281.696866) (xy 191.579029 -281.751522) (xy 191.542315 -281.801967)
			(xy 191.499558 -281.847403) (xy 191.451434 -281.887111) (xy 191.425322 -281.904186) (xy 191.415162 -281.91079)
			(xy 191.40297 -281.930602) (xy 191.393572 -282.034742) (xy 191.401954 -282.056332) (xy 191.410844 -282.064714)
			(xy 191.429144 -282.082215) (xy 191.46122 -282.121396) (xy 191.487636 -282.164596) (xy 191.507894 -282.211003)
			(xy 191.521614 -282.259745) (xy 191.528537 -282.309906) (xy 191.528954 -282.335224) (xy 191.528553 -282.360573)
			(xy 191.521617 -282.410794) (xy 191.507864 -282.459591) (xy 191.487555 -282.506043) (xy 191.461072 -282.549274)
			(xy 191.428916 -282.588469) (xy 191.41059 -282.605988) (xy 191.4017 -282.614116) (xy 191.393318 -282.63596)
			(xy 191.40297 -282.7401) (xy 191.415162 -282.759912) (xy 191.425322 -282.766262) (xy 191.451428 -282.783369)
			(xy 191.49955 -282.823121) (xy 191.542305 -282.868594) (xy 191.579019 -282.91907) (xy 191.609113 -282.973753)
			(xy 191.63211 -283.031779) (xy 191.647648 -283.092231) (xy 191.655481 -283.154154) (xy 191.655954 -283.185362)
			(xy 191.655465 -283.216525) (xy 191.647653 -283.278359) (xy 191.632153 -283.338727) (xy 191.60921 -283.396675)
			(xy 191.579184 -283.451292) (xy 191.54255 -283.501714) (xy 191.499885 -283.547148) (xy 191.451863 -283.586876)
			(xy 191.399239 -283.620271) (xy 191.342845 -283.646808) (xy 191.28357 -283.666068) (xy 191.222349 -283.677747)
			(xy 191.160146 -283.68166) (xy 191.097943 -283.677747) (xy 191.036722 -283.666068) (xy 190.977447 -283.646808)
			(xy 190.921053 -283.620271) (xy 190.868429 -283.586876) (xy 190.820407 -283.547148) (xy 190.777742 -283.501714)
			(xy 190.741108 -283.451292) (xy 190.711082 -283.396675) (xy 190.688139 -283.338727) (xy 190.672639 -283.278359)
			(xy 190.664827 -283.216525) (xy 190.664338 -283.185362) (xy 187.428886 -283.185362) (xy 187.428457 -283.210679)
			(xy 187.421535 -283.260838) (xy 187.407815 -283.309578) (xy 187.387556 -283.355983) (xy 187.361139 -283.399179)
			(xy 187.32906 -283.438356) (xy 187.310776 -283.455872) (xy 187.301886 -283.464254) (xy 187.293504 -283.485844)
			(xy 187.302902 -283.589984) (xy 187.315094 -283.609796) (xy 187.325254 -283.6164) (xy 187.351349 -283.6335)
			(xy 187.399468 -283.673211) (xy 187.442223 -283.718647) (xy 187.478939 -283.769088) (xy 187.509035 -283.823739)
			(xy 187.532035 -283.881734) (xy 187.547576 -283.942156) (xy 187.555412 -284.004051) (xy 187.555886 -284.035246)
			(xy 189.406545 -284.035246) (xy 189.41048 -283.981475) (xy 189.422203 -283.928851) (xy 189.441463 -283.878494)
			(xy 189.467849 -283.831477) (xy 189.500801 -283.788804) (xy 189.539614 -283.751383) (xy 189.583462 -283.720013)
			(xy 189.63141 -283.695361) (xy 189.682437 -283.677953) (xy 189.735455 -283.66816) (xy 189.789334 -283.666191)
			(xy 189.842925 -283.672088) (xy 189.895086 -283.685724) (xy 189.944706 -283.706811) (xy 189.990727 -283.734897)
			(xy 190.032169 -283.769385) (xy 190.068147 -283.809539) (xy 190.097895 -283.854503) (xy 190.12078 -283.90332)
			(xy 190.136312 -283.954949) (xy 190.144162 -284.008289) (xy 190.144654 -284.035246) (xy 194.108324 -284.035246)
			(xy 194.108785 -284.004049) (xy 194.116602 -283.942145) (xy 194.132131 -283.881714) (xy 194.155125 -283.823711)
			(xy 194.185221 -283.769054) (xy 194.221943 -283.71861) (xy 194.264708 -283.673176) (xy 194.31284 -283.633472)
			(xy 194.338956 -283.6164) (xy 194.349116 -283.609796) (xy 194.361308 -283.589984) (xy 194.370706 -283.485844)
			(xy 194.362324 -283.464254) (xy 194.353434 -283.455872) (xy 194.335123 -283.438382) (xy 194.303048 -283.399199)
			(xy 194.276635 -283.355996) (xy 194.256379 -283.309587) (xy 194.242661 -283.260843) (xy 194.23574 -283.210681)
			(xy 194.235324 -283.185362) (xy 194.235723 -283.160013) (xy 194.24266 -283.109792) (xy 194.256414 -283.060995)
			(xy 194.276724 -283.014543) (xy 194.303206 -282.971312) (xy 194.335362 -282.932117) (xy 194.353688 -282.914598)
			(xy 194.362578 -282.90647) (xy 194.37096 -282.884626) (xy 194.361308 -282.780486) (xy 194.349116 -282.760674)
			(xy 194.338956 -282.754324) (xy 194.312838 -282.737234) (xy 194.264718 -282.697479) (xy 194.221964 -282.652003)
			(xy 194.185251 -282.601524) (xy 194.155159 -282.546839) (xy 194.132164 -282.488811) (xy 194.116627 -282.428358)
			(xy 194.108796 -282.366433) (xy 194.108324 -282.335224) (xy 194.108768 -282.304026) (xy 194.116588 -282.242122)
			(xy 194.132119 -282.18169) (xy 194.155116 -282.123687) (xy 194.185214 -282.069031) (xy 194.221938 -282.018586)
			(xy 194.264705 -281.973153) (xy 194.312839 -281.93345) (xy 194.338956 -281.916378) (xy 194.349116 -281.909774)
			(xy 194.361308 -281.889962) (xy 194.370706 -281.785822) (xy 194.362324 -281.764232) (xy 194.353434 -281.75585)
			(xy 194.335161 -281.738322) (xy 194.303083 -281.699147) (xy 194.276664 -281.655952) (xy 194.256401 -281.60955)
			(xy 194.242676 -281.560813) (xy 194.235745 -281.510657) (xy 194.235324 -281.48534) (xy 194.235708 -281.459991)
			(xy 194.242649 -281.409769) (xy 194.256405 -281.360972) (xy 194.276718 -281.31452) (xy 194.303203 -281.271289)
			(xy 194.335361 -281.232095) (xy 194.353688 -281.214576) (xy 194.362578 -281.206448) (xy 194.37096 -281.184604)
			(xy 194.361308 -281.080464) (xy 194.349116 -281.060652) (xy 194.338956 -281.054302) (xy 194.312828 -281.037227)
			(xy 194.264708 -280.99747) (xy 194.221954 -280.951991) (xy 194.185242 -280.90151) (xy 194.155152 -280.846823)
			(xy 194.132158 -280.788793) (xy 194.116624 -280.728338) (xy 194.108795 -280.666412) (xy 194.108324 -280.635202)
			(xy 194.108751 -280.604003) (xy 194.116573 -280.542099) (xy 194.132107 -280.481667) (xy 194.155107 -280.423663)
			(xy 194.185207 -280.369007) (xy 194.221933 -280.318563) (xy 194.264703 -280.27313) (xy 194.312838 -280.233427)
			(xy 194.338956 -280.216356) (xy 194.349116 -280.209752) (xy 194.361308 -280.18994) (xy 194.370706 -280.0858)
			(xy 194.362324 -280.06421) (xy 194.353434 -280.055828) (xy 194.333525 -280.036674) (xy 194.299057 -279.993503)
			(xy 194.271414 -279.945674) (xy 194.251214 -279.894256) (xy 194.23891 -279.840401) (xy 194.234777 -279.785312)
			(xy 194.238906 -279.730224) (xy 194.251207 -279.676367) (xy 194.271403 -279.624948) (xy 194.299043 -279.577117)
			(xy 194.333509 -279.533944) (xy 194.353434 -279.514808) (xy 194.362324 -279.506426) (xy 194.370706 -279.484836)
			(xy 194.361308 -279.380696) (xy 194.349116 -279.360884) (xy 194.338956 -279.35428) (xy 194.312854 -279.33719)
			(xy 194.264735 -279.297478) (xy 194.22198 -279.252041) (xy 194.185264 -279.201598) (xy 194.155169 -279.146946)
			(xy 194.13217 -279.08895) (xy 194.116631 -279.028525) (xy 194.108797 -278.966629) (xy 194.108324 -278.935434)
			(xy 194.108813 -278.904271) (xy 194.116625 -278.842437) (xy 194.132125 -278.782069) (xy 194.155068 -278.724121)
			(xy 194.185094 -278.669504) (xy 194.221728 -278.619082) (xy 194.264393 -278.573648) (xy 194.312415 -278.53392)
			(xy 194.365039 -278.500525) (xy 194.421433 -278.473988) (xy 194.480708 -278.454728) (xy 194.541929 -278.443049)
			(xy 194.604132 -278.439136) (xy 194.666335 -278.443049) (xy 194.727556 -278.454728) (xy 194.786831 -278.473988)
			(xy 194.843225 -278.500525) (xy 194.895849 -278.53392) (xy 194.943871 -278.573648) (xy 194.986536 -278.619082)
			(xy 195.02317 -278.669504) (xy 195.053196 -278.724121) (xy 195.076139 -278.782069) (xy 195.091639 -278.842437)
			(xy 195.099451 -278.904271) (xy 195.09994 -278.935434) (xy 195.099433 -278.96663) (xy 195.09162 -279.02853)
			(xy 195.076096 -279.088959) (xy 195.053107 -279.146961) (xy 195.023017 -279.201617) (xy 194.986303 -279.252062)
			(xy 194.943545 -279.297498) (xy 194.89542 -279.337206) (xy 194.869308 -279.35428) (xy 194.859148 -279.360884)
			(xy 194.846956 -279.380696) (xy 194.837558 -279.484836) (xy 194.84594 -279.506426) (xy 194.85483 -279.514808)
			(xy 194.874772 -279.533927) (xy 194.909234 -279.577106) (xy 194.936871 -279.624941) (xy 194.957065 -279.676363)
			(xy 194.969364 -279.730222) (xy 194.973493 -279.785312) (xy 194.96936 -279.840403) (xy 194.957058 -279.89426)
			(xy 194.93686 -279.945681) (xy 194.90922 -279.993514) (xy 194.874755 -280.036691) (xy 194.85483 -280.055828)
			(xy 194.84594 -280.06421) (xy 194.837558 -280.0858) (xy 194.846956 -280.18994) (xy 194.859148 -280.209752)
			(xy 194.869308 -280.216356) (xy 194.895441 -280.2334) (xy 194.943557 -280.273121) (xy 194.986309 -280.318566)
			(xy 195.023021 -280.369016) (xy 195.053111 -280.423674) (xy 195.076106 -280.481676) (xy 195.09164 -280.542105)
			(xy 195.099469 -280.604005) (xy 195.09994 -280.635202) (xy 195.099423 -280.66641) (xy 195.091604 -280.728334)
			(xy 195.076078 -280.788788) (xy 195.05309 -280.846816) (xy 195.023003 -280.901501) (xy 194.986293 -280.95198)
			(xy 194.94354 -280.997454) (xy 194.89542 -281.037204) (xy 194.869308 -281.054302) (xy 194.859148 -281.060652)
			(xy 194.846956 -281.080464) (xy 194.837304 -281.184604) (xy 194.845686 -281.206448) (xy 194.854576 -281.214576)
			(xy 194.872879 -281.232115) (xy 194.905025 -281.271313) (xy 194.931501 -281.314542) (xy 194.951809 -281.360989)
			(xy 194.965567 -281.409779) (xy 194.972516 -281.459994) (xy 194.97294 -281.48534) (xy 194.972511 -281.510657)
			(xy 194.96559 -281.560817) (xy 194.951872 -281.609557) (xy 194.931613 -281.655962) (xy 194.905195 -281.699159)
			(xy 194.873115 -281.738334) (xy 194.85483 -281.75585) (xy 194.84594 -281.764232) (xy 194.837558 -281.785822)
			(xy 194.846956 -281.889962) (xy 194.859148 -281.909774) (xy 194.869308 -281.916378) (xy 194.895405 -281.933474)
			(xy 194.943522 -281.973188) (xy 194.986275 -282.018625) (xy 195.02299 -282.069067) (xy 195.053085 -282.123718)
			(xy 195.076085 -282.181713) (xy 195.091627 -282.242135) (xy 195.099464 -282.30403) (xy 195.09994 -282.335224)
			(xy 195.09944 -282.366432) (xy 195.091619 -282.428357) (xy 195.07609 -282.488811) (xy 195.0531 -282.54684)
			(xy 195.02301 -282.601525) (xy 194.986298 -282.652003) (xy 194.943543 -282.697477) (xy 194.89542 -282.737227)
			(xy 194.869308 -282.754324) (xy 194.859148 -282.760674) (xy 194.846956 -282.780486) (xy 194.837304 -282.884626)
			(xy 194.845686 -282.90647) (xy 194.854576 -282.914598) (xy 194.87289 -282.932126) (xy 194.905034 -282.971326)
			(xy 194.931509 -283.014558) (xy 194.951816 -283.061007) (xy 194.965571 -283.109799) (xy 194.972517 -283.160015)
			(xy 194.97294 -283.185362) (xy 198.208392 -283.185362) (xy 198.208866 -283.154153) (xy 198.21669 -283.092226)
			(xy 198.232221 -283.031771) (xy 198.255215 -282.973742) (xy 198.285308 -282.919056) (xy 198.322024 -282.868579)
			(xy 198.364783 -282.823106) (xy 198.41291 -282.783358) (xy 198.439024 -282.766262) (xy 198.449184 -282.759912)
			(xy 198.461376 -282.7401) (xy 198.471028 -282.63596) (xy 198.462646 -282.614116) (xy 198.453756 -282.605988)
			(xy 198.435441 -282.58846) (xy 198.403296 -282.549261) (xy 198.37682 -282.506029) (xy 198.356514 -282.45958)
			(xy 198.342759 -282.410787) (xy 198.335814 -282.360571) (xy 198.335392 -282.335224) (xy 198.335819 -282.309907)
			(xy 198.342742 -282.259748) (xy 198.356463 -282.211008) (xy 198.376722 -282.164604) (xy 198.40314 -282.121407)
			(xy 198.435218 -282.082231) (xy 198.453502 -282.064714) (xy 198.462392 -282.056332) (xy 198.470774 -282.034742)
			(xy 198.461376 -281.930602) (xy 198.449184 -281.91079) (xy 198.439024 -281.904186) (xy 198.412918 -281.887103)
			(xy 198.3648 -281.847389) (xy 198.322046 -281.80195) (xy 198.285331 -281.751506) (xy 198.255237 -281.696853)
			(xy 198.232239 -281.638856) (xy 198.216699 -281.578432) (xy 198.208866 -281.516535) (xy 198.208392 -281.48534)
			(xy 198.208849 -281.45413) (xy 198.216675 -281.392203) (xy 198.232209 -281.331747) (xy 198.255206 -281.273718)
			(xy 198.285301 -281.219033) (xy 198.322019 -281.168555) (xy 198.36478 -281.123083) (xy 198.412909 -281.083336)
			(xy 198.439024 -281.06624) (xy 198.449184 -281.05989) (xy 198.461376 -281.040078) (xy 198.471028 -280.935938)
			(xy 198.462646 -280.914094) (xy 198.453756 -280.905966) (xy 198.435431 -280.888449) (xy 198.403286 -280.849247)
			(xy 198.376812 -280.806014) (xy 198.356507 -280.759562) (xy 198.342754 -280.710768) (xy 198.335812 -280.66055)
			(xy 198.335392 -280.635202) (xy 198.335804 -280.609884) (xy 198.342731 -280.559725) (xy 198.356454 -280.510985)
			(xy 198.376716 -280.464581) (xy 198.403136 -280.421384) (xy 198.435217 -280.382208) (xy 198.453502 -280.364692)
			(xy 198.462392 -280.35631) (xy 198.470774 -280.33472) (xy 198.461376 -280.23058) (xy 198.449184 -280.210768)
			(xy 198.439024 -280.204164) (xy 198.412925 -280.187065) (xy 198.364793 -280.147361) (xy 198.322026 -280.101929)
			(xy 198.2853 -280.051488) (xy 198.255197 -279.996835) (xy 198.232192 -279.938836) (xy 198.21665 -279.878408)
			(xy 198.208816 -279.816507) (xy 198.208815 -279.754112) (xy 198.216646 -279.692211) (xy 198.232186 -279.631782)
			(xy 198.255188 -279.573782) (xy 198.28529 -279.519129) (xy 198.322013 -279.468686) (xy 198.364779 -279.423252)
			(xy 198.412909 -279.383546) (xy 198.439024 -279.366472) (xy 198.449184 -279.359868) (xy 198.461376 -279.340056)
			(xy 198.470774 -279.235916) (xy 198.462392 -279.214326) (xy 198.453502 -279.205944) (xy 198.435239 -279.188406)
			(xy 198.403157 -279.149234) (xy 198.376736 -279.106043) (xy 198.356471 -279.059642) (xy 198.342744 -279.010906)
			(xy 198.335813 -278.96075) (xy 198.335392 -278.935434) (xy 198.335782 -278.910085) (xy 198.342723 -278.859864)
			(xy 198.356479 -278.811068) (xy 198.37679 -278.764616) (xy 198.403274 -278.721385) (xy 198.43543 -278.682189)
			(xy 198.453756 -278.66467) (xy 198.462646 -278.656542) (xy 198.471028 -278.634698) (xy 198.461376 -278.530558)
			(xy 198.449184 -278.510746) (xy 198.439024 -278.504396) (xy 198.412909 -278.487301) (xy 198.364786 -278.447549)
			(xy 198.32203 -278.402075) (xy 198.285315 -278.351597) (xy 198.255222 -278.296912) (xy 198.232227 -278.238884)
			(xy 198.216692 -278.17843) (xy 198.208863 -278.116505) (xy 198.208392 -278.085296) (xy 198.208881 -278.054133)
			(xy 198.216693 -277.992299) (xy 198.232193 -277.931931) (xy 198.255136 -277.873983) (xy 198.285162 -277.819366)
			(xy 198.321796 -277.768944) (xy 198.364461 -277.72351) (xy 198.412483 -277.683782) (xy 198.465107 -277.650387)
			(xy 198.521501 -277.62385) (xy 198.580776 -277.60459) (xy 198.641997 -277.592911) (xy 198.7042 -277.588998)
			(xy 198.766403 -277.592911) (xy 198.827624 -277.60459) (xy 198.886899 -277.62385) (xy 198.943293 -277.650387)
			(xy 198.995917 -277.683782) (xy 199.043939 -277.72351) (xy 199.086604 -277.768944) (xy 199.123238 -277.819366)
			(xy 199.153264 -277.873983) (xy 199.176207 -277.931931) (xy 199.191707 -277.992299) (xy 199.199519 -278.054133)
			(xy 199.200008 -278.085296) (xy 203.162931 -278.085296) (xy 203.166866 -278.031525) (xy 203.178589 -277.978901)
			(xy 203.197849 -277.928544) (xy 203.224235 -277.881527) (xy 203.257187 -277.838854) (xy 203.296 -277.801433)
			(xy 203.339848 -277.770063) (xy 203.387796 -277.745411) (xy 203.438823 -277.728003) (xy 203.491841 -277.71821)
			(xy 203.54572 -277.716241) (xy 203.599311 -277.722138) (xy 203.651472 -277.735774) (xy 203.701092 -277.756861)
			(xy 203.747113 -277.784947) (xy 203.788555 -277.819435) (xy 203.824533 -277.859589) (xy 203.854281 -277.904553)
			(xy 203.877166 -277.95337) (xy 203.892698 -278.004999) (xy 203.900548 -278.058339) (xy 203.90104 -278.085296)
			(xy 203.900548 -278.112253) (xy 203.892698 -278.165593) (xy 203.877166 -278.217222) (xy 203.854281 -278.266039)
			(xy 203.824533 -278.311003) (xy 203.788555 -278.351157) (xy 203.747113 -278.385645) (xy 203.701092 -278.413731)
			(xy 203.651472 -278.434818) (xy 203.599311 -278.448454) (xy 203.54572 -278.454351) (xy 203.491841 -278.452382)
			(xy 203.438823 -278.442589) (xy 203.387796 -278.425181) (xy 203.339848 -278.400529) (xy 203.296 -278.369159)
			(xy 203.257187 -278.331738) (xy 203.224235 -278.289065) (xy 203.197849 -278.242048) (xy 203.178589 -278.191691)
			(xy 203.166866 -278.139067) (xy 203.162931 -278.085296) (xy 199.200008 -278.085296) (xy 199.199501 -278.116504)
			(xy 199.191683 -278.178429) (xy 199.176156 -278.238884) (xy 199.153167 -278.296913) (xy 199.123079 -278.351598)
			(xy 199.086367 -278.402077) (xy 199.043612 -278.44755) (xy 198.995489 -278.487299) (xy 198.969376 -278.504396)
			(xy 198.959216 -278.510746) (xy 198.947024 -278.530558) (xy 198.937372 -278.634698) (xy 198.945754 -278.656542)
			(xy 198.954644 -278.66467) (xy 198.972938 -278.682218) (xy 199.005086 -278.721413) (xy 199.031564 -278.76464)
			(xy 199.051874 -278.811086) (xy 199.065634 -278.859875) (xy 199.072583 -278.910088) (xy 199.073008 -278.935434)
			(xy 199.072553 -278.96075) (xy 199.065635 -279.010908) (xy 199.05192 -279.059647) (xy 199.031666 -279.106051)
			(xy 199.005253 -279.149249) (xy 198.973179 -279.188426) (xy 198.954898 -279.205944) (xy 198.946008 -279.214326)
			(xy 198.937626 -279.235916) (xy 198.947024 -279.340056) (xy 198.959216 -279.359868) (xy 198.969376 -279.366472)
			(xy 198.995509 -279.383521) (xy 199.043642 -279.42323) (xy 199.08641 -279.468666) (xy 199.123136 -279.519112)
			(xy 199.153239 -279.573769) (xy 199.176243 -279.631773) (xy 199.191784 -279.692205) (xy 199.199615 -279.75411)
			(xy 199.199614 -279.816509) (xy 199.19178 -279.878414) (xy 199.176237 -279.938846) (xy 199.153231 -279.996848)
			(xy 199.123126 -280.051504) (xy 199.086398 -280.101948) (xy 199.043628 -280.147383) (xy 198.995493 -280.18709)
			(xy 198.969376 -280.204164) (xy 198.959216 -280.210768) (xy 198.947024 -280.23058) (xy 198.937626 -280.33472)
			(xy 198.946008 -280.35631) (xy 198.954898 -280.364692) (xy 198.973178 -280.382213) (xy 199.005259 -280.421388)
			(xy 199.031678 -280.464583) (xy 199.05194 -280.510987) (xy 199.065663 -280.559726) (xy 199.07259 -280.609885)
			(xy 199.073008 -280.635202) (xy 199.072575 -280.66055) (xy 199.065643 -280.710769) (xy 199.051895 -280.759564)
			(xy 199.031592 -280.806016) (xy 199.005116 -280.849248) (xy 198.972966 -280.888445) (xy 198.954644 -280.905966)
			(xy 198.945754 -280.914094) (xy 198.937372 -280.935938) (xy 198.947024 -281.040078) (xy 198.959216 -281.05989)
			(xy 198.969376 -281.06624) (xy 198.995462 -281.083378) (xy 199.043585 -281.123123) (xy 199.086342 -281.168591)
			(xy 199.123059 -281.219063) (xy 199.153156 -281.273742) (xy 199.176156 -281.331764) (xy 199.191697 -281.392212)
			(xy 199.199533 -281.454133) (xy 199.200008 -281.48534) (xy 199.199521 -281.516537) (xy 199.191706 -281.578438)
			(xy 199.17618 -281.638868) (xy 199.153189 -281.696871) (xy 199.123097 -281.751527) (xy 199.086379 -281.801972)
			(xy 199.043618 -281.847407) (xy 198.99549 -281.887113) (xy 198.969376 -281.904186) (xy 198.959216 -281.91079)
			(xy 198.947024 -281.930602) (xy 198.937626 -282.034742) (xy 198.946008 -282.056332) (xy 198.954898 -282.064714)
			(xy 198.973189 -282.082224) (xy 199.005268 -282.121402) (xy 199.031686 -282.164599) (xy 199.051946 -282.211005)
			(xy 199.065667 -282.259746) (xy 199.072591 -282.309906) (xy 199.073008 -282.335224) (xy 199.07259 -282.360572)
			(xy 199.065655 -282.410792) (xy 199.051904 -282.459588) (xy 199.031598 -282.50604) (xy 199.00512 -282.549271)
			(xy 198.972967 -282.588468) (xy 198.954644 -282.605988) (xy 198.945754 -282.614116) (xy 198.937372 -282.63596)
			(xy 198.947024 -282.7401) (xy 198.959216 -282.759912) (xy 198.969376 -282.766262) (xy 198.995472 -282.783385)
			(xy 199.043595 -282.823133) (xy 199.086352 -282.868603) (xy 199.123068 -282.919077) (xy 199.153163 -282.973758)
			(xy 199.176162 -283.031782) (xy 199.191701 -283.092232) (xy 199.199535 -283.154154) (xy 199.200008 -283.185362)
			(xy 199.199519 -283.216525) (xy 199.191707 -283.278359) (xy 199.176207 -283.338727) (xy 199.153264 -283.396675)
			(xy 199.123238 -283.451292) (xy 199.086604 -283.501714) (xy 199.043939 -283.547148) (xy 198.995917 -283.586876)
			(xy 198.943293 -283.620271) (xy 198.886899 -283.646808) (xy 198.827624 -283.666068) (xy 198.766403 -283.677747)
			(xy 198.7042 -283.68166) (xy 198.641997 -283.677747) (xy 198.580776 -283.666068) (xy 198.521501 -283.646808)
			(xy 198.465107 -283.620271) (xy 198.412483 -283.586876) (xy 198.364461 -283.547148) (xy 198.321796 -283.501714)
			(xy 198.285162 -283.451292) (xy 198.255136 -283.396675) (xy 198.232193 -283.338727) (xy 198.216693 -283.278359)
			(xy 198.208881 -283.216525) (xy 198.208392 -283.185362) (xy 194.97294 -283.185362) (xy 194.972525 -283.21068)
			(xy 194.965602 -283.26084) (xy 194.951881 -283.309581) (xy 194.931619 -283.355986) (xy 194.905198 -283.399182)
			(xy 194.873116 -283.438356) (xy 194.85483 -283.455872) (xy 194.84594 -283.464254) (xy 194.837558 -283.485844)
			(xy 194.846956 -283.589984) (xy 194.859148 -283.609796) (xy 194.869308 -283.6164) (xy 194.895415 -283.633481)
			(xy 194.943532 -283.673197) (xy 194.986285 -283.718636) (xy 195.022998 -283.769081) (xy 195.053092 -283.823734)
			(xy 195.076091 -283.88173) (xy 195.09163 -283.942155) (xy 195.099466 -284.004051) (xy 195.09994 -284.035246)
			(xy 196.950599 -284.035246) (xy 196.954534 -283.981475) (xy 196.966257 -283.928851) (xy 196.985517 -283.878494)
			(xy 197.011903 -283.831477) (xy 197.044855 -283.788804) (xy 197.083668 -283.751383) (xy 197.127516 -283.720013)
			(xy 197.175464 -283.695361) (xy 197.226491 -283.677953) (xy 197.279509 -283.66816) (xy 197.333388 -283.666191)
			(xy 197.386979 -283.672088) (xy 197.43914 -283.685724) (xy 197.48876 -283.706811) (xy 197.534781 -283.734897)
			(xy 197.576223 -283.769385) (xy 197.612201 -283.809539) (xy 197.641949 -283.854503) (xy 197.664834 -283.90332)
			(xy 197.680366 -283.954949) (xy 197.688216 -284.008289) (xy 197.688708 -284.035246) (xy 201.652124 -284.035246)
			(xy 201.652585 -284.004049) (xy 201.660402 -283.942145) (xy 201.675931 -283.881714) (xy 201.698925 -283.823711)
			(xy 201.729021 -283.769054) (xy 201.765743 -283.71861) (xy 201.808508 -283.673176) (xy 201.85664 -283.633472)
			(xy 201.882756 -283.6164) (xy 201.892916 -283.609796) (xy 201.905108 -283.589984) (xy 201.914506 -283.485844)
			(xy 201.906124 -283.464254) (xy 201.897234 -283.455872) (xy 201.878923 -283.438382) (xy 201.846848 -283.399199)
			(xy 201.820435 -283.355996) (xy 201.800179 -283.309587) (xy 201.786461 -283.260843) (xy 201.77954 -283.210681)
			(xy 201.779124 -283.185362) (xy 201.779523 -283.160013) (xy 201.78646 -283.109792) (xy 201.800214 -283.060995)
			(xy 201.820524 -283.014543) (xy 201.847006 -282.971312) (xy 201.879162 -282.932117) (xy 201.897488 -282.914598)
			(xy 201.906378 -282.90647) (xy 201.91476 -282.884626) (xy 201.905108 -282.780486) (xy 201.892916 -282.760674)
			(xy 201.882756 -282.754324) (xy 201.856638 -282.737234) (xy 201.808518 -282.697479) (xy 201.765764 -282.652003)
			(xy 201.729051 -282.601524) (xy 201.698959 -282.546839) (xy 201.675964 -282.488811) (xy 201.660427 -282.428358)
			(xy 201.652596 -282.366433) (xy 201.652124 -282.335224) (xy 201.652568 -282.304026) (xy 201.660388 -282.242122)
			(xy 201.675919 -282.18169) (xy 201.698916 -282.123687) (xy 201.729014 -282.069031) (xy 201.765738 -282.018586)
			(xy 201.808505 -281.973153) (xy 201.856639 -281.93345) (xy 201.882756 -281.916378) (xy 201.892916 -281.909774)
			(xy 201.905108 -281.889962) (xy 201.914506 -281.785822) (xy 201.906124 -281.764232) (xy 201.897234 -281.75585)
			(xy 201.878961 -281.738322) (xy 201.846883 -281.699147) (xy 201.820464 -281.655952) (xy 201.800201 -281.60955)
			(xy 201.786476 -281.560813) (xy 201.779545 -281.510657) (xy 201.779124 -281.48534) (xy 201.779508 -281.459991)
			(xy 201.786449 -281.409769) (xy 201.800205 -281.360972) (xy 201.820518 -281.31452) (xy 201.847003 -281.271289)
			(xy 201.879161 -281.232095) (xy 201.897488 -281.214576) (xy 201.906378 -281.206448) (xy 201.91476 -281.184604)
			(xy 201.905108 -281.080464) (xy 201.892916 -281.060652) (xy 201.882756 -281.054302) (xy 201.856628 -281.037227)
			(xy 201.808508 -280.99747) (xy 201.765754 -280.951991) (xy 201.729042 -280.90151) (xy 201.698952 -280.846823)
			(xy 201.675958 -280.788793) (xy 201.660424 -280.728338) (xy 201.652595 -280.666412) (xy 201.652124 -280.635202)
			(xy 201.652551 -280.604003) (xy 201.660373 -280.542099) (xy 201.675907 -280.481667) (xy 201.698907 -280.423663)
			(xy 201.729007 -280.369007) (xy 201.765733 -280.318563) (xy 201.808503 -280.27313) (xy 201.856638 -280.233427)
			(xy 201.882756 -280.216356) (xy 201.892916 -280.209752) (xy 201.905108 -280.18994) (xy 201.914506 -280.0858)
			(xy 201.906124 -280.06421) (xy 201.897234 -280.055828) (xy 201.877325 -280.036674) (xy 201.842857 -279.993503)
			(xy 201.815214 -279.945674) (xy 201.795014 -279.894256) (xy 201.78271 -279.840401) (xy 201.778577 -279.785312)
			(xy 201.782706 -279.730224) (xy 201.795007 -279.676367) (xy 201.815203 -279.624948) (xy 201.842843 -279.577117)
			(xy 201.877309 -279.533944) (xy 201.897234 -279.514808) (xy 201.906124 -279.506426) (xy 201.914506 -279.484836)
			(xy 201.905108 -279.380696) (xy 201.892916 -279.360884) (xy 201.882756 -279.35428) (xy 201.856654 -279.33719)
			(xy 201.808535 -279.297478) (xy 201.76578 -279.252041) (xy 201.729064 -279.201598) (xy 201.698969 -279.146946)
			(xy 201.67597 -279.08895) (xy 201.660431 -279.028525) (xy 201.652597 -278.966629) (xy 201.652124 -278.935434)
			(xy 201.652613 -278.904271) (xy 201.660425 -278.842437) (xy 201.675925 -278.782069) (xy 201.698868 -278.724121)
			(xy 201.728894 -278.669504) (xy 201.765528 -278.619082) (xy 201.808193 -278.573648) (xy 201.856215 -278.53392)
			(xy 201.908839 -278.500525) (xy 201.965233 -278.473988) (xy 202.024508 -278.454728) (xy 202.085729 -278.443049)
			(xy 202.147932 -278.439136) (xy 202.210135 -278.443049) (xy 202.271356 -278.454728) (xy 202.330631 -278.473988)
			(xy 202.387025 -278.500525) (xy 202.439649 -278.53392) (xy 202.487671 -278.573648) (xy 202.530336 -278.619082)
			(xy 202.56697 -278.669504) (xy 202.596996 -278.724121) (xy 202.619939 -278.782069) (xy 202.635439 -278.842437)
			(xy 202.643251 -278.904271) (xy 202.64374 -278.935434) (xy 202.643233 -278.96663) (xy 202.63542 -279.02853)
			(xy 202.619896 -279.088959) (xy 202.596907 -279.146961) (xy 202.566817 -279.201617) (xy 202.530103 -279.252062)
			(xy 202.487345 -279.297498) (xy 202.43922 -279.337206) (xy 202.413108 -279.35428) (xy 202.402948 -279.360884)
			(xy 202.390756 -279.380696) (xy 202.381358 -279.484836) (xy 202.38974 -279.506426) (xy 202.39863 -279.514808)
			(xy 202.418572 -279.533927) (xy 202.453034 -279.577106) (xy 202.480671 -279.624941) (xy 202.500865 -279.676363)
			(xy 202.513164 -279.730222) (xy 202.517293 -279.785312) (xy 202.51316 -279.840403) (xy 202.500858 -279.89426)
			(xy 202.48066 -279.945681) (xy 202.45302 -279.993514) (xy 202.418555 -280.036691) (xy 202.39863 -280.055828)
			(xy 202.38974 -280.06421) (xy 202.381358 -280.0858) (xy 202.390756 -280.18994) (xy 202.402948 -280.209752)
			(xy 202.413108 -280.216356) (xy 202.439241 -280.2334) (xy 202.487357 -280.273121) (xy 202.530109 -280.318566)
			(xy 202.566821 -280.369016) (xy 202.596911 -280.423674) (xy 202.619906 -280.481676) (xy 202.63544 -280.542105)
			(xy 202.643269 -280.604005) (xy 202.64374 -280.635202) (xy 202.643223 -280.66641) (xy 202.635404 -280.728334)
			(xy 202.619878 -280.788788) (xy 202.59689 -280.846816) (xy 202.566803 -280.901501) (xy 202.530093 -280.95198)
			(xy 202.48734 -280.997454) (xy 202.43922 -281.037204) (xy 202.413108 -281.054302) (xy 202.402948 -281.060652)
			(xy 202.390756 -281.080464) (xy 202.381104 -281.184604) (xy 202.389486 -281.206448) (xy 202.398376 -281.214576)
			(xy 202.416679 -281.232115) (xy 202.448825 -281.271313) (xy 202.475301 -281.314542) (xy 202.495609 -281.360989)
			(xy 202.509367 -281.409779) (xy 202.516316 -281.459994) (xy 202.51674 -281.48534) (xy 202.516311 -281.510657)
			(xy 202.50939 -281.560817) (xy 202.495672 -281.609557) (xy 202.475413 -281.655962) (xy 202.448995 -281.699159)
			(xy 202.416915 -281.738334) (xy 202.39863 -281.75585) (xy 202.38974 -281.764232) (xy 202.381358 -281.785822)
			(xy 202.390756 -281.889962) (xy 202.402948 -281.909774) (xy 202.413108 -281.916378) (xy 202.439205 -281.933474)
			(xy 202.487322 -281.973188) (xy 202.530075 -282.018625) (xy 202.56679 -282.069067) (xy 202.596885 -282.123718)
			(xy 202.619885 -282.181713) (xy 202.635427 -282.242135) (xy 202.643264 -282.30403) (xy 202.64374 -282.335224)
			(xy 202.64324 -282.366432) (xy 202.635419 -282.428357) (xy 202.61989 -282.488811) (xy 202.5969 -282.54684)
			(xy 202.56681 -282.601525) (xy 202.530098 -282.652003) (xy 202.487343 -282.697477) (xy 202.43922 -282.737227)
			(xy 202.413108 -282.754324) (xy 202.402948 -282.760674) (xy 202.390756 -282.780486) (xy 202.381104 -282.884626)
			(xy 202.389486 -282.90647) (xy 202.398376 -282.914598) (xy 202.41669 -282.932126) (xy 202.448834 -282.971326)
			(xy 202.475309 -283.014558) (xy 202.495616 -283.061007) (xy 202.509371 -283.109799) (xy 202.516317 -283.160015)
			(xy 202.51674 -283.185362) (xy 205.752192 -283.185362) (xy 205.752666 -283.154153) (xy 205.76049 -283.092226)
			(xy 205.776021 -283.031771) (xy 205.799015 -282.973742) (xy 205.829108 -282.919056) (xy 205.865824 -282.868579)
			(xy 205.908583 -282.823106) (xy 205.95671 -282.783358) (xy 205.982824 -282.766262) (xy 205.992984 -282.759912)
			(xy 206.005176 -282.7401) (xy 206.014828 -282.63596) (xy 206.006446 -282.614116) (xy 205.997556 -282.605988)
			(xy 205.979241 -282.58846) (xy 205.947096 -282.549261) (xy 205.92062 -282.506029) (xy 205.900314 -282.45958)
			(xy 205.886559 -282.410787) (xy 205.879614 -282.360571) (xy 205.879192 -282.335224) (xy 205.879619 -282.309907)
			(xy 205.886542 -282.259748) (xy 205.900263 -282.211008) (xy 205.920522 -282.164604) (xy 205.94694 -282.121407)
			(xy 205.979018 -282.082231) (xy 205.997302 -282.064714) (xy 206.006192 -282.056332) (xy 206.014574 -282.034742)
			(xy 206.005176 -281.930602) (xy 205.992984 -281.91079) (xy 205.982824 -281.904186) (xy 205.956718 -281.887103)
			(xy 205.9086 -281.847389) (xy 205.865846 -281.80195) (xy 205.829131 -281.751506) (xy 205.799037 -281.696853)
			(xy 205.776039 -281.638856) (xy 205.760499 -281.578432) (xy 205.752666 -281.516535) (xy 205.752192 -281.48534)
			(xy 205.752649 -281.45413) (xy 205.760475 -281.392203) (xy 205.776009 -281.331747) (xy 205.799006 -281.273718)
			(xy 205.829101 -281.219033) (xy 205.865819 -281.168555) (xy 205.90858 -281.123083) (xy 205.956709 -281.083336)
			(xy 205.982824 -281.06624) (xy 205.992984 -281.05989) (xy 206.005176 -281.040078) (xy 206.014828 -280.935938)
			(xy 206.006446 -280.914094) (xy 205.997556 -280.905966) (xy 205.979231 -280.888449) (xy 205.947086 -280.849247)
			(xy 205.920612 -280.806014) (xy 205.900307 -280.759562) (xy 205.886554 -280.710768) (xy 205.879612 -280.66055)
			(xy 205.879192 -280.635202) (xy 205.879604 -280.609884) (xy 205.886531 -280.559725) (xy 205.900254 -280.510985)
			(xy 205.920516 -280.464581) (xy 205.946936 -280.421384) (xy 205.979017 -280.382208) (xy 205.997302 -280.364692)
			(xy 206.006192 -280.35631) (xy 206.014574 -280.33472) (xy 206.005176 -280.23058) (xy 205.992984 -280.210768)
			(xy 205.982824 -280.204164) (xy 205.956725 -280.187065) (xy 205.908593 -280.147361) (xy 205.865826 -280.101929)
			(xy 205.8291 -280.051488) (xy 205.798997 -279.996835) (xy 205.775992 -279.938836) (xy 205.76045 -279.878408)
			(xy 205.752616 -279.816507) (xy 205.752615 -279.754112) (xy 205.760446 -279.692211) (xy 205.775986 -279.631782)
			(xy 205.798988 -279.573782) (xy 205.82909 -279.519129) (xy 205.865813 -279.468686) (xy 205.908579 -279.423252)
			(xy 205.956709 -279.383546) (xy 205.982824 -279.366472) (xy 205.992984 -279.359868) (xy 206.005176 -279.340056)
			(xy 206.014574 -279.235916) (xy 206.006192 -279.214326) (xy 205.997302 -279.205944) (xy 205.979039 -279.188406)
			(xy 205.946957 -279.149234) (xy 205.920536 -279.106043) (xy 205.900271 -279.059642) (xy 205.886544 -279.010906)
			(xy 205.879613 -278.96075) (xy 205.879192 -278.935434) (xy 205.879582 -278.910085) (xy 205.886523 -278.859864)
			(xy 205.900279 -278.811068) (xy 205.92059 -278.764616) (xy 205.947074 -278.721385) (xy 205.97923 -278.682189)
			(xy 205.997556 -278.66467) (xy 206.006446 -278.656542) (xy 206.014828 -278.634698) (xy 206.005176 -278.530558)
			(xy 205.992984 -278.510746) (xy 205.982824 -278.504396) (xy 205.956709 -278.487301) (xy 205.908586 -278.447549)
			(xy 205.86583 -278.402075) (xy 205.829115 -278.351597) (xy 205.799022 -278.296912) (xy 205.776027 -278.238884)
			(xy 205.760492 -278.17843) (xy 205.752663 -278.116505) (xy 205.752192 -278.085296) (xy 205.752681 -278.054133)
			(xy 205.760493 -277.992299) (xy 205.775993 -277.931931) (xy 205.798936 -277.873983) (xy 205.828962 -277.819366)
			(xy 205.865596 -277.768944) (xy 205.908261 -277.72351) (xy 205.956283 -277.683782) (xy 206.008907 -277.650387)
			(xy 206.065301 -277.62385) (xy 206.124576 -277.60459) (xy 206.185797 -277.592911) (xy 206.248 -277.588998)
			(xy 206.310203 -277.592911) (xy 206.371424 -277.60459) (xy 206.430699 -277.62385) (xy 206.487093 -277.650387)
			(xy 206.539717 -277.683782) (xy 206.587739 -277.72351) (xy 206.630404 -277.768944) (xy 206.667038 -277.819366)
			(xy 206.697064 -277.873983) (xy 206.720007 -277.931931) (xy 206.735507 -277.992299) (xy 206.743319 -278.054133)
			(xy 206.743808 -278.085296) (xy 206.743301 -278.116504) (xy 206.735483 -278.178429) (xy 206.719956 -278.238884)
			(xy 206.696967 -278.296913) (xy 206.666879 -278.351598) (xy 206.630167 -278.402077) (xy 206.587412 -278.44755)
			(xy 206.539289 -278.487299) (xy 206.513176 -278.504396) (xy 206.503016 -278.510746) (xy 206.490824 -278.530558)
			(xy 206.481172 -278.634698) (xy 206.489554 -278.656542) (xy 206.498444 -278.66467) (xy 206.516738 -278.682218)
			(xy 206.548886 -278.721413) (xy 206.575364 -278.76464) (xy 206.595674 -278.811086) (xy 206.609434 -278.859875)
			(xy 206.616383 -278.910088) (xy 206.616808 -278.935434) (xy 206.616353 -278.96075) (xy 206.609435 -279.010908)
			(xy 206.59572 -279.059647) (xy 206.575466 -279.106051) (xy 206.549053 -279.149249) (xy 206.516979 -279.188426)
			(xy 206.498698 -279.205944) (xy 206.489808 -279.214326) (xy 206.481426 -279.235916) (xy 206.490824 -279.340056)
			(xy 206.503016 -279.359868) (xy 206.513176 -279.366472) (xy 206.539309 -279.383521) (xy 206.587442 -279.42323)
			(xy 206.63021 -279.468666) (xy 206.666936 -279.519112) (xy 206.697039 -279.573769) (xy 206.720043 -279.631773)
			(xy 206.735584 -279.692205) (xy 206.743415 -279.75411) (xy 206.743414 -279.816509) (xy 206.73558 -279.878414)
			(xy 206.720037 -279.938846) (xy 206.697031 -279.996848) (xy 206.666926 -280.051504) (xy 206.630198 -280.101948)
			(xy 206.587428 -280.147383) (xy 206.539293 -280.18709) (xy 206.513176 -280.204164) (xy 206.503016 -280.210768)
			(xy 206.490824 -280.23058) (xy 206.481426 -280.33472) (xy 206.489808 -280.35631) (xy 206.498698 -280.364692)
			(xy 206.516978 -280.382213) (xy 206.549059 -280.421388) (xy 206.575478 -280.464583) (xy 206.59574 -280.510987)
			(xy 206.609463 -280.559726) (xy 206.61639 -280.609885) (xy 206.616808 -280.635202) (xy 206.616375 -280.66055)
			(xy 206.609443 -280.710769) (xy 206.595695 -280.759564) (xy 206.575392 -280.806016) (xy 206.548916 -280.849248)
			(xy 206.516766 -280.888445) (xy 206.498444 -280.905966) (xy 206.489554 -280.914094) (xy 206.481172 -280.935938)
			(xy 206.490824 -281.040078) (xy 206.503016 -281.05989) (xy 206.513176 -281.06624) (xy 206.539262 -281.083378)
			(xy 206.587385 -281.123123) (xy 206.630142 -281.168591) (xy 206.666859 -281.219063) (xy 206.696956 -281.273742)
			(xy 206.719956 -281.331764) (xy 206.735497 -281.392212) (xy 206.743333 -281.454133) (xy 206.743808 -281.48534)
			(xy 206.743321 -281.516537) (xy 206.735506 -281.578438) (xy 206.71998 -281.638868) (xy 206.696989 -281.696871)
			(xy 206.666897 -281.751527) (xy 206.630179 -281.801972) (xy 206.587418 -281.847407) (xy 206.53929 -281.887113)
			(xy 206.513176 -281.904186) (xy 206.503016 -281.91079) (xy 206.490824 -281.930602) (xy 206.481426 -282.034742)
			(xy 206.489808 -282.056332) (xy 206.498698 -282.064714) (xy 206.516989 -282.082224) (xy 206.549068 -282.121402)
			(xy 206.575486 -282.164599) (xy 206.595746 -282.211005) (xy 206.609467 -282.259746) (xy 206.616391 -282.309906)
			(xy 206.616808 -282.335224) (xy 206.61639 -282.360572) (xy 206.609455 -282.410792) (xy 206.595704 -282.459588)
			(xy 206.575398 -282.50604) (xy 206.54892 -282.549271) (xy 206.516767 -282.588468) (xy 206.498444 -282.605988)
			(xy 206.489554 -282.614116) (xy 206.481172 -282.63596) (xy 206.490824 -282.7401) (xy 206.503016 -282.759912)
			(xy 206.513176 -282.766262) (xy 206.539272 -282.783385) (xy 206.587395 -282.823133) (xy 206.630152 -282.868603)
			(xy 206.666868 -282.919077) (xy 206.696963 -282.973758) (xy 206.719962 -283.031782) (xy 206.735501 -283.092232)
			(xy 206.743335 -283.154154) (xy 206.743808 -283.185362) (xy 206.743319 -283.216525) (xy 206.735507 -283.278359)
			(xy 206.720007 -283.338727) (xy 206.697064 -283.396675) (xy 206.667038 -283.451292) (xy 206.630404 -283.501714)
			(xy 206.587739 -283.547148) (xy 206.539717 -283.586876) (xy 206.487093 -283.620271) (xy 206.430699 -283.646808)
			(xy 206.371424 -283.666068) (xy 206.310203 -283.677747) (xy 206.248 -283.68166) (xy 206.185797 -283.677747)
			(xy 206.124576 -283.666068) (xy 206.065301 -283.646808) (xy 206.008907 -283.620271) (xy 205.956283 -283.586876)
			(xy 205.908261 -283.547148) (xy 205.865596 -283.501714) (xy 205.828962 -283.451292) (xy 205.798936 -283.396675)
			(xy 205.775993 -283.338727) (xy 205.760493 -283.278359) (xy 205.752681 -283.216525) (xy 205.752192 -283.185362)
			(xy 202.51674 -283.185362) (xy 202.516325 -283.21068) (xy 202.509402 -283.26084) (xy 202.495681 -283.309581)
			(xy 202.475419 -283.355986) (xy 202.448998 -283.399182) (xy 202.416916 -283.438356) (xy 202.39863 -283.455872)
			(xy 202.38974 -283.464254) (xy 202.381358 -283.485844) (xy 202.390756 -283.589984) (xy 202.402948 -283.609796)
			(xy 202.413108 -283.6164) (xy 202.439215 -283.633481) (xy 202.487332 -283.673197) (xy 202.530085 -283.718636)
			(xy 202.566798 -283.769081) (xy 202.596892 -283.823734) (xy 202.619891 -283.88173) (xy 202.63543 -283.942155)
			(xy 202.643266 -284.004051) (xy 202.64374 -284.035246) (xy 204.494399 -284.035246) (xy 204.498334 -283.981475)
			(xy 204.510057 -283.928851) (xy 204.529317 -283.878494) (xy 204.555703 -283.831477) (xy 204.588655 -283.788804)
			(xy 204.627468 -283.751383) (xy 204.671316 -283.720013) (xy 204.719264 -283.695361) (xy 204.770291 -283.677953)
			(xy 204.823309 -283.66816) (xy 204.877188 -283.666191) (xy 204.930779 -283.672088) (xy 204.98294 -283.685724)
			(xy 205.03256 -283.706811) (xy 205.078581 -283.734897) (xy 205.120023 -283.769385) (xy 205.156001 -283.809539)
			(xy 205.185749 -283.854503) (xy 205.208634 -283.90332) (xy 205.224166 -283.954949) (xy 205.232016 -284.008289)
			(xy 205.232508 -284.035246) (xy 205.232016 -284.062203) (xy 205.224166 -284.115543) (xy 205.208634 -284.167172)
			(xy 205.185749 -284.215989) (xy 205.156001 -284.260953) (xy 205.120023 -284.301107) (xy 205.078581 -284.335595)
			(xy 205.03256 -284.363681) (xy 204.98294 -284.384768) (xy 204.930779 -284.398404) (xy 204.877188 -284.404301)
			(xy 204.823309 -284.402332) (xy 204.770291 -284.392539) (xy 204.719264 -284.375131) (xy 204.671316 -284.350479)
			(xy 204.627468 -284.319109) (xy 204.588655 -284.281688) (xy 204.555703 -284.239015) (xy 204.529317 -284.191998)
			(xy 204.510057 -284.141641) (xy 204.498334 -284.089017) (xy 204.494399 -284.035246) (xy 202.64374 -284.035246)
			(xy 202.643251 -284.066409) (xy 202.635439 -284.128243) (xy 202.619939 -284.188611) (xy 202.596996 -284.246559)
			(xy 202.56697 -284.301176) (xy 202.530336 -284.351598) (xy 202.487671 -284.397032) (xy 202.439649 -284.43676)
			(xy 202.387025 -284.470155) (xy 202.330631 -284.496692) (xy 202.271356 -284.515952) (xy 202.210135 -284.527631)
			(xy 202.147932 -284.531544) (xy 202.085729 -284.527631) (xy 202.024508 -284.515952) (xy 201.965233 -284.496692)
			(xy 201.908839 -284.470155) (xy 201.856215 -284.43676) (xy 201.808193 -284.397032) (xy 201.765528 -284.351598)
			(xy 201.728894 -284.301176) (xy 201.698868 -284.246559) (xy 201.675925 -284.188611) (xy 201.660425 -284.128243)
			(xy 201.652613 -284.066409) (xy 201.652124 -284.035246) (xy 197.688708 -284.035246) (xy 197.688216 -284.062203)
			(xy 197.680366 -284.115543) (xy 197.664834 -284.167172) (xy 197.641949 -284.215989) (xy 197.612201 -284.260953)
			(xy 197.576223 -284.301107) (xy 197.534781 -284.335595) (xy 197.48876 -284.363681) (xy 197.43914 -284.384768)
			(xy 197.386979 -284.398404) (xy 197.333388 -284.404301) (xy 197.279509 -284.402332) (xy 197.226491 -284.392539)
			(xy 197.175464 -284.375131) (xy 197.127516 -284.350479) (xy 197.083668 -284.319109) (xy 197.044855 -284.281688)
			(xy 197.011903 -284.239015) (xy 196.985517 -284.191998) (xy 196.966257 -284.141641) (xy 196.954534 -284.089017)
			(xy 196.950599 -284.035246) (xy 195.09994 -284.035246) (xy 195.099451 -284.066409) (xy 195.091639 -284.128243)
			(xy 195.076139 -284.188611) (xy 195.053196 -284.246559) (xy 195.02317 -284.301176) (xy 194.986536 -284.351598)
			(xy 194.943871 -284.397032) (xy 194.895849 -284.43676) (xy 194.843225 -284.470155) (xy 194.786831 -284.496692)
			(xy 194.727556 -284.515952) (xy 194.666335 -284.527631) (xy 194.604132 -284.531544) (xy 194.541929 -284.527631)
			(xy 194.480708 -284.515952) (xy 194.421433 -284.496692) (xy 194.365039 -284.470155) (xy 194.312415 -284.43676)
			(xy 194.264393 -284.397032) (xy 194.221728 -284.351598) (xy 194.185094 -284.301176) (xy 194.155068 -284.246559)
			(xy 194.132125 -284.188611) (xy 194.116625 -284.128243) (xy 194.108813 -284.066409) (xy 194.108324 -284.035246)
			(xy 190.144654 -284.035246) (xy 190.144162 -284.062203) (xy 190.136312 -284.115543) (xy 190.12078 -284.167172)
			(xy 190.097895 -284.215989) (xy 190.068147 -284.260953) (xy 190.032169 -284.301107) (xy 189.990727 -284.335595)
			(xy 189.944706 -284.363681) (xy 189.895086 -284.384768) (xy 189.842925 -284.398404) (xy 189.789334 -284.404301)
			(xy 189.735455 -284.402332) (xy 189.682437 -284.392539) (xy 189.63141 -284.375131) (xy 189.583462 -284.350479)
			(xy 189.539614 -284.319109) (xy 189.500801 -284.281688) (xy 189.467849 -284.239015) (xy 189.441463 -284.191998)
			(xy 189.422203 -284.141641) (xy 189.41048 -284.089017) (xy 189.406545 -284.035246) (xy 187.555886 -284.035246)
			(xy 187.555397 -284.066409) (xy 187.547585 -284.128243) (xy 187.532085 -284.188611) (xy 187.509142 -284.246559)
			(xy 187.479116 -284.301176) (xy 187.442482 -284.351598) (xy 187.399817 -284.397032) (xy 187.351795 -284.43676)
			(xy 187.299171 -284.470155) (xy 187.242777 -284.496692) (xy 187.183502 -284.515952) (xy 187.122281 -284.527631)
			(xy 187.060078 -284.531544) (xy 186.997875 -284.527631) (xy 186.936654 -284.515952) (xy 186.877379 -284.496692)
			(xy 186.820985 -284.470155) (xy 186.768361 -284.43676) (xy 186.720339 -284.397032) (xy 186.677674 -284.351598)
			(xy 186.64104 -284.301176) (xy 186.611014 -284.246559) (xy 186.588071 -284.188611) (xy 186.572571 -284.128243)
			(xy 186.564759 -284.066409) (xy 186.56427 -284.035246) (xy 185.96864 -284.035246) (xy 185.96864 -284.885384)
			(xy 188.075077 -284.885384) (xy 188.079012 -284.831613) (xy 188.090735 -284.778989) (xy 188.109995 -284.728632)
			(xy 188.136381 -284.681615) (xy 188.169333 -284.638942) (xy 188.208146 -284.601521) (xy 188.251994 -284.570151)
			(xy 188.299942 -284.545499) (xy 188.350969 -284.528091) (xy 188.403987 -284.518298) (xy 188.457866 -284.516329)
			(xy 188.511457 -284.522226) (xy 188.563618 -284.535862) (xy 188.613238 -284.556949) (xy 188.659259 -284.585035)
			(xy 188.700701 -284.619523) (xy 188.736679 -284.659677) (xy 188.766427 -284.704641) (xy 188.789312 -284.753458)
			(xy 188.804844 -284.805087) (xy 188.812694 -284.858427) (xy 188.813186 -284.885384) (xy 188.812694 -284.912341)
			(xy 188.804844 -284.965681) (xy 188.789312 -285.01731) (xy 188.766427 -285.066127) (xy 188.736679 -285.111091)
			(xy 188.700701 -285.151245) (xy 188.659259 -285.185733) (xy 188.613238 -285.213819) (xy 188.563618 -285.234906)
			(xy 188.511457 -285.248542) (xy 188.457866 -285.254439) (xy 188.403987 -285.25247) (xy 188.350969 -285.242677)
			(xy 188.299942 -285.225269) (xy 188.251994 -285.200617) (xy 188.208146 -285.169247) (xy 188.169333 -285.131826)
			(xy 188.136381 -285.089153) (xy 188.109995 -285.042136) (xy 188.090735 -284.991779) (xy 188.079012 -284.939155)
			(xy 188.075077 -284.885384) (xy 185.96864 -284.885384) (xy 185.96864 -286.585406) (xy 186.56427 -286.585406)
			(xy 186.564837 -286.552687) (xy 186.573429 -286.487816) (xy 186.590476 -286.424639) (xy 186.615683 -286.364251)
			(xy 186.648612 -286.307703) (xy 186.688692 -286.255976) (xy 186.71159 -286.2326) (xy 186.718956 -286.225488)
			(xy 186.72683 -286.206692) (xy 186.72683 -286.113982) (xy 186.718956 -286.095186) (xy 186.71159 -286.088074)
			(xy 186.68872 -286.064669) (xy 186.648634 -286.012949) (xy 186.615694 -285.956407) (xy 186.590474 -285.896026)
			(xy 186.57341 -285.832854) (xy 186.564798 -285.767986) (xy 186.56427 -285.735268) (xy 186.564759 -285.704105)
			(xy 186.572571 -285.642271) (xy 186.588071 -285.581903) (xy 186.611014 -285.523955) (xy 186.64104 -285.469338)
			(xy 186.677674 -285.418916) (xy 186.720339 -285.373482) (xy 186.768361 -285.333754) (xy 186.820985 -285.300359)
			(xy 186.877379 -285.273822) (xy 186.936654 -285.254562) (xy 186.997875 -285.242883) (xy 187.060078 -285.23897)
			(xy 187.122281 -285.242883) (xy 187.183502 -285.254562) (xy 187.242777 -285.273822) (xy 187.299171 -285.300359)
			(xy 187.351795 -285.333754) (xy 187.399817 -285.373482) (xy 187.442482 -285.418916) (xy 187.479116 -285.469338)
			(xy 187.509142 -285.523955) (xy 187.532085 -285.581903) (xy 187.547585 -285.642271) (xy 187.555397 -285.704105)
			(xy 187.555886 -285.735268) (xy 190.664338 -285.735268) (xy 190.664888 -285.702568) (xy 190.673493 -285.637738)
			(xy 190.69055 -285.574602) (xy 190.715761 -285.514258) (xy 190.74869 -285.457753) (xy 190.788765 -285.406071)
			(xy 190.811658 -285.382716) (xy 190.819024 -285.37535) (xy 190.826644 -285.356808) (xy 190.826644 -285.263844)
			(xy 190.819024 -285.245302) (xy 190.811658 -285.237936) (xy 190.78876 -285.214584) (xy 190.748676 -285.162905)
			(xy 190.715739 -285.106402) (xy 190.690522 -285.046057) (xy 190.673464 -284.982919) (xy 190.664862 -284.918085)
			(xy 190.664338 -284.885384) (xy 190.664827 -284.854221) (xy 190.672639 -284.792387) (xy 190.688139 -284.732019)
			(xy 190.711082 -284.674071) (xy 190.741108 -284.619454) (xy 190.777742 -284.569032) (xy 190.820407 -284.523598)
			(xy 190.868429 -284.48387) (xy 190.921053 -284.450475) (xy 190.977447 -284.423938) (xy 191.036722 -284.404678)
			(xy 191.097943 -284.392999) (xy 191.160146 -284.389086) (xy 191.222349 -284.392999) (xy 191.28357 -284.404678)
			(xy 191.342845 -284.423938) (xy 191.399239 -284.450475) (xy 191.451863 -284.48387) (xy 191.499885 -284.523598)
			(xy 191.54255 -284.569032) (xy 191.579184 -284.619454) (xy 191.60921 -284.674071) (xy 191.632153 -284.732019)
			(xy 191.647653 -284.792387) (xy 191.655465 -284.854221) (xy 191.655954 -284.885384) (xy 195.619131 -284.885384)
			(xy 195.623066 -284.831613) (xy 195.634789 -284.778989) (xy 195.654049 -284.728632) (xy 195.680435 -284.681615)
			(xy 195.713387 -284.638942) (xy 195.7522 -284.601521) (xy 195.796048 -284.570151) (xy 195.843996 -284.545499)
			(xy 195.895023 -284.528091) (xy 195.948041 -284.518298) (xy 196.00192 -284.516329) (xy 196.055511 -284.522226)
			(xy 196.107672 -284.535862) (xy 196.157292 -284.556949) (xy 196.203313 -284.585035) (xy 196.244755 -284.619523)
			(xy 196.280733 -284.659677) (xy 196.310481 -284.704641) (xy 196.333366 -284.753458) (xy 196.348898 -284.805087)
			(xy 196.356748 -284.858427) (xy 196.35724 -284.885384) (xy 196.356748 -284.912341) (xy 196.348898 -284.965681)
			(xy 196.333366 -285.01731) (xy 196.310481 -285.066127) (xy 196.280733 -285.111091) (xy 196.244755 -285.151245)
			(xy 196.203313 -285.185733) (xy 196.157292 -285.213819) (xy 196.107672 -285.234906) (xy 196.055511 -285.248542)
			(xy 196.00192 -285.254439) (xy 195.948041 -285.25247) (xy 195.895023 -285.242677) (xy 195.843996 -285.225269)
			(xy 195.796048 -285.200617) (xy 195.7522 -285.169247) (xy 195.713387 -285.131826) (xy 195.680435 -285.089153)
			(xy 195.654049 -285.042136) (xy 195.634789 -284.991779) (xy 195.623066 -284.939155) (xy 195.619131 -284.885384)
			(xy 191.655954 -284.885384) (xy 191.65544 -284.918085) (xy 191.646828 -284.982917) (xy 191.629765 -285.046054)
			(xy 191.604546 -285.106398) (xy 191.57161 -285.162901) (xy 191.53153 -285.214582) (xy 191.508634 -285.237936)
			(xy 191.501268 -285.245302) (xy 191.493648 -285.263844) (xy 191.493648 -285.310326) (xy 191.908445 -285.310326)
			(xy 191.91238 -285.256555) (xy 191.924103 -285.203931) (xy 191.943363 -285.153574) (xy 191.969749 -285.106557)
			(xy 192.002701 -285.063884) (xy 192.041514 -285.026463) (xy 192.085362 -284.995093) (xy 192.13331 -284.970441)
			(xy 192.184337 -284.953033) (xy 192.237355 -284.94324) (xy 192.291234 -284.941271) (xy 192.344825 -284.947168)
			(xy 192.396986 -284.960804) (xy 192.446606 -284.981891) (xy 192.492627 -285.009977) (xy 192.534069 -285.044465)
			(xy 192.570047 -285.084619) (xy 192.599795 -285.129583) (xy 192.62268 -285.1784) (xy 192.638212 -285.230029)
			(xy 192.646062 -285.283369) (xy 192.646554 -285.310326) (xy 192.646062 -285.337283) (xy 192.638212 -285.390623)
			(xy 192.62268 -285.442252) (xy 192.599795 -285.491069) (xy 192.570047 -285.536033) (xy 192.534069 -285.576187)
			(xy 192.492627 -285.610675) (xy 192.446606 -285.638761) (xy 192.396986 -285.659848) (xy 192.344825 -285.673484)
			(xy 192.291234 -285.679381) (xy 192.237355 -285.677412) (xy 192.184337 -285.667619) (xy 192.13331 -285.650211)
			(xy 192.085362 -285.625559) (xy 192.041514 -285.594189) (xy 192.002701 -285.556768) (xy 191.969749 -285.514095)
			(xy 191.943363 -285.467078) (xy 191.924103 -285.416721) (xy 191.91238 -285.364097) (xy 191.908445 -285.310326)
			(xy 191.493648 -285.310326) (xy 191.493648 -285.356808) (xy 191.501268 -285.37535) (xy 191.508634 -285.382716)
			(xy 191.531555 -285.406046) (xy 191.571638 -285.457729) (xy 191.604572 -285.514237) (xy 191.629784 -285.574586)
			(xy 191.646837 -285.637729) (xy 191.655434 -285.702566) (xy 191.655954 -285.735268) (xy 191.655465 -285.766431)
			(xy 191.647653 -285.828265) (xy 191.632153 -285.888633) (xy 191.60921 -285.946581) (xy 191.579184 -286.001198)
			(xy 191.54255 -286.05162) (xy 191.499885 -286.097054) (xy 191.451863 -286.136782) (xy 191.399239 -286.170177)
			(xy 191.342845 -286.196714) (xy 191.28357 -286.215974) (xy 191.222349 -286.227653) (xy 191.160146 -286.231566)
			(xy 191.097943 -286.227653) (xy 191.036722 -286.215974) (xy 190.977447 -286.196714) (xy 190.921053 -286.170177)
			(xy 190.868429 -286.136782) (xy 190.820407 -286.097054) (xy 190.777742 -286.05162) (xy 190.741108 -286.001198)
			(xy 190.711082 -285.946581) (xy 190.688139 -285.888633) (xy 190.672639 -285.828265) (xy 190.664827 -285.766431)
			(xy 190.664338 -285.735268) (xy 187.555886 -285.735268) (xy 187.555379 -285.767989) (xy 187.546778 -285.832863)
			(xy 187.529719 -285.896042) (xy 187.504501 -285.95643) (xy 187.47156 -286.012976) (xy 187.43147 -286.0647)
			(xy 187.408566 -286.088074) (xy 187.4012 -286.095186) (xy 187.393326 -286.113982) (xy 187.393326 -286.160464)
			(xy 187.808377 -286.160464) (xy 187.812312 -286.106693) (xy 187.824035 -286.054069) (xy 187.843295 -286.003712)
			(xy 187.869681 -285.956695) (xy 187.902633 -285.914022) (xy 187.941446 -285.876601) (xy 187.985294 -285.845231)
			(xy 188.033242 -285.820579) (xy 188.084269 -285.803171) (xy 188.137287 -285.793378) (xy 188.191166 -285.791409)
			(xy 188.244757 -285.797306) (xy 188.296918 -285.810942) (xy 188.346538 -285.832029) (xy 188.392559 -285.860115)
			(xy 188.434001 -285.894603) (xy 188.469979 -285.934757) (xy 188.499727 -285.979721) (xy 188.522612 -286.028538)
			(xy 188.538144 -286.080167) (xy 188.545994 -286.133507) (xy 188.546486 -286.160464) (xy 188.545994 -286.187421)
			(xy 188.538144 -286.240761) (xy 188.522612 -286.29239) (xy 188.499727 -286.341207) (xy 188.469979 -286.386171)
			(xy 188.434001 -286.426325) (xy 188.392559 -286.460813) (xy 188.346538 -286.488899) (xy 188.296918 -286.509986)
			(xy 188.244757 -286.523622) (xy 188.191166 -286.529519) (xy 188.137287 -286.52755) (xy 188.084269 -286.517757)
			(xy 188.033242 -286.500349) (xy 187.985294 -286.475697) (xy 187.941446 -286.444327) (xy 187.902633 -286.406906)
			(xy 187.869681 -286.364233) (xy 187.843295 -286.317216) (xy 187.824035 -286.266859) (xy 187.812312 -286.214235)
			(xy 187.808377 -286.160464) (xy 187.393326 -286.160464) (xy 187.393326 -286.206692) (xy 187.4012 -286.225488)
			(xy 187.408566 -286.2326) (xy 187.431482 -286.255961) (xy 187.471562 -286.307692) (xy 187.504494 -286.364243)
			(xy 187.529706 -286.424633) (xy 187.546761 -286.487812) (xy 187.555363 -286.552685) (xy 187.555886 -286.585406)
			(xy 189.406545 -286.585406) (xy 189.41048 -286.531635) (xy 189.422203 -286.479011) (xy 189.441463 -286.428654)
			(xy 189.467849 -286.381637) (xy 189.500801 -286.338964) (xy 189.539614 -286.301543) (xy 189.583462 -286.270173)
			(xy 189.63141 -286.245521) (xy 189.682437 -286.228113) (xy 189.735455 -286.21832) (xy 189.789334 -286.216351)
			(xy 189.842925 -286.222248) (xy 189.895086 -286.235884) (xy 189.944706 -286.256971) (xy 189.990727 -286.285057)
			(xy 190.032169 -286.319545) (xy 190.068147 -286.359699) (xy 190.097895 -286.404663) (xy 190.12078 -286.45348)
			(xy 190.136312 -286.505109) (xy 190.144162 -286.558449) (xy 190.144654 -286.585406) (xy 194.108324 -286.585406)
			(xy 194.108875 -286.552687) (xy 194.117468 -286.487814) (xy 194.134517 -286.424636) (xy 194.159727 -286.364248)
			(xy 194.19266 -286.3077) (xy 194.232744 -286.255975) (xy 194.255644 -286.2326) (xy 194.26301 -286.225488)
			(xy 194.270884 -286.206692) (xy 194.270884 -286.113982) (xy 194.26301 -286.095186) (xy 194.255644 -286.088074)
			(xy 194.232765 -286.064678) (xy 194.192681 -286.012954) (xy 194.159744 -285.956411) (xy 194.134525 -285.896028)
			(xy 194.117462 -285.832855) (xy 194.108852 -285.767987) (xy 194.108324 -285.735268) (xy 194.108813 -285.704105)
			(xy 194.116625 -285.642271) (xy 194.132125 -285.581903) (xy 194.155068 -285.523955) (xy 194.185094 -285.469338)
			(xy 194.221728 -285.418916) (xy 194.264393 -285.373482) (xy 194.312415 -285.333754) (xy 194.365039 -285.300359)
			(xy 194.421433 -285.273822) (xy 194.480708 -285.254562) (xy 194.541929 -285.242883) (xy 194.604132 -285.23897)
			(xy 194.666335 -285.242883) (xy 194.727556 -285.254562) (xy 194.786831 -285.273822) (xy 194.843225 -285.300359)
			(xy 194.895849 -285.333754) (xy 194.943871 -285.373482) (xy 194.986536 -285.418916) (xy 195.02317 -285.469338)
			(xy 195.053196 -285.523955) (xy 195.076139 -285.581903) (xy 195.091639 -285.642271) (xy 195.099451 -285.704105)
			(xy 195.09994 -285.735268) (xy 198.208392 -285.735268) (xy 198.208926 -285.702568) (xy 198.217532 -285.637736)
			(xy 198.234591 -285.574599) (xy 198.259805 -285.514255) (xy 198.292738 -285.457751) (xy 198.332817 -285.406069)
			(xy 198.355712 -285.382716) (xy 198.363078 -285.37535) (xy 198.370698 -285.356808) (xy 198.370698 -285.263844)
			(xy 198.363078 -285.245302) (xy 198.355712 -285.237936) (xy 198.332806 -285.214592) (xy 198.292724 -285.162911)
			(xy 198.259789 -285.106406) (xy 198.234574 -285.046059) (xy 198.217518 -284.98292) (xy 198.208915 -284.918085)
			(xy 198.208392 -284.885384) (xy 198.208881 -284.854221) (xy 198.216693 -284.792387) (xy 198.232193 -284.732019)
			(xy 198.255136 -284.674071) (xy 198.285162 -284.619454) (xy 198.321796 -284.569032) (xy 198.364461 -284.523598)
			(xy 198.412483 -284.48387) (xy 198.465107 -284.450475) (xy 198.521501 -284.423938) (xy 198.580776 -284.404678)
			(xy 198.641997 -284.392999) (xy 198.7042 -284.389086) (xy 198.766403 -284.392999) (xy 198.827624 -284.404678)
			(xy 198.886899 -284.423938) (xy 198.943293 -284.450475) (xy 198.995917 -284.48387) (xy 199.043939 -284.523598)
			(xy 199.086604 -284.569032) (xy 199.123238 -284.619454) (xy 199.153264 -284.674071) (xy 199.176207 -284.732019)
			(xy 199.191707 -284.792387) (xy 199.199519 -284.854221) (xy 199.200008 -284.885384) (xy 203.162931 -284.885384)
			(xy 203.166866 -284.831613) (xy 203.178589 -284.778989) (xy 203.197849 -284.728632) (xy 203.224235 -284.681615)
			(xy 203.257187 -284.638942) (xy 203.296 -284.601521) (xy 203.339848 -284.570151) (xy 203.387796 -284.545499)
			(xy 203.438823 -284.528091) (xy 203.491841 -284.518298) (xy 203.54572 -284.516329) (xy 203.599311 -284.522226)
			(xy 203.651472 -284.535862) (xy 203.701092 -284.556949) (xy 203.747113 -284.585035) (xy 203.788555 -284.619523)
			(xy 203.824533 -284.659677) (xy 203.854281 -284.704641) (xy 203.877166 -284.753458) (xy 203.892698 -284.805087)
			(xy 203.900548 -284.858427) (xy 203.90104 -284.885384) (xy 203.900548 -284.912341) (xy 203.892698 -284.965681)
			(xy 203.877166 -285.01731) (xy 203.854281 -285.066127) (xy 203.824533 -285.111091) (xy 203.788555 -285.151245)
			(xy 203.747113 -285.185733) (xy 203.701092 -285.213819) (xy 203.651472 -285.234906) (xy 203.599311 -285.248542)
			(xy 203.54572 -285.254439) (xy 203.491841 -285.25247) (xy 203.438823 -285.242677) (xy 203.387796 -285.225269)
			(xy 203.339848 -285.200617) (xy 203.296 -285.169247) (xy 203.257187 -285.131826) (xy 203.224235 -285.089153)
			(xy 203.197849 -285.042136) (xy 203.178589 -284.991779) (xy 203.166866 -284.939155) (xy 203.162931 -284.885384)
			(xy 199.200008 -284.885384) (xy 199.199508 -284.918085) (xy 199.190895 -284.982919) (xy 199.17383 -285.046056)
			(xy 199.148609 -285.1064) (xy 199.11567 -285.162903) (xy 199.075586 -285.214583) (xy 199.052688 -285.237936)
			(xy 199.045322 -285.245302) (xy 199.037702 -285.263844) (xy 199.037702 -285.310326) (xy 199.452499 -285.310326)
			(xy 199.456434 -285.256555) (xy 199.468157 -285.203931) (xy 199.487417 -285.153574) (xy 199.513803 -285.106557)
			(xy 199.546755 -285.063884) (xy 199.585568 -285.026463) (xy 199.629416 -284.995093) (xy 199.677364 -284.970441)
			(xy 199.728391 -284.953033) (xy 199.781409 -284.94324) (xy 199.835288 -284.941271) (xy 199.888879 -284.947168)
			(xy 199.94104 -284.960804) (xy 199.99066 -284.981891) (xy 200.036681 -285.009977) (xy 200.078123 -285.044465)
			(xy 200.114101 -285.084619) (xy 200.143849 -285.129583) (xy 200.166734 -285.1784) (xy 200.182266 -285.230029)
			(xy 200.190116 -285.283369) (xy 200.190608 -285.310326) (xy 200.190116 -285.337283) (xy 200.182266 -285.390623)
			(xy 200.166734 -285.442252) (xy 200.143849 -285.491069) (xy 200.114101 -285.536033) (xy 200.078123 -285.576187)
			(xy 200.036681 -285.610675) (xy 199.99066 -285.638761) (xy 199.94104 -285.659848) (xy 199.888879 -285.673484)
			(xy 199.835288 -285.679381) (xy 199.781409 -285.677412) (xy 199.728391 -285.667619) (xy 199.677364 -285.650211)
			(xy 199.629416 -285.625559) (xy 199.585568 -285.594189) (xy 199.546755 -285.556768) (xy 199.513803 -285.514095)
			(xy 199.487417 -285.467078) (xy 199.468157 -285.416721) (xy 199.456434 -285.364097) (xy 199.452499 -285.310326)
			(xy 199.037702 -285.310326) (xy 199.037702 -285.356808) (xy 199.045322 -285.37535) (xy 199.052688 -285.382716)
			(xy 199.075619 -285.406037) (xy 199.115699 -285.457723) (xy 199.14863 -285.514233) (xy 199.173841 -285.574584)
			(xy 199.190892 -285.637727) (xy 199.199488 -285.702565) (xy 199.200008 -285.735268) (xy 199.199519 -285.766431)
			(xy 199.191707 -285.828265) (xy 199.176207 -285.888633) (xy 199.153264 -285.946581) (xy 199.123238 -286.001198)
			(xy 199.086604 -286.05162) (xy 199.043939 -286.097054) (xy 198.995917 -286.136782) (xy 198.943293 -286.170177)
			(xy 198.886899 -286.196714) (xy 198.827624 -286.215974) (xy 198.766403 -286.227653) (xy 198.7042 -286.231566)
			(xy 198.641997 -286.227653) (xy 198.580776 -286.215974) (xy 198.521501 -286.196714) (xy 198.465107 -286.170177)
			(xy 198.412483 -286.136782) (xy 198.364461 -286.097054) (xy 198.321796 -286.05162) (xy 198.285162 -286.001198)
			(xy 198.255136 -285.946581) (xy 198.232193 -285.888633) (xy 198.216693 -285.828265) (xy 198.208881 -285.766431)
			(xy 198.208392 -285.735268) (xy 195.09994 -285.735268) (xy 195.099447 -285.767989) (xy 195.090844 -285.832864)
			(xy 195.073784 -285.896045) (xy 195.048564 -285.956432) (xy 195.01562 -286.012978) (xy 194.975526 -286.064701)
			(xy 194.95262 -286.088074) (xy 194.945254 -286.095186) (xy 194.93738 -286.113982) (xy 194.93738 -286.160464)
			(xy 195.352431 -286.160464) (xy 195.356366 -286.106693) (xy 195.368089 -286.054069) (xy 195.387349 -286.003712)
			(xy 195.413735 -285.956695) (xy 195.446687 -285.914022) (xy 195.4855 -285.876601) (xy 195.529348 -285.845231)
			(xy 195.577296 -285.820579) (xy 195.628323 -285.803171) (xy 195.681341 -285.793378) (xy 195.73522 -285.791409)
			(xy 195.788811 -285.797306) (xy 195.840972 -285.810942) (xy 195.890592 -285.832029) (xy 195.936613 -285.860115)
			(xy 195.978055 -285.894603) (xy 196.014033 -285.934757) (xy 196.043781 -285.979721) (xy 196.066666 -286.028538)
			(xy 196.082198 -286.080167) (xy 196.090048 -286.133507) (xy 196.09054 -286.160464) (xy 196.090048 -286.187421)
			(xy 196.082198 -286.240761) (xy 196.066666 -286.29239) (xy 196.043781 -286.341207) (xy 196.014033 -286.386171)
			(xy 195.978055 -286.426325) (xy 195.936613 -286.460813) (xy 195.890592 -286.488899) (xy 195.840972 -286.509986)
			(xy 195.788811 -286.523622) (xy 195.73522 -286.529519) (xy 195.681341 -286.52755) (xy 195.628323 -286.517757)
			(xy 195.577296 -286.500349) (xy 195.529348 -286.475697) (xy 195.4855 -286.444327) (xy 195.446687 -286.406906)
			(xy 195.413735 -286.364233) (xy 195.387349 -286.317216) (xy 195.368089 -286.266859) (xy 195.356366 -286.214235)
			(xy 195.352431 -286.160464) (xy 194.93738 -286.160464) (xy 194.93738 -286.206692) (xy 194.945254 -286.225488)
			(xy 194.95262 -286.2326) (xy 194.975527 -286.255969) (xy 195.01561 -286.307698) (xy 195.048544 -286.364247)
			(xy 195.073758 -286.424635) (xy 195.090814 -286.487813) (xy 195.099416 -286.552686) (xy 195.09994 -286.585406)
			(xy 196.950599 -286.585406) (xy 196.954534 -286.531635) (xy 196.966257 -286.479011) (xy 196.985517 -286.428654)
			(xy 197.011903 -286.381637) (xy 197.044855 -286.338964) (xy 197.083668 -286.301543) (xy 197.127516 -286.270173)
			(xy 197.175464 -286.245521) (xy 197.226491 -286.228113) (xy 197.279509 -286.21832) (xy 197.333388 -286.216351)
			(xy 197.386979 -286.222248) (xy 197.43914 -286.235884) (xy 197.48876 -286.256971) (xy 197.534781 -286.285057)
			(xy 197.576223 -286.319545) (xy 197.612201 -286.359699) (xy 197.641949 -286.404663) (xy 197.664834 -286.45348)
			(xy 197.680366 -286.505109) (xy 197.688216 -286.558449) (xy 197.688708 -286.585406) (xy 201.652124 -286.585406)
			(xy 201.652675 -286.552687) (xy 201.661268 -286.487814) (xy 201.678317 -286.424636) (xy 201.703527 -286.364248)
			(xy 201.73646 -286.3077) (xy 201.776544 -286.255975) (xy 201.799444 -286.2326) (xy 201.80681 -286.225488)
			(xy 201.814684 -286.206692) (xy 201.814684 -286.113982) (xy 201.80681 -286.095186) (xy 201.799444 -286.088074)
			(xy 201.776565 -286.064678) (xy 201.736481 -286.012954) (xy 201.703544 -285.956411) (xy 201.678325 -285.896028)
			(xy 201.661262 -285.832855) (xy 201.652652 -285.767987) (xy 201.652124 -285.735268) (xy 201.652613 -285.704105)
			(xy 201.660425 -285.642271) (xy 201.675925 -285.581903) (xy 201.698868 -285.523955) (xy 201.728894 -285.469338)
			(xy 201.765528 -285.418916) (xy 201.808193 -285.373482) (xy 201.856215 -285.333754) (xy 201.908839 -285.300359)
			(xy 201.965233 -285.273822) (xy 202.024508 -285.254562) (xy 202.085729 -285.242883) (xy 202.147932 -285.23897)
			(xy 202.210135 -285.242883) (xy 202.271356 -285.254562) (xy 202.330631 -285.273822) (xy 202.387025 -285.300359)
			(xy 202.439649 -285.333754) (xy 202.487671 -285.373482) (xy 202.530336 -285.418916) (xy 202.56697 -285.469338)
			(xy 202.596996 -285.523955) (xy 202.619939 -285.581903) (xy 202.635439 -285.642271) (xy 202.643251 -285.704105)
			(xy 202.64374 -285.735268) (xy 205.752192 -285.735268) (xy 205.752726 -285.702568) (xy 205.761332 -285.637736)
			(xy 205.778391 -285.574599) (xy 205.803605 -285.514255) (xy 205.836538 -285.457751) (xy 205.876617 -285.406069)
			(xy 205.899512 -285.382716) (xy 205.906878 -285.37535) (xy 205.914498 -285.356808) (xy 205.914498 -285.263844)
			(xy 205.906878 -285.245302) (xy 205.899512 -285.237936) (xy 205.876606 -285.214592) (xy 205.836524 -285.162911)
			(xy 205.803589 -285.106406) (xy 205.778374 -285.046059) (xy 205.761318 -284.98292) (xy 205.752715 -284.918085)
			(xy 205.752192 -284.885384) (xy 205.752681 -284.854221) (xy 205.760493 -284.792387) (xy 205.775993 -284.732019)
			(xy 205.798936 -284.674071) (xy 205.828962 -284.619454) (xy 205.865596 -284.569032) (xy 205.908261 -284.523598)
			(xy 205.956283 -284.48387) (xy 206.008907 -284.450475) (xy 206.065301 -284.423938) (xy 206.124576 -284.404678)
			(xy 206.185797 -284.392999) (xy 206.248 -284.389086) (xy 206.310203 -284.392999) (xy 206.371424 -284.404678)
			(xy 206.430699 -284.423938) (xy 206.487093 -284.450475) (xy 206.539717 -284.48387) (xy 206.587739 -284.523598)
			(xy 206.630404 -284.569032) (xy 206.667038 -284.619454) (xy 206.697064 -284.674071) (xy 206.720007 -284.732019)
			(xy 206.735507 -284.792387) (xy 206.743319 -284.854221) (xy 206.743808 -284.885384) (xy 206.743308 -284.918085)
			(xy 206.734695 -284.982919) (xy 206.71763 -285.046056) (xy 206.692409 -285.1064) (xy 206.65947 -285.162903)
			(xy 206.619386 -285.214583) (xy 206.596488 -285.237936) (xy 206.589122 -285.245302) (xy 206.581502 -285.263844)
			(xy 206.581502 -285.310326) (xy 206.996299 -285.310326) (xy 207.000234 -285.256555) (xy 207.011957 -285.203931)
			(xy 207.031217 -285.153574) (xy 207.057603 -285.106557) (xy 207.090555 -285.063884) (xy 207.129368 -285.026463)
			(xy 207.173216 -284.995093) (xy 207.221164 -284.970441) (xy 207.272191 -284.953033) (xy 207.325209 -284.94324)
			(xy 207.379088 -284.941271) (xy 207.432679 -284.947168) (xy 207.48484 -284.960804) (xy 207.53446 -284.981891)
			(xy 207.580481 -285.009977) (xy 207.621923 -285.044465) (xy 207.657901 -285.084619) (xy 207.687649 -285.129583)
			(xy 207.710534 -285.1784) (xy 207.726066 -285.230029) (xy 207.733916 -285.283369) (xy 207.734408 -285.310326)
			(xy 207.733916 -285.337283) (xy 207.726066 -285.390623) (xy 207.710534 -285.442252) (xy 207.687649 -285.491069)
			(xy 207.657901 -285.536033) (xy 207.621923 -285.576187) (xy 207.580481 -285.610675) (xy 207.53446 -285.638761)
			(xy 207.48484 -285.659848) (xy 207.432679 -285.673484) (xy 207.379088 -285.679381) (xy 207.325209 -285.677412)
			(xy 207.272191 -285.667619) (xy 207.221164 -285.650211) (xy 207.173216 -285.625559) (xy 207.129368 -285.594189)
			(xy 207.090555 -285.556768) (xy 207.057603 -285.514095) (xy 207.031217 -285.467078) (xy 207.011957 -285.416721)
			(xy 207.000234 -285.364097) (xy 206.996299 -285.310326) (xy 206.581502 -285.310326) (xy 206.581502 -285.356808)
			(xy 206.589122 -285.37535) (xy 206.596488 -285.382716) (xy 206.619419 -285.406037) (xy 206.659499 -285.457723)
			(xy 206.69243 -285.514233) (xy 206.717641 -285.574584) (xy 206.734692 -285.637727) (xy 206.743288 -285.702565)
			(xy 206.743808 -285.735268) (xy 206.743319 -285.766431) (xy 206.735507 -285.828265) (xy 206.720007 -285.888633)
			(xy 206.697064 -285.946581) (xy 206.667038 -286.001198) (xy 206.630404 -286.05162) (xy 206.587739 -286.097054)
			(xy 206.539717 -286.136782) (xy 206.487093 -286.170177) (xy 206.430699 -286.196714) (xy 206.371424 -286.215974)
			(xy 206.310203 -286.227653) (xy 206.248 -286.231566) (xy 206.185797 -286.227653) (xy 206.124576 -286.215974)
			(xy 206.065301 -286.196714) (xy 206.008907 -286.170177) (xy 205.956283 -286.136782) (xy 205.908261 -286.097054)
			(xy 205.865596 -286.05162) (xy 205.828962 -286.001198) (xy 205.798936 -285.946581) (xy 205.775993 -285.888633)
			(xy 205.760493 -285.828265) (xy 205.752681 -285.766431) (xy 205.752192 -285.735268) (xy 202.64374 -285.735268)
			(xy 202.643247 -285.767989) (xy 202.634644 -285.832864) (xy 202.617584 -285.896045) (xy 202.592364 -285.956432)
			(xy 202.55942 -286.012978) (xy 202.519326 -286.064701) (xy 202.49642 -286.088074) (xy 202.489054 -286.095186)
			(xy 202.48118 -286.113982) (xy 202.48118 -286.160464) (xy 202.896231 -286.160464) (xy 202.900166 -286.106693)
			(xy 202.911889 -286.054069) (xy 202.931149 -286.003712) (xy 202.957535 -285.956695) (xy 202.990487 -285.914022)
			(xy 203.0293 -285.876601) (xy 203.073148 -285.845231) (xy 203.121096 -285.820579) (xy 203.172123 -285.803171)
			(xy 203.225141 -285.793378) (xy 203.27902 -285.791409) (xy 203.332611 -285.797306) (xy 203.384772 -285.810942)
			(xy 203.434392 -285.832029) (xy 203.480413 -285.860115) (xy 203.521855 -285.894603) (xy 203.557833 -285.934757)
			(xy 203.587581 -285.979721) (xy 203.610466 -286.028538) (xy 203.625998 -286.080167) (xy 203.633848 -286.133507)
			(xy 203.63434 -286.160464) (xy 203.633848 -286.187421) (xy 203.625998 -286.240761) (xy 203.610466 -286.29239)
			(xy 203.587581 -286.341207) (xy 203.557833 -286.386171) (xy 203.521855 -286.426325) (xy 203.480413 -286.460813)
			(xy 203.434392 -286.488899) (xy 203.384772 -286.509986) (xy 203.332611 -286.523622) (xy 203.27902 -286.529519)
			(xy 203.225141 -286.52755) (xy 203.172123 -286.517757) (xy 203.121096 -286.500349) (xy 203.073148 -286.475697)
			(xy 203.0293 -286.444327) (xy 202.990487 -286.406906) (xy 202.957535 -286.364233) (xy 202.931149 -286.317216)
			(xy 202.911889 -286.266859) (xy 202.900166 -286.214235) (xy 202.896231 -286.160464) (xy 202.48118 -286.160464)
			(xy 202.48118 -286.206692) (xy 202.489054 -286.225488) (xy 202.49642 -286.2326) (xy 202.519327 -286.255969)
			(xy 202.55941 -286.307698) (xy 202.592344 -286.364247) (xy 202.617558 -286.424635) (xy 202.634614 -286.487813)
			(xy 202.643216 -286.552686) (xy 202.64374 -286.585406) (xy 204.494399 -286.585406) (xy 204.498334 -286.531635)
			(xy 204.510057 -286.479011) (xy 204.529317 -286.428654) (xy 204.555703 -286.381637) (xy 204.588655 -286.338964)
			(xy 204.627468 -286.301543) (xy 204.671316 -286.270173) (xy 204.719264 -286.245521) (xy 204.770291 -286.228113)
			(xy 204.823309 -286.21832) (xy 204.877188 -286.216351) (xy 204.930779 -286.222248) (xy 204.98294 -286.235884)
			(xy 205.03256 -286.256971) (xy 205.078581 -286.285057) (xy 205.120023 -286.319545) (xy 205.156001 -286.359699)
			(xy 205.185749 -286.404663) (xy 205.208634 -286.45348) (xy 205.224166 -286.505109) (xy 205.232016 -286.558449)
			(xy 205.232508 -286.585406) (xy 205.232016 -286.612363) (xy 205.224166 -286.665703) (xy 205.208634 -286.717332)
			(xy 205.185749 -286.766149) (xy 205.156001 -286.811113) (xy 205.120023 -286.851267) (xy 205.078581 -286.885755)
			(xy 205.03256 -286.913841) (xy 204.98294 -286.934928) (xy 204.930779 -286.948564) (xy 204.877188 -286.954461)
			(xy 204.823309 -286.952492) (xy 204.770291 -286.942699) (xy 204.719264 -286.925291) (xy 204.671316 -286.900639)
			(xy 204.627468 -286.869269) (xy 204.588655 -286.831848) (xy 204.555703 -286.789175) (xy 204.529317 -286.742158)
			(xy 204.510057 -286.691801) (xy 204.498334 -286.639177) (xy 204.494399 -286.585406) (xy 202.64374 -286.585406)
			(xy 202.643251 -286.616569) (xy 202.635439 -286.678403) (xy 202.619939 -286.738771) (xy 202.596996 -286.796719)
			(xy 202.56697 -286.851336) (xy 202.530336 -286.901758) (xy 202.487671 -286.947192) (xy 202.439649 -286.98692)
			(xy 202.387025 -287.020315) (xy 202.330631 -287.046852) (xy 202.271356 -287.066112) (xy 202.210135 -287.077791)
			(xy 202.147932 -287.081704) (xy 202.085729 -287.077791) (xy 202.024508 -287.066112) (xy 201.965233 -287.046852)
			(xy 201.908839 -287.020315) (xy 201.856215 -286.98692) (xy 201.808193 -286.947192) (xy 201.765528 -286.901758)
			(xy 201.728894 -286.851336) (xy 201.698868 -286.796719) (xy 201.675925 -286.738771) (xy 201.660425 -286.678403)
			(xy 201.652613 -286.616569) (xy 201.652124 -286.585406) (xy 197.688708 -286.585406) (xy 197.688216 -286.612363)
			(xy 197.680366 -286.665703) (xy 197.664834 -286.717332) (xy 197.641949 -286.766149) (xy 197.612201 -286.811113)
			(xy 197.576223 -286.851267) (xy 197.534781 -286.885755) (xy 197.48876 -286.913841) (xy 197.43914 -286.934928)
			(xy 197.386979 -286.948564) (xy 197.333388 -286.954461) (xy 197.279509 -286.952492) (xy 197.226491 -286.942699)
			(xy 197.175464 -286.925291) (xy 197.127516 -286.900639) (xy 197.083668 -286.869269) (xy 197.044855 -286.831848)
			(xy 197.011903 -286.789175) (xy 196.985517 -286.742158) (xy 196.966257 -286.691801) (xy 196.954534 -286.639177)
			(xy 196.950599 -286.585406) (xy 195.09994 -286.585406) (xy 195.099451 -286.616569) (xy 195.091639 -286.678403)
			(xy 195.076139 -286.738771) (xy 195.053196 -286.796719) (xy 195.02317 -286.851336) (xy 194.986536 -286.901758)
			(xy 194.943871 -286.947192) (xy 194.895849 -286.98692) (xy 194.843225 -287.020315) (xy 194.786831 -287.046852)
			(xy 194.727556 -287.066112) (xy 194.666335 -287.077791) (xy 194.604132 -287.081704) (xy 194.541929 -287.077791)
			(xy 194.480708 -287.066112) (xy 194.421433 -287.046852) (xy 194.365039 -287.020315) (xy 194.312415 -286.98692)
			(xy 194.264393 -286.947192) (xy 194.221728 -286.901758) (xy 194.185094 -286.851336) (xy 194.155068 -286.796719)
			(xy 194.132125 -286.738771) (xy 194.116625 -286.678403) (xy 194.108813 -286.616569) (xy 194.108324 -286.585406)
			(xy 190.144654 -286.585406) (xy 190.144162 -286.612363) (xy 190.136312 -286.665703) (xy 190.12078 -286.717332)
			(xy 190.097895 -286.766149) (xy 190.068147 -286.811113) (xy 190.032169 -286.851267) (xy 189.990727 -286.885755)
			(xy 189.944706 -286.913841) (xy 189.895086 -286.934928) (xy 189.842925 -286.948564) (xy 189.789334 -286.954461)
			(xy 189.735455 -286.952492) (xy 189.682437 -286.942699) (xy 189.63141 -286.925291) (xy 189.583462 -286.900639)
			(xy 189.539614 -286.869269) (xy 189.500801 -286.831848) (xy 189.467849 -286.789175) (xy 189.441463 -286.742158)
			(xy 189.422203 -286.691801) (xy 189.41048 -286.639177) (xy 189.406545 -286.585406) (xy 187.555886 -286.585406)
			(xy 187.555397 -286.616569) (xy 187.547585 -286.678403) (xy 187.532085 -286.738771) (xy 187.509142 -286.796719)
			(xy 187.479116 -286.851336) (xy 187.442482 -286.901758) (xy 187.399817 -286.947192) (xy 187.351795 -286.98692)
			(xy 187.299171 -287.020315) (xy 187.242777 -287.046852) (xy 187.183502 -287.066112) (xy 187.122281 -287.077791)
			(xy 187.060078 -287.081704) (xy 186.997875 -287.077791) (xy 186.936654 -287.066112) (xy 186.877379 -287.046852)
			(xy 186.820985 -287.020315) (xy 186.768361 -286.98692) (xy 186.720339 -286.947192) (xy 186.677674 -286.901758)
			(xy 186.64104 -286.851336) (xy 186.611014 -286.796719) (xy 186.588071 -286.738771) (xy 186.572571 -286.678403)
			(xy 186.564759 -286.616569) (xy 186.56427 -286.585406) (xy 185.96864 -286.585406) (xy 185.96864 -287.43529)
			(xy 188.075077 -287.43529) (xy 188.079012 -287.381519) (xy 188.090735 -287.328895) (xy 188.109995 -287.278538)
			(xy 188.136381 -287.231521) (xy 188.169333 -287.188848) (xy 188.208146 -287.151427) (xy 188.251994 -287.120057)
			(xy 188.299942 -287.095405) (xy 188.350969 -287.077997) (xy 188.403987 -287.068204) (xy 188.457866 -287.066235)
			(xy 188.511457 -287.072132) (xy 188.563618 -287.085768) (xy 188.613238 -287.106855) (xy 188.659259 -287.134941)
			(xy 188.700701 -287.169429) (xy 188.736679 -287.209583) (xy 188.766427 -287.254547) (xy 188.789312 -287.303364)
			(xy 188.804844 -287.354993) (xy 188.812694 -287.408333) (xy 188.813186 -287.43529) (xy 188.812694 -287.462247)
			(xy 188.804844 -287.515587) (xy 188.789312 -287.567216) (xy 188.766427 -287.616033) (xy 188.736679 -287.660997)
			(xy 188.700701 -287.701151) (xy 188.659259 -287.735639) (xy 188.613238 -287.763725) (xy 188.563618 -287.784812)
			(xy 188.511457 -287.798448) (xy 188.457866 -287.804345) (xy 188.403987 -287.802376) (xy 188.350969 -287.792583)
			(xy 188.299942 -287.775175) (xy 188.251994 -287.750523) (xy 188.208146 -287.719153) (xy 188.169333 -287.681732)
			(xy 188.136381 -287.639059) (xy 188.109995 -287.592042) (xy 188.090735 -287.541685) (xy 188.079012 -287.489061)
			(xy 188.075077 -287.43529) (xy 185.96864 -287.43529) (xy 185.96864 -293.38524) (xy 186.56427 -293.38524)
			(xy 186.564752 -293.354043) (xy 186.572569 -293.292142) (xy 186.588096 -293.231712) (xy 186.611088 -293.17371)
			(xy 186.641181 -293.119054) (xy 186.677899 -293.068609) (xy 186.72066 -293.023174) (xy 186.768788 -292.983468)
			(xy 186.794902 -292.966394) (xy 186.805062 -292.95979) (xy 186.817254 -292.939978) (xy 186.826652 -292.835838)
			(xy 186.81827 -292.814248) (xy 186.80938 -292.805866) (xy 186.791124 -292.788321) (xy 186.759042 -292.749151)
			(xy 186.73262 -292.70596) (xy 186.712354 -292.659561) (xy 186.698625 -292.610826) (xy 186.691692 -292.560672)
			(xy 186.69127 -292.535356) (xy 186.691682 -292.510008) (xy 186.698619 -292.459788) (xy 186.712371 -292.410992)
			(xy 186.732679 -292.364541) (xy 186.759158 -292.321309) (xy 186.791311 -292.282112) (xy 186.809634 -292.264592)
			(xy 186.818524 -292.256464) (xy 186.826906 -292.23462) (xy 186.817254 -292.13048) (xy 186.805062 -292.110668)
			(xy 186.794902 -292.104318) (xy 186.768792 -292.087216) (xy 186.72067 -292.047464) (xy 186.677914 -292.001991)
			(xy 186.6412 -291.951514) (xy 186.611107 -291.89683) (xy 186.58811 -291.838803) (xy 186.572573 -291.778351)
			(xy 186.564742 -291.716427) (xy 186.56427 -291.685218) (xy 186.564735 -291.654021) (xy 186.572554 -291.592119)
			(xy 186.588084 -291.531688) (xy 186.611079 -291.473686) (xy 186.641174 -291.41903) (xy 186.677894 -291.368586)
			(xy 186.720658 -291.323151) (xy 186.768787 -291.283445) (xy 186.794902 -291.266372) (xy 186.805062 -291.259768)
			(xy 186.817254 -291.239956) (xy 186.826652 -291.135816) (xy 186.81827 -291.114226) (xy 186.80938 -291.105844)
			(xy 186.78949 -291.086673) (xy 186.755026 -291.043502) (xy 186.727387 -290.995675) (xy 186.707189 -290.94426)
			(xy 186.694886 -290.890408) (xy 186.690752 -290.835323) (xy 186.694879 -290.780238) (xy 186.707176 -290.726384)
			(xy 186.727367 -290.674967) (xy 186.755 -290.627136) (xy 186.789458 -290.583961) (xy 186.80938 -290.564824)
			(xy 186.81827 -290.556442) (xy 186.826652 -290.534852) (xy 186.817254 -290.430712) (xy 186.805062 -290.4109)
			(xy 186.794902 -290.404296) (xy 186.768795 -290.387214) (xy 186.720678 -290.347499) (xy 186.677925 -290.30206)
			(xy 186.641211 -290.251615) (xy 186.611117 -290.196962) (xy 186.588118 -290.138966) (xy 186.572579 -290.078542)
			(xy 186.564744 -290.016645) (xy 186.56427 -289.98545) (xy 186.564745 -289.954241) (xy 186.57257 -289.892315)
			(xy 186.588102 -289.83186) (xy 186.611096 -289.773831) (xy 186.641188 -289.719146) (xy 186.677904 -289.668668)
			(xy 186.720662 -289.623196) (xy 186.768788 -289.583447) (xy 186.794902 -289.56635) (xy 186.805062 -289.56)
			(xy 186.817254 -289.540188) (xy 186.826906 -289.436048) (xy 186.818524 -289.414204) (xy 186.809634 -289.406076)
			(xy 186.791309 -289.388558) (xy 186.759165 -289.349356) (xy 186.732692 -289.306123) (xy 186.712387 -289.259671)
			(xy 186.698634 -289.210877) (xy 186.691691 -289.16066) (xy 186.69127 -289.135312) (xy 186.691664 -289.109993)
			(xy 186.698591 -289.059833) (xy 186.712317 -289.011091) (xy 186.732582 -288.964686) (xy 186.759006 -288.921491)
			(xy 186.791093 -288.882317) (xy 186.80938 -288.864802) (xy 186.81827 -288.85642) (xy 186.826652 -288.83483)
			(xy 186.817254 -288.73069) (xy 186.805062 -288.710878) (xy 186.794902 -288.704274) (xy 186.768785 -288.687207)
			(xy 186.720668 -288.647489) (xy 186.677915 -288.602048) (xy 186.641202 -288.551601) (xy 186.61111 -288.496947)
			(xy 186.588113 -288.438948) (xy 186.572575 -288.378522) (xy 186.564743 -288.316624) (xy 186.56427 -288.285428)
			(xy 186.564759 -288.254265) (xy 186.572571 -288.192431) (xy 186.588071 -288.132063) (xy 186.611014 -288.074115)
			(xy 186.64104 -288.019498) (xy 186.677674 -287.969076) (xy 186.720339 -287.923642) (xy 186.768361 -287.883914)
			(xy 186.820985 -287.850519) (xy 186.877379 -287.823982) (xy 186.936654 -287.804722) (xy 186.997875 -287.793043)
			(xy 187.060078 -287.78913) (xy 187.122281 -287.793043) (xy 187.183502 -287.804722) (xy 187.242777 -287.823982)
			(xy 187.299171 -287.850519) (xy 187.351795 -287.883914) (xy 187.399817 -287.923642) (xy 187.442482 -287.969076)
			(xy 187.479116 -288.019498) (xy 187.509142 -288.074115) (xy 187.532085 -288.132063) (xy 187.547585 -288.192431)
			(xy 187.555397 -288.254265) (xy 187.555886 -288.285428) (xy 187.555478 -288.316627) (xy 187.547652 -288.378532)
			(xy 187.532115 -288.438965) (xy 187.509112 -288.496968) (xy 187.479009 -288.551624) (xy 187.442281 -288.602068)
			(xy 187.39951 -288.6475) (xy 187.351372 -288.687203) (xy 187.325254 -288.704274) (xy 187.315094 -288.710878)
			(xy 187.302902 -288.73069) (xy 187.293504 -288.83483) (xy 187.301886 -288.85642) (xy 187.310776 -288.864802)
			(xy 187.329076 -288.882303) (xy 187.361151 -288.921484) (xy 187.387566 -288.964684) (xy 187.407824 -289.011092)
			(xy 187.421544 -289.059833) (xy 187.428469 -289.109994) (xy 187.428886 -289.135312) (xy 187.428467 -289.16066)
			(xy 187.421533 -289.21088) (xy 187.407783 -289.259676) (xy 187.387477 -289.306128) (xy 187.360998 -289.34936)
			(xy 187.328846 -289.388556) (xy 187.310522 -289.406076) (xy 187.301632 -289.414204) (xy 187.29325 -289.436048)
			(xy 187.302902 -289.540188) (xy 187.315094 -289.56) (xy 187.325254 -289.56635) (xy 187.351362 -289.583454)
			(xy 187.399482 -289.623207) (xy 187.442236 -289.668681) (xy 187.47895 -289.719159) (xy 187.509043 -289.773842)
			(xy 187.53204 -289.831867) (xy 187.547578 -289.892319) (xy 187.555412 -289.954242) (xy 187.555886 -289.98545)
			(xy 187.555417 -290.016647) (xy 187.5476 -290.07855) (xy 187.532073 -290.138981) (xy 187.509079 -290.196984)
			(xy 187.478984 -290.25164) (xy 187.442264 -290.302085) (xy 187.3995 -290.347519) (xy 187.351369 -290.387224)
			(xy 187.325254 -290.404296) (xy 187.315094 -290.4109) (xy 187.302902 -290.430712) (xy 187.293504 -290.534852)
			(xy 187.301886 -290.556442) (xy 187.310776 -290.564824) (xy 187.330736 -290.583926) (xy 187.365203 -290.627105)
			(xy 187.392844 -290.674942) (xy 187.41304 -290.726367) (xy 187.42534 -290.780229) (xy 187.429468 -290.835323)
			(xy 187.425333 -290.890417) (xy 187.413026 -290.944277) (xy 187.392824 -290.995699) (xy 187.365177 -291.043533)
			(xy 187.330705 -291.086708) (xy 187.310776 -291.105844) (xy 187.301886 -291.114226) (xy 187.293504 -291.135816)
			(xy 187.302902 -291.239956) (xy 187.315094 -291.259768) (xy 187.325254 -291.266372) (xy 187.351336 -291.283491)
			(xy 187.399455 -291.323199) (xy 187.442211 -291.368632) (xy 187.478928 -291.419071) (xy 187.509025 -291.473718)
			(xy 187.532028 -291.531711) (xy 187.547571 -291.592131) (xy 187.55541 -291.654024) (xy 187.555886 -291.685218)
			(xy 187.555406 -291.716427) (xy 187.547585 -291.778354) (xy 187.532055 -291.838809) (xy 187.509062 -291.896839)
			(xy 187.47897 -291.951525) (xy 187.442255 -292.002002) (xy 187.399495 -292.047475) (xy 187.351369 -292.087222)
			(xy 187.325254 -292.104318) (xy 187.315094 -292.110668) (xy 187.302902 -292.13048) (xy 187.29325 -292.23462)
			(xy 187.301632 -292.256464) (xy 187.310522 -292.264592) (xy 187.328842 -292.282114) (xy 187.360984 -292.321317)
			(xy 187.387457 -292.36455) (xy 187.407762 -292.411) (xy 187.421517 -292.459793) (xy 187.428463 -292.510009)
			(xy 187.428886 -292.535356) (xy 190.664338 -292.535356) (xy 190.664786 -292.504146) (xy 190.672611 -292.442217)
			(xy 190.688145 -292.381761) (xy 190.711142 -292.323731) (xy 190.741238 -292.269045) (xy 190.777959 -292.218567)
			(xy 190.820722 -292.173096) (xy 190.868853 -292.133351) (xy 190.89497 -292.116256) (xy 190.90513 -292.109906)
			(xy 190.917322 -292.090094) (xy 190.926974 -291.985954) (xy 190.918592 -291.96411) (xy 190.909702 -291.955982)
			(xy 190.891374 -291.938468) (xy 190.859232 -291.899264) (xy 190.832759 -291.85603) (xy 190.812456 -291.809578)
			(xy 190.798703 -291.760783) (xy 190.791759 -291.710566) (xy 190.791338 -291.685218) (xy 190.791746 -291.6599)
			(xy 190.798671 -291.60974) (xy 190.812395 -291.560999) (xy 190.832658 -291.514594) (xy 190.859079 -291.471398)
			(xy 190.891162 -291.432223) (xy 190.909448 -291.414708) (xy 190.918338 -291.406326) (xy 190.92672 -291.384736)
			(xy 190.917322 -291.280596) (xy 190.90513 -291.260784) (xy 190.89497 -291.25418) (xy 190.868888 -291.237058)
			(xy 190.820762 -291.197353) (xy 190.777999 -291.151921) (xy 190.741278 -291.101481) (xy 190.711178 -291.046831)
			(xy 190.688176 -290.988835) (xy 190.672635 -290.928411) (xy 190.664801 -290.866514) (xy 190.664799 -290.804123)
			(xy 190.672628 -290.742225) (xy 190.688164 -290.681799) (xy 190.711162 -290.623801) (xy 190.741258 -290.569149)
			(xy 190.777976 -290.518707) (xy 190.820735 -290.473272) (xy 190.868859 -290.433564) (xy 190.89497 -290.416488)
			(xy 190.90513 -290.409884) (xy 190.917322 -290.390072) (xy 190.92672 -290.285932) (xy 190.918338 -290.264342)
			(xy 190.909448 -290.25596) (xy 190.891183 -290.238425) (xy 190.859103 -290.199251) (xy 190.832683 -290.156059)
			(xy 190.812419 -290.109658) (xy 190.798692 -290.060922) (xy 190.79176 -290.010766) (xy 190.791338 -289.98545)
			(xy 190.791724 -289.960101) (xy 190.798664 -289.909879) (xy 190.81242 -289.861082) (xy 190.832731 -289.81463)
			(xy 190.859217 -289.771399) (xy 190.891375 -289.732205) (xy 190.909702 -289.714686) (xy 190.918592 -289.706558)
			(xy 190.926974 -289.684714) (xy 190.917322 -289.580574) (xy 190.90513 -289.560762) (xy 190.89497 -289.554412)
			(xy 190.86885 -289.537325) (xy 190.820729 -289.49757) (xy 190.777975 -289.452094) (xy 190.741262 -289.401614)
			(xy 190.71117 -289.346929) (xy 190.688175 -289.2889) (xy 190.67264 -289.228446) (xy 190.664809 -289.166521)
			(xy 190.664338 -289.135312) (xy 190.664813 -289.104115) (xy 190.672632 -289.042214) (xy 190.688162 -288.981785)
			(xy 190.711156 -288.923783) (xy 190.74125 -288.869128) (xy 190.777968 -288.818683) (xy 190.820729 -288.773247)
			(xy 190.868856 -288.73354) (xy 190.89497 -288.716466) (xy 190.90513 -288.709862) (xy 190.917322 -288.69005)
			(xy 190.92672 -288.58591) (xy 190.918338 -288.56432) (xy 190.909448 -288.555938) (xy 190.891172 -288.538413)
			(xy 190.859093 -288.499238) (xy 190.832675 -288.456043) (xy 190.812412 -288.40964) (xy 190.798688 -288.360902)
			(xy 190.791758 -288.310745) (xy 190.791338 -288.285428) (xy 190.791776 -288.26008) (xy 190.798705 -288.209861)
			(xy 190.812451 -288.161065) (xy 190.832753 -288.114612) (xy 190.859229 -288.07138) (xy 190.891379 -288.032184)
			(xy 190.909702 -288.014664) (xy 190.918592 -288.006536) (xy 190.926974 -287.984692) (xy 190.917322 -287.880552)
			(xy 190.90513 -287.86074) (xy 190.89497 -287.85439) (xy 190.86884 -287.837318) (xy 190.820719 -287.797561)
			(xy 190.777965 -287.752083) (xy 190.741253 -287.701601) (xy 190.711163 -287.646913) (xy 190.688169 -287.588883)
			(xy 190.672636 -287.528427) (xy 190.664808 -287.4665) (xy 190.664338 -287.43529) (xy 190.664827 -287.404127)
			(xy 190.672639 -287.342293) (xy 190.688139 -287.281925) (xy 190.711082 -287.223977) (xy 190.741108 -287.16936)
			(xy 190.777742 -287.118938) (xy 190.820407 -287.073504) (xy 190.868429 -287.033776) (xy 190.921053 -287.000381)
			(xy 190.977447 -286.973844) (xy 191.036722 -286.954584) (xy 191.097943 -286.942905) (xy 191.160146 -286.938992)
			(xy 191.222349 -286.942905) (xy 191.28357 -286.954584) (xy 191.342845 -286.973844) (xy 191.399239 -287.000381)
			(xy 191.451863 -287.033776) (xy 191.499885 -287.073504) (xy 191.54255 -287.118938) (xy 191.579184 -287.16936)
			(xy 191.60921 -287.223977) (xy 191.632153 -287.281925) (xy 191.647653 -287.342293) (xy 191.655465 -287.404127)
			(xy 191.655954 -287.43529) (xy 195.619131 -287.43529) (xy 195.623066 -287.381519) (xy 195.634789 -287.328895)
			(xy 195.654049 -287.278538) (xy 195.680435 -287.231521) (xy 195.713387 -287.188848) (xy 195.7522 -287.151427)
			(xy 195.796048 -287.120057) (xy 195.843996 -287.095405) (xy 195.895023 -287.077997) (xy 195.948041 -287.068204)
			(xy 196.00192 -287.066235) (xy 196.055511 -287.072132) (xy 196.107672 -287.085768) (xy 196.157292 -287.106855)
			(xy 196.203313 -287.134941) (xy 196.244755 -287.169429) (xy 196.280733 -287.209583) (xy 196.310481 -287.254547)
			(xy 196.333366 -287.303364) (xy 196.348898 -287.354993) (xy 196.356748 -287.408333) (xy 196.35724 -287.43529)
			(xy 196.356748 -287.462247) (xy 196.348898 -287.515587) (xy 196.333366 -287.567216) (xy 196.310481 -287.616033)
			(xy 196.280733 -287.660997) (xy 196.244755 -287.701151) (xy 196.203313 -287.735639) (xy 196.157292 -287.763725)
			(xy 196.107672 -287.784812) (xy 196.055511 -287.798448) (xy 196.00192 -287.804345) (xy 195.948041 -287.802376)
			(xy 195.895023 -287.792583) (xy 195.843996 -287.775175) (xy 195.796048 -287.750523) (xy 195.7522 -287.719153)
			(xy 195.713387 -287.681732) (xy 195.680435 -287.639059) (xy 195.654049 -287.592042) (xy 195.634789 -287.541685)
			(xy 195.623066 -287.489061) (xy 195.619131 -287.43529) (xy 191.655954 -287.43529) (xy 191.655546 -287.466502)
			(xy 191.647714 -287.528432) (xy 191.632175 -287.58889) (xy 191.609172 -287.64692) (xy 191.579071 -287.701606)
			(xy 191.542345 -287.752082) (xy 191.499577 -287.797552) (xy 191.451441 -287.837296) (xy 191.425322 -287.85439)
			(xy 191.415162 -287.86074) (xy 191.40297 -287.880552) (xy 191.393318 -287.984692) (xy 191.4017 -288.006536)
			(xy 191.41059 -288.014664) (xy 191.42889 -288.032206) (xy 191.461035 -288.071403) (xy 191.487512 -288.114632)
			(xy 191.50782 -288.161079) (xy 191.521579 -288.209868) (xy 191.528529 -288.260082) (xy 191.528954 -288.285428)
			(xy 191.528512 -288.310745) (xy 191.521594 -288.360903) (xy 191.507877 -288.409644) (xy 191.487621 -288.456049)
			(xy 191.461205 -288.499245) (xy 191.429127 -288.538421) (xy 191.410844 -288.555938) (xy 191.401954 -288.56432)
			(xy 191.393572 -288.58591) (xy 191.40297 -288.69005) (xy 191.415162 -288.709862) (xy 191.425322 -288.716466)
			(xy 191.451417 -288.733565) (xy 191.499533 -288.773279) (xy 191.542286 -288.818716) (xy 191.579 -288.869158)
			(xy 191.609096 -288.923808) (xy 191.632096 -288.981802) (xy 191.647639 -289.042224) (xy 191.655478 -289.104118)
			(xy 191.655954 -289.135312) (xy 191.655484 -289.166522) (xy 191.647663 -289.228449) (xy 191.632133 -289.288906)
			(xy 191.609139 -289.346936) (xy 191.579046 -289.401622) (xy 191.542328 -289.452099) (xy 191.499567 -289.497571)
			(xy 191.451438 -289.537317) (xy 191.425322 -289.554412) (xy 191.415162 -289.560762) (xy 191.40297 -289.580574)
			(xy 191.393318 -289.684714) (xy 191.4017 -289.706558) (xy 191.41059 -289.714686) (xy 191.428901 -289.732218)
			(xy 191.461045 -289.771417) (xy 191.48752 -289.814648) (xy 191.507827 -289.861097) (xy 191.521583 -289.909888)
			(xy 191.52853 -289.960103) (xy 191.528954 -289.98545) (xy 191.528527 -290.010767) (xy 191.521605 -290.060927)
			(xy 191.507886 -290.109667) (xy 191.487627 -290.156072) (xy 191.461209 -290.199268) (xy 191.429128 -290.238444)
			(xy 191.410844 -290.25596) (xy 191.401954 -290.264342) (xy 191.393572 -290.285932) (xy 191.40297 -290.390072)
			(xy 191.415162 -290.409884) (xy 191.425322 -290.416488) (xy 191.451467 -290.433517) (xy 191.499597 -290.473229)
			(xy 191.542362 -290.518669) (xy 191.579085 -290.569117) (xy 191.609185 -290.623776) (xy 191.632186 -290.681781)
			(xy 191.647724 -290.742214) (xy 191.655554 -290.804119) (xy 191.655552 -290.866517) (xy 191.647717 -290.928422)
			(xy 191.632174 -290.988854) (xy 191.609169 -291.046857) (xy 191.579065 -291.101513) (xy 191.542339 -291.151959)
			(xy 191.499571 -291.197395) (xy 191.451438 -291.237104) (xy 191.425322 -291.25418) (xy 191.415162 -291.260784)
			(xy 191.40297 -291.280596) (xy 191.393572 -291.384736) (xy 191.401954 -291.406326) (xy 191.410844 -291.414708)
			(xy 191.429141 -291.432212) (xy 191.461218 -291.471392) (xy 191.487634 -291.514591) (xy 191.507893 -291.560998)
			(xy 191.521613 -291.60974) (xy 191.528537 -291.6599) (xy 191.528954 -291.685218) (xy 191.528549 -291.710567)
			(xy 191.521613 -291.760788) (xy 191.507862 -291.809585) (xy 191.487553 -291.856037) (xy 191.461071 -291.899268)
			(xy 191.428916 -291.938463) (xy 191.41059 -291.955982) (xy 191.4017 -291.96411) (xy 191.393318 -291.985954)
			(xy 191.40297 -292.090094) (xy 191.415162 -292.109906) (xy 191.425322 -292.116256) (xy 191.451426 -292.133367)
			(xy 191.499547 -292.173118) (xy 191.542302 -292.218591) (xy 191.579017 -292.269067) (xy 191.609111 -292.323749)
			(xy 191.632108 -292.381774) (xy 191.647647 -292.442225) (xy 191.655481 -292.504148) (xy 191.655954 -292.535356)
			(xy 191.655465 -292.566519) (xy 191.647653 -292.628353) (xy 191.632153 -292.688721) (xy 191.60921 -292.746669)
			(xy 191.579184 -292.801286) (xy 191.54255 -292.851708) (xy 191.499885 -292.897142) (xy 191.451863 -292.93687)
			(xy 191.399239 -292.970265) (xy 191.342845 -292.996802) (xy 191.28357 -293.016062) (xy 191.222349 -293.027741)
			(xy 191.160146 -293.031654) (xy 191.097943 -293.027741) (xy 191.036722 -293.016062) (xy 190.977447 -292.996802)
			(xy 190.921053 -292.970265) (xy 190.868429 -292.93687) (xy 190.820407 -292.897142) (xy 190.777742 -292.851708)
			(xy 190.741108 -292.801286) (xy 190.711082 -292.746669) (xy 190.688139 -292.688721) (xy 190.672639 -292.628353)
			(xy 190.664827 -292.566519) (xy 190.664338 -292.535356) (xy 187.428886 -292.535356) (xy 187.428453 -292.560673)
			(xy 187.421531 -292.610832) (xy 187.407812 -292.659571) (xy 187.387554 -292.705976) (xy 187.361138 -292.749173)
			(xy 187.329059 -292.788349) (xy 187.310776 -292.805866) (xy 187.301886 -292.814248) (xy 187.293504 -292.835838)
			(xy 187.302902 -292.939978) (xy 187.315094 -292.95979) (xy 187.325254 -292.966394) (xy 187.351346 -292.983498)
			(xy 187.399465 -293.023209) (xy 187.442221 -293.068644) (xy 187.478937 -293.119085) (xy 187.509033 -293.173734)
			(xy 187.532033 -293.231729) (xy 187.547575 -293.292151) (xy 187.555411 -293.354046) (xy 187.555886 -293.38524)
			(xy 189.406545 -293.38524) (xy 189.41048 -293.331469) (xy 189.422203 -293.278845) (xy 189.441463 -293.228488)
			(xy 189.467849 -293.181471) (xy 189.500801 -293.138798) (xy 189.539614 -293.101377) (xy 189.583462 -293.070007)
			(xy 189.63141 -293.045355) (xy 189.682437 -293.027947) (xy 189.735455 -293.018154) (xy 189.789334 -293.016185)
			(xy 189.842925 -293.022082) (xy 189.895086 -293.035718) (xy 189.944706 -293.056805) (xy 189.990727 -293.084891)
			(xy 190.032169 -293.119379) (xy 190.068147 -293.159533) (xy 190.097895 -293.204497) (xy 190.12078 -293.253314)
			(xy 190.136312 -293.304943) (xy 190.144162 -293.358283) (xy 190.144654 -293.38524) (xy 194.108324 -293.38524)
			(xy 194.108781 -293.354042) (xy 194.116598 -293.292139) (xy 194.132128 -293.231707) (xy 194.155123 -293.173704)
			(xy 194.18522 -293.119048) (xy 194.221941 -293.068603) (xy 194.264707 -293.02317) (xy 194.31284 -292.983466)
			(xy 194.338956 -292.966394) (xy 194.349116 -292.95979) (xy 194.361308 -292.939978) (xy 194.370706 -292.835838)
			(xy 194.362324 -292.814248) (xy 194.353434 -292.805866) (xy 194.335169 -292.78833) (xy 194.30309 -292.749157)
			(xy 194.27667 -292.705964) (xy 194.256406 -292.659564) (xy 194.242679 -292.610828) (xy 194.235746 -292.560672)
			(xy 194.235324 -292.535356) (xy 194.235719 -292.510007) (xy 194.242657 -292.459786) (xy 194.256412 -292.410989)
			(xy 194.276722 -292.364537) (xy 194.303205 -292.321306) (xy 194.335362 -292.282111) (xy 194.353688 -292.264592)
			(xy 194.362578 -292.256464) (xy 194.37096 -292.23462) (xy 194.361308 -292.13048) (xy 194.349116 -292.110668)
			(xy 194.338956 -292.104318) (xy 194.312835 -292.087232) (xy 194.264715 -292.047477) (xy 194.221961 -292.002)
			(xy 194.185249 -291.95152) (xy 194.155157 -291.896834) (xy 194.132162 -291.838806) (xy 194.116626 -291.778352)
			(xy 194.108796 -291.716427) (xy 194.108324 -291.685218) (xy 194.108764 -291.65402) (xy 194.116584 -291.592116)
			(xy 194.132116 -291.531684) (xy 194.155113 -291.473681) (xy 194.185213 -291.419024) (xy 194.221937 -291.36858)
			(xy 194.264704 -291.323147) (xy 194.312839 -291.283444) (xy 194.338956 -291.266372) (xy 194.349116 -291.259768)
			(xy 194.361308 -291.239956) (xy 194.370706 -291.135816) (xy 194.362324 -291.114226) (xy 194.353434 -291.105844)
			(xy 194.333541 -291.086674) (xy 194.299073 -291.043506) (xy 194.271429 -290.995678) (xy 194.251229 -290.944263)
			(xy 194.238923 -290.89041) (xy 194.234788 -290.835323) (xy 194.238916 -290.780236) (xy 194.251215 -290.726381)
			(xy 194.271409 -290.674963) (xy 194.299047 -290.627133) (xy 194.33351 -290.58396) (xy 194.353434 -290.564824)
			(xy 194.362324 -290.556442) (xy 194.370706 -290.534852) (xy 194.361308 -290.430712) (xy 194.349116 -290.4109)
			(xy 194.338956 -290.404296) (xy 194.312862 -290.387195) (xy 194.264742 -290.347485) (xy 194.221986 -290.302049)
			(xy 194.18527 -290.251608) (xy 194.155174 -290.196958) (xy 194.132174 -290.138963) (xy 194.116634 -290.07854)
			(xy 194.108798 -290.016645) (xy 194.108324 -289.98545) (xy 194.108774 -289.95424) (xy 194.1166 -289.892312)
			(xy 194.132134 -289.831855) (xy 194.15513 -289.773826) (xy 194.185227 -289.71914) (xy 194.221946 -289.668662)
			(xy 194.264709 -289.623191) (xy 194.31284 -289.583445) (xy 194.338956 -289.56635) (xy 194.349116 -289.56)
			(xy 194.361308 -289.540188) (xy 194.37096 -289.436048) (xy 194.362578 -289.414204) (xy 194.353688 -289.406076)
			(xy 194.335354 -289.388567) (xy 194.303213 -289.349362) (xy 194.276742 -289.306126) (xy 194.256439 -289.259673)
			(xy 194.242687 -289.210878) (xy 194.235745 -289.16066) (xy 194.235324 -289.135312) (xy 194.235732 -289.109994)
			(xy 194.242658 -289.059834) (xy 194.256382 -289.011094) (xy 194.276645 -288.964689) (xy 194.303066 -288.921493)
			(xy 194.335148 -288.882318) (xy 194.353434 -288.864802) (xy 194.362324 -288.85642) (xy 194.370706 -288.83483)
			(xy 194.361308 -288.73069) (xy 194.349116 -288.710878) (xy 194.338956 -288.704274) (xy 194.312852 -288.687188)
			(xy 194.264732 -288.647475) (xy 194.221977 -288.602038) (xy 194.185262 -288.551594) (xy 194.155167 -288.496942)
			(xy 194.132168 -288.438945) (xy 194.11663 -288.37852) (xy 194.108797 -288.316623) (xy 194.108324 -288.285428)
			(xy 194.108813 -288.254265) (xy 194.116625 -288.192431) (xy 194.132125 -288.132063) (xy 194.155068 -288.074115)
			(xy 194.185094 -288.019498) (xy 194.221728 -287.969076) (xy 194.264393 -287.923642) (xy 194.312415 -287.883914)
			(xy 194.365039 -287.850519) (xy 194.421433 -287.823982) (xy 194.480708 -287.804722) (xy 194.541929 -287.793043)
			(xy 194.604132 -287.78913) (xy 194.666335 -287.793043) (xy 194.727556 -287.804722) (xy 194.786831 -287.823982)
			(xy 194.843225 -287.850519) (xy 194.895849 -287.883914) (xy 194.943871 -287.923642) (xy 194.986536 -287.969076)
			(xy 195.02317 -288.019498) (xy 195.053196 -288.074115) (xy 195.076139 -288.132063) (xy 195.091639 -288.192431)
			(xy 195.099451 -288.254265) (xy 195.09994 -288.285428) (xy 195.099507 -288.316626) (xy 195.091682 -288.378529)
			(xy 195.076147 -288.43896) (xy 195.053147 -288.496962) (xy 195.023047 -288.551618) (xy 194.986323 -288.602062)
			(xy 194.943557 -288.647496) (xy 194.895424 -288.687201) (xy 194.869308 -288.704274) (xy 194.859148 -288.710878)
			(xy 194.846956 -288.73069) (xy 194.837558 -288.83483) (xy 194.84594 -288.85642) (xy 194.85483 -288.864802)
			(xy 194.873121 -288.882312) (xy 194.905199 -288.92149) (xy 194.931616 -288.964688) (xy 194.951876 -289.011094)
			(xy 194.965598 -289.059835) (xy 194.972522 -289.109994) (xy 194.97294 -289.135312) (xy 194.972504 -289.160659)
			(xy 194.965571 -289.210878) (xy 194.951823 -289.259673) (xy 194.931521 -289.306125) (xy 194.905046 -289.349357)
			(xy 194.872897 -289.388555) (xy 194.854576 -289.406076) (xy 194.845686 -289.414204) (xy 194.837304 -289.436048)
			(xy 194.846956 -289.540188) (xy 194.859148 -289.56) (xy 194.869308 -289.56635) (xy 194.895405 -289.58347)
			(xy 194.943527 -289.623219) (xy 194.986283 -289.66869) (xy 195.022999 -289.719165) (xy 195.053093 -289.773846)
			(xy 195.076092 -289.83187) (xy 195.091631 -289.89232) (xy 195.099466 -289.954242) (xy 195.09994 -289.98545)
			(xy 195.099446 -290.016646) (xy 195.09163 -290.078547) (xy 195.076105 -290.138976) (xy 195.053114 -290.196978)
			(xy 195.023023 -290.251634) (xy 194.986306 -290.302079) (xy 194.943547 -290.347515) (xy 194.895421 -290.387222)
			(xy 194.869308 -290.404296) (xy 194.859148 -290.4109) (xy 194.846956 -290.430712) (xy 194.837558 -290.534852)
			(xy 194.84594 -290.556442) (xy 194.85483 -290.564824) (xy 194.874788 -290.583927) (xy 194.90925 -290.627108)
			(xy 194.936886 -290.674946) (xy 194.957079 -290.72637) (xy 194.969377 -290.780231) (xy 194.973505 -290.835323)
			(xy 194.96937 -290.890415) (xy 194.957066 -290.944274) (xy 194.936866 -290.995696) (xy 194.909224 -291.04353)
			(xy 194.874756 -291.086707) (xy 194.85483 -291.105844) (xy 194.84594 -291.114226) (xy 194.837558 -291.135816)
			(xy 194.846956 -291.239956) (xy 194.859148 -291.259768) (xy 194.869308 -291.266372) (xy 194.895402 -291.283472)
			(xy 194.943519 -291.323185) (xy 194.986273 -291.368622) (xy 195.022987 -291.419064) (xy 195.053083 -291.473714)
			(xy 195.076083 -291.531708) (xy 195.091626 -291.592129) (xy 195.099464 -291.654024) (xy 195.09994 -291.685218)
			(xy 195.099435 -291.716426) (xy 195.091615 -291.778351) (xy 195.076087 -291.838805) (xy 195.053097 -291.896833)
			(xy 195.023009 -291.951518) (xy 194.986297 -292.001997) (xy 194.943542 -292.04747) (xy 194.89542 -292.087221)
			(xy 194.869308 -292.104318) (xy 194.859148 -292.110668) (xy 194.846956 -292.13048) (xy 194.837304 -292.23462)
			(xy 194.845686 -292.256464) (xy 194.854576 -292.264592) (xy 194.872887 -292.282123) (xy 194.905032 -292.321323)
			(xy 194.931507 -292.364554) (xy 194.951814 -292.411002) (xy 194.96557 -292.459794) (xy 194.972517 -292.510009)
			(xy 194.97294 -292.535356) (xy 198.208392 -292.535356) (xy 198.208861 -292.504147) (xy 198.216686 -292.44222)
			(xy 198.232218 -292.381764) (xy 198.255212 -292.323735) (xy 198.285306 -292.26905) (xy 198.322023 -292.218572)
			(xy 198.364782 -292.1731) (xy 198.412909 -292.133352) (xy 198.439024 -292.116256) (xy 198.449184 -292.109906)
			(xy 198.461376 -292.090094) (xy 198.471028 -291.985954) (xy 198.462646 -291.96411) (xy 198.453756 -291.955982)
			(xy 198.435438 -291.938457) (xy 198.403293 -291.899257) (xy 198.376818 -291.856025) (xy 198.356512 -291.809575)
			(xy 198.342757 -291.760782) (xy 198.335813 -291.710565) (xy 198.335392 -291.685218) (xy 198.335815 -291.659901)
			(xy 198.342739 -291.609742) (xy 198.356461 -291.561002) (xy 198.376721 -291.514597) (xy 198.403139 -291.471401)
			(xy 198.435218 -291.432225) (xy 198.453502 -291.414708) (xy 198.462392 -291.406326) (xy 198.470774 -291.384736)
			(xy 198.461376 -291.280596) (xy 198.449184 -291.260784) (xy 198.439024 -291.25418) (xy 198.41294 -291.237059)
			(xy 198.364808 -291.197357) (xy 198.322042 -291.151927) (xy 198.285316 -291.101488) (xy 198.255212 -291.046837)
			(xy 198.232207 -290.98884) (xy 198.216665 -290.928414) (xy 198.20883 -290.866515) (xy 198.208828 -290.804122)
			(xy 198.216658 -290.742222) (xy 198.232196 -290.681794) (xy 198.255197 -290.623796) (xy 198.285296 -290.569143)
			(xy 198.322018 -290.518701) (xy 198.364782 -290.473268) (xy 198.41291 -290.433562) (xy 198.439024 -290.416488)
			(xy 198.449184 -290.409884) (xy 198.461376 -290.390072) (xy 198.470774 -290.285932) (xy 198.462392 -290.264342)
			(xy 198.453502 -290.25596) (xy 198.435247 -290.238414) (xy 198.403164 -290.199244) (xy 198.376742 -290.156054)
			(xy 198.356475 -290.109655) (xy 198.342747 -290.06092) (xy 198.335814 -290.010766) (xy 198.335392 -289.98545)
			(xy 198.335793 -289.960101) (xy 198.342732 -289.909881) (xy 198.356485 -289.861085) (xy 198.376795 -289.814633)
			(xy 198.403276 -289.771401) (xy 198.435431 -289.732206) (xy 198.453756 -289.714686) (xy 198.462646 -289.706558)
			(xy 198.471028 -289.684714) (xy 198.461376 -289.580574) (xy 198.449184 -289.560762) (xy 198.439024 -289.554412)
			(xy 198.412917 -289.537306) (xy 198.364794 -289.497556) (xy 198.322037 -289.452083) (xy 198.285322 -289.401607)
			(xy 198.255228 -289.346923) (xy 198.232231 -289.288897) (xy 198.216695 -289.228445) (xy 198.208864 -289.166521)
			(xy 198.208392 -289.135312) (xy 198.208842 -289.104114) (xy 198.216662 -289.042211) (xy 198.232194 -288.98178)
			(xy 198.25519 -288.923777) (xy 198.285288 -288.869121) (xy 198.32201 -288.818677) (xy 198.364776 -288.773243)
			(xy 198.412908 -288.733538) (xy 198.439024 -288.716466) (xy 198.449184 -288.709862) (xy 198.461376 -288.69005)
			(xy 198.470774 -288.58591) (xy 198.462392 -288.56432) (xy 198.453502 -288.555938) (xy 198.435236 -288.538403)
			(xy 198.403155 -288.499231) (xy 198.376733 -288.456038) (xy 198.356469 -288.409637) (xy 198.342743 -288.360901)
			(xy 198.335812 -288.310744) (xy 198.335392 -288.285428) (xy 198.335845 -288.260081) (xy 198.342773 -288.209863)
			(xy 198.356517 -288.161068) (xy 198.376816 -288.114616) (xy 198.403289 -288.071383) (xy 198.435435 -288.032185)
			(xy 198.453756 -288.014664) (xy 198.462646 -288.006536) (xy 198.471028 -287.984692) (xy 198.461376 -287.880552)
			(xy 198.449184 -287.86074) (xy 198.439024 -287.85439) (xy 198.412906 -287.837299) (xy 198.364784 -287.797547)
			(xy 198.322027 -287.752072) (xy 198.285313 -287.701593) (xy 198.25522 -287.646908) (xy 198.232225 -287.588879)
			(xy 198.216691 -287.528425) (xy 198.208862 -287.466499) (xy 198.208392 -287.43529) (xy 198.208881 -287.404127)
			(xy 198.216693 -287.342293) (xy 198.232193 -287.281925) (xy 198.255136 -287.223977) (xy 198.285162 -287.16936)
			(xy 198.321796 -287.118938) (xy 198.364461 -287.073504) (xy 198.412483 -287.033776) (xy 198.465107 -287.000381)
			(xy 198.521501 -286.973844) (xy 198.580776 -286.954584) (xy 198.641997 -286.942905) (xy 198.7042 -286.938992)
			(xy 198.766403 -286.942905) (xy 198.827624 -286.954584) (xy 198.886899 -286.973844) (xy 198.943293 -287.000381)
			(xy 198.995917 -287.033776) (xy 199.043939 -287.073504) (xy 199.086604 -287.118938) (xy 199.123238 -287.16936)
			(xy 199.153264 -287.223977) (xy 199.176207 -287.281925) (xy 199.191707 -287.342293) (xy 199.199519 -287.404127)
			(xy 199.200008 -287.43529) (xy 203.162931 -287.43529) (xy 203.166866 -287.381519) (xy 203.178589 -287.328895)
			(xy 203.197849 -287.278538) (xy 203.224235 -287.231521) (xy 203.257187 -287.188848) (xy 203.296 -287.151427)
			(xy 203.339848 -287.120057) (xy 203.387796 -287.095405) (xy 203.438823 -287.077997) (xy 203.491841 -287.068204)
			(xy 203.54572 -287.066235) (xy 203.599311 -287.072132) (xy 203.651472 -287.085768) (xy 203.701092 -287.106855)
			(xy 203.747113 -287.134941) (xy 203.788555 -287.169429) (xy 203.824533 -287.209583) (xy 203.854281 -287.254547)
			(xy 203.877166 -287.303364) (xy 203.892698 -287.354993) (xy 203.900548 -287.408333) (xy 203.90104 -287.43529)
			(xy 203.900548 -287.462247) (xy 203.892698 -287.515587) (xy 203.877166 -287.567216) (xy 203.854281 -287.616033)
			(xy 203.824533 -287.660997) (xy 203.788555 -287.701151) (xy 203.747113 -287.735639) (xy 203.701092 -287.763725)
			(xy 203.651472 -287.784812) (xy 203.599311 -287.798448) (xy 203.54572 -287.804345) (xy 203.491841 -287.802376)
			(xy 203.438823 -287.792583) (xy 203.387796 -287.775175) (xy 203.339848 -287.750523) (xy 203.296 -287.719153)
			(xy 203.257187 -287.681732) (xy 203.224235 -287.639059) (xy 203.197849 -287.592042) (xy 203.178589 -287.541685)
			(xy 203.166866 -287.489061) (xy 203.162931 -287.43529) (xy 199.200008 -287.43529) (xy 199.199575 -287.466501)
			(xy 199.191744 -287.528429) (xy 199.176207 -287.588885) (xy 199.153207 -287.646914) (xy 199.123109 -287.7016)
			(xy 199.086387 -287.752077) (xy 199.043623 -287.797548) (xy 198.995492 -287.837295) (xy 198.969376 -287.85439)
			(xy 198.959216 -287.86074) (xy 198.947024 -287.880552) (xy 198.937372 -287.984692) (xy 198.945754 -288.006536)
			(xy 198.954644 -288.014664) (xy 198.972936 -288.032215) (xy 199.005083 -288.071409) (xy 199.031562 -288.114636)
			(xy 199.051872 -288.161081) (xy 199.065632 -288.209869) (xy 199.072583 -288.260082) (xy 199.073008 -288.285428)
			(xy 199.072549 -288.310744) (xy 199.065632 -288.360901) (xy 199.051917 -288.40964) (xy 199.031664 -288.456045)
			(xy 199.005252 -288.499242) (xy 198.973179 -288.53842) (xy 198.954898 -288.555938) (xy 198.946008 -288.56432)
			(xy 198.937626 -288.58591) (xy 198.947024 -288.69005) (xy 198.959216 -288.709862) (xy 198.969376 -288.716466)
			(xy 198.99546 -288.733581) (xy 199.043578 -288.773291) (xy 199.086334 -288.818725) (xy 199.12305 -288.869164)
			(xy 199.153147 -288.923812) (xy 199.176149 -288.981805) (xy 199.191692 -289.042225) (xy 199.199532 -289.104118)
			(xy 199.200008 -289.135312) (xy 199.199514 -289.166521) (xy 199.191693 -289.228446) (xy 199.176165 -289.288901)
			(xy 199.153174 -289.34693) (xy 199.123084 -289.401616) (xy 199.086371 -289.452094) (xy 199.043614 -289.497567)
			(xy 198.995489 -289.537315) (xy 198.969376 -289.554412) (xy 198.959216 -289.560762) (xy 198.947024 -289.580574)
			(xy 198.937372 -289.684714) (xy 198.945754 -289.706558) (xy 198.954644 -289.714686) (xy 198.972946 -289.732227)
			(xy 199.005093 -289.771423) (xy 199.03157 -289.814652) (xy 199.051879 -289.861099) (xy 199.065637 -289.909889)
			(xy 199.072584 -289.960104) (xy 199.073008 -289.98545) (xy 199.072564 -290.010767) (xy 199.065644 -290.060924)
			(xy 199.051927 -290.109664) (xy 199.031671 -290.156069) (xy 199.005256 -290.199266) (xy 198.97318 -290.238443)
			(xy 198.954898 -290.25596) (xy 198.946008 -290.264342) (xy 198.937626 -290.285932) (xy 198.947024 -290.390072)
			(xy 198.959216 -290.409884) (xy 198.969376 -290.416488) (xy 198.995523 -290.433515) (xy 199.043657 -290.473226)
			(xy 199.086426 -290.518664) (xy 199.123152 -290.569112) (xy 199.153255 -290.623771) (xy 199.176259 -290.681777)
			(xy 199.191799 -290.742211) (xy 199.199629 -290.804118) (xy 199.199627 -290.866518) (xy 199.191792 -290.928425)
			(xy 199.176247 -290.988858) (xy 199.15324 -291.046862) (xy 199.123133 -291.101519) (xy 199.086403 -291.151964)
			(xy 199.043631 -291.197399) (xy 198.995494 -291.237106) (xy 198.969376 -291.25418) (xy 198.959216 -291.260784)
			(xy 198.947024 -291.280596) (xy 198.937626 -291.384736) (xy 198.946008 -291.406326) (xy 198.954898 -291.414708)
			(xy 198.973186 -291.432221) (xy 199.005266 -291.471398) (xy 199.031684 -291.514595) (xy 199.051945 -291.561)
			(xy 199.065666 -291.609741) (xy 199.072591 -291.6599) (xy 199.073008 -291.685218) (xy 199.072586 -291.710566)
			(xy 199.065651 -291.760786) (xy 199.051902 -291.809581) (xy 199.031597 -291.856033) (xy 199.005119 -291.899265)
			(xy 198.972967 -291.938462) (xy 198.954644 -291.955982) (xy 198.945754 -291.96411) (xy 198.937372 -291.985954)
			(xy 198.947024 -292.090094) (xy 198.959216 -292.109906) (xy 198.969376 -292.116256) (xy 198.995469 -292.133383)
			(xy 199.043592 -292.17313) (xy 199.086349 -292.2186) (xy 199.123066 -292.269073) (xy 199.153161 -292.323753)
			(xy 199.17616 -292.381777) (xy 199.1917 -292.442227) (xy 199.199534 -292.504148) (xy 199.200008 -292.535356)
			(xy 199.199519 -292.566519) (xy 199.191707 -292.628353) (xy 199.176207 -292.688721) (xy 199.153264 -292.746669)
			(xy 199.123238 -292.801286) (xy 199.086604 -292.851708) (xy 199.043939 -292.897142) (xy 198.995917 -292.93687)
			(xy 198.943293 -292.970265) (xy 198.886899 -292.996802) (xy 198.827624 -293.016062) (xy 198.766403 -293.027741)
			(xy 198.7042 -293.031654) (xy 198.641997 -293.027741) (xy 198.580776 -293.016062) (xy 198.521501 -292.996802)
			(xy 198.465107 -292.970265) (xy 198.412483 -292.93687) (xy 198.364461 -292.897142) (xy 198.321796 -292.851708)
			(xy 198.285162 -292.801286) (xy 198.255136 -292.746669) (xy 198.232193 -292.688721) (xy 198.216693 -292.628353)
			(xy 198.208881 -292.566519) (xy 198.208392 -292.535356) (xy 194.97294 -292.535356) (xy 194.972521 -292.560674)
			(xy 194.965599 -292.610833) (xy 194.951878 -292.659574) (xy 194.931617 -292.705979) (xy 194.905197 -292.749175)
			(xy 194.873115 -292.78835) (xy 194.85483 -292.805866) (xy 194.84594 -292.814248) (xy 194.837558 -292.835838)
			(xy 194.846956 -292.939978) (xy 194.859148 -292.95979) (xy 194.869308 -292.966394) (xy 194.895413 -292.983479)
			(xy 194.943529 -293.023195) (xy 194.986282 -293.068633) (xy 195.022996 -293.119077) (xy 195.05309 -293.173729)
			(xy 195.076089 -293.231726) (xy 195.091629 -293.292149) (xy 195.099465 -293.354045) (xy 195.09994 -293.38524)
			(xy 196.950599 -293.38524) (xy 196.954534 -293.331469) (xy 196.966257 -293.278845) (xy 196.985517 -293.228488)
			(xy 197.011903 -293.181471) (xy 197.044855 -293.138798) (xy 197.083668 -293.101377) (xy 197.127516 -293.070007)
			(xy 197.175464 -293.045355) (xy 197.226491 -293.027947) (xy 197.279509 -293.018154) (xy 197.333388 -293.016185)
			(xy 197.386979 -293.022082) (xy 197.43914 -293.035718) (xy 197.48876 -293.056805) (xy 197.534781 -293.084891)
			(xy 197.576223 -293.119379) (xy 197.612201 -293.159533) (xy 197.641949 -293.204497) (xy 197.664834 -293.253314)
			(xy 197.680366 -293.304943) (xy 197.688216 -293.358283) (xy 197.688708 -293.38524) (xy 201.652124 -293.38524)
			(xy 201.652581 -293.354042) (xy 201.660398 -293.292139) (xy 201.675928 -293.231707) (xy 201.698923 -293.173704)
			(xy 201.72902 -293.119048) (xy 201.765741 -293.068603) (xy 201.808507 -293.02317) (xy 201.85664 -292.983466)
			(xy 201.882756 -292.966394) (xy 201.892916 -292.95979) (xy 201.905108 -292.939978) (xy 201.914506 -292.835838)
			(xy 201.906124 -292.814248) (xy 201.897234 -292.805866) (xy 201.878969 -292.78833) (xy 201.84689 -292.749157)
			(xy 201.82047 -292.705964) (xy 201.800206 -292.659564) (xy 201.786479 -292.610828) (xy 201.779546 -292.560672)
			(xy 201.779124 -292.535356) (xy 201.779519 -292.510007) (xy 201.786457 -292.459786) (xy 201.800212 -292.410989)
			(xy 201.820522 -292.364537) (xy 201.847005 -292.321306) (xy 201.879162 -292.282111) (xy 201.897488 -292.264592)
			(xy 201.906378 -292.256464) (xy 201.91476 -292.23462) (xy 201.905108 -292.13048) (xy 201.892916 -292.110668)
			(xy 201.882756 -292.104318) (xy 201.856635 -292.087232) (xy 201.808515 -292.047477) (xy 201.765761 -292.002)
			(xy 201.729049 -291.95152) (xy 201.698957 -291.896834) (xy 201.675962 -291.838806) (xy 201.660426 -291.778352)
			(xy 201.652596 -291.716427) (xy 201.652124 -291.685218) (xy 201.652564 -291.65402) (xy 201.660384 -291.592116)
			(xy 201.675916 -291.531684) (xy 201.698913 -291.473681) (xy 201.729013 -291.419024) (xy 201.765737 -291.36858)
			(xy 201.808504 -291.323147) (xy 201.856639 -291.283444) (xy 201.882756 -291.266372) (xy 201.892916 -291.259768)
			(xy 201.905108 -291.239956) (xy 201.914506 -291.135816) (xy 201.906124 -291.114226) (xy 201.897234 -291.105844)
			(xy 201.877341 -291.086674) (xy 201.842873 -291.043506) (xy 201.815229 -290.995678) (xy 201.795029 -290.944263)
			(xy 201.782723 -290.89041) (xy 201.778588 -290.835323) (xy 201.782716 -290.780236) (xy 201.795015 -290.726381)
			(xy 201.815209 -290.674963) (xy 201.842847 -290.627133) (xy 201.87731 -290.58396) (xy 201.897234 -290.564824)
			(xy 201.906124 -290.556442) (xy 201.914506 -290.534852) (xy 201.905108 -290.430712) (xy 201.892916 -290.4109)
			(xy 201.882756 -290.404296) (xy 201.856662 -290.387195) (xy 201.808542 -290.347485) (xy 201.765786 -290.302049)
			(xy 201.72907 -290.251608) (xy 201.698974 -290.196958) (xy 201.675974 -290.138963) (xy 201.660434 -290.07854)
			(xy 201.652598 -290.016645) (xy 201.652124 -289.98545) (xy 201.652574 -289.95424) (xy 201.6604 -289.892312)
			(xy 201.675934 -289.831855) (xy 201.69893 -289.773826) (xy 201.729027 -289.71914) (xy 201.765746 -289.668662)
			(xy 201.808509 -289.623191) (xy 201.85664 -289.583445) (xy 201.882756 -289.56635) (xy 201.892916 -289.56)
			(xy 201.905108 -289.540188) (xy 201.91476 -289.436048) (xy 201.906378 -289.414204) (xy 201.897488 -289.406076)
			(xy 201.879154 -289.388567) (xy 201.847013 -289.349362) (xy 201.820542 -289.306126) (xy 201.800239 -289.259673)
			(xy 201.786487 -289.210878) (xy 201.779545 -289.16066) (xy 201.779124 -289.135312) (xy 201.779532 -289.109994)
			(xy 201.786458 -289.059834) (xy 201.800182 -289.011094) (xy 201.820445 -288.964689) (xy 201.846866 -288.921493)
			(xy 201.878948 -288.882318) (xy 201.897234 -288.864802) (xy 201.906124 -288.85642) (xy 201.914506 -288.83483)
			(xy 201.905108 -288.73069) (xy 201.892916 -288.710878) (xy 201.882756 -288.704274) (xy 201.856652 -288.687188)
			(xy 201.808532 -288.647475) (xy 201.765777 -288.602038) (xy 201.729062 -288.551594) (xy 201.698967 -288.496942)
			(xy 201.675968 -288.438945) (xy 201.66043 -288.37852) (xy 201.652597 -288.316623) (xy 201.652124 -288.285428)
			(xy 201.652613 -288.254265) (xy 201.660425 -288.192431) (xy 201.675925 -288.132063) (xy 201.698868 -288.074115)
			(xy 201.728894 -288.019498) (xy 201.765528 -287.969076) (xy 201.808193 -287.923642) (xy 201.856215 -287.883914)
			(xy 201.908839 -287.850519) (xy 201.965233 -287.823982) (xy 202.024508 -287.804722) (xy 202.085729 -287.793043)
			(xy 202.147932 -287.78913) (xy 202.210135 -287.793043) (xy 202.271356 -287.804722) (xy 202.330631 -287.823982)
			(xy 202.387025 -287.850519) (xy 202.439649 -287.883914) (xy 202.487671 -287.923642) (xy 202.530336 -287.969076)
			(xy 202.56697 -288.019498) (xy 202.596996 -288.074115) (xy 202.619939 -288.132063) (xy 202.635439 -288.192431)
			(xy 202.643251 -288.254265) (xy 202.64374 -288.285428) (xy 202.643307 -288.316626) (xy 202.635482 -288.378529)
			(xy 202.619947 -288.43896) (xy 202.596947 -288.496962) (xy 202.566847 -288.551618) (xy 202.530123 -288.602062)
			(xy 202.487357 -288.647496) (xy 202.439224 -288.687201) (xy 202.413108 -288.704274) (xy 202.402948 -288.710878)
			(xy 202.390756 -288.73069) (xy 202.381358 -288.83483) (xy 202.38974 -288.85642) (xy 202.39863 -288.864802)
			(xy 202.416921 -288.882312) (xy 202.448999 -288.92149) (xy 202.475416 -288.964688) (xy 202.495676 -289.011094)
			(xy 202.509398 -289.059835) (xy 202.516322 -289.109994) (xy 202.51674 -289.135312) (xy 202.516304 -289.160659)
			(xy 202.509371 -289.210878) (xy 202.495623 -289.259673) (xy 202.475321 -289.306125) (xy 202.448846 -289.349357)
			(xy 202.416697 -289.388555) (xy 202.398376 -289.406076) (xy 202.389486 -289.414204) (xy 202.381104 -289.436048)
			(xy 202.390756 -289.540188) (xy 202.402948 -289.56) (xy 202.413108 -289.56635) (xy 202.439205 -289.58347)
			(xy 202.487327 -289.623219) (xy 202.530083 -289.66869) (xy 202.566799 -289.719165) (xy 202.596893 -289.773846)
			(xy 202.619892 -289.83187) (xy 202.635431 -289.89232) (xy 202.643266 -289.954242) (xy 202.64374 -289.98545)
			(xy 202.643246 -290.016646) (xy 202.63543 -290.078547) (xy 202.619905 -290.138976) (xy 202.596914 -290.196978)
			(xy 202.566823 -290.251634) (xy 202.530106 -290.302079) (xy 202.487347 -290.347515) (xy 202.439221 -290.387222)
			(xy 202.413108 -290.404296) (xy 202.402948 -290.4109) (xy 202.390756 -290.430712) (xy 202.381358 -290.534852)
			(xy 202.38974 -290.556442) (xy 202.39863 -290.564824) (xy 202.418588 -290.583927) (xy 202.45305 -290.627108)
			(xy 202.480686 -290.674946) (xy 202.500879 -290.72637) (xy 202.513177 -290.780231) (xy 202.517305 -290.835323)
			(xy 202.51317 -290.890415) (xy 202.500866 -290.944274) (xy 202.480666 -290.995696) (xy 202.453024 -291.04353)
			(xy 202.418556 -291.086707) (xy 202.39863 -291.105844) (xy 202.38974 -291.114226) (xy 202.381358 -291.135816)
			(xy 202.390756 -291.239956) (xy 202.402948 -291.259768) (xy 202.413108 -291.266372) (xy 202.439202 -291.283472)
			(xy 202.487319 -291.323185) (xy 202.530073 -291.368622) (xy 202.566787 -291.419064) (xy 202.596883 -291.473714)
			(xy 202.619883 -291.531708) (xy 202.635426 -291.592129) (xy 202.643264 -291.654024) (xy 202.64374 -291.685218)
			(xy 202.643235 -291.716426) (xy 202.635415 -291.778351) (xy 202.619887 -291.838805) (xy 202.596897 -291.896833)
			(xy 202.566809 -291.951518) (xy 202.530097 -292.001997) (xy 202.487342 -292.04747) (xy 202.43922 -292.087221)
			(xy 202.413108 -292.104318) (xy 202.402948 -292.110668) (xy 202.390756 -292.13048) (xy 202.381104 -292.23462)
			(xy 202.389486 -292.256464) (xy 202.398376 -292.264592) (xy 202.416687 -292.282123) (xy 202.448832 -292.321323)
			(xy 202.475307 -292.364554) (xy 202.495614 -292.411002) (xy 202.50937 -292.459794) (xy 202.516317 -292.510009)
			(xy 202.51674 -292.535356) (xy 205.752192 -292.535356) (xy 205.752661 -292.504147) (xy 205.760486 -292.44222)
			(xy 205.776018 -292.381764) (xy 205.799012 -292.323735) (xy 205.829106 -292.26905) (xy 205.865823 -292.218572)
			(xy 205.908582 -292.1731) (xy 205.956709 -292.133352) (xy 205.982824 -292.116256) (xy 205.992984 -292.109906)
			(xy 206.005176 -292.090094) (xy 206.014828 -291.985954) (xy 206.006446 -291.96411) (xy 205.997556 -291.955982)
			(xy 205.979238 -291.938457) (xy 205.947093 -291.899257) (xy 205.920618 -291.856025) (xy 205.900312 -291.809575)
			(xy 205.886557 -291.760782) (xy 205.879613 -291.710565) (xy 205.879192 -291.685218) (xy 205.879615 -291.659901)
			(xy 205.886539 -291.609742) (xy 205.900261 -291.561002) (xy 205.920521 -291.514597) (xy 205.946939 -291.471401)
			(xy 205.979018 -291.432225) (xy 205.997302 -291.414708) (xy 206.006192 -291.406326) (xy 206.014574 -291.384736)
			(xy 206.005176 -291.280596) (xy 205.992984 -291.260784) (xy 205.982824 -291.25418) (xy 205.95674 -291.237059)
			(xy 205.908608 -291.197357) (xy 205.865842 -291.151927) (xy 205.829116 -291.101488) (xy 205.799012 -291.046837)
			(xy 205.776007 -290.98884) (xy 205.760465 -290.928414) (xy 205.75263 -290.866515) (xy 205.752628 -290.804122)
			(xy 205.760458 -290.742222) (xy 205.775996 -290.681794) (xy 205.798997 -290.623796) (xy 205.829096 -290.569143)
			(xy 205.865818 -290.518701) (xy 205.908582 -290.473268) (xy 205.95671 -290.433562) (xy 205.982824 -290.416488)
			(xy 205.992984 -290.409884) (xy 206.005176 -290.390072) (xy 206.014574 -290.285932) (xy 206.006192 -290.264342)
			(xy 205.997302 -290.25596) (xy 205.979047 -290.238414) (xy 205.946964 -290.199244) (xy 205.920542 -290.156054)
			(xy 205.900275 -290.109655) (xy 205.886547 -290.06092) (xy 205.879614 -290.010766) (xy 205.879192 -289.98545)
			(xy 205.879593 -289.960101) (xy 205.886532 -289.909881) (xy 205.900285 -289.861085) (xy 205.920595 -289.814633)
			(xy 205.947076 -289.771401) (xy 205.979231 -289.732206) (xy 205.997556 -289.714686) (xy 206.006446 -289.706558)
			(xy 206.014828 -289.684714) (xy 206.005176 -289.580574) (xy 205.992984 -289.560762) (xy 205.982824 -289.554412)
			(xy 205.956717 -289.537306) (xy 205.908594 -289.497556) (xy 205.865837 -289.452083) (xy 205.829122 -289.401607)
			(xy 205.799028 -289.346923) (xy 205.776031 -289.288897) (xy 205.760495 -289.228445) (xy 205.752664 -289.166521)
			(xy 205.752192 -289.135312) (xy 205.752642 -289.104114) (xy 205.760462 -289.042211) (xy 205.775994 -288.98178)
			(xy 205.79899 -288.923777) (xy 205.829088 -288.869121) (xy 205.86581 -288.818677) (xy 205.908576 -288.773243)
			(xy 205.956708 -288.733538) (xy 205.982824 -288.716466) (xy 205.992984 -288.709862) (xy 206.005176 -288.69005)
			(xy 206.014574 -288.58591) (xy 206.006192 -288.56432) (xy 205.997302 -288.555938) (xy 205.979036 -288.538403)
			(xy 205.946955 -288.499231) (xy 205.920533 -288.456038) (xy 205.900269 -288.409637) (xy 205.886543 -288.360901)
			(xy 205.879612 -288.310744) (xy 205.879192 -288.285428) (xy 205.879645 -288.260081) (xy 205.886573 -288.209863)
			(xy 205.900317 -288.161068) (xy 205.920616 -288.114616) (xy 205.947089 -288.071383) (xy 205.979235 -288.032185)
			(xy 205.997556 -288.014664) (xy 206.006446 -288.006536) (xy 206.014828 -287.984692) (xy 206.005176 -287.880552)
			(xy 205.992984 -287.86074) (xy 205.982824 -287.85439) (xy 205.956706 -287.837299) (xy 205.908584 -287.797547)
			(xy 205.865827 -287.752072) (xy 205.829113 -287.701593) (xy 205.79902 -287.646908) (xy 205.776025 -287.588879)
			(xy 205.760491 -287.528425) (xy 205.752662 -287.466499) (xy 205.752192 -287.43529) (xy 205.752681 -287.404127)
			(xy 205.760493 -287.342293) (xy 205.775993 -287.281925) (xy 205.798936 -287.223977) (xy 205.828962 -287.16936)
			(xy 205.865596 -287.118938) (xy 205.908261 -287.073504) (xy 205.956283 -287.033776) (xy 206.008907 -287.000381)
			(xy 206.065301 -286.973844) (xy 206.124576 -286.954584) (xy 206.185797 -286.942905) (xy 206.248 -286.938992)
			(xy 206.310203 -286.942905) (xy 206.371424 -286.954584) (xy 206.430699 -286.973844) (xy 206.487093 -287.000381)
			(xy 206.539717 -287.033776) (xy 206.587739 -287.073504) (xy 206.630404 -287.118938) (xy 206.667038 -287.16936)
			(xy 206.697064 -287.223977) (xy 206.720007 -287.281925) (xy 206.735507 -287.342293) (xy 206.743319 -287.404127)
			(xy 206.743808 -287.43529) (xy 206.743375 -287.466501) (xy 206.735544 -287.528429) (xy 206.720007 -287.588885)
			(xy 206.697007 -287.646914) (xy 206.666909 -287.7016) (xy 206.630187 -287.752077) (xy 206.587423 -287.797548)
			(xy 206.539292 -287.837295) (xy 206.513176 -287.85439) (xy 206.503016 -287.86074) (xy 206.490824 -287.880552)
			(xy 206.481172 -287.984692) (xy 206.489554 -288.006536) (xy 206.498444 -288.014664) (xy 206.516736 -288.032215)
			(xy 206.548883 -288.071409) (xy 206.575362 -288.114636) (xy 206.595672 -288.161081) (xy 206.609432 -288.209869)
			(xy 206.616383 -288.260082) (xy 206.616808 -288.285428) (xy 206.616349 -288.310744) (xy 206.609432 -288.360901)
			(xy 206.595717 -288.40964) (xy 206.575464 -288.456045) (xy 206.549052 -288.499242) (xy 206.516979 -288.53842)
			(xy 206.498698 -288.555938) (xy 206.489808 -288.56432) (xy 206.481426 -288.58591) (xy 206.490824 -288.69005)
			(xy 206.503016 -288.709862) (xy 206.513176 -288.716466) (xy 206.53926 -288.733581) (xy 206.587378 -288.773291)
			(xy 206.630134 -288.818725) (xy 206.66685 -288.869164) (xy 206.696947 -288.923812) (xy 206.719949 -288.981805)
			(xy 206.735492 -289.042225) (xy 206.743332 -289.104118) (xy 206.743808 -289.135312) (xy 206.743314 -289.166521)
			(xy 206.735493 -289.228446) (xy 206.719965 -289.288901) (xy 206.696974 -289.34693) (xy 206.666884 -289.401616)
			(xy 206.630171 -289.452094) (xy 206.587414 -289.497567) (xy 206.539289 -289.537315) (xy 206.513176 -289.554412)
			(xy 206.503016 -289.560762) (xy 206.490824 -289.580574) (xy 206.481172 -289.684714) (xy 206.489554 -289.706558)
			(xy 206.498444 -289.714686) (xy 206.516746 -289.732227) (xy 206.548893 -289.771423) (xy 206.57537 -289.814652)
			(xy 206.595679 -289.861099) (xy 206.609437 -289.909889) (xy 206.616384 -289.960104) (xy 206.616808 -289.98545)
			(xy 206.616364 -290.010767) (xy 206.609444 -290.060924) (xy 206.595727 -290.109664) (xy 206.575471 -290.156069)
			(xy 206.549056 -290.199266) (xy 206.51698 -290.238443) (xy 206.498698 -290.25596) (xy 206.489808 -290.264342)
			(xy 206.481426 -290.285932) (xy 206.490824 -290.390072) (xy 206.503016 -290.409884) (xy 206.513176 -290.416488)
			(xy 206.539323 -290.433515) (xy 206.587457 -290.473226) (xy 206.630226 -290.518664) (xy 206.666952 -290.569112)
			(xy 206.697055 -290.623771) (xy 206.720059 -290.681777) (xy 206.735599 -290.742211) (xy 206.743429 -290.804118)
			(xy 206.743427 -290.866518) (xy 206.735592 -290.928425) (xy 206.720047 -290.988858) (xy 206.69704 -291.046862)
			(xy 206.666933 -291.101519) (xy 206.630203 -291.151964) (xy 206.587431 -291.197399) (xy 206.539294 -291.237106)
			(xy 206.513176 -291.25418) (xy 206.503016 -291.260784) (xy 206.490824 -291.280596) (xy 206.481426 -291.384736)
			(xy 206.489808 -291.406326) (xy 206.498698 -291.414708) (xy 206.516986 -291.432221) (xy 206.549066 -291.471398)
			(xy 206.575484 -291.514595) (xy 206.595745 -291.561) (xy 206.609466 -291.609741) (xy 206.616391 -291.6599)
			(xy 206.616808 -291.685218) (xy 206.616386 -291.710566) (xy 206.609451 -291.760786) (xy 206.595702 -291.809581)
			(xy 206.575397 -291.856033) (xy 206.548919 -291.899265) (xy 206.516767 -291.938462) (xy 206.498444 -291.955982)
			(xy 206.489554 -291.96411) (xy 206.481172 -291.985954) (xy 206.490824 -292.090094) (xy 206.503016 -292.109906)
			(xy 206.513176 -292.116256) (xy 206.539269 -292.133383) (xy 206.587392 -292.17313) (xy 206.630149 -292.2186)
			(xy 206.666866 -292.269073) (xy 206.696961 -292.323753) (xy 206.71996 -292.381777) (xy 206.7355 -292.442227)
			(xy 206.743334 -292.504148) (xy 206.743808 -292.535356) (xy 206.743319 -292.566519) (xy 206.735507 -292.628353)
			(xy 206.720007 -292.688721) (xy 206.697064 -292.746669) (xy 206.667038 -292.801286) (xy 206.630404 -292.851708)
			(xy 206.587739 -292.897142) (xy 206.539717 -292.93687) (xy 206.487093 -292.970265) (xy 206.430699 -292.996802)
			(xy 206.371424 -293.016062) (xy 206.310203 -293.027741) (xy 206.248 -293.031654) (xy 206.185797 -293.027741)
			(xy 206.124576 -293.016062) (xy 206.065301 -292.996802) (xy 206.008907 -292.970265) (xy 205.956283 -292.93687)
			(xy 205.908261 -292.897142) (xy 205.865596 -292.851708) (xy 205.828962 -292.801286) (xy 205.798936 -292.746669)
			(xy 205.775993 -292.688721) (xy 205.760493 -292.628353) (xy 205.752681 -292.566519) (xy 205.752192 -292.535356)
			(xy 202.51674 -292.535356) (xy 202.516321 -292.560674) (xy 202.509399 -292.610833) (xy 202.495678 -292.659574)
			(xy 202.475417 -292.705979) (xy 202.448997 -292.749175) (xy 202.416915 -292.78835) (xy 202.39863 -292.805866)
			(xy 202.38974 -292.814248) (xy 202.381358 -292.835838) (xy 202.390756 -292.939978) (xy 202.402948 -292.95979)
			(xy 202.413108 -292.966394) (xy 202.439213 -292.983479) (xy 202.487329 -293.023195) (xy 202.530082 -293.068633)
			(xy 202.566796 -293.119077) (xy 202.59689 -293.173729) (xy 202.619889 -293.231726) (xy 202.635429 -293.292149)
			(xy 202.643265 -293.354045) (xy 202.64374 -293.38524) (xy 204.494399 -293.38524) (xy 204.498334 -293.331469)
			(xy 204.510057 -293.278845) (xy 204.529317 -293.228488) (xy 204.555703 -293.181471) (xy 204.588655 -293.138798)
			(xy 204.627468 -293.101377) (xy 204.671316 -293.070007) (xy 204.719264 -293.045355) (xy 204.770291 -293.027947)
			(xy 204.823309 -293.018154) (xy 204.877188 -293.016185) (xy 204.930779 -293.022082) (xy 204.98294 -293.035718)
			(xy 205.03256 -293.056805) (xy 205.078581 -293.084891) (xy 205.120023 -293.119379) (xy 205.156001 -293.159533)
			(xy 205.185749 -293.204497) (xy 205.208634 -293.253314) (xy 205.224166 -293.304943) (xy 205.232016 -293.358283)
			(xy 205.232508 -293.38524) (xy 205.232016 -293.412197) (xy 205.224166 -293.465537) (xy 205.208634 -293.517166)
			(xy 205.185749 -293.565983) (xy 205.156001 -293.610947) (xy 205.120023 -293.651101) (xy 205.078581 -293.685589)
			(xy 205.03256 -293.713675) (xy 204.98294 -293.734762) (xy 204.930779 -293.748398) (xy 204.877188 -293.754295)
			(xy 204.823309 -293.752326) (xy 204.770291 -293.742533) (xy 204.719264 -293.725125) (xy 204.671316 -293.700473)
			(xy 204.627468 -293.669103) (xy 204.588655 -293.631682) (xy 204.555703 -293.589009) (xy 204.529317 -293.541992)
			(xy 204.510057 -293.491635) (xy 204.498334 -293.439011) (xy 204.494399 -293.38524) (xy 202.64374 -293.38524)
			(xy 202.643251 -293.416403) (xy 202.635439 -293.478237) (xy 202.619939 -293.538605) (xy 202.596996 -293.596553)
			(xy 202.56697 -293.65117) (xy 202.530336 -293.701592) (xy 202.487671 -293.747026) (xy 202.439649 -293.786754)
			(xy 202.387025 -293.820149) (xy 202.330631 -293.846686) (xy 202.271356 -293.865946) (xy 202.210135 -293.877625)
			(xy 202.147932 -293.881538) (xy 202.085729 -293.877625) (xy 202.024508 -293.865946) (xy 201.965233 -293.846686)
			(xy 201.908839 -293.820149) (xy 201.856215 -293.786754) (xy 201.808193 -293.747026) (xy 201.765528 -293.701592)
			(xy 201.728894 -293.65117) (xy 201.698868 -293.596553) (xy 201.675925 -293.538605) (xy 201.660425 -293.478237)
			(xy 201.652613 -293.416403) (xy 201.652124 -293.38524) (xy 197.688708 -293.38524) (xy 197.688216 -293.412197)
			(xy 197.680366 -293.465537) (xy 197.664834 -293.517166) (xy 197.641949 -293.565983) (xy 197.612201 -293.610947)
			(xy 197.576223 -293.651101) (xy 197.534781 -293.685589) (xy 197.48876 -293.713675) (xy 197.43914 -293.734762)
			(xy 197.386979 -293.748398) (xy 197.333388 -293.754295) (xy 197.279509 -293.752326) (xy 197.226491 -293.742533)
			(xy 197.175464 -293.725125) (xy 197.127516 -293.700473) (xy 197.083668 -293.669103) (xy 197.044855 -293.631682)
			(xy 197.011903 -293.589009) (xy 196.985517 -293.541992) (xy 196.966257 -293.491635) (xy 196.954534 -293.439011)
			(xy 196.950599 -293.38524) (xy 195.09994 -293.38524) (xy 195.099451 -293.416403) (xy 195.091639 -293.478237)
			(xy 195.076139 -293.538605) (xy 195.053196 -293.596553) (xy 195.02317 -293.65117) (xy 194.986536 -293.701592)
			(xy 194.943871 -293.747026) (xy 194.895849 -293.786754) (xy 194.843225 -293.820149) (xy 194.786831 -293.846686)
			(xy 194.727556 -293.865946) (xy 194.666335 -293.877625) (xy 194.604132 -293.881538) (xy 194.541929 -293.877625)
			(xy 194.480708 -293.865946) (xy 194.421433 -293.846686) (xy 194.365039 -293.820149) (xy 194.312415 -293.786754)
			(xy 194.264393 -293.747026) (xy 194.221728 -293.701592) (xy 194.185094 -293.65117) (xy 194.155068 -293.596553)
			(xy 194.132125 -293.538605) (xy 194.116625 -293.478237) (xy 194.108813 -293.416403) (xy 194.108324 -293.38524)
			(xy 190.144654 -293.38524) (xy 190.144162 -293.412197) (xy 190.136312 -293.465537) (xy 190.12078 -293.517166)
			(xy 190.097895 -293.565983) (xy 190.068147 -293.610947) (xy 190.032169 -293.651101) (xy 189.990727 -293.685589)
			(xy 189.944706 -293.713675) (xy 189.895086 -293.734762) (xy 189.842925 -293.748398) (xy 189.789334 -293.754295)
			(xy 189.735455 -293.752326) (xy 189.682437 -293.742533) (xy 189.63141 -293.725125) (xy 189.583462 -293.700473)
			(xy 189.539614 -293.669103) (xy 189.500801 -293.631682) (xy 189.467849 -293.589009) (xy 189.441463 -293.541992)
			(xy 189.422203 -293.491635) (xy 189.41048 -293.439011) (xy 189.406545 -293.38524) (xy 187.555886 -293.38524)
			(xy 187.555397 -293.416403) (xy 187.547585 -293.478237) (xy 187.532085 -293.538605) (xy 187.509142 -293.596553)
			(xy 187.479116 -293.65117) (xy 187.442482 -293.701592) (xy 187.399817 -293.747026) (xy 187.351795 -293.786754)
			(xy 187.299171 -293.820149) (xy 187.242777 -293.846686) (xy 187.183502 -293.865946) (xy 187.122281 -293.877625)
			(xy 187.060078 -293.881538) (xy 186.997875 -293.877625) (xy 186.936654 -293.865946) (xy 186.877379 -293.846686)
			(xy 186.820985 -293.820149) (xy 186.768361 -293.786754) (xy 186.720339 -293.747026) (xy 186.677674 -293.701592)
			(xy 186.64104 -293.65117) (xy 186.611014 -293.596553) (xy 186.588071 -293.538605) (xy 186.572571 -293.478237)
			(xy 186.564759 -293.416403) (xy 186.56427 -293.38524) (xy 185.96864 -293.38524) (xy 185.96864 -294.235378)
			(xy 188.075077 -294.235378) (xy 188.079012 -294.181607) (xy 188.090735 -294.128983) (xy 188.109995 -294.078626)
			(xy 188.136381 -294.031609) (xy 188.169333 -293.988936) (xy 188.208146 -293.951515) (xy 188.251994 -293.920145)
			(xy 188.299942 -293.895493) (xy 188.350969 -293.878085) (xy 188.403987 -293.868292) (xy 188.457866 -293.866323)
			(xy 188.511457 -293.87222) (xy 188.563618 -293.885856) (xy 188.613238 -293.906943) (xy 188.659259 -293.935029)
			(xy 188.700701 -293.969517) (xy 188.736679 -294.009671) (xy 188.766427 -294.054635) (xy 188.789312 -294.103452)
			(xy 188.804844 -294.155081) (xy 188.812694 -294.208421) (xy 188.813186 -294.235378) (xy 188.812694 -294.262335)
			(xy 188.804844 -294.315675) (xy 188.789312 -294.367304) (xy 188.766427 -294.416121) (xy 188.736679 -294.461085)
			(xy 188.700701 -294.501239) (xy 188.659259 -294.535727) (xy 188.613238 -294.563813) (xy 188.563618 -294.5849)
			(xy 188.511457 -294.598536) (xy 188.457866 -294.604433) (xy 188.403987 -294.602464) (xy 188.350969 -294.592671)
			(xy 188.299942 -294.575263) (xy 188.251994 -294.550611) (xy 188.208146 -294.519241) (xy 188.169333 -294.48182)
			(xy 188.136381 -294.439147) (xy 188.109995 -294.39213) (xy 188.090735 -294.341773) (xy 188.079012 -294.289149)
			(xy 188.075077 -294.235378) (xy 185.96864 -294.235378) (xy 185.96864 -295.9354) (xy 186.56427 -295.9354)
			(xy 186.564834 -295.902681) (xy 186.573426 -295.83781) (xy 186.590473 -295.774632) (xy 186.615681 -295.714245)
			(xy 186.648611 -295.657697) (xy 186.688691 -295.60597) (xy 186.71159 -295.582594) (xy 186.718956 -295.575482)
			(xy 186.72683 -295.556686) (xy 186.72683 -295.463976) (xy 186.718956 -295.44518) (xy 186.71159 -295.438068)
			(xy 186.688717 -295.414666) (xy 186.648631 -295.362945) (xy 186.615692 -295.306403) (xy 186.590472 -295.246021)
			(xy 186.573408 -295.182848) (xy 186.564798 -295.11798) (xy 186.56427 -295.085262) (xy 186.564759 -295.054099)
			(xy 186.572571 -294.992265) (xy 186.588071 -294.931897) (xy 186.611014 -294.873949) (xy 186.64104 -294.819332)
			(xy 186.677674 -294.76891) (xy 186.720339 -294.723476) (xy 186.768361 -294.683748) (xy 186.820985 -294.650353)
			(xy 186.877379 -294.623816) (xy 186.936654 -294.604556) (xy 186.997875 -294.592877) (xy 187.060078 -294.588964)
			(xy 187.122281 -294.592877) (xy 187.183502 -294.604556) (xy 187.242777 -294.623816) (xy 187.299171 -294.650353)
			(xy 187.351795 -294.683748) (xy 187.399817 -294.723476) (xy 187.442482 -294.76891) (xy 187.479116 -294.819332)
			(xy 187.509142 -294.873949) (xy 187.532085 -294.931897) (xy 187.547585 -294.992265) (xy 187.555397 -295.054099)
			(xy 187.555886 -295.085262) (xy 190.664338 -295.085262) (xy 190.664884 -295.052562) (xy 190.67349 -294.987731)
			(xy 190.690547 -294.924596) (xy 190.71576 -294.864251) (xy 190.74869 -294.807747) (xy 190.788764 -294.756065)
			(xy 190.811658 -294.73271) (xy 190.819024 -294.725344) (xy 190.826644 -294.706802) (xy 190.826644 -294.613838)
			(xy 190.819024 -294.595296) (xy 190.811658 -294.58793) (xy 190.788757 -294.56458) (xy 190.748673 -294.512901)
			(xy 190.715737 -294.456398) (xy 190.690521 -294.396052) (xy 190.673463 -294.332913) (xy 190.664861 -294.268079)
			(xy 190.664338 -294.235378) (xy 190.664827 -294.204215) (xy 190.672639 -294.142381) (xy 190.688139 -294.082013)
			(xy 190.711082 -294.024065) (xy 190.741108 -293.969448) (xy 190.777742 -293.919026) (xy 190.820407 -293.873592)
			(xy 190.868429 -293.833864) (xy 190.921053 -293.800469) (xy 190.977447 -293.773932) (xy 191.036722 -293.754672)
			(xy 191.097943 -293.742993) (xy 191.160146 -293.73908) (xy 191.222349 -293.742993) (xy 191.28357 -293.754672)
			(xy 191.342845 -293.773932) (xy 191.399239 -293.800469) (xy 191.451863 -293.833864) (xy 191.499885 -293.873592)
			(xy 191.54255 -293.919026) (xy 191.579184 -293.969448) (xy 191.60921 -294.024065) (xy 191.632153 -294.082013)
			(xy 191.647653 -294.142381) (xy 191.655465 -294.204215) (xy 191.655954 -294.235378) (xy 195.619131 -294.235378)
			(xy 195.623066 -294.181607) (xy 195.634789 -294.128983) (xy 195.654049 -294.078626) (xy 195.680435 -294.031609)
			(xy 195.713387 -293.988936) (xy 195.7522 -293.951515) (xy 195.796048 -293.920145) (xy 195.843996 -293.895493)
			(xy 195.895023 -293.878085) (xy 195.948041 -293.868292) (xy 196.00192 -293.866323) (xy 196.055511 -293.87222)
			(xy 196.107672 -293.885856) (xy 196.157292 -293.906943) (xy 196.203313 -293.935029) (xy 196.244755 -293.969517)
			(xy 196.280733 -294.009671) (xy 196.310481 -294.054635) (xy 196.333366 -294.103452) (xy 196.348898 -294.155081)
			(xy 196.356748 -294.208421) (xy 196.35724 -294.235378) (xy 196.356748 -294.262335) (xy 196.348898 -294.315675)
			(xy 196.333366 -294.367304) (xy 196.310481 -294.416121) (xy 196.280733 -294.461085) (xy 196.244755 -294.501239)
			(xy 196.203313 -294.535727) (xy 196.157292 -294.563813) (xy 196.107672 -294.5849) (xy 196.055511 -294.598536)
			(xy 196.00192 -294.604433) (xy 195.948041 -294.602464) (xy 195.895023 -294.592671) (xy 195.843996 -294.575263)
			(xy 195.796048 -294.550611) (xy 195.7522 -294.519241) (xy 195.713387 -294.48182) (xy 195.680435 -294.439147)
			(xy 195.654049 -294.39213) (xy 195.634789 -294.341773) (xy 195.623066 -294.289149) (xy 195.619131 -294.235378)
			(xy 191.655954 -294.235378) (xy 191.655436 -294.268079) (xy 191.646825 -294.332911) (xy 191.629762 -294.396047)
			(xy 191.604544 -294.456391) (xy 191.57161 -294.512895) (xy 191.53153 -294.564576) (xy 191.508634 -294.58793)
			(xy 191.501268 -294.595296) (xy 191.493648 -294.613838) (xy 191.493648 -294.66032) (xy 191.908445 -294.66032)
			(xy 191.91238 -294.606549) (xy 191.924103 -294.553925) (xy 191.943363 -294.503568) (xy 191.969749 -294.456551)
			(xy 192.002701 -294.413878) (xy 192.041514 -294.376457) (xy 192.085362 -294.345087) (xy 192.13331 -294.320435)
			(xy 192.184337 -294.303027) (xy 192.237355 -294.293234) (xy 192.291234 -294.291265) (xy 192.344825 -294.297162)
			(xy 192.396986 -294.310798) (xy 192.446606 -294.331885) (xy 192.492627 -294.359971) (xy 192.534069 -294.394459)
			(xy 192.570047 -294.434613) (xy 192.599795 -294.479577) (xy 192.62268 -294.528394) (xy 192.638212 -294.580023)
			(xy 192.646062 -294.633363) (xy 192.646554 -294.66032) (xy 192.646062 -294.687277) (xy 192.638212 -294.740617)
			(xy 192.62268 -294.792246) (xy 192.599795 -294.841063) (xy 192.570047 -294.886027) (xy 192.534069 -294.926181)
			(xy 192.492627 -294.960669) (xy 192.446606 -294.988755) (xy 192.396986 -295.009842) (xy 192.344825 -295.023478)
			(xy 192.291234 -295.029375) (xy 192.237355 -295.027406) (xy 192.184337 -295.017613) (xy 192.13331 -295.000205)
			(xy 192.085362 -294.975553) (xy 192.041514 -294.944183) (xy 192.002701 -294.906762) (xy 191.969749 -294.864089)
			(xy 191.943363 -294.817072) (xy 191.924103 -294.766715) (xy 191.91238 -294.714091) (xy 191.908445 -294.66032)
			(xy 191.493648 -294.66032) (xy 191.493648 -294.706802) (xy 191.501268 -294.725344) (xy 191.508634 -294.73271)
			(xy 191.531552 -294.756043) (xy 191.571635 -294.807725) (xy 191.604569 -294.864232) (xy 191.629783 -294.924581)
			(xy 191.646836 -294.987723) (xy 191.655433 -295.05256) (xy 191.655954 -295.085262) (xy 191.655465 -295.116425)
			(xy 191.647653 -295.178259) (xy 191.632153 -295.238627) (xy 191.60921 -295.296575) (xy 191.579184 -295.351192)
			(xy 191.54255 -295.401614) (xy 191.499885 -295.447048) (xy 191.451863 -295.486776) (xy 191.399239 -295.520171)
			(xy 191.342845 -295.546708) (xy 191.28357 -295.565968) (xy 191.222349 -295.577647) (xy 191.160146 -295.58156)
			(xy 191.097943 -295.577647) (xy 191.036722 -295.565968) (xy 190.977447 -295.546708) (xy 190.921053 -295.520171)
			(xy 190.868429 -295.486776) (xy 190.820407 -295.447048) (xy 190.777742 -295.401614) (xy 190.741108 -295.351192)
			(xy 190.711082 -295.296575) (xy 190.688139 -295.238627) (xy 190.672639 -295.178259) (xy 190.664827 -295.116425)
			(xy 190.664338 -295.085262) (xy 187.555886 -295.085262) (xy 187.555375 -295.117983) (xy 187.546775 -295.182856)
			(xy 187.529717 -295.246036) (xy 187.504499 -295.306423) (xy 187.471559 -295.36297) (xy 187.431469 -295.414694)
			(xy 187.408566 -295.438068) (xy 187.4012 -295.44518) (xy 187.393326 -295.463976) (xy 187.393326 -295.510458)
			(xy 187.808377 -295.510458) (xy 187.812312 -295.456687) (xy 187.824035 -295.404063) (xy 187.843295 -295.353706)
			(xy 187.869681 -295.306689) (xy 187.902633 -295.264016) (xy 187.941446 -295.226595) (xy 187.985294 -295.195225)
			(xy 188.033242 -295.170573) (xy 188.084269 -295.153165) (xy 188.137287 -295.143372) (xy 188.191166 -295.141403)
			(xy 188.244757 -295.1473) (xy 188.296918 -295.160936) (xy 188.346538 -295.182023) (xy 188.392559 -295.210109)
			(xy 188.434001 -295.244597) (xy 188.469979 -295.284751) (xy 188.499727 -295.329715) (xy 188.522612 -295.378532)
			(xy 188.538144 -295.430161) (xy 188.545994 -295.483501) (xy 188.546486 -295.510458) (xy 188.545994 -295.537415)
			(xy 188.538144 -295.590755) (xy 188.522612 -295.642384) (xy 188.499727 -295.691201) (xy 188.469979 -295.736165)
			(xy 188.434001 -295.776319) (xy 188.392559 -295.810807) (xy 188.346538 -295.838893) (xy 188.296918 -295.85998)
			(xy 188.244757 -295.873616) (xy 188.191166 -295.879513) (xy 188.137287 -295.877544) (xy 188.084269 -295.867751)
			(xy 188.033242 -295.850343) (xy 187.985294 -295.825691) (xy 187.941446 -295.794321) (xy 187.902633 -295.7569)
			(xy 187.869681 -295.714227) (xy 187.843295 -295.66721) (xy 187.824035 -295.616853) (xy 187.812312 -295.564229)
			(xy 187.808377 -295.510458) (xy 187.393326 -295.510458) (xy 187.393326 -295.556686) (xy 187.4012 -295.575482)
			(xy 187.408566 -295.582594) (xy 187.431479 -295.605958) (xy 187.47156 -295.657688) (xy 187.504492 -295.714239)
			(xy 187.529705 -295.774628) (xy 187.54676 -295.837807) (xy 187.555363 -295.90268) (xy 187.555886 -295.9354)
			(xy 189.406545 -295.9354) (xy 189.41048 -295.881629) (xy 189.422203 -295.829005) (xy 189.441463 -295.778648)
			(xy 189.467849 -295.731631) (xy 189.500801 -295.688958) (xy 189.539614 -295.651537) (xy 189.583462 -295.620167)
			(xy 189.63141 -295.595515) (xy 189.682437 -295.578107) (xy 189.735455 -295.568314) (xy 189.789334 -295.566345)
			(xy 189.842925 -295.572242) (xy 189.895086 -295.585878) (xy 189.944706 -295.606965) (xy 189.990727 -295.635051)
			(xy 190.032169 -295.669539) (xy 190.068147 -295.709693) (xy 190.097895 -295.754657) (xy 190.12078 -295.803474)
			(xy 190.136312 -295.855103) (xy 190.144162 -295.908443) (xy 190.144654 -295.9354) (xy 194.108324 -295.9354)
			(xy 194.108872 -295.90268) (xy 194.117465 -295.837808) (xy 194.134515 -295.774629) (xy 194.159725 -295.714242)
			(xy 194.192659 -295.657694) (xy 194.232743 -295.605969) (xy 194.255644 -295.582594) (xy 194.26301 -295.575482)
			(xy 194.270884 -295.556686) (xy 194.270884 -295.463976) (xy 194.26301 -295.44518) (xy 194.255644 -295.438068)
			(xy 194.232763 -295.414674) (xy 194.192679 -295.362951) (xy 194.159742 -295.306406) (xy 194.134523 -295.246023)
			(xy 194.117461 -295.182849) (xy 194.108851 -295.117981) (xy 194.108324 -295.085262) (xy 194.108813 -295.054099)
			(xy 194.116625 -294.992265) (xy 194.132125 -294.931897) (xy 194.155068 -294.873949) (xy 194.185094 -294.819332)
			(xy 194.221728 -294.76891) (xy 194.264393 -294.723476) (xy 194.312415 -294.683748) (xy 194.365039 -294.650353)
			(xy 194.421433 -294.623816) (xy 194.480708 -294.604556) (xy 194.541929 -294.592877) (xy 194.604132 -294.588964)
			(xy 194.666335 -294.592877) (xy 194.727556 -294.604556) (xy 194.786831 -294.623816) (xy 194.843225 -294.650353)
			(xy 194.895849 -294.683748) (xy 194.943871 -294.723476) (xy 194.986536 -294.76891) (xy 195.02317 -294.819332)
			(xy 195.053196 -294.873949) (xy 195.076139 -294.931897) (xy 195.091639 -294.992265) (xy 195.099451 -295.054099)
			(xy 195.09994 -295.085262) (xy 198.208392 -295.085262) (xy 198.208922 -295.052562) (xy 198.217529 -294.98773)
			(xy 198.234588 -294.924593) (xy 198.259804 -294.864248) (xy 198.292737 -294.807745) (xy 198.332816 -294.756063)
			(xy 198.355712 -294.73271) (xy 198.363078 -294.725344) (xy 198.370698 -294.706802) (xy 198.370698 -294.613838)
			(xy 198.363078 -294.595296) (xy 198.355712 -294.58793) (xy 198.332803 -294.564589) (xy 198.292721 -294.512907)
			(xy 198.259787 -294.456401) (xy 198.234573 -294.396054) (xy 198.217516 -294.332914) (xy 198.208915 -294.268079)
			(xy 198.208392 -294.235378) (xy 198.208881 -294.204215) (xy 198.216693 -294.142381) (xy 198.232193 -294.082013)
			(xy 198.255136 -294.024065) (xy 198.285162 -293.969448) (xy 198.321796 -293.919026) (xy 198.364461 -293.873592)
			(xy 198.412483 -293.833864) (xy 198.465107 -293.800469) (xy 198.521501 -293.773932) (xy 198.580776 -293.754672)
			(xy 198.641997 -293.742993) (xy 198.7042 -293.73908) (xy 198.766403 -293.742993) (xy 198.827624 -293.754672)
			(xy 198.886899 -293.773932) (xy 198.943293 -293.800469) (xy 198.995917 -293.833864) (xy 199.043939 -293.873592)
			(xy 199.086604 -293.919026) (xy 199.123238 -293.969448) (xy 199.153264 -294.024065) (xy 199.176207 -294.082013)
			(xy 199.191707 -294.142381) (xy 199.199519 -294.204215) (xy 199.200008 -294.235378) (xy 203.162931 -294.235378)
			(xy 203.166866 -294.181607) (xy 203.178589 -294.128983) (xy 203.197849 -294.078626) (xy 203.224235 -294.031609)
			(xy 203.257187 -293.988936) (xy 203.296 -293.951515) (xy 203.339848 -293.920145) (xy 203.387796 -293.895493)
			(xy 203.438823 -293.878085) (xy 203.491841 -293.868292) (xy 203.54572 -293.866323) (xy 203.599311 -293.87222)
			(xy 203.651472 -293.885856) (xy 203.701092 -293.906943) (xy 203.747113 -293.935029) (xy 203.788555 -293.969517)
			(xy 203.824533 -294.009671) (xy 203.854281 -294.054635) (xy 203.877166 -294.103452) (xy 203.892698 -294.155081)
			(xy 203.900548 -294.208421) (xy 203.90104 -294.235378) (xy 203.900548 -294.262335) (xy 203.892698 -294.315675)
			(xy 203.877166 -294.367304) (xy 203.854281 -294.416121) (xy 203.824533 -294.461085) (xy 203.788555 -294.501239)
			(xy 203.747113 -294.535727) (xy 203.701092 -294.563813) (xy 203.651472 -294.5849) (xy 203.599311 -294.598536)
			(xy 203.54572 -294.604433) (xy 203.491841 -294.602464) (xy 203.438823 -294.592671) (xy 203.387796 -294.575263)
			(xy 203.339848 -294.550611) (xy 203.296 -294.519241) (xy 203.257187 -294.48182) (xy 203.224235 -294.439147)
			(xy 203.197849 -294.39213) (xy 203.178589 -294.341773) (xy 203.166866 -294.289149) (xy 203.162931 -294.235378)
			(xy 199.200008 -294.235378) (xy 199.199504 -294.268079) (xy 199.190892 -294.332912) (xy 199.173827 -294.39605)
			(xy 199.148607 -294.456394) (xy 199.115669 -294.512897) (xy 199.075586 -294.564577) (xy 199.052688 -294.58793)
			(xy 199.045322 -294.595296) (xy 199.037702 -294.613838) (xy 199.037702 -294.66032) (xy 199.452499 -294.66032)
			(xy 199.456434 -294.606549) (xy 199.468157 -294.553925) (xy 199.487417 -294.503568) (xy 199.513803 -294.456551)
			(xy 199.546755 -294.413878) (xy 199.585568 -294.376457) (xy 199.629416 -294.345087) (xy 199.677364 -294.320435)
			(xy 199.728391 -294.303027) (xy 199.781409 -294.293234) (xy 199.835288 -294.291265) (xy 199.888879 -294.297162)
			(xy 199.94104 -294.310798) (xy 199.99066 -294.331885) (xy 200.036681 -294.359971) (xy 200.078123 -294.394459)
			(xy 200.114101 -294.434613) (xy 200.143849 -294.479577) (xy 200.166734 -294.528394) (xy 200.182266 -294.580023)
			(xy 200.190116 -294.633363) (xy 200.190608 -294.66032) (xy 200.190116 -294.687277) (xy 200.182266 -294.740617)
			(xy 200.166734 -294.792246) (xy 200.143849 -294.841063) (xy 200.114101 -294.886027) (xy 200.078123 -294.926181)
			(xy 200.036681 -294.960669) (xy 199.99066 -294.988755) (xy 199.94104 -295.009842) (xy 199.888879 -295.023478)
			(xy 199.835288 -295.029375) (xy 199.781409 -295.027406) (xy 199.728391 -295.017613) (xy 199.677364 -295.000205)
			(xy 199.629416 -294.975553) (xy 199.585568 -294.944183) (xy 199.546755 -294.906762) (xy 199.513803 -294.864089)
			(xy 199.487417 -294.817072) (xy 199.468157 -294.766715) (xy 199.456434 -294.714091) (xy 199.452499 -294.66032)
			(xy 199.037702 -294.66032) (xy 199.037702 -294.706802) (xy 199.045322 -294.725344) (xy 199.052688 -294.73271)
			(xy 199.075616 -294.756033) (xy 199.115696 -294.807719) (xy 199.148628 -294.864228) (xy 199.173839 -294.924579)
			(xy 199.190891 -294.987722) (xy 199.199487 -295.052559) (xy 199.200008 -295.085262) (xy 199.199519 -295.116425)
			(xy 199.191707 -295.178259) (xy 199.176207 -295.238627) (xy 199.153264 -295.296575) (xy 199.123238 -295.351192)
			(xy 199.086604 -295.401614) (xy 199.043939 -295.447048) (xy 198.995917 -295.486776) (xy 198.943293 -295.520171)
			(xy 198.886899 -295.546708) (xy 198.827624 -295.565968) (xy 198.766403 -295.577647) (xy 198.7042 -295.58156)
			(xy 198.641997 -295.577647) (xy 198.580776 -295.565968) (xy 198.521501 -295.546708) (xy 198.465107 -295.520171)
			(xy 198.412483 -295.486776) (xy 198.364461 -295.447048) (xy 198.321796 -295.401614) (xy 198.285162 -295.351192)
			(xy 198.255136 -295.296575) (xy 198.232193 -295.238627) (xy 198.216693 -295.178259) (xy 198.208881 -295.116425)
			(xy 198.208392 -295.085262) (xy 195.09994 -295.085262) (xy 195.099443 -295.117983) (xy 195.090841 -295.182858)
			(xy 195.073782 -295.246038) (xy 195.048562 -295.306426) (xy 195.015619 -295.362972) (xy 194.975525 -295.414695)
			(xy 194.95262 -295.438068) (xy 194.945254 -295.44518) (xy 194.93738 -295.463976) (xy 194.93738 -295.510458)
			(xy 195.352431 -295.510458) (xy 195.356366 -295.456687) (xy 195.368089 -295.404063) (xy 195.387349 -295.353706)
			(xy 195.413735 -295.306689) (xy 195.446687 -295.264016) (xy 195.4855 -295.226595) (xy 195.529348 -295.195225)
			(xy 195.577296 -295.170573) (xy 195.628323 -295.153165) (xy 195.681341 -295.143372) (xy 195.73522 -295.141403)
			(xy 195.788811 -295.1473) (xy 195.840972 -295.160936) (xy 195.890592 -295.182023) (xy 195.936613 -295.210109)
			(xy 195.978055 -295.244597) (xy 196.014033 -295.284751) (xy 196.043781 -295.329715) (xy 196.066666 -295.378532)
			(xy 196.082198 -295.430161) (xy 196.090048 -295.483501) (xy 196.09054 -295.510458) (xy 196.090048 -295.537415)
			(xy 196.082198 -295.590755) (xy 196.066666 -295.642384) (xy 196.043781 -295.691201) (xy 196.014033 -295.736165)
			(xy 195.978055 -295.776319) (xy 195.936613 -295.810807) (xy 195.890592 -295.838893) (xy 195.840972 -295.85998)
			(xy 195.788811 -295.873616) (xy 195.73522 -295.879513) (xy 195.681341 -295.877544) (xy 195.628323 -295.867751)
			(xy 195.577296 -295.850343) (xy 195.529348 -295.825691) (xy 195.4855 -295.794321) (xy 195.446687 -295.7569)
			(xy 195.413735 -295.714227) (xy 195.387349 -295.66721) (xy 195.368089 -295.616853) (xy 195.356366 -295.564229)
			(xy 195.352431 -295.510458) (xy 194.93738 -295.510458) (xy 194.93738 -295.556686) (xy 194.945254 -295.575482)
			(xy 194.95262 -295.582594) (xy 194.975525 -295.605966) (xy 195.015607 -295.657694) (xy 195.048542 -295.714242)
			(xy 195.073756 -295.77463) (xy 195.090813 -295.837808) (xy 195.099416 -295.90268) (xy 195.09994 -295.9354)
			(xy 196.950599 -295.9354) (xy 196.954534 -295.881629) (xy 196.966257 -295.829005) (xy 196.985517 -295.778648)
			(xy 197.011903 -295.731631) (xy 197.044855 -295.688958) (xy 197.083668 -295.651537) (xy 197.127516 -295.620167)
			(xy 197.175464 -295.595515) (xy 197.226491 -295.578107) (xy 197.279509 -295.568314) (xy 197.333388 -295.566345)
			(xy 197.386979 -295.572242) (xy 197.43914 -295.585878) (xy 197.48876 -295.606965) (xy 197.534781 -295.635051)
			(xy 197.576223 -295.669539) (xy 197.612201 -295.709693) (xy 197.641949 -295.754657) (xy 197.664834 -295.803474)
			(xy 197.680366 -295.855103) (xy 197.688216 -295.908443) (xy 197.688708 -295.9354) (xy 201.652124 -295.9354)
			(xy 201.652672 -295.90268) (xy 201.661265 -295.837808) (xy 201.678315 -295.774629) (xy 201.703525 -295.714242)
			(xy 201.736459 -295.657694) (xy 201.776543 -295.605969) (xy 201.799444 -295.582594) (xy 201.80681 -295.575482)
			(xy 201.814684 -295.556686) (xy 201.814684 -295.463976) (xy 201.80681 -295.44518) (xy 201.799444 -295.438068)
			(xy 201.776563 -295.414674) (xy 201.736479 -295.362951) (xy 201.703542 -295.306406) (xy 201.678323 -295.246023)
			(xy 201.661261 -295.182849) (xy 201.652651 -295.117981) (xy 201.652124 -295.085262) (xy 201.652613 -295.054099)
			(xy 201.660425 -294.992265) (xy 201.675925 -294.931897) (xy 201.698868 -294.873949) (xy 201.728894 -294.819332)
			(xy 201.765528 -294.76891) (xy 201.808193 -294.723476) (xy 201.856215 -294.683748) (xy 201.908839 -294.650353)
			(xy 201.965233 -294.623816) (xy 202.024508 -294.604556) (xy 202.085729 -294.592877) (xy 202.147932 -294.588964)
			(xy 202.210135 -294.592877) (xy 202.271356 -294.604556) (xy 202.330631 -294.623816) (xy 202.387025 -294.650353)
			(xy 202.439649 -294.683748) (xy 202.487671 -294.723476) (xy 202.530336 -294.76891) (xy 202.56697 -294.819332)
			(xy 202.596996 -294.873949) (xy 202.619939 -294.931897) (xy 202.635439 -294.992265) (xy 202.643251 -295.054099)
			(xy 202.64374 -295.085262) (xy 205.752192 -295.085262) (xy 205.752722 -295.052562) (xy 205.761329 -294.98773)
			(xy 205.778388 -294.924593) (xy 205.803604 -294.864248) (xy 205.836537 -294.807745) (xy 205.876616 -294.756063)
			(xy 205.899512 -294.73271) (xy 205.906878 -294.725344) (xy 205.914498 -294.706802) (xy 205.914498 -294.613838)
			(xy 205.906878 -294.595296) (xy 205.899512 -294.58793) (xy 205.876603 -294.564589) (xy 205.836521 -294.512907)
			(xy 205.803587 -294.456401) (xy 205.778373 -294.396054) (xy 205.761316 -294.332914) (xy 205.752715 -294.268079)
			(xy 205.752192 -294.235378) (xy 205.752681 -294.204215) (xy 205.760493 -294.142381) (xy 205.775993 -294.082013)
			(xy 205.798936 -294.024065) (xy 205.828962 -293.969448) (xy 205.865596 -293.919026) (xy 205.908261 -293.873592)
			(xy 205.956283 -293.833864) (xy 206.008907 -293.800469) (xy 206.065301 -293.773932) (xy 206.124576 -293.754672)
			(xy 206.185797 -293.742993) (xy 206.248 -293.73908) (xy 206.310203 -293.742993) (xy 206.371424 -293.754672)
			(xy 206.430699 -293.773932) (xy 206.487093 -293.800469) (xy 206.539717 -293.833864) (xy 206.587739 -293.873592)
			(xy 206.630404 -293.919026) (xy 206.667038 -293.969448) (xy 206.697064 -294.024065) (xy 206.720007 -294.082013)
			(xy 206.735507 -294.142381) (xy 206.743319 -294.204215) (xy 206.743808 -294.235378) (xy 206.743304 -294.268079)
			(xy 206.734692 -294.332912) (xy 206.717627 -294.39605) (xy 206.692407 -294.456394) (xy 206.659469 -294.512897)
			(xy 206.619386 -294.564577) (xy 206.596488 -294.58793) (xy 206.589122 -294.595296) (xy 206.581502 -294.613838)
			(xy 206.581502 -294.66032) (xy 206.996299 -294.66032) (xy 207.000234 -294.606549) (xy 207.011957 -294.553925)
			(xy 207.031217 -294.503568) (xy 207.057603 -294.456551) (xy 207.090555 -294.413878) (xy 207.129368 -294.376457)
			(xy 207.173216 -294.345087) (xy 207.221164 -294.320435) (xy 207.272191 -294.303027) (xy 207.325209 -294.293234)
			(xy 207.379088 -294.291265) (xy 207.432679 -294.297162) (xy 207.48484 -294.310798) (xy 207.53446 -294.331885)
			(xy 207.580481 -294.359971) (xy 207.621923 -294.394459) (xy 207.657901 -294.434613) (xy 207.687649 -294.479577)
			(xy 207.710534 -294.528394) (xy 207.726066 -294.580023) (xy 207.733916 -294.633363) (xy 207.734408 -294.66032)
			(xy 207.733916 -294.687277) (xy 207.726066 -294.740617) (xy 207.710534 -294.792246) (xy 207.687649 -294.841063)
			(xy 207.657901 -294.886027) (xy 207.621923 -294.926181) (xy 207.580481 -294.960669) (xy 207.53446 -294.988755)
			(xy 207.48484 -295.009842) (xy 207.432679 -295.023478) (xy 207.379088 -295.029375) (xy 207.325209 -295.027406)
			(xy 207.272191 -295.017613) (xy 207.221164 -295.000205) (xy 207.173216 -294.975553) (xy 207.129368 -294.944183)
			(xy 207.090555 -294.906762) (xy 207.057603 -294.864089) (xy 207.031217 -294.817072) (xy 207.011957 -294.766715)
			(xy 207.000234 -294.714091) (xy 206.996299 -294.66032) (xy 206.581502 -294.66032) (xy 206.581502 -294.706802)
			(xy 206.589122 -294.725344) (xy 206.596488 -294.73271) (xy 206.619416 -294.756033) (xy 206.659496 -294.807719)
			(xy 206.692428 -294.864228) (xy 206.717639 -294.924579) (xy 206.734691 -294.987722) (xy 206.743287 -295.052559)
			(xy 206.743808 -295.085262) (xy 206.743319 -295.116425) (xy 206.735507 -295.178259) (xy 206.720007 -295.238627)
			(xy 206.697064 -295.296575) (xy 206.667038 -295.351192) (xy 206.630404 -295.401614) (xy 206.587739 -295.447048)
			(xy 206.539717 -295.486776) (xy 206.487093 -295.520171) (xy 206.430699 -295.546708) (xy 206.371424 -295.565968)
			(xy 206.310203 -295.577647) (xy 206.248 -295.58156) (xy 206.185797 -295.577647) (xy 206.124576 -295.565968)
			(xy 206.065301 -295.546708) (xy 206.008907 -295.520171) (xy 205.956283 -295.486776) (xy 205.908261 -295.447048)
			(xy 205.865596 -295.401614) (xy 205.828962 -295.351192) (xy 205.798936 -295.296575) (xy 205.775993 -295.238627)
			(xy 205.760493 -295.178259) (xy 205.752681 -295.116425) (xy 205.752192 -295.085262) (xy 202.64374 -295.085262)
			(xy 202.643243 -295.117983) (xy 202.634641 -295.182858) (xy 202.617582 -295.246038) (xy 202.592362 -295.306426)
			(xy 202.559419 -295.362972) (xy 202.519325 -295.414695) (xy 202.49642 -295.438068) (xy 202.489054 -295.44518)
			(xy 202.48118 -295.463976) (xy 202.48118 -295.510458) (xy 202.896231 -295.510458) (xy 202.900166 -295.456687)
			(xy 202.911889 -295.404063) (xy 202.931149 -295.353706) (xy 202.957535 -295.306689) (xy 202.990487 -295.264016)
			(xy 203.0293 -295.226595) (xy 203.073148 -295.195225) (xy 203.121096 -295.170573) (xy 203.172123 -295.153165)
			(xy 203.225141 -295.143372) (xy 203.27902 -295.141403) (xy 203.332611 -295.1473) (xy 203.384772 -295.160936)
			(xy 203.434392 -295.182023) (xy 203.480413 -295.210109) (xy 203.521855 -295.244597) (xy 203.557833 -295.284751)
			(xy 203.587581 -295.329715) (xy 203.610466 -295.378532) (xy 203.625998 -295.430161) (xy 203.633848 -295.483501)
			(xy 203.63434 -295.510458) (xy 203.633848 -295.537415) (xy 203.625998 -295.590755) (xy 203.610466 -295.642384)
			(xy 203.587581 -295.691201) (xy 203.557833 -295.736165) (xy 203.521855 -295.776319) (xy 203.480413 -295.810807)
			(xy 203.434392 -295.838893) (xy 203.384772 -295.85998) (xy 203.332611 -295.873616) (xy 203.27902 -295.879513)
			(xy 203.225141 -295.877544) (xy 203.172123 -295.867751) (xy 203.121096 -295.850343) (xy 203.073148 -295.825691)
			(xy 203.0293 -295.794321) (xy 202.990487 -295.7569) (xy 202.957535 -295.714227) (xy 202.931149 -295.66721)
			(xy 202.911889 -295.616853) (xy 202.900166 -295.564229) (xy 202.896231 -295.510458) (xy 202.48118 -295.510458)
			(xy 202.48118 -295.556686) (xy 202.489054 -295.575482) (xy 202.49642 -295.582594) (xy 202.519325 -295.605966)
			(xy 202.559407 -295.657694) (xy 202.592342 -295.714242) (xy 202.617556 -295.77463) (xy 202.634613 -295.837808)
			(xy 202.643216 -295.90268) (xy 202.64374 -295.9354) (xy 204.494399 -295.9354) (xy 204.498334 -295.881629)
			(xy 204.510057 -295.829005) (xy 204.529317 -295.778648) (xy 204.555703 -295.731631) (xy 204.588655 -295.688958)
			(xy 204.627468 -295.651537) (xy 204.671316 -295.620167) (xy 204.719264 -295.595515) (xy 204.770291 -295.578107)
			(xy 204.823309 -295.568314) (xy 204.877188 -295.566345) (xy 204.930779 -295.572242) (xy 204.98294 -295.585878)
			(xy 205.03256 -295.606965) (xy 205.078581 -295.635051) (xy 205.120023 -295.669539) (xy 205.156001 -295.709693)
			(xy 205.185749 -295.754657) (xy 205.208634 -295.803474) (xy 205.224166 -295.855103) (xy 205.232016 -295.908443)
			(xy 205.232508 -295.9354) (xy 205.232016 -295.962357) (xy 205.224166 -296.015697) (xy 205.208634 -296.067326)
			(xy 205.185749 -296.116143) (xy 205.156001 -296.161107) (xy 205.120023 -296.201261) (xy 205.078581 -296.235749)
			(xy 205.03256 -296.263835) (xy 204.98294 -296.284922) (xy 204.930779 -296.298558) (xy 204.877188 -296.304455)
			(xy 204.823309 -296.302486) (xy 204.770291 -296.292693) (xy 204.719264 -296.275285) (xy 204.671316 -296.250633)
			(xy 204.627468 -296.219263) (xy 204.588655 -296.181842) (xy 204.555703 -296.139169) (xy 204.529317 -296.092152)
			(xy 204.510057 -296.041795) (xy 204.498334 -295.989171) (xy 204.494399 -295.9354) (xy 202.64374 -295.9354)
			(xy 202.643251 -295.966563) (xy 202.635439 -296.028397) (xy 202.619939 -296.088765) (xy 202.596996 -296.146713)
			(xy 202.56697 -296.20133) (xy 202.530336 -296.251752) (xy 202.487671 -296.297186) (xy 202.439649 -296.336914)
			(xy 202.387025 -296.370309) (xy 202.330631 -296.396846) (xy 202.271356 -296.416106) (xy 202.210135 -296.427785)
			(xy 202.147932 -296.431698) (xy 202.085729 -296.427785) (xy 202.024508 -296.416106) (xy 201.965233 -296.396846)
			(xy 201.908839 -296.370309) (xy 201.856215 -296.336914) (xy 201.808193 -296.297186) (xy 201.765528 -296.251752)
			(xy 201.728894 -296.20133) (xy 201.698868 -296.146713) (xy 201.675925 -296.088765) (xy 201.660425 -296.028397)
			(xy 201.652613 -295.966563) (xy 201.652124 -295.9354) (xy 197.688708 -295.9354) (xy 197.688216 -295.962357)
			(xy 197.680366 -296.015697) (xy 197.664834 -296.067326) (xy 197.641949 -296.116143) (xy 197.612201 -296.161107)
			(xy 197.576223 -296.201261) (xy 197.534781 -296.235749) (xy 197.48876 -296.263835) (xy 197.43914 -296.284922)
			(xy 197.386979 -296.298558) (xy 197.333388 -296.304455) (xy 197.279509 -296.302486) (xy 197.226491 -296.292693)
			(xy 197.175464 -296.275285) (xy 197.127516 -296.250633) (xy 197.083668 -296.219263) (xy 197.044855 -296.181842)
			(xy 197.011903 -296.139169) (xy 196.985517 -296.092152) (xy 196.966257 -296.041795) (xy 196.954534 -295.989171)
			(xy 196.950599 -295.9354) (xy 195.09994 -295.9354) (xy 195.099451 -295.966563) (xy 195.091639 -296.028397)
			(xy 195.076139 -296.088765) (xy 195.053196 -296.146713) (xy 195.02317 -296.20133) (xy 194.986536 -296.251752)
			(xy 194.943871 -296.297186) (xy 194.895849 -296.336914) (xy 194.843225 -296.370309) (xy 194.786831 -296.396846)
			(xy 194.727556 -296.416106) (xy 194.666335 -296.427785) (xy 194.604132 -296.431698) (xy 194.541929 -296.427785)
			(xy 194.480708 -296.416106) (xy 194.421433 -296.396846) (xy 194.365039 -296.370309) (xy 194.312415 -296.336914)
			(xy 194.264393 -296.297186) (xy 194.221728 -296.251752) (xy 194.185094 -296.20133) (xy 194.155068 -296.146713)
			(xy 194.132125 -296.088765) (xy 194.116625 -296.028397) (xy 194.108813 -295.966563) (xy 194.108324 -295.9354)
			(xy 190.144654 -295.9354) (xy 190.144162 -295.962357) (xy 190.136312 -296.015697) (xy 190.12078 -296.067326)
			(xy 190.097895 -296.116143) (xy 190.068147 -296.161107) (xy 190.032169 -296.201261) (xy 189.990727 -296.235749)
			(xy 189.944706 -296.263835) (xy 189.895086 -296.284922) (xy 189.842925 -296.298558) (xy 189.789334 -296.304455)
			(xy 189.735455 -296.302486) (xy 189.682437 -296.292693) (xy 189.63141 -296.275285) (xy 189.583462 -296.250633)
			(xy 189.539614 -296.219263) (xy 189.500801 -296.181842) (xy 189.467849 -296.139169) (xy 189.441463 -296.092152)
			(xy 189.422203 -296.041795) (xy 189.41048 -295.989171) (xy 189.406545 -295.9354) (xy 187.555886 -295.9354)
			(xy 187.555397 -295.966563) (xy 187.547585 -296.028397) (xy 187.532085 -296.088765) (xy 187.509142 -296.146713)
			(xy 187.479116 -296.20133) (xy 187.442482 -296.251752) (xy 187.399817 -296.297186) (xy 187.351795 -296.336914)
			(xy 187.299171 -296.370309) (xy 187.242777 -296.396846) (xy 187.183502 -296.416106) (xy 187.122281 -296.427785)
			(xy 187.060078 -296.431698) (xy 186.997875 -296.427785) (xy 186.936654 -296.416106) (xy 186.877379 -296.396846)
			(xy 186.820985 -296.370309) (xy 186.768361 -296.336914) (xy 186.720339 -296.297186) (xy 186.677674 -296.251752)
			(xy 186.64104 -296.20133) (xy 186.611014 -296.146713) (xy 186.588071 -296.088765) (xy 186.572571 -296.028397)
			(xy 186.564759 -295.966563) (xy 186.56427 -295.9354) (xy 185.96864 -295.9354) (xy 185.96864 -296.785284)
			(xy 188.075077 -296.785284) (xy 188.079012 -296.731513) (xy 188.090735 -296.678889) (xy 188.109995 -296.628532)
			(xy 188.136381 -296.581515) (xy 188.169333 -296.538842) (xy 188.208146 -296.501421) (xy 188.251994 -296.470051)
			(xy 188.299942 -296.445399) (xy 188.350969 -296.427991) (xy 188.403987 -296.418198) (xy 188.457866 -296.416229)
			(xy 188.511457 -296.422126) (xy 188.563618 -296.435762) (xy 188.613238 -296.456849) (xy 188.659259 -296.484935)
			(xy 188.700701 -296.519423) (xy 188.736679 -296.559577) (xy 188.766427 -296.604541) (xy 188.789312 -296.653358)
			(xy 188.804844 -296.704987) (xy 188.812694 -296.758327) (xy 188.813186 -296.785284) (xy 188.812694 -296.812241)
			(xy 188.804844 -296.865581) (xy 188.789312 -296.91721) (xy 188.766427 -296.966027) (xy 188.736679 -297.010991)
			(xy 188.700701 -297.051145) (xy 188.659259 -297.085633) (xy 188.613238 -297.113719) (xy 188.563618 -297.134806)
			(xy 188.511457 -297.148442) (xy 188.457866 -297.154339) (xy 188.403987 -297.15237) (xy 188.350969 -297.142577)
			(xy 188.299942 -297.125169) (xy 188.251994 -297.100517) (xy 188.208146 -297.069147) (xy 188.169333 -297.031726)
			(xy 188.136381 -296.989053) (xy 188.109995 -296.942036) (xy 188.090735 -296.891679) (xy 188.079012 -296.839055)
			(xy 188.075077 -296.785284) (xy 185.96864 -296.785284) (xy 185.96864 -302.735234) (xy 186.56427 -302.735234)
			(xy 186.564747 -302.704037) (xy 186.572565 -302.642136) (xy 186.588093 -302.581706) (xy 186.611086 -302.523704)
			(xy 186.641179 -302.469048) (xy 186.677898 -302.418603) (xy 186.72066 -302.373168) (xy 186.768788 -302.333462)
			(xy 186.794902 -302.316388) (xy 186.805062 -302.309784) (xy 186.817254 -302.289972) (xy 186.826652 -302.185832)
			(xy 186.81827 -302.164242) (xy 186.80938 -302.15586) (xy 186.791121 -302.138318) (xy 186.759039 -302.099147)
			(xy 186.732618 -302.055956) (xy 186.712352 -302.009556) (xy 186.698624 -301.960821) (xy 186.691692 -301.910666)
			(xy 186.69127 -301.88535) (xy 186.691678 -301.860002) (xy 186.698616 -301.809782) (xy 186.712369 -301.760986)
			(xy 186.732677 -301.714534) (xy 186.759157 -301.671303) (xy 186.79131 -301.632106) (xy 186.809634 -301.614586)
			(xy 186.818524 -301.606458) (xy 186.826906 -301.584614) (xy 186.817254 -301.480474) (xy 186.805062 -301.460662)
			(xy 186.794902 -301.454312) (xy 186.76879 -301.437214) (xy 186.720667 -301.397462) (xy 186.677912 -301.351988)
			(xy 186.641197 -301.30151) (xy 186.611104 -301.246825) (xy 186.588108 -301.188798) (xy 186.572572 -301.128345)
			(xy 186.564742 -301.066421) (xy 186.56427 -301.035212) (xy 186.56473 -301.004015) (xy 186.57255 -300.942112)
			(xy 186.588081 -300.881682) (xy 186.611076 -300.82368) (xy 186.641173 -300.769024) (xy 186.677893 -300.718579)
			(xy 186.720657 -300.673145) (xy 186.768787 -300.633439) (xy 186.794902 -300.616366) (xy 186.805062 -300.609762)
			(xy 186.817254 -300.58995) (xy 186.826652 -300.48581) (xy 186.81827 -300.46422) (xy 186.80938 -300.455838)
			(xy 186.789484 -300.436673) (xy 186.75502 -300.393502) (xy 186.727381 -300.345673) (xy 186.707184 -300.294257)
			(xy 186.694881 -300.240405) (xy 186.690747 -300.185319) (xy 186.694875 -300.130233) (xy 186.707173 -300.076379)
			(xy 186.727364 -300.024961) (xy 186.754999 -299.97713) (xy 186.789458 -299.933955) (xy 186.80938 -299.914818)
			(xy 186.81827 -299.906436) (xy 186.826652 -299.884846) (xy 186.817254 -299.780706) (xy 186.805062 -299.760894)
			(xy 186.794902 -299.75429) (xy 186.768792 -299.737212) (xy 186.720675 -299.697496) (xy 186.677922 -299.652056)
			(xy 186.641209 -299.601611) (xy 186.611115 -299.546958) (xy 186.588117 -299.488961) (xy 186.572578 -299.428536)
			(xy 186.564744 -299.366639) (xy 186.56427 -299.335444) (xy 186.56474 -299.304235) (xy 186.572566 -299.242309)
			(xy 186.588099 -299.181853) (xy 186.611093 -299.123825) (xy 186.641187 -299.06914) (xy 186.677903 -299.018662)
			(xy 186.720662 -298.973189) (xy 186.768788 -298.933441) (xy 186.794902 -298.916344) (xy 186.805062 -298.909994)
			(xy 186.817254 -298.890182) (xy 186.826906 -298.786042) (xy 186.818524 -298.764198) (xy 186.809634 -298.75607)
			(xy 186.791306 -298.738555) (xy 186.759163 -298.699353) (xy 186.73269 -298.656118) (xy 186.712385 -298.609666)
			(xy 186.698633 -298.560872) (xy 186.691691 -298.510654) (xy 186.69127 -298.485306) (xy 186.69166 -298.459987)
			(xy 186.698588 -298.409826) (xy 186.712314 -298.361085) (xy 186.73258 -298.31468) (xy 186.759005 -298.271484)
			(xy 186.791092 -298.232311) (xy 186.80938 -298.214796) (xy 186.81827 -298.206414) (xy 186.826652 -298.184824)
			(xy 186.817254 -298.080684) (xy 186.805062 -298.060872) (xy 186.794902 -298.054268) (xy 186.768782 -298.037205)
			(xy 186.720665 -297.997487) (xy 186.677913 -297.952045) (xy 186.6412 -297.901598) (xy 186.611107 -297.846942)
			(xy 186.588111 -297.788943) (xy 186.572574 -297.728516) (xy 186.564742 -297.666618) (xy 186.56427 -297.635422)
			(xy 186.564759 -297.604259) (xy 186.572571 -297.542425) (xy 186.588071 -297.482057) (xy 186.611014 -297.424109)
			(xy 186.64104 -297.369492) (xy 186.677674 -297.31907) (xy 186.720339 -297.273636) (xy 186.768361 -297.233908)
			(xy 186.820985 -297.200513) (xy 186.877379 -297.173976) (xy 186.936654 -297.154716) (xy 186.997875 -297.143037)
			(xy 187.060078 -297.139124) (xy 187.122281 -297.143037) (xy 187.183502 -297.154716) (xy 187.242777 -297.173976)
			(xy 187.299171 -297.200513) (xy 187.351795 -297.233908) (xy 187.399817 -297.273636) (xy 187.442482 -297.31907)
			(xy 187.479116 -297.369492) (xy 187.509142 -297.424109) (xy 187.532085 -297.482057) (xy 187.547585 -297.542425)
			(xy 187.555397 -297.604259) (xy 187.555886 -297.635422) (xy 187.555473 -297.666621) (xy 187.547648 -297.728526)
			(xy 187.532112 -297.788958) (xy 187.50911 -297.846962) (xy 187.479007 -297.901618) (xy 187.44228 -297.952061)
			(xy 187.399509 -297.997494) (xy 187.351372 -298.037197) (xy 187.325254 -298.054268) (xy 187.315094 -298.060872)
			(xy 187.302902 -298.080684) (xy 187.293504 -298.184824) (xy 187.301886 -298.206414) (xy 187.310776 -298.214796)
			(xy 187.329073 -298.2323) (xy 187.361149 -298.27148) (xy 187.387564 -298.31468) (xy 187.407822 -298.361087)
			(xy 187.421543 -298.409828) (xy 187.428468 -298.459988) (xy 187.428886 -298.485306) (xy 187.428463 -298.510654)
			(xy 187.42153 -298.560874) (xy 187.407781 -298.60967) (xy 187.387476 -298.656122) (xy 187.360997 -298.699354)
			(xy 187.328846 -298.73855) (xy 187.310522 -298.75607) (xy 187.301632 -298.764198) (xy 187.29325 -298.786042)
			(xy 187.302902 -298.890182) (xy 187.315094 -298.909994) (xy 187.325254 -298.916344) (xy 187.351359 -298.933452)
			(xy 187.399479 -298.973205) (xy 187.442234 -299.018678) (xy 187.478947 -299.069155) (xy 187.50904 -299.123837)
			(xy 187.532038 -299.181862) (xy 187.547577 -299.242313) (xy 187.555412 -299.304236) (xy 187.555886 -299.335444)
			(xy 187.555412 -299.366641) (xy 187.547597 -299.428544) (xy 187.53207 -299.488974) (xy 187.509077 -299.546977)
			(xy 187.478982 -299.601634) (xy 187.442263 -299.652078) (xy 187.399499 -299.697513) (xy 187.351369 -299.737218)
			(xy 187.325254 -299.75429) (xy 187.315094 -299.760894) (xy 187.302902 -299.780706) (xy 187.293504 -299.884846)
			(xy 187.301886 -299.906436) (xy 187.310776 -299.914818) (xy 187.33073 -299.933926) (xy 187.365197 -299.977104)
			(xy 187.392838 -300.02494) (xy 187.413035 -300.076364) (xy 187.425335 -300.130226) (xy 187.429464 -300.185319)
			(xy 187.425329 -300.240412) (xy 187.413023 -300.294272) (xy 187.392821 -300.345694) (xy 187.365176 -300.393527)
			(xy 187.330704 -300.436702) (xy 187.310776 -300.455838) (xy 187.301886 -300.46422) (xy 187.293504 -300.48581)
			(xy 187.302902 -300.58995) (xy 187.315094 -300.609762) (xy 187.325254 -300.616366) (xy 187.351333 -300.633489)
			(xy 187.399452 -300.673197) (xy 187.442208 -300.718629) (xy 187.478926 -300.769067) (xy 187.509023 -300.823714)
			(xy 187.532026 -300.881706) (xy 187.54757 -300.942126) (xy 187.555409 -301.004018) (xy 187.555886 -301.035212)
			(xy 187.555402 -301.066421) (xy 187.547581 -301.128347) (xy 187.532052 -301.188803) (xy 187.50906 -301.246832)
			(xy 187.478968 -301.301518) (xy 187.442253 -301.351996) (xy 187.399495 -301.397468) (xy 187.351368 -301.437216)
			(xy 187.325254 -301.454312) (xy 187.315094 -301.460662) (xy 187.302902 -301.480474) (xy 187.29325 -301.584614)
			(xy 187.301632 -301.606458) (xy 187.310522 -301.614586) (xy 187.328839 -301.632111) (xy 187.360981 -301.671313)
			(xy 187.387455 -301.714545) (xy 187.40776 -301.760995) (xy 187.421516 -301.809787) (xy 187.428463 -301.860003)
			(xy 187.428886 -301.88535) (xy 190.664338 -301.88535) (xy 190.664781 -301.854139) (xy 190.672607 -301.792211)
			(xy 190.688142 -301.731754) (xy 190.711139 -301.673724) (xy 190.741236 -301.619038) (xy 190.777957 -301.568561)
			(xy 190.820721 -301.52309) (xy 190.868853 -301.483344) (xy 190.89497 -301.46625) (xy 190.90513 -301.4599)
			(xy 190.917322 -301.440088) (xy 190.926974 -301.335948) (xy 190.918592 -301.314104) (xy 190.909702 -301.305976)
			(xy 190.891371 -301.288464) (xy 190.859229 -301.249261) (xy 190.832757 -301.206025) (xy 190.812454 -301.159573)
			(xy 190.798701 -301.110778) (xy 190.791759 -301.06056) (xy 190.791338 -301.035212) (xy 190.791742 -301.009894)
			(xy 190.798668 -300.959734) (xy 190.812392 -300.910993) (xy 190.832656 -300.864588) (xy 190.859078 -300.821392)
			(xy 190.891162 -300.782217) (xy 190.909448 -300.764702) (xy 190.918338 -300.75632) (xy 190.92672 -300.73473)
			(xy 190.917322 -300.63059) (xy 190.90513 -300.610778) (xy 190.89497 -300.604174) (xy 190.868883 -300.58706)
			(xy 190.820756 -300.547354) (xy 190.777993 -300.501922) (xy 190.741272 -300.451482) (xy 190.711172 -300.396831)
			(xy 190.68817 -300.338834) (xy 190.672629 -300.278409) (xy 190.664796 -300.216511) (xy 190.664794 -300.154119)
			(xy 190.672623 -300.092221) (xy 190.68816 -300.031795) (xy 190.711159 -299.973796) (xy 190.741256 -299.919144)
			(xy 190.777974 -299.868701) (xy 190.820734 -299.823266) (xy 190.868858 -299.783558) (xy 190.89497 -299.766482)
			(xy 190.90513 -299.759878) (xy 190.917322 -299.740066) (xy 190.92672 -299.635926) (xy 190.918338 -299.614336)
			(xy 190.909448 -299.605954) (xy 190.89118 -299.588422) (xy 190.8591 -299.549248) (xy 190.832681 -299.506054)
			(xy 190.812417 -299.459653) (xy 190.798691 -299.410916) (xy 190.791759 -299.36076) (xy 190.791338 -299.335444)
			(xy 190.79172 -299.310094) (xy 190.798661 -299.259873) (xy 190.812417 -299.211075) (xy 190.83273 -299.164623)
			(xy 190.859216 -299.121393) (xy 190.891375 -299.082198) (xy 190.909702 -299.06468) (xy 190.918592 -299.056552)
			(xy 190.926974 -299.034708) (xy 190.917322 -298.930568) (xy 190.90513 -298.910756) (xy 190.89497 -298.904406)
			(xy 190.868847 -298.887323) (xy 190.820726 -298.847568) (xy 190.777972 -298.802091) (xy 190.741259 -298.751611)
			(xy 190.711168 -298.696924) (xy 190.688173 -298.638896) (xy 190.672639 -298.578441) (xy 190.664809 -298.516515)
			(xy 190.664338 -298.485306) (xy 190.664808 -298.454109) (xy 190.672628 -298.392208) (xy 190.688159 -298.331778)
			(xy 190.711153 -298.273777) (xy 190.741248 -298.219121) (xy 190.777967 -298.168676) (xy 190.820728 -298.123241)
			(xy 190.868856 -298.083534) (xy 190.89497 -298.06646) (xy 190.90513 -298.059856) (xy 190.917322 -298.040044)
			(xy 190.92672 -297.935904) (xy 190.918338 -297.914314) (xy 190.909448 -297.905932) (xy 190.891169 -297.88841)
			(xy 190.859091 -297.849234) (xy 190.832672 -297.806038) (xy 190.812411 -297.759635) (xy 190.798687 -297.710897)
			(xy 190.791758 -297.660739) (xy 190.791338 -297.635422) (xy 190.791772 -297.610074) (xy 190.798702 -297.559855)
			(xy 190.812448 -297.511058) (xy 190.832751 -297.464606) (xy 190.859228 -297.421374) (xy 190.891379 -297.382178)
			(xy 190.909702 -297.364658) (xy 190.918592 -297.35653) (xy 190.926974 -297.334686) (xy 190.917322 -297.230546)
			(xy 190.90513 -297.210734) (xy 190.89497 -297.204384) (xy 190.868837 -297.187316) (xy 190.820716 -297.147559)
			(xy 190.777963 -297.102079) (xy 190.741251 -297.051597) (xy 190.711161 -296.996908) (xy 190.688168 -296.938878)
			(xy 190.672635 -296.878421) (xy 190.664808 -296.816494) (xy 190.664338 -296.785284) (xy 190.664827 -296.754121)
			(xy 190.672639 -296.692287) (xy 190.688139 -296.631919) (xy 190.711082 -296.573971) (xy 190.741108 -296.519354)
			(xy 190.777742 -296.468932) (xy 190.820407 -296.423498) (xy 190.868429 -296.38377) (xy 190.921053 -296.350375)
			(xy 190.977447 -296.323838) (xy 191.036722 -296.304578) (xy 191.097943 -296.292899) (xy 191.160146 -296.288986)
			(xy 191.222349 -296.292899) (xy 191.28357 -296.304578) (xy 191.342845 -296.323838) (xy 191.399239 -296.350375)
			(xy 191.451863 -296.38377) (xy 191.499885 -296.423498) (xy 191.54255 -296.468932) (xy 191.579184 -296.519354)
			(xy 191.60921 -296.573971) (xy 191.632153 -296.631919) (xy 191.647653 -296.692287) (xy 191.655465 -296.754121)
			(xy 191.655954 -296.785284) (xy 195.619131 -296.785284) (xy 195.623066 -296.731513) (xy 195.634789 -296.678889)
			(xy 195.654049 -296.628532) (xy 195.680435 -296.581515) (xy 195.713387 -296.538842) (xy 195.7522 -296.501421)
			(xy 195.796048 -296.470051) (xy 195.843996 -296.445399) (xy 195.895023 -296.427991) (xy 195.948041 -296.418198)
			(xy 196.00192 -296.416229) (xy 196.055511 -296.422126) (xy 196.107672 -296.435762) (xy 196.157292 -296.456849)
			(xy 196.203313 -296.484935) (xy 196.244755 -296.519423) (xy 196.280733 -296.559577) (xy 196.310481 -296.604541)
			(xy 196.333366 -296.653358) (xy 196.348898 -296.704987) (xy 196.356748 -296.758327) (xy 196.35724 -296.785284)
			(xy 196.356748 -296.812241) (xy 196.348898 -296.865581) (xy 196.333366 -296.91721) (xy 196.310481 -296.966027)
			(xy 196.280733 -297.010991) (xy 196.244755 -297.051145) (xy 196.203313 -297.085633) (xy 196.157292 -297.113719)
			(xy 196.107672 -297.134806) (xy 196.055511 -297.148442) (xy 196.00192 -297.154339) (xy 195.948041 -297.15237)
			(xy 195.895023 -297.142577) (xy 195.843996 -297.125169) (xy 195.796048 -297.100517) (xy 195.7522 -297.069147)
			(xy 195.713387 -297.031726) (xy 195.680435 -296.989053) (xy 195.654049 -296.942036) (xy 195.634789 -296.891679)
			(xy 195.623066 -296.839055) (xy 195.619131 -296.785284) (xy 191.655954 -296.785284) (xy 191.655541 -296.816495)
			(xy 191.647711 -296.878425) (xy 191.632172 -296.938883) (xy 191.60917 -296.996914) (xy 191.579069 -297.051599)
			(xy 191.542344 -297.102076) (xy 191.499576 -297.147546) (xy 191.451441 -297.18729) (xy 191.425322 -297.204384)
			(xy 191.415162 -297.210734) (xy 191.40297 -297.230546) (xy 191.393318 -297.334686) (xy 191.4017 -297.35653)
			(xy 191.41059 -297.364658) (xy 191.428936 -297.382155) (xy 191.461077 -297.421362) (xy 191.487547 -297.4646)
			(xy 191.507848 -297.511055) (xy 191.521597 -297.559853) (xy 191.528535 -297.610073) (xy 191.528954 -297.635422)
			(xy 191.528508 -297.660739) (xy 191.521591 -297.710897) (xy 191.507875 -297.759637) (xy 191.487619 -297.806042)
			(xy 191.461204 -297.849239) (xy 191.429127 -297.888415) (xy 191.410844 -297.905932) (xy 191.401954 -297.914314)
			(xy 191.393572 -297.935904) (xy 191.40297 -298.040044) (xy 191.415162 -298.059856) (xy 191.425322 -298.06646)
			(xy 191.45146 -298.083496) (xy 191.499576 -298.123219) (xy 191.542327 -298.168665) (xy 191.579038 -298.219117)
			(xy 191.609128 -298.273776) (xy 191.632121 -298.331778) (xy 191.647655 -298.392208) (xy 191.655483 -298.454109)
			(xy 191.655954 -298.485306) (xy 191.65548 -298.516516) (xy 191.647659 -298.578443) (xy 191.63213 -298.638899)
			(xy 191.609137 -298.696929) (xy 191.579044 -298.751615) (xy 191.542327 -298.802093) (xy 191.499566 -298.847565)
			(xy 191.451438 -298.887311) (xy 191.425322 -298.904406) (xy 191.415162 -298.910756) (xy 191.40297 -298.930568)
			(xy 191.393318 -299.034708) (xy 191.4017 -299.056552) (xy 191.41059 -299.06468) (xy 191.428898 -299.082214)
			(xy 191.461042 -299.121413) (xy 191.487518 -299.164644) (xy 191.507825 -299.211092) (xy 191.521582 -299.259883)
			(xy 191.52853 -299.310097) (xy 191.528954 -299.335444) (xy 191.528523 -299.360761) (xy 191.521602 -299.41092)
			(xy 191.507884 -299.459661) (xy 191.487625 -299.506066) (xy 191.461208 -299.549262) (xy 191.429128 -299.588438)
			(xy 191.410844 -299.605954) (xy 191.401954 -299.614336) (xy 191.393572 -299.635926) (xy 191.40297 -299.740066)
			(xy 191.415162 -299.759878) (xy 191.425322 -299.766482) (xy 191.451462 -299.783519) (xy 191.499592 -299.823231)
			(xy 191.542356 -299.86867) (xy 191.579079 -299.919117) (xy 191.609179 -299.973775) (xy 191.63218 -300.031779)
			(xy 191.647719 -300.092211) (xy 191.655549 -300.154116) (xy 191.655547 -300.216514) (xy 191.647713 -300.278418)
			(xy 191.632171 -300.338849) (xy 191.609166 -300.396852) (xy 191.579062 -300.451508) (xy 191.542337 -300.501953)
			(xy 191.49957 -300.54739) (xy 191.451438 -300.587098) (xy 191.425322 -300.604174) (xy 191.415162 -300.610778)
			(xy 191.40297 -300.63059) (xy 191.393572 -300.73473) (xy 191.401954 -300.75632) (xy 191.410844 -300.764702)
			(xy 191.429138 -300.782209) (xy 191.461215 -300.821388) (xy 191.487632 -300.864587) (xy 191.507891 -300.910993)
			(xy 191.521612 -300.959734) (xy 191.528536 -301.009894) (xy 191.528954 -301.035212) (xy 191.528545 -301.060561)
			(xy 191.52161 -301.110781) (xy 191.507859 -301.159578) (xy 191.487552 -301.20603) (xy 191.46107 -301.249262)
			(xy 191.428915 -301.288457) (xy 191.41059 -301.305976) (xy 191.4017 -301.314104) (xy 191.393318 -301.335948)
			(xy 191.40297 -301.440088) (xy 191.415162 -301.4599) (xy 191.425322 -301.46625) (xy 191.451423 -301.483365)
			(xy 191.499544 -301.523115) (xy 191.5423 -301.568588) (xy 191.579014 -301.619063) (xy 191.609109 -301.673745)
			(xy 191.632107 -301.731769) (xy 191.647646 -301.79222) (xy 191.65548 -301.854142) (xy 191.655954 -301.88535)
			(xy 191.655465 -301.916513) (xy 191.647653 -301.978347) (xy 191.632153 -302.038715) (xy 191.60921 -302.096663)
			(xy 191.579184 -302.15128) (xy 191.54255 -302.201702) (xy 191.499885 -302.247136) (xy 191.451863 -302.286864)
			(xy 191.399239 -302.320259) (xy 191.342845 -302.346796) (xy 191.28357 -302.366056) (xy 191.222349 -302.377735)
			(xy 191.160146 -302.381648) (xy 191.097943 -302.377735) (xy 191.036722 -302.366056) (xy 190.977447 -302.346796)
			(xy 190.921053 -302.320259) (xy 190.868429 -302.286864) (xy 190.820407 -302.247136) (xy 190.777742 -302.201702)
			(xy 190.741108 -302.15128) (xy 190.711082 -302.096663) (xy 190.688139 -302.038715) (xy 190.672639 -301.978347)
			(xy 190.664827 -301.916513) (xy 190.664338 -301.88535) (xy 187.428886 -301.88535) (xy 187.428449 -301.910667)
			(xy 187.421528 -301.960825) (xy 187.40781 -302.009565) (xy 187.387552 -302.05597) (xy 187.361137 -302.099167)
			(xy 187.329059 -302.138343) (xy 187.310776 -302.15586) (xy 187.301886 -302.164242) (xy 187.293504 -302.185832)
			(xy 187.302902 -302.289972) (xy 187.315094 -302.309784) (xy 187.325254 -302.316388) (xy 187.351343 -302.333496)
			(xy 187.399462 -302.373206) (xy 187.442218 -302.41864) (xy 187.478934 -302.469081) (xy 187.509031 -302.52373)
			(xy 187.532032 -302.581724) (xy 187.547574 -302.642145) (xy 187.555411 -302.70404) (xy 187.555886 -302.735234)
			(xy 189.406545 -302.735234) (xy 189.41048 -302.681463) (xy 189.422203 -302.628839) (xy 189.441463 -302.578482)
			(xy 189.467849 -302.531465) (xy 189.500801 -302.488792) (xy 189.539614 -302.451371) (xy 189.583462 -302.420001)
			(xy 189.63141 -302.395349) (xy 189.682437 -302.377941) (xy 189.735455 -302.368148) (xy 189.789334 -302.366179)
			(xy 189.842925 -302.372076) (xy 189.895086 -302.385712) (xy 189.944706 -302.406799) (xy 189.990727 -302.434885)
			(xy 190.032169 -302.469373) (xy 190.068147 -302.509527) (xy 190.097895 -302.554491) (xy 190.12078 -302.603308)
			(xy 190.136312 -302.654937) (xy 190.144162 -302.708277) (xy 190.144654 -302.735234) (xy 194.108324 -302.735234)
			(xy 194.108776 -302.704036) (xy 194.116595 -302.642133) (xy 194.132125 -302.581701) (xy 194.15512 -302.523698)
			(xy 194.185218 -302.469041) (xy 194.22194 -302.418597) (xy 194.264706 -302.373163) (xy 194.31284 -302.33346)
			(xy 194.338956 -302.316388) (xy 194.349116 -302.309784) (xy 194.361308 -302.289972) (xy 194.370706 -302.185832)
			(xy 194.362324 -302.164242) (xy 194.353434 -302.15586) (xy 194.335166 -302.138327) (xy 194.303087 -302.099153)
			(xy 194.276668 -302.05596) (xy 194.256404 -302.009559) (xy 194.242678 -301.960822) (xy 194.235746 -301.910666)
			(xy 194.235324 -301.88535) (xy 194.235715 -301.860001) (xy 194.242654 -301.809779) (xy 194.256409 -301.760983)
			(xy 194.27672 -301.714531) (xy 194.303204 -301.6713) (xy 194.335362 -301.632105) (xy 194.353688 -301.614586)
			(xy 194.362578 -301.606458) (xy 194.37096 -301.584614) (xy 194.361308 -301.480474) (xy 194.349116 -301.460662)
			(xy 194.338956 -301.454312) (xy 194.312833 -301.43723) (xy 194.264713 -301.397474) (xy 194.221959 -301.351997)
			(xy 194.185246 -301.301516) (xy 194.155155 -301.24683) (xy 194.13216 -301.188801) (xy 194.116625 -301.128347)
			(xy 194.108795 -301.066421) (xy 194.108324 -301.035212) (xy 194.108759 -301.004014) (xy 194.11658 -300.942109)
			(xy 194.132113 -300.881677) (xy 194.155111 -300.823674) (xy 194.185211 -300.769018) (xy 194.221935 -300.718574)
			(xy 194.264704 -300.673141) (xy 194.312839 -300.633437) (xy 194.338956 -300.616366) (xy 194.349116 -300.609762)
			(xy 194.361308 -300.58995) (xy 194.370706 -300.48581) (xy 194.362324 -300.46422) (xy 194.353434 -300.455838)
			(xy 194.333535 -300.436674) (xy 194.299067 -300.393505) (xy 194.271423 -300.345677) (xy 194.251223 -300.29426)
			(xy 194.238918 -300.240406) (xy 194.234784 -300.185319) (xy 194.238913 -300.130232) (xy 194.251212 -300.076376)
			(xy 194.271407 -300.024958) (xy 194.299045 -299.977127) (xy 194.333509 -299.933954) (xy 194.353434 -299.914818)
			(xy 194.362324 -299.906436) (xy 194.370706 -299.884846) (xy 194.361308 -299.780706) (xy 194.349116 -299.760894)
			(xy 194.338956 -299.75429) (xy 194.312859 -299.737193) (xy 194.264739 -299.697482) (xy 194.221984 -299.652046)
			(xy 194.185268 -299.601604) (xy 194.155172 -299.546953) (xy 194.132173 -299.488958) (xy 194.116633 -299.428534)
			(xy 194.108798 -299.366639) (xy 194.108324 -299.335444) (xy 194.108769 -299.304234) (xy 194.116596 -299.242306)
			(xy 194.13213 -299.181849) (xy 194.155128 -299.123819) (xy 194.185225 -299.069133) (xy 194.221945 -299.018656)
			(xy 194.264709 -298.973185) (xy 194.312839 -298.933439) (xy 194.338956 -298.916344) (xy 194.349116 -298.909994)
			(xy 194.361308 -298.890182) (xy 194.37096 -298.786042) (xy 194.362578 -298.764198) (xy 194.353688 -298.75607)
			(xy 194.335352 -298.738564) (xy 194.303211 -298.699359) (xy 194.27674 -298.656122) (xy 194.256437 -298.609669)
			(xy 194.242686 -298.560873) (xy 194.235745 -298.510654) (xy 194.235324 -298.485306) (xy 194.235728 -298.459988)
			(xy 194.242655 -298.409828) (xy 194.256379 -298.361087) (xy 194.276643 -298.314683) (xy 194.303065 -298.271487)
			(xy 194.335148 -298.232312) (xy 194.353434 -298.214796) (xy 194.362324 -298.206414) (xy 194.370706 -298.184824)
			(xy 194.361308 -298.080684) (xy 194.349116 -298.060872) (xy 194.338956 -298.054268) (xy 194.312849 -298.037186)
			(xy 194.264729 -297.997473) (xy 194.221974 -297.952035) (xy 194.185259 -297.90159) (xy 194.155165 -297.846937)
			(xy 194.132167 -297.78894) (xy 194.116629 -297.728515) (xy 194.108796 -297.666617) (xy 194.108324 -297.635422)
			(xy 194.108813 -297.604259) (xy 194.116625 -297.542425) (xy 194.132125 -297.482057) (xy 194.155068 -297.424109)
			(xy 194.185094 -297.369492) (xy 194.221728 -297.31907) (xy 194.264393 -297.273636) (xy 194.312415 -297.233908)
			(xy 194.365039 -297.200513) (xy 194.421433 -297.173976) (xy 194.480708 -297.154716) (xy 194.541929 -297.143037)
			(xy 194.604132 -297.139124) (xy 194.666335 -297.143037) (xy 194.727556 -297.154716) (xy 194.786831 -297.173976)
			(xy 194.843225 -297.200513) (xy 194.895849 -297.233908) (xy 194.943871 -297.273636) (xy 194.986536 -297.31907)
			(xy 195.02317 -297.369492) (xy 195.053196 -297.424109) (xy 195.076139 -297.482057) (xy 195.091639 -297.542425)
			(xy 195.099451 -297.604259) (xy 195.09994 -297.635422) (xy 195.099502 -297.66662) (xy 195.091678 -297.728523)
			(xy 195.076143 -297.788954) (xy 195.053145 -297.846956) (xy 195.023045 -297.901612) (xy 194.986322 -297.952056)
			(xy 194.943556 -297.99749) (xy 194.895424 -298.037195) (xy 194.869308 -298.054268) (xy 194.859148 -298.060872)
			(xy 194.846956 -298.080684) (xy 194.837558 -298.184824) (xy 194.84594 -298.206414) (xy 194.85483 -298.214796)
			(xy 194.873118 -298.232309) (xy 194.905197 -298.271486) (xy 194.931614 -298.314684) (xy 194.951874 -298.361089)
			(xy 194.965596 -298.409829) (xy 194.972522 -298.459988) (xy 194.97294 -298.485306) (xy 194.9725 -298.510653)
			(xy 194.965567 -298.560872) (xy 194.951821 -298.609667) (xy 194.931519 -298.656118) (xy 194.905045 -298.699351)
			(xy 194.872897 -298.738549) (xy 194.854576 -298.75607) (xy 194.845686 -298.764198) (xy 194.837304 -298.786042)
			(xy 194.846956 -298.890182) (xy 194.859148 -298.909994) (xy 194.869308 -298.916344) (xy 194.895403 -298.933468)
			(xy 194.943524 -298.973217) (xy 194.986281 -299.018687) (xy 195.022996 -299.069161) (xy 195.053091 -299.123842)
			(xy 195.07609 -299.181865) (xy 195.09163 -299.242315) (xy 195.099466 -299.304236) (xy 195.09994 -299.335444)
			(xy 195.099441 -299.36664) (xy 195.091626 -299.428541) (xy 195.076101 -299.48897) (xy 195.053111 -299.546972)
			(xy 195.023021 -299.601628) (xy 194.986305 -299.652073) (xy 194.943546 -299.697508) (xy 194.895421 -299.737216)
			(xy 194.869308 -299.75429) (xy 194.859148 -299.760894) (xy 194.846956 -299.780706) (xy 194.837558 -299.884846)
			(xy 194.84594 -299.906436) (xy 194.85483 -299.914818) (xy 194.874782 -299.933927) (xy 194.909244 -299.977107)
			(xy 194.93688 -300.024944) (xy 194.957074 -300.076367) (xy 194.969372 -300.130227) (xy 194.973501 -300.185319)
			(xy 194.969367 -300.24041) (xy 194.957063 -300.294269) (xy 194.936864 -300.34569) (xy 194.909222 -300.393524)
			(xy 194.874756 -300.436701) (xy 194.85483 -300.455838) (xy 194.84594 -300.46422) (xy 194.837558 -300.48581)
			(xy 194.846956 -300.58995) (xy 194.859148 -300.609762) (xy 194.869308 -300.616366) (xy 194.8954 -300.63347)
			(xy 194.943516 -300.673183) (xy 194.98627 -300.718619) (xy 195.022985 -300.76906) (xy 195.053081 -300.823709)
			(xy 195.076082 -300.881703) (xy 195.091625 -300.942124) (xy 195.099464 -301.004018) (xy 195.09994 -301.035212)
			(xy 195.099431 -301.06642) (xy 195.091611 -301.128344) (xy 195.076084 -301.188798) (xy 195.053094 -301.246827)
			(xy 195.023007 -301.301512) (xy 194.986296 -301.35199) (xy 194.943541 -301.397464) (xy 194.89542 -301.437214)
			(xy 194.869308 -301.454312) (xy 194.859148 -301.460662) (xy 194.846956 -301.480474) (xy 194.837304 -301.584614)
			(xy 194.845686 -301.606458) (xy 194.854576 -301.614586) (xy 194.872884 -301.63212) (xy 194.905029 -301.671319)
			(xy 194.931505 -301.714549) (xy 194.951812 -301.760997) (xy 194.965569 -301.809788) (xy 194.972516 -301.860003)
			(xy 194.97294 -301.88535) (xy 198.208392 -301.88535) (xy 198.208857 -301.85414) (xy 198.216682 -301.792214)
			(xy 198.232215 -301.731758) (xy 198.25521 -301.673729) (xy 198.285304 -301.619043) (xy 198.322021 -301.568566)
			(xy 198.364782 -301.523094) (xy 198.412909 -301.483346) (xy 198.439024 -301.46625) (xy 198.449184 -301.4599)
			(xy 198.461376 -301.440088) (xy 198.471028 -301.335948) (xy 198.462646 -301.314104) (xy 198.453756 -301.305976)
			(xy 198.435435 -301.288454) (xy 198.40329 -301.249253) (xy 198.376816 -301.206021) (xy 198.35651 -301.15957)
			(xy 198.342756 -301.110777) (xy 198.335813 -301.060559) (xy 198.335392 -301.035212) (xy 198.335811 -301.009895)
			(xy 198.342736 -300.959736) (xy 198.356458 -300.910996) (xy 198.376719 -300.864591) (xy 198.403138 -300.821395)
			(xy 198.435218 -300.782219) (xy 198.453502 -300.764702) (xy 198.462392 -300.75632) (xy 198.470774 -300.73473)
			(xy 198.461376 -300.63059) (xy 198.449184 -300.610778) (xy 198.439024 -300.604174) (xy 198.412934 -300.587062)
			(xy 198.364803 -300.547359) (xy 198.322036 -300.501928) (xy 198.28531 -300.451488) (xy 198.255206 -300.396836)
			(xy 198.232202 -300.338839) (xy 198.216659 -300.278412) (xy 198.208825 -300.216512) (xy 198.208823 -300.154118)
			(xy 198.216653 -300.092218) (xy 198.232192 -300.03179) (xy 198.255194 -299.973791) (xy 198.285294 -299.919138)
			(xy 198.322017 -299.868695) (xy 198.364781 -299.823262) (xy 198.41291 -299.783556) (xy 198.439024 -299.766482)
			(xy 198.449184 -299.759878) (xy 198.461376 -299.740066) (xy 198.470774 -299.635926) (xy 198.462392 -299.614336)
			(xy 198.453502 -299.605954) (xy 198.435244 -299.588411) (xy 198.403162 -299.549241) (xy 198.376739 -299.50605)
			(xy 198.356474 -299.45965) (xy 198.342746 -299.410915) (xy 198.335813 -299.36076) (xy 198.335392 -299.335444)
			(xy 198.335789 -299.310095) (xy 198.342728 -299.259874) (xy 198.356483 -299.211078) (xy 198.376793 -299.164626)
			(xy 198.403275 -299.121395) (xy 198.435431 -299.0822) (xy 198.453756 -299.06468) (xy 198.462646 -299.056552)
			(xy 198.471028 -299.034708) (xy 198.461376 -298.930568) (xy 198.449184 -298.910756) (xy 198.439024 -298.904406)
			(xy 198.412914 -298.887304) (xy 198.364791 -298.847554) (xy 198.322034 -298.80208) (xy 198.285319 -298.751603)
			(xy 198.255226 -298.696919) (xy 198.23223 -298.638892) (xy 198.216694 -298.578439) (xy 198.208863 -298.516515)
			(xy 198.208392 -298.485306) (xy 198.208837 -298.454108) (xy 198.216658 -298.392205) (xy 198.232191 -298.331774)
			(xy 198.255188 -298.273771) (xy 198.285286 -298.219115) (xy 198.322009 -298.168671) (xy 198.364775 -298.123237)
			(xy 198.412908 -298.083532) (xy 198.439024 -298.06646) (xy 198.449184 -298.059856) (xy 198.461376 -298.040044)
			(xy 198.470774 -297.935904) (xy 198.462392 -297.914314) (xy 198.453502 -297.905932) (xy 198.435233 -297.8884)
			(xy 198.403152 -297.849227) (xy 198.376731 -297.806034) (xy 198.356467 -297.759632) (xy 198.342741 -297.710895)
			(xy 198.335812 -297.660739) (xy 198.335392 -297.635422) (xy 198.335841 -297.610075) (xy 198.34277 -297.559857)
			(xy 198.356514 -297.511061) (xy 198.376814 -297.464609) (xy 198.403288 -297.421377) (xy 198.435435 -297.382179)
			(xy 198.453756 -297.364658) (xy 198.462646 -297.35653) (xy 198.471028 -297.334686) (xy 198.461376 -297.230546)
			(xy 198.449184 -297.210734) (xy 198.439024 -297.204384) (xy 198.412904 -297.187297) (xy 198.364781 -297.147544)
			(xy 198.322025 -297.102069) (xy 198.28531 -297.051589) (xy 198.255218 -296.996903) (xy 198.232224 -296.938874)
			(xy 198.21669 -296.878419) (xy 198.208862 -296.816493) (xy 198.208392 -296.785284) (xy 198.208881 -296.754121)
			(xy 198.216693 -296.692287) (xy 198.232193 -296.631919) (xy 198.255136 -296.573971) (xy 198.285162 -296.519354)
			(xy 198.321796 -296.468932) (xy 198.364461 -296.423498) (xy 198.412483 -296.38377) (xy 198.465107 -296.350375)
			(xy 198.521501 -296.323838) (xy 198.580776 -296.304578) (xy 198.641997 -296.292899) (xy 198.7042 -296.288986)
			(xy 198.766403 -296.292899) (xy 198.827624 -296.304578) (xy 198.886899 -296.323838) (xy 198.943293 -296.350375)
			(xy 198.995917 -296.38377) (xy 199.043939 -296.423498) (xy 199.086604 -296.468932) (xy 199.123238 -296.519354)
			(xy 199.153264 -296.573971) (xy 199.176207 -296.631919) (xy 199.191707 -296.692287) (xy 199.199519 -296.754121)
			(xy 199.200008 -296.785284) (xy 203.162931 -296.785284) (xy 203.166866 -296.731513) (xy 203.178589 -296.678889)
			(xy 203.197849 -296.628532) (xy 203.224235 -296.581515) (xy 203.257187 -296.538842) (xy 203.296 -296.501421)
			(xy 203.339848 -296.470051) (xy 203.387796 -296.445399) (xy 203.438823 -296.427991) (xy 203.491841 -296.418198)
			(xy 203.54572 -296.416229) (xy 203.599311 -296.422126) (xy 203.651472 -296.435762) (xy 203.701092 -296.456849)
			(xy 203.747113 -296.484935) (xy 203.788555 -296.519423) (xy 203.824533 -296.559577) (xy 203.854281 -296.604541)
			(xy 203.877166 -296.653358) (xy 203.892698 -296.704987) (xy 203.900548 -296.758327) (xy 203.90104 -296.785284)
			(xy 203.900548 -296.812241) (xy 203.892698 -296.865581) (xy 203.877166 -296.91721) (xy 203.854281 -296.966027)
			(xy 203.824533 -297.010991) (xy 203.788555 -297.051145) (xy 203.747113 -297.085633) (xy 203.701092 -297.113719)
			(xy 203.651472 -297.134806) (xy 203.599311 -297.148442) (xy 203.54572 -297.154339) (xy 203.491841 -297.15237)
			(xy 203.438823 -297.142577) (xy 203.387796 -297.125169) (xy 203.339848 -297.100517) (xy 203.296 -297.069147)
			(xy 203.257187 -297.031726) (xy 203.224235 -296.989053) (xy 203.197849 -296.942036) (xy 203.178589 -296.891679)
			(xy 203.166866 -296.839055) (xy 203.162931 -296.785284) (xy 199.200008 -296.785284) (xy 199.19957 -296.816494)
			(xy 199.19174 -296.878422) (xy 199.176204 -296.938879) (xy 199.153204 -296.996908) (xy 199.123107 -297.051593)
			(xy 199.086386 -297.10207) (xy 199.043623 -297.147542) (xy 198.995492 -297.187289) (xy 198.969376 -297.204384)
			(xy 198.959216 -297.210734) (xy 198.947024 -297.230546) (xy 198.937372 -297.334686) (xy 198.945754 -297.35653)
			(xy 198.954644 -297.364658) (xy 198.972981 -297.382164) (xy 199.005125 -297.421368) (xy 199.031597 -297.464604)
			(xy 199.0519 -297.511058) (xy 199.06565 -297.559854) (xy 199.072589 -297.610074) (xy 199.073008 -297.635422)
			(xy 199.072545 -297.660738) (xy 199.065629 -297.710895) (xy 199.051915 -297.759634) (xy 199.031662 -297.806039)
			(xy 199.005251 -297.849236) (xy 198.973179 -297.888414) (xy 198.954898 -297.905932) (xy 198.946008 -297.914314)
			(xy 198.937626 -297.935904) (xy 198.947024 -298.040044) (xy 198.959216 -298.059856) (xy 198.969376 -298.06646)
			(xy 198.995503 -298.083512) (xy 199.043621 -298.123231) (xy 199.086374 -298.168674) (xy 199.123087 -298.219123)
			(xy 199.153179 -298.27378) (xy 199.176174 -298.331781) (xy 199.191708 -298.392209) (xy 199.199537 -298.454109)
			(xy 199.200008 -298.485306) (xy 199.199509 -298.516515) (xy 199.191689 -298.57844) (xy 199.176162 -298.638895)
			(xy 199.153171 -298.696923) (xy 199.123082 -298.751609) (xy 199.086369 -298.802087) (xy 199.043613 -298.84756)
			(xy 198.995489 -298.887309) (xy 198.969376 -298.904406) (xy 198.959216 -298.910756) (xy 198.947024 -298.930568)
			(xy 198.937372 -299.034708) (xy 198.945754 -299.056552) (xy 198.954644 -299.06468) (xy 198.972943 -299.082223)
			(xy 199.00509 -299.121419) (xy 199.031568 -299.164647) (xy 199.051877 -299.211094) (xy 199.065635 -299.259884)
			(xy 199.072584 -299.310098) (xy 199.073008 -299.335444) (xy 199.07256 -299.36076) (xy 199.065641 -299.410918)
			(xy 199.051924 -299.459658) (xy 199.031669 -299.506062) (xy 199.005255 -299.549259) (xy 198.97318 -299.588437)
			(xy 198.954898 -299.605954) (xy 198.946008 -299.614336) (xy 198.937626 -299.635926) (xy 198.947024 -299.740066)
			(xy 198.959216 -299.759878) (xy 198.969376 -299.766482) (xy 198.995518 -299.783518) (xy 199.043652 -299.823227)
			(xy 199.08642 -299.868665) (xy 199.123146 -299.919112) (xy 199.153249 -299.97377) (xy 199.176253 -300.031775)
			(xy 199.191793 -300.092209) (xy 199.199624 -300.154115) (xy 199.199622 -300.216515) (xy 199.191787 -300.278421)
			(xy 199.176243 -300.338853) (xy 199.153236 -300.396857) (xy 199.12313 -300.451513) (xy 199.086401 -300.501958)
			(xy 199.04363 -300.547393) (xy 198.995494 -300.5871) (xy 198.969376 -300.604174) (xy 198.959216 -300.610778)
			(xy 198.947024 -300.63059) (xy 198.937626 -300.73473) (xy 198.946008 -300.75632) (xy 198.954898 -300.764702)
			(xy 198.973183 -300.782218) (xy 199.005263 -300.821394) (xy 199.031682 -300.864591) (xy 199.051943 -300.910995)
			(xy 199.065665 -300.959735) (xy 199.07259 -301.009895) (xy 199.073008 -301.035212) (xy 199.072582 -301.06056)
			(xy 199.065648 -301.110779) (xy 199.051899 -301.159575) (xy 199.031595 -301.206027) (xy 199.005118 -301.249259)
			(xy 198.972967 -301.288456) (xy 198.954644 -301.305976) (xy 198.945754 -301.314104) (xy 198.937372 -301.335948)
			(xy 198.947024 -301.440088) (xy 198.959216 -301.4599) (xy 198.969376 -301.46625) (xy 198.995466 -301.483381)
			(xy 199.043589 -301.523128) (xy 199.086347 -301.568597) (xy 199.123063 -301.619069) (xy 199.153159 -301.673749)
			(xy 199.176159 -301.731772) (xy 199.191699 -301.792221) (xy 199.199534 -301.854143) (xy 199.200008 -301.88535)
			(xy 199.199519 -301.916513) (xy 199.191707 -301.978347) (xy 199.176207 -302.038715) (xy 199.153264 -302.096663)
			(xy 199.123238 -302.15128) (xy 199.086604 -302.201702) (xy 199.043939 -302.247136) (xy 198.995917 -302.286864)
			(xy 198.943293 -302.320259) (xy 198.886899 -302.346796) (xy 198.827624 -302.366056) (xy 198.766403 -302.377735)
			(xy 198.7042 -302.381648) (xy 198.641997 -302.377735) (xy 198.580776 -302.366056) (xy 198.521501 -302.346796)
			(xy 198.465107 -302.320259) (xy 198.412483 -302.286864) (xy 198.364461 -302.247136) (xy 198.321796 -302.201702)
			(xy 198.285162 -302.15128) (xy 198.255136 -302.096663) (xy 198.232193 -302.038715) (xy 198.216693 -301.978347)
			(xy 198.208881 -301.916513) (xy 198.208392 -301.88535) (xy 194.97294 -301.88535) (xy 194.972517 -301.910668)
			(xy 194.965596 -301.960827) (xy 194.951876 -302.009568) (xy 194.931616 -302.055973) (xy 194.905196 -302.099169)
			(xy 194.873115 -302.138344) (xy 194.85483 -302.15586) (xy 194.84594 -302.164242) (xy 194.837558 -302.185832)
			(xy 194.846956 -302.289972) (xy 194.859148 -302.309784) (xy 194.869308 -302.316388) (xy 194.89541 -302.333477)
			(xy 194.943526 -302.373192) (xy 194.98628 -302.41863) (xy 195.022994 -302.469074) (xy 195.053088 -302.523725)
			(xy 195.076088 -302.581721) (xy 195.091628 -302.642144) (xy 195.099465 -302.704039) (xy 195.09994 -302.735234)
			(xy 196.950599 -302.735234) (xy 196.954534 -302.681463) (xy 196.966257 -302.628839) (xy 196.985517 -302.578482)
			(xy 197.011903 -302.531465) (xy 197.044855 -302.488792) (xy 197.083668 -302.451371) (xy 197.127516 -302.420001)
			(xy 197.175464 -302.395349) (xy 197.226491 -302.377941) (xy 197.279509 -302.368148) (xy 197.333388 -302.366179)
			(xy 197.386979 -302.372076) (xy 197.43914 -302.385712) (xy 197.48876 -302.406799) (xy 197.534781 -302.434885)
			(xy 197.576223 -302.469373) (xy 197.612201 -302.509527) (xy 197.641949 -302.554491) (xy 197.664834 -302.603308)
			(xy 197.680366 -302.654937) (xy 197.688216 -302.708277) (xy 197.688708 -302.735234) (xy 201.652124 -302.735234)
			(xy 201.652576 -302.704036) (xy 201.660395 -302.642133) (xy 201.675925 -302.581701) (xy 201.69892 -302.523698)
			(xy 201.729018 -302.469041) (xy 201.76574 -302.418597) (xy 201.808506 -302.373163) (xy 201.85664 -302.33346)
			(xy 201.882756 -302.316388) (xy 201.892916 -302.309784) (xy 201.905108 -302.289972) (xy 201.914506 -302.185832)
			(xy 201.906124 -302.164242) (xy 201.897234 -302.15586) (xy 201.878966 -302.138327) (xy 201.846887 -302.099153)
			(xy 201.820468 -302.05596) (xy 201.800204 -302.009559) (xy 201.786478 -301.960822) (xy 201.779546 -301.910666)
			(xy 201.779124 -301.88535) (xy 201.779515 -301.860001) (xy 201.786454 -301.809779) (xy 201.800209 -301.760983)
			(xy 201.82052 -301.714531) (xy 201.847004 -301.6713) (xy 201.879162 -301.632105) (xy 201.897488 -301.614586)
			(xy 201.906378 -301.606458) (xy 201.91476 -301.584614) (xy 201.905108 -301.480474) (xy 201.892916 -301.460662)
			(xy 201.882756 -301.454312) (xy 201.856633 -301.43723) (xy 201.808513 -301.397474) (xy 201.765759 -301.351997)
			(xy 201.729046 -301.301516) (xy 201.698955 -301.24683) (xy 201.67596 -301.188801) (xy 201.660425 -301.128347)
			(xy 201.652595 -301.066421) (xy 201.652124 -301.035212) (xy 201.652559 -301.004014) (xy 201.66038 -300.942109)
			(xy 201.675913 -300.881677) (xy 201.698911 -300.823674) (xy 201.729011 -300.769018) (xy 201.765735 -300.718574)
			(xy 201.808504 -300.673141) (xy 201.856639 -300.633437) (xy 201.882756 -300.616366) (xy 201.892916 -300.609762)
			(xy 201.905108 -300.58995) (xy 201.914506 -300.48581) (xy 201.906124 -300.46422) (xy 201.897234 -300.455838)
			(xy 201.877335 -300.436674) (xy 201.842867 -300.393505) (xy 201.815223 -300.345677) (xy 201.795023 -300.29426)
			(xy 201.782718 -300.240406) (xy 201.778584 -300.185319) (xy 201.782713 -300.130232) (xy 201.795012 -300.076376)
			(xy 201.815207 -300.024958) (xy 201.842845 -299.977127) (xy 201.877309 -299.933954) (xy 201.897234 -299.914818)
			(xy 201.906124 -299.906436) (xy 201.914506 -299.884846) (xy 201.905108 -299.780706) (xy 201.892916 -299.760894)
			(xy 201.882756 -299.75429) (xy 201.856659 -299.737193) (xy 201.808539 -299.697482) (xy 201.765784 -299.652046)
			(xy 201.729068 -299.601604) (xy 201.698972 -299.546953) (xy 201.675973 -299.488958) (xy 201.660433 -299.428534)
			(xy 201.652598 -299.366639) (xy 201.652124 -299.335444) (xy 201.652569 -299.304234) (xy 201.660396 -299.242306)
			(xy 201.67593 -299.181849) (xy 201.698928 -299.123819) (xy 201.729025 -299.069133) (xy 201.765745 -299.018656)
			(xy 201.808509 -298.973185) (xy 201.856639 -298.933439) (xy 201.882756 -298.916344) (xy 201.892916 -298.909994)
			(xy 201.905108 -298.890182) (xy 201.91476 -298.786042) (xy 201.906378 -298.764198) (xy 201.897488 -298.75607)
			(xy 201.879152 -298.738564) (xy 201.847011 -298.699359) (xy 201.82054 -298.656122) (xy 201.800237 -298.609669)
			(xy 201.786486 -298.560873) (xy 201.779545 -298.510654) (xy 201.779124 -298.485306) (xy 201.779528 -298.459988)
			(xy 201.786455 -298.409828) (xy 201.800179 -298.361087) (xy 201.820443 -298.314683) (xy 201.846865 -298.271487)
			(xy 201.878948 -298.232312) (xy 201.897234 -298.214796) (xy 201.906124 -298.206414) (xy 201.914506 -298.184824)
			(xy 201.905108 -298.080684) (xy 201.892916 -298.060872) (xy 201.882756 -298.054268) (xy 201.856649 -298.037186)
			(xy 201.808529 -297.997473) (xy 201.765774 -297.952035) (xy 201.729059 -297.90159) (xy 201.698965 -297.846937)
			(xy 201.675967 -297.78894) (xy 201.660429 -297.728515) (xy 201.652596 -297.666617) (xy 201.652124 -297.635422)
			(xy 201.652613 -297.604259) (xy 201.660425 -297.542425) (xy 201.675925 -297.482057) (xy 201.698868 -297.424109)
			(xy 201.728894 -297.369492) (xy 201.765528 -297.31907) (xy 201.808193 -297.273636) (xy 201.856215 -297.233908)
			(xy 201.908839 -297.200513) (xy 201.965233 -297.173976) (xy 202.024508 -297.154716) (xy 202.085729 -297.143037)
			(xy 202.147932 -297.139124) (xy 202.210135 -297.143037) (xy 202.271356 -297.154716) (xy 202.330631 -297.173976)
			(xy 202.387025 -297.200513) (xy 202.439649 -297.233908) (xy 202.487671 -297.273636) (xy 202.530336 -297.31907)
			(xy 202.56697 -297.369492) (xy 202.596996 -297.424109) (xy 202.619939 -297.482057) (xy 202.635439 -297.542425)
			(xy 202.643251 -297.604259) (xy 202.64374 -297.635422) (xy 202.643302 -297.66662) (xy 202.635478 -297.728523)
			(xy 202.619943 -297.788954) (xy 202.596945 -297.846956) (xy 202.566845 -297.901612) (xy 202.530122 -297.952056)
			(xy 202.487356 -297.99749) (xy 202.439224 -298.037195) (xy 202.413108 -298.054268) (xy 202.402948 -298.060872)
			(xy 202.390756 -298.080684) (xy 202.381358 -298.184824) (xy 202.38974 -298.206414) (xy 202.39863 -298.214796)
			(xy 202.416918 -298.232309) (xy 202.448997 -298.271486) (xy 202.475414 -298.314684) (xy 202.495674 -298.361089)
			(xy 202.509396 -298.409829) (xy 202.516322 -298.459988) (xy 202.51674 -298.485306) (xy 202.5163 -298.510653)
			(xy 202.509367 -298.560872) (xy 202.495621 -298.609667) (xy 202.475319 -298.656118) (xy 202.448845 -298.699351)
			(xy 202.416697 -298.738549) (xy 202.398376 -298.75607) (xy 202.389486 -298.764198) (xy 202.381104 -298.786042)
			(xy 202.390756 -298.890182) (xy 202.402948 -298.909994) (xy 202.413108 -298.916344) (xy 202.439203 -298.933468)
			(xy 202.487324 -298.973217) (xy 202.530081 -299.018687) (xy 202.566796 -299.069161) (xy 202.596891 -299.123842)
			(xy 202.61989 -299.181865) (xy 202.63543 -299.242315) (xy 202.643266 -299.304236) (xy 202.64374 -299.335444)
			(xy 202.643241 -299.36664) (xy 202.635426 -299.428541) (xy 202.619901 -299.48897) (xy 202.596911 -299.546972)
			(xy 202.566821 -299.601628) (xy 202.530105 -299.652073) (xy 202.487346 -299.697508) (xy 202.439221 -299.737216)
			(xy 202.413108 -299.75429) (xy 202.402948 -299.760894) (xy 202.390756 -299.780706) (xy 202.381358 -299.884846)
			(xy 202.38974 -299.906436) (xy 202.39863 -299.914818) (xy 202.418582 -299.933927) (xy 202.453044 -299.977107)
			(xy 202.48068 -300.024944) (xy 202.500874 -300.076367) (xy 202.513172 -300.130227) (xy 202.517301 -300.185319)
			(xy 202.513167 -300.24041) (xy 202.500863 -300.294269) (xy 202.480664 -300.34569) (xy 202.453022 -300.393524)
			(xy 202.418556 -300.436701) (xy 202.39863 -300.455838) (xy 202.38974 -300.46422) (xy 202.381358 -300.48581)
			(xy 202.390756 -300.58995) (xy 202.402948 -300.609762) (xy 202.413108 -300.616366) (xy 202.4392 -300.63347)
			(xy 202.487316 -300.673183) (xy 202.53007 -300.718619) (xy 202.566785 -300.76906) (xy 202.596881 -300.823709)
			(xy 202.619882 -300.881703) (xy 202.635425 -300.942124) (xy 202.643264 -301.004018) (xy 202.64374 -301.035212)
			(xy 202.643231 -301.06642) (xy 202.635411 -301.128344) (xy 202.619884 -301.188798) (xy 202.596894 -301.246827)
			(xy 202.566807 -301.301512) (xy 202.530096 -301.35199) (xy 202.487341 -301.397464) (xy 202.43922 -301.437214)
			(xy 202.413108 -301.454312) (xy 202.402948 -301.460662) (xy 202.390756 -301.480474) (xy 202.381104 -301.584614)
			(xy 202.389486 -301.606458) (xy 202.398376 -301.614586) (xy 202.416684 -301.63212) (xy 202.448829 -301.671319)
			(xy 202.475305 -301.714549) (xy 202.495612 -301.760997) (xy 202.509369 -301.809788) (xy 202.516316 -301.860003)
			(xy 202.51674 -301.88535) (xy 205.752192 -301.88535) (xy 205.752657 -301.85414) (xy 205.760482 -301.792214)
			(xy 205.776015 -301.731758) (xy 205.79901 -301.673729) (xy 205.829104 -301.619043) (xy 205.865821 -301.568566)
			(xy 205.908582 -301.523094) (xy 205.956709 -301.483346) (xy 205.982824 -301.46625) (xy 205.992984 -301.4599)
			(xy 206.005176 -301.440088) (xy 206.014828 -301.335948) (xy 206.006446 -301.314104) (xy 205.997556 -301.305976)
			(xy 205.979235 -301.288454) (xy 205.94709 -301.249253) (xy 205.920616 -301.206021) (xy 205.90031 -301.15957)
			(xy 205.886556 -301.110777) (xy 205.879613 -301.060559) (xy 205.879192 -301.035212) (xy 205.879611 -301.009895)
			(xy 205.886536 -300.959736) (xy 205.900258 -300.910996) (xy 205.920519 -300.864591) (xy 205.946938 -300.821395)
			(xy 205.979018 -300.782219) (xy 205.997302 -300.764702) (xy 206.006192 -300.75632) (xy 206.014574 -300.73473)
			(xy 206.005176 -300.63059) (xy 205.992984 -300.610778) (xy 205.982824 -300.604174) (xy 205.956734 -300.587062)
			(xy 205.908603 -300.547359) (xy 205.865836 -300.501928) (xy 205.82911 -300.451488) (xy 205.799006 -300.396836)
			(xy 205.776002 -300.338839) (xy 205.760459 -300.278412) (xy 205.752625 -300.216512) (xy 205.752623 -300.154118)
			(xy 205.760453 -300.092218) (xy 205.775992 -300.03179) (xy 205.798994 -299.973791) (xy 205.829094 -299.919138)
			(xy 205.865817 -299.868695) (xy 205.908581 -299.823262) (xy 205.95671 -299.783556) (xy 205.982824 -299.766482)
			(xy 205.992984 -299.759878) (xy 206.005176 -299.740066) (xy 206.014574 -299.635926) (xy 206.006192 -299.614336)
			(xy 205.997302 -299.605954) (xy 205.979044 -299.588411) (xy 205.946962 -299.549241) (xy 205.920539 -299.50605)
			(xy 205.900274 -299.45965) (xy 205.886546 -299.410915) (xy 205.879613 -299.36076) (xy 205.879192 -299.335444)
			(xy 205.879589 -299.310095) (xy 205.886528 -299.259874) (xy 205.900283 -299.211078) (xy 205.920593 -299.164626)
			(xy 205.947075 -299.121395) (xy 205.979231 -299.0822) (xy 205.997556 -299.06468) (xy 206.006446 -299.056552)
			(xy 206.014828 -299.034708) (xy 206.005176 -298.930568) (xy 205.992984 -298.910756) (xy 205.982824 -298.904406)
			(xy 205.956714 -298.887304) (xy 205.908591 -298.847554) (xy 205.865834 -298.80208) (xy 205.829119 -298.751603)
			(xy 205.799026 -298.696919) (xy 205.77603 -298.638892) (xy 205.760494 -298.578439) (xy 205.752663 -298.516515)
			(xy 205.752192 -298.485306) (xy 205.752637 -298.454108) (xy 205.760458 -298.392205) (xy 205.775991 -298.331774)
			(xy 205.798988 -298.273771) (xy 205.829086 -298.219115) (xy 205.865809 -298.168671) (xy 205.908575 -298.123237)
			(xy 205.956708 -298.083532) (xy 205.982824 -298.06646) (xy 205.992984 -298.059856) (xy 206.005176 -298.040044)
			(xy 206.014574 -297.935904) (xy 206.006192 -297.914314) (xy 205.997302 -297.905932) (xy 205.979033 -297.8884)
			(xy 205.946952 -297.849227) (xy 205.920531 -297.806034) (xy 205.900267 -297.759632) (xy 205.886541 -297.710895)
			(xy 205.879612 -297.660739) (xy 205.879192 -297.635422) (xy 205.879641 -297.610075) (xy 205.88657 -297.559857)
			(xy 205.900314 -297.511061) (xy 205.920614 -297.464609) (xy 205.947088 -297.421377) (xy 205.979235 -297.382179)
			(xy 205.997556 -297.364658) (xy 206.006446 -297.35653) (xy 206.014828 -297.334686) (xy 206.005176 -297.230546)
			(xy 205.992984 -297.210734) (xy 205.982824 -297.204384) (xy 205.956704 -297.187297) (xy 205.908581 -297.147544)
			(xy 205.865825 -297.102069) (xy 205.82911 -297.051589) (xy 205.799018 -296.996903) (xy 205.776024 -296.938874)
			(xy 205.76049 -296.878419) (xy 205.752662 -296.816493) (xy 205.752192 -296.785284) (xy 205.752681 -296.754121)
			(xy 205.760493 -296.692287) (xy 205.775993 -296.631919) (xy 205.798936 -296.573971) (xy 205.828962 -296.519354)
			(xy 205.865596 -296.468932) (xy 205.908261 -296.423498) (xy 205.956283 -296.38377) (xy 206.008907 -296.350375)
			(xy 206.065301 -296.323838) (xy 206.124576 -296.304578) (xy 206.185797 -296.292899) (xy 206.248 -296.288986)
			(xy 206.310203 -296.292899) (xy 206.371424 -296.304578) (xy 206.430699 -296.323838) (xy 206.487093 -296.350375)
			(xy 206.539717 -296.38377) (xy 206.587739 -296.423498) (xy 206.630404 -296.468932) (xy 206.667038 -296.519354)
			(xy 206.697064 -296.573971) (xy 206.720007 -296.631919) (xy 206.735507 -296.692287) (xy 206.743319 -296.754121)
			(xy 206.743808 -296.785284) (xy 206.74337 -296.816494) (xy 206.73554 -296.878422) (xy 206.720004 -296.938879)
			(xy 206.697004 -296.996908) (xy 206.666907 -297.051593) (xy 206.630186 -297.10207) (xy 206.587423 -297.147542)
			(xy 206.539292 -297.187289) (xy 206.513176 -297.204384) (xy 206.503016 -297.210734) (xy 206.490824 -297.230546)
			(xy 206.481172 -297.334686) (xy 206.489554 -297.35653) (xy 206.498444 -297.364658) (xy 206.516781 -297.382164)
			(xy 206.548925 -297.421368) (xy 206.575397 -297.464604) (xy 206.5957 -297.511058) (xy 206.60945 -297.559854)
			(xy 206.616389 -297.610074) (xy 206.616808 -297.635422) (xy 206.616345 -297.660738) (xy 206.609429 -297.710895)
			(xy 206.595715 -297.759634) (xy 206.575462 -297.806039) (xy 206.549051 -297.849236) (xy 206.516979 -297.888414)
			(xy 206.498698 -297.905932) (xy 206.489808 -297.914314) (xy 206.481426 -297.935904) (xy 206.490824 -298.040044)
			(xy 206.503016 -298.059856) (xy 206.513176 -298.06646) (xy 206.539303 -298.083512) (xy 206.587421 -298.123231)
			(xy 206.630174 -298.168674) (xy 206.666887 -298.219123) (xy 206.696979 -298.27378) (xy 206.719974 -298.331781)
			(xy 206.735508 -298.392209) (xy 206.743337 -298.454109) (xy 206.743808 -298.485306) (xy 206.743309 -298.516515)
			(xy 206.735489 -298.57844) (xy 206.719962 -298.638895) (xy 206.696971 -298.696923) (xy 206.666882 -298.751609)
			(xy 206.630169 -298.802087) (xy 206.587413 -298.84756) (xy 206.539289 -298.887309) (xy 206.513176 -298.904406)
			(xy 206.503016 -298.910756) (xy 206.490824 -298.930568) (xy 206.481172 -299.034708) (xy 206.489554 -299.056552)
			(xy 206.498444 -299.06468) (xy 206.516743 -299.082223) (xy 206.54889 -299.121419) (xy 206.575368 -299.164647)
			(xy 206.595677 -299.211094) (xy 206.609435 -299.259884) (xy 206.616384 -299.310098) (xy 206.616808 -299.335444)
			(xy 206.61636 -299.36076) (xy 206.609441 -299.410918) (xy 206.595724 -299.459658) (xy 206.575469 -299.506062)
			(xy 206.549055 -299.549259) (xy 206.51698 -299.588437) (xy 206.498698 -299.605954) (xy 206.489808 -299.614336)
			(xy 206.481426 -299.635926) (xy 206.490824 -299.740066) (xy 206.503016 -299.759878) (xy 206.513176 -299.766482)
			(xy 206.539318 -299.783518) (xy 206.587452 -299.823227) (xy 206.63022 -299.868665) (xy 206.666946 -299.919112)
			(xy 206.697049 -299.97377) (xy 206.720053 -300.031775) (xy 206.735593 -300.092209) (xy 206.743424 -300.154115)
			(xy 206.743422 -300.216515) (xy 206.735587 -300.278421) (xy 206.720043 -300.338853) (xy 206.697036 -300.396857)
			(xy 206.66693 -300.451513) (xy 206.630201 -300.501958) (xy 206.58743 -300.547393) (xy 206.539294 -300.5871)
			(xy 206.513176 -300.604174) (xy 206.503016 -300.610778) (xy 206.490824 -300.63059) (xy 206.481426 -300.73473)
			(xy 206.489808 -300.75632) (xy 206.498698 -300.764702) (xy 206.516983 -300.782218) (xy 206.549063 -300.821394)
			(xy 206.575482 -300.864591) (xy 206.595743 -300.910995) (xy 206.609465 -300.959735) (xy 206.61639 -301.009895)
			(xy 206.616808 -301.035212) (xy 206.616382 -301.06056) (xy 206.609448 -301.110779) (xy 206.595699 -301.159575)
			(xy 206.575395 -301.206027) (xy 206.548918 -301.249259) (xy 206.516767 -301.288456) (xy 206.498444 -301.305976)
			(xy 206.489554 -301.314104) (xy 206.481172 -301.335948) (xy 206.490824 -301.440088) (xy 206.503016 -301.4599)
			(xy 206.513176 -301.46625) (xy 206.539266 -301.483381) (xy 206.587389 -301.523128) (xy 206.630147 -301.568597)
			(xy 206.666863 -301.619069) (xy 206.696959 -301.673749) (xy 206.719959 -301.731772) (xy 206.735499 -301.792221)
			(xy 206.743334 -301.854143) (xy 206.743808 -301.88535) (xy 206.743319 -301.916513) (xy 206.735507 -301.978347)
			(xy 206.720007 -302.038715) (xy 206.697064 -302.096663) (xy 206.667038 -302.15128) (xy 206.630404 -302.201702)
			(xy 206.587739 -302.247136) (xy 206.539717 -302.286864) (xy 206.487093 -302.320259) (xy 206.430699 -302.346796)
			(xy 206.371424 -302.366056) (xy 206.310203 -302.377735) (xy 206.248 -302.381648) (xy 206.185797 -302.377735)
			(xy 206.124576 -302.366056) (xy 206.065301 -302.346796) (xy 206.008907 -302.320259) (xy 205.956283 -302.286864)
			(xy 205.908261 -302.247136) (xy 205.865596 -302.201702) (xy 205.828962 -302.15128) (xy 205.798936 -302.096663)
			(xy 205.775993 -302.038715) (xy 205.760493 -301.978347) (xy 205.752681 -301.916513) (xy 205.752192 -301.88535)
			(xy 202.51674 -301.88535) (xy 202.516317 -301.910668) (xy 202.509396 -301.960827) (xy 202.495676 -302.009568)
			(xy 202.475416 -302.055973) (xy 202.448996 -302.099169) (xy 202.416915 -302.138344) (xy 202.39863 -302.15586)
			(xy 202.38974 -302.164242) (xy 202.381358 -302.185832) (xy 202.390756 -302.289972) (xy 202.402948 -302.309784)
			(xy 202.413108 -302.316388) (xy 202.43921 -302.333477) (xy 202.487326 -302.373192) (xy 202.53008 -302.41863)
			(xy 202.566794 -302.469074) (xy 202.596888 -302.523725) (xy 202.619888 -302.581721) (xy 202.635428 -302.642144)
			(xy 202.643265 -302.704039) (xy 202.64374 -302.735234) (xy 204.494399 -302.735234) (xy 204.498334 -302.681463)
			(xy 204.510057 -302.628839) (xy 204.529317 -302.578482) (xy 204.555703 -302.531465) (xy 204.588655 -302.488792)
			(xy 204.627468 -302.451371) (xy 204.671316 -302.420001) (xy 204.719264 -302.395349) (xy 204.770291 -302.377941)
			(xy 204.823309 -302.368148) (xy 204.877188 -302.366179) (xy 204.930779 -302.372076) (xy 204.98294 -302.385712)
			(xy 205.03256 -302.406799) (xy 205.078581 -302.434885) (xy 205.120023 -302.469373) (xy 205.156001 -302.509527)
			(xy 205.185749 -302.554491) (xy 205.208634 -302.603308) (xy 205.224166 -302.654937) (xy 205.232016 -302.708277)
			(xy 205.232508 -302.735234) (xy 205.232016 -302.762191) (xy 205.224166 -302.815531) (xy 205.208634 -302.86716)
			(xy 205.185749 -302.915977) (xy 205.156001 -302.960941) (xy 205.120023 -303.001095) (xy 205.078581 -303.035583)
			(xy 205.03256 -303.063669) (xy 204.98294 -303.084756) (xy 204.930779 -303.098392) (xy 204.877188 -303.104289)
			(xy 204.823309 -303.10232) (xy 204.770291 -303.092527) (xy 204.719264 -303.075119) (xy 204.671316 -303.050467)
			(xy 204.627468 -303.019097) (xy 204.588655 -302.981676) (xy 204.555703 -302.939003) (xy 204.529317 -302.891986)
			(xy 204.510057 -302.841629) (xy 204.498334 -302.789005) (xy 204.494399 -302.735234) (xy 202.64374 -302.735234)
			(xy 202.643251 -302.766397) (xy 202.635439 -302.828231) (xy 202.619939 -302.888599) (xy 202.596996 -302.946547)
			(xy 202.56697 -303.001164) (xy 202.530336 -303.051586) (xy 202.487671 -303.09702) (xy 202.439649 -303.136748)
			(xy 202.387025 -303.170143) (xy 202.330631 -303.19668) (xy 202.271356 -303.21594) (xy 202.210135 -303.227619)
			(xy 202.147932 -303.231532) (xy 202.085729 -303.227619) (xy 202.024508 -303.21594) (xy 201.965233 -303.19668)
			(xy 201.908839 -303.170143) (xy 201.856215 -303.136748) (xy 201.808193 -303.09702) (xy 201.765528 -303.051586)
			(xy 201.728894 -303.001164) (xy 201.698868 -302.946547) (xy 201.675925 -302.888599) (xy 201.660425 -302.828231)
			(xy 201.652613 -302.766397) (xy 201.652124 -302.735234) (xy 197.688708 -302.735234) (xy 197.688216 -302.762191)
			(xy 197.680366 -302.815531) (xy 197.664834 -302.86716) (xy 197.641949 -302.915977) (xy 197.612201 -302.960941)
			(xy 197.576223 -303.001095) (xy 197.534781 -303.035583) (xy 197.48876 -303.063669) (xy 197.43914 -303.084756)
			(xy 197.386979 -303.098392) (xy 197.333388 -303.104289) (xy 197.279509 -303.10232) (xy 197.226491 -303.092527)
			(xy 197.175464 -303.075119) (xy 197.127516 -303.050467) (xy 197.083668 -303.019097) (xy 197.044855 -302.981676)
			(xy 197.011903 -302.939003) (xy 196.985517 -302.891986) (xy 196.966257 -302.841629) (xy 196.954534 -302.789005)
			(xy 196.950599 -302.735234) (xy 195.09994 -302.735234) (xy 195.099451 -302.766397) (xy 195.091639 -302.828231)
			(xy 195.076139 -302.888599) (xy 195.053196 -302.946547) (xy 195.02317 -303.001164) (xy 194.986536 -303.051586)
			(xy 194.943871 -303.09702) (xy 194.895849 -303.136748) (xy 194.843225 -303.170143) (xy 194.786831 -303.19668)
			(xy 194.727556 -303.21594) (xy 194.666335 -303.227619) (xy 194.604132 -303.231532) (xy 194.541929 -303.227619)
			(xy 194.480708 -303.21594) (xy 194.421433 -303.19668) (xy 194.365039 -303.170143) (xy 194.312415 -303.136748)
			(xy 194.264393 -303.09702) (xy 194.221728 -303.051586) (xy 194.185094 -303.001164) (xy 194.155068 -302.946547)
			(xy 194.132125 -302.888599) (xy 194.116625 -302.828231) (xy 194.108813 -302.766397) (xy 194.108324 -302.735234)
			(xy 190.144654 -302.735234) (xy 190.144162 -302.762191) (xy 190.136312 -302.815531) (xy 190.12078 -302.86716)
			(xy 190.097895 -302.915977) (xy 190.068147 -302.960941) (xy 190.032169 -303.001095) (xy 189.990727 -303.035583)
			(xy 189.944706 -303.063669) (xy 189.895086 -303.084756) (xy 189.842925 -303.098392) (xy 189.789334 -303.104289)
			(xy 189.735455 -303.10232) (xy 189.682437 -303.092527) (xy 189.63141 -303.075119) (xy 189.583462 -303.050467)
			(xy 189.539614 -303.019097) (xy 189.500801 -302.981676) (xy 189.467849 -302.939003) (xy 189.441463 -302.891986)
			(xy 189.422203 -302.841629) (xy 189.41048 -302.789005) (xy 189.406545 -302.735234) (xy 187.555886 -302.735234)
			(xy 187.555397 -302.766397) (xy 187.547585 -302.828231) (xy 187.532085 -302.888599) (xy 187.509142 -302.946547)
			(xy 187.479116 -303.001164) (xy 187.442482 -303.051586) (xy 187.399817 -303.09702) (xy 187.351795 -303.136748)
			(xy 187.299171 -303.170143) (xy 187.242777 -303.19668) (xy 187.183502 -303.21594) (xy 187.122281 -303.227619)
			(xy 187.060078 -303.231532) (xy 186.997875 -303.227619) (xy 186.936654 -303.21594) (xy 186.877379 -303.19668)
			(xy 186.820985 -303.170143) (xy 186.768361 -303.136748) (xy 186.720339 -303.09702) (xy 186.677674 -303.051586)
			(xy 186.64104 -303.001164) (xy 186.611014 -302.946547) (xy 186.588071 -302.888599) (xy 186.572571 -302.828231)
			(xy 186.564759 -302.766397) (xy 186.56427 -302.735234) (xy 185.96864 -302.735234) (xy 185.96864 -303.585372)
			(xy 188.075077 -303.585372) (xy 188.079012 -303.531601) (xy 188.090735 -303.478977) (xy 188.109995 -303.42862)
			(xy 188.136381 -303.381603) (xy 188.169333 -303.33893) (xy 188.208146 -303.301509) (xy 188.251994 -303.270139)
			(xy 188.299942 -303.245487) (xy 188.350969 -303.228079) (xy 188.403987 -303.218286) (xy 188.457866 -303.216317)
			(xy 188.511457 -303.222214) (xy 188.563618 -303.23585) (xy 188.613238 -303.256937) (xy 188.659259 -303.285023)
			(xy 188.700701 -303.319511) (xy 188.736679 -303.359665) (xy 188.766427 -303.404629) (xy 188.789312 -303.453446)
			(xy 188.804844 -303.505075) (xy 188.812694 -303.558415) (xy 188.813186 -303.585372) (xy 188.812694 -303.612329)
			(xy 188.804844 -303.665669) (xy 188.789312 -303.717298) (xy 188.766427 -303.766115) (xy 188.736679 -303.811079)
			(xy 188.700701 -303.851233) (xy 188.659259 -303.885721) (xy 188.613238 -303.913807) (xy 188.563618 -303.934894)
			(xy 188.511457 -303.94853) (xy 188.457866 -303.954427) (xy 188.403987 -303.952458) (xy 188.350969 -303.942665)
			(xy 188.299942 -303.925257) (xy 188.251994 -303.900605) (xy 188.208146 -303.869235) (xy 188.169333 -303.831814)
			(xy 188.136381 -303.789141) (xy 188.109995 -303.742124) (xy 188.090735 -303.691767) (xy 188.079012 -303.639143)
			(xy 188.075077 -303.585372) (xy 185.96864 -303.585372) (xy 185.96864 -305.285394) (xy 186.56427 -305.285394)
			(xy 186.56483 -305.252675) (xy 186.573422 -305.187804) (xy 186.590471 -305.124626) (xy 186.61568 -305.064239)
			(xy 186.64861 -305.007691) (xy 186.688691 -304.955964) (xy 186.71159 -304.932588) (xy 186.718956 -304.925476)
			(xy 186.72683 -304.90668) (xy 186.72683 -304.81397) (xy 186.718956 -304.795174) (xy 186.71159 -304.788062)
			(xy 186.688714 -304.764663) (xy 186.648628 -304.712941) (xy 186.61569 -304.656398) (xy 186.59047 -304.596016)
			(xy 186.573407 -304.532843) (xy 186.564798 -304.467975) (xy 186.56427 -304.435256) (xy 186.564759 -304.404093)
			(xy 186.572571 -304.342259) (xy 186.588071 -304.281891) (xy 186.611014 -304.223943) (xy 186.64104 -304.169326)
			(xy 186.677674 -304.118904) (xy 186.720339 -304.07347) (xy 186.768361 -304.033742) (xy 186.820985 -304.000347)
			(xy 186.877379 -303.97381) (xy 186.936654 -303.95455) (xy 186.997875 -303.942871) (xy 187.060078 -303.938958)
			(xy 187.122281 -303.942871) (xy 187.183502 -303.95455) (xy 187.242777 -303.97381) (xy 187.299171 -304.000347)
			(xy 187.351795 -304.033742) (xy 187.399817 -304.07347) (xy 187.442482 -304.118904) (xy 187.479116 -304.169326)
			(xy 187.509142 -304.223943) (xy 187.532085 -304.281891) (xy 187.547585 -304.342259) (xy 187.555397 -304.404093)
			(xy 187.555886 -304.435256) (xy 190.664338 -304.435256) (xy 190.66488 -304.402556) (xy 190.673487 -304.337725)
			(xy 190.690545 -304.274589) (xy 190.715758 -304.214245) (xy 190.748689 -304.157741) (xy 190.788764 -304.106058)
			(xy 190.811658 -304.082704) (xy 190.819024 -304.075338) (xy 190.826644 -304.056796) (xy 190.826644 -303.963832)
			(xy 190.819024 -303.94529) (xy 190.811658 -303.937924) (xy 190.788755 -303.914577) (xy 190.748671 -303.862898)
			(xy 190.715734 -303.806393) (xy 190.690519 -303.746047) (xy 190.673462 -303.682908) (xy 190.664861 -303.618073)
			(xy 190.664338 -303.585372) (xy 190.664827 -303.554209) (xy 190.672639 -303.492375) (xy 190.688139 -303.432007)
			(xy 190.711082 -303.374059) (xy 190.741108 -303.319442) (xy 190.777742 -303.26902) (xy 190.820407 -303.223586)
			(xy 190.868429 -303.183858) (xy 190.921053 -303.150463) (xy 190.977447 -303.123926) (xy 191.036722 -303.104666)
			(xy 191.097943 -303.092987) (xy 191.160146 -303.089074) (xy 191.222349 -303.092987) (xy 191.28357 -303.104666)
			(xy 191.342845 -303.123926) (xy 191.399239 -303.150463) (xy 191.451863 -303.183858) (xy 191.499885 -303.223586)
			(xy 191.54255 -303.26902) (xy 191.579184 -303.319442) (xy 191.60921 -303.374059) (xy 191.632153 -303.432007)
			(xy 191.647653 -303.492375) (xy 191.655465 -303.554209) (xy 191.655954 -303.585372) (xy 195.619131 -303.585372)
			(xy 195.623066 -303.531601) (xy 195.634789 -303.478977) (xy 195.654049 -303.42862) (xy 195.680435 -303.381603)
			(xy 195.713387 -303.33893) (xy 195.7522 -303.301509) (xy 195.796048 -303.270139) (xy 195.843996 -303.245487)
			(xy 195.895023 -303.228079) (xy 195.948041 -303.218286) (xy 196.00192 -303.216317) (xy 196.055511 -303.222214)
			(xy 196.107672 -303.23585) (xy 196.157292 -303.256937) (xy 196.203313 -303.285023) (xy 196.244755 -303.319511)
			(xy 196.280733 -303.359665) (xy 196.310481 -303.404629) (xy 196.333366 -303.453446) (xy 196.348898 -303.505075)
			(xy 196.356748 -303.558415) (xy 196.35724 -303.585372) (xy 196.356748 -303.612329) (xy 196.348898 -303.665669)
			(xy 196.333366 -303.717298) (xy 196.310481 -303.766115) (xy 196.280733 -303.811079) (xy 196.244755 -303.851233)
			(xy 196.203313 -303.885721) (xy 196.157292 -303.913807) (xy 196.107672 -303.934894) (xy 196.055511 -303.94853)
			(xy 196.00192 -303.954427) (xy 195.948041 -303.952458) (xy 195.895023 -303.942665) (xy 195.843996 -303.925257)
			(xy 195.796048 -303.900605) (xy 195.7522 -303.869235) (xy 195.713387 -303.831814) (xy 195.680435 -303.789141)
			(xy 195.654049 -303.742124) (xy 195.634789 -303.691767) (xy 195.623066 -303.639143) (xy 195.619131 -303.585372)
			(xy 191.655954 -303.585372) (xy 191.655433 -303.618073) (xy 191.646822 -303.682904) (xy 191.62976 -303.746041)
			(xy 191.604543 -303.806385) (xy 191.571609 -303.862889) (xy 191.53153 -303.91457) (xy 191.508634 -303.937924)
			(xy 191.501268 -303.94529) (xy 191.493648 -303.963832) (xy 191.493648 -304.010314) (xy 191.908445 -304.010314)
			(xy 191.91238 -303.956543) (xy 191.924103 -303.903919) (xy 191.943363 -303.853562) (xy 191.969749 -303.806545)
			(xy 192.002701 -303.763872) (xy 192.041514 -303.726451) (xy 192.085362 -303.695081) (xy 192.13331 -303.670429)
			(xy 192.184337 -303.653021) (xy 192.237355 -303.643228) (xy 192.291234 -303.641259) (xy 192.344825 -303.647156)
			(xy 192.396986 -303.660792) (xy 192.446606 -303.681879) (xy 192.492627 -303.709965) (xy 192.534069 -303.744453)
			(xy 192.570047 -303.784607) (xy 192.599795 -303.829571) (xy 192.62268 -303.878388) (xy 192.638212 -303.930017)
			(xy 192.646062 -303.983357) (xy 192.646554 -304.010314) (xy 192.646062 -304.037271) (xy 192.638212 -304.090611)
			(xy 192.62268 -304.14224) (xy 192.599795 -304.191057) (xy 192.570047 -304.236021) (xy 192.534069 -304.276175)
			(xy 192.492627 -304.310663) (xy 192.446606 -304.338749) (xy 192.396986 -304.359836) (xy 192.344825 -304.373472)
			(xy 192.291234 -304.379369) (xy 192.237355 -304.3774) (xy 192.184337 -304.367607) (xy 192.13331 -304.350199)
			(xy 192.085362 -304.325547) (xy 192.041514 -304.294177) (xy 192.002701 -304.256756) (xy 191.969749 -304.214083)
			(xy 191.943363 -304.167066) (xy 191.924103 -304.116709) (xy 191.91238 -304.064085) (xy 191.908445 -304.010314)
			(xy 191.493648 -304.010314) (xy 191.493648 -304.056796) (xy 191.501268 -304.075338) (xy 191.508634 -304.082704)
			(xy 191.53155 -304.106039) (xy 191.571633 -304.157721) (xy 191.604567 -304.214228) (xy 191.629781 -304.274576)
			(xy 191.646835 -304.337718) (xy 191.655433 -304.402554) (xy 191.655954 -304.435256) (xy 191.655465 -304.466419)
			(xy 191.647653 -304.528253) (xy 191.632153 -304.588621) (xy 191.60921 -304.646569) (xy 191.579184 -304.701186)
			(xy 191.54255 -304.751608) (xy 191.499885 -304.797042) (xy 191.451863 -304.83677) (xy 191.399239 -304.870165)
			(xy 191.342845 -304.896702) (xy 191.28357 -304.915962) (xy 191.222349 -304.927641) (xy 191.160146 -304.931554)
			(xy 191.097943 -304.927641) (xy 191.036722 -304.915962) (xy 190.977447 -304.896702) (xy 190.921053 -304.870165)
			(xy 190.868429 -304.83677) (xy 190.820407 -304.797042) (xy 190.777742 -304.751608) (xy 190.741108 -304.701186)
			(xy 190.711082 -304.646569) (xy 190.688139 -304.588621) (xy 190.672639 -304.528253) (xy 190.664827 -304.466419)
			(xy 190.664338 -304.435256) (xy 187.555886 -304.435256) (xy 187.555372 -304.467977) (xy 187.546771 -304.53285)
			(xy 187.529715 -304.596029) (xy 187.504498 -304.656417) (xy 187.471559 -304.712964) (xy 187.431469 -304.764688)
			(xy 187.408566 -304.788062) (xy 187.4012 -304.795174) (xy 187.393326 -304.81397) (xy 187.393326 -304.860452)
			(xy 187.808377 -304.860452) (xy 187.812312 -304.806681) (xy 187.824035 -304.754057) (xy 187.843295 -304.7037)
			(xy 187.869681 -304.656683) (xy 187.902633 -304.61401) (xy 187.941446 -304.576589) (xy 187.985294 -304.545219)
			(xy 188.033242 -304.520567) (xy 188.084269 -304.503159) (xy 188.137287 -304.493366) (xy 188.191166 -304.491397)
			(xy 188.244757 -304.497294) (xy 188.296918 -304.51093) (xy 188.346538 -304.532017) (xy 188.392559 -304.560103)
			(xy 188.434001 -304.594591) (xy 188.469979 -304.634745) (xy 188.499727 -304.679709) (xy 188.522612 -304.728526)
			(xy 188.538144 -304.780155) (xy 188.545994 -304.833495) (xy 188.546486 -304.860452) (xy 188.545994 -304.887409)
			(xy 188.538144 -304.940749) (xy 188.522612 -304.992378) (xy 188.499727 -305.041195) (xy 188.469979 -305.086159)
			(xy 188.434001 -305.126313) (xy 188.392559 -305.160801) (xy 188.346538 -305.188887) (xy 188.296918 -305.209974)
			(xy 188.244757 -305.22361) (xy 188.191166 -305.229507) (xy 188.137287 -305.227538) (xy 188.084269 -305.217745)
			(xy 188.033242 -305.200337) (xy 187.985294 -305.175685) (xy 187.941446 -305.144315) (xy 187.902633 -305.106894)
			(xy 187.869681 -305.064221) (xy 187.843295 -305.017204) (xy 187.824035 -304.966847) (xy 187.812312 -304.914223)
			(xy 187.808377 -304.860452) (xy 187.393326 -304.860452) (xy 187.393326 -304.90668) (xy 187.4012 -304.925476)
			(xy 187.408566 -304.932588) (xy 187.431476 -304.955954) (xy 187.471557 -305.007684) (xy 187.50449 -305.064234)
			(xy 187.529703 -305.124623) (xy 187.546759 -305.187801) (xy 187.555362 -305.252674) (xy 187.555886 -305.285394)
			(xy 189.406545 -305.285394) (xy 189.41048 -305.231623) (xy 189.422203 -305.178999) (xy 189.441463 -305.128642)
			(xy 189.467849 -305.081625) (xy 189.500801 -305.038952) (xy 189.539614 -305.001531) (xy 189.583462 -304.970161)
			(xy 189.63141 -304.945509) (xy 189.682437 -304.928101) (xy 189.735455 -304.918308) (xy 189.789334 -304.916339)
			(xy 189.842925 -304.922236) (xy 189.895086 -304.935872) (xy 189.944706 -304.956959) (xy 189.990727 -304.985045)
			(xy 190.032169 -305.019533) (xy 190.068147 -305.059687) (xy 190.097895 -305.104651) (xy 190.12078 -305.153468)
			(xy 190.136312 -305.205097) (xy 190.144162 -305.258437) (xy 190.144654 -305.285394) (xy 194.108324 -305.285394)
			(xy 194.108868 -305.252674) (xy 194.117462 -305.187802) (xy 194.134512 -305.124623) (xy 194.159724 -305.064235)
			(xy 194.192658 -305.007688) (xy 194.232743 -304.955963) (xy 194.255644 -304.932588) (xy 194.26301 -304.925476)
			(xy 194.270884 -304.90668) (xy 194.270884 -304.81397) (xy 194.26301 -304.795174) (xy 194.255644 -304.788062)
			(xy 194.23276 -304.764671) (xy 194.192676 -304.712947) (xy 194.15974 -304.656402) (xy 194.134522 -304.596018)
			(xy 194.11746 -304.532844) (xy 194.108851 -304.467975) (xy 194.108324 -304.435256) (xy 194.108813 -304.404093)
			(xy 194.116625 -304.342259) (xy 194.132125 -304.281891) (xy 194.155068 -304.223943) (xy 194.185094 -304.169326)
			(xy 194.221728 -304.118904) (xy 194.264393 -304.07347) (xy 194.312415 -304.033742) (xy 194.365039 -304.000347)
			(xy 194.421433 -303.97381) (xy 194.480708 -303.95455) (xy 194.541929 -303.942871) (xy 194.604132 -303.938958)
			(xy 194.666335 -303.942871) (xy 194.727556 -303.95455) (xy 194.786831 -303.97381) (xy 194.843225 -304.000347)
			(xy 194.895849 -304.033742) (xy 194.943871 -304.07347) (xy 194.986536 -304.118904) (xy 195.02317 -304.169326)
			(xy 195.053196 -304.223943) (xy 195.076139 -304.281891) (xy 195.091639 -304.342259) (xy 195.099451 -304.404093)
			(xy 195.09994 -304.435256) (xy 198.208392 -304.435256) (xy 198.208918 -304.402555) (xy 198.217526 -304.337723)
			(xy 198.234586 -304.274586) (xy 198.259802 -304.214242) (xy 198.292736 -304.157738) (xy 198.332816 -304.106057)
			(xy 198.355712 -304.082704) (xy 198.363078 -304.075338) (xy 198.370698 -304.056796) (xy 198.370698 -303.963832)
			(xy 198.363078 -303.94529) (xy 198.355712 -303.937924) (xy 198.3328 -303.914585) (xy 198.292719 -303.862903)
			(xy 198.259785 -303.806397) (xy 198.234571 -303.746049) (xy 198.217515 -303.682909) (xy 198.208915 -303.618074)
			(xy 198.208392 -303.585372) (xy 198.208881 -303.554209) (xy 198.216693 -303.492375) (xy 198.232193 -303.432007)
			(xy 198.255136 -303.374059) (xy 198.285162 -303.319442) (xy 198.321796 -303.26902) (xy 198.364461 -303.223586)
			(xy 198.412483 -303.183858) (xy 198.465107 -303.150463) (xy 198.521501 -303.123926) (xy 198.580776 -303.104666)
			(xy 198.641997 -303.092987) (xy 198.7042 -303.089074) (xy 198.766403 -303.092987) (xy 198.827624 -303.104666)
			(xy 198.886899 -303.123926) (xy 198.943293 -303.150463) (xy 198.995917 -303.183858) (xy 199.043939 -303.223586)
			(xy 199.086604 -303.26902) (xy 199.123238 -303.319442) (xy 199.153264 -303.374059) (xy 199.176207 -303.432007)
			(xy 199.191707 -303.492375) (xy 199.199519 -303.554209) (xy 199.200008 -303.585372) (xy 203.162931 -303.585372)
			(xy 203.166866 -303.531601) (xy 203.178589 -303.478977) (xy 203.197849 -303.42862) (xy 203.224235 -303.381603)
			(xy 203.257187 -303.33893) (xy 203.296 -303.301509) (xy 203.339848 -303.270139) (xy 203.387796 -303.245487)
			(xy 203.438823 -303.228079) (xy 203.491841 -303.218286) (xy 203.54572 -303.216317) (xy 203.599311 -303.222214)
			(xy 203.651472 -303.23585) (xy 203.701092 -303.256937) (xy 203.747113 -303.285023) (xy 203.788555 -303.319511)
			(xy 203.824533 -303.359665) (xy 203.854281 -303.404629) (xy 203.877166 -303.453446) (xy 203.892698 -303.505075)
			(xy 203.900548 -303.558415) (xy 203.90104 -303.585372) (xy 203.900548 -303.612329) (xy 203.892698 -303.665669)
			(xy 203.877166 -303.717298) (xy 203.854281 -303.766115) (xy 203.824533 -303.811079) (xy 203.788555 -303.851233)
			(xy 203.747113 -303.885721) (xy 203.701092 -303.913807) (xy 203.651472 -303.934894) (xy 203.599311 -303.94853)
			(xy 203.54572 -303.954427) (xy 203.491841 -303.952458) (xy 203.438823 -303.942665) (xy 203.387796 -303.925257)
			(xy 203.339848 -303.900605) (xy 203.296 -303.869235) (xy 203.257187 -303.831814) (xy 203.224235 -303.789141)
			(xy 203.197849 -303.742124) (xy 203.178589 -303.691767) (xy 203.166866 -303.639143) (xy 203.162931 -303.585372)
			(xy 199.200008 -303.585372) (xy 199.1995 -303.618073) (xy 199.190889 -303.682906) (xy 199.173825 -303.746043)
			(xy 199.148605 -303.806388) (xy 199.115668 -303.862891) (xy 199.075585 -303.914571) (xy 199.052688 -303.937924)
			(xy 199.045322 -303.94529) (xy 199.037702 -303.963832) (xy 199.037702 -304.010314) (xy 199.452499 -304.010314)
			(xy 199.456434 -303.956543) (xy 199.468157 -303.903919) (xy 199.487417 -303.853562) (xy 199.513803 -303.806545)
			(xy 199.546755 -303.763872) (xy 199.585568 -303.726451) (xy 199.629416 -303.695081) (xy 199.677364 -303.670429)
			(xy 199.728391 -303.653021) (xy 199.781409 -303.643228) (xy 199.835288 -303.641259) (xy 199.888879 -303.647156)
			(xy 199.94104 -303.660792) (xy 199.99066 -303.681879) (xy 200.036681 -303.709965) (xy 200.078123 -303.744453)
			(xy 200.114101 -303.784607) (xy 200.143849 -303.829571) (xy 200.166734 -303.878388) (xy 200.182266 -303.930017)
			(xy 200.190116 -303.983357) (xy 200.190608 -304.010314) (xy 200.190116 -304.037271) (xy 200.182266 -304.090611)
			(xy 200.166734 -304.14224) (xy 200.143849 -304.191057) (xy 200.114101 -304.236021) (xy 200.078123 -304.276175)
			(xy 200.036681 -304.310663) (xy 199.99066 -304.338749) (xy 199.94104 -304.359836) (xy 199.888879 -304.373472)
			(xy 199.835288 -304.379369) (xy 199.781409 -304.3774) (xy 199.728391 -304.367607) (xy 199.677364 -304.350199)
			(xy 199.629416 -304.325547) (xy 199.585568 -304.294177) (xy 199.546755 -304.256756) (xy 199.513803 -304.214083)
			(xy 199.487417 -304.167066) (xy 199.468157 -304.116709) (xy 199.456434 -304.064085) (xy 199.452499 -304.010314)
			(xy 199.037702 -304.010314) (xy 199.037702 -304.056796) (xy 199.045322 -304.075338) (xy 199.052688 -304.082704)
			(xy 199.075613 -304.10603) (xy 199.115694 -304.157715) (xy 199.148626 -304.214224) (xy 199.173837 -304.274574)
			(xy 199.19089 -304.337717) (xy 199.199487 -304.402554) (xy 199.200008 -304.435256) (xy 199.199519 -304.466419)
			(xy 199.191707 -304.528253) (xy 199.176207 -304.588621) (xy 199.153264 -304.646569) (xy 199.123238 -304.701186)
			(xy 199.086604 -304.751608) (xy 199.043939 -304.797042) (xy 198.995917 -304.83677) (xy 198.943293 -304.870165)
			(xy 198.886899 -304.896702) (xy 198.827624 -304.915962) (xy 198.766403 -304.927641) (xy 198.7042 -304.931554)
			(xy 198.641997 -304.927641) (xy 198.580776 -304.915962) (xy 198.521501 -304.896702) (xy 198.465107 -304.870165)
			(xy 198.412483 -304.83677) (xy 198.364461 -304.797042) (xy 198.321796 -304.751608) (xy 198.285162 -304.701186)
			(xy 198.255136 -304.646569) (xy 198.232193 -304.588621) (xy 198.216693 -304.528253) (xy 198.208881 -304.466419)
			(xy 198.208392 -304.435256) (xy 195.09994 -304.435256) (xy 195.099439 -304.467977) (xy 195.090838 -304.532852)
			(xy 195.07378 -304.596032) (xy 195.04856 -304.65642) (xy 195.015618 -304.712966) (xy 194.975525 -304.764689)
			(xy 194.95262 -304.788062) (xy 194.945254 -304.795174) (xy 194.93738 -304.81397) (xy 194.93738 -304.860452)
			(xy 195.352431 -304.860452) (xy 195.356366 -304.806681) (xy 195.368089 -304.754057) (xy 195.387349 -304.7037)
			(xy 195.413735 -304.656683) (xy 195.446687 -304.61401) (xy 195.4855 -304.576589) (xy 195.529348 -304.545219)
			(xy 195.577296 -304.520567) (xy 195.628323 -304.503159) (xy 195.681341 -304.493366) (xy 195.73522 -304.491397)
			(xy 195.788811 -304.497294) (xy 195.840972 -304.51093) (xy 195.890592 -304.532017) (xy 195.936613 -304.560103)
			(xy 195.978055 -304.594591) (xy 196.014033 -304.634745) (xy 196.043781 -304.679709) (xy 196.066666 -304.728526)
			(xy 196.082198 -304.780155) (xy 196.090048 -304.833495) (xy 196.09054 -304.860452) (xy 196.090048 -304.887409)
			(xy 196.082198 -304.940749) (xy 196.066666 -304.992378) (xy 196.043781 -305.041195) (xy 196.014033 -305.086159)
			(xy 195.978055 -305.126313) (xy 195.936613 -305.160801) (xy 195.890592 -305.188887) (xy 195.840972 -305.209974)
			(xy 195.788811 -305.22361) (xy 195.73522 -305.229507) (xy 195.681341 -305.227538) (xy 195.628323 -305.217745)
			(xy 195.577296 -305.200337) (xy 195.529348 -305.175685) (xy 195.4855 -305.144315) (xy 195.446687 -305.106894)
			(xy 195.413735 -305.064221) (xy 195.387349 -305.017204) (xy 195.368089 -304.966847) (xy 195.356366 -304.914223)
			(xy 195.352431 -304.860452) (xy 194.93738 -304.860452) (xy 194.93738 -304.90668) (xy 194.945254 -304.925476)
			(xy 194.95262 -304.932588) (xy 194.975522 -304.955963) (xy 195.015605 -305.00769) (xy 195.04854 -305.064238)
			(xy 195.073755 -305.124625) (xy 195.090812 -305.187802) (xy 195.099416 -305.252674) (xy 195.09994 -305.285394)
			(xy 196.950599 -305.285394) (xy 196.954534 -305.231623) (xy 196.966257 -305.178999) (xy 196.985517 -305.128642)
			(xy 197.011903 -305.081625) (xy 197.044855 -305.038952) (xy 197.083668 -305.001531) (xy 197.127516 -304.970161)
			(xy 197.175464 -304.945509) (xy 197.226491 -304.928101) (xy 197.279509 -304.918308) (xy 197.333388 -304.916339)
			(xy 197.386979 -304.922236) (xy 197.43914 -304.935872) (xy 197.48876 -304.956959) (xy 197.534781 -304.985045)
			(xy 197.576223 -305.019533) (xy 197.612201 -305.059687) (xy 197.641949 -305.104651) (xy 197.664834 -305.153468)
			(xy 197.680366 -305.205097) (xy 197.688216 -305.258437) (xy 197.688708 -305.285394) (xy 201.652124 -305.285394)
			(xy 201.652668 -305.252674) (xy 201.661262 -305.187802) (xy 201.678312 -305.124623) (xy 201.703524 -305.064235)
			(xy 201.736458 -305.007688) (xy 201.776543 -304.955963) (xy 201.799444 -304.932588) (xy 201.80681 -304.925476)
			(xy 201.814684 -304.90668) (xy 201.814684 -304.81397) (xy 201.80681 -304.795174) (xy 201.799444 -304.788062)
			(xy 201.77656 -304.764671) (xy 201.736476 -304.712947) (xy 201.70354 -304.656402) (xy 201.678322 -304.596018)
			(xy 201.66126 -304.532844) (xy 201.652651 -304.467975) (xy 201.652124 -304.435256) (xy 201.652613 -304.404093)
			(xy 201.660425 -304.342259) (xy 201.675925 -304.281891) (xy 201.698868 -304.223943) (xy 201.728894 -304.169326)
			(xy 201.765528 -304.118904) (xy 201.808193 -304.07347) (xy 201.856215 -304.033742) (xy 201.908839 -304.000347)
			(xy 201.965233 -303.97381) (xy 202.024508 -303.95455) (xy 202.085729 -303.942871) (xy 202.147932 -303.938958)
			(xy 202.210135 -303.942871) (xy 202.271356 -303.95455) (xy 202.330631 -303.97381) (xy 202.387025 -304.000347)
			(xy 202.439649 -304.033742) (xy 202.487671 -304.07347) (xy 202.530336 -304.118904) (xy 202.56697 -304.169326)
			(xy 202.596996 -304.223943) (xy 202.619939 -304.281891) (xy 202.635439 -304.342259) (xy 202.643251 -304.404093)
			(xy 202.64374 -304.435256) (xy 205.752192 -304.435256) (xy 205.752718 -304.402555) (xy 205.761326 -304.337723)
			(xy 205.778386 -304.274586) (xy 205.803602 -304.214242) (xy 205.836536 -304.157738) (xy 205.876616 -304.106057)
			(xy 205.899512 -304.082704) (xy 205.906878 -304.075338) (xy 205.914498 -304.056796) (xy 205.914498 -303.963832)
			(xy 205.906878 -303.94529) (xy 205.899512 -303.937924) (xy 205.8766 -303.914585) (xy 205.836519 -303.862903)
			(xy 205.803585 -303.806397) (xy 205.778371 -303.746049) (xy 205.761315 -303.682909) (xy 205.752715 -303.618074)
			(xy 205.752192 -303.585372) (xy 205.752681 -303.554209) (xy 205.760493 -303.492375) (xy 205.775993 -303.432007)
			(xy 205.798936 -303.374059) (xy 205.828962 -303.319442) (xy 205.865596 -303.26902) (xy 205.908261 -303.223586)
			(xy 205.956283 -303.183858) (xy 206.008907 -303.150463) (xy 206.065301 -303.123926) (xy 206.124576 -303.104666)
			(xy 206.185797 -303.092987) (xy 206.248 -303.089074) (xy 206.310203 -303.092987) (xy 206.371424 -303.104666)
			(xy 206.430699 -303.123926) (xy 206.487093 -303.150463) (xy 206.539717 -303.183858) (xy 206.587739 -303.223586)
			(xy 206.630404 -303.26902) (xy 206.667038 -303.319442) (xy 206.697064 -303.374059) (xy 206.720007 -303.432007)
			(xy 206.735507 -303.492375) (xy 206.743319 -303.554209) (xy 206.743808 -303.585372) (xy 206.7433 -303.618073)
			(xy 206.734689 -303.682906) (xy 206.717625 -303.746043) (xy 206.692405 -303.806388) (xy 206.659468 -303.862891)
			(xy 206.619385 -303.914571) (xy 206.596488 -303.937924) (xy 206.589122 -303.94529) (xy 206.581502 -303.963832)
			(xy 206.581502 -304.010314) (xy 206.996299 -304.010314) (xy 207.000234 -303.956543) (xy 207.011957 -303.903919)
			(xy 207.031217 -303.853562) (xy 207.057603 -303.806545) (xy 207.090555 -303.763872) (xy 207.129368 -303.726451)
			(xy 207.173216 -303.695081) (xy 207.221164 -303.670429) (xy 207.272191 -303.653021) (xy 207.325209 -303.643228)
			(xy 207.379088 -303.641259) (xy 207.432679 -303.647156) (xy 207.48484 -303.660792) (xy 207.53446 -303.681879)
			(xy 207.580481 -303.709965) (xy 207.621923 -303.744453) (xy 207.657901 -303.784607) (xy 207.687649 -303.829571)
			(xy 207.710534 -303.878388) (xy 207.726066 -303.930017) (xy 207.733916 -303.983357) (xy 207.734408 -304.010314)
			(xy 207.733916 -304.037271) (xy 207.726066 -304.090611) (xy 207.710534 -304.14224) (xy 207.687649 -304.191057)
			(xy 207.657901 -304.236021) (xy 207.621923 -304.276175) (xy 207.580481 -304.310663) (xy 207.53446 -304.338749)
			(xy 207.48484 -304.359836) (xy 207.432679 -304.373472) (xy 207.379088 -304.379369) (xy 207.325209 -304.3774)
			(xy 207.272191 -304.367607) (xy 207.221164 -304.350199) (xy 207.173216 -304.325547) (xy 207.129368 -304.294177)
			(xy 207.090555 -304.256756) (xy 207.057603 -304.214083) (xy 207.031217 -304.167066) (xy 207.011957 -304.116709)
			(xy 207.000234 -304.064085) (xy 206.996299 -304.010314) (xy 206.581502 -304.010314) (xy 206.581502 -304.056796)
			(xy 206.589122 -304.075338) (xy 206.596488 -304.082704) (xy 206.619413 -304.10603) (xy 206.659494 -304.157715)
			(xy 206.692426 -304.214224) (xy 206.717637 -304.274574) (xy 206.73469 -304.337717) (xy 206.743287 -304.402554)
			(xy 206.743808 -304.435256) (xy 206.743319 -304.466419) (xy 206.735507 -304.528253) (xy 206.720007 -304.588621)
			(xy 206.697064 -304.646569) (xy 206.667038 -304.701186) (xy 206.630404 -304.751608) (xy 206.587739 -304.797042)
			(xy 206.539717 -304.83677) (xy 206.487093 -304.870165) (xy 206.430699 -304.896702) (xy 206.371424 -304.915962)
			(xy 206.310203 -304.927641) (xy 206.248 -304.931554) (xy 206.185797 -304.927641) (xy 206.124576 -304.915962)
			(xy 206.065301 -304.896702) (xy 206.008907 -304.870165) (xy 205.956283 -304.83677) (xy 205.908261 -304.797042)
			(xy 205.865596 -304.751608) (xy 205.828962 -304.701186) (xy 205.798936 -304.646569) (xy 205.775993 -304.588621)
			(xy 205.760493 -304.528253) (xy 205.752681 -304.466419) (xy 205.752192 -304.435256) (xy 202.64374 -304.435256)
			(xy 202.643239 -304.467977) (xy 202.634638 -304.532852) (xy 202.61758 -304.596032) (xy 202.59236 -304.65642)
			(xy 202.559418 -304.712966) (xy 202.519325 -304.764689) (xy 202.49642 -304.788062) (xy 202.489054 -304.795174)
			(xy 202.48118 -304.81397) (xy 202.48118 -304.860452) (xy 202.896231 -304.860452) (xy 202.900166 -304.806681)
			(xy 202.911889 -304.754057) (xy 202.931149 -304.7037) (xy 202.957535 -304.656683) (xy 202.990487 -304.61401)
			(xy 203.0293 -304.576589) (xy 203.073148 -304.545219) (xy 203.121096 -304.520567) (xy 203.172123 -304.503159)
			(xy 203.225141 -304.493366) (xy 203.27902 -304.491397) (xy 203.332611 -304.497294) (xy 203.384772 -304.51093)
			(xy 203.434392 -304.532017) (xy 203.480413 -304.560103) (xy 203.521855 -304.594591) (xy 203.557833 -304.634745)
			(xy 203.587581 -304.679709) (xy 203.610466 -304.728526) (xy 203.625998 -304.780155) (xy 203.633848 -304.833495)
			(xy 203.63434 -304.860452) (xy 203.633848 -304.887409) (xy 203.625998 -304.940749) (xy 203.610466 -304.992378)
			(xy 203.587581 -305.041195) (xy 203.557833 -305.086159) (xy 203.521855 -305.126313) (xy 203.480413 -305.160801)
			(xy 203.434392 -305.188887) (xy 203.384772 -305.209974) (xy 203.332611 -305.22361) (xy 203.27902 -305.229507)
			(xy 203.225141 -305.227538) (xy 203.172123 -305.217745) (xy 203.121096 -305.200337) (xy 203.073148 -305.175685)
			(xy 203.0293 -305.144315) (xy 202.990487 -305.106894) (xy 202.957535 -305.064221) (xy 202.931149 -305.017204)
			(xy 202.911889 -304.966847) (xy 202.900166 -304.914223) (xy 202.896231 -304.860452) (xy 202.48118 -304.860452)
			(xy 202.48118 -304.90668) (xy 202.489054 -304.925476) (xy 202.49642 -304.932588) (xy 202.519322 -304.955963)
			(xy 202.559405 -305.00769) (xy 202.59234 -305.064238) (xy 202.617555 -305.124625) (xy 202.634612 -305.187802)
			(xy 202.643216 -305.252674) (xy 202.64374 -305.285394) (xy 204.494399 -305.285394) (xy 204.498334 -305.231623)
			(xy 204.510057 -305.178999) (xy 204.529317 -305.128642) (xy 204.555703 -305.081625) (xy 204.588655 -305.038952)
			(xy 204.627468 -305.001531) (xy 204.671316 -304.970161) (xy 204.719264 -304.945509) (xy 204.770291 -304.928101)
			(xy 204.823309 -304.918308) (xy 204.877188 -304.916339) (xy 204.930779 -304.922236) (xy 204.98294 -304.935872)
			(xy 205.03256 -304.956959) (xy 205.078581 -304.985045) (xy 205.120023 -305.019533) (xy 205.156001 -305.059687)
			(xy 205.185749 -305.104651) (xy 205.208634 -305.153468) (xy 205.224166 -305.205097) (xy 205.232016 -305.258437)
			(xy 205.232508 -305.285394) (xy 205.232016 -305.312351) (xy 205.224166 -305.365691) (xy 205.208634 -305.41732)
			(xy 205.185749 -305.466137) (xy 205.156001 -305.511101) (xy 205.120023 -305.551255) (xy 205.078581 -305.585743)
			(xy 205.03256 -305.613829) (xy 204.98294 -305.634916) (xy 204.930779 -305.648552) (xy 204.877188 -305.654449)
			(xy 204.823309 -305.65248) (xy 204.770291 -305.642687) (xy 204.719264 -305.625279) (xy 204.671316 -305.600627)
			(xy 204.627468 -305.569257) (xy 204.588655 -305.531836) (xy 204.555703 -305.489163) (xy 204.529317 -305.442146)
			(xy 204.510057 -305.391789) (xy 204.498334 -305.339165) (xy 204.494399 -305.285394) (xy 202.64374 -305.285394)
			(xy 202.643251 -305.316557) (xy 202.635439 -305.378391) (xy 202.619939 -305.438759) (xy 202.596996 -305.496707)
			(xy 202.56697 -305.551324) (xy 202.530336 -305.601746) (xy 202.487671 -305.64718) (xy 202.439649 -305.686908)
			(xy 202.387025 -305.720303) (xy 202.330631 -305.74684) (xy 202.271356 -305.7661) (xy 202.210135 -305.777779)
			(xy 202.147932 -305.781692) (xy 202.085729 -305.777779) (xy 202.024508 -305.7661) (xy 201.965233 -305.74684)
			(xy 201.908839 -305.720303) (xy 201.856215 -305.686908) (xy 201.808193 -305.64718) (xy 201.765528 -305.601746)
			(xy 201.728894 -305.551324) (xy 201.698868 -305.496707) (xy 201.675925 -305.438759) (xy 201.660425 -305.378391)
			(xy 201.652613 -305.316557) (xy 201.652124 -305.285394) (xy 197.688708 -305.285394) (xy 197.688216 -305.312351)
			(xy 197.680366 -305.365691) (xy 197.664834 -305.41732) (xy 197.641949 -305.466137) (xy 197.612201 -305.511101)
			(xy 197.576223 -305.551255) (xy 197.534781 -305.585743) (xy 197.48876 -305.613829) (xy 197.43914 -305.634916)
			(xy 197.386979 -305.648552) (xy 197.333388 -305.654449) (xy 197.279509 -305.65248) (xy 197.226491 -305.642687)
			(xy 197.175464 -305.625279) (xy 197.127516 -305.600627) (xy 197.083668 -305.569257) (xy 197.044855 -305.531836)
			(xy 197.011903 -305.489163) (xy 196.985517 -305.442146) (xy 196.966257 -305.391789) (xy 196.954534 -305.339165)
			(xy 196.950599 -305.285394) (xy 195.09994 -305.285394) (xy 195.099451 -305.316557) (xy 195.091639 -305.378391)
			(xy 195.076139 -305.438759) (xy 195.053196 -305.496707) (xy 195.02317 -305.551324) (xy 194.986536 -305.601746)
			(xy 194.943871 -305.64718) (xy 194.895849 -305.686908) (xy 194.843225 -305.720303) (xy 194.786831 -305.74684)
			(xy 194.727556 -305.7661) (xy 194.666335 -305.777779) (xy 194.604132 -305.781692) (xy 194.541929 -305.777779)
			(xy 194.480708 -305.7661) (xy 194.421433 -305.74684) (xy 194.365039 -305.720303) (xy 194.312415 -305.686908)
			(xy 194.264393 -305.64718) (xy 194.221728 -305.601746) (xy 194.185094 -305.551324) (xy 194.155068 -305.496707)
			(xy 194.132125 -305.438759) (xy 194.116625 -305.378391) (xy 194.108813 -305.316557) (xy 194.108324 -305.285394)
			(xy 190.144654 -305.285394) (xy 190.144162 -305.312351) (xy 190.136312 -305.365691) (xy 190.12078 -305.41732)
			(xy 190.097895 -305.466137) (xy 190.068147 -305.511101) (xy 190.032169 -305.551255) (xy 189.990727 -305.585743)
			(xy 189.944706 -305.613829) (xy 189.895086 -305.634916) (xy 189.842925 -305.648552) (xy 189.789334 -305.654449)
			(xy 189.735455 -305.65248) (xy 189.682437 -305.642687) (xy 189.63141 -305.625279) (xy 189.583462 -305.600627)
			(xy 189.539614 -305.569257) (xy 189.500801 -305.531836) (xy 189.467849 -305.489163) (xy 189.441463 -305.442146)
			(xy 189.422203 -305.391789) (xy 189.41048 -305.339165) (xy 189.406545 -305.285394) (xy 187.555886 -305.285394)
			(xy 187.555397 -305.316557) (xy 187.547585 -305.378391) (xy 187.532085 -305.438759) (xy 187.509142 -305.496707)
			(xy 187.479116 -305.551324) (xy 187.442482 -305.601746) (xy 187.399817 -305.64718) (xy 187.351795 -305.686908)
			(xy 187.299171 -305.720303) (xy 187.242777 -305.74684) (xy 187.183502 -305.7661) (xy 187.122281 -305.777779)
			(xy 187.060078 -305.781692) (xy 186.997875 -305.777779) (xy 186.936654 -305.7661) (xy 186.877379 -305.74684)
			(xy 186.820985 -305.720303) (xy 186.768361 -305.686908) (xy 186.720339 -305.64718) (xy 186.677674 -305.601746)
			(xy 186.64104 -305.551324) (xy 186.611014 -305.496707) (xy 186.588071 -305.438759) (xy 186.572571 -305.378391)
			(xy 186.564759 -305.316557) (xy 186.56427 -305.285394) (xy 185.96864 -305.285394) (xy 185.96864 -306.135278)
			(xy 188.075077 -306.135278) (xy 188.079012 -306.081507) (xy 188.090735 -306.028883) (xy 188.109995 -305.978526)
			(xy 188.136381 -305.931509) (xy 188.169333 -305.888836) (xy 188.208146 -305.851415) (xy 188.251994 -305.820045)
			(xy 188.299942 -305.795393) (xy 188.350969 -305.777985) (xy 188.403987 -305.768192) (xy 188.457866 -305.766223)
			(xy 188.511457 -305.77212) (xy 188.563618 -305.785756) (xy 188.613238 -305.806843) (xy 188.659259 -305.834929)
			(xy 188.700701 -305.869417) (xy 188.736679 -305.909571) (xy 188.766427 -305.954535) (xy 188.789312 -306.003352)
			(xy 188.804844 -306.054981) (xy 188.812694 -306.108321) (xy 188.813186 -306.135278) (xy 188.812694 -306.162235)
			(xy 188.804844 -306.215575) (xy 188.789312 -306.267204) (xy 188.766427 -306.316021) (xy 188.736679 -306.360985)
			(xy 188.700701 -306.401139) (xy 188.659259 -306.435627) (xy 188.613238 -306.463713) (xy 188.563618 -306.4848)
			(xy 188.511457 -306.498436) (xy 188.457866 -306.504333) (xy 188.403987 -306.502364) (xy 188.350969 -306.492571)
			(xy 188.299942 -306.475163) (xy 188.251994 -306.450511) (xy 188.208146 -306.419141) (xy 188.169333 -306.38172)
			(xy 188.136381 -306.339047) (xy 188.109995 -306.29203) (xy 188.090735 -306.241673) (xy 188.079012 -306.189049)
			(xy 188.075077 -306.135278) (xy 185.96864 -306.135278) (xy 185.96864 -312.085228) (xy 186.56427 -312.085228)
			(xy 186.564742 -312.054031) (xy 186.572561 -311.992129) (xy 186.588089 -311.931699) (xy 186.611083 -311.873697)
			(xy 186.641178 -311.819041) (xy 186.677897 -311.768596) (xy 186.720659 -311.723162) (xy 186.768788 -311.683455)
			(xy 186.794902 -311.666382) (xy 186.805062 -311.659778) (xy 186.817254 -311.639966) (xy 186.826652 -311.535826)
			(xy 186.81827 -311.514236) (xy 186.80938 -311.505854) (xy 186.791118 -311.488315) (xy 186.759037 -311.449143)
			(xy 186.732615 -311.405952) (xy 186.712351 -311.359552) (xy 186.698623 -311.310816) (xy 186.691691 -311.26066)
			(xy 186.69127 -311.235344) (xy 186.691674 -311.209995) (xy 186.698613 -311.159775) (xy 186.712367 -311.11098)
			(xy 186.732675 -311.064528) (xy 186.759156 -311.021296) (xy 186.79131 -310.9821) (xy 186.809634 -310.96458)
			(xy 186.818524 -310.956452) (xy 186.826906 -310.934608) (xy 186.817254 -310.830468) (xy 186.805062 -310.810656)
			(xy 186.794902 -310.804306) (xy 186.768787 -310.787212) (xy 186.720665 -310.747459) (xy 186.677909 -310.701985)
			(xy 186.641195 -310.651506) (xy 186.611102 -310.596821) (xy 186.588107 -310.538794) (xy 186.572571 -310.47834)
			(xy 186.564741 -310.416415) (xy 186.56427 -310.385206) (xy 186.564725 -310.354009) (xy 186.572546 -310.292106)
			(xy 186.588078 -310.231676) (xy 186.611074 -310.173673) (xy 186.641171 -310.119017) (xy 186.677892 -310.068573)
			(xy 186.720656 -310.023139) (xy 186.768787 -309.983433) (xy 186.794902 -309.96636) (xy 186.805062 -309.959756)
			(xy 186.817254 -309.939944) (xy 186.826652 -309.835804) (xy 186.81827 -309.814214) (xy 186.80938 -309.805832)
			(xy 186.789478 -309.786673) (xy 186.755014 -309.743501) (xy 186.727375 -309.695671) (xy 186.707179 -309.644255)
			(xy 186.694876 -309.590401) (xy 186.690743 -309.535315) (xy 186.694871 -309.480228) (xy 186.70717 -309.426374)
			(xy 186.727362 -309.374956) (xy 186.754998 -309.327124) (xy 186.789457 -309.283949) (xy 186.80938 -309.264812)
			(xy 186.81827 -309.25643) (xy 186.826652 -309.23484) (xy 186.817254 -309.1307) (xy 186.805062 -309.110888)
			(xy 186.794902 -309.104284) (xy 186.76879 -309.08721) (xy 186.720673 -309.047493) (xy 186.67792 -309.002053)
			(xy 186.641206 -308.951608) (xy 186.611113 -308.896954) (xy 186.588115 -308.838956) (xy 186.572577 -308.778531)
			(xy 186.564743 -308.716633) (xy 186.56427 -308.685438) (xy 186.564736 -308.654229) (xy 186.572562 -308.592302)
			(xy 186.588095 -308.531847) (xy 186.611091 -308.473818) (xy 186.641185 -308.419133) (xy 186.677901 -308.368655)
			(xy 186.720661 -308.323183) (xy 186.768788 -308.283434) (xy 186.794902 -308.266338) (xy 186.805062 -308.259988)
			(xy 186.817254 -308.240176) (xy 186.826906 -308.136036) (xy 186.818524 -308.114192) (xy 186.809634 -308.106064)
			(xy 186.791303 -308.088552) (xy 186.75916 -308.049349) (xy 186.732687 -308.006114) (xy 186.712384 -307.959661)
			(xy 186.698632 -307.910866) (xy 186.69169 -307.860648) (xy 186.69127 -307.8353) (xy 186.691656 -307.809981)
			(xy 186.698585 -307.75982) (xy 186.712312 -307.711078) (xy 186.732579 -307.664673) (xy 186.759004 -307.621478)
			(xy 186.791092 -307.582305) (xy 186.80938 -307.56479) (xy 186.81827 -307.556408) (xy 186.826652 -307.534818)
			(xy 186.817254 -307.430678) (xy 186.805062 -307.410866) (xy 186.794902 -307.404262) (xy 186.76878 -307.387203)
			(xy 186.720663 -307.347484) (xy 186.67791 -307.302042) (xy 186.641198 -307.251594) (xy 186.611105 -307.196938)
			(xy 186.588109 -307.138938) (xy 186.572573 -307.078511) (xy 186.564742 -307.016612) (xy 186.56427 -306.985416)
			(xy 186.564759 -306.954253) (xy 186.572571 -306.892419) (xy 186.588071 -306.832051) (xy 186.611014 -306.774103)
			(xy 186.64104 -306.719486) (xy 186.677674 -306.669064) (xy 186.720339 -306.62363) (xy 186.768361 -306.583902)
			(xy 186.820985 -306.550507) (xy 186.877379 -306.52397) (xy 186.936654 -306.50471) (xy 186.997875 -306.493031)
			(xy 187.060078 -306.489118) (xy 187.122281 -306.493031) (xy 187.183502 -306.50471) (xy 187.242777 -306.52397)
			(xy 187.299171 -306.550507) (xy 187.351795 -306.583902) (xy 187.399817 -306.62363) (xy 187.442482 -306.669064)
			(xy 187.479116 -306.719486) (xy 187.509142 -306.774103) (xy 187.532085 -306.832051) (xy 187.547585 -306.892419)
			(xy 187.555397 -306.954253) (xy 187.555886 -306.985416) (xy 187.555468 -307.016615) (xy 187.547644 -307.07852)
			(xy 187.532108 -307.138952) (xy 187.509107 -307.196955) (xy 187.479005 -307.251611) (xy 187.442278 -307.302055)
			(xy 187.399508 -307.347488) (xy 187.351372 -307.387191) (xy 187.325254 -307.404262) (xy 187.315094 -307.410866)
			(xy 187.302902 -307.430678) (xy 187.293504 -307.534818) (xy 187.301886 -307.556408) (xy 187.310776 -307.56479)
			(xy 187.32907 -307.582296) (xy 187.361146 -307.621477) (xy 187.387562 -307.664676) (xy 187.407821 -307.711082)
			(xy 187.421542 -307.759823) (xy 187.428468 -307.809982) (xy 187.428886 -307.8353) (xy 187.428459 -307.860648)
			(xy 187.421526 -307.910868) (xy 187.407778 -307.959664) (xy 187.387474 -308.006116) (xy 187.360997 -308.049348)
			(xy 187.328845 -308.088544) (xy 187.310522 -308.106064) (xy 187.301632 -308.114192) (xy 187.29325 -308.136036)
			(xy 187.302902 -308.240176) (xy 187.315094 -308.259988) (xy 187.325254 -308.266338) (xy 187.351357 -308.28345)
			(xy 187.399477 -308.323202) (xy 187.442231 -308.368675) (xy 187.478945 -308.419151) (xy 187.509038 -308.473833)
			(xy 187.532037 -308.531857) (xy 187.547576 -308.592308) (xy 187.555412 -308.65423) (xy 187.555886 -308.685438)
			(xy 187.555407 -308.716635) (xy 187.547593 -308.778537) (xy 187.532066 -308.838968) (xy 187.509074 -308.896971)
			(xy 187.478981 -308.951627) (xy 187.442262 -309.002072) (xy 187.399499 -309.047507) (xy 187.351369 -309.087211)
			(xy 187.325254 -309.104284) (xy 187.315094 -309.110888) (xy 187.302902 -309.1307) (xy 187.293504 -309.23484)
			(xy 187.301886 -309.25643) (xy 187.310776 -309.264812) (xy 187.330724 -309.283926) (xy 187.365191 -309.327103)
			(xy 187.392832 -309.374939) (xy 187.413029 -309.426362) (xy 187.42533 -309.480222) (xy 187.42946 -309.535315)
			(xy 187.425325 -309.590407) (xy 187.41302 -309.644267) (xy 187.392819 -309.695688) (xy 187.365174 -309.743521)
			(xy 187.330704 -309.786696) (xy 187.310776 -309.805832) (xy 187.301886 -309.814214) (xy 187.293504 -309.835804)
			(xy 187.302902 -309.939944) (xy 187.315094 -309.959756) (xy 187.325254 -309.96636) (xy 187.351376 -309.98342)
			(xy 187.399495 -310.023137) (xy 187.442249 -310.068578) (xy 187.478963 -310.119026) (xy 187.509055 -310.173682)
			(xy 187.532051 -310.231682) (xy 187.547586 -310.29211) (xy 187.555415 -310.35401) (xy 187.555886 -310.385206)
			(xy 187.555397 -310.416415) (xy 187.547577 -310.478341) (xy 187.532049 -310.538797) (xy 187.509057 -310.596826)
			(xy 187.478967 -310.651512) (xy 187.442252 -310.70199) (xy 187.399494 -310.747462) (xy 187.351368 -310.78721)
			(xy 187.325254 -310.804306) (xy 187.315094 -310.810656) (xy 187.302902 -310.830468) (xy 187.29325 -310.934608)
			(xy 187.301632 -310.956452) (xy 187.310522 -310.96458) (xy 187.328836 -310.982108) (xy 187.360979 -311.021309)
			(xy 187.387452 -311.064541) (xy 187.407758 -311.11099) (xy 187.421515 -311.159782) (xy 187.428462 -311.209997)
			(xy 187.428886 -311.235344) (xy 190.664338 -311.235344) (xy 190.664777 -311.204133) (xy 190.672603 -311.142205)
			(xy 190.688139 -311.081748) (xy 190.711137 -311.023718) (xy 190.741235 -310.969032) (xy 190.777956 -310.918555)
			(xy 190.820721 -310.873084) (xy 190.868853 -310.833338) (xy 190.89497 -310.816244) (xy 190.90513 -310.809894)
			(xy 190.917322 -310.790082) (xy 190.926974 -310.685942) (xy 190.918592 -310.664098) (xy 190.909702 -310.65597)
			(xy 190.891368 -310.638461) (xy 190.859226 -310.599257) (xy 190.832755 -310.556021) (xy 190.812452 -310.509568)
			(xy 190.7987 -310.460773) (xy 190.791759 -310.410554) (xy 190.791338 -310.385206) (xy 190.791738 -310.359888)
			(xy 190.798665 -310.309727) (xy 190.81239 -310.260986) (xy 190.832654 -310.214582) (xy 190.859077 -310.171386)
			(xy 190.891161 -310.132211) (xy 190.909448 -310.114696) (xy 190.918338 -310.106314) (xy 190.92672 -310.084724)
			(xy 190.917322 -309.980584) (xy 190.90513 -309.960772) (xy 190.89497 -309.954168) (xy 190.868877 -309.937062)
			(xy 190.82075 -309.897356) (xy 190.777987 -309.851923) (xy 190.741266 -309.801482) (xy 190.711166 -309.74683)
			(xy 190.688164 -309.688832) (xy 190.672624 -309.628407) (xy 190.664791 -309.566508) (xy 190.664789 -309.504116)
			(xy 190.672619 -309.442217) (xy 190.688157 -309.38179) (xy 190.711156 -309.323791) (xy 190.741253 -309.269138)
			(xy 190.777972 -309.218695) (xy 190.820733 -309.17326) (xy 190.868858 -309.133552) (xy 190.89497 -309.116476)
			(xy 190.90513 -309.109872) (xy 190.917322 -309.09006) (xy 190.92672 -308.98592) (xy 190.918338 -308.96433)
			(xy 190.909448 -308.955948) (xy 190.891177 -308.938418) (xy 190.859098 -308.899244) (xy 190.832678 -308.85605)
			(xy 190.812415 -308.809648) (xy 190.79869 -308.760911) (xy 190.791759 -308.710755) (xy 190.791338 -308.685438)
			(xy 190.791716 -308.660088) (xy 190.798658 -308.609866) (xy 190.812415 -308.561069) (xy 190.832728 -308.514617)
			(xy 190.859215 -308.471386) (xy 190.891375 -308.432192) (xy 190.909702 -308.414674) (xy 190.918592 -308.406546)
			(xy 190.926974 -308.384702) (xy 190.917322 -308.280562) (xy 190.90513 -308.26075) (xy 190.89497 -308.2544)
			(xy 190.868844 -308.237321) (xy 190.820724 -308.197565) (xy 190.77797 -308.152088) (xy 190.741257 -308.101607)
			(xy 190.711166 -308.04692) (xy 190.688172 -307.988891) (xy 190.672637 -307.928436) (xy 190.664809 -307.866509)
			(xy 190.664338 -307.8353) (xy 190.664803 -307.804103) (xy 190.672624 -307.742202) (xy 190.688155 -307.681772)
			(xy 190.711151 -307.62377) (xy 190.741246 -307.569115) (xy 190.777965 -307.51867) (xy 190.820728 -307.473235)
			(xy 190.868856 -307.433528) (xy 190.89497 -307.416454) (xy 190.90513 -307.40985) (xy 190.917322 -307.390038)
			(xy 190.92672 -307.285898) (xy 190.918338 -307.264308) (xy 190.909448 -307.255926) (xy 190.891166 -307.238407)
			(xy 190.859088 -307.19923) (xy 190.83267 -307.156034) (xy 190.812409 -307.10963) (xy 190.798685 -307.060891)
			(xy 190.791757 -307.010733) (xy 190.791338 -306.985416) (xy 190.791768 -306.960068) (xy 190.798699 -306.909848)
			(xy 190.812446 -306.861052) (xy 190.83275 -306.8146) (xy 190.859227 -306.771368) (xy 190.891379 -306.732172)
			(xy 190.909702 -306.714652) (xy 190.918592 -306.706524) (xy 190.926974 -306.68468) (xy 190.917322 -306.58054)
			(xy 190.90513 -306.560728) (xy 190.89497 -306.554378) (xy 190.868834 -306.537314) (xy 190.820714 -306.497556)
			(xy 190.77796 -306.452076) (xy 190.741248 -306.401593) (xy 190.711158 -306.346904) (xy 190.688166 -306.288873)
			(xy 190.672634 -306.228416) (xy 190.664807 -306.166488) (xy 190.664338 -306.135278) (xy 190.664827 -306.104115)
			(xy 190.672639 -306.042281) (xy 190.688139 -305.981913) (xy 190.711082 -305.923965) (xy 190.741108 -305.869348)
			(xy 190.777742 -305.818926) (xy 190.820407 -305.773492) (xy 190.868429 -305.733764) (xy 190.921053 -305.700369)
			(xy 190.977447 -305.673832) (xy 191.036722 -305.654572) (xy 191.097943 -305.642893) (xy 191.160146 -305.63898)
			(xy 191.222349 -305.642893) (xy 191.28357 -305.654572) (xy 191.342845 -305.673832) (xy 191.399239 -305.700369)
			(xy 191.451863 -305.733764) (xy 191.499885 -305.773492) (xy 191.54255 -305.818926) (xy 191.579184 -305.869348)
			(xy 191.60921 -305.923965) (xy 191.632153 -305.981913) (xy 191.647653 -306.042281) (xy 191.655465 -306.104115)
			(xy 191.655954 -306.135278) (xy 195.619131 -306.135278) (xy 195.623066 -306.081507) (xy 195.634789 -306.028883)
			(xy 195.654049 -305.978526) (xy 195.680435 -305.931509) (xy 195.713387 -305.888836) (xy 195.7522 -305.851415)
			(xy 195.796048 -305.820045) (xy 195.843996 -305.795393) (xy 195.895023 -305.777985) (xy 195.948041 -305.768192)
			(xy 196.00192 -305.766223) (xy 196.055511 -305.77212) (xy 196.107672 -305.785756) (xy 196.157292 -305.806843)
			(xy 196.203313 -305.834929) (xy 196.244755 -305.869417) (xy 196.280733 -305.909571) (xy 196.310481 -305.954535)
			(xy 196.333366 -306.003352) (xy 196.348898 -306.054981) (xy 196.356748 -306.108321) (xy 196.35724 -306.135278)
			(xy 196.356748 -306.162235) (xy 196.348898 -306.215575) (xy 196.333366 -306.267204) (xy 196.310481 -306.316021)
			(xy 196.280733 -306.360985) (xy 196.244755 -306.401139) (xy 196.203313 -306.435627) (xy 196.157292 -306.463713)
			(xy 196.107672 -306.4848) (xy 196.055511 -306.498436) (xy 196.00192 -306.504333) (xy 195.948041 -306.502364)
			(xy 195.895023 -306.492571) (xy 195.843996 -306.475163) (xy 195.796048 -306.450511) (xy 195.7522 -306.419141)
			(xy 195.713387 -306.38172) (xy 195.680435 -306.339047) (xy 195.654049 -306.29203) (xy 195.634789 -306.241673)
			(xy 195.623066 -306.189049) (xy 195.619131 -306.135278) (xy 191.655954 -306.135278) (xy 191.655536 -306.166489)
			(xy 191.647707 -306.228419) (xy 191.632168 -306.288877) (xy 191.609167 -306.346907) (xy 191.579067 -306.401593)
			(xy 191.542343 -306.45207) (xy 191.499575 -306.49754) (xy 191.45144 -306.537284) (xy 191.425322 -306.554378)
			(xy 191.415162 -306.560728) (xy 191.40297 -306.58054) (xy 191.393318 -306.68468) (xy 191.4017 -306.706524)
			(xy 191.41059 -306.714652) (xy 191.428933 -306.732152) (xy 191.461074 -306.771358) (xy 191.487545 -306.814596)
			(xy 191.507846 -306.86105) (xy 191.521596 -306.909847) (xy 191.528535 -306.960067) (xy 191.528954 -306.985416)
			(xy 191.528571 -307.010735) (xy 191.521641 -307.060896) (xy 191.507913 -307.109637) (xy 191.487645 -307.156042)
			(xy 191.461219 -307.199238) (xy 191.429132 -307.238411) (xy 191.410844 -307.255926) (xy 191.401954 -307.264308)
			(xy 191.393572 -307.285898) (xy 191.40297 -307.390038) (xy 191.415162 -307.40985) (xy 191.425322 -307.416454)
			(xy 191.451457 -307.433494) (xy 191.499573 -307.473217) (xy 191.542324 -307.518662) (xy 191.579035 -307.569113)
			(xy 191.609126 -307.623771) (xy 191.63212 -307.681774) (xy 191.647654 -307.742203) (xy 191.655483 -307.804103)
			(xy 191.655954 -307.8353) (xy 191.655475 -307.86651) (xy 191.647655 -307.928437) (xy 191.632126 -307.988893)
			(xy 191.609134 -308.046923) (xy 191.579042 -308.101609) (xy 191.542326 -308.152087) (xy 191.499565 -308.197558)
			(xy 191.451437 -308.237305) (xy 191.425322 -308.2544) (xy 191.415162 -308.26075) (xy 191.40297 -308.280562)
			(xy 191.393318 -308.384702) (xy 191.4017 -308.406546) (xy 191.41059 -308.414674) (xy 191.428895 -308.432211)
			(xy 191.46104 -308.47141) (xy 191.487515 -308.514639) (xy 191.507823 -308.561087) (xy 191.521581 -308.609877)
			(xy 191.52853 -308.660092) (xy 191.528954 -308.685438) (xy 191.528519 -308.710755) (xy 191.521599 -308.760914)
			(xy 191.507881 -308.809654) (xy 191.487624 -308.856059) (xy 191.461207 -308.899256) (xy 191.429128 -308.938432)
			(xy 191.410844 -308.955948) (xy 191.401954 -308.96433) (xy 191.393572 -308.98592) (xy 191.40297 -309.09006)
			(xy 191.415162 -309.109872) (xy 191.425322 -309.116476) (xy 191.451456 -309.133521) (xy 191.499586 -309.173232)
			(xy 191.54235 -309.218671) (xy 191.579073 -309.269117) (xy 191.609173 -309.323775) (xy 191.632174 -309.381778)
			(xy 191.647713 -309.442209) (xy 191.655544 -309.504113) (xy 191.655542 -309.56651) (xy 191.647709 -309.628414)
			(xy 191.632167 -309.688845) (xy 191.609163 -309.746847) (xy 191.57906 -309.801502) (xy 191.542335 -309.851947)
			(xy 191.499569 -309.897384) (xy 191.451437 -309.937092) (xy 191.425322 -309.954168) (xy 191.415162 -309.960772)
			(xy 191.40297 -309.980584) (xy 191.393572 -310.084724) (xy 191.401954 -310.106314) (xy 191.410844 -310.114696)
			(xy 191.429135 -310.132206) (xy 191.461212 -310.171384) (xy 191.487629 -310.214583) (xy 191.507889 -310.260988)
			(xy 191.521611 -310.309729) (xy 191.528536 -310.359888) (xy 191.528954 -310.385206) (xy 191.528541 -310.410555)
			(xy 191.521607 -310.460775) (xy 191.507857 -310.509572) (xy 191.48755 -310.556024) (xy 191.46107 -310.599256)
			(xy 191.428915 -310.638451) (xy 191.41059 -310.65597) (xy 191.4017 -310.664098) (xy 191.393318 -310.685942)
			(xy 191.40297 -310.790082) (xy 191.415162 -310.809894) (xy 191.425322 -310.816244) (xy 191.45142 -310.833363)
			(xy 191.499541 -310.873113) (xy 191.542297 -310.918584) (xy 191.579012 -310.969059) (xy 191.609107 -311.02374)
			(xy 191.632105 -311.081764) (xy 191.647645 -311.142214) (xy 191.65548 -311.204136) (xy 191.655954 -311.235344)
			(xy 191.655465 -311.266507) (xy 191.647653 -311.328341) (xy 191.632153 -311.388709) (xy 191.60921 -311.446657)
			(xy 191.579184 -311.501274) (xy 191.54255 -311.551696) (xy 191.499885 -311.59713) (xy 191.451863 -311.636858)
			(xy 191.399239 -311.670253) (xy 191.342845 -311.69679) (xy 191.28357 -311.71605) (xy 191.222349 -311.727729)
			(xy 191.160146 -311.731642) (xy 191.097943 -311.727729) (xy 191.036722 -311.71605) (xy 190.977447 -311.69679)
			(xy 190.921053 -311.670253) (xy 190.868429 -311.636858) (xy 190.820407 -311.59713) (xy 190.777742 -311.551696)
			(xy 190.741108 -311.501274) (xy 190.711082 -311.446657) (xy 190.688139 -311.388709) (xy 190.672639 -311.328341)
			(xy 190.664827 -311.266507) (xy 190.664338 -311.235344) (xy 187.428886 -311.235344) (xy 187.428445 -311.260661)
			(xy 187.421525 -311.310819) (xy 187.407808 -311.359559) (xy 187.387551 -311.405963) (xy 187.361136 -311.44916)
			(xy 187.329059 -311.488337) (xy 187.310776 -311.505854) (xy 187.301886 -311.514236) (xy 187.293504 -311.535826)
			(xy 187.302902 -311.639966) (xy 187.315094 -311.659778) (xy 187.325254 -311.666382) (xy 187.351341 -311.683494)
			(xy 187.39946 -311.723204) (xy 187.442215 -311.768637) (xy 187.478932 -311.819077) (xy 187.509029 -311.873726)
			(xy 187.53203 -311.931719) (xy 187.547573 -311.99214) (xy 187.55541 -312.054034) (xy 187.555886 -312.085228)
			(xy 189.406545 -312.085228) (xy 189.41048 -312.031457) (xy 189.422203 -311.978833) (xy 189.441463 -311.928476)
			(xy 189.467849 -311.881459) (xy 189.500801 -311.838786) (xy 189.539614 -311.801365) (xy 189.583462 -311.769995)
			(xy 189.63141 -311.745343) (xy 189.682437 -311.727935) (xy 189.735455 -311.718142) (xy 189.789334 -311.716173)
			(xy 189.842925 -311.72207) (xy 189.895086 -311.735706) (xy 189.944706 -311.756793) (xy 189.990727 -311.784879)
			(xy 190.032169 -311.819367) (xy 190.068147 -311.859521) (xy 190.097895 -311.904485) (xy 190.12078 -311.953302)
			(xy 190.136312 -312.004931) (xy 190.144162 -312.058271) (xy 190.144654 -312.085228) (xy 194.108324 -312.085228)
			(xy 194.108771 -312.05403) (xy 194.116591 -311.992126) (xy 194.132121 -311.931695) (xy 194.155118 -311.873691)
			(xy 194.185216 -311.819035) (xy 194.221939 -311.768591) (xy 194.264706 -311.723157) (xy 194.312839 -311.683454)
			(xy 194.338956 -311.666382) (xy 194.349116 -311.659778) (xy 194.361308 -311.639966) (xy 194.370706 -311.535826)
			(xy 194.362324 -311.514236) (xy 194.353434 -311.505854) (xy 194.335163 -311.488324) (xy 194.303085 -311.449149)
			(xy 194.276666 -311.405955) (xy 194.256403 -311.359554) (xy 194.242676 -311.310817) (xy 194.235745 -311.26066)
			(xy 194.235324 -311.235344) (xy 194.235711 -311.209995) (xy 194.242651 -311.159773) (xy 194.256407 -311.110976)
			(xy 194.276719 -311.064524) (xy 194.303203 -311.021293) (xy 194.335362 -310.982099) (xy 194.353688 -310.96458)
			(xy 194.362578 -310.956452) (xy 194.37096 -310.934608) (xy 194.361308 -310.830468) (xy 194.349116 -310.810656)
			(xy 194.338956 -310.804306) (xy 194.31283 -310.787228) (xy 194.26471 -310.747472) (xy 194.221956 -310.701994)
			(xy 194.185244 -310.651513) (xy 194.155153 -310.596826) (xy 194.132159 -310.538796) (xy 194.116624 -310.478341)
			(xy 194.108795 -310.416415) (xy 194.108324 -310.385206) (xy 194.108754 -310.354008) (xy 194.116576 -310.292103)
			(xy 194.132109 -310.231671) (xy 194.155108 -310.173668) (xy 194.185209 -310.119011) (xy 194.221934 -310.068567)
			(xy 194.264703 -310.023134) (xy 194.312838 -309.983431) (xy 194.338956 -309.96636) (xy 194.349116 -309.959756)
			(xy 194.361308 -309.939944) (xy 194.370706 -309.835804) (xy 194.362324 -309.814214) (xy 194.353434 -309.805832)
			(xy 194.333529 -309.786674) (xy 194.299061 -309.743504) (xy 194.271418 -309.695675) (xy 194.251218 -309.644258)
			(xy 194.238913 -309.590403) (xy 194.23478 -309.535315) (xy 194.238909 -309.480227) (xy 194.251209 -309.426371)
			(xy 194.271405 -309.374952) (xy 194.299044 -309.327121) (xy 194.333509 -309.283948) (xy 194.353434 -309.264812)
			(xy 194.362324 -309.25643) (xy 194.370706 -309.23484) (xy 194.361308 -309.1307) (xy 194.349116 -309.110888)
			(xy 194.338956 -309.104284) (xy 194.312856 -309.087191) (xy 194.264737 -309.047479) (xy 194.221981 -309.002043)
			(xy 194.185266 -308.9516) (xy 194.15517 -308.896949) (xy 194.132171 -308.838953) (xy 194.116632 -308.778529)
			(xy 194.108797 -308.716633) (xy 194.108324 -308.685438) (xy 194.108765 -308.654227) (xy 194.116592 -308.592299)
			(xy 194.132127 -308.531842) (xy 194.155125 -308.473813) (xy 194.185223 -308.419127) (xy 194.221944 -308.36865)
			(xy 194.264708 -308.323179) (xy 194.312839 -308.283433) (xy 194.338956 -308.266338) (xy 194.349116 -308.259988)
			(xy 194.361308 -308.240176) (xy 194.37096 -308.136036) (xy 194.362578 -308.114192) (xy 194.353688 -308.106064)
			(xy 194.335349 -308.088561) (xy 194.303208 -308.049355) (xy 194.276737 -308.006118) (xy 194.256436 -307.959664)
			(xy 194.242685 -307.910868) (xy 194.235744 -307.860648) (xy 194.235324 -307.8353) (xy 194.235724 -307.809982)
			(xy 194.242652 -307.759822) (xy 194.256377 -307.711081) (xy 194.276641 -307.664676) (xy 194.303064 -307.62148)
			(xy 194.335148 -307.582306) (xy 194.353434 -307.56479) (xy 194.362324 -307.556408) (xy 194.370706 -307.534818)
			(xy 194.361308 -307.430678) (xy 194.349116 -307.410866) (xy 194.338956 -307.404262) (xy 194.312846 -307.387184)
			(xy 194.264727 -307.34747) (xy 194.221972 -307.302031) (xy 194.185257 -307.251587) (xy 194.155163 -307.196933)
			(xy 194.132165 -307.138935) (xy 194.116628 -307.078509) (xy 194.108796 -307.016612) (xy 194.108324 -306.985416)
			(xy 194.108813 -306.954253) (xy 194.116625 -306.892419) (xy 194.132125 -306.832051) (xy 194.155068 -306.774103)
			(xy 194.185094 -306.719486) (xy 194.221728 -306.669064) (xy 194.264393 -306.62363) (xy 194.312415 -306.583902)
			(xy 194.365039 -306.550507) (xy 194.421433 -306.52397) (xy 194.480708 -306.50471) (xy 194.541929 -306.493031)
			(xy 194.604132 -306.489118) (xy 194.666335 -306.493031) (xy 194.727556 -306.50471) (xy 194.786831 -306.52397)
			(xy 194.843225 -306.550507) (xy 194.895849 -306.583902) (xy 194.943871 -306.62363) (xy 194.986536 -306.669064)
			(xy 195.02317 -306.719486) (xy 195.053196 -306.774103) (xy 195.076139 -306.832051) (xy 195.091639 -306.892419)
			(xy 195.099451 -306.954253) (xy 195.09994 -306.985416) (xy 195.099497 -307.016614) (xy 195.091674 -307.078517)
			(xy 195.07614 -307.138947) (xy 195.053142 -307.196949) (xy 195.023043 -307.251605) (xy 194.986321 -307.302049)
			(xy 194.943555 -307.347484) (xy 194.895424 -307.387189) (xy 194.869308 -307.404262) (xy 194.859148 -307.410866)
			(xy 194.846956 -307.430678) (xy 194.837558 -307.534818) (xy 194.84594 -307.556408) (xy 194.85483 -307.56479)
			(xy 194.873115 -307.582305) (xy 194.905194 -307.621483) (xy 194.931612 -307.664679) (xy 194.951873 -307.711084)
			(xy 194.965595 -307.759824) (xy 194.972522 -307.809983) (xy 194.97294 -307.8353) (xy 194.972496 -307.860647)
			(xy 194.965564 -307.910865) (xy 194.951818 -307.95966) (xy 194.931517 -308.006112) (xy 194.905044 -308.049345)
			(xy 194.872897 -308.088543) (xy 194.854576 -308.106064) (xy 194.845686 -308.114192) (xy 194.837304 -308.136036)
			(xy 194.846956 -308.240176) (xy 194.859148 -308.259988) (xy 194.869308 -308.266338) (xy 194.8954 -308.283466)
			(xy 194.943522 -308.323214) (xy 194.986278 -308.368684) (xy 195.022994 -308.419158) (xy 195.053089 -308.473838)
			(xy 195.076089 -308.53186) (xy 195.091629 -308.59231) (xy 195.099465 -308.654231) (xy 195.09994 -308.685438)
			(xy 195.099436 -308.716634) (xy 195.091623 -308.778534) (xy 195.076098 -308.838963) (xy 195.053109 -308.896965)
			(xy 195.023019 -308.951621) (xy 194.986304 -309.002066) (xy 194.943546 -309.047502) (xy 194.895421 -309.08721)
			(xy 194.869308 -309.104284) (xy 194.859148 -309.110888) (xy 194.846956 -309.1307) (xy 194.837558 -309.23484)
			(xy 194.84594 -309.25643) (xy 194.85483 -309.264812) (xy 194.874776 -309.283927) (xy 194.909238 -309.327106)
			(xy 194.936875 -309.374942) (xy 194.957068 -309.426365) (xy 194.969367 -309.480224) (xy 194.973496 -309.535315)
			(xy 194.969363 -309.590406) (xy 194.95706 -309.644264) (xy 194.936862 -309.695685) (xy 194.909221 -309.743518)
			(xy 194.874755 -309.786695) (xy 194.85483 -309.805832) (xy 194.84594 -309.814214) (xy 194.837558 -309.835804)
			(xy 194.846956 -309.939944) (xy 194.859148 -309.959756) (xy 194.869308 -309.96636) (xy 194.895443 -309.983401)
			(xy 194.943559 -310.023123) (xy 194.986311 -310.068568) (xy 195.023022 -310.119019) (xy 195.053113 -310.173677)
			(xy 195.076107 -310.231679) (xy 195.091641 -310.292108) (xy 195.099469 -310.354009) (xy 195.09994 -310.385206)
			(xy 195.099426 -310.416414) (xy 195.091607 -310.478338) (xy 195.07608 -310.538792) (xy 195.053092 -310.59682)
			(xy 195.023005 -310.651505) (xy 194.986294 -310.701984) (xy 194.943541 -310.747458) (xy 194.89542 -310.787208)
			(xy 194.869308 -310.804306) (xy 194.859148 -310.810656) (xy 194.846956 -310.830468) (xy 194.837304 -310.934608)
			(xy 194.845686 -310.956452) (xy 194.854576 -310.96458) (xy 194.872881 -310.982117) (xy 194.905027 -311.021315)
			(xy 194.931502 -311.064545) (xy 194.95181 -311.110992) (xy 194.965568 -311.159783) (xy 194.972516 -311.209998)
			(xy 194.97294 -311.235344) (xy 198.208392 -311.235344) (xy 198.208852 -311.204134) (xy 198.216678 -311.142207)
			(xy 198.232212 -311.081752) (xy 198.255207 -311.023722) (xy 198.285302 -310.969037) (xy 198.32202 -310.918559)
			(xy 198.364781 -310.873088) (xy 198.412909 -310.83334) (xy 198.439024 -310.816244) (xy 198.449184 -310.809894)
			(xy 198.461376 -310.790082) (xy 198.471028 -310.685942) (xy 198.462646 -310.664098) (xy 198.453756 -310.65597)
			(xy 198.435432 -310.638451) (xy 198.403288 -310.59925) (xy 198.376813 -310.556016) (xy 198.356508 -310.509565)
			(xy 198.342755 -310.460771) (xy 198.335813 -310.410554) (xy 198.335392 -310.385206) (xy 198.335807 -310.359888)
			(xy 198.342733 -310.309729) (xy 198.356456 -310.260989) (xy 198.376717 -310.214585) (xy 198.403137 -310.171388)
			(xy 198.435217 -310.132212) (xy 198.453502 -310.114696) (xy 198.462392 -310.106314) (xy 198.470774 -310.084724)
			(xy 198.461376 -309.980584) (xy 198.449184 -309.960772) (xy 198.439024 -309.954168) (xy 198.412929 -309.937064)
			(xy 198.364797 -309.89736) (xy 198.32203 -309.851929) (xy 198.285304 -309.801488) (xy 198.255201 -309.746836)
			(xy 198.232196 -309.688837) (xy 198.216653 -309.62841) (xy 198.20882 -309.566509) (xy 198.208818 -309.504115)
			(xy 198.216649 -309.442214) (xy 198.232188 -309.381785) (xy 198.255191 -309.323786) (xy 198.285291 -309.269132)
			(xy 198.322015 -309.21869) (xy 198.36478 -309.173256) (xy 198.41291 -309.13355) (xy 198.439024 -309.116476)
			(xy 198.449184 -309.109872) (xy 198.461376 -309.09006) (xy 198.470774 -308.98592) (xy 198.462392 -308.96433)
			(xy 198.453502 -308.955948) (xy 198.435241 -308.938408) (xy 198.403159 -308.899237) (xy 198.376737 -308.856045)
			(xy 198.356472 -308.809646) (xy 198.342744 -308.76091) (xy 198.335813 -308.710754) (xy 198.335392 -308.685438)
			(xy 198.335785 -308.660089) (xy 198.342725 -308.609868) (xy 198.356481 -308.561072) (xy 198.376791 -308.51462)
			(xy 198.403275 -308.471389) (xy 198.435431 -308.432193) (xy 198.453756 -308.414674) (xy 198.462646 -308.406546)
			(xy 198.471028 -308.384702) (xy 198.461376 -308.280562) (xy 198.449184 -308.26075) (xy 198.439024 -308.2544)
			(xy 198.412911 -308.237302) (xy 198.364788 -308.197551) (xy 198.322032 -308.152077) (xy 198.285317 -308.101599)
			(xy 198.255224 -308.046915) (xy 198.232228 -307.988887) (xy 198.216693 -307.928434) (xy 198.208863 -307.866509)
			(xy 198.208392 -307.8353) (xy 198.208832 -307.804102) (xy 198.216654 -307.742199) (xy 198.232187 -307.681767)
			(xy 198.255185 -307.623764) (xy 198.285284 -307.569108) (xy 198.322008 -307.518664) (xy 198.364775 -307.473231)
			(xy 198.412908 -307.433526) (xy 198.439024 -307.416454) (xy 198.449184 -307.40985) (xy 198.461376 -307.390038)
			(xy 198.470774 -307.285898) (xy 198.462392 -307.264308) (xy 198.453502 -307.255926) (xy 198.435231 -307.238397)
			(xy 198.403149 -307.199223) (xy 198.376729 -307.15603) (xy 198.356465 -307.109628) (xy 198.34274 -307.06089)
			(xy 198.335811 -307.010733) (xy 198.335392 -306.985416) (xy 198.335837 -306.960069) (xy 198.342767 -306.90985)
			(xy 198.356512 -306.861055) (xy 198.376813 -306.814603) (xy 198.403287 -306.77137) (xy 198.435435 -306.732173)
			(xy 198.453756 -306.714652) (xy 198.462646 -306.706524) (xy 198.471028 -306.68468) (xy 198.461376 -306.58054)
			(xy 198.449184 -306.560728) (xy 198.439024 -306.554378) (xy 198.412901 -306.537295) (xy 198.364778 -306.497542)
			(xy 198.322022 -306.452066) (xy 198.285308 -306.401586) (xy 198.255216 -306.346899) (xy 198.232222 -306.288869)
			(xy 198.216689 -306.228414) (xy 198.208862 -306.166488) (xy 198.208392 -306.135278) (xy 198.208881 -306.104115)
			(xy 198.216693 -306.042281) (xy 198.232193 -305.981913) (xy 198.255136 -305.923965) (xy 198.285162 -305.869348)
			(xy 198.321796 -305.818926) (xy 198.364461 -305.773492) (xy 198.412483 -305.733764) (xy 198.465107 -305.700369)
			(xy 198.521501 -305.673832) (xy 198.580776 -305.654572) (xy 198.641997 -305.642893) (xy 198.7042 -305.63898)
			(xy 198.766403 -305.642893) (xy 198.827624 -305.654572) (xy 198.886899 -305.673832) (xy 198.943293 -305.700369)
			(xy 198.995917 -305.733764) (xy 199.043939 -305.773492) (xy 199.086604 -305.818926) (xy 199.123238 -305.869348)
			(xy 199.153264 -305.923965) (xy 199.176207 -305.981913) (xy 199.191707 -306.042281) (xy 199.199519 -306.104115)
			(xy 199.200008 -306.135278) (xy 203.162931 -306.135278) (xy 203.166866 -306.081507) (xy 203.178589 -306.028883)
			(xy 203.197849 -305.978526) (xy 203.224235 -305.931509) (xy 203.257187 -305.888836) (xy 203.296 -305.851415)
			(xy 203.339848 -305.820045) (xy 203.387796 -305.795393) (xy 203.438823 -305.777985) (xy 203.491841 -305.768192)
			(xy 203.54572 -305.766223) (xy 203.599311 -305.77212) (xy 203.651472 -305.785756) (xy 203.701092 -305.806843)
			(xy 203.747113 -305.834929) (xy 203.788555 -305.869417) (xy 203.824533 -305.909571) (xy 203.854281 -305.954535)
			(xy 203.877166 -306.003352) (xy 203.892698 -306.054981) (xy 203.900548 -306.108321) (xy 203.90104 -306.135278)
			(xy 203.900548 -306.162235) (xy 203.892698 -306.215575) (xy 203.877166 -306.267204) (xy 203.854281 -306.316021)
			(xy 203.824533 -306.360985) (xy 203.788555 -306.401139) (xy 203.747113 -306.435627) (xy 203.701092 -306.463713)
			(xy 203.651472 -306.4848) (xy 203.599311 -306.498436) (xy 203.54572 -306.504333) (xy 203.491841 -306.502364)
			(xy 203.438823 -306.492571) (xy 203.387796 -306.475163) (xy 203.339848 -306.450511) (xy 203.296 -306.419141)
			(xy 203.257187 -306.38172) (xy 203.224235 -306.339047) (xy 203.197849 -306.29203) (xy 203.178589 -306.241673)
			(xy 203.166866 -306.189049) (xy 203.162931 -306.135278) (xy 199.200008 -306.135278) (xy 199.199565 -306.166488)
			(xy 199.191737 -306.228416) (xy 199.1762 -306.288872) (xy 199.153202 -306.346901) (xy 199.123105 -306.401587)
			(xy 199.086385 -306.452064) (xy 199.043622 -306.497535) (xy 198.995492 -306.537282) (xy 198.969376 -306.554378)
			(xy 198.959216 -306.560728) (xy 198.947024 -306.58054) (xy 198.937372 -306.68468) (xy 198.945754 -306.706524)
			(xy 198.954644 -306.714652) (xy 198.972978 -306.732161) (xy 199.005122 -306.771364) (xy 199.031595 -306.814599)
			(xy 199.051898 -306.861053) (xy 199.065649 -306.909849) (xy 199.072589 -306.960068) (xy 199.073008 -306.985416)
			(xy 199.072608 -307.010734) (xy 199.065679 -307.060894) (xy 199.051953 -307.109634) (xy 199.031689 -307.156039)
			(xy 199.005267 -307.199235) (xy 198.973184 -307.23841) (xy 198.954898 -307.255926) (xy 198.946008 -307.264308)
			(xy 198.937626 -307.285898) (xy 198.947024 -307.390038) (xy 198.959216 -307.40985) (xy 198.969376 -307.416454)
			(xy 198.995501 -307.43351) (xy 199.043618 -307.473228) (xy 199.086372 -307.518671) (xy 199.123085 -307.569119)
			(xy 199.153177 -307.623776) (xy 199.176172 -307.681776) (xy 199.191707 -307.742204) (xy 199.199537 -307.804104)
			(xy 199.200008 -307.8353) (xy 199.199504 -307.866508) (xy 199.191685 -307.928434) (xy 199.176158 -307.988888)
			(xy 199.153169 -308.046917) (xy 199.12308 -308.101603) (xy 199.086368 -308.152081) (xy 199.043612 -308.197554)
			(xy 198.995489 -308.237303) (xy 198.969376 -308.2544) (xy 198.959216 -308.26075) (xy 198.947024 -308.280562)
			(xy 198.937372 -308.384702) (xy 198.945754 -308.406546) (xy 198.954644 -308.414674) (xy 198.97294 -308.43222)
			(xy 199.005088 -308.471416) (xy 199.031565 -308.514643) (xy 199.051875 -308.561089) (xy 199.065634 -308.609878)
			(xy 199.072584 -308.660092) (xy 199.073008 -308.685438) (xy 199.072556 -308.710754) (xy 199.065637 -308.760912)
			(xy 199.051921 -308.809651) (xy 199.031667 -308.856056) (xy 199.005254 -308.899253) (xy 198.97318 -308.93843)
			(xy 198.954898 -308.955948) (xy 198.946008 -308.96433) (xy 198.937626 -308.98592) (xy 198.947024 -309.09006)
			(xy 198.959216 -309.109872) (xy 198.969376 -309.116476) (xy 198.995512 -309.13352) (xy 199.043646 -309.173229)
			(xy 199.086414 -309.218666) (xy 199.12314 -309.269112) (xy 199.153243 -309.32377) (xy 199.176247 -309.381774)
			(xy 199.191787 -309.442207) (xy 199.199619 -309.504112) (xy 199.199617 -309.566511) (xy 199.191783 -309.628417)
			(xy 199.17624 -309.688849) (xy 199.153233 -309.746852) (xy 199.123127 -309.801508) (xy 199.086399 -309.851952)
			(xy 199.043629 -309.897387) (xy 198.995493 -309.937094) (xy 198.969376 -309.954168) (xy 198.959216 -309.960772)
			(xy 198.947024 -309.980584) (xy 198.937626 -310.084724) (xy 198.946008 -310.106314) (xy 198.954898 -310.114696)
			(xy 198.97318 -310.132215) (xy 199.00526 -310.17139) (xy 199.031679 -310.214586) (xy 199.051941 -310.26099)
			(xy 199.065664 -310.30973) (xy 199.07259 -310.359889) (xy 199.073008 -310.385206) (xy 199.072578 -310.410554)
			(xy 199.065645 -310.460773) (xy 199.051897 -310.509569) (xy 199.031593 -310.556021) (xy 199.005117 -310.599253)
			(xy 198.972967 -310.63845) (xy 198.954644 -310.65597) (xy 198.945754 -310.664098) (xy 198.937372 -310.685942)
			(xy 198.947024 -310.790082) (xy 198.959216 -310.809894) (xy 198.969376 -310.816244) (xy 198.995463 -310.833379)
			(xy 199.043586 -310.873125) (xy 199.086344 -310.918593) (xy 199.123061 -310.969066) (xy 199.153157 -311.023745)
			(xy 199.176157 -311.081767) (xy 199.191698 -311.142216) (xy 199.199533 -311.204137) (xy 199.200008 -311.235344)
			(xy 199.199519 -311.266507) (xy 199.191707 -311.328341) (xy 199.176207 -311.388709) (xy 199.153264 -311.446657)
			(xy 199.123238 -311.501274) (xy 199.086604 -311.551696) (xy 199.043939 -311.59713) (xy 198.995917 -311.636858)
			(xy 198.943293 -311.670253) (xy 198.886899 -311.69679) (xy 198.827624 -311.71605) (xy 198.766403 -311.727729)
			(xy 198.7042 -311.731642) (xy 198.641997 -311.727729) (xy 198.580776 -311.71605) (xy 198.521501 -311.69679)
			(xy 198.465107 -311.670253) (xy 198.412483 -311.636858) (xy 198.364461 -311.59713) (xy 198.321796 -311.551696)
			(xy 198.285162 -311.501274) (xy 198.255136 -311.446657) (xy 198.232193 -311.388709) (xy 198.216693 -311.328341)
			(xy 198.208881 -311.266507) (xy 198.208392 -311.235344) (xy 194.97294 -311.235344) (xy 194.972513 -311.260661)
			(xy 194.965592 -311.310821) (xy 194.951873 -311.359561) (xy 194.931614 -311.405966) (xy 194.905195 -311.449163)
			(xy 194.873115 -311.488338) (xy 194.85483 -311.505854) (xy 194.84594 -311.514236) (xy 194.837558 -311.535826)
			(xy 194.846956 -311.639966) (xy 194.859148 -311.659778) (xy 194.869308 -311.666382) (xy 194.895407 -311.683475)
			(xy 194.943524 -311.723189) (xy 194.986277 -311.768627) (xy 195.022991 -311.81907) (xy 195.053086 -311.873721)
			(xy 195.076086 -311.931716) (xy 195.091627 -311.992138) (xy 195.099465 -312.054033) (xy 195.09994 -312.085228)
			(xy 196.950599 -312.085228) (xy 196.954534 -312.031457) (xy 196.966257 -311.978833) (xy 196.985517 -311.928476)
			(xy 197.011903 -311.881459) (xy 197.044855 -311.838786) (xy 197.083668 -311.801365) (xy 197.127516 -311.769995)
			(xy 197.175464 -311.745343) (xy 197.226491 -311.727935) (xy 197.279509 -311.718142) (xy 197.333388 -311.716173)
			(xy 197.386979 -311.72207) (xy 197.43914 -311.735706) (xy 197.48876 -311.756793) (xy 197.534781 -311.784879)
			(xy 197.576223 -311.819367) (xy 197.612201 -311.859521) (xy 197.641949 -311.904485) (xy 197.664834 -311.953302)
			(xy 197.680366 -312.004931) (xy 197.688216 -312.058271) (xy 197.688708 -312.085228) (xy 201.652124 -312.085228)
			(xy 201.652571 -312.05403) (xy 201.660391 -311.992126) (xy 201.675921 -311.931695) (xy 201.698918 -311.873691)
			(xy 201.729016 -311.819035) (xy 201.765739 -311.768591) (xy 201.808506 -311.723157) (xy 201.856639 -311.683454)
			(xy 201.882756 -311.666382) (xy 201.892916 -311.659778) (xy 201.905108 -311.639966) (xy 201.914506 -311.535826)
			(xy 201.906124 -311.514236) (xy 201.897234 -311.505854) (xy 201.878963 -311.488324) (xy 201.846885 -311.449149)
			(xy 201.820466 -311.405955) (xy 201.800203 -311.359554) (xy 201.786476 -311.310817) (xy 201.779545 -311.26066)
			(xy 201.779124 -311.235344) (xy 201.779511 -311.209995) (xy 201.786451 -311.159773) (xy 201.800207 -311.110976)
			(xy 201.820519 -311.064524) (xy 201.847003 -311.021293) (xy 201.879162 -310.982099) (xy 201.897488 -310.96458)
			(xy 201.906378 -310.956452) (xy 201.91476 -310.934608) (xy 201.905108 -310.830468) (xy 201.892916 -310.810656)
			(xy 201.882756 -310.804306) (xy 201.85663 -310.787228) (xy 201.80851 -310.747472) (xy 201.765756 -310.701994)
			(xy 201.729044 -310.651513) (xy 201.698953 -310.596826) (xy 201.675959 -310.538796) (xy 201.660424 -310.478341)
			(xy 201.652595 -310.416415) (xy 201.652124 -310.385206) (xy 201.652554 -310.354008) (xy 201.660376 -310.292103)
			(xy 201.675909 -310.231671) (xy 201.698908 -310.173668) (xy 201.729009 -310.119011) (xy 201.765734 -310.068567)
			(xy 201.808503 -310.023134) (xy 201.856638 -309.983431) (xy 201.882756 -309.96636) (xy 201.892916 -309.959756)
			(xy 201.905108 -309.939944) (xy 201.914506 -309.835804) (xy 201.906124 -309.814214) (xy 201.897234 -309.805832)
			(xy 201.877329 -309.786674) (xy 201.842861 -309.743504) (xy 201.815218 -309.695675) (xy 201.795018 -309.644258)
			(xy 201.782713 -309.590403) (xy 201.77858 -309.535315) (xy 201.782709 -309.480227) (xy 201.795009 -309.426371)
			(xy 201.815205 -309.374952) (xy 201.842844 -309.327121) (xy 201.877309 -309.283948) (xy 201.897234 -309.264812)
			(xy 201.906124 -309.25643) (xy 201.914506 -309.23484) (xy 201.905108 -309.1307) (xy 201.892916 -309.110888)
			(xy 201.882756 -309.104284) (xy 201.856656 -309.087191) (xy 201.808537 -309.047479) (xy 201.765781 -309.002043)
			(xy 201.729066 -308.9516) (xy 201.69897 -308.896949) (xy 201.675971 -308.838953) (xy 201.660432 -308.778529)
			(xy 201.652597 -308.716633) (xy 201.652124 -308.685438) (xy 201.652565 -308.654227) (xy 201.660392 -308.592299)
			(xy 201.675927 -308.531842) (xy 201.698925 -308.473813) (xy 201.729023 -308.419127) (xy 201.765744 -308.36865)
			(xy 201.808508 -308.323179) (xy 201.856639 -308.283433) (xy 201.882756 -308.266338) (xy 201.892916 -308.259988)
			(xy 201.905108 -308.240176) (xy 201.91476 -308.136036) (xy 201.906378 -308.114192) (xy 201.897488 -308.106064)
			(xy 201.879149 -308.088561) (xy 201.847008 -308.049355) (xy 201.820537 -308.006118) (xy 201.800236 -307.959664)
			(xy 201.786485 -307.910868) (xy 201.779544 -307.860648) (xy 201.779124 -307.8353) (xy 201.779524 -307.809982)
			(xy 201.786452 -307.759822) (xy 201.800177 -307.711081) (xy 201.820441 -307.664676) (xy 201.846864 -307.62148)
			(xy 201.878948 -307.582306) (xy 201.897234 -307.56479) (xy 201.906124 -307.556408) (xy 201.914506 -307.534818)
			(xy 201.905108 -307.430678) (xy 201.892916 -307.410866) (xy 201.882756 -307.404262) (xy 201.856646 -307.387184)
			(xy 201.808527 -307.34747) (xy 201.765772 -307.302031) (xy 201.729057 -307.251587) (xy 201.698963 -307.196933)
			(xy 201.675965 -307.138935) (xy 201.660428 -307.078509) (xy 201.652596 -307.016612) (xy 201.652124 -306.985416)
			(xy 201.652613 -306.954253) (xy 201.660425 -306.892419) (xy 201.675925 -306.832051) (xy 201.698868 -306.774103)
			(xy 201.728894 -306.719486) (xy 201.765528 -306.669064) (xy 201.808193 -306.62363) (xy 201.856215 -306.583902)
			(xy 201.908839 -306.550507) (xy 201.965233 -306.52397) (xy 202.024508 -306.50471) (xy 202.085729 -306.493031)
			(xy 202.147932 -306.489118) (xy 202.210135 -306.493031) (xy 202.271356 -306.50471) (xy 202.330631 -306.52397)
			(xy 202.387025 -306.550507) (xy 202.439649 -306.583902) (xy 202.487671 -306.62363) (xy 202.530336 -306.669064)
			(xy 202.56697 -306.719486) (xy 202.596996 -306.774103) (xy 202.619939 -306.832051) (xy 202.635439 -306.892419)
			(xy 202.643251 -306.954253) (xy 202.64374 -306.985416) (xy 202.643297 -307.016614) (xy 202.635474 -307.078517)
			(xy 202.61994 -307.138947) (xy 202.596942 -307.196949) (xy 202.566843 -307.251605) (xy 202.530121 -307.302049)
			(xy 202.487355 -307.347484) (xy 202.439224 -307.387189) (xy 202.413108 -307.404262) (xy 202.402948 -307.410866)
			(xy 202.390756 -307.430678) (xy 202.381358 -307.534818) (xy 202.38974 -307.556408) (xy 202.39863 -307.56479)
			(xy 202.416915 -307.582305) (xy 202.448994 -307.621483) (xy 202.475412 -307.664679) (xy 202.495673 -307.711084)
			(xy 202.509395 -307.759824) (xy 202.516322 -307.809983) (xy 202.51674 -307.8353) (xy 202.516296 -307.860647)
			(xy 202.509364 -307.910865) (xy 202.495618 -307.95966) (xy 202.475317 -308.006112) (xy 202.448844 -308.049345)
			(xy 202.416697 -308.088543) (xy 202.398376 -308.106064) (xy 202.389486 -308.114192) (xy 202.381104 -308.136036)
			(xy 202.390756 -308.240176) (xy 202.402948 -308.259988) (xy 202.413108 -308.266338) (xy 202.4392 -308.283466)
			(xy 202.487322 -308.323214) (xy 202.530078 -308.368684) (xy 202.566794 -308.419158) (xy 202.596889 -308.473838)
			(xy 202.619889 -308.53186) (xy 202.635429 -308.59231) (xy 202.643265 -308.654231) (xy 202.64374 -308.685438)
			(xy 202.643236 -308.716634) (xy 202.635423 -308.778534) (xy 202.619898 -308.838963) (xy 202.596909 -308.896965)
			(xy 202.566819 -308.951621) (xy 202.530104 -309.002066) (xy 202.487346 -309.047502) (xy 202.439221 -309.08721)
			(xy 202.413108 -309.104284) (xy 202.402948 -309.110888) (xy 202.390756 -309.1307) (xy 202.381358 -309.23484)
			(xy 202.38974 -309.25643) (xy 202.39863 -309.264812) (xy 202.418576 -309.283927) (xy 202.453038 -309.327106)
			(xy 202.480675 -309.374942) (xy 202.500868 -309.426365) (xy 202.513167 -309.480224) (xy 202.517296 -309.535315)
			(xy 202.513163 -309.590406) (xy 202.50086 -309.644264) (xy 202.480662 -309.695685) (xy 202.453021 -309.743518)
			(xy 202.418555 -309.786695) (xy 202.39863 -309.805832) (xy 202.38974 -309.814214) (xy 202.381358 -309.835804)
			(xy 202.390756 -309.939944) (xy 202.402948 -309.959756) (xy 202.413108 -309.96636) (xy 202.439243 -309.983401)
			(xy 202.487359 -310.023123) (xy 202.530111 -310.068568) (xy 202.566822 -310.119019) (xy 202.596913 -310.173677)
			(xy 202.619907 -310.231679) (xy 202.635441 -310.292108) (xy 202.643269 -310.354009) (xy 202.64374 -310.385206)
			(xy 202.643226 -310.416414) (xy 202.635407 -310.478338) (xy 202.61988 -310.538792) (xy 202.596892 -310.59682)
			(xy 202.566805 -310.651505) (xy 202.530094 -310.701984) (xy 202.487341 -310.747458) (xy 202.43922 -310.787208)
			(xy 202.413108 -310.804306) (xy 202.402948 -310.810656) (xy 202.390756 -310.830468) (xy 202.381104 -310.934608)
			(xy 202.389486 -310.956452) (xy 202.398376 -310.96458) (xy 202.416681 -310.982117) (xy 202.448827 -311.021315)
			(xy 202.475302 -311.064545) (xy 202.49561 -311.110992) (xy 202.509368 -311.159783) (xy 202.516316 -311.209998)
			(xy 202.51674 -311.235344) (xy 205.752192 -311.235344) (xy 205.752652 -311.204134) (xy 205.760478 -311.142207)
			(xy 205.776012 -311.081752) (xy 205.799007 -311.023722) (xy 205.829102 -310.969037) (xy 205.86582 -310.918559)
			(xy 205.908581 -310.873088) (xy 205.956709 -310.83334) (xy 205.982824 -310.816244) (xy 205.992984 -310.809894)
			(xy 206.005176 -310.790082) (xy 206.014828 -310.685942) (xy 206.006446 -310.664098) (xy 205.997556 -310.65597)
			(xy 205.979232 -310.638451) (xy 205.947088 -310.59925) (xy 205.920613 -310.556016) (xy 205.900308 -310.509565)
			(xy 205.886555 -310.460771) (xy 205.879613 -310.410554) (xy 205.879192 -310.385206) (xy 205.879607 -310.359888)
			(xy 205.886533 -310.309729) (xy 205.900256 -310.260989) (xy 205.920517 -310.214585) (xy 205.946937 -310.171388)
			(xy 205.979017 -310.132212) (xy 205.997302 -310.114696) (xy 206.006192 -310.106314) (xy 206.014574 -310.084724)
			(xy 206.005176 -309.980584) (xy 205.992984 -309.960772) (xy 205.982824 -309.954168) (xy 205.956729 -309.937064)
			(xy 205.908597 -309.89736) (xy 205.86583 -309.851929) (xy 205.829104 -309.801488) (xy 205.799001 -309.746836)
			(xy 205.775996 -309.688837) (xy 205.760453 -309.62841) (xy 205.75262 -309.566509) (xy 205.752618 -309.504115)
			(xy 205.760449 -309.442214) (xy 205.775988 -309.381785) (xy 205.798991 -309.323786) (xy 205.829091 -309.269132)
			(xy 205.865815 -309.21869) (xy 205.90858 -309.173256) (xy 205.95671 -309.13355) (xy 205.982824 -309.116476)
			(xy 205.992984 -309.109872) (xy 206.005176 -309.09006) (xy 206.014574 -308.98592) (xy 206.006192 -308.96433)
			(xy 205.997302 -308.955948) (xy 205.979041 -308.938408) (xy 205.946959 -308.899237) (xy 205.920537 -308.856045)
			(xy 205.900272 -308.809646) (xy 205.886544 -308.76091) (xy 205.879613 -308.710754) (xy 205.879192 -308.685438)
			(xy 205.879585 -308.660089) (xy 205.886525 -308.609868) (xy 205.900281 -308.561072) (xy 205.920591 -308.51462)
			(xy 205.947075 -308.471389) (xy 205.979231 -308.432193) (xy 205.997556 -308.414674) (xy 206.006446 -308.406546)
			(xy 206.014828 -308.384702) (xy 206.005176 -308.280562) (xy 205.992984 -308.26075) (xy 205.982824 -308.2544)
			(xy 205.956711 -308.237302) (xy 205.908588 -308.197551) (xy 205.865832 -308.152077) (xy 205.829117 -308.101599)
			(xy 205.799024 -308.046915) (xy 205.776028 -307.988887) (xy 205.760493 -307.928434) (xy 205.752663 -307.866509)
			(xy 205.752192 -307.8353) (xy 205.752632 -307.804102) (xy 205.760454 -307.742199) (xy 205.775987 -307.681767)
			(xy 205.798985 -307.623764) (xy 205.829084 -307.569108) (xy 205.865808 -307.518664) (xy 205.908575 -307.473231)
			(xy 205.956708 -307.433526) (xy 205.982824 -307.416454) (xy 205.992984 -307.40985) (xy 206.005176 -307.390038)
			(xy 206.014574 -307.285898) (xy 206.006192 -307.264308) (xy 205.997302 -307.255926) (xy 205.979031 -307.238397)
			(xy 205.946949 -307.199223) (xy 205.920529 -307.15603) (xy 205.900265 -307.109628) (xy 205.88654 -307.06089)
			(xy 205.879611 -307.010733) (xy 205.879192 -306.985416) (xy 205.879637 -306.960069) (xy 205.886567 -306.90985)
			(xy 205.900312 -306.861055) (xy 205.920613 -306.814603) (xy 205.947087 -306.77137) (xy 205.979235 -306.732173)
			(xy 205.997556 -306.714652) (xy 206.006446 -306.706524) (xy 206.014828 -306.68468) (xy 206.005176 -306.58054)
			(xy 205.992984 -306.560728) (xy 205.982824 -306.554378) (xy 205.956701 -306.537295) (xy 205.908578 -306.497542)
			(xy 205.865822 -306.452066) (xy 205.829108 -306.401586) (xy 205.799016 -306.346899) (xy 205.776022 -306.288869)
			(xy 205.760489 -306.228414) (xy 205.752662 -306.166488) (xy 205.752192 -306.135278) (xy 205.752681 -306.104115)
			(xy 205.760493 -306.042281) (xy 205.775993 -305.981913) (xy 205.798936 -305.923965) (xy 205.828962 -305.869348)
			(xy 205.865596 -305.818926) (xy 205.908261 -305.773492) (xy 205.956283 -305.733764) (xy 206.008907 -305.700369)
			(xy 206.065301 -305.673832) (xy 206.124576 -305.654572) (xy 206.185797 -305.642893) (xy 206.248 -305.63898)
			(xy 206.310203 -305.642893) (xy 206.371424 -305.654572) (xy 206.430699 -305.673832) (xy 206.487093 -305.700369)
			(xy 206.539717 -305.733764) (xy 206.587739 -305.773492) (xy 206.630404 -305.818926) (xy 206.667038 -305.869348)
			(xy 206.697064 -305.923965) (xy 206.720007 -305.981913) (xy 206.735507 -306.042281) (xy 206.743319 -306.104115)
			(xy 206.743808 -306.135278) (xy 206.743365 -306.166488) (xy 206.735537 -306.228416) (xy 206.72 -306.288872)
			(xy 206.697002 -306.346901) (xy 206.666905 -306.401587) (xy 206.630185 -306.452064) (xy 206.587422 -306.497535)
			(xy 206.539292 -306.537282) (xy 206.513176 -306.554378) (xy 206.503016 -306.560728) (xy 206.490824 -306.58054)
			(xy 206.481172 -306.68468) (xy 206.489554 -306.706524) (xy 206.498444 -306.714652) (xy 206.516778 -306.732161)
			(xy 206.548922 -306.771364) (xy 206.575395 -306.814599) (xy 206.595698 -306.861053) (xy 206.609449 -306.909849)
			(xy 206.616389 -306.960068) (xy 206.616808 -306.985416) (xy 206.616408 -307.010734) (xy 206.609479 -307.060894)
			(xy 206.595753 -307.109634) (xy 206.575489 -307.156039) (xy 206.549067 -307.199235) (xy 206.516984 -307.23841)
			(xy 206.498698 -307.255926) (xy 206.489808 -307.264308) (xy 206.481426 -307.285898) (xy 206.490824 -307.390038)
			(xy 206.503016 -307.40985) (xy 206.513176 -307.416454) (xy 206.539301 -307.43351) (xy 206.587418 -307.473228)
			(xy 206.630172 -307.518671) (xy 206.666885 -307.569119) (xy 206.696977 -307.623776) (xy 206.719972 -307.681776)
			(xy 206.735507 -307.742204) (xy 206.743337 -307.804104) (xy 206.743808 -307.8353) (xy 206.743304 -307.866508)
			(xy 206.735485 -307.928434) (xy 206.719958 -307.988888) (xy 206.696969 -308.046917) (xy 206.66688 -308.101603)
			(xy 206.630168 -308.152081) (xy 206.587412 -308.197554) (xy 206.539289 -308.237303) (xy 206.513176 -308.2544)
			(xy 206.503016 -308.26075) (xy 206.490824 -308.280562) (xy 206.481172 -308.384702) (xy 206.489554 -308.406546)
			(xy 206.498444 -308.414674) (xy 206.51674 -308.43222) (xy 206.548888 -308.471416) (xy 206.575365 -308.514643)
			(xy 206.595675 -308.561089) (xy 206.609434 -308.609878) (xy 206.616384 -308.660092) (xy 206.616808 -308.685438)
			(xy 206.616356 -308.710754) (xy 206.609437 -308.760912) (xy 206.595721 -308.809651) (xy 206.575467 -308.856056)
			(xy 206.549054 -308.899253) (xy 206.51698 -308.93843) (xy 206.498698 -308.955948) (xy 206.489808 -308.96433)
			(xy 206.481426 -308.98592) (xy 206.490824 -309.09006) (xy 206.503016 -309.109872) (xy 206.513176 -309.116476)
			(xy 206.539312 -309.13352) (xy 206.587446 -309.173229) (xy 206.630214 -309.218666) (xy 206.66694 -309.269112)
			(xy 206.697043 -309.32377) (xy 206.720047 -309.381774) (xy 206.735587 -309.442207) (xy 206.743419 -309.504112)
			(xy 206.743417 -309.566511) (xy 206.735583 -309.628417) (xy 206.72004 -309.688849) (xy 206.697033 -309.746852)
			(xy 206.666927 -309.801508) (xy 206.630199 -309.851952) (xy 206.587429 -309.897387) (xy 206.539293 -309.937094)
			(xy 206.513176 -309.954168) (xy 206.503016 -309.960772) (xy 206.490824 -309.980584) (xy 206.481426 -310.084724)
			(xy 206.489808 -310.106314) (xy 206.498698 -310.114696) (xy 206.51698 -310.132215) (xy 206.54906 -310.17139)
			(xy 206.575479 -310.214586) (xy 206.595741 -310.26099) (xy 206.609464 -310.30973) (xy 206.61639 -310.359889)
			(xy 206.616808 -310.385206) (xy 206.616378 -310.410554) (xy 206.609445 -310.460773) (xy 206.595697 -310.509569)
			(xy 206.575393 -310.556021) (xy 206.548917 -310.599253) (xy 206.516767 -310.63845) (xy 206.498444 -310.65597)
			(xy 206.489554 -310.664098) (xy 206.481172 -310.685942) (xy 206.490824 -310.790082) (xy 206.503016 -310.809894)
			(xy 206.513176 -310.816244) (xy 206.539263 -310.833379) (xy 206.587386 -310.873125) (xy 206.630144 -310.918593)
			(xy 206.666861 -310.969066) (xy 206.696957 -311.023745) (xy 206.719957 -311.081767) (xy 206.735498 -311.142216)
			(xy 206.743333 -311.204137) (xy 206.743808 -311.235344) (xy 206.743319 -311.266507) (xy 206.735507 -311.328341)
			(xy 206.720007 -311.388709) (xy 206.697064 -311.446657) (xy 206.667038 -311.501274) (xy 206.630404 -311.551696)
			(xy 206.587739 -311.59713) (xy 206.539717 -311.636858) (xy 206.487093 -311.670253) (xy 206.430699 -311.69679)
			(xy 206.371424 -311.71605) (xy 206.310203 -311.727729) (xy 206.248 -311.731642) (xy 206.185797 -311.727729)
			(xy 206.124576 -311.71605) (xy 206.065301 -311.69679) (xy 206.008907 -311.670253) (xy 205.956283 -311.636858)
			(xy 205.908261 -311.59713) (xy 205.865596 -311.551696) (xy 205.828962 -311.501274) (xy 205.798936 -311.446657)
			(xy 205.775993 -311.388709) (xy 205.760493 -311.328341) (xy 205.752681 -311.266507) (xy 205.752192 -311.235344)
			(xy 202.51674 -311.235344) (xy 202.516313 -311.260661) (xy 202.509392 -311.310821) (xy 202.495673 -311.359561)
			(xy 202.475414 -311.405966) (xy 202.448995 -311.449163) (xy 202.416915 -311.488338) (xy 202.39863 -311.505854)
			(xy 202.38974 -311.514236) (xy 202.381358 -311.535826) (xy 202.390756 -311.639966) (xy 202.402948 -311.659778)
			(xy 202.413108 -311.666382) (xy 202.439207 -311.683475) (xy 202.487324 -311.723189) (xy 202.530077 -311.768627)
			(xy 202.566791 -311.81907) (xy 202.596886 -311.873721) (xy 202.619886 -311.931716) (xy 202.635427 -311.992138)
			(xy 202.643265 -312.054033) (xy 202.64374 -312.085228) (xy 204.494399 -312.085228) (xy 204.498334 -312.031457)
			(xy 204.510057 -311.978833) (xy 204.529317 -311.928476) (xy 204.555703 -311.881459) (xy 204.588655 -311.838786)
			(xy 204.627468 -311.801365) (xy 204.671316 -311.769995) (xy 204.719264 -311.745343) (xy 204.770291 -311.727935)
			(xy 204.823309 -311.718142) (xy 204.877188 -311.716173) (xy 204.930779 -311.72207) (xy 204.98294 -311.735706)
			(xy 205.03256 -311.756793) (xy 205.078581 -311.784879) (xy 205.120023 -311.819367) (xy 205.156001 -311.859521)
			(xy 205.185749 -311.904485) (xy 205.208634 -311.953302) (xy 205.224166 -312.004931) (xy 205.232016 -312.058271)
			(xy 205.232508 -312.085228) (xy 205.232016 -312.112185) (xy 205.224166 -312.165525) (xy 205.208634 -312.217154)
			(xy 205.185749 -312.265971) (xy 205.156001 -312.310935) (xy 205.120023 -312.351089) (xy 205.078581 -312.385577)
			(xy 205.03256 -312.413663) (xy 204.98294 -312.43475) (xy 204.930779 -312.448386) (xy 204.877188 -312.454283)
			(xy 204.823309 -312.452314) (xy 204.770291 -312.442521) (xy 204.719264 -312.425113) (xy 204.671316 -312.400461)
			(xy 204.627468 -312.369091) (xy 204.588655 -312.33167) (xy 204.555703 -312.288997) (xy 204.529317 -312.24198)
			(xy 204.510057 -312.191623) (xy 204.498334 -312.138999) (xy 204.494399 -312.085228) (xy 202.64374 -312.085228)
			(xy 202.643251 -312.116391) (xy 202.635439 -312.178225) (xy 202.619939 -312.238593) (xy 202.596996 -312.296541)
			(xy 202.56697 -312.351158) (xy 202.530336 -312.40158) (xy 202.487671 -312.447014) (xy 202.439649 -312.486742)
			(xy 202.387025 -312.520137) (xy 202.330631 -312.546674) (xy 202.271356 -312.565934) (xy 202.210135 -312.577613)
			(xy 202.147932 -312.581526) (xy 202.085729 -312.577613) (xy 202.024508 -312.565934) (xy 201.965233 -312.546674)
			(xy 201.908839 -312.520137) (xy 201.856215 -312.486742) (xy 201.808193 -312.447014) (xy 201.765528 -312.40158)
			(xy 201.728894 -312.351158) (xy 201.698868 -312.296541) (xy 201.675925 -312.238593) (xy 201.660425 -312.178225)
			(xy 201.652613 -312.116391) (xy 201.652124 -312.085228) (xy 197.688708 -312.085228) (xy 197.688216 -312.112185)
			(xy 197.680366 -312.165525) (xy 197.664834 -312.217154) (xy 197.641949 -312.265971) (xy 197.612201 -312.310935)
			(xy 197.576223 -312.351089) (xy 197.534781 -312.385577) (xy 197.48876 -312.413663) (xy 197.43914 -312.43475)
			(xy 197.386979 -312.448386) (xy 197.333388 -312.454283) (xy 197.279509 -312.452314) (xy 197.226491 -312.442521)
			(xy 197.175464 -312.425113) (xy 197.127516 -312.400461) (xy 197.083668 -312.369091) (xy 197.044855 -312.33167)
			(xy 197.011903 -312.288997) (xy 196.985517 -312.24198) (xy 196.966257 -312.191623) (xy 196.954534 -312.138999)
			(xy 196.950599 -312.085228) (xy 195.09994 -312.085228) (xy 195.099451 -312.116391) (xy 195.091639 -312.178225)
			(xy 195.076139 -312.238593) (xy 195.053196 -312.296541) (xy 195.02317 -312.351158) (xy 194.986536 -312.40158)
			(xy 194.943871 -312.447014) (xy 194.895849 -312.486742) (xy 194.843225 -312.520137) (xy 194.786831 -312.546674)
			(xy 194.727556 -312.565934) (xy 194.666335 -312.577613) (xy 194.604132 -312.581526) (xy 194.541929 -312.577613)
			(xy 194.480708 -312.565934) (xy 194.421433 -312.546674) (xy 194.365039 -312.520137) (xy 194.312415 -312.486742)
			(xy 194.264393 -312.447014) (xy 194.221728 -312.40158) (xy 194.185094 -312.351158) (xy 194.155068 -312.296541)
			(xy 194.132125 -312.238593) (xy 194.116625 -312.178225) (xy 194.108813 -312.116391) (xy 194.108324 -312.085228)
			(xy 190.144654 -312.085228) (xy 190.144162 -312.112185) (xy 190.136312 -312.165525) (xy 190.12078 -312.217154)
			(xy 190.097895 -312.265971) (xy 190.068147 -312.310935) (xy 190.032169 -312.351089) (xy 189.990727 -312.385577)
			(xy 189.944706 -312.413663) (xy 189.895086 -312.43475) (xy 189.842925 -312.448386) (xy 189.789334 -312.454283)
			(xy 189.735455 -312.452314) (xy 189.682437 -312.442521) (xy 189.63141 -312.425113) (xy 189.583462 -312.400461)
			(xy 189.539614 -312.369091) (xy 189.500801 -312.33167) (xy 189.467849 -312.288997) (xy 189.441463 -312.24198)
			(xy 189.422203 -312.191623) (xy 189.41048 -312.138999) (xy 189.406545 -312.085228) (xy 187.555886 -312.085228)
			(xy 187.555397 -312.116391) (xy 187.547585 -312.178225) (xy 187.532085 -312.238593) (xy 187.509142 -312.296541)
			(xy 187.479116 -312.351158) (xy 187.442482 -312.40158) (xy 187.399817 -312.447014) (xy 187.351795 -312.486742)
			(xy 187.299171 -312.520137) (xy 187.242777 -312.546674) (xy 187.183502 -312.565934) (xy 187.122281 -312.577613)
			(xy 187.060078 -312.581526) (xy 186.997875 -312.577613) (xy 186.936654 -312.565934) (xy 186.877379 -312.546674)
			(xy 186.820985 -312.520137) (xy 186.768361 -312.486742) (xy 186.720339 -312.447014) (xy 186.677674 -312.40158)
			(xy 186.64104 -312.351158) (xy 186.611014 -312.296541) (xy 186.588071 -312.238593) (xy 186.572571 -312.178225)
			(xy 186.564759 -312.116391) (xy 186.56427 -312.085228) (xy 185.96864 -312.085228) (xy 185.96864 -312.935366)
			(xy 188.075077 -312.935366) (xy 188.079012 -312.881595) (xy 188.090735 -312.828971) (xy 188.109995 -312.778614)
			(xy 188.136381 -312.731597) (xy 188.169333 -312.688924) (xy 188.208146 -312.651503) (xy 188.251994 -312.620133)
			(xy 188.299942 -312.595481) (xy 188.350969 -312.578073) (xy 188.403987 -312.56828) (xy 188.457866 -312.566311)
			(xy 188.511457 -312.572208) (xy 188.563618 -312.585844) (xy 188.613238 -312.606931) (xy 188.659259 -312.635017)
			(xy 188.700701 -312.669505) (xy 188.736679 -312.709659) (xy 188.766427 -312.754623) (xy 188.789312 -312.80344)
			(xy 188.804844 -312.855069) (xy 188.812694 -312.908409) (xy 188.813186 -312.935366) (xy 188.812694 -312.962323)
			(xy 188.804844 -313.015663) (xy 188.789312 -313.067292) (xy 188.766427 -313.116109) (xy 188.736679 -313.161073)
			(xy 188.700701 -313.201227) (xy 188.659259 -313.235715) (xy 188.613238 -313.263801) (xy 188.563618 -313.284888)
			(xy 188.511457 -313.298524) (xy 188.457866 -313.304421) (xy 188.403987 -313.302452) (xy 188.350969 -313.292659)
			(xy 188.299942 -313.275251) (xy 188.251994 -313.250599) (xy 188.208146 -313.219229) (xy 188.169333 -313.181808)
			(xy 188.136381 -313.139135) (xy 188.109995 -313.092118) (xy 188.090735 -313.041761) (xy 188.079012 -312.989137)
			(xy 188.075077 -312.935366) (xy 185.96864 -312.935366) (xy 185.96864 -314.635388) (xy 186.56427 -314.635388)
			(xy 186.564826 -314.602669) (xy 186.573419 -314.537798) (xy 186.590469 -314.47462) (xy 186.615678 -314.414232)
			(xy 186.648609 -314.357684) (xy 186.688691 -314.305958) (xy 186.71159 -314.282582) (xy 186.718956 -314.27547)
			(xy 186.72683 -314.256674) (xy 186.72683 -314.163964) (xy 186.718956 -314.145168) (xy 186.71159 -314.138056)
			(xy 186.688711 -314.11466) (xy 186.648626 -314.062937) (xy 186.615687 -314.006394) (xy 186.590468 -313.946011)
			(xy 186.573406 -313.882837) (xy 186.564797 -313.817969) (xy 186.56427 -313.78525) (xy 186.564759 -313.754087)
			(xy 186.572571 -313.692253) (xy 186.588071 -313.631885) (xy 186.611014 -313.573937) (xy 186.64104 -313.51932)
			(xy 186.677674 -313.468898) (xy 186.720339 -313.423464) (xy 186.768361 -313.383736) (xy 186.820985 -313.350341)
			(xy 186.877379 -313.323804) (xy 186.936654 -313.304544) (xy 186.997875 -313.292865) (xy 187.060078 -313.288952)
			(xy 187.122281 -313.292865) (xy 187.183502 -313.304544) (xy 187.242777 -313.323804) (xy 187.299171 -313.350341)
			(xy 187.351795 -313.383736) (xy 187.399817 -313.423464) (xy 187.442482 -313.468898) (xy 187.479116 -313.51932)
			(xy 187.509142 -313.573937) (xy 187.532085 -313.631885) (xy 187.547585 -313.692253) (xy 187.555397 -313.754087)
			(xy 187.555886 -313.78525) (xy 190.664338 -313.78525) (xy 190.664876 -313.75255) (xy 190.673484 -313.687719)
			(xy 190.690543 -313.624583) (xy 190.715757 -313.564239) (xy 190.748688 -313.507735) (xy 190.788764 -313.456052)
			(xy 190.811658 -313.432698) (xy 190.819024 -313.425332) (xy 190.826644 -313.40679) (xy 190.826644 -313.313826)
			(xy 190.819024 -313.295284) (xy 190.811658 -313.287918) (xy 190.788752 -313.264574) (xy 190.748668 -313.212894)
			(xy 190.715732 -313.156389) (xy 190.690517 -313.096042) (xy 190.673461 -313.032902) (xy 190.66486 -312.968067)
			(xy 190.664338 -312.935366) (xy 190.664827 -312.904203) (xy 190.672639 -312.842369) (xy 190.688139 -312.782001)
			(xy 190.711082 -312.724053) (xy 190.741108 -312.669436) (xy 190.777742 -312.619014) (xy 190.820407 -312.57358)
			(xy 190.868429 -312.533852) (xy 190.921053 -312.500457) (xy 190.977447 -312.47392) (xy 191.036722 -312.45466)
			(xy 191.097943 -312.442981) (xy 191.160146 -312.439068) (xy 191.222349 -312.442981) (xy 191.28357 -312.45466)
			(xy 191.342845 -312.47392) (xy 191.399239 -312.500457) (xy 191.451863 -312.533852) (xy 191.499885 -312.57358)
			(xy 191.54255 -312.619014) (xy 191.579184 -312.669436) (xy 191.60921 -312.724053) (xy 191.632153 -312.782001)
			(xy 191.647653 -312.842369) (xy 191.655465 -312.904203) (xy 191.655954 -312.935366) (xy 195.619131 -312.935366)
			(xy 195.623066 -312.881595) (xy 195.634789 -312.828971) (xy 195.654049 -312.778614) (xy 195.680435 -312.731597)
			(xy 195.713387 -312.688924) (xy 195.7522 -312.651503) (xy 195.796048 -312.620133) (xy 195.843996 -312.595481)
			(xy 195.895023 -312.578073) (xy 195.948041 -312.56828) (xy 196.00192 -312.566311) (xy 196.055511 -312.572208)
			(xy 196.107672 -312.585844) (xy 196.157292 -312.606931) (xy 196.203313 -312.635017) (xy 196.244755 -312.669505)
			(xy 196.280733 -312.709659) (xy 196.310481 -312.754623) (xy 196.333366 -312.80344) (xy 196.348898 -312.855069)
			(xy 196.356748 -312.908409) (xy 196.35724 -312.935366) (xy 196.356748 -312.962323) (xy 196.348898 -313.015663)
			(xy 196.333366 -313.067292) (xy 196.310481 -313.116109) (xy 196.280733 -313.161073) (xy 196.244755 -313.201227)
			(xy 196.203313 -313.235715) (xy 196.157292 -313.263801) (xy 196.107672 -313.284888) (xy 196.055511 -313.298524)
			(xy 196.00192 -313.304421) (xy 195.948041 -313.302452) (xy 195.895023 -313.292659) (xy 195.843996 -313.275251)
			(xy 195.796048 -313.250599) (xy 195.7522 -313.219229) (xy 195.713387 -313.181808) (xy 195.680435 -313.139135)
			(xy 195.654049 -313.092118) (xy 195.634789 -313.041761) (xy 195.623066 -312.989137) (xy 195.619131 -312.935366)
			(xy 191.655954 -312.935366) (xy 191.655429 -312.968066) (xy 191.646819 -313.032898) (xy 191.629758 -313.096035)
			(xy 191.604541 -313.156379) (xy 191.571608 -313.212882) (xy 191.531529 -313.264564) (xy 191.508634 -313.287918)
			(xy 191.501268 -313.295284) (xy 191.493648 -313.313826) (xy 191.493648 -313.360308) (xy 191.908445 -313.360308)
			(xy 191.91238 -313.306537) (xy 191.924103 -313.253913) (xy 191.943363 -313.203556) (xy 191.969749 -313.156539)
			(xy 192.002701 -313.113866) (xy 192.041514 -313.076445) (xy 192.085362 -313.045075) (xy 192.13331 -313.020423)
			(xy 192.184337 -313.003015) (xy 192.237355 -312.993222) (xy 192.291234 -312.991253) (xy 192.344825 -312.99715)
			(xy 192.396986 -313.010786) (xy 192.446606 -313.031873) (xy 192.492627 -313.059959) (xy 192.534069 -313.094447)
			(xy 192.570047 -313.134601) (xy 192.599795 -313.179565) (xy 192.62268 -313.228382) (xy 192.638212 -313.280011)
			(xy 192.646062 -313.333351) (xy 192.646554 -313.360308) (xy 192.646062 -313.387265) (xy 192.638212 -313.440605)
			(xy 192.62268 -313.492234) (xy 192.599795 -313.541051) (xy 192.570047 -313.586015) (xy 192.534069 -313.626169)
			(xy 192.492627 -313.660657) (xy 192.446606 -313.688743) (xy 192.396986 -313.70983) (xy 192.344825 -313.723466)
			(xy 192.291234 -313.729363) (xy 192.237355 -313.727394) (xy 192.184337 -313.717601) (xy 192.13331 -313.700193)
			(xy 192.085362 -313.675541) (xy 192.041514 -313.644171) (xy 192.002701 -313.60675) (xy 191.969749 -313.564077)
			(xy 191.943363 -313.51706) (xy 191.924103 -313.466703) (xy 191.91238 -313.414079) (xy 191.908445 -313.360308)
			(xy 191.493648 -313.360308) (xy 191.493648 -313.40679) (xy 191.501268 -313.425332) (xy 191.508634 -313.432698)
			(xy 191.531547 -313.456036) (xy 191.57163 -313.507718) (xy 191.604565 -313.564223) (xy 191.629779 -313.624571)
			(xy 191.646834 -313.687712) (xy 191.655433 -313.752548) (xy 191.655954 -313.78525) (xy 191.655465 -313.816413)
			(xy 191.647653 -313.878247) (xy 191.632153 -313.938615) (xy 191.60921 -313.996563) (xy 191.579184 -314.05118)
			(xy 191.54255 -314.101602) (xy 191.499885 -314.147036) (xy 191.451863 -314.186764) (xy 191.399239 -314.220159)
			(xy 191.342845 -314.246696) (xy 191.28357 -314.265956) (xy 191.222349 -314.277635) (xy 191.160146 -314.281548)
			(xy 191.097943 -314.277635) (xy 191.036722 -314.265956) (xy 190.977447 -314.246696) (xy 190.921053 -314.220159)
			(xy 190.868429 -314.186764) (xy 190.820407 -314.147036) (xy 190.777742 -314.101602) (xy 190.741108 -314.05118)
			(xy 190.711082 -313.996563) (xy 190.688139 -313.938615) (xy 190.672639 -313.878247) (xy 190.664827 -313.816413)
			(xy 190.664338 -313.78525) (xy 187.555886 -313.78525) (xy 187.555368 -313.81797) (xy 187.546768 -313.882844)
			(xy 187.529712 -313.946023) (xy 187.504496 -314.00641) (xy 187.471558 -314.062957) (xy 187.431469 -314.114682)
			(xy 187.408566 -314.138056) (xy 187.4012 -314.145168) (xy 187.393326 -314.163964) (xy 187.393326 -314.210446)
			(xy 187.808377 -314.210446) (xy 187.812312 -314.156675) (xy 187.824035 -314.104051) (xy 187.843295 -314.053694)
			(xy 187.869681 -314.006677) (xy 187.902633 -313.964004) (xy 187.941446 -313.926583) (xy 187.985294 -313.895213)
			(xy 188.033242 -313.870561) (xy 188.084269 -313.853153) (xy 188.137287 -313.84336) (xy 188.191166 -313.841391)
			(xy 188.244757 -313.847288) (xy 188.296918 -313.860924) (xy 188.346538 -313.882011) (xy 188.392559 -313.910097)
			(xy 188.434001 -313.944585) (xy 188.469979 -313.984739) (xy 188.499727 -314.029703) (xy 188.522612 -314.07852)
			(xy 188.538144 -314.130149) (xy 188.545994 -314.183489) (xy 188.546486 -314.210446) (xy 188.545994 -314.237403)
			(xy 188.538144 -314.290743) (xy 188.522612 -314.342372) (xy 188.499727 -314.391189) (xy 188.469979 -314.436153)
			(xy 188.434001 -314.476307) (xy 188.392559 -314.510795) (xy 188.346538 -314.538881) (xy 188.296918 -314.559968)
			(xy 188.244757 -314.573604) (xy 188.191166 -314.579501) (xy 188.137287 -314.577532) (xy 188.084269 -314.567739)
			(xy 188.033242 -314.550331) (xy 187.985294 -314.525679) (xy 187.941446 -314.494309) (xy 187.902633 -314.456888)
			(xy 187.869681 -314.414215) (xy 187.843295 -314.367198) (xy 187.824035 -314.316841) (xy 187.812312 -314.264217)
			(xy 187.808377 -314.210446) (xy 187.393326 -314.210446) (xy 187.393326 -314.256674) (xy 187.4012 -314.27547)
			(xy 187.408566 -314.282582) (xy 187.431473 -314.305951) (xy 187.471554 -314.357681) (xy 187.504487 -314.41423)
			(xy 187.529701 -314.474618) (xy 187.546758 -314.537796) (xy 187.555362 -314.602668) (xy 187.555886 -314.635388)
			(xy 189.406545 -314.635388) (xy 189.41048 -314.581617) (xy 189.422203 -314.528993) (xy 189.441463 -314.478636)
			(xy 189.467849 -314.431619) (xy 189.500801 -314.388946) (xy 189.539614 -314.351525) (xy 189.583462 -314.320155)
			(xy 189.63141 -314.295503) (xy 189.682437 -314.278095) (xy 189.735455 -314.268302) (xy 189.789334 -314.266333)
			(xy 189.842925 -314.27223) (xy 189.895086 -314.285866) (xy 189.944706 -314.306953) (xy 189.990727 -314.335039)
			(xy 190.032169 -314.369527) (xy 190.068147 -314.409681) (xy 190.097895 -314.454645) (xy 190.12078 -314.503462)
			(xy 190.136312 -314.555091) (xy 190.144162 -314.608431) (xy 190.144654 -314.635388) (xy 194.108324 -314.635388)
			(xy 194.108864 -314.602668) (xy 194.117458 -314.537796) (xy 194.13451 -314.474617) (xy 194.159722 -314.414229)
			(xy 194.192657 -314.357682) (xy 194.232743 -314.305957) (xy 194.255644 -314.282582) (xy 194.26301 -314.27547)
			(xy 194.270884 -314.256674) (xy 194.270884 -314.163964) (xy 194.26301 -314.145168) (xy 194.255644 -314.138056)
			(xy 194.232757 -314.114668) (xy 194.192673 -314.062943) (xy 194.159737 -314.006398) (xy 194.13452 -313.946013)
			(xy 194.117459 -313.882838) (xy 194.108851 -313.817969) (xy 194.108324 -313.78525) (xy 194.108813 -313.754087)
			(xy 194.116625 -313.692253) (xy 194.132125 -313.631885) (xy 194.155068 -313.573937) (xy 194.185094 -313.51932)
			(xy 194.221728 -313.468898) (xy 194.264393 -313.423464) (xy 194.312415 -313.383736) (xy 194.365039 -313.350341)
			(xy 194.421433 -313.323804) (xy 194.480708 -313.304544) (xy 194.541929 -313.292865) (xy 194.604132 -313.288952)
			(xy 194.666335 -313.292865) (xy 194.727556 -313.304544) (xy 194.786831 -313.323804) (xy 194.843225 -313.350341)
			(xy 194.895849 -313.383736) (xy 194.943871 -313.423464) (xy 194.986536 -313.468898) (xy 195.02317 -313.51932)
			(xy 195.053196 -313.573937) (xy 195.076139 -313.631885) (xy 195.091639 -313.692253) (xy 195.099451 -313.754087)
			(xy 195.09994 -313.78525) (xy 198.208392 -313.78525) (xy 198.208914 -313.752549) (xy 198.217523 -313.687717)
			(xy 198.234584 -313.62458) (xy 198.259801 -313.564236) (xy 198.292735 -313.507732) (xy 198.332816 -313.456051)
			(xy 198.355712 -313.432698) (xy 198.363078 -313.425332) (xy 198.370698 -313.40679) (xy 198.370698 -313.313826)
			(xy 198.363078 -313.295284) (xy 198.355712 -313.287918) (xy 198.332797 -313.264582) (xy 198.292716 -313.212899)
			(xy 198.259783 -313.156392) (xy 198.234569 -313.096044) (xy 198.217514 -313.032903) (xy 198.208914 -312.968068)
			(xy 198.208392 -312.935366) (xy 198.208881 -312.904203) (xy 198.216693 -312.842369) (xy 198.232193 -312.782001)
			(xy 198.255136 -312.724053) (xy 198.285162 -312.669436) (xy 198.321796 -312.619014) (xy 198.364461 -312.57358)
			(xy 198.412483 -312.533852) (xy 198.465107 -312.500457) (xy 198.521501 -312.47392) (xy 198.580776 -312.45466)
			(xy 198.641997 -312.442981) (xy 198.7042 -312.439068) (xy 198.766403 -312.442981) (xy 198.827624 -312.45466)
			(xy 198.886899 -312.47392) (xy 198.943293 -312.500457) (xy 198.995917 -312.533852) (xy 199.043939 -312.57358)
			(xy 199.086604 -312.619014) (xy 199.123238 -312.669436) (xy 199.153264 -312.724053) (xy 199.176207 -312.782001)
			(xy 199.191707 -312.842369) (xy 199.199519 -312.904203) (xy 199.200008 -312.935366) (xy 203.162931 -312.935366)
			(xy 203.166866 -312.881595) (xy 203.178589 -312.828971) (xy 203.197849 -312.778614) (xy 203.224235 -312.731597)
			(xy 203.257187 -312.688924) (xy 203.296 -312.651503) (xy 203.339848 -312.620133) (xy 203.387796 -312.595481)
			(xy 203.438823 -312.578073) (xy 203.491841 -312.56828) (xy 203.54572 -312.566311) (xy 203.599311 -312.572208)
			(xy 203.651472 -312.585844) (xy 203.701092 -312.606931) (xy 203.747113 -312.635017) (xy 203.788555 -312.669505)
			(xy 203.824533 -312.709659) (xy 203.854281 -312.754623) (xy 203.877166 -312.80344) (xy 203.892698 -312.855069)
			(xy 203.900548 -312.908409) (xy 203.90104 -312.935366) (xy 203.900548 -312.962323) (xy 203.892698 -313.015663)
			(xy 203.877166 -313.067292) (xy 203.854281 -313.116109) (xy 203.824533 -313.161073) (xy 203.788555 -313.201227)
			(xy 203.747113 -313.235715) (xy 203.701092 -313.263801) (xy 203.651472 -313.284888) (xy 203.599311 -313.298524)
			(xy 203.54572 -313.304421) (xy 203.491841 -313.302452) (xy 203.438823 -313.292659) (xy 203.387796 -313.275251)
			(xy 203.339848 -313.250599) (xy 203.296 -313.219229) (xy 203.257187 -313.181808) (xy 203.224235 -313.139135)
			(xy 203.197849 -313.092118) (xy 203.178589 -313.041761) (xy 203.166866 -312.989137) (xy 203.162931 -312.935366)
			(xy 199.200008 -312.935366) (xy 199.199496 -312.968067) (xy 199.190886 -313.0329) (xy 199.173823 -313.096037)
			(xy 199.148604 -313.156381) (xy 199.115667 -313.212885) (xy 199.075585 -313.264565) (xy 199.052688 -313.287918)
			(xy 199.045322 -313.295284) (xy 199.037702 -313.313826) (xy 199.037702 -313.360308) (xy 199.452499 -313.360308)
			(xy 199.456434 -313.306537) (xy 199.468157 -313.253913) (xy 199.487417 -313.203556) (xy 199.513803 -313.156539)
			(xy 199.546755 -313.113866) (xy 199.585568 -313.076445) (xy 199.629416 -313.045075) (xy 199.677364 -313.020423)
			(xy 199.728391 -313.003015) (xy 199.781409 -312.993222) (xy 199.835288 -312.991253) (xy 199.888879 -312.99715)
			(xy 199.94104 -313.010786) (xy 199.99066 -313.031873) (xy 200.036681 -313.059959) (xy 200.078123 -313.094447)
			(xy 200.114101 -313.134601) (xy 200.143849 -313.179565) (xy 200.166734 -313.228382) (xy 200.182266 -313.280011)
			(xy 200.190116 -313.333351) (xy 200.190608 -313.360308) (xy 200.190116 -313.387265) (xy 200.182266 -313.440605)
			(xy 200.166734 -313.492234) (xy 200.143849 -313.541051) (xy 200.114101 -313.586015) (xy 200.078123 -313.626169)
			(xy 200.036681 -313.660657) (xy 199.99066 -313.688743) (xy 199.94104 -313.70983) (xy 199.888879 -313.723466)
			(xy 199.835288 -313.729363) (xy 199.781409 -313.727394) (xy 199.728391 -313.717601) (xy 199.677364 -313.700193)
			(xy 199.629416 -313.675541) (xy 199.585568 -313.644171) (xy 199.546755 -313.60675) (xy 199.513803 -313.564077)
			(xy 199.487417 -313.51706) (xy 199.468157 -313.466703) (xy 199.456434 -313.414079) (xy 199.452499 -313.360308)
			(xy 199.037702 -313.360308) (xy 199.037702 -313.40679) (xy 199.045322 -313.425332) (xy 199.052688 -313.432698)
			(xy 199.07561 -313.456027) (xy 199.115691 -313.507711) (xy 199.148623 -313.564219) (xy 199.173835 -313.624569)
			(xy 199.190889 -313.687711) (xy 199.199487 -313.752548) (xy 199.200008 -313.78525) (xy 199.199519 -313.816413)
			(xy 199.191707 -313.878247) (xy 199.176207 -313.938615) (xy 199.153264 -313.996563) (xy 199.123238 -314.05118)
			(xy 199.086604 -314.101602) (xy 199.043939 -314.147036) (xy 198.995917 -314.186764) (xy 198.943293 -314.220159)
			(xy 198.886899 -314.246696) (xy 198.827624 -314.265956) (xy 198.766403 -314.277635) (xy 198.7042 -314.281548)
			(xy 198.641997 -314.277635) (xy 198.580776 -314.265956) (xy 198.521501 -314.246696) (xy 198.465107 -314.220159)
			(xy 198.412483 -314.186764) (xy 198.364461 -314.147036) (xy 198.321796 -314.101602) (xy 198.285162 -314.05118)
			(xy 198.255136 -313.996563) (xy 198.232193 -313.938615) (xy 198.216693 -313.878247) (xy 198.208881 -313.816413)
			(xy 198.208392 -313.78525) (xy 195.09994 -313.78525) (xy 195.099435 -313.817971) (xy 195.090835 -313.882846)
			(xy 195.073777 -313.946025) (xy 195.048559 -314.006413) (xy 195.015617 -314.06296) (xy 194.975525 -314.114683)
			(xy 194.95262 -314.138056) (xy 194.945254 -314.145168) (xy 194.93738 -314.163964) (xy 194.93738 -314.210446)
			(xy 195.352431 -314.210446) (xy 195.356366 -314.156675) (xy 195.368089 -314.104051) (xy 195.387349 -314.053694)
			(xy 195.413735 -314.006677) (xy 195.446687 -313.964004) (xy 195.4855 -313.926583) (xy 195.529348 -313.895213)
			(xy 195.577296 -313.870561) (xy 195.628323 -313.853153) (xy 195.681341 -313.84336) (xy 195.73522 -313.841391)
			(xy 195.788811 -313.847288) (xy 195.840972 -313.860924) (xy 195.890592 -313.882011) (xy 195.936613 -313.910097)
			(xy 195.978055 -313.944585) (xy 196.014033 -313.984739) (xy 196.043781 -314.029703) (xy 196.066666 -314.07852)
			(xy 196.082198 -314.130149) (xy 196.090048 -314.183489) (xy 196.09054 -314.210446) (xy 196.090048 -314.237403)
			(xy 196.082198 -314.290743) (xy 196.066666 -314.342372) (xy 196.043781 -314.391189) (xy 196.014033 -314.436153)
			(xy 195.978055 -314.476307) (xy 195.936613 -314.510795) (xy 195.890592 -314.538881) (xy 195.840972 -314.559968)
			(xy 195.788811 -314.573604) (xy 195.73522 -314.579501) (xy 195.681341 -314.577532) (xy 195.628323 -314.567739)
			(xy 195.577296 -314.550331) (xy 195.529348 -314.525679) (xy 195.4855 -314.494309) (xy 195.446687 -314.456888)
			(xy 195.413735 -314.414215) (xy 195.387349 -314.367198) (xy 195.368089 -314.316841) (xy 195.356366 -314.264217)
			(xy 195.352431 -314.210446) (xy 194.93738 -314.210446) (xy 194.93738 -314.256674) (xy 194.945254 -314.27547)
			(xy 194.95262 -314.282582) (xy 194.975519 -314.305959) (xy 195.015602 -314.357686) (xy 195.048537 -314.414233)
			(xy 195.073753 -314.47462) (xy 195.090811 -314.537797) (xy 195.099415 -314.602668) (xy 195.09994 -314.635388)
			(xy 196.950599 -314.635388) (xy 196.954534 -314.581617) (xy 196.966257 -314.528993) (xy 196.985517 -314.478636)
			(xy 197.011903 -314.431619) (xy 197.044855 -314.388946) (xy 197.083668 -314.351525) (xy 197.127516 -314.320155)
			(xy 197.175464 -314.295503) (xy 197.226491 -314.278095) (xy 197.279509 -314.268302) (xy 197.333388 -314.266333)
			(xy 197.386979 -314.27223) (xy 197.43914 -314.285866) (xy 197.48876 -314.306953) (xy 197.534781 -314.335039)
			(xy 197.576223 -314.369527) (xy 197.612201 -314.409681) (xy 197.641949 -314.454645) (xy 197.664834 -314.503462)
			(xy 197.680366 -314.555091) (xy 197.688216 -314.608431) (xy 197.688708 -314.635388) (xy 201.652124 -314.635388)
			(xy 201.652664 -314.602668) (xy 201.661258 -314.537796) (xy 201.67831 -314.474617) (xy 201.703522 -314.414229)
			(xy 201.736457 -314.357682) (xy 201.776543 -314.305957) (xy 201.799444 -314.282582) (xy 201.80681 -314.27547)
			(xy 201.814684 -314.256674) (xy 201.814684 -314.163964) (xy 201.80681 -314.145168) (xy 201.799444 -314.138056)
			(xy 201.776557 -314.114668) (xy 201.736473 -314.062943) (xy 201.703537 -314.006398) (xy 201.67832 -313.946013)
			(xy 201.661259 -313.882838) (xy 201.652651 -313.817969) (xy 201.652124 -313.78525) (xy 201.652613 -313.754087)
			(xy 201.660425 -313.692253) (xy 201.675925 -313.631885) (xy 201.698868 -313.573937) (xy 201.728894 -313.51932)
			(xy 201.765528 -313.468898) (xy 201.808193 -313.423464) (xy 201.856215 -313.383736) (xy 201.908839 -313.350341)
			(xy 201.965233 -313.323804) (xy 202.024508 -313.304544) (xy 202.085729 -313.292865) (xy 202.147932 -313.288952)
			(xy 202.210135 -313.292865) (xy 202.271356 -313.304544) (xy 202.330631 -313.323804) (xy 202.387025 -313.350341)
			(xy 202.439649 -313.383736) (xy 202.487671 -313.423464) (xy 202.530336 -313.468898) (xy 202.56697 -313.51932)
			(xy 202.596996 -313.573937) (xy 202.619939 -313.631885) (xy 202.635439 -313.692253) (xy 202.643251 -313.754087)
			(xy 202.64374 -313.78525) (xy 205.752192 -313.78525) (xy 205.752714 -313.752549) (xy 205.761323 -313.687717)
			(xy 205.778384 -313.62458) (xy 205.803601 -313.564236) (xy 205.836535 -313.507732) (xy 205.876616 -313.456051)
			(xy 205.899512 -313.432698) (xy 205.906878 -313.425332) (xy 205.914498 -313.40679) (xy 205.914498 -313.313826)
			(xy 205.906878 -313.295284) (xy 205.899512 -313.287918) (xy 205.876597 -313.264582) (xy 205.836516 -313.212899)
			(xy 205.803583 -313.156392) (xy 205.778369 -313.096044) (xy 205.761314 -313.032903) (xy 205.752714 -312.968068)
			(xy 205.752192 -312.935366) (xy 205.752681 -312.904203) (xy 205.760493 -312.842369) (xy 205.775993 -312.782001)
			(xy 205.798936 -312.724053) (xy 205.828962 -312.669436) (xy 205.865596 -312.619014) (xy 205.908261 -312.57358)
			(xy 205.956283 -312.533852) (xy 206.008907 -312.500457) (xy 206.065301 -312.47392) (xy 206.124576 -312.45466)
			(xy 206.185797 -312.442981) (xy 206.248 -312.439068) (xy 206.310203 -312.442981) (xy 206.371424 -312.45466)
			(xy 206.430699 -312.47392) (xy 206.487093 -312.500457) (xy 206.539717 -312.533852) (xy 206.587739 -312.57358)
			(xy 206.630404 -312.619014) (xy 206.667038 -312.669436) (xy 206.697064 -312.724053) (xy 206.720007 -312.782001)
			(xy 206.735507 -312.842369) (xy 206.743319 -312.904203) (xy 206.743808 -312.935366) (xy 206.743296 -312.968067)
			(xy 206.734686 -313.0329) (xy 206.717623 -313.096037) (xy 206.692404 -313.156381) (xy 206.659467 -313.212885)
			(xy 206.619385 -313.264565) (xy 206.596488 -313.287918) (xy 206.589122 -313.295284) (xy 206.581502 -313.313826)
			(xy 206.581502 -313.360308) (xy 206.996299 -313.360308) (xy 207.000234 -313.306537) (xy 207.011957 -313.253913)
			(xy 207.031217 -313.203556) (xy 207.057603 -313.156539) (xy 207.090555 -313.113866) (xy 207.129368 -313.076445)
			(xy 207.173216 -313.045075) (xy 207.221164 -313.020423) (xy 207.272191 -313.003015) (xy 207.325209 -312.993222)
			(xy 207.379088 -312.991253) (xy 207.432679 -312.99715) (xy 207.48484 -313.010786) (xy 207.53446 -313.031873)
			(xy 207.580481 -313.059959) (xy 207.621923 -313.094447) (xy 207.657901 -313.134601) (xy 207.687649 -313.179565)
			(xy 207.710534 -313.228382) (xy 207.726066 -313.280011) (xy 207.733916 -313.333351) (xy 207.734408 -313.360308)
			(xy 207.733916 -313.387265) (xy 207.726066 -313.440605) (xy 207.710534 -313.492234) (xy 207.687649 -313.541051)
			(xy 207.657901 -313.586015) (xy 207.621923 -313.626169) (xy 207.580481 -313.660657) (xy 207.53446 -313.688743)
			(xy 207.48484 -313.70983) (xy 207.432679 -313.723466) (xy 207.379088 -313.729363) (xy 207.325209 -313.727394)
			(xy 207.272191 -313.717601) (xy 207.221164 -313.700193) (xy 207.173216 -313.675541) (xy 207.129368 -313.644171)
			(xy 207.090555 -313.60675) (xy 207.057603 -313.564077) (xy 207.031217 -313.51706) (xy 207.011957 -313.466703)
			(xy 207.000234 -313.414079) (xy 206.996299 -313.360308) (xy 206.581502 -313.360308) (xy 206.581502 -313.40679)
			(xy 206.589122 -313.425332) (xy 206.596488 -313.432698) (xy 206.61941 -313.456027) (xy 206.659491 -313.507711)
			(xy 206.692423 -313.564219) (xy 206.717635 -313.624569) (xy 206.734689 -313.687711) (xy 206.743287 -313.752548)
			(xy 206.743808 -313.78525) (xy 206.743319 -313.816413) (xy 206.735507 -313.878247) (xy 206.720007 -313.938615)
			(xy 206.697064 -313.996563) (xy 206.667038 -314.05118) (xy 206.630404 -314.101602) (xy 206.587739 -314.147036)
			(xy 206.539717 -314.186764) (xy 206.487093 -314.220159) (xy 206.430699 -314.246696) (xy 206.371424 -314.265956)
			(xy 206.310203 -314.277635) (xy 206.248 -314.281548) (xy 206.185797 -314.277635) (xy 206.124576 -314.265956)
			(xy 206.065301 -314.246696) (xy 206.008907 -314.220159) (xy 205.956283 -314.186764) (xy 205.908261 -314.147036)
			(xy 205.865596 -314.101602) (xy 205.828962 -314.05118) (xy 205.798936 -313.996563) (xy 205.775993 -313.938615)
			(xy 205.760493 -313.878247) (xy 205.752681 -313.816413) (xy 205.752192 -313.78525) (xy 202.64374 -313.78525)
			(xy 202.643235 -313.817971) (xy 202.634635 -313.882846) (xy 202.617577 -313.946025) (xy 202.592359 -314.006413)
			(xy 202.559417 -314.06296) (xy 202.519325 -314.114683) (xy 202.49642 -314.138056) (xy 202.489054 -314.145168)
			(xy 202.48118 -314.163964) (xy 202.48118 -314.210446) (xy 202.896231 -314.210446) (xy 202.900166 -314.156675)
			(xy 202.911889 -314.104051) (xy 202.931149 -314.053694) (xy 202.957535 -314.006677) (xy 202.990487 -313.964004)
			(xy 203.0293 -313.926583) (xy 203.073148 -313.895213) (xy 203.121096 -313.870561) (xy 203.172123 -313.853153)
			(xy 203.225141 -313.84336) (xy 203.27902 -313.841391) (xy 203.332611 -313.847288) (xy 203.384772 -313.860924)
			(xy 203.434392 -313.882011) (xy 203.480413 -313.910097) (xy 203.521855 -313.944585) (xy 203.557833 -313.984739)
			(xy 203.587581 -314.029703) (xy 203.610466 -314.07852) (xy 203.625998 -314.130149) (xy 203.633848 -314.183489)
			(xy 203.63434 -314.210446) (xy 203.633848 -314.237403) (xy 203.625998 -314.290743) (xy 203.610466 -314.342372)
			(xy 203.587581 -314.391189) (xy 203.557833 -314.436153) (xy 203.521855 -314.476307) (xy 203.480413 -314.510795)
			(xy 203.434392 -314.538881) (xy 203.384772 -314.559968) (xy 203.332611 -314.573604) (xy 203.27902 -314.579501)
			(xy 203.225141 -314.577532) (xy 203.172123 -314.567739) (xy 203.121096 -314.550331) (xy 203.073148 -314.525679)
			(xy 203.0293 -314.494309) (xy 202.990487 -314.456888) (xy 202.957535 -314.414215) (xy 202.931149 -314.367198)
			(xy 202.911889 -314.316841) (xy 202.900166 -314.264217) (xy 202.896231 -314.210446) (xy 202.48118 -314.210446)
			(xy 202.48118 -314.256674) (xy 202.489054 -314.27547) (xy 202.49642 -314.282582) (xy 202.519319 -314.305959)
			(xy 202.559402 -314.357686) (xy 202.592337 -314.414233) (xy 202.617553 -314.47462) (xy 202.634611 -314.537797)
			(xy 202.643215 -314.602668) (xy 202.64374 -314.635388) (xy 204.494399 -314.635388) (xy 204.498334 -314.581617)
			(xy 204.510057 -314.528993) (xy 204.529317 -314.478636) (xy 204.555703 -314.431619) (xy 204.588655 -314.388946)
			(xy 204.627468 -314.351525) (xy 204.671316 -314.320155) (xy 204.719264 -314.295503) (xy 204.770291 -314.278095)
			(xy 204.823309 -314.268302) (xy 204.877188 -314.266333) (xy 204.930779 -314.27223) (xy 204.98294 -314.285866)
			(xy 205.03256 -314.306953) (xy 205.078581 -314.335039) (xy 205.120023 -314.369527) (xy 205.156001 -314.409681)
			(xy 205.185749 -314.454645) (xy 205.208634 -314.503462) (xy 205.224166 -314.555091) (xy 205.232016 -314.608431)
			(xy 205.232508 -314.635388) (xy 205.232016 -314.662345) (xy 205.224166 -314.715685) (xy 205.208634 -314.767314)
			(xy 205.185749 -314.816131) (xy 205.156001 -314.861095) (xy 205.120023 -314.901249) (xy 205.078581 -314.935737)
			(xy 205.03256 -314.963823) (xy 204.98294 -314.98491) (xy 204.930779 -314.998546) (xy 204.877188 -315.004443)
			(xy 204.823309 -315.002474) (xy 204.770291 -314.992681) (xy 204.719264 -314.975273) (xy 204.671316 -314.950621)
			(xy 204.627468 -314.919251) (xy 204.588655 -314.88183) (xy 204.555703 -314.839157) (xy 204.529317 -314.79214)
			(xy 204.510057 -314.741783) (xy 204.498334 -314.689159) (xy 204.494399 -314.635388) (xy 202.64374 -314.635388)
			(xy 202.643251 -314.666551) (xy 202.635439 -314.728385) (xy 202.619939 -314.788753) (xy 202.596996 -314.846701)
			(xy 202.56697 -314.901318) (xy 202.530336 -314.95174) (xy 202.487671 -314.997174) (xy 202.439649 -315.036902)
			(xy 202.387025 -315.070297) (xy 202.330631 -315.096834) (xy 202.271356 -315.116094) (xy 202.210135 -315.127773)
			(xy 202.147932 -315.131686) (xy 202.085729 -315.127773) (xy 202.024508 -315.116094) (xy 201.965233 -315.096834)
			(xy 201.908839 -315.070297) (xy 201.856215 -315.036902) (xy 201.808193 -314.997174) (xy 201.765528 -314.95174)
			(xy 201.728894 -314.901318) (xy 201.698868 -314.846701) (xy 201.675925 -314.788753) (xy 201.660425 -314.728385)
			(xy 201.652613 -314.666551) (xy 201.652124 -314.635388) (xy 197.688708 -314.635388) (xy 197.688216 -314.662345)
			(xy 197.680366 -314.715685) (xy 197.664834 -314.767314) (xy 197.641949 -314.816131) (xy 197.612201 -314.861095)
			(xy 197.576223 -314.901249) (xy 197.534781 -314.935737) (xy 197.48876 -314.963823) (xy 197.43914 -314.98491)
			(xy 197.386979 -314.998546) (xy 197.333388 -315.004443) (xy 197.279509 -315.002474) (xy 197.226491 -314.992681)
			(xy 197.175464 -314.975273) (xy 197.127516 -314.950621) (xy 197.083668 -314.919251) (xy 197.044855 -314.88183)
			(xy 197.011903 -314.839157) (xy 196.985517 -314.79214) (xy 196.966257 -314.741783) (xy 196.954534 -314.689159)
			(xy 196.950599 -314.635388) (xy 195.09994 -314.635388) (xy 195.099451 -314.666551) (xy 195.091639 -314.728385)
			(xy 195.076139 -314.788753) (xy 195.053196 -314.846701) (xy 195.02317 -314.901318) (xy 194.986536 -314.95174)
			(xy 194.943871 -314.997174) (xy 194.895849 -315.036902) (xy 194.843225 -315.070297) (xy 194.786831 -315.096834)
			(xy 194.727556 -315.116094) (xy 194.666335 -315.127773) (xy 194.604132 -315.131686) (xy 194.541929 -315.127773)
			(xy 194.480708 -315.116094) (xy 194.421433 -315.096834) (xy 194.365039 -315.070297) (xy 194.312415 -315.036902)
			(xy 194.264393 -314.997174) (xy 194.221728 -314.95174) (xy 194.185094 -314.901318) (xy 194.155068 -314.846701)
			(xy 194.132125 -314.788753) (xy 194.116625 -314.728385) (xy 194.108813 -314.666551) (xy 194.108324 -314.635388)
			(xy 190.144654 -314.635388) (xy 190.144162 -314.662345) (xy 190.136312 -314.715685) (xy 190.12078 -314.767314)
			(xy 190.097895 -314.816131) (xy 190.068147 -314.861095) (xy 190.032169 -314.901249) (xy 189.990727 -314.935737)
			(xy 189.944706 -314.963823) (xy 189.895086 -314.98491) (xy 189.842925 -314.998546) (xy 189.789334 -315.004443)
			(xy 189.735455 -315.002474) (xy 189.682437 -314.992681) (xy 189.63141 -314.975273) (xy 189.583462 -314.950621)
			(xy 189.539614 -314.919251) (xy 189.500801 -314.88183) (xy 189.467849 -314.839157) (xy 189.441463 -314.79214)
			(xy 189.422203 -314.741783) (xy 189.41048 -314.689159) (xy 189.406545 -314.635388) (xy 187.555886 -314.635388)
			(xy 187.555397 -314.666551) (xy 187.547585 -314.728385) (xy 187.532085 -314.788753) (xy 187.509142 -314.846701)
			(xy 187.479116 -314.901318) (xy 187.442482 -314.95174) (xy 187.399817 -314.997174) (xy 187.351795 -315.036902)
			(xy 187.299171 -315.070297) (xy 187.242777 -315.096834) (xy 187.183502 -315.116094) (xy 187.122281 -315.127773)
			(xy 187.060078 -315.131686) (xy 186.997875 -315.127773) (xy 186.936654 -315.116094) (xy 186.877379 -315.096834)
			(xy 186.820985 -315.070297) (xy 186.768361 -315.036902) (xy 186.720339 -314.997174) (xy 186.677674 -314.95174)
			(xy 186.64104 -314.901318) (xy 186.611014 -314.846701) (xy 186.588071 -314.788753) (xy 186.572571 -314.728385)
			(xy 186.564759 -314.666551) (xy 186.56427 -314.635388) (xy 185.96864 -314.635388) (xy 185.96864 -315.485272)
			(xy 188.075077 -315.485272) (xy 188.079012 -315.431501) (xy 188.090735 -315.378877) (xy 188.109995 -315.32852)
			(xy 188.136381 -315.281503) (xy 188.169333 -315.23883) (xy 188.208146 -315.201409) (xy 188.251994 -315.170039)
			(xy 188.299942 -315.145387) (xy 188.350969 -315.127979) (xy 188.403987 -315.118186) (xy 188.457866 -315.116217)
			(xy 188.511457 -315.122114) (xy 188.563618 -315.13575) (xy 188.613238 -315.156837) (xy 188.659259 -315.184923)
			(xy 188.700701 -315.219411) (xy 188.736679 -315.259565) (xy 188.766427 -315.304529) (xy 188.789312 -315.353346)
			(xy 188.804844 -315.404975) (xy 188.812694 -315.458315) (xy 188.813186 -315.485272) (xy 188.812694 -315.512229)
			(xy 188.804844 -315.565569) (xy 188.789312 -315.617198) (xy 188.766427 -315.666015) (xy 188.736679 -315.710979)
			(xy 188.700701 -315.751133) (xy 188.659259 -315.785621) (xy 188.613238 -315.813707) (xy 188.563618 -315.834794)
			(xy 188.511457 -315.84843) (xy 188.457866 -315.854327) (xy 188.403987 -315.852358) (xy 188.350969 -315.842565)
			(xy 188.299942 -315.825157) (xy 188.251994 -315.800505) (xy 188.208146 -315.769135) (xy 188.169333 -315.731714)
			(xy 188.136381 -315.689041) (xy 188.109995 -315.642024) (xy 188.090735 -315.591667) (xy 188.079012 -315.539043)
			(xy 188.075077 -315.485272) (xy 185.96864 -315.485272) (xy 185.96864 -318.035432) (xy 186.56427 -318.035432)
			(xy 186.564731 -318.004222) (xy 186.572558 -317.942296) (xy 186.588092 -317.881841) (xy 186.611088 -317.823812)
			(xy 186.641183 -317.769127) (xy 186.6779 -317.718649) (xy 186.72066 -317.673177) (xy 186.768787 -317.633428)
			(xy 186.794902 -317.616332) (xy 186.805062 -317.609982) (xy 186.817254 -317.59017) (xy 186.826906 -317.48603)
			(xy 186.818524 -317.464186) (xy 186.809634 -317.456058) (xy 186.791301 -317.438549) (xy 186.759157 -317.399345)
			(xy 186.732685 -317.35611) (xy 186.712382 -317.309657) (xy 186.698631 -317.260861) (xy 186.69169 -317.210642)
			(xy 186.69127 -317.185294) (xy 186.691652 -317.159975) (xy 186.698582 -317.109814) (xy 186.712309 -317.061072)
			(xy 186.732577 -317.014667) (xy 186.759004 -316.971472) (xy 186.791092 -316.932299) (xy 186.80938 -316.914784)
			(xy 186.81827 -316.906402) (xy 186.826652 -316.884812) (xy 186.817254 -316.780672) (xy 186.805062 -316.76086)
			(xy 186.794902 -316.754256) (xy 186.768777 -316.737201) (xy 186.72066 -316.697482) (xy 186.677908 -316.652039)
			(xy 186.641195 -316.60159) (xy 186.611103 -316.546934) (xy 186.588108 -316.488933) (xy 186.572572 -316.428506)
			(xy 186.564742 -316.366606) (xy 186.56427 -316.33541) (xy 186.564759 -316.304247) (xy 186.572571 -316.242413)
			(xy 186.588071 -316.182045) (xy 186.611014 -316.124097) (xy 186.64104 -316.06948) (xy 186.677674 -316.019058)
			(xy 186.720339 -315.973624) (xy 186.768361 -315.933896) (xy 186.820985 -315.900501) (xy 186.877379 -315.873964)
			(xy 186.936654 -315.854704) (xy 186.997875 -315.843025) (xy 187.060078 -315.839112) (xy 187.122281 -315.843025)
			(xy 187.183502 -315.854704) (xy 187.242777 -315.873964) (xy 187.299171 -315.900501) (xy 187.351795 -315.933896)
			(xy 187.399817 -315.973624) (xy 187.442482 -316.019058) (xy 187.479116 -316.06948) (xy 187.509142 -316.124097)
			(xy 187.532085 -316.182045) (xy 187.547585 -316.242413) (xy 187.555397 -316.304247) (xy 187.555886 -316.33541)
			(xy 187.555464 -316.366609) (xy 187.54764 -316.428513) (xy 187.532105 -316.488945) (xy 187.509105 -316.546949)
			(xy 187.479003 -316.601605) (xy 187.442277 -316.652049) (xy 187.399508 -316.697482) (xy 187.351372 -316.737185)
			(xy 187.325254 -316.754256) (xy 187.315094 -316.76086) (xy 187.302902 -316.780672) (xy 187.293504 -316.884812)
			(xy 187.301886 -316.906402) (xy 187.310776 -316.914784) (xy 187.329067 -316.932293) (xy 187.361143 -316.971473)
			(xy 187.38756 -317.014671) (xy 187.407819 -317.061077) (xy 187.421541 -317.109817) (xy 187.428467 -317.159976)
			(xy 187.428886 -317.185294) (xy 190.664338 -317.185294) (xy 190.664799 -317.154097) (xy 190.67262 -317.092195)
			(xy 190.688152 -317.031765) (xy 190.711148 -316.973764) (xy 190.741244 -316.919108) (xy 190.777964 -316.868664)
			(xy 190.820727 -316.823229) (xy 190.868856 -316.783522) (xy 190.89497 -316.766448) (xy 190.90513 -316.759844)
			(xy 190.917322 -316.740032) (xy 190.92672 -316.635892) (xy 190.918338 -316.614302) (xy 190.909448 -316.60592)
			(xy 190.891163 -316.588404) (xy 190.859086 -316.549227) (xy 190.832668 -316.50603) (xy 190.812407 -316.459625)
			(xy 190.798684 -316.410886) (xy 190.791757 -316.360727) (xy 190.791338 -316.33541) (xy 190.791764 -316.310062)
			(xy 190.798696 -316.259842) (xy 190.812443 -316.211046) (xy 190.832748 -316.164593) (xy 190.859226 -316.121362)
			(xy 190.891378 -316.082166) (xy 190.909702 -316.064646) (xy 190.918592 -316.056518) (xy 190.926974 -316.034674)
			(xy 190.917322 -315.930534) (xy 190.90513 -315.910722) (xy 190.89497 -315.904372) (xy 190.868832 -315.887312)
			(xy 190.820711 -315.847553) (xy 190.777957 -315.802073) (xy 190.741246 -315.751589) (xy 190.711156 -315.6969)
			(xy 190.688164 -315.638868) (xy 190.672633 -315.57841) (xy 190.664807 -315.516482) (xy 190.664338 -315.485272)
			(xy 190.664827 -315.454109) (xy 190.672639 -315.392275) (xy 190.688139 -315.331907) (xy 190.711082 -315.273959)
			(xy 190.741108 -315.219342) (xy 190.777742 -315.16892) (xy 190.820407 -315.123486) (xy 190.868429 -315.083758)
			(xy 190.921053 -315.050363) (xy 190.977447 -315.023826) (xy 191.036722 -315.004566) (xy 191.097943 -314.992887)
			(xy 191.160146 -314.988974) (xy 191.222349 -314.992887) (xy 191.28357 -315.004566) (xy 191.342845 -315.023826)
			(xy 191.399239 -315.050363) (xy 191.451863 -315.083758) (xy 191.499885 -315.123486) (xy 191.54255 -315.16892)
			(xy 191.579184 -315.219342) (xy 191.60921 -315.273959) (xy 191.632153 -315.331907) (xy 191.647653 -315.392275)
			(xy 191.655465 -315.454109) (xy 191.655954 -315.485272) (xy 195.619131 -315.485272) (xy 195.623066 -315.431501)
			(xy 195.634789 -315.378877) (xy 195.654049 -315.32852) (xy 195.680435 -315.281503) (xy 195.713387 -315.23883)
			(xy 195.7522 -315.201409) (xy 195.796048 -315.170039) (xy 195.843996 -315.145387) (xy 195.895023 -315.127979)
			(xy 195.948041 -315.118186) (xy 196.00192 -315.116217) (xy 196.055511 -315.122114) (xy 196.107672 -315.13575)
			(xy 196.157292 -315.156837) (xy 196.203313 -315.184923) (xy 196.244755 -315.219411) (xy 196.280733 -315.259565)
			(xy 196.310481 -315.304529) (xy 196.333366 -315.353346) (xy 196.348898 -315.404975) (xy 196.356748 -315.458315)
			(xy 196.35724 -315.485272) (xy 196.356748 -315.512229) (xy 196.348898 -315.565569) (xy 196.333366 -315.617198)
			(xy 196.310481 -315.666015) (xy 196.280733 -315.710979) (xy 196.244755 -315.751133) (xy 196.203313 -315.785621)
			(xy 196.157292 -315.813707) (xy 196.107672 -315.834794) (xy 196.055511 -315.84843) (xy 196.00192 -315.854327)
			(xy 195.948041 -315.852358) (xy 195.895023 -315.842565) (xy 195.843996 -315.825157) (xy 195.796048 -315.800505)
			(xy 195.7522 -315.769135) (xy 195.713387 -315.731714) (xy 195.680435 -315.689041) (xy 195.654049 -315.642024)
			(xy 195.634789 -315.591667) (xy 195.623066 -315.539043) (xy 195.619131 -315.485272) (xy 191.655954 -315.485272)
			(xy 191.655531 -315.516483) (xy 191.647703 -315.578413) (xy 191.632165 -315.63887) (xy 191.609165 -315.696901)
			(xy 191.579065 -315.751586) (xy 191.542341 -315.802063) (xy 191.499574 -315.847533) (xy 191.45144 -315.887278)
			(xy 191.425322 -315.904372) (xy 191.415162 -315.910722) (xy 191.40297 -315.930534) (xy 191.393318 -316.034674)
			(xy 191.4017 -316.056518) (xy 191.41059 -316.064646) (xy 191.42893 -316.082148) (xy 191.461072 -316.121354)
			(xy 191.487542 -316.164591) (xy 191.507844 -316.211046) (xy 191.521595 -316.259842) (xy 191.528534 -316.310062)
			(xy 191.528954 -316.33541) (xy 191.528567 -316.360729) (xy 191.521638 -316.41089) (xy 191.507911 -316.459631)
			(xy 191.487644 -316.506036) (xy 191.461218 -316.549231) (xy 191.429132 -316.588405) (xy 191.410844 -316.60592)
			(xy 191.401954 -316.614302) (xy 191.393572 -316.635892) (xy 191.40297 -316.740032) (xy 191.415162 -316.759844)
			(xy 191.425322 -316.766448) (xy 191.451454 -316.783492) (xy 191.49957 -316.823214) (xy 191.542322 -316.868659)
			(xy 191.579033 -316.919109) (xy 191.609123 -316.973767) (xy 191.632118 -317.031769) (xy 191.647653 -317.092197)
			(xy 191.655483 -317.154097) (xy 191.655954 -317.185294) (xy 191.65547 -317.216503) (xy 191.647651 -317.27843)
			(xy 191.632123 -317.338886) (xy 191.609132 -317.396916) (xy 191.57904 -317.451602) (xy 191.542324 -317.50208)
			(xy 191.499565 -317.547552) (xy 191.451437 -317.587299) (xy 191.425322 -317.604394) (xy 191.415162 -317.610744)
			(xy 191.40297 -317.630556) (xy 191.393318 -317.734696) (xy 191.4017 -317.75654) (xy 191.41059 -317.764668)
			(xy 191.428892 -317.782208) (xy 191.461037 -317.821406) (xy 191.487513 -317.864635) (xy 191.507822 -317.911082)
			(xy 191.52158 -317.959872) (xy 191.528529 -318.010086) (xy 191.528954 -318.035432) (xy 194.108324 -318.035432)
			(xy 194.10876 -318.004221) (xy 194.116588 -317.942293) (xy 194.132124 -317.881836) (xy 194.155123 -317.823806)
			(xy 194.185221 -317.76912) (xy 194.221942 -317.718643) (xy 194.264707 -317.673172) (xy 194.312839 -317.633427)
			(xy 194.338956 -317.616332) (xy 194.349116 -317.609982) (xy 194.361308 -317.59017) (xy 194.37096 -317.48603)
			(xy 194.362578 -317.464186) (xy 194.353688 -317.456058) (xy 194.335346 -317.438558) (xy 194.303205 -317.399351)
			(xy 194.276735 -317.356113) (xy 194.256434 -317.309659) (xy 194.242684 -317.260862) (xy 194.235744 -317.210642)
			(xy 194.235324 -317.185294) (xy 194.23572 -317.159976) (xy 194.242649 -317.109815) (xy 194.256375 -317.061075)
			(xy 194.27664 -317.01467) (xy 194.303063 -316.971474) (xy 194.335147 -316.932299) (xy 194.353434 -316.914784)
			(xy 194.362324 -316.906402) (xy 194.370706 -316.884812) (xy 194.361308 -316.780672) (xy 194.349116 -316.76086)
			(xy 194.338956 -316.754256) (xy 194.312843 -316.737182) (xy 194.264724 -316.697467) (xy 194.221969 -316.652028)
			(xy 194.185255 -316.601583) (xy 194.155161 -316.546929) (xy 194.132164 -316.48893) (xy 194.116627 -316.428504)
			(xy 194.108796 -316.366606) (xy 194.108324 -316.33541) (xy 194.108813 -316.304247) (xy 194.116625 -316.242413)
			(xy 194.132125 -316.182045) (xy 194.155068 -316.124097) (xy 194.185094 -316.06948) (xy 194.221728 -316.019058)
			(xy 194.264393 -315.973624) (xy 194.312415 -315.933896) (xy 194.365039 -315.900501) (xy 194.421433 -315.873964)
			(xy 194.480708 -315.854704) (xy 194.541929 -315.843025) (xy 194.604132 -315.839112) (xy 194.666335 -315.843025)
			(xy 194.727556 -315.854704) (xy 194.786831 -315.873964) (xy 194.843225 -315.900501) (xy 194.895849 -315.933896)
			(xy 194.943871 -315.973624) (xy 194.986536 -316.019058) (xy 195.02317 -316.06948) (xy 195.053196 -316.124097)
			(xy 195.076139 -316.182045) (xy 195.091639 -316.242413) (xy 195.099451 -316.304247) (xy 195.09994 -316.33541)
			(xy 195.099493 -316.366608) (xy 195.09167 -316.42851) (xy 195.076137 -316.488941) (xy 195.053139 -316.546943)
			(xy 195.023042 -316.601599) (xy 194.986319 -316.652043) (xy 194.943554 -316.697477) (xy 194.895423 -316.737183)
			(xy 194.869308 -316.754256) (xy 194.859148 -316.76086) (xy 194.846956 -316.780672) (xy 194.837558 -316.884812)
			(xy 194.84594 -316.906402) (xy 194.85483 -316.914784) (xy 194.873112 -316.932302) (xy 194.905191 -316.971479)
			(xy 194.93161 -317.014675) (xy 194.951871 -317.061079) (xy 194.965594 -317.109818) (xy 194.972521 -317.159977)
			(xy 194.97294 -317.185294) (xy 198.208392 -317.185294) (xy 198.208828 -317.154096) (xy 198.21665 -317.092192)
			(xy 198.232184 -317.031761) (xy 198.255183 -316.973758) (xy 198.285282 -316.919102) (xy 198.322006 -316.868658)
			(xy 198.364774 -316.823224) (xy 198.412907 -316.78352) (xy 198.439024 -316.766448) (xy 198.449184 -316.759844)
			(xy 198.461376 -316.740032) (xy 198.470774 -316.635892) (xy 198.462392 -316.614302) (xy 198.453502 -316.60592)
			(xy 198.435228 -316.588393) (xy 198.403147 -316.54922) (xy 198.376727 -316.506025) (xy 198.356464 -316.459623)
			(xy 198.342739 -316.410884) (xy 198.335811 -316.360727) (xy 198.335392 -316.33541) (xy 198.335833 -316.310063)
			(xy 198.342763 -316.259844) (xy 198.356509 -316.211048) (xy 198.376811 -316.164596) (xy 198.403286 -316.121364)
			(xy 198.435434 -316.082167) (xy 198.453756 -316.064646) (xy 198.462646 -316.056518) (xy 198.471028 -316.034674)
			(xy 198.461376 -315.930534) (xy 198.449184 -315.910722) (xy 198.439024 -315.904372) (xy 198.412898 -315.887293)
			(xy 198.364775 -315.847539) (xy 198.322019 -315.802063) (xy 198.285306 -315.751582) (xy 198.255214 -315.696895)
			(xy 198.232221 -315.638865) (xy 198.216688 -315.578409) (xy 198.208861 -315.516482) (xy 198.208392 -315.485272)
			(xy 198.208881 -315.454109) (xy 198.216693 -315.392275) (xy 198.232193 -315.331907) (xy 198.255136 -315.273959)
			(xy 198.285162 -315.219342) (xy 198.321796 -315.16892) (xy 198.364461 -315.123486) (xy 198.412483 -315.083758)
			(xy 198.465107 -315.050363) (xy 198.521501 -315.023826) (xy 198.580776 -315.004566) (xy 198.641997 -314.992887)
			(xy 198.7042 -314.988974) (xy 198.766403 -314.992887) (xy 198.827624 -315.004566) (xy 198.886899 -315.023826)
			(xy 198.943293 -315.050363) (xy 198.995917 -315.083758) (xy 199.043939 -315.123486) (xy 199.086604 -315.16892)
			(xy 199.123238 -315.219342) (xy 199.153264 -315.273959) (xy 199.176207 -315.331907) (xy 199.191707 -315.392275)
			(xy 199.199519 -315.454109) (xy 199.200008 -315.485272) (xy 203.162931 -315.485272) (xy 203.166866 -315.431501)
			(xy 203.178589 -315.378877) (xy 203.197849 -315.32852) (xy 203.224235 -315.281503) (xy 203.257187 -315.23883)
			(xy 203.296 -315.201409) (xy 203.339848 -315.170039) (xy 203.387796 -315.145387) (xy 203.438823 -315.127979)
			(xy 203.491841 -315.118186) (xy 203.54572 -315.116217) (xy 203.599311 -315.122114) (xy 203.651472 -315.13575)
			(xy 203.701092 -315.156837) (xy 203.747113 -315.184923) (xy 203.788555 -315.219411) (xy 203.824533 -315.259565)
			(xy 203.854281 -315.304529) (xy 203.877166 -315.353346) (xy 203.892698 -315.404975) (xy 203.900548 -315.458315)
			(xy 203.90104 -315.485272) (xy 203.900548 -315.512229) (xy 203.892698 -315.565569) (xy 203.877166 -315.617198)
			(xy 203.854281 -315.666015) (xy 203.824533 -315.710979) (xy 203.788555 -315.751133) (xy 203.747113 -315.785621)
			(xy 203.701092 -315.813707) (xy 203.651472 -315.834794) (xy 203.599311 -315.84843) (xy 203.54572 -315.854327)
			(xy 203.491841 -315.852358) (xy 203.438823 -315.842565) (xy 203.387796 -315.825157) (xy 203.339848 -315.800505)
			(xy 203.296 -315.769135) (xy 203.257187 -315.731714) (xy 203.224235 -315.689041) (xy 203.197849 -315.642024)
			(xy 203.178589 -315.591667) (xy 203.166866 -315.539043) (xy 203.162931 -315.485272) (xy 199.200008 -315.485272)
			(xy 199.19956 -315.516482) (xy 199.191733 -315.57841) (xy 199.176197 -315.638866) (xy 199.153199 -315.696895)
			(xy 199.123103 -315.75158) (xy 199.086383 -315.802058) (xy 199.043621 -315.847529) (xy 198.995492 -315.887276)
			(xy 198.969376 -315.904372) (xy 198.959216 -315.910722) (xy 198.947024 -315.930534) (xy 198.937372 -316.034674)
			(xy 198.945754 -316.056518) (xy 198.954644 -316.064646) (xy 198.972975 -316.082157) (xy 199.005119 -316.12136)
			(xy 199.031593 -316.164595) (xy 199.051896 -316.211048) (xy 199.065648 -316.259843) (xy 199.072588 -316.310062)
			(xy 199.073008 -316.33541) (xy 199.072604 -316.360728) (xy 199.065676 -316.410888) (xy 199.051951 -316.459628)
			(xy 199.031687 -316.506032) (xy 199.005266 -316.549228) (xy 198.973183 -316.588404) (xy 198.954898 -316.60592)
			(xy 198.946008 -316.614302) (xy 198.937626 -316.635892) (xy 198.947024 -316.740032) (xy 198.959216 -316.759844)
			(xy 198.969376 -316.766448) (xy 198.995498 -316.783508) (xy 199.043616 -316.823226) (xy 199.086369 -316.868668)
			(xy 199.123082 -316.919115) (xy 199.153175 -316.973771) (xy 199.17617 -317.031771) (xy 199.191706 -317.092199)
			(xy 199.199537 -317.154098) (xy 199.200008 -317.185294) (xy 199.199499 -317.216502) (xy 199.191681 -317.278427)
			(xy 199.176155 -317.338882) (xy 199.153166 -317.39691) (xy 199.123078 -317.451596) (xy 199.086367 -317.502075)
			(xy 199.043612 -317.547548) (xy 198.995489 -317.587297) (xy 198.969376 -317.604394) (xy 198.959216 -317.610744)
			(xy 198.947024 -317.630556) (xy 198.937372 -317.734696) (xy 198.945754 -317.75654) (xy 198.954644 -317.764668)
			(xy 198.972937 -317.782217) (xy 199.005085 -317.821412) (xy 199.031563 -317.864639) (xy 199.051873 -317.911084)
			(xy 199.065633 -317.959873) (xy 199.072583 -318.010086) (xy 199.073008 -318.035432) (xy 201.652124 -318.035432)
			(xy 201.65256 -318.004221) (xy 201.660388 -317.942293) (xy 201.675924 -317.881836) (xy 201.698923 -317.823806)
			(xy 201.729021 -317.76912) (xy 201.765742 -317.718643) (xy 201.808507 -317.673172) (xy 201.856639 -317.633427)
			(xy 201.882756 -317.616332) (xy 201.892916 -317.609982) (xy 201.905108 -317.59017) (xy 201.91476 -317.48603)
			(xy 201.906378 -317.464186) (xy 201.897488 -317.456058) (xy 201.879146 -317.438558) (xy 201.847005 -317.399351)
			(xy 201.820535 -317.356113) (xy 201.800234 -317.309659) (xy 201.786484 -317.260862) (xy 201.779544 -317.210642)
			(xy 201.779124 -317.185294) (xy 201.77952 -317.159976) (xy 201.786449 -317.109815) (xy 201.800175 -317.061075)
			(xy 201.82044 -317.01467) (xy 201.846863 -316.971474) (xy 201.878947 -316.932299) (xy 201.897234 -316.914784)
			(xy 201.906124 -316.906402) (xy 201.914506 -316.884812) (xy 201.905108 -316.780672) (xy 201.892916 -316.76086)
			(xy 201.882756 -316.754256) (xy 201.856643 -316.737182) (xy 201.808524 -316.697467) (xy 201.765769 -316.652028)
			(xy 201.729055 -316.601583) (xy 201.698961 -316.546929) (xy 201.675964 -316.48893) (xy 201.660427 -316.428504)
			(xy 201.652596 -316.366606) (xy 201.652124 -316.33541) (xy 201.652613 -316.304247) (xy 201.660425 -316.242413)
			(xy 201.675925 -316.182045) (xy 201.698868 -316.124097) (xy 201.728894 -316.06948) (xy 201.765528 -316.019058)
			(xy 201.808193 -315.973624) (xy 201.856215 -315.933896) (xy 201.908839 -315.900501) (xy 201.965233 -315.873964)
			(xy 202.024508 -315.854704) (xy 202.085729 -315.843025) (xy 202.147932 -315.839112) (xy 202.210135 -315.843025)
			(xy 202.271356 -315.854704) (xy 202.330631 -315.873964) (xy 202.387025 -315.900501) (xy 202.439649 -315.933896)
			(xy 202.487671 -315.973624) (xy 202.530336 -316.019058) (xy 202.56697 -316.06948) (xy 202.596996 -316.124097)
			(xy 202.619939 -316.182045) (xy 202.635439 -316.242413) (xy 202.643251 -316.304247) (xy 202.64374 -316.33541)
			(xy 202.643293 -316.366608) (xy 202.63547 -316.42851) (xy 202.619937 -316.488941) (xy 202.596939 -316.546943)
			(xy 202.566842 -316.601599) (xy 202.530119 -316.652043) (xy 202.487354 -316.697477) (xy 202.439223 -316.737183)
			(xy 202.413108 -316.754256) (xy 202.402948 -316.76086) (xy 202.390756 -316.780672) (xy 202.381358 -316.884812)
			(xy 202.38974 -316.906402) (xy 202.39863 -316.914784) (xy 202.416912 -316.932302) (xy 202.448991 -316.971479)
			(xy 202.47541 -317.014675) (xy 202.495671 -317.061079) (xy 202.509394 -317.109818) (xy 202.516321 -317.159977)
			(xy 202.51674 -317.185294) (xy 205.752192 -317.185294) (xy 205.752628 -317.154096) (xy 205.76045 -317.092192)
			(xy 205.775984 -317.031761) (xy 205.798983 -316.973758) (xy 205.829082 -316.919102) (xy 205.865806 -316.868658)
			(xy 205.908574 -316.823224) (xy 205.956707 -316.78352) (xy 205.982824 -316.766448) (xy 205.992984 -316.759844)
			(xy 206.005176 -316.740032) (xy 206.014574 -316.635892) (xy 206.006192 -316.614302) (xy 205.997302 -316.60592)
			(xy 205.979028 -316.588393) (xy 205.946947 -316.54922) (xy 205.920527 -316.506025) (xy 205.900264 -316.459623)
			(xy 205.886539 -316.410884) (xy 205.879611 -316.360727) (xy 205.879192 -316.33541) (xy 205.879633 -316.310063)
			(xy 205.886563 -316.259844) (xy 205.900309 -316.211048) (xy 205.920611 -316.164596) (xy 205.947086 -316.121364)
			(xy 205.979234 -316.082167) (xy 205.997556 -316.064646) (xy 206.006446 -316.056518) (xy 206.014828 -316.034674)
			(xy 206.005176 -315.930534) (xy 205.992984 -315.910722) (xy 205.982824 -315.904372) (xy 205.956698 -315.887293)
			(xy 205.908575 -315.847539) (xy 205.865819 -315.802063) (xy 205.829106 -315.751582) (xy 205.799014 -315.696895)
			(xy 205.776021 -315.638865) (xy 205.760488 -315.578409) (xy 205.752661 -315.516482) (xy 205.752192 -315.485272)
			(xy 205.752681 -315.454109) (xy 205.760493 -315.392275) (xy 205.775993 -315.331907) (xy 205.798936 -315.273959)
			(xy 205.828962 -315.219342) (xy 205.865596 -315.16892) (xy 205.908261 -315.123486) (xy 205.956283 -315.083758)
			(xy 206.008907 -315.050363) (xy 206.065301 -315.023826) (xy 206.124576 -315.004566) (xy 206.185797 -314.992887)
			(xy 206.248 -314.988974) (xy 206.310203 -314.992887) (xy 206.371424 -315.004566) (xy 206.430699 -315.023826)
			(xy 206.487093 -315.050363) (xy 206.539717 -315.083758) (xy 206.587739 -315.123486) (xy 206.630404 -315.16892)
			(xy 206.667038 -315.219342) (xy 206.697064 -315.273959) (xy 206.720007 -315.331907) (xy 206.735507 -315.392275)
			(xy 206.743319 -315.454109) (xy 206.743808 -315.485272) (xy 206.74336 -315.516482) (xy 206.735533 -315.57841)
			(xy 206.719997 -315.638866) (xy 206.696999 -315.696895) (xy 206.666903 -315.75158) (xy 206.630183 -315.802058)
			(xy 206.587421 -315.847529) (xy 206.539292 -315.887276) (xy 206.513176 -315.904372) (xy 206.503016 -315.910722)
			(xy 206.490824 -315.930534) (xy 206.481172 -316.034674) (xy 206.489554 -316.056518) (xy 206.498444 -316.064646)
			(xy 206.516775 -316.082157) (xy 206.548919 -316.12136) (xy 206.575393 -316.164595) (xy 206.595696 -316.211048)
			(xy 206.609448 -316.259843) (xy 206.616388 -316.310062) (xy 206.616808 -316.33541) (xy 206.616404 -316.360728)
			(xy 206.609476 -316.410888) (xy 206.595751 -316.459628) (xy 206.575487 -316.506032) (xy 206.549066 -316.549228)
			(xy 206.516983 -316.588404) (xy 206.498698 -316.60592) (xy 206.489808 -316.614302) (xy 206.481426 -316.635892)
			(xy 206.490824 -316.740032) (xy 206.503016 -316.759844) (xy 206.513176 -316.766448) (xy 206.539298 -316.783508)
			(xy 206.587416 -316.823226) (xy 206.630169 -316.868668) (xy 206.666882 -316.919115) (xy 206.696975 -316.973771)
			(xy 206.71997 -317.031771) (xy 206.735506 -317.092199) (xy 206.743337 -317.154098) (xy 206.743808 -317.185294)
			(xy 206.743299 -317.216502) (xy 206.735481 -317.278427) (xy 206.719955 -317.338882) (xy 206.696966 -317.39691)
			(xy 206.666878 -317.451596) (xy 206.630167 -317.502075) (xy 206.587412 -317.547548) (xy 206.539289 -317.587297)
			(xy 206.513176 -317.604394) (xy 206.503016 -317.610744) (xy 206.490824 -317.630556) (xy 206.481172 -317.734696)
			(xy 206.489554 -317.75654) (xy 206.498444 -317.764668) (xy 206.516737 -317.782217) (xy 206.548885 -317.821412)
			(xy 206.575363 -317.864639) (xy 206.595673 -317.911084) (xy 206.609433 -317.959873) (xy 206.616383 -318.010086)
			(xy 206.616808 -318.035432) (xy 206.616292 -318.063032) (xy 206.608065 -318.117615) (xy 206.591795 -318.170362)
			(xy 206.567845 -318.220095) (xy 206.53675 -318.265702) (xy 206.499205 -318.306166) (xy 206.456048 -318.340583)
			(xy 206.408244 -318.368182) (xy 206.35686 -318.388349) (xy 206.303045 -318.400632) (xy 206.248 -318.404757)
			(xy 206.192955 -318.400632) (xy 206.13914 -318.388349) (xy 206.087756 -318.368182) (xy 206.039952 -318.340583)
			(xy 205.996795 -318.306166) (xy 205.95925 -318.265702) (xy 205.928155 -318.220095) (xy 205.904205 -318.170362)
			(xy 205.887935 -318.117615) (xy 205.879708 -318.063032) (xy 205.879192 -318.035432) (xy 205.879581 -318.010083)
			(xy 205.886522 -317.959862) (xy 205.900278 -317.911065) (xy 205.92059 -317.864614) (xy 205.947074 -317.821383)
			(xy 205.97923 -317.782187) (xy 205.997556 -317.764668) (xy 206.006446 -317.75654) (xy 206.014828 -317.734696)
			(xy 206.005176 -317.630556) (xy 205.992984 -317.610744) (xy 205.982824 -317.604394) (xy 205.956708 -317.5873)
			(xy 205.908585 -317.547548) (xy 205.865829 -317.502074) (xy 205.829114 -317.451596) (xy 205.799022 -317.39691)
			(xy 205.776026 -317.338882) (xy 205.760492 -317.278428) (xy 205.752663 -317.216503) (xy 205.752192 -317.185294)
			(xy 202.51674 -317.185294) (xy 202.516292 -317.210641) (xy 202.509361 -317.260859) (xy 202.495616 -317.309654)
			(xy 202.475316 -317.356106) (xy 202.448843 -317.399338) (xy 202.416697 -317.438537) (xy 202.398376 -317.456058)
			(xy 202.389486 -317.464186) (xy 202.381104 -317.48603) (xy 202.390756 -317.59017) (xy 202.402948 -317.609982)
			(xy 202.413108 -317.616332) (xy 202.439197 -317.633464) (xy 202.487319 -317.673212) (xy 202.530075 -317.718681)
			(xy 202.566791 -317.769154) (xy 202.596887 -317.823833) (xy 202.619887 -317.881855) (xy 202.635428 -317.942304)
			(xy 202.643265 -318.004225) (xy 202.64374 -318.035432) (xy 202.643232 -318.066628) (xy 202.635419 -318.128528)
			(xy 202.619895 -318.188957) (xy 202.596906 -318.246959) (xy 202.566817 -318.301615) (xy 202.530103 -318.35206)
			(xy 202.487345 -318.397496) (xy 202.43922 -318.437204) (xy 202.413108 -318.454278) (xy 202.402948 -318.460882)
			(xy 202.390756 -318.480694) (xy 202.381358 -318.584834) (xy 202.38974 -318.606424) (xy 202.39863 -318.614806)
			(xy 202.416923 -318.632314) (xy 202.449001 -318.671492) (xy 202.475418 -318.714691) (xy 202.495677 -318.761097)
			(xy 202.509398 -318.809838) (xy 202.516323 -318.859998) (xy 202.51674 -318.885316) (xy 202.516224 -318.912916)
			(xy 202.507997 -318.967499) (xy 202.491727 -319.020246) (xy 202.467777 -319.069979) (xy 202.436682 -319.115586)
			(xy 202.399137 -319.15605) (xy 202.35598 -319.190467) (xy 202.308176 -319.218066) (xy 202.256792 -319.238233)
			(xy 202.202977 -319.250516) (xy 202.147932 -319.254641) (xy 202.092887 -319.250516) (xy 202.039072 -319.238233)
			(xy 201.987688 -319.218066) (xy 201.939884 -319.190467) (xy 201.896727 -319.15605) (xy 201.859182 -319.115586)
			(xy 201.828087 -319.069979) (xy 201.804137 -319.020246) (xy 201.787867 -318.967499) (xy 201.77964 -318.912916)
			(xy 201.779124 -318.885316) (xy 201.779535 -318.859998) (xy 201.786461 -318.809838) (xy 201.800183 -318.761098)
			(xy 201.820446 -318.714693) (xy 201.846866 -318.671497) (xy 201.878948 -318.632322) (xy 201.897234 -318.614806)
			(xy 201.906124 -318.606424) (xy 201.914506 -318.584834) (xy 201.905108 -318.480694) (xy 201.892916 -318.460882)
			(xy 201.882756 -318.454278) (xy 201.856653 -318.437189) (xy 201.808534 -318.397477) (xy 201.765779 -318.35204)
			(xy 201.729063 -318.301596) (xy 201.698968 -318.246945) (xy 201.675969 -318.188948) (xy 201.660431 -318.128524)
			(xy 201.652597 -318.066627) (xy 201.652124 -318.035432) (xy 199.073008 -318.035432) (xy 199.072492 -318.063032)
			(xy 199.064265 -318.117615) (xy 199.047995 -318.170362) (xy 199.024045 -318.220095) (xy 198.99295 -318.265702)
			(xy 198.955405 -318.306166) (xy 198.912248 -318.340583) (xy 198.864444 -318.368182) (xy 198.81306 -318.388349)
			(xy 198.759245 -318.400632) (xy 198.7042 -318.404757) (xy 198.649155 -318.400632) (xy 198.59534 -318.388349)
			(xy 198.543956 -318.368182) (xy 198.496152 -318.340583) (xy 198.452995 -318.306166) (xy 198.41545 -318.265702)
			(xy 198.384355 -318.220095) (xy 198.360405 -318.170362) (xy 198.344135 -318.117615) (xy 198.335908 -318.063032)
			(xy 198.335392 -318.035432) (xy 198.335781 -318.010083) (xy 198.342722 -317.959862) (xy 198.356478 -317.911065)
			(xy 198.37679 -317.864614) (xy 198.403274 -317.821383) (xy 198.43543 -317.782187) (xy 198.453756 -317.764668)
			(xy 198.462646 -317.75654) (xy 198.471028 -317.734696) (xy 198.461376 -317.630556) (xy 198.449184 -317.610744)
			(xy 198.439024 -317.604394) (xy 198.412908 -317.5873) (xy 198.364785 -317.547548) (xy 198.322029 -317.502074)
			(xy 198.285314 -317.451596) (xy 198.255222 -317.39691) (xy 198.232226 -317.338882) (xy 198.216692 -317.278428)
			(xy 198.208863 -317.216503) (xy 198.208392 -317.185294) (xy 194.97294 -317.185294) (xy 194.972492 -317.210641)
			(xy 194.965561 -317.260859) (xy 194.951816 -317.309654) (xy 194.931516 -317.356106) (xy 194.905043 -317.399338)
			(xy 194.872897 -317.438537) (xy 194.854576 -317.456058) (xy 194.845686 -317.464186) (xy 194.837304 -317.48603)
			(xy 194.846956 -317.59017) (xy 194.859148 -317.609982) (xy 194.869308 -317.616332) (xy 194.895397 -317.633464)
			(xy 194.943519 -317.673212) (xy 194.986275 -317.718681) (xy 195.022991 -317.769154) (xy 195.053087 -317.823833)
			(xy 195.076087 -317.881855) (xy 195.091628 -317.942304) (xy 195.099465 -318.004225) (xy 195.09994 -318.035432)
			(xy 195.099432 -318.066628) (xy 195.091619 -318.128528) (xy 195.076095 -318.188957) (xy 195.053106 -318.246959)
			(xy 195.023017 -318.301615) (xy 194.986303 -318.35206) (xy 194.943545 -318.397496) (xy 194.89542 -318.437204)
			(xy 194.869308 -318.454278) (xy 194.859148 -318.460882) (xy 194.846956 -318.480694) (xy 194.837558 -318.584834)
			(xy 194.84594 -318.606424) (xy 194.85483 -318.614806) (xy 194.873123 -318.632314) (xy 194.905201 -318.671492)
			(xy 194.931618 -318.714691) (xy 194.951877 -318.761097) (xy 194.965598 -318.809838) (xy 194.972523 -318.859998)
			(xy 194.97294 -318.885316) (xy 194.972424 -318.912916) (xy 194.964197 -318.967499) (xy 194.947927 -319.020246)
			(xy 194.923977 -319.069979) (xy 194.892882 -319.115586) (xy 194.855337 -319.15605) (xy 194.81218 -319.190467)
			(xy 194.764376 -319.218066) (xy 194.712992 -319.238233) (xy 194.659177 -319.250516) (xy 194.604132 -319.254641)
			(xy 194.549087 -319.250516) (xy 194.495272 -319.238233) (xy 194.443888 -319.218066) (xy 194.396084 -319.190467)
			(xy 194.352927 -319.15605) (xy 194.315382 -319.115586) (xy 194.284287 -319.069979) (xy 194.260337 -319.020246)
			(xy 194.244067 -318.967499) (xy 194.23584 -318.912916) (xy 194.235324 -318.885316) (xy 194.235735 -318.859998)
			(xy 194.242661 -318.809838) (xy 194.256383 -318.761098) (xy 194.276646 -318.714693) (xy 194.303066 -318.671497)
			(xy 194.335148 -318.632322) (xy 194.353434 -318.614806) (xy 194.362324 -318.606424) (xy 194.370706 -318.584834)
			(xy 194.361308 -318.480694) (xy 194.349116 -318.460882) (xy 194.338956 -318.454278) (xy 194.312853 -318.437189)
			(xy 194.264734 -318.397477) (xy 194.221979 -318.35204) (xy 194.185263 -318.301596) (xy 194.155168 -318.246945)
			(xy 194.132169 -318.188948) (xy 194.116631 -318.128524) (xy 194.108797 -318.066627) (xy 194.108324 -318.035432)
			(xy 191.528954 -318.035432) (xy 191.528438 -318.063032) (xy 191.520211 -318.117615) (xy 191.503941 -318.170362)
			(xy 191.479991 -318.220095) (xy 191.448896 -318.265702) (xy 191.411351 -318.306166) (xy 191.368194 -318.340583)
			(xy 191.32039 -318.368182) (xy 191.269006 -318.388349) (xy 191.215191 -318.400632) (xy 191.160146 -318.404757)
			(xy 191.105101 -318.400632) (xy 191.051286 -318.388349) (xy 190.999902 -318.368182) (xy 190.952098 -318.340583)
			(xy 190.908941 -318.306166) (xy 190.871396 -318.265702) (xy 190.840301 -318.220095) (xy 190.816351 -318.170362)
			(xy 190.800081 -318.117615) (xy 190.791854 -318.063032) (xy 190.791338 -318.035432) (xy 190.791712 -318.010082)
			(xy 190.798654 -317.95986) (xy 190.812412 -317.911063) (xy 190.832727 -317.864611) (xy 190.859214 -317.82138)
			(xy 190.891374 -317.782186) (xy 190.909702 -317.764668) (xy 190.918592 -317.75654) (xy 190.926974 -317.734696)
			(xy 190.917322 -317.630556) (xy 190.90513 -317.610744) (xy 190.89497 -317.604394) (xy 190.868842 -317.587319)
			(xy 190.820721 -317.547563) (xy 190.777967 -317.502085) (xy 190.741255 -317.451603) (xy 190.711164 -317.396916)
			(xy 190.68817 -317.338886) (xy 190.672636 -317.27843) (xy 190.664808 -317.216504) (xy 190.664338 -317.185294)
			(xy 187.428886 -317.185294) (xy 187.428455 -317.210642) (xy 187.421523 -317.260861) (xy 187.407776 -317.309657)
			(xy 187.387472 -317.356109) (xy 187.360996 -317.399341) (xy 187.328845 -317.438538) (xy 187.310522 -317.456058)
			(xy 187.301632 -317.464186) (xy 187.29325 -317.48603) (xy 187.302902 -317.59017) (xy 187.315094 -317.609982)
			(xy 187.325254 -317.616332) (xy 187.351354 -317.633448) (xy 187.399474 -317.673199) (xy 187.442228 -317.718672)
			(xy 187.478942 -317.769147) (xy 187.509036 -317.823829) (xy 187.532035 -317.881853) (xy 187.547575 -317.942303)
			(xy 187.555411 -318.004224) (xy 187.555886 -318.035432) (xy 187.555403 -318.066629) (xy 187.547589 -318.128531)
			(xy 187.532063 -318.188962) (xy 187.509072 -318.246964) (xy 187.478979 -318.301621) (xy 187.44226 -318.352066)
			(xy 187.399498 -318.3975) (xy 187.351369 -318.437205) (xy 187.325254 -318.454278) (xy 187.315094 -318.460882)
			(xy 187.302902 -318.480694) (xy 187.293504 -318.584834) (xy 187.301886 -318.606424) (xy 187.310776 -318.614806)
			(xy 187.329078 -318.632305) (xy 187.361153 -318.671486) (xy 187.387568 -318.714687) (xy 187.407825 -318.761095)
			(xy 187.421545 -318.809837) (xy 187.428469 -318.859998) (xy 187.428886 -318.885316) (xy 187.42837 -318.912916)
			(xy 187.420143 -318.967499) (xy 187.403873 -319.020246) (xy 187.379923 -319.069979) (xy 187.348828 -319.115586)
			(xy 187.311283 -319.15605) (xy 187.268126 -319.190467) (xy 187.220322 -319.218066) (xy 187.168938 -319.238233)
			(xy 187.115123 -319.250516) (xy 187.060078 -319.254641) (xy 187.005033 -319.250516) (xy 186.951218 -319.238233)
			(xy 186.899834 -319.218066) (xy 186.85203 -319.190467) (xy 186.808873 -319.15605) (xy 186.771328 -319.115586)
			(xy 186.740233 -319.069979) (xy 186.716283 -319.020246) (xy 186.700013 -318.967499) (xy 186.691786 -318.912916)
			(xy 186.69127 -318.885316) (xy 186.691667 -318.859998) (xy 186.698593 -318.809837) (xy 186.712318 -318.761095)
			(xy 186.732583 -318.71469) (xy 186.759007 -318.671495) (xy 186.791093 -318.632321) (xy 186.80938 -318.614806)
			(xy 186.81827 -318.606424) (xy 186.826652 -318.584834) (xy 186.817254 -318.480694) (xy 186.805062 -318.460882)
			(xy 186.794902 -318.454278) (xy 186.768787 -318.437208) (xy 186.72067 -318.397491) (xy 186.677917 -318.35205)
			(xy 186.641204 -318.301604) (xy 186.611111 -318.246949) (xy 186.588114 -318.188951) (xy 186.572576 -318.128525)
			(xy 186.564743 -318.066628) (xy 186.56427 -318.035432) (xy 185.96864 -318.035432) (xy 185.96864 -320.168778)
			(xy 185.969079 -320.178841) (xy 185.976817 -320.197421) (xy 185.983626 -320.204846) (xy 186.591194 -320.812414)
			(xy 186.598588 -320.819271) (xy 186.617187 -320.827021) (xy 186.627262 -320.8274) (xy 192.884298 -320.8274)
			(xy 192.894368 -320.827823) (xy 192.912973 -320.835537) (xy 192.920366 -320.842386) (xy 193.698114 -321.620134)
			(xy 193.704965 -321.62753) (xy 193.7127 -321.646129) (xy 193.7131 -321.656202) (xy 193.7131 -324.5353)
			(xy 194.786284 -324.5353) (xy 194.790276 -324.446414) (xy 194.802219 -324.358244) (xy 194.822018 -324.271499)
			(xy 194.849512 -324.186879) (xy 194.884481 -324.105063) (xy 194.926643 -324.026711) (xy 194.975658 -323.952454)
			(xy 195.031132 -323.882889) (xy 195.092619 -323.818577) (xy 195.159623 -323.760036) (xy 195.231604 -323.707736)
			(xy 195.307984 -323.662099) (xy 195.388147 -323.623492) (xy 195.471448 -323.592226) (xy 195.557216 -323.568553)
			(xy 195.644761 -323.552663) (xy 195.733378 -323.544684) (xy 195.777866 -323.544184) (xy 197.530466 -323.544184)
			(xy 197.574956 -323.544683) (xy 197.663577 -323.552656) (xy 197.751126 -323.568541) (xy 197.8369 -323.592211)
			(xy 197.920206 -323.623473) (xy 198.000374 -323.662078) (xy 198.076759 -323.707714) (xy 198.148746 -323.760013)
			(xy 198.215755 -323.818554) (xy 198.277246 -323.882867) (xy 198.332725 -323.952433) (xy 198.381744 -324.026692)
			(xy 198.423909 -324.105046) (xy 198.458881 -324.186865) (xy 198.486378 -324.271489) (xy 198.506178 -324.358237)
			(xy 198.518122 -324.44641) (xy 198.522114 -324.5353) (xy 202.330084 -324.5353) (xy 202.334076 -324.446414)
			(xy 202.346019 -324.358244) (xy 202.365818 -324.271499) (xy 202.393312 -324.186879) (xy 202.428281 -324.105063)
			(xy 202.470443 -324.026711) (xy 202.519458 -323.952454) (xy 202.574932 -323.882889) (xy 202.636419 -323.818577)
			(xy 202.703423 -323.760036) (xy 202.775404 -323.707736) (xy 202.851784 -323.662099) (xy 202.931947 -323.623492)
			(xy 203.015248 -323.592226) (xy 203.101016 -323.568553) (xy 203.188561 -323.552663) (xy 203.277178 -323.544684)
			(xy 203.321666 -323.544184) (xy 205.074266 -323.544184) (xy 205.118756 -323.544683) (xy 205.207377 -323.552656)
			(xy 205.294926 -323.568541) (xy 205.3807 -323.592211) (xy 205.464006 -323.623473) (xy 205.544174 -323.662078)
			(xy 205.620559 -323.707714) (xy 205.692546 -323.760013) (xy 205.759555 -323.818554) (xy 205.821046 -323.882867)
			(xy 205.876525 -323.952433) (xy 205.925544 -324.026692) (xy 205.967709 -324.105046) (xy 206.002681 -324.186865)
			(xy 206.030178 -324.271489) (xy 206.049978 -324.358237) (xy 206.061922 -324.44641) (xy 206.065914 -324.5353)
			(xy 206.061922 -324.62419) (xy 206.049978 -324.712363) (xy 206.030178 -324.799111) (xy 206.002681 -324.883735)
			(xy 205.967709 -324.965554) (xy 205.925544 -325.043908) (xy 205.876525 -325.118167) (xy 205.821046 -325.187733)
			(xy 205.759555 -325.252046) (xy 205.692546 -325.310587) (xy 205.620559 -325.362886) (xy 205.544174 -325.408522)
			(xy 205.464006 -325.447127) (xy 205.439573 -325.456296) (xy 211.848698 -325.456296) (xy 211.852769 -325.400674)
			(xy 211.864895 -325.346237) (xy 211.884818 -325.294146) (xy 211.912114 -325.245511) (xy 211.9462 -325.201368)
			(xy 211.986349 -325.162659) (xy 212.031707 -325.130208) (xy 212.081307 -325.104707) (xy 212.134091 -325.0867)
			(xy 212.188934 -325.07657) (xy 212.244668 -325.074533) (xy 212.300105 -325.080633) (xy 212.354062 -325.094739)
			(xy 212.405391 -325.116551) (xy 212.452997 -325.145605) (xy 212.495865 -325.18128) (xy 212.533082 -325.222817)
			(xy 212.563855 -325.26933) (xy 212.587527 -325.319827) (xy 212.603595 -325.373234) (xy 212.611715 -325.42841)
			(xy 212.612224 -325.456296) (xy 212.611715 -325.484182) (xy 212.603595 -325.539358) (xy 212.587527 -325.592765)
			(xy 212.563855 -325.643262) (xy 212.533082 -325.689775) (xy 212.495865 -325.731312) (xy 212.452997 -325.766987)
			(xy 212.405391 -325.796041) (xy 212.354062 -325.817853) (xy 212.300105 -325.831959) (xy 212.244668 -325.838059)
			(xy 212.188934 -325.836022) (xy 212.134091 -325.825892) (xy 212.081307 -325.807885) (xy 212.031707 -325.782384)
			(xy 211.986349 -325.749933) (xy 211.9462 -325.711224) (xy 211.912114 -325.667081) (xy 211.884818 -325.618446)
			(xy 211.864895 -325.566355) (xy 211.852769 -325.511918) (xy 211.848698 -325.456296) (xy 205.439573 -325.456296)
			(xy 205.3807 -325.478389) (xy 205.294926 -325.502059) (xy 205.207377 -325.517944) (xy 205.118756 -325.525917)
			(xy 205.074266 -325.5264) (xy 203.321666 -325.5264) (xy 203.277178 -325.525916) (xy 203.188561 -325.517937)
			(xy 203.101016 -325.502047) (xy 203.015248 -325.478374) (xy 202.931947 -325.447108) (xy 202.851784 -325.408501)
			(xy 202.775404 -325.362864) (xy 202.703423 -325.310564) (xy 202.636419 -325.252023) (xy 202.574932 -325.187711)
			(xy 202.519458 -325.118146) (xy 202.470443 -325.043889) (xy 202.428281 -324.965537) (xy 202.393312 -324.883721)
			(xy 202.365818 -324.799101) (xy 202.346019 -324.712356) (xy 202.334076 -324.624186) (xy 202.330084 -324.5353)
			(xy 198.522114 -324.5353) (xy 198.518122 -324.62419) (xy 198.506178 -324.712363) (xy 198.486378 -324.799111)
			(xy 198.458881 -324.883735) (xy 198.423909 -324.965554) (xy 198.381744 -325.043908) (xy 198.332725 -325.118167)
			(xy 198.277246 -325.187733) (xy 198.215755 -325.252046) (xy 198.148746 -325.310587) (xy 198.076759 -325.362886)
			(xy 198.000374 -325.408522) (xy 197.920206 -325.447127) (xy 197.8369 -325.478389) (xy 197.751126 -325.502059)
			(xy 197.663577 -325.517944) (xy 197.574956 -325.525917) (xy 197.530466 -325.5264) (xy 195.777866 -325.5264)
			(xy 195.733378 -325.525916) (xy 195.644761 -325.517937) (xy 195.557216 -325.502047) (xy 195.471448 -325.478374)
			(xy 195.388147 -325.447108) (xy 195.307984 -325.408501) (xy 195.231604 -325.362864) (xy 195.159623 -325.310564)
			(xy 195.092619 -325.252023) (xy 195.031132 -325.187711) (xy 194.975658 -325.118146) (xy 194.926643 -325.043889)
			(xy 194.884481 -324.965537) (xy 194.849512 -324.883721) (xy 194.822018 -324.799101) (xy 194.802219 -324.712356)
			(xy 194.790276 -324.624186) (xy 194.786284 -324.5353) (xy 193.7131 -324.5353) (xy 193.7131 -325.797926)
			(xy 193.713528 -325.807994) (xy 193.721249 -325.826592) (xy 193.728086 -325.833994) (xy 194.40398 -326.509888)
			(xy 211.88121 -326.509888) (xy 211.885281 -326.454266) (xy 211.897407 -326.399829) (xy 211.91733 -326.347738)
			(xy 211.944626 -326.299103) (xy 211.978712 -326.25496) (xy 212.018861 -326.216251) (xy 212.064219 -326.1838)
			(xy 212.113819 -326.158299) (xy 212.166603 -326.140292) (xy 212.221446 -326.130162) (xy 212.27718 -326.128125)
			(xy 212.332617 -326.134225) (xy 212.386574 -326.148331) (xy 212.437903 -326.170143) (xy 212.485509 -326.199197)
			(xy 212.528377 -326.234872) (xy 212.565594 -326.276409) (xy 212.596367 -326.322922) (xy 212.620039 -326.373419)
			(xy 212.636107 -326.426826) (xy 212.644227 -326.482002) (xy 212.644736 -326.509888) (xy 212.644227 -326.537774)
			(xy 212.636107 -326.59295) (xy 212.620039 -326.646357) (xy 212.596367 -326.696854) (xy 212.565594 -326.743367)
			(xy 212.528377 -326.784904) (xy 212.485509 -326.820579) (xy 212.437903 -326.849633) (xy 212.386574 -326.871445)
			(xy 212.332617 -326.885551) (xy 212.27718 -326.891651) (xy 212.221446 -326.889614) (xy 212.166603 -326.879484)
			(xy 212.113819 -326.861477) (xy 212.064219 -326.835976) (xy 212.018861 -326.803525) (xy 211.978712 -326.764816)
			(xy 211.944626 -326.720673) (xy 211.91733 -326.672038) (xy 211.897407 -326.619947) (xy 211.885281 -326.56551)
			(xy 211.88121 -326.509888) (xy 194.40398 -326.509888) (xy 194.805554 -326.911462) (xy 194.812954 -326.918304)
			(xy 194.831552 -326.926025) (xy 194.841622 -326.926448) (xy 204.225652 -326.926448) (xy 204.230671 -326.926356)
			(xy 204.240523 -326.924437) (xy 204.24521 -326.922638) (xy 204.271118 -326.911716) (xy 204.277468 -326.911716)
			(xy 204.492817 -327.127065) (xy 214.325448 -327.127065) (xy 214.325448 -327.063143) (xy 214.333459 -326.999725)
			(xy 214.349356 -326.937811) (xy 214.372888 -326.878378) (xy 214.403682 -326.822363) (xy 214.441255 -326.770648)
			(xy 214.485012 -326.724051) (xy 214.534265 -326.683306) (xy 214.588236 -326.649055) (xy 214.646075 -326.621838)
			(xy 214.706868 -326.602085) (xy 214.769658 -326.590107) (xy 214.833454 -326.586094) (xy 214.89725 -326.590107)
			(xy 214.96004 -326.602085) (xy 215.020833 -326.621838) (xy 215.078672 -326.649055) (xy 215.132643 -326.683306)
			(xy 215.181896 -326.724051) (xy 215.225653 -326.770648) (xy 215.263226 -326.822363) (xy 215.29402 -326.878378)
			(xy 215.317552 -326.937811) (xy 215.333449 -326.999725) (xy 215.34146 -327.063143) (xy 215.341962 -327.095104)
			(xy 215.34146 -327.127065) (xy 215.333449 -327.190483) (xy 215.317552 -327.252397) (xy 215.29402 -327.31183)
			(xy 215.263226 -327.367845) (xy 215.225653 -327.41956) (xy 215.181896 -327.466157) (xy 215.132643 -327.506902)
			(xy 215.078672 -327.541153) (xy 215.020833 -327.56837) (xy 214.96004 -327.588123) (xy 214.89725 -327.600101)
			(xy 214.833454 -327.604115) (xy 214.769658 -327.600101) (xy 214.706868 -327.588123) (xy 214.646075 -327.56837)
			(xy 214.588236 -327.541153) (xy 214.534265 -327.506902) (xy 214.485012 -327.466157) (xy 214.441255 -327.41956)
			(xy 214.403682 -327.367845) (xy 214.372888 -327.31183) (xy 214.349356 -327.252397) (xy 214.333459 -327.190483)
			(xy 214.325448 -327.127065) (xy 204.492817 -327.127065) (xy 204.601064 -327.235312) (xy 204.608462 -327.242158)
			(xy 204.627061 -327.249883) (xy 204.637132 -327.250298) (xy 208.078578 -327.250298) (xy 208.088642 -327.250736)
			(xy 208.107226 -327.25847) (xy 208.114646 -327.265284) (xy 208.853532 -328.00417) (xy 212.132162 -328.00417)
			(xy 212.136233 -327.948548) (xy 212.148359 -327.894111) (xy 212.168282 -327.84202) (xy 212.195578 -327.793385)
			(xy 212.229664 -327.749242) (xy 212.269813 -327.710533) (xy 212.315171 -327.678082) (xy 212.364771 -327.652581)
			(xy 212.417555 -327.634574) (xy 212.472398 -327.624444) (xy 212.528132 -327.622407) (xy 212.583569 -327.628507)
			(xy 212.637526 -327.642613) (xy 212.688855 -327.664425) (xy 212.736461 -327.693479) (xy 212.779329 -327.729154)
			(xy 212.816546 -327.770691) (xy 212.847319 -327.817204) (xy 212.870991 -327.867701) (xy 212.887059 -327.921108)
			(xy 212.895179 -327.976284) (xy 212.895688 -328.00417) (xy 212.895179 -328.032056) (xy 212.887059 -328.087232)
			(xy 212.870991 -328.140639) (xy 212.847319 -328.191136) (xy 212.816546 -328.237649) (xy 212.779329 -328.279186)
			(xy 212.736461 -328.314861) (xy 212.688855 -328.343915) (xy 212.637526 -328.365727) (xy 212.583569 -328.379833)
			(xy 212.528132 -328.385933) (xy 212.472398 -328.383896) (xy 212.417555 -328.373766) (xy 212.364771 -328.355759)
			(xy 212.315171 -328.330258) (xy 212.269813 -328.297807) (xy 212.229664 -328.259098) (xy 212.195578 -328.214955)
			(xy 212.168282 -328.16632) (xy 212.148359 -328.114229) (xy 212.136233 -328.059792) (xy 212.132162 -328.00417)
			(xy 208.853532 -328.00417) (xy 209.863944 -329.014582) (xy 212.11108 -329.014582) (xy 212.115151 -328.95896)
			(xy 212.127277 -328.904523) (xy 212.1472 -328.852432) (xy 212.174496 -328.803797) (xy 212.208582 -328.759654)
			(xy 212.248731 -328.720945) (xy 212.294089 -328.688494) (xy 212.343689 -328.662993) (xy 212.396473 -328.644986)
			(xy 212.451316 -328.634856) (xy 212.50705 -328.632819) (xy 212.562487 -328.638919) (xy 212.616444 -328.653025)
			(xy 212.667773 -328.674837) (xy 212.715379 -328.703891) (xy 212.758247 -328.739566) (xy 212.795464 -328.781103)
			(xy 212.826237 -328.827616) (xy 212.849909 -328.878113) (xy 212.865977 -328.93152) (xy 212.874097 -328.986696)
			(xy 212.874606 -329.014582) (xy 212.874097 -329.042468) (xy 212.865977 -329.097644) (xy 212.849909 -329.151051)
			(xy 212.826237 -329.201548) (xy 212.795464 -329.248061) (xy 212.758247 -329.289598) (xy 212.715379 -329.325273)
			(xy 212.667773 -329.354327) (xy 212.616444 -329.376139) (xy 212.562487 -329.390245) (xy 212.50705 -329.396345)
			(xy 212.451316 -329.394308) (xy 212.396473 -329.384178) (xy 212.343689 -329.366171) (xy 212.294089 -329.34067)
			(xy 212.248731 -329.308219) (xy 212.208582 -329.26951) (xy 212.174496 -329.225367) (xy 212.1472 -329.176732)
			(xy 212.127277 -329.124641) (xy 212.115151 -329.070204) (xy 212.11108 -329.014582) (xy 209.863944 -329.014582)
			(xy 210.360768 -329.511406) (xy 210.367617 -329.518803) (xy 210.375354 -329.537402) (xy 210.375754 -329.547474)
			(xy 210.375754 -329.574906) (xy 210.37618 -329.584975) (xy 210.383902 -329.603572) (xy 210.39074 -329.610974)
			(xy 211.080604 -330.300838) (xy 211.088 -330.307691) (xy 211.106598 -330.315434) (xy 211.116672 -330.315824)
		)
		(stroke
			(width 0)
			(type solid)
		)
		(fill yes)
		(layer "In15.Cu")
		(net "P3V3_AUX")
	)
	(gr_poly
		(pts
			(xy 305.133502 -335.505298) (xy 305.140106 -335.49209) (xy 305.152159 -335.468303) (xy 305.181921 -335.424055)
			(xy 305.217559 -335.384387) (xy 305.258377 -335.350072) (xy 305.303579 -335.32178) (xy 305.352283 -335.300064)
			(xy 305.403538 -335.285347) (xy 305.456343 -335.277916) (xy 305.483006 -335.27746) (xy 305.510376 -335.277932)
			(xy 305.564552 -335.285758) (xy 305.617054 -335.301248) (xy 305.666803 -335.324083) (xy 305.712776 -335.353796)
			(xy 305.733704 -335.37144) (xy 305.740816 -335.377536) (xy 305.757834 -335.383886) (xy 305.843178 -335.383886)
			(xy 305.860196 -335.377536) (xy 305.867308 -335.37144) (xy 305.876948 -335.363175) (xy 305.897159 -335.347796)
			(xy 305.907694 -335.340706) (xy 305.918616 -335.33334) (xy 305.930808 -335.31048) (xy 305.92903 -335.19872)
			(xy 305.91633 -335.176368) (xy 305.905154 -335.169256) (xy 305.877891 -335.151838) (xy 305.827591 -335.111152)
			(xy 305.782862 -335.06441) (xy 305.744428 -335.01237) (xy 305.712909 -334.955871) (xy 305.688816 -334.89583)
			(xy 305.672539 -334.833215) (xy 305.664341 -334.769042) (xy 305.663854 -334.736694) (xy 305.664333 -334.705999)
			(xy 305.671755 -334.645059) (xy 305.686453 -334.585454) (xy 305.708215 -334.52805) (xy 305.736724 -334.473681)
			(xy 305.75377 -334.44815) (xy 305.759243 -334.439399) (xy 305.763372 -334.419195) (xy 305.75924 -334.398992)
			(xy 305.75377 -334.390238) (xy 305.736712 -334.364712) (xy 305.708176 -334.310351) (xy 305.6864 -334.252948)
			(xy 305.671699 -334.193338) (xy 305.664289 -334.132392) (xy 305.663854 -334.101694) (xy 305.664333 -334.070999)
			(xy 305.671755 -334.010059) (xy 305.686453 -333.950454) (xy 305.708215 -333.89305) (xy 305.736724 -333.838681)
			(xy 305.75377 -333.81315) (xy 305.759243 -333.804399) (xy 305.763372 -333.784195) (xy 305.75924 -333.763992)
			(xy 305.75377 -333.755238) (xy 305.736712 -333.729712) (xy 305.708176 -333.675351) (xy 305.6864 -333.617948)
			(xy 305.671699 -333.558338) (xy 305.664289 -333.497392) (xy 305.663854 -333.466694) (xy 305.664333 -333.435999)
			(xy 305.671755 -333.375059) (xy 305.686453 -333.315454) (xy 305.708215 -333.25805) (xy 305.736724 -333.203681)
			(xy 305.75377 -333.17815) (xy 305.759243 -333.169399) (xy 305.763372 -333.149195) (xy 305.75924 -333.128992)
			(xy 305.75377 -333.120238) (xy 305.736712 -333.094712) (xy 305.708176 -333.040351) (xy 305.6864 -332.982948)
			(xy 305.671699 -332.923338) (xy 305.664289 -332.862392) (xy 305.663854 -332.831694) (xy 305.664333 -332.800999)
			(xy 305.671755 -332.740059) (xy 305.686453 -332.680454) (xy 305.708215 -332.62305) (xy 305.736724 -332.568681)
			(xy 305.75377 -332.54315) (xy 305.759243 -332.534399) (xy 305.763372 -332.514195) (xy 305.75924 -332.493992)
			(xy 305.75377 -332.485238) (xy 305.736712 -332.459712) (xy 305.708176 -332.405351) (xy 305.6864 -332.347948)
			(xy 305.671699 -332.288338) (xy 305.664289 -332.227392) (xy 305.663854 -332.196694) (xy 305.664333 -332.165999)
			(xy 305.671755 -332.105059) (xy 305.686453 -332.045454) (xy 305.708215 -331.98805) (xy 305.736724 -331.933681)
			(xy 305.75377 -331.90815) (xy 305.759243 -331.899399) (xy 305.763372 -331.879195) (xy 305.75924 -331.858992)
			(xy 305.75377 -331.850238) (xy 305.736712 -331.824712) (xy 305.708176 -331.770351) (xy 305.6864 -331.712948)
			(xy 305.671699 -331.653338) (xy 305.664289 -331.592392) (xy 305.663854 -331.561694) (xy 305.664333 -331.530999)
			(xy 305.671755 -331.470059) (xy 305.686453 -331.410454) (xy 305.708215 -331.35305) (xy 305.736724 -331.298681)
			(xy 305.75377 -331.27315) (xy 305.759243 -331.264399) (xy 305.763372 -331.244195) (xy 305.75924 -331.223992)
			(xy 305.75377 -331.215238) (xy 305.736712 -331.189712) (xy 305.708176 -331.135351) (xy 305.6864 -331.077948)
			(xy 305.671699 -331.018338) (xy 305.664289 -330.957392) (xy 305.663854 -330.926694) (xy 305.664333 -330.895999)
			(xy 305.671755 -330.835059) (xy 305.686453 -330.775454) (xy 305.708215 -330.71805) (xy 305.736724 -330.663681)
			(xy 305.75377 -330.63815) (xy 305.759243 -330.629399) (xy 305.763372 -330.609195) (xy 305.75924 -330.588992)
			(xy 305.75377 -330.580238) (xy 305.736712 -330.554712) (xy 305.708176 -330.500351) (xy 305.6864 -330.442948)
			(xy 305.671699 -330.383338) (xy 305.664289 -330.322392) (xy 305.663854 -330.291694) (xy 305.664318 -330.260962)
			(xy 305.671727 -330.199947) (xy 305.686436 -330.14027) (xy 305.708231 -330.082801) (xy 305.736793 -330.028377)
			(xy 305.771707 -329.977793) (xy 305.812464 -329.931786) (xy 305.858468 -329.891027) (xy 305.90905 -329.85611)
			(xy 305.963471 -329.827544) (xy 306.020939 -329.805745) (xy 306.080616 -329.791033) (xy 306.14163 -329.78362)
			(xy 306.172362 -329.783186) (xy 306.203056 -329.783668) (xy 306.263994 -329.791095) (xy 306.323597 -329.805797)
			(xy 306.380998 -329.827562) (xy 306.435365 -329.856072) (xy 306.460906 -329.873102) (xy 306.469658 -329.878573)
			(xy 306.489862 -329.882701) (xy 306.510066 -329.878573) (xy 306.518818 -329.873102) (xy 306.544346 -329.856049)
			(xy 306.598708 -329.827523) (xy 306.656112 -329.805755) (xy 306.715721 -329.791064) (xy 306.776666 -329.783662)
			(xy 306.807362 -329.783186) (xy 306.838056 -329.783668) (xy 306.898994 -329.791095) (xy 306.958597 -329.805797)
			(xy 307.015998 -329.827562) (xy 307.070365 -329.856072) (xy 307.095906 -329.873102) (xy 307.104658 -329.878573)
			(xy 307.124862 -329.882701) (xy 307.145066 -329.878573) (xy 307.153818 -329.873102) (xy 307.179346 -329.856049)
			(xy 307.233708 -329.827523) (xy 307.291112 -329.805755) (xy 307.350721 -329.791064) (xy 307.411666 -329.783662)
			(xy 307.442362 -329.783186) (xy 307.473096 -329.783629) (xy 307.534115 -329.791034) (xy 307.593798 -329.80574)
			(xy 307.651272 -329.827534) (xy 307.7057 -329.856096) (xy 307.756289 -329.891011) (xy 307.8023 -329.931769)
			(xy 307.843062 -329.977777) (xy 307.877981 -330.028362) (xy 307.906548 -330.082788) (xy 307.928346 -330.14026)
			(xy 307.943058 -330.199941) (xy 307.950468 -330.26096) (xy 307.95087 -330.291694) (xy 307.950392 -330.322389)
			(xy 307.942972 -330.38333) (xy 307.928275 -330.442936) (xy 307.906516 -330.500341) (xy 307.878009 -330.554712)
			(xy 307.860954 -330.580238) (xy 307.855484 -330.588991) (xy 307.851357 -330.609195) (xy 307.85548 -330.6294)
			(xy 307.860954 -330.63815) (xy 307.878007 -330.663677) (xy 307.906532 -330.71804) (xy 307.928298 -330.775445)
			(xy 307.942987 -330.835053) (xy 307.950386 -330.895998) (xy 307.95087 -330.926694) (xy 307.950392 -330.957389)
			(xy 307.942972 -331.01833) (xy 307.928275 -331.077936) (xy 307.906516 -331.135341) (xy 307.878009 -331.189712)
			(xy 307.860954 -331.215238) (xy 307.855484 -331.223991) (xy 307.851357 -331.244195) (xy 307.85548 -331.2644)
			(xy 307.860954 -331.27315) (xy 307.878007 -331.298677) (xy 307.906532 -331.35304) (xy 307.928298 -331.410445)
			(xy 307.942987 -331.470053) (xy 307.950386 -331.530998) (xy 307.95087 -331.561694) (xy 307.950392 -331.592389)
			(xy 307.942972 -331.65333) (xy 307.928275 -331.712936) (xy 307.906516 -331.770341) (xy 307.878009 -331.824712)
			(xy 307.860954 -331.850238) (xy 307.855484 -331.858991) (xy 307.851357 -331.879195) (xy 307.85548 -331.8994)
			(xy 307.860954 -331.90815) (xy 307.878007 -331.933677) (xy 307.906532 -331.98804) (xy 307.928298 -332.045445)
			(xy 307.942987 -332.105053) (xy 307.950386 -332.165998) (xy 307.95087 -332.196694) (xy 307.950392 -332.227389)
			(xy 307.942972 -332.28833) (xy 307.928275 -332.347936) (xy 307.906516 -332.405341) (xy 307.878009 -332.459712)
			(xy 307.860954 -332.485238) (xy 307.855484 -332.493991) (xy 307.851357 -332.514195) (xy 307.85548 -332.5344)
			(xy 307.860954 -332.54315) (xy 307.878007 -332.568677) (xy 307.906532 -332.62304) (xy 307.928298 -332.680445)
			(xy 307.942987 -332.740053) (xy 307.950386 -332.800998) (xy 307.95087 -332.831694) (xy 307.950392 -332.862389)
			(xy 307.942972 -332.92333) (xy 307.928275 -332.982936) (xy 307.906516 -333.040341) (xy 307.878009 -333.094712)
			(xy 307.860954 -333.120238) (xy 307.855484 -333.128991) (xy 307.851357 -333.149195) (xy 307.85548 -333.1694)
			(xy 307.860954 -333.17815) (xy 307.878007 -333.203677) (xy 307.906532 -333.25804) (xy 307.928298 -333.315445)
			(xy 307.942987 -333.375053) (xy 307.950386 -333.435998) (xy 307.95087 -333.466694) (xy 307.950392 -333.497389)
			(xy 307.942972 -333.55833) (xy 307.928275 -333.617936) (xy 307.906516 -333.675341) (xy 307.878009 -333.729712)
			(xy 307.860954 -333.755238) (xy 307.855484 -333.763991) (xy 307.851357 -333.784195) (xy 307.85548 -333.8044)
			(xy 307.860954 -333.81315) (xy 307.878007 -333.838677) (xy 307.906532 -333.89304) (xy 307.928298 -333.950445)
			(xy 307.942987 -334.010053) (xy 307.950386 -334.070998) (xy 307.95087 -334.101694) (xy 307.950392 -334.132389)
			(xy 307.942972 -334.19333) (xy 307.928275 -334.252936) (xy 307.906516 -334.310341) (xy 307.878009 -334.364712)
			(xy 307.860954 -334.390238) (xy 307.855484 -334.398991) (xy 307.851357 -334.419195) (xy 307.85548 -334.4394)
			(xy 307.860954 -334.44815) (xy 307.878007 -334.473677) (xy 307.906532 -334.52804) (xy 307.928298 -334.585445)
			(xy 307.942987 -334.645053) (xy 307.950386 -334.705998) (xy 307.95087 -334.736694) (xy 309.677054 -334.736694)
			(xy 309.677534 -334.705998) (xy 309.684933 -334.645053) (xy 309.699623 -334.585444) (xy 309.72139 -334.52804)
			(xy 309.749916 -334.473677) (xy 309.76697 -334.44815) (xy 309.77245 -334.439402) (xy 309.776579 -334.419195)
			(xy 309.772446 -334.398989) (xy 309.76697 -334.390238) (xy 309.749918 -334.364711) (xy 309.72141 -334.31034)
			(xy 309.69965 -334.252936) (xy 309.684953 -334.19333) (xy 309.677532 -334.132389) (xy 309.677054 -334.101694)
			(xy 309.677534 -334.070998) (xy 309.684933 -334.010053) (xy 309.699623 -333.950444) (xy 309.72139 -333.89304)
			(xy 309.749916 -333.838677) (xy 309.76697 -333.81315) (xy 309.77245 -333.804402) (xy 309.776579 -333.784195)
			(xy 309.772446 -333.763989) (xy 309.76697 -333.755238) (xy 309.749918 -333.729711) (xy 309.72141 -333.67534)
			(xy 309.69965 -333.617936) (xy 309.684953 -333.55833) (xy 309.677532 -333.497389) (xy 309.677054 -333.466694)
			(xy 309.677534 -333.435998) (xy 309.684933 -333.375053) (xy 309.699623 -333.315444) (xy 309.72139 -333.25804)
			(xy 309.749916 -333.203677) (xy 309.76697 -333.17815) (xy 309.77245 -333.169402) (xy 309.776579 -333.149195)
			(xy 309.772446 -333.128989) (xy 309.76697 -333.120238) (xy 309.749918 -333.094711) (xy 309.72141 -333.04034)
			(xy 309.69965 -332.982936) (xy 309.684953 -332.92333) (xy 309.677532 -332.862389) (xy 309.677054 -332.831694)
			(xy 309.677534 -332.800998) (xy 309.684933 -332.740053) (xy 309.699623 -332.680444) (xy 309.72139 -332.62304)
			(xy 309.749916 -332.568677) (xy 309.76697 -332.54315) (xy 309.77245 -332.534402) (xy 309.776579 -332.514195)
			(xy 309.772446 -332.493989) (xy 309.76697 -332.485238) (xy 309.749918 -332.459711) (xy 309.72141 -332.40534)
			(xy 309.69965 -332.347936) (xy 309.684953 -332.28833) (xy 309.677532 -332.227389) (xy 309.677054 -332.196694)
			(xy 309.677534 -332.165998) (xy 309.684933 -332.105053) (xy 309.699623 -332.045444) (xy 309.72139 -331.98804)
			(xy 309.749916 -331.933677) (xy 309.76697 -331.90815) (xy 309.77245 -331.899402) (xy 309.776579 -331.879195)
			(xy 309.772446 -331.858989) (xy 309.76697 -331.850238) (xy 309.749918 -331.824711) (xy 309.72141 -331.77034)
			(xy 309.69965 -331.712936) (xy 309.684953 -331.65333) (xy 309.677532 -331.592389) (xy 309.677054 -331.561694)
			(xy 309.677534 -331.530998) (xy 309.684933 -331.470053) (xy 309.699623 -331.410444) (xy 309.72139 -331.35304)
			(xy 309.749916 -331.298677) (xy 309.76697 -331.27315) (xy 309.77245 -331.264402) (xy 309.776579 -331.244195)
			(xy 309.772446 -331.223989) (xy 309.76697 -331.215238) (xy 309.749918 -331.189711) (xy 309.72141 -331.13534)
			(xy 309.69965 -331.077936) (xy 309.684953 -331.01833) (xy 309.677532 -330.957389) (xy 309.677054 -330.926694)
			(xy 309.677534 -330.895998) (xy 309.684933 -330.835053) (xy 309.699623 -330.775444) (xy 309.72139 -330.71804)
			(xy 309.749916 -330.663677) (xy 309.76697 -330.63815) (xy 309.77245 -330.629402) (xy 309.776579 -330.609195)
			(xy 309.772446 -330.588989) (xy 309.76697 -330.580238) (xy 309.749918 -330.554711) (xy 309.72141 -330.50034)
			(xy 309.69965 -330.442936) (xy 309.684953 -330.38333) (xy 309.677532 -330.322389) (xy 309.677054 -330.291694)
			(xy 309.67755 -330.260964) (xy 309.684959 -330.199953) (xy 309.699667 -330.14028) (xy 309.72146 -330.082814)
			(xy 309.750021 -330.028394) (xy 309.784933 -329.977813) (xy 309.825687 -329.931809) (xy 309.871688 -329.891052)
			(xy 309.922267 -329.856138) (xy 309.976685 -329.827573) (xy 310.034149 -329.805776) (xy 310.093822 -329.791065)
			(xy 310.154832 -329.783652) (xy 310.185562 -329.783186) (xy 310.216259 -329.783649) (xy 310.277204 -329.791054)
			(xy 310.336812 -329.805749) (xy 310.394216 -329.827519) (xy 310.448579 -329.856047) (xy 310.474106 -329.873102)
			(xy 310.482858 -329.878573) (xy 310.503062 -329.882701) (xy 310.523266 -329.878573) (xy 310.532018 -329.873102)
			(xy 310.557552 -329.856061) (xy 310.611921 -329.827553) (xy 310.669324 -329.805791) (xy 310.728928 -329.791091)
			(xy 310.789867 -329.783667) (xy 310.820562 -329.783186) (xy 310.851293 -329.783673) (xy 310.912308 -329.791078)
			(xy 310.971985 -329.805782) (xy 311.029454 -329.827574) (xy 311.083878 -329.856134) (xy 311.134462 -329.891046)
			(xy 311.180469 -329.9318) (xy 311.221227 -329.977804) (xy 311.256144 -330.028385) (xy 311.284708 -330.082806)
			(xy 311.306504 -330.140273) (xy 311.321215 -330.199949) (xy 311.328624 -330.260963) (xy 311.32907 -330.291694)
			(xy 311.328631 -330.322391) (xy 311.321221 -330.383338) (xy 311.306521 -330.442947) (xy 311.284746 -330.50035)
			(xy 311.256212 -330.554712) (xy 311.239154 -330.580238) (xy 311.233691 -330.588994) (xy 311.229564 -330.609195)
			(xy 311.233687 -330.629397) (xy 311.239154 -330.63815) (xy 311.256203 -330.663679) (xy 311.284711 -330.718049)
			(xy 311.306472 -330.775453) (xy 311.32117 -330.835059) (xy 311.328591 -330.895999) (xy 311.32907 -330.926694)
			(xy 311.328631 -330.957391) (xy 311.321221 -331.018338) (xy 311.306521 -331.077947) (xy 311.284746 -331.13535)
			(xy 311.256212 -331.189712) (xy 311.239154 -331.215238) (xy 311.233691 -331.223994) (xy 311.229564 -331.244195)
			(xy 311.233687 -331.264397) (xy 311.239154 -331.27315) (xy 311.256203 -331.298679) (xy 311.284711 -331.353049)
			(xy 311.306472 -331.410453) (xy 311.32117 -331.470059) (xy 311.328591 -331.530999) (xy 311.32907 -331.561694)
			(xy 311.328631 -331.592391) (xy 311.321221 -331.653338) (xy 311.306521 -331.712947) (xy 311.284746 -331.77035)
			(xy 311.256212 -331.824712) (xy 311.239154 -331.850238) (xy 311.233691 -331.858994) (xy 311.229564 -331.879195)
			(xy 311.233687 -331.899397) (xy 311.239154 -331.90815) (xy 311.256203 -331.933679) (xy 311.284711 -331.988049)
			(xy 311.306472 -332.045453) (xy 311.32117 -332.105059) (xy 311.328591 -332.165999) (xy 311.32907 -332.196694)
			(xy 311.328631 -332.227391) (xy 311.321221 -332.288338) (xy 311.306521 -332.347947) (xy 311.284746 -332.40535)
			(xy 311.256212 -332.459712) (xy 311.239154 -332.485238) (xy 311.233691 -332.493994) (xy 311.229564 -332.514195)
			(xy 311.233687 -332.534397) (xy 311.239154 -332.54315) (xy 311.256203 -332.568679) (xy 311.284711 -332.623049)
			(xy 311.306472 -332.680453) (xy 311.32117 -332.740059) (xy 311.328591 -332.800999) (xy 311.32907 -332.831694)
			(xy 311.328631 -332.862391) (xy 311.321221 -332.923338) (xy 311.306521 -332.982947) (xy 311.284746 -333.04035)
			(xy 311.256212 -333.094712) (xy 311.239154 -333.120238) (xy 311.233691 -333.128994) (xy 311.229564 -333.149195)
			(xy 311.233687 -333.169397) (xy 311.239154 -333.17815) (xy 311.256203 -333.203679) (xy 311.284711 -333.258049)
			(xy 311.306472 -333.315453) (xy 311.32117 -333.375059) (xy 311.328591 -333.435999) (xy 311.32907 -333.466694)
			(xy 311.328631 -333.497391) (xy 311.321221 -333.558338) (xy 311.306521 -333.617947) (xy 311.284746 -333.67535)
			(xy 311.256212 -333.729712) (xy 311.239154 -333.755238) (xy 311.233691 -333.763994) (xy 311.229564 -333.784195)
			(xy 311.233687 -333.804397) (xy 311.239154 -333.81315) (xy 311.256203 -333.838679) (xy 311.284711 -333.893049)
			(xy 311.306472 -333.950453) (xy 311.32117 -334.010059) (xy 311.328591 -334.070999) (xy 311.32907 -334.101694)
			(xy 311.328631 -334.132391) (xy 311.321221 -334.193338) (xy 311.306521 -334.252947) (xy 311.284746 -334.31035)
			(xy 311.256212 -334.364712) (xy 311.239154 -334.390238) (xy 311.233691 -334.398994) (xy 311.229564 -334.419195)
			(xy 311.233687 -334.439397) (xy 311.239154 -334.44815) (xy 311.256203 -334.473679) (xy 311.284711 -334.528049)
			(xy 311.306472 -334.585453) (xy 311.32117 -334.645059) (xy 311.328591 -334.705999) (xy 311.32907 -334.736694)
			(xy 311.328657 -334.767427) (xy 311.321248 -334.828446) (xy 311.306538 -334.888127) (xy 311.284741 -334.945599)
			(xy 311.256175 -335.000025) (xy 311.221257 -335.050611) (xy 311.180495 -335.096618) (xy 311.134485 -335.137377)
			(xy 311.083898 -335.172292) (xy 311.02947 -335.200854) (xy 310.971996 -335.222647) (xy 310.912315 -335.237354)
			(xy 310.851295 -335.244759) (xy 310.820562 -335.245202) (xy 310.789866 -335.244729) (xy 310.728921 -335.237326)
			(xy 310.669312 -335.222634) (xy 310.611908 -335.200866) (xy 310.557545 -335.17234) (xy 310.532018 -335.155286)
			(xy 310.523266 -335.149815) (xy 310.503062 -335.145687) (xy 310.482858 -335.149815) (xy 310.474106 -335.155286)
			(xy 310.448564 -335.172315) (xy 310.394197 -335.200826) (xy 310.336796 -335.22259) (xy 310.277194 -335.237293)
			(xy 310.216256 -335.24472) (xy 310.185562 -335.245202) (xy 310.15483 -335.24478) (xy 310.093814 -335.237367)
			(xy 310.034137 -335.222654) (xy 309.976669 -335.200855) (xy 309.922246 -335.172288) (xy 309.871664 -335.13737)
			(xy 309.825659 -335.09661) (xy 309.784903 -335.050601) (xy 309.749989 -335.000016) (xy 309.721427 -334.945591)
			(xy 309.699633 -334.888121) (xy 309.684925 -334.828442) (xy 309.677517 -334.767426) (xy 309.677054 -334.736694)
			(xy 307.95087 -334.736694) (xy 307.950425 -334.767426) (xy 307.943016 -334.82844) (xy 307.928307 -334.888117)
			(xy 307.906512 -334.945586) (xy 307.877948 -335.000009) (xy 307.843032 -335.050591) (xy 307.802273 -335.096595)
			(xy 307.756266 -335.137351) (xy 307.705681 -335.172264) (xy 307.651257 -335.200825) (xy 307.593787 -335.222617)
			(xy 307.534109 -335.237322) (xy 307.473094 -335.244727) (xy 307.442362 -335.245202) (xy 307.411667 -335.244721)
			(xy 307.350728 -335.237297) (xy 307.291125 -335.222597) (xy 307.233722 -335.200834) (xy 307.179353 -335.172325)
			(xy 307.153818 -335.155286) (xy 307.145066 -335.149815) (xy 307.124862 -335.145687) (xy 307.104658 -335.149815)
			(xy 307.095906 -335.155286) (xy 307.070379 -335.172341) (xy 307.016017 -335.20087) (xy 306.958613 -335.222641)
			(xy 306.899004 -335.237336) (xy 306.838059 -335.244741) (xy 306.807362 -335.245202) (xy 306.776667 -335.244721)
			(xy 306.715728 -335.237297) (xy 306.656125 -335.222597) (xy 306.598722 -335.200834) (xy 306.544353 -335.172325)
			(xy 306.518818 -335.155286) (xy 306.510066 -335.149815) (xy 306.489862 -335.145687) (xy 306.469658 -335.149815)
			(xy 306.460906 -335.155286) (xy 306.443171 -335.167244) (xy 306.406039 -335.188485) (xy 306.386738 -335.197704)
			(xy 306.375054 -335.203292) (xy 306.35956 -335.22412) (xy 306.344828 -335.334864) (xy 306.354226 -335.358994)
			(xy 306.364132 -335.367376) (xy 306.384073 -335.384853) (xy 306.419409 -335.424387) (xy 306.448928 -335.468434)
			(xy 306.460906 -335.49209) (xy 306.46751 -335.505298) (xy 306.491894 -335.520538) (xy 311.987946 -335.520538)
			(xy 311.998011 -335.520105) (xy 312.016598 -335.512372) (xy 312.024014 -335.505552) (xy 312.77306 -334.756506)
			(xy 312.779912 -334.74911) (xy 312.787655 -334.730511) (xy 312.788046 -334.720438) (xy 312.788046 -328.09815)
			(xy 312.78848 -328.088085) (xy 312.796212 -328.069498) (xy 312.803032 -328.062082) (xy 313.756548 -327.108566)
			(xy 313.763946 -327.10172) (xy 313.782545 -327.093992) (xy 313.792616 -327.09358) (xy 348.668848 -327.09358)
			(xy 348.677437 -327.093288) (xy 348.693673 -327.087686) (xy 348.70714 -327.077028) (xy 348.712028 -327.069958)
			(xy 348.723712 -327.052178) (xy 348.729187 -327.043426) (xy 348.733323 -327.023218) (xy 348.729202 -327.003008)
			(xy 348.723712 -326.994266) (xy 348.706659 -326.968738) (xy 348.678135 -326.914375) (xy 348.656369 -326.856971)
			(xy 348.641678 -326.797363) (xy 348.634278 -326.736418) (xy 348.633796 -326.705722) (xy 348.634273 -326.675026)
			(xy 348.641691 -326.614084) (xy 348.656385 -326.554477) (xy 348.678142 -326.49707) (xy 348.706646 -326.442696)
			(xy 348.723712 -326.417178) (xy 348.729187 -326.408426) (xy 348.733323 -326.388218) (xy 348.729202 -326.368008)
			(xy 348.723712 -326.359266) (xy 348.706659 -326.333738) (xy 348.678135 -326.279375) (xy 348.656369 -326.221971)
			(xy 348.641678 -326.162363) (xy 348.634278 -326.101418) (xy 348.633796 -326.070722) (xy 348.634273 -326.040026)
			(xy 348.641691 -325.979084) (xy 348.656385 -325.919477) (xy 348.678142 -325.86207) (xy 348.706646 -325.807696)
			(xy 348.723712 -325.782178) (xy 348.729187 -325.773426) (xy 348.733323 -325.753218) (xy 348.729202 -325.733008)
			(xy 348.723712 -325.724266) (xy 348.706659 -325.698738) (xy 348.678135 -325.644375) (xy 348.656369 -325.586971)
			(xy 348.641678 -325.527363) (xy 348.634278 -325.466418) (xy 348.633796 -325.435722) (xy 348.634209 -325.405525)
			(xy 348.641328 -325.345552) (xy 348.655502 -325.286846) (xy 348.676534 -325.230233) (xy 348.704125 -325.17651)
			(xy 348.720664 -325.151242) (xy 348.726305 -325.142064) (xy 348.730026 -325.120865) (xy 348.724717 -325.100007)
			(xy 348.718378 -325.091298) (xy 348.697616 -325.064233) (xy 348.662763 -325.005595) (xy 348.636073 -324.942819)
			(xy 348.618025 -324.877036) (xy 348.608945 -324.809429) (xy 348.608396 -324.775322) (xy 348.608873 -324.744626)
			(xy 348.616291 -324.683684) (xy 348.630985 -324.624077) (xy 348.652742 -324.56667) (xy 348.681246 -324.512296)
			(xy 348.698312 -324.486778) (xy 348.703787 -324.478026) (xy 348.707923 -324.457818) (xy 348.703802 -324.437608)
			(xy 348.698312 -324.428866) (xy 348.681259 -324.403338) (xy 348.652735 -324.348975) (xy 348.630969 -324.291571)
			(xy 348.616278 -324.231963) (xy 348.608878 -324.171018) (xy 348.608396 -324.140322) (xy 348.608873 -324.109626)
			(xy 348.616291 -324.048684) (xy 348.630985 -323.989077) (xy 348.652742 -323.93167) (xy 348.681246 -323.877296)
			(xy 348.698312 -323.851778) (xy 348.703787 -323.843026) (xy 348.707923 -323.822818) (xy 348.703802 -323.802608)
			(xy 348.698312 -323.793866) (xy 348.681259 -323.768338) (xy 348.652735 -323.713975) (xy 348.630969 -323.656571)
			(xy 348.616278 -323.596963) (xy 348.608878 -323.536018) (xy 348.608396 -323.505322) (xy 348.608873 -323.474626)
			(xy 348.616291 -323.413684) (xy 348.630985 -323.354077) (xy 348.652742 -323.29667) (xy 348.681246 -323.242296)
			(xy 348.698312 -323.216778) (xy 348.703787 -323.208026) (xy 348.707923 -323.187818) (xy 348.703802 -323.167608)
			(xy 348.698312 -323.158866) (xy 348.681259 -323.133338) (xy 348.652735 -323.078975) (xy 348.630969 -323.021571)
			(xy 348.616278 -322.961963) (xy 348.608878 -322.901018) (xy 348.608396 -322.870322) (xy 348.608873 -322.839626)
			(xy 348.616291 -322.778684) (xy 348.630985 -322.719077) (xy 348.652742 -322.66167) (xy 348.681246 -322.607296)
			(xy 348.698312 -322.581778) (xy 348.703787 -322.573026) (xy 348.707923 -322.552818) (xy 348.703802 -322.532608)
			(xy 348.698312 -322.523866) (xy 348.681259 -322.498338) (xy 348.652735 -322.443975) (xy 348.630969 -322.386571)
			(xy 348.616278 -322.326963) (xy 348.608878 -322.266018) (xy 348.608396 -322.235322) (xy 348.608873 -322.204626)
			(xy 348.616291 -322.143684) (xy 348.630985 -322.084077) (xy 348.652742 -322.02667) (xy 348.681246 -321.972296)
			(xy 348.698312 -321.946778) (xy 348.703787 -321.938026) (xy 348.707923 -321.917818) (xy 348.703802 -321.897608)
			(xy 348.698312 -321.888866) (xy 348.681259 -321.863338) (xy 348.652735 -321.808975) (xy 348.630969 -321.751571)
			(xy 348.616278 -321.691963) (xy 348.608878 -321.631018) (xy 348.608396 -321.600322) (xy 348.60884 -321.569589)
			(xy 348.616247 -321.508571) (xy 348.630954 -321.448891) (xy 348.652749 -321.391419) (xy 348.681312 -321.336993)
			(xy 348.716227 -321.286407) (xy 348.756985 -321.240398) (xy 348.802993 -321.199638) (xy 348.853577 -321.164721)
			(xy 348.908002 -321.136156) (xy 348.965474 -321.11436) (xy 349.025154 -321.09965) (xy 349.086171 -321.092241)
			(xy 349.116904 -321.091814) (xy 349.147599 -321.092293) (xy 349.20854 -321.099714) (xy 349.268145 -321.114411)
			(xy 349.32555 -321.136171) (xy 349.379921 -321.164678) (xy 349.405448 -321.18173) (xy 349.4142 -321.187201)
			(xy 349.434404 -321.191329) (xy 349.454608 -321.187201) (xy 349.46336 -321.18173) (xy 349.488886 -321.164673)
			(xy 349.543248 -321.136139) (xy 349.600651 -321.114364) (xy 349.660261 -321.099665) (xy 349.721207 -321.092255)
			(xy 349.751904 -321.091814) (xy 349.782599 -321.092293) (xy 349.84354 -321.099714) (xy 349.903145 -321.114411)
			(xy 349.96055 -321.136171) (xy 350.014921 -321.164678) (xy 350.040448 -321.18173) (xy 350.0492 -321.187201)
			(xy 350.069404 -321.191329) (xy 350.089608 -321.187201) (xy 350.09836 -321.18173) (xy 350.123886 -321.164673)
			(xy 350.178248 -321.136139) (xy 350.235651 -321.114364) (xy 350.295261 -321.099665) (xy 350.356207 -321.092255)
			(xy 350.386904 -321.091814) (xy 350.417635 -321.09226) (xy 350.47865 -321.099669) (xy 350.538327 -321.114379)
			(xy 350.595795 -321.136175) (xy 350.650218 -321.164739) (xy 350.7008 -321.199655) (xy 350.746805 -321.240414)
			(xy 350.787561 -321.286421) (xy 350.822474 -321.337005) (xy 350.851036 -321.391428) (xy 350.872829 -321.448898)
			(xy 350.887536 -321.508575) (xy 350.894942 -321.569591) (xy 350.895412 -321.600322) (xy 350.894932 -321.631017)
			(xy 350.88751 -321.691957) (xy 350.872811 -321.751562) (xy 350.851051 -321.808966) (xy 350.822543 -321.863336)
			(xy 350.805496 -321.888866) (xy 350.800028 -321.897618) (xy 350.795908 -321.917818) (xy 350.800043 -321.938016)
			(xy 350.805496 -321.946778) (xy 350.822551 -321.972305) (xy 350.851082 -322.026667) (xy 350.872854 -322.084071)
			(xy 350.88755 -322.14368) (xy 350.894957 -322.204625) (xy 350.895412 -322.235322) (xy 350.894932 -322.266017)
			(xy 350.88751 -322.326957) (xy 350.872811 -322.386562) (xy 350.851051 -322.443966) (xy 350.822543 -322.498336)
			(xy 350.805496 -322.523866) (xy 350.800028 -322.532618) (xy 350.795908 -322.552818) (xy 350.800043 -322.573016)
			(xy 350.805496 -322.581778) (xy 350.822551 -322.607305) (xy 350.851082 -322.661667) (xy 350.872854 -322.719071)
			(xy 350.88755 -322.77868) (xy 350.894957 -322.839625) (xy 350.895412 -322.870322) (xy 350.894932 -322.901017)
			(xy 350.88751 -322.961957) (xy 350.872811 -323.021562) (xy 350.851051 -323.078966) (xy 350.822543 -323.133336)
			(xy 350.805496 -323.158866) (xy 350.800028 -323.167618) (xy 350.795908 -323.187818) (xy 350.800043 -323.208016)
			(xy 350.805496 -323.216778) (xy 350.822551 -323.242305) (xy 350.851082 -323.296667) (xy 350.872854 -323.354071)
			(xy 350.88755 -323.41368) (xy 350.894957 -323.474625) (xy 350.895412 -323.505322) (xy 350.894932 -323.536017)
			(xy 350.88751 -323.596957) (xy 350.872811 -323.656562) (xy 350.851051 -323.713966) (xy 350.822543 -323.768336)
			(xy 350.805496 -323.793866) (xy 350.800028 -323.802618) (xy 350.795908 -323.822818) (xy 350.800043 -323.843016)
			(xy 350.805496 -323.851778) (xy 350.822551 -323.877305) (xy 350.851082 -323.931667) (xy 350.872854 -323.989071)
			(xy 350.88755 -324.04868) (xy 350.894957 -324.109625) (xy 350.895412 -324.140322) (xy 350.894932 -324.171017)
			(xy 350.88751 -324.231957) (xy 350.872811 -324.291562) (xy 350.851051 -324.348966) (xy 350.822543 -324.403336)
			(xy 350.805496 -324.428866) (xy 350.800028 -324.437618) (xy 350.795908 -324.457818) (xy 350.800043 -324.478016)
			(xy 350.805496 -324.486778) (xy 350.822551 -324.512305) (xy 350.851082 -324.566667) (xy 350.872854 -324.624071)
			(xy 350.88755 -324.68368) (xy 350.894957 -324.744625) (xy 350.895412 -324.775322) (xy 350.895011 -324.804279)
			(xy 350.888439 -324.86182) (xy 350.875362 -324.918238) (xy 350.855948 -324.972802) (xy 350.830451 -325.024802)
			(xy 350.815148 -325.049388) (xy 350.809963 -325.058382) (xy 350.806588 -325.078846) (xy 350.811582 -325.098976)
			(xy 350.817434 -325.107554) (xy 350.836972 -325.134173) (xy 350.869741 -325.191499) (xy 350.894814 -325.252585)
			(xy 350.911767 -325.316403) (xy 350.920316 -325.381878) (xy 350.920812 -325.414894) (xy 350.920334 -325.445589)
			(xy 350.912914 -325.506531) (xy 350.898219 -325.566137) (xy 350.876461 -325.623543) (xy 350.847956 -325.677916)
			(xy 350.830896 -325.703438) (xy 350.825423 -325.71219) (xy 350.821292 -325.732395) (xy 350.825419 -325.752601)
			(xy 350.830896 -325.76135) (xy 350.847948 -325.786878) (xy 350.87647 -325.841241) (xy 350.898234 -325.898646)
			(xy 350.912922 -325.958254) (xy 350.920321 -326.019198) (xy 350.920812 -326.049894) (xy 350.920334 -326.080589)
			(xy 350.912914 -326.141531) (xy 350.898219 -326.201137) (xy 350.876461 -326.258543) (xy 350.847956 -326.312916)
			(xy 350.830896 -326.338438) (xy 350.825423 -326.34719) (xy 350.821292 -326.367395) (xy 350.825419 -326.387601)
			(xy 350.830896 -326.39635) (xy 350.847948 -326.421878) (xy 350.87647 -326.476241) (xy 350.898234 -326.533646)
			(xy 350.912922 -326.593254) (xy 350.920321 -326.654198) (xy 350.920812 -326.684894) (xy 350.920334 -326.715589)
			(xy 350.912914 -326.776531) (xy 350.898219 -326.836137) (xy 350.876461 -326.893543) (xy 350.847956 -326.947916)
			(xy 350.830896 -326.973438) (xy 350.825423 -326.98219) (xy 350.821292 -327.002395) (xy 350.825419 -327.022601)
			(xy 350.830896 -327.03135) (xy 350.85401 -327.067926) (xy 350.858738 -327.075544) (xy 350.872416 -327.087118)
			(xy 350.889246 -327.093264) (xy 350.898206 -327.09358) (xy 352.669602 -327.09358) (xy 352.678558 -327.093235)
			(xy 352.695384 -327.08709) (xy 352.709081 -327.075546) (xy 352.713798 -327.067926) (xy 352.736912 -327.03135)
			(xy 352.742382 -327.022598) (xy 352.746507 -327.002395) (xy 352.742378 -326.982193) (xy 352.736912 -326.973438)
			(xy 352.719855 -326.947911) (xy 352.691323 -326.89355) (xy 352.669549 -326.836146) (xy 352.65485 -326.776537)
			(xy 352.647441 -326.715591) (xy 352.646996 -326.684894) (xy 352.647475 -326.654199) (xy 352.654896 -326.593258)
			(xy 352.669593 -326.533653) (xy 352.691352 -326.476247) (xy 352.719859 -326.421876) (xy 352.736912 -326.39635)
			(xy 352.742382 -326.387598) (xy 352.746507 -326.367395) (xy 352.742378 -326.347193) (xy 352.736912 -326.338438)
			(xy 352.719855 -326.312911) (xy 352.691323 -326.25855) (xy 352.669549 -326.201146) (xy 352.65485 -326.141537)
			(xy 352.647441 -326.080591) (xy 352.646996 -326.049894) (xy 352.647475 -326.019199) (xy 352.654896 -325.958258)
			(xy 352.669593 -325.898653) (xy 352.691352 -325.841247) (xy 352.719859 -325.786876) (xy 352.736912 -325.76135)
			(xy 352.742382 -325.752598) (xy 352.746507 -325.732395) (xy 352.742378 -325.712193) (xy 352.736912 -325.703438)
			(xy 352.719855 -325.677911) (xy 352.691323 -325.62355) (xy 352.669549 -325.566146) (xy 352.65485 -325.506537)
			(xy 352.647441 -325.445591) (xy 352.646996 -325.414894) (xy 352.647457 -325.383921) (xy 352.654988 -325.322433)
			(xy 352.669936 -325.262317) (xy 352.692081 -325.204464) (xy 352.721094 -325.149731) (xy 352.738436 -325.124064)
			(xy 352.743907 -325.115311) (xy 352.748036 -325.095107) (xy 352.743912 -325.074901) (xy 352.738436 -325.066152)
			(xy 352.721091 -325.040487) (xy 352.692081 -324.985753) (xy 352.669939 -324.927899) (xy 352.654991 -324.867782)
			(xy 352.64746 -324.806295) (xy 352.646996 -324.775322) (xy 352.647473 -324.744626) (xy 352.654891 -324.683684)
			(xy 352.669585 -324.624077) (xy 352.691342 -324.56667) (xy 352.719846 -324.512296) (xy 352.736912 -324.486778)
			(xy 352.742387 -324.478026) (xy 352.746523 -324.457818) (xy 352.742402 -324.437608) (xy 352.736912 -324.428866)
			(xy 352.719859 -324.403338) (xy 352.691335 -324.348975) (xy 352.669569 -324.291571) (xy 352.654878 -324.231963)
			(xy 352.647478 -324.171018) (xy 352.646996 -324.140322) (xy 352.647473 -324.109626) (xy 352.654891 -324.048684)
			(xy 352.669585 -323.989077) (xy 352.691342 -323.93167) (xy 352.719846 -323.877296) (xy 352.736912 -323.851778)
			(xy 352.742387 -323.843026) (xy 352.746523 -323.822818) (xy 352.742402 -323.802608) (xy 352.736912 -323.793866)
			(xy 352.719859 -323.768338) (xy 352.691335 -323.713975) (xy 352.669569 -323.656571) (xy 352.654878 -323.596963)
			(xy 352.647478 -323.536018) (xy 352.646996 -323.505322) (xy 352.647473 -323.474626) (xy 352.654891 -323.413684)
			(xy 352.669585 -323.354077) (xy 352.691342 -323.29667) (xy 352.719846 -323.242296) (xy 352.736912 -323.216778)
			(xy 352.742387 -323.208026) (xy 352.746523 -323.187818) (xy 352.742402 -323.167608) (xy 352.736912 -323.158866)
			(xy 352.719859 -323.133338) (xy 352.691335 -323.078975) (xy 352.669569 -323.021571) (xy 352.654878 -322.961963)
			(xy 352.647478 -322.901018) (xy 352.646996 -322.870322) (xy 352.647473 -322.839626) (xy 352.654891 -322.778684)
			(xy 352.669585 -322.719077) (xy 352.691342 -322.66167) (xy 352.719846 -322.607296) (xy 352.736912 -322.581778)
			(xy 352.742387 -322.573026) (xy 352.746523 -322.552818) (xy 352.742402 -322.532608) (xy 352.736912 -322.523866)
			(xy 352.719859 -322.498338) (xy 352.691335 -322.443975) (xy 352.669569 -322.386571) (xy 352.654878 -322.326963)
			(xy 352.647478 -322.266018) (xy 352.646996 -322.235322) (xy 352.64744 -322.204589) (xy 352.654847 -322.143571)
			(xy 352.669554 -322.083891) (xy 352.691349 -322.026419) (xy 352.719912 -321.971993) (xy 352.754827 -321.921407)
			(xy 352.795585 -321.875398) (xy 352.841593 -321.834638) (xy 352.892177 -321.799721) (xy 352.946602 -321.771156)
			(xy 353.004074 -321.74936) (xy 353.063754 -321.73465) (xy 353.124771 -321.727241) (xy 353.155504 -321.726814)
			(xy 353.186199 -321.727293) (xy 353.24714 -321.734714) (xy 353.306745 -321.749411) (xy 353.36415 -321.771171)
			(xy 353.418521 -321.799678) (xy 353.444048 -321.81673) (xy 353.4528 -321.822201) (xy 353.473004 -321.826329)
			(xy 353.493208 -321.822201) (xy 353.50196 -321.81673) (xy 353.527486 -321.799673) (xy 353.581848 -321.771139)
			(xy 353.639251 -321.749364) (xy 353.698861 -321.734665) (xy 353.759807 -321.727255) (xy 353.790504 -321.726814)
			(xy 353.821199 -321.727293) (xy 353.88214 -321.734714) (xy 353.941745 -321.749411) (xy 353.99915 -321.771171)
			(xy 354.053521 -321.799678) (xy 354.079048 -321.81673) (xy 354.0878 -321.822201) (xy 354.108004 -321.826329)
			(xy 354.128208 -321.822201) (xy 354.13696 -321.81673) (xy 354.162486 -321.799673) (xy 354.216848 -321.771139)
			(xy 354.274251 -321.749364) (xy 354.333861 -321.734665) (xy 354.394807 -321.727255) (xy 354.425504 -321.726814)
			(xy 354.456235 -321.72726) (xy 354.51725 -321.734669) (xy 354.576927 -321.749379) (xy 354.634395 -321.771175)
			(xy 354.688818 -321.799739) (xy 354.7394 -321.834655) (xy 354.785405 -321.875414) (xy 354.826161 -321.921421)
			(xy 354.861074 -321.972005) (xy 354.889636 -322.026428) (xy 354.911429 -322.083898) (xy 354.926136 -322.143575)
			(xy 354.933542 -322.204591) (xy 354.934012 -322.235322) (xy 354.933532 -322.266017) (xy 354.92611 -322.326957)
			(xy 354.911411 -322.386562) (xy 354.889651 -322.443966) (xy 354.861143 -322.498336) (xy 354.844096 -322.523866)
			(xy 354.838628 -322.532618) (xy 354.834508 -322.552818) (xy 354.838643 -322.573016) (xy 354.844096 -322.581778)
			(xy 354.861151 -322.607305) (xy 354.889682 -322.661667) (xy 354.911454 -322.719071) (xy 354.92615 -322.77868)
			(xy 354.933557 -322.839625) (xy 354.934012 -322.870322) (xy 354.933532 -322.901017) (xy 354.92611 -322.961957)
			(xy 354.911411 -323.021562) (xy 354.889651 -323.078966) (xy 354.861143 -323.133336) (xy 354.844096 -323.158866)
			(xy 354.838628 -323.167618) (xy 354.834508 -323.187818) (xy 354.838643 -323.208016) (xy 354.844096 -323.216778)
			(xy 354.861151 -323.242305) (xy 354.889682 -323.296667) (xy 354.911454 -323.354071) (xy 354.92615 -323.41368)
			(xy 354.933557 -323.474625) (xy 354.934012 -323.505322) (xy 354.933532 -323.536017) (xy 354.92611 -323.596957)
			(xy 354.911411 -323.656562) (xy 354.889651 -323.713966) (xy 354.861143 -323.768336) (xy 354.844096 -323.793866)
			(xy 354.838628 -323.802618) (xy 354.834508 -323.822818) (xy 354.838643 -323.843016) (xy 354.844096 -323.851778)
			(xy 354.861151 -323.877305) (xy 354.889682 -323.931667) (xy 354.911454 -323.989071) (xy 354.92615 -324.04868)
			(xy 354.933557 -324.109625) (xy 354.934012 -324.140322) (xy 354.933532 -324.171017) (xy 354.92611 -324.231957)
			(xy 354.911411 -324.291562) (xy 354.889651 -324.348966) (xy 354.861143 -324.403336) (xy 354.844096 -324.428866)
			(xy 354.838628 -324.437618) (xy 354.834508 -324.457818) (xy 354.838643 -324.478016) (xy 354.844096 -324.486778)
			(xy 354.861151 -324.512305) (xy 354.889682 -324.566667) (xy 354.911454 -324.624071) (xy 354.92615 -324.68368)
			(xy 354.933557 -324.744625) (xy 354.934012 -324.775322) (xy 354.93352 -324.807447) (xy 354.925425 -324.871184)
			(xy 354.909368 -324.933395) (xy 354.885604 -324.993087) (xy 354.854511 -325.049312) (xy 354.835968 -325.07555)
			(xy 354.830015 -325.084506) (xy 354.825529 -325.105518) (xy 354.830029 -325.126527) (xy 354.835968 -325.135494)
			(xy 354.854529 -325.161719) (xy 354.885612 -325.21795) (xy 354.90937 -325.277647) (xy 354.925425 -325.339859)
			(xy 354.933522 -325.403597) (xy 354.934012 -325.435722) (xy 354.933532 -325.466417) (xy 354.92611 -325.527357)
			(xy 354.911411 -325.586962) (xy 354.889651 -325.644366) (xy 354.861143 -325.698736) (xy 354.844096 -325.724266)
			(xy 354.838628 -325.733018) (xy 354.834508 -325.753218) (xy 354.838643 -325.773416) (xy 354.844096 -325.782178)
			(xy 354.861151 -325.807705) (xy 354.889682 -325.862067) (xy 354.911454 -325.919471) (xy 354.92615 -325.97908)
			(xy 354.933557 -326.040025) (xy 354.934012 -326.070722) (xy 354.933532 -326.101417) (xy 354.92611 -326.162357)
			(xy 354.911411 -326.221962) (xy 354.889651 -326.279366) (xy 354.861143 -326.333736) (xy 354.844096 -326.359266)
			(xy 354.838628 -326.368018) (xy 354.834508 -326.388218) (xy 354.838643 -326.408416) (xy 354.844096 -326.417178)
			(xy 354.861151 -326.442705) (xy 354.889682 -326.497067) (xy 354.911454 -326.554471) (xy 354.92615 -326.61408)
			(xy 354.933557 -326.675025) (xy 354.934012 -326.705722) (xy 354.933532 -326.736417) (xy 354.92611 -326.797357)
			(xy 354.911411 -326.856962) (xy 354.889651 -326.914366) (xy 354.861143 -326.968736) (xy 354.844096 -326.994266)
			(xy 354.838628 -327.003018) (xy 354.834508 -327.023218) (xy 354.838643 -327.043416) (xy 354.844096 -327.052178)
			(xy 354.85578 -327.069958) (xy 354.860655 -327.077038) (xy 354.874128 -327.087698) (xy 354.890369 -327.0933)
			(xy 354.89896 -327.09358) (xy 355.138482 -327.09358) (xy 355.148545 -327.093141) (xy 355.167126 -327.085404)
			(xy 355.17455 -327.078594) (xy 357.313484 -324.93966) (xy 357.320326 -324.93226) (xy 357.328048 -324.913662)
			(xy 357.32847 -324.903592) (xy 357.32847 -315.169804) (xy 357.328296 -315.163074) (xy 357.324813 -315.150074)
			(xy 357.321612 -315.14415) (xy 351.65792 -305.421792) (xy 351.625356 -305.364784) (xy 351.56691 -305.247209)
			(xy 351.516323 -305.126044) (xy 351.473814 -305.001815) (xy 351.439569 -304.875058) (xy 351.413733 -304.746324)
			(xy 351.396421 -304.61617) (xy 351.387706 -304.485158) (xy 351.387156 -304.419508) (xy 351.387156 -296.374566)
			(xy 351.387612 -296.342775) (xy 351.394624 -296.279581) (xy 351.408516 -296.217536) (xy 351.42912 -296.157385)
			(xy 351.442274 -296.12844) (xy 351.4471 -296.11828) (xy 351.4471 -295.924478) (xy 351.447647 -295.881109)
			(xy 351.456176 -295.794791) (xy 351.47312 -295.709724) (xy 351.498316 -295.626726) (xy 351.531521 -295.546595)
			(xy 351.572417 -295.470103) (xy 351.62061 -295.397985) (xy 351.675637 -295.330936) (xy 351.705926 -295.299892)
			(xy 351.734882 -295.270936) (xy 351.74174 -295.244266) (xy 351.737676 -295.230804) (xy 351.732069 -295.210046)
			(xy 351.726072 -295.167468) (xy 351.725738 -295.145968) (xy 351.726206 -295.121724) (xy 351.733871 -295.073844)
			(xy 351.749005 -295.027777) (xy 351.771226 -294.98468) (xy 351.799977 -294.945634) (xy 351.816924 -294.92829)
			(xy 351.823866 -294.920862) (xy 351.831716 -294.902126) (xy 351.832164 -294.891968) (xy 351.832164 -294.717216)
			(xy 351.83146 -294.704485) (xy 351.819324 -294.682097) (xy 351.80905 -294.674544) (xy 351.726754 -294.62095)
			(xy 351.701354 -294.618918) (xy 351.689416 -294.624252) (xy 351.669151 -294.632907) (xy 351.626808 -294.64511)
			(xy 351.583179 -294.651296) (xy 351.561146 -294.651684) (xy 351.536335 -294.651226) (xy 351.487323 -294.64347)
			(xy 351.440128 -294.628142) (xy 351.395913 -294.605618) (xy 351.355765 -294.576455) (xy 351.320675 -294.54137)
			(xy 351.291506 -294.501226) (xy 351.268976 -294.457014) (xy 351.253641 -294.409822) (xy 351.245877 -294.360811)
			(xy 351.245877 -294.311189) (xy 351.253641 -294.262178) (xy 351.268976 -294.214986) (xy 351.291506 -294.170774)
			(xy 351.320675 -294.13063) (xy 351.355765 -294.095545) (xy 351.395913 -294.066382) (xy 351.440128 -294.043858)
			(xy 351.487323 -294.02853) (xy 351.536335 -294.020774) (xy 351.561146 -294.02024) (xy 351.583176 -294.020659)
			(xy 351.626801 -294.026851) (xy 351.669144 -294.039039) (xy 351.689416 -294.047672) (xy 351.701354 -294.053006)
			(xy 351.726754 -294.050974) (xy 351.80905 -293.99738) (xy 351.815986 -293.99252) (xy 351.826409 -293.979185)
			(xy 351.831891 -293.963172) (xy 351.832164 -293.954708) (xy 351.832164 -293.779956) (xy 351.831714 -293.769801)
			(xy 351.82385 -293.751075) (xy 351.816924 -293.743634) (xy 351.799967 -293.7263) (xy 351.771208 -293.687259)
			(xy 351.748982 -293.644163) (xy 351.733849 -293.598095) (xy 351.726188 -293.550214) (xy 351.726193 -293.501724)
			(xy 351.733863 -293.453845) (xy 351.749006 -293.40778) (xy 351.77124 -293.364689) (xy 351.800007 -293.325654)
			(xy 351.816924 -293.308278) (xy 351.823865 -293.30085) (xy 351.83171 -293.282113) (xy 351.832164 -293.271956)
			(xy 351.832164 -293.097204) (xy 351.831457 -293.084474) (xy 351.819319 -293.062091) (xy 351.80905 -293.054532)
			(xy 351.726754 -293.000938) (xy 351.701354 -292.998906) (xy 351.689416 -293.00424) (xy 351.66915 -293.012893)
			(xy 351.626807 -293.025092) (xy 351.583178 -293.031276) (xy 351.561146 -293.031672) (xy 351.536328 -293.031214)
			(xy 351.487303 -293.023456) (xy 351.440095 -293.008123) (xy 351.395867 -292.985593) (xy 351.355708 -292.956422)
			(xy 351.320608 -292.921327) (xy 351.291431 -292.881172) (xy 351.268895 -292.836948) (xy 351.253555 -292.789742)
			(xy 351.24579 -292.740718) (xy 351.24579 -292.691082) (xy 351.253555 -292.642058) (xy 351.268895 -292.594852)
			(xy 351.291431 -292.550628) (xy 351.320608 -292.510473) (xy 351.355708 -292.475378) (xy 351.395867 -292.446207)
			(xy 351.440095 -292.423677) (xy 351.487303 -292.408344) (xy 351.536328 -292.400586) (xy 351.561146 -292.400228)
			(xy 351.583176 -292.400647) (xy 351.626801 -292.406839) (xy 351.669144 -292.419026) (xy 351.689416 -292.42766)
			(xy 351.701354 -292.432994) (xy 351.726754 -292.430962) (xy 351.80905 -292.377368) (xy 351.815984 -292.372508)
			(xy 351.826405 -292.359172) (xy 351.831883 -292.343159) (xy 351.832164 -292.334696) (xy 351.832164 -292.159944)
			(xy 351.831712 -292.14979) (xy 351.823845 -292.131067) (xy 351.816924 -292.123622) (xy 351.79996 -292.106288)
			(xy 351.771187 -292.067245) (xy 351.748948 -292.024144) (xy 351.733802 -291.97807) (xy 351.726131 -291.930181)
			(xy 351.726126 -291.881681) (xy 351.733788 -291.83379) (xy 351.748924 -291.787713) (xy 351.771154 -291.744608)
			(xy 351.799919 -291.705559) (xy 351.816924 -291.688266) (xy 351.823863 -291.680837) (xy 351.831704 -291.662101)
			(xy 351.832164 -291.651944) (xy 351.832164 -291.477192) (xy 351.831454 -291.464464) (xy 351.819313 -291.442085)
			(xy 351.80905 -291.43452) (xy 351.726754 -291.380926) (xy 351.701354 -291.378894) (xy 351.689416 -291.384228)
			(xy 351.66915 -291.392881) (xy 351.626807 -291.405081) (xy 351.583178 -291.411265) (xy 351.561146 -291.41166)
			(xy 351.536329 -291.411202) (xy 351.487305 -291.403444) (xy 351.440099 -291.388112) (xy 351.395873 -291.365583)
			(xy 351.355716 -291.336413) (xy 351.320617 -291.301319) (xy 351.291441 -291.261166) (xy 351.268906 -291.216943)
			(xy 351.253567 -291.169739) (xy 351.245802 -291.120717) (xy 351.245802 -291.071083) (xy 351.253567 -291.022061)
			(xy 351.268906 -290.974857) (xy 351.291441 -290.930634) (xy 351.320617 -290.890481) (xy 351.355716 -290.855387)
			(xy 351.395873 -290.826217) (xy 351.440099 -290.803688) (xy 351.487306 -290.788356) (xy 351.536329 -290.780598)
			(xy 351.561146 -290.780216) (xy 351.583176 -290.780636) (xy 351.6268 -290.786829) (xy 351.669142 -290.799019)
			(xy 351.689416 -290.807648) (xy 351.701354 -290.812982) (xy 351.726754 -290.81095) (xy 351.80905 -290.757356)
			(xy 351.815983 -290.752495) (xy 351.826401 -290.739159) (xy 351.831875 -290.723147) (xy 351.832164 -290.714684)
			(xy 351.832164 -290.539932) (xy 351.83171 -290.529779) (xy 351.82384 -290.511059) (xy 351.816924 -290.50361)
			(xy 351.799961 -290.486276) (xy 351.77119 -290.447233) (xy 351.748953 -290.404133) (xy 351.733809 -290.35806)
			(xy 351.726139 -290.310172) (xy 351.726135 -290.261673) (xy 351.733798 -290.213784) (xy 351.748935 -290.167709)
			(xy 351.771166 -290.124605) (xy 351.799931 -290.085558) (xy 351.816924 -290.068254) (xy 351.823876 -290.06083)
			(xy 351.83175 -290.042094) (xy 351.832164 -290.031932) (xy 351.832164 -289.85718) (xy 351.831474 -289.844441)
			(xy 351.819353 -289.822029) (xy 351.80905 -289.814508) (xy 351.726754 -289.760914) (xy 351.701354 -289.758882)
			(xy 351.689416 -289.764216) (xy 351.66915 -289.77287) (xy 351.626808 -289.78507) (xy 351.583178 -289.791254)
			(xy 351.561146 -289.791648) (xy 351.53633 -289.79119) (xy 351.487308 -289.783432) (xy 351.440104 -289.768101)
			(xy 351.395879 -289.745573) (xy 351.355724 -289.716404) (xy 351.320626 -289.681311) (xy 351.291451 -289.64116)
			(xy 351.268917 -289.596939) (xy 351.253578 -289.549736) (xy 351.245814 -289.500716) (xy 351.245814 -289.451084)
			(xy 351.253578 -289.402063) (xy 351.268917 -289.354861) (xy 351.291451 -289.31064) (xy 351.320626 -289.270489)
			(xy 351.355724 -289.235396) (xy 351.395879 -289.206227) (xy 351.440104 -289.183699) (xy 351.487308 -289.168368)
			(xy 351.53633 -289.16061) (xy 351.561146 -289.160204) (xy 351.583176 -289.160624) (xy 351.6268 -289.166816)
			(xy 351.669142 -289.179006) (xy 351.689416 -289.187636) (xy 351.701354 -289.19297) (xy 351.726754 -289.190938)
			(xy 351.80905 -289.137344) (xy 351.815982 -289.132483) (xy 351.826396 -289.119146) (xy 351.831867 -289.103134)
			(xy 351.832164 -289.094672) (xy 351.832164 -288.91992) (xy 351.831708 -288.909768) (xy 351.823834 -288.891051)
			(xy 351.816924 -288.883598) (xy 351.799961 -288.866264) (xy 351.771193 -288.827221) (xy 351.748957 -288.784122)
			(xy 351.733815 -288.738049) (xy 351.726146 -288.690163) (xy 351.726144 -288.641665) (xy 351.733808 -288.593778)
			(xy 351.748947 -288.547704) (xy 351.771178 -288.504603) (xy 351.799943 -288.465558) (xy 351.816924 -288.448242)
			(xy 351.823875 -288.440817) (xy 351.831743 -288.422081) (xy 351.832164 -288.41192) (xy 351.832164 -288.237422)
			(xy 351.831461 -288.22469) (xy 351.819327 -288.2023) (xy 351.80905 -288.19475) (xy 351.726754 -288.141156)
			(xy 351.701354 -288.139124) (xy 351.689416 -288.144458) (xy 351.669132 -288.153039) (xy 351.626784 -288.165137)
			(xy 351.583167 -288.171241) (xy 351.561146 -288.171636) (xy 351.536355 -288.171178) (xy 351.487381 -288.163428)
			(xy 351.440223 -288.148112) (xy 351.396043 -288.125606) (xy 351.355927 -288.096466) (xy 351.320864 -288.061408)
			(xy 351.291718 -288.021297) (xy 351.269206 -287.977119) (xy 351.253882 -287.929964) (xy 351.246125 -287.880991)
			(xy 351.246125 -287.831409) (xy 351.253882 -287.782436) (xy 351.269206 -287.735281) (xy 351.291718 -287.691103)
			(xy 351.320864 -287.650992) (xy 351.355927 -287.615934) (xy 351.396043 -287.586794) (xy 351.440223 -287.564288)
			(xy 351.487381 -287.548972) (xy 351.536355 -287.541222) (xy 351.561146 -287.5407) (xy 351.583171 -287.541044)
			(xy 351.626797 -287.547138) (xy 351.669146 -287.559255) (xy 351.689416 -287.567878) (xy 351.701354 -287.573212)
			(xy 351.726754 -287.57118) (xy 351.80905 -287.517586) (xy 351.815986 -287.512726) (xy 351.826412 -287.499392)
			(xy 351.831896 -287.483378) (xy 351.832164 -287.474914) (xy 351.832164 -287.299908) (xy 351.831724 -287.289749)
			(xy 351.823873 -287.271009) (xy 351.816924 -287.263586) (xy 351.799962 -287.246252) (xy 351.771195 -287.207209)
			(xy 351.748962 -287.164111) (xy 351.733821 -287.118039) (xy 351.726154 -287.070153) (xy 351.726153 -287.021658)
			(xy 351.733819 -286.973772) (xy 351.748958 -286.9277) (xy 351.77119 -286.8846) (xy 351.799955 -286.845557)
			(xy 351.816924 -286.82823) (xy 351.823873 -286.820804) (xy 351.831737 -286.802069) (xy 351.832164 -286.791908)
			(xy 351.832164 -286.61741) (xy 351.831458 -286.604679) (xy 351.819321 -286.582294) (xy 351.80905 -286.574738)
			(xy 351.726754 -286.521144) (xy 351.701354 -286.519112) (xy 351.689416 -286.524446) (xy 351.669132 -286.533027)
			(xy 351.626784 -286.545126) (xy 351.583167 -286.55123) (xy 351.561146 -286.551624) (xy 351.536356 -286.551167)
			(xy 351.487384 -286.543417) (xy 351.440228 -286.528101) (xy 351.396049 -286.505596) (xy 351.355935 -286.476457)
			(xy 351.320873 -286.4414) (xy 351.291728 -286.40129) (xy 351.269217 -286.357115) (xy 351.253894 -286.309961)
			(xy 351.246137 -286.26099) (xy 351.246137 -286.21141) (xy 351.253894 -286.162439) (xy 351.269217 -286.115286)
			(xy 351.291728 -286.07111) (xy 351.320873 -286.031) (xy 351.355935 -285.995943) (xy 351.396049 -285.966804)
			(xy 351.440228 -285.944299) (xy 351.487384 -285.928983) (xy 351.536355 -285.921233) (xy 351.561146 -285.920688)
			(xy 351.583171 -285.921032) (xy 351.626797 -285.927125) (xy 351.669147 -285.939243) (xy 351.689416 -285.947866)
			(xy 351.701354 -285.9532) (xy 351.726754 -285.951168) (xy 351.80905 -285.897574) (xy 351.815985 -285.892714)
			(xy 351.826407 -285.879379) (xy 351.831887 -285.863366) (xy 351.832164 -285.854902) (xy 351.832164 -285.68015)
			(xy 351.831713 -285.669996) (xy 351.823848 -285.651271) (xy 351.816924 -285.643828) (xy 351.799959 -285.626494)
			(xy 351.771186 -285.58745) (xy 351.748946 -285.544349) (xy 351.733799 -285.498275) (xy 351.726127 -285.450385)
			(xy 351.726121 -285.401885) (xy 351.733783 -285.353993) (xy 351.748919 -285.307915) (xy 351.771149 -285.264809)
			(xy 351.799913 -285.22576) (xy 351.816924 -285.208472) (xy 351.823864 -285.201043) (xy 351.831707 -285.182307)
			(xy 351.832164 -285.17215) (xy 351.832164 -284.997398) (xy 351.831456 -284.984669) (xy 351.819316 -284.962288)
			(xy 351.80905 -284.954726) (xy 351.726754 -284.901132) (xy 351.701354 -284.8991) (xy 351.689416 -284.904434)
			(xy 351.669132 -284.913015) (xy 351.626784 -284.925114) (xy 351.583167 -284.931219) (xy 351.561146 -284.931612)
			(xy 351.536349 -284.931154) (xy 351.487364 -284.923402) (xy 351.440194 -284.908082) (xy 351.396003 -284.885571)
			(xy 351.355877 -284.856424) (xy 351.320806 -284.821358) (xy 351.291653 -284.781236) (xy 351.269135 -284.737048)
			(xy 351.253808 -284.689881) (xy 351.246049 -284.640897) (xy 351.246049 -284.591303) (xy 351.253808 -284.542319)
			(xy 351.269135 -284.495152) (xy 351.291653 -284.450964) (xy 351.320806 -284.410842) (xy 351.355877 -284.375776)
			(xy 351.396003 -284.346629) (xy 351.440194 -284.324118) (xy 351.487364 -284.308798) (xy 351.536349 -284.301046)
			(xy 351.561146 -284.300676) (xy 351.583171 -284.30102) (xy 351.626797 -284.307113) (xy 351.669147 -284.31923)
			(xy 351.689416 -284.327854) (xy 351.701354 -284.333188) (xy 351.726754 -284.331156) (xy 351.80905 -284.277562)
			(xy 351.815984 -284.272702) (xy 351.826403 -284.259366) (xy 351.831879 -284.243353) (xy 351.832164 -284.23489)
			(xy 351.832164 -284.060138) (xy 351.831711 -284.049985) (xy 351.823842 -284.031263) (xy 351.816924 -284.023816)
			(xy 351.79996 -284.006482) (xy 351.771188 -283.967439) (xy 351.748951 -283.924338) (xy 351.733806 -283.878265)
			(xy 351.726135 -283.830376) (xy 351.72613 -283.781877) (xy 351.733793 -283.733987) (xy 351.74893 -283.687911)
			(xy 351.77116 -283.644807) (xy 351.799925 -283.605759) (xy 351.816924 -283.58846) (xy 351.823862 -283.581031)
			(xy 351.8317 -283.562294) (xy 351.832164 -283.552138) (xy 351.832164 -283.377386) (xy 351.831453 -283.364658)
			(xy 351.81931 -283.342282) (xy 351.80905 -283.334714) (xy 351.726754 -283.28112) (xy 351.701354 -283.279088)
			(xy 351.689416 -283.284422) (xy 351.669132 -283.293004) (xy 351.626784 -283.305103) (xy 351.583167 -283.311208)
			(xy 351.561146 -283.3116) (xy 351.53635 -283.311142) (xy 351.487366 -283.303391) (xy 351.440199 -283.288071)
			(xy 351.396009 -283.265561) (xy 351.355885 -283.236415) (xy 351.320815 -283.20135) (xy 351.291663 -283.16123)
			(xy 351.269146 -283.117044) (xy 351.25382 -283.069878) (xy 351.246061 -283.020896) (xy 351.246061 -282.971304)
			(xy 351.25382 -282.922322) (xy 351.269146 -282.875156) (xy 351.291663 -282.83097) (xy 351.320815 -282.79085)
			(xy 351.355885 -282.755785) (xy 351.396009 -282.726639) (xy 351.440199 -282.704129) (xy 351.487366 -282.688809)
			(xy 351.53635 -282.681058) (xy 351.561146 -282.680664) (xy 351.583171 -282.681008) (xy 351.626797 -282.687101)
			(xy 351.669147 -282.699217) (xy 351.689416 -282.707842) (xy 351.701354 -282.713176) (xy 351.726754 -282.711144)
			(xy 351.80905 -282.65755) (xy 351.815982 -282.652689) (xy 351.826398 -282.639353) (xy 351.831871 -282.62334)
			(xy 351.832164 -282.614878) (xy 351.832164 -282.440126) (xy 351.831709 -282.429974) (xy 351.823837 -282.411255)
			(xy 351.816924 -282.403804) (xy 351.799961 -282.38647) (xy 351.771191 -282.347427) (xy 351.748955 -282.304327)
			(xy 351.733812 -282.258254) (xy 351.726142 -282.210367) (xy 351.72614 -282.161869) (xy 351.733803 -282.113981)
			(xy 351.748941 -282.067906) (xy 351.771172 -282.024804) (xy 351.799937 -281.985758) (xy 351.816924 -281.968448)
			(xy 351.823876 -281.961023) (xy 351.831747 -281.942288) (xy 351.832164 -281.932126) (xy 351.832164 -281.746198)
			(xy 351.831884 -281.737672) (xy 351.826345 -281.721549) (xy 351.815788 -281.708162) (xy 351.808796 -281.703272)
			(xy 351.725992 -281.650186) (xy 351.700084 -281.648154) (xy 351.688146 -281.653742) (xy 351.668131 -281.662495)
			(xy 351.626225 -281.674827) (xy 351.582988 -281.681053) (xy 351.561146 -281.681428) (xy 351.535884 -281.680939)
			(xy 351.486049 -281.67263) (xy 351.43826 -281.65623) (xy 351.393824 -281.632188) (xy 351.353951 -281.60116)
			(xy 351.31973 -281.563991) (xy 351.292093 -281.521696) (xy 351.271797 -281.475428) (xy 351.259393 -281.426451)
			(xy 351.25522 -281.3761) (xy 351.259393 -281.325749) (xy 351.271797 -281.276772) (xy 351.292093 -281.230504)
			(xy 351.31973 -281.188209) (xy 351.353951 -281.15104) (xy 351.393824 -281.120012) (xy 351.438261 -281.09597)
			(xy 351.486049 -281.07957) (xy 351.535884 -281.071261) (xy 351.561146 -281.070812) (xy 351.582987 -281.071189)
			(xy 351.626222 -281.077423) (xy 351.668126 -281.089758) (xy 351.688146 -281.098498) (xy 351.700084 -281.104086)
			(xy 351.725992 -281.102054) (xy 351.808796 -281.048968) (xy 351.815779 -281.04408) (xy 351.826283 -281.030668)
			(xy 351.831829 -281.01456) (xy 351.832164 -281.006042) (xy 351.832164 -280.820114) (xy 351.831706 -280.809963)
			(xy 351.823832 -280.791247) (xy 351.816924 -280.783792) (xy 351.799962 -280.766458) (xy 351.771194 -280.727415)
			(xy 351.74896 -280.684316) (xy 351.733818 -280.638244) (xy 351.72615 -280.590358) (xy 351.726149 -280.541862)
			(xy 351.733814 -280.493975) (xy 351.748952 -280.447902) (xy 351.771184 -280.404801) (xy 351.799949 -280.365757)
			(xy 351.816924 -280.348436) (xy 351.823874 -280.341011) (xy 351.83174 -280.322275) (xy 351.832164 -280.312114)
			(xy 351.832164 -280.126186) (xy 351.831882 -280.117661) (xy 351.82634 -280.101541) (xy 351.815782 -280.088157)
			(xy 351.808796 -280.08326) (xy 351.725992 -280.030174) (xy 351.700084 -280.028142) (xy 351.688146 -280.03373)
			(xy 351.668131 -280.042483) (xy 351.626225 -280.054816) (xy 351.582988 -280.061042) (xy 351.561146 -280.061416)
			(xy 351.535885 -280.060927) (xy 351.486051 -280.052618) (xy 351.438265 -280.036219) (xy 351.39383 -280.012178)
			(xy 351.353959 -279.981151) (xy 351.319739 -279.943983) (xy 351.292104 -279.90169) (xy 351.271808 -279.855424)
			(xy 351.259404 -279.806449) (xy 351.255232 -279.7561) (xy 351.259404 -279.705751) (xy 351.271808 -279.656776)
			(xy 351.292104 -279.61051) (xy 351.319739 -279.568217) (xy 351.353959 -279.531049) (xy 351.39383 -279.500022)
			(xy 351.438265 -279.475981) (xy 351.486051 -279.459582) (xy 351.535885 -279.451273) (xy 351.561146 -279.4508)
			(xy 351.582987 -279.451177) (xy 351.626222 -279.457411) (xy 351.668126 -279.469746) (xy 351.688146 -279.478486)
			(xy 351.700084 -279.484074) (xy 351.725992 -279.482042) (xy 351.808796 -279.428956) (xy 351.815777 -279.424067)
			(xy 351.826278 -279.410655) (xy 351.831821 -279.394548) (xy 351.832164 -279.38603) (xy 351.832164 -279.200102)
			(xy 351.831723 -279.189943) (xy 351.82387 -279.171205) (xy 351.816924 -279.16378) (xy 351.799963 -279.146446)
			(xy 351.771197 -279.107404) (xy 351.748964 -279.064305) (xy 351.733825 -279.018234) (xy 351.726158 -278.970349)
			(xy 351.726158 -278.921854) (xy 351.733824 -278.873969) (xy 351.748963 -278.827897) (xy 351.771195 -278.784799)
			(xy 351.799961 -278.745756) (xy 351.816924 -278.728424) (xy 351.823872 -278.720998) (xy 351.831734 -278.702262)
			(xy 351.832164 -278.692102) (xy 351.832164 -278.51735) (xy 351.831467 -278.504614) (xy 351.81934 -278.482214)
			(xy 351.80905 -278.474678) (xy 351.726754 -278.421084) (xy 351.701354 -278.419052) (xy 351.689416 -278.424386)
			(xy 351.669132 -278.432969) (xy 351.626785 -278.445069) (xy 351.583167 -278.451175) (xy 351.561146 -278.451564)
			(xy 351.536352 -278.451106) (xy 351.487375 -278.443356) (xy 351.440213 -278.428038) (xy 351.396028 -278.40553)
			(xy 351.355909 -278.376387) (xy 351.320843 -278.341326) (xy 351.291694 -278.301211) (xy 351.26918 -278.25703)
			(xy 351.253855 -278.20987) (xy 351.246097 -278.160894) (xy 351.246097 -278.111306) (xy 351.253855 -278.06233)
			(xy 351.26918 -278.01517) (xy 351.291694 -277.970989) (xy 351.320843 -277.930874) (xy 351.355909 -277.895813)
			(xy 351.396028 -277.86667) (xy 351.440213 -277.844162) (xy 351.487375 -277.828844) (xy 351.536352 -277.821094)
			(xy 351.561146 -277.820628) (xy 351.583171 -277.820972) (xy 351.626796 -277.827066) (xy 351.669146 -277.839185)
			(xy 351.689416 -277.847806) (xy 351.701354 -277.85314) (xy 351.726754 -277.851108) (xy 351.80905 -277.797514)
			(xy 351.81599 -277.792656) (xy 351.826422 -277.779322) (xy 351.831915 -277.763308) (xy 351.832164 -277.754842)
			(xy 351.832164 -277.58009) (xy 351.83172 -277.569932) (xy 351.823865 -277.551197) (xy 351.816924 -277.543768)
			(xy 351.799964 -277.526434) (xy 351.7712 -277.487392) (xy 351.748969 -277.444294) (xy 351.733831 -277.398224)
			(xy 351.726166 -277.35034) (xy 351.726167 -277.301846) (xy 351.733834 -277.253963) (xy 351.748974 -277.207893)
			(xy 351.771207 -277.164796) (xy 351.799973 -277.125756) (xy 351.816924 -277.108412) (xy 351.82387 -277.100986)
			(xy 351.831728 -277.08225) (xy 351.832164 -277.07209) (xy 351.832164 -276.897338) (xy 351.831464 -276.884604)
			(xy 351.819334 -276.862208) (xy 351.80905 -276.854666) (xy 351.726754 -276.801072) (xy 351.701354 -276.79904)
			(xy 351.689416 -276.804374) (xy 351.669132 -276.812954) (xy 351.626784 -276.825052) (xy 351.583167 -276.831156)
			(xy 351.561146 -276.831552) (xy 351.536353 -276.831094) (xy 351.487378 -276.823344) (xy 351.440217 -276.808027)
			(xy 351.396034 -276.78552) (xy 351.355916 -276.756378) (xy 351.320852 -276.721319) (xy 351.291704 -276.681205)
			(xy 351.269191 -276.637025) (xy 351.253867 -276.589867) (xy 351.246109 -276.540893) (xy 351.246109 -276.491307)
			(xy 351.253867 -276.442333) (xy 351.269191 -276.395175) (xy 351.291704 -276.350995) (xy 351.320852 -276.310881)
			(xy 351.355916 -276.275822) (xy 351.396034 -276.24668) (xy 351.440217 -276.224173) (xy 351.487378 -276.208856)
			(xy 351.536353 -276.201106) (xy 351.561146 -276.200616) (xy 351.583171 -276.20096) (xy 351.626797 -276.207054)
			(xy 351.669146 -276.219172) (xy 351.689416 -276.227794) (xy 351.701354 -276.233128) (xy 351.726754 -276.231096)
			(xy 351.80905 -276.177502) (xy 351.815988 -276.172644) (xy 351.826418 -276.159309) (xy 351.831907 -276.143295)
			(xy 351.832164 -276.13483) (xy 351.832164 -275.960078) (xy 351.831718 -275.949921) (xy 351.82386 -275.931189)
			(xy 351.816924 -275.923756) (xy 351.799965 -275.906422) (xy 351.771203 -275.86738) (xy 351.748974 -275.824283)
			(xy 351.733837 -275.778214) (xy 351.726174 -275.730331) (xy 351.726176 -275.681838) (xy 351.733845 -275.633956)
			(xy 351.748986 -275.587888) (xy 351.771219 -275.544793) (xy 351.799985 -275.505755) (xy 351.816924 -275.4884)
			(xy 351.823868 -275.480973) (xy 351.831722 -275.462237) (xy 351.832164 -275.452078) (xy 351.832164 -275.277326)
			(xy 351.831462 -275.264593) (xy 351.819329 -275.242202) (xy 351.80905 -275.234654) (xy 351.726754 -275.18106)
			(xy 351.701354 -275.179028) (xy 351.689416 -275.184362) (xy 351.669132 -275.192943) (xy 351.626784 -275.205041)
			(xy 351.583167 -275.211145) (xy 351.561146 -275.21154) (xy 351.536354 -275.211082) (xy 351.48738 -275.203332)
			(xy 351.440222 -275.188016) (xy 351.396041 -275.16551) (xy 351.355924 -275.136369) (xy 351.320861 -275.101311)
			(xy 351.291714 -275.061199) (xy 351.269202 -275.017021) (xy 351.253878 -274.969864) (xy 351.246121 -274.920892)
			(xy 351.246121 -274.871308) (xy 351.253878 -274.822336) (xy 351.269202 -274.775179) (xy 351.291714 -274.731001)
			(xy 351.320861 -274.690889) (xy 351.355924 -274.655831) (xy 351.396041 -274.62669) (xy 351.440222 -274.604184)
			(xy 351.48738 -274.588868) (xy 351.536354 -274.581118) (xy 351.561146 -274.580604) (xy 351.583171 -274.580948)
			(xy 351.626797 -274.587042) (xy 351.669146 -274.59916) (xy 351.689416 -274.607782) (xy 351.701354 -274.613116)
			(xy 351.726754 -274.611084) (xy 351.80905 -274.55749) (xy 351.815987 -274.552631) (xy 351.826413 -274.539296)
			(xy 351.831898 -274.523282) (xy 351.832164 -274.514818) (xy 351.832164 -274.340066) (xy 351.831716 -274.32991)
			(xy 351.823855 -274.311181) (xy 351.816924 -274.303744) (xy 351.799966 -274.28641) (xy 351.771205 -274.247369)
			(xy 351.748978 -274.204272) (xy 351.733844 -274.158203) (xy 351.726182 -274.110322) (xy 351.726186 -274.061831)
			(xy 351.733855 -274.01395) (xy 351.748997 -273.967884) (xy 351.771231 -273.924791) (xy 351.799997 -273.885754)
			(xy 351.816924 -273.868388) (xy 351.823866 -273.86096) (xy 351.831715 -273.842224) (xy 351.832164 -273.832066)
			(xy 351.832164 -273.657314) (xy 351.831459 -273.644583) (xy 351.819323 -273.622196) (xy 351.80905 -273.614642)
			(xy 351.726754 -273.561048) (xy 351.701354 -273.559016) (xy 351.689416 -273.56435) (xy 351.669132 -273.572931)
			(xy 351.626784 -273.585029) (xy 351.583167 -273.591134) (xy 351.561146 -273.591528) (xy 351.536355 -273.59107)
			(xy 351.487383 -273.583321) (xy 351.440227 -273.568005) (xy 351.396047 -273.5455) (xy 351.355932 -273.51636)
			(xy 351.32087 -273.481303) (xy 351.291724 -273.441192) (xy 351.269213 -273.397016) (xy 351.25389 -273.349862)
			(xy 351.246133 -273.300891) (xy 351.246133 -273.251309) (xy 351.25389 -273.202338) (xy 351.269213 -273.155184)
			(xy 351.291724 -273.111008) (xy 351.32087 -273.070897) (xy 351.355932 -273.03584) (xy 351.396047 -273.0067)
			(xy 351.440227 -272.984195) (xy 351.487383 -272.968879) (xy 351.536355 -272.96113) (xy 351.561146 -272.960592)
			(xy 351.583171 -272.960936) (xy 351.626797 -272.967029) (xy 351.669146 -272.979147) (xy 351.689416 -272.98777)
			(xy 351.701354 -272.993104) (xy 351.726754 -272.991072) (xy 351.80905 -272.937478) (xy 351.815985 -272.932618)
			(xy 351.826409 -272.919283) (xy 351.83189 -272.90327) (xy 351.832164 -272.894806) (xy 351.832164 -272.720054)
			(xy 351.831714 -272.709899) (xy 351.823849 -272.691173) (xy 351.816924 -272.683732) (xy 351.799967 -272.666398)
			(xy 351.771208 -272.627357) (xy 351.748983 -272.584261) (xy 351.73385 -272.538193) (xy 351.72619 -272.490313)
			(xy 351.726195 -272.441823) (xy 351.733865 -272.393944) (xy 351.749008 -272.34788) (xy 351.771242 -272.304788)
			(xy 351.800009 -272.265753) (xy 351.816924 -272.248376) (xy 351.823864 -272.240948) (xy 351.831709 -272.222211)
			(xy 351.832164 -272.212054) (xy 351.832164 -272.037302) (xy 351.831456 -272.024572) (xy 351.819318 -272.00219)
			(xy 351.80905 -271.99463) (xy 351.726754 -271.941036) (xy 351.701354 -271.939004) (xy 351.689416 -271.944338)
			(xy 351.669132 -271.952919) (xy 351.626784 -271.965018) (xy 351.583167 -271.971123) (xy 351.561146 -271.971516)
			(xy 351.536348 -271.971058) (xy 351.487363 -271.963306) (xy 351.440193 -271.947986) (xy 351.396001 -271.925475)
			(xy 351.355875 -271.896327) (xy 351.320803 -271.86126) (xy 351.291649 -271.821138) (xy 351.269132 -271.77695)
			(xy 351.253805 -271.729782) (xy 351.246045 -271.680798) (xy 351.246045 -271.631202) (xy 351.253805 -271.582218)
			(xy 351.269132 -271.53505) (xy 351.291649 -271.490862) (xy 351.320803 -271.45074) (xy 351.355875 -271.415673)
			(xy 351.396001 -271.386525) (xy 351.440193 -271.364014) (xy 351.487363 -271.348694) (xy 351.536348 -271.340942)
			(xy 351.561146 -271.34058) (xy 351.583171 -271.340924) (xy 351.626797 -271.347017) (xy 351.669147 -271.359134)
			(xy 351.689416 -271.367758) (xy 351.701354 -271.373092) (xy 351.726754 -271.37106) (xy 351.80905 -271.317466)
			(xy 351.815984 -271.312606) (xy 351.826404 -271.29927) (xy 351.831882 -271.283257) (xy 351.832164 -271.274794)
			(xy 351.832164 -271.100042) (xy 351.831712 -271.089888) (xy 351.823844 -271.071166) (xy 351.816924 -271.06372)
			(xy 351.79771 -271.043991) (xy 351.766008 -270.998968) (xy 351.742872 -270.948999) (xy 351.73539 -270.922496)
			(xy 351.733866 -270.915892) (xy 351.727262 -270.904462) (xy 351.405698 -270.582898) (xy 351.395792 -270.576802)
			(xy 351.389696 -270.575024) (xy 351.383346 -270.572992) (xy 351.372778 -270.570031) (xy 351.350981 -270.572394)
			(xy 351.332145 -270.583617) (xy 351.319691 -270.601662) (xy 351.315879 -270.623253) (xy 351.3214 -270.644471)
			(xy 351.327974 -270.653256) (xy 351.344044 -270.67383) (xy 351.369649 -270.71932) (xy 351.387149 -270.768501)
			(xy 351.396033 -270.819941) (xy 351.396554 -270.846042) (xy 351.396032 -270.871297) (xy 351.387719 -270.921119)
			(xy 351.371318 -270.968893) (xy 351.347277 -271.013316) (xy 351.316253 -271.053176) (xy 351.279091 -271.087386)
			(xy 351.236805 -271.115012) (xy 351.190549 -271.135302) (xy 351.141584 -271.147702) (xy 351.091246 -271.151873)
			(xy 351.040908 -271.147702) (xy 350.991943 -271.135302) (xy 350.945687 -271.115012) (xy 350.903401 -271.087386)
			(xy 350.866239 -271.053176) (xy 350.835215 -271.013316) (xy 350.811174 -270.968893) (xy 350.794773 -270.921119)
			(xy 350.78646 -270.871297) (xy 350.785938 -270.846042) (xy 350.786398 -270.82183) (xy 350.794034 -270.774012)
			(xy 350.809121 -270.727999) (xy 350.83128 -270.684944) (xy 350.859957 -270.645925) (xy 350.894433 -270.611921)
			(xy 350.933844 -270.583785) (xy 350.977201 -270.562221) (xy 351.023418 -270.54777) (xy 351.047304 -270.543782)
			(xy 351.06102 -270.542004) (xy 351.082102 -270.52524) (xy 351.125282 -270.418814) (xy 351.121726 -270.392144)
			(xy 351.113344 -270.381222) (xy 351.093622 -270.354912) (xy 351.059731 -270.298563) (xy 351.032604 -270.238664)
			(xy 351.022158 -270.207486) (xy 351.02038 -270.20139) (xy 351.014284 -270.191484) (xy 350.985836 -270.163036)
			(xy 350.978436 -270.156196) (xy 350.959837 -270.148479) (xy 350.949768 -270.14805) (xy 350.923352 -270.14805)
			(xy 350.899222 -270.162782) (xy 350.892618 -270.175736) (xy 350.881267 -270.196784) (xy 350.853029 -270.235375)
			(xy 350.819122 -270.269092) (xy 350.780373 -270.297111) (xy 350.73773 -270.318748) (xy 350.692235 -270.333474)
			(xy 350.645001 -270.340928) (xy 350.597183 -270.340928) (xy 350.549949 -270.333474) (xy 350.504454 -270.318748)
			(xy 350.461811 -270.297111) (xy 350.423062 -270.269092) (xy 350.389155 -270.235375) (xy 350.360917 -270.196784)
			(xy 350.349566 -270.175736) (xy 350.342962 -270.162782) (xy 350.318832 -270.14805) (xy 349.994728 -270.14805)
			(xy 349.97009 -270.16329) (xy 349.96374 -270.176244) (xy 349.952171 -270.198451) (xy 349.923092 -270.239213)
			(xy 349.887944 -270.274873) (xy 349.847606 -270.304537) (xy 349.803092 -270.327462) (xy 349.755516 -270.343072)
			(xy 349.706073 -270.350977) (xy 349.656003 -270.350977) (xy 349.60656 -270.343072) (xy 349.558984 -270.327462)
			(xy 349.51447 -270.304537) (xy 349.474132 -270.274873) (xy 349.438984 -270.239213) (xy 349.409905 -270.198451)
			(xy 349.398336 -270.176244) (xy 349.391986 -270.16329) (xy 349.367348 -270.14805) (xy 349.054928 -270.14805)
			(xy 349.03029 -270.16329) (xy 349.02394 -270.176244) (xy 349.012371 -270.198451) (xy 348.983292 -270.239213)
			(xy 348.948144 -270.274873) (xy 348.907806 -270.304537) (xy 348.863292 -270.327462) (xy 348.815716 -270.343072)
			(xy 348.766273 -270.350977) (xy 348.716203 -270.350977) (xy 348.66676 -270.343072) (xy 348.619184 -270.327462)
			(xy 348.57467 -270.304537) (xy 348.534332 -270.274873) (xy 348.499184 -270.239213) (xy 348.470105 -270.198451)
			(xy 348.458536 -270.176244) (xy 348.452186 -270.16329) (xy 348.427548 -270.14805) (xy 348.103444 -270.14805)
			(xy 348.079314 -270.162782) (xy 348.07271 -270.175736) (xy 348.061359 -270.196784) (xy 348.033121 -270.235375)
			(xy 347.999214 -270.269092) (xy 347.960465 -270.297111) (xy 347.917822 -270.318748) (xy 347.872327 -270.333474)
			(xy 347.825093 -270.340928) (xy 347.777275 -270.340928) (xy 347.730041 -270.333474) (xy 347.684546 -270.318748)
			(xy 347.641903 -270.297111) (xy 347.603154 -270.269092) (xy 347.569247 -270.235375) (xy 347.541009 -270.196784)
			(xy 347.529658 -270.175736) (xy 347.523054 -270.162782) (xy 347.498924 -270.14805) (xy 347.17482 -270.14805)
			(xy 347.150182 -270.16329) (xy 347.143832 -270.176244) (xy 347.132263 -270.198451) (xy 347.103184 -270.239213)
			(xy 347.068036 -270.274873) (xy 347.027698 -270.304537) (xy 346.983184 -270.327462) (xy 346.935608 -270.343072)
			(xy 346.886165 -270.350977) (xy 346.836095 -270.350977) (xy 346.786652 -270.343072) (xy 346.739076 -270.327462)
			(xy 346.694562 -270.304537) (xy 346.654224 -270.274873) (xy 346.619076 -270.239213) (xy 346.589997 -270.198451)
			(xy 346.578428 -270.176244) (xy 346.572078 -270.16329) (xy 346.54744 -270.14805) (xy 346.234766 -270.14805)
			(xy 346.210128 -270.16329) (xy 346.203778 -270.176244) (xy 346.192209 -270.198451) (xy 346.16313 -270.239213)
			(xy 346.127982 -270.274873) (xy 346.087644 -270.304537) (xy 346.04313 -270.327462) (xy 345.995554 -270.343072)
			(xy 345.946111 -270.350977) (xy 345.896041 -270.350977) (xy 345.846598 -270.343072) (xy 345.799022 -270.327462)
			(xy 345.754508 -270.304537) (xy 345.71417 -270.274873) (xy 345.679022 -270.239213) (xy 345.649943 -270.198451)
			(xy 345.638374 -270.176244) (xy 345.632024 -270.16329) (xy 345.607386 -270.14805) (xy 345.283282 -270.14805)
			(xy 345.259152 -270.162782) (xy 345.252548 -270.175736) (xy 345.241203 -270.19679) (xy 345.212974 -270.235392)
			(xy 345.179069 -270.269118) (xy 345.140319 -270.297144) (xy 345.097673 -270.318784) (xy 345.052173 -270.333507)
			(xy 345.004933 -270.340953) (xy 344.981022 -270.341344) (xy 344.954944 -270.340815) (xy 344.903547 -270.331953)
			(xy 344.854403 -270.314484) (xy 344.808944 -270.288917) (xy 344.768492 -270.255994) (xy 344.734225 -270.216675)
			(xy 344.70714 -270.172104) (xy 344.69705 -270.14805) (xy 344.695018 -270.14297) (xy 344.686011 -270.117159)
			(xy 344.676297 -270.063367) (xy 344.675714 -270.036036) (xy 344.676184 -270.011801) (xy 344.683851 -269.963941)
			(xy 344.698981 -269.917892) (xy 344.721195 -269.874812) (xy 344.749936 -269.835782) (xy 344.784481 -269.801782)
			(xy 344.823963 -269.773665) (xy 344.867391 -269.752138) (xy 344.913674 -269.737741) (xy 344.937588 -269.733776)
			(xy 344.956384 -269.730982) (xy 344.981022 -269.702534) (xy 344.981022 -268.749526) (xy 344.956384 -268.721078)
			(xy 344.937588 -268.718284) (xy 344.913657 -268.714377) (xy 344.867354 -268.699986) (xy 344.823907 -268.67846)
			(xy 344.784407 -268.650339) (xy 344.749847 -268.61633) (xy 344.721096 -268.577287) (xy 344.698875 -268.534191)
			(xy 344.683743 -268.488125) (xy 344.676081 -268.440247) (xy 344.67608 -268.39176) (xy 344.683741 -268.343881)
			(xy 344.698872 -268.297815) (xy 344.721092 -268.254719) (xy 344.749843 -268.215675) (xy 344.784402 -268.181665)
			(xy 344.823901 -268.153543) (xy 344.867348 -268.132016) (xy 344.91365 -268.117625) (xy 344.937588 -268.113764)
			(xy 344.956384 -268.11097) (xy 344.981022 -268.082522) (xy 344.981022 -267.76934) (xy 344.981457 -267.759275)
			(xy 344.989189 -267.740689) (xy 344.996008 -267.733272) (xy 345.140026 -267.589254) (xy 345.147138 -267.574522)
			(xy 345.148408 -267.56614) (xy 345.152166 -267.541421) (xy 345.166678 -267.493577) (xy 345.188789 -267.448735)
			(xy 345.217908 -267.408094) (xy 345.253258 -267.372739) (xy 345.293895 -267.343613) (xy 345.338733 -267.321495)
			(xy 345.386575 -267.306976) (xy 345.411298 -267.30325) (xy 345.41968 -267.30198) (xy 345.434412 -267.294868)
			(xy 345.66352 -267.06576) (xy 345.669715 -267.058945) (xy 345.677248 -267.042151) (xy 345.678252 -267.032994)
			(xy 345.680538 -266.994386) (xy 345.675966 -266.978384) (xy 345.670886 -266.971018) (xy 345.657886 -266.951668)
			(xy 345.637285 -266.909854) (xy 345.623283 -266.865393) (xy 345.616206 -266.819319) (xy 345.615768 -266.796012)
			(xy 345.616238 -266.772019) (xy 345.623742 -266.724625) (xy 345.638568 -266.678988) (xy 345.660351 -266.636232)
			(xy 345.688553 -266.597409) (xy 345.722482 -266.563477) (xy 345.761301 -266.53527) (xy 345.804054 -266.513482)
			(xy 345.84969 -266.498651) (xy 345.897084 -266.491141) (xy 345.921076 -266.490704) (xy 345.933839 -266.490844)
			(xy 345.959272 -266.49301) (xy 345.971876 -266.495022) (xy 345.971876 -266.494768) (xy 345.996906 -266.499504)
			(xy 346.045036 -266.516185) (xy 346.089732 -266.540619) (xy 346.110052 -266.555982) (xy 346.125292 -266.56792)
			(xy 346.163646 -266.565634) (xy 346.280994 -266.448286) (xy 346.288388 -266.441429) (xy 346.306987 -266.433679)
			(xy 346.317062 -266.4333) (xy 348.019878 -266.4333) (xy 348.02975 -266.432829) (xy 348.048033 -266.425371)
			(xy 348.055438 -266.418822) (xy 348.055692 -266.418568) (xy 348.0943 -266.37996) (xy 348.101563 -266.371926)
			(xy 348.109183 -266.351674) (xy 348.109032 -266.340844) (xy 348.103444 -266.253722) (xy 348.093284 -266.234418)
			(xy 348.084394 -266.227814) (xy 348.066278 -266.213232) (xy 348.034247 -266.179518) (xy 348.007686 -266.141345)
			(xy 347.987207 -266.099594) (xy 347.973281 -266.055224) (xy 347.966229 -266.009258) (xy 347.965776 -265.986006)
			(xy 347.966246 -265.962014) (xy 347.973751 -265.914621) (xy 347.988578 -265.868985) (xy 348.010361 -265.82623)
			(xy 348.038564 -265.787409) (xy 348.072493 -265.753478) (xy 348.111311 -265.725273) (xy 348.154064 -265.703487)
			(xy 348.199699 -265.688657) (xy 348.247092 -265.681148) (xy 348.271084 -265.680698) (xy 348.283847 -265.680834)
			(xy 348.309282 -265.682992) (xy 348.321884 -265.685016) (xy 348.321884 -265.684762) (xy 348.344306 -265.688971)
			(xy 348.387662 -265.70316) (xy 348.428426 -265.723638) (xy 348.465691 -265.74995) (xy 348.498629 -265.781511)
			(xy 348.512892 -265.799316) (xy 348.519496 -265.808206) (xy 348.5388 -265.818366) (xy 348.625922 -265.823954)
			(xy 348.636763 -265.824168) (xy 348.657035 -265.816537) (xy 348.665038 -265.809222) (xy 348.942914 -265.531346)
			(xy 348.943422 -265.530838) (xy 348.950006 -265.523458) (xy 348.957458 -265.505158) (xy 348.9579 -265.495278)
			(xy 348.9579 -264.551414) (xy 348.957658 -264.544463) (xy 348.95392 -264.531073) (xy 348.950534 -264.524998)
			(xy 348.938472 -264.504353) (xy 348.920224 -264.46016) (xy 348.909093 -264.413661) (xy 348.905353 -264.365995)
			(xy 348.909095 -264.318329) (xy 348.920227 -264.271831) (xy 348.938476 -264.227638) (xy 348.950534 -264.20699)
			(xy 348.953967 -264.200935) (xy 348.9577 -264.187532) (xy 348.9579 -264.180574) (xy 348.9579 -262.992362)
			(xy 348.957967 -262.988555) (xy 348.959117 -262.98103) (xy 348.960186 -262.977376) (xy 348.961465 -262.972792)
			(xy 348.962489 -262.963331) (xy 348.962218 -262.95858) (xy 348.96044 -262.93191) (xy 348.959836 -262.925719)
			(xy 348.955988 -262.913894) (xy 348.95282 -262.908542) (xy 348.93811 -262.884004) (xy 348.917147 -262.830781)
			(xy 348.906471 -262.774583) (xy 348.90583 -262.745982) (xy 348.906278 -262.721991) (xy 348.913787 -262.6746)
			(xy 348.928617 -262.628967) (xy 348.950404 -262.586216) (xy 348.978611 -262.5474) (xy 349.012543 -262.513474)
			(xy 349.051364 -262.485275) (xy 349.094119 -262.463496) (xy 349.139754 -262.448674) (xy 349.187147 -262.441173)
			(xy 349.211138 -262.440674) (xy 349.233526 -262.441065) (xy 349.277822 -262.447611) (xy 349.320682 -262.46057)
			(xy 349.361183 -262.479664) (xy 349.380048 -262.491728) (xy 349.390126 -262.497662) (xy 349.413305 -262.50058)
			(xy 349.435399 -262.492988) (xy 349.444056 -262.485124) (xy 349.562166 -262.367014) (xy 349.570106 -262.358107)
			(xy 349.577519 -262.335459) (xy 349.57639 -262.32358) (xy 349.56242 -262.231124) (xy 349.54845 -262.211566)
			(xy 349.537782 -262.205724) (xy 349.51713 -262.19424) (xy 349.479323 -262.165893) (xy 349.44633 -262.132065)
			(xy 349.418937 -262.093562) (xy 349.397797 -262.051301) (xy 349.383413 -262.006291) (xy 349.376129 -261.959602)
			(xy 349.37573 -261.935976) (xy 349.376178 -261.911985) (xy 349.383688 -261.864595) (xy 349.398519 -261.818963)
			(xy 349.420306 -261.776213) (xy 349.448513 -261.737397) (xy 349.482445 -261.703473) (xy 349.521266 -261.675274)
			(xy 349.56402 -261.653495) (xy 349.609655 -261.638673) (xy 349.657047 -261.631173) (xy 349.681038 -261.630668)
			(xy 349.704666 -261.631104) (xy 349.751359 -261.63837) (xy 349.796376 -261.652739) (xy 349.838645 -261.673868)
			(xy 349.877157 -261.701252) (xy 349.910993 -261.734239) (xy 349.939346 -261.772043) (xy 349.950786 -261.79272)
			(xy 349.956628 -261.803388) (xy 349.976186 -261.817358) (xy 350.068642 -261.831328) (xy 350.080526 -261.832495)
			(xy 350.103194 -261.825083) (xy 350.112076 -261.817104) (xy 350.179894 -261.749286) (xy 350.187288 -261.742429)
			(xy 350.205887 -261.734679) (xy 350.215962 -261.7343) (xy 350.369886 -261.7343) (xy 350.379847 -261.73381)
			(xy 350.398266 -261.726217) (xy 350.4057 -261.719568) (xy 350.422983 -261.703023) (xy 350.461741 -261.674974)
			(xy 350.504399 -261.653314) (xy 350.549914 -261.638573) (xy 350.597171 -261.631111) (xy 350.645013 -261.631111)
			(xy 350.69227 -261.638573) (xy 350.737785 -261.653314) (xy 350.780443 -261.674974) (xy 350.819201 -261.703023)
			(xy 350.836484 -261.719568) (xy 350.843891 -261.726258) (xy 350.862328 -261.733851) (xy 350.872298 -261.7343)
			(xy 355.268784 -261.7343) (xy 355.271324 -261.7343) (xy 355.280413 -261.733421) (xy 355.297132 -261.72611)
			(xy 355.310246 -261.713421) (xy 355.314504 -261.705344) (xy 355.31552 -261.703312) (xy 355.357938 -261.602982)
			(xy 355.35235 -261.57301) (xy 355.341682 -261.562088) (xy 355.323585 -261.542746) (xy 355.292962 -261.499529)
			(xy 355.269343 -261.45212) (xy 355.253287 -261.401646) (xy 355.245177 -261.349304) (xy 355.244654 -261.32282)
			(xy 355.245182 -261.295833) (xy 355.253622 -261.242522) (xy 355.270297 -261.191188) (xy 355.294798 -261.143095)
			(xy 355.32652 -261.099426) (xy 355.364682 -261.061257) (xy 355.408345 -261.029528) (xy 355.456435 -261.00502)
			(xy 355.507766 -260.988335) (xy 355.561075 -260.979886) (xy 355.588062 -260.979412) (xy 355.615098 -260.979922)
			(xy 355.668502 -260.988404) (xy 355.719917 -261.005149) (xy 355.768073 -261.029742) (xy 355.811781 -261.061577)
			(xy 355.849962 -261.099867) (xy 355.881672 -261.143666) (xy 355.906127 -261.191892) (xy 355.922725 -261.243355)
			(xy 355.927406 -261.269988) (xy 355.928422 -261.2771) (xy 355.934264 -261.289546) (xy 355.938836 -261.295134)
			(xy 355.943563 -261.300386) (xy 355.955298 -261.308245) (xy 355.96195 -261.310628) (xy 356.047802 -261.338568)
			(xy 356.059337 -261.341665) (xy 356.082923 -261.338097) (xy 356.093014 -261.33171) (xy 356.09657 -261.32917)
			(xy 356.20452 -261.22122) (xy 356.208267 -261.217303) (xy 356.214155 -261.208205) (xy 356.216204 -261.203186)
			(xy 356.225166 -261.180285) (xy 356.248702 -261.137107) (xy 356.278157 -261.097728) (xy 356.31293 -261.062956)
			(xy 356.352309 -261.0335) (xy 356.395488 -261.009965) (xy 356.418388 -261.001002) (xy 356.423401 -260.998944)
			(xy 356.432488 -260.993045) (xy 356.436422 -260.989318) (xy 356.540054 -260.885686) (xy 356.540562 -260.885178)
			(xy 356.547148 -260.877798) (xy 356.554608 -260.859499) (xy 356.55504 -260.849618) (xy 356.55504 -260.1341)
			(xy 356.554486 -260.123648) (xy 356.546109 -260.10449) (xy 356.538784 -260.097016) (xy 356.52023 -260.079186)
			(xy 356.488139 -260.038963) (xy 356.462402 -259.994406) (xy 356.443595 -259.946509) (xy 356.432137 -259.896345)
			(xy 356.428286 -259.845033) (xy 356.432128 -259.79372) (xy 356.443575 -259.743553) (xy 356.462373 -259.695653)
			(xy 356.488102 -259.651091) (xy 356.520186 -259.610862) (xy 356.538784 -259.59308) (xy 356.54612 -259.58561)
			(xy 356.554513 -259.566453) (xy 356.55504 -259.555996) (xy 356.55504 -259.084064) (xy 356.554479 -259.073615)
			(xy 356.546093 -259.054467) (xy 356.538784 -259.04698) (xy 356.520233 -259.02915) (xy 356.488147 -258.988928)
			(xy 356.462415 -258.944372) (xy 356.443613 -258.896478) (xy 356.43216 -258.846317) (xy 356.428313 -258.795008)
			(xy 356.432157 -258.7437) (xy 356.443608 -258.693537) (xy 356.462408 -258.645643) (xy 356.488138 -258.601086)
			(xy 356.520222 -258.560862) (xy 356.538784 -258.543044) (xy 356.54613 -258.535577) (xy 356.554548 -258.516421)
			(xy 356.55504 -258.50596) (xy 356.55504 -258.313682) (xy 356.554612 -258.303615) (xy 356.546886 -258.285021)
			(xy 356.540054 -258.277614) (xy 356.247192 -257.984752) (xy 356.244906 -257.982466) (xy 356.244652 -257.982466)
			(xy 356.23744 -257.976656) (xy 356.220122 -257.970137) (xy 356.21087 -257.969766) (xy 356.128828 -257.970274)
			(xy 356.110032 -257.978148) (xy 356.10292 -257.985514) (xy 356.083413 -258.004633) (xy 356.039464 -258.037062)
			(xy 355.990935 -258.062123) (xy 355.939051 -258.079186) (xy 355.885119 -258.087819) (xy 355.85781 -258.088384)
			(xy 355.830823 -258.087883) (xy 355.777513 -258.07944) (xy 355.72618 -258.062762) (xy 355.678089 -258.038258)
			(xy 355.634423 -258.006532) (xy 355.596258 -257.968366) (xy 355.564534 -257.924699) (xy 355.540033 -257.876607)
			(xy 355.523356 -257.825273) (xy 355.514916 -257.771963) (xy 355.514402 -257.744976) (xy 355.514931 -257.717666)
			(xy 355.523579 -257.663735) (xy 355.540652 -257.611851) (xy 355.565721 -257.563324) (xy 355.598153 -257.519375)
			(xy 355.617272 -257.499866) (xy 355.624638 -257.4925) (xy 355.632512 -257.473958) (xy 355.63302 -257.391916)
			(xy 355.632665 -257.382659) (xy 355.62615 -257.365334) (xy 355.62032 -257.358134) (xy 355.619304 -257.356864)
			(xy 355.454966 -257.192526) (xy 355.447854 -257.18516) (xy 355.429058 -257.17754) (xy 354.763832 -257.17754)
			(xy 354.756466 -257.178048) (xy 354.74689 -257.179894) (xy 354.730048 -257.189694) (xy 354.7237 -257.197098)
			(xy 354.722176 -257.19913) (xy 354.674424 -257.266948) (xy 354.66797 -257.277387) (xy 354.664785 -257.30168)
			(xy 354.668328 -257.31343) (xy 354.668836 -257.314446) (xy 354.670868 -257.321304) (xy 354.679124 -257.347723)
			(xy 354.688064 -257.402343) (xy 354.688648 -257.430016) (xy 354.688168 -257.455715) (xy 354.680507 -257.506539)
			(xy 354.665358 -257.555653) (xy 354.643057 -257.601961) (xy 354.614104 -257.644428) (xy 354.579144 -257.682105)
			(xy 354.53896 -257.714151) (xy 354.494448 -257.73985) (xy 354.446603 -257.758627) (xy 354.396494 -257.770065)
			(xy 354.34524 -257.773906) (xy 354.293986 -257.770065) (xy 354.243877 -257.758627) (xy 354.196032 -257.73985)
			(xy 354.15152 -257.714151) (xy 354.111336 -257.682105) (xy 354.076376 -257.644428) (xy 354.047423 -257.601961)
			(xy 354.025122 -257.555653) (xy 354.009973 -257.506539) (xy 354.002312 -257.455715) (xy 354.001832 -257.430016)
			(xy 354.00238 -257.40234) (xy 354.011319 -257.347714) (xy 354.019612 -257.321304) (xy 354.021644 -257.314446)
			(xy 354.022152 -257.31343) (xy 354.025641 -257.301677) (xy 354.02246 -257.277403) (xy 354.016056 -257.266948)
			(xy 353.968304 -257.19913) (xy 353.96678 -257.197098) (xy 353.960448 -257.189677) (xy 353.943595 -257.179887)
			(xy 353.934014 -257.178048) (xy 353.926648 -257.17754) (xy 349.240856 -257.17754) (xy 349.230791 -257.177107)
			(xy 349.212204 -257.169375) (xy 349.204788 -257.162554) (xy 348.993714 -256.95148) (xy 348.975172 -256.932938)
			(xy 348.959357 -256.936073) (xy 348.927286 -256.939378) (xy 348.911164 -256.939542) (xy 348.887174 -256.939069)
			(xy 348.839784 -256.931558) (xy 348.794153 -256.916728) (xy 348.751403 -256.894943) (xy 348.712586 -256.86674)
			(xy 348.678659 -256.832812) (xy 348.650456 -256.793995) (xy 348.628671 -256.751245) (xy 348.613841 -256.705614)
			(xy 348.606331 -256.658224) (xy 348.605856 -256.634234) (xy 348.605913 -256.624173) (xy 348.607181 -256.60409)
			(xy 348.608396 -256.594102) (xy 348.60992 -256.582164) (xy 348.602554 -256.56032) (xy 348.593918 -256.551684)
			(xy 348.444566 -256.402332) (xy 348.437454 -256.394966) (xy 348.418658 -256.387346) (xy 347.41104 -256.387346)
			(xy 347.398619 -256.387957) (xy 347.376643 -256.399536) (xy 347.36913 -256.409444) (xy 347.314774 -256.488946)
			(xy 347.311726 -256.51333) (xy 347.316298 -256.525268) (xy 347.325635 -256.551406) (xy 347.335729 -256.605978)
			(xy 347.336364 -256.633726) (xy 347.336364 -256.637028) (xy 347.335625 -256.662132) (xy 347.326954 -256.711597)
			(xy 347.310305 -256.758976) (xy 347.286127 -256.802992) (xy 347.255072 -256.842458) (xy 347.217978 -256.87631)
			(xy 347.175844 -256.903635) (xy 347.129806 -256.923697) (xy 347.081106 -256.935955) (xy 347.031056 -256.940078)
			(xy 346.981006 -256.935955) (xy 346.932306 -256.923697) (xy 346.886268 -256.903635) (xy 346.844134 -256.87631)
			(xy 346.80704 -256.842458) (xy 346.775985 -256.802992) (xy 346.751807 -256.758976) (xy 346.735158 -256.711597)
			(xy 346.726487 -256.662132) (xy 346.725748 -256.637028) (xy 346.725748 -256.63398) (xy 346.726382 -256.606169)
			(xy 346.736469 -256.551469) (xy 346.745814 -256.525268) (xy 346.750386 -256.51333) (xy 346.747338 -256.488946)
			(xy 346.692982 -256.409444) (xy 346.68545 -256.399561) (xy 346.663483 -256.388005) (xy 346.651072 -256.387346)
			(xy 346.205302 -256.387346) (xy 346.195233 -256.386922) (xy 346.176633 -256.379202) (xy 346.169234 -256.37236)
			(xy 345.872562 -256.075688) (xy 345.865648 -256.06926) (xy 345.848414 -256.061581) (xy 345.829571 -256.060649)
			(xy 345.820492 -256.063242) (xy 345.804236 -256.06883) (xy 345.79814 -256.073148) (xy 345.778632 -256.086457)
			(xy 345.736377 -256.107539) (xy 345.69138 -256.121863) (xy 345.644714 -256.129089) (xy 345.621102 -256.129536)
			(xy 345.603322 -256.129028) (xy 345.578708 -256.127117) (xy 345.530529 -256.116352) (xy 345.484709 -256.097976)
			(xy 345.442442 -256.072468) (xy 345.404829 -256.040493) (xy 345.37285 -256.002884) (xy 345.347338 -255.96062)
			(xy 345.328958 -255.914802) (xy 345.318187 -255.866624) (xy 345.316302 -255.842008) (xy 345.315794 -255.833626)
			(xy 345.315794 -255.824228) (xy 345.316217 -255.800616) (xy 345.323454 -255.75395) (xy 345.337789 -255.708956)
			(xy 345.358882 -255.666705) (xy 345.372182 -255.64719) (xy 345.3765 -255.641094) (xy 345.382088 -255.624838)
			(xy 345.38471 -255.615762) (xy 345.383786 -255.596905) (xy 345.376101 -255.57966) (xy 345.369642 -255.572768)
			(xy 345.120468 -255.323594) (xy 345.106498 -255.316482) (xy 345.098878 -255.314958) (xy 345.075888 -255.310527)
			(xy 345.031529 -255.295554) (xy 344.989975 -255.273984) (xy 344.952202 -255.246323) (xy 344.919095 -255.213219)
			(xy 344.89143 -255.175449) (xy 344.869857 -255.133897) (xy 344.85488 -255.089539) (xy 344.850466 -255.066546)
			(xy 344.848942 -255.058926) (xy 344.84183 -255.044956) (xy 344.696034 -254.89916) (xy 344.68919 -254.891761)
			(xy 344.681465 -254.873162) (xy 344.681048 -254.863092) (xy 344.681048 -254.537718) (xy 344.65641 -254.50927)
			(xy 344.637614 -254.506476) (xy 344.613682 -254.50257) (xy 344.567377 -254.488183) (xy 344.523928 -254.466659)
			(xy 344.484426 -254.43854) (xy 344.449864 -254.404531) (xy 344.42111 -254.365488) (xy 344.398888 -254.322392)
			(xy 344.383755 -254.276325) (xy 344.376092 -254.228446) (xy 344.376092 -254.179958) (xy 344.383754 -254.132079)
			(xy 344.398886 -254.086012) (xy 344.421108 -254.042916) (xy 344.449861 -254.003872) (xy 344.484422 -253.969863)
			(xy 344.523924 -253.941743) (xy 344.567373 -253.920218) (xy 344.613677 -253.905831) (xy 344.637614 -253.901956)
			(xy 344.65641 -253.899162) (xy 344.681048 -253.870714) (xy 344.681048 -252.917706) (xy 344.65641 -252.889258)
			(xy 344.637614 -252.886464) (xy 344.613683 -252.882558) (xy 344.56738 -252.868172) (xy 344.523932 -252.846648)
			(xy 344.484432 -252.81853) (xy 344.449872 -252.784522) (xy 344.421119 -252.745481) (xy 344.398898 -252.702386)
			(xy 344.383766 -252.656321) (xy 344.376104 -252.608444) (xy 344.376104 -252.559957) (xy 344.383766 -252.51208)
			(xy 344.398898 -252.466015) (xy 344.421119 -252.42292) (xy 344.449871 -252.383879) (xy 344.484431 -252.349871)
			(xy 344.523931 -252.321752) (xy 344.567379 -252.300229) (xy 344.613682 -252.285842) (xy 344.637614 -252.281944)
			(xy 344.65641 -252.27915) (xy 344.681048 -252.250702) (xy 344.681048 -251.297694) (xy 344.65641 -251.269246)
			(xy 344.637614 -251.266452) (xy 344.613684 -251.262546) (xy 344.567383 -251.24816) (xy 344.523937 -251.226637)
			(xy 344.484438 -251.198519) (xy 344.449879 -251.164513) (xy 344.421129 -251.125473) (xy 344.398908 -251.08238)
			(xy 344.383777 -251.036317) (xy 344.376116 -250.988441) (xy 344.376116 -250.939957) (xy 344.383778 -250.892081)
			(xy 344.398909 -250.846018) (xy 344.42113 -250.802925) (xy 344.449881 -250.763885) (xy 344.48444 -250.729879)
			(xy 344.523939 -250.701762) (xy 344.567385 -250.680239) (xy 344.613686 -250.665853) (xy 344.637614 -250.661932)
			(xy 344.65641 -250.659138) (xy 344.681048 -250.63069) (xy 344.681048 -249.677682) (xy 344.65641 -249.649234)
			(xy 344.637614 -249.64644) (xy 344.613685 -249.642534) (xy 344.567386 -249.628148) (xy 344.523942 -249.606626)
			(xy 344.484445 -249.578509) (xy 344.449887 -249.544504) (xy 344.421138 -249.505465) (xy 344.398919 -249.462373)
			(xy 344.383789 -249.416312) (xy 344.376127 -249.368439) (xy 344.376128 -249.319956) (xy 344.38379 -249.272082)
			(xy 344.398921 -249.226021) (xy 344.421141 -249.18293) (xy 344.449891 -249.143892) (xy 344.484449 -249.109887)
			(xy 344.523947 -249.081771) (xy 344.567391 -249.06025) (xy 344.61369 -249.045864) (xy 344.637614 -249.04192)
			(xy 344.65641 -249.039126) (xy 344.681048 -249.010678) (xy 344.681048 -248.05767) (xy 344.65641 -248.029222)
			(xy 344.637614 -248.026428) (xy 344.613686 -248.022523) (xy 344.567388 -248.008137) (xy 344.523946 -247.986615)
			(xy 344.484451 -247.958499) (xy 344.449895 -247.924495) (xy 344.421147 -247.885457) (xy 344.398929 -247.842367)
			(xy 344.3838 -247.796308) (xy 344.376139 -247.748436) (xy 344.37614 -247.699955) (xy 344.383802 -247.652084)
			(xy 344.398933 -247.606024) (xy 344.421152 -247.562935) (xy 344.449901 -247.523898) (xy 344.484458 -247.489895)
			(xy 344.523954 -247.46178) (xy 344.567397 -247.44026) (xy 344.613695 -247.425875) (xy 344.637614 -247.421908)
			(xy 344.65641 -247.419114) (xy 344.681048 -247.390666) (xy 344.681048 -246.437658) (xy 344.65641 -246.40921)
			(xy 344.637614 -246.406416) (xy 344.613687 -246.402511) (xy 344.567391 -246.388125) (xy 344.523951 -246.366604)
			(xy 344.484457 -246.338489) (xy 344.449903 -246.304486) (xy 344.421156 -246.26545) (xy 344.398939 -246.222361)
			(xy 344.383811 -246.176303) (xy 344.376151 -246.128433) (xy 344.376152 -246.079954) (xy 344.383814 -246.032085)
			(xy 344.398944 -245.986027) (xy 344.421163 -245.94294) (xy 344.449911 -245.903905) (xy 344.484467 -245.869903)
			(xy 344.523962 -245.84179) (xy 344.567403 -245.82027) (xy 344.613699 -245.805887) (xy 344.637614 -245.801896)
			(xy 344.65641 -245.799102) (xy 344.681048 -245.770654) (xy 344.681048 -245.441724) (xy 344.673682 -245.423436)
			(xy 344.66657 -245.41607) (xy 344.65895 -245.408196) (xy 344.658696 -245.408196) (xy 344.651584 -245.400576)
			(xy 344.642948 -245.391432) (xy 344.619326 -245.383304) (xy 344.51163 -245.400322) (xy 344.491818 -245.415054)
			(xy 344.48623 -245.426484) (xy 344.475173 -245.448338) (xy 344.447163 -245.488511) (xy 344.413102 -245.5237)
			(xy 344.373863 -245.553004) (xy 344.33045 -245.575672) (xy 344.283977 -245.591122) (xy 344.235635 -245.59896)
			(xy 344.211148 -245.599458) (xy 344.185884 -245.598969) (xy 344.136043 -245.590659) (xy 344.08825 -245.574258)
			(xy 344.043809 -245.550214) (xy 344.003931 -245.519182) (xy 343.969706 -245.48201) (xy 343.942067 -245.43971)
			(xy 343.921768 -245.393438) (xy 343.909363 -245.344456) (xy 343.90519 -245.2941) (xy 343.909363 -245.243744)
			(xy 343.921768 -245.194762) (xy 343.942067 -245.14849) (xy 343.969706 -245.10619) (xy 344.003931 -245.069018)
			(xy 344.043809 -245.037986) (xy 344.08825 -245.013942) (xy 344.136043 -244.997541) (xy 344.185884 -244.989231)
			(xy 344.211148 -244.988842) (xy 344.235278 -244.989858) (xy 344.247978 -244.990874) (xy 344.270838 -244.980968)
			(xy 344.339672 -244.896386) (xy 344.344498 -244.871748) (xy 344.340942 -244.85981) (xy 344.331889 -244.828278)
			(xy 344.316516 -244.764495) (xy 344.310208 -244.732302) (xy 344.308684 -244.72392) (xy 344.291412 -244.694202)
			(xy 344.284808 -244.688614) (xy 344.258587 -244.665962) (xy 344.208268 -244.618315) (xy 344.184224 -244.593364)
			(xy 344.175588 -244.583966) (xy 344.151966 -244.576092) (xy 344.052144 -244.59184) (xy 344.032078 -244.60708)
			(xy 344.02649 -244.61851) (xy 344.01519 -244.641378) (xy 343.986331 -244.683434) (xy 343.951079 -244.720297)
			(xy 343.910353 -244.751004) (xy 343.865215 -244.774755) (xy 343.816843 -244.79093) (xy 343.766497 -244.799108)
			(xy 343.740994 -244.799612) (xy 343.716201 -244.799125) (xy 343.667226 -244.791368) (xy 343.620068 -244.776044)
			(xy 343.575887 -244.753532) (xy 343.535772 -244.724386) (xy 343.50071 -244.689324) (xy 343.471565 -244.649208)
			(xy 343.449053 -244.605027) (xy 343.433731 -244.557868) (xy 343.425974 -244.508893) (xy 343.425974 -244.459307)
			(xy 343.433731 -244.410332) (xy 343.449053 -244.363173) (xy 343.471565 -244.318992) (xy 343.50071 -244.278876)
			(xy 343.535772 -244.243814) (xy 343.575887 -244.214668) (xy 343.620068 -244.192156) (xy 343.667226 -244.176832)
			(xy 343.716201 -244.169075) (xy 343.740994 -244.168676) (xy 343.752847 -244.168719) (xy 343.776494 -244.170375)
			(xy 343.788238 -244.171978) (xy 343.788746 -244.171724) (xy 343.794281 -244.169157) (xy 343.804046 -244.161849)
			(xy 343.80805 -244.157246) (xy 343.860628 -244.092222) (xy 343.864332 -244.087426) (xy 343.869595 -244.076516)
			(xy 343.871042 -244.070632) (xy 343.873582 -244.058186) (xy 343.858344 -244.005594) (xy 343.835515 -243.898494)
			(xy 343.821548 -243.789884) (xy 343.816537 -243.680493) (xy 343.820516 -243.57106) (xy 343.833457 -243.462323)
			(xy 343.855275 -243.355013) (xy 343.870026 -243.302282) (xy 343.873582 -243.29009) (xy 343.868502 -243.265706)
			(xy 343.805002 -243.18722) (xy 343.781888 -243.177314) (xy 343.768934 -243.178584) (xy 343.740994 -243.1796)
			(xy 343.716202 -243.179113) (xy 343.667229 -243.171356) (xy 343.620072 -243.156033) (xy 343.575893 -243.133522)
			(xy 343.53578 -243.104377) (xy 343.500719 -243.069316) (xy 343.471575 -243.029201) (xy 343.449065 -242.985022)
			(xy 343.433743 -242.937865) (xy 343.425986 -242.888892) (xy 343.425986 -242.839308) (xy 343.433743 -242.790335)
			(xy 343.449065 -242.743178) (xy 343.471575 -242.698999) (xy 343.500719 -242.658884) (xy 343.53578 -242.623823)
			(xy 343.575893 -242.594678) (xy 343.620072 -242.572167) (xy 343.667229 -242.556844) (xy 343.716202 -242.549087)
			(xy 343.740994 -242.548664) (xy 343.752847 -242.548707) (xy 343.776494 -242.550363) (xy 343.788238 -242.551966)
			(xy 343.788746 -242.551712) (xy 343.79428 -242.549145) (xy 343.804044 -242.541835) (xy 343.80805 -242.537234)
			(xy 343.860628 -242.47221) (xy 343.864331 -242.467414) (xy 343.869591 -242.456503) (xy 343.871042 -242.45062)
			(xy 343.873582 -242.438174) (xy 343.858345 -242.385582) (xy 343.835517 -242.278483) (xy 343.821551 -242.169872)
			(xy 343.816541 -242.060482) (xy 343.82052 -241.951049) (xy 343.833463 -241.842312) (xy 343.855281 -241.735002)
			(xy 343.870026 -241.68227) (xy 343.873582 -241.670078) (xy 343.868502 -241.645694) (xy 343.805002 -241.567208)
			(xy 343.781888 -241.557302) (xy 343.768934 -241.558572) (xy 343.740994 -241.559588) (xy 343.716203 -241.559102)
			(xy 343.667232 -241.551344) (xy 343.620077 -241.536022) (xy 343.5759 -241.513512) (xy 343.535787 -241.484368)
			(xy 343.500728 -241.449308) (xy 343.471585 -241.409195) (xy 343.449076 -241.365017) (xy 343.433754 -241.317862)
			(xy 343.425998 -241.268891) (xy 343.425998 -241.219309) (xy 343.433754 -241.170338) (xy 343.449076 -241.123183)
			(xy 343.471585 -241.079005) (xy 343.500728 -241.038892) (xy 343.535787 -241.003832) (xy 343.5759 -240.974688)
			(xy 343.620077 -240.952178) (xy 343.667232 -240.936856) (xy 343.716203 -240.929098) (xy 343.740994 -240.928652)
			(xy 343.752847 -240.928695) (xy 343.776494 -240.930351) (xy 343.788238 -240.931954) (xy 343.788746 -240.9317)
			(xy 343.79428 -240.929132) (xy 343.804043 -240.921821) (xy 343.80805 -240.917222) (xy 343.860628 -240.852198)
			(xy 343.86433 -240.847402) (xy 343.869587 -240.83649) (xy 343.871042 -240.830608) (xy 343.873582 -240.818162)
			(xy 343.858345 -240.76557) (xy 343.835518 -240.658471) (xy 343.821553 -240.54986) (xy 343.816544 -240.44047)
			(xy 343.820524 -240.331038) (xy 343.833468 -240.222301) (xy 343.855287 -240.114992) (xy 343.870026 -240.062258)
			(xy 343.873582 -240.050066) (xy 343.868502 -240.025682) (xy 343.805002 -239.947196) (xy 343.781888 -239.93729)
			(xy 343.768934 -239.93856) (xy 343.740994 -239.939576) (xy 343.716204 -239.93909) (xy 343.667235 -239.931333)
			(xy 343.620082 -239.916011) (xy 343.575906 -239.893502) (xy 343.535795 -239.864359) (xy 343.500737 -239.8293)
			(xy 343.471595 -239.789189) (xy 343.449087 -239.745013) (xy 343.433766 -239.697859) (xy 343.42601 -239.64889)
			(xy 343.42601 -239.59931) (xy 343.433766 -239.550341) (xy 343.449087 -239.503187) (xy 343.471595 -239.459011)
			(xy 343.500737 -239.4189) (xy 343.535795 -239.383841) (xy 343.575906 -239.354698) (xy 343.620082 -239.332189)
			(xy 343.667235 -239.316867) (xy 343.716204 -239.30911) (xy 343.740994 -239.30864) (xy 343.752847 -239.308683)
			(xy 343.776494 -239.310339) (xy 343.788238 -239.311942) (xy 343.788746 -239.311688) (xy 343.79428 -239.30912)
			(xy 343.804041 -239.301808) (xy 343.80805 -239.29721) (xy 343.860628 -239.232186) (xy 343.864328 -239.227389)
			(xy 343.869584 -239.216477) (xy 343.871042 -239.210596) (xy 343.873582 -239.19815) (xy 343.858346 -239.145558)
			(xy 343.83552 -239.038459) (xy 343.821556 -238.929848) (xy 343.816547 -238.820459) (xy 343.820529 -238.711027)
			(xy 343.833473 -238.60229) (xy 343.855293 -238.494982) (xy 343.870026 -238.442246) (xy 343.873582 -238.430054)
			(xy 343.868502 -238.40567) (xy 343.805002 -238.327184) (xy 343.781888 -238.317278) (xy 343.768934 -238.318548)
			(xy 343.740994 -238.319564) (xy 343.716205 -238.319077) (xy 343.667238 -238.311321) (xy 343.620086 -238.295999)
			(xy 343.575912 -238.273491) (xy 343.535803 -238.244349) (xy 343.500747 -238.209292) (xy 343.471606 -238.169182)
			(xy 343.449098 -238.125008) (xy 343.433778 -238.077857) (xy 343.426022 -238.028889) (xy 343.426022 -237.979311)
			(xy 343.433778 -237.930343) (xy 343.449098 -237.883192) (xy 343.471606 -237.839018) (xy 343.500747 -237.798908)
			(xy 343.535803 -237.763851) (xy 343.575912 -237.734709) (xy 343.620086 -237.712201) (xy 343.667238 -237.696879)
			(xy 343.716205 -237.689123) (xy 343.740994 -237.688628) (xy 343.752847 -237.688671) (xy 343.776494 -237.690327)
			(xy 343.788238 -237.69193) (xy 343.788746 -237.691676) (xy 343.794279 -237.689107) (xy 343.804039 -237.681794)
			(xy 343.80805 -237.677198) (xy 343.860628 -237.612174) (xy 343.864327 -237.607377) (xy 343.86958 -237.596464)
			(xy 343.871042 -237.590584) (xy 343.873582 -237.578138) (xy 343.858346 -237.525546) (xy 343.835521 -237.418447)
			(xy 343.821558 -237.309837) (xy 343.816551 -237.200447) (xy 343.820533 -237.091015) (xy 343.833478 -236.982279)
			(xy 343.855299 -236.874971) (xy 343.870026 -236.822234) (xy 343.873582 -236.810042) (xy 343.868502 -236.785658)
			(xy 343.805002 -236.707172) (xy 343.781888 -236.697266) (xy 343.768934 -236.698536) (xy 343.740994 -236.699552)
			(xy 343.716206 -236.699065) (xy 343.66724 -236.691309) (xy 343.620091 -236.675988) (xy 343.575919 -236.653481)
			(xy 343.535811 -236.62434) (xy 343.500756 -236.589284) (xy 343.471616 -236.549176) (xy 343.449109 -236.505003)
			(xy 343.43379 -236.457854) (xy 343.426034 -236.408888) (xy 343.426034 -236.359312) (xy 343.43379 -236.310346)
			(xy 343.449109 -236.263197) (xy 343.471616 -236.219024) (xy 343.500756 -236.178916) (xy 343.535811 -236.14386)
			(xy 343.575919 -236.114719) (xy 343.620091 -236.092212) (xy 343.66724 -236.076891) (xy 343.716206 -236.069135)
			(xy 343.740994 -236.068616) (xy 343.752847 -236.068659) (xy 343.776494 -236.070315) (xy 343.788238 -236.071918)
			(xy 343.788746 -236.071664) (xy 343.794279 -236.069095) (xy 343.804037 -236.061781) (xy 343.80805 -236.057186)
			(xy 343.860628 -235.992162) (xy 343.864335 -235.987368) (xy 343.869606 -235.976459) (xy 343.871042 -235.970572)
			(xy 343.873582 -235.958126) (xy 343.858347 -235.905534) (xy 343.835523 -235.798435) (xy 343.82156 -235.689825)
			(xy 343.816554 -235.580436) (xy 343.820537 -235.471004) (xy 343.833484 -235.362268) (xy 343.855305 -235.254961)
			(xy 343.870026 -235.202222) (xy 343.873582 -235.19003) (xy 343.868502 -235.165646) (xy 343.805002 -235.08716)
			(xy 343.781888 -235.077254) (xy 343.768934 -235.078524) (xy 343.740994 -235.07954) (xy 343.716207 -235.079053)
			(xy 343.667243 -235.071297) (xy 343.620096 -235.055977) (xy 343.575925 -235.03347) (xy 343.535819 -235.004331)
			(xy 343.500765 -234.969276) (xy 343.471626 -234.92917) (xy 343.44912 -234.884999) (xy 343.433801 -234.837851)
			(xy 343.426046 -234.788887) (xy 343.426046 -234.739313) (xy 343.433801 -234.690349) (xy 343.44912 -234.643201)
			(xy 343.471626 -234.59903) (xy 343.500765 -234.558924) (xy 343.535819 -234.523869) (xy 343.575925 -234.49473)
			(xy 343.620096 -234.472223) (xy 343.667243 -234.456903) (xy 343.716207 -234.449147) (xy 343.740994 -234.448604)
			(xy 343.752847 -234.448647) (xy 343.776494 -234.450303) (xy 343.788238 -234.451906) (xy 343.788746 -234.451652)
			(xy 343.794278 -234.449082) (xy 343.804036 -234.441767) (xy 343.80805 -234.437174) (xy 343.860628 -234.37215)
			(xy 343.864334 -234.367356) (xy 343.869603 -234.356446) (xy 343.871042 -234.35056) (xy 343.873582 -234.338114)
			(xy 343.858343 -234.285522) (xy 343.835512 -234.178422) (xy 343.821543 -234.069811) (xy 343.816529 -233.96042)
			(xy 343.820506 -233.850987) (xy 343.833445 -233.742248) (xy 343.855261 -233.634937) (xy 343.870026 -233.58221)
			(xy 343.873582 -233.570018) (xy 343.868502 -233.545634) (xy 343.805002 -233.467148) (xy 343.781888 -233.457242)
			(xy 343.768934 -233.458512) (xy 343.740994 -233.459528) (xy 343.716208 -233.459041) (xy 343.667246 -233.451286)
			(xy 343.6201 -233.435966) (xy 343.575931 -233.41346) (xy 343.535827 -233.384322) (xy 343.500774 -233.349269)
			(xy 343.471637 -233.309164) (xy 343.449132 -233.264994) (xy 343.433813 -233.217848) (xy 343.426058 -233.168886)
			(xy 343.426058 -233.119314) (xy 343.433813 -233.070352) (xy 343.449132 -233.023206) (xy 343.471637 -232.979036)
			(xy 343.500774 -232.938931) (xy 343.535827 -232.903878) (xy 343.575931 -232.87474) (xy 343.6201 -232.852234)
			(xy 343.667246 -232.836914) (xy 343.716208 -232.829159) (xy 343.740994 -232.828592) (xy 343.752847 -232.828635)
			(xy 343.776494 -232.830291) (xy 343.788238 -232.831894) (xy 343.788746 -232.83164) (xy 343.794281 -232.829074)
			(xy 343.804048 -232.821767) (xy 343.80805 -232.817162) (xy 343.860628 -232.752138) (xy 343.864333 -232.747343)
			(xy 343.869599 -232.736433) (xy 343.871042 -232.730548) (xy 343.873582 -232.718102) (xy 343.858344 -232.66551)
			(xy 343.835513 -232.55841) (xy 343.821545 -232.449799) (xy 343.816533 -232.340409) (xy 343.82051 -232.230975)
			(xy 343.83345 -232.122237) (xy 343.855267 -232.014927) (xy 343.870026 -231.962198) (xy 343.873582 -231.950006)
			(xy 343.868502 -231.925622) (xy 343.805002 -231.847136) (xy 343.781888 -231.83723) (xy 343.768934 -231.8385)
			(xy 343.740994 -231.839516) (xy 343.716201 -231.839029) (xy 343.667225 -231.831272) (xy 343.620066 -231.815948)
			(xy 343.575885 -231.793436) (xy 343.535769 -231.764289) (xy 343.500707 -231.729226) (xy 343.471561 -231.68911)
			(xy 343.44905 -231.644928) (xy 343.433727 -231.597769) (xy 343.42597 -231.548793) (xy 343.42597 -231.499207)
			(xy 343.433727 -231.450231) (xy 343.44905 -231.403072) (xy 343.471561 -231.35889) (xy 343.500707 -231.318774)
			(xy 343.535769 -231.283711) (xy 343.575885 -231.254564) (xy 343.620066 -231.232052) (xy 343.667225 -231.216728)
			(xy 343.716201 -231.208971) (xy 343.740994 -231.20858) (xy 343.752783 -231.208629) (xy 343.776304 -231.21028)
			(xy 343.787984 -231.211882) (xy 343.788492 -231.211628) (xy 343.794048 -231.209097) (xy 343.803811 -231.201774)
			(xy 343.807796 -231.19715) (xy 343.860628 -231.132126) (xy 343.864381 -231.12729) (xy 343.86965 -231.116243)
			(xy 343.871042 -231.110282) (xy 343.873582 -231.098344) (xy 343.862839 -231.061793) (xy 343.845047 -230.987706)
			(xy 343.838022 -230.950262) (xy 343.82836 -230.893024) (xy 343.817801 -230.777417) (xy 343.81694 -230.719376)
			(xy 343.81694 -230.710486) (xy 343.817485 -230.663785) (xy 343.824305 -230.570631) (xy 343.837624 -230.478181)
			(xy 343.857375 -230.38689) (xy 343.870026 -230.341932) (xy 343.873582 -230.329994) (xy 343.868502 -230.30561)
			(xy 343.805002 -230.227124) (xy 343.781888 -230.217218) (xy 343.768934 -230.218488) (xy 343.740994 -230.219504)
			(xy 343.716202 -230.219017) (xy 343.667228 -230.21126) (xy 343.620071 -230.195937) (xy 343.575891 -230.173425)
			(xy 343.535777 -230.14428) (xy 343.500716 -230.109218) (xy 343.471571 -230.069104) (xy 343.449061 -230.024924)
			(xy 343.433739 -229.977766) (xy 343.425982 -229.928792) (xy 343.425982 -229.879208) (xy 343.433739 -229.830234)
			(xy 343.449061 -229.783076) (xy 343.471571 -229.738896) (xy 343.500716 -229.698782) (xy 343.535777 -229.66372)
			(xy 343.575891 -229.634575) (xy 343.620071 -229.612063) (xy 343.667228 -229.59674) (xy 343.716202 -229.588983)
			(xy 343.740994 -229.588568) (xy 343.752783 -229.588617) (xy 343.776304 -229.590268) (xy 343.787984 -229.59187)
			(xy 343.788492 -229.591616) (xy 343.794047 -229.589085) (xy 343.803809 -229.581761) (xy 343.807796 -229.577138)
			(xy 343.860628 -229.512114) (xy 343.86438 -229.507277) (xy 343.869646 -229.49623) (xy 343.871042 -229.49027)
			(xy 343.873582 -229.478332) (xy 343.858346 -229.42574) (xy 343.835522 -229.318641) (xy 343.821559 -229.210031)
			(xy 343.816552 -229.100641) (xy 343.820535 -228.99121) (xy 343.833481 -228.882474) (xy 343.855302 -228.775166)
			(xy 343.870026 -228.722428) (xy 343.873582 -228.710236) (xy 343.868502 -228.685852) (xy 343.805002 -228.607366)
			(xy 343.781888 -228.59746) (xy 343.768934 -228.59873) (xy 343.740994 -228.6) (xy 343.716186 -228.599513)
			(xy 343.667182 -228.591751) (xy 343.619996 -228.576418) (xy 343.575789 -228.553893) (xy 343.53565 -228.524729)
			(xy 343.500567 -228.489646) (xy 343.471404 -228.449506) (xy 343.44888 -228.405299) (xy 343.433548 -228.358112)
			(xy 343.425787 -228.309108) (xy 343.425787 -228.259492) (xy 343.433548 -228.210488) (xy 343.44888 -228.163301)
			(xy 343.471404 -228.119094) (xy 343.500567 -228.078954) (xy 343.53565 -228.043871) (xy 343.575789 -228.014707)
			(xy 343.619996 -227.992182) (xy 343.667182 -227.976849) (xy 343.716186 -227.969087) (xy 343.740994 -227.968556)
			(xy 343.768934 -227.969826) (xy 343.781888 -227.971096) (xy 343.805002 -227.96119) (xy 343.860882 -227.892356)
			(xy 343.864513 -227.887542) (xy 343.869638 -227.876631) (xy 343.871042 -227.870766) (xy 343.873582 -227.85832)
			(xy 343.858347 -227.805728) (xy 343.835523 -227.698629) (xy 343.821562 -227.590019) (xy 343.816556 -227.48063)
			(xy 343.82054 -227.371199) (xy 343.833486 -227.262463) (xy 343.855308 -227.155156) (xy 343.870026 -227.102416)
			(xy 343.873582 -227.090224) (xy 343.868502 -227.06584) (xy 343.805002 -226.987354) (xy 343.781888 -226.977448)
			(xy 343.768934 -226.978718) (xy 343.740994 -226.979988) (xy 343.716184 -226.979526) (xy 343.667174 -226.971762)
			(xy 343.619983 -226.956427) (xy 343.575772 -226.933898) (xy 343.535629 -226.904729) (xy 343.500545 -226.86964)
			(xy 343.471381 -226.829494) (xy 343.448858 -226.78528) (xy 343.433528 -226.738087) (xy 343.425771 -226.689076)
			(xy 343.425272 -226.664266) (xy 343.42578 -226.63849) (xy 343.434154 -226.587624) (xy 343.450691 -226.538798)
			(xy 343.47495 -226.493312) (xy 343.506284 -226.452377) (xy 343.54386 -226.417084) (xy 343.586675 -226.388374)
			(xy 343.60993 -226.377246) (xy 343.62136 -226.371912) (xy 343.636854 -226.3521) (xy 343.65184 -226.265486)
			(xy 343.653205 -226.253294) (xy 343.645761 -226.229958) (xy 343.637616 -226.220782) (xy 343.514172 -226.097338)
			(xy 343.476326 -226.094798) (xy 343.461086 -226.106228) (xy 343.440422 -226.121171) (xy 343.395283 -226.144894)
			(xy 343.346921 -226.161059) (xy 343.29659 -226.169248) (xy 343.271094 -226.169728) (xy 343.245977 -226.169242)
			(xy 343.196376 -226.161287) (xy 343.148662 -226.145578) (xy 343.104036 -226.122511) (xy 343.063626 -226.09267)
			(xy 343.028451 -226.056806) (xy 342.999399 -226.015825) (xy 342.977203 -225.97076) (xy 342.962422 -225.92275)
			(xy 342.95842 -225.897948) (xy 342.95588 -225.879152) (xy 342.927178 -225.85426) (xy 342.674956 -225.85426)
			(xy 342.646254 -225.879152) (xy 342.643714 -225.897948) (xy 342.639737 -225.922755) (xy 342.624956 -225.97077)
			(xy 342.602758 -226.015838) (xy 342.573704 -226.056823) (xy 342.538526 -226.09269) (xy 342.498112 -226.122534)
			(xy 342.453483 -226.145602) (xy 342.405764 -226.161312) (xy 342.356159 -226.169267) (xy 342.305921 -226.169267)
			(xy 342.256316 -226.161312) (xy 342.208597 -226.145602) (xy 342.163968 -226.122534) (xy 342.123554 -226.09269)
			(xy 342.088376 -226.056823) (xy 342.059322 -226.015838) (xy 342.037124 -225.97077) (xy 342.022343 -225.922755)
			(xy 342.018366 -225.897948) (xy 342.015826 -225.879152) (xy 341.987124 -225.85426) (xy 341.724488 -225.85426)
			(xy 341.69604 -225.878898) (xy 341.693246 -225.897694) (xy 341.689337 -225.921622) (xy 341.674945 -225.967918)
			(xy 341.653419 -226.011359) (xy 341.625299 -226.050852) (xy 341.591292 -226.085407) (xy 341.552252 -226.114153)
			(xy 341.50916 -226.13637) (xy 341.463099 -226.151499) (xy 341.415227 -226.159159) (xy 341.366745 -226.159159)
			(xy 341.318873 -226.151499) (xy 341.272812 -226.13637) (xy 341.22972 -226.114153) (xy 341.19068 -226.085407)
			(xy 341.156673 -226.050852) (xy 341.128553 -226.011359) (xy 341.107027 -225.967918) (xy 341.092635 -225.921622)
			(xy 341.088726 -225.897694) (xy 341.085932 -225.878898) (xy 341.057484 -225.85426) (xy 340.795102 -225.85426)
			(xy 340.7664 -225.879152) (xy 340.76386 -225.897948) (xy 340.759883 -225.922755) (xy 340.745102 -225.97077)
			(xy 340.722904 -226.015838) (xy 340.69385 -226.056823) (xy 340.658672 -226.09269) (xy 340.618258 -226.122534)
			(xy 340.573629 -226.145602) (xy 340.52591 -226.161312) (xy 340.476305 -226.169267) (xy 340.426067 -226.169267)
			(xy 340.376462 -226.161312) (xy 340.328743 -226.145602) (xy 340.284114 -226.122534) (xy 340.2437 -226.09269)
			(xy 340.208522 -226.056823) (xy 340.179468 -226.015838) (xy 340.15727 -225.97077) (xy 340.142489 -225.922755)
			(xy 340.138512 -225.897948) (xy 340.135972 -225.879152) (xy 340.10727 -225.85426) (xy 339.844634 -225.85426)
			(xy 339.816186 -225.878898) (xy 339.813392 -225.897694) (xy 339.809483 -225.921622) (xy 339.795091 -225.967918)
			(xy 339.773565 -226.011359) (xy 339.745445 -226.050852) (xy 339.711438 -226.085407) (xy 339.672398 -226.114153)
			(xy 339.629306 -226.13637) (xy 339.583245 -226.151499) (xy 339.535373 -226.159159) (xy 339.486891 -226.159159)
			(xy 339.439019 -226.151499) (xy 339.392958 -226.13637) (xy 339.349866 -226.114153) (xy 339.310826 -226.085407)
			(xy 339.276819 -226.050852) (xy 339.248699 -226.011359) (xy 339.227173 -225.967918) (xy 339.212781 -225.921622)
			(xy 339.208872 -225.897694) (xy 339.206078 -225.878898) (xy 339.17763 -225.85426) (xy 338.914994 -225.85426)
			(xy 338.886292 -225.879152) (xy 338.883752 -225.897948) (xy 338.879775 -225.922755) (xy 338.864994 -225.97077)
			(xy 338.842796 -226.015838) (xy 338.813742 -226.056823) (xy 338.778564 -226.09269) (xy 338.73815 -226.122534)
			(xy 338.693521 -226.145602) (xy 338.645802 -226.161312) (xy 338.596197 -226.169267) (xy 338.545959 -226.169267)
			(xy 338.496354 -226.161312) (xy 338.448635 -226.145602) (xy 338.404006 -226.122534) (xy 338.363592 -226.09269)
			(xy 338.328414 -226.056823) (xy 338.29936 -226.015838) (xy 338.277162 -225.97077) (xy 338.262381 -225.922755)
			(xy 338.258404 -225.897948) (xy 338.255864 -225.879152) (xy 338.227162 -225.85426) (xy 337.964526 -225.85426)
			(xy 337.936078 -225.878898) (xy 337.933284 -225.897694) (xy 337.929375 -225.921622) (xy 337.914983 -225.967918)
			(xy 337.893457 -226.011359) (xy 337.865337 -226.050852) (xy 337.83133 -226.085407) (xy 337.79229 -226.114153)
			(xy 337.749198 -226.13637) (xy 337.703137 -226.151499) (xy 337.655265 -226.159159) (xy 337.606783 -226.159159)
			(xy 337.558911 -226.151499) (xy 337.51285 -226.13637) (xy 337.469758 -226.114153) (xy 337.430718 -226.085407)
			(xy 337.396711 -226.050852) (xy 337.368591 -226.011359) (xy 337.347065 -225.967918) (xy 337.332673 -225.921622)
			(xy 337.328764 -225.897694) (xy 337.32597 -225.878898) (xy 337.297522 -225.85426) (xy 337.03514 -225.85426)
			(xy 337.006438 -225.879152) (xy 337.003898 -225.897948) (xy 336.999921 -225.922755) (xy 336.98514 -225.97077)
			(xy 336.962942 -226.015838) (xy 336.933888 -226.056823) (xy 336.89871 -226.09269) (xy 336.858296 -226.122534)
			(xy 336.813667 -226.145602) (xy 336.765948 -226.161312) (xy 336.716343 -226.169267) (xy 336.666105 -226.169267)
			(xy 336.6165 -226.161312) (xy 336.568781 -226.145602) (xy 336.524152 -226.122534) (xy 336.483738 -226.09269)
			(xy 336.44856 -226.056823) (xy 336.419506 -226.015838) (xy 336.397308 -225.97077) (xy 336.382527 -225.922755)
			(xy 336.37855 -225.897948) (xy 336.37601 -225.879152) (xy 336.347308 -225.85426) (xy 336.095086 -225.85426)
			(xy 336.066384 -225.879152) (xy 336.063844 -225.897948) (xy 336.059867 -225.922755) (xy 336.045086 -225.97077)
			(xy 336.022888 -226.015838) (xy 335.993834 -226.056823) (xy 335.958656 -226.09269) (xy 335.918242 -226.122534)
			(xy 335.873613 -226.145602) (xy 335.825894 -226.161312) (xy 335.776289 -226.169267) (xy 335.726051 -226.169267)
			(xy 335.676446 -226.161312) (xy 335.628727 -226.145602) (xy 335.584098 -226.122534) (xy 335.543684 -226.09269)
			(xy 335.508506 -226.056823) (xy 335.479452 -226.015838) (xy 335.457254 -225.97077) (xy 335.442473 -225.922755)
			(xy 335.438496 -225.897948) (xy 335.435956 -225.879152) (xy 335.407254 -225.85426) (xy 335.144618 -225.85426)
			(xy 335.11617 -225.878898) (xy 335.113376 -225.897694) (xy 335.109467 -225.921622) (xy 335.095075 -225.967918)
			(xy 335.073549 -226.011359) (xy 335.045429 -226.050852) (xy 335.011422 -226.085407) (xy 334.972382 -226.114153)
			(xy 334.92929 -226.13637) (xy 334.883229 -226.151499) (xy 334.835357 -226.159159) (xy 334.786875 -226.159159)
			(xy 334.739003 -226.151499) (xy 334.692942 -226.13637) (xy 334.64985 -226.114153) (xy 334.61081 -226.085407)
			(xy 334.576803 -226.050852) (xy 334.548683 -226.011359) (xy 334.527157 -225.967918) (xy 334.512765 -225.921622)
			(xy 334.508856 -225.897694) (xy 334.506062 -225.878898) (xy 334.477614 -225.85426) (xy 334.214978 -225.85426)
			(xy 334.186276 -225.879152) (xy 334.183736 -225.897948) (xy 334.179759 -225.922755) (xy 334.164978 -225.97077)
			(xy 334.14278 -226.015838) (xy 334.113726 -226.056823) (xy 334.078548 -226.09269) (xy 334.038134 -226.122534)
			(xy 333.993505 -226.145602) (xy 333.945786 -226.161312) (xy 333.896181 -226.169267) (xy 333.845943 -226.169267)
			(xy 333.796338 -226.161312) (xy 333.748619 -226.145602) (xy 333.70399 -226.122534) (xy 333.663576 -226.09269)
			(xy 333.628398 -226.056823) (xy 333.599344 -226.015838) (xy 333.577146 -225.97077) (xy 333.562365 -225.922755)
			(xy 333.558388 -225.897948) (xy 333.555848 -225.879152) (xy 333.527146 -225.85426) (xy 333.26451 -225.85426)
			(xy 333.236062 -225.878898) (xy 333.233268 -225.897694) (xy 333.229359 -225.921622) (xy 333.214967 -225.967918)
			(xy 333.193441 -226.011359) (xy 333.165321 -226.050852) (xy 333.131314 -226.085407) (xy 333.092274 -226.114153)
			(xy 333.049182 -226.13637) (xy 333.003121 -226.151499) (xy 332.955249 -226.159159) (xy 332.906767 -226.159159)
			(xy 332.858895 -226.151499) (xy 332.812834 -226.13637) (xy 332.769742 -226.114153) (xy 332.730702 -226.085407)
			(xy 332.696695 -226.050852) (xy 332.668575 -226.011359) (xy 332.647049 -225.967918) (xy 332.632657 -225.921622)
			(xy 332.628748 -225.897694) (xy 332.625954 -225.878898) (xy 332.597506 -225.85426) (xy 332.335124 -225.85426)
			(xy 332.306422 -225.879152) (xy 332.303882 -225.897948) (xy 332.299905 -225.922755) (xy 332.285124 -225.97077)
			(xy 332.262926 -226.015838) (xy 332.233872 -226.056823) (xy 332.198694 -226.09269) (xy 332.15828 -226.122534)
			(xy 332.113651 -226.145602) (xy 332.065932 -226.161312) (xy 332.016327 -226.169267) (xy 331.966089 -226.169267)
			(xy 331.916484 -226.161312) (xy 331.868765 -226.145602) (xy 331.824136 -226.122534) (xy 331.783722 -226.09269)
			(xy 331.748544 -226.056823) (xy 331.71949 -226.015838) (xy 331.697292 -225.97077) (xy 331.682511 -225.922755)
			(xy 331.678534 -225.897948) (xy 331.675994 -225.879152) (xy 331.647292 -225.85426) (xy 331.384656 -225.85426)
			(xy 331.356208 -225.878898) (xy 331.353414 -225.897694) (xy 331.349505 -225.921622) (xy 331.335113 -225.967918)
			(xy 331.313587 -226.011359) (xy 331.285467 -226.050852) (xy 331.25146 -226.085407) (xy 331.21242 -226.114153)
			(xy 331.169328 -226.13637) (xy 331.123267 -226.151499) (xy 331.075395 -226.159159) (xy 331.026913 -226.159159)
			(xy 330.979041 -226.151499) (xy 330.93298 -226.13637) (xy 330.889888 -226.114153) (xy 330.850848 -226.085407)
			(xy 330.816841 -226.050852) (xy 330.788721 -226.011359) (xy 330.767195 -225.967918) (xy 330.752803 -225.921622)
			(xy 330.748894 -225.897694) (xy 330.7461 -225.878898) (xy 330.717652 -225.85426) (xy 330.455016 -225.85426)
			(xy 330.426314 -225.879152) (xy 330.423774 -225.897948) (xy 330.419797 -225.922755) (xy 330.405016 -225.97077)
			(xy 330.382818 -226.015838) (xy 330.353764 -226.056823) (xy 330.318586 -226.09269) (xy 330.278172 -226.122534)
			(xy 330.233543 -226.145602) (xy 330.185824 -226.161312) (xy 330.136219 -226.169267) (xy 330.085981 -226.169267)
			(xy 330.036376 -226.161312) (xy 329.988657 -226.145602) (xy 329.944028 -226.122534) (xy 329.903614 -226.09269)
			(xy 329.868436 -226.056823) (xy 329.839382 -226.015838) (xy 329.817184 -225.97077) (xy 329.802403 -225.922755)
			(xy 329.798426 -225.897948) (xy 329.795886 -225.879152) (xy 329.767184 -225.85426) (xy 329.514962 -225.85426)
			(xy 329.48626 -225.879152) (xy 329.48372 -225.897948) (xy 329.479743 -225.922755) (xy 329.464962 -225.97077)
			(xy 329.442764 -226.015838) (xy 329.41371 -226.056823) (xy 329.378532 -226.09269) (xy 329.338118 -226.122534)
			(xy 329.293489 -226.145602) (xy 329.24577 -226.161312) (xy 329.196165 -226.169267) (xy 329.145927 -226.169267)
			(xy 329.096322 -226.161312) (xy 329.048603 -226.145602) (xy 329.003974 -226.122534) (xy 328.96356 -226.09269)
			(xy 328.928382 -226.056823) (xy 328.899328 -226.015838) (xy 328.87713 -225.97077) (xy 328.862349 -225.922755)
			(xy 328.858372 -225.897948) (xy 328.855832 -225.879152) (xy 328.82713 -225.85426) (xy 328.564748 -225.85426)
			(xy 328.5363 -225.878898) (xy 328.533506 -225.897694) (xy 328.529597 -225.921622) (xy 328.515205 -225.967918)
			(xy 328.493679 -226.011359) (xy 328.465559 -226.050852) (xy 328.431552 -226.085407) (xy 328.392512 -226.114153)
			(xy 328.34942 -226.13637) (xy 328.303359 -226.151499) (xy 328.255487 -226.159159) (xy 328.207005 -226.159159)
			(xy 328.159133 -226.151499) (xy 328.113072 -226.13637) (xy 328.06998 -226.114153) (xy 328.03094 -226.085407)
			(xy 327.996933 -226.050852) (xy 327.968813 -226.011359) (xy 327.947287 -225.967918) (xy 327.932895 -225.921622)
			(xy 327.928986 -225.897694) (xy 327.926192 -225.878898) (xy 327.897744 -225.85426) (xy 326.68464 -225.85426)
			(xy 326.656192 -225.878898) (xy 326.653398 -225.897694) (xy 326.649489 -225.921622) (xy 326.635097 -225.967918)
			(xy 326.613571 -226.011359) (xy 326.585451 -226.050852) (xy 326.551444 -226.085407) (xy 326.512404 -226.114153)
			(xy 326.469312 -226.13637) (xy 326.423251 -226.151499) (xy 326.375379 -226.159159) (xy 326.326897 -226.159159)
			(xy 326.279025 -226.151499) (xy 326.232964 -226.13637) (xy 326.189872 -226.114153) (xy 326.150832 -226.085407)
			(xy 326.116825 -226.050852) (xy 326.088705 -226.011359) (xy 326.067179 -225.967918) (xy 326.052787 -225.921622)
			(xy 326.048878 -225.897694) (xy 326.046084 -225.878898) (xy 326.017636 -225.85426) (xy 312.334402 -225.85426)
			(xy 312.324333 -225.854684) (xy 312.305734 -225.862405) (xy 312.298334 -225.869246) (xy 311.503314 -226.664266)
			(xy 324.63538 -226.664266) (xy 324.63934 -226.615212) (xy 324.651117 -226.567428) (xy 324.670408 -226.522152)
			(xy 324.696711 -226.480556) (xy 324.729346 -226.443719) (xy 324.767467 -226.412594) (xy 324.810088 -226.387987)
			(xy 324.856104 -226.370535) (xy 324.904323 -226.360691) (xy 324.953498 -226.35871) (xy 325.002353 -226.364642)
			(xy 325.049624 -226.378334) (xy 325.094086 -226.399432) (xy 325.134589 -226.427388) (xy 325.170082 -226.46148)
			(xy 325.199647 -226.500824) (xy 325.222518 -226.544401) (xy 325.238102 -226.591082) (xy 325.245997 -226.639659)
			(xy 325.246492 -226.664266) (xy 327.455288 -226.664266) (xy 327.459248 -226.615212) (xy 327.471025 -226.567428)
			(xy 327.490316 -226.522152) (xy 327.516619 -226.480556) (xy 327.549254 -226.443719) (xy 327.587375 -226.412594)
			(xy 327.629996 -226.387987) (xy 327.676012 -226.370535) (xy 327.724231 -226.360691) (xy 327.773406 -226.35871)
			(xy 327.822261 -226.364642) (xy 327.869532 -226.378334) (xy 327.913994 -226.399432) (xy 327.954497 -226.427388)
			(xy 327.98999 -226.46148) (xy 328.019555 -226.500824) (xy 328.042426 -226.544401) (xy 328.05801 -226.591082)
			(xy 328.065905 -226.639659) (xy 328.0664 -226.664266) (xy 328.384911 -226.664266) (xy 328.389006 -226.613538)
			(xy 328.401185 -226.564124) (xy 328.421133 -226.517304) (xy 328.448334 -226.47429) (xy 328.482082 -226.436196)
			(xy 328.521504 -226.404009) (xy 328.565578 -226.378563) (xy 328.613164 -226.360516) (xy 328.663028 -226.350336)
			(xy 328.71388 -226.348287) (xy 328.764401 -226.354421) (xy 328.813285 -226.368581) (xy 328.859264 -226.390398)
			(xy 328.901148 -226.419308) (xy 328.937852 -226.454563) (xy 328.968425 -226.495249) (xy 328.992076 -226.540312)
			(xy 329.008192 -226.588586) (xy 329.016356 -226.63882) (xy 329.016868 -226.664266) (xy 329.335396 -226.664266)
			(xy 329.339356 -226.615212) (xy 329.351133 -226.567428) (xy 329.370424 -226.522152) (xy 329.396727 -226.480556)
			(xy 329.429362 -226.443719) (xy 329.467483 -226.412594) (xy 329.510104 -226.387987) (xy 329.55612 -226.370535)
			(xy 329.604339 -226.360691) (xy 329.653514 -226.35871) (xy 329.702369 -226.364642) (xy 329.74964 -226.378334)
			(xy 329.794102 -226.399432) (xy 329.834605 -226.427388) (xy 329.870098 -226.46148) (xy 329.899663 -226.500824)
			(xy 329.922534 -226.544401) (xy 329.938118 -226.591082) (xy 329.946013 -226.639659) (xy 329.946508 -226.664266)
			(xy 330.264765 -226.664266) (xy 330.26886 -226.613538) (xy 330.281039 -226.564124) (xy 330.300987 -226.517304)
			(xy 330.328188 -226.47429) (xy 330.361936 -226.436196) (xy 330.401358 -226.404009) (xy 330.445432 -226.378563)
			(xy 330.493018 -226.360516) (xy 330.542882 -226.350336) (xy 330.593734 -226.348287) (xy 330.644255 -226.354421)
			(xy 330.693139 -226.368581) (xy 330.739118 -226.390398) (xy 330.781002 -226.419308) (xy 330.817706 -226.454563)
			(xy 330.848279 -226.495249) (xy 330.87193 -226.540312) (xy 330.888046 -226.588586) (xy 330.89621 -226.63882)
			(xy 330.896722 -226.664266) (xy 331.21525 -226.664266) (xy 331.21921 -226.615212) (xy 331.230987 -226.567428)
			(xy 331.250278 -226.522152) (xy 331.276581 -226.480556) (xy 331.309216 -226.443719) (xy 331.347337 -226.412594)
			(xy 331.389958 -226.387987) (xy 331.435974 -226.370535) (xy 331.484193 -226.360691) (xy 331.533368 -226.35871)
			(xy 331.582223 -226.364642) (xy 331.629494 -226.378334) (xy 331.673956 -226.399432) (xy 331.714459 -226.427388)
			(xy 331.749952 -226.46148) (xy 331.779517 -226.500824) (xy 331.802388 -226.544401) (xy 331.817972 -226.591082)
			(xy 331.825867 -226.639659) (xy 331.826362 -226.664266) (xy 332.144873 -226.664266) (xy 332.148968 -226.613538)
			(xy 332.161147 -226.564124) (xy 332.181095 -226.517304) (xy 332.208296 -226.47429) (xy 332.242044 -226.436196)
			(xy 332.281466 -226.404009) (xy 332.32554 -226.378563) (xy 332.373126 -226.360516) (xy 332.42299 -226.350336)
			(xy 332.473842 -226.348287) (xy 332.524363 -226.354421) (xy 332.573247 -226.368581) (xy 332.619226 -226.390398)
			(xy 332.66111 -226.419308) (xy 332.697814 -226.454563) (xy 332.728387 -226.495249) (xy 332.752038 -226.540312)
			(xy 332.768154 -226.588586) (xy 332.776318 -226.63882) (xy 332.77683 -226.664266) (xy 333.084927 -226.664266)
			(xy 333.089022 -226.613538) (xy 333.101201 -226.564124) (xy 333.121149 -226.517304) (xy 333.14835 -226.47429)
			(xy 333.182098 -226.436196) (xy 333.22152 -226.404009) (xy 333.265594 -226.378563) (xy 333.31318 -226.360516)
			(xy 333.363044 -226.350336) (xy 333.413896 -226.348287) (xy 333.464417 -226.354421) (xy 333.513301 -226.368581)
			(xy 333.55928 -226.390398) (xy 333.601164 -226.419308) (xy 333.637868 -226.454563) (xy 333.668441 -226.495249)
			(xy 333.692092 -226.540312) (xy 333.708208 -226.588586) (xy 333.716372 -226.63882) (xy 333.716884 -226.664266)
			(xy 334.035412 -226.664266) (xy 334.039372 -226.615212) (xy 334.051149 -226.567428) (xy 334.07044 -226.522152)
			(xy 334.096743 -226.480556) (xy 334.129378 -226.443719) (xy 334.167499 -226.412594) (xy 334.21012 -226.387987)
			(xy 334.256136 -226.370535) (xy 334.304355 -226.360691) (xy 334.35353 -226.35871) (xy 334.402385 -226.364642)
			(xy 334.449656 -226.378334) (xy 334.494118 -226.399432) (xy 334.534621 -226.427388) (xy 334.570114 -226.46148)
			(xy 334.599679 -226.500824) (xy 334.62255 -226.544401) (xy 334.638134 -226.591082) (xy 334.646029 -226.639659)
			(xy 334.646524 -226.664266) (xy 334.964781 -226.664266) (xy 334.968876 -226.613538) (xy 334.981055 -226.564124)
			(xy 335.001003 -226.517304) (xy 335.028204 -226.47429) (xy 335.061952 -226.436196) (xy 335.101374 -226.404009)
			(xy 335.145448 -226.378563) (xy 335.193034 -226.360516) (xy 335.242898 -226.350336) (xy 335.29375 -226.348287)
			(xy 335.344271 -226.354421) (xy 335.393155 -226.368581) (xy 335.439134 -226.390398) (xy 335.481018 -226.419308)
			(xy 335.517722 -226.454563) (xy 335.548295 -226.495249) (xy 335.571946 -226.540312) (xy 335.588062 -226.588586)
			(xy 335.596226 -226.63882) (xy 335.596738 -226.664266) (xy 335.915266 -226.664266) (xy 335.919226 -226.615212)
			(xy 335.931003 -226.567428) (xy 335.950294 -226.522152) (xy 335.976597 -226.480556) (xy 336.009232 -226.443719)
			(xy 336.047353 -226.412594) (xy 336.089974 -226.387987) (xy 336.13599 -226.370535) (xy 336.184209 -226.360691)
			(xy 336.233384 -226.35871) (xy 336.282239 -226.364642) (xy 336.32951 -226.378334) (xy 336.373972 -226.399432)
			(xy 336.414475 -226.427388) (xy 336.449968 -226.46148) (xy 336.479533 -226.500824) (xy 336.502404 -226.544401)
			(xy 336.517988 -226.591082) (xy 336.525883 -226.639659) (xy 336.526378 -226.664266) (xy 336.844889 -226.664266)
			(xy 336.848984 -226.613538) (xy 336.861163 -226.564124) (xy 336.881111 -226.517304) (xy 336.908312 -226.47429)
			(xy 336.94206 -226.436196) (xy 336.981482 -226.404009) (xy 337.025556 -226.378563) (xy 337.073142 -226.360516)
			(xy 337.123006 -226.350336) (xy 337.173858 -226.348287) (xy 337.224379 -226.354421) (xy 337.273263 -226.368581)
			(xy 337.319242 -226.390398) (xy 337.361126 -226.419308) (xy 337.39783 -226.454563) (xy 337.428403 -226.495249)
			(xy 337.452054 -226.540312) (xy 337.46817 -226.588586) (xy 337.476334 -226.63882) (xy 337.476846 -226.664266)
			(xy 337.795374 -226.664266) (xy 337.799334 -226.615212) (xy 337.811111 -226.567428) (xy 337.830402 -226.522152)
			(xy 337.856705 -226.480556) (xy 337.88934 -226.443719) (xy 337.927461 -226.412594) (xy 337.970082 -226.387987)
			(xy 338.016098 -226.370535) (xy 338.064317 -226.360691) (xy 338.113492 -226.35871) (xy 338.162347 -226.364642)
			(xy 338.209618 -226.378334) (xy 338.25408 -226.399432) (xy 338.294583 -226.427388) (xy 338.330076 -226.46148)
			(xy 338.359641 -226.500824) (xy 338.382512 -226.544401) (xy 338.398096 -226.591082) (xy 338.405991 -226.639659)
			(xy 338.406486 -226.664266) (xy 338.724743 -226.664266) (xy 338.728838 -226.613538) (xy 338.741017 -226.564124)
			(xy 338.760965 -226.517304) (xy 338.788166 -226.47429) (xy 338.821914 -226.436196) (xy 338.861336 -226.404009)
			(xy 338.90541 -226.378563) (xy 338.952996 -226.360516) (xy 339.00286 -226.350336) (xy 339.053712 -226.348287)
			(xy 339.104233 -226.354421) (xy 339.153117 -226.368581) (xy 339.199096 -226.390398) (xy 339.24098 -226.419308)
			(xy 339.277684 -226.454563) (xy 339.308257 -226.495249) (xy 339.331908 -226.540312) (xy 339.348024 -226.588586)
			(xy 339.356188 -226.63882) (xy 339.3567 -226.664266) (xy 339.664797 -226.664266) (xy 339.668892 -226.613538)
			(xy 339.681071 -226.564124) (xy 339.701019 -226.517304) (xy 339.72822 -226.47429) (xy 339.761968 -226.436196)
			(xy 339.80139 -226.404009) (xy 339.845464 -226.378563) (xy 339.89305 -226.360516) (xy 339.942914 -226.350336)
			(xy 339.993766 -226.348287) (xy 340.044287 -226.354421) (xy 340.093171 -226.368581) (xy 340.13915 -226.390398)
			(xy 340.181034 -226.419308) (xy 340.217738 -226.454563) (xy 340.248311 -226.495249) (xy 340.271962 -226.540312)
			(xy 340.288078 -226.588586) (xy 340.296242 -226.63882) (xy 340.296754 -226.664266) (xy 340.615282 -226.664266)
			(xy 340.619242 -226.615212) (xy 340.631019 -226.567428) (xy 340.65031 -226.522152) (xy 340.676613 -226.480556)
			(xy 340.709248 -226.443719) (xy 340.747369 -226.412594) (xy 340.78999 -226.387987) (xy 340.836006 -226.370535)
			(xy 340.884225 -226.360691) (xy 340.9334 -226.35871) (xy 340.982255 -226.364642) (xy 341.029526 -226.378334)
			(xy 341.073988 -226.399432) (xy 341.114491 -226.427388) (xy 341.149984 -226.46148) (xy 341.179549 -226.500824)
			(xy 341.20242 -226.544401) (xy 341.218004 -226.591082) (xy 341.225899 -226.639659) (xy 341.226394 -226.664266)
			(xy 341.544905 -226.664266) (xy 341.549 -226.613538) (xy 341.561179 -226.564124) (xy 341.581127 -226.517304)
			(xy 341.608328 -226.47429) (xy 341.642076 -226.436196) (xy 341.681498 -226.404009) (xy 341.725572 -226.378563)
			(xy 341.773158 -226.360516) (xy 341.823022 -226.350336) (xy 341.873874 -226.348287) (xy 341.924395 -226.354421)
			(xy 341.973279 -226.368581) (xy 342.019258 -226.390398) (xy 342.061142 -226.419308) (xy 342.097846 -226.454563)
			(xy 342.128419 -226.495249) (xy 342.15207 -226.540312) (xy 342.168186 -226.588586) (xy 342.17635 -226.63882)
			(xy 342.176862 -226.664266) (xy 342.49539 -226.664266) (xy 342.49935 -226.615212) (xy 342.511127 -226.567428)
			(xy 342.530418 -226.522152) (xy 342.556721 -226.480556) (xy 342.589356 -226.443719) (xy 342.627477 -226.412594)
			(xy 342.670098 -226.387987) (xy 342.716114 -226.370535) (xy 342.764333 -226.360691) (xy 342.813508 -226.35871)
			(xy 342.862363 -226.364642) (xy 342.909634 -226.378334) (xy 342.954096 -226.399432) (xy 342.994599 -226.427388)
			(xy 343.030092 -226.46148) (xy 343.059657 -226.500824) (xy 343.082528 -226.544401) (xy 343.098112 -226.591082)
			(xy 343.106007 -226.639659) (xy 343.106502 -226.664266) (xy 343.106007 -226.688873) (xy 343.098112 -226.73745)
			(xy 343.082528 -226.784131) (xy 343.059657 -226.827708) (xy 343.030092 -226.867052) (xy 342.994599 -226.901144)
			(xy 342.954096 -226.9291) (xy 342.909634 -226.950198) (xy 342.862363 -226.96389) (xy 342.813508 -226.969822)
			(xy 342.764333 -226.967841) (xy 342.716114 -226.957997) (xy 342.670098 -226.940545) (xy 342.627477 -226.915938)
			(xy 342.589356 -226.884813) (xy 342.556721 -226.847976) (xy 342.530418 -226.80638) (xy 342.511127 -226.761104)
			(xy 342.49935 -226.71332) (xy 342.49539 -226.664266) (xy 342.176862 -226.664266) (xy 342.17635 -226.689712)
			(xy 342.168186 -226.739946) (xy 342.15207 -226.78822) (xy 342.128419 -226.833283) (xy 342.097846 -226.873969)
			(xy 342.061142 -226.909224) (xy 342.019258 -226.938134) (xy 341.973279 -226.959951) (xy 341.924395 -226.974111)
			(xy 341.873874 -226.980245) (xy 341.823022 -226.978196) (xy 341.773158 -226.968016) (xy 341.725572 -226.949969)
			(xy 341.681498 -226.924523) (xy 341.642076 -226.892336) (xy 341.608328 -226.854242) (xy 341.581127 -226.811228)
			(xy 341.561179 -226.764408) (xy 341.549 -226.714994) (xy 341.544905 -226.664266) (xy 341.226394 -226.664266)
			(xy 341.225899 -226.688873) (xy 341.218004 -226.73745) (xy 341.20242 -226.784131) (xy 341.179549 -226.827708)
			(xy 341.149984 -226.867052) (xy 341.114491 -226.901144) (xy 341.073988 -226.9291) (xy 341.029526 -226.950198)
			(xy 340.982255 -226.96389) (xy 340.9334 -226.969822) (xy 340.884225 -226.967841) (xy 340.836006 -226.957997)
			(xy 340.78999 -226.940545) (xy 340.747369 -226.915938) (xy 340.709248 -226.884813) (xy 340.676613 -226.847976)
			(xy 340.65031 -226.80638) (xy 340.631019 -226.761104) (xy 340.619242 -226.71332) (xy 340.615282 -226.664266)
			(xy 340.296754 -226.664266) (xy 340.296242 -226.689712) (xy 340.288078 -226.739946) (xy 340.271962 -226.78822)
			(xy 340.248311 -226.833283) (xy 340.217738 -226.873969) (xy 340.181034 -226.909224) (xy 340.13915 -226.938134)
			(xy 340.093171 -226.959951) (xy 340.044287 -226.974111) (xy 339.993766 -226.980245) (xy 339.942914 -226.978196)
			(xy 339.89305 -226.968016) (xy 339.845464 -226.949969) (xy 339.80139 -226.924523) (xy 339.761968 -226.892336)
			(xy 339.72822 -226.854242) (xy 339.701019 -226.811228) (xy 339.681071 -226.764408) (xy 339.668892 -226.714994)
			(xy 339.664797 -226.664266) (xy 339.3567 -226.664266) (xy 339.356188 -226.689712) (xy 339.348024 -226.739946)
			(xy 339.331908 -226.78822) (xy 339.308257 -226.833283) (xy 339.277684 -226.873969) (xy 339.24098 -226.909224)
			(xy 339.199096 -226.938134) (xy 339.153117 -226.959951) (xy 339.104233 -226.974111) (xy 339.053712 -226.980245)
			(xy 339.00286 -226.978196) (xy 338.952996 -226.968016) (xy 338.90541 -226.949969) (xy 338.861336 -226.924523)
			(xy 338.821914 -226.892336) (xy 338.788166 -226.854242) (xy 338.760965 -226.811228) (xy 338.741017 -226.764408)
			(xy 338.728838 -226.714994) (xy 338.724743 -226.664266) (xy 338.406486 -226.664266) (xy 338.405991 -226.688873)
			(xy 338.398096 -226.73745) (xy 338.382512 -226.784131) (xy 338.359641 -226.827708) (xy 338.330076 -226.867052)
			(xy 338.294583 -226.901144) (xy 338.25408 -226.9291) (xy 338.209618 -226.950198) (xy 338.162347 -226.96389)
			(xy 338.113492 -226.969822) (xy 338.064317 -226.967841) (xy 338.016098 -226.957997) (xy 337.970082 -226.940545)
			(xy 337.927461 -226.915938) (xy 337.88934 -226.884813) (xy 337.856705 -226.847976) (xy 337.830402 -226.80638)
			(xy 337.811111 -226.761104) (xy 337.799334 -226.71332) (xy 337.795374 -226.664266) (xy 337.476846 -226.664266)
			(xy 337.476334 -226.689712) (xy 337.46817 -226.739946) (xy 337.452054 -226.78822) (xy 337.428403 -226.833283)
			(xy 337.39783 -226.873969) (xy 337.361126 -226.909224) (xy 337.319242 -226.938134) (xy 337.273263 -226.959951)
			(xy 337.224379 -226.974111) (xy 337.173858 -226.980245) (xy 337.123006 -226.978196) (xy 337.073142 -226.968016)
			(xy 337.025556 -226.949969) (xy 336.981482 -226.924523) (xy 336.94206 -226.892336) (xy 336.908312 -226.854242)
			(xy 336.881111 -226.811228) (xy 336.861163 -226.764408) (xy 336.848984 -226.714994) (xy 336.844889 -226.664266)
			(xy 336.526378 -226.664266) (xy 336.525883 -226.688873) (xy 336.517988 -226.73745) (xy 336.502404 -226.784131)
			(xy 336.479533 -226.827708) (xy 336.449968 -226.867052) (xy 336.414475 -226.901144) (xy 336.373972 -226.9291)
			(xy 336.32951 -226.950198) (xy 336.282239 -226.96389) (xy 336.233384 -226.969822) (xy 336.184209 -226.967841)
			(xy 336.13599 -226.957997) (xy 336.089974 -226.940545) (xy 336.047353 -226.915938) (xy 336.009232 -226.884813)
			(xy 335.976597 -226.847976) (xy 335.950294 -226.80638) (xy 335.931003 -226.761104) (xy 335.919226 -226.71332)
			(xy 335.915266 -226.664266) (xy 335.596738 -226.664266) (xy 335.596226 -226.689712) (xy 335.588062 -226.739946)
			(xy 335.571946 -226.78822) (xy 335.548295 -226.833283) (xy 335.517722 -226.873969) (xy 335.481018 -226.909224)
			(xy 335.439134 -226.938134) (xy 335.393155 -226.959951) (xy 335.344271 -226.974111) (xy 335.29375 -226.980245)
			(xy 335.242898 -226.978196) (xy 335.193034 -226.968016) (xy 335.145448 -226.949969) (xy 335.101374 -226.924523)
			(xy 335.061952 -226.892336) (xy 335.028204 -226.854242) (xy 335.001003 -226.811228) (xy 334.981055 -226.764408)
			(xy 334.968876 -226.714994) (xy 334.964781 -226.664266) (xy 334.646524 -226.664266) (xy 334.646029 -226.688873)
			(xy 334.638134 -226.73745) (xy 334.62255 -226.784131) (xy 334.599679 -226.827708) (xy 334.570114 -226.867052)
			(xy 334.534621 -226.901144) (xy 334.494118 -226.9291) (xy 334.449656 -226.950198) (xy 334.402385 -226.96389)
			(xy 334.35353 -226.969822) (xy 334.304355 -226.967841) (xy 334.256136 -226.957997) (xy 334.21012 -226.940545)
			(xy 334.167499 -226.915938) (xy 334.129378 -226.884813) (xy 334.096743 -226.847976) (xy 334.07044 -226.80638)
			(xy 334.051149 -226.761104) (xy 334.039372 -226.71332) (xy 334.035412 -226.664266) (xy 333.716884 -226.664266)
			(xy 333.716372 -226.689712) (xy 333.708208 -226.739946) (xy 333.692092 -226.78822) (xy 333.668441 -226.833283)
			(xy 333.637868 -226.873969) (xy 333.601164 -226.909224) (xy 333.55928 -226.938134) (xy 333.513301 -226.959951)
			(xy 333.464417 -226.974111) (xy 333.413896 -226.980245) (xy 333.363044 -226.978196) (xy 333.31318 -226.968016)
			(xy 333.265594 -226.949969) (xy 333.22152 -226.924523) (xy 333.182098 -226.892336) (xy 333.14835 -226.854242)
			(xy 333.121149 -226.811228) (xy 333.101201 -226.764408) (xy 333.089022 -226.714994) (xy 333.084927 -226.664266)
			(xy 332.77683 -226.664266) (xy 332.776318 -226.689712) (xy 332.768154 -226.739946) (xy 332.752038 -226.78822)
			(xy 332.728387 -226.833283) (xy 332.697814 -226.873969) (xy 332.66111 -226.909224) (xy 332.619226 -226.938134)
			(xy 332.573247 -226.959951) (xy 332.524363 -226.974111) (xy 332.473842 -226.980245) (xy 332.42299 -226.978196)
			(xy 332.373126 -226.968016) (xy 332.32554 -226.949969) (xy 332.281466 -226.924523) (xy 332.242044 -226.892336)
			(xy 332.208296 -226.854242) (xy 332.181095 -226.811228) (xy 332.161147 -226.764408) (xy 332.148968 -226.714994)
			(xy 332.144873 -226.664266) (xy 331.826362 -226.664266) (xy 331.825867 -226.688873) (xy 331.817972 -226.73745)
			(xy 331.802388 -226.784131) (xy 331.779517 -226.827708) (xy 331.749952 -226.867052) (xy 331.714459 -226.901144)
			(xy 331.673956 -226.9291) (xy 331.629494 -226.950198) (xy 331.582223 -226.96389) (xy 331.533368 -226.969822)
			(xy 331.484193 -226.967841) (xy 331.435974 -226.957997) (xy 331.389958 -226.940545) (xy 331.347337 -226.915938)
			(xy 331.309216 -226.884813) (xy 331.276581 -226.847976) (xy 331.250278 -226.80638) (xy 331.230987 -226.761104)
			(xy 331.21921 -226.71332) (xy 331.21525 -226.664266) (xy 330.896722 -226.664266) (xy 330.89621 -226.689712)
			(xy 330.888046 -226.739946) (xy 330.87193 -226.78822) (xy 330.848279 -226.833283) (xy 330.817706 -226.873969)
			(xy 330.781002 -226.909224) (xy 330.739118 -226.938134) (xy 330.693139 -226.959951) (xy 330.644255 -226.974111)
			(xy 330.593734 -226.980245) (xy 330.542882 -226.978196) (xy 330.493018 -226.968016) (xy 330.445432 -226.949969)
			(xy 330.401358 -226.924523) (xy 330.361936 -226.892336) (xy 330.328188 -226.854242) (xy 330.300987 -226.811228)
			(xy 330.281039 -226.764408) (xy 330.26886 -226.714994) (xy 330.264765 -226.664266) (xy 329.946508 -226.664266)
			(xy 329.946013 -226.688873) (xy 329.938118 -226.73745) (xy 329.922534 -226.784131) (xy 329.899663 -226.827708)
			(xy 329.870098 -226.867052) (xy 329.834605 -226.901144) (xy 329.794102 -226.9291) (xy 329.74964 -226.950198)
			(xy 329.702369 -226.96389) (xy 329.653514 -226.969822) (xy 329.604339 -226.967841) (xy 329.55612 -226.957997)
			(xy 329.510104 -226.940545) (xy 329.467483 -226.915938) (xy 329.429362 -226.884813) (xy 329.396727 -226.847976)
			(xy 329.370424 -226.80638) (xy 329.351133 -226.761104) (xy 329.339356 -226.71332) (xy 329.335396 -226.664266)
			(xy 329.016868 -226.664266) (xy 329.016356 -226.689712) (xy 329.008192 -226.739946) (xy 328.992076 -226.78822)
			(xy 328.968425 -226.833283) (xy 328.937852 -226.873969) (xy 328.901148 -226.909224) (xy 328.859264 -226.938134)
			(xy 328.813285 -226.959951) (xy 328.764401 -226.974111) (xy 328.71388 -226.980245) (xy 328.663028 -226.978196)
			(xy 328.613164 -226.968016) (xy 328.565578 -226.949969) (xy 328.521504 -226.924523) (xy 328.482082 -226.892336)
			(xy 328.448334 -226.854242) (xy 328.421133 -226.811228) (xy 328.401185 -226.764408) (xy 328.389006 -226.714994)
			(xy 328.384911 -226.664266) (xy 328.0664 -226.664266) (xy 328.065905 -226.688873) (xy 328.05801 -226.73745)
			(xy 328.042426 -226.784131) (xy 328.019555 -226.827708) (xy 327.98999 -226.867052) (xy 327.954497 -226.901144)
			(xy 327.913994 -226.9291) (xy 327.869532 -226.950198) (xy 327.822261 -226.96389) (xy 327.773406 -226.969822)
			(xy 327.724231 -226.967841) (xy 327.676012 -226.957997) (xy 327.629996 -226.940545) (xy 327.587375 -226.915938)
			(xy 327.549254 -226.884813) (xy 327.516619 -226.847976) (xy 327.490316 -226.80638) (xy 327.471025 -226.761104)
			(xy 327.459248 -226.71332) (xy 327.455288 -226.664266) (xy 325.246492 -226.664266) (xy 325.245997 -226.688873)
			(xy 325.238102 -226.73745) (xy 325.222518 -226.784131) (xy 325.199647 -226.827708) (xy 325.170082 -226.867052)
			(xy 325.134589 -226.901144) (xy 325.094086 -226.9291) (xy 325.049624 -226.950198) (xy 325.002353 -226.96389)
			(xy 324.953498 -226.969822) (xy 324.904323 -226.967841) (xy 324.856104 -226.957997) (xy 324.810088 -226.940545)
			(xy 324.767467 -226.915938) (xy 324.729346 -226.884813) (xy 324.696711 -226.847976) (xy 324.670408 -226.80638)
			(xy 324.651117 -226.761104) (xy 324.63934 -226.71332) (xy 324.63538 -226.664266) (xy 311.503314 -226.664266)
			(xy 310.693308 -227.474272) (xy 326.045334 -227.474272) (xy 326.049294 -227.425218) (xy 326.061071 -227.377434)
			(xy 326.080362 -227.332158) (xy 326.106665 -227.290562) (xy 326.1393 -227.253725) (xy 326.177421 -227.2226)
			(xy 326.220042 -227.197993) (xy 326.266058 -227.180541) (xy 326.314277 -227.170697) (xy 326.363452 -227.168716)
			(xy 326.412307 -227.174648) (xy 326.459578 -227.18834) (xy 326.50404 -227.209438) (xy 326.544543 -227.237394)
			(xy 326.580036 -227.271486) (xy 326.609601 -227.31083) (xy 326.632472 -227.354407) (xy 326.648056 -227.401088)
			(xy 326.655951 -227.449665) (xy 326.656446 -227.474272) (xy 328.854811 -227.474272) (xy 328.858906 -227.423544)
			(xy 328.871085 -227.37413) (xy 328.891033 -227.32731) (xy 328.918234 -227.284296) (xy 328.951982 -227.246202)
			(xy 328.991404 -227.214015) (xy 329.035478 -227.188569) (xy 329.083064 -227.170522) (xy 329.132928 -227.160342)
			(xy 329.18378 -227.158293) (xy 329.234301 -227.164427) (xy 329.283185 -227.178587) (xy 329.329164 -227.200404)
			(xy 329.371048 -227.229314) (xy 329.407752 -227.264569) (xy 329.438325 -227.305255) (xy 329.461976 -227.350318)
			(xy 329.478092 -227.398592) (xy 329.486256 -227.448826) (xy 329.486768 -227.474272) (xy 329.794865 -227.474272)
			(xy 329.79896 -227.423544) (xy 329.811139 -227.37413) (xy 329.831087 -227.32731) (xy 329.858288 -227.284296)
			(xy 329.892036 -227.246202) (xy 329.931458 -227.214015) (xy 329.975532 -227.188569) (xy 330.023118 -227.170522)
			(xy 330.072982 -227.160342) (xy 330.123834 -227.158293) (xy 330.174355 -227.164427) (xy 330.223239 -227.178587)
			(xy 330.269218 -227.200404) (xy 330.311102 -227.229314) (xy 330.347806 -227.264569) (xy 330.378379 -227.305255)
			(xy 330.40203 -227.350318) (xy 330.418146 -227.398592) (xy 330.42631 -227.448826) (xy 330.426822 -227.474272)
			(xy 330.74535 -227.474272) (xy 330.74931 -227.425218) (xy 330.761087 -227.377434) (xy 330.780378 -227.332158)
			(xy 330.806681 -227.290562) (xy 330.839316 -227.253725) (xy 330.877437 -227.2226) (xy 330.920058 -227.197993)
			(xy 330.966074 -227.180541) (xy 331.014293 -227.170697) (xy 331.063468 -227.168716) (xy 331.112323 -227.174648)
			(xy 331.159594 -227.18834) (xy 331.204056 -227.209438) (xy 331.244559 -227.237394) (xy 331.280052 -227.271486)
			(xy 331.309617 -227.31083) (xy 331.332488 -227.354407) (xy 331.348072 -227.401088) (xy 331.355967 -227.449665)
			(xy 331.356462 -227.474272) (xy 331.674973 -227.474272) (xy 331.679068 -227.423544) (xy 331.691247 -227.37413)
			(xy 331.711195 -227.32731) (xy 331.738396 -227.284296) (xy 331.772144 -227.246202) (xy 331.811566 -227.214015)
			(xy 331.85564 -227.188569) (xy 331.903226 -227.170522) (xy 331.95309 -227.160342) (xy 332.003942 -227.158293)
			(xy 332.054463 -227.164427) (xy 332.103347 -227.178587) (xy 332.149326 -227.200404) (xy 332.19121 -227.229314)
			(xy 332.227914 -227.264569) (xy 332.258487 -227.305255) (xy 332.282138 -227.350318) (xy 332.298254 -227.398592)
			(xy 332.306418 -227.448826) (xy 332.30693 -227.474272) (xy 332.625204 -227.474272) (xy 332.629164 -227.425218)
			(xy 332.640941 -227.377434) (xy 332.660232 -227.332158) (xy 332.686535 -227.290562) (xy 332.71917 -227.253725)
			(xy 332.757291 -227.2226) (xy 332.799912 -227.197993) (xy 332.845928 -227.180541) (xy 332.894147 -227.170697)
			(xy 332.943322 -227.168716) (xy 332.992177 -227.174648) (xy 333.039448 -227.18834) (xy 333.08391 -227.209438)
			(xy 333.124413 -227.237394) (xy 333.159906 -227.271486) (xy 333.189471 -227.31083) (xy 333.212342 -227.354407)
			(xy 333.227926 -227.401088) (xy 333.235821 -227.449665) (xy 333.236316 -227.474272) (xy 333.554827 -227.474272)
			(xy 333.558922 -227.423544) (xy 333.571101 -227.37413) (xy 333.591049 -227.32731) (xy 333.61825 -227.284296)
			(xy 333.651998 -227.246202) (xy 333.69142 -227.214015) (xy 333.735494 -227.188569) (xy 333.78308 -227.170522)
			(xy 333.832944 -227.160342) (xy 333.883796 -227.158293) (xy 333.934317 -227.164427) (xy 333.983201 -227.178587)
			(xy 334.02918 -227.200404) (xy 334.071064 -227.229314) (xy 334.107768 -227.264569) (xy 334.138341 -227.305255)
			(xy 334.161992 -227.350318) (xy 334.178108 -227.398592) (xy 334.186272 -227.448826) (xy 334.186784 -227.474272)
			(xy 335.434935 -227.474272) (xy 335.43903 -227.423544) (xy 335.451209 -227.37413) (xy 335.471157 -227.32731)
			(xy 335.498358 -227.284296) (xy 335.532106 -227.246202) (xy 335.571528 -227.214015) (xy 335.615602 -227.188569)
			(xy 335.663188 -227.170522) (xy 335.713052 -227.160342) (xy 335.763904 -227.158293) (xy 335.814425 -227.164427)
			(xy 335.863309 -227.178587) (xy 335.909288 -227.200404) (xy 335.951172 -227.229314) (xy 335.987876 -227.264569)
			(xy 336.018449 -227.305255) (xy 336.0421 -227.350318) (xy 336.058216 -227.398592) (xy 336.06638 -227.448826)
			(xy 336.066892 -227.474272) (xy 336.374989 -227.474272) (xy 336.379084 -227.423544) (xy 336.391263 -227.37413)
			(xy 336.411211 -227.32731) (xy 336.438412 -227.284296) (xy 336.47216 -227.246202) (xy 336.511582 -227.214015)
			(xy 336.555656 -227.188569) (xy 336.603242 -227.170522) (xy 336.653106 -227.160342) (xy 336.703958 -227.158293)
			(xy 336.754479 -227.164427) (xy 336.803363 -227.178587) (xy 336.849342 -227.200404) (xy 336.891226 -227.229314)
			(xy 336.92793 -227.264569) (xy 336.958503 -227.305255) (xy 336.982154 -227.350318) (xy 336.99827 -227.398592)
			(xy 337.006434 -227.448826) (xy 337.006946 -227.474272) (xy 337.32522 -227.474272) (xy 337.32918 -227.425218)
			(xy 337.340957 -227.377434) (xy 337.360248 -227.332158) (xy 337.386551 -227.290562) (xy 337.419186 -227.253725)
			(xy 337.457307 -227.2226) (xy 337.499928 -227.197993) (xy 337.545944 -227.180541) (xy 337.594163 -227.170697)
			(xy 337.643338 -227.168716) (xy 337.692193 -227.174648) (xy 337.739464 -227.18834) (xy 337.783926 -227.209438)
			(xy 337.824429 -227.237394) (xy 337.859922 -227.271486) (xy 337.889487 -227.31083) (xy 337.912358 -227.354407)
			(xy 337.927942 -227.401088) (xy 337.935837 -227.449665) (xy 337.936332 -227.474272) (xy 338.254843 -227.474272)
			(xy 338.258938 -227.423544) (xy 338.271117 -227.37413) (xy 338.291065 -227.32731) (xy 338.318266 -227.284296)
			(xy 338.352014 -227.246202) (xy 338.391436 -227.214015) (xy 338.43551 -227.188569) (xy 338.483096 -227.170522)
			(xy 338.53296 -227.160342) (xy 338.583812 -227.158293) (xy 338.634333 -227.164427) (xy 338.683217 -227.178587)
			(xy 338.729196 -227.200404) (xy 338.77108 -227.229314) (xy 338.807784 -227.264569) (xy 338.838357 -227.305255)
			(xy 338.862008 -227.350318) (xy 338.878124 -227.398592) (xy 338.886288 -227.448826) (xy 338.8868 -227.474272)
			(xy 339.205328 -227.474272) (xy 339.209288 -227.425218) (xy 339.221065 -227.377434) (xy 339.240356 -227.332158)
			(xy 339.266659 -227.290562) (xy 339.299294 -227.253725) (xy 339.337415 -227.2226) (xy 339.380036 -227.197993)
			(xy 339.426052 -227.180541) (xy 339.474271 -227.170697) (xy 339.523446 -227.168716) (xy 339.572301 -227.174648)
			(xy 339.619572 -227.18834) (xy 339.664034 -227.209438) (xy 339.704537 -227.237394) (xy 339.74003 -227.271486)
			(xy 339.769595 -227.31083) (xy 339.792466 -227.354407) (xy 339.80805 -227.401088) (xy 339.815945 -227.449665)
			(xy 339.81644 -227.474272) (xy 340.134951 -227.474272) (xy 340.139046 -227.423544) (xy 340.151225 -227.37413)
			(xy 340.171173 -227.32731) (xy 340.198374 -227.284296) (xy 340.232122 -227.246202) (xy 340.271544 -227.214015)
			(xy 340.315618 -227.188569) (xy 340.363204 -227.170522) (xy 340.413068 -227.160342) (xy 340.46392 -227.158293)
			(xy 340.514441 -227.164427) (xy 340.563325 -227.178587) (xy 340.609304 -227.200404) (xy 340.651188 -227.229314)
			(xy 340.687892 -227.264569) (xy 340.718465 -227.305255) (xy 340.742116 -227.350318) (xy 340.758232 -227.398592)
			(xy 340.766396 -227.448826) (xy 340.766908 -227.474272) (xy 342.014805 -227.474272) (xy 342.0189 -227.423544)
			(xy 342.031079 -227.37413) (xy 342.051027 -227.32731) (xy 342.078228 -227.284296) (xy 342.111976 -227.246202)
			(xy 342.151398 -227.214015) (xy 342.195472 -227.188569) (xy 342.243058 -227.170522) (xy 342.292922 -227.160342)
			(xy 342.343774 -227.158293) (xy 342.394295 -227.164427) (xy 342.443179 -227.178587) (xy 342.489158 -227.200404)
			(xy 342.531042 -227.229314) (xy 342.567746 -227.264569) (xy 342.598319 -227.305255) (xy 342.62197 -227.350318)
			(xy 342.638086 -227.398592) (xy 342.64625 -227.448826) (xy 342.646762 -227.474272) (xy 342.954859 -227.474272)
			(xy 342.958954 -227.423544) (xy 342.971133 -227.37413) (xy 342.991081 -227.32731) (xy 343.018282 -227.284296)
			(xy 343.05203 -227.246202) (xy 343.091452 -227.214015) (xy 343.135526 -227.188569) (xy 343.183112 -227.170522)
			(xy 343.232976 -227.160342) (xy 343.283828 -227.158293) (xy 343.334349 -227.164427) (xy 343.383233 -227.178587)
			(xy 343.429212 -227.200404) (xy 343.471096 -227.229314) (xy 343.5078 -227.264569) (xy 343.538373 -227.305255)
			(xy 343.562024 -227.350318) (xy 343.57814 -227.398592) (xy 343.586304 -227.448826) (xy 343.586816 -227.474272)
			(xy 343.586304 -227.499718) (xy 343.57814 -227.549952) (xy 343.562024 -227.598226) (xy 343.538373 -227.643289)
			(xy 343.5078 -227.683975) (xy 343.471096 -227.71923) (xy 343.429212 -227.74814) (xy 343.383233 -227.769957)
			(xy 343.334349 -227.784117) (xy 343.283828 -227.790251) (xy 343.232976 -227.788202) (xy 343.183112 -227.778022)
			(xy 343.135526 -227.759975) (xy 343.091452 -227.734529) (xy 343.05203 -227.702342) (xy 343.018282 -227.664248)
			(xy 342.991081 -227.621234) (xy 342.971133 -227.574414) (xy 342.958954 -227.525) (xy 342.954859 -227.474272)
			(xy 342.646762 -227.474272) (xy 342.64625 -227.499718) (xy 342.638086 -227.549952) (xy 342.62197 -227.598226)
			(xy 342.598319 -227.643289) (xy 342.567746 -227.683975) (xy 342.531042 -227.71923) (xy 342.489158 -227.74814)
			(xy 342.443179 -227.769957) (xy 342.394295 -227.784117) (xy 342.343774 -227.790251) (xy 342.292922 -227.788202)
			(xy 342.243058 -227.778022) (xy 342.195472 -227.759975) (xy 342.151398 -227.734529) (xy 342.111976 -227.702342)
			(xy 342.078228 -227.664248) (xy 342.051027 -227.621234) (xy 342.031079 -227.574414) (xy 342.0189 -227.525)
			(xy 342.014805 -227.474272) (xy 340.766908 -227.474272) (xy 340.766396 -227.499718) (xy 340.758232 -227.549952)
			(xy 340.742116 -227.598226) (xy 340.718465 -227.643289) (xy 340.687892 -227.683975) (xy 340.651188 -227.71923)
			(xy 340.609304 -227.74814) (xy 340.563325 -227.769957) (xy 340.514441 -227.784117) (xy 340.46392 -227.790251)
			(xy 340.413068 -227.788202) (xy 340.363204 -227.778022) (xy 340.315618 -227.759975) (xy 340.271544 -227.734529)
			(xy 340.232122 -227.702342) (xy 340.198374 -227.664248) (xy 340.171173 -227.621234) (xy 340.151225 -227.574414)
			(xy 340.139046 -227.525) (xy 340.134951 -227.474272) (xy 339.81644 -227.474272) (xy 339.815945 -227.498879)
			(xy 339.80805 -227.547456) (xy 339.792466 -227.594137) (xy 339.769595 -227.637714) (xy 339.74003 -227.677058)
			(xy 339.704537 -227.71115) (xy 339.664034 -227.739106) (xy 339.619572 -227.760204) (xy 339.572301 -227.773896)
			(xy 339.523446 -227.779828) (xy 339.474271 -227.777847) (xy 339.426052 -227.768003) (xy 339.380036 -227.750551)
			(xy 339.337415 -227.725944) (xy 339.299294 -227.694819) (xy 339.266659 -227.657982) (xy 339.240356 -227.616386)
			(xy 339.221065 -227.57111) (xy 339.209288 -227.523326) (xy 339.205328 -227.474272) (xy 338.8868 -227.474272)
			(xy 338.886288 -227.499718) (xy 338.878124 -227.549952) (xy 338.862008 -227.598226) (xy 338.838357 -227.643289)
			(xy 338.807784 -227.683975) (xy 338.77108 -227.71923) (xy 338.729196 -227.74814) (xy 338.683217 -227.769957)
			(xy 338.634333 -227.784117) (xy 338.583812 -227.790251) (xy 338.53296 -227.788202) (xy 338.483096 -227.778022)
			(xy 338.43551 -227.759975) (xy 338.391436 -227.734529) (xy 338.352014 -227.702342) (xy 338.318266 -227.664248)
			(xy 338.291065 -227.621234) (xy 338.271117 -227.574414) (xy 338.258938 -227.525) (xy 338.254843 -227.474272)
			(xy 337.936332 -227.474272) (xy 337.935837 -227.498879) (xy 337.927942 -227.547456) (xy 337.912358 -227.594137)
			(xy 337.889487 -227.637714) (xy 337.859922 -227.677058) (xy 337.824429 -227.71115) (xy 337.783926 -227.739106)
			(xy 337.739464 -227.760204) (xy 337.692193 -227.773896) (xy 337.643338 -227.779828) (xy 337.594163 -227.777847)
			(xy 337.545944 -227.768003) (xy 337.499928 -227.750551) (xy 337.457307 -227.725944) (xy 337.419186 -227.694819)
			(xy 337.386551 -227.657982) (xy 337.360248 -227.616386) (xy 337.340957 -227.57111) (xy 337.32918 -227.523326)
			(xy 337.32522 -227.474272) (xy 337.006946 -227.474272) (xy 337.006434 -227.499718) (xy 336.99827 -227.549952)
			(xy 336.982154 -227.598226) (xy 336.958503 -227.643289) (xy 336.92793 -227.683975) (xy 336.891226 -227.71923)
			(xy 336.849342 -227.74814) (xy 336.803363 -227.769957) (xy 336.754479 -227.784117) (xy 336.703958 -227.790251)
			(xy 336.653106 -227.788202) (xy 336.603242 -227.778022) (xy 336.555656 -227.759975) (xy 336.511582 -227.734529)
			(xy 336.47216 -227.702342) (xy 336.438412 -227.664248) (xy 336.411211 -227.621234) (xy 336.391263 -227.574414)
			(xy 336.379084 -227.525) (xy 336.374989 -227.474272) (xy 336.066892 -227.474272) (xy 336.06638 -227.499718)
			(xy 336.058216 -227.549952) (xy 336.0421 -227.598226) (xy 336.018449 -227.643289) (xy 335.987876 -227.683975)
			(xy 335.951172 -227.71923) (xy 335.909288 -227.74814) (xy 335.863309 -227.769957) (xy 335.814425 -227.784117)
			(xy 335.763904 -227.790251) (xy 335.713052 -227.788202) (xy 335.663188 -227.778022) (xy 335.615602 -227.759975)
			(xy 335.571528 -227.734529) (xy 335.532106 -227.702342) (xy 335.498358 -227.664248) (xy 335.471157 -227.621234)
			(xy 335.451209 -227.574414) (xy 335.43903 -227.525) (xy 335.434935 -227.474272) (xy 334.186784 -227.474272)
			(xy 334.186272 -227.499718) (xy 334.178108 -227.549952) (xy 334.161992 -227.598226) (xy 334.138341 -227.643289)
			(xy 334.107768 -227.683975) (xy 334.071064 -227.71923) (xy 334.02918 -227.74814) (xy 333.983201 -227.769957)
			(xy 333.934317 -227.784117) (xy 333.883796 -227.790251) (xy 333.832944 -227.788202) (xy 333.78308 -227.778022)
			(xy 333.735494 -227.759975) (xy 333.69142 -227.734529) (xy 333.651998 -227.702342) (xy 333.61825 -227.664248)
			(xy 333.591049 -227.621234) (xy 333.571101 -227.574414) (xy 333.558922 -227.525) (xy 333.554827 -227.474272)
			(xy 333.236316 -227.474272) (xy 333.235821 -227.498879) (xy 333.227926 -227.547456) (xy 333.212342 -227.594137)
			(xy 333.189471 -227.637714) (xy 333.159906 -227.677058) (xy 333.124413 -227.71115) (xy 333.08391 -227.739106)
			(xy 333.039448 -227.760204) (xy 332.992177 -227.773896) (xy 332.943322 -227.779828) (xy 332.894147 -227.777847)
			(xy 332.845928 -227.768003) (xy 332.799912 -227.750551) (xy 332.757291 -227.725944) (xy 332.71917 -227.694819)
			(xy 332.686535 -227.657982) (xy 332.660232 -227.616386) (xy 332.640941 -227.57111) (xy 332.629164 -227.523326)
			(xy 332.625204 -227.474272) (xy 332.30693 -227.474272) (xy 332.306418 -227.499718) (xy 332.298254 -227.549952)
			(xy 332.282138 -227.598226) (xy 332.258487 -227.643289) (xy 332.227914 -227.683975) (xy 332.19121 -227.71923)
			(xy 332.149326 -227.74814) (xy 332.103347 -227.769957) (xy 332.054463 -227.784117) (xy 332.003942 -227.790251)
			(xy 331.95309 -227.788202) (xy 331.903226 -227.778022) (xy 331.85564 -227.759975) (xy 331.811566 -227.734529)
			(xy 331.772144 -227.702342) (xy 331.738396 -227.664248) (xy 331.711195 -227.621234) (xy 331.691247 -227.574414)
			(xy 331.679068 -227.525) (xy 331.674973 -227.474272) (xy 331.356462 -227.474272) (xy 331.355967 -227.498879)
			(xy 331.348072 -227.547456) (xy 331.332488 -227.594137) (xy 331.309617 -227.637714) (xy 331.280052 -227.677058)
			(xy 331.244559 -227.71115) (xy 331.204056 -227.739106) (xy 331.159594 -227.760204) (xy 331.112323 -227.773896)
			(xy 331.063468 -227.779828) (xy 331.014293 -227.777847) (xy 330.966074 -227.768003) (xy 330.920058 -227.750551)
			(xy 330.877437 -227.725944) (xy 330.839316 -227.694819) (xy 330.806681 -227.657982) (xy 330.780378 -227.616386)
			(xy 330.761087 -227.57111) (xy 330.74931 -227.523326) (xy 330.74535 -227.474272) (xy 330.426822 -227.474272)
			(xy 330.42631 -227.499718) (xy 330.418146 -227.549952) (xy 330.40203 -227.598226) (xy 330.378379 -227.643289)
			(xy 330.347806 -227.683975) (xy 330.311102 -227.71923) (xy 330.269218 -227.74814) (xy 330.223239 -227.769957)
			(xy 330.174355 -227.784117) (xy 330.123834 -227.790251) (xy 330.072982 -227.788202) (xy 330.023118 -227.778022)
			(xy 329.975532 -227.759975) (xy 329.931458 -227.734529) (xy 329.892036 -227.702342) (xy 329.858288 -227.664248)
			(xy 329.831087 -227.621234) (xy 329.811139 -227.574414) (xy 329.79896 -227.525) (xy 329.794865 -227.474272)
			(xy 329.486768 -227.474272) (xy 329.486256 -227.499718) (xy 329.478092 -227.549952) (xy 329.461976 -227.598226)
			(xy 329.438325 -227.643289) (xy 329.407752 -227.683975) (xy 329.371048 -227.71923) (xy 329.329164 -227.74814)
			(xy 329.283185 -227.769957) (xy 329.234301 -227.784117) (xy 329.18378 -227.790251) (xy 329.132928 -227.788202)
			(xy 329.083064 -227.778022) (xy 329.035478 -227.759975) (xy 328.991404 -227.734529) (xy 328.951982 -227.702342)
			(xy 328.918234 -227.664248) (xy 328.891033 -227.621234) (xy 328.871085 -227.574414) (xy 328.858906 -227.525)
			(xy 328.854811 -227.474272) (xy 326.656446 -227.474272) (xy 326.655951 -227.498879) (xy 326.648056 -227.547456)
			(xy 326.632472 -227.594137) (xy 326.609601 -227.637714) (xy 326.580036 -227.677058) (xy 326.544543 -227.71115)
			(xy 326.50404 -227.739106) (xy 326.459578 -227.760204) (xy 326.412307 -227.773896) (xy 326.363452 -227.779828)
			(xy 326.314277 -227.777847) (xy 326.266058 -227.768003) (xy 326.220042 -227.750551) (xy 326.177421 -227.725944)
			(xy 326.1393 -227.694819) (xy 326.106665 -227.657982) (xy 326.080362 -227.616386) (xy 326.061071 -227.57111)
			(xy 326.049294 -227.523326) (xy 326.045334 -227.474272) (xy 310.693308 -227.474272) (xy 310.474106 -227.693474)
			(xy 310.46674 -227.700586) (xy 310.45912 -227.719382) (xy 310.45912 -228.284278) (xy 324.63538 -228.284278)
			(xy 324.63934 -228.235224) (xy 324.651117 -228.18744) (xy 324.670408 -228.142164) (xy 324.696711 -228.100568)
			(xy 324.729346 -228.063731) (xy 324.767467 -228.032606) (xy 324.810088 -228.007999) (xy 324.856104 -227.990547)
			(xy 324.904323 -227.980703) (xy 324.953498 -227.978722) (xy 325.002353 -227.984654) (xy 325.049624 -227.998346)
			(xy 325.094086 -228.019444) (xy 325.134589 -228.0474) (xy 325.170082 -228.081492) (xy 325.199647 -228.120836)
			(xy 325.222518 -228.164413) (xy 325.238102 -228.211094) (xy 325.245997 -228.259671) (xy 325.246492 -228.284278)
			(xy 327.455288 -228.284278) (xy 327.459248 -228.235224) (xy 327.471025 -228.18744) (xy 327.490316 -228.142164)
			(xy 327.516619 -228.100568) (xy 327.549254 -228.063731) (xy 327.587375 -228.032606) (xy 327.629996 -228.007999)
			(xy 327.676012 -227.990547) (xy 327.724231 -227.980703) (xy 327.773406 -227.978722) (xy 327.822261 -227.984654)
			(xy 327.869532 -227.998346) (xy 327.913994 -228.019444) (xy 327.954497 -228.0474) (xy 327.98999 -228.081492)
			(xy 328.019555 -228.120836) (xy 328.042426 -228.164413) (xy 328.05801 -228.211094) (xy 328.065905 -228.259671)
			(xy 328.0664 -228.284278) (xy 328.384911 -228.284278) (xy 328.389006 -228.23355) (xy 328.401185 -228.184136)
			(xy 328.421133 -228.137316) (xy 328.448334 -228.094302) (xy 328.482082 -228.056208) (xy 328.521504 -228.024021)
			(xy 328.565578 -227.998575) (xy 328.613164 -227.980528) (xy 328.663028 -227.970348) (xy 328.71388 -227.968299)
			(xy 328.764401 -227.974433) (xy 328.813285 -227.988593) (xy 328.859264 -228.01041) (xy 328.901148 -228.03932)
			(xy 328.937852 -228.074575) (xy 328.968425 -228.115261) (xy 328.992076 -228.160324) (xy 329.008192 -228.208598)
			(xy 329.016356 -228.258832) (xy 329.016868 -228.284278) (xy 329.335396 -228.284278) (xy 329.339356 -228.235224)
			(xy 329.351133 -228.18744) (xy 329.370424 -228.142164) (xy 329.396727 -228.100568) (xy 329.429362 -228.063731)
			(xy 329.467483 -228.032606) (xy 329.510104 -228.007999) (xy 329.55612 -227.990547) (xy 329.604339 -227.980703)
			(xy 329.653514 -227.978722) (xy 329.702369 -227.984654) (xy 329.74964 -227.998346) (xy 329.794102 -228.019444)
			(xy 329.834605 -228.0474) (xy 329.870098 -228.081492) (xy 329.899663 -228.120836) (xy 329.922534 -228.164413)
			(xy 329.938118 -228.211094) (xy 329.946013 -228.259671) (xy 329.946508 -228.284278) (xy 330.264765 -228.284278)
			(xy 330.26886 -228.23355) (xy 330.281039 -228.184136) (xy 330.300987 -228.137316) (xy 330.328188 -228.094302)
			(xy 330.361936 -228.056208) (xy 330.401358 -228.024021) (xy 330.445432 -227.998575) (xy 330.493018 -227.980528)
			(xy 330.542882 -227.970348) (xy 330.593734 -227.968299) (xy 330.644255 -227.974433) (xy 330.693139 -227.988593)
			(xy 330.739118 -228.01041) (xy 330.781002 -228.03932) (xy 330.817706 -228.074575) (xy 330.848279 -228.115261)
			(xy 330.87193 -228.160324) (xy 330.888046 -228.208598) (xy 330.89621 -228.258832) (xy 330.896722 -228.284278)
			(xy 331.21525 -228.284278) (xy 331.21921 -228.235224) (xy 331.230987 -228.18744) (xy 331.250278 -228.142164)
			(xy 331.276581 -228.100568) (xy 331.309216 -228.063731) (xy 331.347337 -228.032606) (xy 331.389958 -228.007999)
			(xy 331.435974 -227.990547) (xy 331.484193 -227.980703) (xy 331.533368 -227.978722) (xy 331.582223 -227.984654)
			(xy 331.629494 -227.998346) (xy 331.673956 -228.019444) (xy 331.714459 -228.0474) (xy 331.749952 -228.081492)
			(xy 331.779517 -228.120836) (xy 331.802388 -228.164413) (xy 331.817972 -228.211094) (xy 331.825867 -228.259671)
			(xy 331.826362 -228.284278) (xy 332.144873 -228.284278) (xy 332.148968 -228.23355) (xy 332.161147 -228.184136)
			(xy 332.181095 -228.137316) (xy 332.208296 -228.094302) (xy 332.242044 -228.056208) (xy 332.281466 -228.024021)
			(xy 332.32554 -227.998575) (xy 332.373126 -227.980528) (xy 332.42299 -227.970348) (xy 332.473842 -227.968299)
			(xy 332.524363 -227.974433) (xy 332.573247 -227.988593) (xy 332.619226 -228.01041) (xy 332.66111 -228.03932)
			(xy 332.697814 -228.074575) (xy 332.728387 -228.115261) (xy 332.752038 -228.160324) (xy 332.768154 -228.208598)
			(xy 332.776318 -228.258832) (xy 332.77683 -228.284278) (xy 333.084927 -228.284278) (xy 333.089022 -228.23355)
			(xy 333.101201 -228.184136) (xy 333.121149 -228.137316) (xy 333.14835 -228.094302) (xy 333.182098 -228.056208)
			(xy 333.22152 -228.024021) (xy 333.265594 -227.998575) (xy 333.31318 -227.980528) (xy 333.363044 -227.970348)
			(xy 333.413896 -227.968299) (xy 333.464417 -227.974433) (xy 333.513301 -227.988593) (xy 333.55928 -228.01041)
			(xy 333.601164 -228.03932) (xy 333.637868 -228.074575) (xy 333.668441 -228.115261) (xy 333.692092 -228.160324)
			(xy 333.708208 -228.208598) (xy 333.716372 -228.258832) (xy 333.716884 -228.284278) (xy 334.035412 -228.284278)
			(xy 334.039372 -228.235224) (xy 334.051149 -228.18744) (xy 334.07044 -228.142164) (xy 334.096743 -228.100568)
			(xy 334.129378 -228.063731) (xy 334.167499 -228.032606) (xy 334.21012 -228.007999) (xy 334.256136 -227.990547)
			(xy 334.304355 -227.980703) (xy 334.35353 -227.978722) (xy 334.402385 -227.984654) (xy 334.449656 -227.998346)
			(xy 334.494118 -228.019444) (xy 334.534621 -228.0474) (xy 334.570114 -228.081492) (xy 334.599679 -228.120836)
			(xy 334.62255 -228.164413) (xy 334.638134 -228.211094) (xy 334.646029 -228.259671) (xy 334.646524 -228.284278)
			(xy 334.964781 -228.284278) (xy 334.968876 -228.23355) (xy 334.981055 -228.184136) (xy 335.001003 -228.137316)
			(xy 335.028204 -228.094302) (xy 335.061952 -228.056208) (xy 335.101374 -228.024021) (xy 335.145448 -227.998575)
			(xy 335.193034 -227.980528) (xy 335.242898 -227.970348) (xy 335.29375 -227.968299) (xy 335.344271 -227.974433)
			(xy 335.393155 -227.988593) (xy 335.439134 -228.01041) (xy 335.481018 -228.03932) (xy 335.517722 -228.074575)
			(xy 335.548295 -228.115261) (xy 335.571946 -228.160324) (xy 335.588062 -228.208598) (xy 335.596226 -228.258832)
			(xy 335.596738 -228.284278) (xy 335.915266 -228.284278) (xy 335.919226 -228.235224) (xy 335.931003 -228.18744)
			(xy 335.950294 -228.142164) (xy 335.976597 -228.100568) (xy 336.009232 -228.063731) (xy 336.047353 -228.032606)
			(xy 336.089974 -228.007999) (xy 336.13599 -227.990547) (xy 336.184209 -227.980703) (xy 336.233384 -227.978722)
			(xy 336.282239 -227.984654) (xy 336.32951 -227.998346) (xy 336.373972 -228.019444) (xy 336.414475 -228.0474)
			(xy 336.449968 -228.081492) (xy 336.479533 -228.120836) (xy 336.502404 -228.164413) (xy 336.517988 -228.211094)
			(xy 336.525883 -228.259671) (xy 336.526378 -228.284278) (xy 336.844889 -228.284278) (xy 336.848984 -228.23355)
			(xy 336.861163 -228.184136) (xy 336.881111 -228.137316) (xy 336.908312 -228.094302) (xy 336.94206 -228.056208)
			(xy 336.981482 -228.024021) (xy 337.025556 -227.998575) (xy 337.073142 -227.980528) (xy 337.123006 -227.970348)
			(xy 337.173858 -227.968299) (xy 337.224379 -227.974433) (xy 337.273263 -227.988593) (xy 337.319242 -228.01041)
			(xy 337.361126 -228.03932) (xy 337.39783 -228.074575) (xy 337.428403 -228.115261) (xy 337.452054 -228.160324)
			(xy 337.46817 -228.208598) (xy 337.476334 -228.258832) (xy 337.476846 -228.284278) (xy 337.795374 -228.284278)
			(xy 337.799334 -228.235224) (xy 337.811111 -228.18744) (xy 337.830402 -228.142164) (xy 337.856705 -228.100568)
			(xy 337.88934 -228.063731) (xy 337.927461 -228.032606) (xy 337.970082 -228.007999) (xy 338.016098 -227.990547)
			(xy 338.064317 -227.980703) (xy 338.113492 -227.978722) (xy 338.162347 -227.984654) (xy 338.209618 -227.998346)
			(xy 338.25408 -228.019444) (xy 338.294583 -228.0474) (xy 338.330076 -228.081492) (xy 338.359641 -228.120836)
			(xy 338.382512 -228.164413) (xy 338.398096 -228.211094) (xy 338.405991 -228.259671) (xy 338.406486 -228.284278)
			(xy 338.724743 -228.284278) (xy 338.728838 -228.23355) (xy 338.741017 -228.184136) (xy 338.760965 -228.137316)
			(xy 338.788166 -228.094302) (xy 338.821914 -228.056208) (xy 338.861336 -228.024021) (xy 338.90541 -227.998575)
			(xy 338.952996 -227.980528) (xy 339.00286 -227.970348) (xy 339.053712 -227.968299) (xy 339.104233 -227.974433)
			(xy 339.153117 -227.988593) (xy 339.199096 -228.01041) (xy 339.24098 -228.03932) (xy 339.277684 -228.074575)
			(xy 339.308257 -228.115261) (xy 339.331908 -228.160324) (xy 339.348024 -228.208598) (xy 339.356188 -228.258832)
			(xy 339.3567 -228.284278) (xy 339.664797 -228.284278) (xy 339.668892 -228.23355) (xy 339.681071 -228.184136)
			(xy 339.701019 -228.137316) (xy 339.72822 -228.094302) (xy 339.761968 -228.056208) (xy 339.80139 -228.024021)
			(xy 339.845464 -227.998575) (xy 339.89305 -227.980528) (xy 339.942914 -227.970348) (xy 339.993766 -227.968299)
			(xy 340.044287 -227.974433) (xy 340.093171 -227.988593) (xy 340.13915 -228.01041) (xy 340.181034 -228.03932)
			(xy 340.217738 -228.074575) (xy 340.248311 -228.115261) (xy 340.271962 -228.160324) (xy 340.288078 -228.208598)
			(xy 340.296242 -228.258832) (xy 340.296754 -228.284278) (xy 340.615282 -228.284278) (xy 340.619242 -228.235224)
			(xy 340.631019 -228.18744) (xy 340.65031 -228.142164) (xy 340.676613 -228.100568) (xy 340.709248 -228.063731)
			(xy 340.747369 -228.032606) (xy 340.78999 -228.007999) (xy 340.836006 -227.990547) (xy 340.884225 -227.980703)
			(xy 340.9334 -227.978722) (xy 340.982255 -227.984654) (xy 341.029526 -227.998346) (xy 341.073988 -228.019444)
			(xy 341.114491 -228.0474) (xy 341.149984 -228.081492) (xy 341.179549 -228.120836) (xy 341.20242 -228.164413)
			(xy 341.218004 -228.211094) (xy 341.225899 -228.259671) (xy 341.226394 -228.284278) (xy 341.544905 -228.284278)
			(xy 341.549 -228.23355) (xy 341.561179 -228.184136) (xy 341.581127 -228.137316) (xy 341.608328 -228.094302)
			(xy 341.642076 -228.056208) (xy 341.681498 -228.024021) (xy 341.725572 -227.998575) (xy 341.773158 -227.980528)
			(xy 341.823022 -227.970348) (xy 341.873874 -227.968299) (xy 341.924395 -227.974433) (xy 341.973279 -227.988593)
			(xy 342.019258 -228.01041) (xy 342.061142 -228.03932) (xy 342.097846 -228.074575) (xy 342.128419 -228.115261)
			(xy 342.15207 -228.160324) (xy 342.168186 -228.208598) (xy 342.17635 -228.258832) (xy 342.176862 -228.284278)
			(xy 342.49539 -228.284278) (xy 342.49935 -228.235224) (xy 342.511127 -228.18744) (xy 342.530418 -228.142164)
			(xy 342.556721 -228.100568) (xy 342.589356 -228.063731) (xy 342.627477 -228.032606) (xy 342.670098 -228.007999)
			(xy 342.716114 -227.990547) (xy 342.764333 -227.980703) (xy 342.813508 -227.978722) (xy 342.862363 -227.984654)
			(xy 342.909634 -227.998346) (xy 342.954096 -228.019444) (xy 342.994599 -228.0474) (xy 343.030092 -228.081492)
			(xy 343.059657 -228.120836) (xy 343.082528 -228.164413) (xy 343.098112 -228.211094) (xy 343.106007 -228.259671)
			(xy 343.106502 -228.284278) (xy 343.106007 -228.308885) (xy 343.098112 -228.357462) (xy 343.082528 -228.404143)
			(xy 343.059657 -228.44772) (xy 343.030092 -228.487064) (xy 342.994599 -228.521156) (xy 342.954096 -228.549112)
			(xy 342.909634 -228.57021) (xy 342.862363 -228.583902) (xy 342.813508 -228.589834) (xy 342.764333 -228.587853)
			(xy 342.716114 -228.578009) (xy 342.670098 -228.560557) (xy 342.627477 -228.53595) (xy 342.589356 -228.504825)
			(xy 342.556721 -228.467988) (xy 342.530418 -228.426392) (xy 342.511127 -228.381116) (xy 342.49935 -228.333332)
			(xy 342.49539 -228.284278) (xy 342.176862 -228.284278) (xy 342.17635 -228.309724) (xy 342.168186 -228.359958)
			(xy 342.15207 -228.408232) (xy 342.128419 -228.453295) (xy 342.097846 -228.493981) (xy 342.061142 -228.529236)
			(xy 342.019258 -228.558146) (xy 341.973279 -228.579963) (xy 341.924395 -228.594123) (xy 341.873874 -228.600257)
			(xy 341.823022 -228.598208) (xy 341.773158 -228.588028) (xy 341.725572 -228.569981) (xy 341.681498 -228.544535)
			(xy 341.642076 -228.512348) (xy 341.608328 -228.474254) (xy 341.581127 -228.43124) (xy 341.561179 -228.38442)
			(xy 341.549 -228.335006) (xy 341.544905 -228.284278) (xy 341.226394 -228.284278) (xy 341.225899 -228.308885)
			(xy 341.218004 -228.357462) (xy 341.20242 -228.404143) (xy 341.179549 -228.44772) (xy 341.149984 -228.487064)
			(xy 341.114491 -228.521156) (xy 341.073988 -228.549112) (xy 341.029526 -228.57021) (xy 340.982255 -228.583902)
			(xy 340.9334 -228.589834) (xy 340.884225 -228.587853) (xy 340.836006 -228.578009) (xy 340.78999 -228.560557)
			(xy 340.747369 -228.53595) (xy 340.709248 -228.504825) (xy 340.676613 -228.467988) (xy 340.65031 -228.426392)
			(xy 340.631019 -228.381116) (xy 340.619242 -228.333332) (xy 340.615282 -228.284278) (xy 340.296754 -228.284278)
			(xy 340.296242 -228.309724) (xy 340.288078 -228.359958) (xy 340.271962 -228.408232) (xy 340.248311 -228.453295)
			(xy 340.217738 -228.493981) (xy 340.181034 -228.529236) (xy 340.13915 -228.558146) (xy 340.093171 -228.579963)
			(xy 340.044287 -228.594123) (xy 339.993766 -228.600257) (xy 339.942914 -228.598208) (xy 339.89305 -228.588028)
			(xy 339.845464 -228.569981) (xy 339.80139 -228.544535) (xy 339.761968 -228.512348) (xy 339.72822 -228.474254)
			(xy 339.701019 -228.43124) (xy 339.681071 -228.38442) (xy 339.668892 -228.335006) (xy 339.664797 -228.284278)
			(xy 339.3567 -228.284278) (xy 339.356188 -228.309724) (xy 339.348024 -228.359958) (xy 339.331908 -228.408232)
			(xy 339.308257 -228.453295) (xy 339.277684 -228.493981) (xy 339.24098 -228.529236) (xy 339.199096 -228.558146)
			(xy 339.153117 -228.579963) (xy 339.104233 -228.594123) (xy 339.053712 -228.600257) (xy 339.00286 -228.598208)
			(xy 338.952996 -228.588028) (xy 338.90541 -228.569981) (xy 338.861336 -228.544535) (xy 338.821914 -228.512348)
			(xy 338.788166 -228.474254) (xy 338.760965 -228.43124) (xy 338.741017 -228.38442) (xy 338.728838 -228.335006)
			(xy 338.724743 -228.284278) (xy 338.406486 -228.284278) (xy 338.405991 -228.308885) (xy 338.398096 -228.357462)
			(xy 338.382512 -228.404143) (xy 338.359641 -228.44772) (xy 338.330076 -228.487064) (xy 338.294583 -228.521156)
			(xy 338.25408 -228.549112) (xy 338.209618 -228.57021) (xy 338.162347 -228.583902) (xy 338.113492 -228.589834)
			(xy 338.064317 -228.587853) (xy 338.016098 -228.578009) (xy 337.970082 -228.560557) (xy 337.927461 -228.53595)
			(xy 337.88934 -228.504825) (xy 337.856705 -228.467988) (xy 337.830402 -228.426392) (xy 337.811111 -228.381116)
			(xy 337.799334 -228.333332) (xy 337.795374 -228.284278) (xy 337.476846 -228.284278) (xy 337.476334 -228.309724)
			(xy 337.46817 -228.359958) (xy 337.452054 -228.408232) (xy 337.428403 -228.453295) (xy 337.39783 -228.493981)
			(xy 337.361126 -228.529236) (xy 337.319242 -228.558146) (xy 337.273263 -228.579963) (xy 337.224379 -228.594123)
			(xy 337.173858 -228.600257) (xy 337.123006 -228.598208) (xy 337.073142 -228.588028) (xy 337.025556 -228.569981)
			(xy 336.981482 -228.544535) (xy 336.94206 -228.512348) (xy 336.908312 -228.474254) (xy 336.881111 -228.43124)
			(xy 336.861163 -228.38442) (xy 336.848984 -228.335006) (xy 336.844889 -228.284278) (xy 336.526378 -228.284278)
			(xy 336.525883 -228.308885) (xy 336.517988 -228.357462) (xy 336.502404 -228.404143) (xy 336.479533 -228.44772)
			(xy 336.449968 -228.487064) (xy 336.414475 -228.521156) (xy 336.373972 -228.549112) (xy 336.32951 -228.57021)
			(xy 336.282239 -228.583902) (xy 336.233384 -228.589834) (xy 336.184209 -228.587853) (xy 336.13599 -228.578009)
			(xy 336.089974 -228.560557) (xy 336.047353 -228.53595) (xy 336.009232 -228.504825) (xy 335.976597 -228.467988)
			(xy 335.950294 -228.426392) (xy 335.931003 -228.381116) (xy 335.919226 -228.333332) (xy 335.915266 -228.284278)
			(xy 335.596738 -228.284278) (xy 335.596226 -228.309724) (xy 335.588062 -228.359958) (xy 335.571946 -228.408232)
			(xy 335.548295 -228.453295) (xy 335.517722 -228.493981) (xy 335.481018 -228.529236) (xy 335.439134 -228.558146)
			(xy 335.393155 -228.579963) (xy 335.344271 -228.594123) (xy 335.29375 -228.600257) (xy 335.242898 -228.598208)
			(xy 335.193034 -228.588028) (xy 335.145448 -228.569981) (xy 335.101374 -228.544535) (xy 335.061952 -228.512348)
			(xy 335.028204 -228.474254) (xy 335.001003 -228.43124) (xy 334.981055 -228.38442) (xy 334.968876 -228.335006)
			(xy 334.964781 -228.284278) (xy 334.646524 -228.284278) (xy 334.646029 -228.308885) (xy 334.638134 -228.357462)
			(xy 334.62255 -228.404143) (xy 334.599679 -228.44772) (xy 334.570114 -228.487064) (xy 334.534621 -228.521156)
			(xy 334.494118 -228.549112) (xy 334.449656 -228.57021) (xy 334.402385 -228.583902) (xy 334.35353 -228.589834)
			(xy 334.304355 -228.587853) (xy 334.256136 -228.578009) (xy 334.21012 -228.560557) (xy 334.167499 -228.53595)
			(xy 334.129378 -228.504825) (xy 334.096743 -228.467988) (xy 334.07044 -228.426392) (xy 334.051149 -228.381116)
			(xy 334.039372 -228.333332) (xy 334.035412 -228.284278) (xy 333.716884 -228.284278) (xy 333.716372 -228.309724)
			(xy 333.708208 -228.359958) (xy 333.692092 -228.408232) (xy 333.668441 -228.453295) (xy 333.637868 -228.493981)
			(xy 333.601164 -228.529236) (xy 333.55928 -228.558146) (xy 333.513301 -228.579963) (xy 333.464417 -228.594123)
			(xy 333.413896 -228.600257) (xy 333.363044 -228.598208) (xy 333.31318 -228.588028) (xy 333.265594 -228.569981)
			(xy 333.22152 -228.544535) (xy 333.182098 -228.512348) (xy 333.14835 -228.474254) (xy 333.121149 -228.43124)
			(xy 333.101201 -228.38442) (xy 333.089022 -228.335006) (xy 333.084927 -228.284278) (xy 332.77683 -228.284278)
			(xy 332.776318 -228.309724) (xy 332.768154 -228.359958) (xy 332.752038 -228.408232) (xy 332.728387 -228.453295)
			(xy 332.697814 -228.493981) (xy 332.66111 -228.529236) (xy 332.619226 -228.558146) (xy 332.573247 -228.579963)
			(xy 332.524363 -228.594123) (xy 332.473842 -228.600257) (xy 332.42299 -228.598208) (xy 332.373126 -228.588028)
			(xy 332.32554 -228.569981) (xy 332.281466 -228.544535) (xy 332.242044 -228.512348) (xy 332.208296 -228.474254)
			(xy 332.181095 -228.43124) (xy 332.161147 -228.38442) (xy 332.148968 -228.335006) (xy 332.144873 -228.284278)
			(xy 331.826362 -228.284278) (xy 331.825867 -228.308885) (xy 331.817972 -228.357462) (xy 331.802388 -228.404143)
			(xy 331.779517 -228.44772) (xy 331.749952 -228.487064) (xy 331.714459 -228.521156) (xy 331.673956 -228.549112)
			(xy 331.629494 -228.57021) (xy 331.582223 -228.583902) (xy 331.533368 -228.589834) (xy 331.484193 -228.587853)
			(xy 331.435974 -228.578009) (xy 331.389958 -228.560557) (xy 331.347337 -228.53595) (xy 331.309216 -228.504825)
			(xy 331.276581 -228.467988) (xy 331.250278 -228.426392) (xy 331.230987 -228.381116) (xy 331.21921 -228.333332)
			(xy 331.21525 -228.284278) (xy 330.896722 -228.284278) (xy 330.89621 -228.309724) (xy 330.888046 -228.359958)
			(xy 330.87193 -228.408232) (xy 330.848279 -228.453295) (xy 330.817706 -228.493981) (xy 330.781002 -228.529236)
			(xy 330.739118 -228.558146) (xy 330.693139 -228.579963) (xy 330.644255 -228.594123) (xy 330.593734 -228.600257)
			(xy 330.542882 -228.598208) (xy 330.493018 -228.588028) (xy 330.445432 -228.569981) (xy 330.401358 -228.544535)
			(xy 330.361936 -228.512348) (xy 330.328188 -228.474254) (xy 330.300987 -228.43124) (xy 330.281039 -228.38442)
			(xy 330.26886 -228.335006) (xy 330.264765 -228.284278) (xy 329.946508 -228.284278) (xy 329.946013 -228.308885)
			(xy 329.938118 -228.357462) (xy 329.922534 -228.404143) (xy 329.899663 -228.44772) (xy 329.870098 -228.487064)
			(xy 329.834605 -228.521156) (xy 329.794102 -228.549112) (xy 329.74964 -228.57021) (xy 329.702369 -228.583902)
			(xy 329.653514 -228.589834) (xy 329.604339 -228.587853) (xy 329.55612 -228.578009) (xy 329.510104 -228.560557)
			(xy 329.467483 -228.53595) (xy 329.429362 -228.504825) (xy 329.396727 -228.467988) (xy 329.370424 -228.426392)
			(xy 329.351133 -228.381116) (xy 329.339356 -228.333332) (xy 329.335396 -228.284278) (xy 329.016868 -228.284278)
			(xy 329.016356 -228.309724) (xy 329.008192 -228.359958) (xy 328.992076 -228.408232) (xy 328.968425 -228.453295)
			(xy 328.937852 -228.493981) (xy 328.901148 -228.529236) (xy 328.859264 -228.558146) (xy 328.813285 -228.579963)
			(xy 328.764401 -228.594123) (xy 328.71388 -228.600257) (xy 328.663028 -228.598208) (xy 328.613164 -228.588028)
			(xy 328.565578 -228.569981) (xy 328.521504 -228.544535) (xy 328.482082 -228.512348) (xy 328.448334 -228.474254)
			(xy 328.421133 -228.43124) (xy 328.401185 -228.38442) (xy 328.389006 -228.335006) (xy 328.384911 -228.284278)
			(xy 328.0664 -228.284278) (xy 328.065905 -228.308885) (xy 328.05801 -228.357462) (xy 328.042426 -228.404143)
			(xy 328.019555 -228.44772) (xy 327.98999 -228.487064) (xy 327.954497 -228.521156) (xy 327.913994 -228.549112)
			(xy 327.869532 -228.57021) (xy 327.822261 -228.583902) (xy 327.773406 -228.589834) (xy 327.724231 -228.587853)
			(xy 327.676012 -228.578009) (xy 327.629996 -228.560557) (xy 327.587375 -228.53595) (xy 327.549254 -228.504825)
			(xy 327.516619 -228.467988) (xy 327.490316 -228.426392) (xy 327.471025 -228.381116) (xy 327.459248 -228.333332)
			(xy 327.455288 -228.284278) (xy 325.246492 -228.284278) (xy 325.245997 -228.308885) (xy 325.238102 -228.357462)
			(xy 325.222518 -228.404143) (xy 325.199647 -228.44772) (xy 325.170082 -228.487064) (xy 325.134589 -228.521156)
			(xy 325.094086 -228.549112) (xy 325.049624 -228.57021) (xy 325.002353 -228.583902) (xy 324.953498 -228.589834)
			(xy 324.904323 -228.587853) (xy 324.856104 -228.578009) (xy 324.810088 -228.560557) (xy 324.767467 -228.53595)
			(xy 324.729346 -228.504825) (xy 324.696711 -228.467988) (xy 324.670408 -228.426392) (xy 324.651117 -228.381116)
			(xy 324.63934 -228.333332) (xy 324.63538 -228.284278) (xy 310.45912 -228.284278) (xy 310.45912 -229.094284)
			(xy 326.045334 -229.094284) (xy 326.049294 -229.04523) (xy 326.061071 -228.997446) (xy 326.080362 -228.95217)
			(xy 326.106665 -228.910574) (xy 326.1393 -228.873737) (xy 326.177421 -228.842612) (xy 326.220042 -228.818005)
			(xy 326.266058 -228.800553) (xy 326.314277 -228.790709) (xy 326.363452 -228.788728) (xy 326.412307 -228.79466)
			(xy 326.459578 -228.808352) (xy 326.50404 -228.82945) (xy 326.544543 -228.857406) (xy 326.580036 -228.891498)
			(xy 326.609601 -228.930842) (xy 326.632472 -228.974419) (xy 326.648056 -229.0211) (xy 326.655951 -229.069677)
			(xy 326.656446 -229.094284) (xy 327.925442 -229.094284) (xy 327.929402 -229.04523) (xy 327.941179 -228.997446)
			(xy 327.96047 -228.95217) (xy 327.986773 -228.910574) (xy 328.019408 -228.873737) (xy 328.057529 -228.842612)
			(xy 328.10015 -228.818005) (xy 328.146166 -228.800553) (xy 328.194385 -228.790709) (xy 328.24356 -228.788728)
			(xy 328.292415 -228.79466) (xy 328.339686 -228.808352) (xy 328.384148 -228.82945) (xy 328.424651 -228.857406)
			(xy 328.460144 -228.891498) (xy 328.489709 -228.930842) (xy 328.51258 -228.974419) (xy 328.528164 -229.0211)
			(xy 328.536059 -229.069677) (xy 328.536554 -229.094284) (xy 328.854811 -229.094284) (xy 328.858906 -229.043556)
			(xy 328.871085 -228.994142) (xy 328.891033 -228.947322) (xy 328.918234 -228.904308) (xy 328.951982 -228.866214)
			(xy 328.991404 -228.834027) (xy 329.035478 -228.808581) (xy 329.083064 -228.790534) (xy 329.132928 -228.780354)
			(xy 329.18378 -228.778305) (xy 329.234301 -228.784439) (xy 329.283185 -228.798599) (xy 329.329164 -228.820416)
			(xy 329.371048 -228.849326) (xy 329.407752 -228.884581) (xy 329.438325 -228.925267) (xy 329.461976 -228.97033)
			(xy 329.478092 -229.018604) (xy 329.486256 -229.068838) (xy 329.486768 -229.094284) (xy 329.794865 -229.094284)
			(xy 329.79896 -229.043556) (xy 329.811139 -228.994142) (xy 329.831087 -228.947322) (xy 329.858288 -228.904308)
			(xy 329.892036 -228.866214) (xy 329.931458 -228.834027) (xy 329.975532 -228.808581) (xy 330.023118 -228.790534)
			(xy 330.072982 -228.780354) (xy 330.123834 -228.778305) (xy 330.174355 -228.784439) (xy 330.223239 -228.798599)
			(xy 330.269218 -228.820416) (xy 330.311102 -228.849326) (xy 330.347806 -228.884581) (xy 330.378379 -228.925267)
			(xy 330.40203 -228.97033) (xy 330.418146 -229.018604) (xy 330.42631 -229.068838) (xy 330.426822 -229.094284)
			(xy 330.74535 -229.094284) (xy 330.74931 -229.04523) (xy 330.761087 -228.997446) (xy 330.780378 -228.95217)
			(xy 330.806681 -228.910574) (xy 330.839316 -228.873737) (xy 330.877437 -228.842612) (xy 330.920058 -228.818005)
			(xy 330.966074 -228.800553) (xy 331.014293 -228.790709) (xy 331.063468 -228.788728) (xy 331.112323 -228.79466)
			(xy 331.159594 -228.808352) (xy 331.204056 -228.82945) (xy 331.244559 -228.857406) (xy 331.280052 -228.891498)
			(xy 331.309617 -228.930842) (xy 331.332488 -228.974419) (xy 331.348072 -229.0211) (xy 331.355967 -229.069677)
			(xy 331.356462 -229.094284) (xy 331.674973 -229.094284) (xy 331.679068 -229.043556) (xy 331.691247 -228.994142)
			(xy 331.711195 -228.947322) (xy 331.738396 -228.904308) (xy 331.772144 -228.866214) (xy 331.811566 -228.834027)
			(xy 331.85564 -228.808581) (xy 331.903226 -228.790534) (xy 331.95309 -228.780354) (xy 332.003942 -228.778305)
			(xy 332.054463 -228.784439) (xy 332.103347 -228.798599) (xy 332.149326 -228.820416) (xy 332.19121 -228.849326)
			(xy 332.227914 -228.884581) (xy 332.258487 -228.925267) (xy 332.282138 -228.97033) (xy 332.298254 -229.018604)
			(xy 332.306418 -229.068838) (xy 332.30693 -229.094284) (xy 332.625204 -229.094284) (xy 332.629164 -229.04523)
			(xy 332.640941 -228.997446) (xy 332.660232 -228.95217) (xy 332.686535 -228.910574) (xy 332.71917 -228.873737)
			(xy 332.757291 -228.842612) (xy 332.799912 -228.818005) (xy 332.845928 -228.800553) (xy 332.894147 -228.790709)
			(xy 332.943322 -228.788728) (xy 332.992177 -228.79466) (xy 333.039448 -228.808352) (xy 333.08391 -228.82945)
			(xy 333.124413 -228.857406) (xy 333.159906 -228.891498) (xy 333.189471 -228.930842) (xy 333.212342 -228.974419)
			(xy 333.227926 -229.0211) (xy 333.235821 -229.069677) (xy 333.236316 -229.094284) (xy 333.554827 -229.094284)
			(xy 333.558922 -229.043556) (xy 333.571101 -228.994142) (xy 333.591049 -228.947322) (xy 333.61825 -228.904308)
			(xy 333.651998 -228.866214) (xy 333.69142 -228.834027) (xy 333.735494 -228.808581) (xy 333.78308 -228.790534)
			(xy 333.832944 -228.780354) (xy 333.883796 -228.778305) (xy 333.934317 -228.784439) (xy 333.983201 -228.798599)
			(xy 334.02918 -228.820416) (xy 334.071064 -228.849326) (xy 334.107768 -228.884581) (xy 334.138341 -228.925267)
			(xy 334.161992 -228.97033) (xy 334.178108 -229.018604) (xy 334.186272 -229.068838) (xy 334.186784 -229.094284)
			(xy 334.505312 -229.094284) (xy 334.509272 -229.04523) (xy 334.521049 -228.997446) (xy 334.54034 -228.95217)
			(xy 334.566643 -228.910574) (xy 334.599278 -228.873737) (xy 334.637399 -228.842612) (xy 334.68002 -228.818005)
			(xy 334.726036 -228.800553) (xy 334.774255 -228.790709) (xy 334.82343 -228.788728) (xy 334.872285 -228.79466)
			(xy 334.919556 -228.808352) (xy 334.964018 -228.82945) (xy 335.004521 -228.857406) (xy 335.040014 -228.891498)
			(xy 335.069579 -228.930842) (xy 335.09245 -228.974419) (xy 335.108034 -229.0211) (xy 335.115929 -229.069677)
			(xy 335.116424 -229.094284) (xy 335.434935 -229.094284) (xy 335.43903 -229.043556) (xy 335.451209 -228.994142)
			(xy 335.471157 -228.947322) (xy 335.498358 -228.904308) (xy 335.532106 -228.866214) (xy 335.571528 -228.834027)
			(xy 335.615602 -228.808581) (xy 335.663188 -228.790534) (xy 335.713052 -228.780354) (xy 335.763904 -228.778305)
			(xy 335.814425 -228.784439) (xy 335.863309 -228.798599) (xy 335.909288 -228.820416) (xy 335.951172 -228.849326)
			(xy 335.987876 -228.884581) (xy 336.018449 -228.925267) (xy 336.0421 -228.97033) (xy 336.058216 -229.018604)
			(xy 336.06638 -229.068838) (xy 336.066892 -229.094284) (xy 336.374989 -229.094284) (xy 336.379084 -229.043556)
			(xy 336.391263 -228.994142) (xy 336.411211 -228.947322) (xy 336.438412 -228.904308) (xy 336.47216 -228.866214)
			(xy 336.511582 -228.834027) (xy 336.555656 -228.808581) (xy 336.603242 -228.790534) (xy 336.653106 -228.780354)
			(xy 336.703958 -228.778305) (xy 336.754479 -228.784439) (xy 336.803363 -228.798599) (xy 336.849342 -228.820416)
			(xy 336.891226 -228.849326) (xy 336.92793 -228.884581) (xy 336.958503 -228.925267) (xy 336.982154 -228.97033)
			(xy 336.99827 -229.018604) (xy 337.006434 -229.068838) (xy 337.006946 -229.094284) (xy 337.32522 -229.094284)
			(xy 337.32918 -229.04523) (xy 337.340957 -228.997446) (xy 337.360248 -228.95217) (xy 337.386551 -228.910574)
			(xy 337.419186 -228.873737) (xy 337.457307 -228.842612) (xy 337.499928 -228.818005) (xy 337.545944 -228.800553)
			(xy 337.594163 -228.790709) (xy 337.643338 -228.788728) (xy 337.692193 -228.79466) (xy 337.739464 -228.808352)
			(xy 337.783926 -228.82945) (xy 337.824429 -228.857406) (xy 337.859922 -228.891498) (xy 337.889487 -228.930842)
			(xy 337.912358 -228.974419) (xy 337.927942 -229.0211) (xy 337.935837 -229.069677) (xy 337.936332 -229.094284)
			(xy 338.254843 -229.094284) (xy 338.258938 -229.043556) (xy 338.271117 -228.994142) (xy 338.291065 -228.947322)
			(xy 338.318266 -228.904308) (xy 338.352014 -228.866214) (xy 338.391436 -228.834027) (xy 338.43551 -228.808581)
			(xy 338.483096 -228.790534) (xy 338.53296 -228.780354) (xy 338.583812 -228.778305) (xy 338.634333 -228.784439)
			(xy 338.683217 -228.798599) (xy 338.729196 -228.820416) (xy 338.77108 -228.849326) (xy 338.807784 -228.884581)
			(xy 338.838357 -228.925267) (xy 338.862008 -228.97033) (xy 338.878124 -229.018604) (xy 338.886288 -229.068838)
			(xy 338.8868 -229.094284) (xy 339.205328 -229.094284) (xy 339.209288 -229.04523) (xy 339.221065 -228.997446)
			(xy 339.240356 -228.95217) (xy 339.266659 -228.910574) (xy 339.299294 -228.873737) (xy 339.337415 -228.842612)
			(xy 339.380036 -228.818005) (xy 339.426052 -228.800553) (xy 339.474271 -228.790709) (xy 339.523446 -228.788728)
			(xy 339.572301 -228.79466) (xy 339.619572 -228.808352) (xy 339.664034 -228.82945) (xy 339.704537 -228.857406)
			(xy 339.74003 -228.891498) (xy 339.769595 -228.930842) (xy 339.792466 -228.974419) (xy 339.80805 -229.0211)
			(xy 339.815945 -229.069677) (xy 339.81644 -229.094284) (xy 340.134951 -229.094284) (xy 340.139046 -229.043556)
			(xy 340.151225 -228.994142) (xy 340.171173 -228.947322) (xy 340.198374 -228.904308) (xy 340.232122 -228.866214)
			(xy 340.271544 -228.834027) (xy 340.315618 -228.808581) (xy 340.363204 -228.790534) (xy 340.413068 -228.780354)
			(xy 340.46392 -228.778305) (xy 340.514441 -228.784439) (xy 340.563325 -228.798599) (xy 340.609304 -228.820416)
			(xy 340.651188 -228.849326) (xy 340.687892 -228.884581) (xy 340.718465 -228.925267) (xy 340.742116 -228.97033)
			(xy 340.758232 -229.018604) (xy 340.766396 -229.068838) (xy 340.766908 -229.094284) (xy 341.085182 -229.094284)
			(xy 341.089142 -229.04523) (xy 341.100919 -228.997446) (xy 341.12021 -228.95217) (xy 341.146513 -228.910574)
			(xy 341.179148 -228.873737) (xy 341.217269 -228.842612) (xy 341.25989 -228.818005) (xy 341.305906 -228.800553)
			(xy 341.354125 -228.790709) (xy 341.4033 -228.788728) (xy 341.452155 -228.79466) (xy 341.499426 -228.808352)
			(xy 341.543888 -228.82945) (xy 341.584391 -228.857406) (xy 341.619884 -228.891498) (xy 341.649449 -228.930842)
			(xy 341.67232 -228.974419) (xy 341.687904 -229.0211) (xy 341.695799 -229.069677) (xy 341.696294 -229.094284)
			(xy 342.014805 -229.094284) (xy 342.0189 -229.043556) (xy 342.031079 -228.994142) (xy 342.051027 -228.947322)
			(xy 342.078228 -228.904308) (xy 342.111976 -228.866214) (xy 342.151398 -228.834027) (xy 342.195472 -228.808581)
			(xy 342.243058 -228.790534) (xy 342.292922 -228.780354) (xy 342.343774 -228.778305) (xy 342.394295 -228.784439)
			(xy 342.443179 -228.798599) (xy 342.489158 -228.820416) (xy 342.531042 -228.849326) (xy 342.567746 -228.884581)
			(xy 342.598319 -228.925267) (xy 342.62197 -228.97033) (xy 342.638086 -229.018604) (xy 342.64625 -229.068838)
			(xy 342.646762 -229.094284) (xy 342.954859 -229.094284) (xy 342.958954 -229.043556) (xy 342.971133 -228.994142)
			(xy 342.991081 -228.947322) (xy 343.018282 -228.904308) (xy 343.05203 -228.866214) (xy 343.091452 -228.834027)
			(xy 343.135526 -228.808581) (xy 343.183112 -228.790534) (xy 343.232976 -228.780354) (xy 343.283828 -228.778305)
			(xy 343.334349 -228.784439) (xy 343.383233 -228.798599) (xy 343.429212 -228.820416) (xy 343.471096 -228.849326)
			(xy 343.5078 -228.884581) (xy 343.538373 -228.925267) (xy 343.562024 -228.97033) (xy 343.57814 -229.018604)
			(xy 343.586304 -229.068838) (xy 343.586816 -229.094284) (xy 343.586304 -229.11973) (xy 343.57814 -229.169964)
			(xy 343.562024 -229.218238) (xy 343.538373 -229.263301) (xy 343.5078 -229.303987) (xy 343.471096 -229.339242)
			(xy 343.429212 -229.368152) (xy 343.383233 -229.389969) (xy 343.334349 -229.404129) (xy 343.283828 -229.410263)
			(xy 343.232976 -229.408214) (xy 343.183112 -229.398034) (xy 343.135526 -229.379987) (xy 343.091452 -229.354541)
			(xy 343.05203 -229.322354) (xy 343.018282 -229.28426) (xy 342.991081 -229.241246) (xy 342.971133 -229.194426)
			(xy 342.958954 -229.145012) (xy 342.954859 -229.094284) (xy 342.646762 -229.094284) (xy 342.64625 -229.11973)
			(xy 342.638086 -229.169964) (xy 342.62197 -229.218238) (xy 342.598319 -229.263301) (xy 342.567746 -229.303987)
			(xy 342.531042 -229.339242) (xy 342.489158 -229.368152) (xy 342.443179 -229.389969) (xy 342.394295 -229.404129)
			(xy 342.343774 -229.410263) (xy 342.292922 -229.408214) (xy 342.243058 -229.398034) (xy 342.195472 -229.379987)
			(xy 342.151398 -229.354541) (xy 342.111976 -229.322354) (xy 342.078228 -229.28426) (xy 342.051027 -229.241246)
			(xy 342.031079 -229.194426) (xy 342.0189 -229.145012) (xy 342.014805 -229.094284) (xy 341.696294 -229.094284)
			(xy 341.695799 -229.118891) (xy 341.687904 -229.167468) (xy 341.67232 -229.214149) (xy 341.649449 -229.257726)
			(xy 341.619884 -229.29707) (xy 341.584391 -229.331162) (xy 341.543888 -229.359118) (xy 341.499426 -229.380216)
			(xy 341.452155 -229.393908) (xy 341.4033 -229.39984) (xy 341.354125 -229.397859) (xy 341.305906 -229.388015)
			(xy 341.25989 -229.370563) (xy 341.217269 -229.345956) (xy 341.179148 -229.314831) (xy 341.146513 -229.277994)
			(xy 341.12021 -229.236398) (xy 341.100919 -229.191122) (xy 341.089142 -229.143338) (xy 341.085182 -229.094284)
			(xy 340.766908 -229.094284) (xy 340.766396 -229.11973) (xy 340.758232 -229.169964) (xy 340.742116 -229.218238)
			(xy 340.718465 -229.263301) (xy 340.687892 -229.303987) (xy 340.651188 -229.339242) (xy 340.609304 -229.368152)
			(xy 340.563325 -229.389969) (xy 340.514441 -229.404129) (xy 340.46392 -229.410263) (xy 340.413068 -229.408214)
			(xy 340.363204 -229.398034) (xy 340.315618 -229.379987) (xy 340.271544 -229.354541) (xy 340.232122 -229.322354)
			(xy 340.198374 -229.28426) (xy 340.171173 -229.241246) (xy 340.151225 -229.194426) (xy 340.139046 -229.145012)
			(xy 340.134951 -229.094284) (xy 339.81644 -229.094284) (xy 339.815945 -229.118891) (xy 339.80805 -229.167468)
			(xy 339.792466 -229.214149) (xy 339.769595 -229.257726) (xy 339.74003 -229.29707) (xy 339.704537 -229.331162)
			(xy 339.664034 -229.359118) (xy 339.619572 -229.380216) (xy 339.572301 -229.393908) (xy 339.523446 -229.39984)
			(xy 339.474271 -229.397859) (xy 339.426052 -229.388015) (xy 339.380036 -229.370563) (xy 339.337415 -229.345956)
			(xy 339.299294 -229.314831) (xy 339.266659 -229.277994) (xy 339.240356 -229.236398) (xy 339.221065 -229.191122)
			(xy 339.209288 -229.143338) (xy 339.205328 -229.094284) (xy 338.8868 -229.094284) (xy 338.886288 -229.11973)
			(xy 338.878124 -229.169964) (xy 338.862008 -229.218238) (xy 338.838357 -229.263301) (xy 338.807784 -229.303987)
			(xy 338.77108 -229.339242) (xy 338.729196 -229.368152) (xy 338.683217 -229.389969) (xy 338.634333 -229.404129)
			(xy 338.583812 -229.410263) (xy 338.53296 -229.408214) (xy 338.483096 -229.398034) (xy 338.43551 -229.379987)
			(xy 338.391436 -229.354541) (xy 338.352014 -229.322354) (xy 338.318266 -229.28426) (xy 338.291065 -229.241246)
			(xy 338.271117 -229.194426) (xy 338.258938 -229.145012) (xy 338.254843 -229.094284) (xy 337.936332 -229.094284)
			(xy 337.935837 -229.118891) (xy 337.927942 -229.167468) (xy 337.912358 -229.214149) (xy 337.889487 -229.257726)
			(xy 337.859922 -229.29707) (xy 337.824429 -229.331162) (xy 337.783926 -229.359118) (xy 337.739464 -229.380216)
			(xy 337.692193 -229.393908) (xy 337.643338 -229.39984) (xy 337.594163 -229.397859) (xy 337.545944 -229.388015)
			(xy 337.499928 -229.370563) (xy 337.457307 -229.345956) (xy 337.419186 -229.314831) (xy 337.386551 -229.277994)
			(xy 337.360248 -229.236398) (xy 337.340957 -229.191122) (xy 337.32918 -229.143338) (xy 337.32522 -229.094284)
			(xy 337.006946 -229.094284) (xy 337.006434 -229.11973) (xy 336.99827 -229.169964) (xy 336.982154 -229.218238)
			(xy 336.958503 -229.263301) (xy 336.92793 -229.303987) (xy 336.891226 -229.339242) (xy 336.849342 -229.368152)
			(xy 336.803363 -229.389969) (xy 336.754479 -229.404129) (xy 336.703958 -229.410263) (xy 336.653106 -229.408214)
			(xy 336.603242 -229.398034) (xy 336.555656 -229.379987) (xy 336.511582 -229.354541) (xy 336.47216 -229.322354)
			(xy 336.438412 -229.28426) (xy 336.411211 -229.241246) (xy 336.391263 -229.194426) (xy 336.379084 -229.145012)
			(xy 336.374989 -229.094284) (xy 336.066892 -229.094284) (xy 336.06638 -229.11973) (xy 336.058216 -229.169964)
			(xy 336.0421 -229.218238) (xy 336.018449 -229.263301) (xy 335.987876 -229.303987) (xy 335.951172 -229.339242)
			(xy 335.909288 -229.368152) (xy 335.863309 -229.389969) (xy 335.814425 -229.404129) (xy 335.763904 -229.410263)
			(xy 335.713052 -229.408214) (xy 335.663188 -229.398034) (xy 335.615602 -229.379987) (xy 335.571528 -229.354541)
			(xy 335.532106 -229.322354) (xy 335.498358 -229.28426) (xy 335.471157 -229.241246) (xy 335.451209 -229.194426)
			(xy 335.43903 -229.145012) (xy 335.434935 -229.094284) (xy 335.116424 -229.094284) (xy 335.115929 -229.118891)
			(xy 335.108034 -229.167468) (xy 335.09245 -229.214149) (xy 335.069579 -229.257726) (xy 335.040014 -229.29707)
			(xy 335.004521 -229.331162) (xy 334.964018 -229.359118) (xy 334.919556 -229.380216) (xy 334.872285 -229.393908)
			(xy 334.82343 -229.39984) (xy 334.774255 -229.397859) (xy 334.726036 -229.388015) (xy 334.68002 -229.370563)
			(xy 334.637399 -229.345956) (xy 334.599278 -229.314831) (xy 334.566643 -229.277994) (xy 334.54034 -229.236398)
			(xy 334.521049 -229.191122) (xy 334.509272 -229.143338) (xy 334.505312 -229.094284) (xy 334.186784 -229.094284)
			(xy 334.186272 -229.11973) (xy 334.178108 -229.169964) (xy 334.161992 -229.218238) (xy 334.138341 -229.263301)
			(xy 334.107768 -229.303987) (xy 334.071064 -229.339242) (xy 334.02918 -229.368152) (xy 333.983201 -229.389969)
			(xy 333.934317 -229.404129) (xy 333.883796 -229.410263) (xy 333.832944 -229.408214) (xy 333.78308 -229.398034)
			(xy 333.735494 -229.379987) (xy 333.69142 -229.354541) (xy 333.651998 -229.322354) (xy 333.61825 -229.28426)
			(xy 333.591049 -229.241246) (xy 333.571101 -229.194426) (xy 333.558922 -229.145012) (xy 333.554827 -229.094284)
			(xy 333.236316 -229.094284) (xy 333.235821 -229.118891) (xy 333.227926 -229.167468) (xy 333.212342 -229.214149)
			(xy 333.189471 -229.257726) (xy 333.159906 -229.29707) (xy 333.124413 -229.331162) (xy 333.08391 -229.359118)
			(xy 333.039448 -229.380216) (xy 332.992177 -229.393908) (xy 332.943322 -229.39984) (xy 332.894147 -229.397859)
			(xy 332.845928 -229.388015) (xy 332.799912 -229.370563) (xy 332.757291 -229.345956) (xy 332.71917 -229.314831)
			(xy 332.686535 -229.277994) (xy 332.660232 -229.236398) (xy 332.640941 -229.191122) (xy 332.629164 -229.143338)
			(xy 332.625204 -229.094284) (xy 332.30693 -229.094284) (xy 332.306418 -229.11973) (xy 332.298254 -229.169964)
			(xy 332.282138 -229.218238) (xy 332.258487 -229.263301) (xy 332.227914 -229.303987) (xy 332.19121 -229.339242)
			(xy 332.149326 -229.368152) (xy 332.103347 -229.389969) (xy 332.054463 -229.404129) (xy 332.003942 -229.410263)
			(xy 331.95309 -229.408214) (xy 331.903226 -229.398034) (xy 331.85564 -229.379987) (xy 331.811566 -229.354541)
			(xy 331.772144 -229.322354) (xy 331.738396 -229.28426) (xy 331.711195 -229.241246) (xy 331.691247 -229.194426)
			(xy 331.679068 -229.145012) (xy 331.674973 -229.094284) (xy 331.356462 -229.094284) (xy 331.355967 -229.118891)
			(xy 331.348072 -229.167468) (xy 331.332488 -229.214149) (xy 331.309617 -229.257726) (xy 331.280052 -229.29707)
			(xy 331.244559 -229.331162) (xy 331.204056 -229.359118) (xy 331.159594 -229.380216) (xy 331.112323 -229.393908)
			(xy 331.063468 -229.39984) (xy 331.014293 -229.397859) (xy 330.966074 -229.388015) (xy 330.920058 -229.370563)
			(xy 330.877437 -229.345956) (xy 330.839316 -229.314831) (xy 330.806681 -229.277994) (xy 330.780378 -229.236398)
			(xy 330.761087 -229.191122) (xy 330.74931 -229.143338) (xy 330.74535 -229.094284) (xy 330.426822 -229.094284)
			(xy 330.42631 -229.11973) (xy 330.418146 -229.169964) (xy 330.40203 -229.218238) (xy 330.378379 -229.263301)
			(xy 330.347806 -229.303987) (xy 330.311102 -229.339242) (xy 330.269218 -229.368152) (xy 330.223239 -229.389969)
			(xy 330.174355 -229.404129) (xy 330.123834 -229.410263) (xy 330.072982 -229.408214) (xy 330.023118 -229.398034)
			(xy 329.975532 -229.379987) (xy 329.931458 -229.354541) (xy 329.892036 -229.322354) (xy 329.858288 -229.28426)
			(xy 329.831087 -229.241246) (xy 329.811139 -229.194426) (xy 329.79896 -229.145012) (xy 329.794865 -229.094284)
			(xy 329.486768 -229.094284) (xy 329.486256 -229.11973) (xy 329.478092 -229.169964) (xy 329.461976 -229.218238)
			(xy 329.438325 -229.263301) (xy 329.407752 -229.303987) (xy 329.371048 -229.339242) (xy 329.329164 -229.368152)
			(xy 329.283185 -229.389969) (xy 329.234301 -229.404129) (xy 329.18378 -229.410263) (xy 329.132928 -229.408214)
			(xy 329.083064 -229.398034) (xy 329.035478 -229.379987) (xy 328.991404 -229.354541) (xy 328.951982 -229.322354)
			(xy 328.918234 -229.28426) (xy 328.891033 -229.241246) (xy 328.871085 -229.194426) (xy 328.858906 -229.145012)
			(xy 328.854811 -229.094284) (xy 328.536554 -229.094284) (xy 328.536059 -229.118891) (xy 328.528164 -229.167468)
			(xy 328.51258 -229.214149) (xy 328.489709 -229.257726) (xy 328.460144 -229.29707) (xy 328.424651 -229.331162)
			(xy 328.384148 -229.359118) (xy 328.339686 -229.380216) (xy 328.292415 -229.393908) (xy 328.24356 -229.39984)
			(xy 328.194385 -229.397859) (xy 328.146166 -229.388015) (xy 328.10015 -229.370563) (xy 328.057529 -229.345956)
			(xy 328.019408 -229.314831) (xy 327.986773 -229.277994) (xy 327.96047 -229.236398) (xy 327.941179 -229.191122)
			(xy 327.929402 -229.143338) (xy 327.925442 -229.094284) (xy 326.656446 -229.094284) (xy 326.655951 -229.118891)
			(xy 326.648056 -229.167468) (xy 326.632472 -229.214149) (xy 326.609601 -229.257726) (xy 326.580036 -229.29707)
			(xy 326.544543 -229.331162) (xy 326.50404 -229.359118) (xy 326.459578 -229.380216) (xy 326.412307 -229.393908)
			(xy 326.363452 -229.39984) (xy 326.314277 -229.397859) (xy 326.266058 -229.388015) (xy 326.220042 -229.370563)
			(xy 326.177421 -229.345956) (xy 326.1393 -229.314831) (xy 326.106665 -229.277994) (xy 326.080362 -229.236398)
			(xy 326.061071 -229.191122) (xy 326.049294 -229.143338) (xy 326.045334 -229.094284) (xy 310.45912 -229.094284)
			(xy 310.45912 -230.169974) (xy 324.447166 -230.169974) (xy 324.451126 -230.12092) (xy 324.462903 -230.073136)
			(xy 324.482194 -230.02786) (xy 324.508497 -229.986264) (xy 324.541132 -229.949427) (xy 324.579253 -229.918302)
			(xy 324.621874 -229.893695) (xy 324.66789 -229.876243) (xy 324.716109 -229.866399) (xy 324.765284 -229.864418)
			(xy 324.814139 -229.87035) (xy 324.86141 -229.884042) (xy 324.903545 -229.904036) (xy 328.384911 -229.904036)
			(xy 328.389006 -229.853308) (xy 328.401185 -229.803894) (xy 328.421133 -229.757074) (xy 328.448334 -229.71406)
			(xy 328.482082 -229.675966) (xy 328.521504 -229.643779) (xy 328.565578 -229.618333) (xy 328.613164 -229.600286)
			(xy 328.663028 -229.590106) (xy 328.71388 -229.588057) (xy 328.764401 -229.594191) (xy 328.813285 -229.608351)
			(xy 328.859264 -229.630168) (xy 328.901148 -229.659078) (xy 328.937852 -229.694333) (xy 328.968425 -229.735019)
			(xy 328.992076 -229.780082) (xy 329.008192 -229.828356) (xy 329.016356 -229.87859) (xy 329.016868 -229.904036)
			(xy 329.335396 -229.904036) (xy 329.339356 -229.854982) (xy 329.351133 -229.807198) (xy 329.370424 -229.761922)
			(xy 329.396727 -229.720326) (xy 329.429362 -229.683489) (xy 329.467483 -229.652364) (xy 329.510104 -229.627757)
			(xy 329.55612 -229.610305) (xy 329.604339 -229.600461) (xy 329.653514 -229.59848) (xy 329.702369 -229.604412)
			(xy 329.74964 -229.618104) (xy 329.794102 -229.639202) (xy 329.834605 -229.667158) (xy 329.870098 -229.70125)
			(xy 329.899663 -229.740594) (xy 329.922534 -229.784171) (xy 329.938118 -229.830852) (xy 329.946013 -229.879429)
			(xy 329.946508 -229.904036) (xy 330.264765 -229.904036) (xy 330.26886 -229.853308) (xy 330.281039 -229.803894)
			(xy 330.300987 -229.757074) (xy 330.328188 -229.71406) (xy 330.361936 -229.675966) (xy 330.401358 -229.643779)
			(xy 330.445432 -229.618333) (xy 330.493018 -229.600286) (xy 330.542882 -229.590106) (xy 330.593734 -229.588057)
			(xy 330.644255 -229.594191) (xy 330.693139 -229.608351) (xy 330.739118 -229.630168) (xy 330.781002 -229.659078)
			(xy 330.817706 -229.694333) (xy 330.848279 -229.735019) (xy 330.87193 -229.780082) (xy 330.888046 -229.828356)
			(xy 330.89621 -229.87859) (xy 330.896722 -229.904036) (xy 331.21525 -229.904036) (xy 331.21921 -229.854982)
			(xy 331.230987 -229.807198) (xy 331.250278 -229.761922) (xy 331.276581 -229.720326) (xy 331.309216 -229.683489)
			(xy 331.347337 -229.652364) (xy 331.389958 -229.627757) (xy 331.435974 -229.610305) (xy 331.484193 -229.600461)
			(xy 331.533368 -229.59848) (xy 331.582223 -229.604412) (xy 331.629494 -229.618104) (xy 331.673956 -229.639202)
			(xy 331.714459 -229.667158) (xy 331.749952 -229.70125) (xy 331.779517 -229.740594) (xy 331.802388 -229.784171)
			(xy 331.817972 -229.830852) (xy 331.825867 -229.879429) (xy 331.826362 -229.904036) (xy 332.144873 -229.904036)
			(xy 332.148968 -229.853308) (xy 332.161147 -229.803894) (xy 332.181095 -229.757074) (xy 332.208296 -229.71406)
			(xy 332.242044 -229.675966) (xy 332.281466 -229.643779) (xy 332.32554 -229.618333) (xy 332.373126 -229.600286)
			(xy 332.42299 -229.590106) (xy 332.473842 -229.588057) (xy 332.524363 -229.594191) (xy 332.573247 -229.608351)
			(xy 332.619226 -229.630168) (xy 332.66111 -229.659078) (xy 332.697814 -229.694333) (xy 332.728387 -229.735019)
			(xy 332.752038 -229.780082) (xy 332.768154 -229.828356) (xy 332.776318 -229.87859) (xy 332.77683 -229.904036)
			(xy 333.084927 -229.904036) (xy 333.089022 -229.853308) (xy 333.101201 -229.803894) (xy 333.121149 -229.757074)
			(xy 333.14835 -229.71406) (xy 333.182098 -229.675966) (xy 333.22152 -229.643779) (xy 333.265594 -229.618333)
			(xy 333.31318 -229.600286) (xy 333.363044 -229.590106) (xy 333.413896 -229.588057) (xy 333.464417 -229.594191)
			(xy 333.513301 -229.608351) (xy 333.55928 -229.630168) (xy 333.601164 -229.659078) (xy 333.637868 -229.694333)
			(xy 333.668441 -229.735019) (xy 333.692092 -229.780082) (xy 333.708208 -229.828356) (xy 333.716372 -229.87859)
			(xy 333.716884 -229.904036) (xy 334.964781 -229.904036) (xy 334.968876 -229.853308) (xy 334.981055 -229.803894)
			(xy 335.001003 -229.757074) (xy 335.028204 -229.71406) (xy 335.061952 -229.675966) (xy 335.101374 -229.643779)
			(xy 335.145448 -229.618333) (xy 335.193034 -229.600286) (xy 335.242898 -229.590106) (xy 335.29375 -229.588057)
			(xy 335.344271 -229.594191) (xy 335.393155 -229.608351) (xy 335.439134 -229.630168) (xy 335.481018 -229.659078)
			(xy 335.517722 -229.694333) (xy 335.548295 -229.735019) (xy 335.571946 -229.780082) (xy 335.588062 -229.828356)
			(xy 335.596226 -229.87859) (xy 335.596738 -229.904036) (xy 335.915266 -229.904036) (xy 335.919226 -229.854982)
			(xy 335.931003 -229.807198) (xy 335.950294 -229.761922) (xy 335.976597 -229.720326) (xy 336.009232 -229.683489)
			(xy 336.047353 -229.652364) (xy 336.089974 -229.627757) (xy 336.13599 -229.610305) (xy 336.184209 -229.600461)
			(xy 336.233384 -229.59848) (xy 336.282239 -229.604412) (xy 336.32951 -229.618104) (xy 336.373972 -229.639202)
			(xy 336.414475 -229.667158) (xy 336.449968 -229.70125) (xy 336.479533 -229.740594) (xy 336.502404 -229.784171)
			(xy 336.517988 -229.830852) (xy 336.525883 -229.879429) (xy 336.526378 -229.904036) (xy 336.844889 -229.904036)
			(xy 336.848984 -229.853308) (xy 336.861163 -229.803894) (xy 336.881111 -229.757074) (xy 336.908312 -229.71406)
			(xy 336.94206 -229.675966) (xy 336.981482 -229.643779) (xy 337.025556 -229.618333) (xy 337.073142 -229.600286)
			(xy 337.123006 -229.590106) (xy 337.173858 -229.588057) (xy 337.224379 -229.594191) (xy 337.273263 -229.608351)
			(xy 337.319242 -229.630168) (xy 337.361126 -229.659078) (xy 337.39783 -229.694333) (xy 337.428403 -229.735019)
			(xy 337.452054 -229.780082) (xy 337.46817 -229.828356) (xy 337.476334 -229.87859) (xy 337.476846 -229.904036)
			(xy 337.795374 -229.904036) (xy 337.799334 -229.854982) (xy 337.811111 -229.807198) (xy 337.830402 -229.761922)
			(xy 337.856705 -229.720326) (xy 337.88934 -229.683489) (xy 337.927461 -229.652364) (xy 337.970082 -229.627757)
			(xy 338.016098 -229.610305) (xy 338.064317 -229.600461) (xy 338.113492 -229.59848) (xy 338.162347 -229.604412)
			(xy 338.209618 -229.618104) (xy 338.25408 -229.639202) (xy 338.294583 -229.667158) (xy 338.330076 -229.70125)
			(xy 338.359641 -229.740594) (xy 338.382512 -229.784171) (xy 338.398096 -229.830852) (xy 338.405991 -229.879429)
			(xy 338.406486 -229.904036) (xy 338.724743 -229.904036) (xy 338.728838 -229.853308) (xy 338.741017 -229.803894)
			(xy 338.760965 -229.757074) (xy 338.788166 -229.71406) (xy 338.821914 -229.675966) (xy 338.861336 -229.643779)
			(xy 338.90541 -229.618333) (xy 338.952996 -229.600286) (xy 339.00286 -229.590106) (xy 339.053712 -229.588057)
			(xy 339.104233 -229.594191) (xy 339.153117 -229.608351) (xy 339.199096 -229.630168) (xy 339.24098 -229.659078)
			(xy 339.277684 -229.694333) (xy 339.308257 -229.735019) (xy 339.331908 -229.780082) (xy 339.348024 -229.828356)
			(xy 339.356188 -229.87859) (xy 339.3567 -229.904036) (xy 339.664797 -229.904036) (xy 339.668892 -229.853308)
			(xy 339.681071 -229.803894) (xy 339.701019 -229.757074) (xy 339.72822 -229.71406) (xy 339.761968 -229.675966)
			(xy 339.80139 -229.643779) (xy 339.845464 -229.618333) (xy 339.89305 -229.600286) (xy 339.942914 -229.590106)
			(xy 339.993766 -229.588057) (xy 340.044287 -229.594191) (xy 340.093171 -229.608351) (xy 340.13915 -229.630168)
			(xy 340.181034 -229.659078) (xy 340.217738 -229.694333) (xy 340.248311 -229.735019) (xy 340.271962 -229.780082)
			(xy 340.288078 -229.828356) (xy 340.296242 -229.87859) (xy 340.296754 -229.904036) (xy 341.544905 -229.904036)
			(xy 341.549 -229.853308) (xy 341.561179 -229.803894) (xy 341.581127 -229.757074) (xy 341.608328 -229.71406)
			(xy 341.642076 -229.675966) (xy 341.681498 -229.643779) (xy 341.725572 -229.618333) (xy 341.773158 -229.600286)
			(xy 341.823022 -229.590106) (xy 341.873874 -229.588057) (xy 341.924395 -229.594191) (xy 341.973279 -229.608351)
			(xy 342.019258 -229.630168) (xy 342.061142 -229.659078) (xy 342.097846 -229.694333) (xy 342.128419 -229.735019)
			(xy 342.15207 -229.780082) (xy 342.168186 -229.828356) (xy 342.17635 -229.87859) (xy 342.176862 -229.904036)
			(xy 342.49539 -229.904036) (xy 342.49935 -229.854982) (xy 342.511127 -229.807198) (xy 342.530418 -229.761922)
			(xy 342.556721 -229.720326) (xy 342.589356 -229.683489) (xy 342.627477 -229.652364) (xy 342.670098 -229.627757)
			(xy 342.716114 -229.610305) (xy 342.764333 -229.600461) (xy 342.813508 -229.59848) (xy 342.862363 -229.604412)
			(xy 342.909634 -229.618104) (xy 342.954096 -229.639202) (xy 342.994599 -229.667158) (xy 343.030092 -229.70125)
			(xy 343.059657 -229.740594) (xy 343.082528 -229.784171) (xy 343.098112 -229.830852) (xy 343.106007 -229.879429)
			(xy 343.106502 -229.904036) (xy 343.106007 -229.928643) (xy 343.098112 -229.97722) (xy 343.082528 -230.023901)
			(xy 343.059657 -230.067478) (xy 343.030092 -230.106822) (xy 342.994599 -230.140914) (xy 342.954096 -230.16887)
			(xy 342.909634 -230.189968) (xy 342.862363 -230.20366) (xy 342.813508 -230.209592) (xy 342.764333 -230.207611)
			(xy 342.716114 -230.197767) (xy 342.670098 -230.180315) (xy 342.627477 -230.155708) (xy 342.589356 -230.124583)
			(xy 342.556721 -230.087746) (xy 342.530418 -230.04615) (xy 342.511127 -230.000874) (xy 342.49935 -229.95309)
			(xy 342.49539 -229.904036) (xy 342.176862 -229.904036) (xy 342.17635 -229.929482) (xy 342.168186 -229.979716)
			(xy 342.15207 -230.02799) (xy 342.128419 -230.073053) (xy 342.097846 -230.113739) (xy 342.061142 -230.148994)
			(xy 342.019258 -230.177904) (xy 341.973279 -230.199721) (xy 341.924395 -230.213881) (xy 341.873874 -230.220015)
			(xy 341.823022 -230.217966) (xy 341.773158 -230.207786) (xy 341.725572 -230.189739) (xy 341.681498 -230.164293)
			(xy 341.642076 -230.132106) (xy 341.608328 -230.094012) (xy 341.581127 -230.050998) (xy 341.561179 -230.004178)
			(xy 341.549 -229.954764) (xy 341.544905 -229.904036) (xy 340.296754 -229.904036) (xy 340.296242 -229.929482)
			(xy 340.288078 -229.979716) (xy 340.271962 -230.02799) (xy 340.248311 -230.073053) (xy 340.217738 -230.113739)
			(xy 340.181034 -230.148994) (xy 340.13915 -230.177904) (xy 340.093171 -230.199721) (xy 340.044287 -230.213881)
			(xy 339.993766 -230.220015) (xy 339.942914 -230.217966) (xy 339.89305 -230.207786) (xy 339.845464 -230.189739)
			(xy 339.80139 -230.164293) (xy 339.761968 -230.132106) (xy 339.72822 -230.094012) (xy 339.701019 -230.050998)
			(xy 339.681071 -230.004178) (xy 339.668892 -229.954764) (xy 339.664797 -229.904036) (xy 339.3567 -229.904036)
			(xy 339.356188 -229.929482) (xy 339.348024 -229.979716) (xy 339.331908 -230.02799) (xy 339.308257 -230.073053)
			(xy 339.277684 -230.113739) (xy 339.24098 -230.148994) (xy 339.199096 -230.177904) (xy 339.153117 -230.199721)
			(xy 339.104233 -230.213881) (xy 339.053712 -230.220015) (xy 339.00286 -230.217966) (xy 338.952996 -230.207786)
			(xy 338.90541 -230.189739) (xy 338.861336 -230.164293) (xy 338.821914 -230.132106) (xy 338.788166 -230.094012)
			(xy 338.760965 -230.050998) (xy 338.741017 -230.004178) (xy 338.728838 -229.954764) (xy 338.724743 -229.904036)
			(xy 338.406486 -229.904036) (xy 338.405991 -229.928643) (xy 338.398096 -229.97722) (xy 338.382512 -230.023901)
			(xy 338.359641 -230.067478) (xy 338.330076 -230.106822) (xy 338.294583 -230.140914) (xy 338.25408 -230.16887)
			(xy 338.209618 -230.189968) (xy 338.162347 -230.20366) (xy 338.113492 -230.209592) (xy 338.064317 -230.207611)
			(xy 338.016098 -230.197767) (xy 337.970082 -230.180315) (xy 337.927461 -230.155708) (xy 337.88934 -230.124583)
			(xy 337.856705 -230.087746) (xy 337.830402 -230.04615) (xy 337.811111 -230.000874) (xy 337.799334 -229.95309)
			(xy 337.795374 -229.904036) (xy 337.476846 -229.904036) (xy 337.476334 -229.929482) (xy 337.46817 -229.979716)
			(xy 337.452054 -230.02799) (xy 337.428403 -230.073053) (xy 337.39783 -230.113739) (xy 337.361126 -230.148994)
			(xy 337.319242 -230.177904) (xy 337.273263 -230.199721) (xy 337.224379 -230.213881) (xy 337.173858 -230.220015)
			(xy 337.123006 -230.217966) (xy 337.073142 -230.207786) (xy 337.025556 -230.189739) (xy 336.981482 -230.164293)
			(xy 336.94206 -230.132106) (xy 336.908312 -230.094012) (xy 336.881111 -230.050998) (xy 336.861163 -230.004178)
			(xy 336.848984 -229.954764) (xy 336.844889 -229.904036) (xy 336.526378 -229.904036) (xy 336.525883 -229.928643)
			(xy 336.517988 -229.97722) (xy 336.502404 -230.023901) (xy 336.479533 -230.067478) (xy 336.449968 -230.106822)
			(xy 336.414475 -230.140914) (xy 336.373972 -230.16887) (xy 336.32951 -230.189968) (xy 336.282239 -230.20366)
			(xy 336.233384 -230.209592) (xy 336.184209 -230.207611) (xy 336.13599 -230.197767) (xy 336.089974 -230.180315)
			(xy 336.047353 -230.155708) (xy 336.009232 -230.124583) (xy 335.976597 -230.087746) (xy 335.950294 -230.04615)
			(xy 335.931003 -230.000874) (xy 335.919226 -229.95309) (xy 335.915266 -229.904036) (xy 335.596738 -229.904036)
			(xy 335.596226 -229.929482) (xy 335.588062 -229.979716) (xy 335.571946 -230.02799) (xy 335.548295 -230.073053)
			(xy 335.517722 -230.113739) (xy 335.481018 -230.148994) (xy 335.439134 -230.177904) (xy 335.393155 -230.199721)
			(xy 335.344271 -230.213881) (xy 335.29375 -230.220015) (xy 335.242898 -230.217966) (xy 335.193034 -230.207786)
			(xy 335.145448 -230.189739) (xy 335.101374 -230.164293) (xy 335.061952 -230.132106) (xy 335.028204 -230.094012)
			(xy 335.001003 -230.050998) (xy 334.981055 -230.004178) (xy 334.968876 -229.954764) (xy 334.964781 -229.904036)
			(xy 333.716884 -229.904036) (xy 333.716372 -229.929482) (xy 333.708208 -229.979716) (xy 333.692092 -230.02799)
			(xy 333.668441 -230.073053) (xy 333.637868 -230.113739) (xy 333.601164 -230.148994) (xy 333.55928 -230.177904)
			(xy 333.513301 -230.199721) (xy 333.464417 -230.213881) (xy 333.413896 -230.220015) (xy 333.363044 -230.217966)
			(xy 333.31318 -230.207786) (xy 333.265594 -230.189739) (xy 333.22152 -230.164293) (xy 333.182098 -230.132106)
			(xy 333.14835 -230.094012) (xy 333.121149 -230.050998) (xy 333.101201 -230.004178) (xy 333.089022 -229.954764)
			(xy 333.084927 -229.904036) (xy 332.77683 -229.904036) (xy 332.776318 -229.929482) (xy 332.768154 -229.979716)
			(xy 332.752038 -230.02799) (xy 332.728387 -230.073053) (xy 332.697814 -230.113739) (xy 332.66111 -230.148994)
			(xy 332.619226 -230.177904) (xy 332.573247 -230.199721) (xy 332.524363 -230.213881) (xy 332.473842 -230.220015)
			(xy 332.42299 -230.217966) (xy 332.373126 -230.207786) (xy 332.32554 -230.189739) (xy 332.281466 -230.164293)
			(xy 332.242044 -230.132106) (xy 332.208296 -230.094012) (xy 332.181095 -230.050998) (xy 332.161147 -230.004178)
			(xy 332.148968 -229.954764) (xy 332.144873 -229.904036) (xy 331.826362 -229.904036) (xy 331.825867 -229.928643)
			(xy 331.817972 -229.97722) (xy 331.802388 -230.023901) (xy 331.779517 -230.067478) (xy 331.749952 -230.106822)
			(xy 331.714459 -230.140914) (xy 331.673956 -230.16887) (xy 331.629494 -230.189968) (xy 331.582223 -230.20366)
			(xy 331.533368 -230.209592) (xy 331.484193 -230.207611) (xy 331.435974 -230.197767) (xy 331.389958 -230.180315)
			(xy 331.347337 -230.155708) (xy 331.309216 -230.124583) (xy 331.276581 -230.087746) (xy 331.250278 -230.04615)
			(xy 331.230987 -230.000874) (xy 331.21921 -229.95309) (xy 331.21525 -229.904036) (xy 330.896722 -229.904036)
			(xy 330.89621 -229.929482) (xy 330.888046 -229.979716) (xy 330.87193 -230.02799) (xy 330.848279 -230.073053)
			(xy 330.817706 -230.113739) (xy 330.781002 -230.148994) (xy 330.739118 -230.177904) (xy 330.693139 -230.199721)
			(xy 330.644255 -230.213881) (xy 330.593734 -230.220015) (xy 330.542882 -230.217966) (xy 330.493018 -230.207786)
			(xy 330.445432 -230.189739) (xy 330.401358 -230.164293) (xy 330.361936 -230.132106) (xy 330.328188 -230.094012)
			(xy 330.300987 -230.050998) (xy 330.281039 -230.004178) (xy 330.26886 -229.954764) (xy 330.264765 -229.904036)
			(xy 329.946508 -229.904036) (xy 329.946013 -229.928643) (xy 329.938118 -229.97722) (xy 329.922534 -230.023901)
			(xy 329.899663 -230.067478) (xy 329.870098 -230.106822) (xy 329.834605 -230.140914) (xy 329.794102 -230.16887)
			(xy 329.74964 -230.189968) (xy 329.702369 -230.20366) (xy 329.653514 -230.209592) (xy 329.604339 -230.207611)
			(xy 329.55612 -230.197767) (xy 329.510104 -230.180315) (xy 329.467483 -230.155708) (xy 329.429362 -230.124583)
			(xy 329.396727 -230.087746) (xy 329.370424 -230.04615) (xy 329.351133 -230.000874) (xy 329.339356 -229.95309)
			(xy 329.335396 -229.904036) (xy 329.016868 -229.904036) (xy 329.016356 -229.929482) (xy 329.008192 -229.979716)
			(xy 328.992076 -230.02799) (xy 328.968425 -230.073053) (xy 328.937852 -230.113739) (xy 328.901148 -230.148994)
			(xy 328.859264 -230.177904) (xy 328.813285 -230.199721) (xy 328.764401 -230.213881) (xy 328.71388 -230.220015)
			(xy 328.663028 -230.217966) (xy 328.613164 -230.207786) (xy 328.565578 -230.189739) (xy 328.521504 -230.164293)
			(xy 328.482082 -230.132106) (xy 328.448334 -230.094012) (xy 328.421133 -230.050998) (xy 328.401185 -230.004178)
			(xy 328.389006 -229.954764) (xy 328.384911 -229.904036) (xy 324.903545 -229.904036) (xy 324.905872 -229.90514)
			(xy 324.946375 -229.933096) (xy 324.981868 -229.967188) (xy 325.011433 -230.006532) (xy 325.034304 -230.050109)
			(xy 325.049888 -230.09679) (xy 325.057783 -230.145367) (xy 325.058278 -230.169974) (xy 325.057783 -230.194581)
			(xy 325.049888 -230.243158) (xy 325.034304 -230.289839) (xy 325.011433 -230.333416) (xy 324.981868 -230.37276)
			(xy 324.946375 -230.406852) (xy 324.905872 -230.434808) (xy 324.86141 -230.455906) (xy 324.814139 -230.469598)
			(xy 324.765284 -230.47553) (xy 324.716109 -230.473549) (xy 324.66789 -230.463705) (xy 324.621874 -230.446253)
			(xy 324.579253 -230.421646) (xy 324.541132 -230.390521) (xy 324.508497 -230.353684) (xy 324.482194 -230.312088)
			(xy 324.462903 -230.266812) (xy 324.451126 -230.219028) (xy 324.447166 -230.169974) (xy 310.45912 -230.169974)
			(xy 310.45912 -230.714296) (xy 326.045334 -230.714296) (xy 326.049294 -230.665242) (xy 326.061071 -230.617458)
			(xy 326.080362 -230.572182) (xy 326.106665 -230.530586) (xy 326.1393 -230.493749) (xy 326.177421 -230.462624)
			(xy 326.220042 -230.438017) (xy 326.266058 -230.420565) (xy 326.314277 -230.410721) (xy 326.363452 -230.40874)
			(xy 326.412307 -230.414672) (xy 326.459578 -230.428364) (xy 326.50404 -230.449462) (xy 326.544543 -230.477418)
			(xy 326.580036 -230.51151) (xy 326.609601 -230.550854) (xy 326.632472 -230.594431) (xy 326.648056 -230.641112)
			(xy 326.655951 -230.689689) (xy 326.656446 -230.714296) (xy 327.925442 -230.714296) (xy 327.929402 -230.665242)
			(xy 327.941179 -230.617458) (xy 327.96047 -230.572182) (xy 327.986773 -230.530586) (xy 328.019408 -230.493749)
			(xy 328.057529 -230.462624) (xy 328.10015 -230.438017) (xy 328.146166 -230.420565) (xy 328.194385 -230.410721)
			(xy 328.24356 -230.40874) (xy 328.292415 -230.414672) (xy 328.339686 -230.428364) (xy 328.384148 -230.449462)
			(xy 328.424651 -230.477418) (xy 328.460144 -230.51151) (xy 328.489709 -230.550854) (xy 328.51258 -230.594431)
			(xy 328.528164 -230.641112) (xy 328.536059 -230.689689) (xy 328.536554 -230.714296) (xy 328.854811 -230.714296)
			(xy 328.858906 -230.663568) (xy 328.871085 -230.614154) (xy 328.891033 -230.567334) (xy 328.918234 -230.52432)
			(xy 328.951982 -230.486226) (xy 328.991404 -230.454039) (xy 329.035478 -230.428593) (xy 329.083064 -230.410546)
			(xy 329.132928 -230.400366) (xy 329.18378 -230.398317) (xy 329.234301 -230.404451) (xy 329.283185 -230.418611)
			(xy 329.329164 -230.440428) (xy 329.371048 -230.469338) (xy 329.407752 -230.504593) (xy 329.438325 -230.545279)
			(xy 329.461976 -230.590342) (xy 329.478092 -230.638616) (xy 329.486256 -230.68885) (xy 329.486768 -230.714296)
			(xy 329.794865 -230.714296) (xy 329.79896 -230.663568) (xy 329.811139 -230.614154) (xy 329.831087 -230.567334)
			(xy 329.858288 -230.52432) (xy 329.892036 -230.486226) (xy 329.931458 -230.454039) (xy 329.975532 -230.428593)
			(xy 330.023118 -230.410546) (xy 330.072982 -230.400366) (xy 330.123834 -230.398317) (xy 330.174355 -230.404451)
			(xy 330.223239 -230.418611) (xy 330.269218 -230.440428) (xy 330.311102 -230.469338) (xy 330.347806 -230.504593)
			(xy 330.378379 -230.545279) (xy 330.40203 -230.590342) (xy 330.418146 -230.638616) (xy 330.42631 -230.68885)
			(xy 330.426822 -230.714296) (xy 330.74535 -230.714296) (xy 330.74931 -230.665242) (xy 330.761087 -230.617458)
			(xy 330.780378 -230.572182) (xy 330.806681 -230.530586) (xy 330.839316 -230.493749) (xy 330.877437 -230.462624)
			(xy 330.920058 -230.438017) (xy 330.966074 -230.420565) (xy 331.014293 -230.410721) (xy 331.063468 -230.40874)
			(xy 331.112323 -230.414672) (xy 331.159594 -230.428364) (xy 331.204056 -230.449462) (xy 331.244559 -230.477418)
			(xy 331.280052 -230.51151) (xy 331.309617 -230.550854) (xy 331.332488 -230.594431) (xy 331.348072 -230.641112)
			(xy 331.355967 -230.689689) (xy 331.356462 -230.714296) (xy 331.674973 -230.714296) (xy 331.679068 -230.663568)
			(xy 331.691247 -230.614154) (xy 331.711195 -230.567334) (xy 331.738396 -230.52432) (xy 331.772144 -230.486226)
			(xy 331.811566 -230.454039) (xy 331.85564 -230.428593) (xy 331.903226 -230.410546) (xy 331.95309 -230.400366)
			(xy 332.003942 -230.398317) (xy 332.054463 -230.404451) (xy 332.103347 -230.418611) (xy 332.149326 -230.440428)
			(xy 332.19121 -230.469338) (xy 332.227914 -230.504593) (xy 332.258487 -230.545279) (xy 332.282138 -230.590342)
			(xy 332.298254 -230.638616) (xy 332.306418 -230.68885) (xy 332.306925 -230.714042) (xy 332.625204 -230.714042)
			(xy 332.629164 -230.664988) (xy 332.640941 -230.617204) (xy 332.660232 -230.571928) (xy 332.686535 -230.530332)
			(xy 332.71917 -230.493495) (xy 332.757291 -230.46237) (xy 332.799912 -230.437763) (xy 332.845928 -230.420311)
			(xy 332.894147 -230.410467) (xy 332.943322 -230.408486) (xy 332.992177 -230.414418) (xy 333.039448 -230.42811)
			(xy 333.08391 -230.449208) (xy 333.124413 -230.477164) (xy 333.159906 -230.511256) (xy 333.189471 -230.5506)
			(xy 333.212342 -230.594177) (xy 333.227926 -230.640858) (xy 333.235821 -230.689435) (xy 333.236316 -230.714042)
			(xy 333.236311 -230.714296) (xy 333.554827 -230.714296) (xy 333.558922 -230.663568) (xy 333.571101 -230.614154)
			(xy 333.591049 -230.567334) (xy 333.61825 -230.52432) (xy 333.651998 -230.486226) (xy 333.69142 -230.454039)
			(xy 333.735494 -230.428593) (xy 333.78308 -230.410546) (xy 333.832944 -230.400366) (xy 333.883796 -230.398317)
			(xy 333.934317 -230.404451) (xy 333.983201 -230.418611) (xy 334.02918 -230.440428) (xy 334.071064 -230.469338)
			(xy 334.107768 -230.504593) (xy 334.138341 -230.545279) (xy 334.161992 -230.590342) (xy 334.178108 -230.638616)
			(xy 334.186272 -230.68885) (xy 334.186784 -230.714296) (xy 334.505312 -230.714296) (xy 334.509272 -230.665242)
			(xy 334.521049 -230.617458) (xy 334.54034 -230.572182) (xy 334.566643 -230.530586) (xy 334.599278 -230.493749)
			(xy 334.637399 -230.462624) (xy 334.68002 -230.438017) (xy 334.726036 -230.420565) (xy 334.774255 -230.410721)
			(xy 334.82343 -230.40874) (xy 334.872285 -230.414672) (xy 334.919556 -230.428364) (xy 334.964018 -230.449462)
			(xy 335.004521 -230.477418) (xy 335.040014 -230.51151) (xy 335.069579 -230.550854) (xy 335.09245 -230.594431)
			(xy 335.108034 -230.641112) (xy 335.115929 -230.689689) (xy 335.116424 -230.714296) (xy 335.434935 -230.714296)
			(xy 335.43903 -230.663568) (xy 335.451209 -230.614154) (xy 335.471157 -230.567334) (xy 335.498358 -230.52432)
			(xy 335.532106 -230.486226) (xy 335.571528 -230.454039) (xy 335.615602 -230.428593) (xy 335.663188 -230.410546)
			(xy 335.713052 -230.400366) (xy 335.763904 -230.398317) (xy 335.814425 -230.404451) (xy 335.863309 -230.418611)
			(xy 335.909288 -230.440428) (xy 335.951172 -230.469338) (xy 335.987876 -230.504593) (xy 336.018449 -230.545279)
			(xy 336.0421 -230.590342) (xy 336.058216 -230.638616) (xy 336.06638 -230.68885) (xy 336.066892 -230.714296)
			(xy 336.374989 -230.714296) (xy 336.379084 -230.663568) (xy 336.391263 -230.614154) (xy 336.411211 -230.567334)
			(xy 336.438412 -230.52432) (xy 336.47216 -230.486226) (xy 336.511582 -230.454039) (xy 336.555656 -230.428593)
			(xy 336.603242 -230.410546) (xy 336.653106 -230.400366) (xy 336.703958 -230.398317) (xy 336.754479 -230.404451)
			(xy 336.803363 -230.418611) (xy 336.849342 -230.440428) (xy 336.891226 -230.469338) (xy 336.92793 -230.504593)
			(xy 336.958503 -230.545279) (xy 336.982154 -230.590342) (xy 336.99827 -230.638616) (xy 337.006434 -230.68885)
			(xy 337.006941 -230.714042) (xy 337.32522 -230.714042) (xy 337.32918 -230.664988) (xy 337.340957 -230.617204)
			(xy 337.360248 -230.571928) (xy 337.386551 -230.530332) (xy 337.419186 -230.493495) (xy 337.457307 -230.46237)
			(xy 337.499928 -230.437763) (xy 337.545944 -230.420311) (xy 337.594163 -230.410467) (xy 337.643338 -230.408486)
			(xy 337.692193 -230.414418) (xy 337.739464 -230.42811) (xy 337.783926 -230.449208) (xy 337.824429 -230.477164)
			(xy 337.859922 -230.511256) (xy 337.889487 -230.5506) (xy 337.912358 -230.594177) (xy 337.927942 -230.640858)
			(xy 337.935837 -230.689435) (xy 337.936332 -230.714042) (xy 337.936327 -230.714296) (xy 338.254843 -230.714296)
			(xy 338.258938 -230.663568) (xy 338.271117 -230.614154) (xy 338.291065 -230.567334) (xy 338.318266 -230.52432)
			(xy 338.352014 -230.486226) (xy 338.391436 -230.454039) (xy 338.43551 -230.428593) (xy 338.483096 -230.410546)
			(xy 338.53296 -230.400366) (xy 338.583812 -230.398317) (xy 338.634333 -230.404451) (xy 338.683217 -230.418611)
			(xy 338.729196 -230.440428) (xy 338.77108 -230.469338) (xy 338.807784 -230.504593) (xy 338.838357 -230.545279)
			(xy 338.862008 -230.590342) (xy 338.878124 -230.638616) (xy 338.886288 -230.68885) (xy 338.8868 -230.714296)
			(xy 339.205328 -230.714296) (xy 339.209288 -230.665242) (xy 339.221065 -230.617458) (xy 339.240356 -230.572182)
			(xy 339.266659 -230.530586) (xy 339.299294 -230.493749) (xy 339.337415 -230.462624) (xy 339.380036 -230.438017)
			(xy 339.426052 -230.420565) (xy 339.474271 -230.410721) (xy 339.523446 -230.40874) (xy 339.572301 -230.414672)
			(xy 339.619572 -230.428364) (xy 339.664034 -230.449462) (xy 339.704537 -230.477418) (xy 339.74003 -230.51151)
			(xy 339.769595 -230.550854) (xy 339.792466 -230.594431) (xy 339.80805 -230.641112) (xy 339.815945 -230.689689)
			(xy 339.81644 -230.714296) (xy 340.134951 -230.714296) (xy 340.139046 -230.663568) (xy 340.151225 -230.614154)
			(xy 340.171173 -230.567334) (xy 340.198374 -230.52432) (xy 340.232122 -230.486226) (xy 340.271544 -230.454039)
			(xy 340.315618 -230.428593) (xy 340.363204 -230.410546) (xy 340.413068 -230.400366) (xy 340.46392 -230.398317)
			(xy 340.514441 -230.404451) (xy 340.563325 -230.418611) (xy 340.609304 -230.440428) (xy 340.651188 -230.469338)
			(xy 340.687892 -230.504593) (xy 340.718465 -230.545279) (xy 340.742116 -230.590342) (xy 340.758232 -230.638616)
			(xy 340.766396 -230.68885) (xy 340.766903 -230.714042) (xy 341.085182 -230.714042) (xy 341.089142 -230.664988)
			(xy 341.100919 -230.617204) (xy 341.12021 -230.571928) (xy 341.146513 -230.530332) (xy 341.179148 -230.493495)
			(xy 341.217269 -230.46237) (xy 341.25989 -230.437763) (xy 341.305906 -230.420311) (xy 341.354125 -230.410467)
			(xy 341.4033 -230.408486) (xy 341.452155 -230.414418) (xy 341.499426 -230.42811) (xy 341.543888 -230.449208)
			(xy 341.584391 -230.477164) (xy 341.619884 -230.511256) (xy 341.649449 -230.5506) (xy 341.67232 -230.594177)
			(xy 341.687904 -230.640858) (xy 341.695799 -230.689435) (xy 341.696294 -230.714042) (xy 341.696289 -230.714296)
			(xy 342.014805 -230.714296) (xy 342.0189 -230.663568) (xy 342.031079 -230.614154) (xy 342.051027 -230.567334)
			(xy 342.078228 -230.52432) (xy 342.111976 -230.486226) (xy 342.151398 -230.454039) (xy 342.195472 -230.428593)
			(xy 342.243058 -230.410546) (xy 342.292922 -230.400366) (xy 342.343774 -230.398317) (xy 342.394295 -230.404451)
			(xy 342.443179 -230.418611) (xy 342.489158 -230.440428) (xy 342.531042 -230.469338) (xy 342.567746 -230.504593)
			(xy 342.598319 -230.545279) (xy 342.62197 -230.590342) (xy 342.638086 -230.638616) (xy 342.64625 -230.68885)
			(xy 342.646762 -230.714296) (xy 342.954859 -230.714296) (xy 342.958954 -230.663568) (xy 342.971133 -230.614154)
			(xy 342.991081 -230.567334) (xy 343.018282 -230.52432) (xy 343.05203 -230.486226) (xy 343.091452 -230.454039)
			(xy 343.135526 -230.428593) (xy 343.183112 -230.410546) (xy 343.232976 -230.400366) (xy 343.283828 -230.398317)
			(xy 343.334349 -230.404451) (xy 343.383233 -230.418611) (xy 343.429212 -230.440428) (xy 343.471096 -230.469338)
			(xy 343.5078 -230.504593) (xy 343.538373 -230.545279) (xy 343.562024 -230.590342) (xy 343.57814 -230.638616)
			(xy 343.586304 -230.68885) (xy 343.586816 -230.714296) (xy 343.586304 -230.739742) (xy 343.57814 -230.789976)
			(xy 343.562024 -230.83825) (xy 343.538373 -230.883313) (xy 343.5078 -230.923999) (xy 343.471096 -230.959254)
			(xy 343.429212 -230.988164) (xy 343.383233 -231.009981) (xy 343.334349 -231.024141) (xy 343.283828 -231.030275)
			(xy 343.232976 -231.028226) (xy 343.183112 -231.018046) (xy 343.135526 -230.999999) (xy 343.091452 -230.974553)
			(xy 343.05203 -230.942366) (xy 343.018282 -230.904272) (xy 342.991081 -230.861258) (xy 342.971133 -230.814438)
			(xy 342.958954 -230.765024) (xy 342.954859 -230.714296) (xy 342.646762 -230.714296) (xy 342.64625 -230.739742)
			(xy 342.638086 -230.789976) (xy 342.62197 -230.83825) (xy 342.598319 -230.883313) (xy 342.567746 -230.923999)
			(xy 342.531042 -230.959254) (xy 342.489158 -230.988164) (xy 342.443179 -231.009981) (xy 342.394295 -231.024141)
			(xy 342.343774 -231.030275) (xy 342.292922 -231.028226) (xy 342.243058 -231.018046) (xy 342.195472 -230.999999)
			(xy 342.151398 -230.974553) (xy 342.111976 -230.942366) (xy 342.078228 -230.904272) (xy 342.051027 -230.861258)
			(xy 342.031079 -230.814438) (xy 342.0189 -230.765024) (xy 342.014805 -230.714296) (xy 341.696289 -230.714296)
			(xy 341.695799 -230.738649) (xy 341.687904 -230.787226) (xy 341.67232 -230.833907) (xy 341.649449 -230.877484)
			(xy 341.619884 -230.916828) (xy 341.584391 -230.95092) (xy 341.543888 -230.978876) (xy 341.499426 -230.999974)
			(xy 341.452155 -231.013666) (xy 341.4033 -231.019598) (xy 341.354125 -231.017617) (xy 341.305906 -231.007773)
			(xy 341.25989 -230.990321) (xy 341.217269 -230.965714) (xy 341.179148 -230.934589) (xy 341.146513 -230.897752)
			(xy 341.12021 -230.856156) (xy 341.100919 -230.81088) (xy 341.089142 -230.763096) (xy 341.085182 -230.714042)
			(xy 340.766903 -230.714042) (xy 340.766908 -230.714296) (xy 340.766396 -230.739742) (xy 340.758232 -230.789976)
			(xy 340.742116 -230.83825) (xy 340.718465 -230.883313) (xy 340.687892 -230.923999) (xy 340.651188 -230.959254)
			(xy 340.609304 -230.988164) (xy 340.563325 -231.009981) (xy 340.514441 -231.024141) (xy 340.46392 -231.030275)
			(xy 340.413068 -231.028226) (xy 340.363204 -231.018046) (xy 340.315618 -230.999999) (xy 340.271544 -230.974553)
			(xy 340.232122 -230.942366) (xy 340.198374 -230.904272) (xy 340.171173 -230.861258) (xy 340.151225 -230.814438)
			(xy 340.139046 -230.765024) (xy 340.134951 -230.714296) (xy 339.81644 -230.714296) (xy 339.815945 -230.738903)
			(xy 339.80805 -230.78748) (xy 339.792466 -230.834161) (xy 339.769595 -230.877738) (xy 339.74003 -230.917082)
			(xy 339.704537 -230.951174) (xy 339.664034 -230.97913) (xy 339.619572 -231.000228) (xy 339.572301 -231.01392)
			(xy 339.523446 -231.019852) (xy 339.474271 -231.017871) (xy 339.426052 -231.008027) (xy 339.380036 -230.990575)
			(xy 339.337415 -230.965968) (xy 339.299294 -230.934843) (xy 339.266659 -230.898006) (xy 339.240356 -230.85641)
			(xy 339.221065 -230.811134) (xy 339.209288 -230.76335) (xy 339.205328 -230.714296) (xy 338.8868 -230.714296)
			(xy 338.886288 -230.739742) (xy 338.878124 -230.789976) (xy 338.862008 -230.83825) (xy 338.838357 -230.883313)
			(xy 338.807784 -230.923999) (xy 338.77108 -230.959254) (xy 338.729196 -230.988164) (xy 338.683217 -231.009981)
			(xy 338.634333 -231.024141) (xy 338.583812 -231.030275) (xy 338.53296 -231.028226) (xy 338.483096 -231.018046)
			(xy 338.43551 -230.999999) (xy 338.391436 -230.974553) (xy 338.352014 -230.942366) (xy 338.318266 -230.904272)
			(xy 338.291065 -230.861258) (xy 338.271117 -230.814438) (xy 338.258938 -230.765024) (xy 338.254843 -230.714296)
			(xy 337.936327 -230.714296) (xy 337.935837 -230.738649) (xy 337.927942 -230.787226) (xy 337.912358 -230.833907)
			(xy 337.889487 -230.877484) (xy 337.859922 -230.916828) (xy 337.824429 -230.95092) (xy 337.783926 -230.978876)
			(xy 337.739464 -230.999974) (xy 337.692193 -231.013666) (xy 337.643338 -231.019598) (xy 337.594163 -231.017617)
			(xy 337.545944 -231.007773) (xy 337.499928 -230.990321) (xy 337.457307 -230.965714) (xy 337.419186 -230.934589)
			(xy 337.386551 -230.897752) (xy 337.360248 -230.856156) (xy 337.340957 -230.81088) (xy 337.32918 -230.763096)
			(xy 337.32522 -230.714042) (xy 337.006941 -230.714042) (xy 337.006946 -230.714296) (xy 337.006434 -230.739742)
			(xy 336.99827 -230.789976) (xy 336.982154 -230.83825) (xy 336.958503 -230.883313) (xy 336.92793 -230.923999)
			(xy 336.891226 -230.959254) (xy 336.849342 -230.988164) (xy 336.803363 -231.009981) (xy 336.754479 -231.024141)
			(xy 336.703958 -231.030275) (xy 336.653106 -231.028226) (xy 336.603242 -231.018046) (xy 336.555656 -230.999999)
			(xy 336.511582 -230.974553) (xy 336.47216 -230.942366) (xy 336.438412 -230.904272) (xy 336.411211 -230.861258)
			(xy 336.391263 -230.814438) (xy 336.379084 -230.765024) (xy 336.374989 -230.714296) (xy 336.066892 -230.714296)
			(xy 336.06638 -230.739742) (xy 336.058216 -230.789976) (xy 336.0421 -230.83825) (xy 336.018449 -230.883313)
			(xy 335.987876 -230.923999) (xy 335.951172 -230.959254) (xy 335.909288 -230.988164) (xy 335.863309 -231.009981)
			(xy 335.814425 -231.024141) (xy 335.763904 -231.030275) (xy 335.713052 -231.028226) (xy 335.663188 -231.018046)
			(xy 335.615602 -230.999999) (xy 335.571528 -230.974553) (xy 335.532106 -230.942366) (xy 335.498358 -230.904272)
			(xy 335.471157 -230.861258) (xy 335.451209 -230.814438) (xy 335.43903 -230.765024) (xy 335.434935 -230.714296)
			(xy 335.116424 -230.714296) (xy 335.115929 -230.738903) (xy 335.108034 -230.78748) (xy 335.09245 -230.834161)
			(xy 335.069579 -230.877738) (xy 335.040014 -230.917082) (xy 335.004521 -230.951174) (xy 334.964018 -230.97913)
			(xy 334.919556 -231.000228) (xy 334.872285 -231.01392) (xy 334.82343 -231.019852) (xy 334.774255 -231.017871)
			(xy 334.726036 -231.008027) (xy 334.68002 -230.990575) (xy 334.637399 -230.965968) (xy 334.599278 -230.934843)
			(xy 334.566643 -230.898006) (xy 334.54034 -230.85641) (xy 334.521049 -230.811134) (xy 334.509272 -230.76335)
			(xy 334.505312 -230.714296) (xy 334.186784 -230.714296) (xy 334.186272 -230.739742) (xy 334.178108 -230.789976)
			(xy 334.161992 -230.83825) (xy 334.138341 -230.883313) (xy 334.107768 -230.923999) (xy 334.071064 -230.959254)
			(xy 334.02918 -230.988164) (xy 333.983201 -231.009981) (xy 333.934317 -231.024141) (xy 333.883796 -231.030275)
			(xy 333.832944 -231.028226) (xy 333.78308 -231.018046) (xy 333.735494 -230.999999) (xy 333.69142 -230.974553)
			(xy 333.651998 -230.942366) (xy 333.61825 -230.904272) (xy 333.591049 -230.861258) (xy 333.571101 -230.814438)
			(xy 333.558922 -230.765024) (xy 333.554827 -230.714296) (xy 333.236311 -230.714296) (xy 333.235821 -230.738649)
			(xy 333.227926 -230.787226) (xy 333.212342 -230.833907) (xy 333.189471 -230.877484) (xy 333.159906 -230.916828)
			(xy 333.124413 -230.95092) (xy 333.08391 -230.978876) (xy 333.039448 -230.999974) (xy 332.992177 -231.013666)
			(xy 332.943322 -231.019598) (xy 332.894147 -231.017617) (xy 332.845928 -231.007773) (xy 332.799912 -230.990321)
			(xy 332.757291 -230.965714) (xy 332.71917 -230.934589) (xy 332.686535 -230.897752) (xy 332.660232 -230.856156)
			(xy 332.640941 -230.81088) (xy 332.629164 -230.763096) (xy 332.625204 -230.714042) (xy 332.306925 -230.714042)
			(xy 332.30693 -230.714296) (xy 332.306418 -230.739742) (xy 332.298254 -230.789976) (xy 332.282138 -230.83825)
			(xy 332.258487 -230.883313) (xy 332.227914 -230.923999) (xy 332.19121 -230.959254) (xy 332.149326 -230.988164)
			(xy 332.103347 -231.009981) (xy 332.054463 -231.024141) (xy 332.003942 -231.030275) (xy 331.95309 -231.028226)
			(xy 331.903226 -231.018046) (xy 331.85564 -230.999999) (xy 331.811566 -230.974553) (xy 331.772144 -230.942366)
			(xy 331.738396 -230.904272) (xy 331.711195 -230.861258) (xy 331.691247 -230.814438) (xy 331.679068 -230.765024)
			(xy 331.674973 -230.714296) (xy 331.356462 -230.714296) (xy 331.355967 -230.738903) (xy 331.348072 -230.78748)
			(xy 331.332488 -230.834161) (xy 331.309617 -230.877738) (xy 331.280052 -230.917082) (xy 331.244559 -230.951174)
			(xy 331.204056 -230.97913) (xy 331.159594 -231.000228) (xy 331.112323 -231.01392) (xy 331.063468 -231.019852)
			(xy 331.014293 -231.017871) (xy 330.966074 -231.008027) (xy 330.920058 -230.990575) (xy 330.877437 -230.965968)
			(xy 330.839316 -230.934843) (xy 330.806681 -230.898006) (xy 330.780378 -230.85641) (xy 330.761087 -230.811134)
			(xy 330.74931 -230.76335) (xy 330.74535 -230.714296) (xy 330.426822 -230.714296) (xy 330.42631 -230.739742)
			(xy 330.418146 -230.789976) (xy 330.40203 -230.83825) (xy 330.378379 -230.883313) (xy 330.347806 -230.923999)
			(xy 330.311102 -230.959254) (xy 330.269218 -230.988164) (xy 330.223239 -231.009981) (xy 330.174355 -231.024141)
			(xy 330.123834 -231.030275) (xy 330.072982 -231.028226) (xy 330.023118 -231.018046) (xy 329.975532 -230.999999)
			(xy 329.931458 -230.974553) (xy 329.892036 -230.942366) (xy 329.858288 -230.904272) (xy 329.831087 -230.861258)
			(xy 329.811139 -230.814438) (xy 329.79896 -230.765024) (xy 329.794865 -230.714296) (xy 329.486768 -230.714296)
			(xy 329.486256 -230.739742) (xy 329.478092 -230.789976) (xy 329.461976 -230.83825) (xy 329.438325 -230.883313)
			(xy 329.407752 -230.923999) (xy 329.371048 -230.959254) (xy 329.329164 -230.988164) (xy 329.283185 -231.009981)
			(xy 329.234301 -231.024141) (xy 329.18378 -231.030275) (xy 329.132928 -231.028226) (xy 329.083064 -231.018046)
			(xy 329.035478 -230.999999) (xy 328.991404 -230.974553) (xy 328.951982 -230.942366) (xy 328.918234 -230.904272)
			(xy 328.891033 -230.861258) (xy 328.871085 -230.814438) (xy 328.858906 -230.765024) (xy 328.854811 -230.714296)
			(xy 328.536554 -230.714296) (xy 328.536059 -230.738903) (xy 328.528164 -230.78748) (xy 328.51258 -230.834161)
			(xy 328.489709 -230.877738) (xy 328.460144 -230.917082) (xy 328.424651 -230.951174) (xy 328.384148 -230.97913)
			(xy 328.339686 -231.000228) (xy 328.292415 -231.01392) (xy 328.24356 -231.019852) (xy 328.194385 -231.017871)
			(xy 328.146166 -231.008027) (xy 328.10015 -230.990575) (xy 328.057529 -230.965968) (xy 328.019408 -230.934843)
			(xy 327.986773 -230.898006) (xy 327.96047 -230.85641) (xy 327.941179 -230.811134) (xy 327.929402 -230.76335)
			(xy 327.925442 -230.714296) (xy 326.656446 -230.714296) (xy 326.655951 -230.738903) (xy 326.648056 -230.78748)
			(xy 326.632472 -230.834161) (xy 326.609601 -230.877738) (xy 326.580036 -230.917082) (xy 326.544543 -230.951174)
			(xy 326.50404 -230.97913) (xy 326.459578 -231.000228) (xy 326.412307 -231.01392) (xy 326.363452 -231.019852)
			(xy 326.314277 -231.017871) (xy 326.266058 -231.008027) (xy 326.220042 -230.990575) (xy 326.177421 -230.965968)
			(xy 326.1393 -230.934843) (xy 326.106665 -230.898006) (xy 326.080362 -230.85641) (xy 326.061071 -230.811134)
			(xy 326.049294 -230.76335) (xy 326.045334 -230.714296) (xy 310.45912 -230.714296) (xy 310.45912 -231.789986)
			(xy 324.447166 -231.789986) (xy 324.451126 -231.740932) (xy 324.462903 -231.693148) (xy 324.482194 -231.647872)
			(xy 324.508497 -231.606276) (xy 324.541132 -231.569439) (xy 324.579253 -231.538314) (xy 324.621874 -231.513707)
			(xy 324.66789 -231.496255) (xy 324.716109 -231.486411) (xy 324.765284 -231.48443) (xy 324.814139 -231.490362)
			(xy 324.86141 -231.504054) (xy 324.903545 -231.524048) (xy 327.455288 -231.524048) (xy 327.459248 -231.474994)
			(xy 327.471025 -231.42721) (xy 327.490316 -231.381934) (xy 327.516619 -231.340338) (xy 327.549254 -231.303501)
			(xy 327.587375 -231.272376) (xy 327.629996 -231.247769) (xy 327.676012 -231.230317) (xy 327.724231 -231.220473)
			(xy 327.773406 -231.218492) (xy 327.822261 -231.224424) (xy 327.869532 -231.238116) (xy 327.913994 -231.259214)
			(xy 327.954497 -231.28717) (xy 327.98999 -231.321262) (xy 328.019555 -231.360606) (xy 328.042426 -231.404183)
			(xy 328.05801 -231.450864) (xy 328.065905 -231.499441) (xy 328.0664 -231.524048) (xy 328.384911 -231.524048)
			(xy 328.389006 -231.47332) (xy 328.401185 -231.423906) (xy 328.421133 -231.377086) (xy 328.448334 -231.334072)
			(xy 328.482082 -231.295978) (xy 328.521504 -231.263791) (xy 328.565578 -231.238345) (xy 328.613164 -231.220298)
			(xy 328.663028 -231.210118) (xy 328.71388 -231.208069) (xy 328.764401 -231.214203) (xy 328.813285 -231.228363)
			(xy 328.859264 -231.25018) (xy 328.901148 -231.27909) (xy 328.937852 -231.314345) (xy 328.968425 -231.355031)
			(xy 328.992076 -231.400094) (xy 329.008192 -231.448368) (xy 329.016356 -231.498602) (xy 329.016868 -231.524048)
			(xy 329.335396 -231.524048) (xy 329.339356 -231.474994) (xy 329.351133 -231.42721) (xy 329.370424 -231.381934)
			(xy 329.396727 -231.340338) (xy 329.429362 -231.303501) (xy 329.467483 -231.272376) (xy 329.510104 -231.247769)
			(xy 329.55612 -231.230317) (xy 329.604339 -231.220473) (xy 329.653514 -231.218492) (xy 329.702369 -231.224424)
			(xy 329.74964 -231.238116) (xy 329.794102 -231.259214) (xy 329.834605 -231.28717) (xy 329.870098 -231.321262)
			(xy 329.899663 -231.360606) (xy 329.922534 -231.404183) (xy 329.938118 -231.450864) (xy 329.946013 -231.499441)
			(xy 329.946508 -231.524048) (xy 330.264765 -231.524048) (xy 330.26886 -231.47332) (xy 330.281039 -231.423906)
			(xy 330.300987 -231.377086) (xy 330.328188 -231.334072) (xy 330.361936 -231.295978) (xy 330.401358 -231.263791)
			(xy 330.445432 -231.238345) (xy 330.493018 -231.220298) (xy 330.542882 -231.210118) (xy 330.593734 -231.208069)
			(xy 330.644255 -231.214203) (xy 330.693139 -231.228363) (xy 330.739118 -231.25018) (xy 330.781002 -231.27909)
			(xy 330.817706 -231.314345) (xy 330.848279 -231.355031) (xy 330.87193 -231.400094) (xy 330.888046 -231.448368)
			(xy 330.89621 -231.498602) (xy 330.896722 -231.524048) (xy 331.21525 -231.524048) (xy 331.21921 -231.474994)
			(xy 331.230987 -231.42721) (xy 331.250278 -231.381934) (xy 331.276581 -231.340338) (xy 331.309216 -231.303501)
			(xy 331.347337 -231.272376) (xy 331.389958 -231.247769) (xy 331.435974 -231.230317) (xy 331.484193 -231.220473)
			(xy 331.533368 -231.218492) (xy 331.582223 -231.224424) (xy 331.629494 -231.238116) (xy 331.673956 -231.259214)
			(xy 331.714459 -231.28717) (xy 331.749952 -231.321262) (xy 331.779517 -231.360606) (xy 331.802388 -231.404183)
			(xy 331.817972 -231.450864) (xy 331.825867 -231.499441) (xy 331.826362 -231.524048) (xy 332.144873 -231.524048)
			(xy 332.148968 -231.47332) (xy 332.161147 -231.423906) (xy 332.181095 -231.377086) (xy 332.208296 -231.334072)
			(xy 332.242044 -231.295978) (xy 332.281466 -231.263791) (xy 332.32554 -231.238345) (xy 332.373126 -231.220298)
			(xy 332.42299 -231.210118) (xy 332.473842 -231.208069) (xy 332.524363 -231.214203) (xy 332.573247 -231.228363)
			(xy 332.619226 -231.25018) (xy 332.66111 -231.27909) (xy 332.697814 -231.314345) (xy 332.728387 -231.355031)
			(xy 332.752038 -231.400094) (xy 332.768154 -231.448368) (xy 332.776318 -231.498602) (xy 332.77683 -231.524048)
			(xy 333.084927 -231.524048) (xy 333.089022 -231.47332) (xy 333.101201 -231.423906) (xy 333.121149 -231.377086)
			(xy 333.14835 -231.334072) (xy 333.182098 -231.295978) (xy 333.22152 -231.263791) (xy 333.265594 -231.238345)
			(xy 333.31318 -231.220298) (xy 333.363044 -231.210118) (xy 333.413896 -231.208069) (xy 333.464417 -231.214203)
			(xy 333.513301 -231.228363) (xy 333.55928 -231.25018) (xy 333.601164 -231.27909) (xy 333.637868 -231.314345)
			(xy 333.668441 -231.355031) (xy 333.692092 -231.400094) (xy 333.708208 -231.448368) (xy 333.716372 -231.498602)
			(xy 333.716884 -231.524048) (xy 334.035412 -231.524048) (xy 334.039372 -231.474994) (xy 334.051149 -231.42721)
			(xy 334.07044 -231.381934) (xy 334.096743 -231.340338) (xy 334.129378 -231.303501) (xy 334.167499 -231.272376)
			(xy 334.21012 -231.247769) (xy 334.256136 -231.230317) (xy 334.304355 -231.220473) (xy 334.35353 -231.218492)
			(xy 334.402385 -231.224424) (xy 334.449656 -231.238116) (xy 334.494118 -231.259214) (xy 334.534621 -231.28717)
			(xy 334.570114 -231.321262) (xy 334.599679 -231.360606) (xy 334.62255 -231.404183) (xy 334.638134 -231.450864)
			(xy 334.646029 -231.499441) (xy 334.646524 -231.524048) (xy 334.964781 -231.524048) (xy 334.968876 -231.47332)
			(xy 334.981055 -231.423906) (xy 335.001003 -231.377086) (xy 335.028204 -231.334072) (xy 335.061952 -231.295978)
			(xy 335.101374 -231.263791) (xy 335.145448 -231.238345) (xy 335.193034 -231.220298) (xy 335.242898 -231.210118)
			(xy 335.29375 -231.208069) (xy 335.344271 -231.214203) (xy 335.393155 -231.228363) (xy 335.439134 -231.25018)
			(xy 335.481018 -231.27909) (xy 335.517722 -231.314345) (xy 335.548295 -231.355031) (xy 335.571946 -231.400094)
			(xy 335.588062 -231.448368) (xy 335.596226 -231.498602) (xy 335.596738 -231.524048) (xy 335.915266 -231.524048)
			(xy 335.919226 -231.474994) (xy 335.931003 -231.42721) (xy 335.950294 -231.381934) (xy 335.976597 -231.340338)
			(xy 336.009232 -231.303501) (xy 336.047353 -231.272376) (xy 336.089974 -231.247769) (xy 336.13599 -231.230317)
			(xy 336.184209 -231.220473) (xy 336.233384 -231.218492) (xy 336.282239 -231.224424) (xy 336.32951 -231.238116)
			(xy 336.373972 -231.259214) (xy 336.414475 -231.28717) (xy 336.449968 -231.321262) (xy 336.479533 -231.360606)
			(xy 336.502404 -231.404183) (xy 336.517988 -231.450864) (xy 336.525883 -231.499441) (xy 336.526378 -231.524048)
			(xy 336.844889 -231.524048) (xy 336.848984 -231.47332) (xy 336.861163 -231.423906) (xy 336.881111 -231.377086)
			(xy 336.908312 -231.334072) (xy 336.94206 -231.295978) (xy 336.981482 -231.263791) (xy 337.025556 -231.238345)
			(xy 337.073142 -231.220298) (xy 337.123006 -231.210118) (xy 337.173858 -231.208069) (xy 337.224379 -231.214203)
			(xy 337.273263 -231.228363) (xy 337.319242 -231.25018) (xy 337.361126 -231.27909) (xy 337.39783 -231.314345)
			(xy 337.428403 -231.355031) (xy 337.452054 -231.400094) (xy 337.46817 -231.448368) (xy 337.476334 -231.498602)
			(xy 337.476846 -231.524048) (xy 337.795374 -231.524048) (xy 337.799334 -231.474994) (xy 337.811111 -231.42721)
			(xy 337.830402 -231.381934) (xy 337.856705 -231.340338) (xy 337.88934 -231.303501) (xy 337.927461 -231.272376)
			(xy 337.970082 -231.247769) (xy 338.016098 -231.230317) (xy 338.064317 -231.220473) (xy 338.113492 -231.218492)
			(xy 338.162347 -231.224424) (xy 338.209618 -231.238116) (xy 338.25408 -231.259214) (xy 338.294583 -231.28717)
			(xy 338.330076 -231.321262) (xy 338.359641 -231.360606) (xy 338.382512 -231.404183) (xy 338.398096 -231.450864)
			(xy 338.405991 -231.499441) (xy 338.406486 -231.524048) (xy 338.724743 -231.524048) (xy 338.728838 -231.47332)
			(xy 338.741017 -231.423906) (xy 338.760965 -231.377086) (xy 338.788166 -231.334072) (xy 338.821914 -231.295978)
			(xy 338.861336 -231.263791) (xy 338.90541 -231.238345) (xy 338.952996 -231.220298) (xy 339.00286 -231.210118)
			(xy 339.053712 -231.208069) (xy 339.104233 -231.214203) (xy 339.153117 -231.228363) (xy 339.199096 -231.25018)
			(xy 339.24098 -231.27909) (xy 339.277684 -231.314345) (xy 339.308257 -231.355031) (xy 339.331908 -231.400094)
			(xy 339.348024 -231.448368) (xy 339.356188 -231.498602) (xy 339.3567 -231.524048) (xy 339.664797 -231.524048)
			(xy 339.668892 -231.47332) (xy 339.681071 -231.423906) (xy 339.701019 -231.377086) (xy 339.72822 -231.334072)
			(xy 339.761968 -231.295978) (xy 339.80139 -231.263791) (xy 339.845464 -231.238345) (xy 339.89305 -231.220298)
			(xy 339.942914 -231.210118) (xy 339.993766 -231.208069) (xy 340.044287 -231.214203) (xy 340.093171 -231.228363)
			(xy 340.13915 -231.25018) (xy 340.181034 -231.27909) (xy 340.217738 -231.314345) (xy 340.248311 -231.355031)
			(xy 340.271962 -231.400094) (xy 340.288078 -231.448368) (xy 340.296242 -231.498602) (xy 340.296754 -231.524048)
			(xy 340.615282 -231.524048) (xy 340.619242 -231.474994) (xy 340.631019 -231.42721) (xy 340.65031 -231.381934)
			(xy 340.676613 -231.340338) (xy 340.709248 -231.303501) (xy 340.747369 -231.272376) (xy 340.78999 -231.247769)
			(xy 340.836006 -231.230317) (xy 340.884225 -231.220473) (xy 340.9334 -231.218492) (xy 340.982255 -231.224424)
			(xy 341.029526 -231.238116) (xy 341.073988 -231.259214) (xy 341.114491 -231.28717) (xy 341.149984 -231.321262)
			(xy 341.179549 -231.360606) (xy 341.20242 -231.404183) (xy 341.218004 -231.450864) (xy 341.225899 -231.499441)
			(xy 341.226394 -231.524048) (xy 341.544905 -231.524048) (xy 341.549 -231.47332) (xy 341.561179 -231.423906)
			(xy 341.581127 -231.377086) (xy 341.608328 -231.334072) (xy 341.642076 -231.295978) (xy 341.681498 -231.263791)
			(xy 341.725572 -231.238345) (xy 341.773158 -231.220298) (xy 341.823022 -231.210118) (xy 341.873874 -231.208069)
			(xy 341.924395 -231.214203) (xy 341.973279 -231.228363) (xy 342.019258 -231.25018) (xy 342.061142 -231.27909)
			(xy 342.097846 -231.314345) (xy 342.128419 -231.355031) (xy 342.15207 -231.400094) (xy 342.168186 -231.448368)
			(xy 342.17635 -231.498602) (xy 342.176862 -231.524048) (xy 342.49539 -231.524048) (xy 342.49935 -231.474994)
			(xy 342.511127 -231.42721) (xy 342.530418 -231.381934) (xy 342.556721 -231.340338) (xy 342.589356 -231.303501)
			(xy 342.627477 -231.272376) (xy 342.670098 -231.247769) (xy 342.716114 -231.230317) (xy 342.764333 -231.220473)
			(xy 342.813508 -231.218492) (xy 342.862363 -231.224424) (xy 342.909634 -231.238116) (xy 342.954096 -231.259214)
			(xy 342.994599 -231.28717) (xy 343.030092 -231.321262) (xy 343.059657 -231.360606) (xy 343.082528 -231.404183)
			(xy 343.098112 -231.450864) (xy 343.106007 -231.499441) (xy 343.106502 -231.524048) (xy 343.106007 -231.548655)
			(xy 343.098112 -231.597232) (xy 343.082528 -231.643913) (xy 343.059657 -231.68749) (xy 343.030092 -231.726834)
			(xy 342.994599 -231.760926) (xy 342.954096 -231.788882) (xy 342.909634 -231.80998) (xy 342.862363 -231.823672)
			(xy 342.813508 -231.829604) (xy 342.764333 -231.827623) (xy 342.716114 -231.817779) (xy 342.670098 -231.800327)
			(xy 342.627477 -231.77572) (xy 342.589356 -231.744595) (xy 342.556721 -231.707758) (xy 342.530418 -231.666162)
			(xy 342.511127 -231.620886) (xy 342.49935 -231.573102) (xy 342.49539 -231.524048) (xy 342.176862 -231.524048)
			(xy 342.17635 -231.549494) (xy 342.168186 -231.599728) (xy 342.15207 -231.648002) (xy 342.128419 -231.693065)
			(xy 342.097846 -231.733751) (xy 342.061142 -231.769006) (xy 342.019258 -231.797916) (xy 341.973279 -231.819733)
			(xy 341.924395 -231.833893) (xy 341.873874 -231.840027) (xy 341.823022 -231.837978) (xy 341.773158 -231.827798)
			(xy 341.725572 -231.809751) (xy 341.681498 -231.784305) (xy 341.642076 -231.752118) (xy 341.608328 -231.714024)
			(xy 341.581127 -231.67101) (xy 341.561179 -231.62419) (xy 341.549 -231.574776) (xy 341.544905 -231.524048)
			(xy 341.226394 -231.524048) (xy 341.225899 -231.548655) (xy 341.218004 -231.597232) (xy 341.20242 -231.643913)
			(xy 341.179549 -231.68749) (xy 341.149984 -231.726834) (xy 341.114491 -231.760926) (xy 341.073988 -231.788882)
			(xy 341.029526 -231.80998) (xy 340.982255 -231.823672) (xy 340.9334 -231.829604) (xy 340.884225 -231.827623)
			(xy 340.836006 -231.817779) (xy 340.78999 -231.800327) (xy 340.747369 -231.77572) (xy 340.709248 -231.744595)
			(xy 340.676613 -231.707758) (xy 340.65031 -231.666162) (xy 340.631019 -231.620886) (xy 340.619242 -231.573102)
			(xy 340.615282 -231.524048) (xy 340.296754 -231.524048) (xy 340.296242 -231.549494) (xy 340.288078 -231.599728)
			(xy 340.271962 -231.648002) (xy 340.248311 -231.693065) (xy 340.217738 -231.733751) (xy 340.181034 -231.769006)
			(xy 340.13915 -231.797916) (xy 340.093171 -231.819733) (xy 340.044287 -231.833893) (xy 339.993766 -231.840027)
			(xy 339.942914 -231.837978) (xy 339.89305 -231.827798) (xy 339.845464 -231.809751) (xy 339.80139 -231.784305)
			(xy 339.761968 -231.752118) (xy 339.72822 -231.714024) (xy 339.701019 -231.67101) (xy 339.681071 -231.62419)
			(xy 339.668892 -231.574776) (xy 339.664797 -231.524048) (xy 339.3567 -231.524048) (xy 339.356188 -231.549494)
			(xy 339.348024 -231.599728) (xy 339.331908 -231.648002) (xy 339.308257 -231.693065) (xy 339.277684 -231.733751)
			(xy 339.24098 -231.769006) (xy 339.199096 -231.797916) (xy 339.153117 -231.819733) (xy 339.104233 -231.833893)
			(xy 339.053712 -231.840027) (xy 339.00286 -231.837978) (xy 338.952996 -231.827798) (xy 338.90541 -231.809751)
			(xy 338.861336 -231.784305) (xy 338.821914 -231.752118) (xy 338.788166 -231.714024) (xy 338.760965 -231.67101)
			(xy 338.741017 -231.62419) (xy 338.728838 -231.574776) (xy 338.724743 -231.524048) (xy 338.406486 -231.524048)
			(xy 338.405991 -231.548655) (xy 338.398096 -231.597232) (xy 338.382512 -231.643913) (xy 338.359641 -231.68749)
			(xy 338.330076 -231.726834) (xy 338.294583 -231.760926) (xy 338.25408 -231.788882) (xy 338.209618 -231.80998)
			(xy 338.162347 -231.823672) (xy 338.113492 -231.829604) (xy 338.064317 -231.827623) (xy 338.016098 -231.817779)
			(xy 337.970082 -231.800327) (xy 337.927461 -231.77572) (xy 337.88934 -231.744595) (xy 337.856705 -231.707758)
			(xy 337.830402 -231.666162) (xy 337.811111 -231.620886) (xy 337.799334 -231.573102) (xy 337.795374 -231.524048)
			(xy 337.476846 -231.524048) (xy 337.476334 -231.549494) (xy 337.46817 -231.599728) (xy 337.452054 -231.648002)
			(xy 337.428403 -231.693065) (xy 337.39783 -231.733751) (xy 337.361126 -231.769006) (xy 337.319242 -231.797916)
			(xy 337.273263 -231.819733) (xy 337.224379 -231.833893) (xy 337.173858 -231.840027) (xy 337.123006 -231.837978)
			(xy 337.073142 -231.827798) (xy 337.025556 -231.809751) (xy 336.981482 -231.784305) (xy 336.94206 -231.752118)
			(xy 336.908312 -231.714024) (xy 336.881111 -231.67101) (xy 336.861163 -231.62419) (xy 336.848984 -231.574776)
			(xy 336.844889 -231.524048) (xy 336.526378 -231.524048) (xy 336.525883 -231.548655) (xy 336.517988 -231.597232)
			(xy 336.502404 -231.643913) (xy 336.479533 -231.68749) (xy 336.449968 -231.726834) (xy 336.414475 -231.760926)
			(xy 336.373972 -231.788882) (xy 336.32951 -231.80998) (xy 336.282239 -231.823672) (xy 336.233384 -231.829604)
			(xy 336.184209 -231.827623) (xy 336.13599 -231.817779) (xy 336.089974 -231.800327) (xy 336.047353 -231.77572)
			(xy 336.009232 -231.744595) (xy 335.976597 -231.707758) (xy 335.950294 -231.666162) (xy 335.931003 -231.620886)
			(xy 335.919226 -231.573102) (xy 335.915266 -231.524048) (xy 335.596738 -231.524048) (xy 335.596226 -231.549494)
			(xy 335.588062 -231.599728) (xy 335.571946 -231.648002) (xy 335.548295 -231.693065) (xy 335.517722 -231.733751)
			(xy 335.481018 -231.769006) (xy 335.439134 -231.797916) (xy 335.393155 -231.819733) (xy 335.344271 -231.833893)
			(xy 335.29375 -231.840027) (xy 335.242898 -231.837978) (xy 335.193034 -231.827798) (xy 335.145448 -231.809751)
			(xy 335.101374 -231.784305) (xy 335.061952 -231.752118) (xy 335.028204 -231.714024) (xy 335.001003 -231.67101)
			(xy 334.981055 -231.62419) (xy 334.968876 -231.574776) (xy 334.964781 -231.524048) (xy 334.646524 -231.524048)
			(xy 334.646029 -231.548655) (xy 334.638134 -231.597232) (xy 334.62255 -231.643913) (xy 334.599679 -231.68749)
			(xy 334.570114 -231.726834) (xy 334.534621 -231.760926) (xy 334.494118 -231.788882) (xy 334.449656 -231.80998)
			(xy 334.402385 -231.823672) (xy 334.35353 -231.829604) (xy 334.304355 -231.827623) (xy 334.256136 -231.817779)
			(xy 334.21012 -231.800327) (xy 334.167499 -231.77572) (xy 334.129378 -231.744595) (xy 334.096743 -231.707758)
			(xy 334.07044 -231.666162) (xy 334.051149 -231.620886) (xy 334.039372 -231.573102) (xy 334.035412 -231.524048)
			(xy 333.716884 -231.524048) (xy 333.716372 -231.549494) (xy 333.708208 -231.599728) (xy 333.692092 -231.648002)
			(xy 333.668441 -231.693065) (xy 333.637868 -231.733751) (xy 333.601164 -231.769006) (xy 333.55928 -231.797916)
			(xy 333.513301 -231.819733) (xy 333.464417 -231.833893) (xy 333.413896 -231.840027) (xy 333.363044 -231.837978)
			(xy 333.31318 -231.827798) (xy 333.265594 -231.809751) (xy 333.22152 -231.784305) (xy 333.182098 -231.752118)
			(xy 333.14835 -231.714024) (xy 333.121149 -231.67101) (xy 333.101201 -231.62419) (xy 333.089022 -231.574776)
			(xy 333.084927 -231.524048) (xy 332.77683 -231.524048) (xy 332.776318 -231.549494) (xy 332.768154 -231.599728)
			(xy 332.752038 -231.648002) (xy 332.728387 -231.693065) (xy 332.697814 -231.733751) (xy 332.66111 -231.769006)
			(xy 332.619226 -231.797916) (xy 332.573247 -231.819733) (xy 332.524363 -231.833893) (xy 332.473842 -231.840027)
			(xy 332.42299 -231.837978) (xy 332.373126 -231.827798) (xy 332.32554 -231.809751) (xy 332.281466 -231.784305)
			(xy 332.242044 -231.752118) (xy 332.208296 -231.714024) (xy 332.181095 -231.67101) (xy 332.161147 -231.62419)
			(xy 332.148968 -231.574776) (xy 332.144873 -231.524048) (xy 331.826362 -231.524048) (xy 331.825867 -231.548655)
			(xy 331.817972 -231.597232) (xy 331.802388 -231.643913) (xy 331.779517 -231.68749) (xy 331.749952 -231.726834)
			(xy 331.714459 -231.760926) (xy 331.673956 -231.788882) (xy 331.629494 -231.80998) (xy 331.582223 -231.823672)
			(xy 331.533368 -231.829604) (xy 331.484193 -231.827623) (xy 331.435974 -231.817779) (xy 331.389958 -231.800327)
			(xy 331.347337 -231.77572) (xy 331.309216 -231.744595) (xy 331.276581 -231.707758) (xy 331.250278 -231.666162)
			(xy 331.230987 -231.620886) (xy 331.21921 -231.573102) (xy 331.21525 -231.524048) (xy 330.896722 -231.524048)
			(xy 330.89621 -231.549494) (xy 330.888046 -231.599728) (xy 330.87193 -231.648002) (xy 330.848279 -231.693065)
			(xy 330.817706 -231.733751) (xy 330.781002 -231.769006) (xy 330.739118 -231.797916) (xy 330.693139 -231.819733)
			(xy 330.644255 -231.833893) (xy 330.593734 -231.840027) (xy 330.542882 -231.837978) (xy 330.493018 -231.827798)
			(xy 330.445432 -231.809751) (xy 330.401358 -231.784305) (xy 330.361936 -231.752118) (xy 330.328188 -231.714024)
			(xy 330.300987 -231.67101) (xy 330.281039 -231.62419) (xy 330.26886 -231.574776) (xy 330.264765 -231.524048)
			(xy 329.946508 -231.524048) (xy 329.946013 -231.548655) (xy 329.938118 -231.597232) (xy 329.922534 -231.643913)
			(xy 329.899663 -231.68749) (xy 329.870098 -231.726834) (xy 329.834605 -231.760926) (xy 329.794102 -231.788882)
			(xy 329.74964 -231.80998) (xy 329.702369 -231.823672) (xy 329.653514 -231.829604) (xy 329.604339 -231.827623)
			(xy 329.55612 -231.817779) (xy 329.510104 -231.800327) (xy 329.467483 -231.77572) (xy 329.429362 -231.744595)
			(xy 329.396727 -231.707758) (xy 329.370424 -231.666162) (xy 329.351133 -231.620886) (xy 329.339356 -231.573102)
			(xy 329.335396 -231.524048) (xy 329.016868 -231.524048) (xy 329.016356 -231.549494) (xy 329.008192 -231.599728)
			(xy 328.992076 -231.648002) (xy 328.968425 -231.693065) (xy 328.937852 -231.733751) (xy 328.901148 -231.769006)
			(xy 328.859264 -231.797916) (xy 328.813285 -231.819733) (xy 328.764401 -231.833893) (xy 328.71388 -231.840027)
			(xy 328.663028 -231.837978) (xy 328.613164 -231.827798) (xy 328.565578 -231.809751) (xy 328.521504 -231.784305)
			(xy 328.482082 -231.752118) (xy 328.448334 -231.714024) (xy 328.421133 -231.67101) (xy 328.401185 -231.62419)
			(xy 328.389006 -231.574776) (xy 328.384911 -231.524048) (xy 328.0664 -231.524048) (xy 328.065905 -231.548655)
			(xy 328.05801 -231.597232) (xy 328.042426 -231.643913) (xy 328.019555 -231.68749) (xy 327.98999 -231.726834)
			(xy 327.954497 -231.760926) (xy 327.913994 -231.788882) (xy 327.869532 -231.80998) (xy 327.822261 -231.823672)
			(xy 327.773406 -231.829604) (xy 327.724231 -231.827623) (xy 327.676012 -231.817779) (xy 327.629996 -231.800327)
			(xy 327.587375 -231.77572) (xy 327.549254 -231.744595) (xy 327.516619 -231.707758) (xy 327.490316 -231.666162)
			(xy 327.471025 -231.620886) (xy 327.459248 -231.573102) (xy 327.455288 -231.524048) (xy 324.903545 -231.524048)
			(xy 324.905872 -231.525152) (xy 324.946375 -231.553108) (xy 324.981868 -231.5872) (xy 325.011433 -231.626544)
			(xy 325.034304 -231.670121) (xy 325.049888 -231.716802) (xy 325.057783 -231.765379) (xy 325.058278 -231.789986)
			(xy 325.057783 -231.814593) (xy 325.049888 -231.86317) (xy 325.034304 -231.909851) (xy 325.011433 -231.953428)
			(xy 324.981868 -231.992772) (xy 324.946375 -232.026864) (xy 324.905872 -232.05482) (xy 324.86141 -232.075918)
			(xy 324.814139 -232.08961) (xy 324.765284 -232.095542) (xy 324.716109 -232.093561) (xy 324.66789 -232.083717)
			(xy 324.621874 -232.066265) (xy 324.579253 -232.041658) (xy 324.541132 -232.010533) (xy 324.508497 -231.973696)
			(xy 324.482194 -231.9321) (xy 324.462903 -231.886824) (xy 324.451126 -231.83904) (xy 324.447166 -231.789986)
			(xy 310.45912 -231.789986) (xy 310.45912 -232.334054) (xy 326.045334 -232.334054) (xy 326.049294 -232.285)
			(xy 326.061071 -232.237216) (xy 326.080362 -232.19194) (xy 326.106665 -232.150344) (xy 326.1393 -232.113507)
			(xy 326.177421 -232.082382) (xy 326.220042 -232.057775) (xy 326.266058 -232.040323) (xy 326.314277 -232.030479)
			(xy 326.363452 -232.028498) (xy 326.412307 -232.03443) (xy 326.459578 -232.048122) (xy 326.50404 -232.06922)
			(xy 326.544543 -232.097176) (xy 326.580036 -232.131268) (xy 326.609601 -232.170612) (xy 326.632472 -232.214189)
			(xy 326.648056 -232.26087) (xy 326.655951 -232.309447) (xy 326.656446 -232.334054) (xy 328.854811 -232.334054)
			(xy 328.858906 -232.283326) (xy 328.871085 -232.233912) (xy 328.891033 -232.187092) (xy 328.918234 -232.144078)
			(xy 328.951982 -232.105984) (xy 328.991404 -232.073797) (xy 329.035478 -232.048351) (xy 329.083064 -232.030304)
			(xy 329.132928 -232.020124) (xy 329.18378 -232.018075) (xy 329.234301 -232.024209) (xy 329.283185 -232.038369)
			(xy 329.329164 -232.060186) (xy 329.371048 -232.089096) (xy 329.407752 -232.124351) (xy 329.438325 -232.165037)
			(xy 329.461976 -232.2101) (xy 329.478092 -232.258374) (xy 329.486256 -232.308608) (xy 329.486768 -232.334054)
			(xy 329.794865 -232.334054) (xy 329.79896 -232.283326) (xy 329.811139 -232.233912) (xy 329.831087 -232.187092)
			(xy 329.858288 -232.144078) (xy 329.892036 -232.105984) (xy 329.931458 -232.073797) (xy 329.975532 -232.048351)
			(xy 330.023118 -232.030304) (xy 330.072982 -232.020124) (xy 330.123834 -232.018075) (xy 330.174355 -232.024209)
			(xy 330.223239 -232.038369) (xy 330.269218 -232.060186) (xy 330.311102 -232.089096) (xy 330.347806 -232.124351)
			(xy 330.378379 -232.165037) (xy 330.40203 -232.2101) (xy 330.418146 -232.258374) (xy 330.42631 -232.308608)
			(xy 330.426822 -232.334054) (xy 330.74535 -232.334054) (xy 330.74931 -232.285) (xy 330.761087 -232.237216)
			(xy 330.780378 -232.19194) (xy 330.806681 -232.150344) (xy 330.839316 -232.113507) (xy 330.877437 -232.082382)
			(xy 330.920058 -232.057775) (xy 330.966074 -232.040323) (xy 331.014293 -232.030479) (xy 331.063468 -232.028498)
			(xy 331.112323 -232.03443) (xy 331.159594 -232.048122) (xy 331.204056 -232.06922) (xy 331.244559 -232.097176)
			(xy 331.280052 -232.131268) (xy 331.309617 -232.170612) (xy 331.332488 -232.214189) (xy 331.348072 -232.26087)
			(xy 331.355967 -232.309447) (xy 331.356462 -232.334054) (xy 331.674973 -232.334054) (xy 331.679068 -232.283326)
			(xy 331.691247 -232.233912) (xy 331.711195 -232.187092) (xy 331.738396 -232.144078) (xy 331.772144 -232.105984)
			(xy 331.811566 -232.073797) (xy 331.85564 -232.048351) (xy 331.903226 -232.030304) (xy 331.95309 -232.020124)
			(xy 332.003942 -232.018075) (xy 332.054463 -232.024209) (xy 332.103347 -232.038369) (xy 332.149326 -232.060186)
			(xy 332.19121 -232.089096) (xy 332.227914 -232.124351) (xy 332.258487 -232.165037) (xy 332.282138 -232.2101)
			(xy 332.298254 -232.258374) (xy 332.306418 -232.308608) (xy 332.30693 -232.334054) (xy 332.625204 -232.334054)
			(xy 332.629164 -232.285) (xy 332.640941 -232.237216) (xy 332.660232 -232.19194) (xy 332.686535 -232.150344)
			(xy 332.71917 -232.113507) (xy 332.757291 -232.082382) (xy 332.799912 -232.057775) (xy 332.845928 -232.040323)
			(xy 332.894147 -232.030479) (xy 332.943322 -232.028498) (xy 332.992177 -232.03443) (xy 333.039448 -232.048122)
			(xy 333.08391 -232.06922) (xy 333.124413 -232.097176) (xy 333.159906 -232.131268) (xy 333.189471 -232.170612)
			(xy 333.212342 -232.214189) (xy 333.227926 -232.26087) (xy 333.235821 -232.309447) (xy 333.236316 -232.334054)
			(xy 333.554827 -232.334054) (xy 333.558922 -232.283326) (xy 333.571101 -232.233912) (xy 333.591049 -232.187092)
			(xy 333.61825 -232.144078) (xy 333.651998 -232.105984) (xy 333.69142 -232.073797) (xy 333.735494 -232.048351)
			(xy 333.78308 -232.030304) (xy 333.832944 -232.020124) (xy 333.883796 -232.018075) (xy 333.934317 -232.024209)
			(xy 333.983201 -232.038369) (xy 334.02918 -232.060186) (xy 334.071064 -232.089096) (xy 334.107768 -232.124351)
			(xy 334.138341 -232.165037) (xy 334.161992 -232.2101) (xy 334.178108 -232.258374) (xy 334.186272 -232.308608)
			(xy 334.186784 -232.334054) (xy 335.434935 -232.334054) (xy 335.43903 -232.283326) (xy 335.451209 -232.233912)
			(xy 335.471157 -232.187092) (xy 335.498358 -232.144078) (xy 335.532106 -232.105984) (xy 335.571528 -232.073797)
			(xy 335.615602 -232.048351) (xy 335.663188 -232.030304) (xy 335.713052 -232.020124) (xy 335.763904 -232.018075)
			(xy 335.814425 -232.024209) (xy 335.863309 -232.038369) (xy 335.909288 -232.060186) (xy 335.951172 -232.089096)
			(xy 335.987876 -232.124351) (xy 336.018449 -232.165037) (xy 336.0421 -232.2101) (xy 336.058216 -232.258374)
			(xy 336.06638 -232.308608) (xy 336.066892 -232.334054) (xy 336.374989 -232.334054) (xy 336.379084 -232.283326)
			(xy 336.391263 -232.233912) (xy 336.411211 -232.187092) (xy 336.438412 -232.144078) (xy 336.47216 -232.105984)
			(xy 336.511582 -232.073797) (xy 336.555656 -232.048351) (xy 336.603242 -232.030304) (xy 336.653106 -232.020124)
			(xy 336.703958 -232.018075) (xy 336.754479 -232.024209) (xy 336.803363 -232.038369) (xy 336.849342 -232.060186)
			(xy 336.891226 -232.089096) (xy 336.92793 -232.124351) (xy 336.958503 -232.165037) (xy 336.982154 -232.2101)
			(xy 336.99827 -232.258374) (xy 337.006434 -232.308608) (xy 337.006946 -232.334054) (xy 337.32522 -232.334054)
			(xy 337.32918 -232.285) (xy 337.340957 -232.237216) (xy 337.360248 -232.19194) (xy 337.386551 -232.150344)
			(xy 337.419186 -232.113507) (xy 337.457307 -232.082382) (xy 337.499928 -232.057775) (xy 337.545944 -232.040323)
			(xy 337.594163 -232.030479) (xy 337.643338 -232.028498) (xy 337.692193 -232.03443) (xy 337.739464 -232.048122)
			(xy 337.783926 -232.06922) (xy 337.824429 -232.097176) (xy 337.859922 -232.131268) (xy 337.889487 -232.170612)
			(xy 337.912358 -232.214189) (xy 337.927942 -232.26087) (xy 337.935837 -232.309447) (xy 337.936332 -232.334054)
			(xy 338.254843 -232.334054) (xy 338.258938 -232.283326) (xy 338.271117 -232.233912) (xy 338.291065 -232.187092)
			(xy 338.318266 -232.144078) (xy 338.352014 -232.105984) (xy 338.391436 -232.073797) (xy 338.43551 -232.048351)
			(xy 338.483096 -232.030304) (xy 338.53296 -232.020124) (xy 338.583812 -232.018075) (xy 338.634333 -232.024209)
			(xy 338.683217 -232.038369) (xy 338.729196 -232.060186) (xy 338.77108 -232.089096) (xy 338.807784 -232.124351)
			(xy 338.838357 -232.165037) (xy 338.862008 -232.2101) (xy 338.878124 -232.258374) (xy 338.886288 -232.308608)
			(xy 338.8868 -232.334054) (xy 339.205328 -232.334054) (xy 339.209288 -232.285) (xy 339.221065 -232.237216)
			(xy 339.240356 -232.19194) (xy 339.266659 -232.150344) (xy 339.299294 -232.113507) (xy 339.337415 -232.082382)
			(xy 339.380036 -232.057775) (xy 339.426052 -232.040323) (xy 339.474271 -232.030479) (xy 339.523446 -232.028498)
			(xy 339.572301 -232.03443) (xy 339.619572 -232.048122) (xy 339.664034 -232.06922) (xy 339.704537 -232.097176)
			(xy 339.74003 -232.131268) (xy 339.769595 -232.170612) (xy 339.792466 -232.214189) (xy 339.80805 -232.26087)
			(xy 339.815945 -232.309447) (xy 339.81644 -232.334054) (xy 340.134951 -232.334054) (xy 340.139046 -232.283326)
			(xy 340.151225 -232.233912) (xy 340.171173 -232.187092) (xy 340.198374 -232.144078) (xy 340.232122 -232.105984)
			(xy 340.271544 -232.073797) (xy 340.315618 -232.048351) (xy 340.363204 -232.030304) (xy 340.413068 -232.020124)
			(xy 340.46392 -232.018075) (xy 340.514441 -232.024209) (xy 340.563325 -232.038369) (xy 340.609304 -232.060186)
			(xy 340.651188 -232.089096) (xy 340.687892 -232.124351) (xy 340.718465 -232.165037) (xy 340.742116 -232.2101)
			(xy 340.758232 -232.258374) (xy 340.766396 -232.308608) (xy 340.766908 -232.334054) (xy 342.014805 -232.334054)
			(xy 342.0189 -232.283326) (xy 342.031079 -232.233912) (xy 342.051027 -232.187092) (xy 342.078228 -232.144078)
			(xy 342.111976 -232.105984) (xy 342.151398 -232.073797) (xy 342.195472 -232.048351) (xy 342.243058 -232.030304)
			(xy 342.292922 -232.020124) (xy 342.343774 -232.018075) (xy 342.394295 -232.024209) (xy 342.443179 -232.038369)
			(xy 342.489158 -232.060186) (xy 342.531042 -232.089096) (xy 342.567746 -232.124351) (xy 342.598319 -232.165037)
			(xy 342.62197 -232.2101) (xy 342.638086 -232.258374) (xy 342.64625 -232.308608) (xy 342.646762 -232.334054)
			(xy 342.954859 -232.334054) (xy 342.958954 -232.283326) (xy 342.971133 -232.233912) (xy 342.991081 -232.187092)
			(xy 343.018282 -232.144078) (xy 343.05203 -232.105984) (xy 343.091452 -232.073797) (xy 343.135526 -232.048351)
			(xy 343.183112 -232.030304) (xy 343.232976 -232.020124) (xy 343.283828 -232.018075) (xy 343.334349 -232.024209)
			(xy 343.383233 -232.038369) (xy 343.429212 -232.060186) (xy 343.471096 -232.089096) (xy 343.5078 -232.124351)
			(xy 343.538373 -232.165037) (xy 343.562024 -232.2101) (xy 343.57814 -232.258374) (xy 343.586304 -232.308608)
			(xy 343.586816 -232.334054) (xy 343.586304 -232.3595) (xy 343.57814 -232.409734) (xy 343.562024 -232.458008)
			(xy 343.538373 -232.503071) (xy 343.5078 -232.543757) (xy 343.471096 -232.579012) (xy 343.429212 -232.607922)
			(xy 343.383233 -232.629739) (xy 343.334349 -232.643899) (xy 343.283828 -232.650033) (xy 343.232976 -232.647984)
			(xy 343.183112 -232.637804) (xy 343.135526 -232.619757) (xy 343.091452 -232.594311) (xy 343.05203 -232.562124)
			(xy 343.018282 -232.52403) (xy 342.991081 -232.481016) (xy 342.971133 -232.434196) (xy 342.958954 -232.384782)
			(xy 342.954859 -232.334054) (xy 342.646762 -232.334054) (xy 342.64625 -232.3595) (xy 342.638086 -232.409734)
			(xy 342.62197 -232.458008) (xy 342.598319 -232.503071) (xy 342.567746 -232.543757) (xy 342.531042 -232.579012)
			(xy 342.489158 -232.607922) (xy 342.443179 -232.629739) (xy 342.394295 -232.643899) (xy 342.343774 -232.650033)
			(xy 342.292922 -232.647984) (xy 342.243058 -232.637804) (xy 342.195472 -232.619757) (xy 342.151398 -232.594311)
			(xy 342.111976 -232.562124) (xy 342.078228 -232.52403) (xy 342.051027 -232.481016) (xy 342.031079 -232.434196)
			(xy 342.0189 -232.384782) (xy 342.014805 -232.334054) (xy 340.766908 -232.334054) (xy 340.766396 -232.3595)
			(xy 340.758232 -232.409734) (xy 340.742116 -232.458008) (xy 340.718465 -232.503071) (xy 340.687892 -232.543757)
			(xy 340.651188 -232.579012) (xy 340.609304 -232.607922) (xy 340.563325 -232.629739) (xy 340.514441 -232.643899)
			(xy 340.46392 -232.650033) (xy 340.413068 -232.647984) (xy 340.363204 -232.637804) (xy 340.315618 -232.619757)
			(xy 340.271544 -232.594311) (xy 340.232122 -232.562124) (xy 340.198374 -232.52403) (xy 340.171173 -232.481016)
			(xy 340.151225 -232.434196) (xy 340.139046 -232.384782) (xy 340.134951 -232.334054) (xy 339.81644 -232.334054)
			(xy 339.815945 -232.358661) (xy 339.80805 -232.407238) (xy 339.792466 -232.453919) (xy 339.769595 -232.497496)
			(xy 339.74003 -232.53684) (xy 339.704537 -232.570932) (xy 339.664034 -232.598888) (xy 339.619572 -232.619986)
			(xy 339.572301 -232.633678) (xy 339.523446 -232.63961) (xy 339.474271 -232.637629) (xy 339.426052 -232.627785)
			(xy 339.380036 -232.610333) (xy 339.337415 -232.585726) (xy 339.299294 -232.554601) (xy 339.266659 -232.517764)
			(xy 339.240356 -232.476168) (xy 339.221065 -232.430892) (xy 339.209288 -232.383108) (xy 339.205328 -232.334054)
			(xy 338.8868 -232.334054) (xy 338.886288 -232.3595) (xy 338.878124 -232.409734) (xy 338.862008 -232.458008)
			(xy 338.838357 -232.503071) (xy 338.807784 -232.543757) (xy 338.77108 -232.579012) (xy 338.729196 -232.607922)
			(xy 338.683217 -232.629739) (xy 338.634333 -232.643899) (xy 338.583812 -232.650033) (xy 338.53296 -232.647984)
			(xy 338.483096 -232.637804) (xy 338.43551 -232.619757) (xy 338.391436 -232.594311) (xy 338.352014 -232.562124)
			(xy 338.318266 -232.52403) (xy 338.291065 -232.481016) (xy 338.271117 -232.434196) (xy 338.258938 -232.384782)
			(xy 338.254843 -232.334054) (xy 337.936332 -232.334054) (xy 337.935837 -232.358661) (xy 337.927942 -232.407238)
			(xy 337.912358 -232.453919) (xy 337.889487 -232.497496) (xy 337.859922 -232.53684) (xy 337.824429 -232.570932)
			(xy 337.783926 -232.598888) (xy 337.739464 -232.619986) (xy 337.692193 -232.633678) (xy 337.643338 -232.63961)
			(xy 337.594163 -232.637629) (xy 337.545944 -232.627785) (xy 337.499928 -232.610333) (xy 337.457307 -232.585726)
			(xy 337.419186 -232.554601) (xy 337.386551 -232.517764) (xy 337.360248 -232.476168) (xy 337.340957 -232.430892)
			(xy 337.32918 -232.383108) (xy 337.32522 -232.334054) (xy 337.006946 -232.334054) (xy 337.006434 -232.3595)
			(xy 336.99827 -232.409734) (xy 336.982154 -232.458008) (xy 336.958503 -232.503071) (xy 336.92793 -232.543757)
			(xy 336.891226 -232.579012) (xy 336.849342 -232.607922) (xy 336.803363 -232.629739) (xy 336.754479 -232.643899)
			(xy 336.703958 -232.650033) (xy 336.653106 -232.647984) (xy 336.603242 -232.637804) (xy 336.555656 -232.619757)
			(xy 336.511582 -232.594311) (xy 336.47216 -232.562124) (xy 336.438412 -232.52403) (xy 336.411211 -232.481016)
			(xy 336.391263 -232.434196) (xy 336.379084 -232.384782) (xy 336.374989 -232.334054) (xy 336.066892 -232.334054)
			(xy 336.06638 -232.3595) (xy 336.058216 -232.409734) (xy 336.0421 -232.458008) (xy 336.018449 -232.503071)
			(xy 335.987876 -232.543757) (xy 335.951172 -232.579012) (xy 335.909288 -232.607922) (xy 335.863309 -232.629739)
			(xy 335.814425 -232.643899) (xy 335.763904 -232.650033) (xy 335.713052 -232.647984) (xy 335.663188 -232.637804)
			(xy 335.615602 -232.619757) (xy 335.571528 -232.594311) (xy 335.532106 -232.562124) (xy 335.498358 -232.52403)
			(xy 335.471157 -232.481016) (xy 335.451209 -232.434196) (xy 335.43903 -232.384782) (xy 335.434935 -232.334054)
			(xy 334.186784 -232.334054) (xy 334.186272 -232.3595) (xy 334.178108 -232.409734) (xy 334.161992 -232.458008)
			(xy 334.138341 -232.503071) (xy 334.107768 -232.543757) (xy 334.071064 -232.579012) (xy 334.02918 -232.607922)
			(xy 333.983201 -232.629739) (xy 333.934317 -232.643899) (xy 333.883796 -232.650033) (xy 333.832944 -232.647984)
			(xy 333.78308 -232.637804) (xy 333.735494 -232.619757) (xy 333.69142 -232.594311) (xy 333.651998 -232.562124)
			(xy 333.61825 -232.52403) (xy 333.591049 -232.481016) (xy 333.571101 -232.434196) (xy 333.558922 -232.384782)
			(xy 333.554827 -232.334054) (xy 333.236316 -232.334054) (xy 333.235821 -232.358661) (xy 333.227926 -232.407238)
			(xy 333.212342 -232.453919) (xy 333.189471 -232.497496) (xy 333.159906 -232.53684) (xy 333.124413 -232.570932)
			(xy 333.08391 -232.598888) (xy 333.039448 -232.619986) (xy 332.992177 -232.633678) (xy 332.943322 -232.63961)
			(xy 332.894147 -232.637629) (xy 332.845928 -232.627785) (xy 332.799912 -232.610333) (xy 332.757291 -232.585726)
			(xy 332.71917 -232.554601) (xy 332.686535 -232.517764) (xy 332.660232 -232.476168) (xy 332.640941 -232.430892)
			(xy 332.629164 -232.383108) (xy 332.625204 -232.334054) (xy 332.30693 -232.334054) (xy 332.306418 -232.3595)
			(xy 332.298254 -232.409734) (xy 332.282138 -232.458008) (xy 332.258487 -232.503071) (xy 332.227914 -232.543757)
			(xy 332.19121 -232.579012) (xy 332.149326 -232.607922) (xy 332.103347 -232.629739) (xy 332.054463 -232.643899)
			(xy 332.003942 -232.650033) (xy 331.95309 -232.647984) (xy 331.903226 -232.637804) (xy 331.85564 -232.619757)
			(xy 331.811566 -232.594311) (xy 331.772144 -232.562124) (xy 331.738396 -232.52403) (xy 331.711195 -232.481016)
			(xy 331.691247 -232.434196) (xy 331.679068 -232.384782) (xy 331.674973 -232.334054) (xy 331.356462 -232.334054)
			(xy 331.355967 -232.358661) (xy 331.348072 -232.407238) (xy 331.332488 -232.453919) (xy 331.309617 -232.497496)
			(xy 331.280052 -232.53684) (xy 331.244559 -232.570932) (xy 331.204056 -232.598888) (xy 331.159594 -232.619986)
			(xy 331.112323 -232.633678) (xy 331.063468 -232.63961) (xy 331.014293 -232.637629) (xy 330.966074 -232.627785)
			(xy 330.920058 -232.610333) (xy 330.877437 -232.585726) (xy 330.839316 -232.554601) (xy 330.806681 -232.517764)
			(xy 330.780378 -232.476168) (xy 330.761087 -232.430892) (xy 330.74931 -232.383108) (xy 330.74535 -232.334054)
			(xy 330.426822 -232.334054) (xy 330.42631 -232.3595) (xy 330.418146 -232.409734) (xy 330.40203 -232.458008)
			(xy 330.378379 -232.503071) (xy 330.347806 -232.543757) (xy 330.311102 -232.579012) (xy 330.269218 -232.607922)
			(xy 330.223239 -232.629739) (xy 330.174355 -232.643899) (xy 330.123834 -232.650033) (xy 330.072982 -232.647984)
			(xy 330.023118 -232.637804) (xy 329.975532 -232.619757) (xy 329.931458 -232.594311) (xy 329.892036 -232.562124)
			(xy 329.858288 -232.52403) (xy 329.831087 -232.481016) (xy 329.811139 -232.434196) (xy 329.79896 -232.384782)
			(xy 329.794865 -232.334054) (xy 329.486768 -232.334054) (xy 329.486256 -232.3595) (xy 329.478092 -232.409734)
			(xy 329.461976 -232.458008) (xy 329.438325 -232.503071) (xy 329.407752 -232.543757) (xy 329.371048 -232.579012)
			(xy 329.329164 -232.607922) (xy 329.283185 -232.629739) (xy 329.234301 -232.643899) (xy 329.18378 -232.650033)
			(xy 329.132928 -232.647984) (xy 329.083064 -232.637804) (xy 329.035478 -232.619757) (xy 328.991404 -232.594311)
			(xy 328.951982 -232.562124) (xy 328.918234 -232.52403) (xy 328.891033 -232.481016) (xy 328.871085 -232.434196)
			(xy 328.858906 -232.384782) (xy 328.854811 -232.334054) (xy 326.656446 -232.334054) (xy 326.655951 -232.358661)
			(xy 326.648056 -232.407238) (xy 326.632472 -232.453919) (xy 326.609601 -232.497496) (xy 326.580036 -232.53684)
			(xy 326.544543 -232.570932) (xy 326.50404 -232.598888) (xy 326.459578 -232.619986) (xy 326.412307 -232.633678)
			(xy 326.363452 -232.63961) (xy 326.314277 -232.637629) (xy 326.266058 -232.627785) (xy 326.220042 -232.610333)
			(xy 326.177421 -232.585726) (xy 326.1393 -232.554601) (xy 326.106665 -232.517764) (xy 326.080362 -232.476168)
			(xy 326.061071 -232.430892) (xy 326.049294 -232.383108) (xy 326.045334 -232.334054) (xy 310.45912 -232.334054)
			(xy 310.45912 -233.409998) (xy 324.447166 -233.409998) (xy 324.451126 -233.360944) (xy 324.462903 -233.31316)
			(xy 324.482194 -233.267884) (xy 324.508497 -233.226288) (xy 324.541132 -233.189451) (xy 324.579253 -233.158326)
			(xy 324.621874 -233.133719) (xy 324.66789 -233.116267) (xy 324.716109 -233.106423) (xy 324.765284 -233.104442)
			(xy 324.814139 -233.110374) (xy 324.86141 -233.124066) (xy 324.903545 -233.14406) (xy 327.455288 -233.14406)
			(xy 327.459248 -233.095006) (xy 327.471025 -233.047222) (xy 327.490316 -233.001946) (xy 327.516619 -232.96035)
			(xy 327.549254 -232.923513) (xy 327.587375 -232.892388) (xy 327.629996 -232.867781) (xy 327.676012 -232.850329)
			(xy 327.724231 -232.840485) (xy 327.773406 -232.838504) (xy 327.822261 -232.844436) (xy 327.869532 -232.858128)
			(xy 327.913994 -232.879226) (xy 327.954497 -232.907182) (xy 327.98999 -232.941274) (xy 328.019555 -232.980618)
			(xy 328.042426 -233.024195) (xy 328.05801 -233.070876) (xy 328.065905 -233.119453) (xy 328.0664 -233.14406)
			(xy 328.384911 -233.14406) (xy 328.389006 -233.093332) (xy 328.401185 -233.043918) (xy 328.421133 -232.997098)
			(xy 328.448334 -232.954084) (xy 328.482082 -232.91599) (xy 328.521504 -232.883803) (xy 328.565578 -232.858357)
			(xy 328.613164 -232.84031) (xy 328.663028 -232.83013) (xy 328.71388 -232.828081) (xy 328.764401 -232.834215)
			(xy 328.813285 -232.848375) (xy 328.859264 -232.870192) (xy 328.901148 -232.899102) (xy 328.937852 -232.934357)
			(xy 328.968425 -232.975043) (xy 328.992076 -233.020106) (xy 329.008192 -233.06838) (xy 329.016356 -233.118614)
			(xy 329.016868 -233.14406) (xy 329.335396 -233.14406) (xy 329.339356 -233.095006) (xy 329.351133 -233.047222)
			(xy 329.370424 -233.001946) (xy 329.396727 -232.96035) (xy 329.429362 -232.923513) (xy 329.467483 -232.892388)
			(xy 329.510104 -232.867781) (xy 329.55612 -232.850329) (xy 329.604339 -232.840485) (xy 329.653514 -232.838504)
			(xy 329.702369 -232.844436) (xy 329.74964 -232.858128) (xy 329.794102 -232.879226) (xy 329.834605 -232.907182)
			(xy 329.870098 -232.941274) (xy 329.899663 -232.980618) (xy 329.922534 -233.024195) (xy 329.938118 -233.070876)
			(xy 329.946013 -233.119453) (xy 329.946508 -233.14406) (xy 330.264765 -233.14406) (xy 330.26886 -233.093332)
			(xy 330.281039 -233.043918) (xy 330.300987 -232.997098) (xy 330.328188 -232.954084) (xy 330.361936 -232.91599)
			(xy 330.401358 -232.883803) (xy 330.445432 -232.858357) (xy 330.493018 -232.84031) (xy 330.542882 -232.83013)
			(xy 330.593734 -232.828081) (xy 330.644255 -232.834215) (xy 330.693139 -232.848375) (xy 330.739118 -232.870192)
			(xy 330.781002 -232.899102) (xy 330.817706 -232.934357) (xy 330.848279 -232.975043) (xy 330.87193 -233.020106)
			(xy 330.888046 -233.06838) (xy 330.89621 -233.118614) (xy 330.896722 -233.14406) (xy 331.21525 -233.14406)
			(xy 331.21921 -233.095006) (xy 331.230987 -233.047222) (xy 331.250278 -233.001946) (xy 331.276581 -232.96035)
			(xy 331.309216 -232.923513) (xy 331.347337 -232.892388) (xy 331.389958 -232.867781) (xy 331.435974 -232.850329)
			(xy 331.484193 -232.840485) (xy 331.533368 -232.838504) (xy 331.582223 -232.844436) (xy 331.629494 -232.858128)
			(xy 331.673956 -232.879226) (xy 331.714459 -232.907182) (xy 331.749952 -232.941274) (xy 331.779517 -232.980618)
			(xy 331.802388 -233.024195) (xy 331.817972 -233.070876) (xy 331.825867 -233.119453) (xy 331.826362 -233.14406)
			(xy 332.144873 -233.14406) (xy 332.148968 -233.093332) (xy 332.161147 -233.043918) (xy 332.181095 -232.997098)
			(xy 332.208296 -232.954084) (xy 332.242044 -232.91599) (xy 332.281466 -232.883803) (xy 332.32554 -232.858357)
			(xy 332.373126 -232.84031) (xy 332.42299 -232.83013) (xy 332.473842 -232.828081) (xy 332.524363 -232.834215)
			(xy 332.573247 -232.848375) (xy 332.619226 -232.870192) (xy 332.66111 -232.899102) (xy 332.697814 -232.934357)
			(xy 332.728387 -232.975043) (xy 332.752038 -233.020106) (xy 332.768154 -233.06838) (xy 332.776318 -233.118614)
			(xy 332.77683 -233.14406) (xy 333.084927 -233.14406) (xy 333.089022 -233.093332) (xy 333.101201 -233.043918)
			(xy 333.121149 -232.997098) (xy 333.14835 -232.954084) (xy 333.182098 -232.91599) (xy 333.22152 -232.883803)
			(xy 333.265594 -232.858357) (xy 333.31318 -232.84031) (xy 333.363044 -232.83013) (xy 333.413896 -232.828081)
			(xy 333.464417 -232.834215) (xy 333.513301 -232.848375) (xy 333.55928 -232.870192) (xy 333.601164 -232.899102)
			(xy 333.637868 -232.934357) (xy 333.668441 -232.975043) (xy 333.692092 -233.020106) (xy 333.708208 -233.06838)
			(xy 333.716372 -233.118614) (xy 333.716884 -233.14406) (xy 334.035412 -233.14406) (xy 334.039372 -233.095006)
			(xy 334.051149 -233.047222) (xy 334.07044 -233.001946) (xy 334.096743 -232.96035) (xy 334.129378 -232.923513)
			(xy 334.167499 -232.892388) (xy 334.21012 -232.867781) (xy 334.256136 -232.850329) (xy 334.304355 -232.840485)
			(xy 334.35353 -232.838504) (xy 334.402385 -232.844436) (xy 334.449656 -232.858128) (xy 334.494118 -232.879226)
			(xy 334.534621 -232.907182) (xy 334.570114 -232.941274) (xy 334.599679 -232.980618) (xy 334.62255 -233.024195)
			(xy 334.638134 -233.070876) (xy 334.646029 -233.119453) (xy 334.646524 -233.14406) (xy 334.964781 -233.14406)
			(xy 334.968876 -233.093332) (xy 334.981055 -233.043918) (xy 335.001003 -232.997098) (xy 335.028204 -232.954084)
			(xy 335.061952 -232.91599) (xy 335.101374 -232.883803) (xy 335.145448 -232.858357) (xy 335.193034 -232.84031)
			(xy 335.242898 -232.83013) (xy 335.29375 -232.828081) (xy 335.344271 -232.834215) (xy 335.393155 -232.848375)
			(xy 335.439134 -232.870192) (xy 335.481018 -232.899102) (xy 335.517722 -232.934357) (xy 335.548295 -232.975043)
			(xy 335.571946 -233.020106) (xy 335.588062 -233.06838) (xy 335.596226 -233.118614) (xy 335.596738 -233.14406)
			(xy 335.915266 -233.14406) (xy 335.919226 -233.095006) (xy 335.931003 -233.047222) (xy 335.950294 -233.001946)
			(xy 335.976597 -232.96035) (xy 336.009232 -232.923513) (xy 336.047353 -232.892388) (xy 336.089974 -232.867781)
			(xy 336.13599 -232.850329) (xy 336.184209 -232.840485) (xy 336.233384 -232.838504) (xy 336.282239 -232.844436)
			(xy 336.32951 -232.858128) (xy 336.373972 -232.879226) (xy 336.414475 -232.907182) (xy 336.449968 -232.941274)
			(xy 336.479533 -232.980618) (xy 336.502404 -233.024195) (xy 336.517988 -233.070876) (xy 336.525883 -233.119453)
			(xy 336.526378 -233.14406) (xy 336.844889 -233.14406) (xy 336.848984 -233.093332) (xy 336.861163 -233.043918)
			(xy 336.881111 -232.997098) (xy 336.908312 -232.954084) (xy 336.94206 -232.91599) (xy 336.981482 -232.883803)
			(xy 337.025556 -232.858357) (xy 337.073142 -232.84031) (xy 337.123006 -232.83013) (xy 337.173858 -232.828081)
			(xy 337.224379 -232.834215) (xy 337.273263 -232.848375) (xy 337.319242 -232.870192) (xy 337.361126 -232.899102)
			(xy 337.39783 -232.934357) (xy 337.428403 -232.975043) (xy 337.452054 -233.020106) (xy 337.46817 -233.06838)
			(xy 337.476334 -233.118614) (xy 337.476846 -233.14406) (xy 337.795374 -233.14406) (xy 337.799334 -233.095006)
			(xy 337.811111 -233.047222) (xy 337.830402 -233.001946) (xy 337.856705 -232.96035) (xy 337.88934 -232.923513)
			(xy 337.927461 -232.892388) (xy 337.970082 -232.867781) (xy 338.016098 -232.850329) (xy 338.064317 -232.840485)
			(xy 338.113492 -232.838504) (xy 338.162347 -232.844436) (xy 338.209618 -232.858128) (xy 338.25408 -232.879226)
			(xy 338.294583 -232.907182) (xy 338.330076 -232.941274) (xy 338.359641 -232.980618) (xy 338.382512 -233.024195)
			(xy 338.398096 -233.070876) (xy 338.405991 -233.119453) (xy 338.406486 -233.14406) (xy 338.724743 -233.14406)
			(xy 338.728838 -233.093332) (xy 338.741017 -233.043918) (xy 338.760965 -232.997098) (xy 338.788166 -232.954084)
			(xy 338.821914 -232.91599) (xy 338.861336 -232.883803) (xy 338.90541 -232.858357) (xy 338.952996 -232.84031)
			(xy 339.00286 -232.83013) (xy 339.053712 -232.828081) (xy 339.104233 -232.834215) (xy 339.153117 -232.848375)
			(xy 339.199096 -232.870192) (xy 339.24098 -232.899102) (xy 339.277684 -232.934357) (xy 339.308257 -232.975043)
			(xy 339.331908 -233.020106) (xy 339.348024 -233.06838) (xy 339.356188 -233.118614) (xy 339.3567 -233.14406)
			(xy 339.664797 -233.14406) (xy 339.668892 -233.093332) (xy 339.681071 -233.043918) (xy 339.701019 -232.997098)
			(xy 339.72822 -232.954084) (xy 339.761968 -232.91599) (xy 339.80139 -232.883803) (xy 339.845464 -232.858357)
			(xy 339.89305 -232.84031) (xy 339.942914 -232.83013) (xy 339.993766 -232.828081) (xy 340.044287 -232.834215)
			(xy 340.093171 -232.848375) (xy 340.13915 -232.870192) (xy 340.181034 -232.899102) (xy 340.217738 -232.934357)
			(xy 340.248311 -232.975043) (xy 340.271962 -233.020106) (xy 340.288078 -233.06838) (xy 340.296242 -233.118614)
			(xy 340.296754 -233.14406) (xy 340.615282 -233.14406) (xy 340.619242 -233.095006) (xy 340.631019 -233.047222)
			(xy 340.65031 -233.001946) (xy 340.676613 -232.96035) (xy 340.709248 -232.923513) (xy 340.747369 -232.892388)
			(xy 340.78999 -232.867781) (xy 340.836006 -232.850329) (xy 340.884225 -232.840485) (xy 340.9334 -232.838504)
			(xy 340.982255 -232.844436) (xy 341.029526 -232.858128) (xy 341.073988 -232.879226) (xy 341.114491 -232.907182)
			(xy 341.149984 -232.941274) (xy 341.179549 -232.980618) (xy 341.20242 -233.024195) (xy 341.218004 -233.070876)
			(xy 341.225899 -233.119453) (xy 341.226394 -233.14406) (xy 341.544905 -233.14406) (xy 341.549 -233.093332)
			(xy 341.561179 -233.043918) (xy 341.581127 -232.997098) (xy 341.608328 -232.954084) (xy 341.642076 -232.91599)
			(xy 341.681498 -232.883803) (xy 341.725572 -232.858357) (xy 341.773158 -232.84031) (xy 341.823022 -232.83013)
			(xy 341.873874 -232.828081) (xy 341.924395 -232.834215) (xy 341.973279 -232.848375) (xy 342.019258 -232.870192)
			(xy 342.061142 -232.899102) (xy 342.097846 -232.934357) (xy 342.128419 -232.975043) (xy 342.15207 -233.020106)
			(xy 342.168186 -233.06838) (xy 342.17635 -233.118614) (xy 342.176862 -233.14406) (xy 342.49539 -233.14406)
			(xy 342.49935 -233.095006) (xy 342.511127 -233.047222) (xy 342.530418 -233.001946) (xy 342.556721 -232.96035)
			(xy 342.589356 -232.923513) (xy 342.627477 -232.892388) (xy 342.670098 -232.867781) (xy 342.716114 -232.850329)
			(xy 342.764333 -232.840485) (xy 342.813508 -232.838504) (xy 342.862363 -232.844436) (xy 342.909634 -232.858128)
			(xy 342.954096 -232.879226) (xy 342.994599 -232.907182) (xy 343.030092 -232.941274) (xy 343.059657 -232.980618)
			(xy 343.082528 -233.024195) (xy 343.098112 -233.070876) (xy 343.106007 -233.119453) (xy 343.106502 -233.14406)
			(xy 343.106007 -233.168667) (xy 343.098112 -233.217244) (xy 343.082528 -233.263925) (xy 343.059657 -233.307502)
			(xy 343.030092 -233.346846) (xy 342.994599 -233.380938) (xy 342.954096 -233.408894) (xy 342.909634 -233.429992)
			(xy 342.862363 -233.443684) (xy 342.813508 -233.449616) (xy 342.764333 -233.447635) (xy 342.716114 -233.437791)
			(xy 342.670098 -233.420339) (xy 342.627477 -233.395732) (xy 342.589356 -233.364607) (xy 342.556721 -233.32777)
			(xy 342.530418 -233.286174) (xy 342.511127 -233.240898) (xy 342.49935 -233.193114) (xy 342.49539 -233.14406)
			(xy 342.176862 -233.14406) (xy 342.17635 -233.169506) (xy 342.168186 -233.21974) (xy 342.15207 -233.268014)
			(xy 342.128419 -233.313077) (xy 342.097846 -233.353763) (xy 342.061142 -233.389018) (xy 342.019258 -233.417928)
			(xy 341.973279 -233.439745) (xy 341.924395 -233.453905) (xy 341.873874 -233.460039) (xy 341.823022 -233.45799)
			(xy 341.773158 -233.44781) (xy 341.725572 -233.429763) (xy 341.681498 -233.404317) (xy 341.642076 -233.37213)
			(xy 341.608328 -233.334036) (xy 341.581127 -233.291022) (xy 341.561179 -233.244202) (xy 341.549 -233.194788)
			(xy 341.544905 -233.14406) (xy 341.226394 -233.14406) (xy 341.225899 -233.168667) (xy 341.218004 -233.217244)
			(xy 341.20242 -233.263925) (xy 341.179549 -233.307502) (xy 341.149984 -233.346846) (xy 341.114491 -233.380938)
			(xy 341.073988 -233.408894) (xy 341.029526 -233.429992) (xy 340.982255 -233.443684) (xy 340.9334 -233.449616)
			(xy 340.884225 -233.447635) (xy 340.836006 -233.437791) (xy 340.78999 -233.420339) (xy 340.747369 -233.395732)
			(xy 340.709248 -233.364607) (xy 340.676613 -233.32777) (xy 340.65031 -233.286174) (xy 340.631019 -233.240898)
			(xy 340.619242 -233.193114) (xy 340.615282 -233.14406) (xy 340.296754 -233.14406) (xy 340.296242 -233.169506)
			(xy 340.288078 -233.21974) (xy 340.271962 -233.268014) (xy 340.248311 -233.313077) (xy 340.217738 -233.353763)
			(xy 340.181034 -233.389018) (xy 340.13915 -233.417928) (xy 340.093171 -233.439745) (xy 340.044287 -233.453905)
			(xy 339.993766 -233.460039) (xy 339.942914 -233.45799) (xy 339.89305 -233.44781) (xy 339.845464 -233.429763)
			(xy 339.80139 -233.404317) (xy 339.761968 -233.37213) (xy 339.72822 -233.334036) (xy 339.701019 -233.291022)
			(xy 339.681071 -233.244202) (xy 339.668892 -233.194788) (xy 339.664797 -233.14406) (xy 339.3567 -233.14406)
			(xy 339.356188 -233.169506) (xy 339.348024 -233.21974) (xy 339.331908 -233.268014) (xy 339.308257 -233.313077)
			(xy 339.277684 -233.353763) (xy 339.24098 -233.389018) (xy 339.199096 -233.417928) (xy 339.153117 -233.439745)
			(xy 339.104233 -233.453905) (xy 339.053712 -233.460039) (xy 339.00286 -233.45799) (xy 338.952996 -233.44781)
			(xy 338.90541 -233.429763) (xy 338.861336 -233.404317) (xy 338.821914 -233.37213) (xy 338.788166 -233.334036)
			(xy 338.760965 -233.291022) (xy 338.741017 -233.244202) (xy 338.728838 -233.194788) (xy 338.724743 -233.14406)
			(xy 338.406486 -233.14406) (xy 338.405991 -233.168667) (xy 338.398096 -233.217244) (xy 338.382512 -233.263925)
			(xy 338.359641 -233.307502) (xy 338.330076 -233.346846) (xy 338.294583 -233.380938) (xy 338.25408 -233.408894)
			(xy 338.209618 -233.429992) (xy 338.162347 -233.443684) (xy 338.113492 -233.449616) (xy 338.064317 -233.447635)
			(xy 338.016098 -233.437791) (xy 337.970082 -233.420339) (xy 337.927461 -233.395732) (xy 337.88934 -233.364607)
			(xy 337.856705 -233.32777) (xy 337.830402 -233.286174) (xy 337.811111 -233.240898) (xy 337.799334 -233.193114)
			(xy 337.795374 -233.14406) (xy 337.476846 -233.14406) (xy 337.476334 -233.169506) (xy 337.46817 -233.21974)
			(xy 337.452054 -233.268014) (xy 337.428403 -233.313077) (xy 337.39783 -233.353763) (xy 337.361126 -233.389018)
			(xy 337.319242 -233.417928) (xy 337.273263 -233.439745) (xy 337.224379 -233.453905) (xy 337.173858 -233.460039)
			(xy 337.123006 -233.45799) (xy 337.073142 -233.44781) (xy 337.025556 -233.429763) (xy 336.981482 -233.404317)
			(xy 336.94206 -233.37213) (xy 336.908312 -233.334036) (xy 336.881111 -233.291022) (xy 336.861163 -233.244202)
			(xy 336.848984 -233.194788) (xy 336.844889 -233.14406) (xy 336.526378 -233.14406) (xy 336.525883 -233.168667)
			(xy 336.517988 -233.217244) (xy 336.502404 -233.263925) (xy 336.479533 -233.307502) (xy 336.449968 -233.346846)
			(xy 336.414475 -233.380938) (xy 336.373972 -233.408894) (xy 336.32951 -233.429992) (xy 336.282239 -233.443684)
			(xy 336.233384 -233.449616) (xy 336.184209 -233.447635) (xy 336.13599 -233.437791) (xy 336.089974 -233.420339)
			(xy 336.047353 -233.395732) (xy 336.009232 -233.364607) (xy 335.976597 -233.32777) (xy 335.950294 -233.286174)
			(xy 335.931003 -233.240898) (xy 335.919226 -233.193114) (xy 335.915266 -233.14406) (xy 335.596738 -233.14406)
			(xy 335.596226 -233.169506) (xy 335.588062 -233.21974) (xy 335.571946 -233.268014) (xy 335.548295 -233.313077)
			(xy 335.517722 -233.353763) (xy 335.481018 -233.389018) (xy 335.439134 -233.417928) (xy 335.393155 -233.439745)
			(xy 335.344271 -233.453905) (xy 335.29375 -233.460039) (xy 335.242898 -233.45799) (xy 335.193034 -233.44781)
			(xy 335.145448 -233.429763) (xy 335.101374 -233.404317) (xy 335.061952 -233.37213) (xy 335.028204 -233.334036)
			(xy 335.001003 -233.291022) (xy 334.981055 -233.244202) (xy 334.968876 -233.194788) (xy 334.964781 -233.14406)
			(xy 334.646524 -233.14406) (xy 334.646029 -233.168667) (xy 334.638134 -233.217244) (xy 334.62255 -233.263925)
			(xy 334.599679 -233.307502) (xy 334.570114 -233.346846) (xy 334.534621 -233.380938) (xy 334.494118 -233.408894)
			(xy 334.449656 -233.429992) (xy 334.402385 -233.443684) (xy 334.35353 -233.449616) (xy 334.304355 -233.447635)
			(xy 334.256136 -233.437791) (xy 334.21012 -233.420339) (xy 334.167499 -233.395732) (xy 334.129378 -233.364607)
			(xy 334.096743 -233.32777) (xy 334.07044 -233.286174) (xy 334.051149 -233.240898) (xy 334.039372 -233.193114)
			(xy 334.035412 -233.14406) (xy 333.716884 -233.14406) (xy 333.716372 -233.169506) (xy 333.708208 -233.21974)
			(xy 333.692092 -233.268014) (xy 333.668441 -233.313077) (xy 333.637868 -233.353763) (xy 333.601164 -233.389018)
			(xy 333.55928 -233.417928) (xy 333.513301 -233.439745) (xy 333.464417 -233.453905) (xy 333.413896 -233.460039)
			(xy 333.363044 -233.45799) (xy 333.31318 -233.44781) (xy 333.265594 -233.429763) (xy 333.22152 -233.404317)
			(xy 333.182098 -233.37213) (xy 333.14835 -233.334036) (xy 333.121149 -233.291022) (xy 333.101201 -233.244202)
			(xy 333.089022 -233.194788) (xy 333.084927 -233.14406) (xy 332.77683 -233.14406) (xy 332.776318 -233.169506)
			(xy 332.768154 -233.21974) (xy 332.752038 -233.268014) (xy 332.728387 -233.313077) (xy 332.697814 -233.353763)
			(xy 332.66111 -233.389018) (xy 332.619226 -233.417928) (xy 332.573247 -233.439745) (xy 332.524363 -233.453905)
			(xy 332.473842 -233.460039) (xy 332.42299 -233.45799) (xy 332.373126 -233.44781) (xy 332.32554 -233.429763)
			(xy 332.281466 -233.404317) (xy 332.242044 -233.37213) (xy 332.208296 -233.334036) (xy 332.181095 -233.291022)
			(xy 332.161147 -233.244202) (xy 332.148968 -233.194788) (xy 332.144873 -233.14406) (xy 331.826362 -233.14406)
			(xy 331.825867 -233.168667) (xy 331.817972 -233.217244) (xy 331.802388 -233.263925) (xy 331.779517 -233.307502)
			(xy 331.749952 -233.346846) (xy 331.714459 -233.380938) (xy 331.673956 -233.408894) (xy 331.629494 -233.429992)
			(xy 331.582223 -233.443684) (xy 331.533368 -233.449616) (xy 331.484193 -233.447635) (xy 331.435974 -233.437791)
			(xy 331.389958 -233.420339) (xy 331.347337 -233.395732) (xy 331.309216 -233.364607) (xy 331.276581 -233.32777)
			(xy 331.250278 -233.286174) (xy 331.230987 -233.240898) (xy 331.21921 -233.193114) (xy 331.21525 -233.14406)
			(xy 330.896722 -233.14406) (xy 330.89621 -233.169506) (xy 330.888046 -233.21974) (xy 330.87193 -233.268014)
			(xy 330.848279 -233.313077) (xy 330.817706 -233.353763) (xy 330.781002 -233.389018) (xy 330.739118 -233.417928)
			(xy 330.693139 -233.439745) (xy 330.644255 -233.453905) (xy 330.593734 -233.460039) (xy 330.542882 -233.45799)
			(xy 330.493018 -233.44781) (xy 330.445432 -233.429763) (xy 330.401358 -233.404317) (xy 330.361936 -233.37213)
			(xy 330.328188 -233.334036) (xy 330.300987 -233.291022) (xy 330.281039 -233.244202) (xy 330.26886 -233.194788)
			(xy 330.264765 -233.14406) (xy 329.946508 -233.14406) (xy 329.946013 -233.168667) (xy 329.938118 -233.217244)
			(xy 329.922534 -233.263925) (xy 329.899663 -233.307502) (xy 329.870098 -233.346846) (xy 329.834605 -233.380938)
			(xy 329.794102 -233.408894) (xy 329.74964 -233.429992) (xy 329.702369 -233.443684) (xy 329.653514 -233.449616)
			(xy 329.604339 -233.447635) (xy 329.55612 -233.437791) (xy 329.510104 -233.420339) (xy 329.467483 -233.395732)
			(xy 329.429362 -233.364607) (xy 329.396727 -233.32777) (xy 329.370424 -233.286174) (xy 329.351133 -233.240898)
			(xy 329.339356 -233.193114) (xy 329.335396 -233.14406) (xy 329.016868 -233.14406) (xy 329.016356 -233.169506)
			(xy 329.008192 -233.21974) (xy 328.992076 -233.268014) (xy 328.968425 -233.313077) (xy 328.937852 -233.353763)
			(xy 328.901148 -233.389018) (xy 328.859264 -233.417928) (xy 328.813285 -233.439745) (xy 328.764401 -233.453905)
			(xy 328.71388 -233.460039) (xy 328.663028 -233.45799) (xy 328.613164 -233.44781) (xy 328.565578 -233.429763)
			(xy 328.521504 -233.404317) (xy 328.482082 -233.37213) (xy 328.448334 -233.334036) (xy 328.421133 -233.291022)
			(xy 328.401185 -233.244202) (xy 328.389006 -233.194788) (xy 328.384911 -233.14406) (xy 328.0664 -233.14406)
			(xy 328.065905 -233.168667) (xy 328.05801 -233.217244) (xy 328.042426 -233.263925) (xy 328.019555 -233.307502)
			(xy 327.98999 -233.346846) (xy 327.954497 -233.380938) (xy 327.913994 -233.408894) (xy 327.869532 -233.429992)
			(xy 327.822261 -233.443684) (xy 327.773406 -233.449616) (xy 327.724231 -233.447635) (xy 327.676012 -233.437791)
			(xy 327.629996 -233.420339) (xy 327.587375 -233.395732) (xy 327.549254 -233.364607) (xy 327.516619 -233.32777)
			(xy 327.490316 -233.286174) (xy 327.471025 -233.240898) (xy 327.459248 -233.193114) (xy 327.455288 -233.14406)
			(xy 324.903545 -233.14406) (xy 324.905872 -233.145164) (xy 324.946375 -233.17312) (xy 324.981868 -233.207212)
			(xy 325.011433 -233.246556) (xy 325.034304 -233.290133) (xy 325.049888 -233.336814) (xy 325.057783 -233.385391)
			(xy 325.058278 -233.409998) (xy 325.057783 -233.434605) (xy 325.049888 -233.483182) (xy 325.034304 -233.529863)
			(xy 325.011433 -233.57344) (xy 324.981868 -233.612784) (xy 324.946375 -233.646876) (xy 324.905872 -233.674832)
			(xy 324.86141 -233.69593) (xy 324.814139 -233.709622) (xy 324.765284 -233.715554) (xy 324.716109 -233.713573)
			(xy 324.66789 -233.703729) (xy 324.621874 -233.686277) (xy 324.579253 -233.66167) (xy 324.541132 -233.630545)
			(xy 324.508497 -233.593708) (xy 324.482194 -233.552112) (xy 324.462903 -233.506836) (xy 324.451126 -233.459052)
			(xy 324.447166 -233.409998) (xy 310.45912 -233.409998) (xy 310.45912 -233.954066) (xy 326.045334 -233.954066)
			(xy 326.049294 -233.905012) (xy 326.061071 -233.857228) (xy 326.080362 -233.811952) (xy 326.106665 -233.770356)
			(xy 326.1393 -233.733519) (xy 326.177421 -233.702394) (xy 326.220042 -233.677787) (xy 326.266058 -233.660335)
			(xy 326.314277 -233.650491) (xy 326.363452 -233.64851) (xy 326.412307 -233.654442) (xy 326.459578 -233.668134)
			(xy 326.50404 -233.689232) (xy 326.544543 -233.717188) (xy 326.580036 -233.75128) (xy 326.609601 -233.790624)
			(xy 326.632472 -233.834201) (xy 326.648056 -233.880882) (xy 326.655951 -233.929459) (xy 326.656446 -233.954066)
			(xy 327.925442 -233.954066) (xy 327.929402 -233.905012) (xy 327.941179 -233.857228) (xy 327.96047 -233.811952)
			(xy 327.986773 -233.770356) (xy 328.019408 -233.733519) (xy 328.057529 -233.702394) (xy 328.10015 -233.677787)
			(xy 328.146166 -233.660335) (xy 328.194385 -233.650491) (xy 328.24356 -233.64851) (xy 328.292415 -233.654442)
			(xy 328.339686 -233.668134) (xy 328.384148 -233.689232) (xy 328.424651 -233.717188) (xy 328.460144 -233.75128)
			(xy 328.489709 -233.790624) (xy 328.51258 -233.834201) (xy 328.528164 -233.880882) (xy 328.536059 -233.929459)
			(xy 328.536554 -233.954066) (xy 328.854811 -233.954066) (xy 328.858906 -233.903338) (xy 328.871085 -233.853924)
			(xy 328.891033 -233.807104) (xy 328.918234 -233.76409) (xy 328.951982 -233.725996) (xy 328.991404 -233.693809)
			(xy 329.035478 -233.668363) (xy 329.083064 -233.650316) (xy 329.132928 -233.640136) (xy 329.18378 -233.638087)
			(xy 329.234301 -233.644221) (xy 329.283185 -233.658381) (xy 329.329164 -233.680198) (xy 329.371048 -233.709108)
			(xy 329.407752 -233.744363) (xy 329.438325 -233.785049) (xy 329.461976 -233.830112) (xy 329.478092 -233.878386)
			(xy 329.486256 -233.92862) (xy 329.486768 -233.954066) (xy 329.794865 -233.954066) (xy 329.79896 -233.903338)
			(xy 329.811139 -233.853924) (xy 329.831087 -233.807104) (xy 329.858288 -233.76409) (xy 329.892036 -233.725996)
			(xy 329.931458 -233.693809) (xy 329.975532 -233.668363) (xy 330.023118 -233.650316) (xy 330.072982 -233.640136)
			(xy 330.123834 -233.638087) (xy 330.174355 -233.644221) (xy 330.223239 -233.658381) (xy 330.269218 -233.680198)
			(xy 330.311102 -233.709108) (xy 330.347806 -233.744363) (xy 330.378379 -233.785049) (xy 330.40203 -233.830112)
			(xy 330.418146 -233.878386) (xy 330.42631 -233.92862) (xy 330.426822 -233.954066) (xy 330.74535 -233.954066)
			(xy 330.74931 -233.905012) (xy 330.761087 -233.857228) (xy 330.780378 -233.811952) (xy 330.806681 -233.770356)
			(xy 330.839316 -233.733519) (xy 330.877437 -233.702394) (xy 330.920058 -233.677787) (xy 330.966074 -233.660335)
			(xy 331.014293 -233.650491) (xy 331.063468 -233.64851) (xy 331.112323 -233.654442) (xy 331.159594 -233.668134)
			(xy 331.204056 -233.689232) (xy 331.244559 -233.717188) (xy 331.280052 -233.75128) (xy 331.309617 -233.790624)
			(xy 331.332488 -233.834201) (xy 331.348072 -233.880882) (xy 331.355967 -233.929459) (xy 331.356462 -233.954066)
			(xy 331.674973 -233.954066) (xy 331.679068 -233.903338) (xy 331.691247 -233.853924) (xy 331.711195 -233.807104)
			(xy 331.738396 -233.76409) (xy 331.772144 -233.725996) (xy 331.811566 -233.693809) (xy 331.85564 -233.668363)
			(xy 331.903226 -233.650316) (xy 331.95309 -233.640136) (xy 332.003942 -233.638087) (xy 332.054463 -233.644221)
			(xy 332.103347 -233.658381) (xy 332.149326 -233.680198) (xy 332.19121 -233.709108) (xy 332.227914 -233.744363)
			(xy 332.258487 -233.785049) (xy 332.282138 -233.830112) (xy 332.298254 -233.878386) (xy 332.306418 -233.92862)
			(xy 332.30693 -233.954066) (xy 332.625204 -233.954066) (xy 332.629164 -233.905012) (xy 332.640941 -233.857228)
			(xy 332.660232 -233.811952) (xy 332.686535 -233.770356) (xy 332.71917 -233.733519) (xy 332.757291 -233.702394)
			(xy 332.799912 -233.677787) (xy 332.845928 -233.660335) (xy 332.894147 -233.650491) (xy 332.943322 -233.64851)
			(xy 332.992177 -233.654442) (xy 333.039448 -233.668134) (xy 333.08391 -233.689232) (xy 333.124413 -233.717188)
			(xy 333.159906 -233.75128) (xy 333.189471 -233.790624) (xy 333.212342 -233.834201) (xy 333.227926 -233.880882)
			(xy 333.235821 -233.929459) (xy 333.236316 -233.954066) (xy 333.554827 -233.954066) (xy 333.558922 -233.903338)
			(xy 333.571101 -233.853924) (xy 333.591049 -233.807104) (xy 333.61825 -233.76409) (xy 333.651998 -233.725996)
			(xy 333.69142 -233.693809) (xy 333.735494 -233.668363) (xy 333.78308 -233.650316) (xy 333.832944 -233.640136)
			(xy 333.883796 -233.638087) (xy 333.934317 -233.644221) (xy 333.983201 -233.658381) (xy 334.02918 -233.680198)
			(xy 334.071064 -233.709108) (xy 334.107768 -233.744363) (xy 334.138341 -233.785049) (xy 334.161992 -233.830112)
			(xy 334.178108 -233.878386) (xy 334.186272 -233.92862) (xy 334.186784 -233.954066) (xy 334.505312 -233.954066)
			(xy 334.509272 -233.905012) (xy 334.521049 -233.857228) (xy 334.54034 -233.811952) (xy 334.566643 -233.770356)
			(xy 334.599278 -233.733519) (xy 334.637399 -233.702394) (xy 334.68002 -233.677787) (xy 334.726036 -233.660335)
			(xy 334.774255 -233.650491) (xy 334.82343 -233.64851) (xy 334.872285 -233.654442) (xy 334.919556 -233.668134)
			(xy 334.964018 -233.689232) (xy 335.004521 -233.717188) (xy 335.040014 -233.75128) (xy 335.069579 -233.790624)
			(xy 335.09245 -233.834201) (xy 335.108034 -233.880882) (xy 335.115929 -233.929459) (xy 335.116424 -233.954066)
			(xy 335.434935 -233.954066) (xy 335.43903 -233.903338) (xy 335.451209 -233.853924) (xy 335.471157 -233.807104)
			(xy 335.498358 -233.76409) (xy 335.532106 -233.725996) (xy 335.571528 -233.693809) (xy 335.615602 -233.668363)
			(xy 335.663188 -233.650316) (xy 335.713052 -233.640136) (xy 335.763904 -233.638087) (xy 335.814425 -233.644221)
			(xy 335.863309 -233.658381) (xy 335.909288 -233.680198) (xy 335.951172 -233.709108) (xy 335.987876 -233.744363)
			(xy 336.018449 -233.785049) (xy 336.0421 -233.830112) (xy 336.058216 -233.878386) (xy 336.06638 -233.92862)
			(xy 336.066892 -233.954066) (xy 336.374989 -233.954066) (xy 336.379084 -233.903338) (xy 336.391263 -233.853924)
			(xy 336.411211 -233.807104) (xy 336.438412 -233.76409) (xy 336.47216 -233.725996) (xy 336.511582 -233.693809)
			(xy 336.555656 -233.668363) (xy 336.603242 -233.650316) (xy 336.653106 -233.640136) (xy 336.703958 -233.638087)
			(xy 336.754479 -233.644221) (xy 336.803363 -233.658381) (xy 336.849342 -233.680198) (xy 336.891226 -233.709108)
			(xy 336.92793 -233.744363) (xy 336.958503 -233.785049) (xy 336.982154 -233.830112) (xy 336.99827 -233.878386)
			(xy 337.006434 -233.92862) (xy 337.006946 -233.954066) (xy 337.32522 -233.954066) (xy 337.32918 -233.905012)
			(xy 337.340957 -233.857228) (xy 337.360248 -233.811952) (xy 337.386551 -233.770356) (xy 337.419186 -233.733519)
			(xy 337.457307 -233.702394) (xy 337.499928 -233.677787) (xy 337.545944 -233.660335) (xy 337.594163 -233.650491)
			(xy 337.643338 -233.64851) (xy 337.692193 -233.654442) (xy 337.739464 -233.668134) (xy 337.783926 -233.689232)
			(xy 337.824429 -233.717188) (xy 337.859922 -233.75128) (xy 337.889487 -233.790624) (xy 337.912358 -233.834201)
			(xy 337.927942 -233.880882) (xy 337.935837 -233.929459) (xy 337.936332 -233.954066) (xy 338.254843 -233.954066)
			(xy 338.258938 -233.903338) (xy 338.271117 -233.853924) (xy 338.291065 -233.807104) (xy 338.318266 -233.76409)
			(xy 338.352014 -233.725996) (xy 338.391436 -233.693809) (xy 338.43551 -233.668363) (xy 338.483096 -233.650316)
			(xy 338.53296 -233.640136) (xy 338.583812 -233.638087) (xy 338.634333 -233.644221) (xy 338.683217 -233.658381)
			(xy 338.729196 -233.680198) (xy 338.77108 -233.709108) (xy 338.807784 -233.744363) (xy 338.838357 -233.785049)
			(xy 338.862008 -233.830112) (xy 338.878124 -233.878386) (xy 338.886288 -233.92862) (xy 338.8868 -233.954066)
			(xy 339.205328 -233.954066) (xy 339.209288 -233.905012) (xy 339.221065 -233.857228) (xy 339.240356 -233.811952)
			(xy 339.266659 -233.770356) (xy 339.299294 -233.733519) (xy 339.337415 -233.702394) (xy 339.380036 -233.677787)
			(xy 339.426052 -233.660335) (xy 339.474271 -233.650491) (xy 339.523446 -233.64851) (xy 339.572301 -233.654442)
			(xy 339.619572 -233.668134) (xy 339.664034 -233.689232) (xy 339.704537 -233.717188) (xy 339.74003 -233.75128)
			(xy 339.769595 -233.790624) (xy 339.792466 -233.834201) (xy 339.80805 -233.880882) (xy 339.815945 -233.929459)
			(xy 339.81644 -233.954066) (xy 340.134951 -233.954066) (xy 340.139046 -233.903338) (xy 340.151225 -233.853924)
			(xy 340.171173 -233.807104) (xy 340.198374 -233.76409) (xy 340.232122 -233.725996) (xy 340.271544 -233.693809)
			(xy 340.315618 -233.668363) (xy 340.363204 -233.650316) (xy 340.413068 -233.640136) (xy 340.46392 -233.638087)
			(xy 340.514441 -233.644221) (xy 340.563325 -233.658381) (xy 340.609304 -233.680198) (xy 340.651188 -233.709108)
			(xy 340.687892 -233.744363) (xy 340.718465 -233.785049) (xy 340.742116 -233.830112) (xy 340.758232 -233.878386)
			(xy 340.766396 -233.92862) (xy 340.766908 -233.954066) (xy 341.085182 -233.954066) (xy 341.089142 -233.905012)
			(xy 341.100919 -233.857228) (xy 341.12021 -233.811952) (xy 341.146513 -233.770356) (xy 341.179148 -233.733519)
			(xy 341.217269 -233.702394) (xy 341.25989 -233.677787) (xy 341.305906 -233.660335) (xy 341.354125 -233.650491)
			(xy 341.4033 -233.64851) (xy 341.452155 -233.654442) (xy 341.499426 -233.668134) (xy 341.543888 -233.689232)
			(xy 341.584391 -233.717188) (xy 341.619884 -233.75128) (xy 341.649449 -233.790624) (xy 341.67232 -233.834201)
			(xy 341.687904 -233.880882) (xy 341.695799 -233.929459) (xy 341.696294 -233.954066) (xy 342.014805 -233.954066)
			(xy 342.0189 -233.903338) (xy 342.031079 -233.853924) (xy 342.051027 -233.807104) (xy 342.078228 -233.76409)
			(xy 342.111976 -233.725996) (xy 342.151398 -233.693809) (xy 342.195472 -233.668363) (xy 342.243058 -233.650316)
			(xy 342.292922 -233.640136) (xy 342.343774 -233.638087) (xy 342.394295 -233.644221) (xy 342.443179 -233.658381)
			(xy 342.489158 -233.680198) (xy 342.531042 -233.709108) (xy 342.567746 -233.744363) (xy 342.598319 -233.785049)
			(xy 342.62197 -233.830112) (xy 342.638086 -233.878386) (xy 342.64625 -233.92862) (xy 342.646762 -233.954066)
			(xy 342.954859 -233.954066) (xy 342.958954 -233.903338) (xy 342.971133 -233.853924) (xy 342.991081 -233.807104)
			(xy 343.018282 -233.76409) (xy 343.05203 -233.725996) (xy 343.091452 -233.693809) (xy 343.135526 -233.668363)
			(xy 343.183112 -233.650316) (xy 343.232976 -233.640136) (xy 343.283828 -233.638087) (xy 343.334349 -233.644221)
			(xy 343.383233 -233.658381) (xy 343.429212 -233.680198) (xy 343.471096 -233.709108) (xy 343.5078 -233.744363)
			(xy 343.538373 -233.785049) (xy 343.562024 -233.830112) (xy 343.57814 -233.878386) (xy 343.586304 -233.92862)
			(xy 343.586816 -233.954066) (xy 343.586304 -233.979512) (xy 343.57814 -234.029746) (xy 343.562024 -234.07802)
			(xy 343.538373 -234.123083) (xy 343.5078 -234.163769) (xy 343.471096 -234.199024) (xy 343.429212 -234.227934)
			(xy 343.383233 -234.249751) (xy 343.334349 -234.263911) (xy 343.283828 -234.270045) (xy 343.232976 -234.267996)
			(xy 343.183112 -234.257816) (xy 343.135526 -234.239769) (xy 343.091452 -234.214323) (xy 343.05203 -234.182136)
			(xy 343.018282 -234.144042) (xy 342.991081 -234.101028) (xy 342.971133 -234.054208) (xy 342.958954 -234.004794)
			(xy 342.954859 -233.954066) (xy 342.646762 -233.954066) (xy 342.64625 -233.979512) (xy 342.638086 -234.029746)
			(xy 342.62197 -234.07802) (xy 342.598319 -234.123083) (xy 342.567746 -234.163769) (xy 342.531042 -234.199024)
			(xy 342.489158 -234.227934) (xy 342.443179 -234.249751) (xy 342.394295 -234.263911) (xy 342.343774 -234.270045)
			(xy 342.292922 -234.267996) (xy 342.243058 -234.257816) (xy 342.195472 -234.239769) (xy 342.151398 -234.214323)
			(xy 342.111976 -234.182136) (xy 342.078228 -234.144042) (xy 342.051027 -234.101028) (xy 342.031079 -234.054208)
			(xy 342.0189 -234.004794) (xy 342.014805 -233.954066) (xy 341.696294 -233.954066) (xy 341.695799 -233.978673)
			(xy 341.687904 -234.02725) (xy 341.67232 -234.073931) (xy 341.649449 -234.117508) (xy 341.619884 -234.156852)
			(xy 341.584391 -234.190944) (xy 341.543888 -234.2189) (xy 341.499426 -234.239998) (xy 341.452155 -234.25369)
			(xy 341.4033 -234.259622) (xy 341.354125 -234.257641) (xy 341.305906 -234.247797) (xy 341.25989 -234.230345)
			(xy 341.217269 -234.205738) (xy 341.179148 -234.174613) (xy 341.146513 -234.137776) (xy 341.12021 -234.09618)
			(xy 341.100919 -234.050904) (xy 341.089142 -234.00312) (xy 341.085182 -233.954066) (xy 340.766908 -233.954066)
			(xy 340.766396 -233.979512) (xy 340.758232 -234.029746) (xy 340.742116 -234.07802) (xy 340.718465 -234.123083)
			(xy 340.687892 -234.163769) (xy 340.651188 -234.199024) (xy 340.609304 -234.227934) (xy 340.563325 -234.249751)
			(xy 340.514441 -234.263911) (xy 340.46392 -234.270045) (xy 340.413068 -234.267996) (xy 340.363204 -234.257816)
			(xy 340.315618 -234.239769) (xy 340.271544 -234.214323) (xy 340.232122 -234.182136) (xy 340.198374 -234.144042)
			(xy 340.171173 -234.101028) (xy 340.151225 -234.054208) (xy 340.139046 -234.004794) (xy 340.134951 -233.954066)
			(xy 339.81644 -233.954066) (xy 339.815945 -233.978673) (xy 339.80805 -234.02725) (xy 339.792466 -234.073931)
			(xy 339.769595 -234.117508) (xy 339.74003 -234.156852) (xy 339.704537 -234.190944) (xy 339.664034 -234.2189)
			(xy 339.619572 -234.239998) (xy 339.572301 -234.25369) (xy 339.523446 -234.259622) (xy 339.474271 -234.257641)
			(xy 339.426052 -234.247797) (xy 339.380036 -234.230345) (xy 339.337415 -234.205738) (xy 339.299294 -234.174613)
			(xy 339.266659 -234.137776) (xy 339.240356 -234.09618) (xy 339.221065 -234.050904) (xy 339.209288 -234.00312)
			(xy 339.205328 -233.954066) (xy 338.8868 -233.954066) (xy 338.886288 -233.979512) (xy 338.878124 -234.029746)
			(xy 338.862008 -234.07802) (xy 338.838357 -234.123083) (xy 338.807784 -234.163769) (xy 338.77108 -234.199024)
			(xy 338.729196 -234.227934) (xy 338.683217 -234.249751) (xy 338.634333 -234.263911) (xy 338.583812 -234.270045)
			(xy 338.53296 -234.267996) (xy 338.483096 -234.257816) (xy 338.43551 -234.239769) (xy 338.391436 -234.214323)
			(xy 338.352014 -234.182136) (xy 338.318266 -234.144042) (xy 338.291065 -234.101028) (xy 338.271117 -234.054208)
			(xy 338.258938 -234.004794) (xy 338.254843 -233.954066) (xy 337.936332 -233.954066) (xy 337.935837 -233.978673)
			(xy 337.927942 -234.02725) (xy 337.912358 -234.073931) (xy 337.889487 -234.117508) (xy 337.859922 -234.156852)
			(xy 337.824429 -234.190944) (xy 337.783926 -234.2189) (xy 337.739464 -234.239998) (xy 337.692193 -234.25369)
			(xy 337.643338 -234.259622) (xy 337.594163 -234.257641) (xy 337.545944 -234.247797) (xy 337.499928 -234.230345)
			(xy 337.457307 -234.205738) (xy 337.419186 -234.174613) (xy 337.386551 -234.137776) (xy 337.360248 -234.09618)
			(xy 337.340957 -234.050904) (xy 337.32918 -234.00312) (xy 337.32522 -233.954066) (xy 337.006946 -233.954066)
			(xy 337.006434 -233.979512) (xy 336.99827 -234.029746) (xy 336.982154 -234.07802) (xy 336.958503 -234.123083)
			(xy 336.92793 -234.163769) (xy 336.891226 -234.199024) (xy 336.849342 -234.227934) (xy 336.803363 -234.249751)
			(xy 336.754479 -234.263911) (xy 336.703958 -234.270045) (xy 336.653106 -234.267996) (xy 336.603242 -234.257816)
			(xy 336.555656 -234.239769) (xy 336.511582 -234.214323) (xy 336.47216 -234.182136) (xy 336.438412 -234.144042)
			(xy 336.411211 -234.101028) (xy 336.391263 -234.054208) (xy 336.379084 -234.004794) (xy 336.374989 -233.954066)
			(xy 336.066892 -233.954066) (xy 336.06638 -233.979512) (xy 336.058216 -234.029746) (xy 336.0421 -234.07802)
			(xy 336.018449 -234.123083) (xy 335.987876 -234.163769) (xy 335.951172 -234.199024) (xy 335.909288 -234.227934)
			(xy 335.863309 -234.249751) (xy 335.814425 -234.263911) (xy 335.763904 -234.270045) (xy 335.713052 -234.267996)
			(xy 335.663188 -234.257816) (xy 335.615602 -234.239769) (xy 335.571528 -234.214323) (xy 335.532106 -234.182136)
			(xy 335.498358 -234.144042) (xy 335.471157 -234.101028) (xy 335.451209 -234.054208) (xy 335.43903 -234.004794)
			(xy 335.434935 -233.954066) (xy 335.116424 -233.954066) (xy 335.115929 -233.978673) (xy 335.108034 -234.02725)
			(xy 335.09245 -234.073931) (xy 335.069579 -234.117508) (xy 335.040014 -234.156852) (xy 335.004521 -234.190944)
			(xy 334.964018 -234.2189) (xy 334.919556 -234.239998) (xy 334.872285 -234.25369) (xy 334.82343 -234.259622)
			(xy 334.774255 -234.257641) (xy 334.726036 -234.247797) (xy 334.68002 -234.230345) (xy 334.637399 -234.205738)
			(xy 334.599278 -234.174613) (xy 334.566643 -234.137776) (xy 334.54034 -234.09618) (xy 334.521049 -234.050904)
			(xy 334.509272 -234.00312) (xy 334.505312 -233.954066) (xy 334.186784 -233.954066) (xy 334.186272 -233.979512)
			(xy 334.178108 -234.029746) (xy 334.161992 -234.07802) (xy 334.138341 -234.123083) (xy 334.107768 -234.163769)
			(xy 334.071064 -234.199024) (xy 334.02918 -234.227934) (xy 333.983201 -234.249751) (xy 333.934317 -234.263911)
			(xy 333.883796 -234.270045) (xy 333.832944 -234.267996) (xy 333.78308 -234.257816) (xy 333.735494 -234.239769)
			(xy 333.69142 -234.214323) (xy 333.651998 -234.182136) (xy 333.61825 -234.144042) (xy 333.591049 -234.101028)
			(xy 333.571101 -234.054208) (xy 333.558922 -234.004794) (xy 333.554827 -233.954066) (xy 333.236316 -233.954066)
			(xy 333.235821 -233.978673) (xy 333.227926 -234.02725) (xy 333.212342 -234.073931) (xy 333.189471 -234.117508)
			(xy 333.159906 -234.156852) (xy 333.124413 -234.190944) (xy 333.08391 -234.2189) (xy 333.039448 -234.239998)
			(xy 332.992177 -234.25369) (xy 332.943322 -234.259622) (xy 332.894147 -234.257641) (xy 332.845928 -234.247797)
			(xy 332.799912 -234.230345) (xy 332.757291 -234.205738) (xy 332.71917 -234.174613) (xy 332.686535 -234.137776)
			(xy 332.660232 -234.09618) (xy 332.640941 -234.050904) (xy 332.629164 -234.00312) (xy 332.625204 -233.954066)
			(xy 332.30693 -233.954066) (xy 332.306418 -233.979512) (xy 332.298254 -234.029746) (xy 332.282138 -234.07802)
			(xy 332.258487 -234.123083) (xy 332.227914 -234.163769) (xy 332.19121 -234.199024) (xy 332.149326 -234.227934)
			(xy 332.103347 -234.249751) (xy 332.054463 -234.263911) (xy 332.003942 -234.270045) (xy 331.95309 -234.267996)
			(xy 331.903226 -234.257816) (xy 331.85564 -234.239769) (xy 331.811566 -234.214323) (xy 331.772144 -234.182136)
			(xy 331.738396 -234.144042) (xy 331.711195 -234.101028) (xy 331.691247 -234.054208) (xy 331.679068 -234.004794)
			(xy 331.674973 -233.954066) (xy 331.356462 -233.954066) (xy 331.355967 -233.978673) (xy 331.348072 -234.02725)
			(xy 331.332488 -234.073931) (xy 331.309617 -234.117508) (xy 331.280052 -234.156852) (xy 331.244559 -234.190944)
			(xy 331.204056 -234.2189) (xy 331.159594 -234.239998) (xy 331.112323 -234.25369) (xy 331.063468 -234.259622)
			(xy 331.014293 -234.257641) (xy 330.966074 -234.247797) (xy 330.920058 -234.230345) (xy 330.877437 -234.205738)
			(xy 330.839316 -234.174613) (xy 330.806681 -234.137776) (xy 330.780378 -234.09618) (xy 330.761087 -234.050904)
			(xy 330.74931 -234.00312) (xy 330.74535 -233.954066) (xy 330.426822 -233.954066) (xy 330.42631 -233.979512)
			(xy 330.418146 -234.029746) (xy 330.40203 -234.07802) (xy 330.378379 -234.123083) (xy 330.347806 -234.163769)
			(xy 330.311102 -234.199024) (xy 330.269218 -234.227934) (xy 330.223239 -234.249751) (xy 330.174355 -234.263911)
			(xy 330.123834 -234.270045) (xy 330.072982 -234.267996) (xy 330.023118 -234.257816) (xy 329.975532 -234.239769)
			(xy 329.931458 -234.214323) (xy 329.892036 -234.182136) (xy 329.858288 -234.144042) (xy 329.831087 -234.101028)
			(xy 329.811139 -234.054208) (xy 329.79896 -234.004794) (xy 329.794865 -233.954066) (xy 329.486768 -233.954066)
			(xy 329.486256 -233.979512) (xy 329.478092 -234.029746) (xy 329.461976 -234.07802) (xy 329.438325 -234.123083)
			(xy 329.407752 -234.163769) (xy 329.371048 -234.199024) (xy 329.329164 -234.227934) (xy 329.283185 -234.249751)
			(xy 329.234301 -234.263911) (xy 329.18378 -234.270045) (xy 329.132928 -234.267996) (xy 329.083064 -234.257816)
			(xy 329.035478 -234.239769) (xy 328.991404 -234.214323) (xy 328.951982 -234.182136) (xy 328.918234 -234.144042)
			(xy 328.891033 -234.101028) (xy 328.871085 -234.054208) (xy 328.858906 -234.004794) (xy 328.854811 -233.954066)
			(xy 328.536554 -233.954066) (xy 328.536059 -233.978673) (xy 328.528164 -234.02725) (xy 328.51258 -234.073931)
			(xy 328.489709 -234.117508) (xy 328.460144 -234.156852) (xy 328.424651 -234.190944) (xy 328.384148 -234.2189)
			(xy 328.339686 -234.239998) (xy 328.292415 -234.25369) (xy 328.24356 -234.259622) (xy 328.194385 -234.257641)
			(xy 328.146166 -234.247797) (xy 328.10015 -234.230345) (xy 328.057529 -234.205738) (xy 328.019408 -234.174613)
			(xy 327.986773 -234.137776) (xy 327.96047 -234.09618) (xy 327.941179 -234.050904) (xy 327.929402 -234.00312)
			(xy 327.925442 -233.954066) (xy 326.656446 -233.954066) (xy 326.655951 -233.978673) (xy 326.648056 -234.02725)
			(xy 326.632472 -234.073931) (xy 326.609601 -234.117508) (xy 326.580036 -234.156852) (xy 326.544543 -234.190944)
			(xy 326.50404 -234.2189) (xy 326.459578 -234.239998) (xy 326.412307 -234.25369) (xy 326.363452 -234.259622)
			(xy 326.314277 -234.257641) (xy 326.266058 -234.247797) (xy 326.220042 -234.230345) (xy 326.177421 -234.205738)
			(xy 326.1393 -234.174613) (xy 326.106665 -234.137776) (xy 326.080362 -234.09618) (xy 326.061071 -234.050904)
			(xy 326.049294 -234.00312) (xy 326.045334 -233.954066) (xy 310.45912 -233.954066) (xy 310.45912 -235.03001)
			(xy 324.447166 -235.03001) (xy 324.451126 -234.980956) (xy 324.462903 -234.933172) (xy 324.482194 -234.887896)
			(xy 324.508497 -234.8463) (xy 324.541132 -234.809463) (xy 324.579253 -234.778338) (xy 324.621874 -234.753731)
			(xy 324.66789 -234.736279) (xy 324.716109 -234.726435) (xy 324.765284 -234.724454) (xy 324.814139 -234.730386)
			(xy 324.86141 -234.744078) (xy 324.903545 -234.764072) (xy 328.384911 -234.764072) (xy 328.389006 -234.713344)
			(xy 328.401185 -234.66393) (xy 328.421133 -234.61711) (xy 328.448334 -234.574096) (xy 328.482082 -234.536002)
			(xy 328.521504 -234.503815) (xy 328.565578 -234.478369) (xy 328.613164 -234.460322) (xy 328.663028 -234.450142)
			(xy 328.71388 -234.448093) (xy 328.764401 -234.454227) (xy 328.813285 -234.468387) (xy 328.859264 -234.490204)
			(xy 328.901148 -234.519114) (xy 328.937852 -234.554369) (xy 328.968425 -234.595055) (xy 328.992076 -234.640118)
			(xy 329.008192 -234.688392) (xy 329.016356 -234.738626) (xy 329.016868 -234.764072) (xy 329.335396 -234.764072)
			(xy 329.339356 -234.715018) (xy 329.351133 -234.667234) (xy 329.370424 -234.621958) (xy 329.396727 -234.580362)
			(xy 329.429362 -234.543525) (xy 329.467483 -234.5124) (xy 329.510104 -234.487793) (xy 329.55612 -234.470341)
			(xy 329.604339 -234.460497) (xy 329.653514 -234.458516) (xy 329.702369 -234.464448) (xy 329.74964 -234.47814)
			(xy 329.794102 -234.499238) (xy 329.834605 -234.527194) (xy 329.870098 -234.561286) (xy 329.899663 -234.60063)
			(xy 329.922534 -234.644207) (xy 329.938118 -234.690888) (xy 329.946013 -234.739465) (xy 329.946508 -234.764072)
			(xy 330.264765 -234.764072) (xy 330.26886 -234.713344) (xy 330.281039 -234.66393) (xy 330.300987 -234.61711)
			(xy 330.328188 -234.574096) (xy 330.361936 -234.536002) (xy 330.401358 -234.503815) (xy 330.445432 -234.478369)
			(xy 330.493018 -234.460322) (xy 330.542882 -234.450142) (xy 330.593734 -234.448093) (xy 330.644255 -234.454227)
			(xy 330.693139 -234.468387) (xy 330.739118 -234.490204) (xy 330.781002 -234.519114) (xy 330.817706 -234.554369)
			(xy 330.848279 -234.595055) (xy 330.87193 -234.640118) (xy 330.888046 -234.688392) (xy 330.89621 -234.738626)
			(xy 330.896722 -234.764072) (xy 331.21525 -234.764072) (xy 331.21921 -234.715018) (xy 331.230987 -234.667234)
			(xy 331.250278 -234.621958) (xy 331.276581 -234.580362) (xy 331.309216 -234.543525) (xy 331.347337 -234.5124)
			(xy 331.389958 -234.487793) (xy 331.435974 -234.470341) (xy 331.484193 -234.460497) (xy 331.533368 -234.458516)
			(xy 331.582223 -234.464448) (xy 331.629494 -234.47814) (xy 331.673956 -234.499238) (xy 331.714459 -234.527194)
			(xy 331.749952 -234.561286) (xy 331.779517 -234.60063) (xy 331.802388 -234.644207) (xy 331.817972 -234.690888)
			(xy 331.825867 -234.739465) (xy 331.826362 -234.764072) (xy 332.144873 -234.764072) (xy 332.148968 -234.713344)
			(xy 332.161147 -234.66393) (xy 332.181095 -234.61711) (xy 332.208296 -234.574096) (xy 332.242044 -234.536002)
			(xy 332.281466 -234.503815) (xy 332.32554 -234.478369) (xy 332.373126 -234.460322) (xy 332.42299 -234.450142)
			(xy 332.473842 -234.448093) (xy 332.524363 -234.454227) (xy 332.573247 -234.468387) (xy 332.619226 -234.490204)
			(xy 332.66111 -234.519114) (xy 332.697814 -234.554369) (xy 332.728387 -234.595055) (xy 332.752038 -234.640118)
			(xy 332.768154 -234.688392) (xy 332.776318 -234.738626) (xy 332.77683 -234.764072) (xy 333.084927 -234.764072)
			(xy 333.089022 -234.713344) (xy 333.101201 -234.66393) (xy 333.121149 -234.61711) (xy 333.14835 -234.574096)
			(xy 333.182098 -234.536002) (xy 333.22152 -234.503815) (xy 333.265594 -234.478369) (xy 333.31318 -234.460322)
			(xy 333.363044 -234.450142) (xy 333.413896 -234.448093) (xy 333.464417 -234.454227) (xy 333.513301 -234.468387)
			(xy 333.55928 -234.490204) (xy 333.601164 -234.519114) (xy 333.637868 -234.554369) (xy 333.668441 -234.595055)
			(xy 333.692092 -234.640118) (xy 333.708208 -234.688392) (xy 333.716372 -234.738626) (xy 333.716884 -234.764072)
			(xy 334.964781 -234.764072) (xy 334.968876 -234.713344) (xy 334.981055 -234.66393) (xy 335.001003 -234.61711)
			(xy 335.028204 -234.574096) (xy 335.061952 -234.536002) (xy 335.101374 -234.503815) (xy 335.145448 -234.478369)
			(xy 335.193034 -234.460322) (xy 335.242898 -234.450142) (xy 335.29375 -234.448093) (xy 335.344271 -234.454227)
			(xy 335.393155 -234.468387) (xy 335.439134 -234.490204) (xy 335.481018 -234.519114) (xy 335.517722 -234.554369)
			(xy 335.548295 -234.595055) (xy 335.571946 -234.640118) (xy 335.588062 -234.688392) (xy 335.596226 -234.738626)
			(xy 335.596738 -234.764072) (xy 335.915266 -234.764072) (xy 335.919226 -234.715018) (xy 335.931003 -234.667234)
			(xy 335.950294 -234.621958) (xy 335.976597 -234.580362) (xy 336.009232 -234.543525) (xy 336.047353 -234.5124)
			(xy 336.089974 -234.487793) (xy 336.13599 -234.470341) (xy 336.184209 -234.460497) (xy 336.233384 -234.458516)
			(xy 336.282239 -234.464448) (xy 336.32951 -234.47814) (xy 336.373972 -234.499238) (xy 336.414475 -234.527194)
			(xy 336.449968 -234.561286) (xy 336.479533 -234.60063) (xy 336.502404 -234.644207) (xy 336.517988 -234.690888)
			(xy 336.525883 -234.739465) (xy 336.526378 -234.764072) (xy 336.844889 -234.764072) (xy 336.848984 -234.713344)
			(xy 336.861163 -234.66393) (xy 336.881111 -234.61711) (xy 336.908312 -234.574096) (xy 336.94206 -234.536002)
			(xy 336.981482 -234.503815) (xy 337.025556 -234.478369) (xy 337.073142 -234.460322) (xy 337.123006 -234.450142)
			(xy 337.173858 -234.448093) (xy 337.224379 -234.454227) (xy 337.273263 -234.468387) (xy 337.319242 -234.490204)
			(xy 337.361126 -234.519114) (xy 337.39783 -234.554369) (xy 337.428403 -234.595055) (xy 337.452054 -234.640118)
			(xy 337.46817 -234.688392) (xy 337.476334 -234.738626) (xy 337.476846 -234.764072) (xy 337.795374 -234.764072)
			(xy 337.799334 -234.715018) (xy 337.811111 -234.667234) (xy 337.830402 -234.621958) (xy 337.856705 -234.580362)
			(xy 337.88934 -234.543525) (xy 337.927461 -234.5124) (xy 337.970082 -234.487793) (xy 338.016098 -234.470341)
			(xy 338.064317 -234.460497) (xy 338.113492 -234.458516) (xy 338.162347 -234.464448) (xy 338.209618 -234.47814)
			(xy 338.25408 -234.499238) (xy 338.294583 -234.527194) (xy 338.330076 -234.561286) (xy 338.359641 -234.60063)
			(xy 338.382512 -234.644207) (xy 338.398096 -234.690888) (xy 338.405991 -234.739465) (xy 338.406486 -234.764072)
			(xy 338.724743 -234.764072) (xy 338.728838 -234.713344) (xy 338.741017 -234.66393) (xy 338.760965 -234.61711)
			(xy 338.788166 -234.574096) (xy 338.821914 -234.536002) (xy 338.861336 -234.503815) (xy 338.90541 -234.478369)
			(xy 338.952996 -234.460322) (xy 339.00286 -234.450142) (xy 339.053712 -234.448093) (xy 339.104233 -234.454227)
			(xy 339.153117 -234.468387) (xy 339.199096 -234.490204) (xy 339.24098 -234.519114) (xy 339.277684 -234.554369)
			(xy 339.308257 -234.595055) (xy 339.331908 -234.640118) (xy 339.348024 -234.688392) (xy 339.356188 -234.738626)
			(xy 339.3567 -234.764072) (xy 339.664797 -234.764072) (xy 339.668892 -234.713344) (xy 339.681071 -234.66393)
			(xy 339.701019 -234.61711) (xy 339.72822 -234.574096) (xy 339.761968 -234.536002) (xy 339.80139 -234.503815)
			(xy 339.845464 -234.478369) (xy 339.89305 -234.460322) (xy 339.942914 -234.450142) (xy 339.993766 -234.448093)
			(xy 340.044287 -234.454227) (xy 340.093171 -234.468387) (xy 340.13915 -234.490204) (xy 340.181034 -234.519114)
			(xy 340.217738 -234.554369) (xy 340.248311 -234.595055) (xy 340.271962 -234.640118) (xy 340.288078 -234.688392)
			(xy 340.296242 -234.738626) (xy 340.296754 -234.764072) (xy 341.544905 -234.764072) (xy 341.549 -234.713344)
			(xy 341.561179 -234.66393) (xy 341.581127 -234.61711) (xy 341.608328 -234.574096) (xy 341.642076 -234.536002)
			(xy 341.681498 -234.503815) (xy 341.725572 -234.478369) (xy 341.773158 -234.460322) (xy 341.823022 -234.450142)
			(xy 341.873874 -234.448093) (xy 341.924395 -234.454227) (xy 341.973279 -234.468387) (xy 342.019258 -234.490204)
			(xy 342.061142 -234.519114) (xy 342.097846 -234.554369) (xy 342.128419 -234.595055) (xy 342.15207 -234.640118)
			(xy 342.168186 -234.688392) (xy 342.17635 -234.738626) (xy 342.176862 -234.764072) (xy 342.49539 -234.764072)
			(xy 342.49935 -234.715018) (xy 342.511127 -234.667234) (xy 342.530418 -234.621958) (xy 342.556721 -234.580362)
			(xy 342.589356 -234.543525) (xy 342.627477 -234.5124) (xy 342.670098 -234.487793) (xy 342.716114 -234.470341)
			(xy 342.764333 -234.460497) (xy 342.813508 -234.458516) (xy 342.862363 -234.464448) (xy 342.909634 -234.47814)
			(xy 342.954096 -234.499238) (xy 342.994599 -234.527194) (xy 343.030092 -234.561286) (xy 343.059657 -234.60063)
			(xy 343.082528 -234.644207) (xy 343.098112 -234.690888) (xy 343.106007 -234.739465) (xy 343.106502 -234.764072)
			(xy 343.106007 -234.788679) (xy 343.098112 -234.837256) (xy 343.082528 -234.883937) (xy 343.059657 -234.927514)
			(xy 343.030092 -234.966858) (xy 342.994599 -235.00095) (xy 342.954096 -235.028906) (xy 342.909634 -235.050004)
			(xy 342.862363 -235.063696) (xy 342.813508 -235.069628) (xy 342.764333 -235.067647) (xy 342.716114 -235.057803)
			(xy 342.670098 -235.040351) (xy 342.627477 -235.015744) (xy 342.589356 -234.984619) (xy 342.556721 -234.947782)
			(xy 342.530418 -234.906186) (xy 342.511127 -234.86091) (xy 342.49935 -234.813126) (xy 342.49539 -234.764072)
			(xy 342.176862 -234.764072) (xy 342.17635 -234.789518) (xy 342.168186 -234.839752) (xy 342.15207 -234.888026)
			(xy 342.128419 -234.933089) (xy 342.097846 -234.973775) (xy 342.061142 -235.00903) (xy 342.019258 -235.03794)
			(xy 341.973279 -235.059757) (xy 341.924395 -235.073917) (xy 341.873874 -235.080051) (xy 341.823022 -235.078002)
			(xy 341.773158 -235.067822) (xy 341.725572 -235.049775) (xy 341.681498 -235.024329) (xy 341.642076 -234.992142)
			(xy 341.608328 -234.954048) (xy 341.581127 -234.911034) (xy 341.561179 -234.864214) (xy 341.549 -234.8148)
			(xy 341.544905 -234.764072) (xy 340.296754 -234.764072) (xy 340.296242 -234.789518) (xy 340.288078 -234.839752)
			(xy 340.271962 -234.888026) (xy 340.248311 -234.933089) (xy 340.217738 -234.973775) (xy 340.181034 -235.00903)
			(xy 340.13915 -235.03794) (xy 340.093171 -235.059757) (xy 340.044287 -235.073917) (xy 339.993766 -235.080051)
			(xy 339.942914 -235.078002) (xy 339.89305 -235.067822) (xy 339.845464 -235.049775) (xy 339.80139 -235.024329)
			(xy 339.761968 -234.992142) (xy 339.72822 -234.954048) (xy 339.701019 -234.911034) (xy 339.681071 -234.864214)
			(xy 339.668892 -234.8148) (xy 339.664797 -234.764072) (xy 339.3567 -234.764072) (xy 339.356188 -234.789518)
			(xy 339.348024 -234.839752) (xy 339.331908 -234.888026) (xy 339.308257 -234.933089) (xy 339.277684 -234.973775)
			(xy 339.24098 -235.00903) (xy 339.199096 -235.03794) (xy 339.153117 -235.059757) (xy 339.104233 -235.073917)
			(xy 339.053712 -235.080051) (xy 339.00286 -235.078002) (xy 338.952996 -235.067822) (xy 338.90541 -235.049775)
			(xy 338.861336 -235.024329) (xy 338.821914 -234.992142) (xy 338.788166 -234.954048) (xy 338.760965 -234.911034)
			(xy 338.741017 -234.864214) (xy 338.728838 -234.8148) (xy 338.724743 -234.764072) (xy 338.406486 -234.764072)
			(xy 338.405991 -234.788679) (xy 338.398096 -234.837256) (xy 338.382512 -234.883937) (xy 338.359641 -234.927514)
			(xy 338.330076 -234.966858) (xy 338.294583 -235.00095) (xy 338.25408 -235.028906) (xy 338.209618 -235.050004)
			(xy 338.162347 -235.063696) (xy 338.113492 -235.069628) (xy 338.064317 -235.067647) (xy 338.016098 -235.057803)
			(xy 337.970082 -235.040351) (xy 337.927461 -235.015744) (xy 337.88934 -234.984619) (xy 337.856705 -234.947782)
			(xy 337.830402 -234.906186) (xy 337.811111 -234.86091) (xy 337.799334 -234.813126) (xy 337.795374 -234.764072)
			(xy 337.476846 -234.764072) (xy 337.476334 -234.789518) (xy 337.46817 -234.839752) (xy 337.452054 -234.888026)
			(xy 337.428403 -234.933089) (xy 337.39783 -234.973775) (xy 337.361126 -235.00903) (xy 337.319242 -235.03794)
			(xy 337.273263 -235.059757) (xy 337.224379 -235.073917) (xy 337.173858 -235.080051) (xy 337.123006 -235.078002)
			(xy 337.073142 -235.067822) (xy 337.025556 -235.049775) (xy 336.981482 -235.024329) (xy 336.94206 -234.992142)
			(xy 336.908312 -234.954048) (xy 336.881111 -234.911034) (xy 336.861163 -234.864214) (xy 336.848984 -234.8148)
			(xy 336.844889 -234.764072) (xy 336.526378 -234.764072) (xy 336.525883 -234.788679) (xy 336.517988 -234.837256)
			(xy 336.502404 -234.883937) (xy 336.479533 -234.927514) (xy 336.449968 -234.966858) (xy 336.414475 -235.00095)
			(xy 336.373972 -235.028906) (xy 336.32951 -235.050004) (xy 336.282239 -235.063696) (xy 336.233384 -235.069628)
			(xy 336.184209 -235.067647) (xy 336.13599 -235.057803) (xy 336.089974 -235.040351) (xy 336.047353 -235.015744)
			(xy 336.009232 -234.984619) (xy 335.976597 -234.947782) (xy 335.950294 -234.906186) (xy 335.931003 -234.86091)
			(xy 335.919226 -234.813126) (xy 335.915266 -234.764072) (xy 335.596738 -234.764072) (xy 335.596226 -234.789518)
			(xy 335.588062 -234.839752) (xy 335.571946 -234.888026) (xy 335.548295 -234.933089) (xy 335.517722 -234.973775)
			(xy 335.481018 -235.00903) (xy 335.439134 -235.03794) (xy 335.393155 -235.059757) (xy 335.344271 -235.073917)
			(xy 335.29375 -235.080051) (xy 335.242898 -235.078002) (xy 335.193034 -235.067822) (xy 335.145448 -235.049775)
			(xy 335.101374 -235.024329) (xy 335.061952 -234.992142) (xy 335.028204 -234.954048) (xy 335.001003 -234.911034)
			(xy 334.981055 -234.864214) (xy 334.968876 -234.8148) (xy 334.964781 -234.764072) (xy 333.716884 -234.764072)
			(xy 333.716372 -234.789518) (xy 333.708208 -234.839752) (xy 333.692092 -234.888026) (xy 333.668441 -234.933089)
			(xy 333.637868 -234.973775) (xy 333.601164 -235.00903) (xy 333.55928 -235.03794) (xy 333.513301 -235.059757)
			(xy 333.464417 -235.073917) (xy 333.413896 -235.080051) (xy 333.363044 -235.078002) (xy 333.31318 -235.067822)
			(xy 333.265594 -235.049775) (xy 333.22152 -235.024329) (xy 333.182098 -234.992142) (xy 333.14835 -234.954048)
			(xy 333.121149 -234.911034) (xy 333.101201 -234.864214) (xy 333.089022 -234.8148) (xy 333.084927 -234.764072)
			(xy 332.77683 -234.764072) (xy 332.776318 -234.789518) (xy 332.768154 -234.839752) (xy 332.752038 -234.888026)
			(xy 332.728387 -234.933089) (xy 332.697814 -234.973775) (xy 332.66111 -235.00903) (xy 332.619226 -235.03794)
			(xy 332.573247 -235.059757) (xy 332.524363 -235.073917) (xy 332.473842 -235.080051) (xy 332.42299 -235.078002)
			(xy 332.373126 -235.067822) (xy 332.32554 -235.049775) (xy 332.281466 -235.024329) (xy 332.242044 -234.992142)
			(xy 332.208296 -234.954048) (xy 332.181095 -234.911034) (xy 332.161147 -234.864214) (xy 332.148968 -234.8148)
			(xy 332.144873 -234.764072) (xy 331.826362 -234.764072) (xy 331.825867 -234.788679) (xy 331.817972 -234.837256)
			(xy 331.802388 -234.883937) (xy 331.779517 -234.927514) (xy 331.749952 -234.966858) (xy 331.714459 -235.00095)
			(xy 331.673956 -235.028906) (xy 331.629494 -235.050004) (xy 331.582223 -235.063696) (xy 331.533368 -235.069628)
			(xy 331.484193 -235.067647) (xy 331.435974 -235.057803) (xy 331.389958 -235.040351) (xy 331.347337 -235.015744)
			(xy 331.309216 -234.984619) (xy 331.276581 -234.947782) (xy 331.250278 -234.906186) (xy 331.230987 -234.86091)
			(xy 331.21921 -234.813126) (xy 331.21525 -234.764072) (xy 330.896722 -234.764072) (xy 330.89621 -234.789518)
			(xy 330.888046 -234.839752) (xy 330.87193 -234.888026) (xy 330.848279 -234.933089) (xy 330.817706 -234.973775)
			(xy 330.781002 -235.00903) (xy 330.739118 -235.03794) (xy 330.693139 -235.059757) (xy 330.644255 -235.073917)
			(xy 330.593734 -235.080051) (xy 330.542882 -235.078002) (xy 330.493018 -235.067822) (xy 330.445432 -235.049775)
			(xy 330.401358 -235.024329) (xy 330.361936 -234.992142) (xy 330.328188 -234.954048) (xy 330.300987 -234.911034)
			(xy 330.281039 -234.864214) (xy 330.26886 -234.8148) (xy 330.264765 -234.764072) (xy 329.946508 -234.764072)
			(xy 329.946013 -234.788679) (xy 329.938118 -234.837256) (xy 329.922534 -234.883937) (xy 329.899663 -234.927514)
			(xy 329.870098 -234.966858) (xy 329.834605 -235.00095) (xy 329.794102 -235.028906) (xy 329.74964 -235.050004)
			(xy 329.702369 -235.063696) (xy 329.653514 -235.069628) (xy 329.604339 -235.067647) (xy 329.55612 -235.057803)
			(xy 329.510104 -235.040351) (xy 329.467483 -235.015744) (xy 329.429362 -234.984619) (xy 329.396727 -234.947782)
			(xy 329.370424 -234.906186) (xy 329.351133 -234.86091) (xy 329.339356 -234.813126) (xy 329.335396 -234.764072)
			(xy 329.016868 -234.764072) (xy 329.016356 -234.789518) (xy 329.008192 -234.839752) (xy 328.992076 -234.888026)
			(xy 328.968425 -234.933089) (xy 328.937852 -234.973775) (xy 328.901148 -235.00903) (xy 328.859264 -235.03794)
			(xy 328.813285 -235.059757) (xy 328.764401 -235.073917) (xy 328.71388 -235.080051) (xy 328.663028 -235.078002)
			(xy 328.613164 -235.067822) (xy 328.565578 -235.049775) (xy 328.521504 -235.024329) (xy 328.482082 -234.992142)
			(xy 328.448334 -234.954048) (xy 328.421133 -234.911034) (xy 328.401185 -234.864214) (xy 328.389006 -234.8148)
			(xy 328.384911 -234.764072) (xy 324.903545 -234.764072) (xy 324.905872 -234.765176) (xy 324.946375 -234.793132)
			(xy 324.981868 -234.827224) (xy 325.011433 -234.866568) (xy 325.034304 -234.910145) (xy 325.049888 -234.956826)
			(xy 325.057783 -235.005403) (xy 325.058278 -235.03001) (xy 325.057783 -235.054617) (xy 325.049888 -235.103194)
			(xy 325.034304 -235.149875) (xy 325.011433 -235.193452) (xy 324.981868 -235.232796) (xy 324.946375 -235.266888)
			(xy 324.905872 -235.294844) (xy 324.86141 -235.315942) (xy 324.814139 -235.329634) (xy 324.765284 -235.335566)
			(xy 324.716109 -235.333585) (xy 324.66789 -235.323741) (xy 324.621874 -235.306289) (xy 324.579253 -235.281682)
			(xy 324.541132 -235.250557) (xy 324.508497 -235.21372) (xy 324.482194 -235.172124) (xy 324.462903 -235.126848)
			(xy 324.451126 -235.079064) (xy 324.447166 -235.03001) (xy 310.45912 -235.03001) (xy 310.45912 -235.574078)
			(xy 326.045334 -235.574078) (xy 326.049294 -235.525024) (xy 326.061071 -235.47724) (xy 326.080362 -235.431964)
			(xy 326.106665 -235.390368) (xy 326.1393 -235.353531) (xy 326.177421 -235.322406) (xy 326.220042 -235.297799)
			(xy 326.266058 -235.280347) (xy 326.314277 -235.270503) (xy 326.363452 -235.268522) (xy 326.412307 -235.274454)
			(xy 326.459578 -235.288146) (xy 326.50404 -235.309244) (xy 326.544543 -235.3372) (xy 326.580036 -235.371292)
			(xy 326.609601 -235.410636) (xy 326.632472 -235.454213) (xy 326.648056 -235.500894) (xy 326.655951 -235.549471)
			(xy 326.656446 -235.574078) (xy 327.925442 -235.574078) (xy 327.929402 -235.525024) (xy 327.941179 -235.47724)
			(xy 327.96047 -235.431964) (xy 327.986773 -235.390368) (xy 328.019408 -235.353531) (xy 328.057529 -235.322406)
			(xy 328.10015 -235.297799) (xy 328.146166 -235.280347) (xy 328.194385 -235.270503) (xy 328.24356 -235.268522)
			(xy 328.292415 -235.274454) (xy 328.339686 -235.288146) (xy 328.384148 -235.309244) (xy 328.424651 -235.3372)
			(xy 328.460144 -235.371292) (xy 328.489709 -235.410636) (xy 328.51258 -235.454213) (xy 328.528164 -235.500894)
			(xy 328.536059 -235.549471) (xy 328.536554 -235.574078) (xy 328.854811 -235.574078) (xy 328.858906 -235.52335)
			(xy 328.871085 -235.473936) (xy 328.891033 -235.427116) (xy 328.918234 -235.384102) (xy 328.951982 -235.346008)
			(xy 328.991404 -235.313821) (xy 329.035478 -235.288375) (xy 329.083064 -235.270328) (xy 329.132928 -235.260148)
			(xy 329.18378 -235.258099) (xy 329.234301 -235.264233) (xy 329.283185 -235.278393) (xy 329.329164 -235.30021)
			(xy 329.371048 -235.32912) (xy 329.407752 -235.364375) (xy 329.438325 -235.405061) (xy 329.461976 -235.450124)
			(xy 329.478092 -235.498398) (xy 329.486256 -235.548632) (xy 329.486768 -235.574078) (xy 329.794865 -235.574078)
			(xy 329.79896 -235.52335) (xy 329.811139 -235.473936) (xy 329.831087 -235.427116) (xy 329.858288 -235.384102)
			(xy 329.892036 -235.346008) (xy 329.931458 -235.313821) (xy 329.975532 -235.288375) (xy 330.023118 -235.270328)
			(xy 330.072982 -235.260148) (xy 330.123834 -235.258099) (xy 330.174355 -235.264233) (xy 330.223239 -235.278393)
			(xy 330.269218 -235.30021) (xy 330.311102 -235.32912) (xy 330.347806 -235.364375) (xy 330.378379 -235.405061)
			(xy 330.40203 -235.450124) (xy 330.418146 -235.498398) (xy 330.42631 -235.548632) (xy 330.426822 -235.574078)
			(xy 330.74535 -235.574078) (xy 330.74931 -235.525024) (xy 330.761087 -235.47724) (xy 330.780378 -235.431964)
			(xy 330.806681 -235.390368) (xy 330.839316 -235.353531) (xy 330.877437 -235.322406) (xy 330.920058 -235.297799)
			(xy 330.966074 -235.280347) (xy 331.014293 -235.270503) (xy 331.063468 -235.268522) (xy 331.112323 -235.274454)
			(xy 331.159594 -235.288146) (xy 331.204056 -235.309244) (xy 331.244559 -235.3372) (xy 331.280052 -235.371292)
			(xy 331.309617 -235.410636) (xy 331.332488 -235.454213) (xy 331.348072 -235.500894) (xy 331.355967 -235.549471)
			(xy 331.356462 -235.574078) (xy 331.674973 -235.574078) (xy 331.679068 -235.52335) (xy 331.691247 -235.473936)
			(xy 331.711195 -235.427116) (xy 331.738396 -235.384102) (xy 331.772144 -235.346008) (xy 331.811566 -235.313821)
			(xy 331.85564 -235.288375) (xy 331.903226 -235.270328) (xy 331.95309 -235.260148) (xy 332.003942 -235.258099)
			(xy 332.054463 -235.264233) (xy 332.103347 -235.278393) (xy 332.149326 -235.30021) (xy 332.19121 -235.32912)
			(xy 332.227914 -235.364375) (xy 332.258487 -235.405061) (xy 332.282138 -235.450124) (xy 332.298254 -235.498398)
			(xy 332.306418 -235.548632) (xy 332.30693 -235.574078) (xy 332.625204 -235.574078) (xy 332.629164 -235.525024)
			(xy 332.640941 -235.47724) (xy 332.660232 -235.431964) (xy 332.686535 -235.390368) (xy 332.71917 -235.353531)
			(xy 332.757291 -235.322406) (xy 332.799912 -235.297799) (xy 332.845928 -235.280347) (xy 332.894147 -235.270503)
			(xy 332.943322 -235.268522) (xy 332.992177 -235.274454) (xy 333.039448 -235.288146) (xy 333.08391 -235.309244)
			(xy 333.124413 -235.3372) (xy 333.159906 -235.371292) (xy 333.189471 -235.410636) (xy 333.212342 -235.454213)
			(xy 333.227926 -235.500894) (xy 333.235821 -235.549471) (xy 333.236316 -235.574078) (xy 333.554827 -235.574078)
			(xy 333.558922 -235.52335) (xy 333.571101 -235.473936) (xy 333.591049 -235.427116) (xy 333.61825 -235.384102)
			(xy 333.651998 -235.346008) (xy 333.69142 -235.313821) (xy 333.735494 -235.288375) (xy 333.78308 -235.270328)
			(xy 333.832944 -235.260148) (xy 333.883796 -235.258099) (xy 333.934317 -235.264233) (xy 333.983201 -235.278393)
			(xy 334.02918 -235.30021) (xy 334.071064 -235.32912) (xy 334.107768 -235.364375) (xy 334.138341 -235.405061)
			(xy 334.161992 -235.450124) (xy 334.178108 -235.498398) (xy 334.186272 -235.548632) (xy 334.186784 -235.574078)
			(xy 334.505312 -235.574078) (xy 334.509272 -235.525024) (xy 334.521049 -235.47724) (xy 334.54034 -235.431964)
			(xy 334.566643 -235.390368) (xy 334.599278 -235.353531) (xy 334.637399 -235.322406) (xy 334.68002 -235.297799)
			(xy 334.726036 -235.280347) (xy 334.774255 -235.270503) (xy 334.82343 -235.268522) (xy 334.872285 -235.274454)
			(xy 334.919556 -235.288146) (xy 334.964018 -235.309244) (xy 335.004521 -235.3372) (xy 335.040014 -235.371292)
			(xy 335.069579 -235.410636) (xy 335.09245 -235.454213) (xy 335.108034 -235.500894) (xy 335.115929 -235.549471)
			(xy 335.116424 -235.574078) (xy 335.434935 -235.574078) (xy 335.43903 -235.52335) (xy 335.451209 -235.473936)
			(xy 335.471157 -235.427116) (xy 335.498358 -235.384102) (xy 335.532106 -235.346008) (xy 335.571528 -235.313821)
			(xy 335.615602 -235.288375) (xy 335.663188 -235.270328) (xy 335.713052 -235.260148) (xy 335.763904 -235.258099)
			(xy 335.814425 -235.264233) (xy 335.863309 -235.278393) (xy 335.909288 -235.30021) (xy 335.951172 -235.32912)
			(xy 335.987876 -235.364375) (xy 336.018449 -235.405061) (xy 336.0421 -235.450124) (xy 336.058216 -235.498398)
			(xy 336.06638 -235.548632) (xy 336.066892 -235.574078) (xy 336.374989 -235.574078) (xy 336.379084 -235.52335)
			(xy 336.391263 -235.473936) (xy 336.411211 -235.427116) (xy 336.438412 -235.384102) (xy 336.47216 -235.346008)
			(xy 336.511582 -235.313821) (xy 336.555656 -235.288375) (xy 336.603242 -235.270328) (xy 336.653106 -235.260148)
			(xy 336.703958 -235.258099) (xy 336.754479 -235.264233) (xy 336.803363 -235.278393) (xy 336.849342 -235.30021)
			(xy 336.891226 -235.32912) (xy 336.92793 -235.364375) (xy 336.958503 -235.405061) (xy 336.982154 -235.450124)
			(xy 336.99827 -235.498398) (xy 337.006434 -235.548632) (xy 337.006946 -235.574078) (xy 337.32522 -235.574078)
			(xy 337.32918 -235.525024) (xy 337.340957 -235.47724) (xy 337.360248 -235.431964) (xy 337.386551 -235.390368)
			(xy 337.419186 -235.353531) (xy 337.457307 -235.322406) (xy 337.499928 -235.297799) (xy 337.545944 -235.280347)
			(xy 337.594163 -235.270503) (xy 337.643338 -235.268522) (xy 337.692193 -235.274454) (xy 337.739464 -235.288146)
			(xy 337.783926 -235.309244) (xy 337.824429 -235.3372) (xy 337.859922 -235.371292) (xy 337.889487 -235.410636)
			(xy 337.912358 -235.454213) (xy 337.927942 -235.500894) (xy 337.935837 -235.549471) (xy 337.936332 -235.574078)
			(xy 338.254843 -235.574078) (xy 338.258938 -235.52335) (xy 338.271117 -235.473936) (xy 338.291065 -235.427116)
			(xy 338.318266 -235.384102) (xy 338.352014 -235.346008) (xy 338.391436 -235.313821) (xy 338.43551 -235.288375)
			(xy 338.483096 -235.270328) (xy 338.53296 -235.260148) (xy 338.583812 -235.258099) (xy 338.634333 -235.264233)
			(xy 338.683217 -235.278393) (xy 338.729196 -235.30021) (xy 338.77108 -235.32912) (xy 338.807784 -235.364375)
			(xy 338.838357 -235.405061) (xy 338.862008 -235.450124) (xy 338.878124 -235.498398) (xy 338.886288 -235.548632)
			(xy 338.8868 -235.574078) (xy 339.205328 -235.574078) (xy 339.209288 -235.525024) (xy 339.221065 -235.47724)
			(xy 339.240356 -235.431964) (xy 339.266659 -235.390368) (xy 339.299294 -235.353531) (xy 339.337415 -235.322406)
			(xy 339.380036 -235.297799) (xy 339.426052 -235.280347) (xy 339.474271 -235.270503) (xy 339.523446 -235.268522)
			(xy 339.572301 -235.274454) (xy 339.619572 -235.288146) (xy 339.664034 -235.309244) (xy 339.704537 -235.3372)
			(xy 339.74003 -235.371292) (xy 339.769595 -235.410636) (xy 339.792466 -235.454213) (xy 339.80805 -235.500894)
			(xy 339.815945 -235.549471) (xy 339.81644 -235.574078) (xy 340.134951 -235.574078) (xy 340.139046 -235.52335)
			(xy 340.151225 -235.473936) (xy 340.171173 -235.427116) (xy 340.198374 -235.384102) (xy 340.232122 -235.346008)
			(xy 340.271544 -235.313821) (xy 340.315618 -235.288375) (xy 340.363204 -235.270328) (xy 340.413068 -235.260148)
			(xy 340.46392 -235.258099) (xy 340.514441 -235.264233) (xy 340.563325 -235.278393) (xy 340.609304 -235.30021)
			(xy 340.651188 -235.32912) (xy 340.687892 -235.364375) (xy 340.718465 -235.405061) (xy 340.742116 -235.450124)
			(xy 340.758232 -235.498398) (xy 340.766396 -235.548632) (xy 340.766908 -235.574078) (xy 341.085182 -235.574078)
			(xy 341.089142 -235.525024) (xy 341.100919 -235.47724) (xy 341.12021 -235.431964) (xy 341.146513 -235.390368)
			(xy 341.179148 -235.353531) (xy 341.217269 -235.322406) (xy 341.25989 -235.297799) (xy 341.305906 -235.280347)
			(xy 341.354125 -235.270503) (xy 341.4033 -235.268522) (xy 341.452155 -235.274454) (xy 341.499426 -235.288146)
			(xy 341.543888 -235.309244) (xy 341.584391 -235.3372) (xy 341.619884 -235.371292) (xy 341.649449 -235.410636)
			(xy 341.67232 -235.454213) (xy 341.687904 -235.500894) (xy 341.695799 -235.549471) (xy 341.696294 -235.574078)
			(xy 342.014805 -235.574078) (xy 342.0189 -235.52335) (xy 342.031079 -235.473936) (xy 342.051027 -235.427116)
			(xy 342.078228 -235.384102) (xy 342.111976 -235.346008) (xy 342.151398 -235.313821) (xy 342.195472 -235.288375)
			(xy 342.243058 -235.270328) (xy 342.292922 -235.260148) (xy 342.343774 -235.258099) (xy 342.394295 -235.264233)
			(xy 342.443179 -235.278393) (xy 342.489158 -235.30021) (xy 342.531042 -235.32912) (xy 342.567746 -235.364375)
			(xy 342.598319 -235.405061) (xy 342.62197 -235.450124) (xy 342.638086 -235.498398) (xy 342.64625 -235.548632)
			(xy 342.646762 -235.574078) (xy 342.954859 -235.574078) (xy 342.958954 -235.52335) (xy 342.971133 -235.473936)
			(xy 342.991081 -235.427116) (xy 343.018282 -235.384102) (xy 343.05203 -235.346008) (xy 343.091452 -235.313821)
			(xy 343.135526 -235.288375) (xy 343.183112 -235.270328) (xy 343.232976 -235.260148) (xy 343.283828 -235.258099)
			(xy 343.334349 -235.264233) (xy 343.383233 -235.278393) (xy 343.429212 -235.30021) (xy 343.471096 -235.32912)
			(xy 343.5078 -235.364375) (xy 343.538373 -235.405061) (xy 343.562024 -235.450124) (xy 343.57814 -235.498398)
			(xy 343.586304 -235.548632) (xy 343.586816 -235.574078) (xy 343.586304 -235.599524) (xy 343.57814 -235.649758)
			(xy 343.562024 -235.698032) (xy 343.538373 -235.743095) (xy 343.5078 -235.783781) (xy 343.471096 -235.819036)
			(xy 343.429212 -235.847946) (xy 343.383233 -235.869763) (xy 343.334349 -235.883923) (xy 343.283828 -235.890057)
			(xy 343.232976 -235.888008) (xy 343.183112 -235.877828) (xy 343.135526 -235.859781) (xy 343.091452 -235.834335)
			(xy 343.05203 -235.802148) (xy 343.018282 -235.764054) (xy 342.991081 -235.72104) (xy 342.971133 -235.67422)
			(xy 342.958954 -235.624806) (xy 342.954859 -235.574078) (xy 342.646762 -235.574078) (xy 342.64625 -235.599524)
			(xy 342.638086 -235.649758) (xy 342.62197 -235.698032) (xy 342.598319 -235.743095) (xy 342.567746 -235.783781)
			(xy 342.531042 -235.819036) (xy 342.489158 -235.847946) (xy 342.443179 -235.869763) (xy 342.394295 -235.883923)
			(xy 342.343774 -235.890057) (xy 342.292922 -235.888008) (xy 342.243058 -235.877828) (xy 342.195472 -235.859781)
			(xy 342.151398 -235.834335) (xy 342.111976 -235.802148) (xy 342.078228 -235.764054) (xy 342.051027 -235.72104)
			(xy 342.031079 -235.67422) (xy 342.0189 -235.624806) (xy 342.014805 -235.574078) (xy 341.696294 -235.574078)
			(xy 341.695799 -235.598685) (xy 341.687904 -235.647262) (xy 341.67232 -235.693943) (xy 341.649449 -235.73752)
			(xy 341.619884 -235.776864) (xy 341.584391 -235.810956) (xy 341.543888 -235.838912) (xy 341.499426 -235.86001)
			(xy 341.452155 -235.873702) (xy 341.4033 -235.879634) (xy 341.354125 -235.877653) (xy 341.305906 -235.867809)
			(xy 341.25989 -235.850357) (xy 341.217269 -235.82575) (xy 341.179148 -235.794625) (xy 341.146513 -235.757788)
			(xy 341.12021 -235.716192) (xy 341.100919 -235.670916) (xy 341.089142 -235.623132) (xy 341.085182 -235.574078)
			(xy 340.766908 -235.574078) (xy 340.766396 -235.599524) (xy 340.758232 -235.649758) (xy 340.742116 -235.698032)
			(xy 340.718465 -235.743095) (xy 340.687892 -235.783781) (xy 340.651188 -235.819036) (xy 340.609304 -235.847946)
			(xy 340.563325 -235.869763) (xy 340.514441 -235.883923) (xy 340.46392 -235.890057) (xy 340.413068 -235.888008)
			(xy 340.363204 -235.877828) (xy 340.315618 -235.859781) (xy 340.271544 -235.834335) (xy 340.232122 -235.802148)
			(xy 340.198374 -235.764054) (xy 340.171173 -235.72104) (xy 340.151225 -235.67422) (xy 340.139046 -235.624806)
			(xy 340.134951 -235.574078) (xy 339.81644 -235.574078) (xy 339.815945 -235.598685) (xy 339.80805 -235.647262)
			(xy 339.792466 -235.693943) (xy 339.769595 -235.73752) (xy 339.74003 -235.776864) (xy 339.704537 -235.810956)
			(xy 339.664034 -235.838912) (xy 339.619572 -235.86001) (xy 339.572301 -235.873702) (xy 339.523446 -235.879634)
			(xy 339.474271 -235.877653) (xy 339.426052 -235.867809) (xy 339.380036 -235.850357) (xy 339.337415 -235.82575)
			(xy 339.299294 -235.794625) (xy 339.266659 -235.757788) (xy 339.240356 -235.716192) (xy 339.221065 -235.670916)
			(xy 339.209288 -235.623132) (xy 339.205328 -235.574078) (xy 338.8868 -235.574078) (xy 338.886288 -235.599524)
			(xy 338.878124 -235.649758) (xy 338.862008 -235.698032) (xy 338.838357 -235.743095) (xy 338.807784 -235.783781)
			(xy 338.77108 -235.819036) (xy 338.729196 -235.847946) (xy 338.683217 -235.869763) (xy 338.634333 -235.883923)
			(xy 338.583812 -235.890057) (xy 338.53296 -235.888008) (xy 338.483096 -235.877828) (xy 338.43551 -235.859781)
			(xy 338.391436 -235.834335) (xy 338.352014 -235.802148) (xy 338.318266 -235.764054) (xy 338.291065 -235.72104)
			(xy 338.271117 -235.67422) (xy 338.258938 -235.624806) (xy 338.254843 -235.574078) (xy 337.936332 -235.574078)
			(xy 337.935837 -235.598685) (xy 337.927942 -235.647262) (xy 337.912358 -235.693943) (xy 337.889487 -235.73752)
			(xy 337.859922 -235.776864) (xy 337.824429 -235.810956) (xy 337.783926 -235.838912) (xy 337.739464 -235.86001)
			(xy 337.692193 -235.873702) (xy 337.643338 -235.879634) (xy 337.594163 -235.877653) (xy 337.545944 -235.867809)
			(xy 337.499928 -235.850357) (xy 337.457307 -235.82575) (xy 337.419186 -235.794625) (xy 337.386551 -235.757788)
			(xy 337.360248 -235.716192) (xy 337.340957 -235.670916) (xy 337.32918 -235.623132) (xy 337.32522 -235.574078)
			(xy 337.006946 -235.574078) (xy 337.006434 -235.599524) (xy 336.99827 -235.649758) (xy 336.982154 -235.698032)
			(xy 336.958503 -235.743095) (xy 336.92793 -235.783781) (xy 336.891226 -235.819036) (xy 336.849342 -235.847946)
			(xy 336.803363 -235.869763) (xy 336.754479 -235.883923) (xy 336.703958 -235.890057) (xy 336.653106 -235.888008)
			(xy 336.603242 -235.877828) (xy 336.555656 -235.859781) (xy 336.511582 -235.834335) (xy 336.47216 -235.802148)
			(xy 336.438412 -235.764054) (xy 336.411211 -235.72104) (xy 336.391263 -235.67422) (xy 336.379084 -235.624806)
			(xy 336.374989 -235.574078) (xy 336.066892 -235.574078) (xy 336.06638 -235.599524) (xy 336.058216 -235.649758)
			(xy 336.0421 -235.698032) (xy 336.018449 -235.743095) (xy 335.987876 -235.783781) (xy 335.951172 -235.819036)
			(xy 335.909288 -235.847946) (xy 335.863309 -235.869763) (xy 335.814425 -235.883923) (xy 335.763904 -235.890057)
			(xy 335.713052 -235.888008) (xy 335.663188 -235.877828) (xy 335.615602 -235.859781) (xy 335.571528 -235.834335)
			(xy 335.532106 -235.802148) (xy 335.498358 -235.764054) (xy 335.471157 -235.72104) (xy 335.451209 -235.67422)
			(xy 335.43903 -235.624806) (xy 335.434935 -235.574078) (xy 335.116424 -235.574078) (xy 335.115929 -235.598685)
			(xy 335.108034 -235.647262) (xy 335.09245 -235.693943) (xy 335.069579 -235.73752) (xy 335.040014 -235.776864)
			(xy 335.004521 -235.810956) (xy 334.964018 -235.838912) (xy 334.919556 -235.86001) (xy 334.872285 -235.873702)
			(xy 334.82343 -235.879634) (xy 334.774255 -235.877653) (xy 334.726036 -235.867809) (xy 334.68002 -235.850357)
			(xy 334.637399 -235.82575) (xy 334.599278 -235.794625) (xy 334.566643 -235.757788) (xy 334.54034 -235.716192)
			(xy 334.521049 -235.670916) (xy 334.509272 -235.623132) (xy 334.505312 -235.574078) (xy 334.186784 -235.574078)
			(xy 334.186272 -235.599524) (xy 334.178108 -235.649758) (xy 334.161992 -235.698032) (xy 334.138341 -235.743095)
			(xy 334.107768 -235.783781) (xy 334.071064 -235.819036) (xy 334.02918 -235.847946) (xy 333.983201 -235.869763)
			(xy 333.934317 -235.883923) (xy 333.883796 -235.890057) (xy 333.832944 -235.888008) (xy 333.78308 -235.877828)
			(xy 333.735494 -235.859781) (xy 333.69142 -235.834335) (xy 333.651998 -235.802148) (xy 333.61825 -235.764054)
			(xy 333.591049 -235.72104) (xy 333.571101 -235.67422) (xy 333.558922 -235.624806) (xy 333.554827 -235.574078)
			(xy 333.236316 -235.574078) (xy 333.235821 -235.598685) (xy 333.227926 -235.647262) (xy 333.212342 -235.693943)
			(xy 333.189471 -235.73752) (xy 333.159906 -235.776864) (xy 333.124413 -235.810956) (xy 333.08391 -235.838912)
			(xy 333.039448 -235.86001) (xy 332.992177 -235.873702) (xy 332.943322 -235.879634) (xy 332.894147 -235.877653)
			(xy 332.845928 -235.867809) (xy 332.799912 -235.850357) (xy 332.757291 -235.82575) (xy 332.71917 -235.794625)
			(xy 332.686535 -235.757788) (xy 332.660232 -235.716192) (xy 332.640941 -235.670916) (xy 332.629164 -235.623132)
			(xy 332.625204 -235.574078) (xy 332.30693 -235.574078) (xy 332.306418 -235.599524) (xy 332.298254 -235.649758)
			(xy 332.282138 -235.698032) (xy 332.258487 -235.743095) (xy 332.227914 -235.783781) (xy 332.19121 -235.819036)
			(xy 332.149326 -235.847946) (xy 332.103347 -235.869763) (xy 332.054463 -235.883923) (xy 332.003942 -235.890057)
			(xy 331.95309 -235.888008) (xy 331.903226 -235.877828) (xy 331.85564 -235.859781) (xy 331.811566 -235.834335)
			(xy 331.772144 -235.802148) (xy 331.738396 -235.764054) (xy 331.711195 -235.72104) (xy 331.691247 -235.67422)
			(xy 331.679068 -235.624806) (xy 331.674973 -235.574078) (xy 331.356462 -235.574078) (xy 331.355967 -235.598685)
			(xy 331.348072 -235.647262) (xy 331.332488 -235.693943) (xy 331.309617 -235.73752) (xy 331.280052 -235.776864)
			(xy 331.244559 -235.810956) (xy 331.204056 -235.838912) (xy 331.159594 -235.86001) (xy 331.112323 -235.873702)
			(xy 331.063468 -235.879634) (xy 331.014293 -235.877653) (xy 330.966074 -235.867809) (xy 330.920058 -235.850357)
			(xy 330.877437 -235.82575) (xy 330.839316 -235.794625) (xy 330.806681 -235.757788) (xy 330.780378 -235.716192)
			(xy 330.761087 -235.670916) (xy 330.74931 -235.623132) (xy 330.74535 -235.574078) (xy 330.426822 -235.574078)
			(xy 330.42631 -235.599524) (xy 330.418146 -235.649758) (xy 330.40203 -235.698032) (xy 330.378379 -235.743095)
			(xy 330.347806 -235.783781) (xy 330.311102 -235.819036) (xy 330.269218 -235.847946) (xy 330.223239 -235.869763)
			(xy 330.174355 -235.883923) (xy 330.123834 -235.890057) (xy 330.072982 -235.888008) (xy 330.023118 -235.877828)
			(xy 329.975532 -235.859781) (xy 329.931458 -235.834335) (xy 329.892036 -235.802148) (xy 329.858288 -235.764054)
			(xy 329.831087 -235.72104) (xy 329.811139 -235.67422) (xy 329.79896 -235.624806) (xy 329.794865 -235.574078)
			(xy 329.486768 -235.574078) (xy 329.486256 -235.599524) (xy 329.478092 -235.649758) (xy 329.461976 -235.698032)
			(xy 329.438325 -235.743095) (xy 329.407752 -235.783781) (xy 329.371048 -235.819036) (xy 329.329164 -235.847946)
			(xy 329.283185 -235.869763) (xy 329.234301 -235.883923) (xy 329.18378 -235.890057) (xy 329.132928 -235.888008)
			(xy 329.083064 -235.877828) (xy 329.035478 -235.859781) (xy 328.991404 -235.834335) (xy 328.951982 -235.802148)
			(xy 328.918234 -235.764054) (xy 328.891033 -235.72104) (xy 328.871085 -235.67422) (xy 328.858906 -235.624806)
			(xy 328.854811 -235.574078) (xy 328.536554 -235.574078) (xy 328.536059 -235.598685) (xy 328.528164 -235.647262)
			(xy 328.51258 -235.693943) (xy 328.489709 -235.73752) (xy 328.460144 -235.776864) (xy 328.424651 -235.810956)
			(xy 328.384148 -235.838912) (xy 328.339686 -235.86001) (xy 328.292415 -235.873702) (xy 328.24356 -235.879634)
			(xy 328.194385 -235.877653) (xy 328.146166 -235.867809) (xy 328.10015 -235.850357) (xy 328.057529 -235.82575)
			(xy 328.019408 -235.794625) (xy 327.986773 -235.757788) (xy 327.96047 -235.716192) (xy 327.941179 -235.670916)
			(xy 327.929402 -235.623132) (xy 327.925442 -235.574078) (xy 326.656446 -235.574078) (xy 326.655951 -235.598685)
			(xy 326.648056 -235.647262) (xy 326.632472 -235.693943) (xy 326.609601 -235.73752) (xy 326.580036 -235.776864)
			(xy 326.544543 -235.810956) (xy 326.50404 -235.838912) (xy 326.459578 -235.86001) (xy 326.412307 -235.873702)
			(xy 326.363452 -235.879634) (xy 326.314277 -235.877653) (xy 326.266058 -235.867809) (xy 326.220042 -235.850357)
			(xy 326.177421 -235.82575) (xy 326.1393 -235.794625) (xy 326.106665 -235.757788) (xy 326.080362 -235.716192)
			(xy 326.061071 -235.670916) (xy 326.049294 -235.623132) (xy 326.045334 -235.574078) (xy 310.45912 -235.574078)
			(xy 310.45912 -236.650022) (xy 324.447166 -236.650022) (xy 324.451126 -236.600968) (xy 324.462903 -236.553184)
			(xy 324.482194 -236.507908) (xy 324.508497 -236.466312) (xy 324.541132 -236.429475) (xy 324.579253 -236.39835)
			(xy 324.621874 -236.373743) (xy 324.66789 -236.356291) (xy 324.716109 -236.346447) (xy 324.765284 -236.344466)
			(xy 324.814139 -236.350398) (xy 324.86141 -236.36409) (xy 324.903545 -236.384084) (xy 327.455288 -236.384084)
			(xy 327.459248 -236.33503) (xy 327.471025 -236.287246) (xy 327.490316 -236.24197) (xy 327.516619 -236.200374)
			(xy 327.549254 -236.163537) (xy 327.587375 -236.132412) (xy 327.629996 -236.107805) (xy 327.676012 -236.090353)
			(xy 327.724231 -236.080509) (xy 327.773406 -236.078528) (xy 327.822261 -236.08446) (xy 327.869532 -236.098152)
			(xy 327.913994 -236.11925) (xy 327.954497 -236.147206) (xy 327.98999 -236.181298) (xy 328.019555 -236.220642)
			(xy 328.042426 -236.264219) (xy 328.05801 -236.3109) (xy 328.065905 -236.359477) (xy 328.0664 -236.384084)
			(xy 328.384911 -236.384084) (xy 328.389006 -236.333356) (xy 328.401185 -236.283942) (xy 328.421133 -236.237122)
			(xy 328.448334 -236.194108) (xy 328.482082 -236.156014) (xy 328.521504 -236.123827) (xy 328.565578 -236.098381)
			(xy 328.613164 -236.080334) (xy 328.663028 -236.070154) (xy 328.71388 -236.068105) (xy 328.764401 -236.074239)
			(xy 328.813285 -236.088399) (xy 328.859264 -236.110216) (xy 328.901148 -236.139126) (xy 328.937852 -236.174381)
			(xy 328.968425 -236.215067) (xy 328.992076 -236.26013) (xy 329.008192 -236.308404) (xy 329.016356 -236.358638)
			(xy 329.016868 -236.384084) (xy 329.335396 -236.384084) (xy 329.339356 -236.33503) (xy 329.351133 -236.287246)
			(xy 329.370424 -236.24197) (xy 329.396727 -236.200374) (xy 329.429362 -236.163537) (xy 329.467483 -236.132412)
			(xy 329.510104 -236.107805) (xy 329.55612 -236.090353) (xy 329.604339 -236.080509) (xy 329.653514 -236.078528)
			(xy 329.702369 -236.08446) (xy 329.74964 -236.098152) (xy 329.794102 -236.11925) (xy 329.834605 -236.147206)
			(xy 329.870098 -236.181298) (xy 329.899663 -236.220642) (xy 329.922534 -236.264219) (xy 329.938118 -236.3109)
			(xy 329.946013 -236.359477) (xy 329.946508 -236.384084) (xy 330.264765 -236.384084) (xy 330.26886 -236.333356)
			(xy 330.281039 -236.283942) (xy 330.300987 -236.237122) (xy 330.328188 -236.194108) (xy 330.361936 -236.156014)
			(xy 330.401358 -236.123827) (xy 330.445432 -236.098381) (xy 330.493018 -236.080334) (xy 330.542882 -236.070154)
			(xy 330.593734 -236.068105) (xy 330.644255 -236.074239) (xy 330.693139 -236.088399) (xy 330.739118 -236.110216)
			(xy 330.781002 -236.139126) (xy 330.817706 -236.174381) (xy 330.848279 -236.215067) (xy 330.87193 -236.26013)
			(xy 330.888046 -236.308404) (xy 330.89621 -236.358638) (xy 330.896722 -236.384084) (xy 331.21525 -236.384084)
			(xy 331.21921 -236.33503) (xy 331.230987 -236.287246) (xy 331.250278 -236.24197) (xy 331.276581 -236.200374)
			(xy 331.309216 -236.163537) (xy 331.347337 -236.132412) (xy 331.389958 -236.107805) (xy 331.435974 -236.090353)
			(xy 331.484193 -236.080509) (xy 331.533368 -236.078528) (xy 331.582223 -236.08446) (xy 331.629494 -236.098152)
			(xy 331.673956 -236.11925) (xy 331.714459 -236.147206) (xy 331.749952 -236.181298) (xy 331.779517 -236.220642)
			(xy 331.802388 -236.264219) (xy 331.817972 -236.3109) (xy 331.825867 -236.359477) (xy 331.826362 -236.384084)
			(xy 332.144873 -236.384084) (xy 332.148968 -236.333356) (xy 332.161147 -236.283942) (xy 332.181095 -236.237122)
			(xy 332.208296 -236.194108) (xy 332.242044 -236.156014) (xy 332.281466 -236.123827) (xy 332.32554 -236.098381)
			(xy 332.373126 -236.080334) (xy 332.42299 -236.070154) (xy 332.473842 -236.068105) (xy 332.524363 -236.074239)
			(xy 332.573247 -236.088399) (xy 332.619226 -236.110216) (xy 332.66111 -236.139126) (xy 332.697814 -236.174381)
			(xy 332.728387 -236.215067) (xy 332.752038 -236.26013) (xy 332.768154 -236.308404) (xy 332.776318 -236.358638)
			(xy 332.77683 -236.384084) (xy 333.084927 -236.384084) (xy 333.089022 -236.333356) (xy 333.101201 -236.283942)
			(xy 333.121149 -236.237122) (xy 333.14835 -236.194108) (xy 333.182098 -236.156014) (xy 333.22152 -236.123827)
			(xy 333.265594 -236.098381) (xy 333.31318 -236.080334) (xy 333.363044 -236.070154) (xy 333.413896 -236.068105)
			(xy 333.464417 -236.074239) (xy 333.513301 -236.088399) (xy 333.55928 -236.110216) (xy 333.601164 -236.139126)
			(xy 333.637868 -236.174381) (xy 333.668441 -236.215067) (xy 333.692092 -236.26013) (xy 333.708208 -236.308404)
			(xy 333.716372 -236.358638) (xy 333.716884 -236.384084) (xy 334.035412 -236.384084) (xy 334.039372 -236.33503)
			(xy 334.051149 -236.287246) (xy 334.07044 -236.24197) (xy 334.096743 -236.200374) (xy 334.129378 -236.163537)
			(xy 334.167499 -236.132412) (xy 334.21012 -236.107805) (xy 334.256136 -236.090353) (xy 334.304355 -236.080509)
			(xy 334.35353 -236.078528) (xy 334.402385 -236.08446) (xy 334.449656 -236.098152) (xy 334.494118 -236.11925)
			(xy 334.534621 -236.147206) (xy 334.570114 -236.181298) (xy 334.599679 -236.220642) (xy 334.62255 -236.264219)
			(xy 334.638134 -236.3109) (xy 334.646029 -236.359477) (xy 334.646524 -236.384084) (xy 334.964781 -236.384084)
			(xy 334.968876 -236.333356) (xy 334.981055 -236.283942) (xy 335.001003 -236.237122) (xy 335.028204 -236.194108)
			(xy 335.061952 -236.156014) (xy 335.101374 -236.123827) (xy 335.145448 -236.098381) (xy 335.193034 -236.080334)
			(xy 335.242898 -236.070154) (xy 335.29375 -236.068105) (xy 335.344271 -236.074239) (xy 335.393155 -236.088399)
			(xy 335.439134 -236.110216) (xy 335.481018 -236.139126) (xy 335.517722 -236.174381) (xy 335.548295 -236.215067)
			(xy 335.571946 -236.26013) (xy 335.588062 -236.308404) (xy 335.596226 -236.358638) (xy 335.596738 -236.384084)
			(xy 335.915266 -236.384084) (xy 335.919226 -236.33503) (xy 335.931003 -236.287246) (xy 335.950294 -236.24197)
			(xy 335.976597 -236.200374) (xy 336.009232 -236.163537) (xy 336.047353 -236.132412) (xy 336.089974 -236.107805)
			(xy 336.13599 -236.090353) (xy 336.184209 -236.080509) (xy 336.233384 -236.078528) (xy 336.282239 -236.08446)
			(xy 336.32951 -236.098152) (xy 336.373972 -236.11925) (xy 336.414475 -236.147206) (xy 336.449968 -236.181298)
			(xy 336.479533 -236.220642) (xy 336.502404 -236.264219) (xy 336.517988 -236.3109) (xy 336.525883 -236.359477)
			(xy 336.526378 -236.384084) (xy 336.844889 -236.384084) (xy 336.848984 -236.333356) (xy 336.861163 -236.283942)
			(xy 336.881111 -236.237122) (xy 336.908312 -236.194108) (xy 336.94206 -236.156014) (xy 336.981482 -236.123827)
			(xy 337.025556 -236.098381) (xy 337.073142 -236.080334) (xy 337.123006 -236.070154) (xy 337.173858 -236.068105)
			(xy 337.224379 -236.074239) (xy 337.273263 -236.088399) (xy 337.319242 -236.110216) (xy 337.361126 -236.139126)
			(xy 337.39783 -236.174381) (xy 337.428403 -236.215067) (xy 337.452054 -236.26013) (xy 337.46817 -236.308404)
			(xy 337.476334 -236.358638) (xy 337.476846 -236.384084) (xy 337.795374 -236.384084) (xy 337.799334 -236.33503)
			(xy 337.811111 -236.287246) (xy 337.830402 -236.24197) (xy 337.856705 -236.200374) (xy 337.88934 -236.163537)
			(xy 337.927461 -236.132412) (xy 337.970082 -236.107805) (xy 338.016098 -236.090353) (xy 338.064317 -236.080509)
			(xy 338.113492 -236.078528) (xy 338.162347 -236.08446) (xy 338.209618 -236.098152) (xy 338.25408 -236.11925)
			(xy 338.294583 -236.147206) (xy 338.330076 -236.181298) (xy 338.359641 -236.220642) (xy 338.382512 -236.264219)
			(xy 338.398096 -236.3109) (xy 338.405991 -236.359477) (xy 338.406486 -236.384084) (xy 338.724743 -236.384084)
			(xy 338.728838 -236.333356) (xy 338.741017 -236.283942) (xy 338.760965 -236.237122) (xy 338.788166 -236.194108)
			(xy 338.821914 -236.156014) (xy 338.861336 -236.123827) (xy 338.90541 -236.098381) (xy 338.952996 -236.080334)
			(xy 339.00286 -236.070154) (xy 339.053712 -236.068105) (xy 339.104233 -236.074239) (xy 339.153117 -236.088399)
			(xy 339.199096 -236.110216) (xy 339.24098 -236.139126) (xy 339.277684 -236.174381) (xy 339.308257 -236.215067)
			(xy 339.331908 -236.26013) (xy 339.348024 -236.308404) (xy 339.356188 -236.358638) (xy 339.3567 -236.384084)
			(xy 339.664797 -236.384084) (xy 339.668892 -236.333356) (xy 339.681071 -236.283942) (xy 339.701019 -236.237122)
			(xy 339.72822 -236.194108) (xy 339.761968 -236.156014) (xy 339.80139 -236.123827) (xy 339.845464 -236.098381)
			(xy 339.89305 -236.080334) (xy 339.942914 -236.070154) (xy 339.993766 -236.068105) (xy 340.044287 -236.074239)
			(xy 340.093171 -236.088399) (xy 340.13915 -236.110216) (xy 340.181034 -236.139126) (xy 340.217738 -236.174381)
			(xy 340.248311 -236.215067) (xy 340.271962 -236.26013) (xy 340.288078 -236.308404) (xy 340.296242 -236.358638)
			(xy 340.296754 -236.384084) (xy 340.615282 -236.384084) (xy 340.619242 -236.33503) (xy 340.631019 -236.287246)
			(xy 340.65031 -236.24197) (xy 340.676613 -236.200374) (xy 340.709248 -236.163537) (xy 340.747369 -236.132412)
			(xy 340.78999 -236.107805) (xy 340.836006 -236.090353) (xy 340.884225 -236.080509) (xy 340.9334 -236.078528)
			(xy 340.982255 -236.08446) (xy 341.029526 -236.098152) (xy 341.073988 -236.11925) (xy 341.114491 -236.147206)
			(xy 341.149984 -236.181298) (xy 341.179549 -236.220642) (xy 341.20242 -236.264219) (xy 341.218004 -236.3109)
			(xy 341.225899 -236.359477) (xy 341.226394 -236.384084) (xy 341.544905 -236.384084) (xy 341.549 -236.333356)
			(xy 341.561179 -236.283942) (xy 341.581127 -236.237122) (xy 341.608328 -236.194108) (xy 341.642076 -236.156014)
			(xy 341.681498 -236.123827) (xy 341.725572 -236.098381) (xy 341.773158 -236.080334) (xy 341.823022 -236.070154)
			(xy 341.873874 -236.068105) (xy 341.924395 -236.074239) (xy 341.973279 -236.088399) (xy 342.019258 -236.110216)
			(xy 342.061142 -236.139126) (xy 342.097846 -236.174381) (xy 342.128419 -236.215067) (xy 342.15207 -236.26013)
			(xy 342.168186 -236.308404) (xy 342.17635 -236.358638) (xy 342.176862 -236.384084) (xy 342.49539 -236.384084)
			(xy 342.49935 -236.33503) (xy 342.511127 -236.287246) (xy 342.530418 -236.24197) (xy 342.556721 -236.200374)
			(xy 342.589356 -236.163537) (xy 342.627477 -236.132412) (xy 342.670098 -236.107805) (xy 342.716114 -236.090353)
			(xy 342.764333 -236.080509) (xy 342.813508 -236.078528) (xy 342.862363 -236.08446) (xy 342.909634 -236.098152)
			(xy 342.954096 -236.11925) (xy 342.994599 -236.147206) (xy 343.030092 -236.181298) (xy 343.059657 -236.220642)
			(xy 343.082528 -236.264219) (xy 343.098112 -236.3109) (xy 343.106007 -236.359477) (xy 343.106502 -236.384084)
			(xy 343.106007 -236.408691) (xy 343.098112 -236.457268) (xy 343.082528 -236.503949) (xy 343.059657 -236.547526)
			(xy 343.030092 -236.58687) (xy 342.994599 -236.620962) (xy 342.954096 -236.648918) (xy 342.909634 -236.670016)
			(xy 342.862363 -236.683708) (xy 342.813508 -236.68964) (xy 342.764333 -236.687659) (xy 342.716114 -236.677815)
			(xy 342.670098 -236.660363) (xy 342.627477 -236.635756) (xy 342.589356 -236.604631) (xy 342.556721 -236.567794)
			(xy 342.530418 -236.526198) (xy 342.511127 -236.480922) (xy 342.49935 -236.433138) (xy 342.49539 -236.384084)
			(xy 342.176862 -236.384084) (xy 342.17635 -236.40953) (xy 342.168186 -236.459764) (xy 342.15207 -236.508038)
			(xy 342.128419 -236.553101) (xy 342.097846 -236.593787) (xy 342.061142 -236.629042) (xy 342.019258 -236.657952)
			(xy 341.973279 -236.679769) (xy 341.924395 -236.693929) (xy 341.873874 -236.700063) (xy 341.823022 -236.698014)
			(xy 341.773158 -236.687834) (xy 341.725572 -236.669787) (xy 341.681498 -236.644341) (xy 341.642076 -236.612154)
			(xy 341.608328 -236.57406) (xy 341.581127 -236.531046) (xy 341.561179 -236.484226) (xy 341.549 -236.434812)
			(xy 341.544905 -236.384084) (xy 341.226394 -236.384084) (xy 341.225899 -236.408691) (xy 341.218004 -236.457268)
			(xy 341.20242 -236.503949) (xy 341.179549 -236.547526) (xy 341.149984 -236.58687) (xy 341.114491 -236.620962)
			(xy 341.073988 -236.648918) (xy 341.029526 -236.670016) (xy 340.982255 -236.683708) (xy 340.9334 -236.68964)
			(xy 340.884225 -236.687659) (xy 340.836006 -236.677815) (xy 340.78999 -236.660363) (xy 340.747369 -236.635756)
			(xy 340.709248 -236.604631) (xy 340.676613 -236.567794) (xy 340.65031 -236.526198) (xy 340.631019 -236.480922)
			(xy 340.619242 -236.433138) (xy 340.615282 -236.384084) (xy 340.296754 -236.384084) (xy 340.296242 -236.40953)
			(xy 340.288078 -236.459764) (xy 340.271962 -236.508038) (xy 340.248311 -236.553101) (xy 340.217738 -236.593787)
			(xy 340.181034 -236.629042) (xy 340.13915 -236.657952) (xy 340.093171 -236.679769) (xy 340.044287 -236.693929)
			(xy 339.993766 -236.700063) (xy 339.942914 -236.698014) (xy 339.89305 -236.687834) (xy 339.845464 -236.669787)
			(xy 339.80139 -236.644341) (xy 339.761968 -236.612154) (xy 339.72822 -236.57406) (xy 339.701019 -236.531046)
			(xy 339.681071 -236.484226) (xy 339.668892 -236.434812) (xy 339.664797 -236.384084) (xy 339.3567 -236.384084)
			(xy 339.356188 -236.40953) (xy 339.348024 -236.459764) (xy 339.331908 -236.508038) (xy 339.308257 -236.553101)
			(xy 339.277684 -236.593787) (xy 339.24098 -236.629042) (xy 339.199096 -236.657952) (xy 339.153117 -236.679769)
			(xy 339.104233 -236.693929) (xy 339.053712 -236.700063) (xy 339.00286 -236.698014) (xy 338.952996 -236.687834)
			(xy 338.90541 -236.669787) (xy 338.861336 -236.644341) (xy 338.821914 -236.612154) (xy 338.788166 -236.57406)
			(xy 338.760965 -236.531046) (xy 338.741017 -236.484226) (xy 338.728838 -236.434812) (xy 338.724743 -236.384084)
			(xy 338.406486 -236.384084) (xy 338.405991 -236.408691) (xy 338.398096 -236.457268) (xy 338.382512 -236.503949)
			(xy 338.359641 -236.547526) (xy 338.330076 -236.58687) (xy 338.294583 -236.620962) (xy 338.25408 -236.648918)
			(xy 338.209618 -236.670016) (xy 338.162347 -236.683708) (xy 338.113492 -236.68964) (xy 338.064317 -236.687659)
			(xy 338.016098 -236.677815) (xy 337.970082 -236.660363) (xy 337.927461 -236.635756) (xy 337.88934 -236.604631)
			(xy 337.856705 -236.567794) (xy 337.830402 -236.526198) (xy 337.811111 -236.480922) (xy 337.799334 -236.433138)
			(xy 337.795374 -236.384084) (xy 337.476846 -236.384084) (xy 337.476334 -236.40953) (xy 337.46817 -236.459764)
			(xy 337.452054 -236.508038) (xy 337.428403 -236.553101) (xy 337.39783 -236.593787) (xy 337.361126 -236.629042)
			(xy 337.319242 -236.657952) (xy 337.273263 -236.679769) (xy 337.224379 -236.693929) (xy 337.173858 -236.700063)
			(xy 337.123006 -236.698014) (xy 337.073142 -236.687834) (xy 337.025556 -236.669787) (xy 336.981482 -236.644341)
			(xy 336.94206 -236.612154) (xy 336.908312 -236.57406) (xy 336.881111 -236.531046) (xy 336.861163 -236.484226)
			(xy 336.848984 -236.434812) (xy 336.844889 -236.384084) (xy 336.526378 -236.384084) (xy 336.525883 -236.408691)
			(xy 336.517988 -236.457268) (xy 336.502404 -236.503949) (xy 336.479533 -236.547526) (xy 336.449968 -236.58687)
			(xy 336.414475 -236.620962) (xy 336.373972 -236.648918) (xy 336.32951 -236.670016) (xy 336.282239 -236.683708)
			(xy 336.233384 -236.68964) (xy 336.184209 -236.687659) (xy 336.13599 -236.677815) (xy 336.089974 -236.660363)
			(xy 336.047353 -236.635756) (xy 336.009232 -236.604631) (xy 335.976597 -236.567794) (xy 335.950294 -236.526198)
			(xy 335.931003 -236.480922) (xy 335.919226 -236.433138) (xy 335.915266 -236.384084) (xy 335.596738 -236.384084)
			(xy 335.596226 -236.40953) (xy 335.588062 -236.459764) (xy 335.571946 -236.508038) (xy 335.548295 -236.553101)
			(xy 335.517722 -236.593787) (xy 335.481018 -236.629042) (xy 335.439134 -236.657952) (xy 335.393155 -236.679769)
			(xy 335.344271 -236.693929) (xy 335.29375 -236.700063) (xy 335.242898 -236.698014) (xy 335.193034 -236.687834)
			(xy 335.145448 -236.669787) (xy 335.101374 -236.644341) (xy 335.061952 -236.612154) (xy 335.028204 -236.57406)
			(xy 335.001003 -236.531046) (xy 334.981055 -236.484226) (xy 334.968876 -236.434812) (xy 334.964781 -236.384084)
			(xy 334.646524 -236.384084) (xy 334.646029 -236.408691) (xy 334.638134 -236.457268) (xy 334.62255 -236.503949)
			(xy 334.599679 -236.547526) (xy 334.570114 -236.58687) (xy 334.534621 -236.620962) (xy 334.494118 -236.648918)
			(xy 334.449656 -236.670016) (xy 334.402385 -236.683708) (xy 334.35353 -236.68964) (xy 334.304355 -236.687659)
			(xy 334.256136 -236.677815) (xy 334.21012 -236.660363) (xy 334.167499 -236.635756) (xy 334.129378 -236.604631)
			(xy 334.096743 -236.567794) (xy 334.07044 -236.526198) (xy 334.051149 -236.480922) (xy 334.039372 -236.433138)
			(xy 334.035412 -236.384084) (xy 333.716884 -236.384084) (xy 333.716372 -236.40953) (xy 333.708208 -236.459764)
			(xy 333.692092 -236.508038) (xy 333.668441 -236.553101) (xy 333.637868 -236.593787) (xy 333.601164 -236.629042)
			(xy 333.55928 -236.657952) (xy 333.513301 -236.679769) (xy 333.464417 -236.693929) (xy 333.413896 -236.700063)
			(xy 333.363044 -236.698014) (xy 333.31318 -236.687834) (xy 333.265594 -236.669787) (xy 333.22152 -236.644341)
			(xy 333.182098 -236.612154) (xy 333.14835 -236.57406) (xy 333.121149 -236.531046) (xy 333.101201 -236.484226)
			(xy 333.089022 -236.434812) (xy 333.084927 -236.384084) (xy 332.77683 -236.384084) (xy 332.776318 -236.40953)
			(xy 332.768154 -236.459764) (xy 332.752038 -236.508038) (xy 332.728387 -236.553101) (xy 332.697814 -236.593787)
			(xy 332.66111 -236.629042) (xy 332.619226 -236.657952) (xy 332.573247 -236.679769) (xy 332.524363 -236.693929)
			(xy 332.473842 -236.700063) (xy 332.42299 -236.698014) (xy 332.373126 -236.687834) (xy 332.32554 -236.669787)
			(xy 332.281466 -236.644341) (xy 332.242044 -236.612154) (xy 332.208296 -236.57406) (xy 332.181095 -236.531046)
			(xy 332.161147 -236.484226) (xy 332.148968 -236.434812) (xy 332.144873 -236.384084) (xy 331.826362 -236.384084)
			(xy 331.825867 -236.408691) (xy 331.817972 -236.457268) (xy 331.802388 -236.503949) (xy 331.779517 -236.547526)
			(xy 331.749952 -236.58687) (xy 331.714459 -236.620962) (xy 331.673956 -236.648918) (xy 331.629494 -236.670016)
			(xy 331.582223 -236.683708) (xy 331.533368 -236.68964) (xy 331.484193 -236.687659) (xy 331.435974 -236.677815)
			(xy 331.389958 -236.660363) (xy 331.347337 -236.635756) (xy 331.309216 -236.604631) (xy 331.276581 -236.567794)
			(xy 331.250278 -236.526198) (xy 331.230987 -236.480922) (xy 331.21921 -236.433138) (xy 331.21525 -236.384084)
			(xy 330.896722 -236.384084) (xy 330.89621 -236.40953) (xy 330.888046 -236.459764) (xy 330.87193 -236.508038)
			(xy 330.848279 -236.553101) (xy 330.817706 -236.593787) (xy 330.781002 -236.629042) (xy 330.739118 -236.657952)
			(xy 330.693139 -236.679769) (xy 330.644255 -236.693929) (xy 330.593734 -236.700063) (xy 330.542882 -236.698014)
			(xy 330.493018 -236.687834) (xy 330.445432 -236.669787) (xy 330.401358 -236.644341) (xy 330.361936 -236.612154)
			(xy 330.328188 -236.57406) (xy 330.300987 -236.531046) (xy 330.281039 -236.484226) (xy 330.26886 -236.434812)
			(xy 330.264765 -236.384084) (xy 329.946508 -236.384084) (xy 329.946013 -236.408691) (xy 329.938118 -236.457268)
			(xy 329.922534 -236.503949) (xy 329.899663 -236.547526) (xy 329.870098 -236.58687) (xy 329.834605 -236.620962)
			(xy 329.794102 -236.648918) (xy 329.74964 -236.670016) (xy 329.702369 -236.683708) (xy 329.653514 -236.68964)
			(xy 329.604339 -236.687659) (xy 329.55612 -236.677815) (xy 329.510104 -236.660363) (xy 329.467483 -236.635756)
			(xy 329.429362 -236.604631) (xy 329.396727 -236.567794) (xy 329.370424 -236.526198) (xy 329.351133 -236.480922)
			(xy 329.339356 -236.433138) (xy 329.335396 -236.384084) (xy 329.016868 -236.384084) (xy 329.016356 -236.40953)
			(xy 329.008192 -236.459764) (xy 328.992076 -236.508038) (xy 328.968425 -236.553101) (xy 328.937852 -236.593787)
			(xy 328.901148 -236.629042) (xy 328.859264 -236.657952) (xy 328.813285 -236.679769) (xy 328.764401 -236.693929)
			(xy 328.71388 -236.700063) (xy 328.663028 -236.698014) (xy 328.613164 -236.687834) (xy 328.565578 -236.669787)
			(xy 328.521504 -236.644341) (xy 328.482082 -236.612154) (xy 328.448334 -236.57406) (xy 328.421133 -236.531046)
			(xy 328.401185 -236.484226) (xy 328.389006 -236.434812) (xy 328.384911 -236.384084) (xy 328.0664 -236.384084)
			(xy 328.065905 -236.408691) (xy 328.05801 -236.457268) (xy 328.042426 -236.503949) (xy 328.019555 -236.547526)
			(xy 327.98999 -236.58687) (xy 327.954497 -236.620962) (xy 327.913994 -236.648918) (xy 327.869532 -236.670016)
			(xy 327.822261 -236.683708) (xy 327.773406 -236.68964) (xy 327.724231 -236.687659) (xy 327.676012 -236.677815)
			(xy 327.629996 -236.660363) (xy 327.587375 -236.635756) (xy 327.549254 -236.604631) (xy 327.516619 -236.567794)
			(xy 327.490316 -236.526198) (xy 327.471025 -236.480922) (xy 327.459248 -236.433138) (xy 327.455288 -236.384084)
			(xy 324.903545 -236.384084) (xy 324.905872 -236.385188) (xy 324.946375 -236.413144) (xy 324.981868 -236.447236)
			(xy 325.011433 -236.48658) (xy 325.034304 -236.530157) (xy 325.049888 -236.576838) (xy 325.057783 -236.625415)
			(xy 325.058278 -236.650022) (xy 325.057783 -236.674629) (xy 325.049888 -236.723206) (xy 325.034304 -236.769887)
			(xy 325.011433 -236.813464) (xy 324.981868 -236.852808) (xy 324.946375 -236.8869) (xy 324.905872 -236.914856)
			(xy 324.86141 -236.935954) (xy 324.814139 -236.949646) (xy 324.765284 -236.955578) (xy 324.716109 -236.953597)
			(xy 324.66789 -236.943753) (xy 324.621874 -236.926301) (xy 324.579253 -236.901694) (xy 324.541132 -236.870569)
			(xy 324.508497 -236.833732) (xy 324.482194 -236.792136) (xy 324.462903 -236.74686) (xy 324.451126 -236.699076)
			(xy 324.447166 -236.650022) (xy 310.45912 -236.650022) (xy 310.45912 -237.19409) (xy 326.045334 -237.19409)
			(xy 326.049294 -237.145036) (xy 326.061071 -237.097252) (xy 326.080362 -237.051976) (xy 326.106665 -237.01038)
			(xy 326.1393 -236.973543) (xy 326.177421 -236.942418) (xy 326.220042 -236.917811) (xy 326.266058 -236.900359)
			(xy 326.314277 -236.890515) (xy 326.363452 -236.888534) (xy 326.412307 -236.894466) (xy 326.459578 -236.908158)
			(xy 326.50404 -236.929256) (xy 326.544543 -236.957212) (xy 326.580036 -236.991304) (xy 326.609601 -237.030648)
			(xy 326.632472 -237.074225) (xy 326.648056 -237.120906) (xy 326.655951 -237.169483) (xy 326.656446 -237.19409)
			(xy 328.854811 -237.19409) (xy 328.858906 -237.143362) (xy 328.871085 -237.093948) (xy 328.891033 -237.047128)
			(xy 328.918234 -237.004114) (xy 328.951982 -236.96602) (xy 328.991404 -236.933833) (xy 329.035478 -236.908387)
			(xy 329.083064 -236.89034) (xy 329.132928 -236.88016) (xy 329.18378 -236.878111) (xy 329.234301 -236.884245)
			(xy 329.283185 -236.898405) (xy 329.329164 -236.920222) (xy 329.371048 -236.949132) (xy 329.407752 -236.984387)
			(xy 329.438325 -237.025073) (xy 329.461976 -237.070136) (xy 329.478092 -237.11841) (xy 329.486256 -237.168644)
			(xy 329.486768 -237.19409) (xy 329.794865 -237.19409) (xy 329.79896 -237.143362) (xy 329.811139 -237.093948)
			(xy 329.831087 -237.047128) (xy 329.858288 -237.004114) (xy 329.892036 -236.96602) (xy 329.931458 -236.933833)
			(xy 329.975532 -236.908387) (xy 330.023118 -236.89034) (xy 330.072982 -236.88016) (xy 330.123834 -236.878111)
			(xy 330.174355 -236.884245) (xy 330.223239 -236.898405) (xy 330.269218 -236.920222) (xy 330.311102 -236.949132)
			(xy 330.347806 -236.984387) (xy 330.378379 -237.025073) (xy 330.40203 -237.070136) (xy 330.418146 -237.11841)
			(xy 330.42631 -237.168644) (xy 330.426822 -237.19409) (xy 330.74535 -237.19409) (xy 330.74931 -237.145036)
			(xy 330.761087 -237.097252) (xy 330.780378 -237.051976) (xy 330.806681 -237.01038) (xy 330.839316 -236.973543)
			(xy 330.877437 -236.942418) (xy 330.920058 -236.917811) (xy 330.966074 -236.900359) (xy 331.014293 -236.890515)
			(xy 331.063468 -236.888534) (xy 331.112323 -236.894466) (xy 331.159594 -236.908158) (xy 331.204056 -236.929256)
			(xy 331.244559 -236.957212) (xy 331.280052 -236.991304) (xy 331.309617 -237.030648) (xy 331.332488 -237.074225)
			(xy 331.348072 -237.120906) (xy 331.355967 -237.169483) (xy 331.356462 -237.19409) (xy 331.674973 -237.19409)
			(xy 331.679068 -237.143362) (xy 331.691247 -237.093948) (xy 331.711195 -237.047128) (xy 331.738396 -237.004114)
			(xy 331.772144 -236.96602) (xy 331.811566 -236.933833) (xy 331.85564 -236.908387) (xy 331.903226 -236.89034)
			(xy 331.95309 -236.88016) (xy 332.003942 -236.878111) (xy 332.054463 -236.884245) (xy 332.103347 -236.898405)
			(xy 332.149326 -236.920222) (xy 332.19121 -236.949132) (xy 332.227914 -236.984387) (xy 332.258487 -237.025073)
			(xy 332.282138 -237.070136) (xy 332.298254 -237.11841) (xy 332.306418 -237.168644) (xy 332.30693 -237.19409)
			(xy 332.625204 -237.19409) (xy 332.629164 -237.145036) (xy 332.640941 -237.097252) (xy 332.660232 -237.051976)
			(xy 332.686535 -237.01038) (xy 332.71917 -236.973543) (xy 332.757291 -236.942418) (xy 332.799912 -236.917811)
			(xy 332.845928 -236.900359) (xy 332.894147 -236.890515) (xy 332.943322 -236.888534) (xy 332.992177 -236.894466)
			(xy 333.039448 -236.908158) (xy 333.08391 -236.929256) (xy 333.124413 -236.957212) (xy 333.159906 -236.991304)
			(xy 333.189471 -237.030648) (xy 333.212342 -237.074225) (xy 333.227926 -237.120906) (xy 333.235821 -237.169483)
			(xy 333.236316 -237.19409) (xy 333.554827 -237.19409) (xy 333.558922 -237.143362) (xy 333.571101 -237.093948)
			(xy 333.591049 -237.047128) (xy 333.61825 -237.004114) (xy 333.651998 -236.96602) (xy 333.69142 -236.933833)
			(xy 333.735494 -236.908387) (xy 333.78308 -236.89034) (xy 333.832944 -236.88016) (xy 333.883796 -236.878111)
			(xy 333.934317 -236.884245) (xy 333.983201 -236.898405) (xy 334.02918 -236.920222) (xy 334.071064 -236.949132)
			(xy 334.107768 -236.984387) (xy 334.138341 -237.025073) (xy 334.161992 -237.070136) (xy 334.178108 -237.11841)
			(xy 334.186272 -237.168644) (xy 334.186784 -237.19409) (xy 335.434935 -237.19409) (xy 335.43903 -237.143362)
			(xy 335.451209 -237.093948) (xy 335.471157 -237.047128) (xy 335.498358 -237.004114) (xy 335.532106 -236.96602)
			(xy 335.571528 -236.933833) (xy 335.615602 -236.908387) (xy 335.663188 -236.89034) (xy 335.713052 -236.88016)
			(xy 335.763904 -236.878111) (xy 335.814425 -236.884245) (xy 335.863309 -236.898405) (xy 335.909288 -236.920222)
			(xy 335.951172 -236.949132) (xy 335.987876 -236.984387) (xy 336.018449 -237.025073) (xy 336.0421 -237.070136)
			(xy 336.058216 -237.11841) (xy 336.06638 -237.168644) (xy 336.066892 -237.19409) (xy 336.374989 -237.19409)
			(xy 336.379084 -237.143362) (xy 336.391263 -237.093948) (xy 336.411211 -237.047128) (xy 336.438412 -237.004114)
			(xy 336.47216 -236.96602) (xy 336.511582 -236.933833) (xy 336.555656 -236.908387) (xy 336.603242 -236.89034)
			(xy 336.653106 -236.88016) (xy 336.703958 -236.878111) (xy 336.754479 -236.884245) (xy 336.803363 -236.898405)
			(xy 336.849342 -236.920222) (xy 336.891226 -236.949132) (xy 336.92793 -236.984387) (xy 336.958503 -237.025073)
			(xy 336.982154 -237.070136) (xy 336.99827 -237.11841) (xy 337.006434 -237.168644) (xy 337.006946 -237.19409)
			(xy 337.32522 -237.19409) (xy 337.32918 -237.145036) (xy 337.340957 -237.097252) (xy 337.360248 -237.051976)
			(xy 337.386551 -237.01038) (xy 337.419186 -236.973543) (xy 337.457307 -236.942418) (xy 337.499928 -236.917811)
			(xy 337.545944 -236.900359) (xy 337.594163 -236.890515) (xy 337.643338 -236.888534) (xy 337.692193 -236.894466)
			(xy 337.739464 -236.908158) (xy 337.783926 -236.929256) (xy 337.824429 -236.957212) (xy 337.859922 -236.991304)
			(xy 337.889487 -237.030648) (xy 337.912358 -237.074225) (xy 337.927942 -237.120906) (xy 337.935837 -237.169483)
			(xy 337.936332 -237.19409) (xy 338.254843 -237.19409) (xy 338.258938 -237.143362) (xy 338.271117 -237.093948)
			(xy 338.291065 -237.047128) (xy 338.318266 -237.004114) (xy 338.352014 -236.96602) (xy 338.391436 -236.933833)
			(xy 338.43551 -236.908387) (xy 338.483096 -236.89034) (xy 338.53296 -236.88016) (xy 338.583812 -236.878111)
			(xy 338.634333 -236.884245) (xy 338.683217 -236.898405) (xy 338.729196 -236.920222) (xy 338.77108 -236.949132)
			(xy 338.807784 -236.984387) (xy 338.838357 -237.025073) (xy 338.862008 -237.070136) (xy 338.878124 -237.11841)
			(xy 338.886288 -237.168644) (xy 338.8868 -237.19409) (xy 339.205328 -237.19409) (xy 339.209288 -237.145036)
			(xy 339.221065 -237.097252) (xy 339.240356 -237.051976) (xy 339.266659 -237.01038) (xy 339.299294 -236.973543)
			(xy 339.337415 -236.942418) (xy 339.380036 -236.917811) (xy 339.426052 -236.900359) (xy 339.474271 -236.890515)
			(xy 339.523446 -236.888534) (xy 339.572301 -236.894466) (xy 339.619572 -236.908158) (xy 339.664034 -236.929256)
			(xy 339.704537 -236.957212) (xy 339.74003 -236.991304) (xy 339.769595 -237.030648) (xy 339.792466 -237.074225)
			(xy 339.80805 -237.120906) (xy 339.815945 -237.169483) (xy 339.81644 -237.19409) (xy 340.134951 -237.19409)
			(xy 340.139046 -237.143362) (xy 340.151225 -237.093948) (xy 340.171173 -237.047128) (xy 340.198374 -237.004114)
			(xy 340.232122 -236.96602) (xy 340.271544 -236.933833) (xy 340.315618 -236.908387) (xy 340.363204 -236.89034)
			(xy 340.413068 -236.88016) (xy 340.46392 -236.878111) (xy 340.514441 -236.884245) (xy 340.563325 -236.898405)
			(xy 340.609304 -236.920222) (xy 340.651188 -236.949132) (xy 340.687892 -236.984387) (xy 340.718465 -237.025073)
			(xy 340.742116 -237.070136) (xy 340.758232 -237.11841) (xy 340.766396 -237.168644) (xy 340.766908 -237.19409)
			(xy 342.014805 -237.19409) (xy 342.0189 -237.143362) (xy 342.031079 -237.093948) (xy 342.051027 -237.047128)
			(xy 342.078228 -237.004114) (xy 342.111976 -236.96602) (xy 342.151398 -236.933833) (xy 342.195472 -236.908387)
			(xy 342.243058 -236.89034) (xy 342.292922 -236.88016) (xy 342.343774 -236.878111) (xy 342.394295 -236.884245)
			(xy 342.443179 -236.898405) (xy 342.489158 -236.920222) (xy 342.531042 -236.949132) (xy 342.567746 -236.984387)
			(xy 342.598319 -237.025073) (xy 342.62197 -237.070136) (xy 342.638086 -237.11841) (xy 342.64625 -237.168644)
			(xy 342.646762 -237.19409) (xy 342.954859 -237.19409) (xy 342.958954 -237.143362) (xy 342.971133 -237.093948)
			(xy 342.991081 -237.047128) (xy 343.018282 -237.004114) (xy 343.05203 -236.96602) (xy 343.091452 -236.933833)
			(xy 343.135526 -236.908387) (xy 343.183112 -236.89034) (xy 343.232976 -236.88016) (xy 343.283828 -236.878111)
			(xy 343.334349 -236.884245) (xy 343.383233 -236.898405) (xy 343.429212 -236.920222) (xy 343.471096 -236.949132)
			(xy 343.5078 -236.984387) (xy 343.538373 -237.025073) (xy 343.562024 -237.070136) (xy 343.57814 -237.11841)
			(xy 343.586304 -237.168644) (xy 343.586816 -237.19409) (xy 343.586304 -237.219536) (xy 343.57814 -237.26977)
			(xy 343.562024 -237.318044) (xy 343.538373 -237.363107) (xy 343.5078 -237.403793) (xy 343.471096 -237.439048)
			(xy 343.429212 -237.467958) (xy 343.383233 -237.489775) (xy 343.334349 -237.503935) (xy 343.283828 -237.510069)
			(xy 343.232976 -237.50802) (xy 343.183112 -237.49784) (xy 343.135526 -237.479793) (xy 343.091452 -237.454347)
			(xy 343.05203 -237.42216) (xy 343.018282 -237.384066) (xy 342.991081 -237.341052) (xy 342.971133 -237.294232)
			(xy 342.958954 -237.244818) (xy 342.954859 -237.19409) (xy 342.646762 -237.19409) (xy 342.64625 -237.219536)
			(xy 342.638086 -237.26977) (xy 342.62197 -237.318044) (xy 342.598319 -237.363107) (xy 342.567746 -237.403793)
			(xy 342.531042 -237.439048) (xy 342.489158 -237.467958) (xy 342.443179 -237.489775) (xy 342.394295 -237.503935)
			(xy 342.343774 -237.510069) (xy 342.292922 -237.50802) (xy 342.243058 -237.49784) (xy 342.195472 -237.479793)
			(xy 342.151398 -237.454347) (xy 342.111976 -237.42216) (xy 342.078228 -237.384066) (xy 342.051027 -237.341052)
			(xy 342.031079 -237.294232) (xy 342.0189 -237.244818) (xy 342.014805 -237.19409) (xy 340.766908 -237.19409)
			(xy 340.766396 -237.219536) (xy 340.758232 -237.26977) (xy 340.742116 -237.318044) (xy 340.718465 -237.363107)
			(xy 340.687892 -237.403793) (xy 340.651188 -237.439048) (xy 340.609304 -237.467958) (xy 340.563325 -237.489775)
			(xy 340.514441 -237.503935) (xy 340.46392 -237.510069) (xy 340.413068 -237.50802) (xy 340.363204 -237.49784)
			(xy 340.315618 -237.479793) (xy 340.271544 -237.454347) (xy 340.232122 -237.42216) (xy 340.198374 -237.384066)
			(xy 340.171173 -237.341052) (xy 340.151225 -237.294232) (xy 340.139046 -237.244818) (xy 340.134951 -237.19409)
			(xy 339.81644 -237.19409) (xy 339.815945 -237.218697) (xy 339.80805 -237.267274) (xy 339.792466 -237.313955)
			(xy 339.769595 -237.357532) (xy 339.74003 -237.396876) (xy 339.704537 -237.430968) (xy 339.664034 -237.458924)
			(xy 339.619572 -237.480022) (xy 339.572301 -237.493714) (xy 339.523446 -237.499646) (xy 339.474271 -237.497665)
			(xy 339.426052 -237.487821) (xy 339.380036 -237.470369) (xy 339.337415 -237.445762) (xy 339.299294 -237.414637)
			(xy 339.266659 -237.3778) (xy 339.240356 -237.336204) (xy 339.221065 -237.290928) (xy 339.209288 -237.243144)
			(xy 339.205328 -237.19409) (xy 338.8868 -237.19409) (xy 338.886288 -237.219536) (xy 338.878124 -237.26977)
			(xy 338.862008 -237.318044) (xy 338.838357 -237.363107) (xy 338.807784 -237.403793) (xy 338.77108 -237.439048)
			(xy 338.729196 -237.467958) (xy 338.683217 -237.489775) (xy 338.634333 -237.503935) (xy 338.583812 -237.510069)
			(xy 338.53296 -237.50802) (xy 338.483096 -237.49784) (xy 338.43551 -237.479793) (xy 338.391436 -237.454347)
			(xy 338.352014 -237.42216) (xy 338.318266 -237.384066) (xy 338.291065 -237.341052) (xy 338.271117 -237.294232)
			(xy 338.258938 -237.244818) (xy 338.254843 -237.19409) (xy 337.936332 -237.19409) (xy 337.935837 -237.218697)
			(xy 337.927942 -237.267274) (xy 337.912358 -237.313955) (xy 337.889487 -237.357532) (xy 337.859922 -237.396876)
			(xy 337.824429 -237.430968) (xy 337.783926 -237.458924) (xy 337.739464 -237.480022) (xy 337.692193 -237.493714)
			(xy 337.643338 -237.499646) (xy 337.594163 -237.497665) (xy 337.545944 -237.487821) (xy 337.499928 -237.470369)
			(xy 337.457307 -237.445762) (xy 337.419186 -237.414637) (xy 337.386551 -237.3778) (xy 337.360248 -237.336204)
			(xy 337.340957 -237.290928) (xy 337.32918 -237.243144) (xy 337.32522 -237.19409) (xy 337.006946 -237.19409)
			(xy 337.006434 -237.219536) (xy 336.99827 -237.26977) (xy 336.982154 -237.318044) (xy 336.958503 -237.363107)
			(xy 336.92793 -237.403793) (xy 336.891226 -237.439048) (xy 336.849342 -237.467958) (xy 336.803363 -237.489775)
			(xy 336.754479 -237.503935) (xy 336.703958 -237.510069) (xy 336.653106 -237.50802) (xy 336.603242 -237.49784)
			(xy 336.555656 -237.479793) (xy 336.511582 -237.454347) (xy 336.47216 -237.42216) (xy 336.438412 -237.384066)
			(xy 336.411211 -237.341052) (xy 336.391263 -237.294232) (xy 336.379084 -237.244818) (xy 336.374989 -237.19409)
			(xy 336.066892 -237.19409) (xy 336.06638 -237.219536) (xy 336.058216 -237.26977) (xy 336.0421 -237.318044)
			(xy 336.018449 -237.363107) (xy 335.987876 -237.403793) (xy 335.951172 -237.439048) (xy 335.909288 -237.467958)
			(xy 335.863309 -237.489775) (xy 335.814425 -237.503935) (xy 335.763904 -237.510069) (xy 335.713052 -237.50802)
			(xy 335.663188 -237.49784) (xy 335.615602 -237.479793) (xy 335.571528 -237.454347) (xy 335.532106 -237.42216)
			(xy 335.498358 -237.384066) (xy 335.471157 -237.341052) (xy 335.451209 -237.294232) (xy 335.43903 -237.244818)
			(xy 335.434935 -237.19409) (xy 334.186784 -237.19409) (xy 334.186272 -237.219536) (xy 334.178108 -237.26977)
			(xy 334.161992 -237.318044) (xy 334.138341 -237.363107) (xy 334.107768 -237.403793) (xy 334.071064 -237.439048)
			(xy 334.02918 -237.467958) (xy 333.983201 -237.489775) (xy 333.934317 -237.503935) (xy 333.883796 -237.510069)
			(xy 333.832944 -237.50802) (xy 333.78308 -237.49784) (xy 333.735494 -237.479793) (xy 333.69142 -237.454347)
			(xy 333.651998 -237.42216) (xy 333.61825 -237.384066) (xy 333.591049 -237.341052) (xy 333.571101 -237.294232)
			(xy 333.558922 -237.244818) (xy 333.554827 -237.19409) (xy 333.236316 -237.19409) (xy 333.235821 -237.218697)
			(xy 333.227926 -237.267274) (xy 333.212342 -237.313955) (xy 333.189471 -237.357532) (xy 333.159906 -237.396876)
			(xy 333.124413 -237.430968) (xy 333.08391 -237.458924) (xy 333.039448 -237.480022) (xy 332.992177 -237.493714)
			(xy 332.943322 -237.499646) (xy 332.894147 -237.497665) (xy 332.845928 -237.487821) (xy 332.799912 -237.470369)
			(xy 332.757291 -237.445762) (xy 332.71917 -237.414637) (xy 332.686535 -237.3778) (xy 332.660232 -237.336204)
			(xy 332.640941 -237.290928) (xy 332.629164 -237.243144) (xy 332.625204 -237.19409) (xy 332.30693 -237.19409)
			(xy 332.306418 -237.219536) (xy 332.298254 -237.26977) (xy 332.282138 -237.318044) (xy 332.258487 -237.363107)
			(xy 332.227914 -237.403793) (xy 332.19121 -237.439048) (xy 332.149326 -237.467958) (xy 332.103347 -237.489775)
			(xy 332.054463 -237.503935) (xy 332.003942 -237.510069) (xy 331.95309 -237.50802) (xy 331.903226 -237.49784)
			(xy 331.85564 -237.479793) (xy 331.811566 -237.454347) (xy 331.772144 -237.42216) (xy 331.738396 -237.384066)
			(xy 331.711195 -237.341052) (xy 331.691247 -237.294232) (xy 331.679068 -237.244818) (xy 331.674973 -237.19409)
			(xy 331.356462 -237.19409) (xy 331.355967 -237.218697) (xy 331.348072 -237.267274) (xy 331.332488 -237.313955)
			(xy 331.309617 -237.357532) (xy 331.280052 -237.396876) (xy 331.244559 -237.430968) (xy 331.204056 -237.458924)
			(xy 331.159594 -237.480022) (xy 331.112323 -237.493714) (xy 331.063468 -237.499646) (xy 331.014293 -237.497665)
			(xy 330.966074 -237.487821) (xy 330.920058 -237.470369) (xy 330.877437 -237.445762) (xy 330.839316 -237.414637)
			(xy 330.806681 -237.3778) (xy 330.780378 -237.336204) (xy 330.761087 -237.290928) (xy 330.74931 -237.243144)
			(xy 330.74535 -237.19409) (xy 330.426822 -237.19409) (xy 330.42631 -237.219536) (xy 330.418146 -237.26977)
			(xy 330.40203 -237.318044) (xy 330.378379 -237.363107) (xy 330.347806 -237.403793) (xy 330.311102 -237.439048)
			(xy 330.269218 -237.467958) (xy 330.223239 -237.489775) (xy 330.174355 -237.503935) (xy 330.123834 -237.510069)
			(xy 330.072982 -237.50802) (xy 330.023118 -237.49784) (xy 329.975532 -237.479793) (xy 329.931458 -237.454347)
			(xy 329.892036 -237.42216) (xy 329.858288 -237.384066) (xy 329.831087 -237.341052) (xy 329.811139 -237.294232)
			(xy 329.79896 -237.244818) (xy 329.794865 -237.19409) (xy 329.486768 -237.19409) (xy 329.486256 -237.219536)
			(xy 329.478092 -237.26977) (xy 329.461976 -237.318044) (xy 329.438325 -237.363107) (xy 329.407752 -237.403793)
			(xy 329.371048 -237.439048) (xy 329.329164 -237.467958) (xy 329.283185 -237.489775) (xy 329.234301 -237.503935)
			(xy 329.18378 -237.510069) (xy 329.132928 -237.50802) (xy 329.083064 -237.49784) (xy 329.035478 -237.479793)
			(xy 328.991404 -237.454347) (xy 328.951982 -237.42216) (xy 328.918234 -237.384066) (xy 328.891033 -237.341052)
			(xy 328.871085 -237.294232) (xy 328.858906 -237.244818) (xy 328.854811 -237.19409) (xy 326.656446 -237.19409)
			(xy 326.655951 -237.218697) (xy 326.648056 -237.267274) (xy 326.632472 -237.313955) (xy 326.609601 -237.357532)
			(xy 326.580036 -237.396876) (xy 326.544543 -237.430968) (xy 326.50404 -237.458924) (xy 326.459578 -237.480022)
			(xy 326.412307 -237.493714) (xy 326.363452 -237.499646) (xy 326.314277 -237.497665) (xy 326.266058 -237.487821)
			(xy 326.220042 -237.470369) (xy 326.177421 -237.445762) (xy 326.1393 -237.414637) (xy 326.106665 -237.3778)
			(xy 326.080362 -237.336204) (xy 326.061071 -237.290928) (xy 326.049294 -237.243144) (xy 326.045334 -237.19409)
			(xy 310.45912 -237.19409) (xy 310.45912 -238.270034) (xy 324.447166 -238.270034) (xy 324.451126 -238.22098)
			(xy 324.462903 -238.173196) (xy 324.482194 -238.12792) (xy 324.508497 -238.086324) (xy 324.541132 -238.049487)
			(xy 324.579253 -238.018362) (xy 324.621874 -237.993755) (xy 324.66789 -237.976303) (xy 324.716109 -237.966459)
			(xy 324.765284 -237.964478) (xy 324.814139 -237.97041) (xy 324.86141 -237.984102) (xy 324.903545 -238.004096)
			(xy 327.455288 -238.004096) (xy 327.459248 -237.955042) (xy 327.471025 -237.907258) (xy 327.490316 -237.861982)
			(xy 327.516619 -237.820386) (xy 327.549254 -237.783549) (xy 327.587375 -237.752424) (xy 327.629996 -237.727817)
			(xy 327.676012 -237.710365) (xy 327.724231 -237.700521) (xy 327.773406 -237.69854) (xy 327.822261 -237.704472)
			(xy 327.869532 -237.718164) (xy 327.913994 -237.739262) (xy 327.954497 -237.767218) (xy 327.98999 -237.80131)
			(xy 328.019555 -237.840654) (xy 328.042426 -237.884231) (xy 328.05801 -237.930912) (xy 328.065905 -237.979489)
			(xy 328.0664 -238.004096) (xy 328.384911 -238.004096) (xy 328.389006 -237.953368) (xy 328.401185 -237.903954)
			(xy 328.421133 -237.857134) (xy 328.448334 -237.81412) (xy 328.482082 -237.776026) (xy 328.521504 -237.743839)
			(xy 328.565578 -237.718393) (xy 328.613164 -237.700346) (xy 328.663028 -237.690166) (xy 328.71388 -237.688117)
			(xy 328.764401 -237.694251) (xy 328.813285 -237.708411) (xy 328.859264 -237.730228) (xy 328.901148 -237.759138)
			(xy 328.937852 -237.794393) (xy 328.968425 -237.835079) (xy 328.992076 -237.880142) (xy 329.008192 -237.928416)
			(xy 329.016356 -237.97865) (xy 329.016868 -238.004096) (xy 329.335396 -238.004096) (xy 329.339356 -237.955042)
			(xy 329.351133 -237.907258) (xy 329.370424 -237.861982) (xy 329.396727 -237.820386) (xy 329.429362 -237.783549)
			(xy 329.467483 -237.752424) (xy 329.510104 -237.727817) (xy 329.55612 -237.710365) (xy 329.604339 -237.700521)
			(xy 329.653514 -237.69854) (xy 329.702369 -237.704472) (xy 329.74964 -237.718164) (xy 329.794102 -237.739262)
			(xy 329.834605 -237.767218) (xy 329.870098 -237.80131) (xy 329.899663 -237.840654) (xy 329.922534 -237.884231)
			(xy 329.938118 -237.930912) (xy 329.946013 -237.979489) (xy 329.946508 -238.004096) (xy 330.264765 -238.004096)
			(xy 330.26886 -237.953368) (xy 330.281039 -237.903954) (xy 330.300987 -237.857134) (xy 330.328188 -237.81412)
			(xy 330.361936 -237.776026) (xy 330.401358 -237.743839) (xy 330.445432 -237.718393) (xy 330.493018 -237.700346)
			(xy 330.542882 -237.690166) (xy 330.593734 -237.688117) (xy 330.644255 -237.694251) (xy 330.693139 -237.708411)
			(xy 330.739118 -237.730228) (xy 330.781002 -237.759138) (xy 330.817706 -237.794393) (xy 330.848279 -237.835079)
			(xy 330.87193 -237.880142) (xy 330.888046 -237.928416) (xy 330.89621 -237.97865) (xy 330.896722 -238.004096)
			(xy 331.21525 -238.004096) (xy 331.21921 -237.955042) (xy 331.230987 -237.907258) (xy 331.250278 -237.861982)
			(xy 331.276581 -237.820386) (xy 331.309216 -237.783549) (xy 331.347337 -237.752424) (xy 331.389958 -237.727817)
			(xy 331.435974 -237.710365) (xy 331.484193 -237.700521) (xy 331.533368 -237.69854) (xy 331.582223 -237.704472)
			(xy 331.629494 -237.718164) (xy 331.673956 -237.739262) (xy 331.714459 -237.767218) (xy 331.749952 -237.80131)
			(xy 331.779517 -237.840654) (xy 331.802388 -237.884231) (xy 331.817972 -237.930912) (xy 331.825867 -237.979489)
			(xy 331.826362 -238.004096) (xy 332.144873 -238.004096) (xy 332.148968 -237.953368) (xy 332.161147 -237.903954)
			(xy 332.181095 -237.857134) (xy 332.208296 -237.81412) (xy 332.242044 -237.776026) (xy 332.281466 -237.743839)
			(xy 332.32554 -237.718393) (xy 332.373126 -237.700346) (xy 332.42299 -237.690166) (xy 332.473842 -237.688117)
			(xy 332.524363 -237.694251) (xy 332.573247 -237.708411) (xy 332.619226 -237.730228) (xy 332.66111 -237.759138)
			(xy 332.697814 -237.794393) (xy 332.728387 -237.835079) (xy 332.752038 -237.880142) (xy 332.768154 -237.928416)
			(xy 332.776318 -237.97865) (xy 332.77683 -238.004096) (xy 333.084927 -238.004096) (xy 333.089022 -237.953368)
			(xy 333.101201 -237.903954) (xy 333.121149 -237.857134) (xy 333.14835 -237.81412) (xy 333.182098 -237.776026)
			(xy 333.22152 -237.743839) (xy 333.265594 -237.718393) (xy 333.31318 -237.700346) (xy 333.363044 -237.690166)
			(xy 333.413896 -237.688117) (xy 333.464417 -237.694251) (xy 333.513301 -237.708411) (xy 333.55928 -237.730228)
			(xy 333.601164 -237.759138) (xy 333.637868 -237.794393) (xy 333.668441 -237.835079) (xy 333.692092 -237.880142)
			(xy 333.708208 -237.928416) (xy 333.716372 -237.97865) (xy 333.716884 -238.004096) (xy 334.035412 -238.004096)
			(xy 334.039372 -237.955042) (xy 334.051149 -237.907258) (xy 334.07044 -237.861982) (xy 334.096743 -237.820386)
			(xy 334.129378 -237.783549) (xy 334.167499 -237.752424) (xy 334.21012 -237.727817) (xy 334.256136 -237.710365)
			(xy 334.304355 -237.700521) (xy 334.35353 -237.69854) (xy 334.402385 -237.704472) (xy 334.449656 -237.718164)
			(xy 334.494118 -237.739262) (xy 334.534621 -237.767218) (xy 334.570114 -237.80131) (xy 334.599679 -237.840654)
			(xy 334.62255 -237.884231) (xy 334.638134 -237.930912) (xy 334.646029 -237.979489) (xy 334.646524 -238.004096)
			(xy 334.964781 -238.004096) (xy 334.968876 -237.953368) (xy 334.981055 -237.903954) (xy 335.001003 -237.857134)
			(xy 335.028204 -237.81412) (xy 335.061952 -237.776026) (xy 335.101374 -237.743839) (xy 335.145448 -237.718393)
			(xy 335.193034 -237.700346) (xy 335.242898 -237.690166) (xy 335.29375 -237.688117) (xy 335.344271 -237.694251)
			(xy 335.393155 -237.708411) (xy 335.439134 -237.730228) (xy 335.481018 -237.759138) (xy 335.517722 -237.794393)
			(xy 335.548295 -237.835079) (xy 335.571946 -237.880142) (xy 335.588062 -237.928416) (xy 335.596226 -237.97865)
			(xy 335.596738 -238.004096) (xy 335.915266 -238.004096) (xy 335.919226 -237.955042) (xy 335.931003 -237.907258)
			(xy 335.950294 -237.861982) (xy 335.976597 -237.820386) (xy 336.009232 -237.783549) (xy 336.047353 -237.752424)
			(xy 336.089974 -237.727817) (xy 336.13599 -237.710365) (xy 336.184209 -237.700521) (xy 336.233384 -237.69854)
			(xy 336.282239 -237.704472) (xy 336.32951 -237.718164) (xy 336.373972 -237.739262) (xy 336.414475 -237.767218)
			(xy 336.449968 -237.80131) (xy 336.479533 -237.840654) (xy 336.502404 -237.884231) (xy 336.517988 -237.930912)
			(xy 336.525883 -237.979489) (xy 336.526378 -238.004096) (xy 336.844889 -238.004096) (xy 336.848984 -237.953368)
			(xy 336.861163 -237.903954) (xy 336.881111 -237.857134) (xy 336.908312 -237.81412) (xy 336.94206 -237.776026)
			(xy 336.981482 -237.743839) (xy 337.025556 -237.718393) (xy 337.073142 -237.700346) (xy 337.123006 -237.690166)
			(xy 337.173858 -237.688117) (xy 337.224379 -237.694251) (xy 337.273263 -237.708411) (xy 337.319242 -237.730228)
			(xy 337.361126 -237.759138) (xy 337.39783 -237.794393) (xy 337.428403 -237.835079) (xy 337.452054 -237.880142)
			(xy 337.46817 -237.928416) (xy 337.476334 -237.97865) (xy 337.476846 -238.004096) (xy 337.795374 -238.004096)
			(xy 337.799334 -237.955042) (xy 337.811111 -237.907258) (xy 337.830402 -237.861982) (xy 337.856705 -237.820386)
			(xy 337.88934 -237.783549) (xy 337.927461 -237.752424) (xy 337.970082 -237.727817) (xy 338.016098 -237.710365)
			(xy 338.064317 -237.700521) (xy 338.113492 -237.69854) (xy 338.162347 -237.704472) (xy 338.209618 -237.718164)
			(xy 338.25408 -237.739262) (xy 338.294583 -237.767218) (xy 338.330076 -237.80131) (xy 338.359641 -237.840654)
			(xy 338.382512 -237.884231) (xy 338.398096 -237.930912) (xy 338.405991 -237.979489) (xy 338.406486 -238.004096)
			(xy 338.724743 -238.004096) (xy 338.728838 -237.953368) (xy 338.741017 -237.903954) (xy 338.760965 -237.857134)
			(xy 338.788166 -237.81412) (xy 338.821914 -237.776026) (xy 338.861336 -237.743839) (xy 338.90541 -237.718393)
			(xy 338.952996 -237.700346) (xy 339.00286 -237.690166) (xy 339.053712 -237.688117) (xy 339.104233 -237.694251)
			(xy 339.153117 -237.708411) (xy 339.199096 -237.730228) (xy 339.24098 -237.759138) (xy 339.277684 -237.794393)
			(xy 339.308257 -237.835079) (xy 339.331908 -237.880142) (xy 339.348024 -237.928416) (xy 339.356188 -237.97865)
			(xy 339.3567 -238.004096) (xy 339.664797 -238.004096) (xy 339.668892 -237.953368) (xy 339.681071 -237.903954)
			(xy 339.701019 -237.857134) (xy 339.72822 -237.81412) (xy 339.761968 -237.776026) (xy 339.80139 -237.743839)
			(xy 339.845464 -237.718393) (xy 339.89305 -237.700346) (xy 339.942914 -237.690166) (xy 339.993766 -237.688117)
			(xy 340.044287 -237.694251) (xy 340.093171 -237.708411) (xy 340.13915 -237.730228) (xy 340.181034 -237.759138)
			(xy 340.217738 -237.794393) (xy 340.248311 -237.835079) (xy 340.271962 -237.880142) (xy 340.288078 -237.928416)
			(xy 340.296242 -237.97865) (xy 340.296754 -238.004096) (xy 340.615282 -238.004096) (xy 340.619242 -237.955042)
			(xy 340.631019 -237.907258) (xy 340.65031 -237.861982) (xy 340.676613 -237.820386) (xy 340.709248 -237.783549)
			(xy 340.747369 -237.752424) (xy 340.78999 -237.727817) (xy 340.836006 -237.710365) (xy 340.884225 -237.700521)
			(xy 340.9334 -237.69854) (xy 340.982255 -237.704472) (xy 341.029526 -237.718164) (xy 341.073988 -237.739262)
			(xy 341.114491 -237.767218) (xy 341.149984 -237.80131) (xy 341.179549 -237.840654) (xy 341.20242 -237.884231)
			(xy 341.218004 -237.930912) (xy 341.225899 -237.979489) (xy 341.226394 -238.004096) (xy 341.544905 -238.004096)
			(xy 341.549 -237.953368) (xy 341.561179 -237.903954) (xy 341.581127 -237.857134) (xy 341.608328 -237.81412)
			(xy 341.642076 -237.776026) (xy 341.681498 -237.743839) (xy 341.725572 -237.718393) (xy 341.773158 -237.700346)
			(xy 341.823022 -237.690166) (xy 341.873874 -237.688117) (xy 341.924395 -237.694251) (xy 341.973279 -237.708411)
			(xy 342.019258 -237.730228) (xy 342.061142 -237.759138) (xy 342.097846 -237.794393) (xy 342.128419 -237.835079)
			(xy 342.15207 -237.880142) (xy 342.168186 -237.928416) (xy 342.17635 -237.97865) (xy 342.176862 -238.004096)
			(xy 342.49539 -238.004096) (xy 342.49935 -237.955042) (xy 342.511127 -237.907258) (xy 342.530418 -237.861982)
			(xy 342.556721 -237.820386) (xy 342.589356 -237.783549) (xy 342.627477 -237.752424) (xy 342.670098 -237.727817)
			(xy 342.716114 -237.710365) (xy 342.764333 -237.700521) (xy 342.813508 -237.69854) (xy 342.862363 -237.704472)
			(xy 342.909634 -237.718164) (xy 342.954096 -237.739262) (xy 342.994599 -237.767218) (xy 343.030092 -237.80131)
			(xy 343.059657 -237.840654) (xy 343.082528 -237.884231) (xy 343.098112 -237.930912) (xy 343.106007 -237.979489)
			(xy 343.106502 -238.004096) (xy 343.106007 -238.028703) (xy 343.098112 -238.07728) (xy 343.082528 -238.123961)
			(xy 343.059657 -238.167538) (xy 343.030092 -238.206882) (xy 342.994599 -238.240974) (xy 342.954096 -238.26893)
			(xy 342.909634 -238.290028) (xy 342.862363 -238.30372) (xy 342.813508 -238.309652) (xy 342.764333 -238.307671)
			(xy 342.716114 -238.297827) (xy 342.670098 -238.280375) (xy 342.627477 -238.255768) (xy 342.589356 -238.224643)
			(xy 342.556721 -238.187806) (xy 342.530418 -238.14621) (xy 342.511127 -238.100934) (xy 342.49935 -238.05315)
			(xy 342.49539 -238.004096) (xy 342.176862 -238.004096) (xy 342.17635 -238.029542) (xy 342.168186 -238.079776)
			(xy 342.15207 -238.12805) (xy 342.128419 -238.173113) (xy 342.097846 -238.213799) (xy 342.061142 -238.249054)
			(xy 342.019258 -238.277964) (xy 341.973279 -238.299781) (xy 341.924395 -238.313941) (xy 341.873874 -238.320075)
			(xy 341.823022 -238.318026) (xy 341.773158 -238.307846) (xy 341.725572 -238.289799) (xy 341.681498 -238.264353)
			(xy 341.642076 -238.232166) (xy 341.608328 -238.194072) (xy 341.581127 -238.151058) (xy 341.561179 -238.104238)
			(xy 341.549 -238.054824) (xy 341.544905 -238.004096) (xy 341.226394 -238.004096) (xy 341.225899 -238.028703)
			(xy 341.218004 -238.07728) (xy 341.20242 -238.123961) (xy 341.179549 -238.167538) (xy 341.149984 -238.206882)
			(xy 341.114491 -238.240974) (xy 341.073988 -238.26893) (xy 341.029526 -238.290028) (xy 340.982255 -238.30372)
			(xy 340.9334 -238.309652) (xy 340.884225 -238.307671) (xy 340.836006 -238.297827) (xy 340.78999 -238.280375)
			(xy 340.747369 -238.255768) (xy 340.709248 -238.224643) (xy 340.676613 -238.187806) (xy 340.65031 -238.14621)
			(xy 340.631019 -238.100934) (xy 340.619242 -238.05315) (xy 340.615282 -238.004096) (xy 340.296754 -238.004096)
			(xy 340.296242 -238.029542) (xy 340.288078 -238.079776) (xy 340.271962 -238.12805) (xy 340.248311 -238.173113)
			(xy 340.217738 -238.213799) (xy 340.181034 -238.249054) (xy 340.13915 -238.277964) (xy 340.093171 -238.299781)
			(xy 340.044287 -238.313941) (xy 339.993766 -238.320075) (xy 339.942914 -238.318026) (xy 339.89305 -238.307846)
			(xy 339.845464 -238.289799) (xy 339.80139 -238.264353) (xy 339.761968 -238.232166) (xy 339.72822 -238.194072)
			(xy 339.701019 -238.151058) (xy 339.681071 -238.104238) (xy 339.668892 -238.054824) (xy 339.664797 -238.004096)
			(xy 339.3567 -238.004096) (xy 339.356188 -238.029542) (xy 339.348024 -238.079776) (xy 339.331908 -238.12805)
			(xy 339.308257 -238.173113) (xy 339.277684 -238.213799) (xy 339.24098 -238.249054) (xy 339.199096 -238.277964)
			(xy 339.153117 -238.299781) (xy 339.104233 -238.313941) (xy 339.053712 -238.320075) (xy 339.00286 -238.318026)
			(xy 338.952996 -238.307846) (xy 338.90541 -238.289799) (xy 338.861336 -238.264353) (xy 338.821914 -238.232166)
			(xy 338.788166 -238.194072) (xy 338.760965 -238.151058) (xy 338.741017 -238.104238) (xy 338.728838 -238.054824)
			(xy 338.724743 -238.004096) (xy 338.406486 -238.004096) (xy 338.405991 -238.028703) (xy 338.398096 -238.07728)
			(xy 338.382512 -238.123961) (xy 338.359641 -238.167538) (xy 338.330076 -238.206882) (xy 338.294583 -238.240974)
			(xy 338.25408 -238.26893) (xy 338.209618 -238.290028) (xy 338.162347 -238.30372) (xy 338.113492 -238.309652)
			(xy 338.064317 -238.307671) (xy 338.016098 -238.297827) (xy 337.970082 -238.280375) (xy 337.927461 -238.255768)
			(xy 337.88934 -238.224643) (xy 337.856705 -238.187806) (xy 337.830402 -238.14621) (xy 337.811111 -238.100934)
			(xy 337.799334 -238.05315) (xy 337.795374 -238.004096) (xy 337.476846 -238.004096) (xy 337.476334 -238.029542)
			(xy 337.46817 -238.079776) (xy 337.452054 -238.12805) (xy 337.428403 -238.173113) (xy 337.39783 -238.213799)
			(xy 337.361126 -238.249054) (xy 337.319242 -238.277964) (xy 337.273263 -238.299781) (xy 337.224379 -238.313941)
			(xy 337.173858 -238.320075) (xy 337.123006 -238.318026) (xy 337.073142 -238.307846) (xy 337.025556 -238.289799)
			(xy 336.981482 -238.264353) (xy 336.94206 -238.232166) (xy 336.908312 -238.194072) (xy 336.881111 -238.151058)
			(xy 336.861163 -238.104238) (xy 336.848984 -238.054824) (xy 336.844889 -238.004096) (xy 336.526378 -238.004096)
			(xy 336.525883 -238.028703) (xy 336.517988 -238.07728) (xy 336.502404 -238.123961) (xy 336.479533 -238.167538)
			(xy 336.449968 -238.206882) (xy 336.414475 -238.240974) (xy 336.373972 -238.26893) (xy 336.32951 -238.290028)
			(xy 336.282239 -238.30372) (xy 336.233384 -238.309652) (xy 336.184209 -238.307671) (xy 336.13599 -238.297827)
			(xy 336.089974 -238.280375) (xy 336.047353 -238.255768) (xy 336.009232 -238.224643) (xy 335.976597 -238.187806)
			(xy 335.950294 -238.14621) (xy 335.931003 -238.100934) (xy 335.919226 -238.05315) (xy 335.915266 -238.004096)
			(xy 335.596738 -238.004096) (xy 335.596226 -238.029542) (xy 335.588062 -238.079776) (xy 335.571946 -238.12805)
			(xy 335.548295 -238.173113) (xy 335.517722 -238.213799) (xy 335.481018 -238.249054) (xy 335.439134 -238.277964)
			(xy 335.393155 -238.299781) (xy 335.344271 -238.313941) (xy 335.29375 -238.320075) (xy 335.242898 -238.318026)
			(xy 335.193034 -238.307846) (xy 335.145448 -238.289799) (xy 335.101374 -238.264353) (xy 335.061952 -238.232166)
			(xy 335.028204 -238.194072) (xy 335.001003 -238.151058) (xy 334.981055 -238.104238) (xy 334.968876 -238.054824)
			(xy 334.964781 -238.004096) (xy 334.646524 -238.004096) (xy 334.646029 -238.028703) (xy 334.638134 -238.07728)
			(xy 334.62255 -238.123961) (xy 334.599679 -238.167538) (xy 334.570114 -238.206882) (xy 334.534621 -238.240974)
			(xy 334.494118 -238.26893) (xy 334.449656 -238.290028) (xy 334.402385 -238.30372) (xy 334.35353 -238.309652)
			(xy 334.304355 -238.307671) (xy 334.256136 -238.297827) (xy 334.21012 -238.280375) (xy 334.167499 -238.255768)
			(xy 334.129378 -238.224643) (xy 334.096743 -238.187806) (xy 334.07044 -238.14621) (xy 334.051149 -238.100934)
			(xy 334.039372 -238.05315) (xy 334.035412 -238.004096) (xy 333.716884 -238.004096) (xy 333.716372 -238.029542)
			(xy 333.708208 -238.079776) (xy 333.692092 -238.12805) (xy 333.668441 -238.173113) (xy 333.637868 -238.213799)
			(xy 333.601164 -238.249054) (xy 333.55928 -238.277964) (xy 333.513301 -238.299781) (xy 333.464417 -238.313941)
			(xy 333.413896 -238.320075) (xy 333.363044 -238.318026) (xy 333.31318 -238.307846) (xy 333.265594 -238.289799)
			(xy 333.22152 -238.264353) (xy 333.182098 -238.232166) (xy 333.14835 -238.194072) (xy 333.121149 -238.151058)
			(xy 333.101201 -238.104238) (xy 333.089022 -238.054824) (xy 333.084927 -238.004096) (xy 332.77683 -238.004096)
			(xy 332.776318 -238.029542) (xy 332.768154 -238.079776) (xy 332.752038 -238.12805) (xy 332.728387 -238.173113)
			(xy 332.697814 -238.213799) (xy 332.66111 -238.249054) (xy 332.619226 -238.277964) (xy 332.573247 -238.299781)
			(xy 332.524363 -238.313941) (xy 332.473842 -238.320075) (xy 332.42299 -238.318026) (xy 332.373126 -238.307846)
			(xy 332.32554 -238.289799) (xy 332.281466 -238.264353) (xy 332.242044 -238.232166) (xy 332.208296 -238.194072)
			(xy 332.181095 -238.151058) (xy 332.161147 -238.104238) (xy 332.148968 -238.054824) (xy 332.144873 -238.004096)
			(xy 331.826362 -238.004096) (xy 331.825867 -238.028703) (xy 331.817972 -238.07728) (xy 331.802388 -238.123961)
			(xy 331.779517 -238.167538) (xy 331.749952 -238.206882) (xy 331.714459 -238.240974) (xy 331.673956 -238.26893)
			(xy 331.629494 -238.290028) (xy 331.582223 -238.30372) (xy 331.533368 -238.309652) (xy 331.484193 -238.307671)
			(xy 331.435974 -238.297827) (xy 331.389958 -238.280375) (xy 331.347337 -238.255768) (xy 331.309216 -238.224643)
			(xy 331.276581 -238.187806) (xy 331.250278 -238.14621) (xy 331.230987 -238.100934) (xy 331.21921 -238.05315)
			(xy 331.21525 -238.004096) (xy 330.896722 -238.004096) (xy 330.89621 -238.029542) (xy 330.888046 -238.079776)
			(xy 330.87193 -238.12805) (xy 330.848279 -238.173113) (xy 330.817706 -238.213799) (xy 330.781002 -238.249054)
			(xy 330.739118 -238.277964) (xy 330.693139 -238.299781) (xy 330.644255 -238.313941) (xy 330.593734 -238.320075)
			(xy 330.542882 -238.318026) (xy 330.493018 -238.307846) (xy 330.445432 -238.289799) (xy 330.401358 -238.264353)
			(xy 330.361936 -238.232166) (xy 330.328188 -238.194072) (xy 330.300987 -238.151058) (xy 330.281039 -238.104238)
			(xy 330.26886 -238.054824) (xy 330.264765 -238.004096) (xy 329.946508 -238.004096) (xy 329.946013 -238.028703)
			(xy 329.938118 -238.07728) (xy 329.922534 -238.123961) (xy 329.899663 -238.167538) (xy 329.870098 -238.206882)
			(xy 329.834605 -238.240974) (xy 329.794102 -238.26893) (xy 329.74964 -238.290028) (xy 329.702369 -238.30372)
			(xy 329.653514 -238.309652) (xy 329.604339 -238.307671) (xy 329.55612 -238.297827) (xy 329.510104 -238.280375)
			(xy 329.467483 -238.255768) (xy 329.429362 -238.224643) (xy 329.396727 -238.187806) (xy 329.370424 -238.14621)
			(xy 329.351133 -238.100934) (xy 329.339356 -238.05315) (xy 329.335396 -238.004096) (xy 329.016868 -238.004096)
			(xy 329.016356 -238.029542) (xy 329.008192 -238.079776) (xy 328.992076 -238.12805) (xy 328.968425 -238.173113)
			(xy 328.937852 -238.213799) (xy 328.901148 -238.249054) (xy 328.859264 -238.277964) (xy 328.813285 -238.299781)
			(xy 328.764401 -238.313941) (xy 328.71388 -238.320075) (xy 328.663028 -238.318026) (xy 328.613164 -238.307846)
			(xy 328.565578 -238.289799) (xy 328.521504 -238.264353) (xy 328.482082 -238.232166) (xy 328.448334 -238.194072)
			(xy 328.421133 -238.151058) (xy 328.401185 -238.104238) (xy 328.389006 -238.054824) (xy 328.384911 -238.004096)
			(xy 328.0664 -238.004096) (xy 328.065905 -238.028703) (xy 328.05801 -238.07728) (xy 328.042426 -238.123961)
			(xy 328.019555 -238.167538) (xy 327.98999 -238.206882) (xy 327.954497 -238.240974) (xy 327.913994 -238.26893)
			(xy 327.869532 -238.290028) (xy 327.822261 -238.30372) (xy 327.773406 -238.309652) (xy 327.724231 -238.307671)
			(xy 327.676012 -238.297827) (xy 327.629996 -238.280375) (xy 327.587375 -238.255768) (xy 327.549254 -238.224643)
			(xy 327.516619 -238.187806) (xy 327.490316 -238.14621) (xy 327.471025 -238.100934) (xy 327.459248 -238.05315)
			(xy 327.455288 -238.004096) (xy 324.903545 -238.004096) (xy 324.905872 -238.0052) (xy 324.946375 -238.033156)
			(xy 324.981868 -238.067248) (xy 325.011433 -238.106592) (xy 325.034304 -238.150169) (xy 325.049888 -238.19685)
			(xy 325.057783 -238.245427) (xy 325.058278 -238.270034) (xy 325.057783 -238.294641) (xy 325.049888 -238.343218)
			(xy 325.034304 -238.389899) (xy 325.011433 -238.433476) (xy 324.981868 -238.47282) (xy 324.946375 -238.506912)
			(xy 324.905872 -238.534868) (xy 324.86141 -238.555966) (xy 324.814139 -238.569658) (xy 324.765284 -238.57559)
			(xy 324.716109 -238.573609) (xy 324.66789 -238.563765) (xy 324.621874 -238.546313) (xy 324.579253 -238.521706)
			(xy 324.541132 -238.490581) (xy 324.508497 -238.453744) (xy 324.482194 -238.412148) (xy 324.462903 -238.366872)
			(xy 324.451126 -238.319088) (xy 324.447166 -238.270034) (xy 310.45912 -238.270034) (xy 310.45912 -238.814102)
			(xy 326.045334 -238.814102) (xy 326.049294 -238.765048) (xy 326.061071 -238.717264) (xy 326.080362 -238.671988)
			(xy 326.106665 -238.630392) (xy 326.1393 -238.593555) (xy 326.177421 -238.56243) (xy 326.220042 -238.537823)
			(xy 326.266058 -238.520371) (xy 326.314277 -238.510527) (xy 326.363452 -238.508546) (xy 326.412307 -238.514478)
			(xy 326.459578 -238.52817) (xy 326.50404 -238.549268) (xy 326.544543 -238.577224) (xy 326.580036 -238.611316)
			(xy 326.609601 -238.65066) (xy 326.632472 -238.694237) (xy 326.648056 -238.740918) (xy 326.655951 -238.789495)
			(xy 326.656446 -238.814102) (xy 327.925442 -238.814102) (xy 327.929402 -238.765048) (xy 327.941179 -238.717264)
			(xy 327.96047 -238.671988) (xy 327.986773 -238.630392) (xy 328.019408 -238.593555) (xy 328.057529 -238.56243)
			(xy 328.10015 -238.537823) (xy 328.146166 -238.520371) (xy 328.194385 -238.510527) (xy 328.24356 -238.508546)
			(xy 328.292415 -238.514478) (xy 328.339686 -238.52817) (xy 328.384148 -238.549268) (xy 328.424651 -238.577224)
			(xy 328.460144 -238.611316) (xy 328.489709 -238.65066) (xy 328.51258 -238.694237) (xy 328.528164 -238.740918)
			(xy 328.536059 -238.789495) (xy 328.536554 -238.814102) (xy 328.854811 -238.814102) (xy 328.858906 -238.763374)
			(xy 328.871085 -238.71396) (xy 328.891033 -238.66714) (xy 328.918234 -238.624126) (xy 328.951982 -238.586032)
			(xy 328.991404 -238.553845) (xy 329.035478 -238.528399) (xy 329.083064 -238.510352) (xy 329.132928 -238.500172)
			(xy 329.18378 -238.498123) (xy 329.234301 -238.504257) (xy 329.283185 -238.518417) (xy 329.329164 -238.540234)
			(xy 329.371048 -238.569144) (xy 329.407752 -238.604399) (xy 329.438325 -238.645085) (xy 329.461976 -238.690148)
			(xy 329.478092 -238.738422) (xy 329.486256 -238.788656) (xy 329.486768 -238.814102) (xy 329.794865 -238.814102)
			(xy 329.79896 -238.763374) (xy 329.811139 -238.71396) (xy 329.831087 -238.66714) (xy 329.858288 -238.624126)
			(xy 329.892036 -238.586032) (xy 329.931458 -238.553845) (xy 329.975532 -238.528399) (xy 330.023118 -238.510352)
			(xy 330.072982 -238.500172) (xy 330.123834 -238.498123) (xy 330.174355 -238.504257) (xy 330.223239 -238.518417)
			(xy 330.269218 -238.540234) (xy 330.311102 -238.569144) (xy 330.347806 -238.604399) (xy 330.378379 -238.645085)
			(xy 330.40203 -238.690148) (xy 330.418146 -238.738422) (xy 330.42631 -238.788656) (xy 330.426822 -238.814102)
			(xy 330.74535 -238.814102) (xy 330.74931 -238.765048) (xy 330.761087 -238.717264) (xy 330.780378 -238.671988)
			(xy 330.806681 -238.630392) (xy 330.839316 -238.593555) (xy 330.877437 -238.56243) (xy 330.920058 -238.537823)
			(xy 330.966074 -238.520371) (xy 331.014293 -238.510527) (xy 331.063468 -238.508546) (xy 331.112323 -238.514478)
			(xy 331.159594 -238.52817) (xy 331.204056 -238.549268) (xy 331.244559 -238.577224) (xy 331.280052 -238.611316)
			(xy 331.309617 -238.65066) (xy 331.332488 -238.694237) (xy 331.348072 -238.740918) (xy 331.355967 -238.789495)
			(xy 331.356462 -238.814102) (xy 331.674973 -238.814102) (xy 331.679068 -238.763374) (xy 331.691247 -238.71396)
			(xy 331.711195 -238.66714) (xy 331.738396 -238.624126) (xy 331.772144 -238.586032) (xy 331.811566 -238.553845)
			(xy 331.85564 -238.528399) (xy 331.903226 -238.510352) (xy 331.95309 -238.500172) (xy 332.003942 -238.498123)
			(xy 332.054463 -238.504257) (xy 332.103347 -238.518417) (xy 332.149326 -238.540234) (xy 332.19121 -238.569144)
			(xy 332.227914 -238.604399) (xy 332.258487 -238.645085) (xy 332.282138 -238.690148) (xy 332.298254 -238.738422)
			(xy 332.306418 -238.788656) (xy 332.30693 -238.814102) (xy 332.625204 -238.814102) (xy 332.629164 -238.765048)
			(xy 332.640941 -238.717264) (xy 332.660232 -238.671988) (xy 332.686535 -238.630392) (xy 332.71917 -238.593555)
			(xy 332.757291 -238.56243) (xy 332.799912 -238.537823) (xy 332.845928 -238.520371) (xy 332.894147 -238.510527)
			(xy 332.943322 -238.508546) (xy 332.992177 -238.514478) (xy 333.039448 -238.52817) (xy 333.08391 -238.549268)
			(xy 333.124413 -238.577224) (xy 333.159906 -238.611316) (xy 333.189471 -238.65066) (xy 333.212342 -238.694237)
			(xy 333.227926 -238.740918) (xy 333.235821 -238.789495) (xy 333.236316 -238.814102) (xy 333.554827 -238.814102)
			(xy 333.558922 -238.763374) (xy 333.571101 -238.71396) (xy 333.591049 -238.66714) (xy 333.61825 -238.624126)
			(xy 333.651998 -238.586032) (xy 333.69142 -238.553845) (xy 333.735494 -238.528399) (xy 333.78308 -238.510352)
			(xy 333.832944 -238.500172) (xy 333.883796 -238.498123) (xy 333.934317 -238.504257) (xy 333.983201 -238.518417)
			(xy 334.02918 -238.540234) (xy 334.071064 -238.569144) (xy 334.107768 -238.604399) (xy 334.138341 -238.645085)
			(xy 334.161992 -238.690148) (xy 334.178108 -238.738422) (xy 334.186272 -238.788656) (xy 334.186784 -238.814102)
			(xy 334.505312 -238.814102) (xy 334.509272 -238.765048) (xy 334.521049 -238.717264) (xy 334.54034 -238.671988)
			(xy 334.566643 -238.630392) (xy 334.599278 -238.593555) (xy 334.637399 -238.56243) (xy 334.68002 -238.537823)
			(xy 334.726036 -238.520371) (xy 334.774255 -238.510527) (xy 334.82343 -238.508546) (xy 334.872285 -238.514478)
			(xy 334.919556 -238.52817) (xy 334.964018 -238.549268) (xy 335.004521 -238.577224) (xy 335.040014 -238.611316)
			(xy 335.069579 -238.65066) (xy 335.09245 -238.694237) (xy 335.108034 -238.740918) (xy 335.115929 -238.789495)
			(xy 335.116424 -238.814102) (xy 335.434935 -238.814102) (xy 335.43903 -238.763374) (xy 335.451209 -238.71396)
			(xy 335.471157 -238.66714) (xy 335.498358 -238.624126) (xy 335.532106 -238.586032) (xy 335.571528 -238.553845)
			(xy 335.615602 -238.528399) (xy 335.663188 -238.510352) (xy 335.713052 -238.500172) (xy 335.763904 -238.498123)
			(xy 335.814425 -238.504257) (xy 335.863309 -238.518417) (xy 335.909288 -238.540234) (xy 335.951172 -238.569144)
			(xy 335.987876 -238.604399) (xy 336.018449 -238.645085) (xy 336.0421 -238.690148) (xy 336.058216 -238.738422)
			(xy 336.06638 -238.788656) (xy 336.066892 -238.814102) (xy 336.374989 -238.814102) (xy 336.379084 -238.763374)
			(xy 336.391263 -238.71396) (xy 336.411211 -238.66714) (xy 336.438412 -238.624126) (xy 336.47216 -238.586032)
			(xy 336.511582 -238.553845) (xy 336.555656 -238.528399) (xy 336.603242 -238.510352) (xy 336.653106 -238.500172)
			(xy 336.703958 -238.498123) (xy 336.754479 -238.504257) (xy 336.803363 -238.518417) (xy 336.849342 -238.540234)
			(xy 336.891226 -238.569144) (xy 336.92793 -238.604399) (xy 336.958503 -238.645085) (xy 336.982154 -238.690148)
			(xy 336.99827 -238.738422) (xy 337.006434 -238.788656) (xy 337.006946 -238.814102) (xy 337.32522 -238.814102)
			(xy 337.32918 -238.765048) (xy 337.340957 -238.717264) (xy 337.360248 -238.671988) (xy 337.386551 -238.630392)
			(xy 337.419186 -238.593555) (xy 337.457307 -238.56243) (xy 337.499928 -238.537823) (xy 337.545944 -238.520371)
			(xy 337.594163 -238.510527) (xy 337.643338 -238.508546) (xy 337.692193 -238.514478) (xy 337.739464 -238.52817)
			(xy 337.783926 -238.549268) (xy 337.824429 -238.577224) (xy 337.859922 -238.611316) (xy 337.889487 -238.65066)
			(xy 337.912358 -238.694237) (xy 337.927942 -238.740918) (xy 337.935837 -238.789495) (xy 337.936332 -238.814102)
			(xy 338.254843 -238.814102) (xy 338.258938 -238.763374) (xy 338.271117 -238.71396) (xy 338.291065 -238.66714)
			(xy 338.318266 -238.624126) (xy 338.352014 -238.586032) (xy 338.391436 -238.553845) (xy 338.43551 -238.528399)
			(xy 338.483096 -238.510352) (xy 338.53296 -238.500172) (xy 338.583812 -238.498123) (xy 338.634333 -238.504257)
			(xy 338.683217 -238.518417) (xy 338.729196 -238.540234) (xy 338.77108 -238.569144) (xy 338.807784 -238.604399)
			(xy 338.838357 -238.645085) (xy 338.862008 -238.690148) (xy 338.878124 -238.738422) (xy 338.886288 -238.788656)
			(xy 338.8868 -238.814102) (xy 339.205328 -238.814102) (xy 339.209288 -238.765048) (xy 339.221065 -238.717264)
			(xy 339.240356 -238.671988) (xy 339.266659 -238.630392) (xy 339.299294 -238.593555) (xy 339.337415 -238.56243)
			(xy 339.380036 -238.537823) (xy 339.426052 -238.520371) (xy 339.474271 -238.510527) (xy 339.523446 -238.508546)
			(xy 339.572301 -238.514478) (xy 339.619572 -238.52817) (xy 339.664034 -238.549268) (xy 339.704537 -238.577224)
			(xy 339.74003 -238.611316) (xy 339.769595 -238.65066) (xy 339.792466 -238.694237) (xy 339.80805 -238.740918)
			(xy 339.815945 -238.789495) (xy 339.81644 -238.814102) (xy 340.134951 -238.814102) (xy 340.139046 -238.763374)
			(xy 340.151225 -238.71396) (xy 340.171173 -238.66714) (xy 340.198374 -238.624126) (xy 340.232122 -238.586032)
			(xy 340.271544 -238.553845) (xy 340.315618 -238.528399) (xy 340.363204 -238.510352) (xy 340.413068 -238.500172)
			(xy 340.46392 -238.498123) (xy 340.514441 -238.504257) (xy 340.563325 -238.518417) (xy 340.609304 -238.540234)
			(xy 340.651188 -238.569144) (xy 340.687892 -238.604399) (xy 340.718465 -238.645085) (xy 340.742116 -238.690148)
			(xy 340.758232 -238.738422) (xy 340.766396 -238.788656) (xy 340.766908 -238.814102) (xy 341.085182 -238.814102)
			(xy 341.089142 -238.765048) (xy 341.100919 -238.717264) (xy 341.12021 -238.671988) (xy 341.146513 -238.630392)
			(xy 341.179148 -238.593555) (xy 341.217269 -238.56243) (xy 341.25989 -238.537823) (xy 341.305906 -238.520371)
			(xy 341.354125 -238.510527) (xy 341.4033 -238.508546) (xy 341.452155 -238.514478) (xy 341.499426 -238.52817)
			(xy 341.543888 -238.549268) (xy 341.584391 -238.577224) (xy 341.619884 -238.611316) (xy 341.649449 -238.65066)
			(xy 341.67232 -238.694237) (xy 341.687904 -238.740918) (xy 341.695799 -238.789495) (xy 341.696294 -238.814102)
			(xy 342.014805 -238.814102) (xy 342.0189 -238.763374) (xy 342.031079 -238.71396) (xy 342.051027 -238.66714)
			(xy 342.078228 -238.624126) (xy 342.111976 -238.586032) (xy 342.151398 -238.553845) (xy 342.195472 -238.528399)
			(xy 342.243058 -238.510352) (xy 342.292922 -238.500172) (xy 342.343774 -238.498123) (xy 342.394295 -238.504257)
			(xy 342.443179 -238.518417) (xy 342.489158 -238.540234) (xy 342.531042 -238.569144) (xy 342.567746 -238.604399)
			(xy 342.598319 -238.645085) (xy 342.62197 -238.690148) (xy 342.638086 -238.738422) (xy 342.64625 -238.788656)
			(xy 342.646762 -238.814102) (xy 342.954859 -238.814102) (xy 342.958954 -238.763374) (xy 342.971133 -238.71396)
			(xy 342.991081 -238.66714) (xy 343.018282 -238.624126) (xy 343.05203 -238.586032) (xy 343.091452 -238.553845)
			(xy 343.135526 -238.528399) (xy 343.183112 -238.510352) (xy 343.232976 -238.500172) (xy 343.283828 -238.498123)
			(xy 343.334349 -238.504257) (xy 343.383233 -238.518417) (xy 343.429212 -238.540234) (xy 343.471096 -238.569144)
			(xy 343.5078 -238.604399) (xy 343.538373 -238.645085) (xy 343.562024 -238.690148) (xy 343.57814 -238.738422)
			(xy 343.586304 -238.788656) (xy 343.586816 -238.814102) (xy 343.586304 -238.839548) (xy 343.57814 -238.889782)
			(xy 343.562024 -238.938056) (xy 343.538373 -238.983119) (xy 343.5078 -239.023805) (xy 343.471096 -239.05906)
			(xy 343.429212 -239.08797) (xy 343.383233 -239.109787) (xy 343.334349 -239.123947) (xy 343.283828 -239.130081)
			(xy 343.232976 -239.128032) (xy 343.183112 -239.117852) (xy 343.135526 -239.099805) (xy 343.091452 -239.074359)
			(xy 343.05203 -239.042172) (xy 343.018282 -239.004078) (xy 342.991081 -238.961064) (xy 342.971133 -238.914244)
			(xy 342.958954 -238.86483) (xy 342.954859 -238.814102) (xy 342.646762 -238.814102) (xy 342.64625 -238.839548)
			(xy 342.638086 -238.889782) (xy 342.62197 -238.938056) (xy 342.598319 -238.983119) (xy 342.567746 -239.023805)
			(xy 342.531042 -239.05906) (xy 342.489158 -239.08797) (xy 342.443179 -239.109787) (xy 342.394295 -239.123947)
			(xy 342.343774 -239.130081) (xy 342.292922 -239.128032) (xy 342.243058 -239.117852) (xy 342.195472 -239.099805)
			(xy 342.151398 -239.074359) (xy 342.111976 -239.042172) (xy 342.078228 -239.004078) (xy 342.051027 -238.961064)
			(xy 342.031079 -238.914244) (xy 342.0189 -238.86483) (xy 342.014805 -238.814102) (xy 341.696294 -238.814102)
			(xy 341.695799 -238.838709) (xy 341.687904 -238.887286) (xy 341.67232 -238.933967) (xy 341.649449 -238.977544)
			(xy 341.619884 -239.016888) (xy 341.584391 -239.05098) (xy 341.543888 -239.078936) (xy 341.499426 -239.100034)
			(xy 341.452155 -239.113726) (xy 341.4033 -239.119658) (xy 341.354125 -239.117677) (xy 341.305906 -239.107833)
			(xy 341.25989 -239.090381) (xy 341.217269 -239.065774) (xy 341.179148 -239.034649) (xy 341.146513 -238.997812)
			(xy 341.12021 -238.956216) (xy 341.100919 -238.91094) (xy 341.089142 -238.863156) (xy 341.085182 -238.814102)
			(xy 340.766908 -238.814102) (xy 340.766396 -238.839548) (xy 340.758232 -238.889782) (xy 340.742116 -238.938056)
			(xy 340.718465 -238.983119) (xy 340.687892 -239.023805) (xy 340.651188 -239.05906) (xy 340.609304 -239.08797)
			(xy 340.563325 -239.109787) (xy 340.514441 -239.123947) (xy 340.46392 -239.130081) (xy 340.413068 -239.128032)
			(xy 340.363204 -239.117852) (xy 340.315618 -239.099805) (xy 340.271544 -239.074359) (xy 340.232122 -239.042172)
			(xy 340.198374 -239.004078) (xy 340.171173 -238.961064) (xy 340.151225 -238.914244) (xy 340.139046 -238.86483)
			(xy 340.134951 -238.814102) (xy 339.81644 -238.814102) (xy 339.815945 -238.838709) (xy 339.80805 -238.887286)
			(xy 339.792466 -238.933967) (xy 339.769595 -238.977544) (xy 339.74003 -239.016888) (xy 339.704537 -239.05098)
			(xy 339.664034 -239.078936) (xy 339.619572 -239.100034) (xy 339.572301 -239.113726) (xy 339.523446 -239.119658)
			(xy 339.474271 -239.117677) (xy 339.426052 -239.107833) (xy 339.380036 -239.090381) (xy 339.337415 -239.065774)
			(xy 339.299294 -239.034649) (xy 339.266659 -238.997812) (xy 339.240356 -238.956216) (xy 339.221065 -238.91094)
			(xy 339.209288 -238.863156) (xy 339.205328 -238.814102) (xy 338.8868 -238.814102) (xy 338.886288 -238.839548)
			(xy 338.878124 -238.889782) (xy 338.862008 -238.938056) (xy 338.838357 -238.983119) (xy 338.807784 -239.023805)
			(xy 338.77108 -239.05906) (xy 338.729196 -239.08797) (xy 338.683217 -239.109787) (xy 338.634333 -239.123947)
			(xy 338.583812 -239.130081) (xy 338.53296 -239.128032) (xy 338.483096 -239.117852) (xy 338.43551 -239.099805)
			(xy 338.391436 -239.074359) (xy 338.352014 -239.042172) (xy 338.318266 -239.004078) (xy 338.291065 -238.961064)
			(xy 338.271117 -238.914244) (xy 338.258938 -238.86483) (xy 338.254843 -238.814102) (xy 337.936332 -238.814102)
			(xy 337.935837 -238.838709) (xy 337.927942 -238.887286) (xy 337.912358 -238.933967) (xy 337.889487 -238.977544)
			(xy 337.859922 -239.016888) (xy 337.824429 -239.05098) (xy 337.783926 -239.078936) (xy 337.739464 -239.100034)
			(xy 337.692193 -239.113726) (xy 337.643338 -239.119658) (xy 337.594163 -239.117677) (xy 337.545944 -239.107833)
			(xy 337.499928 -239.090381) (xy 337.457307 -239.065774) (xy 337.419186 -239.034649) (xy 337.386551 -238.997812)
			(xy 337.360248 -238.956216) (xy 337.340957 -238.91094) (xy 337.32918 -238.863156) (xy 337.32522 -238.814102)
			(xy 337.006946 -238.814102) (xy 337.006434 -238.839548) (xy 336.99827 -238.889782) (xy 336.982154 -238.938056)
			(xy 336.958503 -238.983119) (xy 336.92793 -239.023805) (xy 336.891226 -239.05906) (xy 336.849342 -239.08797)
			(xy 336.803363 -239.109787) (xy 336.754479 -239.123947) (xy 336.703958 -239.130081) (xy 336.653106 -239.128032)
			(xy 336.603242 -239.117852) (xy 336.555656 -239.099805) (xy 336.511582 -239.074359) (xy 336.47216 -239.042172)
			(xy 336.438412 -239.004078) (xy 336.411211 -238.961064) (xy 336.391263 -238.914244) (xy 336.379084 -238.86483)
			(xy 336.374989 -238.814102) (xy 336.066892 -238.814102) (xy 336.06638 -238.839548) (xy 336.058216 -238.889782)
			(xy 336.0421 -238.938056) (xy 336.018449 -238.983119) (xy 335.987876 -239.023805) (xy 335.951172 -239.05906)
			(xy 335.909288 -239.08797) (xy 335.863309 -239.109787) (xy 335.814425 -239.123947) (xy 335.763904 -239.130081)
			(xy 335.713052 -239.128032) (xy 335.663188 -239.117852) (xy 335.615602 -239.099805) (xy 335.571528 -239.074359)
			(xy 335.532106 -239.042172) (xy 335.498358 -239.004078) (xy 335.471157 -238.961064) (xy 335.451209 -238.914244)
			(xy 335.43903 -238.86483) (xy 335.434935 -238.814102) (xy 335.116424 -238.814102) (xy 335.115929 -238.838709)
			(xy 335.108034 -238.887286) (xy 335.09245 -238.933967) (xy 335.069579 -238.977544) (xy 335.040014 -239.016888)
			(xy 335.004521 -239.05098) (xy 334.964018 -239.078936) (xy 334.919556 -239.100034) (xy 334.872285 -239.113726)
			(xy 334.82343 -239.119658) (xy 334.774255 -239.117677) (xy 334.726036 -239.107833) (xy 334.68002 -239.090381)
			(xy 334.637399 -239.065774) (xy 334.599278 -239.034649) (xy 334.566643 -238.997812) (xy 334.54034 -238.956216)
			(xy 334.521049 -238.91094) (xy 334.509272 -238.863156) (xy 334.505312 -238.814102) (xy 334.186784 -238.814102)
			(xy 334.186272 -238.839548) (xy 334.178108 -238.889782) (xy 334.161992 -238.938056) (xy 334.138341 -238.983119)
			(xy 334.107768 -239.023805) (xy 334.071064 -239.05906) (xy 334.02918 -239.08797) (xy 333.983201 -239.109787)
			(xy 333.934317 -239.123947) (xy 333.883796 -239.130081) (xy 333.832944 -239.128032) (xy 333.78308 -239.117852)
			(xy 333.735494 -239.099805) (xy 333.69142 -239.074359) (xy 333.651998 -239.042172) (xy 333.61825 -239.004078)
			(xy 333.591049 -238.961064) (xy 333.571101 -238.914244) (xy 333.558922 -238.86483) (xy 333.554827 -238.814102)
			(xy 333.236316 -238.814102) (xy 333.235821 -238.838709) (xy 333.227926 -238.887286) (xy 333.212342 -238.933967)
			(xy 333.189471 -238.977544) (xy 333.159906 -239.016888) (xy 333.124413 -239.05098) (xy 333.08391 -239.078936)
			(xy 333.039448 -239.100034) (xy 332.992177 -239.113726) (xy 332.943322 -239.119658) (xy 332.894147 -239.117677)
			(xy 332.845928 -239.107833) (xy 332.799912 -239.090381) (xy 332.757291 -239.065774) (xy 332.71917 -239.034649)
			(xy 332.686535 -238.997812) (xy 332.660232 -238.956216) (xy 332.640941 -238.91094) (xy 332.629164 -238.863156)
			(xy 332.625204 -238.814102) (xy 332.30693 -238.814102) (xy 332.306418 -238.839548) (xy 332.298254 -238.889782)
			(xy 332.282138 -238.938056) (xy 332.258487 -238.983119) (xy 332.227914 -239.023805) (xy 332.19121 -239.05906)
			(xy 332.149326 -239.08797) (xy 332.103347 -239.109787) (xy 332.054463 -239.123947) (xy 332.003942 -239.130081)
			(xy 331.95309 -239.128032) (xy 331.903226 -239.117852) (xy 331.85564 -239.099805) (xy 331.811566 -239.074359)
			(xy 331.772144 -239.042172) (xy 331.738396 -239.004078) (xy 331.711195 -238.961064) (xy 331.691247 -238.914244)
			(xy 331.679068 -238.86483) (xy 331.674973 -238.814102) (xy 331.356462 -238.814102) (xy 331.355967 -238.838709)
			(xy 331.348072 -238.887286) (xy 331.332488 -238.933967) (xy 331.309617 -238.977544) (xy 331.280052 -239.016888)
			(xy 331.244559 -239.05098) (xy 331.204056 -239.078936) (xy 331.159594 -239.100034) (xy 331.112323 -239.113726)
			(xy 331.063468 -239.119658) (xy 331.014293 -239.117677) (xy 330.966074 -239.107833) (xy 330.920058 -239.090381)
			(xy 330.877437 -239.065774) (xy 330.839316 -239.034649) (xy 330.806681 -238.997812) (xy 330.780378 -238.956216)
			(xy 330.761087 -238.91094) (xy 330.74931 -238.863156) (xy 330.74535 -238.814102) (xy 330.426822 -238.814102)
			(xy 330.42631 -238.839548) (xy 330.418146 -238.889782) (xy 330.40203 -238.938056) (xy 330.378379 -238.983119)
			(xy 330.347806 -239.023805) (xy 330.311102 -239.05906) (xy 330.269218 -239.08797) (xy 330.223239 -239.109787)
			(xy 330.174355 -239.123947) (xy 330.123834 -239.130081) (xy 330.072982 -239.128032) (xy 330.023118 -239.117852)
			(xy 329.975532 -239.099805) (xy 329.931458 -239.074359) (xy 329.892036 -239.042172) (xy 329.858288 -239.004078)
			(xy 329.831087 -238.961064) (xy 329.811139 -238.914244) (xy 329.79896 -238.86483) (xy 329.794865 -238.814102)
			(xy 329.486768 -238.814102) (xy 329.486256 -238.839548) (xy 329.478092 -238.889782) (xy 329.461976 -238.938056)
			(xy 329.438325 -238.983119) (xy 329.407752 -239.023805) (xy 329.371048 -239.05906) (xy 329.329164 -239.08797)
			(xy 329.283185 -239.109787) (xy 329.234301 -239.123947) (xy 329.18378 -239.130081) (xy 329.132928 -239.128032)
			(xy 329.083064 -239.117852) (xy 329.035478 -239.099805) (xy 328.991404 -239.074359) (xy 328.951982 -239.042172)
			(xy 328.918234 -239.004078) (xy 328.891033 -238.961064) (xy 328.871085 -238.914244) (xy 328.858906 -238.86483)
			(xy 328.854811 -238.814102) (xy 328.536554 -238.814102) (xy 328.536059 -238.838709) (xy 328.528164 -238.887286)
			(xy 328.51258 -238.933967) (xy 328.489709 -238.977544) (xy 328.460144 -239.016888) (xy 328.424651 -239.05098)
			(xy 328.384148 -239.078936) (xy 328.339686 -239.100034) (xy 328.292415 -239.113726) (xy 328.24356 -239.119658)
			(xy 328.194385 -239.117677) (xy 328.146166 -239.107833) (xy 328.10015 -239.090381) (xy 328.057529 -239.065774)
			(xy 328.019408 -239.034649) (xy 327.986773 -238.997812) (xy 327.96047 -238.956216) (xy 327.941179 -238.91094)
			(xy 327.929402 -238.863156) (xy 327.925442 -238.814102) (xy 326.656446 -238.814102) (xy 326.655951 -238.838709)
			(xy 326.648056 -238.887286) (xy 326.632472 -238.933967) (xy 326.609601 -238.977544) (xy 326.580036 -239.016888)
			(xy 326.544543 -239.05098) (xy 326.50404 -239.078936) (xy 326.459578 -239.100034) (xy 326.412307 -239.113726)
			(xy 326.363452 -239.119658) (xy 326.314277 -239.117677) (xy 326.266058 -239.107833) (xy 326.220042 -239.090381)
			(xy 326.177421 -239.065774) (xy 326.1393 -239.034649) (xy 326.106665 -238.997812) (xy 326.080362 -238.956216)
			(xy 326.061071 -238.91094) (xy 326.049294 -238.863156) (xy 326.045334 -238.814102) (xy 310.45912 -238.814102)
			(xy 310.45912 -239.890046) (xy 324.447166 -239.890046) (xy 324.451126 -239.840992) (xy 324.462903 -239.793208)
			(xy 324.482194 -239.747932) (xy 324.508497 -239.706336) (xy 324.541132 -239.669499) (xy 324.579253 -239.638374)
			(xy 324.621874 -239.613767) (xy 324.66789 -239.596315) (xy 324.716109 -239.586471) (xy 324.765284 -239.58449)
			(xy 324.814139 -239.590422) (xy 324.86141 -239.604114) (xy 324.903545 -239.624108) (xy 328.384911 -239.624108)
			(xy 328.389006 -239.57338) (xy 328.401185 -239.523966) (xy 328.421133 -239.477146) (xy 328.448334 -239.434132)
			(xy 328.482082 -239.396038) (xy 328.521504 -239.363851) (xy 328.565578 -239.338405) (xy 328.613164 -239.320358)
			(xy 328.663028 -239.310178) (xy 328.71388 -239.308129) (xy 328.764401 -239.314263) (xy 328.813285 -239.328423)
			(xy 328.859264 -239.35024) (xy 328.901148 -239.37915) (xy 328.937852 -239.414405) (xy 328.968425 -239.455091)
			(xy 328.992076 -239.500154) (xy 329.008192 -239.548428) (xy 329.016356 -239.598662) (xy 329.016868 -239.624108)
			(xy 329.335396 -239.624108) (xy 329.339356 -239.575054) (xy 329.351133 -239.52727) (xy 329.370424 -239.481994)
			(xy 329.396727 -239.440398) (xy 329.429362 -239.403561) (xy 329.467483 -239.372436) (xy 329.510104 -239.347829)
			(xy 329.55612 -239.330377) (xy 329.604339 -239.320533) (xy 329.653514 -239.318552) (xy 329.702369 -239.324484)
			(xy 329.74964 -239.338176) (xy 329.794102 -239.359274) (xy 329.834605 -239.38723) (xy 329.870098 -239.421322)
			(xy 329.899663 -239.460666) (xy 329.922534 -239.504243) (xy 329.938118 -239.550924) (xy 329.946013 -239.599501)
			(xy 329.946508 -239.624108) (xy 330.264765 -239.624108) (xy 330.26886 -239.57338) (xy 330.281039 -239.523966)
			(xy 330.300987 -239.477146) (xy 330.328188 -239.434132) (xy 330.361936 -239.396038) (xy 330.401358 -239.363851)
			(xy 330.445432 -239.338405) (xy 330.493018 -239.320358) (xy 330.542882 -239.310178) (xy 330.593734 -239.308129)
			(xy 330.644255 -239.314263) (xy 330.693139 -239.328423) (xy 330.739118 -239.35024) (xy 330.781002 -239.37915)
			(xy 330.817706 -239.414405) (xy 330.848279 -239.455091) (xy 330.87193 -239.500154) (xy 330.888046 -239.548428)
			(xy 330.89621 -239.598662) (xy 330.896722 -239.624108) (xy 331.21525 -239.624108) (xy 331.21921 -239.575054)
			(xy 331.230987 -239.52727) (xy 331.250278 -239.481994) (xy 331.276581 -239.440398) (xy 331.309216 -239.403561)
			(xy 331.347337 -239.372436) (xy 331.389958 -239.347829) (xy 331.435974 -239.330377) (xy 331.484193 -239.320533)
			(xy 331.533368 -239.318552) (xy 331.582223 -239.324484) (xy 331.629494 -239.338176) (xy 331.673956 -239.359274)
			(xy 331.714459 -239.38723) (xy 331.749952 -239.421322) (xy 331.779517 -239.460666) (xy 331.802388 -239.504243)
			(xy 331.817972 -239.550924) (xy 331.825867 -239.599501) (xy 331.826362 -239.624108) (xy 332.144873 -239.624108)
			(xy 332.148968 -239.57338) (xy 332.161147 -239.523966) (xy 332.181095 -239.477146) (xy 332.208296 -239.434132)
			(xy 332.242044 -239.396038) (xy 332.281466 -239.363851) (xy 332.32554 -239.338405) (xy 332.373126 -239.320358)
			(xy 332.42299 -239.310178) (xy 332.473842 -239.308129) (xy 332.524363 -239.314263) (xy 332.573247 -239.328423)
			(xy 332.619226 -239.35024) (xy 332.66111 -239.37915) (xy 332.697814 -239.414405) (xy 332.728387 -239.455091)
			(xy 332.752038 -239.500154) (xy 332.768154 -239.548428) (xy 332.776318 -239.598662) (xy 332.77683 -239.624108)
			(xy 333.084927 -239.624108) (xy 333.089022 -239.57338) (xy 333.101201 -239.523966) (xy 333.121149 -239.477146)
			(xy 333.14835 -239.434132) (xy 333.182098 -239.396038) (xy 333.22152 -239.363851) (xy 333.265594 -239.338405)
			(xy 333.31318 -239.320358) (xy 333.363044 -239.310178) (xy 333.413896 -239.308129) (xy 333.464417 -239.314263)
			(xy 333.513301 -239.328423) (xy 333.55928 -239.35024) (xy 333.601164 -239.37915) (xy 333.637868 -239.414405)
			(xy 333.668441 -239.455091) (xy 333.692092 -239.500154) (xy 333.708208 -239.548428) (xy 333.716372 -239.598662)
			(xy 333.716884 -239.624108) (xy 334.964781 -239.624108) (xy 334.968876 -239.57338) (xy 334.981055 -239.523966)
			(xy 335.001003 -239.477146) (xy 335.028204 -239.434132) (xy 335.061952 -239.396038) (xy 335.101374 -239.363851)
			(xy 335.145448 -239.338405) (xy 335.193034 -239.320358) (xy 335.242898 -239.310178) (xy 335.29375 -239.308129)
			(xy 335.344271 -239.314263) (xy 335.393155 -239.328423) (xy 335.439134 -239.35024) (xy 335.481018 -239.37915)
			(xy 335.517722 -239.414405) (xy 335.548295 -239.455091) (xy 335.571946 -239.500154) (xy 335.588062 -239.548428)
			(xy 335.596226 -239.598662) (xy 335.596738 -239.624108) (xy 335.915266 -239.624108) (xy 335.919226 -239.575054)
			(xy 335.931003 -239.52727) (xy 335.950294 -239.481994) (xy 335.976597 -239.440398) (xy 336.009232 -239.403561)
			(xy 336.047353 -239.372436) (xy 336.089974 -239.347829) (xy 336.13599 -239.330377) (xy 336.184209 -239.320533)
			(xy 336.233384 -239.318552) (xy 336.282239 -239.324484) (xy 336.32951 -239.338176) (xy 336.373972 -239.359274)
			(xy 336.414475 -239.38723) (xy 336.449968 -239.421322) (xy 336.479533 -239.460666) (xy 336.502404 -239.504243)
			(xy 336.517988 -239.550924) (xy 336.525883 -239.599501) (xy 336.526378 -239.624108) (xy 336.844889 -239.624108)
			(xy 336.848984 -239.57338) (xy 336.861163 -239.523966) (xy 336.881111 -239.477146) (xy 336.908312 -239.434132)
			(xy 336.94206 -239.396038) (xy 336.981482 -239.363851) (xy 337.025556 -239.338405) (xy 337.073142 -239.320358)
			(xy 337.123006 -239.310178) (xy 337.173858 -239.308129) (xy 337.224379 -239.314263) (xy 337.273263 -239.328423)
			(xy 337.319242 -239.35024) (xy 337.361126 -239.37915) (xy 337.39783 -239.414405) (xy 337.428403 -239.455091)
			(xy 337.452054 -239.500154) (xy 337.46817 -239.548428) (xy 337.476334 -239.598662) (xy 337.476846 -239.624108)
			(xy 337.795374 -239.624108) (xy 337.799334 -239.575054) (xy 337.811111 -239.52727) (xy 337.830402 -239.481994)
			(xy 337.856705 -239.440398) (xy 337.88934 -239.403561) (xy 337.927461 -239.372436) (xy 337.970082 -239.347829)
			(xy 338.016098 -239.330377) (xy 338.064317 -239.320533) (xy 338.113492 -239.318552) (xy 338.162347 -239.324484)
			(xy 338.209618 -239.338176) (xy 338.25408 -239.359274) (xy 338.294583 -239.38723) (xy 338.330076 -239.421322)
			(xy 338.359641 -239.460666) (xy 338.382512 -239.504243) (xy 338.398096 -239.550924) (xy 338.405991 -239.599501)
			(xy 338.406486 -239.624108) (xy 338.724743 -239.624108) (xy 338.728838 -239.57338) (xy 338.741017 -239.523966)
			(xy 338.760965 -239.477146) (xy 338.788166 -239.434132) (xy 338.821914 -239.396038) (xy 338.861336 -239.363851)
			(xy 338.90541 -239.338405) (xy 338.952996 -239.320358) (xy 339.00286 -239.310178) (xy 339.053712 -239.308129)
			(xy 339.104233 -239.314263) (xy 339.153117 -239.328423) (xy 339.199096 -239.35024) (xy 339.24098 -239.37915)
			(xy 339.277684 -239.414405) (xy 339.308257 -239.455091) (xy 339.331908 -239.500154) (xy 339.348024 -239.548428)
			(xy 339.356188 -239.598662) (xy 339.3567 -239.624108) (xy 339.664797 -239.624108) (xy 339.668892 -239.57338)
			(xy 339.681071 -239.523966) (xy 339.701019 -239.477146) (xy 339.72822 -239.434132) (xy 339.761968 -239.396038)
			(xy 339.80139 -239.363851) (xy 339.845464 -239.338405) (xy 339.89305 -239.320358) (xy 339.942914 -239.310178)
			(xy 339.993766 -239.308129) (xy 340.044287 -239.314263) (xy 340.093171 -239.328423) (xy 340.13915 -239.35024)
			(xy 340.181034 -239.37915) (xy 340.217738 -239.414405) (xy 340.248311 -239.455091) (xy 340.271962 -239.500154)
			(xy 340.288078 -239.548428) (xy 340.296242 -239.598662) (xy 340.296754 -239.624108) (xy 341.544905 -239.624108)
			(xy 341.549 -239.57338) (xy 341.561179 -239.523966) (xy 341.581127 -239.477146) (xy 341.608328 -239.434132)
			(xy 341.642076 -239.396038) (xy 341.681498 -239.363851) (xy 341.725572 -239.338405) (xy 341.773158 -239.320358)
			(xy 341.823022 -239.310178) (xy 341.873874 -239.308129) (xy 341.924395 -239.314263) (xy 341.973279 -239.328423)
			(xy 342.019258 -239.35024) (xy 342.061142 -239.37915) (xy 342.097846 -239.414405) (xy 342.128419 -239.455091)
			(xy 342.15207 -239.500154) (xy 342.168186 -239.548428) (xy 342.17635 -239.598662) (xy 342.176862 -239.624108)
			(xy 342.49539 -239.624108) (xy 342.49935 -239.575054) (xy 342.511127 -239.52727) (xy 342.530418 -239.481994)
			(xy 342.556721 -239.440398) (xy 342.589356 -239.403561) (xy 342.627477 -239.372436) (xy 342.670098 -239.347829)
			(xy 342.716114 -239.330377) (xy 342.764333 -239.320533) (xy 342.813508 -239.318552) (xy 342.862363 -239.324484)
			(xy 342.909634 -239.338176) (xy 342.954096 -239.359274) (xy 342.994599 -239.38723) (xy 343.030092 -239.421322)
			(xy 343.059657 -239.460666) (xy 343.082528 -239.504243) (xy 343.098112 -239.550924) (xy 343.106007 -239.599501)
			(xy 343.106502 -239.624108) (xy 343.106007 -239.648715) (xy 343.098112 -239.697292) (xy 343.082528 -239.743973)
			(xy 343.059657 -239.78755) (xy 343.030092 -239.826894) (xy 342.994599 -239.860986) (xy 342.954096 -239.888942)
			(xy 342.909634 -239.91004) (xy 342.862363 -239.923732) (xy 342.813508 -239.929664) (xy 342.764333 -239.927683)
			(xy 342.716114 -239.917839) (xy 342.670098 -239.900387) (xy 342.627477 -239.87578) (xy 342.589356 -239.844655)
			(xy 342.556721 -239.807818) (xy 342.530418 -239.766222) (xy 342.511127 -239.720946) (xy 342.49935 -239.673162)
			(xy 342.49539 -239.624108) (xy 342.176862 -239.624108) (xy 342.17635 -239.649554) (xy 342.168186 -239.699788)
			(xy 342.15207 -239.748062) (xy 342.128419 -239.793125) (xy 342.097846 -239.833811) (xy 342.061142 -239.869066)
			(xy 342.019258 -239.897976) (xy 341.973279 -239.919793) (xy 341.924395 -239.933953) (xy 341.873874 -239.940087)
			(xy 341.823022 -239.938038) (xy 341.773158 -239.927858) (xy 341.725572 -239.909811) (xy 341.681498 -239.884365)
			(xy 341.642076 -239.852178) (xy 341.608328 -239.814084) (xy 341.581127 -239.77107) (xy 341.561179 -239.72425)
			(xy 341.549 -239.674836) (xy 341.544905 -239.624108) (xy 340.296754 -239.624108) (xy 340.296242 -239.649554)
			(xy 340.288078 -239.699788) (xy 340.271962 -239.748062) (xy 340.248311 -239.793125) (xy 340.217738 -239.833811)
			(xy 340.181034 -239.869066) (xy 340.13915 -239.897976) (xy 340.093171 -239.919793) (xy 340.044287 -239.933953)
			(xy 339.993766 -239.940087) (xy 339.942914 -239.938038) (xy 339.89305 -239.927858) (xy 339.845464 -239.909811)
			(xy 339.80139 -239.884365) (xy 339.761968 -239.852178) (xy 339.72822 -239.814084) (xy 339.701019 -239.77107)
			(xy 339.681071 -239.72425) (xy 339.668892 -239.674836) (xy 339.664797 -239.624108) (xy 339.3567 -239.624108)
			(xy 339.356188 -239.649554) (xy 339.348024 -239.699788) (xy 339.331908 -239.748062) (xy 339.308257 -239.793125)
			(xy 339.277684 -239.833811) (xy 339.24098 -239.869066) (xy 339.199096 -239.897976) (xy 339.153117 -239.919793)
			(xy 339.104233 -239.933953) (xy 339.053712 -239.940087) (xy 339.00286 -239.938038) (xy 338.952996 -239.927858)
			(xy 338.90541 -239.909811) (xy 338.861336 -239.884365) (xy 338.821914 -239.852178) (xy 338.788166 -239.814084)
			(xy 338.760965 -239.77107) (xy 338.741017 -239.72425) (xy 338.728838 -239.674836) (xy 338.724743 -239.624108)
			(xy 338.406486 -239.624108) (xy 338.405991 -239.648715) (xy 338.398096 -239.697292) (xy 338.382512 -239.743973)
			(xy 338.359641 -239.78755) (xy 338.330076 -239.826894) (xy 338.294583 -239.860986) (xy 338.25408 -239.888942)
			(xy 338.209618 -239.91004) (xy 338.162347 -239.923732) (xy 338.113492 -239.929664) (xy 338.064317 -239.927683)
			(xy 338.016098 -239.917839) (xy 337.970082 -239.900387) (xy 337.927461 -239.87578) (xy 337.88934 -239.844655)
			(xy 337.856705 -239.807818) (xy 337.830402 -239.766222) (xy 337.811111 -239.720946) (xy 337.799334 -239.673162)
			(xy 337.795374 -239.624108) (xy 337.476846 -239.624108) (xy 337.476334 -239.649554) (xy 337.46817 -239.699788)
			(xy 337.452054 -239.748062) (xy 337.428403 -239.793125) (xy 337.39783 -239.833811) (xy 337.361126 -239.869066)
			(xy 337.319242 -239.897976) (xy 337.273263 -239.919793) (xy 337.224379 -239.933953) (xy 337.173858 -239.940087)
			(xy 337.123006 -239.938038) (xy 337.073142 -239.927858) (xy 337.025556 -239.909811) (xy 336.981482 -239.884365)
			(xy 336.94206 -239.852178) (xy 336.908312 -239.814084) (xy 336.881111 -239.77107) (xy 336.861163 -239.72425)
			(xy 336.848984 -239.674836) (xy 336.844889 -239.624108) (xy 336.526378 -239.624108) (xy 336.525883 -239.648715)
			(xy 336.517988 -239.697292) (xy 336.502404 -239.743973) (xy 336.479533 -239.78755) (xy 336.449968 -239.826894)
			(xy 336.414475 -239.860986) (xy 336.373972 -239.888942) (xy 336.32951 -239.91004) (xy 336.282239 -239.923732)
			(xy 336.233384 -239.929664) (xy 336.184209 -239.927683) (xy 336.13599 -239.917839) (xy 336.089974 -239.900387)
			(xy 336.047353 -239.87578) (xy 336.009232 -239.844655) (xy 335.976597 -239.807818) (xy 335.950294 -239.766222)
			(xy 335.931003 -239.720946) (xy 335.919226 -239.673162) (xy 335.915266 -239.624108) (xy 335.596738 -239.624108)
			(xy 335.596226 -239.649554) (xy 335.588062 -239.699788) (xy 335.571946 -239.748062) (xy 335.548295 -239.793125)
			(xy 335.517722 -239.833811) (xy 335.481018 -239.869066) (xy 335.439134 -239.897976) (xy 335.393155 -239.919793)
			(xy 335.344271 -239.933953) (xy 335.29375 -239.940087) (xy 335.242898 -239.938038) (xy 335.193034 -239.927858)
			(xy 335.145448 -239.909811) (xy 335.101374 -239.884365) (xy 335.061952 -239.852178) (xy 335.028204 -239.814084)
			(xy 335.001003 -239.77107) (xy 334.981055 -239.72425) (xy 334.968876 -239.674836) (xy 334.964781 -239.624108)
			(xy 333.716884 -239.624108) (xy 333.716372 -239.649554) (xy 333.708208 -239.699788) (xy 333.692092 -239.748062)
			(xy 333.668441 -239.793125) (xy 333.637868 -239.833811) (xy 333.601164 -239.869066) (xy 333.55928 -239.897976)
			(xy 333.513301 -239.919793) (xy 333.464417 -239.933953) (xy 333.413896 -239.940087) (xy 333.363044 -239.938038)
			(xy 333.31318 -239.927858) (xy 333.265594 -239.909811) (xy 333.22152 -239.884365) (xy 333.182098 -239.852178)
			(xy 333.14835 -239.814084) (xy 333.121149 -239.77107) (xy 333.101201 -239.72425) (xy 333.089022 -239.674836)
			(xy 333.084927 -239.624108) (xy 332.77683 -239.624108) (xy 332.776318 -239.649554) (xy 332.768154 -239.699788)
			(xy 332.752038 -239.748062) (xy 332.728387 -239.793125) (xy 332.697814 -239.833811) (xy 332.66111 -239.869066)
			(xy 332.619226 -239.897976) (xy 332.573247 -239.919793) (xy 332.524363 -239.933953) (xy 332.473842 -239.940087)
			(xy 332.42299 -239.938038) (xy 332.373126 -239.927858) (xy 332.32554 -239.909811) (xy 332.281466 -239.884365)
			(xy 332.242044 -239.852178) (xy 332.208296 -239.814084) (xy 332.181095 -239.77107) (xy 332.161147 -239.72425)
			(xy 332.148968 -239.674836) (xy 332.144873 -239.624108) (xy 331.826362 -239.624108) (xy 331.825867 -239.648715)
			(xy 331.817972 -239.697292) (xy 331.802388 -239.743973) (xy 331.779517 -239.78755) (xy 331.749952 -239.826894)
			(xy 331.714459 -239.860986) (xy 331.673956 -239.888942) (xy 331.629494 -239.91004) (xy 331.582223 -239.923732)
			(xy 331.533368 -239.929664) (xy 331.484193 -239.927683) (xy 331.435974 -239.917839) (xy 331.389958 -239.900387)
			(xy 331.347337 -239.87578) (xy 331.309216 -239.844655) (xy 331.276581 -239.807818) (xy 331.250278 -239.766222)
			(xy 331.230987 -239.720946) (xy 331.21921 -239.673162) (xy 331.21525 -239.624108) (xy 330.896722 -239.624108)
			(xy 330.89621 -239.649554) (xy 330.888046 -239.699788) (xy 330.87193 -239.748062) (xy 330.848279 -239.793125)
			(xy 330.817706 -239.833811) (xy 330.781002 -239.869066) (xy 330.739118 -239.897976) (xy 330.693139 -239.919793)
			(xy 330.644255 -239.933953) (xy 330.593734 -239.940087) (xy 330.542882 -239.938038) (xy 330.493018 -239.927858)
			(xy 330.445432 -239.909811) (xy 330.401358 -239.884365) (xy 330.361936 -239.852178) (xy 330.328188 -239.814084)
			(xy 330.300987 -239.77107) (xy 330.281039 -239.72425) (xy 330.26886 -239.674836) (xy 330.264765 -239.624108)
			(xy 329.946508 -239.624108) (xy 329.946013 -239.648715) (xy 329.938118 -239.697292) (xy 329.922534 -239.743973)
			(xy 329.899663 -239.78755) (xy 329.870098 -239.826894) (xy 329.834605 -239.860986) (xy 329.794102 -239.888942)
			(xy 329.74964 -239.91004) (xy 329.702369 -239.923732) (xy 329.653514 -239.929664) (xy 329.604339 -239.927683)
			(xy 329.55612 -239.917839) (xy 329.510104 -239.900387) (xy 329.467483 -239.87578) (xy 329.429362 -239.844655)
			(xy 329.396727 -239.807818) (xy 329.370424 -239.766222) (xy 329.351133 -239.720946) (xy 329.339356 -239.673162)
			(xy 329.335396 -239.624108) (xy 329.016868 -239.624108) (xy 329.016356 -239.649554) (xy 329.008192 -239.699788)
			(xy 328.992076 -239.748062) (xy 328.968425 -239.793125) (xy 328.937852 -239.833811) (xy 328.901148 -239.869066)
			(xy 328.859264 -239.897976) (xy 328.813285 -239.919793) (xy 328.764401 -239.933953) (xy 328.71388 -239.940087)
			(xy 328.663028 -239.938038) (xy 328.613164 -239.927858) (xy 328.565578 -239.909811) (xy 328.521504 -239.884365)
			(xy 328.482082 -239.852178) (xy 328.448334 -239.814084) (xy 328.421133 -239.77107) (xy 328.401185 -239.72425)
			(xy 328.389006 -239.674836) (xy 328.384911 -239.624108) (xy 324.903545 -239.624108) (xy 324.905872 -239.625212)
			(xy 324.946375 -239.653168) (xy 324.981868 -239.68726) (xy 325.011433 -239.726604) (xy 325.034304 -239.770181)
			(xy 325.049888 -239.816862) (xy 325.057783 -239.865439) (xy 325.058278 -239.890046) (xy 325.057783 -239.914653)
			(xy 325.049888 -239.96323) (xy 325.034304 -240.009911) (xy 325.011433 -240.053488) (xy 324.981868 -240.092832)
			(xy 324.946375 -240.126924) (xy 324.905872 -240.15488) (xy 324.86141 -240.175978) (xy 324.814139 -240.18967)
			(xy 324.765284 -240.195602) (xy 324.716109 -240.193621) (xy 324.66789 -240.183777) (xy 324.621874 -240.166325)
			(xy 324.579253 -240.141718) (xy 324.541132 -240.110593) (xy 324.508497 -240.073756) (xy 324.482194 -240.03216)
			(xy 324.462903 -239.986884) (xy 324.451126 -239.9391) (xy 324.447166 -239.890046) (xy 310.45912 -239.890046)
			(xy 310.45912 -240.434114) (xy 326.045334 -240.434114) (xy 326.049294 -240.38506) (xy 326.061071 -240.337276)
			(xy 326.080362 -240.292) (xy 326.106665 -240.250404) (xy 326.1393 -240.213567) (xy 326.177421 -240.182442)
			(xy 326.220042 -240.157835) (xy 326.266058 -240.140383) (xy 326.314277 -240.130539) (xy 326.363452 -240.128558)
			(xy 326.412307 -240.13449) (xy 326.459578 -240.148182) (xy 326.50404 -240.16928) (xy 326.544543 -240.197236)
			(xy 326.580036 -240.231328) (xy 326.609601 -240.270672) (xy 326.632472 -240.314249) (xy 326.648056 -240.36093)
			(xy 326.655951 -240.409507) (xy 326.656446 -240.434114) (xy 327.925442 -240.434114) (xy 327.929402 -240.38506)
			(xy 327.941179 -240.337276) (xy 327.96047 -240.292) (xy 327.986773 -240.250404) (xy 328.019408 -240.213567)
			(xy 328.057529 -240.182442) (xy 328.10015 -240.157835) (xy 328.146166 -240.140383) (xy 328.194385 -240.130539)
			(xy 328.24356 -240.128558) (xy 328.292415 -240.13449) (xy 328.339686 -240.148182) (xy 328.384148 -240.16928)
			(xy 328.424651 -240.197236) (xy 328.460144 -240.231328) (xy 328.489709 -240.270672) (xy 328.51258 -240.314249)
			(xy 328.528164 -240.36093) (xy 328.536059 -240.409507) (xy 328.536554 -240.434114) (xy 328.854811 -240.434114)
			(xy 328.858906 -240.383386) (xy 328.871085 -240.333972) (xy 328.891033 -240.287152) (xy 328.918234 -240.244138)
			(xy 328.951982 -240.206044) (xy 328.991404 -240.173857) (xy 329.035478 -240.148411) (xy 329.083064 -240.130364)
			(xy 329.132928 -240.120184) (xy 329.18378 -240.118135) (xy 329.234301 -240.124269) (xy 329.283185 -240.138429)
			(xy 329.329164 -240.160246) (xy 329.371048 -240.189156) (xy 329.407752 -240.224411) (xy 329.438325 -240.265097)
			(xy 329.461976 -240.31016) (xy 329.478092 -240.358434) (xy 329.486256 -240.408668) (xy 329.486768 -240.434114)
			(xy 329.794865 -240.434114) (xy 329.79896 -240.383386) (xy 329.811139 -240.333972) (xy 329.831087 -240.287152)
			(xy 329.858288 -240.244138) (xy 329.892036 -240.206044) (xy 329.931458 -240.173857) (xy 329.975532 -240.148411)
			(xy 330.023118 -240.130364) (xy 330.072982 -240.120184) (xy 330.123834 -240.118135) (xy 330.174355 -240.124269)
			(xy 330.223239 -240.138429) (xy 330.269218 -240.160246) (xy 330.311102 -240.189156) (xy 330.347806 -240.224411)
			(xy 330.378379 -240.265097) (xy 330.40203 -240.31016) (xy 330.418146 -240.358434) (xy 330.42631 -240.408668)
			(xy 330.426822 -240.434114) (xy 330.74535 -240.434114) (xy 330.74931 -240.38506) (xy 330.761087 -240.337276)
			(xy 330.780378 -240.292) (xy 330.806681 -240.250404) (xy 330.839316 -240.213567) (xy 330.877437 -240.182442)
			(xy 330.920058 -240.157835) (xy 330.966074 -240.140383) (xy 331.014293 -240.130539) (xy 331.063468 -240.128558)
			(xy 331.112323 -240.13449) (xy 331.159594 -240.148182) (xy 331.204056 -240.16928) (xy 331.244559 -240.197236)
			(xy 331.280052 -240.231328) (xy 331.309617 -240.270672) (xy 331.332488 -240.314249) (xy 331.348072 -240.36093)
			(xy 331.355967 -240.409507) (xy 331.356462 -240.434114) (xy 331.674973 -240.434114) (xy 331.679068 -240.383386)
			(xy 331.691247 -240.333972) (xy 331.711195 -240.287152) (xy 331.738396 -240.244138) (xy 331.772144 -240.206044)
			(xy 331.811566 -240.173857) (xy 331.85564 -240.148411) (xy 331.903226 -240.130364) (xy 331.95309 -240.120184)
			(xy 332.003942 -240.118135) (xy 332.054463 -240.124269) (xy 332.103347 -240.138429) (xy 332.149326 -240.160246)
			(xy 332.19121 -240.189156) (xy 332.227914 -240.224411) (xy 332.258487 -240.265097) (xy 332.282138 -240.31016)
			(xy 332.298254 -240.358434) (xy 332.306418 -240.408668) (xy 332.30693 -240.434114) (xy 332.625204 -240.434114)
			(xy 332.629164 -240.38506) (xy 332.640941 -240.337276) (xy 332.660232 -240.292) (xy 332.686535 -240.250404)
			(xy 332.71917 -240.213567) (xy 332.757291 -240.182442) (xy 332.799912 -240.157835) (xy 332.845928 -240.140383)
			(xy 332.894147 -240.130539) (xy 332.943322 -240.128558) (xy 332.992177 -240.13449) (xy 333.039448 -240.148182)
			(xy 333.08391 -240.16928) (xy 333.124413 -240.197236) (xy 333.159906 -240.231328) (xy 333.189471 -240.270672)
			(xy 333.212342 -240.314249) (xy 333.227926 -240.36093) (xy 333.235821 -240.409507) (xy 333.236316 -240.434114)
			(xy 333.554827 -240.434114) (xy 333.558922 -240.383386) (xy 333.571101 -240.333972) (xy 333.591049 -240.287152)
			(xy 333.61825 -240.244138) (xy 333.651998 -240.206044) (xy 333.69142 -240.173857) (xy 333.735494 -240.148411)
			(xy 333.78308 -240.130364) (xy 333.832944 -240.120184) (xy 333.883796 -240.118135) (xy 333.934317 -240.124269)
			(xy 333.983201 -240.138429) (xy 334.02918 -240.160246) (xy 334.071064 -240.189156) (xy 334.107768 -240.224411)
			(xy 334.138341 -240.265097) (xy 334.161992 -240.31016) (xy 334.178108 -240.358434) (xy 334.186272 -240.408668)
			(xy 334.186784 -240.434114) (xy 334.505312 -240.434114) (xy 334.509272 -240.38506) (xy 334.521049 -240.337276)
			(xy 334.54034 -240.292) (xy 334.566643 -240.250404) (xy 334.599278 -240.213567) (xy 334.637399 -240.182442)
			(xy 334.68002 -240.157835) (xy 334.726036 -240.140383) (xy 334.774255 -240.130539) (xy 334.82343 -240.128558)
			(xy 334.872285 -240.13449) (xy 334.919556 -240.148182) (xy 334.964018 -240.16928) (xy 335.004521 -240.197236)
			(xy 335.040014 -240.231328) (xy 335.069579 -240.270672) (xy 335.09245 -240.314249) (xy 335.108034 -240.36093)
			(xy 335.115929 -240.409507) (xy 335.116424 -240.434114) (xy 335.434935 -240.434114) (xy 335.43903 -240.383386)
			(xy 335.451209 -240.333972) (xy 335.471157 -240.287152) (xy 335.498358 -240.244138) (xy 335.532106 -240.206044)
			(xy 335.571528 -240.173857) (xy 335.615602 -240.148411) (xy 335.663188 -240.130364) (xy 335.713052 -240.120184)
			(xy 335.763904 -240.118135) (xy 335.814425 -240.124269) (xy 335.863309 -240.138429) (xy 335.909288 -240.160246)
			(xy 335.951172 -240.189156) (xy 335.987876 -240.224411) (xy 336.018449 -240.265097) (xy 336.0421 -240.31016)
			(xy 336.058216 -240.358434) (xy 336.06638 -240.408668) (xy 336.066892 -240.434114) (xy 336.374989 -240.434114)
			(xy 336.379084 -240.383386) (xy 336.391263 -240.333972) (xy 336.411211 -240.287152) (xy 336.438412 -240.244138)
			(xy 336.47216 -240.206044) (xy 336.511582 -240.173857) (xy 336.555656 -240.148411) (xy 336.603242 -240.130364)
			(xy 336.653106 -240.120184) (xy 336.703958 -240.118135) (xy 336.754479 -240.124269) (xy 336.803363 -240.138429)
			(xy 336.849342 -240.160246) (xy 336.891226 -240.189156) (xy 336.92793 -240.224411) (xy 336.958503 -240.265097)
			(xy 336.982154 -240.31016) (xy 336.99827 -240.358434) (xy 337.006434 -240.408668) (xy 337.006946 -240.434114)
			(xy 337.32522 -240.434114) (xy 337.32918 -240.38506) (xy 337.340957 -240.337276) (xy 337.360248 -240.292)
			(xy 337.386551 -240.250404) (xy 337.419186 -240.213567) (xy 337.457307 -240.182442) (xy 337.499928 -240.157835)
			(xy 337.545944 -240.140383) (xy 337.594163 -240.130539) (xy 337.643338 -240.128558) (xy 337.692193 -240.13449)
			(xy 337.739464 -240.148182) (xy 337.783926 -240.16928) (xy 337.824429 -240.197236) (xy 337.859922 -240.231328)
			(xy 337.889487 -240.270672) (xy 337.912358 -240.314249) (xy 337.927942 -240.36093) (xy 337.935837 -240.409507)
			(xy 337.936332 -240.434114) (xy 338.254843 -240.434114) (xy 338.258938 -240.383386) (xy 338.271117 -240.333972)
			(xy 338.291065 -240.287152) (xy 338.318266 -240.244138) (xy 338.352014 -240.206044) (xy 338.391436 -240.173857)
			(xy 338.43551 -240.148411) (xy 338.483096 -240.130364) (xy 338.53296 -240.120184) (xy 338.583812 -240.118135)
			(xy 338.634333 -240.124269) (xy 338.683217 -240.138429) (xy 338.729196 -240.160246) (xy 338.77108 -240.189156)
			(xy 338.807784 -240.224411) (xy 338.838357 -240.265097) (xy 338.862008 -240.31016) (xy 338.878124 -240.358434)
			(xy 338.886288 -240.408668) (xy 338.8868 -240.434114) (xy 339.205328 -240.434114) (xy 339.209288 -240.38506)
			(xy 339.221065 -240.337276) (xy 339.240356 -240.292) (xy 339.266659 -240.250404) (xy 339.299294 -240.213567)
			(xy 339.337415 -240.182442) (xy 339.380036 -240.157835) (xy 339.426052 -240.140383) (xy 339.474271 -240.130539)
			(xy 339.523446 -240.128558) (xy 339.572301 -240.13449) (xy 339.619572 -240.148182) (xy 339.664034 -240.16928)
			(xy 339.704537 -240.197236) (xy 339.74003 -240.231328) (xy 339.769595 -240.270672) (xy 339.792466 -240.314249)
			(xy 339.80805 -240.36093) (xy 339.815945 -240.409507) (xy 339.81644 -240.434114) (xy 340.134951 -240.434114)
			(xy 340.139046 -240.383386) (xy 340.151225 -240.333972) (xy 340.171173 -240.287152) (xy 340.198374 -240.244138)
			(xy 340.232122 -240.206044) (xy 340.271544 -240.173857) (xy 340.315618 -240.148411) (xy 340.363204 -240.130364)
			(xy 340.413068 -240.120184) (xy 340.46392 -240.118135) (xy 340.514441 -240.124269) (xy 340.563325 -240.138429)
			(xy 340.609304 -240.160246) (xy 340.651188 -240.189156) (xy 340.687892 -240.224411) (xy 340.718465 -240.265097)
			(xy 340.742116 -240.31016) (xy 340.758232 -240.358434) (xy 340.766396 -240.408668) (xy 340.766908 -240.434114)
			(xy 341.085182 -240.434114) (xy 341.089142 -240.38506) (xy 341.100919 -240.337276) (xy 341.12021 -240.292)
			(xy 341.146513 -240.250404) (xy 341.179148 -240.213567) (xy 341.217269 -240.182442) (xy 341.25989 -240.157835)
			(xy 341.305906 -240.140383) (xy 341.354125 -240.130539) (xy 341.4033 -240.128558) (xy 341.452155 -240.13449)
			(xy 341.499426 -240.148182) (xy 341.543888 -240.16928) (xy 341.584391 -240.197236) (xy 341.619884 -240.231328)
			(xy 341.649449 -240.270672) (xy 341.67232 -240.314249) (xy 341.687904 -240.36093) (xy 341.695799 -240.409507)
			(xy 341.696294 -240.434114) (xy 342.014805 -240.434114) (xy 342.0189 -240.383386) (xy 342.031079 -240.333972)
			(xy 342.051027 -240.287152) (xy 342.078228 -240.244138) (xy 342.111976 -240.206044) (xy 342.151398 -240.173857)
			(xy 342.195472 -240.148411) (xy 342.243058 -240.130364) (xy 342.292922 -240.120184) (xy 342.343774 -240.118135)
			(xy 342.394295 -240.124269) (xy 342.443179 -240.138429) (xy 342.489158 -240.160246) (xy 342.531042 -240.189156)
			(xy 342.567746 -240.224411) (xy 342.598319 -240.265097) (xy 342.62197 -240.31016) (xy 342.638086 -240.358434)
			(xy 342.64625 -240.408668) (xy 342.646762 -240.434114) (xy 342.954859 -240.434114) (xy 342.958954 -240.383386)
			(xy 342.971133 -240.333972) (xy 342.991081 -240.287152) (xy 343.018282 -240.244138) (xy 343.05203 -240.206044)
			(xy 343.091452 -240.173857) (xy 343.135526 -240.148411) (xy 343.183112 -240.130364) (xy 343.232976 -240.120184)
			(xy 343.283828 -240.118135) (xy 343.334349 -240.124269) (xy 343.383233 -240.138429) (xy 343.429212 -240.160246)
			(xy 343.471096 -240.189156) (xy 343.5078 -240.224411) (xy 343.538373 -240.265097) (xy 343.562024 -240.31016)
			(xy 343.57814 -240.358434) (xy 343.586304 -240.408668) (xy 343.586816 -240.434114) (xy 343.586304 -240.45956)
			(xy 343.57814 -240.509794) (xy 343.562024 -240.558068) (xy 343.538373 -240.603131) (xy 343.5078 -240.643817)
			(xy 343.471096 -240.679072) (xy 343.429212 -240.707982) (xy 343.383233 -240.729799) (xy 343.334349 -240.743959)
			(xy 343.283828 -240.750093) (xy 343.232976 -240.748044) (xy 343.183112 -240.737864) (xy 343.135526 -240.719817)
			(xy 343.091452 -240.694371) (xy 343.05203 -240.662184) (xy 343.018282 -240.62409) (xy 342.991081 -240.581076)
			(xy 342.971133 -240.534256) (xy 342.958954 -240.484842) (xy 342.954859 -240.434114) (xy 342.646762 -240.434114)
			(xy 342.64625 -240.45956) (xy 342.638086 -240.509794) (xy 342.62197 -240.558068) (xy 342.598319 -240.603131)
			(xy 342.567746 -240.643817) (xy 342.531042 -240.679072) (xy 342.489158 -240.707982) (xy 342.443179 -240.729799)
			(xy 342.394295 -240.743959) (xy 342.343774 -240.750093) (xy 342.292922 -240.748044) (xy 342.243058 -240.737864)
			(xy 342.195472 -240.719817) (xy 342.151398 -240.694371) (xy 342.111976 -240.662184) (xy 342.078228 -240.62409)
			(xy 342.051027 -240.581076) (xy 342.031079 -240.534256) (xy 342.0189 -240.484842) (xy 342.014805 -240.434114)
			(xy 341.696294 -240.434114) (xy 341.695799 -240.458721) (xy 341.687904 -240.507298) (xy 341.67232 -240.553979)
			(xy 341.649449 -240.597556) (xy 341.619884 -240.6369) (xy 341.584391 -240.670992) (xy 341.543888 -240.698948)
			(xy 341.499426 -240.720046) (xy 341.452155 -240.733738) (xy 341.4033 -240.73967) (xy 341.354125 -240.737689)
			(xy 341.305906 -240.727845) (xy 341.25989 -240.710393) (xy 341.217269 -240.685786) (xy 341.179148 -240.654661)
			(xy 341.146513 -240.617824) (xy 341.12021 -240.576228) (xy 341.100919 -240.530952) (xy 341.089142 -240.483168)
			(xy 341.085182 -240.434114) (xy 340.766908 -240.434114) (xy 340.766396 -240.45956) (xy 340.758232 -240.509794)
			(xy 340.742116 -240.558068) (xy 340.718465 -240.603131) (xy 340.687892 -240.643817) (xy 340.651188 -240.679072)
			(xy 340.609304 -240.707982) (xy 340.563325 -240.729799) (xy 340.514441 -240.743959) (xy 340.46392 -240.750093)
			(xy 340.413068 -240.748044) (xy 340.363204 -240.737864) (xy 340.315618 -240.719817) (xy 340.271544 -240.694371)
			(xy 340.232122 -240.662184) (xy 340.198374 -240.62409) (xy 340.171173 -240.581076) (xy 340.151225 -240.534256)
			(xy 340.139046 -240.484842) (xy 340.134951 -240.434114) (xy 339.81644 -240.434114) (xy 339.815945 -240.458721)
			(xy 339.80805 -240.507298) (xy 339.792466 -240.553979) (xy 339.769595 -240.597556) (xy 339.74003 -240.6369)
			(xy 339.704537 -240.670992) (xy 339.664034 -240.698948) (xy 339.619572 -240.720046) (xy 339.572301 -240.733738)
			(xy 339.523446 -240.73967) (xy 339.474271 -240.737689) (xy 339.426052 -240.727845) (xy 339.380036 -240.710393)
			(xy 339.337415 -240.685786) (xy 339.299294 -240.654661) (xy 339.266659 -240.617824) (xy 339.240356 -240.576228)
			(xy 339.221065 -240.530952) (xy 339.209288 -240.483168) (xy 339.205328 -240.434114) (xy 338.8868 -240.434114)
			(xy 338.886288 -240.45956) (xy 338.878124 -240.509794) (xy 338.862008 -240.558068) (xy 338.838357 -240.603131)
			(xy 338.807784 -240.643817) (xy 338.77108 -240.679072) (xy 338.729196 -240.707982) (xy 338.683217 -240.729799)
			(xy 338.634333 -240.743959) (xy 338.583812 -240.750093) (xy 338.53296 -240.748044) (xy 338.483096 -240.737864)
			(xy 338.43551 -240.719817) (xy 338.391436 -240.694371) (xy 338.352014 -240.662184) (xy 338.318266 -240.62409)
			(xy 338.291065 -240.581076) (xy 338.271117 -240.534256) (xy 338.258938 -240.484842) (xy 338.254843 -240.434114)
			(xy 337.936332 -240.434114) (xy 337.935837 -240.458721) (xy 337.927942 -240.507298) (xy 337.912358 -240.553979)
			(xy 337.889487 -240.597556) (xy 337.859922 -240.6369) (xy 337.824429 -240.670992) (xy 337.783926 -240.698948)
			(xy 337.739464 -240.720046) (xy 337.692193 -240.733738) (xy 337.643338 -240.73967) (xy 337.594163 -240.737689)
			(xy 337.545944 -240.727845) (xy 337.499928 -240.710393) (xy 337.457307 -240.685786) (xy 337.419186 -240.654661)
			(xy 337.386551 -240.617824) (xy 337.360248 -240.576228) (xy 337.340957 -240.530952) (xy 337.32918 -240.483168)
			(xy 337.32522 -240.434114) (xy 337.006946 -240.434114) (xy 337.006434 -240.45956) (xy 336.99827 -240.509794)
			(xy 336.982154 -240.558068) (xy 336.958503 -240.603131) (xy 336.92793 -240.643817) (xy 336.891226 -240.679072)
			(xy 336.849342 -240.707982) (xy 336.803363 -240.729799) (xy 336.754479 -240.743959) (xy 336.703958 -240.750093)
			(xy 336.653106 -240.748044) (xy 336.603242 -240.737864) (xy 336.555656 -240.719817) (xy 336.511582 -240.694371)
			(xy 336.47216 -240.662184) (xy 336.438412 -240.62409) (xy 336.411211 -240.581076) (xy 336.391263 -240.534256)
			(xy 336.379084 -240.484842) (xy 336.374989 -240.434114) (xy 336.066892 -240.434114) (xy 336.06638 -240.45956)
			(xy 336.058216 -240.509794) (xy 336.0421 -240.558068) (xy 336.018449 -240.603131) (xy 335.987876 -240.643817)
			(xy 335.951172 -240.679072) (xy 335.909288 -240.707982) (xy 335.863309 -240.729799) (xy 335.814425 -240.743959)
			(xy 335.763904 -240.750093) (xy 335.713052 -240.748044) (xy 335.663188 -240.737864) (xy 335.615602 -240.719817)
			(xy 335.571528 -240.694371) (xy 335.532106 -240.662184) (xy 335.498358 -240.62409) (xy 335.471157 -240.581076)
			(xy 335.451209 -240.534256) (xy 335.43903 -240.484842) (xy 335.434935 -240.434114) (xy 335.116424 -240.434114)
			(xy 335.115929 -240.458721) (xy 335.108034 -240.507298) (xy 335.09245 -240.553979) (xy 335.069579 -240.597556)
			(xy 335.040014 -240.6369) (xy 335.004521 -240.670992) (xy 334.964018 -240.698948) (xy 334.919556 -240.720046)
			(xy 334.872285 -240.733738) (xy 334.82343 -240.73967) (xy 334.774255 -240.737689) (xy 334.726036 -240.727845)
			(xy 334.68002 -240.710393) (xy 334.637399 -240.685786) (xy 334.599278 -240.654661) (xy 334.566643 -240.617824)
			(xy 334.54034 -240.576228) (xy 334.521049 -240.530952) (xy 334.509272 -240.483168) (xy 334.505312 -240.434114)
			(xy 334.186784 -240.434114) (xy 334.186272 -240.45956) (xy 334.178108 -240.509794) (xy 334.161992 -240.558068)
			(xy 334.138341 -240.603131) (xy 334.107768 -240.643817) (xy 334.071064 -240.679072) (xy 334.02918 -240.707982)
			(xy 333.983201 -240.729799) (xy 333.934317 -240.743959) (xy 333.883796 -240.750093) (xy 333.832944 -240.748044)
			(xy 333.78308 -240.737864) (xy 333.735494 -240.719817) (xy 333.69142 -240.694371) (xy 333.651998 -240.662184)
			(xy 333.61825 -240.62409) (xy 333.591049 -240.581076) (xy 333.571101 -240.534256) (xy 333.558922 -240.484842)
			(xy 333.554827 -240.434114) (xy 333.236316 -240.434114) (xy 333.235821 -240.458721) (xy 333.227926 -240.507298)
			(xy 333.212342 -240.553979) (xy 333.189471 -240.597556) (xy 333.159906 -240.6369) (xy 333.124413 -240.670992)
			(xy 333.08391 -240.698948) (xy 333.039448 -240.720046) (xy 332.992177 -240.733738) (xy 332.943322 -240.73967)
			(xy 332.894147 -240.737689) (xy 332.845928 -240.727845) (xy 332.799912 -240.710393) (xy 332.757291 -240.685786)
			(xy 332.71917 -240.654661) (xy 332.686535 -240.617824) (xy 332.660232 -240.576228) (xy 332.640941 -240.530952)
			(xy 332.629164 -240.483168) (xy 332.625204 -240.434114) (xy 332.30693 -240.434114) (xy 332.306418 -240.45956)
			(xy 332.298254 -240.509794) (xy 332.282138 -240.558068) (xy 332.258487 -240.603131) (xy 332.227914 -240.643817)
			(xy 332.19121 -240.679072) (xy 332.149326 -240.707982) (xy 332.103347 -240.729799) (xy 332.054463 -240.743959)
			(xy 332.003942 -240.750093) (xy 331.95309 -240.748044) (xy 331.903226 -240.737864) (xy 331.85564 -240.719817)
			(xy 331.811566 -240.694371) (xy 331.772144 -240.662184) (xy 331.738396 -240.62409) (xy 331.711195 -240.581076)
			(xy 331.691247 -240.534256) (xy 331.679068 -240.484842) (xy 331.674973 -240.434114) (xy 331.356462 -240.434114)
			(xy 331.355967 -240.458721) (xy 331.348072 -240.507298) (xy 331.332488 -240.553979) (xy 331.309617 -240.597556)
			(xy 331.280052 -240.6369) (xy 331.244559 -240.670992) (xy 331.204056 -240.698948) (xy 331.159594 -240.720046)
			(xy 331.112323 -240.733738) (xy 331.063468 -240.73967) (xy 331.014293 -240.737689) (xy 330.966074 -240.727845)
			(xy 330.920058 -240.710393) (xy 330.877437 -240.685786) (xy 330.839316 -240.654661) (xy 330.806681 -240.617824)
			(xy 330.780378 -240.576228) (xy 330.761087 -240.530952) (xy 330.74931 -240.483168) (xy 330.74535 -240.434114)
			(xy 330.426822 -240.434114) (xy 330.42631 -240.45956) (xy 330.418146 -240.509794) (xy 330.40203 -240.558068)
			(xy 330.378379 -240.603131) (xy 330.347806 -240.643817) (xy 330.311102 -240.679072) (xy 330.269218 -240.707982)
			(xy 330.223239 -240.729799) (xy 330.174355 -240.743959) (xy 330.123834 -240.750093) (xy 330.072982 -240.748044)
			(xy 330.023118 -240.737864) (xy 329.975532 -240.719817) (xy 329.931458 -240.694371) (xy 329.892036 -240.662184)
			(xy 329.858288 -240.62409) (xy 329.831087 -240.581076) (xy 329.811139 -240.534256) (xy 329.79896 -240.484842)
			(xy 329.794865 -240.434114) (xy 329.486768 -240.434114) (xy 329.486256 -240.45956) (xy 329.478092 -240.509794)
			(xy 329.461976 -240.558068) (xy 329.438325 -240.603131) (xy 329.407752 -240.643817) (xy 329.371048 -240.679072)
			(xy 329.329164 -240.707982) (xy 329.283185 -240.729799) (xy 329.234301 -240.743959) (xy 329.18378 -240.750093)
			(xy 329.132928 -240.748044) (xy 329.083064 -240.737864) (xy 329.035478 -240.719817) (xy 328.991404 -240.694371)
			(xy 328.951982 -240.662184) (xy 328.918234 -240.62409) (xy 328.891033 -240.581076) (xy 328.871085 -240.534256)
			(xy 328.858906 -240.484842) (xy 328.854811 -240.434114) (xy 328.536554 -240.434114) (xy 328.536059 -240.458721)
			(xy 328.528164 -240.507298) (xy 328.51258 -240.553979) (xy 328.489709 -240.597556) (xy 328.460144 -240.6369)
			(xy 328.424651 -240.670992) (xy 328.384148 -240.698948) (xy 328.339686 -240.720046) (xy 328.292415 -240.733738)
			(xy 328.24356 -240.73967) (xy 328.194385 -240.737689) (xy 328.146166 -240.727845) (xy 328.10015 -240.710393)
			(xy 328.057529 -240.685786) (xy 328.019408 -240.654661) (xy 327.986773 -240.617824) (xy 327.96047 -240.576228)
			(xy 327.941179 -240.530952) (xy 327.929402 -240.483168) (xy 327.925442 -240.434114) (xy 326.656446 -240.434114)
			(xy 326.655951 -240.458721) (xy 326.648056 -240.507298) (xy 326.632472 -240.553979) (xy 326.609601 -240.597556)
			(xy 326.580036 -240.6369) (xy 326.544543 -240.670992) (xy 326.50404 -240.698948) (xy 326.459578 -240.720046)
			(xy 326.412307 -240.733738) (xy 326.363452 -240.73967) (xy 326.314277 -240.737689) (xy 326.266058 -240.727845)
			(xy 326.220042 -240.710393) (xy 326.177421 -240.685786) (xy 326.1393 -240.654661) (xy 326.106665 -240.617824)
			(xy 326.080362 -240.576228) (xy 326.061071 -240.530952) (xy 326.049294 -240.483168) (xy 326.045334 -240.434114)
			(xy 310.45912 -240.434114) (xy 310.45912 -241.510058) (xy 324.447166 -241.510058) (xy 324.451126 -241.461004)
			(xy 324.462903 -241.41322) (xy 324.482194 -241.367944) (xy 324.508497 -241.326348) (xy 324.541132 -241.289511)
			(xy 324.579253 -241.258386) (xy 324.621874 -241.233779) (xy 324.66789 -241.216327) (xy 324.716109 -241.206483)
			(xy 324.765284 -241.204502) (xy 324.814139 -241.210434) (xy 324.86141 -241.224126) (xy 324.903545 -241.24412)
			(xy 327.455288 -241.24412) (xy 327.459248 -241.195066) (xy 327.471025 -241.147282) (xy 327.490316 -241.102006)
			(xy 327.516619 -241.06041) (xy 327.549254 -241.023573) (xy 327.587375 -240.992448) (xy 327.629996 -240.967841)
			(xy 327.676012 -240.950389) (xy 327.724231 -240.940545) (xy 327.773406 -240.938564) (xy 327.822261 -240.944496)
			(xy 327.869532 -240.958188) (xy 327.913994 -240.979286) (xy 327.954497 -241.007242) (xy 327.98999 -241.041334)
			(xy 328.019555 -241.080678) (xy 328.042426 -241.124255) (xy 328.05801 -241.170936) (xy 328.065905 -241.219513)
			(xy 328.0664 -241.24412) (xy 328.384911 -241.24412) (xy 328.389006 -241.193392) (xy 328.401185 -241.143978)
			(xy 328.421133 -241.097158) (xy 328.448334 -241.054144) (xy 328.482082 -241.01605) (xy 328.521504 -240.983863)
			(xy 328.565578 -240.958417) (xy 328.613164 -240.94037) (xy 328.663028 -240.93019) (xy 328.71388 -240.928141)
			(xy 328.764401 -240.934275) (xy 328.813285 -240.948435) (xy 328.859264 -240.970252) (xy 328.901148 -240.999162)
			(xy 328.937852 -241.034417) (xy 328.968425 -241.075103) (xy 328.992076 -241.120166) (xy 329.008192 -241.16844)
			(xy 329.016356 -241.218674) (xy 329.016868 -241.24412) (xy 329.335396 -241.24412) (xy 329.339356 -241.195066)
			(xy 329.351133 -241.147282) (xy 329.370424 -241.102006) (xy 329.396727 -241.06041) (xy 329.429362 -241.023573)
			(xy 329.467483 -240.992448) (xy 329.510104 -240.967841) (xy 329.55612 -240.950389) (xy 329.604339 -240.940545)
			(xy 329.653514 -240.938564) (xy 329.702369 -240.944496) (xy 329.74964 -240.958188) (xy 329.794102 -240.979286)
			(xy 329.834605 -241.007242) (xy 329.870098 -241.041334) (xy 329.899663 -241.080678) (xy 329.922534 -241.124255)
			(xy 329.938118 -241.170936) (xy 329.946013 -241.219513) (xy 329.946508 -241.24412) (xy 330.264765 -241.24412)
			(xy 330.26886 -241.193392) (xy 330.281039 -241.143978) (xy 330.300987 -241.097158) (xy 330.328188 -241.054144)
			(xy 330.361936 -241.01605) (xy 330.401358 -240.983863) (xy 330.445432 -240.958417) (xy 330.493018 -240.94037)
			(xy 330.542882 -240.93019) (xy 330.593734 -240.928141) (xy 330.644255 -240.934275) (xy 330.693139 -240.948435)
			(xy 330.739118 -240.970252) (xy 330.781002 -240.999162) (xy 330.817706 -241.034417) (xy 330.848279 -241.075103)
			(xy 330.87193 -241.120166) (xy 330.888046 -241.16844) (xy 330.89621 -241.218674) (xy 330.896722 -241.24412)
			(xy 331.21525 -241.24412) (xy 331.21921 -241.195066) (xy 331.230987 -241.147282) (xy 331.250278 -241.102006)
			(xy 331.276581 -241.06041) (xy 331.309216 -241.023573) (xy 331.347337 -240.992448) (xy 331.389958 -240.967841)
			(xy 331.435974 -240.950389) (xy 331.484193 -240.940545) (xy 331.533368 -240.938564) (xy 331.582223 -240.944496)
			(xy 331.629494 -240.958188) (xy 331.673956 -240.979286) (xy 331.714459 -241.007242) (xy 331.749952 -241.041334)
			(xy 331.779517 -241.080678) (xy 331.802388 -241.124255) (xy 331.817972 -241.170936) (xy 331.825867 -241.219513)
			(xy 331.826362 -241.24412) (xy 332.144873 -241.24412) (xy 332.148968 -241.193392) (xy 332.161147 -241.143978)
			(xy 332.181095 -241.097158) (xy 332.208296 -241.054144) (xy 332.242044 -241.01605) (xy 332.281466 -240.983863)
			(xy 332.32554 -240.958417) (xy 332.373126 -240.94037) (xy 332.42299 -240.93019) (xy 332.473842 -240.928141)
			(xy 332.524363 -240.934275) (xy 332.573247 -240.948435) (xy 332.619226 -240.970252) (xy 332.66111 -240.999162)
			(xy 332.697814 -241.034417) (xy 332.728387 -241.075103) (xy 332.752038 -241.120166) (xy 332.768154 -241.16844)
			(xy 332.776318 -241.218674) (xy 332.77683 -241.24412) (xy 333.084927 -241.24412) (xy 333.089022 -241.193392)
			(xy 333.101201 -241.143978) (xy 333.121149 -241.097158) (xy 333.14835 -241.054144) (xy 333.182098 -241.01605)
			(xy 333.22152 -240.983863) (xy 333.265594 -240.958417) (xy 333.31318 -240.94037) (xy 333.363044 -240.93019)
			(xy 333.413896 -240.928141) (xy 333.464417 -240.934275) (xy 333.513301 -240.948435) (xy 333.55928 -240.970252)
			(xy 333.601164 -240.999162) (xy 333.637868 -241.034417) (xy 333.668441 -241.075103) (xy 333.692092 -241.120166)
			(xy 333.708208 -241.16844) (xy 333.716372 -241.218674) (xy 333.716884 -241.24412) (xy 334.035412 -241.24412)
			(xy 334.039372 -241.195066) (xy 334.051149 -241.147282) (xy 334.07044 -241.102006) (xy 334.096743 -241.06041)
			(xy 334.129378 -241.023573) (xy 334.167499 -240.992448) (xy 334.21012 -240.967841) (xy 334.256136 -240.950389)
			(xy 334.304355 -240.940545) (xy 334.35353 -240.938564) (xy 334.402385 -240.944496) (xy 334.449656 -240.958188)
			(xy 334.494118 -240.979286) (xy 334.534621 -241.007242) (xy 334.570114 -241.041334) (xy 334.599679 -241.080678)
			(xy 334.62255 -241.124255) (xy 334.638134 -241.170936) (xy 334.646029 -241.219513) (xy 334.646524 -241.24412)
			(xy 334.964781 -241.24412) (xy 334.968876 -241.193392) (xy 334.981055 -241.143978) (xy 335.001003 -241.097158)
			(xy 335.028204 -241.054144) (xy 335.061952 -241.01605) (xy 335.101374 -240.983863) (xy 335.145448 -240.958417)
			(xy 335.193034 -240.94037) (xy 335.242898 -240.93019) (xy 335.29375 -240.928141) (xy 335.344271 -240.934275)
			(xy 335.393155 -240.948435) (xy 335.439134 -240.970252) (xy 335.481018 -240.999162) (xy 335.517722 -241.034417)
			(xy 335.548295 -241.075103) (xy 335.571946 -241.120166) (xy 335.588062 -241.16844) (xy 335.596226 -241.218674)
			(xy 335.596738 -241.24412) (xy 335.915266 -241.24412) (xy 335.919226 -241.195066) (xy 335.931003 -241.147282)
			(xy 335.950294 -241.102006) (xy 335.976597 -241.06041) (xy 336.009232 -241.023573) (xy 336.047353 -240.992448)
			(xy 336.089974 -240.967841) (xy 336.13599 -240.950389) (xy 336.184209 -240.940545) (xy 336.233384 -240.938564)
			(xy 336.282239 -240.944496) (xy 336.32951 -240.958188) (xy 336.373972 -240.979286) (xy 336.414475 -241.007242)
			(xy 336.449968 -241.041334) (xy 336.479533 -241.080678) (xy 336.502404 -241.124255) (xy 336.517988 -241.170936)
			(xy 336.525883 -241.219513) (xy 336.526378 -241.24412) (xy 336.844889 -241.24412) (xy 336.848984 -241.193392)
			(xy 336.861163 -241.143978) (xy 336.881111 -241.097158) (xy 336.908312 -241.054144) (xy 336.94206 -241.01605)
			(xy 336.981482 -240.983863) (xy 337.025556 -240.958417) (xy 337.073142 -240.94037) (xy 337.123006 -240.93019)
			(xy 337.173858 -240.928141) (xy 337.224379 -240.934275) (xy 337.273263 -240.948435) (xy 337.319242 -240.970252)
			(xy 337.361126 -240.999162) (xy 337.39783 -241.034417) (xy 337.428403 -241.075103) (xy 337.452054 -241.120166)
			(xy 337.46817 -241.16844) (xy 337.476334 -241.218674) (xy 337.476846 -241.24412) (xy 337.795374 -241.24412)
			(xy 337.799334 -241.195066) (xy 337.811111 -241.147282) (xy 337.830402 -241.102006) (xy 337.856705 -241.06041)
			(xy 337.88934 -241.023573) (xy 337.927461 -240.992448) (xy 337.970082 -240.967841) (xy 338.016098 -240.950389)
			(xy 338.064317 -240.940545) (xy 338.113492 -240.938564) (xy 338.162347 -240.944496) (xy 338.209618 -240.958188)
			(xy 338.25408 -240.979286) (xy 338.294583 -241.007242) (xy 338.330076 -241.041334) (xy 338.359641 -241.080678)
			(xy 338.382512 -241.124255) (xy 338.398096 -241.170936) (xy 338.405991 -241.219513) (xy 338.406486 -241.24412)
			(xy 338.724743 -241.24412) (xy 338.728838 -241.193392) (xy 338.741017 -241.143978) (xy 338.760965 -241.097158)
			(xy 338.788166 -241.054144) (xy 338.821914 -241.01605) (xy 338.861336 -240.983863) (xy 338.90541 -240.958417)
			(xy 338.952996 -240.94037) (xy 339.00286 -240.93019) (xy 339.053712 -240.928141) (xy 339.104233 -240.934275)
			(xy 339.153117 -240.948435) (xy 339.199096 -240.970252) (xy 339.24098 -240.999162) (xy 339.277684 -241.034417)
			(xy 339.308257 -241.075103) (xy 339.331908 -241.120166) (xy 339.348024 -241.16844) (xy 339.356188 -241.218674)
			(xy 339.3567 -241.24412) (xy 339.664797 -241.24412) (xy 339.668892 -241.193392) (xy 339.681071 -241.143978)
			(xy 339.701019 -241.097158) (xy 339.72822 -241.054144) (xy 339.761968 -241.01605) (xy 339.80139 -240.983863)
			(xy 339.845464 -240.958417) (xy 339.89305 -240.94037) (xy 339.942914 -240.93019) (xy 339.993766 -240.928141)
			(xy 340.044287 -240.934275) (xy 340.093171 -240.948435) (xy 340.13915 -240.970252) (xy 340.181034 -240.999162)
			(xy 340.217738 -241.034417) (xy 340.248311 -241.075103) (xy 340.271962 -241.120166) (xy 340.288078 -241.16844)
			(xy 340.296242 -241.218674) (xy 340.296754 -241.24412) (xy 340.615282 -241.24412) (xy 340.619242 -241.195066)
			(xy 340.631019 -241.147282) (xy 340.65031 -241.102006) (xy 340.676613 -241.06041) (xy 340.709248 -241.023573)
			(xy 340.747369 -240.992448) (xy 340.78999 -240.967841) (xy 340.836006 -240.950389) (xy 340.884225 -240.940545)
			(xy 340.9334 -240.938564) (xy 340.982255 -240.944496) (xy 341.029526 -240.958188) (xy 341.073988 -240.979286)
			(xy 341.114491 -241.007242) (xy 341.149984 -241.041334) (xy 341.179549 -241.080678) (xy 341.20242 -241.124255)
			(xy 341.218004 -241.170936) (xy 341.225899 -241.219513) (xy 341.226394 -241.24412) (xy 341.544905 -241.24412)
			(xy 341.549 -241.193392) (xy 341.561179 -241.143978) (xy 341.581127 -241.097158) (xy 341.608328 -241.054144)
			(xy 341.642076 -241.01605) (xy 341.681498 -240.983863) (xy 341.725572 -240.958417) (xy 341.773158 -240.94037)
			(xy 341.823022 -240.93019) (xy 341.873874 -240.928141) (xy 341.924395 -240.934275) (xy 341.973279 -240.948435)
			(xy 342.019258 -240.970252) (xy 342.061142 -240.999162) (xy 342.097846 -241.034417) (xy 342.128419 -241.075103)
			(xy 342.15207 -241.120166) (xy 342.168186 -241.16844) (xy 342.17635 -241.218674) (xy 342.176862 -241.24412)
			(xy 342.49539 -241.24412) (xy 342.49935 -241.195066) (xy 342.511127 -241.147282) (xy 342.530418 -241.102006)
			(xy 342.556721 -241.06041) (xy 342.589356 -241.023573) (xy 342.627477 -240.992448) (xy 342.670098 -240.967841)
			(xy 342.716114 -240.950389) (xy 342.764333 -240.940545) (xy 342.813508 -240.938564) (xy 342.862363 -240.944496)
			(xy 342.909634 -240.958188) (xy 342.954096 -240.979286) (xy 342.994599 -241.007242) (xy 343.030092 -241.041334)
			(xy 343.059657 -241.080678) (xy 343.082528 -241.124255) (xy 343.098112 -241.170936) (xy 343.106007 -241.219513)
			(xy 343.106502 -241.24412) (xy 343.106007 -241.268727) (xy 343.098112 -241.317304) (xy 343.082528 -241.363985)
			(xy 343.059657 -241.407562) (xy 343.030092 -241.446906) (xy 342.994599 -241.480998) (xy 342.954096 -241.508954)
			(xy 342.909634 -241.530052) (xy 342.862363 -241.543744) (xy 342.813508 -241.549676) (xy 342.764333 -241.547695)
			(xy 342.716114 -241.537851) (xy 342.670098 -241.520399) (xy 342.627477 -241.495792) (xy 342.589356 -241.464667)
			(xy 342.556721 -241.42783) (xy 342.530418 -241.386234) (xy 342.511127 -241.340958) (xy 342.49935 -241.293174)
			(xy 342.49539 -241.24412) (xy 342.176862 -241.24412) (xy 342.17635 -241.269566) (xy 342.168186 -241.3198)
			(xy 342.15207 -241.368074) (xy 342.128419 -241.413137) (xy 342.097846 -241.453823) (xy 342.061142 -241.489078)
			(xy 342.019258 -241.517988) (xy 341.973279 -241.539805) (xy 341.924395 -241.553965) (xy 341.873874 -241.560099)
			(xy 341.823022 -241.55805) (xy 341.773158 -241.54787) (xy 341.725572 -241.529823) (xy 341.681498 -241.504377)
			(xy 341.642076 -241.47219) (xy 341.608328 -241.434096) (xy 341.581127 -241.391082) (xy 341.561179 -241.344262)
			(xy 341.549 -241.294848) (xy 341.544905 -241.24412) (xy 341.226394 -241.24412) (xy 341.225899 -241.268727)
			(xy 341.218004 -241.317304) (xy 341.20242 -241.363985) (xy 341.179549 -241.407562) (xy 341.149984 -241.446906)
			(xy 341.114491 -241.480998) (xy 341.073988 -241.508954) (xy 341.029526 -241.530052) (xy 340.982255 -241.543744)
			(xy 340.9334 -241.549676) (xy 340.884225 -241.547695) (xy 340.836006 -241.537851) (xy 340.78999 -241.520399)
			(xy 340.747369 -241.495792) (xy 340.709248 -241.464667) (xy 340.676613 -241.42783) (xy 340.65031 -241.386234)
			(xy 340.631019 -241.340958) (xy 340.619242 -241.293174) (xy 340.615282 -241.24412) (xy 340.296754 -241.24412)
			(xy 340.296242 -241.269566) (xy 340.288078 -241.3198) (xy 340.271962 -241.368074) (xy 340.248311 -241.413137)
			(xy 340.217738 -241.453823) (xy 340.181034 -241.489078) (xy 340.13915 -241.517988) (xy 340.093171 -241.539805)
			(xy 340.044287 -241.553965) (xy 339.993766 -241.560099) (xy 339.942914 -241.55805) (xy 339.89305 -241.54787)
			(xy 339.845464 -241.529823) (xy 339.80139 -241.504377) (xy 339.761968 -241.47219) (xy 339.72822 -241.434096)
			(xy 339.701019 -241.391082) (xy 339.681071 -241.344262) (xy 339.668892 -241.294848) (xy 339.664797 -241.24412)
			(xy 339.3567 -241.24412) (xy 339.356188 -241.269566) (xy 339.348024 -241.3198) (xy 339.331908 -241.368074)
			(xy 339.308257 -241.413137) (xy 339.277684 -241.453823) (xy 339.24098 -241.489078) (xy 339.199096 -241.517988)
			(xy 339.153117 -241.539805) (xy 339.104233 -241.553965) (xy 339.053712 -241.560099) (xy 339.00286 -241.55805)
			(xy 338.952996 -241.54787) (xy 338.90541 -241.529823) (xy 338.861336 -241.504377) (xy 338.821914 -241.47219)
			(xy 338.788166 -241.434096) (xy 338.760965 -241.391082) (xy 338.741017 -241.344262) (xy 338.728838 -241.294848)
			(xy 338.724743 -241.24412) (xy 338.406486 -241.24412) (xy 338.405991 -241.268727) (xy 338.398096 -241.317304)
			(xy 338.382512 -241.363985) (xy 338.359641 -241.407562) (xy 338.330076 -241.446906) (xy 338.294583 -241.480998)
			(xy 338.25408 -241.508954) (xy 338.209618 -241.530052) (xy 338.162347 -241.543744) (xy 338.113492 -241.549676)
			(xy 338.064317 -241.547695) (xy 338.016098 -241.537851) (xy 337.970082 -241.520399) (xy 337.927461 -241.495792)
			(xy 337.88934 -241.464667) (xy 337.856705 -241.42783) (xy 337.830402 -241.386234) (xy 337.811111 -241.340958)
			(xy 337.799334 -241.293174) (xy 337.795374 -241.24412) (xy 337.476846 -241.24412) (xy 337.476334 -241.269566)
			(xy 337.46817 -241.3198) (xy 337.452054 -241.368074) (xy 337.428403 -241.413137) (xy 337.39783 -241.453823)
			(xy 337.361126 -241.489078) (xy 337.319242 -241.517988) (xy 337.273263 -241.539805) (xy 337.224379 -241.553965)
			(xy 337.173858 -241.560099) (xy 337.123006 -241.55805) (xy 337.073142 -241.54787) (xy 337.025556 -241.529823)
			(xy 336.981482 -241.504377) (xy 336.94206 -241.47219) (xy 336.908312 -241.434096) (xy 336.881111 -241.391082)
			(xy 336.861163 -241.344262) (xy 336.848984 -241.294848) (xy 336.844889 -241.24412) (xy 336.526378 -241.24412)
			(xy 336.525883 -241.268727) (xy 336.517988 -241.317304) (xy 336.502404 -241.363985) (xy 336.479533 -241.407562)
			(xy 336.449968 -241.446906) (xy 336.414475 -241.480998) (xy 336.373972 -241.508954) (xy 336.32951 -241.530052)
			(xy 336.282239 -241.543744) (xy 336.233384 -241.549676) (xy 336.184209 -241.547695) (xy 336.13599 -241.537851)
			(xy 336.089974 -241.520399) (xy 336.047353 -241.495792) (xy 336.009232 -241.464667) (xy 335.976597 -241.42783)
			(xy 335.950294 -241.386234) (xy 335.931003 -241.340958) (xy 335.919226 -241.293174) (xy 335.915266 -241.24412)
			(xy 335.596738 -241.24412) (xy 335.596226 -241.269566) (xy 335.588062 -241.3198) (xy 335.571946 -241.368074)
			(xy 335.548295 -241.413137) (xy 335.517722 -241.453823) (xy 335.481018 -241.489078) (xy 335.439134 -241.517988)
			(xy 335.393155 -241.539805) (xy 335.344271 -241.553965) (xy 335.29375 -241.560099) (xy 335.242898 -241.55805)
			(xy 335.193034 -241.54787) (xy 335.145448 -241.529823) (xy 335.101374 -241.504377) (xy 335.061952 -241.47219)
			(xy 335.028204 -241.434096) (xy 335.001003 -241.391082) (xy 334.981055 -241.344262) (xy 334.968876 -241.294848)
			(xy 334.964781 -241.24412) (xy 334.646524 -241.24412) (xy 334.646029 -241.268727) (xy 334.638134 -241.317304)
			(xy 334.62255 -241.363985) (xy 334.599679 -241.407562) (xy 334.570114 -241.446906) (xy 334.534621 -241.480998)
			(xy 334.494118 -241.508954) (xy 334.449656 -241.530052) (xy 334.402385 -241.543744) (xy 334.35353 -241.549676)
			(xy 334.304355 -241.547695) (xy 334.256136 -241.537851) (xy 334.21012 -241.520399) (xy 334.167499 -241.495792)
			(xy 334.129378 -241.464667) (xy 334.096743 -241.42783) (xy 334.07044 -241.386234) (xy 334.051149 -241.340958)
			(xy 334.039372 -241.293174) (xy 334.035412 -241.24412) (xy 333.716884 -241.24412) (xy 333.716372 -241.269566)
			(xy 333.708208 -241.3198) (xy 333.692092 -241.368074) (xy 333.668441 -241.413137) (xy 333.637868 -241.453823)
			(xy 333.601164 -241.489078) (xy 333.55928 -241.517988) (xy 333.513301 -241.539805) (xy 333.464417 -241.553965)
			(xy 333.413896 -241.560099) (xy 333.363044 -241.55805) (xy 333.31318 -241.54787) (xy 333.265594 -241.529823)
			(xy 333.22152 -241.504377) (xy 333.182098 -241.47219) (xy 333.14835 -241.434096) (xy 333.121149 -241.391082)
			(xy 333.101201 -241.344262) (xy 333.089022 -241.294848) (xy 333.084927 -241.24412) (xy 332.77683 -241.24412)
			(xy 332.776318 -241.269566) (xy 332.768154 -241.3198) (xy 332.752038 -241.368074) (xy 332.728387 -241.413137)
			(xy 332.697814 -241.453823) (xy 332.66111 -241.489078) (xy 332.619226 -241.517988) (xy 332.573247 -241.539805)
			(xy 332.524363 -241.553965) (xy 332.473842 -241.560099) (xy 332.42299 -241.55805) (xy 332.373126 -241.54787)
			(xy 332.32554 -241.529823) (xy 332.281466 -241.504377) (xy 332.242044 -241.47219) (xy 332.208296 -241.434096)
			(xy 332.181095 -241.391082) (xy 332.161147 -241.344262) (xy 332.148968 -241.294848) (xy 332.144873 -241.24412)
			(xy 331.826362 -241.24412) (xy 331.825867 -241.268727) (xy 331.817972 -241.317304) (xy 331.802388 -241.363985)
			(xy 331.779517 -241.407562) (xy 331.749952 -241.446906) (xy 331.714459 -241.480998) (xy 331.673956 -241.508954)
			(xy 331.629494 -241.530052) (xy 331.582223 -241.543744) (xy 331.533368 -241.549676) (xy 331.484193 -241.547695)
			(xy 331.435974 -241.537851) (xy 331.389958 -241.520399) (xy 331.347337 -241.495792) (xy 331.309216 -241.464667)
			(xy 331.276581 -241.42783) (xy 331.250278 -241.386234) (xy 331.230987 -241.340958) (xy 331.21921 -241.293174)
			(xy 331.21525 -241.24412) (xy 330.896722 -241.24412) (xy 330.89621 -241.269566) (xy 330.888046 -241.3198)
			(xy 330.87193 -241.368074) (xy 330.848279 -241.413137) (xy 330.817706 -241.453823) (xy 330.781002 -241.489078)
			(xy 330.739118 -241.517988) (xy 330.693139 -241.539805) (xy 330.644255 -241.553965) (xy 330.593734 -241.560099)
			(xy 330.542882 -241.55805) (xy 330.493018 -241.54787) (xy 330.445432 -241.529823) (xy 330.401358 -241.504377)
			(xy 330.361936 -241.47219) (xy 330.328188 -241.434096) (xy 330.300987 -241.391082) (xy 330.281039 -241.344262)
			(xy 330.26886 -241.294848) (xy 330.264765 -241.24412) (xy 329.946508 -241.24412) (xy 329.946013 -241.268727)
			(xy 329.938118 -241.317304) (xy 329.922534 -241.363985) (xy 329.899663 -241.407562) (xy 329.870098 -241.446906)
			(xy 329.834605 -241.480998) (xy 329.794102 -241.508954) (xy 329.74964 -241.530052) (xy 329.702369 -241.543744)
			(xy 329.653514 -241.549676) (xy 329.604339 -241.547695) (xy 329.55612 -241.537851) (xy 329.510104 -241.520399)
			(xy 329.467483 -241.495792) (xy 329.429362 -241.464667) (xy 329.396727 -241.42783) (xy 329.370424 -241.386234)
			(xy 329.351133 -241.340958) (xy 329.339356 -241.293174) (xy 329.335396 -241.24412) (xy 329.016868 -241.24412)
			(xy 329.016356 -241.269566) (xy 329.008192 -241.3198) (xy 328.992076 -241.368074) (xy 328.968425 -241.413137)
			(xy 328.937852 -241.453823) (xy 328.901148 -241.489078) (xy 328.859264 -241.517988) (xy 328.813285 -241.539805)
			(xy 328.764401 -241.553965) (xy 328.71388 -241.560099) (xy 328.663028 -241.55805) (xy 328.613164 -241.54787)
			(xy 328.565578 -241.529823) (xy 328.521504 -241.504377) (xy 328.482082 -241.47219) (xy 328.448334 -241.434096)
			(xy 328.421133 -241.391082) (xy 328.401185 -241.344262) (xy 328.389006 -241.294848) (xy 328.384911 -241.24412)
			(xy 328.0664 -241.24412) (xy 328.065905 -241.268727) (xy 328.05801 -241.317304) (xy 328.042426 -241.363985)
			(xy 328.019555 -241.407562) (xy 327.98999 -241.446906) (xy 327.954497 -241.480998) (xy 327.913994 -241.508954)
			(xy 327.869532 -241.530052) (xy 327.822261 -241.543744) (xy 327.773406 -241.549676) (xy 327.724231 -241.547695)
			(xy 327.676012 -241.537851) (xy 327.629996 -241.520399) (xy 327.587375 -241.495792) (xy 327.549254 -241.464667)
			(xy 327.516619 -241.42783) (xy 327.490316 -241.386234) (xy 327.471025 -241.340958) (xy 327.459248 -241.293174)
			(xy 327.455288 -241.24412) (xy 324.903545 -241.24412) (xy 324.905872 -241.245224) (xy 324.946375 -241.27318)
			(xy 324.981868 -241.307272) (xy 325.011433 -241.346616) (xy 325.034304 -241.390193) (xy 325.049888 -241.436874)
			(xy 325.057783 -241.485451) (xy 325.058278 -241.510058) (xy 325.057783 -241.534665) (xy 325.049888 -241.583242)
			(xy 325.034304 -241.629923) (xy 325.011433 -241.6735) (xy 324.981868 -241.712844) (xy 324.946375 -241.746936)
			(xy 324.905872 -241.774892) (xy 324.86141 -241.79599) (xy 324.814139 -241.809682) (xy 324.765284 -241.815614)
			(xy 324.716109 -241.813633) (xy 324.66789 -241.803789) (xy 324.621874 -241.786337) (xy 324.579253 -241.76173)
			(xy 324.541132 -241.730605) (xy 324.508497 -241.693768) (xy 324.482194 -241.652172) (xy 324.462903 -241.606896)
			(xy 324.451126 -241.559112) (xy 324.447166 -241.510058) (xy 310.45912 -241.510058) (xy 310.45912 -242.054126)
			(xy 326.045334 -242.054126) (xy 326.049294 -242.005072) (xy 326.061071 -241.957288) (xy 326.080362 -241.912012)
			(xy 326.106665 -241.870416) (xy 326.1393 -241.833579) (xy 326.177421 -241.802454) (xy 326.220042 -241.777847)
			(xy 326.266058 -241.760395) (xy 326.314277 -241.750551) (xy 326.363452 -241.74857) (xy 326.412307 -241.754502)
			(xy 326.459578 -241.768194) (xy 326.50404 -241.789292) (xy 326.544543 -241.817248) (xy 326.580036 -241.85134)
			(xy 326.609601 -241.890684) (xy 326.632472 -241.934261) (xy 326.648056 -241.980942) (xy 326.655951 -242.029519)
			(xy 326.656446 -242.054126) (xy 328.854811 -242.054126) (xy 328.858906 -242.003398) (xy 328.871085 -241.953984)
			(xy 328.891033 -241.907164) (xy 328.918234 -241.86415) (xy 328.951982 -241.826056) (xy 328.991404 -241.793869)
			(xy 329.035478 -241.768423) (xy 329.083064 -241.750376) (xy 329.132928 -241.740196) (xy 329.18378 -241.738147)
			(xy 329.234301 -241.744281) (xy 329.283185 -241.758441) (xy 329.329164 -241.780258) (xy 329.371048 -241.809168)
			(xy 329.407752 -241.844423) (xy 329.438325 -241.885109) (xy 329.461976 -241.930172) (xy 329.478092 -241.978446)
			(xy 329.486256 -242.02868) (xy 329.486768 -242.054126) (xy 329.794865 -242.054126) (xy 329.79896 -242.003398)
			(xy 329.811139 -241.953984) (xy 329.831087 -241.907164) (xy 329.858288 -241.86415) (xy 329.892036 -241.826056)
			(xy 329.931458 -241.793869) (xy 329.975532 -241.768423) (xy 330.023118 -241.750376) (xy 330.072982 -241.740196)
			(xy 330.123834 -241.738147) (xy 330.174355 -241.744281) (xy 330.223239 -241.758441) (xy 330.269218 -241.780258)
			(xy 330.311102 -241.809168) (xy 330.347806 -241.844423) (xy 330.378379 -241.885109) (xy 330.40203 -241.930172)
			(xy 330.418146 -241.978446) (xy 330.42631 -242.02868) (xy 330.426822 -242.054126) (xy 330.74535 -242.054126)
			(xy 330.74931 -242.005072) (xy 330.761087 -241.957288) (xy 330.780378 -241.912012) (xy 330.806681 -241.870416)
			(xy 330.839316 -241.833579) (xy 330.877437 -241.802454) (xy 330.920058 -241.777847) (xy 330.966074 -241.760395)
			(xy 331.014293 -241.750551) (xy 331.063468 -241.74857) (xy 331.112323 -241.754502) (xy 331.159594 -241.768194)
			(xy 331.204056 -241.789292) (xy 331.244559 -241.817248) (xy 331.280052 -241.85134) (xy 331.309617 -241.890684)
			(xy 331.332488 -241.934261) (xy 331.348072 -241.980942) (xy 331.355967 -242.029519) (xy 331.356462 -242.054126)
			(xy 331.674973 -242.054126) (xy 331.679068 -242.003398) (xy 331.691247 -241.953984) (xy 331.711195 -241.907164)
			(xy 331.738396 -241.86415) (xy 331.772144 -241.826056) (xy 331.811566 -241.793869) (xy 331.85564 -241.768423)
			(xy 331.903226 -241.750376) (xy 331.95309 -241.740196) (xy 332.003942 -241.738147) (xy 332.054463 -241.744281)
			(xy 332.103347 -241.758441) (xy 332.149326 -241.780258) (xy 332.19121 -241.809168) (xy 332.227914 -241.844423)
			(xy 332.258487 -241.885109) (xy 332.282138 -241.930172) (xy 332.298254 -241.978446) (xy 332.306418 -242.02868)
			(xy 332.30693 -242.054126) (xy 332.625204 -242.054126) (xy 332.629164 -242.005072) (xy 332.640941 -241.957288)
			(xy 332.660232 -241.912012) (xy 332.686535 -241.870416) (xy 332.71917 -241.833579) (xy 332.757291 -241.802454)
			(xy 332.799912 -241.777847) (xy 332.845928 -241.760395) (xy 332.894147 -241.750551) (xy 332.943322 -241.74857)
			(xy 332.992177 -241.754502) (xy 333.039448 -241.768194) (xy 333.08391 -241.789292) (xy 333.124413 -241.817248)
			(xy 333.159906 -241.85134) (xy 333.189471 -241.890684) (xy 333.212342 -241.934261) (xy 333.227926 -241.980942)
			(xy 333.235821 -242.029519) (xy 333.236316 -242.054126) (xy 333.554827 -242.054126) (xy 333.558922 -242.003398)
			(xy 333.571101 -241.953984) (xy 333.591049 -241.907164) (xy 333.61825 -241.86415) (xy 333.651998 -241.826056)
			(xy 333.69142 -241.793869) (xy 333.735494 -241.768423) (xy 333.78308 -241.750376) (xy 333.832944 -241.740196)
			(xy 333.883796 -241.738147) (xy 333.934317 -241.744281) (xy 333.983201 -241.758441) (xy 334.02918 -241.780258)
			(xy 334.071064 -241.809168) (xy 334.107768 -241.844423) (xy 334.138341 -241.885109) (xy 334.161992 -241.930172)
			(xy 334.178108 -241.978446) (xy 334.186272 -242.02868) (xy 334.186784 -242.054126) (xy 335.434935 -242.054126)
			(xy 335.43903 -242.003398) (xy 335.451209 -241.953984) (xy 335.471157 -241.907164) (xy 335.498358 -241.86415)
			(xy 335.532106 -241.826056) (xy 335.571528 -241.793869) (xy 335.615602 -241.768423) (xy 335.663188 -241.750376)
			(xy 335.713052 -241.740196) (xy 335.763904 -241.738147) (xy 335.814425 -241.744281) (xy 335.863309 -241.758441)
			(xy 335.909288 -241.780258) (xy 335.951172 -241.809168) (xy 335.987876 -241.844423) (xy 336.018449 -241.885109)
			(xy 336.0421 -241.930172) (xy 336.058216 -241.978446) (xy 336.06638 -242.02868) (xy 336.066892 -242.054126)
			(xy 336.374989 -242.054126) (xy 336.379084 -242.003398) (xy 336.391263 -241.953984) (xy 336.411211 -241.907164)
			(xy 336.438412 -241.86415) (xy 336.47216 -241.826056) (xy 336.511582 -241.793869) (xy 336.555656 -241.768423)
			(xy 336.603242 -241.750376) (xy 336.653106 -241.740196) (xy 336.703958 -241.738147) (xy 336.754479 -241.744281)
			(xy 336.803363 -241.758441) (xy 336.849342 -241.780258) (xy 336.891226 -241.809168) (xy 336.92793 -241.844423)
			(xy 336.958503 -241.885109) (xy 336.982154 -241.930172) (xy 336.99827 -241.978446) (xy 337.006434 -242.02868)
			(xy 337.006946 -242.054126) (xy 337.32522 -242.054126) (xy 337.32918 -242.005072) (xy 337.340957 -241.957288)
			(xy 337.360248 -241.912012) (xy 337.386551 -241.870416) (xy 337.419186 -241.833579) (xy 337.457307 -241.802454)
			(xy 337.499928 -241.777847) (xy 337.545944 -241.760395) (xy 337.594163 -241.750551) (xy 337.643338 -241.74857)
			(xy 337.692193 -241.754502) (xy 337.739464 -241.768194) (xy 337.783926 -241.789292) (xy 337.824429 -241.817248)
			(xy 337.859922 -241.85134) (xy 337.889487 -241.890684) (xy 337.912358 -241.934261) (xy 337.927942 -241.980942)
			(xy 337.935837 -242.029519) (xy 337.936332 -242.054126) (xy 338.254843 -242.054126) (xy 338.258938 -242.003398)
			(xy 338.271117 -241.953984) (xy 338.291065 -241.907164) (xy 338.318266 -241.86415) (xy 338.352014 -241.826056)
			(xy 338.391436 -241.793869) (xy 338.43551 -241.768423) (xy 338.483096 -241.750376) (xy 338.53296 -241.740196)
			(xy 338.583812 -241.738147) (xy 338.634333 -241.744281) (xy 338.683217 -241.758441) (xy 338.729196 -241.780258)
			(xy 338.77108 -241.809168) (xy 338.807784 -241.844423) (xy 338.838357 -241.885109) (xy 338.862008 -241.930172)
			(xy 338.878124 -241.978446) (xy 338.886288 -242.02868) (xy 338.8868 -242.054126) (xy 339.205328 -242.054126)
			(xy 339.209288 -242.005072) (xy 339.221065 -241.957288) (xy 339.240356 -241.912012) (xy 339.266659 -241.870416)
			(xy 339.299294 -241.833579) (xy 339.337415 -241.802454) (xy 339.380036 -241.777847) (xy 339.426052 -241.760395)
			(xy 339.474271 -241.750551) (xy 339.523446 -241.74857) (xy 339.572301 -241.754502) (xy 339.619572 -241.768194)
			(xy 339.664034 -241.789292) (xy 339.704537 -241.817248) (xy 339.74003 -241.85134) (xy 339.769595 -241.890684)
			(xy 339.792466 -241.934261) (xy 339.80805 -241.980942) (xy 339.815945 -242.029519) (xy 339.81644 -242.054126)
			(xy 340.134951 -242.054126) (xy 340.139046 -242.003398) (xy 340.151225 -241.953984) (xy 340.171173 -241.907164)
			(xy 340.198374 -241.86415) (xy 340.232122 -241.826056) (xy 340.271544 -241.793869) (xy 340.315618 -241.768423)
			(xy 340.363204 -241.750376) (xy 340.413068 -241.740196) (xy 340.46392 -241.738147) (xy 340.514441 -241.744281)
			(xy 340.563325 -241.758441) (xy 340.609304 -241.780258) (xy 340.651188 -241.809168) (xy 340.687892 -241.844423)
			(xy 340.718465 -241.885109) (xy 340.742116 -241.930172) (xy 340.758232 -241.978446) (xy 340.766396 -242.02868)
			(xy 340.766908 -242.054126) (xy 342.014805 -242.054126) (xy 342.0189 -242.003398) (xy 342.031079 -241.953984)
			(xy 342.051027 -241.907164) (xy 342.078228 -241.86415) (xy 342.111976 -241.826056) (xy 342.151398 -241.793869)
			(xy 342.195472 -241.768423) (xy 342.243058 -241.750376) (xy 342.292922 -241.740196) (xy 342.343774 -241.738147)
			(xy 342.394295 -241.744281) (xy 342.443179 -241.758441) (xy 342.489158 -241.780258) (xy 342.531042 -241.809168)
			(xy 342.567746 -241.844423) (xy 342.598319 -241.885109) (xy 342.62197 -241.930172) (xy 342.638086 -241.978446)
			(xy 342.64625 -242.02868) (xy 342.646762 -242.054126) (xy 342.954859 -242.054126) (xy 342.958954 -242.003398)
			(xy 342.971133 -241.953984) (xy 342.991081 -241.907164) (xy 343.018282 -241.86415) (xy 343.05203 -241.826056)
			(xy 343.091452 -241.793869) (xy 343.135526 -241.768423) (xy 343.183112 -241.750376) (xy 343.232976 -241.740196)
			(xy 343.283828 -241.738147) (xy 343.334349 -241.744281) (xy 343.383233 -241.758441) (xy 343.429212 -241.780258)
			(xy 343.471096 -241.809168) (xy 343.5078 -241.844423) (xy 343.538373 -241.885109) (xy 343.562024 -241.930172)
			(xy 343.57814 -241.978446) (xy 343.586304 -242.02868) (xy 343.586816 -242.054126) (xy 343.586304 -242.079572)
			(xy 343.57814 -242.129806) (xy 343.562024 -242.17808) (xy 343.538373 -242.223143) (xy 343.5078 -242.263829)
			(xy 343.471096 -242.299084) (xy 343.429212 -242.327994) (xy 343.383233 -242.349811) (xy 343.334349 -242.363971)
			(xy 343.283828 -242.370105) (xy 343.232976 -242.368056) (xy 343.183112 -242.357876) (xy 343.135526 -242.339829)
			(xy 343.091452 -242.314383) (xy 343.05203 -242.282196) (xy 343.018282 -242.244102) (xy 342.991081 -242.201088)
			(xy 342.971133 -242.154268) (xy 342.958954 -242.104854) (xy 342.954859 -242.054126) (xy 342.646762 -242.054126)
			(xy 342.64625 -242.079572) (xy 342.638086 -242.129806) (xy 342.62197 -242.17808) (xy 342.598319 -242.223143)
			(xy 342.567746 -242.263829) (xy 342.531042 -242.299084) (xy 342.489158 -242.327994) (xy 342.443179 -242.349811)
			(xy 342.394295 -242.363971) (xy 342.343774 -242.370105) (xy 342.292922 -242.368056) (xy 342.243058 -242.357876)
			(xy 342.195472 -242.339829) (xy 342.151398 -242.314383) (xy 342.111976 -242.282196) (xy 342.078228 -242.244102)
			(xy 342.051027 -242.201088) (xy 342.031079 -242.154268) (xy 342.0189 -242.104854) (xy 342.014805 -242.054126)
			(xy 340.766908 -242.054126) (xy 340.766396 -242.079572) (xy 340.758232 -242.129806) (xy 340.742116 -242.17808)
			(xy 340.718465 -242.223143) (xy 340.687892 -242.263829) (xy 340.651188 -242.299084) (xy 340.609304 -242.327994)
			(xy 340.563325 -242.349811) (xy 340.514441 -242.363971) (xy 340.46392 -242.370105) (xy 340.413068 -242.368056)
			(xy 340.363204 -242.357876) (xy 340.315618 -242.339829) (xy 340.271544 -242.314383) (xy 340.232122 -242.282196)
			(xy 340.198374 -242.244102) (xy 340.171173 -242.201088) (xy 340.151225 -242.154268) (xy 340.139046 -242.104854)
			(xy 340.134951 -242.054126) (xy 339.81644 -242.054126) (xy 339.815945 -242.078733) (xy 339.80805 -242.12731)
			(xy 339.792466 -242.173991) (xy 339.769595 -242.217568) (xy 339.74003 -242.256912) (xy 339.704537 -242.291004)
			(xy 339.664034 -242.31896) (xy 339.619572 -242.340058) (xy 339.572301 -242.35375) (xy 339.523446 -242.359682)
			(xy 339.474271 -242.357701) (xy 339.426052 -242.347857) (xy 339.380036 -242.330405) (xy 339.337415 -242.305798)
			(xy 339.299294 -242.274673) (xy 339.266659 -242.237836) (xy 339.240356 -242.19624) (xy 339.221065 -242.150964)
			(xy 339.209288 -242.10318) (xy 339.205328 -242.054126) (xy 338.8868 -242.054126) (xy 338.886288 -242.079572)
			(xy 338.878124 -242.129806) (xy 338.862008 -242.17808) (xy 338.838357 -242.223143) (xy 338.807784 -242.263829)
			(xy 338.77108 -242.299084) (xy 338.729196 -242.327994) (xy 338.683217 -242.349811) (xy 338.634333 -242.363971)
			(xy 338.583812 -242.370105) (xy 338.53296 -242.368056) (xy 338.483096 -242.357876) (xy 338.43551 -242.339829)
			(xy 338.391436 -242.314383) (xy 338.352014 -242.282196) (xy 338.318266 -242.244102) (xy 338.291065 -242.201088)
			(xy 338.271117 -242.154268) (xy 338.258938 -242.104854) (xy 338.254843 -242.054126) (xy 337.936332 -242.054126)
			(xy 337.935837 -242.078733) (xy 337.927942 -242.12731) (xy 337.912358 -242.173991) (xy 337.889487 -242.217568)
			(xy 337.859922 -242.256912) (xy 337.824429 -242.291004) (xy 337.783926 -242.31896) (xy 337.739464 -242.340058)
			(xy 337.692193 -242.35375) (xy 337.643338 -242.359682) (xy 337.594163 -242.357701) (xy 337.545944 -242.347857)
			(xy 337.499928 -242.330405) (xy 337.457307 -242.305798) (xy 337.419186 -242.274673) (xy 337.386551 -242.237836)
			(xy 337.360248 -242.19624) (xy 337.340957 -242.150964) (xy 337.32918 -242.10318) (xy 337.32522 -242.054126)
			(xy 337.006946 -242.054126) (xy 337.006434 -242.079572) (xy 336.99827 -242.129806) (xy 336.982154 -242.17808)
			(xy 336.958503 -242.223143) (xy 336.92793 -242.263829) (xy 336.891226 -242.299084) (xy 336.849342 -242.327994)
			(xy 336.803363 -242.349811) (xy 336.754479 -242.363971) (xy 336.703958 -242.370105) (xy 336.653106 -242.368056)
			(xy 336.603242 -242.357876) (xy 336.555656 -242.339829) (xy 336.511582 -242.314383) (xy 336.47216 -242.282196)
			(xy 336.438412 -242.244102) (xy 336.411211 -242.201088) (xy 336.391263 -242.154268) (xy 336.379084 -242.104854)
			(xy 336.374989 -242.054126) (xy 336.066892 -242.054126) (xy 336.06638 -242.079572) (xy 336.058216 -242.129806)
			(xy 336.0421 -242.17808) (xy 336.018449 -242.223143) (xy 335.987876 -242.263829) (xy 335.951172 -242.299084)
			(xy 335.909288 -242.327994) (xy 335.863309 -242.349811) (xy 335.814425 -242.363971) (xy 335.763904 -242.370105)
			(xy 335.713052 -242.368056) (xy 335.663188 -242.357876) (xy 335.615602 -242.339829) (xy 335.571528 -242.314383)
			(xy 335.532106 -242.282196) (xy 335.498358 -242.244102) (xy 335.471157 -242.201088) (xy 335.451209 -242.154268)
			(xy 335.43903 -242.104854) (xy 335.434935 -242.054126) (xy 334.186784 -242.054126) (xy 334.186272 -242.079572)
			(xy 334.178108 -242.129806) (xy 334.161992 -242.17808) (xy 334.138341 -242.223143) (xy 334.107768 -242.263829)
			(xy 334.071064 -242.299084) (xy 334.02918 -242.327994) (xy 333.983201 -242.349811) (xy 333.934317 -242.363971)
			(xy 333.883796 -242.370105) (xy 333.832944 -242.368056) (xy 333.78308 -242.357876) (xy 333.735494 -242.339829)
			(xy 333.69142 -242.314383) (xy 333.651998 -242.282196) (xy 333.61825 -242.244102) (xy 333.591049 -242.201088)
			(xy 333.571101 -242.154268) (xy 333.558922 -242.104854) (xy 333.554827 -242.054126) (xy 333.236316 -242.054126)
			(xy 333.235821 -242.078733) (xy 333.227926 -242.12731) (xy 333.212342 -242.173991) (xy 333.189471 -242.217568)
			(xy 333.159906 -242.256912) (xy 333.124413 -242.291004) (xy 333.08391 -242.31896) (xy 333.039448 -242.340058)
			(xy 332.992177 -242.35375) (xy 332.943322 -242.359682) (xy 332.894147 -242.357701) (xy 332.845928 -242.347857)
			(xy 332.799912 -242.330405) (xy 332.757291 -242.305798) (xy 332.71917 -242.274673) (xy 332.686535 -242.237836)
			(xy 332.660232 -242.19624) (xy 332.640941 -242.150964) (xy 332.629164 -242.10318) (xy 332.625204 -242.054126)
			(xy 332.30693 -242.054126) (xy 332.306418 -242.079572) (xy 332.298254 -242.129806) (xy 332.282138 -242.17808)
			(xy 332.258487 -242.223143) (xy 332.227914 -242.263829) (xy 332.19121 -242.299084) (xy 332.149326 -242.327994)
			(xy 332.103347 -242.349811) (xy 332.054463 -242.363971) (xy 332.003942 -242.370105) (xy 331.95309 -242.368056)
			(xy 331.903226 -242.357876) (xy 331.85564 -242.339829) (xy 331.811566 -242.314383) (xy 331.772144 -242.282196)
			(xy 331.738396 -242.244102) (xy 331.711195 -242.201088) (xy 331.691247 -242.154268) (xy 331.679068 -242.104854)
			(xy 331.674973 -242.054126) (xy 331.356462 -242.054126) (xy 331.355967 -242.078733) (xy 331.348072 -242.12731)
			(xy 331.332488 -242.173991) (xy 331.309617 -242.217568) (xy 331.280052 -242.256912) (xy 331.244559 -242.291004)
			(xy 331.204056 -242.31896) (xy 331.159594 -242.340058) (xy 331.112323 -242.35375) (xy 331.063468 -242.359682)
			(xy 331.014293 -242.357701) (xy 330.966074 -242.347857) (xy 330.920058 -242.330405) (xy 330.877437 -242.305798)
			(xy 330.839316 -242.274673) (xy 330.806681 -242.237836) (xy 330.780378 -242.19624) (xy 330.761087 -242.150964)
			(xy 330.74931 -242.10318) (xy 330.74535 -242.054126) (xy 330.426822 -242.054126) (xy 330.42631 -242.079572)
			(xy 330.418146 -242.129806) (xy 330.40203 -242.17808) (xy 330.378379 -242.223143) (xy 330.347806 -242.263829)
			(xy 330.311102 -242.299084) (xy 330.269218 -242.327994) (xy 330.223239 -242.349811) (xy 330.174355 -242.363971)
			(xy 330.123834 -242.370105) (xy 330.072982 -242.368056) (xy 330.023118 -242.357876) (xy 329.975532 -242.339829)
			(xy 329.931458 -242.314383) (xy 329.892036 -242.282196) (xy 329.858288 -242.244102) (xy 329.831087 -242.201088)
			(xy 329.811139 -242.154268) (xy 329.79896 -242.104854) (xy 329.794865 -242.054126) (xy 329.486768 -242.054126)
			(xy 329.486256 -242.079572) (xy 329.478092 -242.129806) (xy 329.461976 -242.17808) (xy 329.438325 -242.223143)
			(xy 329.407752 -242.263829) (xy 329.371048 -242.299084) (xy 329.329164 -242.327994) (xy 329.283185 -242.349811)
			(xy 329.234301 -242.363971) (xy 329.18378 -242.370105) (xy 329.132928 -242.368056) (xy 329.083064 -242.357876)
			(xy 329.035478 -242.339829) (xy 328.991404 -242.314383) (xy 328.951982 -242.282196) (xy 328.918234 -242.244102)
			(xy 328.891033 -242.201088) (xy 328.871085 -242.154268) (xy 328.858906 -242.104854) (xy 328.854811 -242.054126)
			(xy 326.656446 -242.054126) (xy 326.655951 -242.078733) (xy 326.648056 -242.12731) (xy 326.632472 -242.173991)
			(xy 326.609601 -242.217568) (xy 326.580036 -242.256912) (xy 326.544543 -242.291004) (xy 326.50404 -242.31896)
			(xy 326.459578 -242.340058) (xy 326.412307 -242.35375) (xy 326.363452 -242.359682) (xy 326.314277 -242.357701)
			(xy 326.266058 -242.347857) (xy 326.220042 -242.330405) (xy 326.177421 -242.305798) (xy 326.1393 -242.274673)
			(xy 326.106665 -242.237836) (xy 326.080362 -242.19624) (xy 326.061071 -242.150964) (xy 326.049294 -242.10318)
			(xy 326.045334 -242.054126) (xy 310.45912 -242.054126) (xy 310.45912 -243.13007) (xy 324.447166 -243.13007)
			(xy 324.451126 -243.081016) (xy 324.462903 -243.033232) (xy 324.482194 -242.987956) (xy 324.508497 -242.94636)
			(xy 324.541132 -242.909523) (xy 324.579253 -242.878398) (xy 324.621874 -242.853791) (xy 324.66789 -242.836339)
			(xy 324.716109 -242.826495) (xy 324.765284 -242.824514) (xy 324.814139 -242.830446) (xy 324.86141 -242.844138)
			(xy 324.903545 -242.864132) (xy 327.455288 -242.864132) (xy 327.459248 -242.815078) (xy 327.471025 -242.767294)
			(xy 327.490316 -242.722018) (xy 327.516619 -242.680422) (xy 327.549254 -242.643585) (xy 327.587375 -242.61246)
			(xy 327.629996 -242.587853) (xy 327.676012 -242.570401) (xy 327.724231 -242.560557) (xy 327.773406 -242.558576)
			(xy 327.822261 -242.564508) (xy 327.869532 -242.5782) (xy 327.913994 -242.599298) (xy 327.954497 -242.627254)
			(xy 327.98999 -242.661346) (xy 328.019555 -242.70069) (xy 328.042426 -242.744267) (xy 328.05801 -242.790948)
			(xy 328.065905 -242.839525) (xy 328.0664 -242.864132) (xy 328.384911 -242.864132) (xy 328.389006 -242.813404)
			(xy 328.401185 -242.76399) (xy 328.421133 -242.71717) (xy 328.448334 -242.674156) (xy 328.482082 -242.636062)
			(xy 328.521504 -242.603875) (xy 328.565578 -242.578429) (xy 328.613164 -242.560382) (xy 328.663028 -242.550202)
			(xy 328.71388 -242.548153) (xy 328.764401 -242.554287) (xy 328.813285 -242.568447) (xy 328.859264 -242.590264)
			(xy 328.901148 -242.619174) (xy 328.937852 -242.654429) (xy 328.968425 -242.695115) (xy 328.992076 -242.740178)
			(xy 329.008192 -242.788452) (xy 329.016356 -242.838686) (xy 329.016868 -242.864132) (xy 329.335396 -242.864132)
			(xy 329.339356 -242.815078) (xy 329.351133 -242.767294) (xy 329.370424 -242.722018) (xy 329.396727 -242.680422)
			(xy 329.429362 -242.643585) (xy 329.467483 -242.61246) (xy 329.510104 -242.587853) (xy 329.55612 -242.570401)
			(xy 329.604339 -242.560557) (xy 329.653514 -242.558576) (xy 329.702369 -242.564508) (xy 329.74964 -242.5782)
			(xy 329.794102 -242.599298) (xy 329.834605 -242.627254) (xy 329.870098 -242.661346) (xy 329.899663 -242.70069)
			(xy 329.922534 -242.744267) (xy 329.938118 -242.790948) (xy 329.946013 -242.839525) (xy 329.946508 -242.864132)
			(xy 330.264765 -242.864132) (xy 330.26886 -242.813404) (xy 330.281039 -242.76399) (xy 330.300987 -242.71717)
			(xy 330.328188 -242.674156) (xy 330.361936 -242.636062) (xy 330.401358 -242.603875) (xy 330.445432 -242.578429)
			(xy 330.493018 -242.560382) (xy 330.542882 -242.550202) (xy 330.593734 -242.548153) (xy 330.644255 -242.554287)
			(xy 330.693139 -242.568447) (xy 330.739118 -242.590264) (xy 330.781002 -242.619174) (xy 330.817706 -242.654429)
			(xy 330.848279 -242.695115) (xy 330.87193 -242.740178) (xy 330.888046 -242.788452) (xy 330.89621 -242.838686)
			(xy 330.896722 -242.864132) (xy 331.21525 -242.864132) (xy 331.21921 -242.815078) (xy 331.230987 -242.767294)
			(xy 331.250278 -242.722018) (xy 331.276581 -242.680422) (xy 331.309216 -242.643585) (xy 331.347337 -242.61246)
			(xy 331.389958 -242.587853) (xy 331.435974 -242.570401) (xy 331.484193 -242.560557) (xy 331.533368 -242.558576)
			(xy 331.582223 -242.564508) (xy 331.629494 -242.5782) (xy 331.673956 -242.599298) (xy 331.714459 -242.627254)
			(xy 331.749952 -242.661346) (xy 331.779517 -242.70069) (xy 331.802388 -242.744267) (xy 331.817972 -242.790948)
			(xy 331.825867 -242.839525) (xy 331.826362 -242.864132) (xy 332.144873 -242.864132) (xy 332.148968 -242.813404)
			(xy 332.161147 -242.76399) (xy 332.181095 -242.71717) (xy 332.208296 -242.674156) (xy 332.242044 -242.636062)
			(xy 332.281466 -242.603875) (xy 332.32554 -242.578429) (xy 332.373126 -242.560382) (xy 332.42299 -242.550202)
			(xy 332.473842 -242.548153) (xy 332.524363 -242.554287) (xy 332.573247 -242.568447) (xy 332.619226 -242.590264)
			(xy 332.66111 -242.619174) (xy 332.697814 -242.654429) (xy 332.728387 -242.695115) (xy 332.752038 -242.740178)
			(xy 332.768154 -242.788452) (xy 332.776318 -242.838686) (xy 332.77683 -242.864132) (xy 333.084927 -242.864132)
			(xy 333.089022 -242.813404) (xy 333.101201 -242.76399) (xy 333.121149 -242.71717) (xy 333.14835 -242.674156)
			(xy 333.182098 -242.636062) (xy 333.22152 -242.603875) (xy 333.265594 -242.578429) (xy 333.31318 -242.560382)
			(xy 333.363044 -242.550202) (xy 333.413896 -242.548153) (xy 333.464417 -242.554287) (xy 333.513301 -242.568447)
			(xy 333.55928 -242.590264) (xy 333.601164 -242.619174) (xy 333.637868 -242.654429) (xy 333.668441 -242.695115)
			(xy 333.692092 -242.740178) (xy 333.708208 -242.788452) (xy 333.716372 -242.838686) (xy 333.716884 -242.864132)
			(xy 334.035412 -242.864132) (xy 334.039372 -242.815078) (xy 334.051149 -242.767294) (xy 334.07044 -242.722018)
			(xy 334.096743 -242.680422) (xy 334.129378 -242.643585) (xy 334.167499 -242.61246) (xy 334.21012 -242.587853)
			(xy 334.256136 -242.570401) (xy 334.304355 -242.560557) (xy 334.35353 -242.558576) (xy 334.402385 -242.564508)
			(xy 334.449656 -242.5782) (xy 334.494118 -242.599298) (xy 334.534621 -242.627254) (xy 334.570114 -242.661346)
			(xy 334.599679 -242.70069) (xy 334.62255 -242.744267) (xy 334.638134 -242.790948) (xy 334.646029 -242.839525)
			(xy 334.646524 -242.864132) (xy 334.964781 -242.864132) (xy 334.968876 -242.813404) (xy 334.981055 -242.76399)
			(xy 335.001003 -242.71717) (xy 335.028204 -242.674156) (xy 335.061952 -242.636062) (xy 335.101374 -242.603875)
			(xy 335.145448 -242.578429) (xy 335.193034 -242.560382) (xy 335.242898 -242.550202) (xy 335.29375 -242.548153)
			(xy 335.344271 -242.554287) (xy 335.393155 -242.568447) (xy 335.439134 -242.590264) (xy 335.481018 -242.619174)
			(xy 335.517722 -242.654429) (xy 335.548295 -242.695115) (xy 335.571946 -242.740178) (xy 335.588062 -242.788452)
			(xy 335.596226 -242.838686) (xy 335.596738 -242.864132) (xy 335.915266 -242.864132) (xy 335.919226 -242.815078)
			(xy 335.931003 -242.767294) (xy 335.950294 -242.722018) (xy 335.976597 -242.680422) (xy 336.009232 -242.643585)
			(xy 336.047353 -242.61246) (xy 336.089974 -242.587853) (xy 336.13599 -242.570401) (xy 336.184209 -242.560557)
			(xy 336.233384 -242.558576) (xy 336.282239 -242.564508) (xy 336.32951 -242.5782) (xy 336.373972 -242.599298)
			(xy 336.414475 -242.627254) (xy 336.449968 -242.661346) (xy 336.479533 -242.70069) (xy 336.502404 -242.744267)
			(xy 336.517988 -242.790948) (xy 336.525883 -242.839525) (xy 336.526378 -242.864132) (xy 336.844889 -242.864132)
			(xy 336.848984 -242.813404) (xy 336.861163 -242.76399) (xy 336.881111 -242.71717) (xy 336.908312 -242.674156)
			(xy 336.94206 -242.636062) (xy 336.981482 -242.603875) (xy 337.025556 -242.578429) (xy 337.073142 -242.560382)
			(xy 337.123006 -242.550202) (xy 337.173858 -242.548153) (xy 337.224379 -242.554287) (xy 337.273263 -242.568447)
			(xy 337.319242 -242.590264) (xy 337.361126 -242.619174) (xy 337.39783 -242.654429) (xy 337.428403 -242.695115)
			(xy 337.452054 -242.740178) (xy 337.46817 -242.788452) (xy 337.476334 -242.838686) (xy 337.476846 -242.864132)
			(xy 337.795374 -242.864132) (xy 337.799334 -242.815078) (xy 337.811111 -242.767294) (xy 337.830402 -242.722018)
			(xy 337.856705 -242.680422) (xy 337.88934 -242.643585) (xy 337.927461 -242.61246) (xy 337.970082 -242.587853)
			(xy 338.016098 -242.570401) (xy 338.064317 -242.560557) (xy 338.113492 -242.558576) (xy 338.162347 -242.564508)
			(xy 338.209618 -242.5782) (xy 338.25408 -242.599298) (xy 338.294583 -242.627254) (xy 338.330076 -242.661346)
			(xy 338.359641 -242.70069) (xy 338.382512 -242.744267) (xy 338.398096 -242.790948) (xy 338.405991 -242.839525)
			(xy 338.406486 -242.864132) (xy 338.724743 -242.864132) (xy 338.728838 -242.813404) (xy 338.741017 -242.76399)
			(xy 338.760965 -242.71717) (xy 338.788166 -242.674156) (xy 338.821914 -242.636062) (xy 338.861336 -242.603875)
			(xy 338.90541 -242.578429) (xy 338.952996 -242.560382) (xy 339.00286 -242.550202) (xy 339.053712 -242.548153)
			(xy 339.104233 -242.554287) (xy 339.153117 -242.568447) (xy 339.199096 -242.590264) (xy 339.24098 -242.619174)
			(xy 339.277684 -242.654429) (xy 339.308257 -242.695115) (xy 339.331908 -242.740178) (xy 339.348024 -242.788452)
			(xy 339.356188 -242.838686) (xy 339.3567 -242.864132) (xy 339.664797 -242.864132) (xy 339.668892 -242.813404)
			(xy 339.681071 -242.76399) (xy 339.701019 -242.71717) (xy 339.72822 -242.674156) (xy 339.761968 -242.636062)
			(xy 339.80139 -242.603875) (xy 339.845464 -242.578429) (xy 339.89305 -242.560382) (xy 339.942914 -242.550202)
			(xy 339.993766 -242.548153) (xy 340.044287 -242.554287) (xy 340.093171 -242.568447) (xy 340.13915 -242.590264)
			(xy 340.181034 -242.619174) (xy 340.217738 -242.654429) (xy 340.248311 -242.695115) (xy 340.271962 -242.740178)
			(xy 340.288078 -242.788452) (xy 340.296242 -242.838686) (xy 340.296754 -242.864132) (xy 340.615282 -242.864132)
			(xy 340.619242 -242.815078) (xy 340.631019 -242.767294) (xy 340.65031 -242.722018) (xy 340.676613 -242.680422)
			(xy 340.709248 -242.643585) (xy 340.747369 -242.61246) (xy 340.78999 -242.587853) (xy 340.836006 -242.570401)
			(xy 340.884225 -242.560557) (xy 340.9334 -242.558576) (xy 340.982255 -242.564508) (xy 341.029526 -242.5782)
			(xy 341.073988 -242.599298) (xy 341.114491 -242.627254) (xy 341.149984 -242.661346) (xy 341.179549 -242.70069)
			(xy 341.20242 -242.744267) (xy 341.218004 -242.790948) (xy 341.225899 -242.839525) (xy 341.226394 -242.864132)
			(xy 341.544905 -242.864132) (xy 341.549 -242.813404) (xy 341.561179 -242.76399) (xy 341.581127 -242.71717)
			(xy 341.608328 -242.674156) (xy 341.642076 -242.636062) (xy 341.681498 -242.603875) (xy 341.725572 -242.578429)
			(xy 341.773158 -242.560382) (xy 341.823022 -242.550202) (xy 341.873874 -242.548153) (xy 341.924395 -242.554287)
			(xy 341.973279 -242.568447) (xy 342.019258 -242.590264) (xy 342.061142 -242.619174) (xy 342.097846 -242.654429)
			(xy 342.128419 -242.695115) (xy 342.15207 -242.740178) (xy 342.168186 -242.788452) (xy 342.17635 -242.838686)
			(xy 342.176862 -242.864132) (xy 342.49539 -242.864132) (xy 342.49935 -242.815078) (xy 342.511127 -242.767294)
			(xy 342.530418 -242.722018) (xy 342.556721 -242.680422) (xy 342.589356 -242.643585) (xy 342.627477 -242.61246)
			(xy 342.670098 -242.587853) (xy 342.716114 -242.570401) (xy 342.764333 -242.560557) (xy 342.813508 -242.558576)
			(xy 342.862363 -242.564508) (xy 342.909634 -242.5782) (xy 342.954096 -242.599298) (xy 342.994599 -242.627254)
			(xy 343.030092 -242.661346) (xy 343.059657 -242.70069) (xy 343.082528 -242.744267) (xy 343.098112 -242.790948)
			(xy 343.106007 -242.839525) (xy 343.106502 -242.864132) (xy 343.106007 -242.888739) (xy 343.098112 -242.937316)
			(xy 343.082528 -242.983997) (xy 343.059657 -243.027574) (xy 343.030092 -243.066918) (xy 342.994599 -243.10101)
			(xy 342.954096 -243.128966) (xy 342.909634 -243.150064) (xy 342.862363 -243.163756) (xy 342.813508 -243.169688)
			(xy 342.764333 -243.167707) (xy 342.716114 -243.157863) (xy 342.670098 -243.140411) (xy 342.627477 -243.115804)
			(xy 342.589356 -243.084679) (xy 342.556721 -243.047842) (xy 342.530418 -243.006246) (xy 342.511127 -242.96097)
			(xy 342.49935 -242.913186) (xy 342.49539 -242.864132) (xy 342.176862 -242.864132) (xy 342.17635 -242.889578)
			(xy 342.168186 -242.939812) (xy 342.15207 -242.988086) (xy 342.128419 -243.033149) (xy 342.097846 -243.073835)
			(xy 342.061142 -243.10909) (xy 342.019258 -243.138) (xy 341.973279 -243.159817) (xy 341.924395 -243.173977)
			(xy 341.873874 -243.180111) (xy 341.823022 -243.178062) (xy 341.773158 -243.167882) (xy 341.725572 -243.149835)
			(xy 341.681498 -243.124389) (xy 341.642076 -243.092202) (xy 341.608328 -243.054108) (xy 341.581127 -243.011094)
			(xy 341.561179 -242.964274) (xy 341.549 -242.91486) (xy 341.544905 -242.864132) (xy 341.226394 -242.864132)
			(xy 341.225899 -242.888739) (xy 341.218004 -242.937316) (xy 341.20242 -242.983997) (xy 341.179549 -243.027574)
			(xy 341.149984 -243.066918) (xy 341.114491 -243.10101) (xy 341.073988 -243.128966) (xy 341.029526 -243.150064)
			(xy 340.982255 -243.163756) (xy 340.9334 -243.169688) (xy 340.884225 -243.167707) (xy 340.836006 -243.157863)
			(xy 340.78999 -243.140411) (xy 340.747369 -243.115804) (xy 340.709248 -243.084679) (xy 340.676613 -243.047842)
			(xy 340.65031 -243.006246) (xy 340.631019 -242.96097) (xy 340.619242 -242.913186) (xy 340.615282 -242.864132)
			(xy 340.296754 -242.864132) (xy 340.296242 -242.889578) (xy 340.288078 -242.939812) (xy 340.271962 -242.988086)
			(xy 340.248311 -243.033149) (xy 340.217738 -243.073835) (xy 340.181034 -243.10909) (xy 340.13915 -243.138)
			(xy 340.093171 -243.159817) (xy 340.044287 -243.173977) (xy 339.993766 -243.180111) (xy 339.942914 -243.178062)
			(xy 339.89305 -243.167882) (xy 339.845464 -243.149835) (xy 339.80139 -243.124389) (xy 339.761968 -243.092202)
			(xy 339.72822 -243.054108) (xy 339.701019 -243.011094) (xy 339.681071 -242.964274) (xy 339.668892 -242.91486)
			(xy 339.664797 -242.864132) (xy 339.3567 -242.864132) (xy 339.356188 -242.889578) (xy 339.348024 -242.939812)
			(xy 339.331908 -242.988086) (xy 339.308257 -243.033149) (xy 339.277684 -243.073835) (xy 339.24098 -243.10909)
			(xy 339.199096 -243.138) (xy 339.153117 -243.159817) (xy 339.104233 -243.173977) (xy 339.053712 -243.180111)
			(xy 339.00286 -243.178062) (xy 338.952996 -243.167882) (xy 338.90541 -243.149835) (xy 338.861336 -243.124389)
			(xy 338.821914 -243.092202) (xy 338.788166 -243.054108) (xy 338.760965 -243.011094) (xy 338.741017 -242.964274)
			(xy 338.728838 -242.91486) (xy 338.724743 -242.864132) (xy 338.406486 -242.864132) (xy 338.405991 -242.888739)
			(xy 338.398096 -242.937316) (xy 338.382512 -242.983997) (xy 338.359641 -243.027574) (xy 338.330076 -243.066918)
			(xy 338.294583 -243.10101) (xy 338.25408 -243.128966) (xy 338.209618 -243.150064) (xy 338.162347 -243.163756)
			(xy 338.113492 -243.169688) (xy 338.064317 -243.167707) (xy 338.016098 -243.157863) (xy 337.970082 -243.140411)
			(xy 337.927461 -243.115804) (xy 337.88934 -243.084679) (xy 337.856705 -243.047842) (xy 337.830402 -243.006246)
			(xy 337.811111 -242.96097) (xy 337.799334 -242.913186) (xy 337.795374 -242.864132) (xy 337.476846 -242.864132)
			(xy 337.476334 -242.889578) (xy 337.46817 -242.939812) (xy 337.452054 -242.988086) (xy 337.428403 -243.033149)
			(xy 337.39783 -243.073835) (xy 337.361126 -243.10909) (xy 337.319242 -243.138) (xy 337.273263 -243.159817)
			(xy 337.224379 -243.173977) (xy 337.173858 -243.180111) (xy 337.123006 -243.178062) (xy 337.073142 -243.167882)
			(xy 337.025556 -243.149835) (xy 336.981482 -243.124389) (xy 336.94206 -243.092202) (xy 336.908312 -243.054108)
			(xy 336.881111 -243.011094) (xy 336.861163 -242.964274) (xy 336.848984 -242.91486) (xy 336.844889 -242.864132)
			(xy 336.526378 -242.864132) (xy 336.525883 -242.888739) (xy 336.517988 -242.937316) (xy 336.502404 -242.983997)
			(xy 336.479533 -243.027574) (xy 336.449968 -243.066918) (xy 336.414475 -243.10101) (xy 336.373972 -243.128966)
			(xy 336.32951 -243.150064) (xy 336.282239 -243.163756) (xy 336.233384 -243.169688) (xy 336.184209 -243.167707)
			(xy 336.13599 -243.157863) (xy 336.089974 -243.140411) (xy 336.047353 -243.115804) (xy 336.009232 -243.084679)
			(xy 335.976597 -243.047842) (xy 335.950294 -243.006246) (xy 335.931003 -242.96097) (xy 335.919226 -242.913186)
			(xy 335.915266 -242.864132) (xy 335.596738 -242.864132) (xy 335.596226 -242.889578) (xy 335.588062 -242.939812)
			(xy 335.571946 -242.988086) (xy 335.548295 -243.033149) (xy 335.517722 -243.073835) (xy 335.481018 -243.10909)
			(xy 335.439134 -243.138) (xy 335.393155 -243.159817) (xy 335.344271 -243.173977) (xy 335.29375 -243.180111)
			(xy 335.242898 -243.178062) (xy 335.193034 -243.167882) (xy 335.145448 -243.149835) (xy 335.101374 -243.124389)
			(xy 335.061952 -243.092202) (xy 335.028204 -243.054108) (xy 335.001003 -243.011094) (xy 334.981055 -242.964274)
			(xy 334.968876 -242.91486) (xy 334.964781 -242.864132) (xy 334.646524 -242.864132) (xy 334.646029 -242.888739)
			(xy 334.638134 -242.937316) (xy 334.62255 -242.983997) (xy 334.599679 -243.027574) (xy 334.570114 -243.066918)
			(xy 334.534621 -243.10101) (xy 334.494118 -243.128966) (xy 334.449656 -243.150064) (xy 334.402385 -243.163756)
			(xy 334.35353 -243.169688) (xy 334.304355 -243.167707) (xy 334.256136 -243.157863) (xy 334.21012 -243.140411)
			(xy 334.167499 -243.115804) (xy 334.129378 -243.084679) (xy 334.096743 -243.047842) (xy 334.07044 -243.006246)
			(xy 334.051149 -242.96097) (xy 334.039372 -242.913186) (xy 334.035412 -242.864132) (xy 333.716884 -242.864132)
			(xy 333.716372 -242.889578) (xy 333.708208 -242.939812) (xy 333.692092 -242.988086) (xy 333.668441 -243.033149)
			(xy 333.637868 -243.073835) (xy 333.601164 -243.10909) (xy 333.55928 -243.138) (xy 333.513301 -243.159817)
			(xy 333.464417 -243.173977) (xy 333.413896 -243.180111) (xy 333.363044 -243.178062) (xy 333.31318 -243.167882)
			(xy 333.265594 -243.149835) (xy 333.22152 -243.124389) (xy 333.182098 -243.092202) (xy 333.14835 -243.054108)
			(xy 333.121149 -243.011094) (xy 333.101201 -242.964274) (xy 333.089022 -242.91486) (xy 333.084927 -242.864132)
			(xy 332.77683 -242.864132) (xy 332.776318 -242.889578) (xy 332.768154 -242.939812) (xy 332.752038 -242.988086)
			(xy 332.728387 -243.033149) (xy 332.697814 -243.073835) (xy 332.66111 -243.10909) (xy 332.619226 -243.138)
			(xy 332.573247 -243.159817) (xy 332.524363 -243.173977) (xy 332.473842 -243.180111) (xy 332.42299 -243.178062)
			(xy 332.373126 -243.167882) (xy 332.32554 -243.149835) (xy 332.281466 -243.124389) (xy 332.242044 -243.092202)
			(xy 332.208296 -243.054108) (xy 332.181095 -243.011094) (xy 332.161147 -242.964274) (xy 332.148968 -242.91486)
			(xy 332.144873 -242.864132) (xy 331.826362 -242.864132) (xy 331.825867 -242.888739) (xy 331.817972 -242.937316)
			(xy 331.802388 -242.983997) (xy 331.779517 -243.027574) (xy 331.749952 -243.066918) (xy 331.714459 -243.10101)
			(xy 331.673956 -243.128966) (xy 331.629494 -243.150064) (xy 331.582223 -243.163756) (xy 331.533368 -243.169688)
			(xy 331.484193 -243.167707) (xy 331.435974 -243.157863) (xy 331.389958 -243.140411) (xy 331.347337 -243.115804)
			(xy 331.309216 -243.084679) (xy 331.276581 -243.047842) (xy 331.250278 -243.006246) (xy 331.230987 -242.96097)
			(xy 331.21921 -242.913186) (xy 331.21525 -242.864132) (xy 330.896722 -242.864132) (xy 330.89621 -242.889578)
			(xy 330.888046 -242.939812) (xy 330.87193 -242.988086) (xy 330.848279 -243.033149) (xy 330.817706 -243.073835)
			(xy 330.781002 -243.10909) (xy 330.739118 -243.138) (xy 330.693139 -243.159817) (xy 330.644255 -243.173977)
			(xy 330.593734 -243.180111) (xy 330.542882 -243.178062) (xy 330.493018 -243.167882) (xy 330.445432 -243.149835)
			(xy 330.401358 -243.124389) (xy 330.361936 -243.092202) (xy 330.328188 -243.054108) (xy 330.300987 -243.011094)
			(xy 330.281039 -242.964274) (xy 330.26886 -242.91486) (xy 330.264765 -242.864132) (xy 329.946508 -242.864132)
			(xy 329.946013 -242.888739) (xy 329.938118 -242.937316) (xy 329.922534 -242.983997) (xy 329.899663 -243.027574)
			(xy 329.870098 -243.066918) (xy 329.834605 -243.10101) (xy 329.794102 -243.128966) (xy 329.74964 -243.150064)
			(xy 329.702369 -243.163756) (xy 329.653514 -243.169688) (xy 329.604339 -243.167707) (xy 329.55612 -243.157863)
			(xy 329.510104 -243.140411) (xy 329.467483 -243.115804) (xy 329.429362 -243.084679) (xy 329.396727 -243.047842)
			(xy 329.370424 -243.006246) (xy 329.351133 -242.96097) (xy 329.339356 -242.913186) (xy 329.335396 -242.864132)
			(xy 329.016868 -242.864132) (xy 329.016356 -242.889578) (xy 329.008192 -242.939812) (xy 328.992076 -242.988086)
			(xy 328.968425 -243.033149) (xy 328.937852 -243.073835) (xy 328.901148 -243.10909) (xy 328.859264 -243.138)
			(xy 328.813285 -243.159817) (xy 328.764401 -243.173977) (xy 328.71388 -243.180111) (xy 328.663028 -243.178062)
			(xy 328.613164 -243.167882) (xy 328.565578 -243.149835) (xy 328.521504 -243.124389) (xy 328.482082 -243.092202)
			(xy 328.448334 -243.054108) (xy 328.421133 -243.011094) (xy 328.401185 -242.964274) (xy 328.389006 -242.91486)
			(xy 328.384911 -242.864132) (xy 328.0664 -242.864132) (xy 328.065905 -242.888739) (xy 328.05801 -242.937316)
			(xy 328.042426 -242.983997) (xy 328.019555 -243.027574) (xy 327.98999 -243.066918) (xy 327.954497 -243.10101)
			(xy 327.913994 -243.128966) (xy 327.869532 -243.150064) (xy 327.822261 -243.163756) (xy 327.773406 -243.169688)
			(xy 327.724231 -243.167707) (xy 327.676012 -243.157863) (xy 327.629996 -243.140411) (xy 327.587375 -243.115804)
			(xy 327.549254 -243.084679) (xy 327.516619 -243.047842) (xy 327.490316 -243.006246) (xy 327.471025 -242.96097)
			(xy 327.459248 -242.913186) (xy 327.455288 -242.864132) (xy 324.903545 -242.864132) (xy 324.905872 -242.865236)
			(xy 324.946375 -242.893192) (xy 324.981868 -242.927284) (xy 325.011433 -242.966628) (xy 325.034304 -243.010205)
			(xy 325.049888 -243.056886) (xy 325.057783 -243.105463) (xy 325.058278 -243.13007) (xy 325.057783 -243.154677)
			(xy 325.049888 -243.203254) (xy 325.034304 -243.249935) (xy 325.011433 -243.293512) (xy 324.981868 -243.332856)
			(xy 324.946375 -243.366948) (xy 324.905872 -243.394904) (xy 324.86141 -243.416002) (xy 324.814139 -243.429694)
			(xy 324.765284 -243.435626) (xy 324.716109 -243.433645) (xy 324.66789 -243.423801) (xy 324.621874 -243.406349)
			(xy 324.579253 -243.381742) (xy 324.541132 -243.350617) (xy 324.508497 -243.31378) (xy 324.482194 -243.272184)
			(xy 324.462903 -243.226908) (xy 324.451126 -243.179124) (xy 324.447166 -243.13007) (xy 310.45912 -243.13007)
			(xy 310.45912 -243.674138) (xy 326.045334 -243.674138) (xy 326.049294 -243.625084) (xy 326.061071 -243.5773)
			(xy 326.080362 -243.532024) (xy 326.106665 -243.490428) (xy 326.1393 -243.453591) (xy 326.177421 -243.422466)
			(xy 326.220042 -243.397859) (xy 326.266058 -243.380407) (xy 326.314277 -243.370563) (xy 326.363452 -243.368582)
			(xy 326.412307 -243.374514) (xy 326.459578 -243.388206) (xy 326.50404 -243.409304) (xy 326.544543 -243.43726)
			(xy 326.580036 -243.471352) (xy 326.609601 -243.510696) (xy 326.632472 -243.554273) (xy 326.648056 -243.600954)
			(xy 326.655951 -243.649531) (xy 326.656446 -243.674138) (xy 327.925442 -243.674138) (xy 327.929402 -243.625084)
			(xy 327.941179 -243.5773) (xy 327.96047 -243.532024) (xy 327.986773 -243.490428) (xy 328.019408 -243.453591)
			(xy 328.057529 -243.422466) (xy 328.10015 -243.397859) (xy 328.146166 -243.380407) (xy 328.194385 -243.370563)
			(xy 328.24356 -243.368582) (xy 328.292415 -243.374514) (xy 328.339686 -243.388206) (xy 328.384148 -243.409304)
			(xy 328.424651 -243.43726) (xy 328.460144 -243.471352) (xy 328.489709 -243.510696) (xy 328.51258 -243.554273)
			(xy 328.528164 -243.600954) (xy 328.536059 -243.649531) (xy 328.536554 -243.674138) (xy 328.854811 -243.674138)
			(xy 328.858906 -243.62341) (xy 328.871085 -243.573996) (xy 328.891033 -243.527176) (xy 328.918234 -243.484162)
			(xy 328.951982 -243.446068) (xy 328.991404 -243.413881) (xy 329.035478 -243.388435) (xy 329.083064 -243.370388)
			(xy 329.132928 -243.360208) (xy 329.18378 -243.358159) (xy 329.234301 -243.364293) (xy 329.283185 -243.378453)
			(xy 329.329164 -243.40027) (xy 329.371048 -243.42918) (xy 329.407752 -243.464435) (xy 329.438325 -243.505121)
			(xy 329.461976 -243.550184) (xy 329.478092 -243.598458) (xy 329.486256 -243.648692) (xy 329.486768 -243.674138)
			(xy 329.794865 -243.674138) (xy 329.79896 -243.62341) (xy 329.811139 -243.573996) (xy 329.831087 -243.527176)
			(xy 329.858288 -243.484162) (xy 329.892036 -243.446068) (xy 329.931458 -243.413881) (xy 329.975532 -243.388435)
			(xy 330.023118 -243.370388) (xy 330.072982 -243.360208) (xy 330.123834 -243.358159) (xy 330.174355 -243.364293)
			(xy 330.223239 -243.378453) (xy 330.269218 -243.40027) (xy 330.311102 -243.42918) (xy 330.347806 -243.464435)
			(xy 330.378379 -243.505121) (xy 330.40203 -243.550184) (xy 330.418146 -243.598458) (xy 330.42631 -243.648692)
			(xy 330.426822 -243.674138) (xy 330.74535 -243.674138) (xy 330.74931 -243.625084) (xy 330.761087 -243.5773)
			(xy 330.780378 -243.532024) (xy 330.806681 -243.490428) (xy 330.839316 -243.453591) (xy 330.877437 -243.422466)
			(xy 330.920058 -243.397859) (xy 330.966074 -243.380407) (xy 331.014293 -243.370563) (xy 331.063468 -243.368582)
			(xy 331.112323 -243.374514) (xy 331.159594 -243.388206) (xy 331.204056 -243.409304) (xy 331.244559 -243.43726)
			(xy 331.280052 -243.471352) (xy 331.309617 -243.510696) (xy 331.332488 -243.554273) (xy 331.348072 -243.600954)
			(xy 331.355967 -243.649531) (xy 331.356462 -243.674138) (xy 331.674973 -243.674138) (xy 331.679068 -243.62341)
			(xy 331.691247 -243.573996) (xy 331.711195 -243.527176) (xy 331.738396 -243.484162) (xy 331.772144 -243.446068)
			(xy 331.811566 -243.413881) (xy 331.85564 -243.388435) (xy 331.903226 -243.370388) (xy 331.95309 -243.360208)
			(xy 332.003942 -243.358159) (xy 332.054463 -243.364293) (xy 332.103347 -243.378453) (xy 332.149326 -243.40027)
			(xy 332.19121 -243.42918) (xy 332.227914 -243.464435) (xy 332.258487 -243.505121) (xy 332.282138 -243.550184)
			(xy 332.298254 -243.598458) (xy 332.306418 -243.648692) (xy 332.30693 -243.674138) (xy 332.625204 -243.674138)
			(xy 332.629164 -243.625084) (xy 332.640941 -243.5773) (xy 332.660232 -243.532024) (xy 332.686535 -243.490428)
			(xy 332.71917 -243.453591) (xy 332.757291 -243.422466) (xy 332.799912 -243.397859) (xy 332.845928 -243.380407)
			(xy 332.894147 -243.370563) (xy 332.943322 -243.368582) (xy 332.992177 -243.374514) (xy 333.039448 -243.388206)
			(xy 333.08391 -243.409304) (xy 333.124413 -243.43726) (xy 333.159906 -243.471352) (xy 333.189471 -243.510696)
			(xy 333.212342 -243.554273) (xy 333.227926 -243.600954) (xy 333.235821 -243.649531) (xy 333.236316 -243.674138)
			(xy 333.554827 -243.674138) (xy 333.558922 -243.62341) (xy 333.571101 -243.573996) (xy 333.591049 -243.527176)
			(xy 333.61825 -243.484162) (xy 333.651998 -243.446068) (xy 333.69142 -243.413881) (xy 333.735494 -243.388435)
			(xy 333.78308 -243.370388) (xy 333.832944 -243.360208) (xy 333.883796 -243.358159) (xy 333.934317 -243.364293)
			(xy 333.983201 -243.378453) (xy 334.02918 -243.40027) (xy 334.071064 -243.42918) (xy 334.107768 -243.464435)
			(xy 334.138341 -243.505121) (xy 334.161992 -243.550184) (xy 334.178108 -243.598458) (xy 334.186272 -243.648692)
			(xy 334.186784 -243.674138) (xy 334.505312 -243.674138) (xy 334.509272 -243.625084) (xy 334.521049 -243.5773)
			(xy 334.54034 -243.532024) (xy 334.566643 -243.490428) (xy 334.599278 -243.453591) (xy 334.637399 -243.422466)
			(xy 334.68002 -243.397859) (xy 334.726036 -243.380407) (xy 334.774255 -243.370563) (xy 334.82343 -243.368582)
			(xy 334.872285 -243.374514) (xy 334.919556 -243.388206) (xy 334.964018 -243.409304) (xy 335.004521 -243.43726)
			(xy 335.040014 -243.471352) (xy 335.069579 -243.510696) (xy 335.09245 -243.554273) (xy 335.108034 -243.600954)
			(xy 335.115929 -243.649531) (xy 335.116424 -243.674138) (xy 335.434935 -243.674138) (xy 335.43903 -243.62341)
			(xy 335.451209 -243.573996) (xy 335.471157 -243.527176) (xy 335.498358 -243.484162) (xy 335.532106 -243.446068)
			(xy 335.571528 -243.413881) (xy 335.615602 -243.388435) (xy 335.663188 -243.370388) (xy 335.713052 -243.360208)
			(xy 335.763904 -243.358159) (xy 335.814425 -243.364293) (xy 335.863309 -243.378453) (xy 335.909288 -243.40027)
			(xy 335.951172 -243.42918) (xy 335.987876 -243.464435) (xy 336.018449 -243.505121) (xy 336.0421 -243.550184)
			(xy 336.058216 -243.598458) (xy 336.06638 -243.648692) (xy 336.066892 -243.674138) (xy 336.374989 -243.674138)
			(xy 336.379084 -243.62341) (xy 336.391263 -243.573996) (xy 336.411211 -243.527176) (xy 336.438412 -243.484162)
			(xy 336.47216 -243.446068) (xy 336.511582 -243.413881) (xy 336.555656 -243.388435) (xy 336.603242 -243.370388)
			(xy 336.653106 -243.360208) (xy 336.703958 -243.358159) (xy 336.754479 -243.364293) (xy 336.803363 -243.378453)
			(xy 336.849342 -243.40027) (xy 336.891226 -243.42918) (xy 336.92793 -243.464435) (xy 336.958503 -243.505121)
			(xy 336.982154 -243.550184) (xy 336.99827 -243.598458) (xy 337.006434 -243.648692) (xy 337.006946 -243.674138)
			(xy 337.32522 -243.674138) (xy 337.32918 -243.625084) (xy 337.340957 -243.5773) (xy 337.360248 -243.532024)
			(xy 337.386551 -243.490428) (xy 337.419186 -243.453591) (xy 337.457307 -243.422466) (xy 337.499928 -243.397859)
			(xy 337.545944 -243.380407) (xy 337.594163 -243.370563) (xy 337.643338 -243.368582) (xy 337.692193 -243.374514)
			(xy 337.739464 -243.388206) (xy 337.783926 -243.409304) (xy 337.824429 -243.43726) (xy 337.859922 -243.471352)
			(xy 337.889487 -243.510696) (xy 337.912358 -243.554273) (xy 337.927942 -243.600954) (xy 337.935837 -243.649531)
			(xy 337.936332 -243.674138) (xy 338.254843 -243.674138) (xy 338.258938 -243.62341) (xy 338.271117 -243.573996)
			(xy 338.291065 -243.527176) (xy 338.318266 -243.484162) (xy 338.352014 -243.446068) (xy 338.391436 -243.413881)
			(xy 338.43551 -243.388435) (xy 338.483096 -243.370388) (xy 338.53296 -243.360208) (xy 338.583812 -243.358159)
			(xy 338.634333 -243.364293) (xy 338.683217 -243.378453) (xy 338.729196 -243.40027) (xy 338.77108 -243.42918)
			(xy 338.807784 -243.464435) (xy 338.838357 -243.505121) (xy 338.862008 -243.550184) (xy 338.878124 -243.598458)
			(xy 338.886288 -243.648692) (xy 338.8868 -243.674138) (xy 339.205328 -243.674138) (xy 339.209288 -243.625084)
			(xy 339.221065 -243.5773) (xy 339.240356 -243.532024) (xy 339.266659 -243.490428) (xy 339.299294 -243.453591)
			(xy 339.337415 -243.422466) (xy 339.380036 -243.397859) (xy 339.426052 -243.380407) (xy 339.474271 -243.370563)
			(xy 339.523446 -243.368582) (xy 339.572301 -243.374514) (xy 339.619572 -243.388206) (xy 339.664034 -243.409304)
			(xy 339.704537 -243.43726) (xy 339.74003 -243.471352) (xy 339.769595 -243.510696) (xy 339.792466 -243.554273)
			(xy 339.80805 -243.600954) (xy 339.815945 -243.649531) (xy 339.81644 -243.674138) (xy 340.134951 -243.674138)
			(xy 340.139046 -243.62341) (xy 340.151225 -243.573996) (xy 340.171173 -243.527176) (xy 340.198374 -243.484162)
			(xy 340.232122 -243.446068) (xy 340.271544 -243.413881) (xy 340.315618 -243.388435) (xy 340.363204 -243.370388)
			(xy 340.413068 -243.360208) (xy 340.46392 -243.358159) (xy 340.514441 -243.364293) (xy 340.563325 -243.378453)
			(xy 340.609304 -243.40027) (xy 340.651188 -243.42918) (xy 340.687892 -243.464435) (xy 340.718465 -243.505121)
			(xy 340.742116 -243.550184) (xy 340.758232 -243.598458) (xy 340.766396 -243.648692) (xy 340.766908 -243.674138)
			(xy 341.085182 -243.674138) (xy 341.089142 -243.625084) (xy 341.100919 -243.5773) (xy 341.12021 -243.532024)
			(xy 341.146513 -243.490428) (xy 341.179148 -243.453591) (xy 341.217269 -243.422466) (xy 341.25989 -243.397859)
			(xy 341.305906 -243.380407) (xy 341.354125 -243.370563) (xy 341.4033 -243.368582) (xy 341.452155 -243.374514)
			(xy 341.499426 -243.388206) (xy 341.543888 -243.409304) (xy 341.584391 -243.43726) (xy 341.619884 -243.471352)
			(xy 341.649449 -243.510696) (xy 341.67232 -243.554273) (xy 341.687904 -243.600954) (xy 341.695799 -243.649531)
			(xy 341.696294 -243.674138) (xy 342.014805 -243.674138) (xy 342.0189 -243.62341) (xy 342.031079 -243.573996)
			(xy 342.051027 -243.527176) (xy 342.078228 -243.484162) (xy 342.111976 -243.446068) (xy 342.151398 -243.413881)
			(xy 342.195472 -243.388435) (xy 342.243058 -243.370388) (xy 342.292922 -243.360208) (xy 342.343774 -243.358159)
			(xy 342.394295 -243.364293) (xy 342.443179 -243.378453) (xy 342.489158 -243.40027) (xy 342.531042 -243.42918)
			(xy 342.567746 -243.464435) (xy 342.598319 -243.505121) (xy 342.62197 -243.550184) (xy 342.638086 -243.598458)
			(xy 342.64625 -243.648692) (xy 342.646762 -243.674138) (xy 342.954859 -243.674138) (xy 342.958954 -243.62341)
			(xy 342.971133 -243.573996) (xy 342.991081 -243.527176) (xy 343.018282 -243.484162) (xy 343.05203 -243.446068)
			(xy 343.091452 -243.413881) (xy 343.135526 -243.388435) (xy 343.183112 -243.370388) (xy 343.232976 -243.360208)
			(xy 343.283828 -243.358159) (xy 343.334349 -243.364293) (xy 343.383233 -243.378453) (xy 343.429212 -243.40027)
			(xy 343.471096 -243.42918) (xy 343.5078 -243.464435) (xy 343.538373 -243.505121) (xy 343.562024 -243.550184)
			(xy 343.57814 -243.598458) (xy 343.586304 -243.648692) (xy 343.586816 -243.674138) (xy 343.586304 -243.699584)
			(xy 343.57814 -243.749818) (xy 343.562024 -243.798092) (xy 343.538373 -243.843155) (xy 343.5078 -243.883841)
			(xy 343.471096 -243.919096) (xy 343.429212 -243.948006) (xy 343.383233 -243.969823) (xy 343.334349 -243.983983)
			(xy 343.283828 -243.990117) (xy 343.232976 -243.988068) (xy 343.183112 -243.977888) (xy 343.135526 -243.959841)
			(xy 343.091452 -243.934395) (xy 343.05203 -243.902208) (xy 343.018282 -243.864114) (xy 342.991081 -243.8211)
			(xy 342.971133 -243.77428) (xy 342.958954 -243.724866) (xy 342.954859 -243.674138) (xy 342.646762 -243.674138)
			(xy 342.64625 -243.699584) (xy 342.638086 -243.749818) (xy 342.62197 -243.798092) (xy 342.598319 -243.843155)
			(xy 342.567746 -243.883841) (xy 342.531042 -243.919096) (xy 342.489158 -243.948006) (xy 342.443179 -243.969823)
			(xy 342.394295 -243.983983) (xy 342.343774 -243.990117) (xy 342.292922 -243.988068) (xy 342.243058 -243.977888)
			(xy 342.195472 -243.959841) (xy 342.151398 -243.934395) (xy 342.111976 -243.902208) (xy 342.078228 -243.864114)
			(xy 342.051027 -243.8211) (xy 342.031079 -243.77428) (xy 342.0189 -243.724866) (xy 342.014805 -243.674138)
			(xy 341.696294 -243.674138) (xy 341.695799 -243.698745) (xy 341.687904 -243.747322) (xy 341.67232 -243.794003)
			(xy 341.649449 -243.83758) (xy 341.619884 -243.876924) (xy 341.584391 -243.911016) (xy 341.543888 -243.938972)
			(xy 341.499426 -243.96007) (xy 341.452155 -243.973762) (xy 341.4033 -243.979694) (xy 341.354125 -243.977713)
			(xy 341.305906 -243.967869) (xy 341.25989 -243.950417) (xy 341.217269 -243.92581) (xy 341.179148 -243.894685)
			(xy 341.146513 -243.857848) (xy 341.12021 -243.816252) (xy 341.100919 -243.770976) (xy 341.089142 -243.723192)
			(xy 341.085182 -243.674138) (xy 340.766908 -243.674138) (xy 340.766396 -243.699584) (xy 340.758232 -243.749818)
			(xy 340.742116 -243.798092) (xy 340.718465 -243.843155) (xy 340.687892 -243.883841) (xy 340.651188 -243.919096)
			(xy 340.609304 -243.948006) (xy 340.563325 -243.969823) (xy 340.514441 -243.983983) (xy 340.46392 -243.990117)
			(xy 340.413068 -243.988068) (xy 340.363204 -243.977888) (xy 340.315618 -243.959841) (xy 340.271544 -243.934395)
			(xy 340.232122 -243.902208) (xy 340.198374 -243.864114) (xy 340.171173 -243.8211) (xy 340.151225 -243.77428)
			(xy 340.139046 -243.724866) (xy 340.134951 -243.674138) (xy 339.81644 -243.674138) (xy 339.815945 -243.698745)
			(xy 339.80805 -243.747322) (xy 339.792466 -243.794003) (xy 339.769595 -243.83758) (xy 339.74003 -243.876924)
			(xy 339.704537 -243.911016) (xy 339.664034 -243.938972) (xy 339.619572 -243.96007) (xy 339.572301 -243.973762)
			(xy 339.523446 -243.979694) (xy 339.474271 -243.977713) (xy 339.426052 -243.967869) (xy 339.380036 -243.950417)
			(xy 339.337415 -243.92581) (xy 339.299294 -243.894685) (xy 339.266659 -243.857848) (xy 339.240356 -243.816252)
			(xy 339.221065 -243.770976) (xy 339.209288 -243.723192) (xy 339.205328 -243.674138) (xy 338.8868 -243.674138)
			(xy 338.886288 -243.699584) (xy 338.878124 -243.749818) (xy 338.862008 -243.798092) (xy 338.838357 -243.843155)
			(xy 338.807784 -243.883841) (xy 338.77108 -243.919096) (xy 338.729196 -243.948006) (xy 338.683217 -243.969823)
			(xy 338.634333 -243.983983) (xy 338.583812 -243.990117) (xy 338.53296 -243.988068) (xy 338.483096 -243.977888)
			(xy 338.43551 -243.959841) (xy 338.391436 -243.934395) (xy 338.352014 -243.902208) (xy 338.318266 -243.864114)
			(xy 338.291065 -243.8211) (xy 338.271117 -243.77428) (xy 338.258938 -243.724866) (xy 338.254843 -243.674138)
			(xy 337.936332 -243.674138) (xy 337.935837 -243.698745) (xy 337.927942 -243.747322) (xy 337.912358 -243.794003)
			(xy 337.889487 -243.83758) (xy 337.859922 -243.876924) (xy 337.824429 -243.911016) (xy 337.783926 -243.938972)
			(xy 337.739464 -243.96007) (xy 337.692193 -243.973762) (xy 337.643338 -243.979694) (xy 337.594163 -243.977713)
			(xy 337.545944 -243.967869) (xy 337.499928 -243.950417) (xy 337.457307 -243.92581) (xy 337.419186 -243.894685)
			(xy 337.386551 -243.857848) (xy 337.360248 -243.816252) (xy 337.340957 -243.770976) (xy 337.32918 -243.723192)
			(xy 337.32522 -243.674138) (xy 337.006946 -243.674138) (xy 337.006434 -243.699584) (xy 336.99827 -243.749818)
			(xy 336.982154 -243.798092) (xy 336.958503 -243.843155) (xy 336.92793 -243.883841) (xy 336.891226 -243.919096)
			(xy 336.849342 -243.948006) (xy 336.803363 -243.969823) (xy 336.754479 -243.983983) (xy 336.703958 -243.990117)
			(xy 336.653106 -243.988068) (xy 336.603242 -243.977888) (xy 336.555656 -243.959841) (xy 336.511582 -243.934395)
			(xy 336.47216 -243.902208) (xy 336.438412 -243.864114) (xy 336.411211 -243.8211) (xy 336.391263 -243.77428)
			(xy 336.379084 -243.724866) (xy 336.374989 -243.674138) (xy 336.066892 -243.674138) (xy 336.06638 -243.699584)
			(xy 336.058216 -243.749818) (xy 336.0421 -243.798092) (xy 336.018449 -243.843155) (xy 335.987876 -243.883841)
			(xy 335.951172 -243.919096) (xy 335.909288 -243.948006) (xy 335.863309 -243.969823) (xy 335.814425 -243.983983)
			(xy 335.763904 -243.990117) (xy 335.713052 -243.988068) (xy 335.663188 -243.977888) (xy 335.615602 -243.959841)
			(xy 335.571528 -243.934395) (xy 335.532106 -243.902208) (xy 335.498358 -243.864114) (xy 335.471157 -243.8211)
			(xy 335.451209 -243.77428) (xy 335.43903 -243.724866) (xy 335.434935 -243.674138) (xy 335.116424 -243.674138)
			(xy 335.115929 -243.698745) (xy 335.108034 -243.747322) (xy 335.09245 -243.794003) (xy 335.069579 -243.83758)
			(xy 335.040014 -243.876924) (xy 335.004521 -243.911016) (xy 334.964018 -243.938972) (xy 334.919556 -243.96007)
			(xy 334.872285 -243.973762) (xy 334.82343 -243.979694) (xy 334.774255 -243.977713) (xy 334.726036 -243.967869)
			(xy 334.68002 -243.950417) (xy 334.637399 -243.92581) (xy 334.599278 -243.894685) (xy 334.566643 -243.857848)
			(xy 334.54034 -243.816252) (xy 334.521049 -243.770976) (xy 334.509272 -243.723192) (xy 334.505312 -243.674138)
			(xy 334.186784 -243.674138) (xy 334.186272 -243.699584) (xy 334.178108 -243.749818) (xy 334.161992 -243.798092)
			(xy 334.138341 -243.843155) (xy 334.107768 -243.883841) (xy 334.071064 -243.919096) (xy 334.02918 -243.948006)
			(xy 333.983201 -243.969823) (xy 333.934317 -243.983983) (xy 333.883796 -243.990117) (xy 333.832944 -243.988068)
			(xy 333.78308 -243.977888) (xy 333.735494 -243.959841) (xy 333.69142 -243.934395) (xy 333.651998 -243.902208)
			(xy 333.61825 -243.864114) (xy 333.591049 -243.8211) (xy 333.571101 -243.77428) (xy 333.558922 -243.724866)
			(xy 333.554827 -243.674138) (xy 333.236316 -243.674138) (xy 333.235821 -243.698745) (xy 333.227926 -243.747322)
			(xy 333.212342 -243.794003) (xy 333.189471 -243.83758) (xy 333.159906 -243.876924) (xy 333.124413 -243.911016)
			(xy 333.08391 -243.938972) (xy 333.039448 -243.96007) (xy 332.992177 -243.973762) (xy 332.943322 -243.979694)
			(xy 332.894147 -243.977713) (xy 332.845928 -243.967869) (xy 332.799912 -243.950417) (xy 332.757291 -243.92581)
			(xy 332.71917 -243.894685) (xy 332.686535 -243.857848) (xy 332.660232 -243.816252) (xy 332.640941 -243.770976)
			(xy 332.629164 -243.723192) (xy 332.625204 -243.674138) (xy 332.30693 -243.674138) (xy 332.306418 -243.699584)
			(xy 332.298254 -243.749818) (xy 332.282138 -243.798092) (xy 332.258487 -243.843155) (xy 332.227914 -243.883841)
			(xy 332.19121 -243.919096) (xy 332.149326 -243.948006) (xy 332.103347 -243.969823) (xy 332.054463 -243.983983)
			(xy 332.003942 -243.990117) (xy 331.95309 -243.988068) (xy 331.903226 -243.977888) (xy 331.85564 -243.959841)
			(xy 331.811566 -243.934395) (xy 331.772144 -243.902208) (xy 331.738396 -243.864114) (xy 331.711195 -243.8211)
			(xy 331.691247 -243.77428) (xy 331.679068 -243.724866) (xy 331.674973 -243.674138) (xy 331.356462 -243.674138)
			(xy 331.355967 -243.698745) (xy 331.348072 -243.747322) (xy 331.332488 -243.794003) (xy 331.309617 -243.83758)
			(xy 331.280052 -243.876924) (xy 331.244559 -243.911016) (xy 331.204056 -243.938972) (xy 331.159594 -243.96007)
			(xy 331.112323 -243.973762) (xy 331.063468 -243.979694) (xy 331.014293 -243.977713) (xy 330.966074 -243.967869)
			(xy 330.920058 -243.950417) (xy 330.877437 -243.92581) (xy 330.839316 -243.894685) (xy 330.806681 -243.857848)
			(xy 330.780378 -243.816252) (xy 330.761087 -243.770976) (xy 330.74931 -243.723192) (xy 330.74535 -243.674138)
			(xy 330.426822 -243.674138) (xy 330.42631 -243.699584) (xy 330.418146 -243.749818) (xy 330.40203 -243.798092)
			(xy 330.378379 -243.843155) (xy 330.347806 -243.883841) (xy 330.311102 -243.919096) (xy 330.269218 -243.948006)
			(xy 330.223239 -243.969823) (xy 330.174355 -243.983983) (xy 330.123834 -243.990117) (xy 330.072982 -243.988068)
			(xy 330.023118 -243.977888) (xy 329.975532 -243.959841) (xy 329.931458 -243.934395) (xy 329.892036 -243.902208)
			(xy 329.858288 -243.864114) (xy 329.831087 -243.8211) (xy 329.811139 -243.77428) (xy 329.79896 -243.724866)
			(xy 329.794865 -243.674138) (xy 329.486768 -243.674138) (xy 329.486256 -243.699584) (xy 329.478092 -243.749818)
			(xy 329.461976 -243.798092) (xy 329.438325 -243.843155) (xy 329.407752 -243.883841) (xy 329.371048 -243.919096)
			(xy 329.329164 -243.948006) (xy 329.283185 -243.969823) (xy 329.234301 -243.983983) (xy 329.18378 -243.990117)
			(xy 329.132928 -243.988068) (xy 329.083064 -243.977888) (xy 329.035478 -243.959841) (xy 328.991404 -243.934395)
			(xy 328.951982 -243.902208) (xy 328.918234 -243.864114) (xy 328.891033 -243.8211) (xy 328.871085 -243.77428)
			(xy 328.858906 -243.724866) (xy 328.854811 -243.674138) (xy 328.536554 -243.674138) (xy 328.536059 -243.698745)
			(xy 328.528164 -243.747322) (xy 328.51258 -243.794003) (xy 328.489709 -243.83758) (xy 328.460144 -243.876924)
			(xy 328.424651 -243.911016) (xy 328.384148 -243.938972) (xy 328.339686 -243.96007) (xy 328.292415 -243.973762)
			(xy 328.24356 -243.979694) (xy 328.194385 -243.977713) (xy 328.146166 -243.967869) (xy 328.10015 -243.950417)
			(xy 328.057529 -243.92581) (xy 328.019408 -243.894685) (xy 327.986773 -243.857848) (xy 327.96047 -243.816252)
			(xy 327.941179 -243.770976) (xy 327.929402 -243.723192) (xy 327.925442 -243.674138) (xy 326.656446 -243.674138)
			(xy 326.655951 -243.698745) (xy 326.648056 -243.747322) (xy 326.632472 -243.794003) (xy 326.609601 -243.83758)
			(xy 326.580036 -243.876924) (xy 326.544543 -243.911016) (xy 326.50404 -243.938972) (xy 326.459578 -243.96007)
			(xy 326.412307 -243.973762) (xy 326.363452 -243.979694) (xy 326.314277 -243.977713) (xy 326.266058 -243.967869)
			(xy 326.220042 -243.950417) (xy 326.177421 -243.92581) (xy 326.1393 -243.894685) (xy 326.106665 -243.857848)
			(xy 326.080362 -243.816252) (xy 326.061071 -243.770976) (xy 326.049294 -243.723192) (xy 326.045334 -243.674138)
			(xy 310.45912 -243.674138) (xy 310.45912 -244.750082) (xy 324.447166 -244.750082) (xy 324.451126 -244.701028)
			(xy 324.462903 -244.653244) (xy 324.482194 -244.607968) (xy 324.508497 -244.566372) (xy 324.541132 -244.529535)
			(xy 324.579253 -244.49841) (xy 324.621874 -244.473803) (xy 324.66789 -244.456351) (xy 324.716109 -244.446507)
			(xy 324.765284 -244.444526) (xy 324.814139 -244.450458) (xy 324.86141 -244.46415) (xy 324.903545 -244.484144)
			(xy 328.384911 -244.484144) (xy 328.389006 -244.433416) (xy 328.401185 -244.384002) (xy 328.421133 -244.337182)
			(xy 328.448334 -244.294168) (xy 328.482082 -244.256074) (xy 328.521504 -244.223887) (xy 328.565578 -244.198441)
			(xy 328.613164 -244.180394) (xy 328.663028 -244.170214) (xy 328.71388 -244.168165) (xy 328.764401 -244.174299)
			(xy 328.813285 -244.188459) (xy 328.859264 -244.210276) (xy 328.901148 -244.239186) (xy 328.937852 -244.274441)
			(xy 328.968425 -244.315127) (xy 328.992076 -244.36019) (xy 329.008192 -244.408464) (xy 329.016356 -244.458698)
			(xy 329.016868 -244.484144) (xy 329.335396 -244.484144) (xy 329.339356 -244.43509) (xy 329.351133 -244.387306)
			(xy 329.370424 -244.34203) (xy 329.396727 -244.300434) (xy 329.429362 -244.263597) (xy 329.467483 -244.232472)
			(xy 329.510104 -244.207865) (xy 329.55612 -244.190413) (xy 329.604339 -244.180569) (xy 329.653514 -244.178588)
			(xy 329.702369 -244.18452) (xy 329.74964 -244.198212) (xy 329.794102 -244.21931) (xy 329.834605 -244.247266)
			(xy 329.870098 -244.281358) (xy 329.899663 -244.320702) (xy 329.922534 -244.364279) (xy 329.938118 -244.41096)
			(xy 329.946013 -244.459537) (xy 329.946508 -244.484144) (xy 330.264765 -244.484144) (xy 330.26886 -244.433416)
			(xy 330.281039 -244.384002) (xy 330.300987 -244.337182) (xy 330.328188 -244.294168) (xy 330.361936 -244.256074)
			(xy 330.401358 -244.223887) (xy 330.445432 -244.198441) (xy 330.493018 -244.180394) (xy 330.542882 -244.170214)
			(xy 330.593734 -244.168165) (xy 330.644255 -244.174299) (xy 330.693139 -244.188459) (xy 330.739118 -244.210276)
			(xy 330.781002 -244.239186) (xy 330.817706 -244.274441) (xy 330.848279 -244.315127) (xy 330.87193 -244.36019)
			(xy 330.888046 -244.408464) (xy 330.89621 -244.458698) (xy 330.896722 -244.484144) (xy 331.21525 -244.484144)
			(xy 331.21921 -244.43509) (xy 331.230987 -244.387306) (xy 331.250278 -244.34203) (xy 331.276581 -244.300434)
			(xy 331.309216 -244.263597) (xy 331.347337 -244.232472) (xy 331.389958 -244.207865) (xy 331.435974 -244.190413)
			(xy 331.484193 -244.180569) (xy 331.533368 -244.178588) (xy 331.582223 -244.18452) (xy 331.629494 -244.198212)
			(xy 331.673956 -244.21931) (xy 331.714459 -244.247266) (xy 331.749952 -244.281358) (xy 331.779517 -244.320702)
			(xy 331.802388 -244.364279) (xy 331.817972 -244.41096) (xy 331.825867 -244.459537) (xy 331.826362 -244.484144)
			(xy 332.144873 -244.484144) (xy 332.148968 -244.433416) (xy 332.161147 -244.384002) (xy 332.181095 -244.337182)
			(xy 332.208296 -244.294168) (xy 332.242044 -244.256074) (xy 332.281466 -244.223887) (xy 332.32554 -244.198441)
			(xy 332.373126 -244.180394) (xy 332.42299 -244.170214) (xy 332.473842 -244.168165) (xy 332.524363 -244.174299)
			(xy 332.573247 -244.188459) (xy 332.619226 -244.210276) (xy 332.66111 -244.239186) (xy 332.697814 -244.274441)
			(xy 332.728387 -244.315127) (xy 332.752038 -244.36019) (xy 332.768154 -244.408464) (xy 332.776318 -244.458698)
			(xy 332.77683 -244.484144) (xy 333.084927 -244.484144) (xy 333.089022 -244.433416) (xy 333.101201 -244.384002)
			(xy 333.121149 -244.337182) (xy 333.14835 -244.294168) (xy 333.182098 -244.256074) (xy 333.22152 -244.223887)
			(xy 333.265594 -244.198441) (xy 333.31318 -244.180394) (xy 333.363044 -244.170214) (xy 333.413896 -244.168165)
			(xy 333.464417 -244.174299) (xy 333.513301 -244.188459) (xy 333.55928 -244.210276) (xy 333.601164 -244.239186)
			(xy 333.637868 -244.274441) (xy 333.668441 -244.315127) (xy 333.692092 -244.36019) (xy 333.708208 -244.408464)
			(xy 333.716372 -244.458698) (xy 333.716884 -244.484144) (xy 334.964781 -244.484144) (xy 334.968876 -244.433416)
			(xy 334.981055 -244.384002) (xy 335.001003 -244.337182) (xy 335.028204 -244.294168) (xy 335.061952 -244.256074)
			(xy 335.101374 -244.223887) (xy 335.145448 -244.198441) (xy 335.193034 -244.180394) (xy 335.242898 -244.170214)
			(xy 335.29375 -244.168165) (xy 335.344271 -244.174299) (xy 335.393155 -244.188459) (xy 335.439134 -244.210276)
			(xy 335.481018 -244.239186) (xy 335.517722 -244.274441) (xy 335.548295 -244.315127) (xy 335.571946 -244.36019)
			(xy 335.588062 -244.408464) (xy 335.596226 -244.458698) (xy 335.596738 -244.484144) (xy 335.915266 -244.484144)
			(xy 335.919226 -244.43509) (xy 335.931003 -244.387306) (xy 335.950294 -244.34203) (xy 335.976597 -244.300434)
			(xy 336.009232 -244.263597) (xy 336.047353 -244.232472) (xy 336.089974 -244.207865) (xy 336.13599 -244.190413)
			(xy 336.184209 -244.180569) (xy 336.233384 -244.178588) (xy 336.282239 -244.18452) (xy 336.32951 -244.198212)
			(xy 336.373972 -244.21931) (xy 336.414475 -244.247266) (xy 336.449968 -244.281358) (xy 336.479533 -244.320702)
			(xy 336.502404 -244.364279) (xy 336.517988 -244.41096) (xy 336.525883 -244.459537) (xy 336.526378 -244.484144)
			(xy 336.844889 -244.484144) (xy 336.848984 -244.433416) (xy 336.861163 -244.384002) (xy 336.881111 -244.337182)
			(xy 336.908312 -244.294168) (xy 336.94206 -244.256074) (xy 336.981482 -244.223887) (xy 337.025556 -244.198441)
			(xy 337.073142 -244.180394) (xy 337.123006 -244.170214) (xy 337.173858 -244.168165) (xy 337.224379 -244.174299)
			(xy 337.273263 -244.188459) (xy 337.319242 -244.210276) (xy 337.361126 -244.239186) (xy 337.39783 -244.274441)
			(xy 337.428403 -244.315127) (xy 337.452054 -244.36019) (xy 337.46817 -244.408464) (xy 337.476334 -244.458698)
			(xy 337.476846 -244.484144) (xy 337.795374 -244.484144) (xy 337.799334 -244.43509) (xy 337.811111 -244.387306)
			(xy 337.830402 -244.34203) (xy 337.856705 -244.300434) (xy 337.88934 -244.263597) (xy 337.927461 -244.232472)
			(xy 337.970082 -244.207865) (xy 338.016098 -244.190413) (xy 338.064317 -244.180569) (xy 338.113492 -244.178588)
			(xy 338.162347 -244.18452) (xy 338.209618 -244.198212) (xy 338.25408 -244.21931) (xy 338.294583 -244.247266)
			(xy 338.330076 -244.281358) (xy 338.359641 -244.320702) (xy 338.382512 -244.364279) (xy 338.398096 -244.41096)
			(xy 338.405991 -244.459537) (xy 338.406486 -244.484144) (xy 338.724743 -244.484144) (xy 338.728838 -244.433416)
			(xy 338.741017 -244.384002) (xy 338.760965 -244.337182) (xy 338.788166 -244.294168) (xy 338.821914 -244.256074)
			(xy 338.861336 -244.223887) (xy 338.90541 -244.198441) (xy 338.952996 -244.180394) (xy 339.00286 -244.170214)
			(xy 339.053712 -244.168165) (xy 339.104233 -244.174299) (xy 339.153117 -244.188459) (xy 339.199096 -244.210276)
			(xy 339.24098 -244.239186) (xy 339.277684 -244.274441) (xy 339.308257 -244.315127) (xy 339.331908 -244.36019)
			(xy 339.348024 -244.408464) (xy 339.356188 -244.458698) (xy 339.3567 -244.484144) (xy 339.664797 -244.484144)
			(xy 339.668892 -244.433416) (xy 339.681071 -244.384002) (xy 339.701019 -244.337182) (xy 339.72822 -244.294168)
			(xy 339.761968 -244.256074) (xy 339.80139 -244.223887) (xy 339.845464 -244.198441) (xy 339.89305 -244.180394)
			(xy 339.942914 -244.170214) (xy 339.993766 -244.168165) (xy 340.044287 -244.174299) (xy 340.093171 -244.188459)
			(xy 340.13915 -244.210276) (xy 340.181034 -244.239186) (xy 340.217738 -244.274441) (xy 340.248311 -244.315127)
			(xy 340.271962 -244.36019) (xy 340.288078 -244.408464) (xy 340.296242 -244.458698) (xy 340.296754 -244.484144)
			(xy 341.544905 -244.484144) (xy 341.549 -244.433416) (xy 341.561179 -244.384002) (xy 341.581127 -244.337182)
			(xy 341.608328 -244.294168) (xy 341.642076 -244.256074) (xy 341.681498 -244.223887) (xy 341.725572 -244.198441)
			(xy 341.773158 -244.180394) (xy 341.823022 -244.170214) (xy 341.873874 -244.168165) (xy 341.924395 -244.174299)
			(xy 341.973279 -244.188459) (xy 342.019258 -244.210276) (xy 342.061142 -244.239186) (xy 342.097846 -244.274441)
			(xy 342.128419 -244.315127) (xy 342.15207 -244.36019) (xy 342.168186 -244.408464) (xy 342.17635 -244.458698)
			(xy 342.176862 -244.484144) (xy 342.49539 -244.484144) (xy 342.49935 -244.43509) (xy 342.511127 -244.387306)
			(xy 342.530418 -244.34203) (xy 342.556721 -244.300434) (xy 342.589356 -244.263597) (xy 342.627477 -244.232472)
			(xy 342.670098 -244.207865) (xy 342.716114 -244.190413) (xy 342.764333 -244.180569) (xy 342.813508 -244.178588)
			(xy 342.862363 -244.18452) (xy 342.909634 -244.198212) (xy 342.954096 -244.21931) (xy 342.994599 -244.247266)
			(xy 343.030092 -244.281358) (xy 343.059657 -244.320702) (xy 343.082528 -244.364279) (xy 343.098112 -244.41096)
			(xy 343.106007 -244.459537) (xy 343.106502 -244.484144) (xy 343.106007 -244.508751) (xy 343.098112 -244.557328)
			(xy 343.082528 -244.604009) (xy 343.059657 -244.647586) (xy 343.030092 -244.68693) (xy 342.994599 -244.721022)
			(xy 342.954096 -244.748978) (xy 342.909634 -244.770076) (xy 342.862363 -244.783768) (xy 342.813508 -244.7897)
			(xy 342.764333 -244.787719) (xy 342.716114 -244.777875) (xy 342.670098 -244.760423) (xy 342.627477 -244.735816)
			(xy 342.589356 -244.704691) (xy 342.556721 -244.667854) (xy 342.530418 -244.626258) (xy 342.511127 -244.580982)
			(xy 342.49935 -244.533198) (xy 342.49539 -244.484144) (xy 342.176862 -244.484144) (xy 342.17635 -244.50959)
			(xy 342.168186 -244.559824) (xy 342.15207 -244.608098) (xy 342.128419 -244.653161) (xy 342.097846 -244.693847)
			(xy 342.061142 -244.729102) (xy 342.019258 -244.758012) (xy 341.973279 -244.779829) (xy 341.924395 -244.793989)
			(xy 341.873874 -244.800123) (xy 341.823022 -244.798074) (xy 341.773158 -244.787894) (xy 341.725572 -244.769847)
			(xy 341.681498 -244.744401) (xy 341.642076 -244.712214) (xy 341.608328 -244.67412) (xy 341.581127 -244.631106)
			(xy 341.561179 -244.584286) (xy 341.549 -244.534872) (xy 341.544905 -244.484144) (xy 340.296754 -244.484144)
			(xy 340.296242 -244.50959) (xy 340.288078 -244.559824) (xy 340.271962 -244.608098) (xy 340.248311 -244.653161)
			(xy 340.217738 -244.693847) (xy 340.181034 -244.729102) (xy 340.13915 -244.758012) (xy 340.093171 -244.779829)
			(xy 340.044287 -244.793989) (xy 339.993766 -244.800123) (xy 339.942914 -244.798074) (xy 339.89305 -244.787894)
			(xy 339.845464 -244.769847) (xy 339.80139 -244.744401) (xy 339.761968 -244.712214) (xy 339.72822 -244.67412)
			(xy 339.701019 -244.631106) (xy 339.681071 -244.584286) (xy 339.668892 -244.534872) (xy 339.664797 -244.484144)
			(xy 339.3567 -244.484144) (xy 339.356188 -244.50959) (xy 339.348024 -244.559824) (xy 339.331908 -244.608098)
			(xy 339.308257 -244.653161) (xy 339.277684 -244.693847) (xy 339.24098 -244.729102) (xy 339.199096 -244.758012)
			(xy 339.153117 -244.779829) (xy 339.104233 -244.793989) (xy 339.053712 -244.800123) (xy 339.00286 -244.798074)
			(xy 338.952996 -244.787894) (xy 338.90541 -244.769847) (xy 338.861336 -244.744401) (xy 338.821914 -244.712214)
			(xy 338.788166 -244.67412) (xy 338.760965 -244.631106) (xy 338.741017 -244.584286) (xy 338.728838 -244.534872)
			(xy 338.724743 -244.484144) (xy 338.406486 -244.484144) (xy 338.405991 -244.508751) (xy 338.398096 -244.557328)
			(xy 338.382512 -244.604009) (xy 338.359641 -244.647586) (xy 338.330076 -244.68693) (xy 338.294583 -244.721022)
			(xy 338.25408 -244.748978) (xy 338.209618 -244.770076) (xy 338.162347 -244.783768) (xy 338.113492 -244.7897)
			(xy 338.064317 -244.787719) (xy 338.016098 -244.777875) (xy 337.970082 -244.760423) (xy 337.927461 -244.735816)
			(xy 337.88934 -244.704691) (xy 337.856705 -244.667854) (xy 337.830402 -244.626258) (xy 337.811111 -244.580982)
			(xy 337.799334 -244.533198) (xy 337.795374 -244.484144) (xy 337.476846 -244.484144) (xy 337.476334 -244.50959)
			(xy 337.46817 -244.559824) (xy 337.452054 -244.608098) (xy 337.428403 -244.653161) (xy 337.39783 -244.693847)
			(xy 337.361126 -244.729102) (xy 337.319242 -244.758012) (xy 337.273263 -244.779829) (xy 337.224379 -244.793989)
			(xy 337.173858 -244.800123) (xy 337.123006 -244.798074) (xy 337.073142 -244.787894) (xy 337.025556 -244.769847)
			(xy 336.981482 -244.744401) (xy 336.94206 -244.712214) (xy 336.908312 -244.67412) (xy 336.881111 -244.631106)
			(xy 336.861163 -244.584286) (xy 336.848984 -244.534872) (xy 336.844889 -244.484144) (xy 336.526378 -244.484144)
			(xy 336.525883 -244.508751) (xy 336.517988 -244.557328) (xy 336.502404 -244.604009) (xy 336.479533 -244.647586)
			(xy 336.449968 -244.68693) (xy 336.414475 -244.721022) (xy 336.373972 -244.748978) (xy 336.32951 -244.770076)
			(xy 336.282239 -244.783768) (xy 336.233384 -244.7897) (xy 336.184209 -244.787719) (xy 336.13599 -244.777875)
			(xy 336.089974 -244.760423) (xy 336.047353 -244.735816) (xy 336.009232 -244.704691) (xy 335.976597 -244.667854)
			(xy 335.950294 -244.626258) (xy 335.931003 -244.580982) (xy 335.919226 -244.533198) (xy 335.915266 -244.484144)
			(xy 335.596738 -244.484144) (xy 335.596226 -244.50959) (xy 335.588062 -244.559824) (xy 335.571946 -244.608098)
			(xy 335.548295 -244.653161) (xy 335.517722 -244.693847) (xy 335.481018 -244.729102) (xy 335.439134 -244.758012)
			(xy 335.393155 -244.779829) (xy 335.344271 -244.793989) (xy 335.29375 -244.800123) (xy 335.242898 -244.798074)
			(xy 335.193034 -244.787894) (xy 335.145448 -244.769847) (xy 335.101374 -244.744401) (xy 335.061952 -244.712214)
			(xy 335.028204 -244.67412) (xy 335.001003 -244.631106) (xy 334.981055 -244.584286) (xy 334.968876 -244.534872)
			(xy 334.964781 -244.484144) (xy 333.716884 -244.484144) (xy 333.716372 -244.50959) (xy 333.708208 -244.559824)
			(xy 333.692092 -244.608098) (xy 333.668441 -244.653161) (xy 333.637868 -244.693847) (xy 333.601164 -244.729102)
			(xy 333.55928 -244.758012) (xy 333.513301 -244.779829) (xy 333.464417 -244.793989) (xy 333.413896 -244.800123)
			(xy 333.363044 -244.798074) (xy 333.31318 -244.787894) (xy 333.265594 -244.769847) (xy 333.22152 -244.744401)
			(xy 333.182098 -244.712214) (xy 333.14835 -244.67412) (xy 333.121149 -244.631106) (xy 333.101201 -244.584286)
			(xy 333.089022 -244.534872) (xy 333.084927 -244.484144) (xy 332.77683 -244.484144) (xy 332.776318 -244.50959)
			(xy 332.768154 -244.559824) (xy 332.752038 -244.608098) (xy 332.728387 -244.653161) (xy 332.697814 -244.693847)
			(xy 332.66111 -244.729102) (xy 332.619226 -244.758012) (xy 332.573247 -244.779829) (xy 332.524363 -244.793989)
			(xy 332.473842 -244.800123) (xy 332.42299 -244.798074) (xy 332.373126 -244.787894) (xy 332.32554 -244.769847)
			(xy 332.281466 -244.744401) (xy 332.242044 -244.712214) (xy 332.208296 -244.67412) (xy 332.181095 -244.631106)
			(xy 332.161147 -244.584286) (xy 332.148968 -244.534872) (xy 332.144873 -244.484144) (xy 331.826362 -244.484144)
			(xy 331.825867 -244.508751) (xy 331.817972 -244.557328) (xy 331.802388 -244.604009) (xy 331.779517 -244.647586)
			(xy 331.749952 -244.68693) (xy 331.714459 -244.721022) (xy 331.673956 -244.748978) (xy 331.629494 -244.770076)
			(xy 331.582223 -244.783768) (xy 331.533368 -244.7897) (xy 331.484193 -244.787719) (xy 331.435974 -244.777875)
			(xy 331.389958 -244.760423) (xy 331.347337 -244.735816) (xy 331.309216 -244.704691) (xy 331.276581 -244.667854)
			(xy 331.250278 -244.626258) (xy 331.230987 -244.580982) (xy 331.21921 -244.533198) (xy 331.21525 -244.484144)
			(xy 330.896722 -244.484144) (xy 330.89621 -244.50959) (xy 330.888046 -244.559824) (xy 330.87193 -244.608098)
			(xy 330.848279 -244.653161) (xy 330.817706 -244.693847) (xy 330.781002 -244.729102) (xy 330.739118 -244.758012)
			(xy 330.693139 -244.779829) (xy 330.644255 -244.793989) (xy 330.593734 -244.800123) (xy 330.542882 -244.798074)
			(xy 330.493018 -244.787894) (xy 330.445432 -244.769847) (xy 330.401358 -244.744401) (xy 330.361936 -244.712214)
			(xy 330.328188 -244.67412) (xy 330.300987 -244.631106) (xy 330.281039 -244.584286) (xy 330.26886 -244.534872)
			(xy 330.264765 -244.484144) (xy 329.946508 -244.484144) (xy 329.946013 -244.508751) (xy 329.938118 -244.557328)
			(xy 329.922534 -244.604009) (xy 329.899663 -244.647586) (xy 329.870098 -244.68693) (xy 329.834605 -244.721022)
			(xy 329.794102 -244.748978) (xy 329.74964 -244.770076) (xy 329.702369 -244.783768) (xy 329.653514 -244.7897)
			(xy 329.604339 -244.787719) (xy 329.55612 -244.777875) (xy 329.510104 -244.760423) (xy 329.467483 -244.735816)
			(xy 329.429362 -244.704691) (xy 329.396727 -244.667854) (xy 329.370424 -244.626258) (xy 329.351133 -244.580982)
			(xy 329.339356 -244.533198) (xy 329.335396 -244.484144) (xy 329.016868 -244.484144) (xy 329.016356 -244.50959)
			(xy 329.008192 -244.559824) (xy 328.992076 -244.608098) (xy 328.968425 -244.653161) (xy 328.937852 -244.693847)
			(xy 328.901148 -244.729102) (xy 328.859264 -244.758012) (xy 328.813285 -244.779829) (xy 328.764401 -244.793989)
			(xy 328.71388 -244.800123) (xy 328.663028 -244.798074) (xy 328.613164 -244.787894) (xy 328.565578 -244.769847)
			(xy 328.521504 -244.744401) (xy 328.482082 -244.712214) (xy 328.448334 -244.67412) (xy 328.421133 -244.631106)
			(xy 328.401185 -244.584286) (xy 328.389006 -244.534872) (xy 328.384911 -244.484144) (xy 324.903545 -244.484144)
			(xy 324.905872 -244.485248) (xy 324.946375 -244.513204) (xy 324.981868 -244.547296) (xy 325.011433 -244.58664)
			(xy 325.034304 -244.630217) (xy 325.049888 -244.676898) (xy 325.057783 -244.725475) (xy 325.058278 -244.750082)
			(xy 325.057783 -244.774689) (xy 325.049888 -244.823266) (xy 325.034304 -244.869947) (xy 325.011433 -244.913524)
			(xy 324.981868 -244.952868) (xy 324.946375 -244.98696) (xy 324.905872 -245.014916) (xy 324.86141 -245.036014)
			(xy 324.814139 -245.049706) (xy 324.765284 -245.055638) (xy 324.716109 -245.053657) (xy 324.66789 -245.043813)
			(xy 324.621874 -245.026361) (xy 324.579253 -245.001754) (xy 324.541132 -244.970629) (xy 324.508497 -244.933792)
			(xy 324.482194 -244.892196) (xy 324.462903 -244.84692) (xy 324.451126 -244.799136) (xy 324.447166 -244.750082)
			(xy 310.45912 -244.750082) (xy 310.45912 -245.29415) (xy 326.045334 -245.29415) (xy 326.049294 -245.245096)
			(xy 326.061071 -245.197312) (xy 326.080362 -245.152036) (xy 326.106665 -245.11044) (xy 326.1393 -245.073603)
			(xy 326.177421 -245.042478) (xy 326.220042 -245.017871) (xy 326.266058 -245.000419) (xy 326.314277 -244.990575)
			(xy 326.363452 -244.988594) (xy 326.412307 -244.994526) (xy 326.459578 -245.008218) (xy 326.50404 -245.029316)
			(xy 326.544543 -245.057272) (xy 326.580036 -245.091364) (xy 326.609601 -245.130708) (xy 326.632472 -245.174285)
			(xy 326.648056 -245.220966) (xy 326.655951 -245.269543) (xy 326.656446 -245.29415) (xy 327.925442 -245.29415)
			(xy 327.929402 -245.245096) (xy 327.941179 -245.197312) (xy 327.96047 -245.152036) (xy 327.986773 -245.11044)
			(xy 328.019408 -245.073603) (xy 328.057529 -245.042478) (xy 328.10015 -245.017871) (xy 328.146166 -245.000419)
			(xy 328.194385 -244.990575) (xy 328.24356 -244.988594) (xy 328.292415 -244.994526) (xy 328.339686 -245.008218)
			(xy 328.384148 -245.029316) (xy 328.424651 -245.057272) (xy 328.460144 -245.091364) (xy 328.489709 -245.130708)
			(xy 328.51258 -245.174285) (xy 328.528164 -245.220966) (xy 328.536059 -245.269543) (xy 328.536554 -245.29415)
			(xy 328.854811 -245.29415) (xy 328.858906 -245.243422) (xy 328.871085 -245.194008) (xy 328.891033 -245.147188)
			(xy 328.918234 -245.104174) (xy 328.951982 -245.06608) (xy 328.991404 -245.033893) (xy 329.035478 -245.008447)
			(xy 329.083064 -244.9904) (xy 329.132928 -244.98022) (xy 329.18378 -244.978171) (xy 329.234301 -244.984305)
			(xy 329.283185 -244.998465) (xy 329.329164 -245.020282) (xy 329.371048 -245.049192) (xy 329.407752 -245.084447)
			(xy 329.438325 -245.125133) (xy 329.461976 -245.170196) (xy 329.478092 -245.21847) (xy 329.486256 -245.268704)
			(xy 329.486768 -245.29415) (xy 329.794865 -245.29415) (xy 329.79896 -245.243422) (xy 329.811139 -245.194008)
			(xy 329.831087 -245.147188) (xy 329.858288 -245.104174) (xy 329.892036 -245.06608) (xy 329.931458 -245.033893)
			(xy 329.975532 -245.008447) (xy 330.023118 -244.9904) (xy 330.072982 -244.98022) (xy 330.123834 -244.978171)
			(xy 330.174355 -244.984305) (xy 330.223239 -244.998465) (xy 330.269218 -245.020282) (xy 330.311102 -245.049192)
			(xy 330.347806 -245.084447) (xy 330.378379 -245.125133) (xy 330.40203 -245.170196) (xy 330.418146 -245.21847)
			(xy 330.42631 -245.268704) (xy 330.426822 -245.29415) (xy 330.74535 -245.29415) (xy 330.74931 -245.245096)
			(xy 330.761087 -245.197312) (xy 330.780378 -245.152036) (xy 330.806681 -245.11044) (xy 330.839316 -245.073603)
			(xy 330.877437 -245.042478) (xy 330.920058 -245.017871) (xy 330.966074 -245.000419) (xy 331.014293 -244.990575)
			(xy 331.063468 -244.988594) (xy 331.112323 -244.994526) (xy 331.159594 -245.008218) (xy 331.204056 -245.029316)
			(xy 331.244559 -245.057272) (xy 331.280052 -245.091364) (xy 331.309617 -245.130708) (xy 331.332488 -245.174285)
			(xy 331.348072 -245.220966) (xy 331.355967 -245.269543) (xy 331.356462 -245.29415) (xy 331.674973 -245.29415)
			(xy 331.679068 -245.243422) (xy 331.691247 -245.194008) (xy 331.711195 -245.147188) (xy 331.738396 -245.104174)
			(xy 331.772144 -245.06608) (xy 331.811566 -245.033893) (xy 331.85564 -245.008447) (xy 331.903226 -244.9904)
			(xy 331.95309 -244.98022) (xy 332.003942 -244.978171) (xy 332.054463 -244.984305) (xy 332.103347 -244.998465)
			(xy 332.149326 -245.020282) (xy 332.19121 -245.049192) (xy 332.227914 -245.084447) (xy 332.258487 -245.125133)
			(xy 332.282138 -245.170196) (xy 332.298254 -245.21847) (xy 332.306418 -245.268704) (xy 332.30693 -245.29415)
			(xy 332.625204 -245.29415) (xy 332.629164 -245.245096) (xy 332.640941 -245.197312) (xy 332.660232 -245.152036)
			(xy 332.686535 -245.11044) (xy 332.71917 -245.073603) (xy 332.757291 -245.042478) (xy 332.799912 -245.017871)
			(xy 332.845928 -245.000419) (xy 332.894147 -244.990575) (xy 332.943322 -244.988594) (xy 332.992177 -244.994526)
			(xy 333.039448 -245.008218) (xy 333.08391 -245.029316) (xy 333.124413 -245.057272) (xy 333.159906 -245.091364)
			(xy 333.189471 -245.130708) (xy 333.212342 -245.174285) (xy 333.227926 -245.220966) (xy 333.235821 -245.269543)
			(xy 333.236316 -245.29415) (xy 333.554827 -245.29415) (xy 333.558922 -245.243422) (xy 333.571101 -245.194008)
			(xy 333.591049 -245.147188) (xy 333.61825 -245.104174) (xy 333.651998 -245.06608) (xy 333.69142 -245.033893)
			(xy 333.735494 -245.008447) (xy 333.78308 -244.9904) (xy 333.832944 -244.98022) (xy 333.883796 -244.978171)
			(xy 333.934317 -244.984305) (xy 333.983201 -244.998465) (xy 334.02918 -245.020282) (xy 334.071064 -245.049192)
			(xy 334.107768 -245.084447) (xy 334.138341 -245.125133) (xy 334.161992 -245.170196) (xy 334.178108 -245.21847)
			(xy 334.186272 -245.268704) (xy 334.186784 -245.29415) (xy 334.505312 -245.29415) (xy 334.509272 -245.245096)
			(xy 334.521049 -245.197312) (xy 334.54034 -245.152036) (xy 334.566643 -245.11044) (xy 334.599278 -245.073603)
			(xy 334.637399 -245.042478) (xy 334.68002 -245.017871) (xy 334.726036 -245.000419) (xy 334.774255 -244.990575)
			(xy 334.82343 -244.988594) (xy 334.872285 -244.994526) (xy 334.919556 -245.008218) (xy 334.964018 -245.029316)
			(xy 335.004521 -245.057272) (xy 335.040014 -245.091364) (xy 335.069579 -245.130708) (xy 335.09245 -245.174285)
			(xy 335.108034 -245.220966) (xy 335.115929 -245.269543) (xy 335.116424 -245.29415) (xy 335.434935 -245.29415)
			(xy 335.43903 -245.243422) (xy 335.451209 -245.194008) (xy 335.471157 -245.147188) (xy 335.498358 -245.104174)
			(xy 335.532106 -245.06608) (xy 335.571528 -245.033893) (xy 335.615602 -245.008447) (xy 335.663188 -244.9904)
			(xy 335.713052 -244.98022) (xy 335.763904 -244.978171) (xy 335.814425 -244.984305) (xy 335.863309 -244.998465)
			(xy 335.909288 -245.020282) (xy 335.951172 -245.049192) (xy 335.987876 -245.084447) (xy 336.018449 -245.125133)
			(xy 336.0421 -245.170196) (xy 336.058216 -245.21847) (xy 336.06638 -245.268704) (xy 336.066892 -245.29415)
			(xy 336.374989 -245.29415) (xy 336.379084 -245.243422) (xy 336.391263 -245.194008) (xy 336.411211 -245.147188)
			(xy 336.438412 -245.104174) (xy 336.47216 -245.06608) (xy 336.511582 -245.033893) (xy 336.555656 -245.008447)
			(xy 336.603242 -244.9904) (xy 336.653106 -244.98022) (xy 336.703958 -244.978171) (xy 336.754479 -244.984305)
			(xy 336.803363 -244.998465) (xy 336.849342 -245.020282) (xy 336.891226 -245.049192) (xy 336.92793 -245.084447)
			(xy 336.958503 -245.125133) (xy 336.982154 -245.170196) (xy 336.99827 -245.21847) (xy 337.006434 -245.268704)
			(xy 337.006946 -245.29415) (xy 337.32522 -245.29415) (xy 337.32918 -245.245096) (xy 337.340957 -245.197312)
			(xy 337.360248 -245.152036) (xy 337.386551 -245.11044) (xy 337.419186 -245.073603) (xy 337.457307 -245.042478)
			(xy 337.499928 -245.017871) (xy 337.545944 -245.000419) (xy 337.594163 -244.990575) (xy 337.643338 -244.988594)
			(xy 337.692193 -244.994526) (xy 337.739464 -245.008218) (xy 337.783926 -245.029316) (xy 337.824429 -245.057272)
			(xy 337.859922 -245.091364) (xy 337.889487 -245.130708) (xy 337.912358 -245.174285) (xy 337.927942 -245.220966)
			(xy 337.935837 -245.269543) (xy 337.936332 -245.29415) (xy 338.254843 -245.29415) (xy 338.258938 -245.243422)
			(xy 338.271117 -245.194008) (xy 338.291065 -245.147188) (xy 338.318266 -245.104174) (xy 338.352014 -245.06608)
			(xy 338.391436 -245.033893) (xy 338.43551 -245.008447) (xy 338.483096 -244.9904) (xy 338.53296 -244.98022)
			(xy 338.583812 -244.978171) (xy 338.634333 -244.984305) (xy 338.683217 -244.998465) (xy 338.729196 -245.020282)
			(xy 338.77108 -245.049192) (xy 338.807784 -245.084447) (xy 338.838357 -245.125133) (xy 338.862008 -245.170196)
			(xy 338.878124 -245.21847) (xy 338.886288 -245.268704) (xy 338.8868 -245.29415) (xy 339.205328 -245.29415)
			(xy 339.209288 -245.245096) (xy 339.221065 -245.197312) (xy 339.240356 -245.152036) (xy 339.266659 -245.11044)
			(xy 339.299294 -245.073603) (xy 339.337415 -245.042478) (xy 339.380036 -245.017871) (xy 339.426052 -245.000419)
			(xy 339.474271 -244.990575) (xy 339.523446 -244.988594) (xy 339.572301 -244.994526) (xy 339.619572 -245.008218)
			(xy 339.664034 -245.029316) (xy 339.704537 -245.057272) (xy 339.74003 -245.091364) (xy 339.769595 -245.130708)
			(xy 339.792466 -245.174285) (xy 339.80805 -245.220966) (xy 339.815945 -245.269543) (xy 339.81644 -245.29415)
			(xy 340.134951 -245.29415) (xy 340.139046 -245.243422) (xy 340.151225 -245.194008) (xy 340.171173 -245.147188)
			(xy 340.198374 -245.104174) (xy 340.232122 -245.06608) (xy 340.271544 -245.033893) (xy 340.315618 -245.008447)
			(xy 340.363204 -244.9904) (xy 340.413068 -244.98022) (xy 340.46392 -244.978171) (xy 340.514441 -244.984305)
			(xy 340.563325 -244.998465) (xy 340.609304 -245.020282) (xy 340.651188 -245.049192) (xy 340.687892 -245.084447)
			(xy 340.718465 -245.125133) (xy 340.742116 -245.170196) (xy 340.758232 -245.21847) (xy 340.766396 -245.268704)
			(xy 340.766908 -245.29415) (xy 341.085182 -245.29415) (xy 341.089142 -245.245096) (xy 341.100919 -245.197312)
			(xy 341.12021 -245.152036) (xy 341.146513 -245.11044) (xy 341.179148 -245.073603) (xy 341.217269 -245.042478)
			(xy 341.25989 -245.017871) (xy 341.305906 -245.000419) (xy 341.354125 -244.990575) (xy 341.4033 -244.988594)
			(xy 341.452155 -244.994526) (xy 341.499426 -245.008218) (xy 341.543888 -245.029316) (xy 341.584391 -245.057272)
			(xy 341.619884 -245.091364) (xy 341.649449 -245.130708) (xy 341.67232 -245.174285) (xy 341.687904 -245.220966)
			(xy 341.695799 -245.269543) (xy 341.696294 -245.29415) (xy 342.014805 -245.29415) (xy 342.0189 -245.243422)
			(xy 342.031079 -245.194008) (xy 342.051027 -245.147188) (xy 342.078228 -245.104174) (xy 342.111976 -245.06608)
			(xy 342.151398 -245.033893) (xy 342.195472 -245.008447) (xy 342.243058 -244.9904) (xy 342.292922 -244.98022)
			(xy 342.343774 -244.978171) (xy 342.394295 -244.984305) (xy 342.443179 -244.998465) (xy 342.489158 -245.020282)
			(xy 342.531042 -245.049192) (xy 342.567746 -245.084447) (xy 342.598319 -245.125133) (xy 342.62197 -245.170196)
			(xy 342.638086 -245.21847) (xy 342.64625 -245.268704) (xy 342.646762 -245.29415) (xy 342.954859 -245.29415)
			(xy 342.958954 -245.243422) (xy 342.971133 -245.194008) (xy 342.991081 -245.147188) (xy 343.018282 -245.104174)
			(xy 343.05203 -245.06608) (xy 343.091452 -245.033893) (xy 343.135526 -245.008447) (xy 343.183112 -244.9904)
			(xy 343.232976 -244.98022) (xy 343.283828 -244.978171) (xy 343.334349 -244.984305) (xy 343.383233 -244.998465)
			(xy 343.429212 -245.020282) (xy 343.471096 -245.049192) (xy 343.5078 -245.084447) (xy 343.538373 -245.125133)
			(xy 343.562024 -245.170196) (xy 343.57814 -245.21847) (xy 343.586304 -245.268704) (xy 343.586816 -245.29415)
			(xy 343.586304 -245.319596) (xy 343.57814 -245.36983) (xy 343.562024 -245.418104) (xy 343.538373 -245.463167)
			(xy 343.5078 -245.503853) (xy 343.471096 -245.539108) (xy 343.429212 -245.568018) (xy 343.383233 -245.589835)
			(xy 343.334349 -245.603995) (xy 343.283828 -245.610129) (xy 343.232976 -245.60808) (xy 343.183112 -245.5979)
			(xy 343.135526 -245.579853) (xy 343.091452 -245.554407) (xy 343.05203 -245.52222) (xy 343.018282 -245.484126)
			(xy 342.991081 -245.441112) (xy 342.971133 -245.394292) (xy 342.958954 -245.344878) (xy 342.954859 -245.29415)
			(xy 342.646762 -245.29415) (xy 342.64625 -245.319596) (xy 342.638086 -245.36983) (xy 342.62197 -245.418104)
			(xy 342.598319 -245.463167) (xy 342.567746 -245.503853) (xy 342.531042 -245.539108) (xy 342.489158 -245.568018)
			(xy 342.443179 -245.589835) (xy 342.394295 -245.603995) (xy 342.343774 -245.610129) (xy 342.292922 -245.60808)
			(xy 342.243058 -245.5979) (xy 342.195472 -245.579853) (xy 342.151398 -245.554407) (xy 342.111976 -245.52222)
			(xy 342.078228 -245.484126) (xy 342.051027 -245.441112) (xy 342.031079 -245.394292) (xy 342.0189 -245.344878)
			(xy 342.014805 -245.29415) (xy 341.696294 -245.29415) (xy 341.695799 -245.318757) (xy 341.687904 -245.367334)
			(xy 341.67232 -245.414015) (xy 341.649449 -245.457592) (xy 341.619884 -245.496936) (xy 341.584391 -245.531028)
			(xy 341.543888 -245.558984) (xy 341.499426 -245.580082) (xy 341.452155 -245.593774) (xy 341.4033 -245.599706)
			(xy 341.354125 -245.597725) (xy 341.305906 -245.587881) (xy 341.25989 -245.570429) (xy 341.217269 -245.545822)
			(xy 341.179148 -245.514697) (xy 341.146513 -245.47786) (xy 341.12021 -245.436264) (xy 341.100919 -245.390988)
			(xy 341.089142 -245.343204) (xy 341.085182 -245.29415) (xy 340.766908 -245.29415) (xy 340.766396 -245.319596)
			(xy 340.758232 -245.36983) (xy 340.742116 -245.418104) (xy 340.718465 -245.463167) (xy 340.687892 -245.503853)
			(xy 340.651188 -245.539108) (xy 340.609304 -245.568018) (xy 340.563325 -245.589835) (xy 340.514441 -245.603995)
			(xy 340.46392 -245.610129) (xy 340.413068 -245.60808) (xy 340.363204 -245.5979) (xy 340.315618 -245.579853)
			(xy 340.271544 -245.554407) (xy 340.232122 -245.52222) (xy 340.198374 -245.484126) (xy 340.171173 -245.441112)
			(xy 340.151225 -245.394292) (xy 340.139046 -245.344878) (xy 340.134951 -245.29415) (xy 339.81644 -245.29415)
			(xy 339.815945 -245.318757) (xy 339.80805 -245.367334) (xy 339.792466 -245.414015) (xy 339.769595 -245.457592)
			(xy 339.74003 -245.496936) (xy 339.704537 -245.531028) (xy 339.664034 -245.558984) (xy 339.619572 -245.580082)
			(xy 339.572301 -245.593774) (xy 339.523446 -245.599706) (xy 339.474271 -245.597725) (xy 339.426052 -245.587881)
			(xy 339.380036 -245.570429) (xy 339.337415 -245.545822) (xy 339.299294 -245.514697) (xy 339.266659 -245.47786)
			(xy 339.240356 -245.436264) (xy 339.221065 -245.390988) (xy 339.209288 -245.343204) (xy 339.205328 -245.29415)
			(xy 338.8868 -245.29415) (xy 338.886288 -245.319596) (xy 338.878124 -245.36983) (xy 338.862008 -245.418104)
			(xy 338.838357 -245.463167) (xy 338.807784 -245.503853) (xy 338.77108 -245.539108) (xy 338.729196 -245.568018)
			(xy 338.683217 -245.589835) (xy 338.634333 -245.603995) (xy 338.583812 -245.610129) (xy 338.53296 -245.60808)
			(xy 338.483096 -245.5979) (xy 338.43551 -245.579853) (xy 338.391436 -245.554407) (xy 338.352014 -245.52222)
			(xy 338.318266 -245.484126) (xy 338.291065 -245.441112) (xy 338.271117 -245.394292) (xy 338.258938 -245.344878)
			(xy 338.254843 -245.29415) (xy 337.936332 -245.29415) (xy 337.935837 -245.318757) (xy 337.927942 -245.367334)
			(xy 337.912358 -245.414015) (xy 337.889487 -245.457592) (xy 337.859922 -245.496936) (xy 337.824429 -245.531028)
			(xy 337.783926 -245.558984) (xy 337.739464 -245.580082) (xy 337.692193 -245.593774) (xy 337.643338 -245.599706)
			(xy 337.594163 -245.597725) (xy 337.545944 -245.587881) (xy 337.499928 -245.570429) (xy 337.457307 -245.545822)
			(xy 337.419186 -245.514697) (xy 337.386551 -245.47786) (xy 337.360248 -245.436264) (xy 337.340957 -245.390988)
			(xy 337.32918 -245.343204) (xy 337.32522 -245.29415) (xy 337.006946 -245.29415) (xy 337.006434 -245.319596)
			(xy 336.99827 -245.36983) (xy 336.982154 -245.418104) (xy 336.958503 -245.463167) (xy 336.92793 -245.503853)
			(xy 336.891226 -245.539108) (xy 336.849342 -245.568018) (xy 336.803363 -245.589835) (xy 336.754479 -245.603995)
			(xy 336.703958 -245.610129) (xy 336.653106 -245.60808) (xy 336.603242 -245.5979) (xy 336.555656 -245.579853)
			(xy 336.511582 -245.554407) (xy 336.47216 -245.52222) (xy 336.438412 -245.484126) (xy 336.411211 -245.441112)
			(xy 336.391263 -245.394292) (xy 336.379084 -245.344878) (xy 336.374989 -245.29415) (xy 336.066892 -245.29415)
			(xy 336.06638 -245.319596) (xy 336.058216 -245.36983) (xy 336.0421 -245.418104) (xy 336.018449 -245.463167)
			(xy 335.987876 -245.503853) (xy 335.951172 -245.539108) (xy 335.909288 -245.568018) (xy 335.863309 -245.589835)
			(xy 335.814425 -245.603995) (xy 335.763904 -245.610129) (xy 335.713052 -245.60808) (xy 335.663188 -245.5979)
			(xy 335.615602 -245.579853) (xy 335.571528 -245.554407) (xy 335.532106 -245.52222) (xy 335.498358 -245.484126)
			(xy 335.471157 -245.441112) (xy 335.451209 -245.394292) (xy 335.43903 -245.344878) (xy 335.434935 -245.29415)
			(xy 335.116424 -245.29415) (xy 335.115929 -245.318757) (xy 335.108034 -245.367334) (xy 335.09245 -245.414015)
			(xy 335.069579 -245.457592) (xy 335.040014 -245.496936) (xy 335.004521 -245.531028) (xy 334.964018 -245.558984)
			(xy 334.919556 -245.580082) (xy 334.872285 -245.593774) (xy 334.82343 -245.599706) (xy 334.774255 -245.597725)
			(xy 334.726036 -245.587881) (xy 334.68002 -245.570429) (xy 334.637399 -245.545822) (xy 334.599278 -245.514697)
			(xy 334.566643 -245.47786) (xy 334.54034 -245.436264) (xy 334.521049 -245.390988) (xy 334.509272 -245.343204)
			(xy 334.505312 -245.29415) (xy 334.186784 -245.29415) (xy 334.186272 -245.319596) (xy 334.178108 -245.36983)
			(xy 334.161992 -245.418104) (xy 334.138341 -245.463167) (xy 334.107768 -245.503853) (xy 334.071064 -245.539108)
			(xy 334.02918 -245.568018) (xy 333.983201 -245.589835) (xy 333.934317 -245.603995) (xy 333.883796 -245.610129)
			(xy 333.832944 -245.60808) (xy 333.78308 -245.5979) (xy 333.735494 -245.579853) (xy 333.69142 -245.554407)
			(xy 333.651998 -245.52222) (xy 333.61825 -245.484126) (xy 333.591049 -245.441112) (xy 333.571101 -245.394292)
			(xy 333.558922 -245.344878) (xy 333.554827 -245.29415) (xy 333.236316 -245.29415) (xy 333.235821 -245.318757)
			(xy 333.227926 -245.367334) (xy 333.212342 -245.414015) (xy 333.189471 -245.457592) (xy 333.159906 -245.496936)
			(xy 333.124413 -245.531028) (xy 333.08391 -245.558984) (xy 333.039448 -245.580082) (xy 332.992177 -245.593774)
			(xy 332.943322 -245.599706) (xy 332.894147 -245.597725) (xy 332.845928 -245.587881) (xy 332.799912 -245.570429)
			(xy 332.757291 -245.545822) (xy 332.71917 -245.514697) (xy 332.686535 -245.47786) (xy 332.660232 -245.436264)
			(xy 332.640941 -245.390988) (xy 332.629164 -245.343204) (xy 332.625204 -245.29415) (xy 332.30693 -245.29415)
			(xy 332.306418 -245.319596) (xy 332.298254 -245.36983) (xy 332.282138 -245.418104) (xy 332.258487 -245.463167)
			(xy 332.227914 -245.503853) (xy 332.19121 -245.539108) (xy 332.149326 -245.568018) (xy 332.103347 -245.589835)
			(xy 332.054463 -245.603995) (xy 332.003942 -245.610129) (xy 331.95309 -245.60808) (xy 331.903226 -245.5979)
			(xy 331.85564 -245.579853) (xy 331.811566 -245.554407) (xy 331.772144 -245.52222) (xy 331.738396 -245.484126)
			(xy 331.711195 -245.441112) (xy 331.691247 -245.394292) (xy 331.679068 -245.344878) (xy 331.674973 -245.29415)
			(xy 331.356462 -245.29415) (xy 331.355967 -245.318757) (xy 331.348072 -245.367334) (xy 331.332488 -245.414015)
			(xy 331.309617 -245.457592) (xy 331.280052 -245.496936) (xy 331.244559 -245.531028) (xy 331.204056 -245.558984)
			(xy 331.159594 -245.580082) (xy 331.112323 -245.593774) (xy 331.063468 -245.599706) (xy 331.014293 -245.597725)
			(xy 330.966074 -245.587881) (xy 330.920058 -245.570429) (xy 330.877437 -245.545822) (xy 330.839316 -245.514697)
			(xy 330.806681 -245.47786) (xy 330.780378 -245.436264) (xy 330.761087 -245.390988) (xy 330.74931 -245.343204)
			(xy 330.74535 -245.29415) (xy 330.426822 -245.29415) (xy 330.42631 -245.319596) (xy 330.418146 -245.36983)
			(xy 330.40203 -245.418104) (xy 330.378379 -245.463167) (xy 330.347806 -245.503853) (xy 330.311102 -245.539108)
			(xy 330.269218 -245.568018) (xy 330.223239 -245.589835) (xy 330.174355 -245.603995) (xy 330.123834 -245.610129)
			(xy 330.072982 -245.60808) (xy 330.023118 -245.5979) (xy 329.975532 -245.579853) (xy 329.931458 -245.554407)
			(xy 329.892036 -245.52222) (xy 329.858288 -245.484126) (xy 329.831087 -245.441112) (xy 329.811139 -245.394292)
			(xy 329.79896 -245.344878) (xy 329.794865 -245.29415) (xy 329.486768 -245.29415) (xy 329.486256 -245.319596)
			(xy 329.478092 -245.36983) (xy 329.461976 -245.418104) (xy 329.438325 -245.463167) (xy 329.407752 -245.503853)
			(xy 329.371048 -245.539108) (xy 329.329164 -245.568018) (xy 329.283185 -245.589835) (xy 329.234301 -245.603995)
			(xy 329.18378 -245.610129) (xy 329.132928 -245.60808) (xy 329.083064 -245.5979) (xy 329.035478 -245.579853)
			(xy 328.991404 -245.554407) (xy 328.951982 -245.52222) (xy 328.918234 -245.484126) (xy 328.891033 -245.441112)
			(xy 328.871085 -245.394292) (xy 328.858906 -245.344878) (xy 328.854811 -245.29415) (xy 328.536554 -245.29415)
			(xy 328.536059 -245.318757) (xy 328.528164 -245.367334) (xy 328.51258 -245.414015) (xy 328.489709 -245.457592)
			(xy 328.460144 -245.496936) (xy 328.424651 -245.531028) (xy 328.384148 -245.558984) (xy 328.339686 -245.580082)
			(xy 328.292415 -245.593774) (xy 328.24356 -245.599706) (xy 328.194385 -245.597725) (xy 328.146166 -245.587881)
			(xy 328.10015 -245.570429) (xy 328.057529 -245.545822) (xy 328.019408 -245.514697) (xy 327.986773 -245.47786)
			(xy 327.96047 -245.436264) (xy 327.941179 -245.390988) (xy 327.929402 -245.343204) (xy 327.925442 -245.29415)
			(xy 326.656446 -245.29415) (xy 326.655951 -245.318757) (xy 326.648056 -245.367334) (xy 326.632472 -245.414015)
			(xy 326.609601 -245.457592) (xy 326.580036 -245.496936) (xy 326.544543 -245.531028) (xy 326.50404 -245.558984)
			(xy 326.459578 -245.580082) (xy 326.412307 -245.593774) (xy 326.363452 -245.599706) (xy 326.314277 -245.597725)
			(xy 326.266058 -245.587881) (xy 326.220042 -245.570429) (xy 326.177421 -245.545822) (xy 326.1393 -245.514697)
			(xy 326.106665 -245.47786) (xy 326.080362 -245.436264) (xy 326.061071 -245.390988) (xy 326.049294 -245.343204)
			(xy 326.045334 -245.29415) (xy 310.45912 -245.29415) (xy 310.45912 -246.370094) (xy 324.447166 -246.370094)
			(xy 324.451126 -246.32104) (xy 324.462903 -246.273256) (xy 324.482194 -246.22798) (xy 324.508497 -246.186384)
			(xy 324.541132 -246.149547) (xy 324.579253 -246.118422) (xy 324.621874 -246.093815) (xy 324.66789 -246.076363)
			(xy 324.716109 -246.066519) (xy 324.765284 -246.064538) (xy 324.814139 -246.07047) (xy 324.86141 -246.084162)
			(xy 324.903545 -246.104156) (xy 327.455288 -246.104156) (xy 327.459248 -246.055102) (xy 327.471025 -246.007318)
			(xy 327.490316 -245.962042) (xy 327.516619 -245.920446) (xy 327.549254 -245.883609) (xy 327.587375 -245.852484)
			(xy 327.629996 -245.827877) (xy 327.676012 -245.810425) (xy 327.724231 -245.800581) (xy 327.773406 -245.7986)
			(xy 327.822261 -245.804532) (xy 327.869532 -245.818224) (xy 327.913994 -245.839322) (xy 327.954497 -245.867278)
			(xy 327.98999 -245.90137) (xy 328.019555 -245.940714) (xy 328.042426 -245.984291) (xy 328.05801 -246.030972)
			(xy 328.065905 -246.079549) (xy 328.0664 -246.104156) (xy 328.384911 -246.104156) (xy 328.389006 -246.053428)
			(xy 328.401185 -246.004014) (xy 328.421133 -245.957194) (xy 328.448334 -245.91418) (xy 328.482082 -245.876086)
			(xy 328.521504 -245.843899) (xy 328.565578 -245.818453) (xy 328.613164 -245.800406) (xy 328.663028 -245.790226)
			(xy 328.71388 -245.788177) (xy 328.764401 -245.794311) (xy 328.813285 -245.808471) (xy 328.859264 -245.830288)
			(xy 328.901148 -245.859198) (xy 328.937852 -245.894453) (xy 328.968425 -245.935139) (xy 328.992076 -245.980202)
			(xy 329.008192 -246.028476) (xy 329.016356 -246.07871) (xy 329.016868 -246.104156) (xy 329.335396 -246.104156)
			(xy 329.339356 -246.055102) (xy 329.351133 -246.007318) (xy 329.370424 -245.962042) (xy 329.396727 -245.920446)
			(xy 329.429362 -245.883609) (xy 329.467483 -245.852484) (xy 329.510104 -245.827877) (xy 329.55612 -245.810425)
			(xy 329.604339 -245.800581) (xy 329.653514 -245.7986) (xy 329.702369 -245.804532) (xy 329.74964 -245.818224)
			(xy 329.794102 -245.839322) (xy 329.834605 -245.867278) (xy 329.870098 -245.90137) (xy 329.899663 -245.940714)
			(xy 329.922534 -245.984291) (xy 329.938118 -246.030972) (xy 329.946013 -246.079549) (xy 329.946508 -246.104156)
			(xy 330.264765 -246.104156) (xy 330.26886 -246.053428) (xy 330.281039 -246.004014) (xy 330.300987 -245.957194)
			(xy 330.328188 -245.91418) (xy 330.361936 -245.876086) (xy 330.401358 -245.843899) (xy 330.445432 -245.818453)
			(xy 330.493018 -245.800406) (xy 330.542882 -245.790226) (xy 330.593734 -245.788177) (xy 330.644255 -245.794311)
			(xy 330.693139 -245.808471) (xy 330.739118 -245.830288) (xy 330.781002 -245.859198) (xy 330.817706 -245.894453)
			(xy 330.848279 -245.935139) (xy 330.87193 -245.980202) (xy 330.888046 -246.028476) (xy 330.89621 -246.07871)
			(xy 330.896722 -246.104156) (xy 331.21525 -246.104156) (xy 331.21921 -246.055102) (xy 331.230987 -246.007318)
			(xy 331.250278 -245.962042) (xy 331.276581 -245.920446) (xy 331.309216 -245.883609) (xy 331.347337 -245.852484)
			(xy 331.389958 -245.827877) (xy 331.435974 -245.810425) (xy 331.484193 -245.800581) (xy 331.533368 -245.7986)
			(xy 331.582223 -245.804532) (xy 331.629494 -245.818224) (xy 331.673956 -245.839322) (xy 331.714459 -245.867278)
			(xy 331.749952 -245.90137) (xy 331.779517 -245.940714) (xy 331.802388 -245.984291) (xy 331.817972 -246.030972)
			(xy 331.825867 -246.079549) (xy 331.826362 -246.104156) (xy 332.144873 -246.104156) (xy 332.148968 -246.053428)
			(xy 332.161147 -246.004014) (xy 332.181095 -245.957194) (xy 332.208296 -245.91418) (xy 332.242044 -245.876086)
			(xy 332.281466 -245.843899) (xy 332.32554 -245.818453) (xy 332.373126 -245.800406) (xy 332.42299 -245.790226)
			(xy 332.473842 -245.788177) (xy 332.524363 -245.794311) (xy 332.573247 -245.808471) (xy 332.619226 -245.830288)
			(xy 332.66111 -245.859198) (xy 332.697814 -245.894453) (xy 332.728387 -245.935139) (xy 332.752038 -245.980202)
			(xy 332.768154 -246.028476) (xy 332.776318 -246.07871) (xy 332.77683 -246.104156) (xy 333.084927 -246.104156)
			(xy 333.089022 -246.053428) (xy 333.101201 -246.004014) (xy 333.121149 -245.957194) (xy 333.14835 -245.91418)
			(xy 333.182098 -245.876086) (xy 333.22152 -245.843899) (xy 333.265594 -245.818453) (xy 333.31318 -245.800406)
			(xy 333.363044 -245.790226) (xy 333.413896 -245.788177) (xy 333.464417 -245.794311) (xy 333.513301 -245.808471)
			(xy 333.55928 -245.830288) (xy 333.601164 -245.859198) (xy 333.637868 -245.894453) (xy 333.668441 -245.935139)
			(xy 333.692092 -245.980202) (xy 333.708208 -246.028476) (xy 333.716372 -246.07871) (xy 333.716884 -246.104156)
			(xy 334.035412 -246.104156) (xy 334.039372 -246.055102) (xy 334.051149 -246.007318) (xy 334.07044 -245.962042)
			(xy 334.096743 -245.920446) (xy 334.129378 -245.883609) (xy 334.167499 -245.852484) (xy 334.21012 -245.827877)
			(xy 334.256136 -245.810425) (xy 334.304355 -245.800581) (xy 334.35353 -245.7986) (xy 334.402385 -245.804532)
			(xy 334.449656 -245.818224) (xy 334.494118 -245.839322) (xy 334.534621 -245.867278) (xy 334.570114 -245.90137)
			(xy 334.599679 -245.940714) (xy 334.62255 -245.984291) (xy 334.638134 -246.030972) (xy 334.646029 -246.079549)
			(xy 334.646524 -246.104156) (xy 334.964781 -246.104156) (xy 334.968876 -246.053428) (xy 334.981055 -246.004014)
			(xy 335.001003 -245.957194) (xy 335.028204 -245.91418) (xy 335.061952 -245.876086) (xy 335.101374 -245.843899)
			(xy 335.145448 -245.818453) (xy 335.193034 -245.800406) (xy 335.242898 -245.790226) (xy 335.29375 -245.788177)
			(xy 335.344271 -245.794311) (xy 335.393155 -245.808471) (xy 335.439134 -245.830288) (xy 335.481018 -245.859198)
			(xy 335.517722 -245.894453) (xy 335.548295 -245.935139) (xy 335.571946 -245.980202) (xy 335.588062 -246.028476)
			(xy 335.596226 -246.07871) (xy 335.596738 -246.104156) (xy 335.915266 -246.104156) (xy 335.919226 -246.055102)
			(xy 335.931003 -246.007318) (xy 335.950294 -245.962042) (xy 335.976597 -245.920446) (xy 336.009232 -245.883609)
			(xy 336.047353 -245.852484) (xy 336.089974 -245.827877) (xy 336.13599 -245.810425) (xy 336.184209 -245.800581)
			(xy 336.233384 -245.7986) (xy 336.282239 -245.804532) (xy 336.32951 -245.818224) (xy 336.373972 -245.839322)
			(xy 336.414475 -245.867278) (xy 336.449968 -245.90137) (xy 336.479533 -245.940714) (xy 336.502404 -245.984291)
			(xy 336.517988 -246.030972) (xy 336.525883 -246.079549) (xy 336.526378 -246.104156) (xy 336.844889 -246.104156)
			(xy 336.848984 -246.053428) (xy 336.861163 -246.004014) (xy 336.881111 -245.957194) (xy 336.908312 -245.91418)
			(xy 336.94206 -245.876086) (xy 336.981482 -245.843899) (xy 337.025556 -245.818453) (xy 337.073142 -245.800406)
			(xy 337.123006 -245.790226) (xy 337.173858 -245.788177) (xy 337.224379 -245.794311) (xy 337.273263 -245.808471)
			(xy 337.319242 -245.830288) (xy 337.361126 -245.859198) (xy 337.39783 -245.894453) (xy 337.428403 -245.935139)
			(xy 337.452054 -245.980202) (xy 337.46817 -246.028476) (xy 337.476334 -246.07871) (xy 337.476846 -246.104156)
			(xy 337.795374 -246.104156) (xy 337.799334 -246.055102) (xy 337.811111 -246.007318) (xy 337.830402 -245.962042)
			(xy 337.856705 -245.920446) (xy 337.88934 -245.883609) (xy 337.927461 -245.852484) (xy 337.970082 -245.827877)
			(xy 338.016098 -245.810425) (xy 338.064317 -245.800581) (xy 338.113492 -245.7986) (xy 338.162347 -245.804532)
			(xy 338.209618 -245.818224) (xy 338.25408 -245.839322) (xy 338.294583 -245.867278) (xy 338.330076 -245.90137)
			(xy 338.359641 -245.940714) (xy 338.382512 -245.984291) (xy 338.398096 -246.030972) (xy 338.405991 -246.079549)
			(xy 338.406486 -246.104156) (xy 338.724743 -246.104156) (xy 338.728838 -246.053428) (xy 338.741017 -246.004014)
			(xy 338.760965 -245.957194) (xy 338.788166 -245.91418) (xy 338.821914 -245.876086) (xy 338.861336 -245.843899)
			(xy 338.90541 -245.818453) (xy 338.952996 -245.800406) (xy 339.00286 -245.790226) (xy 339.053712 -245.788177)
			(xy 339.104233 -245.794311) (xy 339.153117 -245.808471) (xy 339.199096 -245.830288) (xy 339.24098 -245.859198)
			(xy 339.277684 -245.894453) (xy 339.308257 -245.935139) (xy 339.331908 -245.980202) (xy 339.348024 -246.028476)
			(xy 339.356188 -246.07871) (xy 339.3567 -246.104156) (xy 339.664797 -246.104156) (xy 339.668892 -246.053428)
			(xy 339.681071 -246.004014) (xy 339.701019 -245.957194) (xy 339.72822 -245.91418) (xy 339.761968 -245.876086)
			(xy 339.80139 -245.843899) (xy 339.845464 -245.818453) (xy 339.89305 -245.800406) (xy 339.942914 -245.790226)
			(xy 339.993766 -245.788177) (xy 340.044287 -245.794311) (xy 340.093171 -245.808471) (xy 340.13915 -245.830288)
			(xy 340.181034 -245.859198) (xy 340.217738 -245.894453) (xy 340.248311 -245.935139) (xy 340.271962 -245.980202)
			(xy 340.288078 -246.028476) (xy 340.296242 -246.07871) (xy 340.296754 -246.104156) (xy 340.615282 -246.104156)
			(xy 340.619242 -246.055102) (xy 340.631019 -246.007318) (xy 340.65031 -245.962042) (xy 340.676613 -245.920446)
			(xy 340.709248 -245.883609) (xy 340.747369 -245.852484) (xy 340.78999 -245.827877) (xy 340.836006 -245.810425)
			(xy 340.884225 -245.800581) (xy 340.9334 -245.7986) (xy 340.982255 -245.804532) (xy 341.029526 -245.818224)
			(xy 341.073988 -245.839322) (xy 341.114491 -245.867278) (xy 341.149984 -245.90137) (xy 341.179549 -245.940714)
			(xy 341.20242 -245.984291) (xy 341.218004 -246.030972) (xy 341.225899 -246.079549) (xy 341.226394 -246.104156)
			(xy 341.544905 -246.104156) (xy 341.549 -246.053428) (xy 341.561179 -246.004014) (xy 341.581127 -245.957194)
			(xy 341.608328 -245.91418) (xy 341.642076 -245.876086) (xy 341.681498 -245.843899) (xy 341.725572 -245.818453)
			(xy 341.773158 -245.800406) (xy 341.823022 -245.790226) (xy 341.873874 -245.788177) (xy 341.924395 -245.794311)
			(xy 341.973279 -245.808471) (xy 342.019258 -245.830288) (xy 342.061142 -245.859198) (xy 342.097846 -245.894453)
			(xy 342.128419 -245.935139) (xy 342.15207 -245.980202) (xy 342.168186 -246.028476) (xy 342.17635 -246.07871)
			(xy 342.176862 -246.104156) (xy 342.49539 -246.104156) (xy 342.49935 -246.055102) (xy 342.511127 -246.007318)
			(xy 342.530418 -245.962042) (xy 342.556721 -245.920446) (xy 342.589356 -245.883609) (xy 342.627477 -245.852484)
			(xy 342.670098 -245.827877) (xy 342.716114 -245.810425) (xy 342.764333 -245.800581) (xy 342.813508 -245.7986)
			(xy 342.862363 -245.804532) (xy 342.909634 -245.818224) (xy 342.954096 -245.839322) (xy 342.994599 -245.867278)
			(xy 343.030092 -245.90137) (xy 343.059657 -245.940714) (xy 343.082528 -245.984291) (xy 343.098112 -246.030972)
			(xy 343.106007 -246.079549) (xy 343.106502 -246.104156) (xy 343.424759 -246.104156) (xy 343.428854 -246.053428)
			(xy 343.441033 -246.004014) (xy 343.460981 -245.957194) (xy 343.488182 -245.91418) (xy 343.52193 -245.876086)
			(xy 343.561352 -245.843899) (xy 343.605426 -245.818453) (xy 343.653012 -245.800406) (xy 343.702876 -245.790226)
			(xy 343.753728 -245.788177) (xy 343.804249 -245.794311) (xy 343.853133 -245.808471) (xy 343.899112 -245.830288)
			(xy 343.940996 -245.859198) (xy 343.9777 -245.894453) (xy 344.008273 -245.935139) (xy 344.031924 -245.980202)
			(xy 344.04804 -246.028476) (xy 344.056204 -246.07871) (xy 344.056716 -246.104156) (xy 344.056204 -246.129602)
			(xy 344.04804 -246.179836) (xy 344.031924 -246.22811) (xy 344.008273 -246.273173) (xy 343.9777 -246.313859)
			(xy 343.940996 -246.349114) (xy 343.899112 -246.378024) (xy 343.853133 -246.399841) (xy 343.804249 -246.414001)
			(xy 343.753728 -246.420135) (xy 343.702876 -246.418086) (xy 343.653012 -246.407906) (xy 343.605426 -246.389859)
			(xy 343.561352 -246.364413) (xy 343.52193 -246.332226) (xy 343.488182 -246.294132) (xy 343.460981 -246.251118)
			(xy 343.441033 -246.204298) (xy 343.428854 -246.154884) (xy 343.424759 -246.104156) (xy 343.106502 -246.104156)
			(xy 343.106007 -246.128763) (xy 343.098112 -246.17734) (xy 343.082528 -246.224021) (xy 343.059657 -246.267598)
			(xy 343.030092 -246.306942) (xy 342.994599 -246.341034) (xy 342.954096 -246.36899) (xy 342.909634 -246.390088)
			(xy 342.862363 -246.40378) (xy 342.813508 -246.409712) (xy 342.764333 -246.407731) (xy 342.716114 -246.397887)
			(xy 342.670098 -246.380435) (xy 342.627477 -246.355828) (xy 342.589356 -246.324703) (xy 342.556721 -246.287866)
			(xy 342.530418 -246.24627) (xy 342.511127 -246.200994) (xy 342.49935 -246.15321) (xy 342.49539 -246.104156)
			(xy 342.176862 -246.104156) (xy 342.17635 -246.129602) (xy 342.168186 -246.179836) (xy 342.15207 -246.22811)
			(xy 342.128419 -246.273173) (xy 342.097846 -246.313859) (xy 342.061142 -246.349114) (xy 342.019258 -246.378024)
			(xy 341.973279 -246.399841) (xy 341.924395 -246.414001) (xy 341.873874 -246.420135) (xy 341.823022 -246.418086)
			(xy 341.773158 -246.407906) (xy 341.725572 -246.389859) (xy 341.681498 -246.364413) (xy 341.642076 -246.332226)
			(xy 341.608328 -246.294132) (xy 341.581127 -246.251118) (xy 341.561179 -246.204298) (xy 341.549 -246.154884)
			(xy 341.544905 -246.104156) (xy 341.226394 -246.104156) (xy 341.225899 -246.128763) (xy 341.218004 -246.17734)
			(xy 341.20242 -246.224021) (xy 341.179549 -246.267598) (xy 341.149984 -246.306942) (xy 341.114491 -246.341034)
			(xy 341.073988 -246.36899) (xy 341.029526 -246.390088) (xy 340.982255 -246.40378) (xy 340.9334 -246.409712)
			(xy 340.884225 -246.407731) (xy 340.836006 -246.397887) (xy 340.78999 -246.380435) (xy 340.747369 -246.355828)
			(xy 340.709248 -246.324703) (xy 340.676613 -246.287866) (xy 340.65031 -246.24627) (xy 340.631019 -246.200994)
			(xy 340.619242 -246.15321) (xy 340.615282 -246.104156) (xy 340.296754 -246.104156) (xy 340.296242 -246.129602)
			(xy 340.288078 -246.179836) (xy 340.271962 -246.22811) (xy 340.248311 -246.273173) (xy 340.217738 -246.313859)
			(xy 340.181034 -246.349114) (xy 340.13915 -246.378024) (xy 340.093171 -246.399841) (xy 340.044287 -246.414001)
			(xy 339.993766 -246.420135) (xy 339.942914 -246.418086) (xy 339.89305 -246.407906) (xy 339.845464 -246.389859)
			(xy 339.80139 -246.364413) (xy 339.761968 -246.332226) (xy 339.72822 -246.294132) (xy 339.701019 -246.251118)
			(xy 339.681071 -246.204298) (xy 339.668892 -246.154884) (xy 339.664797 -246.104156) (xy 339.3567 -246.104156)
			(xy 339.356188 -246.129602) (xy 339.348024 -246.179836) (xy 339.331908 -246.22811) (xy 339.308257 -246.273173)
			(xy 339.277684 -246.313859) (xy 339.24098 -246.349114) (xy 339.199096 -246.378024) (xy 339.153117 -246.399841)
			(xy 339.104233 -246.414001) (xy 339.053712 -246.420135) (xy 339.00286 -246.418086) (xy 338.952996 -246.407906)
			(xy 338.90541 -246.389859) (xy 338.861336 -246.364413) (xy 338.821914 -246.332226) (xy 338.788166 -246.294132)
			(xy 338.760965 -246.251118) (xy 338.741017 -246.204298) (xy 338.728838 -246.154884) (xy 338.724743 -246.104156)
			(xy 338.406486 -246.104156) (xy 338.405991 -246.128763) (xy 338.398096 -246.17734) (xy 338.382512 -246.224021)
			(xy 338.359641 -246.267598) (xy 338.330076 -246.306942) (xy 338.294583 -246.341034) (xy 338.25408 -246.36899)
			(xy 338.209618 -246.390088) (xy 338.162347 -246.40378) (xy 338.113492 -246.409712) (xy 338.064317 -246.407731)
			(xy 338.016098 -246.397887) (xy 337.970082 -246.380435) (xy 337.927461 -246.355828) (xy 337.88934 -246.324703)
			(xy 337.856705 -246.287866) (xy 337.830402 -246.24627) (xy 337.811111 -246.200994) (xy 337.799334 -246.15321)
			(xy 337.795374 -246.104156) (xy 337.476846 -246.104156) (xy 337.476334 -246.129602) (xy 337.46817 -246.179836)
			(xy 337.452054 -246.22811) (xy 337.428403 -246.273173) (xy 337.39783 -246.313859) (xy 337.361126 -246.349114)
			(xy 337.319242 -246.378024) (xy 337.273263 -246.399841) (xy 337.224379 -246.414001) (xy 337.173858 -246.420135)
			(xy 337.123006 -246.418086) (xy 337.073142 -246.407906) (xy 337.025556 -246.389859) (xy 336.981482 -246.364413)
			(xy 336.94206 -246.332226) (xy 336.908312 -246.294132) (xy 336.881111 -246.251118) (xy 336.861163 -246.204298)
			(xy 336.848984 -246.154884) (xy 336.844889 -246.104156) (xy 336.526378 -246.104156) (xy 336.525883 -246.128763)
			(xy 336.517988 -246.17734) (xy 336.502404 -246.224021) (xy 336.479533 -246.267598) (xy 336.449968 -246.306942)
			(xy 336.414475 -246.341034) (xy 336.373972 -246.36899) (xy 336.32951 -246.390088) (xy 336.282239 -246.40378)
			(xy 336.233384 -246.409712) (xy 336.184209 -246.407731) (xy 336.13599 -246.397887) (xy 336.089974 -246.380435)
			(xy 336.047353 -246.355828) (xy 336.009232 -246.324703) (xy 335.976597 -246.287866) (xy 335.950294 -246.24627)
			(xy 335.931003 -246.200994) (xy 335.919226 -246.15321) (xy 335.915266 -246.104156) (xy 335.596738 -246.104156)
			(xy 335.596226 -246.129602) (xy 335.588062 -246.179836) (xy 335.571946 -246.22811) (xy 335.548295 -246.273173)
			(xy 335.517722 -246.313859) (xy 335.481018 -246.349114) (xy 335.439134 -246.378024) (xy 335.393155 -246.399841)
			(xy 335.344271 -246.414001) (xy 335.29375 -246.420135) (xy 335.242898 -246.418086) (xy 335.193034 -246.407906)
			(xy 335.145448 -246.389859) (xy 335.101374 -246.364413) (xy 335.061952 -246.332226) (xy 335.028204 -246.294132)
			(xy 335.001003 -246.251118) (xy 334.981055 -246.204298) (xy 334.968876 -246.154884) (xy 334.964781 -246.104156)
			(xy 334.646524 -246.104156) (xy 334.646029 -246.128763) (xy 334.638134 -246.17734) (xy 334.62255 -246.224021)
			(xy 334.599679 -246.267598) (xy 334.570114 -246.306942) (xy 334.534621 -246.341034) (xy 334.494118 -246.36899)
			(xy 334.449656 -246.390088) (xy 334.402385 -246.40378) (xy 334.35353 -246.409712) (xy 334.304355 -246.407731)
			(xy 334.256136 -246.397887) (xy 334.21012 -246.380435) (xy 334.167499 -246.355828) (xy 334.129378 -246.324703)
			(xy 334.096743 -246.287866) (xy 334.07044 -246.24627) (xy 334.051149 -246.200994) (xy 334.039372 -246.15321)
			(xy 334.035412 -246.104156) (xy 333.716884 -246.104156) (xy 333.716372 -246.129602) (xy 333.708208 -246.179836)
			(xy 333.692092 -246.22811) (xy 333.668441 -246.273173) (xy 333.637868 -246.313859) (xy 333.601164 -246.349114)
			(xy 333.55928 -246.378024) (xy 333.513301 -246.399841) (xy 333.464417 -246.414001) (xy 333.413896 -246.420135)
			(xy 333.363044 -246.418086) (xy 333.31318 -246.407906) (xy 333.265594 -246.389859) (xy 333.22152 -246.364413)
			(xy 333.182098 -246.332226) (xy 333.14835 -246.294132) (xy 333.121149 -246.251118) (xy 333.101201 -246.204298)
			(xy 333.089022 -246.154884) (xy 333.084927 -246.104156) (xy 332.77683 -246.104156) (xy 332.776318 -246.129602)
			(xy 332.768154 -246.179836) (xy 332.752038 -246.22811) (xy 332.728387 -246.273173) (xy 332.697814 -246.313859)
			(xy 332.66111 -246.349114) (xy 332.619226 -246.378024) (xy 332.573247 -246.399841) (xy 332.524363 -246.414001)
			(xy 332.473842 -246.420135) (xy 332.42299 -246.418086) (xy 332.373126 -246.407906) (xy 332.32554 -246.389859)
			(xy 332.281466 -246.364413) (xy 332.242044 -246.332226) (xy 332.208296 -246.294132) (xy 332.181095 -246.251118)
			(xy 332.161147 -246.204298) (xy 332.148968 -246.154884) (xy 332.144873 -246.104156) (xy 331.826362 -246.104156)
			(xy 331.825867 -246.128763) (xy 331.817972 -246.17734) (xy 331.802388 -246.224021) (xy 331.779517 -246.267598)
			(xy 331.749952 -246.306942) (xy 331.714459 -246.341034) (xy 331.673956 -246.36899) (xy 331.629494 -246.390088)
			(xy 331.582223 -246.40378) (xy 331.533368 -246.409712) (xy 331.484193 -246.407731) (xy 331.435974 -246.397887)
			(xy 331.389958 -246.380435) (xy 331.347337 -246.355828) (xy 331.309216 -246.324703) (xy 331.276581 -246.287866)
			(xy 331.250278 -246.24627) (xy 331.230987 -246.200994) (xy 331.21921 -246.15321) (xy 331.21525 -246.104156)
			(xy 330.896722 -246.104156) (xy 330.89621 -246.129602) (xy 330.888046 -246.179836) (xy 330.87193 -246.22811)
			(xy 330.848279 -246.273173) (xy 330.817706 -246.313859) (xy 330.781002 -246.349114) (xy 330.739118 -246.378024)
			(xy 330.693139 -246.399841) (xy 330.644255 -246.414001) (xy 330.593734 -246.420135) (xy 330.542882 -246.418086)
			(xy 330.493018 -246.407906) (xy 330.445432 -246.389859) (xy 330.401358 -246.364413) (xy 330.361936 -246.332226)
			(xy 330.328188 -246.294132) (xy 330.300987 -246.251118) (xy 330.281039 -246.204298) (xy 330.26886 -246.154884)
			(xy 330.264765 -246.104156) (xy 329.946508 -246.104156) (xy 329.946013 -246.128763) (xy 329.938118 -246.17734)
			(xy 329.922534 -246.224021) (xy 329.899663 -246.267598) (xy 329.870098 -246.306942) (xy 329.834605 -246.341034)
			(xy 329.794102 -246.36899) (xy 329.74964 -246.390088) (xy 329.702369 -246.40378) (xy 329.653514 -246.409712)
			(xy 329.604339 -246.407731) (xy 329.55612 -246.397887) (xy 329.510104 -246.380435) (xy 329.467483 -246.355828)
			(xy 329.429362 -246.324703) (xy 329.396727 -246.287866) (xy 329.370424 -246.24627) (xy 329.351133 -246.200994)
			(xy 329.339356 -246.15321) (xy 329.335396 -246.104156) (xy 329.016868 -246.104156) (xy 329.016356 -246.129602)
			(xy 329.008192 -246.179836) (xy 328.992076 -246.22811) (xy 328.968425 -246.273173) (xy 328.937852 -246.313859)
			(xy 328.901148 -246.349114) (xy 328.859264 -246.378024) (xy 328.813285 -246.399841) (xy 328.764401 -246.414001)
			(xy 328.71388 -246.420135) (xy 328.663028 -246.418086) (xy 328.613164 -246.407906) (xy 328.565578 -246.389859)
			(xy 328.521504 -246.364413) (xy 328.482082 -246.332226) (xy 328.448334 -246.294132) (xy 328.421133 -246.251118)
			(xy 328.401185 -246.204298) (xy 328.389006 -246.154884) (xy 328.384911 -246.104156) (xy 328.0664 -246.104156)
			(xy 328.065905 -246.128763) (xy 328.05801 -246.17734) (xy 328.042426 -246.224021) (xy 328.019555 -246.267598)
			(xy 327.98999 -246.306942) (xy 327.954497 -246.341034) (xy 327.913994 -246.36899) (xy 327.869532 -246.390088)
			(xy 327.822261 -246.40378) (xy 327.773406 -246.409712) (xy 327.724231 -246.407731) (xy 327.676012 -246.397887)
			(xy 327.629996 -246.380435) (xy 327.587375 -246.355828) (xy 327.549254 -246.324703) (xy 327.516619 -246.287866)
			(xy 327.490316 -246.24627) (xy 327.471025 -246.200994) (xy 327.459248 -246.15321) (xy 327.455288 -246.104156)
			(xy 324.903545 -246.104156) (xy 324.905872 -246.10526) (xy 324.946375 -246.133216) (xy 324.981868 -246.167308)
			(xy 325.011433 -246.206652) (xy 325.034304 -246.250229) (xy 325.049888 -246.29691) (xy 325.057783 -246.345487)
			(xy 325.058278 -246.370094) (xy 325.057783 -246.394701) (xy 325.049888 -246.443278) (xy 325.034304 -246.489959)
			(xy 325.011433 -246.533536) (xy 324.981868 -246.57288) (xy 324.946375 -246.606972) (xy 324.905872 -246.634928)
			(xy 324.86141 -246.656026) (xy 324.814139 -246.669718) (xy 324.765284 -246.67565) (xy 324.716109 -246.673669)
			(xy 324.66789 -246.663825) (xy 324.621874 -246.646373) (xy 324.579253 -246.621766) (xy 324.541132 -246.590641)
			(xy 324.508497 -246.553804) (xy 324.482194 -246.512208) (xy 324.462903 -246.466932) (xy 324.451126 -246.419148)
			(xy 324.447166 -246.370094) (xy 310.45912 -246.370094) (xy 310.45912 -246.914162) (xy 326.045334 -246.914162)
			(xy 326.049294 -246.865108) (xy 326.061071 -246.817324) (xy 326.080362 -246.772048) (xy 326.106665 -246.730452)
			(xy 326.1393 -246.693615) (xy 326.177421 -246.66249) (xy 326.220042 -246.637883) (xy 326.266058 -246.620431)
			(xy 326.314277 -246.610587) (xy 326.363452 -246.608606) (xy 326.412307 -246.614538) (xy 326.459578 -246.62823)
			(xy 326.50404 -246.649328) (xy 326.544543 -246.677284) (xy 326.580036 -246.711376) (xy 326.609601 -246.75072)
			(xy 326.632472 -246.794297) (xy 326.648056 -246.840978) (xy 326.655951 -246.889555) (xy 326.656446 -246.914162)
			(xy 328.854811 -246.914162) (xy 328.858906 -246.863434) (xy 328.871085 -246.81402) (xy 328.891033 -246.7672)
			(xy 328.918234 -246.724186) (xy 328.951982 -246.686092) (xy 328.991404 -246.653905) (xy 329.035478 -246.628459)
			(xy 329.083064 -246.610412) (xy 329.132928 -246.600232) (xy 329.18378 -246.598183) (xy 329.234301 -246.604317)
			(xy 329.283185 -246.618477) (xy 329.329164 -246.640294) (xy 329.371048 -246.669204) (xy 329.407752 -246.704459)
			(xy 329.438325 -246.745145) (xy 329.461976 -246.790208) (xy 329.478092 -246.838482) (xy 329.486256 -246.888716)
			(xy 329.486768 -246.914162) (xy 329.794865 -246.914162) (xy 329.79896 -246.863434) (xy 329.811139 -246.81402)
			(xy 329.831087 -246.7672) (xy 329.858288 -246.724186) (xy 329.892036 -246.686092) (xy 329.931458 -246.653905)
			(xy 329.975532 -246.628459) (xy 330.023118 -246.610412) (xy 330.072982 -246.600232) (xy 330.123834 -246.598183)
			(xy 330.174355 -246.604317) (xy 330.223239 -246.618477) (xy 330.269218 -246.640294) (xy 330.311102 -246.669204)
			(xy 330.347806 -246.704459) (xy 330.378379 -246.745145) (xy 330.40203 -246.790208) (xy 330.418146 -246.838482)
			(xy 330.42631 -246.888716) (xy 330.426822 -246.914162) (xy 330.74535 -246.914162) (xy 330.74931 -246.865108)
			(xy 330.761087 -246.817324) (xy 330.780378 -246.772048) (xy 330.806681 -246.730452) (xy 330.839316 -246.693615)
			(xy 330.877437 -246.66249) (xy 330.920058 -246.637883) (xy 330.966074 -246.620431) (xy 331.014293 -246.610587)
			(xy 331.063468 -246.608606) (xy 331.112323 -246.614538) (xy 331.159594 -246.62823) (xy 331.204056 -246.649328)
			(xy 331.244559 -246.677284) (xy 331.280052 -246.711376) (xy 331.309617 -246.75072) (xy 331.332488 -246.794297)
			(xy 331.348072 -246.840978) (xy 331.355967 -246.889555) (xy 331.356462 -246.914162) (xy 331.674973 -246.914162)
			(xy 331.679068 -246.863434) (xy 331.691247 -246.81402) (xy 331.711195 -246.7672) (xy 331.738396 -246.724186)
			(xy 331.772144 -246.686092) (xy 331.811566 -246.653905) (xy 331.85564 -246.628459) (xy 331.903226 -246.610412)
			(xy 331.95309 -246.600232) (xy 332.003942 -246.598183) (xy 332.054463 -246.604317) (xy 332.103347 -246.618477)
			(xy 332.149326 -246.640294) (xy 332.19121 -246.669204) (xy 332.227914 -246.704459) (xy 332.258487 -246.745145)
			(xy 332.282138 -246.790208) (xy 332.298254 -246.838482) (xy 332.306418 -246.888716) (xy 332.30693 -246.914162)
			(xy 332.625204 -246.914162) (xy 332.629164 -246.865108) (xy 332.640941 -246.817324) (xy 332.660232 -246.772048)
			(xy 332.686535 -246.730452) (xy 332.71917 -246.693615) (xy 332.757291 -246.66249) (xy 332.799912 -246.637883)
			(xy 332.845928 -246.620431) (xy 332.894147 -246.610587) (xy 332.943322 -246.608606) (xy 332.992177 -246.614538)
			(xy 333.039448 -246.62823) (xy 333.08391 -246.649328) (xy 333.124413 -246.677284) (xy 333.159906 -246.711376)
			(xy 333.189471 -246.75072) (xy 333.212342 -246.794297) (xy 333.227926 -246.840978) (xy 333.235821 -246.889555)
			(xy 333.236316 -246.914162) (xy 333.554827 -246.914162) (xy 333.558922 -246.863434) (xy 333.571101 -246.81402)
			(xy 333.591049 -246.7672) (xy 333.61825 -246.724186) (xy 333.651998 -246.686092) (xy 333.69142 -246.653905)
			(xy 333.735494 -246.628459) (xy 333.78308 -246.610412) (xy 333.832944 -246.600232) (xy 333.883796 -246.598183)
			(xy 333.934317 -246.604317) (xy 333.983201 -246.618477) (xy 334.02918 -246.640294) (xy 334.071064 -246.669204)
			(xy 334.107768 -246.704459) (xy 334.138341 -246.745145) (xy 334.161992 -246.790208) (xy 334.178108 -246.838482)
			(xy 334.186272 -246.888716) (xy 334.186784 -246.914162) (xy 335.434935 -246.914162) (xy 335.43903 -246.863434)
			(xy 335.451209 -246.81402) (xy 335.471157 -246.7672) (xy 335.498358 -246.724186) (xy 335.532106 -246.686092)
			(xy 335.571528 -246.653905) (xy 335.615602 -246.628459) (xy 335.663188 -246.610412) (xy 335.713052 -246.600232)
			(xy 335.763904 -246.598183) (xy 335.814425 -246.604317) (xy 335.863309 -246.618477) (xy 335.909288 -246.640294)
			(xy 335.951172 -246.669204) (xy 335.987876 -246.704459) (xy 336.018449 -246.745145) (xy 336.0421 -246.790208)
			(xy 336.058216 -246.838482) (xy 336.06638 -246.888716) (xy 336.066892 -246.914162) (xy 336.374989 -246.914162)
			(xy 336.379084 -246.863434) (xy 336.391263 -246.81402) (xy 336.411211 -246.7672) (xy 336.438412 -246.724186)
			(xy 336.47216 -246.686092) (xy 336.511582 -246.653905) (xy 336.555656 -246.628459) (xy 336.603242 -246.610412)
			(xy 336.653106 -246.600232) (xy 336.703958 -246.598183) (xy 336.754479 -246.604317) (xy 336.803363 -246.618477)
			(xy 336.849342 -246.640294) (xy 336.891226 -246.669204) (xy 336.92793 -246.704459) (xy 336.958503 -246.745145)
			(xy 336.982154 -246.790208) (xy 336.99827 -246.838482) (xy 337.006434 -246.888716) (xy 337.006946 -246.914162)
			(xy 337.32522 -246.914162) (xy 337.32918 -246.865108) (xy 337.340957 -246.817324) (xy 337.360248 -246.772048)
			(xy 337.386551 -246.730452) (xy 337.419186 -246.693615) (xy 337.457307 -246.66249) (xy 337.499928 -246.637883)
			(xy 337.545944 -246.620431) (xy 337.594163 -246.610587) (xy 337.643338 -246.608606) (xy 337.692193 -246.614538)
			(xy 337.739464 -246.62823) (xy 337.783926 -246.649328) (xy 337.824429 -246.677284) (xy 337.859922 -246.711376)
			(xy 337.889487 -246.75072) (xy 337.912358 -246.794297) (xy 337.927942 -246.840978) (xy 337.935837 -246.889555)
			(xy 337.936332 -246.914162) (xy 338.254843 -246.914162) (xy 338.258938 -246.863434) (xy 338.271117 -246.81402)
			(xy 338.291065 -246.7672) (xy 338.318266 -246.724186) (xy 338.352014 -246.686092) (xy 338.391436 -246.653905)
			(xy 338.43551 -246.628459) (xy 338.483096 -246.610412) (xy 338.53296 -246.600232) (xy 338.583812 -246.598183)
			(xy 338.634333 -246.604317) (xy 338.683217 -246.618477) (xy 338.729196 -246.640294) (xy 338.77108 -246.669204)
			(xy 338.807784 -246.704459) (xy 338.838357 -246.745145) (xy 338.862008 -246.790208) (xy 338.878124 -246.838482)
			(xy 338.886288 -246.888716) (xy 338.8868 -246.914162) (xy 339.205328 -246.914162) (xy 339.209288 -246.865108)
			(xy 339.221065 -246.817324) (xy 339.240356 -246.772048) (xy 339.266659 -246.730452) (xy 339.299294 -246.693615)
			(xy 339.337415 -246.66249) (xy 339.380036 -246.637883) (xy 339.426052 -246.620431) (xy 339.474271 -246.610587)
			(xy 339.523446 -246.608606) (xy 339.572301 -246.614538) (xy 339.619572 -246.62823) (xy 339.664034 -246.649328)
			(xy 339.704537 -246.677284) (xy 339.74003 -246.711376) (xy 339.769595 -246.75072) (xy 339.792466 -246.794297)
			(xy 339.80805 -246.840978) (xy 339.815945 -246.889555) (xy 339.81644 -246.914162) (xy 340.134951 -246.914162)
			(xy 340.139046 -246.863434) (xy 340.151225 -246.81402) (xy 340.171173 -246.7672) (xy 340.198374 -246.724186)
			(xy 340.232122 -246.686092) (xy 340.271544 -246.653905) (xy 340.315618 -246.628459) (xy 340.363204 -246.610412)
			(xy 340.413068 -246.600232) (xy 340.46392 -246.598183) (xy 340.514441 -246.604317) (xy 340.563325 -246.618477)
			(xy 340.609304 -246.640294) (xy 340.651188 -246.669204) (xy 340.687892 -246.704459) (xy 340.718465 -246.745145)
			(xy 340.742116 -246.790208) (xy 340.758232 -246.838482) (xy 340.766396 -246.888716) (xy 340.766908 -246.914162)
			(xy 342.014805 -246.914162) (xy 342.0189 -246.863434) (xy 342.031079 -246.81402) (xy 342.051027 -246.7672)
			(xy 342.078228 -246.724186) (xy 342.111976 -246.686092) (xy 342.151398 -246.653905) (xy 342.195472 -246.628459)
			(xy 342.243058 -246.610412) (xy 342.292922 -246.600232) (xy 342.343774 -246.598183) (xy 342.394295 -246.604317)
			(xy 342.443179 -246.618477) (xy 342.489158 -246.640294) (xy 342.531042 -246.669204) (xy 342.567746 -246.704459)
			(xy 342.598319 -246.745145) (xy 342.62197 -246.790208) (xy 342.638086 -246.838482) (xy 342.64625 -246.888716)
			(xy 342.646762 -246.914162) (xy 342.954859 -246.914162) (xy 342.958954 -246.863434) (xy 342.971133 -246.81402)
			(xy 342.991081 -246.7672) (xy 343.018282 -246.724186) (xy 343.05203 -246.686092) (xy 343.091452 -246.653905)
			(xy 343.135526 -246.628459) (xy 343.183112 -246.610412) (xy 343.232976 -246.600232) (xy 343.283828 -246.598183)
			(xy 343.334349 -246.604317) (xy 343.383233 -246.618477) (xy 343.429212 -246.640294) (xy 343.471096 -246.669204)
			(xy 343.5078 -246.704459) (xy 343.538373 -246.745145) (xy 343.562024 -246.790208) (xy 343.57814 -246.838482)
			(xy 343.586304 -246.888716) (xy 343.586816 -246.914162) (xy 343.586304 -246.939608) (xy 343.57814 -246.989842)
			(xy 343.562024 -247.038116) (xy 343.538373 -247.083179) (xy 343.5078 -247.123865) (xy 343.471096 -247.15912)
			(xy 343.429212 -247.18803) (xy 343.383233 -247.209847) (xy 343.334349 -247.224007) (xy 343.283828 -247.230141)
			(xy 343.232976 -247.228092) (xy 343.183112 -247.217912) (xy 343.135526 -247.199865) (xy 343.091452 -247.174419)
			(xy 343.05203 -247.142232) (xy 343.018282 -247.104138) (xy 342.991081 -247.061124) (xy 342.971133 -247.014304)
			(xy 342.958954 -246.96489) (xy 342.954859 -246.914162) (xy 342.646762 -246.914162) (xy 342.64625 -246.939608)
			(xy 342.638086 -246.989842) (xy 342.62197 -247.038116) (xy 342.598319 -247.083179) (xy 342.567746 -247.123865)
			(xy 342.531042 -247.15912) (xy 342.489158 -247.18803) (xy 342.443179 -247.209847) (xy 342.394295 -247.224007)
			(xy 342.343774 -247.230141) (xy 342.292922 -247.228092) (xy 342.243058 -247.217912) (xy 342.195472 -247.199865)
			(xy 342.151398 -247.174419) (xy 342.111976 -247.142232) (xy 342.078228 -247.104138) (xy 342.051027 -247.061124)
			(xy 342.031079 -247.014304) (xy 342.0189 -246.96489) (xy 342.014805 -246.914162) (xy 340.766908 -246.914162)
			(xy 340.766396 -246.939608) (xy 340.758232 -246.989842) (xy 340.742116 -247.038116) (xy 340.718465 -247.083179)
			(xy 340.687892 -247.123865) (xy 340.651188 -247.15912) (xy 340.609304 -247.18803) (xy 340.563325 -247.209847)
			(xy 340.514441 -247.224007) (xy 340.46392 -247.230141) (xy 340.413068 -247.228092) (xy 340.363204 -247.217912)
			(xy 340.315618 -247.199865) (xy 340.271544 -247.174419) (xy 340.232122 -247.142232) (xy 340.198374 -247.104138)
			(xy 340.171173 -247.061124) (xy 340.151225 -247.014304) (xy 340.139046 -246.96489) (xy 340.134951 -246.914162)
			(xy 339.81644 -246.914162) (xy 339.815945 -246.938769) (xy 339.80805 -246.987346) (xy 339.792466 -247.034027)
			(xy 339.769595 -247.077604) (xy 339.74003 -247.116948) (xy 339.704537 -247.15104) (xy 339.664034 -247.178996)
			(xy 339.619572 -247.200094) (xy 339.572301 -247.213786) (xy 339.523446 -247.219718) (xy 339.474271 -247.217737)
			(xy 339.426052 -247.207893) (xy 339.380036 -247.190441) (xy 339.337415 -247.165834) (xy 339.299294 -247.134709)
			(xy 339.266659 -247.097872) (xy 339.240356 -247.056276) (xy 339.221065 -247.011) (xy 339.209288 -246.963216)
			(xy 339.205328 -246.914162) (xy 338.8868 -246.914162) (xy 338.886288 -246.939608) (xy 338.878124 -246.989842)
			(xy 338.862008 -247.038116) (xy 338.838357 -247.083179) (xy 338.807784 -247.123865) (xy 338.77108 -247.15912)
			(xy 338.729196 -247.18803) (xy 338.683217 -247.209847) (xy 338.634333 -247.224007) (xy 338.583812 -247.230141)
			(xy 338.53296 -247.228092) (xy 338.483096 -247.217912) (xy 338.43551 -247.199865) (xy 338.391436 -247.174419)
			(xy 338.352014 -247.142232) (xy 338.318266 -247.104138) (xy 338.291065 -247.061124) (xy 338.271117 -247.014304)
			(xy 338.258938 -246.96489) (xy 338.254843 -246.914162) (xy 337.936332 -246.914162) (xy 337.935837 -246.938769)
			(xy 337.927942 -246.987346) (xy 337.912358 -247.034027) (xy 337.889487 -247.077604) (xy 337.859922 -247.116948)
			(xy 337.824429 -247.15104) (xy 337.783926 -247.178996) (xy 337.739464 -247.200094) (xy 337.692193 -247.213786)
			(xy 337.643338 -247.219718) (xy 337.594163 -247.217737) (xy 337.545944 -247.207893) (xy 337.499928 -247.190441)
			(xy 337.457307 -247.165834) (xy 337.419186 -247.134709) (xy 337.386551 -247.097872) (xy 337.360248 -247.056276)
			(xy 337.340957 -247.011) (xy 337.32918 -246.963216) (xy 337.32522 -246.914162) (xy 337.006946 -246.914162)
			(xy 337.006434 -246.939608) (xy 336.99827 -246.989842) (xy 336.982154 -247.038116) (xy 336.958503 -247.083179)
			(xy 336.92793 -247.123865) (xy 336.891226 -247.15912) (xy 336.849342 -247.18803) (xy 336.803363 -247.209847)
			(xy 336.754479 -247.224007) (xy 336.703958 -247.230141) (xy 336.653106 -247.228092) (xy 336.603242 -247.217912)
			(xy 336.555656 -247.199865) (xy 336.511582 -247.174419) (xy 336.47216 -247.142232) (xy 336.438412 -247.104138)
			(xy 336.411211 -247.061124) (xy 336.391263 -247.014304) (xy 336.379084 -246.96489) (xy 336.374989 -246.914162)
			(xy 336.066892 -246.914162) (xy 336.06638 -246.939608) (xy 336.058216 -246.989842) (xy 336.0421 -247.038116)
			(xy 336.018449 -247.083179) (xy 335.987876 -247.123865) (xy 335.951172 -247.15912) (xy 335.909288 -247.18803)
			(xy 335.863309 -247.209847) (xy 335.814425 -247.224007) (xy 335.763904 -247.230141) (xy 335.713052 -247.228092)
			(xy 335.663188 -247.217912) (xy 335.615602 -247.199865) (xy 335.571528 -247.174419) (xy 335.532106 -247.142232)
			(xy 335.498358 -247.104138) (xy 335.471157 -247.061124) (xy 335.451209 -247.014304) (xy 335.43903 -246.96489)
			(xy 335.434935 -246.914162) (xy 334.186784 -246.914162) (xy 334.186272 -246.939608) (xy 334.178108 -246.989842)
			(xy 334.161992 -247.038116) (xy 334.138341 -247.083179) (xy 334.107768 -247.123865) (xy 334.071064 -247.15912)
			(xy 334.02918 -247.18803) (xy 333.983201 -247.209847) (xy 333.934317 -247.224007) (xy 333.883796 -247.230141)
			(xy 333.832944 -247.228092) (xy 333.78308 -247.217912) (xy 333.735494 -247.199865) (xy 333.69142 -247.174419)
			(xy 333.651998 -247.142232) (xy 333.61825 -247.104138) (xy 333.591049 -247.061124) (xy 333.571101 -247.014304)
			(xy 333.558922 -246.96489) (xy 333.554827 -246.914162) (xy 333.236316 -246.914162) (xy 333.235821 -246.938769)
			(xy 333.227926 -246.987346) (xy 333.212342 -247.034027) (xy 333.189471 -247.077604) (xy 333.159906 -247.116948)
			(xy 333.124413 -247.15104) (xy 333.08391 -247.178996) (xy 333.039448 -247.200094) (xy 332.992177 -247.213786)
			(xy 332.943322 -247.219718) (xy 332.894147 -247.217737) (xy 332.845928 -247.207893) (xy 332.799912 -247.190441)
			(xy 332.757291 -247.165834) (xy 332.71917 -247.134709) (xy 332.686535 -247.097872) (xy 332.660232 -247.056276)
			(xy 332.640941 -247.011) (xy 332.629164 -246.963216) (xy 332.625204 -246.914162) (xy 332.30693 -246.914162)
			(xy 332.306418 -246.939608) (xy 332.298254 -246.989842) (xy 332.282138 -247.038116) (xy 332.258487 -247.083179)
			(xy 332.227914 -247.123865) (xy 332.19121 -247.15912) (xy 332.149326 -247.18803) (xy 332.103347 -247.209847)
			(xy 332.054463 -247.224007) (xy 332.003942 -247.230141) (xy 331.95309 -247.228092) (xy 331.903226 -247.217912)
			(xy 331.85564 -247.199865) (xy 331.811566 -247.174419) (xy 331.772144 -247.142232) (xy 331.738396 -247.104138)
			(xy 331.711195 -247.061124) (xy 331.691247 -247.014304) (xy 331.679068 -246.96489) (xy 331.674973 -246.914162)
			(xy 331.356462 -246.914162) (xy 331.355967 -246.938769) (xy 331.348072 -246.987346) (xy 331.332488 -247.034027)
			(xy 331.309617 -247.077604) (xy 331.280052 -247.116948) (xy 331.244559 -247.15104) (xy 331.204056 -247.178996)
			(xy 331.159594 -247.200094) (xy 331.112323 -247.213786) (xy 331.063468 -247.219718) (xy 331.014293 -247.217737)
			(xy 330.966074 -247.207893) (xy 330.920058 -247.190441) (xy 330.877437 -247.165834) (xy 330.839316 -247.134709)
			(xy 330.806681 -247.097872) (xy 330.780378 -247.056276) (xy 330.761087 -247.011) (xy 330.74931 -246.963216)
			(xy 330.74535 -246.914162) (xy 330.426822 -246.914162) (xy 330.42631 -246.939608) (xy 330.418146 -246.989842)
			(xy 330.40203 -247.038116) (xy 330.378379 -247.083179) (xy 330.347806 -247.123865) (xy 330.311102 -247.15912)
			(xy 330.269218 -247.18803) (xy 330.223239 -247.209847) (xy 330.174355 -247.224007) (xy 330.123834 -247.230141)
			(xy 330.072982 -247.228092) (xy 330.023118 -247.217912) (xy 329.975532 -247.199865) (xy 329.931458 -247.174419)
			(xy 329.892036 -247.142232) (xy 329.858288 -247.104138) (xy 329.831087 -247.061124) (xy 329.811139 -247.014304)
			(xy 329.79896 -246.96489) (xy 329.794865 -246.914162) (xy 329.486768 -246.914162) (xy 329.486256 -246.939608)
			(xy 329.478092 -246.989842) (xy 329.461976 -247.038116) (xy 329.438325 -247.083179) (xy 329.407752 -247.123865)
			(xy 329.371048 -247.15912) (xy 329.329164 -247.18803) (xy 329.283185 -247.209847) (xy 329.234301 -247.224007)
			(xy 329.18378 -247.230141) (xy 329.132928 -247.228092) (xy 329.083064 -247.217912) (xy 329.035478 -247.199865)
			(xy 328.991404 -247.174419) (xy 328.951982 -247.142232) (xy 328.918234 -247.104138) (xy 328.891033 -247.061124)
			(xy 328.871085 -247.014304) (xy 328.858906 -246.96489) (xy 328.854811 -246.914162) (xy 326.656446 -246.914162)
			(xy 326.655951 -246.938769) (xy 326.648056 -246.987346) (xy 326.632472 -247.034027) (xy 326.609601 -247.077604)
			(xy 326.580036 -247.116948) (xy 326.544543 -247.15104) (xy 326.50404 -247.178996) (xy 326.459578 -247.200094)
			(xy 326.412307 -247.213786) (xy 326.363452 -247.219718) (xy 326.314277 -247.217737) (xy 326.266058 -247.207893)
			(xy 326.220042 -247.190441) (xy 326.177421 -247.165834) (xy 326.1393 -247.134709) (xy 326.106665 -247.097872)
			(xy 326.080362 -247.056276) (xy 326.061071 -247.011) (xy 326.049294 -246.963216) (xy 326.045334 -246.914162)
			(xy 310.45912 -246.914162) (xy 310.45912 -247.990106) (xy 324.447166 -247.990106) (xy 324.451126 -247.941052)
			(xy 324.462903 -247.893268) (xy 324.482194 -247.847992) (xy 324.508497 -247.806396) (xy 324.541132 -247.769559)
			(xy 324.579253 -247.738434) (xy 324.621874 -247.713827) (xy 324.66789 -247.696375) (xy 324.716109 -247.686531)
			(xy 324.765284 -247.68455) (xy 324.814139 -247.690482) (xy 324.86141 -247.704174) (xy 324.903545 -247.724168)
			(xy 327.455288 -247.724168) (xy 327.459248 -247.675114) (xy 327.471025 -247.62733) (xy 327.490316 -247.582054)
			(xy 327.516619 -247.540458) (xy 327.549254 -247.503621) (xy 327.587375 -247.472496) (xy 327.629996 -247.447889)
			(xy 327.676012 -247.430437) (xy 327.724231 -247.420593) (xy 327.773406 -247.418612) (xy 327.822261 -247.424544)
			(xy 327.869532 -247.438236) (xy 327.913994 -247.459334) (xy 327.954497 -247.48729) (xy 327.98999 -247.521382)
			(xy 328.019555 -247.560726) (xy 328.042426 -247.604303) (xy 328.05801 -247.650984) (xy 328.065905 -247.699561)
			(xy 328.0664 -247.724168) (xy 328.384911 -247.724168) (xy 328.389006 -247.67344) (xy 328.401185 -247.624026)
			(xy 328.421133 -247.577206) (xy 328.448334 -247.534192) (xy 328.482082 -247.496098) (xy 328.521504 -247.463911)
			(xy 328.565578 -247.438465) (xy 328.613164 -247.420418) (xy 328.663028 -247.410238) (xy 328.71388 -247.408189)
			(xy 328.764401 -247.414323) (xy 328.813285 -247.428483) (xy 328.859264 -247.4503) (xy 328.901148 -247.47921)
			(xy 328.937852 -247.514465) (xy 328.968425 -247.555151) (xy 328.992076 -247.600214) (xy 329.008192 -247.648488)
			(xy 329.016356 -247.698722) (xy 329.016868 -247.724168) (xy 329.335396 -247.724168) (xy 329.339356 -247.675114)
			(xy 329.351133 -247.62733) (xy 329.370424 -247.582054) (xy 329.396727 -247.540458) (xy 329.429362 -247.503621)
			(xy 329.467483 -247.472496) (xy 329.510104 -247.447889) (xy 329.55612 -247.430437) (xy 329.604339 -247.420593)
			(xy 329.653514 -247.418612) (xy 329.702369 -247.424544) (xy 329.74964 -247.438236) (xy 329.794102 -247.459334)
			(xy 329.834605 -247.48729) (xy 329.870098 -247.521382) (xy 329.899663 -247.560726) (xy 329.922534 -247.604303)
			(xy 329.938118 -247.650984) (xy 329.946013 -247.699561) (xy 329.946508 -247.724168) (xy 330.264765 -247.724168)
			(xy 330.26886 -247.67344) (xy 330.281039 -247.624026) (xy 330.300987 -247.577206) (xy 330.328188 -247.534192)
			(xy 330.361936 -247.496098) (xy 330.401358 -247.463911) (xy 330.445432 -247.438465) (xy 330.493018 -247.420418)
			(xy 330.542882 -247.410238) (xy 330.593734 -247.408189) (xy 330.644255 -247.414323) (xy 330.693139 -247.428483)
			(xy 330.739118 -247.4503) (xy 330.781002 -247.47921) (xy 330.817706 -247.514465) (xy 330.848279 -247.555151)
			(xy 330.87193 -247.600214) (xy 330.888046 -247.648488) (xy 330.89621 -247.698722) (xy 330.896722 -247.724168)
			(xy 331.21525 -247.724168) (xy 331.21921 -247.675114) (xy 331.230987 -247.62733) (xy 331.250278 -247.582054)
			(xy 331.276581 -247.540458) (xy 331.309216 -247.503621) (xy 331.347337 -247.472496) (xy 331.389958 -247.447889)
			(xy 331.435974 -247.430437) (xy 331.484193 -247.420593) (xy 331.533368 -247.418612) (xy 331.582223 -247.424544)
			(xy 331.629494 -247.438236) (xy 331.673956 -247.459334) (xy 331.714459 -247.48729) (xy 331.749952 -247.521382)
			(xy 331.779517 -247.560726) (xy 331.802388 -247.604303) (xy 331.817972 -247.650984) (xy 331.825867 -247.699561)
			(xy 331.826362 -247.724168) (xy 332.144873 -247.724168) (xy 332.148968 -247.67344) (xy 332.161147 -247.624026)
			(xy 332.181095 -247.577206) (xy 332.208296 -247.534192) (xy 332.242044 -247.496098) (xy 332.281466 -247.463911)
			(xy 332.32554 -247.438465) (xy 332.373126 -247.420418) (xy 332.42299 -247.410238) (xy 332.473842 -247.408189)
			(xy 332.524363 -247.414323) (xy 332.573247 -247.428483) (xy 332.619226 -247.4503) (xy 332.66111 -247.47921)
			(xy 332.697814 -247.514465) (xy 332.728387 -247.555151) (xy 332.752038 -247.600214) (xy 332.768154 -247.648488)
			(xy 332.776318 -247.698722) (xy 332.77683 -247.724168) (xy 333.084927 -247.724168) (xy 333.089022 -247.67344)
			(xy 333.101201 -247.624026) (xy 333.121149 -247.577206) (xy 333.14835 -247.534192) (xy 333.182098 -247.496098)
			(xy 333.22152 -247.463911) (xy 333.265594 -247.438465) (xy 333.31318 -247.420418) (xy 333.363044 -247.410238)
			(xy 333.413896 -247.408189) (xy 333.464417 -247.414323) (xy 333.513301 -247.428483) (xy 333.55928 -247.4503)
			(xy 333.601164 -247.47921) (xy 333.637868 -247.514465) (xy 333.668441 -247.555151) (xy 333.692092 -247.600214)
			(xy 333.708208 -247.648488) (xy 333.716372 -247.698722) (xy 333.716884 -247.724168) (xy 334.035412 -247.724168)
			(xy 334.039372 -247.675114) (xy 334.051149 -247.62733) (xy 334.07044 -247.582054) (xy 334.096743 -247.540458)
			(xy 334.129378 -247.503621) (xy 334.167499 -247.472496) (xy 334.21012 -247.447889) (xy 334.256136 -247.430437)
			(xy 334.304355 -247.420593) (xy 334.35353 -247.418612) (xy 334.402385 -247.424544) (xy 334.449656 -247.438236)
			(xy 334.494118 -247.459334) (xy 334.534621 -247.48729) (xy 334.570114 -247.521382) (xy 334.599679 -247.560726)
			(xy 334.62255 -247.604303) (xy 334.638134 -247.650984) (xy 334.646029 -247.699561) (xy 334.646524 -247.724168)
			(xy 334.964781 -247.724168) (xy 334.968876 -247.67344) (xy 334.981055 -247.624026) (xy 335.001003 -247.577206)
			(xy 335.028204 -247.534192) (xy 335.061952 -247.496098) (xy 335.101374 -247.463911) (xy 335.145448 -247.438465)
			(xy 335.193034 -247.420418) (xy 335.242898 -247.410238) (xy 335.29375 -247.408189) (xy 335.344271 -247.414323)
			(xy 335.393155 -247.428483) (xy 335.439134 -247.4503) (xy 335.481018 -247.47921) (xy 335.517722 -247.514465)
			(xy 335.548295 -247.555151) (xy 335.571946 -247.600214) (xy 335.588062 -247.648488) (xy 335.596226 -247.698722)
			(xy 335.596738 -247.724168) (xy 335.915266 -247.724168) (xy 335.919226 -247.675114) (xy 335.931003 -247.62733)
			(xy 335.950294 -247.582054) (xy 335.976597 -247.540458) (xy 336.009232 -247.503621) (xy 336.047353 -247.472496)
			(xy 336.089974 -247.447889) (xy 336.13599 -247.430437) (xy 336.184209 -247.420593) (xy 336.233384 -247.418612)
			(xy 336.282239 -247.424544) (xy 336.32951 -247.438236) (xy 336.373972 -247.459334) (xy 336.414475 -247.48729)
			(xy 336.449968 -247.521382) (xy 336.479533 -247.560726) (xy 336.502404 -247.604303) (xy 336.517988 -247.650984)
			(xy 336.525883 -247.699561) (xy 336.526378 -247.724168) (xy 336.844889 -247.724168) (xy 336.848984 -247.67344)
			(xy 336.861163 -247.624026) (xy 336.881111 -247.577206) (xy 336.908312 -247.534192) (xy 336.94206 -247.496098)
			(xy 336.981482 -247.463911) (xy 337.025556 -247.438465) (xy 337.073142 -247.420418) (xy 337.123006 -247.410238)
			(xy 337.173858 -247.408189) (xy 337.224379 -247.414323) (xy 337.273263 -247.428483) (xy 337.319242 -247.4503)
			(xy 337.361126 -247.47921) (xy 337.39783 -247.514465) (xy 337.428403 -247.555151) (xy 337.452054 -247.600214)
			(xy 337.46817 -247.648488) (xy 337.476334 -247.698722) (xy 337.476846 -247.724168) (xy 337.795374 -247.724168)
			(xy 337.799334 -247.675114) (xy 337.811111 -247.62733) (xy 337.830402 -247.582054) (xy 337.856705 -247.540458)
			(xy 337.88934 -247.503621) (xy 337.927461 -247.472496) (xy 337.970082 -247.447889) (xy 338.016098 -247.430437)
			(xy 338.064317 -247.420593) (xy 338.113492 -247.418612) (xy 338.162347 -247.424544) (xy 338.209618 -247.438236)
			(xy 338.25408 -247.459334) (xy 338.294583 -247.48729) (xy 338.330076 -247.521382) (xy 338.359641 -247.560726)
			(xy 338.382512 -247.604303) (xy 338.398096 -247.650984) (xy 338.405991 -247.699561) (xy 338.406486 -247.724168)
			(xy 338.724743 -247.724168) (xy 338.728838 -247.67344) (xy 338.741017 -247.624026) (xy 338.760965 -247.577206)
			(xy 338.788166 -247.534192) (xy 338.821914 -247.496098) (xy 338.861336 -247.463911) (xy 338.90541 -247.438465)
			(xy 338.952996 -247.420418) (xy 339.00286 -247.410238) (xy 339.053712 -247.408189) (xy 339.104233 -247.414323)
			(xy 339.153117 -247.428483) (xy 339.199096 -247.4503) (xy 339.24098 -247.47921) (xy 339.277684 -247.514465)
			(xy 339.308257 -247.555151) (xy 339.331908 -247.600214) (xy 339.348024 -247.648488) (xy 339.356188 -247.698722)
			(xy 339.3567 -247.724168) (xy 339.664797 -247.724168) (xy 339.668892 -247.67344) (xy 339.681071 -247.624026)
			(xy 339.701019 -247.577206) (xy 339.72822 -247.534192) (xy 339.761968 -247.496098) (xy 339.80139 -247.463911)
			(xy 339.845464 -247.438465) (xy 339.89305 -247.420418) (xy 339.942914 -247.410238) (xy 339.993766 -247.408189)
			(xy 340.044287 -247.414323) (xy 340.093171 -247.428483) (xy 340.13915 -247.4503) (xy 340.181034 -247.47921)
			(xy 340.217738 -247.514465) (xy 340.248311 -247.555151) (xy 340.271962 -247.600214) (xy 340.288078 -247.648488)
			(xy 340.296242 -247.698722) (xy 340.296754 -247.724168) (xy 340.615282 -247.724168) (xy 340.619242 -247.675114)
			(xy 340.631019 -247.62733) (xy 340.65031 -247.582054) (xy 340.676613 -247.540458) (xy 340.709248 -247.503621)
			(xy 340.747369 -247.472496) (xy 340.78999 -247.447889) (xy 340.836006 -247.430437) (xy 340.884225 -247.420593)
			(xy 340.9334 -247.418612) (xy 340.982255 -247.424544) (xy 341.029526 -247.438236) (xy 341.073988 -247.459334)
			(xy 341.114491 -247.48729) (xy 341.149984 -247.521382) (xy 341.179549 -247.560726) (xy 341.20242 -247.604303)
			(xy 341.218004 -247.650984) (xy 341.225899 -247.699561) (xy 341.226394 -247.724168) (xy 341.544905 -247.724168)
			(xy 341.549 -247.67344) (xy 341.561179 -247.624026) (xy 341.581127 -247.577206) (xy 341.608328 -247.534192)
			(xy 341.642076 -247.496098) (xy 341.681498 -247.463911) (xy 341.725572 -247.438465) (xy 341.773158 -247.420418)
			(xy 341.823022 -247.410238) (xy 341.873874 -247.408189) (xy 341.924395 -247.414323) (xy 341.973279 -247.428483)
			(xy 342.019258 -247.4503) (xy 342.061142 -247.47921) (xy 342.097846 -247.514465) (xy 342.128419 -247.555151)
			(xy 342.15207 -247.600214) (xy 342.168186 -247.648488) (xy 342.17635 -247.698722) (xy 342.176862 -247.724168)
			(xy 342.49539 -247.724168) (xy 342.49935 -247.675114) (xy 342.511127 -247.62733) (xy 342.530418 -247.582054)
			(xy 342.556721 -247.540458) (xy 342.589356 -247.503621) (xy 342.627477 -247.472496) (xy 342.670098 -247.447889)
			(xy 342.716114 -247.430437) (xy 342.764333 -247.420593) (xy 342.813508 -247.418612) (xy 342.862363 -247.424544)
			(xy 342.909634 -247.438236) (xy 342.954096 -247.459334) (xy 342.994599 -247.48729) (xy 343.030092 -247.521382)
			(xy 343.059657 -247.560726) (xy 343.082528 -247.604303) (xy 343.098112 -247.650984) (xy 343.106007 -247.699561)
			(xy 343.106502 -247.724168) (xy 343.424759 -247.724168) (xy 343.428854 -247.67344) (xy 343.441033 -247.624026)
			(xy 343.460981 -247.577206) (xy 343.488182 -247.534192) (xy 343.52193 -247.496098) (xy 343.561352 -247.463911)
			(xy 343.605426 -247.438465) (xy 343.653012 -247.420418) (xy 343.702876 -247.410238) (xy 343.753728 -247.408189)
			(xy 343.804249 -247.414323) (xy 343.853133 -247.428483) (xy 343.899112 -247.4503) (xy 343.940996 -247.47921)
			(xy 343.9777 -247.514465) (xy 344.008273 -247.555151) (xy 344.031924 -247.600214) (xy 344.04804 -247.648488)
			(xy 344.056204 -247.698722) (xy 344.056716 -247.724168) (xy 344.056204 -247.749614) (xy 344.04804 -247.799848)
			(xy 344.031924 -247.848122) (xy 344.008273 -247.893185) (xy 343.9777 -247.933871) (xy 343.940996 -247.969126)
			(xy 343.899112 -247.998036) (xy 343.853133 -248.019853) (xy 343.804249 -248.034013) (xy 343.753728 -248.040147)
			(xy 343.702876 -248.038098) (xy 343.653012 -248.027918) (xy 343.605426 -248.009871) (xy 343.561352 -247.984425)
			(xy 343.52193 -247.952238) (xy 343.488182 -247.914144) (xy 343.460981 -247.87113) (xy 343.441033 -247.82431)
			(xy 343.428854 -247.774896) (xy 343.424759 -247.724168) (xy 343.106502 -247.724168) (xy 343.106007 -247.748775)
			(xy 343.098112 -247.797352) (xy 343.082528 -247.844033) (xy 343.059657 -247.88761) (xy 343.030092 -247.926954)
			(xy 342.994599 -247.961046) (xy 342.954096 -247.989002) (xy 342.909634 -248.0101) (xy 342.862363 -248.023792)
			(xy 342.813508 -248.029724) (xy 342.764333 -248.027743) (xy 342.716114 -248.017899) (xy 342.670098 -248.000447)
			(xy 342.627477 -247.97584) (xy 342.589356 -247.944715) (xy 342.556721 -247.907878) (xy 342.530418 -247.866282)
			(xy 342.511127 -247.821006) (xy 342.49935 -247.773222) (xy 342.49539 -247.724168) (xy 342.176862 -247.724168)
			(xy 342.17635 -247.749614) (xy 342.168186 -247.799848) (xy 342.15207 -247.848122) (xy 342.128419 -247.893185)
			(xy 342.097846 -247.933871) (xy 342.061142 -247.969126) (xy 342.019258 -247.998036) (xy 341.973279 -248.019853)
			(xy 341.924395 -248.034013) (xy 341.873874 -248.040147) (xy 341.823022 -248.038098) (xy 341.773158 -248.027918)
			(xy 341.725572 -248.009871) (xy 341.681498 -247.984425) (xy 341.642076 -247.952238) (xy 341.608328 -247.914144)
			(xy 341.581127 -247.87113) (xy 341.561179 -247.82431) (xy 341.549 -247.774896) (xy 341.544905 -247.724168)
			(xy 341.226394 -247.724168) (xy 341.225899 -247.748775) (xy 341.218004 -247.797352) (xy 341.20242 -247.844033)
			(xy 341.179549 -247.88761) (xy 341.149984 -247.926954) (xy 341.114491 -247.961046) (xy 341.073988 -247.989002)
			(xy 341.029526 -248.0101) (xy 340.982255 -248.023792) (xy 340.9334 -248.029724) (xy 340.884225 -248.027743)
			(xy 340.836006 -248.017899) (xy 340.78999 -248.000447) (xy 340.747369 -247.97584) (xy 340.709248 -247.944715)
			(xy 340.676613 -247.907878) (xy 340.65031 -247.866282) (xy 340.631019 -247.821006) (xy 340.619242 -247.773222)
			(xy 340.615282 -247.724168) (xy 340.296754 -247.724168) (xy 340.296242 -247.749614) (xy 340.288078 -247.799848)
			(xy 340.271962 -247.848122) (xy 340.248311 -247.893185) (xy 340.217738 -247.933871) (xy 340.181034 -247.969126)
			(xy 340.13915 -247.998036) (xy 340.093171 -248.019853) (xy 340.044287 -248.034013) (xy 339.993766 -248.040147)
			(xy 339.942914 -248.038098) (xy 339.89305 -248.027918) (xy 339.845464 -248.009871) (xy 339.80139 -247.984425)
			(xy 339.761968 -247.952238) (xy 339.72822 -247.914144) (xy 339.701019 -247.87113) (xy 339.681071 -247.82431)
			(xy 339.668892 -247.774896) (xy 339.664797 -247.724168) (xy 339.3567 -247.724168) (xy 339.356188 -247.749614)
			(xy 339.348024 -247.799848) (xy 339.331908 -247.848122) (xy 339.308257 -247.893185) (xy 339.277684 -247.933871)
			(xy 339.24098 -247.969126) (xy 339.199096 -247.998036) (xy 339.153117 -248.019853) (xy 339.104233 -248.034013)
			(xy 339.053712 -248.040147) (xy 339.00286 -248.038098) (xy 338.952996 -248.027918) (xy 338.90541 -248.009871)
			(xy 338.861336 -247.984425) (xy 338.821914 -247.952238) (xy 338.788166 -247.914144) (xy 338.760965 -247.87113)
			(xy 338.741017 -247.82431) (xy 338.728838 -247.774896) (xy 338.724743 -247.724168) (xy 338.406486 -247.724168)
			(xy 338.405991 -247.748775) (xy 338.398096 -247.797352) (xy 338.382512 -247.844033) (xy 338.359641 -247.88761)
			(xy 338.330076 -247.926954) (xy 338.294583 -247.961046) (xy 338.25408 -247.989002) (xy 338.209618 -248.0101)
			(xy 338.162347 -248.023792) (xy 338.113492 -248.029724) (xy 338.064317 -248.027743) (xy 338.016098 -248.017899)
			(xy 337.970082 -248.000447) (xy 337.927461 -247.97584) (xy 337.88934 -247.944715) (xy 337.856705 -247.907878)
			(xy 337.830402 -247.866282) (xy 337.811111 -247.821006) (xy 337.799334 -247.773222) (xy 337.795374 -247.724168)
			(xy 337.476846 -247.724168) (xy 337.476334 -247.749614) (xy 337.46817 -247.799848) (xy 337.452054 -247.848122)
			(xy 337.428403 -247.893185) (xy 337.39783 -247.933871) (xy 337.361126 -247.969126) (xy 337.319242 -247.998036)
			(xy 337.273263 -248.019853) (xy 337.224379 -248.034013) (xy 337.173858 -248.040147) (xy 337.123006 -248.038098)
			(xy 337.073142 -248.027918) (xy 337.025556 -248.009871) (xy 336.981482 -247.984425) (xy 336.94206 -247.952238)
			(xy 336.908312 -247.914144) (xy 336.881111 -247.87113) (xy 336.861163 -247.82431) (xy 336.848984 -247.774896)
			(xy 336.844889 -247.724168) (xy 336.526378 -247.724168) (xy 336.525883 -247.748775) (xy 336.517988 -247.797352)
			(xy 336.502404 -247.844033) (xy 336.479533 -247.88761) (xy 336.449968 -247.926954) (xy 336.414475 -247.961046)
			(xy 336.373972 -247.989002) (xy 336.32951 -248.0101) (xy 336.282239 -248.023792) (xy 336.233384 -248.029724)
			(xy 336.184209 -248.027743) (xy 336.13599 -248.017899) (xy 336.089974 -248.000447) (xy 336.047353 -247.97584)
			(xy 336.009232 -247.944715) (xy 335.976597 -247.907878) (xy 335.950294 -247.866282) (xy 335.931003 -247.821006)
			(xy 335.919226 -247.773222) (xy 335.915266 -247.724168) (xy 335.596738 -247.724168) (xy 335.596226 -247.749614)
			(xy 335.588062 -247.799848) (xy 335.571946 -247.848122) (xy 335.548295 -247.893185) (xy 335.517722 -247.933871)
			(xy 335.481018 -247.969126) (xy 335.439134 -247.998036) (xy 335.393155 -248.019853) (xy 335.344271 -248.034013)
			(xy 335.29375 -248.040147) (xy 335.242898 -248.038098) (xy 335.193034 -248.027918) (xy 335.145448 -248.009871)
			(xy 335.101374 -247.984425) (xy 335.061952 -247.952238) (xy 335.028204 -247.914144) (xy 335.001003 -247.87113)
			(xy 334.981055 -247.82431) (xy 334.968876 -247.774896) (xy 334.964781 -247.724168) (xy 334.646524 -247.724168)
			(xy 334.646029 -247.748775) (xy 334.638134 -247.797352) (xy 334.62255 -247.844033) (xy 334.599679 -247.88761)
			(xy 334.570114 -247.926954) (xy 334.534621 -247.961046) (xy 334.494118 -247.989002) (xy 334.449656 -248.0101)
			(xy 334.402385 -248.023792) (xy 334.35353 -248.029724) (xy 334.304355 -248.027743) (xy 334.256136 -248.017899)
			(xy 334.21012 -248.000447) (xy 334.167499 -247.97584) (xy 334.129378 -247.944715) (xy 334.096743 -247.907878)
			(xy 334.07044 -247.866282) (xy 334.051149 -247.821006) (xy 334.039372 -247.773222) (xy 334.035412 -247.724168)
			(xy 333.716884 -247.724168) (xy 333.716372 -247.749614) (xy 333.708208 -247.799848) (xy 333.692092 -247.848122)
			(xy 333.668441 -247.893185) (xy 333.637868 -247.933871) (xy 333.601164 -247.969126) (xy 333.55928 -247.998036)
			(xy 333.513301 -248.019853) (xy 333.464417 -248.034013) (xy 333.413896 -248.040147) (xy 333.363044 -248.038098)
			(xy 333.31318 -248.027918) (xy 333.265594 -248.009871) (xy 333.22152 -247.984425) (xy 333.182098 -247.952238)
			(xy 333.14835 -247.914144) (xy 333.121149 -247.87113) (xy 333.101201 -247.82431) (xy 333.089022 -247.774896)
			(xy 333.084927 -247.724168) (xy 332.77683 -247.724168) (xy 332.776318 -247.749614) (xy 332.768154 -247.799848)
			(xy 332.752038 -247.848122) (xy 332.728387 -247.893185) (xy 332.697814 -247.933871) (xy 332.66111 -247.969126)
			(xy 332.619226 -247.998036) (xy 332.573247 -248.019853) (xy 332.524363 -248.034013) (xy 332.473842 -248.040147)
			(xy 332.42299 -248.038098) (xy 332.373126 -248.027918) (xy 332.32554 -248.009871) (xy 332.281466 -247.984425)
			(xy 332.242044 -247.952238) (xy 332.208296 -247.914144) (xy 332.181095 -247.87113) (xy 332.161147 -247.82431)
			(xy 332.148968 -247.774896) (xy 332.144873 -247.724168) (xy 331.826362 -247.724168) (xy 331.825867 -247.748775)
			(xy 331.817972 -247.797352) (xy 331.802388 -247.844033) (xy 331.779517 -247.88761) (xy 331.749952 -247.926954)
			(xy 331.714459 -247.961046) (xy 331.673956 -247.989002) (xy 331.629494 -248.0101) (xy 331.582223 -248.023792)
			(xy 331.533368 -248.029724) (xy 331.484193 -248.027743) (xy 331.435974 -248.017899) (xy 331.389958 -248.000447)
			(xy 331.347337 -247.97584) (xy 331.309216 -247.944715) (xy 331.276581 -247.907878) (xy 331.250278 -247.866282)
			(xy 331.230987 -247.821006) (xy 331.21921 -247.773222) (xy 331.21525 -247.724168) (xy 330.896722 -247.724168)
			(xy 330.89621 -247.749614) (xy 330.888046 -247.799848) (xy 330.87193 -247.848122) (xy 330.848279 -247.893185)
			(xy 330.817706 -247.933871) (xy 330.781002 -247.969126) (xy 330.739118 -247.998036) (xy 330.693139 -248.019853)
			(xy 330.644255 -248.034013) (xy 330.593734 -248.040147) (xy 330.542882 -248.038098) (xy 330.493018 -248.027918)
			(xy 330.445432 -248.009871) (xy 330.401358 -247.984425) (xy 330.361936 -247.952238) (xy 330.328188 -247.914144)
			(xy 330.300987 -247.87113) (xy 330.281039 -247.82431) (xy 330.26886 -247.774896) (xy 330.264765 -247.724168)
			(xy 329.946508 -247.724168) (xy 329.946013 -247.748775) (xy 329.938118 -247.797352) (xy 329.922534 -247.844033)
			(xy 329.899663 -247.88761) (xy 329.870098 -247.926954) (xy 329.834605 -247.961046) (xy 329.794102 -247.989002)
			(xy 329.74964 -248.0101) (xy 329.702369 -248.023792) (xy 329.653514 -248.029724) (xy 329.604339 -248.027743)
			(xy 329.55612 -248.017899) (xy 329.510104 -248.000447) (xy 329.467483 -247.97584) (xy 329.429362 -247.944715)
			(xy 329.396727 -247.907878) (xy 329.370424 -247.866282) (xy 329.351133 -247.821006) (xy 329.339356 -247.773222)
			(xy 329.335396 -247.724168) (xy 329.016868 -247.724168) (xy 329.016356 -247.749614) (xy 329.008192 -247.799848)
			(xy 328.992076 -247.848122) (xy 328.968425 -247.893185) (xy 328.937852 -247.933871) (xy 328.901148 -247.969126)
			(xy 328.859264 -247.998036) (xy 328.813285 -248.019853) (xy 328.764401 -248.034013) (xy 328.71388 -248.040147)
			(xy 328.663028 -248.038098) (xy 328.613164 -248.027918) (xy 328.565578 -248.009871) (xy 328.521504 -247.984425)
			(xy 328.482082 -247.952238) (xy 328.448334 -247.914144) (xy 328.421133 -247.87113) (xy 328.401185 -247.82431)
			(xy 328.389006 -247.774896) (xy 328.384911 -247.724168) (xy 328.0664 -247.724168) (xy 328.065905 -247.748775)
			(xy 328.05801 -247.797352) (xy 328.042426 -247.844033) (xy 328.019555 -247.88761) (xy 327.98999 -247.926954)
			(xy 327.954497 -247.961046) (xy 327.913994 -247.989002) (xy 327.869532 -248.0101) (xy 327.822261 -248.023792)
			(xy 327.773406 -248.029724) (xy 327.724231 -248.027743) (xy 327.676012 -248.017899) (xy 327.629996 -248.000447)
			(xy 327.587375 -247.97584) (xy 327.549254 -247.944715) (xy 327.516619 -247.907878) (xy 327.490316 -247.866282)
			(xy 327.471025 -247.821006) (xy 327.459248 -247.773222) (xy 327.455288 -247.724168) (xy 324.903545 -247.724168)
			(xy 324.905872 -247.725272) (xy 324.946375 -247.753228) (xy 324.981868 -247.78732) (xy 325.011433 -247.826664)
			(xy 325.034304 -247.870241) (xy 325.049888 -247.916922) (xy 325.057783 -247.965499) (xy 325.058278 -247.990106)
			(xy 325.057783 -248.014713) (xy 325.049888 -248.06329) (xy 325.034304 -248.109971) (xy 325.011433 -248.153548)
			(xy 324.981868 -248.192892) (xy 324.946375 -248.226984) (xy 324.905872 -248.25494) (xy 324.86141 -248.276038)
			(xy 324.814139 -248.28973) (xy 324.765284 -248.295662) (xy 324.716109 -248.293681) (xy 324.66789 -248.283837)
			(xy 324.621874 -248.266385) (xy 324.579253 -248.241778) (xy 324.541132 -248.210653) (xy 324.508497 -248.173816)
			(xy 324.482194 -248.13222) (xy 324.462903 -248.086944) (xy 324.451126 -248.03916) (xy 324.447166 -247.990106)
			(xy 310.45912 -247.990106) (xy 310.45912 -248.534174) (xy 326.045334 -248.534174) (xy 326.049294 -248.48512)
			(xy 326.061071 -248.437336) (xy 326.080362 -248.39206) (xy 326.106665 -248.350464) (xy 326.1393 -248.313627)
			(xy 326.177421 -248.282502) (xy 326.220042 -248.257895) (xy 326.266058 -248.240443) (xy 326.314277 -248.230599)
			(xy 326.363452 -248.228618) (xy 326.412307 -248.23455) (xy 326.459578 -248.248242) (xy 326.50404 -248.26934)
			(xy 326.544543 -248.297296) (xy 326.580036 -248.331388) (xy 326.609601 -248.370732) (xy 326.632472 -248.414309)
			(xy 326.648056 -248.46099) (xy 326.655951 -248.509567) (xy 326.656446 -248.534174) (xy 327.925442 -248.534174)
			(xy 327.929402 -248.48512) (xy 327.941179 -248.437336) (xy 327.96047 -248.39206) (xy 327.986773 -248.350464)
			(xy 328.019408 -248.313627) (xy 328.057529 -248.282502) (xy 328.10015 -248.257895) (xy 328.146166 -248.240443)
			(xy 328.194385 -248.230599) (xy 328.24356 -248.228618) (xy 328.292415 -248.23455) (xy 328.339686 -248.248242)
			(xy 328.384148 -248.26934) (xy 328.424651 -248.297296) (xy 328.460144 -248.331388) (xy 328.489709 -248.370732)
			(xy 328.51258 -248.414309) (xy 328.528164 -248.46099) (xy 328.536059 -248.509567) (xy 328.536554 -248.534174)
			(xy 328.854811 -248.534174) (xy 328.858906 -248.483446) (xy 328.871085 -248.434032) (xy 328.891033 -248.387212)
			(xy 328.918234 -248.344198) (xy 328.951982 -248.306104) (xy 328.991404 -248.273917) (xy 329.035478 -248.248471)
			(xy 329.083064 -248.230424) (xy 329.132928 -248.220244) (xy 329.18378 -248.218195) (xy 329.234301 -248.224329)
			(xy 329.283185 -248.238489) (xy 329.329164 -248.260306) (xy 329.371048 -248.289216) (xy 329.407752 -248.324471)
			(xy 329.438325 -248.365157) (xy 329.461976 -248.41022) (xy 329.478092 -248.458494) (xy 329.486256 -248.508728)
			(xy 329.486768 -248.534174) (xy 329.794865 -248.534174) (xy 329.79896 -248.483446) (xy 329.811139 -248.434032)
			(xy 329.831087 -248.387212) (xy 329.858288 -248.344198) (xy 329.892036 -248.306104) (xy 329.931458 -248.273917)
			(xy 329.975532 -248.248471) (xy 330.023118 -248.230424) (xy 330.072982 -248.220244) (xy 330.123834 -248.218195)
			(xy 330.174355 -248.224329) (xy 330.223239 -248.238489) (xy 330.269218 -248.260306) (xy 330.311102 -248.289216)
			(xy 330.347806 -248.324471) (xy 330.378379 -248.365157) (xy 330.40203 -248.41022) (xy 330.418146 -248.458494)
			(xy 330.42631 -248.508728) (xy 330.426822 -248.534174) (xy 330.74535 -248.534174) (xy 330.74931 -248.48512)
			(xy 330.761087 -248.437336) (xy 330.780378 -248.39206) (xy 330.806681 -248.350464) (xy 330.839316 -248.313627)
			(xy 330.877437 -248.282502) (xy 330.920058 -248.257895) (xy 330.966074 -248.240443) (xy 331.014293 -248.230599)
			(xy 331.063468 -248.228618) (xy 331.112323 -248.23455) (xy 331.159594 -248.248242) (xy 331.204056 -248.26934)
			(xy 331.244559 -248.297296) (xy 331.280052 -248.331388) (xy 331.309617 -248.370732) (xy 331.332488 -248.414309)
			(xy 331.348072 -248.46099) (xy 331.355967 -248.509567) (xy 331.356462 -248.534174) (xy 331.674973 -248.534174)
			(xy 331.679068 -248.483446) (xy 331.691247 -248.434032) (xy 331.711195 -248.387212) (xy 331.738396 -248.344198)
			(xy 331.772144 -248.306104) (xy 331.811566 -248.273917) (xy 331.85564 -248.248471) (xy 331.903226 -248.230424)
			(xy 331.95309 -248.220244) (xy 332.003942 -248.218195) (xy 332.054463 -248.224329) (xy 332.103347 -248.238489)
			(xy 332.149326 -248.260306) (xy 332.19121 -248.289216) (xy 332.227914 -248.324471) (xy 332.258487 -248.365157)
			(xy 332.282138 -248.41022) (xy 332.298254 -248.458494) (xy 332.306418 -248.508728) (xy 332.30693 -248.534174)
			(xy 332.625204 -248.534174) (xy 332.629164 -248.48512) (xy 332.640941 -248.437336) (xy 332.660232 -248.39206)
			(xy 332.686535 -248.350464) (xy 332.71917 -248.313627) (xy 332.757291 -248.282502) (xy 332.799912 -248.257895)
			(xy 332.845928 -248.240443) (xy 332.894147 -248.230599) (xy 332.943322 -248.228618) (xy 332.992177 -248.23455)
			(xy 333.039448 -248.248242) (xy 333.08391 -248.26934) (xy 333.124413 -248.297296) (xy 333.159906 -248.331388)
			(xy 333.189471 -248.370732) (xy 333.212342 -248.414309) (xy 333.227926 -248.46099) (xy 333.235821 -248.509567)
			(xy 333.236316 -248.534174) (xy 333.554827 -248.534174) (xy 333.558922 -248.483446) (xy 333.571101 -248.434032)
			(xy 333.591049 -248.387212) (xy 333.61825 -248.344198) (xy 333.651998 -248.306104) (xy 333.69142 -248.273917)
			(xy 333.735494 -248.248471) (xy 333.78308 -248.230424) (xy 333.832944 -248.220244) (xy 333.883796 -248.218195)
			(xy 333.934317 -248.224329) (xy 333.983201 -248.238489) (xy 334.02918 -248.260306) (xy 334.071064 -248.289216)
			(xy 334.107768 -248.324471) (xy 334.138341 -248.365157) (xy 334.161992 -248.41022) (xy 334.178108 -248.458494)
			(xy 334.186272 -248.508728) (xy 334.186784 -248.534174) (xy 334.505312 -248.534174) (xy 334.509272 -248.48512)
			(xy 334.521049 -248.437336) (xy 334.54034 -248.39206) (xy 334.566643 -248.350464) (xy 334.599278 -248.313627)
			(xy 334.637399 -248.282502) (xy 334.68002 -248.257895) (xy 334.726036 -248.240443) (xy 334.774255 -248.230599)
			(xy 334.82343 -248.228618) (xy 334.872285 -248.23455) (xy 334.919556 -248.248242) (xy 334.964018 -248.26934)
			(xy 335.004521 -248.297296) (xy 335.040014 -248.331388) (xy 335.069579 -248.370732) (xy 335.09245 -248.414309)
			(xy 335.108034 -248.46099) (xy 335.115929 -248.509567) (xy 335.116424 -248.534174) (xy 335.434935 -248.534174)
			(xy 335.43903 -248.483446) (xy 335.451209 -248.434032) (xy 335.471157 -248.387212) (xy 335.498358 -248.344198)
			(xy 335.532106 -248.306104) (xy 335.571528 -248.273917) (xy 335.615602 -248.248471) (xy 335.663188 -248.230424)
			(xy 335.713052 -248.220244) (xy 335.763904 -248.218195) (xy 335.814425 -248.224329) (xy 335.863309 -248.238489)
			(xy 335.909288 -248.260306) (xy 335.951172 -248.289216) (xy 335.987876 -248.324471) (xy 336.018449 -248.365157)
			(xy 336.0421 -248.41022) (xy 336.058216 -248.458494) (xy 336.06638 -248.508728) (xy 336.066892 -248.534174)
			(xy 336.374989 -248.534174) (xy 336.379084 -248.483446) (xy 336.391263 -248.434032) (xy 336.411211 -248.387212)
			(xy 336.438412 -248.344198) (xy 336.47216 -248.306104) (xy 336.511582 -248.273917) (xy 336.555656 -248.248471)
			(xy 336.603242 -248.230424) (xy 336.653106 -248.220244) (xy 336.703958 -248.218195) (xy 336.754479 -248.224329)
			(xy 336.803363 -248.238489) (xy 336.849342 -248.260306) (xy 336.891226 -248.289216) (xy 336.92793 -248.324471)
			(xy 336.958503 -248.365157) (xy 336.982154 -248.41022) (xy 336.99827 -248.458494) (xy 337.006434 -248.508728)
			(xy 337.006946 -248.534174) (xy 337.32522 -248.534174) (xy 337.32918 -248.48512) (xy 337.340957 -248.437336)
			(xy 337.360248 -248.39206) (xy 337.386551 -248.350464) (xy 337.419186 -248.313627) (xy 337.457307 -248.282502)
			(xy 337.499928 -248.257895) (xy 337.545944 -248.240443) (xy 337.594163 -248.230599) (xy 337.643338 -248.228618)
			(xy 337.692193 -248.23455) (xy 337.739464 -248.248242) (xy 337.783926 -248.26934) (xy 337.824429 -248.297296)
			(xy 337.859922 -248.331388) (xy 337.889487 -248.370732) (xy 337.912358 -248.414309) (xy 337.927942 -248.46099)
			(xy 337.935837 -248.509567) (xy 337.936332 -248.534174) (xy 338.254843 -248.534174) (xy 338.258938 -248.483446)
			(xy 338.271117 -248.434032) (xy 338.291065 -248.387212) (xy 338.318266 -248.344198) (xy 338.352014 -248.306104)
			(xy 338.391436 -248.273917) (xy 338.43551 -248.248471) (xy 338.483096 -248.230424) (xy 338.53296 -248.220244)
			(xy 338.583812 -248.218195) (xy 338.634333 -248.224329) (xy 338.683217 -248.238489) (xy 338.729196 -248.260306)
			(xy 338.77108 -248.289216) (xy 338.807784 -248.324471) (xy 338.838357 -248.365157) (xy 338.862008 -248.41022)
			(xy 338.878124 -248.458494) (xy 338.886288 -248.508728) (xy 338.8868 -248.534174) (xy 339.205328 -248.534174)
			(xy 339.209288 -248.48512) (xy 339.221065 -248.437336) (xy 339.240356 -248.39206) (xy 339.266659 -248.350464)
			(xy 339.299294 -248.313627) (xy 339.337415 -248.282502) (xy 339.380036 -248.257895) (xy 339.426052 -248.240443)
			(xy 339.474271 -248.230599) (xy 339.523446 -248.228618) (xy 339.572301 -248.23455) (xy 339.619572 -248.248242)
			(xy 339.664034 -248.26934) (xy 339.704537 -248.297296) (xy 339.74003 -248.331388) (xy 339.769595 -248.370732)
			(xy 339.792466 -248.414309) (xy 339.80805 -248.46099) (xy 339.815945 -248.509567) (xy 339.81644 -248.534174)
			(xy 340.134951 -248.534174) (xy 340.139046 -248.483446) (xy 340.151225 -248.434032) (xy 340.171173 -248.387212)
			(xy 340.198374 -248.344198) (xy 340.232122 -248.306104) (xy 340.271544 -248.273917) (xy 340.315618 -248.248471)
			(xy 340.363204 -248.230424) (xy 340.413068 -248.220244) (xy 340.46392 -248.218195) (xy 340.514441 -248.224329)
			(xy 340.563325 -248.238489) (xy 340.609304 -248.260306) (xy 340.651188 -248.289216) (xy 340.687892 -248.324471)
			(xy 340.718465 -248.365157) (xy 340.742116 -248.41022) (xy 340.758232 -248.458494) (xy 340.766396 -248.508728)
			(xy 340.766908 -248.534174) (xy 341.085182 -248.534174) (xy 341.089142 -248.48512) (xy 341.100919 -248.437336)
			(xy 341.12021 -248.39206) (xy 341.146513 -248.350464) (xy 341.179148 -248.313627) (xy 341.217269 -248.282502)
			(xy 341.25989 -248.257895) (xy 341.305906 -248.240443) (xy 341.354125 -248.230599) (xy 341.4033 -248.228618)
			(xy 341.452155 -248.23455) (xy 341.499426 -248.248242) (xy 341.543888 -248.26934) (xy 341.584391 -248.297296)
			(xy 341.619884 -248.331388) (xy 341.649449 -248.370732) (xy 341.67232 -248.414309) (xy 341.687904 -248.46099)
			(xy 341.695799 -248.509567) (xy 341.696294 -248.534174) (xy 342.014805 -248.534174) (xy 342.0189 -248.483446)
			(xy 342.031079 -248.434032) (xy 342.051027 -248.387212) (xy 342.078228 -248.344198) (xy 342.111976 -248.306104)
			(xy 342.151398 -248.273917) (xy 342.195472 -248.248471) (xy 342.243058 -248.230424) (xy 342.292922 -248.220244)
			(xy 342.343774 -248.218195) (xy 342.394295 -248.224329) (xy 342.443179 -248.238489) (xy 342.489158 -248.260306)
			(xy 342.531042 -248.289216) (xy 342.567746 -248.324471) (xy 342.598319 -248.365157) (xy 342.62197 -248.41022)
			(xy 342.638086 -248.458494) (xy 342.64625 -248.508728) (xy 342.646762 -248.534174) (xy 342.954859 -248.534174)
			(xy 342.958954 -248.483446) (xy 342.971133 -248.434032) (xy 342.991081 -248.387212) (xy 343.018282 -248.344198)
			(xy 343.05203 -248.306104) (xy 343.091452 -248.273917) (xy 343.135526 -248.248471) (xy 343.183112 -248.230424)
			(xy 343.232976 -248.220244) (xy 343.283828 -248.218195) (xy 343.334349 -248.224329) (xy 343.383233 -248.238489)
			(xy 343.429212 -248.260306) (xy 343.471096 -248.289216) (xy 343.5078 -248.324471) (xy 343.538373 -248.365157)
			(xy 343.562024 -248.41022) (xy 343.57814 -248.458494) (xy 343.586304 -248.508728) (xy 343.586816 -248.534174)
			(xy 343.905344 -248.534174) (xy 343.909304 -248.48512) (xy 343.921081 -248.437336) (xy 343.940372 -248.39206)
			(xy 343.966675 -248.350464) (xy 343.99931 -248.313627) (xy 344.037431 -248.282502) (xy 344.080052 -248.257895)
			(xy 344.126068 -248.240443) (xy 344.174287 -248.230599) (xy 344.223462 -248.228618) (xy 344.272317 -248.23455)
			(xy 344.319588 -248.248242) (xy 344.36405 -248.26934) (xy 344.404553 -248.297296) (xy 344.440046 -248.331388)
			(xy 344.469611 -248.370732) (xy 344.492482 -248.414309) (xy 344.508066 -248.46099) (xy 344.515961 -248.509567)
			(xy 344.516456 -248.534174) (xy 344.515961 -248.558781) (xy 344.508066 -248.607358) (xy 344.492482 -248.654039)
			(xy 344.469611 -248.697616) (xy 344.440046 -248.73696) (xy 344.404553 -248.771052) (xy 344.36405 -248.799008)
			(xy 344.319588 -248.820106) (xy 344.272317 -248.833798) (xy 344.223462 -248.83973) (xy 344.174287 -248.837749)
			(xy 344.126068 -248.827905) (xy 344.080052 -248.810453) (xy 344.037431 -248.785846) (xy 343.99931 -248.754721)
			(xy 343.966675 -248.717884) (xy 343.940372 -248.676288) (xy 343.921081 -248.631012) (xy 343.909304 -248.583228)
			(xy 343.905344 -248.534174) (xy 343.586816 -248.534174) (xy 343.586304 -248.55962) (xy 343.57814 -248.609854)
			(xy 343.562024 -248.658128) (xy 343.538373 -248.703191) (xy 343.5078 -248.743877) (xy 343.471096 -248.779132)
			(xy 343.429212 -248.808042) (xy 343.383233 -248.829859) (xy 343.334349 -248.844019) (xy 343.283828 -248.850153)
			(xy 343.232976 -248.848104) (xy 343.183112 -248.837924) (xy 343.135526 -248.819877) (xy 343.091452 -248.794431)
			(xy 343.05203 -248.762244) (xy 343.018282 -248.72415) (xy 342.991081 -248.681136) (xy 342.971133 -248.634316)
			(xy 342.958954 -248.584902) (xy 342.954859 -248.534174) (xy 342.646762 -248.534174) (xy 342.64625 -248.55962)
			(xy 342.638086 -248.609854) (xy 342.62197 -248.658128) (xy 342.598319 -248.703191) (xy 342.567746 -248.743877)
			(xy 342.531042 -248.779132) (xy 342.489158 -248.808042) (xy 342.443179 -248.829859) (xy 342.394295 -248.844019)
			(xy 342.343774 -248.850153) (xy 342.292922 -248.848104) (xy 342.243058 -248.837924) (xy 342.195472 -248.819877)
			(xy 342.151398 -248.794431) (xy 342.111976 -248.762244) (xy 342.078228 -248.72415) (xy 342.051027 -248.681136)
			(xy 342.031079 -248.634316) (xy 342.0189 -248.584902) (xy 342.014805 -248.534174) (xy 341.696294 -248.534174)
			(xy 341.695799 -248.558781) (xy 341.687904 -248.607358) (xy 341.67232 -248.654039) (xy 341.649449 -248.697616)
			(xy 341.619884 -248.73696) (xy 341.584391 -248.771052) (xy 341.543888 -248.799008) (xy 341.499426 -248.820106)
			(xy 341.452155 -248.833798) (xy 341.4033 -248.83973) (xy 341.354125 -248.837749) (xy 341.305906 -248.827905)
			(xy 341.25989 -248.810453) (xy 341.217269 -248.785846) (xy 341.179148 -248.754721) (xy 341.146513 -248.717884)
			(xy 341.12021 -248.676288) (xy 341.100919 -248.631012) (xy 341.089142 -248.583228) (xy 341.085182 -248.534174)
			(xy 340.766908 -248.534174) (xy 340.766396 -248.55962) (xy 340.758232 -248.609854) (xy 340.742116 -248.658128)
			(xy 340.718465 -248.703191) (xy 340.687892 -248.743877) (xy 340.651188 -248.779132) (xy 340.609304 -248.808042)
			(xy 340.563325 -248.829859) (xy 340.514441 -248.844019) (xy 340.46392 -248.850153) (xy 340.413068 -248.848104)
			(xy 340.363204 -248.837924) (xy 340.315618 -248.819877) (xy 340.271544 -248.794431) (xy 340.232122 -248.762244)
			(xy 340.198374 -248.72415) (xy 340.171173 -248.681136) (xy 340.151225 -248.634316) (xy 340.139046 -248.584902)
			(xy 340.134951 -248.534174) (xy 339.81644 -248.534174) (xy 339.815945 -248.558781) (xy 339.80805 -248.607358)
			(xy 339.792466 -248.654039) (xy 339.769595 -248.697616) (xy 339.74003 -248.73696) (xy 339.704537 -248.771052)
			(xy 339.664034 -248.799008) (xy 339.619572 -248.820106) (xy 339.572301 -248.833798) (xy 339.523446 -248.83973)
			(xy 339.474271 -248.837749) (xy 339.426052 -248.827905) (xy 339.380036 -248.810453) (xy 339.337415 -248.785846)
			(xy 339.299294 -248.754721) (xy 339.266659 -248.717884) (xy 339.240356 -248.676288) (xy 339.221065 -248.631012)
			(xy 339.209288 -248.583228) (xy 339.205328 -248.534174) (xy 338.8868 -248.534174) (xy 338.886288 -248.55962)
			(xy 338.878124 -248.609854) (xy 338.862008 -248.658128) (xy 338.838357 -248.703191) (xy 338.807784 -248.743877)
			(xy 338.77108 -248.779132) (xy 338.729196 -248.808042) (xy 338.683217 -248.829859) (xy 338.634333 -248.844019)
			(xy 338.583812 -248.850153) (xy 338.53296 -248.848104) (xy 338.483096 -248.837924) (xy 338.43551 -248.819877)
			(xy 338.391436 -248.794431) (xy 338.352014 -248.762244) (xy 338.318266 -248.72415) (xy 338.291065 -248.681136)
			(xy 338.271117 -248.634316) (xy 338.258938 -248.584902) (xy 338.254843 -248.534174) (xy 337.936332 -248.534174)
			(xy 337.935837 -248.558781) (xy 337.927942 -248.607358) (xy 337.912358 -248.654039) (xy 337.889487 -248.697616)
			(xy 337.859922 -248.73696) (xy 337.824429 -248.771052) (xy 337.783926 -248.799008) (xy 337.739464 -248.820106)
			(xy 337.692193 -248.833798) (xy 337.643338 -248.83973) (xy 337.594163 -248.837749) (xy 337.545944 -248.827905)
			(xy 337.499928 -248.810453) (xy 337.457307 -248.785846) (xy 337.419186 -248.754721) (xy 337.386551 -248.717884)
			(xy 337.360248 -248.676288) (xy 337.340957 -248.631012) (xy 337.32918 -248.583228) (xy 337.32522 -248.534174)
			(xy 337.006946 -248.534174) (xy 337.006434 -248.55962) (xy 336.99827 -248.609854) (xy 336.982154 -248.658128)
			(xy 336.958503 -248.703191) (xy 336.92793 -248.743877) (xy 336.891226 -248.779132) (xy 336.849342 -248.808042)
			(xy 336.803363 -248.829859) (xy 336.754479 -248.844019) (xy 336.703958 -248.850153) (xy 336.653106 -248.848104)
			(xy 336.603242 -248.837924) (xy 336.555656 -248.819877) (xy 336.511582 -248.794431) (xy 336.47216 -248.762244)
			(xy 336.438412 -248.72415) (xy 336.411211 -248.681136) (xy 336.391263 -248.634316) (xy 336.379084 -248.584902)
			(xy 336.374989 -248.534174) (xy 336.066892 -248.534174) (xy 336.06638 -248.55962) (xy 336.058216 -248.609854)
			(xy 336.0421 -248.658128) (xy 336.018449 -248.703191) (xy 335.987876 -248.743877) (xy 335.951172 -248.779132)
			(xy 335.909288 -248.808042) (xy 335.863309 -248.829859) (xy 335.814425 -248.844019) (xy 335.763904 -248.850153)
			(xy 335.713052 -248.848104) (xy 335.663188 -248.837924) (xy 335.615602 -248.819877) (xy 335.571528 -248.794431)
			(xy 335.532106 -248.762244) (xy 335.498358 -248.72415) (xy 335.471157 -248.681136) (xy 335.451209 -248.634316)
			(xy 335.43903 -248.584902) (xy 335.434935 -248.534174) (xy 335.116424 -248.534174) (xy 335.115929 -248.558781)
			(xy 335.108034 -248.607358) (xy 335.09245 -248.654039) (xy 335.069579 -248.697616) (xy 335.040014 -248.73696)
			(xy 335.004521 -248.771052) (xy 334.964018 -248.799008) (xy 334.919556 -248.820106) (xy 334.872285 -248.833798)
			(xy 334.82343 -248.83973) (xy 334.774255 -248.837749) (xy 334.726036 -248.827905) (xy 334.68002 -248.810453)
			(xy 334.637399 -248.785846) (xy 334.599278 -248.754721) (xy 334.566643 -248.717884) (xy 334.54034 -248.676288)
			(xy 334.521049 -248.631012) (xy 334.509272 -248.583228) (xy 334.505312 -248.534174) (xy 334.186784 -248.534174)
			(xy 334.186272 -248.55962) (xy 334.178108 -248.609854) (xy 334.161992 -248.658128) (xy 334.138341 -248.703191)
			(xy 334.107768 -248.743877) (xy 334.071064 -248.779132) (xy 334.02918 -248.808042) (xy 333.983201 -248.829859)
			(xy 333.934317 -248.844019) (xy 333.883796 -248.850153) (xy 333.832944 -248.848104) (xy 333.78308 -248.837924)
			(xy 333.735494 -248.819877) (xy 333.69142 -248.794431) (xy 333.651998 -248.762244) (xy 333.61825 -248.72415)
			(xy 333.591049 -248.681136) (xy 333.571101 -248.634316) (xy 333.558922 -248.584902) (xy 333.554827 -248.534174)
			(xy 333.236316 -248.534174) (xy 333.235821 -248.558781) (xy 333.227926 -248.607358) (xy 333.212342 -248.654039)
			(xy 333.189471 -248.697616) (xy 333.159906 -248.73696) (xy 333.124413 -248.771052) (xy 333.08391 -248.799008)
			(xy 333.039448 -248.820106) (xy 332.992177 -248.833798) (xy 332.943322 -248.83973) (xy 332.894147 -248.837749)
			(xy 332.845928 -248.827905) (xy 332.799912 -248.810453) (xy 332.757291 -248.785846) (xy 332.71917 -248.754721)
			(xy 332.686535 -248.717884) (xy 332.660232 -248.676288) (xy 332.640941 -248.631012) (xy 332.629164 -248.583228)
			(xy 332.625204 -248.534174) (xy 332.30693 -248.534174) (xy 332.306418 -248.55962) (xy 332.298254 -248.609854)
			(xy 332.282138 -248.658128) (xy 332.258487 -248.703191) (xy 332.227914 -248.743877) (xy 332.19121 -248.779132)
			(xy 332.149326 -248.808042) (xy 332.103347 -248.829859) (xy 332.054463 -248.844019) (xy 332.003942 -248.850153)
			(xy 331.95309 -248.848104) (xy 331.903226 -248.837924) (xy 331.85564 -248.819877) (xy 331.811566 -248.794431)
			(xy 331.772144 -248.762244) (xy 331.738396 -248.72415) (xy 331.711195 -248.681136) (xy 331.691247 -248.634316)
			(xy 331.679068 -248.584902) (xy 331.674973 -248.534174) (xy 331.356462 -248.534174) (xy 331.355967 -248.558781)
			(xy 331.348072 -248.607358) (xy 331.332488 -248.654039) (xy 331.309617 -248.697616) (xy 331.280052 -248.73696)
			(xy 331.244559 -248.771052) (xy 331.204056 -248.799008) (xy 331.159594 -248.820106) (xy 331.112323 -248.833798)
			(xy 331.063468 -248.83973) (xy 331.014293 -248.837749) (xy 330.966074 -248.827905) (xy 330.920058 -248.810453)
			(xy 330.877437 -248.785846) (xy 330.839316 -248.754721) (xy 330.806681 -248.717884) (xy 330.780378 -248.676288)
			(xy 330.761087 -248.631012) (xy 330.74931 -248.583228) (xy 330.74535 -248.534174) (xy 330.426822 -248.534174)
			(xy 330.42631 -248.55962) (xy 330.418146 -248.609854) (xy 330.40203 -248.658128) (xy 330.378379 -248.703191)
			(xy 330.347806 -248.743877) (xy 330.311102 -248.779132) (xy 330.269218 -248.808042) (xy 330.223239 -248.829859)
			(xy 330.174355 -248.844019) (xy 330.123834 -248.850153) (xy 330.072982 -248.848104) (xy 330.023118 -248.837924)
			(xy 329.975532 -248.819877) (xy 329.931458 -248.794431) (xy 329.892036 -248.762244) (xy 329.858288 -248.72415)
			(xy 329.831087 -248.681136) (xy 329.811139 -248.634316) (xy 329.79896 -248.584902) (xy 329.794865 -248.534174)
			(xy 329.486768 -248.534174) (xy 329.486256 -248.55962) (xy 329.478092 -248.609854) (xy 329.461976 -248.658128)
			(xy 329.438325 -248.703191) (xy 329.407752 -248.743877) (xy 329.371048 -248.779132) (xy 329.329164 -248.808042)
			(xy 329.283185 -248.829859) (xy 329.234301 -248.844019) (xy 329.18378 -248.850153) (xy 329.132928 -248.848104)
			(xy 329.083064 -248.837924) (xy 329.035478 -248.819877) (xy 328.991404 -248.794431) (xy 328.951982 -248.762244)
			(xy 328.918234 -248.72415) (xy 328.891033 -248.681136) (xy 328.871085 -248.634316) (xy 328.858906 -248.584902)
			(xy 328.854811 -248.534174) (xy 328.536554 -248.534174) (xy 328.536059 -248.558781) (xy 328.528164 -248.607358)
			(xy 328.51258 -248.654039) (xy 328.489709 -248.697616) (xy 328.460144 -248.73696) (xy 328.424651 -248.771052)
			(xy 328.384148 -248.799008) (xy 328.339686 -248.820106) (xy 328.292415 -248.833798) (xy 328.24356 -248.83973)
			(xy 328.194385 -248.837749) (xy 328.146166 -248.827905) (xy 328.10015 -248.810453) (xy 328.057529 -248.785846)
			(xy 328.019408 -248.754721) (xy 327.986773 -248.717884) (xy 327.96047 -248.676288) (xy 327.941179 -248.631012)
			(xy 327.929402 -248.583228) (xy 327.925442 -248.534174) (xy 326.656446 -248.534174) (xy 326.655951 -248.558781)
			(xy 326.648056 -248.607358) (xy 326.632472 -248.654039) (xy 326.609601 -248.697616) (xy 326.580036 -248.73696)
			(xy 326.544543 -248.771052) (xy 326.50404 -248.799008) (xy 326.459578 -248.820106) (xy 326.412307 -248.833798)
			(xy 326.363452 -248.83973) (xy 326.314277 -248.837749) (xy 326.266058 -248.827905) (xy 326.220042 -248.810453)
			(xy 326.177421 -248.785846) (xy 326.1393 -248.754721) (xy 326.106665 -248.717884) (xy 326.080362 -248.676288)
			(xy 326.061071 -248.631012) (xy 326.049294 -248.583228) (xy 326.045334 -248.534174) (xy 310.45912 -248.534174)
			(xy 310.45912 -249.610118) (xy 324.447166 -249.610118) (xy 324.451126 -249.561064) (xy 324.462903 -249.51328)
			(xy 324.482194 -249.468004) (xy 324.508497 -249.426408) (xy 324.541132 -249.389571) (xy 324.579253 -249.358446)
			(xy 324.621874 -249.333839) (xy 324.66789 -249.316387) (xy 324.716109 -249.306543) (xy 324.765284 -249.304562)
			(xy 324.814139 -249.310494) (xy 324.86141 -249.324186) (xy 324.903545 -249.34418) (xy 328.395342 -249.34418)
			(xy 328.399302 -249.295126) (xy 328.411079 -249.247342) (xy 328.43037 -249.202066) (xy 328.456673 -249.16047)
			(xy 328.489308 -249.123633) (xy 328.527429 -249.092508) (xy 328.57005 -249.067901) (xy 328.616066 -249.050449)
			(xy 328.664285 -249.040605) (xy 328.71346 -249.038624) (xy 328.762315 -249.044556) (xy 328.809586 -249.058248)
			(xy 328.854048 -249.079346) (xy 328.894551 -249.107302) (xy 328.930044 -249.141394) (xy 328.959609 -249.180738)
			(xy 328.98248 -249.224315) (xy 328.998064 -249.270996) (xy 329.005959 -249.319573) (xy 329.006454 -249.34418)
			(xy 329.335396 -249.34418) (xy 329.339356 -249.295126) (xy 329.351133 -249.247342) (xy 329.370424 -249.202066)
			(xy 329.396727 -249.16047) (xy 329.429362 -249.123633) (xy 329.467483 -249.092508) (xy 329.510104 -249.067901)
			(xy 329.55612 -249.050449) (xy 329.604339 -249.040605) (xy 329.653514 -249.038624) (xy 329.702369 -249.044556)
			(xy 329.74964 -249.058248) (xy 329.794102 -249.079346) (xy 329.834605 -249.107302) (xy 329.870098 -249.141394)
			(xy 329.899663 -249.180738) (xy 329.922534 -249.224315) (xy 329.938118 -249.270996) (xy 329.946013 -249.319573)
			(xy 329.946508 -249.34418) (xy 330.264765 -249.34418) (xy 330.26886 -249.293452) (xy 330.281039 -249.244038)
			(xy 330.300987 -249.197218) (xy 330.328188 -249.154204) (xy 330.361936 -249.11611) (xy 330.401358 -249.083923)
			(xy 330.445432 -249.058477) (xy 330.493018 -249.04043) (xy 330.542882 -249.03025) (xy 330.593734 -249.028201)
			(xy 330.644255 -249.034335) (xy 330.693139 -249.048495) (xy 330.739118 -249.070312) (xy 330.781002 -249.099222)
			(xy 330.817706 -249.134477) (xy 330.848279 -249.175163) (xy 330.87193 -249.220226) (xy 330.888046 -249.2685)
			(xy 330.89621 -249.318734) (xy 330.896722 -249.34418) (xy 331.21525 -249.34418) (xy 331.21921 -249.295126)
			(xy 331.230987 -249.247342) (xy 331.250278 -249.202066) (xy 331.276581 -249.16047) (xy 331.309216 -249.123633)
			(xy 331.347337 -249.092508) (xy 331.389958 -249.067901) (xy 331.435974 -249.050449) (xy 331.484193 -249.040605)
			(xy 331.533368 -249.038624) (xy 331.582223 -249.044556) (xy 331.629494 -249.058248) (xy 331.673956 -249.079346)
			(xy 331.714459 -249.107302) (xy 331.749952 -249.141394) (xy 331.779517 -249.180738) (xy 331.802388 -249.224315)
			(xy 331.817972 -249.270996) (xy 331.825867 -249.319573) (xy 331.826362 -249.34418) (xy 332.155304 -249.34418)
			(xy 332.159264 -249.295126) (xy 332.171041 -249.247342) (xy 332.190332 -249.202066) (xy 332.216635 -249.16047)
			(xy 332.24927 -249.123633) (xy 332.287391 -249.092508) (xy 332.330012 -249.067901) (xy 332.376028 -249.050449)
			(xy 332.424247 -249.040605) (xy 332.473422 -249.038624) (xy 332.522277 -249.044556) (xy 332.569548 -249.058248)
			(xy 332.61401 -249.079346) (xy 332.654513 -249.107302) (xy 332.690006 -249.141394) (xy 332.719571 -249.180738)
			(xy 332.742442 -249.224315) (xy 332.758026 -249.270996) (xy 332.765921 -249.319573) (xy 332.766416 -249.34418)
			(xy 333.084927 -249.34418) (xy 333.089022 -249.293452) (xy 333.101201 -249.244038) (xy 333.121149 -249.197218)
			(xy 333.14835 -249.154204) (xy 333.182098 -249.11611) (xy 333.22152 -249.083923) (xy 333.265594 -249.058477)
			(xy 333.31318 -249.04043) (xy 333.363044 -249.03025) (xy 333.413896 -249.028201) (xy 333.464417 -249.034335)
			(xy 333.513301 -249.048495) (xy 333.55928 -249.070312) (xy 333.601164 -249.099222) (xy 333.637868 -249.134477)
			(xy 333.668441 -249.175163) (xy 333.692092 -249.220226) (xy 333.708208 -249.2685) (xy 333.716372 -249.318734)
			(xy 333.716884 -249.34418) (xy 334.975212 -249.34418) (xy 334.979172 -249.295126) (xy 334.990949 -249.247342)
			(xy 335.01024 -249.202066) (xy 335.036543 -249.16047) (xy 335.069178 -249.123633) (xy 335.107299 -249.092508)
			(xy 335.14992 -249.067901) (xy 335.195936 -249.050449) (xy 335.244155 -249.040605) (xy 335.29333 -249.038624)
			(xy 335.342185 -249.044556) (xy 335.389456 -249.058248) (xy 335.433918 -249.079346) (xy 335.474421 -249.107302)
			(xy 335.509914 -249.141394) (xy 335.539479 -249.180738) (xy 335.56235 -249.224315) (xy 335.577934 -249.270996)
			(xy 335.585829 -249.319573) (xy 335.586324 -249.34418) (xy 335.915266 -249.34418) (xy 335.919226 -249.295126)
			(xy 335.931003 -249.247342) (xy 335.950294 -249.202066) (xy 335.976597 -249.16047) (xy 336.009232 -249.123633)
			(xy 336.047353 -249.092508) (xy 336.089974 -249.067901) (xy 336.13599 -249.050449) (xy 336.184209 -249.040605)
			(xy 336.233384 -249.038624) (xy 336.282239 -249.044556) (xy 336.32951 -249.058248) (xy 336.373972 -249.079346)
			(xy 336.414475 -249.107302) (xy 336.449968 -249.141394) (xy 336.479533 -249.180738) (xy 336.502404 -249.224315)
			(xy 336.517988 -249.270996) (xy 336.525883 -249.319573) (xy 336.526378 -249.34418) (xy 336.844889 -249.34418)
			(xy 336.848984 -249.293452) (xy 336.861163 -249.244038) (xy 336.881111 -249.197218) (xy 336.908312 -249.154204)
			(xy 336.94206 -249.11611) (xy 336.981482 -249.083923) (xy 337.025556 -249.058477) (xy 337.073142 -249.04043)
			(xy 337.123006 -249.03025) (xy 337.173858 -249.028201) (xy 337.224379 -249.034335) (xy 337.273263 -249.048495)
			(xy 337.319242 -249.070312) (xy 337.361126 -249.099222) (xy 337.39783 -249.134477) (xy 337.428403 -249.175163)
			(xy 337.452054 -249.220226) (xy 337.46817 -249.2685) (xy 337.476334 -249.318734) (xy 337.476846 -249.34418)
			(xy 337.795374 -249.34418) (xy 337.799334 -249.295126) (xy 337.811111 -249.247342) (xy 337.830402 -249.202066)
			(xy 337.856705 -249.16047) (xy 337.88934 -249.123633) (xy 337.927461 -249.092508) (xy 337.970082 -249.067901)
			(xy 338.016098 -249.050449) (xy 338.064317 -249.040605) (xy 338.113492 -249.038624) (xy 338.162347 -249.044556)
			(xy 338.209618 -249.058248) (xy 338.25408 -249.079346) (xy 338.294583 -249.107302) (xy 338.330076 -249.141394)
			(xy 338.359641 -249.180738) (xy 338.382512 -249.224315) (xy 338.398096 -249.270996) (xy 338.405991 -249.319573)
			(xy 338.406486 -249.34418) (xy 338.735174 -249.34418) (xy 338.739134 -249.295126) (xy 338.750911 -249.247342)
			(xy 338.770202 -249.202066) (xy 338.796505 -249.16047) (xy 338.82914 -249.123633) (xy 338.867261 -249.092508)
			(xy 338.909882 -249.067901) (xy 338.955898 -249.050449) (xy 339.004117 -249.040605) (xy 339.053292 -249.038624)
			(xy 339.102147 -249.044556) (xy 339.149418 -249.058248) (xy 339.19388 -249.079346) (xy 339.234383 -249.107302)
			(xy 339.269876 -249.141394) (xy 339.299441 -249.180738) (xy 339.322312 -249.224315) (xy 339.337896 -249.270996)
			(xy 339.345791 -249.319573) (xy 339.346286 -249.34418) (xy 339.664797 -249.34418) (xy 339.668892 -249.293452)
			(xy 339.681071 -249.244038) (xy 339.701019 -249.197218) (xy 339.72822 -249.154204) (xy 339.761968 -249.11611)
			(xy 339.80139 -249.083923) (xy 339.845464 -249.058477) (xy 339.89305 -249.04043) (xy 339.942914 -249.03025)
			(xy 339.993766 -249.028201) (xy 340.044287 -249.034335) (xy 340.093171 -249.048495) (xy 340.13915 -249.070312)
			(xy 340.181034 -249.099222) (xy 340.217738 -249.134477) (xy 340.248311 -249.175163) (xy 340.271962 -249.220226)
			(xy 340.288078 -249.2685) (xy 340.296242 -249.318734) (xy 340.296754 -249.34418) (xy 341.555336 -249.34418)
			(xy 341.559296 -249.295126) (xy 341.571073 -249.247342) (xy 341.590364 -249.202066) (xy 341.616667 -249.16047)
			(xy 341.649302 -249.123633) (xy 341.687423 -249.092508) (xy 341.730044 -249.067901) (xy 341.77606 -249.050449)
			(xy 341.824279 -249.040605) (xy 341.873454 -249.038624) (xy 341.922309 -249.044556) (xy 341.96958 -249.058248)
			(xy 342.014042 -249.079346) (xy 342.054545 -249.107302) (xy 342.090038 -249.141394) (xy 342.119603 -249.180738)
			(xy 342.142474 -249.224315) (xy 342.158058 -249.270996) (xy 342.165953 -249.319573) (xy 342.166448 -249.34418)
			(xy 342.49539 -249.34418) (xy 342.49935 -249.295126) (xy 342.511127 -249.247342) (xy 342.530418 -249.202066)
			(xy 342.556721 -249.16047) (xy 342.589356 -249.123633) (xy 342.627477 -249.092508) (xy 342.670098 -249.067901)
			(xy 342.716114 -249.050449) (xy 342.764333 -249.040605) (xy 342.813508 -249.038624) (xy 342.862363 -249.044556)
			(xy 342.909634 -249.058248) (xy 342.954096 -249.079346) (xy 342.994599 -249.107302) (xy 343.030092 -249.141394)
			(xy 343.059657 -249.180738) (xy 343.082528 -249.224315) (xy 343.098112 -249.270996) (xy 343.106007 -249.319573)
			(xy 343.106502 -249.34418) (xy 343.424759 -249.34418) (xy 343.428854 -249.293452) (xy 343.441033 -249.244038)
			(xy 343.460981 -249.197218) (xy 343.488182 -249.154204) (xy 343.52193 -249.11611) (xy 343.561352 -249.083923)
			(xy 343.605426 -249.058477) (xy 343.653012 -249.04043) (xy 343.702876 -249.03025) (xy 343.753728 -249.028201)
			(xy 343.804249 -249.034335) (xy 343.853133 -249.048495) (xy 343.899112 -249.070312) (xy 343.940996 -249.099222)
			(xy 343.9777 -249.134477) (xy 344.008273 -249.175163) (xy 344.031924 -249.220226) (xy 344.04804 -249.2685)
			(xy 344.056204 -249.318734) (xy 344.056716 -249.34418) (xy 344.056204 -249.369626) (xy 344.04804 -249.41986)
			(xy 344.031924 -249.468134) (xy 344.008273 -249.513197) (xy 343.9777 -249.553883) (xy 343.940996 -249.589138)
			(xy 343.899112 -249.618048) (xy 343.853133 -249.639865) (xy 343.804249 -249.654025) (xy 343.753728 -249.660159)
			(xy 343.702876 -249.65811) (xy 343.653012 -249.64793) (xy 343.605426 -249.629883) (xy 343.561352 -249.604437)
			(xy 343.52193 -249.57225) (xy 343.488182 -249.534156) (xy 343.460981 -249.491142) (xy 343.441033 -249.444322)
			(xy 343.428854 -249.394908) (xy 343.424759 -249.34418) (xy 343.106502 -249.34418) (xy 343.106007 -249.368787)
			(xy 343.098112 -249.417364) (xy 343.082528 -249.464045) (xy 343.059657 -249.507622) (xy 343.030092 -249.546966)
			(xy 342.994599 -249.581058) (xy 342.954096 -249.609014) (xy 342.909634 -249.630112) (xy 342.862363 -249.643804)
			(xy 342.813508 -249.649736) (xy 342.764333 -249.647755) (xy 342.716114 -249.637911) (xy 342.670098 -249.620459)
			(xy 342.627477 -249.595852) (xy 342.589356 -249.564727) (xy 342.556721 -249.52789) (xy 342.530418 -249.486294)
			(xy 342.511127 -249.441018) (xy 342.49935 -249.393234) (xy 342.49539 -249.34418) (xy 342.166448 -249.34418)
			(xy 342.165953 -249.368787) (xy 342.158058 -249.417364) (xy 342.142474 -249.464045) (xy 342.119603 -249.507622)
			(xy 342.090038 -249.546966) (xy 342.054545 -249.581058) (xy 342.014042 -249.609014) (xy 341.96958 -249.630112)
			(xy 341.922309 -249.643804) (xy 341.873454 -249.649736) (xy 341.824279 -249.647755) (xy 341.77606 -249.637911)
			(xy 341.730044 -249.620459) (xy 341.687423 -249.595852) (xy 341.649302 -249.564727) (xy 341.616667 -249.52789)
			(xy 341.590364 -249.486294) (xy 341.571073 -249.441018) (xy 341.559296 -249.393234) (xy 341.555336 -249.34418)
			(xy 340.296754 -249.34418) (xy 340.296242 -249.369626) (xy 340.288078 -249.41986) (xy 340.271962 -249.468134)
			(xy 340.248311 -249.513197) (xy 340.217738 -249.553883) (xy 340.181034 -249.589138) (xy 340.13915 -249.618048)
			(xy 340.093171 -249.639865) (xy 340.044287 -249.654025) (xy 339.993766 -249.660159) (xy 339.942914 -249.65811)
			(xy 339.89305 -249.64793) (xy 339.845464 -249.629883) (xy 339.80139 -249.604437) (xy 339.761968 -249.57225)
			(xy 339.72822 -249.534156) (xy 339.701019 -249.491142) (xy 339.681071 -249.444322) (xy 339.668892 -249.394908)
			(xy 339.664797 -249.34418) (xy 339.346286 -249.34418) (xy 339.345791 -249.368787) (xy 339.337896 -249.417364)
			(xy 339.322312 -249.464045) (xy 339.299441 -249.507622) (xy 339.269876 -249.546966) (xy 339.234383 -249.581058)
			(xy 339.19388 -249.609014) (xy 339.149418 -249.630112) (xy 339.102147 -249.643804) (xy 339.053292 -249.649736)
			(xy 339.004117 -249.647755) (xy 338.955898 -249.637911) (xy 338.909882 -249.620459) (xy 338.867261 -249.595852)
			(xy 338.82914 -249.564727) (xy 338.796505 -249.52789) (xy 338.770202 -249.486294) (xy 338.750911 -249.441018)
			(xy 338.739134 -249.393234) (xy 338.735174 -249.34418) (xy 338.406486 -249.34418) (xy 338.405991 -249.368787)
			(xy 338.398096 -249.417364) (xy 338.382512 -249.464045) (xy 338.359641 -249.507622) (xy 338.330076 -249.546966)
			(xy 338.294583 -249.581058) (xy 338.25408 -249.609014) (xy 338.209618 -249.630112) (xy 338.162347 -249.643804)
			(xy 338.113492 -249.649736) (xy 338.064317 -249.647755) (xy 338.016098 -249.637911) (xy 337.970082 -249.620459)
			(xy 337.927461 -249.595852) (xy 337.88934 -249.564727) (xy 337.856705 -249.52789) (xy 337.830402 -249.486294)
			(xy 337.811111 -249.441018) (xy 337.799334 -249.393234) (xy 337.795374 -249.34418) (xy 337.476846 -249.34418)
			(xy 337.476334 -249.369626) (xy 337.46817 -249.41986) (xy 337.452054 -249.468134) (xy 337.428403 -249.513197)
			(xy 337.39783 -249.553883) (xy 337.361126 -249.589138) (xy 337.319242 -249.618048) (xy 337.273263 -249.639865)
			(xy 337.224379 -249.654025) (xy 337.173858 -249.660159) (xy 337.123006 -249.65811) (xy 337.073142 -249.64793)
			(xy 337.025556 -249.629883) (xy 336.981482 -249.604437) (xy 336.94206 -249.57225) (xy 336.908312 -249.534156)
			(xy 336.881111 -249.491142) (xy 336.861163 -249.444322) (xy 336.848984 -249.394908) (xy 336.844889 -249.34418)
			(xy 336.526378 -249.34418) (xy 336.525883 -249.368787) (xy 336.517988 -249.417364) (xy 336.502404 -249.464045)
			(xy 336.479533 -249.507622) (xy 336.449968 -249.546966) (xy 336.414475 -249.581058) (xy 336.373972 -249.609014)
			(xy 336.32951 -249.630112) (xy 336.282239 -249.643804) (xy 336.233384 -249.649736) (xy 336.184209 -249.647755)
			(xy 336.13599 -249.637911) (xy 336.089974 -249.620459) (xy 336.047353 -249.595852) (xy 336.009232 -249.564727)
			(xy 335.976597 -249.52789) (xy 335.950294 -249.486294) (xy 335.931003 -249.441018) (xy 335.919226 -249.393234)
			(xy 335.915266 -249.34418) (xy 335.586324 -249.34418) (xy 335.585829 -249.368787) (xy 335.577934 -249.417364)
			(xy 335.56235 -249.464045) (xy 335.539479 -249.507622) (xy 335.509914 -249.546966) (xy 335.474421 -249.581058)
			(xy 335.433918 -249.609014) (xy 335.389456 -249.630112) (xy 335.342185 -249.643804) (xy 335.29333 -249.649736)
			(xy 335.244155 -249.647755) (xy 335.195936 -249.637911) (xy 335.14992 -249.620459) (xy 335.107299 -249.595852)
			(xy 335.069178 -249.564727) (xy 335.036543 -249.52789) (xy 335.01024 -249.486294) (xy 334.990949 -249.441018)
			(xy 334.979172 -249.393234) (xy 334.975212 -249.34418) (xy 333.716884 -249.34418) (xy 333.716372 -249.369626)
			(xy 333.708208 -249.41986) (xy 333.692092 -249.468134) (xy 333.668441 -249.513197) (xy 333.637868 -249.553883)
			(xy 333.601164 -249.589138) (xy 333.55928 -249.618048) (xy 333.513301 -249.639865) (xy 333.464417 -249.654025)
			(xy 333.413896 -249.660159) (xy 333.363044 -249.65811) (xy 333.31318 -249.64793) (xy 333.265594 -249.629883)
			(xy 333.22152 -249.604437) (xy 333.182098 -249.57225) (xy 333.14835 -249.534156) (xy 333.121149 -249.491142)
			(xy 333.101201 -249.444322) (xy 333.089022 -249.394908) (xy 333.084927 -249.34418) (xy 332.766416 -249.34418)
			(xy 332.765921 -249.368787) (xy 332.758026 -249.417364) (xy 332.742442 -249.464045) (xy 332.719571 -249.507622)
			(xy 332.690006 -249.546966) (xy 332.654513 -249.581058) (xy 332.61401 -249.609014) (xy 332.569548 -249.630112)
			(xy 332.522277 -249.643804) (xy 332.473422 -249.649736) (xy 332.424247 -249.647755) (xy 332.376028 -249.637911)
			(xy 332.330012 -249.620459) (xy 332.287391 -249.595852) (xy 332.24927 -249.564727) (xy 332.216635 -249.52789)
			(xy 332.190332 -249.486294) (xy 332.171041 -249.441018) (xy 332.159264 -249.393234) (xy 332.155304 -249.34418)
			(xy 331.826362 -249.34418) (xy 331.825867 -249.368787) (xy 331.817972 -249.417364) (xy 331.802388 -249.464045)
			(xy 331.779517 -249.507622) (xy 331.749952 -249.546966) (xy 331.714459 -249.581058) (xy 331.673956 -249.609014)
			(xy 331.629494 -249.630112) (xy 331.582223 -249.643804) (xy 331.533368 -249.649736) (xy 331.484193 -249.647755)
			(xy 331.435974 -249.637911) (xy 331.389958 -249.620459) (xy 331.347337 -249.595852) (xy 331.309216 -249.564727)
			(xy 331.276581 -249.52789) (xy 331.250278 -249.486294) (xy 331.230987 -249.441018) (xy 331.21921 -249.393234)
			(xy 331.21525 -249.34418) (xy 330.896722 -249.34418) (xy 330.89621 -249.369626) (xy 330.888046 -249.41986)
			(xy 330.87193 -249.468134) (xy 330.848279 -249.513197) (xy 330.817706 -249.553883) (xy 330.781002 -249.589138)
			(xy 330.739118 -249.618048) (xy 330.693139 -249.639865) (xy 330.644255 -249.654025) (xy 330.593734 -249.660159)
			(xy 330.542882 -249.65811) (xy 330.493018 -249.64793) (xy 330.445432 -249.629883) (xy 330.401358 -249.604437)
			(xy 330.361936 -249.57225) (xy 330.328188 -249.534156) (xy 330.300987 -249.491142) (xy 330.281039 -249.444322)
			(xy 330.26886 -249.394908) (xy 330.264765 -249.34418) (xy 329.946508 -249.34418) (xy 329.946013 -249.368787)
			(xy 329.938118 -249.417364) (xy 329.922534 -249.464045) (xy 329.899663 -249.507622) (xy 329.870098 -249.546966)
			(xy 329.834605 -249.581058) (xy 329.794102 -249.609014) (xy 329.74964 -249.630112) (xy 329.702369 -249.643804)
			(xy 329.653514 -249.649736) (xy 329.604339 -249.647755) (xy 329.55612 -249.637911) (xy 329.510104 -249.620459)
			(xy 329.467483 -249.595852) (xy 329.429362 -249.564727) (xy 329.396727 -249.52789) (xy 329.370424 -249.486294)
			(xy 329.351133 -249.441018) (xy 329.339356 -249.393234) (xy 329.335396 -249.34418) (xy 329.006454 -249.34418)
			(xy 329.005959 -249.368787) (xy 328.998064 -249.417364) (xy 328.98248 -249.464045) (xy 328.959609 -249.507622)
			(xy 328.930044 -249.546966) (xy 328.894551 -249.581058) (xy 328.854048 -249.609014) (xy 328.809586 -249.630112)
			(xy 328.762315 -249.643804) (xy 328.71346 -249.649736) (xy 328.664285 -249.647755) (xy 328.616066 -249.637911)
			(xy 328.57005 -249.620459) (xy 328.527429 -249.595852) (xy 328.489308 -249.564727) (xy 328.456673 -249.52789)
			(xy 328.43037 -249.486294) (xy 328.411079 -249.441018) (xy 328.399302 -249.393234) (xy 328.395342 -249.34418)
			(xy 324.903545 -249.34418) (xy 324.905872 -249.345284) (xy 324.946375 -249.37324) (xy 324.981868 -249.407332)
			(xy 325.011433 -249.446676) (xy 325.034304 -249.490253) (xy 325.049888 -249.536934) (xy 325.057783 -249.585511)
			(xy 325.058278 -249.610118) (xy 325.057783 -249.634725) (xy 325.049888 -249.683302) (xy 325.034304 -249.729983)
			(xy 325.011433 -249.77356) (xy 324.981868 -249.812904) (xy 324.946375 -249.846996) (xy 324.905872 -249.874952)
			(xy 324.86141 -249.89605) (xy 324.814139 -249.909742) (xy 324.765284 -249.915674) (xy 324.716109 -249.913693)
			(xy 324.66789 -249.903849) (xy 324.621874 -249.886397) (xy 324.579253 -249.86179) (xy 324.541132 -249.830665)
			(xy 324.508497 -249.793828) (xy 324.482194 -249.752232) (xy 324.462903 -249.706956) (xy 324.451126 -249.659172)
			(xy 324.447166 -249.610118) (xy 310.45912 -249.610118) (xy 310.45912 -250.154186) (xy 326.045334 -250.154186)
			(xy 326.049294 -250.105132) (xy 326.061071 -250.057348) (xy 326.080362 -250.012072) (xy 326.106665 -249.970476)
			(xy 326.1393 -249.933639) (xy 326.177421 -249.902514) (xy 326.220042 -249.877907) (xy 326.266058 -249.860455)
			(xy 326.314277 -249.850611) (xy 326.363452 -249.84863) (xy 326.412307 -249.854562) (xy 326.459578 -249.868254)
			(xy 326.50404 -249.889352) (xy 326.544543 -249.917308) (xy 326.580036 -249.9514) (xy 326.609601 -249.990744)
			(xy 326.632472 -250.034321) (xy 326.648056 -250.081002) (xy 326.655951 -250.129579) (xy 326.656446 -250.154186)
			(xy 326.985388 -250.154186) (xy 326.989348 -250.105132) (xy 327.001125 -250.057348) (xy 327.020416 -250.012072)
			(xy 327.046719 -249.970476) (xy 327.079354 -249.933639) (xy 327.117475 -249.902514) (xy 327.160096 -249.877907)
			(xy 327.206112 -249.860455) (xy 327.254331 -249.850611) (xy 327.303506 -249.84863) (xy 327.352361 -249.854562)
			(xy 327.399632 -249.868254) (xy 327.444094 -249.889352) (xy 327.484597 -249.917308) (xy 327.52009 -249.9514)
			(xy 327.549655 -249.990744) (xy 327.572526 -250.034321) (xy 327.58811 -250.081002) (xy 327.596005 -250.129579)
			(xy 327.5965 -250.154186) (xy 327.925442 -250.154186) (xy 327.929402 -250.105132) (xy 327.941179 -250.057348)
			(xy 327.96047 -250.012072) (xy 327.986773 -249.970476) (xy 328.019408 -249.933639) (xy 328.057529 -249.902514)
			(xy 328.10015 -249.877907) (xy 328.146166 -249.860455) (xy 328.194385 -249.850611) (xy 328.24356 -249.84863)
			(xy 328.292415 -249.854562) (xy 328.339686 -249.868254) (xy 328.384148 -249.889352) (xy 328.424651 -249.917308)
			(xy 328.460144 -249.9514) (xy 328.489709 -249.990744) (xy 328.51258 -250.034321) (xy 328.528164 -250.081002)
			(xy 328.536059 -250.129579) (xy 328.536554 -250.154186) (xy 328.865242 -250.154186) (xy 328.869202 -250.105132)
			(xy 328.880979 -250.057348) (xy 328.90027 -250.012072) (xy 328.926573 -249.970476) (xy 328.959208 -249.933639)
			(xy 328.997329 -249.902514) (xy 329.03995 -249.877907) (xy 329.085966 -249.860455) (xy 329.134185 -249.850611)
			(xy 329.18336 -249.84863) (xy 329.232215 -249.854562) (xy 329.279486 -249.868254) (xy 329.323948 -249.889352)
			(xy 329.364451 -249.917308) (xy 329.399944 -249.9514) (xy 329.429509 -249.990744) (xy 329.45238 -250.034321)
			(xy 329.467964 -250.081002) (xy 329.475859 -250.129579) (xy 329.476354 -250.154186) (xy 329.794865 -250.154186)
			(xy 329.79896 -250.103458) (xy 329.811139 -250.054044) (xy 329.831087 -250.007224) (xy 329.858288 -249.96421)
			(xy 329.892036 -249.926116) (xy 329.931458 -249.893929) (xy 329.975532 -249.868483) (xy 330.023118 -249.850436)
			(xy 330.072982 -249.840256) (xy 330.123834 -249.838207) (xy 330.174355 -249.844341) (xy 330.223239 -249.858501)
			(xy 330.269218 -249.880318) (xy 330.311102 -249.909228) (xy 330.347806 -249.944483) (xy 330.378379 -249.985169)
			(xy 330.40203 -250.030232) (xy 330.418146 -250.078506) (xy 330.42631 -250.12874) (xy 330.426822 -250.154186)
			(xy 330.74535 -250.154186) (xy 330.74931 -250.105132) (xy 330.761087 -250.057348) (xy 330.780378 -250.012072)
			(xy 330.806681 -249.970476) (xy 330.839316 -249.933639) (xy 330.877437 -249.902514) (xy 330.920058 -249.877907)
			(xy 330.966074 -249.860455) (xy 331.014293 -249.850611) (xy 331.063468 -249.84863) (xy 331.112323 -249.854562)
			(xy 331.159594 -249.868254) (xy 331.204056 -249.889352) (xy 331.244559 -249.917308) (xy 331.280052 -249.9514)
			(xy 331.309617 -249.990744) (xy 331.332488 -250.034321) (xy 331.348072 -250.081002) (xy 331.355967 -250.129579)
			(xy 331.356462 -250.154186) (xy 331.685404 -250.154186) (xy 331.689364 -250.105132) (xy 331.701141 -250.057348)
			(xy 331.720432 -250.012072) (xy 331.746735 -249.970476) (xy 331.77937 -249.933639) (xy 331.817491 -249.902514)
			(xy 331.860112 -249.877907) (xy 331.906128 -249.860455) (xy 331.954347 -249.850611) (xy 332.003522 -249.84863)
			(xy 332.052377 -249.854562) (xy 332.099648 -249.868254) (xy 332.14411 -249.889352) (xy 332.184613 -249.917308)
			(xy 332.220106 -249.9514) (xy 332.249671 -249.990744) (xy 332.272542 -250.034321) (xy 332.288126 -250.081002)
			(xy 332.296021 -250.129579) (xy 332.296516 -250.154186) (xy 332.625204 -250.154186) (xy 332.629164 -250.105132)
			(xy 332.640941 -250.057348) (xy 332.660232 -250.012072) (xy 332.686535 -249.970476) (xy 332.71917 -249.933639)
			(xy 332.757291 -249.902514) (xy 332.799912 -249.877907) (xy 332.845928 -249.860455) (xy 332.894147 -249.850611)
			(xy 332.943322 -249.84863) (xy 332.992177 -249.854562) (xy 333.039448 -249.868254) (xy 333.08391 -249.889352)
			(xy 333.124413 -249.917308) (xy 333.159906 -249.9514) (xy 333.189471 -249.990744) (xy 333.212342 -250.034321)
			(xy 333.227926 -250.081002) (xy 333.235821 -250.129579) (xy 333.236316 -250.154186) (xy 333.554827 -250.154186)
			(xy 333.558922 -250.103458) (xy 333.571101 -250.054044) (xy 333.591049 -250.007224) (xy 333.61825 -249.96421)
			(xy 333.651998 -249.926116) (xy 333.69142 -249.893929) (xy 333.735494 -249.868483) (xy 333.78308 -249.850436)
			(xy 333.832944 -249.840256) (xy 333.883796 -249.838207) (xy 333.934317 -249.844341) (xy 333.983201 -249.858501)
			(xy 334.02918 -249.880318) (xy 334.071064 -249.909228) (xy 334.107768 -249.944483) (xy 334.138341 -249.985169)
			(xy 334.161992 -250.030232) (xy 334.178108 -250.078506) (xy 334.186272 -250.12874) (xy 334.186784 -250.154186)
			(xy 334.505312 -250.154186) (xy 334.509272 -250.105132) (xy 334.521049 -250.057348) (xy 334.54034 -250.012072)
			(xy 334.566643 -249.970476) (xy 334.599278 -249.933639) (xy 334.637399 -249.902514) (xy 334.68002 -249.877907)
			(xy 334.726036 -249.860455) (xy 334.774255 -249.850611) (xy 334.82343 -249.84863) (xy 334.872285 -249.854562)
			(xy 334.919556 -249.868254) (xy 334.964018 -249.889352) (xy 335.004521 -249.917308) (xy 335.040014 -249.9514)
			(xy 335.069579 -249.990744) (xy 335.09245 -250.034321) (xy 335.108034 -250.081002) (xy 335.115929 -250.129579)
			(xy 335.116424 -250.154186) (xy 335.445366 -250.154186) (xy 335.449326 -250.105132) (xy 335.461103 -250.057348)
			(xy 335.480394 -250.012072) (xy 335.506697 -249.970476) (xy 335.539332 -249.933639) (xy 335.577453 -249.902514)
			(xy 335.620074 -249.877907) (xy 335.66609 -249.860455) (xy 335.714309 -249.850611) (xy 335.763484 -249.84863)
			(xy 335.812339 -249.854562) (xy 335.85961 -249.868254) (xy 335.904072 -249.889352) (xy 335.944575 -249.917308)
			(xy 335.980068 -249.9514) (xy 336.009633 -249.990744) (xy 336.032504 -250.034321) (xy 336.048088 -250.081002)
			(xy 336.055983 -250.129579) (xy 336.056478 -250.154186) (xy 336.374989 -250.154186) (xy 336.379084 -250.103458)
			(xy 336.391263 -250.054044) (xy 336.411211 -250.007224) (xy 336.438412 -249.96421) (xy 336.47216 -249.926116)
			(xy 336.511582 -249.893929) (xy 336.555656 -249.868483) (xy 336.603242 -249.850436) (xy 336.653106 -249.840256)
			(xy 336.703958 -249.838207) (xy 336.754479 -249.844341) (xy 336.803363 -249.858501) (xy 336.849342 -249.880318)
			(xy 336.891226 -249.909228) (xy 336.92793 -249.944483) (xy 336.958503 -249.985169) (xy 336.982154 -250.030232)
			(xy 336.99827 -250.078506) (xy 337.006434 -250.12874) (xy 337.006946 -250.154186) (xy 337.32522 -250.154186)
			(xy 337.32918 -250.105132) (xy 337.340957 -250.057348) (xy 337.360248 -250.012072) (xy 337.386551 -249.970476)
			(xy 337.419186 -249.933639) (xy 337.457307 -249.902514) (xy 337.499928 -249.877907) (xy 337.545944 -249.860455)
			(xy 337.594163 -249.850611) (xy 337.643338 -249.84863) (xy 337.692193 -249.854562) (xy 337.739464 -249.868254)
			(xy 337.783926 -249.889352) (xy 337.824429 -249.917308) (xy 337.859922 -249.9514) (xy 337.889487 -249.990744)
			(xy 337.912358 -250.034321) (xy 337.927942 -250.081002) (xy 337.935837 -250.129579) (xy 337.936332 -250.154186)
			(xy 338.265274 -250.154186) (xy 338.269234 -250.105132) (xy 338.281011 -250.057348) (xy 338.300302 -250.012072)
			(xy 338.326605 -249.970476) (xy 338.35924 -249.933639) (xy 338.397361 -249.902514) (xy 338.439982 -249.877907)
			(xy 338.485998 -249.860455) (xy 338.534217 -249.850611) (xy 338.583392 -249.84863) (xy 338.632247 -249.854562)
			(xy 338.679518 -249.868254) (xy 338.72398 -249.889352) (xy 338.764483 -249.917308) (xy 338.799976 -249.9514)
			(xy 338.829541 -249.990744) (xy 338.852412 -250.034321) (xy 338.867996 -250.081002) (xy 338.875891 -250.129579)
			(xy 338.876386 -250.154186) (xy 339.205328 -250.154186) (xy 339.209288 -250.105132) (xy 339.221065 -250.057348)
			(xy 339.240356 -250.012072) (xy 339.266659 -249.970476) (xy 339.299294 -249.933639) (xy 339.337415 -249.902514)
			(xy 339.380036 -249.877907) (xy 339.426052 -249.860455) (xy 339.474271 -249.850611) (xy 339.523446 -249.84863)
			(xy 339.572301 -249.854562) (xy 339.619572 -249.868254) (xy 339.664034 -249.889352) (xy 339.704537 -249.917308)
			(xy 339.74003 -249.9514) (xy 339.769595 -249.990744) (xy 339.792466 -250.034321) (xy 339.80805 -250.081002)
			(xy 339.815945 -250.129579) (xy 339.81644 -250.154186) (xy 340.134951 -250.154186) (xy 340.139046 -250.103458)
			(xy 340.151225 -250.054044) (xy 340.171173 -250.007224) (xy 340.198374 -249.96421) (xy 340.232122 -249.926116)
			(xy 340.271544 -249.893929) (xy 340.315618 -249.868483) (xy 340.363204 -249.850436) (xy 340.413068 -249.840256)
			(xy 340.46392 -249.838207) (xy 340.514441 -249.844341) (xy 340.563325 -249.858501) (xy 340.609304 -249.880318)
			(xy 340.651188 -249.909228) (xy 340.687892 -249.944483) (xy 340.718465 -249.985169) (xy 340.742116 -250.030232)
			(xy 340.758232 -250.078506) (xy 340.766396 -250.12874) (xy 340.766908 -250.154186) (xy 341.085182 -250.154186)
			(xy 341.089142 -250.105132) (xy 341.100919 -250.057348) (xy 341.12021 -250.012072) (xy 341.146513 -249.970476)
			(xy 341.179148 -249.933639) (xy 341.217269 -249.902514) (xy 341.25989 -249.877907) (xy 341.305906 -249.860455)
			(xy 341.354125 -249.850611) (xy 341.4033 -249.84863) (xy 341.452155 -249.854562) (xy 341.499426 -249.868254)
			(xy 341.543888 -249.889352) (xy 341.584391 -249.917308) (xy 341.619884 -249.9514) (xy 341.649449 -249.990744)
			(xy 341.67232 -250.034321) (xy 341.687904 -250.081002) (xy 341.695799 -250.129579) (xy 341.696294 -250.154186)
			(xy 342.025236 -250.154186) (xy 342.029196 -250.105132) (xy 342.040973 -250.057348) (xy 342.060264 -250.012072)
			(xy 342.086567 -249.970476) (xy 342.119202 -249.933639) (xy 342.157323 -249.902514) (xy 342.199944 -249.877907)
			(xy 342.24596 -249.860455) (xy 342.294179 -249.850611) (xy 342.343354 -249.84863) (xy 342.392209 -249.854562)
			(xy 342.43948 -249.868254) (xy 342.483942 -249.889352) (xy 342.524445 -249.917308) (xy 342.559938 -249.9514)
			(xy 342.589503 -249.990744) (xy 342.612374 -250.034321) (xy 342.627958 -250.081002) (xy 342.635853 -250.129579)
			(xy 342.636348 -250.154186) (xy 342.954859 -250.154186) (xy 342.958954 -250.103458) (xy 342.971133 -250.054044)
			(xy 342.991081 -250.007224) (xy 343.018282 -249.96421) (xy 343.05203 -249.926116) (xy 343.091452 -249.893929)
			(xy 343.135526 -249.868483) (xy 343.183112 -249.850436) (xy 343.232976 -249.840256) (xy 343.283828 -249.838207)
			(xy 343.334349 -249.844341) (xy 343.383233 -249.858501) (xy 343.429212 -249.880318) (xy 343.471096 -249.909228)
			(xy 343.5078 -249.944483) (xy 343.538373 -249.985169) (xy 343.562024 -250.030232) (xy 343.57814 -250.078506)
			(xy 343.586304 -250.12874) (xy 343.586816 -250.154186) (xy 343.905344 -250.154186) (xy 343.909304 -250.105132)
			(xy 343.921081 -250.057348) (xy 343.940372 -250.012072) (xy 343.966675 -249.970476) (xy 343.99931 -249.933639)
			(xy 344.037431 -249.902514) (xy 344.080052 -249.877907) (xy 344.126068 -249.860455) (xy 344.174287 -249.850611)
			(xy 344.223462 -249.84863) (xy 344.272317 -249.854562) (xy 344.319588 -249.868254) (xy 344.36405 -249.889352)
			(xy 344.404553 -249.917308) (xy 344.440046 -249.9514) (xy 344.469611 -249.990744) (xy 344.492482 -250.034321)
			(xy 344.508066 -250.081002) (xy 344.515961 -250.129579) (xy 344.516456 -250.154186) (xy 344.515961 -250.178793)
			(xy 344.508066 -250.22737) (xy 344.492482 -250.274051) (xy 344.469611 -250.317628) (xy 344.440046 -250.356972)
			(xy 344.404553 -250.391064) (xy 344.36405 -250.41902) (xy 344.319588 -250.440118) (xy 344.272317 -250.45381)
			(xy 344.223462 -250.459742) (xy 344.174287 -250.457761) (xy 344.126068 -250.447917) (xy 344.080052 -250.430465)
			(xy 344.037431 -250.405858) (xy 343.99931 -250.374733) (xy 343.966675 -250.337896) (xy 343.940372 -250.2963)
			(xy 343.921081 -250.251024) (xy 343.909304 -250.20324) (xy 343.905344 -250.154186) (xy 343.586816 -250.154186)
			(xy 343.586304 -250.179632) (xy 343.57814 -250.229866) (xy 343.562024 -250.27814) (xy 343.538373 -250.323203)
			(xy 343.5078 -250.363889) (xy 343.471096 -250.399144) (xy 343.429212 -250.428054) (xy 343.383233 -250.449871)
			(xy 343.334349 -250.464031) (xy 343.283828 -250.470165) (xy 343.232976 -250.468116) (xy 343.183112 -250.457936)
			(xy 343.135526 -250.439889) (xy 343.091452 -250.414443) (xy 343.05203 -250.382256) (xy 343.018282 -250.344162)
			(xy 342.991081 -250.301148) (xy 342.971133 -250.254328) (xy 342.958954 -250.204914) (xy 342.954859 -250.154186)
			(xy 342.636348 -250.154186) (xy 342.635853 -250.178793) (xy 342.627958 -250.22737) (xy 342.612374 -250.274051)
			(xy 342.589503 -250.317628) (xy 342.559938 -250.356972) (xy 342.524445 -250.391064) (xy 342.483942 -250.41902)
			(xy 342.43948 -250.440118) (xy 342.392209 -250.45381) (xy 342.343354 -250.459742) (xy 342.294179 -250.457761)
			(xy 342.24596 -250.447917) (xy 342.199944 -250.430465) (xy 342.157323 -250.405858) (xy 342.119202 -250.374733)
			(xy 342.086567 -250.337896) (xy 342.060264 -250.2963) (xy 342.040973 -250.251024) (xy 342.029196 -250.20324)
			(xy 342.025236 -250.154186) (xy 341.696294 -250.154186) (xy 341.695799 -250.178793) (xy 341.687904 -250.22737)
			(xy 341.67232 -250.274051) (xy 341.649449 -250.317628) (xy 341.619884 -250.356972) (xy 341.584391 -250.391064)
			(xy 341.543888 -250.41902) (xy 341.499426 -250.440118) (xy 341.452155 -250.45381) (xy 341.4033 -250.459742)
			(xy 341.354125 -250.457761) (xy 341.305906 -250.447917) (xy 341.25989 -250.430465) (xy 341.217269 -250.405858)
			(xy 341.179148 -250.374733) (xy 341.146513 -250.337896) (xy 341.12021 -250.2963) (xy 341.100919 -250.251024)
			(xy 341.089142 -250.20324) (xy 341.085182 -250.154186) (xy 340.766908 -250.154186) (xy 340.766396 -250.179632)
			(xy 340.758232 -250.229866) (xy 340.742116 -250.27814) (xy 340.718465 -250.323203) (xy 340.687892 -250.363889)
			(xy 340.651188 -250.399144) (xy 340.609304 -250.428054) (xy 340.563325 -250.449871) (xy 340.514441 -250.464031)
			(xy 340.46392 -250.470165) (xy 340.413068 -250.468116) (xy 340.363204 -250.457936) (xy 340.315618 -250.439889)
			(xy 340.271544 -250.414443) (xy 340.232122 -250.382256) (xy 340.198374 -250.344162) (xy 340.171173 -250.301148)
			(xy 340.151225 -250.254328) (xy 340.139046 -250.204914) (xy 340.134951 -250.154186) (xy 339.81644 -250.154186)
			(xy 339.815945 -250.178793) (xy 339.80805 -250.22737) (xy 339.792466 -250.274051) (xy 339.769595 -250.317628)
			(xy 339.74003 -250.356972) (xy 339.704537 -250.391064) (xy 339.664034 -250.41902) (xy 339.619572 -250.440118)
			(xy 339.572301 -250.45381) (xy 339.523446 -250.459742) (xy 339.474271 -250.457761) (xy 339.426052 -250.447917)
			(xy 339.380036 -250.430465) (xy 339.337415 -250.405858) (xy 339.299294 -250.374733) (xy 339.266659 -250.337896)
			(xy 339.240356 -250.2963) (xy 339.221065 -250.251024) (xy 339.209288 -250.20324) (xy 339.205328 -250.154186)
			(xy 338.876386 -250.154186) (xy 338.875891 -250.178793) (xy 338.867996 -250.22737) (xy 338.852412 -250.274051)
			(xy 338.829541 -250.317628) (xy 338.799976 -250.356972) (xy 338.764483 -250.391064) (xy 338.72398 -250.41902)
			(xy 338.679518 -250.440118) (xy 338.632247 -250.45381) (xy 338.583392 -250.459742) (xy 338.534217 -250.457761)
			(xy 338.485998 -250.447917) (xy 338.439982 -250.430465) (xy 338.397361 -250.405858) (xy 338.35924 -250.374733)
			(xy 338.326605 -250.337896) (xy 338.300302 -250.2963) (xy 338.281011 -250.251024) (xy 338.269234 -250.20324)
			(xy 338.265274 -250.154186) (xy 337.936332 -250.154186) (xy 337.935837 -250.178793) (xy 337.927942 -250.22737)
			(xy 337.912358 -250.274051) (xy 337.889487 -250.317628) (xy 337.859922 -250.356972) (xy 337.824429 -250.391064)
			(xy 337.783926 -250.41902) (xy 337.739464 -250.440118) (xy 337.692193 -250.45381) (xy 337.643338 -250.459742)
			(xy 337.594163 -250.457761) (xy 337.545944 -250.447917) (xy 337.499928 -250.430465) (xy 337.457307 -250.405858)
			(xy 337.419186 -250.374733) (xy 337.386551 -250.337896) (xy 337.360248 -250.2963) (xy 337.340957 -250.251024)
			(xy 337.32918 -250.20324) (xy 337.32522 -250.154186) (xy 337.006946 -250.154186) (xy 337.006434 -250.179632)
			(xy 336.99827 -250.229866) (xy 336.982154 -250.27814) (xy 336.958503 -250.323203) (xy 336.92793 -250.363889)
			(xy 336.891226 -250.399144) (xy 336.849342 -250.428054) (xy 336.803363 -250.449871) (xy 336.754479 -250.464031)
			(xy 336.703958 -250.470165) (xy 336.653106 -250.468116) (xy 336.603242 -250.457936) (xy 336.555656 -250.439889)
			(xy 336.511582 -250.414443) (xy 336.47216 -250.382256) (xy 336.438412 -250.344162) (xy 336.411211 -250.301148)
			(xy 336.391263 -250.254328) (xy 336.379084 -250.204914) (xy 336.374989 -250.154186) (xy 336.056478 -250.154186)
			(xy 336.055983 -250.178793) (xy 336.048088 -250.22737) (xy 336.032504 -250.274051) (xy 336.009633 -250.317628)
			(xy 335.980068 -250.356972) (xy 335.944575 -250.391064) (xy 335.904072 -250.41902) (xy 335.85961 -250.440118)
			(xy 335.812339 -250.45381) (xy 335.763484 -250.459742) (xy 335.714309 -250.457761) (xy 335.66609 -250.447917)
			(xy 335.620074 -250.430465) (xy 335.577453 -250.405858) (xy 335.539332 -250.374733) (xy 335.506697 -250.337896)
			(xy 335.480394 -250.2963) (xy 335.461103 -250.251024) (xy 335.449326 -250.20324) (xy 335.445366 -250.154186)
			(xy 335.116424 -250.154186) (xy 335.115929 -250.178793) (xy 335.108034 -250.22737) (xy 335.09245 -250.274051)
			(xy 335.069579 -250.317628) (xy 335.040014 -250.356972) (xy 335.004521 -250.391064) (xy 334.964018 -250.41902)
			(xy 334.919556 -250.440118) (xy 334.872285 -250.45381) (xy 334.82343 -250.459742) (xy 334.774255 -250.457761)
			(xy 334.726036 -250.447917) (xy 334.68002 -250.430465) (xy 334.637399 -250.405858) (xy 334.599278 -250.374733)
			(xy 334.566643 -250.337896) (xy 334.54034 -250.2963) (xy 334.521049 -250.251024) (xy 334.509272 -250.20324)
			(xy 334.505312 -250.154186) (xy 334.186784 -250.154186) (xy 334.186272 -250.179632) (xy 334.178108 -250.229866)
			(xy 334.161992 -250.27814) (xy 334.138341 -250.323203) (xy 334.107768 -250.363889) (xy 334.071064 -250.399144)
			(xy 334.02918 -250.428054) (xy 333.983201 -250.449871) (xy 333.934317 -250.464031) (xy 333.883796 -250.470165)
			(xy 333.832944 -250.468116) (xy 333.78308 -250.457936) (xy 333.735494 -250.439889) (xy 333.69142 -250.414443)
			(xy 333.651998 -250.382256) (xy 333.61825 -250.344162) (xy 333.591049 -250.301148) (xy 333.571101 -250.254328)
			(xy 333.558922 -250.204914) (xy 333.554827 -250.154186) (xy 333.236316 -250.154186) (xy 333.235821 -250.178793)
			(xy 333.227926 -250.22737) (xy 333.212342 -250.274051) (xy 333.189471 -250.317628) (xy 333.159906 -250.356972)
			(xy 333.124413 -250.391064) (xy 333.08391 -250.41902) (xy 333.039448 -250.440118) (xy 332.992177 -250.45381)
			(xy 332.943322 -250.459742) (xy 332.894147 -250.457761) (xy 332.845928 -250.447917) (xy 332.799912 -250.430465)
			(xy 332.757291 -250.405858) (xy 332.71917 -250.374733) (xy 332.686535 -250.337896) (xy 332.660232 -250.2963)
			(xy 332.640941 -250.251024) (xy 332.629164 -250.20324) (xy 332.625204 -250.154186) (xy 332.296516 -250.154186)
			(xy 332.296021 -250.178793) (xy 332.288126 -250.22737) (xy 332.272542 -250.274051) (xy 332.249671 -250.317628)
			(xy 332.220106 -250.356972) (xy 332.184613 -250.391064) (xy 332.14411 -250.41902) (xy 332.099648 -250.440118)
			(xy 332.052377 -250.45381) (xy 332.003522 -250.459742) (xy 331.954347 -250.457761) (xy 331.906128 -250.447917)
			(xy 331.860112 -250.430465) (xy 331.817491 -250.405858) (xy 331.77937 -250.374733) (xy 331.746735 -250.337896)
			(xy 331.720432 -250.2963) (xy 331.701141 -250.251024) (xy 331.689364 -250.20324) (xy 331.685404 -250.154186)
			(xy 331.356462 -250.154186) (xy 331.355967 -250.178793) (xy 331.348072 -250.22737) (xy 331.332488 -250.274051)
			(xy 331.309617 -250.317628) (xy 331.280052 -250.356972) (xy 331.244559 -250.391064) (xy 331.204056 -250.41902)
			(xy 331.159594 -250.440118) (xy 331.112323 -250.45381) (xy 331.063468 -250.459742) (xy 331.014293 -250.457761)
			(xy 330.966074 -250.447917) (xy 330.920058 -250.430465) (xy 330.877437 -250.405858) (xy 330.839316 -250.374733)
			(xy 330.806681 -250.337896) (xy 330.780378 -250.2963) (xy 330.761087 -250.251024) (xy 330.74931 -250.20324)
			(xy 330.74535 -250.154186) (xy 330.426822 -250.154186) (xy 330.42631 -250.179632) (xy 330.418146 -250.229866)
			(xy 330.40203 -250.27814) (xy 330.378379 -250.323203) (xy 330.347806 -250.363889) (xy 330.311102 -250.399144)
			(xy 330.269218 -250.428054) (xy 330.223239 -250.449871) (xy 330.174355 -250.464031) (xy 330.123834 -250.470165)
			(xy 330.072982 -250.468116) (xy 330.023118 -250.457936) (xy 329.975532 -250.439889) (xy 329.931458 -250.414443)
			(xy 329.892036 -250.382256) (xy 329.858288 -250.344162) (xy 329.831087 -250.301148) (xy 329.811139 -250.254328)
			(xy 329.79896 -250.204914) (xy 329.794865 -250.154186) (xy 329.476354 -250.154186) (xy 329.475859 -250.178793)
			(xy 329.467964 -250.22737) (xy 329.45238 -250.274051) (xy 329.429509 -250.317628) (xy 329.399944 -250.356972)
			(xy 329.364451 -250.391064) (xy 329.323948 -250.41902) (xy 329.279486 -250.440118) (xy 329.232215 -250.45381)
			(xy 329.18336 -250.459742) (xy 329.134185 -250.457761) (xy 329.085966 -250.447917) (xy 329.03995 -250.430465)
			(xy 328.997329 -250.405858) (xy 328.959208 -250.374733) (xy 328.926573 -250.337896) (xy 328.90027 -250.2963)
			(xy 328.880979 -250.251024) (xy 328.869202 -250.20324) (xy 328.865242 -250.154186) (xy 328.536554 -250.154186)
			(xy 328.536059 -250.178793) (xy 328.528164 -250.22737) (xy 328.51258 -250.274051) (xy 328.489709 -250.317628)
			(xy 328.460144 -250.356972) (xy 328.424651 -250.391064) (xy 328.384148 -250.41902) (xy 328.339686 -250.440118)
			(xy 328.292415 -250.45381) (xy 328.24356 -250.459742) (xy 328.194385 -250.457761) (xy 328.146166 -250.447917)
			(xy 328.10015 -250.430465) (xy 328.057529 -250.405858) (xy 328.019408 -250.374733) (xy 327.986773 -250.337896)
			(xy 327.96047 -250.2963) (xy 327.941179 -250.251024) (xy 327.929402 -250.20324) (xy 327.925442 -250.154186)
			(xy 327.5965 -250.154186) (xy 327.596005 -250.178793) (xy 327.58811 -250.22737) (xy 327.572526 -250.274051)
			(xy 327.549655 -250.317628) (xy 327.52009 -250.356972) (xy 327.484597 -250.391064) (xy 327.444094 -250.41902)
			(xy 327.399632 -250.440118) (xy 327.352361 -250.45381) (xy 327.303506 -250.459742) (xy 327.254331 -250.457761)
			(xy 327.206112 -250.447917) (xy 327.160096 -250.430465) (xy 327.117475 -250.405858) (xy 327.079354 -250.374733)
			(xy 327.046719 -250.337896) (xy 327.020416 -250.2963) (xy 327.001125 -250.251024) (xy 326.989348 -250.20324)
			(xy 326.985388 -250.154186) (xy 326.656446 -250.154186) (xy 326.655951 -250.178793) (xy 326.648056 -250.22737)
			(xy 326.632472 -250.274051) (xy 326.609601 -250.317628) (xy 326.580036 -250.356972) (xy 326.544543 -250.391064)
			(xy 326.50404 -250.41902) (xy 326.459578 -250.440118) (xy 326.412307 -250.45381) (xy 326.363452 -250.459742)
			(xy 326.314277 -250.457761) (xy 326.266058 -250.447917) (xy 326.220042 -250.430465) (xy 326.177421 -250.405858)
			(xy 326.1393 -250.374733) (xy 326.106665 -250.337896) (xy 326.080362 -250.2963) (xy 326.061071 -250.251024)
			(xy 326.049294 -250.20324) (xy 326.045334 -250.154186) (xy 310.45912 -250.154186) (xy 310.45912 -251.23013)
			(xy 324.447166 -251.23013) (xy 324.451126 -251.181076) (xy 324.462903 -251.133292) (xy 324.482194 -251.088016)
			(xy 324.508497 -251.04642) (xy 324.541132 -251.009583) (xy 324.579253 -250.978458) (xy 324.621874 -250.953851)
			(xy 324.66789 -250.936399) (xy 324.716109 -250.926555) (xy 324.765284 -250.924574) (xy 324.814139 -250.930506)
			(xy 324.86141 -250.944198) (xy 324.903545 -250.964192) (xy 326.515234 -250.964192) (xy 326.519194 -250.915138)
			(xy 326.530971 -250.867354) (xy 326.550262 -250.822078) (xy 326.576565 -250.780482) (xy 326.6092 -250.743645)
			(xy 326.647321 -250.71252) (xy 326.689942 -250.687913) (xy 326.735958 -250.670461) (xy 326.784177 -250.660617)
			(xy 326.833352 -250.658636) (xy 326.882207 -250.664568) (xy 326.929478 -250.67826) (xy 326.97394 -250.699358)
			(xy 327.014443 -250.727314) (xy 327.049936 -250.761406) (xy 327.079501 -250.80075) (xy 327.102372 -250.844327)
			(xy 327.117956 -250.891008) (xy 327.125851 -250.939585) (xy 327.126346 -250.964192) (xy 327.455288 -250.964192)
			(xy 327.459248 -250.915138) (xy 327.471025 -250.867354) (xy 327.490316 -250.822078) (xy 327.516619 -250.780482)
			(xy 327.549254 -250.743645) (xy 327.587375 -250.71252) (xy 327.629996 -250.687913) (xy 327.676012 -250.670461)
			(xy 327.724231 -250.660617) (xy 327.773406 -250.658636) (xy 327.822261 -250.664568) (xy 327.869532 -250.67826)
			(xy 327.913994 -250.699358) (xy 327.954497 -250.727314) (xy 327.98999 -250.761406) (xy 328.019555 -250.80075)
			(xy 328.042426 -250.844327) (xy 328.05801 -250.891008) (xy 328.065905 -250.939585) (xy 328.0664 -250.964192)
			(xy 328.395342 -250.964192) (xy 328.399302 -250.915138) (xy 328.411079 -250.867354) (xy 328.43037 -250.822078)
			(xy 328.456673 -250.780482) (xy 328.489308 -250.743645) (xy 328.527429 -250.71252) (xy 328.57005 -250.687913)
			(xy 328.616066 -250.670461) (xy 328.664285 -250.660617) (xy 328.71346 -250.658636) (xy 328.762315 -250.664568)
			(xy 328.809586 -250.67826) (xy 328.854048 -250.699358) (xy 328.894551 -250.727314) (xy 328.930044 -250.761406)
			(xy 328.959609 -250.80075) (xy 328.98248 -250.844327) (xy 328.998064 -250.891008) (xy 329.005959 -250.939585)
			(xy 329.006454 -250.964192) (xy 329.335396 -250.964192) (xy 329.339356 -250.915138) (xy 329.351133 -250.867354)
			(xy 329.370424 -250.822078) (xy 329.396727 -250.780482) (xy 329.429362 -250.743645) (xy 329.467483 -250.71252)
			(xy 329.510104 -250.687913) (xy 329.55612 -250.670461) (xy 329.604339 -250.660617) (xy 329.653514 -250.658636)
			(xy 329.702369 -250.664568) (xy 329.74964 -250.67826) (xy 329.794102 -250.699358) (xy 329.834605 -250.727314)
			(xy 329.870098 -250.761406) (xy 329.899663 -250.80075) (xy 329.922534 -250.844327) (xy 329.938118 -250.891008)
			(xy 329.946013 -250.939585) (xy 329.946508 -250.964192) (xy 330.264765 -250.964192) (xy 330.26886 -250.913464)
			(xy 330.281039 -250.86405) (xy 330.300987 -250.81723) (xy 330.328188 -250.774216) (xy 330.361936 -250.736122)
			(xy 330.401358 -250.703935) (xy 330.445432 -250.678489) (xy 330.493018 -250.660442) (xy 330.542882 -250.650262)
			(xy 330.593734 -250.648213) (xy 330.644255 -250.654347) (xy 330.693139 -250.668507) (xy 330.739118 -250.690324)
			(xy 330.781002 -250.719234) (xy 330.817706 -250.754489) (xy 330.848279 -250.795175) (xy 330.87193 -250.840238)
			(xy 330.888046 -250.888512) (xy 330.89621 -250.938746) (xy 330.896722 -250.964192) (xy 331.21525 -250.964192)
			(xy 331.21921 -250.915138) (xy 331.230987 -250.867354) (xy 331.250278 -250.822078) (xy 331.276581 -250.780482)
			(xy 331.309216 -250.743645) (xy 331.347337 -250.71252) (xy 331.389958 -250.687913) (xy 331.435974 -250.670461)
			(xy 331.484193 -250.660617) (xy 331.533368 -250.658636) (xy 331.582223 -250.664568) (xy 331.629494 -250.67826)
			(xy 331.673956 -250.699358) (xy 331.714459 -250.727314) (xy 331.749952 -250.761406) (xy 331.779517 -250.80075)
			(xy 331.802388 -250.844327) (xy 331.817972 -250.891008) (xy 331.825867 -250.939585) (xy 331.826362 -250.964192)
			(xy 332.155304 -250.964192) (xy 332.159264 -250.915138) (xy 332.171041 -250.867354) (xy 332.190332 -250.822078)
			(xy 332.216635 -250.780482) (xy 332.24927 -250.743645) (xy 332.287391 -250.71252) (xy 332.330012 -250.687913)
			(xy 332.376028 -250.670461) (xy 332.424247 -250.660617) (xy 332.473422 -250.658636) (xy 332.522277 -250.664568)
			(xy 332.569548 -250.67826) (xy 332.61401 -250.699358) (xy 332.654513 -250.727314) (xy 332.690006 -250.761406)
			(xy 332.719571 -250.80075) (xy 332.742442 -250.844327) (xy 332.758026 -250.891008) (xy 332.765921 -250.939585)
			(xy 332.766416 -250.964192) (xy 333.084927 -250.964192) (xy 333.089022 -250.913464) (xy 333.101201 -250.86405)
			(xy 333.121149 -250.81723) (xy 333.14835 -250.774216) (xy 333.182098 -250.736122) (xy 333.22152 -250.703935)
			(xy 333.265594 -250.678489) (xy 333.31318 -250.660442) (xy 333.363044 -250.650262) (xy 333.413896 -250.648213)
			(xy 333.464417 -250.654347) (xy 333.513301 -250.668507) (xy 333.55928 -250.690324) (xy 333.601164 -250.719234)
			(xy 333.637868 -250.754489) (xy 333.668441 -250.795175) (xy 333.692092 -250.840238) (xy 333.708208 -250.888512)
			(xy 333.716372 -250.938746) (xy 333.716884 -250.964192) (xy 334.035412 -250.964192) (xy 334.039372 -250.915138)
			(xy 334.051149 -250.867354) (xy 334.07044 -250.822078) (xy 334.096743 -250.780482) (xy 334.129378 -250.743645)
			(xy 334.167499 -250.71252) (xy 334.21012 -250.687913) (xy 334.256136 -250.670461) (xy 334.304355 -250.660617)
			(xy 334.35353 -250.658636) (xy 334.402385 -250.664568) (xy 334.449656 -250.67826) (xy 334.494118 -250.699358)
			(xy 334.534621 -250.727314) (xy 334.570114 -250.761406) (xy 334.599679 -250.80075) (xy 334.62255 -250.844327)
			(xy 334.638134 -250.891008) (xy 334.646029 -250.939585) (xy 334.646524 -250.964192) (xy 334.975212 -250.964192)
			(xy 334.979172 -250.915138) (xy 334.990949 -250.867354) (xy 335.01024 -250.822078) (xy 335.036543 -250.780482)
			(xy 335.069178 -250.743645) (xy 335.107299 -250.71252) (xy 335.14992 -250.687913) (xy 335.195936 -250.670461)
			(xy 335.244155 -250.660617) (xy 335.29333 -250.658636) (xy 335.342185 -250.664568) (xy 335.389456 -250.67826)
			(xy 335.433918 -250.699358) (xy 335.474421 -250.727314) (xy 335.509914 -250.761406) (xy 335.539479 -250.80075)
			(xy 335.56235 -250.844327) (xy 335.577934 -250.891008) (xy 335.585829 -250.939585) (xy 335.586324 -250.964192)
			(xy 335.915266 -250.964192) (xy 335.919226 -250.915138) (xy 335.931003 -250.867354) (xy 335.950294 -250.822078)
			(xy 335.976597 -250.780482) (xy 336.009232 -250.743645) (xy 336.047353 -250.71252) (xy 336.089974 -250.687913)
			(xy 336.13599 -250.670461) (xy 336.184209 -250.660617) (xy 336.233384 -250.658636) (xy 336.282239 -250.664568)
			(xy 336.32951 -250.67826) (xy 336.373972 -250.699358) (xy 336.414475 -250.727314) (xy 336.449968 -250.761406)
			(xy 336.479533 -250.80075) (xy 336.502404 -250.844327) (xy 336.517988 -250.891008) (xy 336.525883 -250.939585)
			(xy 336.526378 -250.964192) (xy 336.844889 -250.964192) (xy 336.848984 -250.913464) (xy 336.861163 -250.86405)
			(xy 336.881111 -250.81723) (xy 336.908312 -250.774216) (xy 336.94206 -250.736122) (xy 336.981482 -250.703935)
			(xy 337.025556 -250.678489) (xy 337.073142 -250.660442) (xy 337.123006 -250.650262) (xy 337.173858 -250.648213)
			(xy 337.224379 -250.654347) (xy 337.273263 -250.668507) (xy 337.319242 -250.690324) (xy 337.361126 -250.719234)
			(xy 337.39783 -250.754489) (xy 337.428403 -250.795175) (xy 337.452054 -250.840238) (xy 337.46817 -250.888512)
			(xy 337.476334 -250.938746) (xy 337.476846 -250.964192) (xy 337.795374 -250.964192) (xy 337.799334 -250.915138)
			(xy 337.811111 -250.867354) (xy 337.830402 -250.822078) (xy 337.856705 -250.780482) (xy 337.88934 -250.743645)
			(xy 337.927461 -250.71252) (xy 337.970082 -250.687913) (xy 338.016098 -250.670461) (xy 338.064317 -250.660617)
			(xy 338.113492 -250.658636) (xy 338.162347 -250.664568) (xy 338.209618 -250.67826) (xy 338.25408 -250.699358)
			(xy 338.294583 -250.727314) (xy 338.330076 -250.761406) (xy 338.359641 -250.80075) (xy 338.382512 -250.844327)
			(xy 338.398096 -250.891008) (xy 338.405991 -250.939585) (xy 338.406486 -250.964192) (xy 338.735428 -250.964192)
			(xy 338.739388 -250.915138) (xy 338.751165 -250.867354) (xy 338.770456 -250.822078) (xy 338.796759 -250.780482)
			(xy 338.829394 -250.743645) (xy 338.867515 -250.71252) (xy 338.910136 -250.687913) (xy 338.956152 -250.670461)
			(xy 339.004371 -250.660617) (xy 339.053546 -250.658636) (xy 339.102401 -250.664568) (xy 339.149672 -250.67826)
			(xy 339.194134 -250.699358) (xy 339.234637 -250.727314) (xy 339.27013 -250.761406) (xy 339.299695 -250.80075)
			(xy 339.322566 -250.844327) (xy 339.33815 -250.891008) (xy 339.346045 -250.939585) (xy 339.34654 -250.964192)
			(xy 339.664797 -250.964192) (xy 339.668892 -250.913464) (xy 339.681071 -250.86405) (xy 339.701019 -250.81723)
			(xy 339.72822 -250.774216) (xy 339.761968 -250.736122) (xy 339.80139 -250.703935) (xy 339.845464 -250.678489)
			(xy 339.89305 -250.660442) (xy 339.942914 -250.650262) (xy 339.993766 -250.648213) (xy 340.044287 -250.654347)
			(xy 340.093171 -250.668507) (xy 340.13915 -250.690324) (xy 340.181034 -250.719234) (xy 340.217738 -250.754489)
			(xy 340.248311 -250.795175) (xy 340.271962 -250.840238) (xy 340.288078 -250.888512) (xy 340.296242 -250.938746)
			(xy 340.296754 -250.964192) (xy 340.615282 -250.964192) (xy 340.619242 -250.915138) (xy 340.631019 -250.867354)
			(xy 340.65031 -250.822078) (xy 340.676613 -250.780482) (xy 340.709248 -250.743645) (xy 340.747369 -250.71252)
			(xy 340.78999 -250.687913) (xy 340.836006 -250.670461) (xy 340.884225 -250.660617) (xy 340.9334 -250.658636)
			(xy 340.982255 -250.664568) (xy 341.029526 -250.67826) (xy 341.073988 -250.699358) (xy 341.114491 -250.727314)
			(xy 341.149984 -250.761406) (xy 341.179549 -250.80075) (xy 341.20242 -250.844327) (xy 341.218004 -250.891008)
			(xy 341.225899 -250.939585) (xy 341.226394 -250.964192) (xy 341.555336 -250.964192) (xy 341.559296 -250.915138)
			(xy 341.571073 -250.867354) (xy 341.590364 -250.822078) (xy 341.616667 -250.780482) (xy 341.649302 -250.743645)
			(xy 341.687423 -250.71252) (xy 341.730044 -250.687913) (xy 341.77606 -250.670461) (xy 341.824279 -250.660617)
			(xy 341.873454 -250.658636) (xy 341.922309 -250.664568) (xy 341.96958 -250.67826) (xy 342.014042 -250.699358)
			(xy 342.054545 -250.727314) (xy 342.090038 -250.761406) (xy 342.119603 -250.80075) (xy 342.142474 -250.844327)
			(xy 342.158058 -250.891008) (xy 342.165953 -250.939585) (xy 342.166448 -250.964192) (xy 342.49539 -250.964192)
			(xy 342.49935 -250.915138) (xy 342.511127 -250.867354) (xy 342.530418 -250.822078) (xy 342.556721 -250.780482)
			(xy 342.589356 -250.743645) (xy 342.627477 -250.71252) (xy 342.670098 -250.687913) (xy 342.716114 -250.670461)
			(xy 342.764333 -250.660617) (xy 342.813508 -250.658636) (xy 342.862363 -250.664568) (xy 342.909634 -250.67826)
			(xy 342.954096 -250.699358) (xy 342.994599 -250.727314) (xy 343.030092 -250.761406) (xy 343.059657 -250.80075)
			(xy 343.082528 -250.844327) (xy 343.098112 -250.891008) (xy 343.106007 -250.939585) (xy 343.106502 -250.964192)
			(xy 343.424759 -250.964192) (xy 343.428854 -250.913464) (xy 343.441033 -250.86405) (xy 343.460981 -250.81723)
			(xy 343.488182 -250.774216) (xy 343.52193 -250.736122) (xy 343.561352 -250.703935) (xy 343.605426 -250.678489)
			(xy 343.653012 -250.660442) (xy 343.702876 -250.650262) (xy 343.753728 -250.648213) (xy 343.804249 -250.654347)
			(xy 343.853133 -250.668507) (xy 343.899112 -250.690324) (xy 343.940996 -250.719234) (xy 343.9777 -250.754489)
			(xy 344.008273 -250.795175) (xy 344.031924 -250.840238) (xy 344.04804 -250.888512) (xy 344.056204 -250.938746)
			(xy 344.056716 -250.964192) (xy 344.056204 -250.989638) (xy 344.04804 -251.039872) (xy 344.031924 -251.088146)
			(xy 344.008273 -251.133209) (xy 343.9777 -251.173895) (xy 343.940996 -251.20915) (xy 343.899112 -251.23806)
			(xy 343.853133 -251.259877) (xy 343.804249 -251.274037) (xy 343.753728 -251.280171) (xy 343.702876 -251.278122)
			(xy 343.653012 -251.267942) (xy 343.605426 -251.249895) (xy 343.561352 -251.224449) (xy 343.52193 -251.192262)
			(xy 343.488182 -251.154168) (xy 343.460981 -251.111154) (xy 343.441033 -251.064334) (xy 343.428854 -251.01492)
			(xy 343.424759 -250.964192) (xy 343.106502 -250.964192) (xy 343.106007 -250.988799) (xy 343.098112 -251.037376)
			(xy 343.082528 -251.084057) (xy 343.059657 -251.127634) (xy 343.030092 -251.166978) (xy 342.994599 -251.20107)
			(xy 342.954096 -251.229026) (xy 342.909634 -251.250124) (xy 342.862363 -251.263816) (xy 342.813508 -251.269748)
			(xy 342.764333 -251.267767) (xy 342.716114 -251.257923) (xy 342.670098 -251.240471) (xy 342.627477 -251.215864)
			(xy 342.589356 -251.184739) (xy 342.556721 -251.147902) (xy 342.530418 -251.106306) (xy 342.511127 -251.06103)
			(xy 342.49935 -251.013246) (xy 342.49539 -250.964192) (xy 342.166448 -250.964192) (xy 342.165953 -250.988799)
			(xy 342.158058 -251.037376) (xy 342.142474 -251.084057) (xy 342.119603 -251.127634) (xy 342.090038 -251.166978)
			(xy 342.054545 -251.20107) (xy 342.014042 -251.229026) (xy 341.96958 -251.250124) (xy 341.922309 -251.263816)
			(xy 341.873454 -251.269748) (xy 341.824279 -251.267767) (xy 341.77606 -251.257923) (xy 341.730044 -251.240471)
			(xy 341.687423 -251.215864) (xy 341.649302 -251.184739) (xy 341.616667 -251.147902) (xy 341.590364 -251.106306)
			(xy 341.571073 -251.06103) (xy 341.559296 -251.013246) (xy 341.555336 -250.964192) (xy 341.226394 -250.964192)
			(xy 341.225899 -250.988799) (xy 341.218004 -251.037376) (xy 341.20242 -251.084057) (xy 341.179549 -251.127634)
			(xy 341.149984 -251.166978) (xy 341.114491 -251.20107) (xy 341.073988 -251.229026) (xy 341.029526 -251.250124)
			(xy 340.982255 -251.263816) (xy 340.9334 -251.269748) (xy 340.884225 -251.267767) (xy 340.836006 -251.257923)
			(xy 340.78999 -251.240471) (xy 340.747369 -251.215864) (xy 340.709248 -251.184739) (xy 340.676613 -251.147902)
			(xy 340.65031 -251.106306) (xy 340.631019 -251.06103) (xy 340.619242 -251.013246) (xy 340.615282 -250.964192)
			(xy 340.296754 -250.964192) (xy 340.296242 -250.989638) (xy 340.288078 -251.039872) (xy 340.271962 -251.088146)
			(xy 340.248311 -251.133209) (xy 340.217738 -251.173895) (xy 340.181034 -251.20915) (xy 340.13915 -251.23806)
			(xy 340.093171 -251.259877) (xy 340.044287 -251.274037) (xy 339.993766 -251.280171) (xy 339.942914 -251.278122)
			(xy 339.89305 -251.267942) (xy 339.845464 -251.249895) (xy 339.80139 -251.224449) (xy 339.761968 -251.192262)
			(xy 339.72822 -251.154168) (xy 339.701019 -251.111154) (xy 339.681071 -251.064334) (xy 339.668892 -251.01492)
			(xy 339.664797 -250.964192) (xy 339.34654 -250.964192) (xy 339.346045 -250.988799) (xy 339.33815 -251.037376)
			(xy 339.322566 -251.084057) (xy 339.299695 -251.127634) (xy 339.27013 -251.166978) (xy 339.234637 -251.20107)
			(xy 339.194134 -251.229026) (xy 339.149672 -251.250124) (xy 339.102401 -251.263816) (xy 339.053546 -251.269748)
			(xy 339.004371 -251.267767) (xy 338.956152 -251.257923) (xy 338.910136 -251.240471) (xy 338.867515 -251.215864)
			(xy 338.829394 -251.184739) (xy 338.796759 -251.147902) (xy 338.770456 -251.106306) (xy 338.751165 -251.06103)
			(xy 338.739388 -251.013246) (xy 338.735428 -250.964192) (xy 338.406486 -250.964192) (xy 338.405991 -250.988799)
			(xy 338.398096 -251.037376) (xy 338.382512 -251.084057) (xy 338.359641 -251.127634) (xy 338.330076 -251.166978)
			(xy 338.294583 -251.20107) (xy 338.25408 -251.229026) (xy 338.209618 -251.250124) (xy 338.162347 -251.263816)
			(xy 338.113492 -251.269748) (xy 338.064317 -251.267767) (xy 338.016098 -251.257923) (xy 337.970082 -251.240471)
			(xy 337.927461 -251.215864) (xy 337.88934 -251.184739) (xy 337.856705 -251.147902) (xy 337.830402 -251.106306)
			(xy 337.811111 -251.06103) (xy 337.799334 -251.013246) (xy 337.795374 -250.964192) (xy 337.476846 -250.964192)
			(xy 337.476334 -250.989638) (xy 337.46817 -251.039872) (xy 337.452054 -251.088146) (xy 337.428403 -251.133209)
			(xy 337.39783 -251.173895) (xy 337.361126 -251.20915) (xy 337.319242 -251.23806) (xy 337.273263 -251.259877)
			(xy 337.224379 -251.274037) (xy 337.173858 -251.280171) (xy 337.123006 -251.278122) (xy 337.073142 -251.267942)
			(xy 337.025556 -251.249895) (xy 336.981482 -251.224449) (xy 336.94206 -251.192262) (xy 336.908312 -251.154168)
			(xy 336.881111 -251.111154) (xy 336.861163 -251.064334) (xy 336.848984 -251.01492) (xy 336.844889 -250.964192)
			(xy 336.526378 -250.964192) (xy 336.525883 -250.988799) (xy 336.517988 -251.037376) (xy 336.502404 -251.084057)
			(xy 336.479533 -251.127634) (xy 336.449968 -251.166978) (xy 336.414475 -251.20107) (xy 336.373972 -251.229026)
			(xy 336.32951 -251.250124) (xy 336.282239 -251.263816) (xy 336.233384 -251.269748) (xy 336.184209 -251.267767)
			(xy 336.13599 -251.257923) (xy 336.089974 -251.240471) (xy 336.047353 -251.215864) (xy 336.009232 -251.184739)
			(xy 335.976597 -251.147902) (xy 335.950294 -251.106306) (xy 335.931003 -251.06103) (xy 335.919226 -251.013246)
			(xy 335.915266 -250.964192) (xy 335.586324 -250.964192) (xy 335.585829 -250.988799) (xy 335.577934 -251.037376)
			(xy 335.56235 -251.084057) (xy 335.539479 -251.127634) (xy 335.509914 -251.166978) (xy 335.474421 -251.20107)
			(xy 335.433918 -251.229026) (xy 335.389456 -251.250124) (xy 335.342185 -251.263816) (xy 335.29333 -251.269748)
			(xy 335.244155 -251.267767) (xy 335.195936 -251.257923) (xy 335.14992 -251.240471) (xy 335.107299 -251.215864)
			(xy 335.069178 -251.184739) (xy 335.036543 -251.147902) (xy 335.01024 -251.106306) (xy 334.990949 -251.06103)
			(xy 334.979172 -251.013246) (xy 334.975212 -250.964192) (xy 334.646524 -250.964192) (xy 334.646029 -250.988799)
			(xy 334.638134 -251.037376) (xy 334.62255 -251.084057) (xy 334.599679 -251.127634) (xy 334.570114 -251.166978)
			(xy 334.534621 -251.20107) (xy 334.494118 -251.229026) (xy 334.449656 -251.250124) (xy 334.402385 -251.263816)
			(xy 334.35353 -251.269748) (xy 334.304355 -251.267767) (xy 334.256136 -251.257923) (xy 334.21012 -251.240471)
			(xy 334.167499 -251.215864) (xy 334.129378 -251.184739) (xy 334.096743 -251.147902) (xy 334.07044 -251.106306)
			(xy 334.051149 -251.06103) (xy 334.039372 -251.013246) (xy 334.035412 -250.964192) (xy 333.716884 -250.964192)
			(xy 333.716372 -250.989638) (xy 333.708208 -251.039872) (xy 333.692092 -251.088146) (xy 333.668441 -251.133209)
			(xy 333.637868 -251.173895) (xy 333.601164 -251.20915) (xy 333.55928 -251.23806) (xy 333.513301 -251.259877)
			(xy 333.464417 -251.274037) (xy 333.413896 -251.280171) (xy 333.363044 -251.278122) (xy 333.31318 -251.267942)
			(xy 333.265594 -251.249895) (xy 333.22152 -251.224449) (xy 333.182098 -251.192262) (xy 333.14835 -251.154168)
			(xy 333.121149 -251.111154) (xy 333.101201 -251.064334) (xy 333.089022 -251.01492) (xy 333.084927 -250.964192)
			(xy 332.766416 -250.964192) (xy 332.765921 -250.988799) (xy 332.758026 -251.037376) (xy 332.742442 -251.084057)
			(xy 332.719571 -251.127634) (xy 332.690006 -251.166978) (xy 332.654513 -251.20107) (xy 332.61401 -251.229026)
			(xy 332.569548 -251.250124) (xy 332.522277 -251.263816) (xy 332.473422 -251.269748) (xy 332.424247 -251.267767)
			(xy 332.376028 -251.257923) (xy 332.330012 -251.240471) (xy 332.287391 -251.215864) (xy 332.24927 -251.184739)
			(xy 332.216635 -251.147902) (xy 332.190332 -251.106306) (xy 332.171041 -251.06103) (xy 332.159264 -251.013246)
			(xy 332.155304 -250.964192) (xy 331.826362 -250.964192) (xy 331.825867 -250.988799) (xy 331.817972 -251.037376)
			(xy 331.802388 -251.084057) (xy 331.779517 -251.127634) (xy 331.749952 -251.166978) (xy 331.714459 -251.20107)
			(xy 331.673956 -251.229026) (xy 331.629494 -251.250124) (xy 331.582223 -251.263816) (xy 331.533368 -251.269748)
			(xy 331.484193 -251.267767) (xy 331.435974 -251.257923) (xy 331.389958 -251.240471) (xy 331.347337 -251.215864)
			(xy 331.309216 -251.184739) (xy 331.276581 -251.147902) (xy 331.250278 -251.106306) (xy 331.230987 -251.06103)
			(xy 331.21921 -251.013246) (xy 331.21525 -250.964192) (xy 330.896722 -250.964192) (xy 330.89621 -250.989638)
			(xy 330.888046 -251.039872) (xy 330.87193 -251.088146) (xy 330.848279 -251.133209) (xy 330.817706 -251.173895)
			(xy 330.781002 -251.20915) (xy 330.739118 -251.23806) (xy 330.693139 -251.259877) (xy 330.644255 -251.274037)
			(xy 330.593734 -251.280171) (xy 330.542882 -251.278122) (xy 330.493018 -251.267942) (xy 330.445432 -251.249895)
			(xy 330.401358 -251.224449) (xy 330.361936 -251.192262) (xy 330.328188 -251.154168) (xy 330.300987 -251.111154)
			(xy 330.281039 -251.064334) (xy 330.26886 -251.01492) (xy 330.264765 -250.964192) (xy 329.946508 -250.964192)
			(xy 329.946013 -250.988799) (xy 329.938118 -251.037376) (xy 329.922534 -251.084057) (xy 329.899663 -251.127634)
			(xy 329.870098 -251.166978) (xy 329.834605 -251.20107) (xy 329.794102 -251.229026) (xy 329.74964 -251.250124)
			(xy 329.702369 -251.263816) (xy 329.653514 -251.269748) (xy 329.604339 -251.267767) (xy 329.55612 -251.257923)
			(xy 329.510104 -251.240471) (xy 329.467483 -251.215864) (xy 329.429362 -251.184739) (xy 329.396727 -251.147902)
			(xy 329.370424 -251.106306) (xy 329.351133 -251.06103) (xy 329.339356 -251.013246) (xy 329.335396 -250.964192)
			(xy 329.006454 -250.964192) (xy 329.005959 -250.988799) (xy 328.998064 -251.037376) (xy 328.98248 -251.084057)
			(xy 328.959609 -251.127634) (xy 328.930044 -251.166978) (xy 328.894551 -251.20107) (xy 328.854048 -251.229026)
			(xy 328.809586 -251.250124) (xy 328.762315 -251.263816) (xy 328.71346 -251.269748) (xy 328.664285 -251.267767)
			(xy 328.616066 -251.257923) (xy 328.57005 -251.240471) (xy 328.527429 -251.215864) (xy 328.489308 -251.184739)
			(xy 328.456673 -251.147902) (xy 328.43037 -251.106306) (xy 328.411079 -251.06103) (xy 328.399302 -251.013246)
			(xy 328.395342 -250.964192) (xy 328.0664 -250.964192) (xy 328.065905 -250.988799) (xy 328.05801 -251.037376)
			(xy 328.042426 -251.084057) (xy 328.019555 -251.127634) (xy 327.98999 -251.166978) (xy 327.954497 -251.20107)
			(xy 327.913994 -251.229026) (xy 327.869532 -251.250124) (xy 327.822261 -251.263816) (xy 327.773406 -251.269748)
			(xy 327.724231 -251.267767) (xy 327.676012 -251.257923) (xy 327.629996 -251.240471) (xy 327.587375 -251.215864)
			(xy 327.549254 -251.184739) (xy 327.516619 -251.147902) (xy 327.490316 -251.106306) (xy 327.471025 -251.06103)
			(xy 327.459248 -251.013246) (xy 327.455288 -250.964192) (xy 327.126346 -250.964192) (xy 327.125851 -250.988799)
			(xy 327.117956 -251.037376) (xy 327.102372 -251.084057) (xy 327.079501 -251.127634) (xy 327.049936 -251.166978)
			(xy 327.014443 -251.20107) (xy 326.97394 -251.229026) (xy 326.929478 -251.250124) (xy 326.882207 -251.263816)
			(xy 326.833352 -251.269748) (xy 326.784177 -251.267767) (xy 326.735958 -251.257923) (xy 326.689942 -251.240471)
			(xy 326.647321 -251.215864) (xy 326.6092 -251.184739) (xy 326.576565 -251.147902) (xy 326.550262 -251.106306)
			(xy 326.530971 -251.06103) (xy 326.519194 -251.013246) (xy 326.515234 -250.964192) (xy 324.903545 -250.964192)
			(xy 324.905872 -250.965296) (xy 324.946375 -250.993252) (xy 324.981868 -251.027344) (xy 325.011433 -251.066688)
			(xy 325.034304 -251.110265) (xy 325.049888 -251.156946) (xy 325.057783 -251.205523) (xy 325.058278 -251.23013)
			(xy 325.057783 -251.254737) (xy 325.049888 -251.303314) (xy 325.034304 -251.349995) (xy 325.011433 -251.393572)
			(xy 324.981868 -251.432916) (xy 324.946375 -251.467008) (xy 324.905872 -251.494964) (xy 324.86141 -251.516062)
			(xy 324.814139 -251.529754) (xy 324.765284 -251.535686) (xy 324.716109 -251.533705) (xy 324.66789 -251.523861)
			(xy 324.621874 -251.506409) (xy 324.579253 -251.481802) (xy 324.541132 -251.450677) (xy 324.508497 -251.41384)
			(xy 324.482194 -251.372244) (xy 324.462903 -251.326968) (xy 324.451126 -251.279184) (xy 324.447166 -251.23013)
			(xy 310.45912 -251.23013) (xy 310.45912 -251.774198) (xy 326.045334 -251.774198) (xy 326.049294 -251.725144)
			(xy 326.061071 -251.67736) (xy 326.080362 -251.632084) (xy 326.106665 -251.590488) (xy 326.1393 -251.553651)
			(xy 326.177421 -251.522526) (xy 326.220042 -251.497919) (xy 326.266058 -251.480467) (xy 326.314277 -251.470623)
			(xy 326.363452 -251.468642) (xy 326.412307 -251.474574) (xy 326.459578 -251.488266) (xy 326.50404 -251.509364)
			(xy 326.544543 -251.53732) (xy 326.580036 -251.571412) (xy 326.609601 -251.610756) (xy 326.632472 -251.654333)
			(xy 326.648056 -251.701014) (xy 326.655951 -251.749591) (xy 326.656446 -251.774198) (xy 328.854811 -251.774198)
			(xy 328.858906 -251.72347) (xy 328.871085 -251.674056) (xy 328.891033 -251.627236) (xy 328.918234 -251.584222)
			(xy 328.951982 -251.546128) (xy 328.991404 -251.513941) (xy 329.035478 -251.488495) (xy 329.083064 -251.470448)
			(xy 329.132928 -251.460268) (xy 329.18378 -251.458219) (xy 329.234301 -251.464353) (xy 329.283185 -251.478513)
			(xy 329.329164 -251.50033) (xy 329.371048 -251.52924) (xy 329.407752 -251.564495) (xy 329.438325 -251.605181)
			(xy 329.461976 -251.650244) (xy 329.478092 -251.698518) (xy 329.486256 -251.748752) (xy 329.486768 -251.774198)
			(xy 329.805296 -251.774198) (xy 329.809256 -251.725144) (xy 329.821033 -251.67736) (xy 329.840324 -251.632084)
			(xy 329.866627 -251.590488) (xy 329.899262 -251.553651) (xy 329.937383 -251.522526) (xy 329.980004 -251.497919)
			(xy 330.02602 -251.480467) (xy 330.074239 -251.470623) (xy 330.123414 -251.468642) (xy 330.172269 -251.474574)
			(xy 330.21954 -251.488266) (xy 330.264002 -251.509364) (xy 330.304505 -251.53732) (xy 330.339998 -251.571412)
			(xy 330.369563 -251.610756) (xy 330.392434 -251.654333) (xy 330.408018 -251.701014) (xy 330.415913 -251.749591)
			(xy 330.416408 -251.774198) (xy 330.74535 -251.774198) (xy 330.74931 -251.725144) (xy 330.761087 -251.67736)
			(xy 330.780378 -251.632084) (xy 330.806681 -251.590488) (xy 330.839316 -251.553651) (xy 330.877437 -251.522526)
			(xy 330.920058 -251.497919) (xy 330.966074 -251.480467) (xy 331.014293 -251.470623) (xy 331.063468 -251.468642)
			(xy 331.112323 -251.474574) (xy 331.159594 -251.488266) (xy 331.204056 -251.509364) (xy 331.244559 -251.53732)
			(xy 331.280052 -251.571412) (xy 331.309617 -251.610756) (xy 331.332488 -251.654333) (xy 331.348072 -251.701014)
			(xy 331.355967 -251.749591) (xy 331.356462 -251.774198) (xy 331.674973 -251.774198) (xy 331.679068 -251.72347)
			(xy 331.691247 -251.674056) (xy 331.711195 -251.627236) (xy 331.738396 -251.584222) (xy 331.772144 -251.546128)
			(xy 331.811566 -251.513941) (xy 331.85564 -251.488495) (xy 331.903226 -251.470448) (xy 331.95309 -251.460268)
			(xy 332.003942 -251.458219) (xy 332.054463 -251.464353) (xy 332.103347 -251.478513) (xy 332.149326 -251.50033)
			(xy 332.19121 -251.52924) (xy 332.227914 -251.564495) (xy 332.258487 -251.605181) (xy 332.282138 -251.650244)
			(xy 332.298254 -251.698518) (xy 332.306418 -251.748752) (xy 332.30693 -251.774198) (xy 332.625204 -251.774198)
			(xy 332.629164 -251.725144) (xy 332.640941 -251.67736) (xy 332.660232 -251.632084) (xy 332.686535 -251.590488)
			(xy 332.71917 -251.553651) (xy 332.757291 -251.522526) (xy 332.799912 -251.497919) (xy 332.845928 -251.480467)
			(xy 332.894147 -251.470623) (xy 332.943322 -251.468642) (xy 332.992177 -251.474574) (xy 333.039448 -251.488266)
			(xy 333.08391 -251.509364) (xy 333.124413 -251.53732) (xy 333.159906 -251.571412) (xy 333.189471 -251.610756)
			(xy 333.212342 -251.654333) (xy 333.227926 -251.701014) (xy 333.235821 -251.749591) (xy 333.236316 -251.774198)
			(xy 333.565258 -251.774198) (xy 333.569218 -251.725144) (xy 333.580995 -251.67736) (xy 333.600286 -251.632084)
			(xy 333.626589 -251.590488) (xy 333.659224 -251.553651) (xy 333.697345 -251.522526) (xy 333.739966 -251.497919)
			(xy 333.785982 -251.480467) (xy 333.834201 -251.470623) (xy 333.883376 -251.468642) (xy 333.932231 -251.474574)
			(xy 333.979502 -251.488266) (xy 334.023964 -251.509364) (xy 334.064467 -251.53732) (xy 334.09996 -251.571412)
			(xy 334.129525 -251.610756) (xy 334.152396 -251.654333) (xy 334.16798 -251.701014) (xy 334.175875 -251.749591)
			(xy 334.17637 -251.774198) (xy 335.434935 -251.774198) (xy 335.43903 -251.72347) (xy 335.451209 -251.674056)
			(xy 335.471157 -251.627236) (xy 335.498358 -251.584222) (xy 335.532106 -251.546128) (xy 335.571528 -251.513941)
			(xy 335.615602 -251.488495) (xy 335.663188 -251.470448) (xy 335.713052 -251.460268) (xy 335.763904 -251.458219)
			(xy 335.814425 -251.464353) (xy 335.863309 -251.478513) (xy 335.909288 -251.50033) (xy 335.951172 -251.52924)
			(xy 335.987876 -251.564495) (xy 336.018449 -251.605181) (xy 336.0421 -251.650244) (xy 336.058216 -251.698518)
			(xy 336.06638 -251.748752) (xy 336.066892 -251.774198) (xy 336.38542 -251.774198) (xy 336.38938 -251.725144)
			(xy 336.401157 -251.67736) (xy 336.420448 -251.632084) (xy 336.446751 -251.590488) (xy 336.479386 -251.553651)
			(xy 336.517507 -251.522526) (xy 336.560128 -251.497919) (xy 336.606144 -251.480467) (xy 336.654363 -251.470623)
			(xy 336.703538 -251.468642) (xy 336.752393 -251.474574) (xy 336.799664 -251.488266) (xy 336.844126 -251.509364)
			(xy 336.884629 -251.53732) (xy 336.920122 -251.571412) (xy 336.949687 -251.610756) (xy 336.972558 -251.654333)
			(xy 336.988142 -251.701014) (xy 336.996037 -251.749591) (xy 336.996532 -251.774198) (xy 337.32522 -251.774198)
			(xy 337.32918 -251.725144) (xy 337.340957 -251.67736) (xy 337.360248 -251.632084) (xy 337.386551 -251.590488)
			(xy 337.419186 -251.553651) (xy 337.457307 -251.522526) (xy 337.499928 -251.497919) (xy 337.545944 -251.480467)
			(xy 337.594163 -251.470623) (xy 337.643338 -251.468642) (xy 337.692193 -251.474574) (xy 337.739464 -251.488266)
			(xy 337.783926 -251.509364) (xy 337.824429 -251.53732) (xy 337.859922 -251.571412) (xy 337.889487 -251.610756)
			(xy 337.912358 -251.654333) (xy 337.927942 -251.701014) (xy 337.935837 -251.749591) (xy 337.936332 -251.774198)
			(xy 338.254843 -251.774198) (xy 338.258938 -251.72347) (xy 338.271117 -251.674056) (xy 338.291065 -251.627236)
			(xy 338.318266 -251.584222) (xy 338.352014 -251.546128) (xy 338.391436 -251.513941) (xy 338.43551 -251.488495)
			(xy 338.483096 -251.470448) (xy 338.53296 -251.460268) (xy 338.583812 -251.458219) (xy 338.634333 -251.464353)
			(xy 338.683217 -251.478513) (xy 338.729196 -251.50033) (xy 338.77108 -251.52924) (xy 338.807784 -251.564495)
			(xy 338.838357 -251.605181) (xy 338.862008 -251.650244) (xy 338.878124 -251.698518) (xy 338.886288 -251.748752)
			(xy 338.8868 -251.774198) (xy 339.205328 -251.774198) (xy 339.209288 -251.725144) (xy 339.221065 -251.67736)
			(xy 339.240356 -251.632084) (xy 339.266659 -251.590488) (xy 339.299294 -251.553651) (xy 339.337415 -251.522526)
			(xy 339.380036 -251.497919) (xy 339.426052 -251.480467) (xy 339.474271 -251.470623) (xy 339.523446 -251.468642)
			(xy 339.572301 -251.474574) (xy 339.619572 -251.488266) (xy 339.664034 -251.509364) (xy 339.704537 -251.53732)
			(xy 339.74003 -251.571412) (xy 339.769595 -251.610756) (xy 339.792466 -251.654333) (xy 339.80805 -251.701014)
			(xy 339.815945 -251.749591) (xy 339.81644 -251.774198) (xy 340.145382 -251.774198) (xy 340.149342 -251.725144)
			(xy 340.161119 -251.67736) (xy 340.18041 -251.632084) (xy 340.206713 -251.590488) (xy 340.239348 -251.553651)
			(xy 340.277469 -251.522526) (xy 340.32009 -251.497919) (xy 340.366106 -251.480467) (xy 340.414325 -251.470623)
			(xy 340.4635 -251.468642) (xy 340.512355 -251.474574) (xy 340.559626 -251.488266) (xy 340.604088 -251.509364)
			(xy 340.644591 -251.53732) (xy 340.680084 -251.571412) (xy 340.709649 -251.610756) (xy 340.73252 -251.654333)
			(xy 340.748104 -251.701014) (xy 340.755999 -251.749591) (xy 340.756494 -251.774198) (xy 342.014805 -251.774198)
			(xy 342.0189 -251.72347) (xy 342.031079 -251.674056) (xy 342.051027 -251.627236) (xy 342.078228 -251.584222)
			(xy 342.111976 -251.546128) (xy 342.151398 -251.513941) (xy 342.195472 -251.488495) (xy 342.243058 -251.470448)
			(xy 342.292922 -251.460268) (xy 342.343774 -251.458219) (xy 342.394295 -251.464353) (xy 342.443179 -251.478513)
			(xy 342.489158 -251.50033) (xy 342.531042 -251.52924) (xy 342.567746 -251.564495) (xy 342.598319 -251.605181)
			(xy 342.62197 -251.650244) (xy 342.638086 -251.698518) (xy 342.64625 -251.748752) (xy 342.646762 -251.774198)
			(xy 342.96529 -251.774198) (xy 342.96925 -251.725144) (xy 342.981027 -251.67736) (xy 343.000318 -251.632084)
			(xy 343.026621 -251.590488) (xy 343.059256 -251.553651) (xy 343.097377 -251.522526) (xy 343.139998 -251.497919)
			(xy 343.186014 -251.480467) (xy 343.234233 -251.470623) (xy 343.283408 -251.468642) (xy 343.332263 -251.474574)
			(xy 343.379534 -251.488266) (xy 343.423996 -251.509364) (xy 343.464499 -251.53732) (xy 343.499992 -251.571412)
			(xy 343.529557 -251.610756) (xy 343.552428 -251.654333) (xy 343.568012 -251.701014) (xy 343.575907 -251.749591)
			(xy 343.576402 -251.774198) (xy 343.905344 -251.774198) (xy 343.909304 -251.725144) (xy 343.921081 -251.67736)
			(xy 343.940372 -251.632084) (xy 343.966675 -251.590488) (xy 343.99931 -251.553651) (xy 344.037431 -251.522526)
			(xy 344.080052 -251.497919) (xy 344.126068 -251.480467) (xy 344.174287 -251.470623) (xy 344.223462 -251.468642)
			(xy 344.272317 -251.474574) (xy 344.319588 -251.488266) (xy 344.36405 -251.509364) (xy 344.404553 -251.53732)
			(xy 344.440046 -251.571412) (xy 344.469611 -251.610756) (xy 344.492482 -251.654333) (xy 344.508066 -251.701014)
			(xy 344.515961 -251.749591) (xy 344.516456 -251.774198) (xy 344.515961 -251.798805) (xy 344.508066 -251.847382)
			(xy 344.492482 -251.894063) (xy 344.469611 -251.93764) (xy 344.440046 -251.976984) (xy 344.404553 -252.011076)
			(xy 344.36405 -252.039032) (xy 344.319588 -252.06013) (xy 344.272317 -252.073822) (xy 344.223462 -252.079754)
			(xy 344.174287 -252.077773) (xy 344.126068 -252.067929) (xy 344.080052 -252.050477) (xy 344.037431 -252.02587)
			(xy 343.99931 -251.994745) (xy 343.966675 -251.957908) (xy 343.940372 -251.916312) (xy 343.921081 -251.871036)
			(xy 343.909304 -251.823252) (xy 343.905344 -251.774198) (xy 343.576402 -251.774198) (xy 343.575907 -251.798805)
			(xy 343.568012 -251.847382) (xy 343.552428 -251.894063) (xy 343.529557 -251.93764) (xy 343.499992 -251.976984)
			(xy 343.464499 -252.011076) (xy 343.423996 -252.039032) (xy 343.379534 -252.06013) (xy 343.332263 -252.073822)
			(xy 343.283408 -252.079754) (xy 343.234233 -252.077773) (xy 343.186014 -252.067929) (xy 343.139998 -252.050477)
			(xy 343.097377 -252.02587) (xy 343.059256 -251.994745) (xy 343.026621 -251.957908) (xy 343.000318 -251.916312)
			(xy 342.981027 -251.871036) (xy 342.96925 -251.823252) (xy 342.96529 -251.774198) (xy 342.646762 -251.774198)
			(xy 342.64625 -251.799644) (xy 342.638086 -251.849878) (xy 342.62197 -251.898152) (xy 342.598319 -251.943215)
			(xy 342.567746 -251.983901) (xy 342.531042 -252.019156) (xy 342.489158 -252.048066) (xy 342.443179 -252.069883)
			(xy 342.394295 -252.084043) (xy 342.343774 -252.090177) (xy 342.292922 -252.088128) (xy 342.243058 -252.077948)
			(xy 342.195472 -252.059901) (xy 342.151398 -252.034455) (xy 342.111976 -252.002268) (xy 342.078228 -251.964174)
			(xy 342.051027 -251.92116) (xy 342.031079 -251.87434) (xy 342.0189 -251.824926) (xy 342.014805 -251.774198)
			(xy 340.756494 -251.774198) (xy 340.755999 -251.798805) (xy 340.748104 -251.847382) (xy 340.73252 -251.894063)
			(xy 340.709649 -251.93764) (xy 340.680084 -251.976984) (xy 340.644591 -252.011076) (xy 340.604088 -252.039032)
			(xy 340.559626 -252.06013) (xy 340.512355 -252.073822) (xy 340.4635 -252.079754) (xy 340.414325 -252.077773)
			(xy 340.366106 -252.067929) (xy 340.32009 -252.050477) (xy 340.277469 -252.02587) (xy 340.239348 -251.994745)
			(xy 340.206713 -251.957908) (xy 340.18041 -251.916312) (xy 340.161119 -251.871036) (xy 340.149342 -251.823252)
			(xy 340.145382 -251.774198) (xy 339.81644 -251.774198) (xy 339.815945 -251.798805) (xy 339.80805 -251.847382)
			(xy 339.792466 -251.894063) (xy 339.769595 -251.93764) (xy 339.74003 -251.976984) (xy 339.704537 -252.011076)
			(xy 339.664034 -252.039032) (xy 339.619572 -252.06013) (xy 339.572301 -252.073822) (xy 339.523446 -252.079754)
			(xy 339.474271 -252.077773) (xy 339.426052 -252.067929) (xy 339.380036 -252.050477) (xy 339.337415 -252.02587)
			(xy 339.299294 -251.994745) (xy 339.266659 -251.957908) (xy 339.240356 -251.916312) (xy 339.221065 -251.871036)
			(xy 339.209288 -251.823252) (xy 339.205328 -251.774198) (xy 338.8868 -251.774198) (xy 338.886288 -251.799644)
			(xy 338.878124 -251.849878) (xy 338.862008 -251.898152) (xy 338.838357 -251.943215) (xy 338.807784 -251.983901)
			(xy 338.77108 -252.019156) (xy 338.729196 -252.048066) (xy 338.683217 -252.069883) (xy 338.634333 -252.084043)
			(xy 338.583812 -252.090177) (xy 338.53296 -252.088128) (xy 338.483096 -252.077948) (xy 338.43551 -252.059901)
			(xy 338.391436 -252.034455) (xy 338.352014 -252.002268) (xy 338.318266 -251.964174) (xy 338.291065 -251.92116)
			(xy 338.271117 -251.87434) (xy 338.258938 -251.824926) (xy 338.254843 -251.774198) (xy 337.936332 -251.774198)
			(xy 337.935837 -251.798805) (xy 337.927942 -251.847382) (xy 337.912358 -251.894063) (xy 337.889487 -251.93764)
			(xy 337.859922 -251.976984) (xy 337.824429 -252.011076) (xy 337.783926 -252.039032) (xy 337.739464 -252.06013)
			(xy 337.692193 -252.073822) (xy 337.643338 -252.079754) (xy 337.594163 -252.077773) (xy 337.545944 -252.067929)
			(xy 337.499928 -252.050477) (xy 337.457307 -252.02587) (xy 337.419186 -251.994745) (xy 337.386551 -251.957908)
			(xy 337.360248 -251.916312) (xy 337.340957 -251.871036) (xy 337.32918 -251.823252) (xy 337.32522 -251.774198)
			(xy 336.996532 -251.774198) (xy 336.996037 -251.798805) (xy 336.988142 -251.847382) (xy 336.972558 -251.894063)
			(xy 336.949687 -251.93764) (xy 336.920122 -251.976984) (xy 336.884629 -252.011076) (xy 336.844126 -252.039032)
			(xy 336.799664 -252.06013) (xy 336.752393 -252.073822) (xy 336.703538 -252.079754) (xy 336.654363 -252.077773)
			(xy 336.606144 -252.067929) (xy 336.560128 -252.050477) (xy 336.517507 -252.02587) (xy 336.479386 -251.994745)
			(xy 336.446751 -251.957908) (xy 336.420448 -251.916312) (xy 336.401157 -251.871036) (xy 336.38938 -251.823252)
			(xy 336.38542 -251.774198) (xy 336.066892 -251.774198) (xy 336.06638 -251.799644) (xy 336.058216 -251.849878)
			(xy 336.0421 -251.898152) (xy 336.018449 -251.943215) (xy 335.987876 -251.983901) (xy 335.951172 -252.019156)
			(xy 335.909288 -252.048066) (xy 335.863309 -252.069883) (xy 335.814425 -252.084043) (xy 335.763904 -252.090177)
			(xy 335.713052 -252.088128) (xy 335.663188 -252.077948) (xy 335.615602 -252.059901) (xy 335.571528 -252.034455)
			(xy 335.532106 -252.002268) (xy 335.498358 -251.964174) (xy 335.471157 -251.92116) (xy 335.451209 -251.87434)
			(xy 335.43903 -251.824926) (xy 335.434935 -251.774198) (xy 334.17637 -251.774198) (xy 334.175875 -251.798805)
			(xy 334.16798 -251.847382) (xy 334.152396 -251.894063) (xy 334.129525 -251.93764) (xy 334.09996 -251.976984)
			(xy 334.064467 -252.011076) (xy 334.023964 -252.039032) (xy 333.979502 -252.06013) (xy 333.932231 -252.073822)
			(xy 333.883376 -252.079754) (xy 333.834201 -252.077773) (xy 333.785982 -252.067929) (xy 333.739966 -252.050477)
			(xy 333.697345 -252.02587) (xy 333.659224 -251.994745) (xy 333.626589 -251.957908) (xy 333.600286 -251.916312)
			(xy 333.580995 -251.871036) (xy 333.569218 -251.823252) (xy 333.565258 -251.774198) (xy 333.236316 -251.774198)
			(xy 333.235821 -251.798805) (xy 333.227926 -251.847382) (xy 333.212342 -251.894063) (xy 333.189471 -251.93764)
			(xy 333.159906 -251.976984) (xy 333.124413 -252.011076) (xy 333.08391 -252.039032) (xy 333.039448 -252.06013)
			(xy 332.992177 -252.073822) (xy 332.943322 -252.079754) (xy 332.894147 -252.077773) (xy 332.845928 -252.067929)
			(xy 332.799912 -252.050477) (xy 332.757291 -252.02587) (xy 332.71917 -251.994745) (xy 332.686535 -251.957908)
			(xy 332.660232 -251.916312) (xy 332.640941 -251.871036) (xy 332.629164 -251.823252) (xy 332.625204 -251.774198)
			(xy 332.30693 -251.774198) (xy 332.306418 -251.799644) (xy 332.298254 -251.849878) (xy 332.282138 -251.898152)
			(xy 332.258487 -251.943215) (xy 332.227914 -251.983901) (xy 332.19121 -252.019156) (xy 332.149326 -252.048066)
			(xy 332.103347 -252.069883) (xy 332.054463 -252.084043) (xy 332.003942 -252.090177) (xy 331.95309 -252.088128)
			(xy 331.903226 -252.077948) (xy 331.85564 -252.059901) (xy 331.811566 -252.034455) (xy 331.772144 -252.002268)
			(xy 331.738396 -251.964174) (xy 331.711195 -251.92116) (xy 331.691247 -251.87434) (xy 331.679068 -251.824926)
			(xy 331.674973 -251.774198) (xy 331.356462 -251.774198) (xy 331.355967 -251.798805) (xy 331.348072 -251.847382)
			(xy 331.332488 -251.894063) (xy 331.309617 -251.93764) (xy 331.280052 -251.976984) (xy 331.244559 -252.011076)
			(xy 331.204056 -252.039032) (xy 331.159594 -252.06013) (xy 331.112323 -252.073822) (xy 331.063468 -252.079754)
			(xy 331.014293 -252.077773) (xy 330.966074 -252.067929) (xy 330.920058 -252.050477) (xy 330.877437 -252.02587)
			(xy 330.839316 -251.994745) (xy 330.806681 -251.957908) (xy 330.780378 -251.916312) (xy 330.761087 -251.871036)
			(xy 330.74931 -251.823252) (xy 330.74535 -251.774198) (xy 330.416408 -251.774198) (xy 330.415913 -251.798805)
			(xy 330.408018 -251.847382) (xy 330.392434 -251.894063) (xy 330.369563 -251.93764) (xy 330.339998 -251.976984)
			(xy 330.304505 -252.011076) (xy 330.264002 -252.039032) (xy 330.21954 -252.06013) (xy 330.172269 -252.073822)
			(xy 330.123414 -252.079754) (xy 330.074239 -252.077773) (xy 330.02602 -252.067929) (xy 329.980004 -252.050477)
			(xy 329.937383 -252.02587) (xy 329.899262 -251.994745) (xy 329.866627 -251.957908) (xy 329.840324 -251.916312)
			(xy 329.821033 -251.871036) (xy 329.809256 -251.823252) (xy 329.805296 -251.774198) (xy 329.486768 -251.774198)
			(xy 329.486256 -251.799644) (xy 329.478092 -251.849878) (xy 329.461976 -251.898152) (xy 329.438325 -251.943215)
			(xy 329.407752 -251.983901) (xy 329.371048 -252.019156) (xy 329.329164 -252.048066) (xy 329.283185 -252.069883)
			(xy 329.234301 -252.084043) (xy 329.18378 -252.090177) (xy 329.132928 -252.088128) (xy 329.083064 -252.077948)
			(xy 329.035478 -252.059901) (xy 328.991404 -252.034455) (xy 328.951982 -252.002268) (xy 328.918234 -251.964174)
			(xy 328.891033 -251.92116) (xy 328.871085 -251.87434) (xy 328.858906 -251.824926) (xy 328.854811 -251.774198)
			(xy 326.656446 -251.774198) (xy 326.655951 -251.798805) (xy 326.648056 -251.847382) (xy 326.632472 -251.894063)
			(xy 326.609601 -251.93764) (xy 326.580036 -251.976984) (xy 326.544543 -252.011076) (xy 326.50404 -252.039032)
			(xy 326.459578 -252.06013) (xy 326.412307 -252.073822) (xy 326.363452 -252.079754) (xy 326.314277 -252.077773)
			(xy 326.266058 -252.067929) (xy 326.220042 -252.050477) (xy 326.177421 -252.02587) (xy 326.1393 -251.994745)
			(xy 326.106665 -251.957908) (xy 326.080362 -251.916312) (xy 326.061071 -251.871036) (xy 326.049294 -251.823252)
			(xy 326.045334 -251.774198) (xy 310.45912 -251.774198) (xy 310.45912 -252.850142) (xy 324.447166 -252.850142)
			(xy 324.451126 -252.801088) (xy 324.462903 -252.753304) (xy 324.482194 -252.708028) (xy 324.508497 -252.666432)
			(xy 324.541132 -252.629595) (xy 324.579253 -252.59847) (xy 324.621874 -252.573863) (xy 324.66789 -252.556411)
			(xy 324.716109 -252.546567) (xy 324.765284 -252.544586) (xy 324.814139 -252.550518) (xy 324.86141 -252.56421)
			(xy 324.903545 -252.584204) (xy 327.455288 -252.584204) (xy 327.459248 -252.53515) (xy 327.471025 -252.487366)
			(xy 327.490316 -252.44209) (xy 327.516619 -252.400494) (xy 327.549254 -252.363657) (xy 327.587375 -252.332532)
			(xy 327.629996 -252.307925) (xy 327.676012 -252.290473) (xy 327.724231 -252.280629) (xy 327.773406 -252.278648)
			(xy 327.822261 -252.28458) (xy 327.869532 -252.298272) (xy 327.913994 -252.31937) (xy 327.954497 -252.347326)
			(xy 327.98999 -252.381418) (xy 328.019555 -252.420762) (xy 328.042426 -252.464339) (xy 328.05801 -252.51102)
			(xy 328.065905 -252.559597) (xy 328.0664 -252.584204) (xy 328.384911 -252.584204) (xy 328.389006 -252.533476)
			(xy 328.401185 -252.484062) (xy 328.421133 -252.437242) (xy 328.448334 -252.394228) (xy 328.482082 -252.356134)
			(xy 328.521504 -252.323947) (xy 328.565578 -252.298501) (xy 328.613164 -252.280454) (xy 328.663028 -252.270274)
			(xy 328.71388 -252.268225) (xy 328.764401 -252.274359) (xy 328.813285 -252.288519) (xy 328.859264 -252.310336)
			(xy 328.901148 -252.339246) (xy 328.937852 -252.374501) (xy 328.968425 -252.415187) (xy 328.992076 -252.46025)
			(xy 329.008192 -252.508524) (xy 329.016356 -252.558758) (xy 329.016868 -252.584204) (xy 329.335396 -252.584204)
			(xy 329.339356 -252.53515) (xy 329.351133 -252.487366) (xy 329.370424 -252.44209) (xy 329.396727 -252.400494)
			(xy 329.429362 -252.363657) (xy 329.467483 -252.332532) (xy 329.510104 -252.307925) (xy 329.55612 -252.290473)
			(xy 329.604339 -252.280629) (xy 329.653514 -252.278648) (xy 329.702369 -252.28458) (xy 329.74964 -252.298272)
			(xy 329.794102 -252.31937) (xy 329.834605 -252.347326) (xy 329.870098 -252.381418) (xy 329.899663 -252.420762)
			(xy 329.922534 -252.464339) (xy 329.938118 -252.51102) (xy 329.946013 -252.559597) (xy 329.946508 -252.584204)
			(xy 330.264765 -252.584204) (xy 330.26886 -252.533476) (xy 330.281039 -252.484062) (xy 330.300987 -252.437242)
			(xy 330.328188 -252.394228) (xy 330.361936 -252.356134) (xy 330.401358 -252.323947) (xy 330.445432 -252.298501)
			(xy 330.493018 -252.280454) (xy 330.542882 -252.270274) (xy 330.593734 -252.268225) (xy 330.644255 -252.274359)
			(xy 330.693139 -252.288519) (xy 330.739118 -252.310336) (xy 330.781002 -252.339246) (xy 330.817706 -252.374501)
			(xy 330.848279 -252.415187) (xy 330.87193 -252.46025) (xy 330.888046 -252.508524) (xy 330.89621 -252.558758)
			(xy 330.896722 -252.584204) (xy 331.21525 -252.584204) (xy 331.21921 -252.53515) (xy 331.230987 -252.487366)
			(xy 331.250278 -252.44209) (xy 331.276581 -252.400494) (xy 331.309216 -252.363657) (xy 331.347337 -252.332532)
			(xy 331.389958 -252.307925) (xy 331.435974 -252.290473) (xy 331.484193 -252.280629) (xy 331.533368 -252.278648)
			(xy 331.582223 -252.28458) (xy 331.629494 -252.298272) (xy 331.673956 -252.31937) (xy 331.714459 -252.347326)
			(xy 331.749952 -252.381418) (xy 331.779517 -252.420762) (xy 331.802388 -252.464339) (xy 331.817972 -252.51102)
			(xy 331.825867 -252.559597) (xy 331.826362 -252.584204) (xy 332.144873 -252.584204) (xy 332.148968 -252.533476)
			(xy 332.161147 -252.484062) (xy 332.181095 -252.437242) (xy 332.208296 -252.394228) (xy 332.242044 -252.356134)
			(xy 332.281466 -252.323947) (xy 332.32554 -252.298501) (xy 332.373126 -252.280454) (xy 332.42299 -252.270274)
			(xy 332.473842 -252.268225) (xy 332.524363 -252.274359) (xy 332.573247 -252.288519) (xy 332.619226 -252.310336)
			(xy 332.66111 -252.339246) (xy 332.697814 -252.374501) (xy 332.728387 -252.415187) (xy 332.752038 -252.46025)
			(xy 332.768154 -252.508524) (xy 332.776318 -252.558758) (xy 332.77683 -252.584204) (xy 333.084927 -252.584204)
			(xy 333.089022 -252.533476) (xy 333.101201 -252.484062) (xy 333.121149 -252.437242) (xy 333.14835 -252.394228)
			(xy 333.182098 -252.356134) (xy 333.22152 -252.323947) (xy 333.265594 -252.298501) (xy 333.31318 -252.280454)
			(xy 333.363044 -252.270274) (xy 333.413896 -252.268225) (xy 333.464417 -252.274359) (xy 333.513301 -252.288519)
			(xy 333.55928 -252.310336) (xy 333.601164 -252.339246) (xy 333.637868 -252.374501) (xy 333.668441 -252.415187)
			(xy 333.692092 -252.46025) (xy 333.708208 -252.508524) (xy 333.716372 -252.558758) (xy 333.716884 -252.584204)
			(xy 334.035412 -252.584204) (xy 334.039372 -252.53515) (xy 334.051149 -252.487366) (xy 334.07044 -252.44209)
			(xy 334.096743 -252.400494) (xy 334.129378 -252.363657) (xy 334.167499 -252.332532) (xy 334.21012 -252.307925)
			(xy 334.256136 -252.290473) (xy 334.304355 -252.280629) (xy 334.35353 -252.278648) (xy 334.402385 -252.28458)
			(xy 334.449656 -252.298272) (xy 334.494118 -252.31937) (xy 334.534621 -252.347326) (xy 334.570114 -252.381418)
			(xy 334.599679 -252.420762) (xy 334.62255 -252.464339) (xy 334.638134 -252.51102) (xy 334.646029 -252.559597)
			(xy 334.646524 -252.584204) (xy 334.964781 -252.584204) (xy 334.968876 -252.533476) (xy 334.981055 -252.484062)
			(xy 335.001003 -252.437242) (xy 335.028204 -252.394228) (xy 335.061952 -252.356134) (xy 335.101374 -252.323947)
			(xy 335.145448 -252.298501) (xy 335.193034 -252.280454) (xy 335.242898 -252.270274) (xy 335.29375 -252.268225)
			(xy 335.344271 -252.274359) (xy 335.393155 -252.288519) (xy 335.439134 -252.310336) (xy 335.481018 -252.339246)
			(xy 335.517722 -252.374501) (xy 335.548295 -252.415187) (xy 335.571946 -252.46025) (xy 335.588062 -252.508524)
			(xy 335.596226 -252.558758) (xy 335.596738 -252.584204) (xy 335.915266 -252.584204) (xy 335.919226 -252.53515)
			(xy 335.931003 -252.487366) (xy 335.950294 -252.44209) (xy 335.976597 -252.400494) (xy 336.009232 -252.363657)
			(xy 336.047353 -252.332532) (xy 336.089974 -252.307925) (xy 336.13599 -252.290473) (xy 336.184209 -252.280629)
			(xy 336.233384 -252.278648) (xy 336.282239 -252.28458) (xy 336.32951 -252.298272) (xy 336.373972 -252.31937)
			(xy 336.414475 -252.347326) (xy 336.449968 -252.381418) (xy 336.479533 -252.420762) (xy 336.502404 -252.464339)
			(xy 336.517988 -252.51102) (xy 336.525883 -252.559597) (xy 336.526378 -252.584204) (xy 336.844889 -252.584204)
			(xy 336.848984 -252.533476) (xy 336.861163 -252.484062) (xy 336.881111 -252.437242) (xy 336.908312 -252.394228)
			(xy 336.94206 -252.356134) (xy 336.981482 -252.323947) (xy 337.025556 -252.298501) (xy 337.073142 -252.280454)
			(xy 337.123006 -252.270274) (xy 337.173858 -252.268225) (xy 337.224379 -252.274359) (xy 337.273263 -252.288519)
			(xy 337.319242 -252.310336) (xy 337.361126 -252.339246) (xy 337.39783 -252.374501) (xy 337.428403 -252.415187)
			(xy 337.452054 -252.46025) (xy 337.46817 -252.508524) (xy 337.476334 -252.558758) (xy 337.476846 -252.584204)
			(xy 337.795374 -252.584204) (xy 337.799334 -252.53515) (xy 337.811111 -252.487366) (xy 337.830402 -252.44209)
			(xy 337.856705 -252.400494) (xy 337.88934 -252.363657) (xy 337.927461 -252.332532) (xy 337.970082 -252.307925)
			(xy 338.016098 -252.290473) (xy 338.064317 -252.280629) (xy 338.113492 -252.278648) (xy 338.162347 -252.28458)
			(xy 338.209618 -252.298272) (xy 338.25408 -252.31937) (xy 338.294583 -252.347326) (xy 338.330076 -252.381418)
			(xy 338.359641 -252.420762) (xy 338.382512 -252.464339) (xy 338.398096 -252.51102) (xy 338.405991 -252.559597)
			(xy 338.406486 -252.584204) (xy 338.724743 -252.584204) (xy 338.728838 -252.533476) (xy 338.741017 -252.484062)
			(xy 338.760965 -252.437242) (xy 338.788166 -252.394228) (xy 338.821914 -252.356134) (xy 338.861336 -252.323947)
			(xy 338.90541 -252.298501) (xy 338.952996 -252.280454) (xy 339.00286 -252.270274) (xy 339.053712 -252.268225)
			(xy 339.104233 -252.274359) (xy 339.153117 -252.288519) (xy 339.199096 -252.310336) (xy 339.24098 -252.339246)
			(xy 339.277684 -252.374501) (xy 339.308257 -252.415187) (xy 339.331908 -252.46025) (xy 339.348024 -252.508524)
			(xy 339.356188 -252.558758) (xy 339.3567 -252.584204) (xy 339.664797 -252.584204) (xy 339.668892 -252.533476)
			(xy 339.681071 -252.484062) (xy 339.701019 -252.437242) (xy 339.72822 -252.394228) (xy 339.761968 -252.356134)
			(xy 339.80139 -252.323947) (xy 339.845464 -252.298501) (xy 339.89305 -252.280454) (xy 339.942914 -252.270274)
			(xy 339.993766 -252.268225) (xy 340.044287 -252.274359) (xy 340.093171 -252.288519) (xy 340.13915 -252.310336)
			(xy 340.181034 -252.339246) (xy 340.217738 -252.374501) (xy 340.248311 -252.415187) (xy 340.271962 -252.46025)
			(xy 340.288078 -252.508524) (xy 340.296242 -252.558758) (xy 340.296754 -252.584204) (xy 340.615282 -252.584204)
			(xy 340.619242 -252.53515) (xy 340.631019 -252.487366) (xy 340.65031 -252.44209) (xy 340.676613 -252.400494)
			(xy 340.709248 -252.363657) (xy 340.747369 -252.332532) (xy 340.78999 -252.307925) (xy 340.836006 -252.290473)
			(xy 340.884225 -252.280629) (xy 340.9334 -252.278648) (xy 340.982255 -252.28458) (xy 341.029526 -252.298272)
			(xy 341.073988 -252.31937) (xy 341.114491 -252.347326) (xy 341.149984 -252.381418) (xy 341.179549 -252.420762)
			(xy 341.20242 -252.464339) (xy 341.218004 -252.51102) (xy 341.225899 -252.559597) (xy 341.226394 -252.584204)
			(xy 341.544905 -252.584204) (xy 341.549 -252.533476) (xy 341.561179 -252.484062) (xy 341.581127 -252.437242)
			(xy 341.608328 -252.394228) (xy 341.642076 -252.356134) (xy 341.681498 -252.323947) (xy 341.725572 -252.298501)
			(xy 341.773158 -252.280454) (xy 341.823022 -252.270274) (xy 341.873874 -252.268225) (xy 341.924395 -252.274359)
			(xy 341.973279 -252.288519) (xy 342.019258 -252.310336) (xy 342.061142 -252.339246) (xy 342.097846 -252.374501)
			(xy 342.128419 -252.415187) (xy 342.15207 -252.46025) (xy 342.168186 -252.508524) (xy 342.17635 -252.558758)
			(xy 342.176862 -252.584204) (xy 342.49539 -252.584204) (xy 342.49935 -252.53515) (xy 342.511127 -252.487366)
			(xy 342.530418 -252.44209) (xy 342.556721 -252.400494) (xy 342.589356 -252.363657) (xy 342.627477 -252.332532)
			(xy 342.670098 -252.307925) (xy 342.716114 -252.290473) (xy 342.764333 -252.280629) (xy 342.813508 -252.278648)
			(xy 342.862363 -252.28458) (xy 342.909634 -252.298272) (xy 342.954096 -252.31937) (xy 342.994599 -252.347326)
			(xy 343.030092 -252.381418) (xy 343.059657 -252.420762) (xy 343.082528 -252.464339) (xy 343.098112 -252.51102)
			(xy 343.106007 -252.559597) (xy 343.106502 -252.584204) (xy 343.424759 -252.584204) (xy 343.428854 -252.533476)
			(xy 343.441033 -252.484062) (xy 343.460981 -252.437242) (xy 343.488182 -252.394228) (xy 343.52193 -252.356134)
			(xy 343.561352 -252.323947) (xy 343.605426 -252.298501) (xy 343.653012 -252.280454) (xy 343.702876 -252.270274)
			(xy 343.753728 -252.268225) (xy 343.804249 -252.274359) (xy 343.853133 -252.288519) (xy 343.899112 -252.310336)
			(xy 343.940996 -252.339246) (xy 343.9777 -252.374501) (xy 344.008273 -252.415187) (xy 344.031924 -252.46025)
			(xy 344.04804 -252.508524) (xy 344.056204 -252.558758) (xy 344.056716 -252.584204) (xy 344.056204 -252.60965)
			(xy 344.04804 -252.659884) (xy 344.031924 -252.708158) (xy 344.008273 -252.753221) (xy 343.9777 -252.793907)
			(xy 343.940996 -252.829162) (xy 343.899112 -252.858072) (xy 343.853133 -252.879889) (xy 343.804249 -252.894049)
			(xy 343.753728 -252.900183) (xy 343.702876 -252.898134) (xy 343.653012 -252.887954) (xy 343.605426 -252.869907)
			(xy 343.561352 -252.844461) (xy 343.52193 -252.812274) (xy 343.488182 -252.77418) (xy 343.460981 -252.731166)
			(xy 343.441033 -252.684346) (xy 343.428854 -252.634932) (xy 343.424759 -252.584204) (xy 343.106502 -252.584204)
			(xy 343.106007 -252.608811) (xy 343.098112 -252.657388) (xy 343.082528 -252.704069) (xy 343.059657 -252.747646)
			(xy 343.030092 -252.78699) (xy 342.994599 -252.821082) (xy 342.954096 -252.849038) (xy 342.909634 -252.870136)
			(xy 342.862363 -252.883828) (xy 342.813508 -252.88976) (xy 342.764333 -252.887779) (xy 342.716114 -252.877935)
			(xy 342.670098 -252.860483) (xy 342.627477 -252.835876) (xy 342.589356 -252.804751) (xy 342.556721 -252.767914)
			(xy 342.530418 -252.726318) (xy 342.511127 -252.681042) (xy 342.49935 -252.633258) (xy 342.49539 -252.584204)
			(xy 342.176862 -252.584204) (xy 342.17635 -252.60965) (xy 342.168186 -252.659884) (xy 342.15207 -252.708158)
			(xy 342.128419 -252.753221) (xy 342.097846 -252.793907) (xy 342.061142 -252.829162) (xy 342.019258 -252.858072)
			(xy 341.973279 -252.879889) (xy 341.924395 -252.894049) (xy 341.873874 -252.900183) (xy 341.823022 -252.898134)
			(xy 341.773158 -252.887954) (xy 341.725572 -252.869907) (xy 341.681498 -252.844461) (xy 341.642076 -252.812274)
			(xy 341.608328 -252.77418) (xy 341.581127 -252.731166) (xy 341.561179 -252.684346) (xy 341.549 -252.634932)
			(xy 341.544905 -252.584204) (xy 341.226394 -252.584204) (xy 341.225899 -252.608811) (xy 341.218004 -252.657388)
			(xy 341.20242 -252.704069) (xy 341.179549 -252.747646) (xy 341.149984 -252.78699) (xy 341.114491 -252.821082)
			(xy 341.073988 -252.849038) (xy 341.029526 -252.870136) (xy 340.982255 -252.883828) (xy 340.9334 -252.88976)
			(xy 340.884225 -252.887779) (xy 340.836006 -252.877935) (xy 340.78999 -252.860483) (xy 340.747369 -252.835876)
			(xy 340.709248 -252.804751) (xy 340.676613 -252.767914) (xy 340.65031 -252.726318) (xy 340.631019 -252.681042)
			(xy 340.619242 -252.633258) (xy 340.615282 -252.584204) (xy 340.296754 -252.584204) (xy 340.296242 -252.60965)
			(xy 340.288078 -252.659884) (xy 340.271962 -252.708158) (xy 340.248311 -252.753221) (xy 340.217738 -252.793907)
			(xy 340.181034 -252.829162) (xy 340.13915 -252.858072) (xy 340.093171 -252.879889) (xy 340.044287 -252.894049)
			(xy 339.993766 -252.900183) (xy 339.942914 -252.898134) (xy 339.89305 -252.887954) (xy 339.845464 -252.869907)
			(xy 339.80139 -252.844461) (xy 339.761968 -252.812274) (xy 339.72822 -252.77418) (xy 339.701019 -252.731166)
			(xy 339.681071 -252.684346) (xy 339.668892 -252.634932) (xy 339.664797 -252.584204) (xy 339.3567 -252.584204)
			(xy 339.356188 -252.60965) (xy 339.348024 -252.659884) (xy 339.331908 -252.708158) (xy 339.308257 -252.753221)
			(xy 339.277684 -252.793907) (xy 339.24098 -252.829162) (xy 339.199096 -252.858072) (xy 339.153117 -252.879889)
			(xy 339.104233 -252.894049) (xy 339.053712 -252.900183) (xy 339.00286 -252.898134) (xy 338.952996 -252.887954)
			(xy 338.90541 -252.869907) (xy 338.861336 -252.844461) (xy 338.821914 -252.812274) (xy 338.788166 -252.77418)
			(xy 338.760965 -252.731166) (xy 338.741017 -252.684346) (xy 338.728838 -252.634932) (xy 338.724743 -252.584204)
			(xy 338.406486 -252.584204) (xy 338.405991 -252.608811) (xy 338.398096 -252.657388) (xy 338.382512 -252.704069)
			(xy 338.359641 -252.747646) (xy 338.330076 -252.78699) (xy 338.294583 -252.821082) (xy 338.25408 -252.849038)
			(xy 338.209618 -252.870136) (xy 338.162347 -252.883828) (xy 338.113492 -252.88976) (xy 338.064317 -252.887779)
			(xy 338.016098 -252.877935) (xy 337.970082 -252.860483) (xy 337.927461 -252.835876) (xy 337.88934 -252.804751)
			(xy 337.856705 -252.767914) (xy 337.830402 -252.726318) (xy 337.811111 -252.681042) (xy 337.799334 -252.633258)
			(xy 337.795374 -252.584204) (xy 337.476846 -252.584204) (xy 337.476334 -252.60965) (xy 337.46817 -252.659884)
			(xy 337.452054 -252.708158) (xy 337.428403 -252.753221) (xy 337.39783 -252.793907) (xy 337.361126 -252.829162)
			(xy 337.319242 -252.858072) (xy 337.273263 -252.879889) (xy 337.224379 -252.894049) (xy 337.173858 -252.900183)
			(xy 337.123006 -252.898134) (xy 337.073142 -252.887954) (xy 337.025556 -252.869907) (xy 336.981482 -252.844461)
			(xy 336.94206 -252.812274) (xy 336.908312 -252.77418) (xy 336.881111 -252.731166) (xy 336.861163 -252.684346)
			(xy 336.848984 -252.634932) (xy 336.844889 -252.584204) (xy 336.526378 -252.584204) (xy 336.525883 -252.608811)
			(xy 336.517988 -252.657388) (xy 336.502404 -252.704069) (xy 336.479533 -252.747646) (xy 336.449968 -252.78699)
			(xy 336.414475 -252.821082) (xy 336.373972 -252.849038) (xy 336.32951 -252.870136) (xy 336.282239 -252.883828)
			(xy 336.233384 -252.88976) (xy 336.184209 -252.887779) (xy 336.13599 -252.877935) (xy 336.089974 -252.860483)
			(xy 336.047353 -252.835876) (xy 336.009232 -252.804751) (xy 335.976597 -252.767914) (xy 335.950294 -252.726318)
			(xy 335.931003 -252.681042) (xy 335.919226 -252.633258) (xy 335.915266 -252.584204) (xy 335.596738 -252.584204)
			(xy 335.596226 -252.60965) (xy 335.588062 -252.659884) (xy 335.571946 -252.708158) (xy 335.548295 -252.753221)
			(xy 335.517722 -252.793907) (xy 335.481018 -252.829162) (xy 335.439134 -252.858072) (xy 335.393155 -252.879889)
			(xy 335.344271 -252.894049) (xy 335.29375 -252.900183) (xy 335.242898 -252.898134) (xy 335.193034 -252.887954)
			(xy 335.145448 -252.869907) (xy 335.101374 -252.844461) (xy 335.061952 -252.812274) (xy 335.028204 -252.77418)
			(xy 335.001003 -252.731166) (xy 334.981055 -252.684346) (xy 334.968876 -252.634932) (xy 334.964781 -252.584204)
			(xy 334.646524 -252.584204) (xy 334.646029 -252.608811) (xy 334.638134 -252.657388) (xy 334.62255 -252.704069)
			(xy 334.599679 -252.747646) (xy 334.570114 -252.78699) (xy 334.534621 -252.821082) (xy 334.494118 -252.849038)
			(xy 334.449656 -252.870136) (xy 334.402385 -252.883828) (xy 334.35353 -252.88976) (xy 334.304355 -252.887779)
			(xy 334.256136 -252.877935) (xy 334.21012 -252.860483) (xy 334.167499 -252.835876) (xy 334.129378 -252.804751)
			(xy 334.096743 -252.767914) (xy 334.07044 -252.726318) (xy 334.051149 -252.681042) (xy 334.039372 -252.633258)
			(xy 334.035412 -252.584204) (xy 333.716884 -252.584204) (xy 333.716372 -252.60965) (xy 333.708208 -252.659884)
			(xy 333.692092 -252.708158) (xy 333.668441 -252.753221) (xy 333.637868 -252.793907) (xy 333.601164 -252.829162)
			(xy 333.55928 -252.858072) (xy 333.513301 -252.879889) (xy 333.464417 -252.894049) (xy 333.413896 -252.900183)
			(xy 333.363044 -252.898134) (xy 333.31318 -252.887954) (xy 333.265594 -252.869907) (xy 333.22152 -252.844461)
			(xy 333.182098 -252.812274) (xy 333.14835 -252.77418) (xy 333.121149 -252.731166) (xy 333.101201 -252.684346)
			(xy 333.089022 -252.634932) (xy 333.084927 -252.584204) (xy 332.77683 -252.584204) (xy 332.776318 -252.60965)
			(xy 332.768154 -252.659884) (xy 332.752038 -252.708158) (xy 332.728387 -252.753221) (xy 332.697814 -252.793907)
			(xy 332.66111 -252.829162) (xy 332.619226 -252.858072) (xy 332.573247 -252.879889) (xy 332.524363 -252.894049)
			(xy 332.473842 -252.900183) (xy 332.42299 -252.898134) (xy 332.373126 -252.887954) (xy 332.32554 -252.869907)
			(xy 332.281466 -252.844461) (xy 332.242044 -252.812274) (xy 332.208296 -252.77418) (xy 332.181095 -252.731166)
			(xy 332.161147 -252.684346) (xy 332.148968 -252.634932) (xy 332.144873 -252.584204) (xy 331.826362 -252.584204)
			(xy 331.825867 -252.608811) (xy 331.817972 -252.657388) (xy 331.802388 -252.704069) (xy 331.779517 -252.747646)
			(xy 331.749952 -252.78699) (xy 331.714459 -252.821082) (xy 331.673956 -252.849038) (xy 331.629494 -252.870136)
			(xy 331.582223 -252.883828) (xy 331.533368 -252.88976) (xy 331.484193 -252.887779) (xy 331.435974 -252.877935)
			(xy 331.389958 -252.860483) (xy 331.347337 -252.835876) (xy 331.309216 -252.804751) (xy 331.276581 -252.767914)
			(xy 331.250278 -252.726318) (xy 331.230987 -252.681042) (xy 331.21921 -252.633258) (xy 331.21525 -252.584204)
			(xy 330.896722 -252.584204) (xy 330.89621 -252.60965) (xy 330.888046 -252.659884) (xy 330.87193 -252.708158)
			(xy 330.848279 -252.753221) (xy 330.817706 -252.793907) (xy 330.781002 -252.829162) (xy 330.739118 -252.858072)
			(xy 330.693139 -252.879889) (xy 330.644255 -252.894049) (xy 330.593734 -252.900183) (xy 330.542882 -252.898134)
			(xy 330.493018 -252.887954) (xy 330.445432 -252.869907) (xy 330.401358 -252.844461) (xy 330.361936 -252.812274)
			(xy 330.328188 -252.77418) (xy 330.300987 -252.731166) (xy 330.281039 -252.684346) (xy 330.26886 -252.634932)
			(xy 330.264765 -252.584204) (xy 329.946508 -252.584204) (xy 329.946013 -252.608811) (xy 329.938118 -252.657388)
			(xy 329.922534 -252.704069) (xy 329.899663 -252.747646) (xy 329.870098 -252.78699) (xy 329.834605 -252.821082)
			(xy 329.794102 -252.849038) (xy 329.74964 -252.870136) (xy 329.702369 -252.883828) (xy 329.653514 -252.88976)
			(xy 329.604339 -252.887779) (xy 329.55612 -252.877935) (xy 329.510104 -252.860483) (xy 329.467483 -252.835876)
			(xy 329.429362 -252.804751) (xy 329.396727 -252.767914) (xy 329.370424 -252.726318) (xy 329.351133 -252.681042)
			(xy 329.339356 -252.633258) (xy 329.335396 -252.584204) (xy 329.016868 -252.584204) (xy 329.016356 -252.60965)
			(xy 329.008192 -252.659884) (xy 328.992076 -252.708158) (xy 328.968425 -252.753221) (xy 328.937852 -252.793907)
			(xy 328.901148 -252.829162) (xy 328.859264 -252.858072) (xy 328.813285 -252.879889) (xy 328.764401 -252.894049)
			(xy 328.71388 -252.900183) (xy 328.663028 -252.898134) (xy 328.613164 -252.887954) (xy 328.565578 -252.869907)
			(xy 328.521504 -252.844461) (xy 328.482082 -252.812274) (xy 328.448334 -252.77418) (xy 328.421133 -252.731166)
			(xy 328.401185 -252.684346) (xy 328.389006 -252.634932) (xy 328.384911 -252.584204) (xy 328.0664 -252.584204)
			(xy 328.065905 -252.608811) (xy 328.05801 -252.657388) (xy 328.042426 -252.704069) (xy 328.019555 -252.747646)
			(xy 327.98999 -252.78699) (xy 327.954497 -252.821082) (xy 327.913994 -252.849038) (xy 327.869532 -252.870136)
			(xy 327.822261 -252.883828) (xy 327.773406 -252.88976) (xy 327.724231 -252.887779) (xy 327.676012 -252.877935)
			(xy 327.629996 -252.860483) (xy 327.587375 -252.835876) (xy 327.549254 -252.804751) (xy 327.516619 -252.767914)
			(xy 327.490316 -252.726318) (xy 327.471025 -252.681042) (xy 327.459248 -252.633258) (xy 327.455288 -252.584204)
			(xy 324.903545 -252.584204) (xy 324.905872 -252.585308) (xy 324.946375 -252.613264) (xy 324.981868 -252.647356)
			(xy 325.011433 -252.6867) (xy 325.034304 -252.730277) (xy 325.049888 -252.776958) (xy 325.057783 -252.825535)
			(xy 325.058278 -252.850142) (xy 325.057783 -252.874749) (xy 325.049888 -252.923326) (xy 325.034304 -252.970007)
			(xy 325.011433 -253.013584) (xy 324.981868 -253.052928) (xy 324.946375 -253.08702) (xy 324.905872 -253.114976)
			(xy 324.86141 -253.136074) (xy 324.814139 -253.149766) (xy 324.765284 -253.155698) (xy 324.716109 -253.153717)
			(xy 324.66789 -253.143873) (xy 324.621874 -253.126421) (xy 324.579253 -253.101814) (xy 324.541132 -253.070689)
			(xy 324.508497 -253.033852) (xy 324.482194 -252.992256) (xy 324.462903 -252.94698) (xy 324.451126 -252.899196)
			(xy 324.447166 -252.850142) (xy 310.45912 -252.850142) (xy 310.45912 -253.39421) (xy 326.045334 -253.39421)
			(xy 326.049294 -253.345156) (xy 326.061071 -253.297372) (xy 326.080362 -253.252096) (xy 326.106665 -253.2105)
			(xy 326.1393 -253.173663) (xy 326.177421 -253.142538) (xy 326.220042 -253.117931) (xy 326.266058 -253.100479)
			(xy 326.314277 -253.090635) (xy 326.363452 -253.088654) (xy 326.412307 -253.094586) (xy 326.459578 -253.108278)
			(xy 326.50404 -253.129376) (xy 326.544543 -253.157332) (xy 326.580036 -253.191424) (xy 326.609601 -253.230768)
			(xy 326.632472 -253.274345) (xy 326.648056 -253.321026) (xy 326.655951 -253.369603) (xy 326.656446 -253.39421)
			(xy 327.925442 -253.39421) (xy 327.929402 -253.345156) (xy 327.941179 -253.297372) (xy 327.96047 -253.252096)
			(xy 327.986773 -253.2105) (xy 328.019408 -253.173663) (xy 328.057529 -253.142538) (xy 328.10015 -253.117931)
			(xy 328.146166 -253.100479) (xy 328.194385 -253.090635) (xy 328.24356 -253.088654) (xy 328.292415 -253.094586)
			(xy 328.339686 -253.108278) (xy 328.384148 -253.129376) (xy 328.424651 -253.157332) (xy 328.460144 -253.191424)
			(xy 328.489709 -253.230768) (xy 328.51258 -253.274345) (xy 328.528164 -253.321026) (xy 328.536059 -253.369603)
			(xy 328.536554 -253.39421) (xy 328.854811 -253.39421) (xy 328.858906 -253.343482) (xy 328.871085 -253.294068)
			(xy 328.891033 -253.247248) (xy 328.918234 -253.204234) (xy 328.951982 -253.16614) (xy 328.991404 -253.133953)
			(xy 329.035478 -253.108507) (xy 329.083064 -253.09046) (xy 329.132928 -253.08028) (xy 329.18378 -253.078231)
			(xy 329.234301 -253.084365) (xy 329.283185 -253.098525) (xy 329.329164 -253.120342) (xy 329.371048 -253.149252)
			(xy 329.407752 -253.184507) (xy 329.438325 -253.225193) (xy 329.461976 -253.270256) (xy 329.478092 -253.31853)
			(xy 329.486256 -253.368764) (xy 329.486768 -253.39421) (xy 329.794865 -253.39421) (xy 329.79896 -253.343482)
			(xy 329.811139 -253.294068) (xy 329.831087 -253.247248) (xy 329.858288 -253.204234) (xy 329.892036 -253.16614)
			(xy 329.931458 -253.133953) (xy 329.975532 -253.108507) (xy 330.023118 -253.09046) (xy 330.072982 -253.08028)
			(xy 330.123834 -253.078231) (xy 330.174355 -253.084365) (xy 330.223239 -253.098525) (xy 330.269218 -253.120342)
			(xy 330.311102 -253.149252) (xy 330.347806 -253.184507) (xy 330.378379 -253.225193) (xy 330.40203 -253.270256)
			(xy 330.418146 -253.31853) (xy 330.42631 -253.368764) (xy 330.426822 -253.39421) (xy 330.74535 -253.39421)
			(xy 330.74931 -253.345156) (xy 330.761087 -253.297372) (xy 330.780378 -253.252096) (xy 330.806681 -253.2105)
			(xy 330.839316 -253.173663) (xy 330.877437 -253.142538) (xy 330.920058 -253.117931) (xy 330.966074 -253.100479)
			(xy 331.014293 -253.090635) (xy 331.063468 -253.088654) (xy 331.112323 -253.094586) (xy 331.159594 -253.108278)
			(xy 331.204056 -253.129376) (xy 331.244559 -253.157332) (xy 331.280052 -253.191424) (xy 331.309617 -253.230768)
			(xy 331.332488 -253.274345) (xy 331.348072 -253.321026) (xy 331.355967 -253.369603) (xy 331.356462 -253.39421)
			(xy 331.674973 -253.39421) (xy 331.679068 -253.343482) (xy 331.691247 -253.294068) (xy 331.711195 -253.247248)
			(xy 331.738396 -253.204234) (xy 331.772144 -253.16614) (xy 331.811566 -253.133953) (xy 331.85564 -253.108507)
			(xy 331.903226 -253.09046) (xy 331.95309 -253.08028) (xy 332.003942 -253.078231) (xy 332.054463 -253.084365)
			(xy 332.103347 -253.098525) (xy 332.149326 -253.120342) (xy 332.19121 -253.149252) (xy 332.227914 -253.184507)
			(xy 332.258487 -253.225193) (xy 332.282138 -253.270256) (xy 332.298254 -253.31853) (xy 332.306418 -253.368764)
			(xy 332.30693 -253.39421) (xy 332.625204 -253.39421) (xy 332.629164 -253.345156) (xy 332.640941 -253.297372)
			(xy 332.660232 -253.252096) (xy 332.686535 -253.2105) (xy 332.71917 -253.173663) (xy 332.757291 -253.142538)
			(xy 332.799912 -253.117931) (xy 332.845928 -253.100479) (xy 332.894147 -253.090635) (xy 332.943322 -253.088654)
			(xy 332.992177 -253.094586) (xy 333.039448 -253.108278) (xy 333.08391 -253.129376) (xy 333.124413 -253.157332)
			(xy 333.159906 -253.191424) (xy 333.189471 -253.230768) (xy 333.212342 -253.274345) (xy 333.227926 -253.321026)
			(xy 333.235821 -253.369603) (xy 333.236316 -253.39421) (xy 333.554827 -253.39421) (xy 333.558922 -253.343482)
			(xy 333.571101 -253.294068) (xy 333.591049 -253.247248) (xy 333.61825 -253.204234) (xy 333.651998 -253.16614)
			(xy 333.69142 -253.133953) (xy 333.735494 -253.108507) (xy 333.78308 -253.09046) (xy 333.832944 -253.08028)
			(xy 333.883796 -253.078231) (xy 333.934317 -253.084365) (xy 333.983201 -253.098525) (xy 334.02918 -253.120342)
			(xy 334.071064 -253.149252) (xy 334.107768 -253.184507) (xy 334.138341 -253.225193) (xy 334.161992 -253.270256)
			(xy 334.178108 -253.31853) (xy 334.186272 -253.368764) (xy 334.186784 -253.39421) (xy 334.505312 -253.39421)
			(xy 334.509272 -253.345156) (xy 334.521049 -253.297372) (xy 334.54034 -253.252096) (xy 334.566643 -253.2105)
			(xy 334.599278 -253.173663) (xy 334.637399 -253.142538) (xy 334.68002 -253.117931) (xy 334.726036 -253.100479)
			(xy 334.774255 -253.090635) (xy 334.82343 -253.088654) (xy 334.872285 -253.094586) (xy 334.919556 -253.108278)
			(xy 334.964018 -253.129376) (xy 335.004521 -253.157332) (xy 335.040014 -253.191424) (xy 335.069579 -253.230768)
			(xy 335.09245 -253.274345) (xy 335.108034 -253.321026) (xy 335.115929 -253.369603) (xy 335.116424 -253.39421)
			(xy 335.434935 -253.39421) (xy 335.43903 -253.343482) (xy 335.451209 -253.294068) (xy 335.471157 -253.247248)
			(xy 335.498358 -253.204234) (xy 335.532106 -253.16614) (xy 335.571528 -253.133953) (xy 335.615602 -253.108507)
			(xy 335.663188 -253.09046) (xy 335.713052 -253.08028) (xy 335.763904 -253.078231) (xy 335.814425 -253.084365)
			(xy 335.863309 -253.098525) (xy 335.909288 -253.120342) (xy 335.951172 -253.149252) (xy 335.987876 -253.184507)
			(xy 336.018449 -253.225193) (xy 336.0421 -253.270256) (xy 336.058216 -253.31853) (xy 336.06638 -253.368764)
			(xy 336.066892 -253.39421) (xy 336.374989 -253.39421) (xy 336.379084 -253.343482) (xy 336.391263 -253.294068)
			(xy 336.411211 -253.247248) (xy 336.438412 -253.204234) (xy 336.47216 -253.16614) (xy 336.511582 -253.133953)
			(xy 336.555656 -253.108507) (xy 336.603242 -253.09046) (xy 336.653106 -253.08028) (xy 336.703958 -253.078231)
			(xy 336.754479 -253.084365) (xy 336.803363 -253.098525) (xy 336.849342 -253.120342) (xy 336.891226 -253.149252)
			(xy 336.92793 -253.184507) (xy 336.958503 -253.225193) (xy 336.982154 -253.270256) (xy 336.99827 -253.31853)
			(xy 337.006434 -253.368764) (xy 337.006946 -253.39421) (xy 337.32522 -253.39421) (xy 337.32918 -253.345156)
			(xy 337.340957 -253.297372) (xy 337.360248 -253.252096) (xy 337.386551 -253.2105) (xy 337.419186 -253.173663)
			(xy 337.457307 -253.142538) (xy 337.499928 -253.117931) (xy 337.545944 -253.100479) (xy 337.594163 -253.090635)
			(xy 337.643338 -253.088654) (xy 337.692193 -253.094586) (xy 337.739464 -253.108278) (xy 337.783926 -253.129376)
			(xy 337.824429 -253.157332) (xy 337.859922 -253.191424) (xy 337.889487 -253.230768) (xy 337.912358 -253.274345)
			(xy 337.927942 -253.321026) (xy 337.935837 -253.369603) (xy 337.936332 -253.39421) (xy 338.254843 -253.39421)
			(xy 338.258938 -253.343482) (xy 338.271117 -253.294068) (xy 338.291065 -253.247248) (xy 338.318266 -253.204234)
			(xy 338.352014 -253.16614) (xy 338.391436 -253.133953) (xy 338.43551 -253.108507) (xy 338.483096 -253.09046)
			(xy 338.53296 -253.08028) (xy 338.583812 -253.078231) (xy 338.634333 -253.084365) (xy 338.683217 -253.098525)
			(xy 338.729196 -253.120342) (xy 338.77108 -253.149252) (xy 338.807784 -253.184507) (xy 338.838357 -253.225193)
			(xy 338.862008 -253.270256) (xy 338.878124 -253.31853) (xy 338.886288 -253.368764) (xy 338.8868 -253.39421)
			(xy 339.205328 -253.39421) (xy 339.209288 -253.345156) (xy 339.221065 -253.297372) (xy 339.240356 -253.252096)
			(xy 339.266659 -253.2105) (xy 339.299294 -253.173663) (xy 339.337415 -253.142538) (xy 339.380036 -253.117931)
			(xy 339.426052 -253.100479) (xy 339.474271 -253.090635) (xy 339.523446 -253.088654) (xy 339.572301 -253.094586)
			(xy 339.619572 -253.108278) (xy 339.664034 -253.129376) (xy 339.704537 -253.157332) (xy 339.74003 -253.191424)
			(xy 339.769595 -253.230768) (xy 339.792466 -253.274345) (xy 339.80805 -253.321026) (xy 339.815945 -253.369603)
			(xy 339.81644 -253.39421) (xy 340.134951 -253.39421) (xy 340.139046 -253.343482) (xy 340.151225 -253.294068)
			(xy 340.171173 -253.247248) (xy 340.198374 -253.204234) (xy 340.232122 -253.16614) (xy 340.271544 -253.133953)
			(xy 340.315618 -253.108507) (xy 340.363204 -253.09046) (xy 340.413068 -253.08028) (xy 340.46392 -253.078231)
			(xy 340.514441 -253.084365) (xy 340.563325 -253.098525) (xy 340.609304 -253.120342) (xy 340.651188 -253.149252)
			(xy 340.687892 -253.184507) (xy 340.718465 -253.225193) (xy 340.742116 -253.270256) (xy 340.758232 -253.31853)
			(xy 340.766396 -253.368764) (xy 340.766908 -253.39421) (xy 341.085182 -253.39421) (xy 341.089142 -253.345156)
			(xy 341.100919 -253.297372) (xy 341.12021 -253.252096) (xy 341.146513 -253.2105) (xy 341.179148 -253.173663)
			(xy 341.217269 -253.142538) (xy 341.25989 -253.117931) (xy 341.305906 -253.100479) (xy 341.354125 -253.090635)
			(xy 341.4033 -253.088654) (xy 341.452155 -253.094586) (xy 341.499426 -253.108278) (xy 341.543888 -253.129376)
			(xy 341.584391 -253.157332) (xy 341.619884 -253.191424) (xy 341.649449 -253.230768) (xy 341.67232 -253.274345)
			(xy 341.687904 -253.321026) (xy 341.695799 -253.369603) (xy 341.696294 -253.39421) (xy 342.014805 -253.39421)
			(xy 342.0189 -253.343482) (xy 342.031079 -253.294068) (xy 342.051027 -253.247248) (xy 342.078228 -253.204234)
			(xy 342.111976 -253.16614) (xy 342.151398 -253.133953) (xy 342.195472 -253.108507) (xy 342.243058 -253.09046)
			(xy 342.292922 -253.08028) (xy 342.343774 -253.078231) (xy 342.394295 -253.084365) (xy 342.443179 -253.098525)
			(xy 342.489158 -253.120342) (xy 342.531042 -253.149252) (xy 342.567746 -253.184507) (xy 342.598319 -253.225193)
			(xy 342.62197 -253.270256) (xy 342.638086 -253.31853) (xy 342.64625 -253.368764) (xy 342.646762 -253.39421)
			(xy 342.954859 -253.39421) (xy 342.958954 -253.343482) (xy 342.971133 -253.294068) (xy 342.991081 -253.247248)
			(xy 343.018282 -253.204234) (xy 343.05203 -253.16614) (xy 343.091452 -253.133953) (xy 343.135526 -253.108507)
			(xy 343.183112 -253.09046) (xy 343.232976 -253.08028) (xy 343.283828 -253.078231) (xy 343.334349 -253.084365)
			(xy 343.383233 -253.098525) (xy 343.429212 -253.120342) (xy 343.471096 -253.149252) (xy 343.5078 -253.184507)
			(xy 343.538373 -253.225193) (xy 343.562024 -253.270256) (xy 343.57814 -253.31853) (xy 343.586304 -253.368764)
			(xy 343.586816 -253.39421) (xy 343.905344 -253.39421) (xy 343.909304 -253.345156) (xy 343.921081 -253.297372)
			(xy 343.940372 -253.252096) (xy 343.966675 -253.2105) (xy 343.99931 -253.173663) (xy 344.037431 -253.142538)
			(xy 344.080052 -253.117931) (xy 344.126068 -253.100479) (xy 344.174287 -253.090635) (xy 344.223462 -253.088654)
			(xy 344.272317 -253.094586) (xy 344.319588 -253.108278) (xy 344.36405 -253.129376) (xy 344.404553 -253.157332)
			(xy 344.440046 -253.191424) (xy 344.469611 -253.230768) (xy 344.492482 -253.274345) (xy 344.508066 -253.321026)
			(xy 344.515961 -253.369603) (xy 344.516456 -253.39421) (xy 344.515961 -253.418817) (xy 344.508066 -253.467394)
			(xy 344.492482 -253.514075) (xy 344.469611 -253.557652) (xy 344.440046 -253.596996) (xy 344.404553 -253.631088)
			(xy 344.36405 -253.659044) (xy 344.319588 -253.680142) (xy 344.272317 -253.693834) (xy 344.223462 -253.699766)
			(xy 344.174287 -253.697785) (xy 344.126068 -253.687941) (xy 344.080052 -253.670489) (xy 344.037431 -253.645882)
			(xy 343.99931 -253.614757) (xy 343.966675 -253.57792) (xy 343.940372 -253.536324) (xy 343.921081 -253.491048)
			(xy 343.909304 -253.443264) (xy 343.905344 -253.39421) (xy 343.586816 -253.39421) (xy 343.586304 -253.419656)
			(xy 343.57814 -253.46989) (xy 343.562024 -253.518164) (xy 343.538373 -253.563227) (xy 343.5078 -253.603913)
			(xy 343.471096 -253.639168) (xy 343.429212 -253.668078) (xy 343.383233 -253.689895) (xy 343.334349 -253.704055)
			(xy 343.283828 -253.710189) (xy 343.232976 -253.70814) (xy 343.183112 -253.69796) (xy 343.135526 -253.679913)
			(xy 343.091452 -253.654467) (xy 343.05203 -253.62228) (xy 343.018282 -253.584186) (xy 342.991081 -253.541172)
			(xy 342.971133 -253.494352) (xy 342.958954 -253.444938) (xy 342.954859 -253.39421) (xy 342.646762 -253.39421)
			(xy 342.64625 -253.419656) (xy 342.638086 -253.46989) (xy 342.62197 -253.518164) (xy 342.598319 -253.563227)
			(xy 342.567746 -253.603913) (xy 342.531042 -253.639168) (xy 342.489158 -253.668078) (xy 342.443179 -253.689895)
			(xy 342.394295 -253.704055) (xy 342.343774 -253.710189) (xy 342.292922 -253.70814) (xy 342.243058 -253.69796)
			(xy 342.195472 -253.679913) (xy 342.151398 -253.654467) (xy 342.111976 -253.62228) (xy 342.078228 -253.584186)
			(xy 342.051027 -253.541172) (xy 342.031079 -253.494352) (xy 342.0189 -253.444938) (xy 342.014805 -253.39421)
			(xy 341.696294 -253.39421) (xy 341.695799 -253.418817) (xy 341.687904 -253.467394) (xy 341.67232 -253.514075)
			(xy 341.649449 -253.557652) (xy 341.619884 -253.596996) (xy 341.584391 -253.631088) (xy 341.543888 -253.659044)
			(xy 341.499426 -253.680142) (xy 341.452155 -253.693834) (xy 341.4033 -253.699766) (xy 341.354125 -253.697785)
			(xy 341.305906 -253.687941) (xy 341.25989 -253.670489) (xy 341.217269 -253.645882) (xy 341.179148 -253.614757)
			(xy 341.146513 -253.57792) (xy 341.12021 -253.536324) (xy 341.100919 -253.491048) (xy 341.089142 -253.443264)
			(xy 341.085182 -253.39421) (xy 340.766908 -253.39421) (xy 340.766396 -253.419656) (xy 340.758232 -253.46989)
			(xy 340.742116 -253.518164) (xy 340.718465 -253.563227) (xy 340.687892 -253.603913) (xy 340.651188 -253.639168)
			(xy 340.609304 -253.668078) (xy 340.563325 -253.689895) (xy 340.514441 -253.704055) (xy 340.46392 -253.710189)
			(xy 340.413068 -253.70814) (xy 340.363204 -253.69796) (xy 340.315618 -253.679913) (xy 340.271544 -253.654467)
			(xy 340.232122 -253.62228) (xy 340.198374 -253.584186) (xy 340.171173 -253.541172) (xy 340.151225 -253.494352)
			(xy 340.139046 -253.444938) (xy 340.134951 -253.39421) (xy 339.81644 -253.39421) (xy 339.815945 -253.418817)
			(xy 339.80805 -253.467394) (xy 339.792466 -253.514075) (xy 339.769595 -253.557652) (xy 339.74003 -253.596996)
			(xy 339.704537 -253.631088) (xy 339.664034 -253.659044) (xy 339.619572 -253.680142) (xy 339.572301 -253.693834)
			(xy 339.523446 -253.699766) (xy 339.474271 -253.697785) (xy 339.426052 -253.687941) (xy 339.380036 -253.670489)
			(xy 339.337415 -253.645882) (xy 339.299294 -253.614757) (xy 339.266659 -253.57792) (xy 339.240356 -253.536324)
			(xy 339.221065 -253.491048) (xy 339.209288 -253.443264) (xy 339.205328 -253.39421) (xy 338.8868 -253.39421)
			(xy 338.886288 -253.419656) (xy 338.878124 -253.46989) (xy 338.862008 -253.518164) (xy 338.838357 -253.563227)
			(xy 338.807784 -253.603913) (xy 338.77108 -253.639168) (xy 338.729196 -253.668078) (xy 338.683217 -253.689895)
			(xy 338.634333 -253.704055) (xy 338.583812 -253.710189) (xy 338.53296 -253.70814) (xy 338.483096 -253.69796)
			(xy 338.43551 -253.679913) (xy 338.391436 -253.654467) (xy 338.352014 -253.62228) (xy 338.318266 -253.584186)
			(xy 338.291065 -253.541172) (xy 338.271117 -253.494352) (xy 338.258938 -253.444938) (xy 338.254843 -253.39421)
			(xy 337.936332 -253.39421) (xy 337.935837 -253.418817) (xy 337.927942 -253.467394) (xy 337.912358 -253.514075)
			(xy 337.889487 -253.557652) (xy 337.859922 -253.596996) (xy 337.824429 -253.631088) (xy 337.783926 -253.659044)
			(xy 337.739464 -253.680142) (xy 337.692193 -253.693834) (xy 337.643338 -253.699766) (xy 337.594163 -253.697785)
			(xy 337.545944 -253.687941) (xy 337.499928 -253.670489) (xy 337.457307 -253.645882) (xy 337.419186 -253.614757)
			(xy 337.386551 -253.57792) (xy 337.360248 -253.536324) (xy 337.340957 -253.491048) (xy 337.32918 -253.443264)
			(xy 337.32522 -253.39421) (xy 337.006946 -253.39421) (xy 337.006434 -253.419656) (xy 336.99827 -253.46989)
			(xy 336.982154 -253.518164) (xy 336.958503 -253.563227) (xy 336.92793 -253.603913) (xy 336.891226 -253.639168)
			(xy 336.849342 -253.668078) (xy 336.803363 -253.689895) (xy 336.754479 -253.704055) (xy 336.703958 -253.710189)
			(xy 336.653106 -253.70814) (xy 336.603242 -253.69796) (xy 336.555656 -253.679913) (xy 336.511582 -253.654467)
			(xy 336.47216 -253.62228) (xy 336.438412 -253.584186) (xy 336.411211 -253.541172) (xy 336.391263 -253.494352)
			(xy 336.379084 -253.444938) (xy 336.374989 -253.39421) (xy 336.066892 -253.39421) (xy 336.06638 -253.419656)
			(xy 336.058216 -253.46989) (xy 336.0421 -253.518164) (xy 336.018449 -253.563227) (xy 335.987876 -253.603913)
			(xy 335.951172 -253.639168) (xy 335.909288 -253.668078) (xy 335.863309 -253.689895) (xy 335.814425 -253.704055)
			(xy 335.763904 -253.710189) (xy 335.713052 -253.70814) (xy 335.663188 -253.69796) (xy 335.615602 -253.679913)
			(xy 335.571528 -253.654467) (xy 335.532106 -253.62228) (xy 335.498358 -253.584186) (xy 335.471157 -253.541172)
			(xy 335.451209 -253.494352) (xy 335.43903 -253.444938) (xy 335.434935 -253.39421) (xy 335.116424 -253.39421)
			(xy 335.115929 -253.418817) (xy 335.108034 -253.467394) (xy 335.09245 -253.514075) (xy 335.069579 -253.557652)
			(xy 335.040014 -253.596996) (xy 335.004521 -253.631088) (xy 334.964018 -253.659044) (xy 334.919556 -253.680142)
			(xy 334.872285 -253.693834) (xy 334.82343 -253.699766) (xy 334.774255 -253.697785) (xy 334.726036 -253.687941)
			(xy 334.68002 -253.670489) (xy 334.637399 -253.645882) (xy 334.599278 -253.614757) (xy 334.566643 -253.57792)
			(xy 334.54034 -253.536324) (xy 334.521049 -253.491048) (xy 334.509272 -253.443264) (xy 334.505312 -253.39421)
			(xy 334.186784 -253.39421) (xy 334.186272 -253.419656) (xy 334.178108 -253.46989) (xy 334.161992 -253.518164)
			(xy 334.138341 -253.563227) (xy 334.107768 -253.603913) (xy 334.071064 -253.639168) (xy 334.02918 -253.668078)
			(xy 333.983201 -253.689895) (xy 333.934317 -253.704055) (xy 333.883796 -253.710189) (xy 333.832944 -253.70814)
			(xy 333.78308 -253.69796) (xy 333.735494 -253.679913) (xy 333.69142 -253.654467) (xy 333.651998 -253.62228)
			(xy 333.61825 -253.584186) (xy 333.591049 -253.541172) (xy 333.571101 -253.494352) (xy 333.558922 -253.444938)
			(xy 333.554827 -253.39421) (xy 333.236316 -253.39421) (xy 333.235821 -253.418817) (xy 333.227926 -253.467394)
			(xy 333.212342 -253.514075) (xy 333.189471 -253.557652) (xy 333.159906 -253.596996) (xy 333.124413 -253.631088)
			(xy 333.08391 -253.659044) (xy 333.039448 -253.680142) (xy 332.992177 -253.693834) (xy 332.943322 -253.699766)
			(xy 332.894147 -253.697785) (xy 332.845928 -253.687941) (xy 332.799912 -253.670489) (xy 332.757291 -253.645882)
			(xy 332.71917 -253.614757) (xy 332.686535 -253.57792) (xy 332.660232 -253.536324) (xy 332.640941 -253.491048)
			(xy 332.629164 -253.443264) (xy 332.625204 -253.39421) (xy 332.30693 -253.39421) (xy 332.306418 -253.419656)
			(xy 332.298254 -253.46989) (xy 332.282138 -253.518164) (xy 332.258487 -253.563227) (xy 332.227914 -253.603913)
			(xy 332.19121 -253.639168) (xy 332.149326 -253.668078) (xy 332.103347 -253.689895) (xy 332.054463 -253.704055)
			(xy 332.003942 -253.710189) (xy 331.95309 -253.70814) (xy 331.903226 -253.69796) (xy 331.85564 -253.679913)
			(xy 331.811566 -253.654467) (xy 331.772144 -253.62228) (xy 331.738396 -253.584186) (xy 331.711195 -253.541172)
			(xy 331.691247 -253.494352) (xy 331.679068 -253.444938) (xy 331.674973 -253.39421) (xy 331.356462 -253.39421)
			(xy 331.355967 -253.418817) (xy 331.348072 -253.467394) (xy 331.332488 -253.514075) (xy 331.309617 -253.557652)
			(xy 331.280052 -253.596996) (xy 331.244559 -253.631088) (xy 331.204056 -253.659044) (xy 331.159594 -253.680142)
			(xy 331.112323 -253.693834) (xy 331.063468 -253.699766) (xy 331.014293 -253.697785) (xy 330.966074 -253.687941)
			(xy 330.920058 -253.670489) (xy 330.877437 -253.645882) (xy 330.839316 -253.614757) (xy 330.806681 -253.57792)
			(xy 330.780378 -253.536324) (xy 330.761087 -253.491048) (xy 330.74931 -253.443264) (xy 330.74535 -253.39421)
			(xy 330.426822 -253.39421) (xy 330.42631 -253.419656) (xy 330.418146 -253.46989) (xy 330.40203 -253.518164)
			(xy 330.378379 -253.563227) (xy 330.347806 -253.603913) (xy 330.311102 -253.639168) (xy 330.269218 -253.668078)
			(xy 330.223239 -253.689895) (xy 330.174355 -253.704055) (xy 330.123834 -253.710189) (xy 330.072982 -253.70814)
			(xy 330.023118 -253.69796) (xy 329.975532 -253.679913) (xy 329.931458 -253.654467) (xy 329.892036 -253.62228)
			(xy 329.858288 -253.584186) (xy 329.831087 -253.541172) (xy 329.811139 -253.494352) (xy 329.79896 -253.444938)
			(xy 329.794865 -253.39421) (xy 329.486768 -253.39421) (xy 329.486256 -253.419656) (xy 329.478092 -253.46989)
			(xy 329.461976 -253.518164) (xy 329.438325 -253.563227) (xy 329.407752 -253.603913) (xy 329.371048 -253.639168)
			(xy 329.329164 -253.668078) (xy 329.283185 -253.689895) (xy 329.234301 -253.704055) (xy 329.18378 -253.710189)
			(xy 329.132928 -253.70814) (xy 329.083064 -253.69796) (xy 329.035478 -253.679913) (xy 328.991404 -253.654467)
			(xy 328.951982 -253.62228) (xy 328.918234 -253.584186) (xy 328.891033 -253.541172) (xy 328.871085 -253.494352)
			(xy 328.858906 -253.444938) (xy 328.854811 -253.39421) (xy 328.536554 -253.39421) (xy 328.536059 -253.418817)
			(xy 328.528164 -253.467394) (xy 328.51258 -253.514075) (xy 328.489709 -253.557652) (xy 328.460144 -253.596996)
			(xy 328.424651 -253.631088) (xy 328.384148 -253.659044) (xy 328.339686 -253.680142) (xy 328.292415 -253.693834)
			(xy 328.24356 -253.699766) (xy 328.194385 -253.697785) (xy 328.146166 -253.687941) (xy 328.10015 -253.670489)
			(xy 328.057529 -253.645882) (xy 328.019408 -253.614757) (xy 327.986773 -253.57792) (xy 327.96047 -253.536324)
			(xy 327.941179 -253.491048) (xy 327.929402 -253.443264) (xy 327.925442 -253.39421) (xy 326.656446 -253.39421)
			(xy 326.655951 -253.418817) (xy 326.648056 -253.467394) (xy 326.632472 -253.514075) (xy 326.609601 -253.557652)
			(xy 326.580036 -253.596996) (xy 326.544543 -253.631088) (xy 326.50404 -253.659044) (xy 326.459578 -253.680142)
			(xy 326.412307 -253.693834) (xy 326.363452 -253.699766) (xy 326.314277 -253.697785) (xy 326.266058 -253.687941)
			(xy 326.220042 -253.670489) (xy 326.177421 -253.645882) (xy 326.1393 -253.614757) (xy 326.106665 -253.57792)
			(xy 326.080362 -253.536324) (xy 326.061071 -253.491048) (xy 326.049294 -253.443264) (xy 326.045334 -253.39421)
			(xy 310.45912 -253.39421) (xy 310.45912 -254.470154) (xy 324.447166 -254.470154) (xy 324.451126 -254.4211)
			(xy 324.462903 -254.373316) (xy 324.482194 -254.32804) (xy 324.508497 -254.286444) (xy 324.541132 -254.249607)
			(xy 324.579253 -254.218482) (xy 324.621874 -254.193875) (xy 324.66789 -254.176423) (xy 324.716109 -254.166579)
			(xy 324.765284 -254.164598) (xy 324.814139 -254.17053) (xy 324.86141 -254.184222) (xy 324.903545 -254.204216)
			(xy 328.384911 -254.204216) (xy 328.389006 -254.153488) (xy 328.401185 -254.104074) (xy 328.421133 -254.057254)
			(xy 328.448334 -254.01424) (xy 328.482082 -253.976146) (xy 328.521504 -253.943959) (xy 328.565578 -253.918513)
			(xy 328.613164 -253.900466) (xy 328.663028 -253.890286) (xy 328.71388 -253.888237) (xy 328.764401 -253.894371)
			(xy 328.813285 -253.908531) (xy 328.859264 -253.930348) (xy 328.901148 -253.959258) (xy 328.937852 -253.994513)
			(xy 328.968425 -254.035199) (xy 328.992076 -254.080262) (xy 329.008192 -254.128536) (xy 329.016356 -254.17877)
			(xy 329.016868 -254.204216) (xy 329.335396 -254.204216) (xy 329.339356 -254.155162) (xy 329.351133 -254.107378)
			(xy 329.370424 -254.062102) (xy 329.396727 -254.020506) (xy 329.429362 -253.983669) (xy 329.467483 -253.952544)
			(xy 329.510104 -253.927937) (xy 329.55612 -253.910485) (xy 329.604339 -253.900641) (xy 329.653514 -253.89866)
			(xy 329.702369 -253.904592) (xy 329.74964 -253.918284) (xy 329.794102 -253.939382) (xy 329.834605 -253.967338)
			(xy 329.870098 -254.00143) (xy 329.899663 -254.040774) (xy 329.922534 -254.084351) (xy 329.938118 -254.131032)
			(xy 329.946013 -254.179609) (xy 329.946508 -254.204216) (xy 330.264765 -254.204216) (xy 330.26886 -254.153488)
			(xy 330.281039 -254.104074) (xy 330.300987 -254.057254) (xy 330.328188 -254.01424) (xy 330.361936 -253.976146)
			(xy 330.401358 -253.943959) (xy 330.445432 -253.918513) (xy 330.493018 -253.900466) (xy 330.542882 -253.890286)
			(xy 330.593734 -253.888237) (xy 330.644255 -253.894371) (xy 330.693139 -253.908531) (xy 330.739118 -253.930348)
			(xy 330.781002 -253.959258) (xy 330.817706 -253.994513) (xy 330.848279 -254.035199) (xy 330.87193 -254.080262)
			(xy 330.888046 -254.128536) (xy 330.89621 -254.17877) (xy 330.896722 -254.204216) (xy 331.21525 -254.204216)
			(xy 331.21921 -254.155162) (xy 331.230987 -254.107378) (xy 331.250278 -254.062102) (xy 331.276581 -254.020506)
			(xy 331.309216 -253.983669) (xy 331.347337 -253.952544) (xy 331.389958 -253.927937) (xy 331.435974 -253.910485)
			(xy 331.484193 -253.900641) (xy 331.533368 -253.89866) (xy 331.582223 -253.904592) (xy 331.629494 -253.918284)
			(xy 331.673956 -253.939382) (xy 331.714459 -253.967338) (xy 331.749952 -254.00143) (xy 331.779517 -254.040774)
			(xy 331.802388 -254.084351) (xy 331.817972 -254.131032) (xy 331.825867 -254.179609) (xy 331.826362 -254.204216)
			(xy 332.144873 -254.204216) (xy 332.148968 -254.153488) (xy 332.161147 -254.104074) (xy 332.181095 -254.057254)
			(xy 332.208296 -254.01424) (xy 332.242044 -253.976146) (xy 332.281466 -253.943959) (xy 332.32554 -253.918513)
			(xy 332.373126 -253.900466) (xy 332.42299 -253.890286) (xy 332.473842 -253.888237) (xy 332.524363 -253.894371)
			(xy 332.573247 -253.908531) (xy 332.619226 -253.930348) (xy 332.66111 -253.959258) (xy 332.697814 -253.994513)
			(xy 332.728387 -254.035199) (xy 332.752038 -254.080262) (xy 332.768154 -254.128536) (xy 332.776318 -254.17877)
			(xy 332.77683 -254.204216) (xy 333.084927 -254.204216) (xy 333.089022 -254.153488) (xy 333.101201 -254.104074)
			(xy 333.121149 -254.057254) (xy 333.14835 -254.01424) (xy 333.182098 -253.976146) (xy 333.22152 -253.943959)
			(xy 333.265594 -253.918513) (xy 333.31318 -253.900466) (xy 333.363044 -253.890286) (xy 333.413896 -253.888237)
			(xy 333.464417 -253.894371) (xy 333.513301 -253.908531) (xy 333.55928 -253.930348) (xy 333.601164 -253.959258)
			(xy 333.637868 -253.994513) (xy 333.668441 -254.035199) (xy 333.692092 -254.080262) (xy 333.708208 -254.128536)
			(xy 333.716372 -254.17877) (xy 333.716884 -254.204216) (xy 334.964781 -254.204216) (xy 334.968876 -254.153488)
			(xy 334.981055 -254.104074) (xy 335.001003 -254.057254) (xy 335.028204 -254.01424) (xy 335.061952 -253.976146)
			(xy 335.101374 -253.943959) (xy 335.145448 -253.918513) (xy 335.193034 -253.900466) (xy 335.242898 -253.890286)
			(xy 335.29375 -253.888237) (xy 335.344271 -253.894371) (xy 335.393155 -253.908531) (xy 335.439134 -253.930348)
			(xy 335.481018 -253.959258) (xy 335.517722 -253.994513) (xy 335.548295 -254.035199) (xy 335.571946 -254.080262)
			(xy 335.588062 -254.128536) (xy 335.596226 -254.17877) (xy 335.596738 -254.204216) (xy 335.915266 -254.204216)
			(xy 335.919226 -254.155162) (xy 335.931003 -254.107378) (xy 335.950294 -254.062102) (xy 335.976597 -254.020506)
			(xy 336.009232 -253.983669) (xy 336.047353 -253.952544) (xy 336.089974 -253.927937) (xy 336.13599 -253.910485)
			(xy 336.184209 -253.900641) (xy 336.233384 -253.89866) (xy 336.282239 -253.904592) (xy 336.32951 -253.918284)
			(xy 336.373972 -253.939382) (xy 336.414475 -253.967338) (xy 336.449968 -254.00143) (xy 336.479533 -254.040774)
			(xy 336.502404 -254.084351) (xy 336.517988 -254.131032) (xy 336.525883 -254.179609) (xy 336.526378 -254.204216)
			(xy 336.844889 -254.204216) (xy 336.848984 -254.153488) (xy 336.861163 -254.104074) (xy 336.881111 -254.057254)
			(xy 336.908312 -254.01424) (xy 336.94206 -253.976146) (xy 336.981482 -253.943959) (xy 337.025556 -253.918513)
			(xy 337.073142 -253.900466) (xy 337.123006 -253.890286) (xy 337.173858 -253.888237) (xy 337.224379 -253.894371)
			(xy 337.273263 -253.908531) (xy 337.319242 -253.930348) (xy 337.361126 -253.959258) (xy 337.39783 -253.994513)
			(xy 337.428403 -254.035199) (xy 337.452054 -254.080262) (xy 337.46817 -254.128536) (xy 337.476334 -254.17877)
			(xy 337.476846 -254.204216) (xy 337.795374 -254.204216) (xy 337.799334 -254.155162) (xy 337.811111 -254.107378)
			(xy 337.830402 -254.062102) (xy 337.856705 -254.020506) (xy 337.88934 -253.983669) (xy 337.927461 -253.952544)
			(xy 337.970082 -253.927937) (xy 338.016098 -253.910485) (xy 338.064317 -253.900641) (xy 338.113492 -253.89866)
			(xy 338.162347 -253.904592) (xy 338.209618 -253.918284) (xy 338.25408 -253.939382) (xy 338.294583 -253.967338)
			(xy 338.330076 -254.00143) (xy 338.359641 -254.040774) (xy 338.382512 -254.084351) (xy 338.398096 -254.131032)
			(xy 338.405991 -254.179609) (xy 338.406486 -254.204216) (xy 338.724743 -254.204216) (xy 338.728838 -254.153488)
			(xy 338.741017 -254.104074) (xy 338.760965 -254.057254) (xy 338.788166 -254.01424) (xy 338.821914 -253.976146)
			(xy 338.861336 -253.943959) (xy 338.90541 -253.918513) (xy 338.952996 -253.900466) (xy 339.00286 -253.890286)
			(xy 339.053712 -253.888237) (xy 339.104233 -253.894371) (xy 339.153117 -253.908531) (xy 339.199096 -253.930348)
			(xy 339.24098 -253.959258) (xy 339.277684 -253.994513) (xy 339.308257 -254.035199) (xy 339.331908 -254.080262)
			(xy 339.348024 -254.128536) (xy 339.356188 -254.17877) (xy 339.3567 -254.204216) (xy 339.664797 -254.204216)
			(xy 339.668892 -254.153488) (xy 339.681071 -254.104074) (xy 339.701019 -254.057254) (xy 339.72822 -254.01424)
			(xy 339.761968 -253.976146) (xy 339.80139 -253.943959) (xy 339.845464 -253.918513) (xy 339.89305 -253.900466)
			(xy 339.942914 -253.890286) (xy 339.993766 -253.888237) (xy 340.044287 -253.894371) (xy 340.093171 -253.908531)
			(xy 340.13915 -253.930348) (xy 340.181034 -253.959258) (xy 340.217738 -253.994513) (xy 340.248311 -254.035199)
			(xy 340.271962 -254.080262) (xy 340.288078 -254.128536) (xy 340.296242 -254.17877) (xy 340.296754 -254.204216)
			(xy 341.544905 -254.204216) (xy 341.549 -254.153488) (xy 341.561179 -254.104074) (xy 341.581127 -254.057254)
			(xy 341.608328 -254.01424) (xy 341.642076 -253.976146) (xy 341.681498 -253.943959) (xy 341.725572 -253.918513)
			(xy 341.773158 -253.900466) (xy 341.823022 -253.890286) (xy 341.873874 -253.888237) (xy 341.924395 -253.894371)
			(xy 341.973279 -253.908531) (xy 342.019258 -253.930348) (xy 342.061142 -253.959258) (xy 342.097846 -253.994513)
			(xy 342.128419 -254.035199) (xy 342.15207 -254.080262) (xy 342.168186 -254.128536) (xy 342.17635 -254.17877)
			(xy 342.176862 -254.204216) (xy 342.49539 -254.204216) (xy 342.49935 -254.155162) (xy 342.511127 -254.107378)
			(xy 342.530418 -254.062102) (xy 342.556721 -254.020506) (xy 342.589356 -253.983669) (xy 342.627477 -253.952544)
			(xy 342.670098 -253.927937) (xy 342.716114 -253.910485) (xy 342.764333 -253.900641) (xy 342.813508 -253.89866)
			(xy 342.862363 -253.904592) (xy 342.909634 -253.918284) (xy 342.954096 -253.939382) (xy 342.994599 -253.967338)
			(xy 343.030092 -254.00143) (xy 343.059657 -254.040774) (xy 343.082528 -254.084351) (xy 343.098112 -254.131032)
			(xy 343.106007 -254.179609) (xy 343.106502 -254.204216) (xy 343.424759 -254.204216) (xy 343.428854 -254.153488)
			(xy 343.441033 -254.104074) (xy 343.460981 -254.057254) (xy 343.488182 -254.01424) (xy 343.52193 -253.976146)
			(xy 343.561352 -253.943959) (xy 343.605426 -253.918513) (xy 343.653012 -253.900466) (xy 343.702876 -253.890286)
			(xy 343.753728 -253.888237) (xy 343.804249 -253.894371) (xy 343.853133 -253.908531) (xy 343.899112 -253.930348)
			(xy 343.940996 -253.959258) (xy 343.9777 -253.994513) (xy 344.008273 -254.035199) (xy 344.031924 -254.080262)
			(xy 344.04804 -254.128536) (xy 344.056204 -254.17877) (xy 344.056716 -254.204216) (xy 344.056204 -254.229662)
			(xy 344.04804 -254.279896) (xy 344.031924 -254.32817) (xy 344.008273 -254.373233) (xy 343.9777 -254.413919)
			(xy 343.940996 -254.449174) (xy 343.899112 -254.478084) (xy 343.853133 -254.499901) (xy 343.804249 -254.514061)
			(xy 343.753728 -254.520195) (xy 343.702876 -254.518146) (xy 343.653012 -254.507966) (xy 343.605426 -254.489919)
			(xy 343.561352 -254.464473) (xy 343.52193 -254.432286) (xy 343.488182 -254.394192) (xy 343.460981 -254.351178)
			(xy 343.441033 -254.304358) (xy 343.428854 -254.254944) (xy 343.424759 -254.204216) (xy 343.106502 -254.204216)
			(xy 343.106007 -254.228823) (xy 343.098112 -254.2774) (xy 343.082528 -254.324081) (xy 343.059657 -254.367658)
			(xy 343.030092 -254.407002) (xy 342.994599 -254.441094) (xy 342.954096 -254.46905) (xy 342.909634 -254.490148)
			(xy 342.862363 -254.50384) (xy 342.813508 -254.509772) (xy 342.764333 -254.507791) (xy 342.716114 -254.497947)
			(xy 342.670098 -254.480495) (xy 342.627477 -254.455888) (xy 342.589356 -254.424763) (xy 342.556721 -254.387926)
			(xy 342.530418 -254.34633) (xy 342.511127 -254.301054) (xy 342.49935 -254.25327) (xy 342.49539 -254.204216)
			(xy 342.176862 -254.204216) (xy 342.17635 -254.229662) (xy 342.168186 -254.279896) (xy 342.15207 -254.32817)
			(xy 342.128419 -254.373233) (xy 342.097846 -254.413919) (xy 342.061142 -254.449174) (xy 342.019258 -254.478084)
			(xy 341.973279 -254.499901) (xy 341.924395 -254.514061) (xy 341.873874 -254.520195) (xy 341.823022 -254.518146)
			(xy 341.773158 -254.507966) (xy 341.725572 -254.489919) (xy 341.681498 -254.464473) (xy 341.642076 -254.432286)
			(xy 341.608328 -254.394192) (xy 341.581127 -254.351178) (xy 341.561179 -254.304358) (xy 341.549 -254.254944)
			(xy 341.544905 -254.204216) (xy 340.296754 -254.204216) (xy 340.296242 -254.229662) (xy 340.288078 -254.279896)
			(xy 340.271962 -254.32817) (xy 340.248311 -254.373233) (xy 340.217738 -254.413919) (xy 340.181034 -254.449174)
			(xy 340.13915 -254.478084) (xy 340.093171 -254.499901) (xy 340.044287 -254.514061) (xy 339.993766 -254.520195)
			(xy 339.942914 -254.518146) (xy 339.89305 -254.507966) (xy 339.845464 -254.489919) (xy 339.80139 -254.464473)
			(xy 339.761968 -254.432286) (xy 339.72822 -254.394192) (xy 339.701019 -254.351178) (xy 339.681071 -254.304358)
			(xy 339.668892 -254.254944) (xy 339.664797 -254.204216) (xy 339.3567 -254.204216) (xy 339.356188 -254.229662)
			(xy 339.348024 -254.279896) (xy 339.331908 -254.32817) (xy 339.308257 -254.373233) (xy 339.277684 -254.413919)
			(xy 339.24098 -254.449174) (xy 339.199096 -254.478084) (xy 339.153117 -254.499901) (xy 339.104233 -254.514061)
			(xy 339.053712 -254.520195) (xy 339.00286 -254.518146) (xy 338.952996 -254.507966) (xy 338.90541 -254.489919)
			(xy 338.861336 -254.464473) (xy 338.821914 -254.432286) (xy 338.788166 -254.394192) (xy 338.760965 -254.351178)
			(xy 338.741017 -254.304358) (xy 338.728838 -254.254944) (xy 338.724743 -254.204216) (xy 338.406486 -254.204216)
			(xy 338.405991 -254.228823) (xy 338.398096 -254.2774) (xy 338.382512 -254.324081) (xy 338.359641 -254.367658)
			(xy 338.330076 -254.407002) (xy 338.294583 -254.441094) (xy 338.25408 -254.46905) (xy 338.209618 -254.490148)
			(xy 338.162347 -254.50384) (xy 338.113492 -254.509772) (xy 338.064317 -254.507791) (xy 338.016098 -254.497947)
			(xy 337.970082 -254.480495) (xy 337.927461 -254.455888) (xy 337.88934 -254.424763) (xy 337.856705 -254.387926)
			(xy 337.830402 -254.34633) (xy 337.811111 -254.301054) (xy 337.799334 -254.25327) (xy 337.795374 -254.204216)
			(xy 337.476846 -254.204216) (xy 337.476334 -254.229662) (xy 337.46817 -254.279896) (xy 337.452054 -254.32817)
			(xy 337.428403 -254.373233) (xy 337.39783 -254.413919) (xy 337.361126 -254.449174) (xy 337.319242 -254.478084)
			(xy 337.273263 -254.499901) (xy 337.224379 -254.514061) (xy 337.173858 -254.520195) (xy 337.123006 -254.518146)
			(xy 337.073142 -254.507966) (xy 337.025556 -254.489919) (xy 336.981482 -254.464473) (xy 336.94206 -254.432286)
			(xy 336.908312 -254.394192) (xy 336.881111 -254.351178) (xy 336.861163 -254.304358) (xy 336.848984 -254.254944)
			(xy 336.844889 -254.204216) (xy 336.526378 -254.204216) (xy 336.525883 -254.228823) (xy 336.517988 -254.2774)
			(xy 336.502404 -254.324081) (xy 336.479533 -254.367658) (xy 336.449968 -254.407002) (xy 336.414475 -254.441094)
			(xy 336.373972 -254.46905) (xy 336.32951 -254.490148) (xy 336.282239 -254.50384) (xy 336.233384 -254.509772)
			(xy 336.184209 -254.507791) (xy 336.13599 -254.497947) (xy 336.089974 -254.480495) (xy 336.047353 -254.455888)
			(xy 336.009232 -254.424763) (xy 335.976597 -254.387926) (xy 335.950294 -254.34633) (xy 335.931003 -254.301054)
			(xy 335.919226 -254.25327) (xy 335.915266 -254.204216) (xy 335.596738 -254.204216) (xy 335.596226 -254.229662)
			(xy 335.588062 -254.279896) (xy 335.571946 -254.32817) (xy 335.548295 -254.373233) (xy 335.517722 -254.413919)
			(xy 335.481018 -254.449174) (xy 335.439134 -254.478084) (xy 335.393155 -254.499901) (xy 335.344271 -254.514061)
			(xy 335.29375 -254.520195) (xy 335.242898 -254.518146) (xy 335.193034 -254.507966) (xy 335.145448 -254.489919)
			(xy 335.101374 -254.464473) (xy 335.061952 -254.432286) (xy 335.028204 -254.394192) (xy 335.001003 -254.351178)
			(xy 334.981055 -254.304358) (xy 334.968876 -254.254944) (xy 334.964781 -254.204216) (xy 333.716884 -254.204216)
			(xy 333.716372 -254.229662) (xy 333.708208 -254.279896) (xy 333.692092 -254.32817) (xy 333.668441 -254.373233)
			(xy 333.637868 -254.413919) (xy 333.601164 -254.449174) (xy 333.55928 -254.478084) (xy 333.513301 -254.499901)
			(xy 333.464417 -254.514061) (xy 333.413896 -254.520195) (xy 333.363044 -254.518146) (xy 333.31318 -254.507966)
			(xy 333.265594 -254.489919) (xy 333.22152 -254.464473) (xy 333.182098 -254.432286) (xy 333.14835 -254.394192)
			(xy 333.121149 -254.351178) (xy 333.101201 -254.304358) (xy 333.089022 -254.254944) (xy 333.084927 -254.204216)
			(xy 332.77683 -254.204216) (xy 332.776318 -254.229662) (xy 332.768154 -254.279896) (xy 332.752038 -254.32817)
			(xy 332.728387 -254.373233) (xy 332.697814 -254.413919) (xy 332.66111 -254.449174) (xy 332.619226 -254.478084)
			(xy 332.573247 -254.499901) (xy 332.524363 -254.514061) (xy 332.473842 -254.520195) (xy 332.42299 -254.518146)
			(xy 332.373126 -254.507966) (xy 332.32554 -254.489919) (xy 332.281466 -254.464473) (xy 332.242044 -254.432286)
			(xy 332.208296 -254.394192) (xy 332.181095 -254.351178) (xy 332.161147 -254.304358) (xy 332.148968 -254.254944)
			(xy 332.144873 -254.204216) (xy 331.826362 -254.204216) (xy 331.825867 -254.228823) (xy 331.817972 -254.2774)
			(xy 331.802388 -254.324081) (xy 331.779517 -254.367658) (xy 331.749952 -254.407002) (xy 331.714459 -254.441094)
			(xy 331.673956 -254.46905) (xy 331.629494 -254.490148) (xy 331.582223 -254.50384) (xy 331.533368 -254.509772)
			(xy 331.484193 -254.507791) (xy 331.435974 -254.497947) (xy 331.389958 -254.480495) (xy 331.347337 -254.455888)
			(xy 331.309216 -254.424763) (xy 331.276581 -254.387926) (xy 331.250278 -254.34633) (xy 331.230987 -254.301054)
			(xy 331.21921 -254.25327) (xy 331.21525 -254.204216) (xy 330.896722 -254.204216) (xy 330.89621 -254.229662)
			(xy 330.888046 -254.279896) (xy 330.87193 -254.32817) (xy 330.848279 -254.373233) (xy 330.817706 -254.413919)
			(xy 330.781002 -254.449174) (xy 330.739118 -254.478084) (xy 330.693139 -254.499901) (xy 330.644255 -254.514061)
			(xy 330.593734 -254.520195) (xy 330.542882 -254.518146) (xy 330.493018 -254.507966) (xy 330.445432 -254.489919)
			(xy 330.401358 -254.464473) (xy 330.361936 -254.432286) (xy 330.328188 -254.394192) (xy 330.300987 -254.351178)
			(xy 330.281039 -254.304358) (xy 330.26886 -254.254944) (xy 330.264765 -254.204216) (xy 329.946508 -254.204216)
			(xy 329.946013 -254.228823) (xy 329.938118 -254.2774) (xy 329.922534 -254.324081) (xy 329.899663 -254.367658)
			(xy 329.870098 -254.407002) (xy 329.834605 -254.441094) (xy 329.794102 -254.46905) (xy 329.74964 -254.490148)
			(xy 329.702369 -254.50384) (xy 329.653514 -254.509772) (xy 329.604339 -254.507791) (xy 329.55612 -254.497947)
			(xy 329.510104 -254.480495) (xy 329.467483 -254.455888) (xy 329.429362 -254.424763) (xy 329.396727 -254.387926)
			(xy 329.370424 -254.34633) (xy 329.351133 -254.301054) (xy 329.339356 -254.25327) (xy 329.335396 -254.204216)
			(xy 329.016868 -254.204216) (xy 329.016356 -254.229662) (xy 329.008192 -254.279896) (xy 328.992076 -254.32817)
			(xy 328.968425 -254.373233) (xy 328.937852 -254.413919) (xy 328.901148 -254.449174) (xy 328.859264 -254.478084)
			(xy 328.813285 -254.499901) (xy 328.764401 -254.514061) (xy 328.71388 -254.520195) (xy 328.663028 -254.518146)
			(xy 328.613164 -254.507966) (xy 328.565578 -254.489919) (xy 328.521504 -254.464473) (xy 328.482082 -254.432286)
			(xy 328.448334 -254.394192) (xy 328.421133 -254.351178) (xy 328.401185 -254.304358) (xy 328.389006 -254.254944)
			(xy 328.384911 -254.204216) (xy 324.903545 -254.204216) (xy 324.905872 -254.20532) (xy 324.946375 -254.233276)
			(xy 324.981868 -254.267368) (xy 325.011433 -254.306712) (xy 325.034304 -254.350289) (xy 325.049888 -254.39697)
			(xy 325.057783 -254.445547) (xy 325.058278 -254.470154) (xy 325.057783 -254.494761) (xy 325.049888 -254.543338)
			(xy 325.034304 -254.590019) (xy 325.011433 -254.633596) (xy 324.981868 -254.67294) (xy 324.946375 -254.707032)
			(xy 324.905872 -254.734988) (xy 324.86141 -254.756086) (xy 324.814139 -254.769778) (xy 324.765284 -254.77571)
			(xy 324.716109 -254.773729) (xy 324.66789 -254.763885) (xy 324.621874 -254.746433) (xy 324.579253 -254.721826)
			(xy 324.541132 -254.690701) (xy 324.508497 -254.653864) (xy 324.482194 -254.612268) (xy 324.462903 -254.566992)
			(xy 324.451126 -254.519208) (xy 324.447166 -254.470154) (xy 310.45912 -254.470154) (xy 310.45912 -255.014222)
			(xy 326.045334 -255.014222) (xy 326.049294 -254.965168) (xy 326.061071 -254.917384) (xy 326.080362 -254.872108)
			(xy 326.106665 -254.830512) (xy 326.1393 -254.793675) (xy 326.177421 -254.76255) (xy 326.220042 -254.737943)
			(xy 326.266058 -254.720491) (xy 326.314277 -254.710647) (xy 326.363452 -254.708666) (xy 326.412307 -254.714598)
			(xy 326.459578 -254.72829) (xy 326.50404 -254.749388) (xy 326.544543 -254.777344) (xy 326.580036 -254.811436)
			(xy 326.609601 -254.85078) (xy 326.632472 -254.894357) (xy 326.648056 -254.941038) (xy 326.655951 -254.989615)
			(xy 326.656446 -255.014222) (xy 327.925442 -255.014222) (xy 327.929402 -254.965168) (xy 327.941179 -254.917384)
			(xy 327.96047 -254.872108) (xy 327.986773 -254.830512) (xy 328.019408 -254.793675) (xy 328.057529 -254.76255)
			(xy 328.10015 -254.737943) (xy 328.146166 -254.720491) (xy 328.194385 -254.710647) (xy 328.24356 -254.708666)
			(xy 328.292415 -254.714598) (xy 328.339686 -254.72829) (xy 328.384148 -254.749388) (xy 328.424651 -254.777344)
			(xy 328.460144 -254.811436) (xy 328.489709 -254.85078) (xy 328.51258 -254.894357) (xy 328.528164 -254.941038)
			(xy 328.536059 -254.989615) (xy 328.536554 -255.014222) (xy 328.854811 -255.014222) (xy 328.858906 -254.963494)
			(xy 328.871085 -254.91408) (xy 328.891033 -254.86726) (xy 328.918234 -254.824246) (xy 328.951982 -254.786152)
			(xy 328.991404 -254.753965) (xy 329.035478 -254.728519) (xy 329.083064 -254.710472) (xy 329.132928 -254.700292)
			(xy 329.18378 -254.698243) (xy 329.234301 -254.704377) (xy 329.283185 -254.718537) (xy 329.329164 -254.740354)
			(xy 329.371048 -254.769264) (xy 329.407752 -254.804519) (xy 329.438325 -254.845205) (xy 329.461976 -254.890268)
			(xy 329.478092 -254.938542) (xy 329.486256 -254.988776) (xy 329.486768 -255.014222) (xy 329.794865 -255.014222)
			(xy 329.79896 -254.963494) (xy 329.811139 -254.91408) (xy 329.831087 -254.86726) (xy 329.858288 -254.824246)
			(xy 329.892036 -254.786152) (xy 329.931458 -254.753965) (xy 329.975532 -254.728519) (xy 330.023118 -254.710472)
			(xy 330.072982 -254.700292) (xy 330.123834 -254.698243) (xy 330.174355 -254.704377) (xy 330.223239 -254.718537)
			(xy 330.269218 -254.740354) (xy 330.311102 -254.769264) (xy 330.347806 -254.804519) (xy 330.378379 -254.845205)
			(xy 330.40203 -254.890268) (xy 330.418146 -254.938542) (xy 330.42631 -254.988776) (xy 330.426822 -255.014222)
			(xy 330.74535 -255.014222) (xy 330.74931 -254.965168) (xy 330.761087 -254.917384) (xy 330.780378 -254.872108)
			(xy 330.806681 -254.830512) (xy 330.839316 -254.793675) (xy 330.877437 -254.76255) (xy 330.920058 -254.737943)
			(xy 330.966074 -254.720491) (xy 331.014293 -254.710647) (xy 331.063468 -254.708666) (xy 331.112323 -254.714598)
			(xy 331.159594 -254.72829) (xy 331.204056 -254.749388) (xy 331.244559 -254.777344) (xy 331.280052 -254.811436)
			(xy 331.309617 -254.85078) (xy 331.332488 -254.894357) (xy 331.348072 -254.941038) (xy 331.355967 -254.989615)
			(xy 331.356462 -255.014222) (xy 331.674973 -255.014222) (xy 331.679068 -254.963494) (xy 331.691247 -254.91408)
			(xy 331.711195 -254.86726) (xy 331.738396 -254.824246) (xy 331.772144 -254.786152) (xy 331.811566 -254.753965)
			(xy 331.85564 -254.728519) (xy 331.903226 -254.710472) (xy 331.95309 -254.700292) (xy 332.003942 -254.698243)
			(xy 332.054463 -254.704377) (xy 332.103347 -254.718537) (xy 332.149326 -254.740354) (xy 332.19121 -254.769264)
			(xy 332.227914 -254.804519) (xy 332.258487 -254.845205) (xy 332.282138 -254.890268) (xy 332.298254 -254.938542)
			(xy 332.306418 -254.988776) (xy 332.30693 -255.014222) (xy 332.625204 -255.014222) (xy 332.629164 -254.965168)
			(xy 332.640941 -254.917384) (xy 332.660232 -254.872108) (xy 332.686535 -254.830512) (xy 332.71917 -254.793675)
			(xy 332.757291 -254.76255) (xy 332.799912 -254.737943) (xy 332.845928 -254.720491) (xy 332.894147 -254.710647)
			(xy 332.943322 -254.708666) (xy 332.992177 -254.714598) (xy 333.039448 -254.72829) (xy 333.08391 -254.749388)
			(xy 333.124413 -254.777344) (xy 333.159906 -254.811436) (xy 333.189471 -254.85078) (xy 333.212342 -254.894357)
			(xy 333.227926 -254.941038) (xy 333.235821 -254.989615) (xy 333.236316 -255.014222) (xy 333.554827 -255.014222)
			(xy 333.558922 -254.963494) (xy 333.571101 -254.91408) (xy 333.591049 -254.86726) (xy 333.61825 -254.824246)
			(xy 333.651998 -254.786152) (xy 333.69142 -254.753965) (xy 333.735494 -254.728519) (xy 333.78308 -254.710472)
			(xy 333.832944 -254.700292) (xy 333.883796 -254.698243) (xy 333.934317 -254.704377) (xy 333.983201 -254.718537)
			(xy 334.02918 -254.740354) (xy 334.071064 -254.769264) (xy 334.107768 -254.804519) (xy 334.138341 -254.845205)
			(xy 334.161992 -254.890268) (xy 334.178108 -254.938542) (xy 334.186272 -254.988776) (xy 334.186784 -255.014222)
			(xy 334.505312 -255.014222) (xy 334.509272 -254.965168) (xy 334.521049 -254.917384) (xy 334.54034 -254.872108)
			(xy 334.566643 -254.830512) (xy 334.599278 -254.793675) (xy 334.637399 -254.76255) (xy 334.68002 -254.737943)
			(xy 334.726036 -254.720491) (xy 334.774255 -254.710647) (xy 334.82343 -254.708666) (xy 334.872285 -254.714598)
			(xy 334.919556 -254.72829) (xy 334.964018 -254.749388) (xy 335.004521 -254.777344) (xy 335.040014 -254.811436)
			(xy 335.069579 -254.85078) (xy 335.09245 -254.894357) (xy 335.108034 -254.941038) (xy 335.115929 -254.989615)
			(xy 335.116424 -255.014222) (xy 335.434935 -255.014222) (xy 335.43903 -254.963494) (xy 335.451209 -254.91408)
			(xy 335.471157 -254.86726) (xy 335.498358 -254.824246) (xy 335.532106 -254.786152) (xy 335.571528 -254.753965)
			(xy 335.615602 -254.728519) (xy 335.663188 -254.710472) (xy 335.713052 -254.700292) (xy 335.763904 -254.698243)
			(xy 335.814425 -254.704377) (xy 335.863309 -254.718537) (xy 335.909288 -254.740354) (xy 335.951172 -254.769264)
			(xy 335.987876 -254.804519) (xy 336.018449 -254.845205) (xy 336.0421 -254.890268) (xy 336.058216 -254.938542)
			(xy 336.06638 -254.988776) (xy 336.066892 -255.014222) (xy 336.374989 -255.014222) (xy 336.379084 -254.963494)
			(xy 336.391263 -254.91408) (xy 336.411211 -254.86726) (xy 336.438412 -254.824246) (xy 336.47216 -254.786152)
			(xy 336.511582 -254.753965) (xy 336.555656 -254.728519) (xy 336.603242 -254.710472) (xy 336.653106 -254.700292)
			(xy 336.703958 -254.698243) (xy 336.754479 -254.704377) (xy 336.803363 -254.718537) (xy 336.849342 -254.740354)
			(xy 336.891226 -254.769264) (xy 336.92793 -254.804519) (xy 336.958503 -254.845205) (xy 336.982154 -254.890268)
			(xy 336.99827 -254.938542) (xy 337.006434 -254.988776) (xy 337.006946 -255.014222) (xy 337.32522 -255.014222)
			(xy 337.32918 -254.965168) (xy 337.340957 -254.917384) (xy 337.360248 -254.872108) (xy 337.386551 -254.830512)
			(xy 337.419186 -254.793675) (xy 337.457307 -254.76255) (xy 337.499928 -254.737943) (xy 337.545944 -254.720491)
			(xy 337.594163 -254.710647) (xy 337.643338 -254.708666) (xy 337.692193 -254.714598) (xy 337.739464 -254.72829)
			(xy 337.783926 -254.749388) (xy 337.824429 -254.777344) (xy 337.859922 -254.811436) (xy 337.889487 -254.85078)
			(xy 337.912358 -254.894357) (xy 337.927942 -254.941038) (xy 337.935837 -254.989615) (xy 337.936332 -255.014222)
			(xy 338.254843 -255.014222) (xy 338.258938 -254.963494) (xy 338.271117 -254.91408) (xy 338.291065 -254.86726)
			(xy 338.318266 -254.824246) (xy 338.352014 -254.786152) (xy 338.391436 -254.753965) (xy 338.43551 -254.728519)
			(xy 338.483096 -254.710472) (xy 338.53296 -254.700292) (xy 338.583812 -254.698243) (xy 338.634333 -254.704377)
			(xy 338.683217 -254.718537) (xy 338.729196 -254.740354) (xy 338.77108 -254.769264) (xy 338.807784 -254.804519)
			(xy 338.838357 -254.845205) (xy 338.862008 -254.890268) (xy 338.878124 -254.938542) (xy 338.886288 -254.988776)
			(xy 338.8868 -255.014222) (xy 339.205328 -255.014222) (xy 339.209288 -254.965168) (xy 339.221065 -254.917384)
			(xy 339.240356 -254.872108) (xy 339.266659 -254.830512) (xy 339.299294 -254.793675) (xy 339.337415 -254.76255)
			(xy 339.380036 -254.737943) (xy 339.426052 -254.720491) (xy 339.474271 -254.710647) (xy 339.523446 -254.708666)
			(xy 339.572301 -254.714598) (xy 339.619572 -254.72829) (xy 339.664034 -254.749388) (xy 339.704537 -254.777344)
			(xy 339.74003 -254.811436) (xy 339.769595 -254.85078) (xy 339.792466 -254.894357) (xy 339.80805 -254.941038)
			(xy 339.815945 -254.989615) (xy 339.81644 -255.014222) (xy 340.134951 -255.014222) (xy 340.139046 -254.963494)
			(xy 340.151225 -254.91408) (xy 340.171173 -254.86726) (xy 340.198374 -254.824246) (xy 340.232122 -254.786152)
			(xy 340.271544 -254.753965) (xy 340.315618 -254.728519) (xy 340.363204 -254.710472) (xy 340.413068 -254.700292)
			(xy 340.46392 -254.698243) (xy 340.514441 -254.704377) (xy 340.563325 -254.718537) (xy 340.609304 -254.740354)
			(xy 340.651188 -254.769264) (xy 340.687892 -254.804519) (xy 340.718465 -254.845205) (xy 340.742116 -254.890268)
			(xy 340.758232 -254.938542) (xy 340.766396 -254.988776) (xy 340.766908 -255.014222) (xy 341.085182 -255.014222)
			(xy 341.089142 -254.965168) (xy 341.100919 -254.917384) (xy 341.12021 -254.872108) (xy 341.146513 -254.830512)
			(xy 341.179148 -254.793675) (xy 341.217269 -254.76255) (xy 341.25989 -254.737943) (xy 341.305906 -254.720491)
			(xy 341.354125 -254.710647) (xy 341.4033 -254.708666) (xy 341.452155 -254.714598) (xy 341.499426 -254.72829)
			(xy 341.543888 -254.749388) (xy 341.584391 -254.777344) (xy 341.619884 -254.811436) (xy 341.649449 -254.85078)
			(xy 341.67232 -254.894357) (xy 341.687904 -254.941038) (xy 341.695799 -254.989615) (xy 341.696294 -255.014222)
			(xy 342.014805 -255.014222) (xy 342.0189 -254.963494) (xy 342.031079 -254.91408) (xy 342.051027 -254.86726)
			(xy 342.078228 -254.824246) (xy 342.111976 -254.786152) (xy 342.151398 -254.753965) (xy 342.195472 -254.728519)
			(xy 342.243058 -254.710472) (xy 342.292922 -254.700292) (xy 342.343774 -254.698243) (xy 342.394295 -254.704377)
			(xy 342.443179 -254.718537) (xy 342.489158 -254.740354) (xy 342.531042 -254.769264) (xy 342.567746 -254.804519)
			(xy 342.598319 -254.845205) (xy 342.62197 -254.890268) (xy 342.638086 -254.938542) (xy 342.64625 -254.988776)
			(xy 342.646762 -255.014222) (xy 342.954859 -255.014222) (xy 342.958954 -254.963494) (xy 342.971133 -254.91408)
			(xy 342.991081 -254.86726) (xy 343.018282 -254.824246) (xy 343.05203 -254.786152) (xy 343.091452 -254.753965)
			(xy 343.135526 -254.728519) (xy 343.183112 -254.710472) (xy 343.232976 -254.700292) (xy 343.283828 -254.698243)
			(xy 343.334349 -254.704377) (xy 343.383233 -254.718537) (xy 343.429212 -254.740354) (xy 343.471096 -254.769264)
			(xy 343.5078 -254.804519) (xy 343.538373 -254.845205) (xy 343.562024 -254.890268) (xy 343.57814 -254.938542)
			(xy 343.586304 -254.988776) (xy 343.586816 -255.014222) (xy 343.905344 -255.014222) (xy 343.909304 -254.965168)
			(xy 343.921081 -254.917384) (xy 343.940372 -254.872108) (xy 343.966675 -254.830512) (xy 343.99931 -254.793675)
			(xy 344.037431 -254.76255) (xy 344.080052 -254.737943) (xy 344.126068 -254.720491) (xy 344.174287 -254.710647)
			(xy 344.223462 -254.708666) (xy 344.272317 -254.714598) (xy 344.319588 -254.72829) (xy 344.36405 -254.749388)
			(xy 344.404553 -254.777344) (xy 344.440046 -254.811436) (xy 344.469611 -254.85078) (xy 344.492482 -254.894357)
			(xy 344.508066 -254.941038) (xy 344.515961 -254.989615) (xy 344.516456 -255.014222) (xy 344.515961 -255.038829)
			(xy 344.508066 -255.087406) (xy 344.492482 -255.134087) (xy 344.469611 -255.177664) (xy 344.440046 -255.217008)
			(xy 344.404553 -255.2511) (xy 344.36405 -255.279056) (xy 344.319588 -255.300154) (xy 344.272317 -255.313846)
			(xy 344.223462 -255.319778) (xy 344.174287 -255.317797) (xy 344.126068 -255.307953) (xy 344.080052 -255.290501)
			(xy 344.037431 -255.265894) (xy 343.99931 -255.234769) (xy 343.966675 -255.197932) (xy 343.940372 -255.156336)
			(xy 343.921081 -255.11106) (xy 343.909304 -255.063276) (xy 343.905344 -255.014222) (xy 343.586816 -255.014222)
			(xy 343.586304 -255.039668) (xy 343.57814 -255.089902) (xy 343.562024 -255.138176) (xy 343.538373 -255.183239)
			(xy 343.5078 -255.223925) (xy 343.471096 -255.25918) (xy 343.429212 -255.28809) (xy 343.383233 -255.309907)
			(xy 343.334349 -255.324067) (xy 343.283828 -255.330201) (xy 343.232976 -255.328152) (xy 343.183112 -255.317972)
			(xy 343.135526 -255.299925) (xy 343.091452 -255.274479) (xy 343.05203 -255.242292) (xy 343.018282 -255.204198)
			(xy 342.991081 -255.161184) (xy 342.971133 -255.114364) (xy 342.958954 -255.06495) (xy 342.954859 -255.014222)
			(xy 342.646762 -255.014222) (xy 342.64625 -255.039668) (xy 342.638086 -255.089902) (xy 342.62197 -255.138176)
			(xy 342.598319 -255.183239) (xy 342.567746 -255.223925) (xy 342.531042 -255.25918) (xy 342.489158 -255.28809)
			(xy 342.443179 -255.309907) (xy 342.394295 -255.324067) (xy 342.343774 -255.330201) (xy 342.292922 -255.328152)
			(xy 342.243058 -255.317972) (xy 342.195472 -255.299925) (xy 342.151398 -255.274479) (xy 342.111976 -255.242292)
			(xy 342.078228 -255.204198) (xy 342.051027 -255.161184) (xy 342.031079 -255.114364) (xy 342.0189 -255.06495)
			(xy 342.014805 -255.014222) (xy 341.696294 -255.014222) (xy 341.695799 -255.038829) (xy 341.687904 -255.087406)
			(xy 341.67232 -255.134087) (xy 341.649449 -255.177664) (xy 341.619884 -255.217008) (xy 341.584391 -255.2511)
			(xy 341.543888 -255.279056) (xy 341.499426 -255.300154) (xy 341.452155 -255.313846) (xy 341.4033 -255.319778)
			(xy 341.354125 -255.317797) (xy 341.305906 -255.307953) (xy 341.25989 -255.290501) (xy 341.217269 -255.265894)
			(xy 341.179148 -255.234769) (xy 341.146513 -255.197932) (xy 341.12021 -255.156336) (xy 341.100919 -255.11106)
			(xy 341.089142 -255.063276) (xy 341.085182 -255.014222) (xy 340.766908 -255.014222) (xy 340.766396 -255.039668)
			(xy 340.758232 -255.089902) (xy 340.742116 -255.138176) (xy 340.718465 -255.183239) (xy 340.687892 -255.223925)
			(xy 340.651188 -255.25918) (xy 340.609304 -255.28809) (xy 340.563325 -255.309907) (xy 340.514441 -255.324067)
			(xy 340.46392 -255.330201) (xy 340.413068 -255.328152) (xy 340.363204 -255.317972) (xy 340.315618 -255.299925)
			(xy 340.271544 -255.274479) (xy 340.232122 -255.242292) (xy 340.198374 -255.204198) (xy 340.171173 -255.161184)
			(xy 340.151225 -255.114364) (xy 340.139046 -255.06495) (xy 340.134951 -255.014222) (xy 339.81644 -255.014222)
			(xy 339.815945 -255.038829) (xy 339.80805 -255.087406) (xy 339.792466 -255.134087) (xy 339.769595 -255.177664)
			(xy 339.74003 -255.217008) (xy 339.704537 -255.2511) (xy 339.664034 -255.279056) (xy 339.619572 -255.300154)
			(xy 339.572301 -255.313846) (xy 339.523446 -255.319778) (xy 339.474271 -255.317797) (xy 339.426052 -255.307953)
			(xy 339.380036 -255.290501) (xy 339.337415 -255.265894) (xy 339.299294 -255.234769) (xy 339.266659 -255.197932)
			(xy 339.240356 -255.156336) (xy 339.221065 -255.11106) (xy 339.209288 -255.063276) (xy 339.205328 -255.014222)
			(xy 338.8868 -255.014222) (xy 338.886288 -255.039668) (xy 338.878124 -255.089902) (xy 338.862008 -255.138176)
			(xy 338.838357 -255.183239) (xy 338.807784 -255.223925) (xy 338.77108 -255.25918) (xy 338.729196 -255.28809)
			(xy 338.683217 -255.309907) (xy 338.634333 -255.324067) (xy 338.583812 -255.330201) (xy 338.53296 -255.328152)
			(xy 338.483096 -255.317972) (xy 338.43551 -255.299925) (xy 338.391436 -255.274479) (xy 338.352014 -255.242292)
			(xy 338.318266 -255.204198) (xy 338.291065 -255.161184) (xy 338.271117 -255.114364) (xy 338.258938 -255.06495)
			(xy 338.254843 -255.014222) (xy 337.936332 -255.014222) (xy 337.935837 -255.038829) (xy 337.927942 -255.087406)
			(xy 337.912358 -255.134087) (xy 337.889487 -255.177664) (xy 337.859922 -255.217008) (xy 337.824429 -255.2511)
			(xy 337.783926 -255.279056) (xy 337.739464 -255.300154) (xy 337.692193 -255.313846) (xy 337.643338 -255.319778)
			(xy 337.594163 -255.317797) (xy 337.545944 -255.307953) (xy 337.499928 -255.290501) (xy 337.457307 -255.265894)
			(xy 337.419186 -255.234769) (xy 337.386551 -255.197932) (xy 337.360248 -255.156336) (xy 337.340957 -255.11106)
			(xy 337.32918 -255.063276) (xy 337.32522 -255.014222) (xy 337.006946 -255.014222) (xy 337.006434 -255.039668)
			(xy 336.99827 -255.089902) (xy 336.982154 -255.138176) (xy 336.958503 -255.183239) (xy 336.92793 -255.223925)
			(xy 336.891226 -255.25918) (xy 336.849342 -255.28809) (xy 336.803363 -255.309907) (xy 336.754479 -255.324067)
			(xy 336.703958 -255.330201) (xy 336.653106 -255.328152) (xy 336.603242 -255.317972) (xy 336.555656 -255.299925)
			(xy 336.511582 -255.274479) (xy 336.47216 -255.242292) (xy 336.438412 -255.204198) (xy 336.411211 -255.161184)
			(xy 336.391263 -255.114364) (xy 336.379084 -255.06495) (xy 336.374989 -255.014222) (xy 336.066892 -255.014222)
			(xy 336.06638 -255.039668) (xy 336.058216 -255.089902) (xy 336.0421 -255.138176) (xy 336.018449 -255.183239)
			(xy 335.987876 -255.223925) (xy 335.951172 -255.25918) (xy 335.909288 -255.28809) (xy 335.863309 -255.309907)
			(xy 335.814425 -255.324067) (xy 335.763904 -255.330201) (xy 335.713052 -255.328152) (xy 335.663188 -255.317972)
			(xy 335.615602 -255.299925) (xy 335.571528 -255.274479) (xy 335.532106 -255.242292) (xy 335.498358 -255.204198)
			(xy 335.471157 -255.161184) (xy 335.451209 -255.114364) (xy 335.43903 -255.06495) (xy 335.434935 -255.014222)
			(xy 335.116424 -255.014222) (xy 335.115929 -255.038829) (xy 335.108034 -255.087406) (xy 335.09245 -255.134087)
			(xy 335.069579 -255.177664) (xy 335.040014 -255.217008) (xy 335.004521 -255.2511) (xy 334.964018 -255.279056)
			(xy 334.919556 -255.300154) (xy 334.872285 -255.313846) (xy 334.82343 -255.319778) (xy 334.774255 -255.317797)
			(xy 334.726036 -255.307953) (xy 334.68002 -255.290501) (xy 334.637399 -255.265894) (xy 334.599278 -255.234769)
			(xy 334.566643 -255.197932) (xy 334.54034 -255.156336) (xy 334.521049 -255.11106) (xy 334.509272 -255.063276)
			(xy 334.505312 -255.014222) (xy 334.186784 -255.014222) (xy 334.186272 -255.039668) (xy 334.178108 -255.089902)
			(xy 334.161992 -255.138176) (xy 334.138341 -255.183239) (xy 334.107768 -255.223925) (xy 334.071064 -255.25918)
			(xy 334.02918 -255.28809) (xy 333.983201 -255.309907) (xy 333.934317 -255.324067) (xy 333.883796 -255.330201)
			(xy 333.832944 -255.328152) (xy 333.78308 -255.317972) (xy 333.735494 -255.299925) (xy 333.69142 -255.274479)
			(xy 333.651998 -255.242292) (xy 333.61825 -255.204198) (xy 333.591049 -255.161184) (xy 333.571101 -255.114364)
			(xy 333.558922 -255.06495) (xy 333.554827 -255.014222) (xy 333.236316 -255.014222) (xy 333.235821 -255.038829)
			(xy 333.227926 -255.087406) (xy 333.212342 -255.134087) (xy 333.189471 -255.177664) (xy 333.159906 -255.217008)
			(xy 333.124413 -255.2511) (xy 333.08391 -255.279056) (xy 333.039448 -255.300154) (xy 332.992177 -255.313846)
			(xy 332.943322 -255.319778) (xy 332.894147 -255.317797) (xy 332.845928 -255.307953) (xy 332.799912 -255.290501)
			(xy 332.757291 -255.265894) (xy 332.71917 -255.234769) (xy 332.686535 -255.197932) (xy 332.660232 -255.156336)
			(xy 332.640941 -255.11106) (xy 332.629164 -255.063276) (xy 332.625204 -255.014222) (xy 332.30693 -255.014222)
			(xy 332.306418 -255.039668) (xy 332.298254 -255.089902) (xy 332.282138 -255.138176) (xy 332.258487 -255.183239)
			(xy 332.227914 -255.223925) (xy 332.19121 -255.25918) (xy 332.149326 -255.28809) (xy 332.103347 -255.309907)
			(xy 332.054463 -255.324067) (xy 332.003942 -255.330201) (xy 331.95309 -255.328152) (xy 331.903226 -255.317972)
			(xy 331.85564 -255.299925) (xy 331.811566 -255.274479) (xy 331.772144 -255.242292) (xy 331.738396 -255.204198)
			(xy 331.711195 -255.161184) (xy 331.691247 -255.114364) (xy 331.679068 -255.06495) (xy 331.674973 -255.014222)
			(xy 331.356462 -255.014222) (xy 331.355967 -255.038829) (xy 331.348072 -255.087406) (xy 331.332488 -255.134087)
			(xy 331.309617 -255.177664) (xy 331.280052 -255.217008) (xy 331.244559 -255.2511) (xy 331.204056 -255.279056)
			(xy 331.159594 -255.300154) (xy 331.112323 -255.313846) (xy 331.063468 -255.319778) (xy 331.014293 -255.317797)
			(xy 330.966074 -255.307953) (xy 330.920058 -255.290501) (xy 330.877437 -255.265894) (xy 330.839316 -255.234769)
			(xy 330.806681 -255.197932) (xy 330.780378 -255.156336) (xy 330.761087 -255.11106) (xy 330.74931 -255.063276)
			(xy 330.74535 -255.014222) (xy 330.426822 -255.014222) (xy 330.42631 -255.039668) (xy 330.418146 -255.089902)
			(xy 330.40203 -255.138176) (xy 330.378379 -255.183239) (xy 330.347806 -255.223925) (xy 330.311102 -255.25918)
			(xy 330.269218 -255.28809) (xy 330.223239 -255.309907) (xy 330.174355 -255.324067) (xy 330.123834 -255.330201)
			(xy 330.072982 -255.328152) (xy 330.023118 -255.317972) (xy 329.975532 -255.299925) (xy 329.931458 -255.274479)
			(xy 329.892036 -255.242292) (xy 329.858288 -255.204198) (xy 329.831087 -255.161184) (xy 329.811139 -255.114364)
			(xy 329.79896 -255.06495) (xy 329.794865 -255.014222) (xy 329.486768 -255.014222) (xy 329.486256 -255.039668)
			(xy 329.478092 -255.089902) (xy 329.461976 -255.138176) (xy 329.438325 -255.183239) (xy 329.407752 -255.223925)
			(xy 329.371048 -255.25918) (xy 329.329164 -255.28809) (xy 329.283185 -255.309907) (xy 329.234301 -255.324067)
			(xy 329.18378 -255.330201) (xy 329.132928 -255.328152) (xy 329.083064 -255.317972) (xy 329.035478 -255.299925)
			(xy 328.991404 -255.274479) (xy 328.951982 -255.242292) (xy 328.918234 -255.204198) (xy 328.891033 -255.161184)
			(xy 328.871085 -255.114364) (xy 328.858906 -255.06495) (xy 328.854811 -255.014222) (xy 328.536554 -255.014222)
			(xy 328.536059 -255.038829) (xy 328.528164 -255.087406) (xy 328.51258 -255.134087) (xy 328.489709 -255.177664)
			(xy 328.460144 -255.217008) (xy 328.424651 -255.2511) (xy 328.384148 -255.279056) (xy 328.339686 -255.300154)
			(xy 328.292415 -255.313846) (xy 328.24356 -255.319778) (xy 328.194385 -255.317797) (xy 328.146166 -255.307953)
			(xy 328.10015 -255.290501) (xy 328.057529 -255.265894) (xy 328.019408 -255.234769) (xy 327.986773 -255.197932)
			(xy 327.96047 -255.156336) (xy 327.941179 -255.11106) (xy 327.929402 -255.063276) (xy 327.925442 -255.014222)
			(xy 326.656446 -255.014222) (xy 326.655951 -255.038829) (xy 326.648056 -255.087406) (xy 326.632472 -255.134087)
			(xy 326.609601 -255.177664) (xy 326.580036 -255.217008) (xy 326.544543 -255.2511) (xy 326.50404 -255.279056)
			(xy 326.459578 -255.300154) (xy 326.412307 -255.313846) (xy 326.363452 -255.319778) (xy 326.314277 -255.317797)
			(xy 326.266058 -255.307953) (xy 326.220042 -255.290501) (xy 326.177421 -255.265894) (xy 326.1393 -255.234769)
			(xy 326.106665 -255.197932) (xy 326.080362 -255.156336) (xy 326.061071 -255.11106) (xy 326.049294 -255.063276)
			(xy 326.045334 -255.014222) (xy 310.45912 -255.014222) (xy 310.45912 -256.090166) (xy 324.447166 -256.090166)
			(xy 324.451126 -256.041112) (xy 324.462903 -255.993328) (xy 324.482194 -255.948052) (xy 324.508497 -255.906456)
			(xy 324.541132 -255.869619) (xy 324.579253 -255.838494) (xy 324.621874 -255.813887) (xy 324.66789 -255.796435)
			(xy 324.716109 -255.786591) (xy 324.765284 -255.78461) (xy 324.814139 -255.790542) (xy 324.86141 -255.804234)
			(xy 324.903545 -255.824228) (xy 327.455288 -255.824228) (xy 327.459248 -255.775174) (xy 327.471025 -255.72739)
			(xy 327.490316 -255.682114) (xy 327.516619 -255.640518) (xy 327.549254 -255.603681) (xy 327.587375 -255.572556)
			(xy 327.629996 -255.547949) (xy 327.676012 -255.530497) (xy 327.724231 -255.520653) (xy 327.773406 -255.518672)
			(xy 327.822261 -255.524604) (xy 327.869532 -255.538296) (xy 327.913994 -255.559394) (xy 327.954497 -255.58735)
			(xy 327.98999 -255.621442) (xy 328.019555 -255.660786) (xy 328.042426 -255.704363) (xy 328.05801 -255.751044)
			(xy 328.065905 -255.799621) (xy 328.0664 -255.824228) (xy 328.384911 -255.824228) (xy 328.389006 -255.7735)
			(xy 328.401185 -255.724086) (xy 328.421133 -255.677266) (xy 328.448334 -255.634252) (xy 328.482082 -255.596158)
			(xy 328.521504 -255.563971) (xy 328.565578 -255.538525) (xy 328.613164 -255.520478) (xy 328.663028 -255.510298)
			(xy 328.71388 -255.508249) (xy 328.764401 -255.514383) (xy 328.813285 -255.528543) (xy 328.859264 -255.55036)
			(xy 328.901148 -255.57927) (xy 328.937852 -255.614525) (xy 328.968425 -255.655211) (xy 328.992076 -255.700274)
			(xy 329.008192 -255.748548) (xy 329.016356 -255.798782) (xy 329.016868 -255.824228) (xy 329.335396 -255.824228)
			(xy 329.339356 -255.775174) (xy 329.351133 -255.72739) (xy 329.370424 -255.682114) (xy 329.396727 -255.640518)
			(xy 329.429362 -255.603681) (xy 329.467483 -255.572556) (xy 329.510104 -255.547949) (xy 329.55612 -255.530497)
			(xy 329.604339 -255.520653) (xy 329.653514 -255.518672) (xy 329.702369 -255.524604) (xy 329.74964 -255.538296)
			(xy 329.794102 -255.559394) (xy 329.834605 -255.58735) (xy 329.870098 -255.621442) (xy 329.899663 -255.660786)
			(xy 329.922534 -255.704363) (xy 329.938118 -255.751044) (xy 329.946013 -255.799621) (xy 329.946508 -255.824228)
			(xy 330.264765 -255.824228) (xy 330.26886 -255.7735) (xy 330.281039 -255.724086) (xy 330.300987 -255.677266)
			(xy 330.328188 -255.634252) (xy 330.361936 -255.596158) (xy 330.401358 -255.563971) (xy 330.445432 -255.538525)
			(xy 330.493018 -255.520478) (xy 330.542882 -255.510298) (xy 330.593734 -255.508249) (xy 330.644255 -255.514383)
			(xy 330.693139 -255.528543) (xy 330.739118 -255.55036) (xy 330.781002 -255.57927) (xy 330.817706 -255.614525)
			(xy 330.848279 -255.655211) (xy 330.87193 -255.700274) (xy 330.888046 -255.748548) (xy 330.89621 -255.798782)
			(xy 330.896722 -255.824228) (xy 331.21525 -255.824228) (xy 331.21921 -255.775174) (xy 331.230987 -255.72739)
			(xy 331.250278 -255.682114) (xy 331.276581 -255.640518) (xy 331.309216 -255.603681) (xy 331.347337 -255.572556)
			(xy 331.389958 -255.547949) (xy 331.435974 -255.530497) (xy 331.484193 -255.520653) (xy 331.533368 -255.518672)
			(xy 331.582223 -255.524604) (xy 331.629494 -255.538296) (xy 331.673956 -255.559394) (xy 331.714459 -255.58735)
			(xy 331.749952 -255.621442) (xy 331.779517 -255.660786) (xy 331.802388 -255.704363) (xy 331.817972 -255.751044)
			(xy 331.825867 -255.799621) (xy 331.826362 -255.824228) (xy 332.144873 -255.824228) (xy 332.148968 -255.7735)
			(xy 332.161147 -255.724086) (xy 332.181095 -255.677266) (xy 332.208296 -255.634252) (xy 332.242044 -255.596158)
			(xy 332.281466 -255.563971) (xy 332.32554 -255.538525) (xy 332.373126 -255.520478) (xy 332.42299 -255.510298)
			(xy 332.473842 -255.508249) (xy 332.524363 -255.514383) (xy 332.573247 -255.528543) (xy 332.619226 -255.55036)
			(xy 332.66111 -255.57927) (xy 332.697814 -255.614525) (xy 332.728387 -255.655211) (xy 332.752038 -255.700274)
			(xy 332.768154 -255.748548) (xy 332.776318 -255.798782) (xy 332.77683 -255.824228) (xy 333.084927 -255.824228)
			(xy 333.089022 -255.7735) (xy 333.101201 -255.724086) (xy 333.121149 -255.677266) (xy 333.14835 -255.634252)
			(xy 333.182098 -255.596158) (xy 333.22152 -255.563971) (xy 333.265594 -255.538525) (xy 333.31318 -255.520478)
			(xy 333.363044 -255.510298) (xy 333.413896 -255.508249) (xy 333.464417 -255.514383) (xy 333.513301 -255.528543)
			(xy 333.55928 -255.55036) (xy 333.601164 -255.57927) (xy 333.637868 -255.614525) (xy 333.668441 -255.655211)
			(xy 333.692092 -255.700274) (xy 333.708208 -255.748548) (xy 333.716372 -255.798782) (xy 333.716884 -255.824228)
			(xy 334.035412 -255.824228) (xy 334.039372 -255.775174) (xy 334.051149 -255.72739) (xy 334.07044 -255.682114)
			(xy 334.096743 -255.640518) (xy 334.129378 -255.603681) (xy 334.167499 -255.572556) (xy 334.21012 -255.547949)
			(xy 334.256136 -255.530497) (xy 334.304355 -255.520653) (xy 334.35353 -255.518672) (xy 334.402385 -255.524604)
			(xy 334.449656 -255.538296) (xy 334.494118 -255.559394) (xy 334.534621 -255.58735) (xy 334.570114 -255.621442)
			(xy 334.599679 -255.660786) (xy 334.62255 -255.704363) (xy 334.638134 -255.751044) (xy 334.646029 -255.799621)
			(xy 334.646524 -255.824228) (xy 334.964781 -255.824228) (xy 334.968876 -255.7735) (xy 334.981055 -255.724086)
			(xy 335.001003 -255.677266) (xy 335.028204 -255.634252) (xy 335.061952 -255.596158) (xy 335.101374 -255.563971)
			(xy 335.145448 -255.538525) (xy 335.193034 -255.520478) (xy 335.242898 -255.510298) (xy 335.29375 -255.508249)
			(xy 335.344271 -255.514383) (xy 335.393155 -255.528543) (xy 335.439134 -255.55036) (xy 335.481018 -255.57927)
			(xy 335.517722 -255.614525) (xy 335.548295 -255.655211) (xy 335.571946 -255.700274) (xy 335.588062 -255.748548)
			(xy 335.596226 -255.798782) (xy 335.596738 -255.824228) (xy 335.915266 -255.824228) (xy 335.919226 -255.775174)
			(xy 335.931003 -255.72739) (xy 335.950294 -255.682114) (xy 335.976597 -255.640518) (xy 336.009232 -255.603681)
			(xy 336.047353 -255.572556) (xy 336.089974 -255.547949) (xy 336.13599 -255.530497) (xy 336.184209 -255.520653)
			(xy 336.233384 -255.518672) (xy 336.282239 -255.524604) (xy 336.32951 -255.538296) (xy 336.373972 -255.559394)
			(xy 336.414475 -255.58735) (xy 336.449968 -255.621442) (xy 336.479533 -255.660786) (xy 336.502404 -255.704363)
			(xy 336.517988 -255.751044) (xy 336.525883 -255.799621) (xy 336.526378 -255.824228) (xy 336.844889 -255.824228)
			(xy 336.848984 -255.7735) (xy 336.861163 -255.724086) (xy 336.881111 -255.677266) (xy 336.908312 -255.634252)
			(xy 336.94206 -255.596158) (xy 336.981482 -255.563971) (xy 337.025556 -255.538525) (xy 337.073142 -255.520478)
			(xy 337.123006 -255.510298) (xy 337.173858 -255.508249) (xy 337.224379 -255.514383) (xy 337.273263 -255.528543)
			(xy 337.319242 -255.55036) (xy 337.361126 -255.57927) (xy 337.39783 -255.614525) (xy 337.428403 -255.655211)
			(xy 337.452054 -255.700274) (xy 337.46817 -255.748548) (xy 337.476334 -255.798782) (xy 337.476846 -255.824228)
			(xy 337.795374 -255.824228) (xy 337.799334 -255.775174) (xy 337.811111 -255.72739) (xy 337.830402 -255.682114)
			(xy 337.856705 -255.640518) (xy 337.88934 -255.603681) (xy 337.927461 -255.572556) (xy 337.970082 -255.547949)
			(xy 338.016098 -255.530497) (xy 338.064317 -255.520653) (xy 338.113492 -255.518672) (xy 338.162347 -255.524604)
			(xy 338.209618 -255.538296) (xy 338.25408 -255.559394) (xy 338.294583 -255.58735) (xy 338.330076 -255.621442)
			(xy 338.359641 -255.660786) (xy 338.382512 -255.704363) (xy 338.398096 -255.751044) (xy 338.405991 -255.799621)
			(xy 338.406486 -255.824228) (xy 338.724743 -255.824228) (xy 338.728838 -255.7735) (xy 338.741017 -255.724086)
			(xy 338.760965 -255.677266) (xy 338.788166 -255.634252) (xy 338.821914 -255.596158) (xy 338.861336 -255.563971)
			(xy 338.90541 -255.538525) (xy 338.952996 -255.520478) (xy 339.00286 -255.510298) (xy 339.053712 -255.508249)
			(xy 339.104233 -255.514383) (xy 339.153117 -255.528543) (xy 339.199096 -255.55036) (xy 339.24098 -255.57927)
			(xy 339.277684 -255.614525) (xy 339.308257 -255.655211) (xy 339.331908 -255.700274) (xy 339.348024 -255.748548)
			(xy 339.356188 -255.798782) (xy 339.3567 -255.824228) (xy 339.664797 -255.824228) (xy 339.668892 -255.7735)
			(xy 339.681071 -255.724086) (xy 339.701019 -255.677266) (xy 339.72822 -255.634252) (xy 339.761968 -255.596158)
			(xy 339.80139 -255.563971) (xy 339.845464 -255.538525) (xy 339.89305 -255.520478) (xy 339.942914 -255.510298)
			(xy 339.993766 -255.508249) (xy 340.044287 -255.514383) (xy 340.093171 -255.528543) (xy 340.13915 -255.55036)
			(xy 340.181034 -255.57927) (xy 340.217738 -255.614525) (xy 340.248311 -255.655211) (xy 340.271962 -255.700274)
			(xy 340.288078 -255.748548) (xy 340.296242 -255.798782) (xy 340.296754 -255.824228) (xy 340.615282 -255.824228)
			(xy 340.619242 -255.775174) (xy 340.631019 -255.72739) (xy 340.65031 -255.682114) (xy 340.676613 -255.640518)
			(xy 340.709248 -255.603681) (xy 340.747369 -255.572556) (xy 340.78999 -255.547949) (xy 340.836006 -255.530497)
			(xy 340.884225 -255.520653) (xy 340.9334 -255.518672) (xy 340.982255 -255.524604) (xy 341.029526 -255.538296)
			(xy 341.073988 -255.559394) (xy 341.114491 -255.58735) (xy 341.149984 -255.621442) (xy 341.179549 -255.660786)
			(xy 341.20242 -255.704363) (xy 341.218004 -255.751044) (xy 341.225899 -255.799621) (xy 341.226394 -255.824228)
			(xy 341.544905 -255.824228) (xy 341.549 -255.7735) (xy 341.561179 -255.724086) (xy 341.581127 -255.677266)
			(xy 341.608328 -255.634252) (xy 341.642076 -255.596158) (xy 341.681498 -255.563971) (xy 341.725572 -255.538525)
			(xy 341.773158 -255.520478) (xy 341.823022 -255.510298) (xy 341.873874 -255.508249) (xy 341.924395 -255.514383)
			(xy 341.973279 -255.528543) (xy 342.019258 -255.55036) (xy 342.061142 -255.57927) (xy 342.097846 -255.614525)
			(xy 342.128419 -255.655211) (xy 342.15207 -255.700274) (xy 342.168186 -255.748548) (xy 342.17635 -255.798782)
			(xy 342.176862 -255.824228) (xy 342.49539 -255.824228) (xy 342.49935 -255.775174) (xy 342.511127 -255.72739)
			(xy 342.530418 -255.682114) (xy 342.556721 -255.640518) (xy 342.589356 -255.603681) (xy 342.627477 -255.572556)
			(xy 342.670098 -255.547949) (xy 342.716114 -255.530497) (xy 342.764333 -255.520653) (xy 342.813508 -255.518672)
			(xy 342.862363 -255.524604) (xy 342.909634 -255.538296) (xy 342.954096 -255.559394) (xy 342.994599 -255.58735)
			(xy 343.030092 -255.621442) (xy 343.059657 -255.660786) (xy 343.082528 -255.704363) (xy 343.098112 -255.751044)
			(xy 343.106007 -255.799621) (xy 343.106502 -255.824228) (xy 343.424759 -255.824228) (xy 343.428854 -255.7735)
			(xy 343.441033 -255.724086) (xy 343.460981 -255.677266) (xy 343.488182 -255.634252) (xy 343.52193 -255.596158)
			(xy 343.561352 -255.563971) (xy 343.605426 -255.538525) (xy 343.653012 -255.520478) (xy 343.702876 -255.510298)
			(xy 343.753728 -255.508249) (xy 343.804249 -255.514383) (xy 343.853133 -255.528543) (xy 343.899112 -255.55036)
			(xy 343.940996 -255.57927) (xy 343.9777 -255.614525) (xy 344.008273 -255.655211) (xy 344.031924 -255.700274)
			(xy 344.04804 -255.748548) (xy 344.056204 -255.798782) (xy 344.056716 -255.824228) (xy 344.375244 -255.824228)
			(xy 344.379204 -255.775174) (xy 344.390981 -255.72739) (xy 344.410272 -255.682114) (xy 344.436575 -255.640518)
			(xy 344.46921 -255.603681) (xy 344.507331 -255.572556) (xy 344.549952 -255.547949) (xy 344.595968 -255.530497)
			(xy 344.644187 -255.520653) (xy 344.693362 -255.518672) (xy 344.742217 -255.524604) (xy 344.789488 -255.538296)
			(xy 344.83395 -255.559394) (xy 344.874453 -255.58735) (xy 344.909946 -255.621442) (xy 344.939511 -255.660786)
			(xy 344.962382 -255.704363) (xy 344.977966 -255.751044) (xy 344.985861 -255.799621) (xy 344.986356 -255.824228)
			(xy 344.985861 -255.848835) (xy 344.977966 -255.897412) (xy 344.962382 -255.944093) (xy 344.939511 -255.98767)
			(xy 344.909946 -256.027014) (xy 344.874453 -256.061106) (xy 344.83395 -256.089062) (xy 344.789488 -256.11016)
			(xy 344.742217 -256.123852) (xy 344.693362 -256.129784) (xy 344.644187 -256.127803) (xy 344.595968 -256.117959)
			(xy 344.549952 -256.100507) (xy 344.507331 -256.0759) (xy 344.46921 -256.044775) (xy 344.436575 -256.007938)
			(xy 344.410272 -255.966342) (xy 344.390981 -255.921066) (xy 344.379204 -255.873282) (xy 344.375244 -255.824228)
			(xy 344.056716 -255.824228) (xy 344.056204 -255.849674) (xy 344.04804 -255.899908) (xy 344.031924 -255.948182)
			(xy 344.008273 -255.993245) (xy 343.9777 -256.033931) (xy 343.940996 -256.069186) (xy 343.899112 -256.098096)
			(xy 343.853133 -256.119913) (xy 343.804249 -256.134073) (xy 343.753728 -256.140207) (xy 343.702876 -256.138158)
			(xy 343.653012 -256.127978) (xy 343.605426 -256.109931) (xy 343.561352 -256.084485) (xy 343.52193 -256.052298)
			(xy 343.488182 -256.014204) (xy 343.460981 -255.97119) (xy 343.441033 -255.92437) (xy 343.428854 -255.874956)
			(xy 343.424759 -255.824228) (xy 343.106502 -255.824228) (xy 343.106007 -255.848835) (xy 343.098112 -255.897412)
			(xy 343.082528 -255.944093) (xy 343.059657 -255.98767) (xy 343.030092 -256.027014) (xy 342.994599 -256.061106)
			(xy 342.954096 -256.089062) (xy 342.909634 -256.11016) (xy 342.862363 -256.123852) (xy 342.813508 -256.129784)
			(xy 342.764333 -256.127803) (xy 342.716114 -256.117959) (xy 342.670098 -256.100507) (xy 342.627477 -256.0759)
			(xy 342.589356 -256.044775) (xy 342.556721 -256.007938) (xy 342.530418 -255.966342) (xy 342.511127 -255.921066)
			(xy 342.49935 -255.873282) (xy 342.49539 -255.824228) (xy 342.176862 -255.824228) (xy 342.17635 -255.849674)
			(xy 342.168186 -255.899908) (xy 342.15207 -255.948182) (xy 342.128419 -255.993245) (xy 342.097846 -256.033931)
			(xy 342.061142 -256.069186) (xy 342.019258 -256.098096) (xy 341.973279 -256.119913) (xy 341.924395 -256.134073)
			(xy 341.873874 -256.140207) (xy 341.823022 -256.138158) (xy 341.773158 -256.127978) (xy 341.725572 -256.109931)
			(xy 341.681498 -256.084485) (xy 341.642076 -256.052298) (xy 341.608328 -256.014204) (xy 341.581127 -255.97119)
			(xy 341.561179 -255.92437) (xy 341.549 -255.874956) (xy 341.544905 -255.824228) (xy 341.226394 -255.824228)
			(xy 341.225899 -255.848835) (xy 341.218004 -255.897412) (xy 341.20242 -255.944093) (xy 341.179549 -255.98767)
			(xy 341.149984 -256.027014) (xy 341.114491 -256.061106) (xy 341.073988 -256.089062) (xy 341.029526 -256.11016)
			(xy 340.982255 -256.123852) (xy 340.9334 -256.129784) (xy 340.884225 -256.127803) (xy 340.836006 -256.117959)
			(xy 340.78999 -256.100507) (xy 340.747369 -256.0759) (xy 340.709248 -256.044775) (xy 340.676613 -256.007938)
			(xy 340.65031 -255.966342) (xy 340.631019 -255.921066) (xy 340.619242 -255.873282) (xy 340.615282 -255.824228)
			(xy 340.296754 -255.824228) (xy 340.296242 -255.849674) (xy 340.288078 -255.899908) (xy 340.271962 -255.948182)
			(xy 340.248311 -255.993245) (xy 340.217738 -256.033931) (xy 340.181034 -256.069186) (xy 340.13915 -256.098096)
			(xy 340.093171 -256.119913) (xy 340.044287 -256.134073) (xy 339.993766 -256.140207) (xy 339.942914 -256.138158)
			(xy 339.89305 -256.127978) (xy 339.845464 -256.109931) (xy 339.80139 -256.084485) (xy 339.761968 -256.052298)
			(xy 339.72822 -256.014204) (xy 339.701019 -255.97119) (xy 339.681071 -255.92437) (xy 339.668892 -255.874956)
			(xy 339.664797 -255.824228) (xy 339.3567 -255.824228) (xy 339.356188 -255.849674) (xy 339.348024 -255.899908)
			(xy 339.331908 -255.948182) (xy 339.308257 -255.993245) (xy 339.277684 -256.033931) (xy 339.24098 -256.069186)
			(xy 339.199096 -256.098096) (xy 339.153117 -256.119913) (xy 339.104233 -256.134073) (xy 339.053712 -256.140207)
			(xy 339.00286 -256.138158) (xy 338.952996 -256.127978) (xy 338.90541 -256.109931) (xy 338.861336 -256.084485)
			(xy 338.821914 -256.052298) (xy 338.788166 -256.014204) (xy 338.760965 -255.97119) (xy 338.741017 -255.92437)
			(xy 338.728838 -255.874956) (xy 338.724743 -255.824228) (xy 338.406486 -255.824228) (xy 338.405991 -255.848835)
			(xy 338.398096 -255.897412) (xy 338.382512 -255.944093) (xy 338.359641 -255.98767) (xy 338.330076 -256.027014)
			(xy 338.294583 -256.061106) (xy 338.25408 -256.089062) (xy 338.209618 -256.11016) (xy 338.162347 -256.123852)
			(xy 338.113492 -256.129784) (xy 338.064317 -256.127803) (xy 338.016098 -256.117959) (xy 337.970082 -256.100507)
			(xy 337.927461 -256.0759) (xy 337.88934 -256.044775) (xy 337.856705 -256.007938) (xy 337.830402 -255.966342)
			(xy 337.811111 -255.921066) (xy 337.799334 -255.873282) (xy 337.795374 -255.824228) (xy 337.476846 -255.824228)
			(xy 337.476334 -255.849674) (xy 337.46817 -255.899908) (xy 337.452054 -255.948182) (xy 337.428403 -255.993245)
			(xy 337.39783 -256.033931) (xy 337.361126 -256.069186) (xy 337.319242 -256.098096) (xy 337.273263 -256.119913)
			(xy 337.224379 -256.134073) (xy 337.173858 -256.140207) (xy 337.123006 -256.138158) (xy 337.073142 -256.127978)
			(xy 337.025556 -256.109931) (xy 336.981482 -256.084485) (xy 336.94206 -256.052298) (xy 336.908312 -256.014204)
			(xy 336.881111 -255.97119) (xy 336.861163 -255.92437) (xy 336.848984 -255.874956) (xy 336.844889 -255.824228)
			(xy 336.526378 -255.824228) (xy 336.525883 -255.848835) (xy 336.517988 -255.897412) (xy 336.502404 -255.944093)
			(xy 336.479533 -255.98767) (xy 336.449968 -256.027014) (xy 336.414475 -256.061106) (xy 336.373972 -256.089062)
			(xy 336.32951 -256.11016) (xy 336.282239 -256.123852) (xy 336.233384 -256.129784) (xy 336.184209 -256.127803)
			(xy 336.13599 -256.117959) (xy 336.089974 -256.100507) (xy 336.047353 -256.0759) (xy 336.009232 -256.044775)
			(xy 335.976597 -256.007938) (xy 335.950294 -255.966342) (xy 335.931003 -255.921066) (xy 335.919226 -255.873282)
			(xy 335.915266 -255.824228) (xy 335.596738 -255.824228) (xy 335.596226 -255.849674) (xy 335.588062 -255.899908)
			(xy 335.571946 -255.948182) (xy 335.548295 -255.993245) (xy 335.517722 -256.033931) (xy 335.481018 -256.069186)
			(xy 335.439134 -256.098096) (xy 335.393155 -256.119913) (xy 335.344271 -256.134073) (xy 335.29375 -256.140207)
			(xy 335.242898 -256.138158) (xy 335.193034 -256.127978) (xy 335.145448 -256.109931) (xy 335.101374 -256.084485)
			(xy 335.061952 -256.052298) (xy 335.028204 -256.014204) (xy 335.001003 -255.97119) (xy 334.981055 -255.92437)
			(xy 334.968876 -255.874956) (xy 334.964781 -255.824228) (xy 334.646524 -255.824228) (xy 334.646029 -255.848835)
			(xy 334.638134 -255.897412) (xy 334.62255 -255.944093) (xy 334.599679 -255.98767) (xy 334.570114 -256.027014)
			(xy 334.534621 -256.061106) (xy 334.494118 -256.089062) (xy 334.449656 -256.11016) (xy 334.402385 -256.123852)
			(xy 334.35353 -256.129784) (xy 334.304355 -256.127803) (xy 334.256136 -256.117959) (xy 334.21012 -256.100507)
			(xy 334.167499 -256.0759) (xy 334.129378 -256.044775) (xy 334.096743 -256.007938) (xy 334.07044 -255.966342)
			(xy 334.051149 -255.921066) (xy 334.039372 -255.873282) (xy 334.035412 -255.824228) (xy 333.716884 -255.824228)
			(xy 333.716372 -255.849674) (xy 333.708208 -255.899908) (xy 333.692092 -255.948182) (xy 333.668441 -255.993245)
			(xy 333.637868 -256.033931) (xy 333.601164 -256.069186) (xy 333.55928 -256.098096) (xy 333.513301 -256.119913)
			(xy 333.464417 -256.134073) (xy 333.413896 -256.140207) (xy 333.363044 -256.138158) (xy 333.31318 -256.127978)
			(xy 333.265594 -256.109931) (xy 333.22152 -256.084485) (xy 333.182098 -256.052298) (xy 333.14835 -256.014204)
			(xy 333.121149 -255.97119) (xy 333.101201 -255.92437) (xy 333.089022 -255.874956) (xy 333.084927 -255.824228)
			(xy 332.77683 -255.824228) (xy 332.776318 -255.849674) (xy 332.768154 -255.899908) (xy 332.752038 -255.948182)
			(xy 332.728387 -255.993245) (xy 332.697814 -256.033931) (xy 332.66111 -256.069186) (xy 332.619226 -256.098096)
			(xy 332.573247 -256.119913) (xy 332.524363 -256.134073) (xy 332.473842 -256.140207) (xy 332.42299 -256.138158)
			(xy 332.373126 -256.127978) (xy 332.32554 -256.109931) (xy 332.281466 -256.084485) (xy 332.242044 -256.052298)
			(xy 332.208296 -256.014204) (xy 332.181095 -255.97119) (xy 332.161147 -255.92437) (xy 332.148968 -255.874956)
			(xy 332.144873 -255.824228) (xy 331.826362 -255.824228) (xy 331.825867 -255.848835) (xy 331.817972 -255.897412)
			(xy 331.802388 -255.944093) (xy 331.779517 -255.98767) (xy 331.749952 -256.027014) (xy 331.714459 -256.061106)
			(xy 331.673956 -256.089062) (xy 331.629494 -256.11016) (xy 331.582223 -256.123852) (xy 331.533368 -256.129784)
			(xy 331.484193 -256.127803) (xy 331.435974 -256.117959) (xy 331.389958 -256.100507) (xy 331.347337 -256.0759)
			(xy 331.309216 -256.044775) (xy 331.276581 -256.007938) (xy 331.250278 -255.966342) (xy 331.230987 -255.921066)
			(xy 331.21921 -255.873282) (xy 331.21525 -255.824228) (xy 330.896722 -255.824228) (xy 330.89621 -255.849674)
			(xy 330.888046 -255.899908) (xy 330.87193 -255.948182) (xy 330.848279 -255.993245) (xy 330.817706 -256.033931)
			(xy 330.781002 -256.069186) (xy 330.739118 -256.098096) (xy 330.693139 -256.119913) (xy 330.644255 -256.134073)
			(xy 330.593734 -256.140207) (xy 330.542882 -256.138158) (xy 330.493018 -256.127978) (xy 330.445432 -256.109931)
			(xy 330.401358 -256.084485) (xy 330.361936 -256.052298) (xy 330.328188 -256.014204) (xy 330.300987 -255.97119)
			(xy 330.281039 -255.92437) (xy 330.26886 -255.874956) (xy 330.264765 -255.824228) (xy 329.946508 -255.824228)
			(xy 329.946013 -255.848835) (xy 329.938118 -255.897412) (xy 329.922534 -255.944093) (xy 329.899663 -255.98767)
			(xy 329.870098 -256.027014) (xy 329.834605 -256.061106) (xy 329.794102 -256.089062) (xy 329.74964 -256.11016)
			(xy 329.702369 -256.123852) (xy 329.653514 -256.129784) (xy 329.604339 -256.127803) (xy 329.55612 -256.117959)
			(xy 329.510104 -256.100507) (xy 329.467483 -256.0759) (xy 329.429362 -256.044775) (xy 329.396727 -256.007938)
			(xy 329.370424 -255.966342) (xy 329.351133 -255.921066) (xy 329.339356 -255.873282) (xy 329.335396 -255.824228)
			(xy 329.016868 -255.824228) (xy 329.016356 -255.849674) (xy 329.008192 -255.899908) (xy 328.992076 -255.948182)
			(xy 328.968425 -255.993245) (xy 328.937852 -256.033931) (xy 328.901148 -256.069186) (xy 328.859264 -256.098096)
			(xy 328.813285 -256.119913) (xy 328.764401 -256.134073) (xy 328.71388 -256.140207) (xy 328.663028 -256.138158)
			(xy 328.613164 -256.127978) (xy 328.565578 -256.109931) (xy 328.521504 -256.084485) (xy 328.482082 -256.052298)
			(xy 328.448334 -256.014204) (xy 328.421133 -255.97119) (xy 328.401185 -255.92437) (xy 328.389006 -255.874956)
			(xy 328.384911 -255.824228) (xy 328.0664 -255.824228) (xy 328.065905 -255.848835) (xy 328.05801 -255.897412)
			(xy 328.042426 -255.944093) (xy 328.019555 -255.98767) (xy 327.98999 -256.027014) (xy 327.954497 -256.061106)
			(xy 327.913994 -256.089062) (xy 327.869532 -256.11016) (xy 327.822261 -256.123852) (xy 327.773406 -256.129784)
			(xy 327.724231 -256.127803) (xy 327.676012 -256.117959) (xy 327.629996 -256.100507) (xy 327.587375 -256.0759)
			(xy 327.549254 -256.044775) (xy 327.516619 -256.007938) (xy 327.490316 -255.966342) (xy 327.471025 -255.921066)
			(xy 327.459248 -255.873282) (xy 327.455288 -255.824228) (xy 324.903545 -255.824228) (xy 324.905872 -255.825332)
			(xy 324.946375 -255.853288) (xy 324.981868 -255.88738) (xy 325.011433 -255.926724) (xy 325.034304 -255.970301)
			(xy 325.049888 -256.016982) (xy 325.057783 -256.065559) (xy 325.058278 -256.090166) (xy 325.057783 -256.114773)
			(xy 325.049888 -256.16335) (xy 325.034304 -256.210031) (xy 325.011433 -256.253608) (xy 324.981868 -256.292952)
			(xy 324.946375 -256.327044) (xy 324.905872 -256.355) (xy 324.86141 -256.376098) (xy 324.814139 -256.38979)
			(xy 324.765284 -256.395722) (xy 324.716109 -256.393741) (xy 324.66789 -256.383897) (xy 324.621874 -256.366445)
			(xy 324.579253 -256.341838) (xy 324.541132 -256.310713) (xy 324.508497 -256.273876) (xy 324.482194 -256.23228)
			(xy 324.462903 -256.187004) (xy 324.451126 -256.13922) (xy 324.447166 -256.090166) (xy 310.45912 -256.090166)
			(xy 310.45912 -258.880102) (xy 315.252104 -258.880102) (xy 315.256134 -258.737767) (xy 315.268209 -258.595887)
			(xy 315.288292 -258.454919) (xy 315.316319 -258.315312) (xy 315.352199 -258.177514) (xy 315.395817 -258.041967)
			(xy 315.447034 -257.909105) (xy 315.505685 -257.779353) (xy 315.571583 -257.653127) (xy 315.644517 -257.530831)
			(xy 315.724254 -257.412858) (xy 315.810536 -257.299585) (xy 315.903089 -257.191374) (xy 316.001616 -257.088573)
			(xy 316.105801 -256.991511) (xy 316.21531 -256.900499) (xy 316.329793 -256.815827) (xy 316.448883 -256.737769)
			(xy 316.572198 -256.666573) (xy 316.699344 -256.602467) (xy 316.829913 -256.545658) (xy 316.963487 -256.496326)
			(xy 317.099638 -256.45463) (xy 317.237929 -256.420704) (xy 317.377919 -256.394656) (xy 317.519158 -256.37657)
			(xy 317.661194 -256.366503) (xy 317.803572 -256.364488) (xy 317.945836 -256.370531) (xy 318.08753 -256.384613)
			(xy 318.2282 -256.406689) (xy 318.367397 -256.436689) (xy 318.504673 -256.474515) (xy 318.639589 -256.520047)
			(xy 318.771713 -256.573138) (xy 318.900622 -256.63362) (xy 318.901759 -256.634234) (xy 326.045334 -256.634234)
			(xy 326.049294 -256.58518) (xy 326.061071 -256.537396) (xy 326.080362 -256.49212) (xy 326.106665 -256.450524)
			(xy 326.1393 -256.413687) (xy 326.177421 -256.382562) (xy 326.220042 -256.357955) (xy 326.266058 -256.340503)
			(xy 326.314277 -256.330659) (xy 326.363452 -256.328678) (xy 326.412307 -256.33461) (xy 326.459578 -256.348302)
			(xy 326.50404 -256.3694) (xy 326.544543 -256.397356) (xy 326.580036 -256.431448) (xy 326.609601 -256.470792)
			(xy 326.632472 -256.514369) (xy 326.648056 -256.56105) (xy 326.655951 -256.609627) (xy 326.656446 -256.634234)
			(xy 326.985388 -256.634234) (xy 326.989348 -256.58518) (xy 327.001125 -256.537396) (xy 327.020416 -256.49212)
			(xy 327.046719 -256.450524) (xy 327.079354 -256.413687) (xy 327.117475 -256.382562) (xy 327.160096 -256.357955)
			(xy 327.206112 -256.340503) (xy 327.254331 -256.330659) (xy 327.303506 -256.328678) (xy 327.352361 -256.33461)
			(xy 327.399632 -256.348302) (xy 327.444094 -256.3694) (xy 327.484597 -256.397356) (xy 327.52009 -256.431448)
			(xy 327.549655 -256.470792) (xy 327.572526 -256.514369) (xy 327.58811 -256.56105) (xy 327.596005 -256.609627)
			(xy 327.5965 -256.634234) (xy 327.925442 -256.634234) (xy 327.929402 -256.58518) (xy 327.941179 -256.537396)
			(xy 327.96047 -256.49212) (xy 327.986773 -256.450524) (xy 328.019408 -256.413687) (xy 328.057529 -256.382562)
			(xy 328.10015 -256.357955) (xy 328.146166 -256.340503) (xy 328.194385 -256.330659) (xy 328.24356 -256.328678)
			(xy 328.292415 -256.33461) (xy 328.339686 -256.348302) (xy 328.384148 -256.3694) (xy 328.424651 -256.397356)
			(xy 328.460144 -256.431448) (xy 328.489709 -256.470792) (xy 328.51258 -256.514369) (xy 328.528164 -256.56105)
			(xy 328.536059 -256.609627) (xy 328.536554 -256.634234) (xy 328.854811 -256.634234) (xy 328.858906 -256.583506)
			(xy 328.871085 -256.534092) (xy 328.891033 -256.487272) (xy 328.918234 -256.444258) (xy 328.951982 -256.406164)
			(xy 328.991404 -256.373977) (xy 329.035478 -256.348531) (xy 329.083064 -256.330484) (xy 329.132928 -256.320304)
			(xy 329.18378 -256.318255) (xy 329.234301 -256.324389) (xy 329.283185 -256.338549) (xy 329.329164 -256.360366)
			(xy 329.371048 -256.389276) (xy 329.407752 -256.424531) (xy 329.438325 -256.465217) (xy 329.461976 -256.51028)
			(xy 329.478092 -256.558554) (xy 329.486256 -256.608788) (xy 329.486768 -256.634234) (xy 329.805296 -256.634234)
			(xy 329.809256 -256.58518) (xy 329.821033 -256.537396) (xy 329.840324 -256.49212) (xy 329.866627 -256.450524)
			(xy 329.899262 -256.413687) (xy 329.937383 -256.382562) (xy 329.980004 -256.357955) (xy 330.02602 -256.340503)
			(xy 330.074239 -256.330659) (xy 330.123414 -256.328678) (xy 330.172269 -256.33461) (xy 330.21954 -256.348302)
			(xy 330.264002 -256.3694) (xy 330.304505 -256.397356) (xy 330.339998 -256.431448) (xy 330.369563 -256.470792)
			(xy 330.392434 -256.514369) (xy 330.408018 -256.56105) (xy 330.415913 -256.609627) (xy 330.416408 -256.634234)
			(xy 330.74535 -256.634234) (xy 330.74931 -256.58518) (xy 330.761087 -256.537396) (xy 330.780378 -256.49212)
			(xy 330.806681 -256.450524) (xy 330.839316 -256.413687) (xy 330.877437 -256.382562) (xy 330.920058 -256.357955)
			(xy 330.966074 -256.340503) (xy 331.014293 -256.330659) (xy 331.063468 -256.328678) (xy 331.112323 -256.33461)
			(xy 331.159594 -256.348302) (xy 331.204056 -256.3694) (xy 331.244559 -256.397356) (xy 331.280052 -256.431448)
			(xy 331.309617 -256.470792) (xy 331.332488 -256.514369) (xy 331.348072 -256.56105) (xy 331.355967 -256.609627)
			(xy 331.356462 -256.634234) (xy 331.674973 -256.634234) (xy 331.679068 -256.583506) (xy 331.691247 -256.534092)
			(xy 331.711195 -256.487272) (xy 331.738396 -256.444258) (xy 331.772144 -256.406164) (xy 331.811566 -256.373977)
			(xy 331.85564 -256.348531) (xy 331.903226 -256.330484) (xy 331.95309 -256.320304) (xy 332.003942 -256.318255)
			(xy 332.054463 -256.324389) (xy 332.103347 -256.338549) (xy 332.149326 -256.360366) (xy 332.19121 -256.389276)
			(xy 332.227914 -256.424531) (xy 332.258487 -256.465217) (xy 332.282138 -256.51028) (xy 332.298254 -256.558554)
			(xy 332.306418 -256.608788) (xy 332.30693 -256.634234) (xy 332.625204 -256.634234) (xy 332.629164 -256.58518)
			(xy 332.640941 -256.537396) (xy 332.660232 -256.49212) (xy 332.686535 -256.450524) (xy 332.71917 -256.413687)
			(xy 332.757291 -256.382562) (xy 332.799912 -256.357955) (xy 332.845928 -256.340503) (xy 332.894147 -256.330659)
			(xy 332.943322 -256.328678) (xy 332.992177 -256.33461) (xy 333.039448 -256.348302) (xy 333.08391 -256.3694)
			(xy 333.124413 -256.397356) (xy 333.159906 -256.431448) (xy 333.189471 -256.470792) (xy 333.212342 -256.514369)
			(xy 333.227926 -256.56105) (xy 333.235821 -256.609627) (xy 333.236316 -256.634234) (xy 333.565258 -256.634234)
			(xy 333.569218 -256.58518) (xy 333.580995 -256.537396) (xy 333.600286 -256.49212) (xy 333.626589 -256.450524)
			(xy 333.659224 -256.413687) (xy 333.697345 -256.382562) (xy 333.739966 -256.357955) (xy 333.785982 -256.340503)
			(xy 333.834201 -256.330659) (xy 333.883376 -256.328678) (xy 333.932231 -256.33461) (xy 333.979502 -256.348302)
			(xy 334.023964 -256.3694) (xy 334.064467 -256.397356) (xy 334.09996 -256.431448) (xy 334.129525 -256.470792)
			(xy 334.152396 -256.514369) (xy 334.16798 -256.56105) (xy 334.175875 -256.609627) (xy 334.17637 -256.634234)
			(xy 334.505312 -256.634234) (xy 334.509272 -256.58518) (xy 334.521049 -256.537396) (xy 334.54034 -256.49212)
			(xy 334.566643 -256.450524) (xy 334.599278 -256.413687) (xy 334.637399 -256.382562) (xy 334.68002 -256.357955)
			(xy 334.726036 -256.340503) (xy 334.774255 -256.330659) (xy 334.82343 -256.328678) (xy 334.872285 -256.33461)
			(xy 334.919556 -256.348302) (xy 334.964018 -256.3694) (xy 335.004521 -256.397356) (xy 335.040014 -256.431448)
			(xy 335.069579 -256.470792) (xy 335.09245 -256.514369) (xy 335.108034 -256.56105) (xy 335.115929 -256.609627)
			(xy 335.116424 -256.634234) (xy 335.434935 -256.634234) (xy 335.43903 -256.583506) (xy 335.451209 -256.534092)
			(xy 335.471157 -256.487272) (xy 335.498358 -256.444258) (xy 335.532106 -256.406164) (xy 335.571528 -256.373977)
			(xy 335.615602 -256.348531) (xy 335.663188 -256.330484) (xy 335.713052 -256.320304) (xy 335.763904 -256.318255)
			(xy 335.814425 -256.324389) (xy 335.863309 -256.338549) (xy 335.909288 -256.360366) (xy 335.951172 -256.389276)
			(xy 335.987876 -256.424531) (xy 336.018449 -256.465217) (xy 336.0421 -256.51028) (xy 336.058216 -256.558554)
			(xy 336.06638 -256.608788) (xy 336.066892 -256.634234) (xy 336.38542 -256.634234) (xy 336.38938 -256.58518)
			(xy 336.401157 -256.537396) (xy 336.420448 -256.49212) (xy 336.446751 -256.450524) (xy 336.479386 -256.413687)
			(xy 336.517507 -256.382562) (xy 336.560128 -256.357955) (xy 336.606144 -256.340503) (xy 336.654363 -256.330659)
			(xy 336.703538 -256.328678) (xy 336.752393 -256.33461) (xy 336.799664 -256.348302) (xy 336.844126 -256.3694)
			(xy 336.884629 -256.397356) (xy 336.920122 -256.431448) (xy 336.949687 -256.470792) (xy 336.972558 -256.514369)
			(xy 336.988142 -256.56105) (xy 336.996037 -256.609627) (xy 336.996532 -256.634234) (xy 337.32522 -256.634234)
			(xy 337.32918 -256.58518) (xy 337.340957 -256.537396) (xy 337.360248 -256.49212) (xy 337.386551 -256.450524)
			(xy 337.419186 -256.413687) (xy 337.457307 -256.382562) (xy 337.499928 -256.357955) (xy 337.545944 -256.340503)
			(xy 337.594163 -256.330659) (xy 337.643338 -256.328678) (xy 337.692193 -256.33461) (xy 337.739464 -256.348302)
			(xy 337.783926 -256.3694) (xy 337.824429 -256.397356) (xy 337.859922 -256.431448) (xy 337.889487 -256.470792)
			(xy 337.912358 -256.514369) (xy 337.927942 -256.56105) (xy 337.935837 -256.609627) (xy 337.936332 -256.634234)
			(xy 338.254843 -256.634234) (xy 338.258938 -256.583506) (xy 338.271117 -256.534092) (xy 338.291065 -256.487272)
			(xy 338.318266 -256.444258) (xy 338.352014 -256.406164) (xy 338.391436 -256.373977) (xy 338.43551 -256.348531)
			(xy 338.483096 -256.330484) (xy 338.53296 -256.320304) (xy 338.583812 -256.318255) (xy 338.634333 -256.324389)
			(xy 338.683217 -256.338549) (xy 338.729196 -256.360366) (xy 338.77108 -256.389276) (xy 338.807784 -256.424531)
			(xy 338.838357 -256.465217) (xy 338.862008 -256.51028) (xy 338.878124 -256.558554) (xy 338.886288 -256.608788)
			(xy 338.8868 -256.634234) (xy 339.205328 -256.634234) (xy 339.209288 -256.58518) (xy 339.221065 -256.537396)
			(xy 339.240356 -256.49212) (xy 339.266659 -256.450524) (xy 339.299294 -256.413687) (xy 339.337415 -256.382562)
			(xy 339.380036 -256.357955) (xy 339.426052 -256.340503) (xy 339.474271 -256.330659) (xy 339.523446 -256.328678)
			(xy 339.572301 -256.33461) (xy 339.619572 -256.348302) (xy 339.664034 -256.3694) (xy 339.704537 -256.397356)
			(xy 339.74003 -256.431448) (xy 339.769595 -256.470792) (xy 339.792466 -256.514369) (xy 339.80805 -256.56105)
			(xy 339.815945 -256.609627) (xy 339.81644 -256.634234) (xy 340.145382 -256.634234) (xy 340.149342 -256.58518)
			(xy 340.161119 -256.537396) (xy 340.18041 -256.49212) (xy 340.206713 -256.450524) (xy 340.239348 -256.413687)
			(xy 340.277469 -256.382562) (xy 340.32009 -256.357955) (xy 340.366106 -256.340503) (xy 340.414325 -256.330659)
			(xy 340.4635 -256.328678) (xy 340.512355 -256.33461) (xy 340.559626 -256.348302) (xy 340.604088 -256.3694)
			(xy 340.644591 -256.397356) (xy 340.680084 -256.431448) (xy 340.709649 -256.470792) (xy 340.73252 -256.514369)
			(xy 340.748104 -256.56105) (xy 340.755999 -256.609627) (xy 340.756494 -256.634234) (xy 341.085182 -256.634234)
			(xy 341.089142 -256.58518) (xy 341.100919 -256.537396) (xy 341.12021 -256.49212) (xy 341.146513 -256.450524)
			(xy 341.179148 -256.413687) (xy 341.217269 -256.382562) (xy 341.25989 -256.357955) (xy 341.305906 -256.340503)
			(xy 341.354125 -256.330659) (xy 341.4033 -256.328678) (xy 341.452155 -256.33461) (xy 341.499426 -256.348302)
			(xy 341.543888 -256.3694) (xy 341.584391 -256.397356) (xy 341.619884 -256.431448) (xy 341.649449 -256.470792)
			(xy 341.67232 -256.514369) (xy 341.687904 -256.56105) (xy 341.695799 -256.609627) (xy 341.696294 -256.634234)
			(xy 342.014805 -256.634234) (xy 342.0189 -256.583506) (xy 342.031079 -256.534092) (xy 342.051027 -256.487272)
			(xy 342.078228 -256.444258) (xy 342.111976 -256.406164) (xy 342.151398 -256.373977) (xy 342.195472 -256.348531)
			(xy 342.243058 -256.330484) (xy 342.292922 -256.320304) (xy 342.343774 -256.318255) (xy 342.394295 -256.324389)
			(xy 342.443179 -256.338549) (xy 342.489158 -256.360366) (xy 342.531042 -256.389276) (xy 342.567746 -256.424531)
			(xy 342.598319 -256.465217) (xy 342.62197 -256.51028) (xy 342.638086 -256.558554) (xy 342.64625 -256.608788)
			(xy 342.646762 -256.634234) (xy 342.96529 -256.634234) (xy 342.96925 -256.58518) (xy 342.981027 -256.537396)
			(xy 343.000318 -256.49212) (xy 343.026621 -256.450524) (xy 343.059256 -256.413687) (xy 343.097377 -256.382562)
			(xy 343.139998 -256.357955) (xy 343.186014 -256.340503) (xy 343.234233 -256.330659) (xy 343.283408 -256.328678)
			(xy 343.332263 -256.33461) (xy 343.379534 -256.348302) (xy 343.423996 -256.3694) (xy 343.464499 -256.397356)
			(xy 343.499992 -256.431448) (xy 343.529557 -256.470792) (xy 343.552428 -256.514369) (xy 343.568012 -256.56105)
			(xy 343.575907 -256.609627) (xy 343.576402 -256.634234) (xy 344.845398 -256.634234) (xy 344.849358 -256.58518)
			(xy 344.861135 -256.537396) (xy 344.880426 -256.49212) (xy 344.906729 -256.450524) (xy 344.939364 -256.413687)
			(xy 344.977485 -256.382562) (xy 345.020106 -256.357955) (xy 345.066122 -256.340503) (xy 345.114341 -256.330659)
			(xy 345.163516 -256.328678) (xy 345.212371 -256.33461) (xy 345.259642 -256.348302) (xy 345.304104 -256.3694)
			(xy 345.344607 -256.397356) (xy 345.3801 -256.431448) (xy 345.409665 -256.470792) (xy 345.432536 -256.514369)
			(xy 345.44812 -256.56105) (xy 345.456015 -256.609627) (xy 345.45651 -256.634234) (xy 345.456015 -256.658841)
			(xy 345.44812 -256.707418) (xy 345.432536 -256.754099) (xy 345.409665 -256.797676) (xy 345.3801 -256.83702)
			(xy 345.344607 -256.871112) (xy 345.304104 -256.899068) (xy 345.259642 -256.920166) (xy 345.212371 -256.933858)
			(xy 345.163516 -256.93979) (xy 345.114341 -256.937809) (xy 345.066122 -256.927965) (xy 345.020106 -256.910513)
			(xy 344.977485 -256.885906) (xy 344.939364 -256.854781) (xy 344.906729 -256.817944) (xy 344.880426 -256.776348)
			(xy 344.861135 -256.731072) (xy 344.849358 -256.683288) (xy 344.845398 -256.634234) (xy 343.576402 -256.634234)
			(xy 343.575907 -256.658841) (xy 343.568012 -256.707418) (xy 343.552428 -256.754099) (xy 343.529557 -256.797676)
			(xy 343.499992 -256.83702) (xy 343.464499 -256.871112) (xy 343.423996 -256.899068) (xy 343.379534 -256.920166)
			(xy 343.332263 -256.933858) (xy 343.283408 -256.93979) (xy 343.234233 -256.937809) (xy 343.186014 -256.927965)
			(xy 343.139998 -256.910513) (xy 343.097377 -256.885906) (xy 343.059256 -256.854781) (xy 343.026621 -256.817944)
			(xy 343.000318 -256.776348) (xy 342.981027 -256.731072) (xy 342.96925 -256.683288) (xy 342.96529 -256.634234)
			(xy 342.646762 -256.634234) (xy 342.64625 -256.65968) (xy 342.638086 -256.709914) (xy 342.62197 -256.758188)
			(xy 342.598319 -256.803251) (xy 342.567746 -256.843937) (xy 342.531042 -256.879192) (xy 342.489158 -256.908102)
			(xy 342.443179 -256.929919) (xy 342.394295 -256.944079) (xy 342.343774 -256.950213) (xy 342.292922 -256.948164)
			(xy 342.243058 -256.937984) (xy 342.195472 -256.919937) (xy 342.151398 -256.894491) (xy 342.111976 -256.862304)
			(xy 342.078228 -256.82421) (xy 342.051027 -256.781196) (xy 342.031079 -256.734376) (xy 342.0189 -256.684962)
			(xy 342.014805 -256.634234) (xy 341.696294 -256.634234) (xy 341.695799 -256.658841) (xy 341.687904 -256.707418)
			(xy 341.67232 -256.754099) (xy 341.649449 -256.797676) (xy 341.619884 -256.83702) (xy 341.584391 -256.871112)
			(xy 341.543888 -256.899068) (xy 341.499426 -256.920166) (xy 341.452155 -256.933858) (xy 341.4033 -256.93979)
			(xy 341.354125 -256.937809) (xy 341.305906 -256.927965) (xy 341.25989 -256.910513) (xy 341.217269 -256.885906)
			(xy 341.179148 -256.854781) (xy 341.146513 -256.817944) (xy 341.12021 -256.776348) (xy 341.100919 -256.731072)
			(xy 341.089142 -256.683288) (xy 341.085182 -256.634234) (xy 340.756494 -256.634234) (xy 340.755999 -256.658841)
			(xy 340.748104 -256.707418) (xy 340.73252 -256.754099) (xy 340.709649 -256.797676) (xy 340.680084 -256.83702)
			(xy 340.644591 -256.871112) (xy 340.604088 -256.899068) (xy 340.559626 -256.920166) (xy 340.512355 -256.933858)
			(xy 340.4635 -256.93979) (xy 340.414325 -256.937809) (xy 340.366106 -256.927965) (xy 340.32009 -256.910513)
			(xy 340.277469 -256.885906) (xy 340.239348 -256.854781) (xy 340.206713 -256.817944) (xy 340.18041 -256.776348)
			(xy 340.161119 -256.731072) (xy 340.149342 -256.683288) (xy 340.145382 -256.634234) (xy 339.81644 -256.634234)
			(xy 339.815945 -256.658841) (xy 339.80805 -256.707418) (xy 339.792466 -256.754099) (xy 339.769595 -256.797676)
			(xy 339.74003 -256.83702) (xy 339.704537 -256.871112) (xy 339.664034 -256.899068) (xy 339.619572 -256.920166)
			(xy 339.572301 -256.933858) (xy 339.523446 -256.93979) (xy 339.474271 -256.937809) (xy 339.426052 -256.927965)
			(xy 339.380036 -256.910513) (xy 339.337415 -256.885906) (xy 339.299294 -256.854781) (xy 339.266659 -256.817944)
			(xy 339.240356 -256.776348) (xy 339.221065 -256.731072) (xy 339.209288 -256.683288) (xy 339.205328 -256.634234)
			(xy 338.8868 -256.634234) (xy 338.886288 -256.65968) (xy 338.878124 -256.709914) (xy 338.862008 -256.758188)
			(xy 338.838357 -256.803251) (xy 338.807784 -256.843937) (xy 338.77108 -256.879192) (xy 338.729196 -256.908102)
			(xy 338.683217 -256.929919) (xy 338.634333 -256.944079) (xy 338.583812 -256.950213) (xy 338.53296 -256.948164)
			(xy 338.483096 -256.937984) (xy 338.43551 -256.919937) (xy 338.391436 -256.894491) (xy 338.352014 -256.862304)
			(xy 338.318266 -256.82421) (xy 338.291065 -256.781196) (xy 338.271117 -256.734376) (xy 338.258938 -256.684962)
			(xy 338.254843 -256.634234) (xy 337.936332 -256.634234) (xy 337.935837 -256.658841) (xy 337.927942 -256.707418)
			(xy 337.912358 -256.754099) (xy 337.889487 -256.797676) (xy 337.859922 -256.83702) (xy 337.824429 -256.871112)
			(xy 337.783926 -256.899068) (xy 337.739464 -256.920166) (xy 337.692193 -256.933858) (xy 337.643338 -256.93979)
			(xy 337.594163 -256.937809) (xy 337.545944 -256.927965) (xy 337.499928 -256.910513) (xy 337.457307 -256.885906)
			(xy 337.419186 -256.854781) (xy 337.386551 -256.817944) (xy 337.360248 -256.776348) (xy 337.340957 -256.731072)
			(xy 337.32918 -256.683288) (xy 337.32522 -256.634234) (xy 336.996532 -256.634234) (xy 336.996037 -256.658841)
			(xy 336.988142 -256.707418) (xy 336.972558 -256.754099) (xy 336.949687 -256.797676) (xy 336.920122 -256.83702)
			(xy 336.884629 -256.871112) (xy 336.844126 -256.899068) (xy 336.799664 -256.920166) (xy 336.752393 -256.933858)
			(xy 336.703538 -256.93979) (xy 336.654363 -256.937809) (xy 336.606144 -256.927965) (xy 336.560128 -256.910513)
			(xy 336.517507 -256.885906) (xy 336.479386 -256.854781) (xy 336.446751 -256.817944) (xy 336.420448 -256.776348)
			(xy 336.401157 -256.731072) (xy 336.38938 -256.683288) (xy 336.38542 -256.634234) (xy 336.066892 -256.634234)
			(xy 336.06638 -256.65968) (xy 336.058216 -256.709914) (xy 336.0421 -256.758188) (xy 336.018449 -256.803251)
			(xy 335.987876 -256.843937) (xy 335.951172 -256.879192) (xy 335.909288 -256.908102) (xy 335.863309 -256.929919)
			(xy 335.814425 -256.944079) (xy 335.763904 -256.950213) (xy 335.713052 -256.948164) (xy 335.663188 -256.937984)
			(xy 335.615602 -256.919937) (xy 335.571528 -256.894491) (xy 335.532106 -256.862304) (xy 335.498358 -256.82421)
			(xy 335.471157 -256.781196) (xy 335.451209 -256.734376) (xy 335.43903 -256.684962) (xy 335.434935 -256.634234)
			(xy 335.116424 -256.634234) (xy 335.115929 -256.658841) (xy 335.108034 -256.707418) (xy 335.09245 -256.754099)
			(xy 335.069579 -256.797676) (xy 335.040014 -256.83702) (xy 335.004521 -256.871112) (xy 334.964018 -256.899068)
			(xy 334.919556 -256.920166) (xy 334.872285 -256.933858) (xy 334.82343 -256.93979) (xy 334.774255 -256.937809)
			(xy 334.726036 -256.927965) (xy 334.68002 -256.910513) (xy 334.637399 -256.885906) (xy 334.599278 -256.854781)
			(xy 334.566643 -256.817944) (xy 334.54034 -256.776348) (xy 334.521049 -256.731072) (xy 334.509272 -256.683288)
			(xy 334.505312 -256.634234) (xy 334.17637 -256.634234) (xy 334.175875 -256.658841) (xy 334.16798 -256.707418)
			(xy 334.152396 -256.754099) (xy 334.129525 -256.797676) (xy 334.09996 -256.83702) (xy 334.064467 -256.871112)
			(xy 334.023964 -256.899068) (xy 333.979502 -256.920166) (xy 333.932231 -256.933858) (xy 333.883376 -256.93979)
			(xy 333.834201 -256.937809) (xy 333.785982 -256.927965) (xy 333.739966 -256.910513) (xy 333.697345 -256.885906)
			(xy 333.659224 -256.854781) (xy 333.626589 -256.817944) (xy 333.600286 -256.776348) (xy 333.580995 -256.731072)
			(xy 333.569218 -256.683288) (xy 333.565258 -256.634234) (xy 333.236316 -256.634234) (xy 333.235821 -256.658841)
			(xy 333.227926 -256.707418) (xy 333.212342 -256.754099) (xy 333.189471 -256.797676) (xy 333.159906 -256.83702)
			(xy 333.124413 -256.871112) (xy 333.08391 -256.899068) (xy 333.039448 -256.920166) (xy 332.992177 -256.933858)
			(xy 332.943322 -256.93979) (xy 332.894147 -256.937809) (xy 332.845928 -256.927965) (xy 332.799912 -256.910513)
			(xy 332.757291 -256.885906) (xy 332.71917 -256.854781) (xy 332.686535 -256.817944) (xy 332.660232 -256.776348)
			(xy 332.640941 -256.731072) (xy 332.629164 -256.683288) (xy 332.625204 -256.634234) (xy 332.30693 -256.634234)
			(xy 332.306418 -256.65968) (xy 332.298254 -256.709914) (xy 332.282138 -256.758188) (xy 332.258487 -256.803251)
			(xy 332.227914 -256.843937) (xy 332.19121 -256.879192) (xy 332.149326 -256.908102) (xy 332.103347 -256.929919)
			(xy 332.054463 -256.944079) (xy 332.003942 -256.950213) (xy 331.95309 -256.948164) (xy 331.903226 -256.937984)
			(xy 331.85564 -256.919937) (xy 331.811566 -256.894491) (xy 331.772144 -256.862304) (xy 331.738396 -256.82421)
			(xy 331.711195 -256.781196) (xy 331.691247 -256.734376) (xy 331.679068 -256.684962) (xy 331.674973 -256.634234)
			(xy 331.356462 -256.634234) (xy 331.355967 -256.658841) (xy 331.348072 -256.707418) (xy 331.332488 -256.754099)
			(xy 331.309617 -256.797676) (xy 331.280052 -256.83702) (xy 331.244559 -256.871112) (xy 331.204056 -256.899068)
			(xy 331.159594 -256.920166) (xy 331.112323 -256.933858) (xy 331.063468 -256.93979) (xy 331.014293 -256.937809)
			(xy 330.966074 -256.927965) (xy 330.920058 -256.910513) (xy 330.877437 -256.885906) (xy 330.839316 -256.854781)
			(xy 330.806681 -256.817944) (xy 330.780378 -256.776348) (xy 330.761087 -256.731072) (xy 330.74931 -256.683288)
			(xy 330.74535 -256.634234) (xy 330.416408 -256.634234) (xy 330.415913 -256.658841) (xy 330.408018 -256.707418)
			(xy 330.392434 -256.754099) (xy 330.369563 -256.797676) (xy 330.339998 -256.83702) (xy 330.304505 -256.871112)
			(xy 330.264002 -256.899068) (xy 330.21954 -256.920166) (xy 330.172269 -256.933858) (xy 330.123414 -256.93979)
			(xy 330.074239 -256.937809) (xy 330.02602 -256.927965) (xy 329.980004 -256.910513) (xy 329.937383 -256.885906)
			(xy 329.899262 -256.854781) (xy 329.866627 -256.817944) (xy 329.840324 -256.776348) (xy 329.821033 -256.731072)
			(xy 329.809256 -256.683288) (xy 329.805296 -256.634234) (xy 329.486768 -256.634234) (xy 329.486256 -256.65968)
			(xy 329.478092 -256.709914) (xy 329.461976 -256.758188) (xy 329.438325 -256.803251) (xy 329.407752 -256.843937)
			(xy 329.371048 -256.879192) (xy 329.329164 -256.908102) (xy 329.283185 -256.929919) (xy 329.234301 -256.944079)
			(xy 329.18378 -256.950213) (xy 329.132928 -256.948164) (xy 329.083064 -256.937984) (xy 329.035478 -256.919937)
			(xy 328.991404 -256.894491) (xy 328.951982 -256.862304) (xy 328.918234 -256.82421) (xy 328.891033 -256.781196)
			(xy 328.871085 -256.734376) (xy 328.858906 -256.684962) (xy 328.854811 -256.634234) (xy 328.536554 -256.634234)
			(xy 328.536059 -256.658841) (xy 328.528164 -256.707418) (xy 328.51258 -256.754099) (xy 328.489709 -256.797676)
			(xy 328.460144 -256.83702) (xy 328.424651 -256.871112) (xy 328.384148 -256.899068) (xy 328.339686 -256.920166)
			(xy 328.292415 -256.933858) (xy 328.24356 -256.93979) (xy 328.194385 -256.937809) (xy 328.146166 -256.927965)
			(xy 328.10015 -256.910513) (xy 328.057529 -256.885906) (xy 328.019408 -256.854781) (xy 327.986773 -256.817944)
			(xy 327.96047 -256.776348) (xy 327.941179 -256.731072) (xy 327.929402 -256.683288) (xy 327.925442 -256.634234)
			(xy 327.5965 -256.634234) (xy 327.596005 -256.658841) (xy 327.58811 -256.707418) (xy 327.572526 -256.754099)
			(xy 327.549655 -256.797676) (xy 327.52009 -256.83702) (xy 327.484597 -256.871112) (xy 327.444094 -256.899068)
			(xy 327.399632 -256.920166) (xy 327.352361 -256.933858) (xy 327.303506 -256.93979) (xy 327.254331 -256.937809)
			(xy 327.206112 -256.927965) (xy 327.160096 -256.910513) (xy 327.117475 -256.885906) (xy 327.079354 -256.854781)
			(xy 327.046719 -256.817944) (xy 327.020416 -256.776348) (xy 327.001125 -256.731072) (xy 326.989348 -256.683288)
			(xy 326.985388 -256.634234) (xy 326.656446 -256.634234) (xy 326.655951 -256.658841) (xy 326.648056 -256.707418)
			(xy 326.632472 -256.754099) (xy 326.609601 -256.797676) (xy 326.580036 -256.83702) (xy 326.544543 -256.871112)
			(xy 326.50404 -256.899068) (xy 326.459578 -256.920166) (xy 326.412307 -256.933858) (xy 326.363452 -256.93979)
			(xy 326.314277 -256.937809) (xy 326.266058 -256.927965) (xy 326.220042 -256.910513) (xy 326.177421 -256.885906)
			(xy 326.1393 -256.854781) (xy 326.106665 -256.817944) (xy 326.080362 -256.776348) (xy 326.061071 -256.731072)
			(xy 326.049294 -256.683288) (xy 326.045334 -256.634234) (xy 318.901759 -256.634234) (xy 319.025903 -256.701298)
			(xy 319.147154 -256.775955) (xy 319.263987 -256.857353) (xy 319.376028 -256.94523) (xy 319.482918 -257.039305)
			(xy 319.584315 -257.139277) (xy 319.679893 -257.244825) (xy 319.769347 -257.355611) (xy 319.852389 -257.47128)
			(xy 319.928755 -257.591463) (xy 319.998199 -257.715773) (xy 320.060499 -257.843814) (xy 320.096616 -257.930142)
			(xy 346.651329 -257.930142) (xy 346.655359 -257.877644) (xy 346.667356 -257.826376) (xy 346.687039 -257.777541)
			(xy 346.713945 -257.732282) (xy 346.747445 -257.691661) (xy 346.786753 -257.65663) (xy 346.830948 -257.62801)
			(xy 346.878993 -257.606471) (xy 346.929764 -257.592519) (xy 346.982069 -257.586481) (xy 347.034683 -257.588498)
			(xy 347.086373 -257.598522) (xy 347.135926 -257.61632) (xy 347.182182 -257.641473) (xy 347.224056 -257.673392)
			(xy 347.260568 -257.71133) (xy 347.29086 -257.754396) (xy 347.314223 -257.801581) (xy 347.330109 -257.85178)
			(xy 347.338146 -257.903816) (xy 347.33865 -257.930142) (xy 348.551249 -257.930142) (xy 348.555279 -257.877644)
			(xy 348.567276 -257.826376) (xy 348.586959 -257.777541) (xy 348.613865 -257.732282) (xy 348.647365 -257.691661)
			(xy 348.686673 -257.65663) (xy 348.730868 -257.62801) (xy 348.778913 -257.606471) (xy 348.829684 -257.592519)
			(xy 348.881989 -257.586481) (xy 348.934603 -257.588498) (xy 348.986293 -257.598522) (xy 349.035846 -257.61632)
			(xy 349.082102 -257.641473) (xy 349.123976 -257.673392) (xy 349.160488 -257.71133) (xy 349.19078 -257.754396)
			(xy 349.214143 -257.801581) (xy 349.230029 -257.85178) (xy 349.238066 -257.903816) (xy 349.23857 -257.930142)
			(xy 350.451169 -257.930142) (xy 350.455199 -257.877644) (xy 350.467196 -257.826376) (xy 350.486879 -257.777541)
			(xy 350.513785 -257.732282) (xy 350.547285 -257.691661) (xy 350.586593 -257.65663) (xy 350.630788 -257.62801)
			(xy 350.678833 -257.606471) (xy 350.729604 -257.592519) (xy 350.781909 -257.586481) (xy 350.834523 -257.588498)
			(xy 350.886213 -257.598522) (xy 350.935766 -257.61632) (xy 350.982022 -257.641473) (xy 351.023896 -257.673392)
			(xy 351.060408 -257.71133) (xy 351.0907 -257.754396) (xy 351.114063 -257.801581) (xy 351.129949 -257.85178)
			(xy 351.137986 -257.903816) (xy 351.13849 -257.930142) (xy 351.137986 -257.956468) (xy 351.129949 -258.008504)
			(xy 351.114063 -258.058703) (xy 351.0907 -258.105888) (xy 351.060408 -258.148954) (xy 351.023896 -258.186892)
			(xy 350.982022 -258.218811) (xy 350.935766 -258.243964) (xy 350.886213 -258.261762) (xy 350.834523 -258.271786)
			(xy 350.781909 -258.273803) (xy 350.729604 -258.267765) (xy 350.678833 -258.253813) (xy 350.630788 -258.232274)
			(xy 350.586593 -258.203654) (xy 350.547285 -258.168623) (xy 350.513785 -258.128002) (xy 350.486879 -258.082743)
			(xy 350.467196 -258.033908) (xy 350.455199 -257.98264) (xy 350.451169 -257.930142) (xy 349.23857 -257.930142)
			(xy 349.238066 -257.956468) (xy 349.230029 -258.008504) (xy 349.214143 -258.058703) (xy 349.19078 -258.105888)
			(xy 349.160488 -258.148954) (xy 349.123976 -258.186892) (xy 349.082102 -258.218811) (xy 349.035846 -258.243964)
			(xy 348.986293 -258.261762) (xy 348.934603 -258.271786) (xy 348.881989 -258.273803) (xy 348.829684 -258.267765)
			(xy 348.778913 -258.253813) (xy 348.730868 -258.232274) (xy 348.686673 -258.203654) (xy 348.647365 -258.168623)
			(xy 348.613865 -258.128002) (xy 348.586959 -258.082743) (xy 348.567276 -258.033908) (xy 348.555279 -257.98264)
			(xy 348.551249 -257.930142) (xy 347.33865 -257.930142) (xy 347.338146 -257.956468) (xy 347.330109 -258.008504)
			(xy 347.314223 -258.058703) (xy 347.29086 -258.105888) (xy 347.260568 -258.148954) (xy 347.224056 -258.186892)
			(xy 347.182182 -258.218811) (xy 347.135926 -258.243964) (xy 347.086373 -258.261762) (xy 347.034683 -258.271786)
			(xy 346.982069 -258.273803) (xy 346.929764 -258.267765) (xy 346.878993 -258.253813) (xy 346.830948 -258.232274)
			(xy 346.786753 -258.203654) (xy 346.747445 -258.168623) (xy 346.713945 -258.128002) (xy 346.687039 -258.082743)
			(xy 346.667356 -258.033908) (xy 346.655359 -257.98264) (xy 346.651329 -257.930142) (xy 320.096616 -257.930142)
			(xy 320.115455 -257.975173) (xy 320.162892 -258.109432) (xy 320.202656 -258.246159) (xy 320.233484 -258.379976)
			(xy 354.001327 -258.379976) (xy 354.005357 -258.327478) (xy 354.017354 -258.27621) (xy 354.037037 -258.227375)
			(xy 354.063943 -258.182116) (xy 354.097443 -258.141495) (xy 354.136751 -258.106464) (xy 354.180946 -258.077844)
			(xy 354.228991 -258.056305) (xy 354.279762 -258.042353) (xy 354.332067 -258.036315) (xy 354.384681 -258.038332)
			(xy 354.436371 -258.048356) (xy 354.485924 -258.066154) (xy 354.53218 -258.091307) (xy 354.574054 -258.123226)
			(xy 354.610566 -258.161164) (xy 354.640858 -258.20423) (xy 354.664221 -258.251415) (xy 354.680107 -258.301614)
			(xy 354.688144 -258.35365) (xy 354.688648 -258.379976) (xy 354.688144 -258.406302) (xy 354.680107 -258.458338)
			(xy 354.664221 -258.508537) (xy 354.640858 -258.555722) (xy 354.610566 -258.598788) (xy 354.574054 -258.636726)
			(xy 354.53218 -258.668645) (xy 354.485924 -258.693798) (xy 354.436371 -258.711596) (xy 354.384681 -258.72162)
			(xy 354.332067 -258.723637) (xy 354.279762 -258.717599) (xy 354.228991 -258.703647) (xy 354.180946 -258.682108)
			(xy 354.136751 -258.653488) (xy 354.097443 -258.618457) (xy 354.063943 -258.577836) (xy 354.037037 -258.532577)
			(xy 354.017354 -258.483742) (xy 354.005357 -258.432474) (xy 354.001327 -258.379976) (xy 320.233484 -258.379976)
			(xy 320.234622 -258.384917) (xy 320.258687 -258.525261) (xy 320.274773 -258.666742) (xy 320.282828 -258.808906)
			(xy 320.282978 -258.830064) (xy 346.651329 -258.830064) (xy 346.655359 -258.777566) (xy 346.667356 -258.726298)
			(xy 346.687039 -258.677463) (xy 346.713945 -258.632204) (xy 346.747445 -258.591583) (xy 346.786753 -258.556552)
			(xy 346.830948 -258.527932) (xy 346.878993 -258.506393) (xy 346.929764 -258.492441) (xy 346.982069 -258.486403)
			(xy 347.034683 -258.48842) (xy 347.086373 -258.498444) (xy 347.135926 -258.516242) (xy 347.182182 -258.541395)
			(xy 347.224056 -258.573314) (xy 347.260568 -258.611252) (xy 347.29086 -258.654318) (xy 347.314223 -258.701503)
			(xy 347.330109 -258.751702) (xy 347.338146 -258.803738) (xy 347.33865 -258.830064) (xy 348.551249 -258.830064)
			(xy 348.555279 -258.777566) (xy 348.567276 -258.726298) (xy 348.586959 -258.677463) (xy 348.613865 -258.632204)
			(xy 348.647365 -258.591583) (xy 348.686673 -258.556552) (xy 348.730868 -258.527932) (xy 348.778913 -258.506393)
			(xy 348.829684 -258.492441) (xy 348.881989 -258.486403) (xy 348.934603 -258.48842) (xy 348.986293 -258.498444)
			(xy 349.035846 -258.516242) (xy 349.082102 -258.541395) (xy 349.123976 -258.573314) (xy 349.160488 -258.611252)
			(xy 349.19078 -258.654318) (xy 349.214143 -258.701503) (xy 349.230029 -258.751702) (xy 349.238066 -258.803738)
			(xy 349.23857 -258.830064) (xy 350.451169 -258.830064) (xy 350.455199 -258.777566) (xy 350.467196 -258.726298)
			(xy 350.486879 -258.677463) (xy 350.513785 -258.632204) (xy 350.547285 -258.591583) (xy 350.586593 -258.556552)
			(xy 350.630788 -258.527932) (xy 350.678833 -258.506393) (xy 350.729604 -258.492441) (xy 350.781909 -258.486403)
			(xy 350.834523 -258.48842) (xy 350.886213 -258.498444) (xy 350.935766 -258.516242) (xy 350.982022 -258.541395)
			(xy 351.023896 -258.573314) (xy 351.060408 -258.611252) (xy 351.0907 -258.654318) (xy 351.114063 -258.701503)
			(xy 351.129949 -258.751702) (xy 351.137986 -258.803738) (xy 351.13849 -258.830064) (xy 351.137986 -258.85639)
			(xy 351.129949 -258.908426) (xy 351.114063 -258.958625) (xy 351.0907 -259.00581) (xy 351.060408 -259.048876)
			(xy 351.023896 -259.086814) (xy 350.982022 -259.118733) (xy 350.935766 -259.143886) (xy 350.886213 -259.161684)
			(xy 350.834523 -259.171708) (xy 350.781909 -259.173725) (xy 350.729604 -259.167687) (xy 350.678833 -259.153735)
			(xy 350.630788 -259.132196) (xy 350.586593 -259.103576) (xy 350.547285 -259.068545) (xy 350.513785 -259.027924)
			(xy 350.486879 -258.982665) (xy 350.467196 -258.93383) (xy 350.455199 -258.882562) (xy 350.451169 -258.830064)
			(xy 349.23857 -258.830064) (xy 349.238066 -258.85639) (xy 349.230029 -258.908426) (xy 349.214143 -258.958625)
			(xy 349.19078 -259.00581) (xy 349.160488 -259.048876) (xy 349.123976 -259.086814) (xy 349.082102 -259.118733)
			(xy 349.035846 -259.143886) (xy 348.986293 -259.161684) (xy 348.934603 -259.171708) (xy 348.881989 -259.173725)
			(xy 348.829684 -259.167687) (xy 348.778913 -259.153735) (xy 348.730868 -259.132196) (xy 348.686673 -259.103576)
			(xy 348.647365 -259.068545) (xy 348.613865 -259.027924) (xy 348.586959 -258.982665) (xy 348.567276 -258.93383)
			(xy 348.555279 -258.882562) (xy 348.551249 -258.830064) (xy 347.33865 -258.830064) (xy 347.338146 -258.85639)
			(xy 347.330109 -258.908426) (xy 347.314223 -258.958625) (xy 347.29086 -259.00581) (xy 347.260568 -259.048876)
			(xy 347.224056 -259.086814) (xy 347.182182 -259.118733) (xy 347.135926 -259.143886) (xy 347.086373 -259.161684)
			(xy 347.034683 -259.171708) (xy 346.982069 -259.173725) (xy 346.929764 -259.167687) (xy 346.878993 -259.153735)
			(xy 346.830948 -259.132196) (xy 346.786753 -259.103576) (xy 346.747445 -259.068545) (xy 346.713945 -259.027924)
			(xy 346.687039 -258.982665) (xy 346.667356 -258.93383) (xy 346.655359 -258.882562) (xy 346.651329 -258.830064)
			(xy 320.282978 -258.830064) (xy 320.283332 -258.880102) (xy 320.282828 -258.951298) (xy 320.274773 -259.093462)
			(xy 320.258687 -259.234943) (xy 320.242355 -259.33019) (xy 354.001327 -259.33019) (xy 354.005357 -259.277692)
			(xy 354.017354 -259.226424) (xy 354.037037 -259.177589) (xy 354.063943 -259.13233) (xy 354.097443 -259.091709)
			(xy 354.136751 -259.056678) (xy 354.180946 -259.028058) (xy 354.228991 -259.006519) (xy 354.279762 -258.992567)
			(xy 354.332067 -258.986529) (xy 354.384681 -258.988546) (xy 354.436371 -258.99857) (xy 354.485924 -259.016368)
			(xy 354.53218 -259.041521) (xy 354.574054 -259.07344) (xy 354.610566 -259.111378) (xy 354.640858 -259.154444)
			(xy 354.664221 -259.201629) (xy 354.680107 -259.251828) (xy 354.688144 -259.303864) (xy 354.688648 -259.33019)
			(xy 354.688144 -259.356516) (xy 354.680107 -259.408552) (xy 354.664221 -259.458751) (xy 354.640858 -259.505936)
			(xy 354.610566 -259.549002) (xy 354.574054 -259.58694) (xy 354.53218 -259.618859) (xy 354.485924 -259.644012)
			(xy 354.436371 -259.66181) (xy 354.384681 -259.671834) (xy 354.332067 -259.673851) (xy 354.279762 -259.667813)
			(xy 354.228991 -259.653861) (xy 354.180946 -259.632322) (xy 354.136751 -259.603702) (xy 354.097443 -259.568671)
			(xy 354.063943 -259.52805) (xy 354.037037 -259.482791) (xy 354.017354 -259.433956) (xy 354.005357 -259.382688)
			(xy 354.001327 -259.33019) (xy 320.242355 -259.33019) (xy 320.234622 -259.375287) (xy 320.202656 -259.514045)
			(xy 320.162892 -259.650772) (xy 320.134904 -259.729986) (xy 346.651329 -259.729986) (xy 346.655359 -259.677488)
			(xy 346.667356 -259.62622) (xy 346.687039 -259.577385) (xy 346.713945 -259.532126) (xy 346.747445 -259.491505)
			(xy 346.786753 -259.456474) (xy 346.830948 -259.427854) (xy 346.878993 -259.406315) (xy 346.929764 -259.392363)
			(xy 346.982069 -259.386325) (xy 347.034683 -259.388342) (xy 347.086373 -259.398366) (xy 347.135926 -259.416164)
			(xy 347.182182 -259.441317) (xy 347.224056 -259.473236) (xy 347.260568 -259.511174) (xy 347.29086 -259.55424)
			(xy 347.314223 -259.601425) (xy 347.330109 -259.651624) (xy 347.338146 -259.70366) (xy 347.33865 -259.729986)
			(xy 348.551249 -259.729986) (xy 348.555279 -259.677488) (xy 348.567276 -259.62622) (xy 348.586959 -259.577385)
			(xy 348.613865 -259.532126) (xy 348.647365 -259.491505) (xy 348.686673 -259.456474) (xy 348.730868 -259.427854)
			(xy 348.778913 -259.406315) (xy 348.829684 -259.392363) (xy 348.881989 -259.386325) (xy 348.934603 -259.388342)
			(xy 348.986293 -259.398366) (xy 349.035846 -259.416164) (xy 349.082102 -259.441317) (xy 349.123976 -259.473236)
			(xy 349.160488 -259.511174) (xy 349.19078 -259.55424) (xy 349.214143 -259.601425) (xy 349.230029 -259.651624)
			(xy 349.238066 -259.70366) (xy 349.23857 -259.729986) (xy 350.451169 -259.729986) (xy 350.455199 -259.677488)
			(xy 350.467196 -259.62622) (xy 350.486879 -259.577385) (xy 350.513785 -259.532126) (xy 350.547285 -259.491505)
			(xy 350.586593 -259.456474) (xy 350.630788 -259.427854) (xy 350.678833 -259.406315) (xy 350.729604 -259.392363)
			(xy 350.781909 -259.386325) (xy 350.834523 -259.388342) (xy 350.886213 -259.398366) (xy 350.935766 -259.416164)
			(xy 350.982022 -259.441317) (xy 351.023896 -259.473236) (xy 351.060408 -259.511174) (xy 351.0907 -259.55424)
			(xy 351.114063 -259.601425) (xy 351.129949 -259.651624) (xy 351.137986 -259.70366) (xy 351.13849 -259.729986)
			(xy 351.137986 -259.756312) (xy 351.129949 -259.808348) (xy 351.114063 -259.858547) (xy 351.0907 -259.905732)
			(xy 351.060408 -259.948798) (xy 351.023896 -259.986736) (xy 350.982022 -260.018655) (xy 350.935766 -260.043808)
			(xy 350.886213 -260.061606) (xy 350.834523 -260.07163) (xy 350.781909 -260.073647) (xy 350.729604 -260.067609)
			(xy 350.678833 -260.053657) (xy 350.630788 -260.032118) (xy 350.586593 -260.003498) (xy 350.547285 -259.968467)
			(xy 350.513785 -259.927846) (xy 350.486879 -259.882587) (xy 350.467196 -259.833752) (xy 350.455199 -259.782484)
			(xy 350.451169 -259.729986) (xy 349.23857 -259.729986) (xy 349.238066 -259.756312) (xy 349.230029 -259.808348)
			(xy 349.214143 -259.858547) (xy 349.19078 -259.905732) (xy 349.160488 -259.948798) (xy 349.123976 -259.986736)
			(xy 349.082102 -260.018655) (xy 349.035846 -260.043808) (xy 348.986293 -260.061606) (xy 348.934603 -260.07163)
			(xy 348.881989 -260.073647) (xy 348.829684 -260.067609) (xy 348.778913 -260.053657) (xy 348.730868 -260.032118)
			(xy 348.686673 -260.003498) (xy 348.647365 -259.968467) (xy 348.613865 -259.927846) (xy 348.586959 -259.882587)
			(xy 348.567276 -259.833752) (xy 348.555279 -259.782484) (xy 348.551249 -259.729986) (xy 347.33865 -259.729986)
			(xy 347.338146 -259.756312) (xy 347.330109 -259.808348) (xy 347.314223 -259.858547) (xy 347.29086 -259.905732)
			(xy 347.260568 -259.948798) (xy 347.224056 -259.986736) (xy 347.182182 -260.018655) (xy 347.135926 -260.043808)
			(xy 347.086373 -260.061606) (xy 347.034683 -260.07163) (xy 346.982069 -260.073647) (xy 346.929764 -260.067609)
			(xy 346.878993 -260.053657) (xy 346.830948 -260.032118) (xy 346.786753 -260.003498) (xy 346.747445 -259.968467)
			(xy 346.713945 -259.927846) (xy 346.687039 -259.882587) (xy 346.667356 -259.833752) (xy 346.655359 -259.782484)
			(xy 346.651329 -259.729986) (xy 320.134904 -259.729986) (xy 320.115455 -259.785031) (xy 320.060499 -259.91639)
			(xy 319.998199 -260.044431) (xy 319.928755 -260.168741) (xy 319.857964 -260.28015) (xy 354.001327 -260.28015)
			(xy 354.005357 -260.227652) (xy 354.017354 -260.176384) (xy 354.037037 -260.127549) (xy 354.063943 -260.08229)
			(xy 354.097443 -260.041669) (xy 354.136751 -260.006638) (xy 354.180946 -259.978018) (xy 354.228991 -259.956479)
			(xy 354.279762 -259.942527) (xy 354.332067 -259.936489) (xy 354.384681 -259.938506) (xy 354.436371 -259.94853)
			(xy 354.485924 -259.966328) (xy 354.53218 -259.991481) (xy 354.574054 -260.0234) (xy 354.610566 -260.061338)
			(xy 354.640858 -260.104404) (xy 354.664221 -260.151589) (xy 354.680107 -260.201788) (xy 354.688144 -260.253824)
			(xy 354.688648 -260.28015) (xy 354.688144 -260.306476) (xy 354.680107 -260.358512) (xy 354.664221 -260.408711)
			(xy 354.640858 -260.455896) (xy 354.610566 -260.498962) (xy 354.574054 -260.5369) (xy 354.53218 -260.568819)
			(xy 354.485924 -260.593972) (xy 354.436371 -260.61177) (xy 354.384681 -260.621794) (xy 354.332067 -260.623811)
			(xy 354.279762 -260.617773) (xy 354.228991 -260.603821) (xy 354.180946 -260.582282) (xy 354.136751 -260.553662)
			(xy 354.097443 -260.518631) (xy 354.063943 -260.47801) (xy 354.037037 -260.432751) (xy 354.017354 -260.383916)
			(xy 354.005357 -260.332648) (xy 354.001327 -260.28015) (xy 319.857964 -260.28015) (xy 319.852389 -260.288924)
			(xy 319.769347 -260.404593) (xy 319.679893 -260.515379) (xy 319.584315 -260.620927) (xy 319.482918 -260.720899)
			(xy 319.376028 -260.814974) (xy 319.263987 -260.902851) (xy 319.147154 -260.984249) (xy 319.025903 -261.058906)
			(xy 318.901759 -261.12597) (xy 326.345308 -261.12597) (xy 326.349268 -261.076916) (xy 326.361045 -261.029132)
			(xy 326.380336 -260.983856) (xy 326.406639 -260.94226) (xy 326.439274 -260.905423) (xy 326.477395 -260.874298)
			(xy 326.520016 -260.849691) (xy 326.566032 -260.832239) (xy 326.614251 -260.822395) (xy 326.663426 -260.820414)
			(xy 326.712281 -260.826346) (xy 326.759552 -260.840038) (xy 326.804014 -260.861136) (xy 326.844517 -260.889092)
			(xy 326.88001 -260.923184) (xy 326.909575 -260.962528) (xy 326.932446 -261.006105) (xy 326.94803 -261.052786)
			(xy 326.955925 -261.101363) (xy 326.95642 -261.12597) (xy 327.285362 -261.12597) (xy 327.289322 -261.076916)
			(xy 327.301099 -261.029132) (xy 327.32039 -260.983856) (xy 327.346693 -260.94226) (xy 327.379328 -260.905423)
			(xy 327.417449 -260.874298) (xy 327.46007 -260.849691) (xy 327.506086 -260.832239) (xy 327.554305 -260.822395)
			(xy 327.60348 -260.820414) (xy 327.652335 -260.826346) (xy 327.699606 -260.840038) (xy 327.744068 -260.861136)
			(xy 327.784571 -260.889092) (xy 327.820064 -260.923184) (xy 327.849629 -260.962528) (xy 327.8725 -261.006105)
			(xy 327.888084 -261.052786) (xy 327.895979 -261.101363) (xy 327.896474 -261.12597) (xy 329.165216 -261.12597)
			(xy 329.169176 -261.076916) (xy 329.180953 -261.029132) (xy 329.200244 -260.983856) (xy 329.226547 -260.94226)
			(xy 329.259182 -260.905423) (xy 329.297303 -260.874298) (xy 329.339924 -260.849691) (xy 329.38594 -260.832239)
			(xy 329.434159 -260.822395) (xy 329.483334 -260.820414) (xy 329.532189 -260.826346) (xy 329.57946 -260.840038)
			(xy 329.623922 -260.861136) (xy 329.664425 -260.889092) (xy 329.699918 -260.923184) (xy 329.729483 -260.962528)
			(xy 329.752354 -261.006105) (xy 329.767938 -261.052786) (xy 329.775833 -261.101363) (xy 329.776328 -261.12597)
			(xy 330.10527 -261.12597) (xy 330.10923 -261.076916) (xy 330.121007 -261.029132) (xy 330.140298 -260.983856)
			(xy 330.166601 -260.94226) (xy 330.199236 -260.905423) (xy 330.237357 -260.874298) (xy 330.279978 -260.849691)
			(xy 330.325994 -260.832239) (xy 330.374213 -260.822395) (xy 330.423388 -260.820414) (xy 330.472243 -260.826346)
			(xy 330.519514 -260.840038) (xy 330.563976 -260.861136) (xy 330.604479 -260.889092) (xy 330.639972 -260.923184)
			(xy 330.669537 -260.962528) (xy 330.692408 -261.006105) (xy 330.707992 -261.052786) (xy 330.715887 -261.101363)
			(xy 330.716382 -261.12597) (xy 331.045324 -261.12597) (xy 331.049284 -261.076916) (xy 331.061061 -261.029132)
			(xy 331.080352 -260.983856) (xy 331.106655 -260.94226) (xy 331.13929 -260.905423) (xy 331.177411 -260.874298)
			(xy 331.220032 -260.849691) (xy 331.266048 -260.832239) (xy 331.314267 -260.822395) (xy 331.363442 -260.820414)
			(xy 331.412297 -260.826346) (xy 331.459568 -260.840038) (xy 331.50403 -260.861136) (xy 331.544533 -260.889092)
			(xy 331.580026 -260.923184) (xy 331.609591 -260.962528) (xy 331.632462 -261.006105) (xy 331.648046 -261.052786)
			(xy 331.655941 -261.101363) (xy 331.656436 -261.12597) (xy 331.985378 -261.12597) (xy 331.989338 -261.076916)
			(xy 332.001115 -261.029132) (xy 332.020406 -260.983856) (xy 332.046709 -260.94226) (xy 332.079344 -260.905423)
			(xy 332.117465 -260.874298) (xy 332.160086 -260.849691) (xy 332.206102 -260.832239) (xy 332.254321 -260.822395)
			(xy 332.303496 -260.820414) (xy 332.352351 -260.826346) (xy 332.399622 -260.840038) (xy 332.444084 -260.861136)
			(xy 332.484587 -260.889092) (xy 332.52008 -260.923184) (xy 332.549645 -260.962528) (xy 332.572516 -261.006105)
			(xy 332.5881 -261.052786) (xy 332.595995 -261.101363) (xy 332.59649 -261.12597) (xy 332.925178 -261.12597)
			(xy 332.929138 -261.076916) (xy 332.940915 -261.029132) (xy 332.960206 -260.983856) (xy 332.986509 -260.94226)
			(xy 333.019144 -260.905423) (xy 333.057265 -260.874298) (xy 333.099886 -260.849691) (xy 333.145902 -260.832239)
			(xy 333.194121 -260.822395) (xy 333.243296 -260.820414) (xy 333.292151 -260.826346) (xy 333.339422 -260.840038)
			(xy 333.383884 -260.861136) (xy 333.424387 -260.889092) (xy 333.45988 -260.923184) (xy 333.489445 -260.962528)
			(xy 333.512316 -261.006105) (xy 333.5279 -261.052786) (xy 333.535795 -261.101363) (xy 333.53629 -261.12597)
			(xy 333.865232 -261.12597) (xy 333.869192 -261.076916) (xy 333.880969 -261.029132) (xy 333.90026 -260.983856)
			(xy 333.926563 -260.94226) (xy 333.959198 -260.905423) (xy 333.997319 -260.874298) (xy 334.03994 -260.849691)
			(xy 334.085956 -260.832239) (xy 334.134175 -260.822395) (xy 334.18335 -260.820414) (xy 334.232205 -260.826346)
			(xy 334.279476 -260.840038) (xy 334.323938 -260.861136) (xy 334.364441 -260.889092) (xy 334.399934 -260.923184)
			(xy 334.429499 -260.962528) (xy 334.45237 -261.006105) (xy 334.467954 -261.052786) (xy 334.475849 -261.101363)
			(xy 334.476344 -261.12597) (xy 335.74534 -261.12597) (xy 335.7493 -261.076916) (xy 335.761077 -261.029132)
			(xy 335.780368 -260.983856) (xy 335.806671 -260.94226) (xy 335.839306 -260.905423) (xy 335.877427 -260.874298)
			(xy 335.920048 -260.849691) (xy 335.966064 -260.832239) (xy 336.014283 -260.822395) (xy 336.063458 -260.820414)
			(xy 336.112313 -260.826346) (xy 336.159584 -260.840038) (xy 336.204046 -260.861136) (xy 336.244549 -260.889092)
			(xy 336.280042 -260.923184) (xy 336.309607 -260.962528) (xy 336.332478 -261.006105) (xy 336.348062 -261.052786)
			(xy 336.355957 -261.101363) (xy 336.356452 -261.12597) (xy 336.685394 -261.12597) (xy 336.689354 -261.076916)
			(xy 336.701131 -261.029132) (xy 336.720422 -260.983856) (xy 336.746725 -260.94226) (xy 336.77936 -260.905423)
			(xy 336.817481 -260.874298) (xy 336.860102 -260.849691) (xy 336.906118 -260.832239) (xy 336.954337 -260.822395)
			(xy 337.003512 -260.820414) (xy 337.052367 -260.826346) (xy 337.099638 -260.840038) (xy 337.1441 -260.861136)
			(xy 337.184603 -260.889092) (xy 337.220096 -260.923184) (xy 337.249661 -260.962528) (xy 337.272532 -261.006105)
			(xy 337.288116 -261.052786) (xy 337.296011 -261.101363) (xy 337.296506 -261.12597) (xy 337.625194 -261.12597)
			(xy 337.629154 -261.076916) (xy 337.640931 -261.029132) (xy 337.660222 -260.983856) (xy 337.686525 -260.94226)
			(xy 337.71916 -260.905423) (xy 337.757281 -260.874298) (xy 337.799902 -260.849691) (xy 337.845918 -260.832239)
			(xy 337.894137 -260.822395) (xy 337.943312 -260.820414) (xy 337.992167 -260.826346) (xy 338.039438 -260.840038)
			(xy 338.0839 -260.861136) (xy 338.124403 -260.889092) (xy 338.159896 -260.923184) (xy 338.189461 -260.962528)
			(xy 338.212332 -261.006105) (xy 338.227916 -261.052786) (xy 338.235811 -261.101363) (xy 338.236306 -261.12597)
			(xy 338.565248 -261.12597) (xy 338.569208 -261.076916) (xy 338.580985 -261.029132) (xy 338.600276 -260.983856)
			(xy 338.626579 -260.94226) (xy 338.659214 -260.905423) (xy 338.697335 -260.874298) (xy 338.739956 -260.849691)
			(xy 338.785972 -260.832239) (xy 338.834191 -260.822395) (xy 338.883366 -260.820414) (xy 338.932221 -260.826346)
			(xy 338.979492 -260.840038) (xy 339.023954 -260.861136) (xy 339.064457 -260.889092) (xy 339.09995 -260.923184)
			(xy 339.129515 -260.962528) (xy 339.152386 -261.006105) (xy 339.16797 -261.052786) (xy 339.175865 -261.101363)
			(xy 339.17636 -261.12597) (xy 339.505302 -261.12597) (xy 339.509262 -261.076916) (xy 339.521039 -261.029132)
			(xy 339.54033 -260.983856) (xy 339.566633 -260.94226) (xy 339.599268 -260.905423) (xy 339.637389 -260.874298)
			(xy 339.68001 -260.849691) (xy 339.726026 -260.832239) (xy 339.774245 -260.822395) (xy 339.82342 -260.820414)
			(xy 339.872275 -260.826346) (xy 339.919546 -260.840038) (xy 339.964008 -260.861136) (xy 340.004511 -260.889092)
			(xy 340.040004 -260.923184) (xy 340.069569 -260.962528) (xy 340.09244 -261.006105) (xy 340.108024 -261.052786)
			(xy 340.115919 -261.101363) (xy 340.116414 -261.12597) (xy 340.445356 -261.12597) (xy 340.449316 -261.076916)
			(xy 340.461093 -261.029132) (xy 340.480384 -260.983856) (xy 340.506687 -260.94226) (xy 340.539322 -260.905423)
			(xy 340.577443 -260.874298) (xy 340.620064 -260.849691) (xy 340.66608 -260.832239) (xy 340.714299 -260.822395)
			(xy 340.763474 -260.820414) (xy 340.812329 -260.826346) (xy 340.8596 -260.840038) (xy 340.904062 -260.861136)
			(xy 340.944565 -260.889092) (xy 340.980058 -260.923184) (xy 341.009623 -260.962528) (xy 341.032494 -261.006105)
			(xy 341.048078 -261.052786) (xy 341.055973 -261.101363) (xy 341.056468 -261.12597) (xy 342.32521 -261.12597)
			(xy 342.32917 -261.076916) (xy 342.340947 -261.029132) (xy 342.360238 -260.983856) (xy 342.386541 -260.94226)
			(xy 342.419176 -260.905423) (xy 342.457297 -260.874298) (xy 342.499918 -260.849691) (xy 342.545934 -260.832239)
			(xy 342.594153 -260.822395) (xy 342.643328 -260.820414) (xy 342.692183 -260.826346) (xy 342.739454 -260.840038)
			(xy 342.783916 -260.861136) (xy 342.824419 -260.889092) (xy 342.859912 -260.923184) (xy 342.889477 -260.962528)
			(xy 342.912348 -261.006105) (xy 342.927932 -261.052786) (xy 342.935827 -261.101363) (xy 342.936322 -261.12597)
			(xy 343.265264 -261.12597) (xy 343.269224 -261.076916) (xy 343.281001 -261.029132) (xy 343.300292 -260.983856)
			(xy 343.326595 -260.94226) (xy 343.35923 -260.905423) (xy 343.397351 -260.874298) (xy 343.439972 -260.849691)
			(xy 343.485988 -260.832239) (xy 343.534207 -260.822395) (xy 343.583382 -260.820414) (xy 343.632237 -260.826346)
			(xy 343.679508 -260.840038) (xy 343.72397 -260.861136) (xy 343.764473 -260.889092) (xy 343.799966 -260.923184)
			(xy 343.829531 -260.962528) (xy 343.852402 -261.006105) (xy 343.867986 -261.052786) (xy 343.875881 -261.101363)
			(xy 343.876376 -261.12597) (xy 344.205318 -261.12597) (xy 344.209278 -261.076916) (xy 344.221055 -261.029132)
			(xy 344.240346 -260.983856) (xy 344.266649 -260.94226) (xy 344.299284 -260.905423) (xy 344.337405 -260.874298)
			(xy 344.380026 -260.849691) (xy 344.426042 -260.832239) (xy 344.474261 -260.822395) (xy 344.523436 -260.820414)
			(xy 344.572291 -260.826346) (xy 344.619562 -260.840038) (xy 344.664024 -260.861136) (xy 344.704527 -260.889092)
			(xy 344.74002 -260.923184) (xy 344.769585 -260.962528) (xy 344.792456 -261.006105) (xy 344.80804 -261.052786)
			(xy 344.815935 -261.101363) (xy 344.81643 -261.12597) (xy 346.085426 -261.12597) (xy 346.089386 -261.076916)
			(xy 346.101163 -261.029132) (xy 346.120454 -260.983856) (xy 346.146757 -260.94226) (xy 346.179392 -260.905423)
			(xy 346.217513 -260.874298) (xy 346.260134 -260.849691) (xy 346.30615 -260.832239) (xy 346.354369 -260.822395)
			(xy 346.403544 -260.820414) (xy 346.452399 -260.826346) (xy 346.49967 -260.840038) (xy 346.544132 -260.861136)
			(xy 346.584635 -260.889092) (xy 346.620128 -260.923184) (xy 346.649693 -260.962528) (xy 346.672564 -261.006105)
			(xy 346.688148 -261.052786) (xy 346.696043 -261.101363) (xy 346.696538 -261.12597) (xy 347.96528 -261.12597)
			(xy 347.96924 -261.076916) (xy 347.981017 -261.029132) (xy 348.000308 -260.983856) (xy 348.026611 -260.94226)
			(xy 348.059246 -260.905423) (xy 348.097367 -260.874298) (xy 348.139988 -260.849691) (xy 348.186004 -260.832239)
			(xy 348.234223 -260.822395) (xy 348.283398 -260.820414) (xy 348.332253 -260.826346) (xy 348.379524 -260.840038)
			(xy 348.423986 -260.861136) (xy 348.464489 -260.889092) (xy 348.499982 -260.923184) (xy 348.529547 -260.962528)
			(xy 348.552418 -261.006105) (xy 348.568002 -261.052786) (xy 348.575897 -261.101363) (xy 348.576392 -261.12597)
			(xy 348.905334 -261.12597) (xy 348.909294 -261.076916) (xy 348.921071 -261.029132) (xy 348.940362 -260.983856)
			(xy 348.966665 -260.94226) (xy 348.9993 -260.905423) (xy 349.037421 -260.874298) (xy 349.080042 -260.849691)
			(xy 349.126058 -260.832239) (xy 349.174277 -260.822395) (xy 349.223452 -260.820414) (xy 349.272307 -260.826346)
			(xy 349.319578 -260.840038) (xy 349.36404 -260.861136) (xy 349.404543 -260.889092) (xy 349.440036 -260.923184)
			(xy 349.469601 -260.962528) (xy 349.492472 -261.006105) (xy 349.508056 -261.052786) (xy 349.515951 -261.101363)
			(xy 349.516446 -261.12597) (xy 349.845388 -261.12597) (xy 349.849348 -261.076916) (xy 349.861125 -261.029132)
			(xy 349.880416 -260.983856) (xy 349.906719 -260.94226) (xy 349.939354 -260.905423) (xy 349.977475 -260.874298)
			(xy 350.020096 -260.849691) (xy 350.066112 -260.832239) (xy 350.114331 -260.822395) (xy 350.163506 -260.820414)
			(xy 350.212361 -260.826346) (xy 350.259632 -260.840038) (xy 350.304094 -260.861136) (xy 350.344597 -260.889092)
			(xy 350.38009 -260.923184) (xy 350.409655 -260.962528) (xy 350.432526 -261.006105) (xy 350.44811 -261.052786)
			(xy 350.456005 -261.101363) (xy 350.4565 -261.12597) (xy 350.456459 -261.128002) (xy 350.78214 -261.128002)
			(xy 350.7861 -261.078948) (xy 350.797877 -261.031164) (xy 350.817168 -260.985888) (xy 350.843471 -260.944292)
			(xy 350.876106 -260.907455) (xy 350.914227 -260.87633) (xy 350.956848 -260.851723) (xy 351.002864 -260.834271)
			(xy 351.051083 -260.824427) (xy 351.100258 -260.822446) (xy 351.149113 -260.828378) (xy 351.196384 -260.84207)
			(xy 351.240846 -260.863168) (xy 351.281349 -260.891124) (xy 351.316842 -260.925216) (xy 351.346407 -260.96456)
			(xy 351.369278 -261.008137) (xy 351.384862 -261.054818) (xy 351.392757 -261.103395) (xy 351.393252 -261.128002)
			(xy 351.722194 -261.128002) (xy 351.726154 -261.078948) (xy 351.737931 -261.031164) (xy 351.757222 -260.985888)
			(xy 351.783525 -260.944292) (xy 351.81616 -260.907455) (xy 351.854281 -260.87633) (xy 351.896902 -260.851723)
			(xy 351.942918 -260.834271) (xy 351.991137 -260.824427) (xy 352.040312 -260.822446) (xy 352.089167 -260.828378)
			(xy 352.136438 -260.84207) (xy 352.1809 -260.863168) (xy 352.221403 -260.891124) (xy 352.256896 -260.925216)
			(xy 352.286461 -260.96456) (xy 352.309332 -261.008137) (xy 352.324916 -261.054818) (xy 352.332811 -261.103395)
			(xy 352.333306 -261.128002) (xy 352.332811 -261.152609) (xy 352.324916 -261.201186) (xy 352.31526 -261.23011)
			(xy 354.001327 -261.23011) (xy 354.005357 -261.177612) (xy 354.017354 -261.126344) (xy 354.037037 -261.077509)
			(xy 354.063943 -261.03225) (xy 354.097443 -260.991629) (xy 354.136751 -260.956598) (xy 354.180946 -260.927978)
			(xy 354.228991 -260.906439) (xy 354.279762 -260.892487) (xy 354.332067 -260.886449) (xy 354.384681 -260.888466)
			(xy 354.436371 -260.89849) (xy 354.485924 -260.916288) (xy 354.53218 -260.941441) (xy 354.574054 -260.97336)
			(xy 354.610566 -261.011298) (xy 354.640858 -261.054364) (xy 354.664221 -261.101549) (xy 354.680107 -261.151748)
			(xy 354.688144 -261.203784) (xy 354.688648 -261.23011) (xy 354.688144 -261.256436) (xy 354.680107 -261.308472)
			(xy 354.664221 -261.358671) (xy 354.640858 -261.405856) (xy 354.610566 -261.448922) (xy 354.574054 -261.48686)
			(xy 354.53218 -261.518779) (xy 354.485924 -261.543932) (xy 354.436371 -261.56173) (xy 354.384681 -261.571754)
			(xy 354.332067 -261.573771) (xy 354.279762 -261.567733) (xy 354.228991 -261.553781) (xy 354.180946 -261.532242)
			(xy 354.136751 -261.503622) (xy 354.097443 -261.468591) (xy 354.063943 -261.42797) (xy 354.037037 -261.382711)
			(xy 354.017354 -261.333876) (xy 354.005357 -261.282608) (xy 354.001327 -261.23011) (xy 352.31526 -261.23011)
			(xy 352.309332 -261.247867) (xy 352.286461 -261.291444) (xy 352.256896 -261.330788) (xy 352.221403 -261.36488)
			(xy 352.1809 -261.392836) (xy 352.136438 -261.413934) (xy 352.089167 -261.427626) (xy 352.040312 -261.433558)
			(xy 351.991137 -261.431577) (xy 351.942918 -261.421733) (xy 351.896902 -261.404281) (xy 351.854281 -261.379674)
			(xy 351.81616 -261.348549) (xy 351.783525 -261.311712) (xy 351.757222 -261.270116) (xy 351.737931 -261.22484)
			(xy 351.726154 -261.177056) (xy 351.722194 -261.128002) (xy 351.393252 -261.128002) (xy 351.392757 -261.152609)
			(xy 351.384862 -261.201186) (xy 351.369278 -261.247867) (xy 351.346407 -261.291444) (xy 351.316842 -261.330788)
			(xy 351.281349 -261.36488) (xy 351.240846 -261.392836) (xy 351.196384 -261.413934) (xy 351.149113 -261.427626)
			(xy 351.100258 -261.433558) (xy 351.051083 -261.431577) (xy 351.002864 -261.421733) (xy 350.956848 -261.404281)
			(xy 350.914227 -261.379674) (xy 350.876106 -261.348549) (xy 350.843471 -261.311712) (xy 350.817168 -261.270116)
			(xy 350.797877 -261.22484) (xy 350.7861 -261.177056) (xy 350.78214 -261.128002) (xy 350.456459 -261.128002)
			(xy 350.456005 -261.150577) (xy 350.44811 -261.199154) (xy 350.432526 -261.245835) (xy 350.409655 -261.289412)
			(xy 350.38009 -261.328756) (xy 350.344597 -261.362848) (xy 350.304094 -261.390804) (xy 350.259632 -261.411902)
			(xy 350.212361 -261.425594) (xy 350.163506 -261.431526) (xy 350.114331 -261.429545) (xy 350.066112 -261.419701)
			(xy 350.020096 -261.402249) (xy 349.977475 -261.377642) (xy 349.939354 -261.346517) (xy 349.906719 -261.30968)
			(xy 349.880416 -261.268084) (xy 349.861125 -261.222808) (xy 349.849348 -261.175024) (xy 349.845388 -261.12597)
			(xy 349.516446 -261.12597) (xy 349.515951 -261.150577) (xy 349.508056 -261.199154) (xy 349.492472 -261.245835)
			(xy 349.469601 -261.289412) (xy 349.440036 -261.328756) (xy 349.404543 -261.362848) (xy 349.36404 -261.390804)
			(xy 349.319578 -261.411902) (xy 349.272307 -261.425594) (xy 349.223452 -261.431526) (xy 349.174277 -261.429545)
			(xy 349.126058 -261.419701) (xy 349.080042 -261.402249) (xy 349.037421 -261.377642) (xy 348.9993 -261.346517)
			(xy 348.966665 -261.30968) (xy 348.940362 -261.268084) (xy 348.921071 -261.222808) (xy 348.909294 -261.175024)
			(xy 348.905334 -261.12597) (xy 348.576392 -261.12597) (xy 348.575897 -261.150577) (xy 348.568002 -261.199154)
			(xy 348.552418 -261.245835) (xy 348.529547 -261.289412) (xy 348.499982 -261.328756) (xy 348.464489 -261.362848)
			(xy 348.423986 -261.390804) (xy 348.379524 -261.411902) (xy 348.332253 -261.425594) (xy 348.283398 -261.431526)
			(xy 348.234223 -261.429545) (xy 348.186004 -261.419701) (xy 348.139988 -261.402249) (xy 348.097367 -261.377642)
			(xy 348.059246 -261.346517) (xy 348.026611 -261.30968) (xy 348.000308 -261.268084) (xy 347.981017 -261.222808)
			(xy 347.96924 -261.175024) (xy 347.96528 -261.12597) (xy 346.696538 -261.12597) (xy 346.696043 -261.150577)
			(xy 346.688148 -261.199154) (xy 346.672564 -261.245835) (xy 346.649693 -261.289412) (xy 346.620128 -261.328756)
			(xy 346.584635 -261.362848) (xy 346.544132 -261.390804) (xy 346.49967 -261.411902) (xy 346.452399 -261.425594)
			(xy 346.403544 -261.431526) (xy 346.354369 -261.429545) (xy 346.30615 -261.419701) (xy 346.260134 -261.402249)
			(xy 346.217513 -261.377642) (xy 346.179392 -261.346517) (xy 346.146757 -261.30968) (xy 346.120454 -261.268084)
			(xy 346.101163 -261.222808) (xy 346.089386 -261.175024) (xy 346.085426 -261.12597) (xy 344.81643 -261.12597)
			(xy 344.815935 -261.150577) (xy 344.80804 -261.199154) (xy 344.792456 -261.245835) (xy 344.769585 -261.289412)
			(xy 344.74002 -261.328756) (xy 344.704527 -261.362848) (xy 344.664024 -261.390804) (xy 344.619562 -261.411902)
			(xy 344.572291 -261.425594) (xy 344.523436 -261.431526) (xy 344.474261 -261.429545) (xy 344.426042 -261.419701)
			(xy 344.380026 -261.402249) (xy 344.337405 -261.377642) (xy 344.299284 -261.346517) (xy 344.266649 -261.30968)
			(xy 344.240346 -261.268084) (xy 344.221055 -261.222808) (xy 344.209278 -261.175024) (xy 344.205318 -261.12597)
			(xy 343.876376 -261.12597) (xy 343.875881 -261.150577) (xy 343.867986 -261.199154) (xy 343.852402 -261.245835)
			(xy 343.829531 -261.289412) (xy 343.799966 -261.328756) (xy 343.764473 -261.362848) (xy 343.72397 -261.390804)
			(xy 343.679508 -261.411902) (xy 343.632237 -261.425594) (xy 343.583382 -261.431526) (xy 343.534207 -261.429545)
			(xy 343.485988 -261.419701) (xy 343.439972 -261.402249) (xy 343.397351 -261.377642) (xy 343.35923 -261.346517)
			(xy 343.326595 -261.30968) (xy 343.300292 -261.268084) (xy 343.281001 -261.222808) (xy 343.269224 -261.175024)
			(xy 343.265264 -261.12597) (xy 342.936322 -261.12597) (xy 342.935827 -261.150577) (xy 342.927932 -261.199154)
			(xy 342.912348 -261.245835) (xy 342.889477 -261.289412) (xy 342.859912 -261.328756) (xy 342.824419 -261.362848)
			(xy 342.783916 -261.390804) (xy 342.739454 -261.411902) (xy 342.692183 -261.425594) (xy 342.643328 -261.431526)
			(xy 342.594153 -261.429545) (xy 342.545934 -261.419701) (xy 342.499918 -261.402249) (xy 342.457297 -261.377642)
			(xy 342.419176 -261.346517) (xy 342.386541 -261.30968) (xy 342.360238 -261.268084) (xy 342.340947 -261.222808)
			(xy 342.32917 -261.175024) (xy 342.32521 -261.12597) (xy 341.056468 -261.12597) (xy 341.055973 -261.150577)
			(xy 341.048078 -261.199154) (xy 341.032494 -261.245835) (xy 341.009623 -261.289412) (xy 340.980058 -261.328756)
			(xy 340.944565 -261.362848) (xy 340.904062 -261.390804) (xy 340.8596 -261.411902) (xy 340.812329 -261.425594)
			(xy 340.763474 -261.431526) (xy 340.714299 -261.429545) (xy 340.66608 -261.419701) (xy 340.620064 -261.402249)
			(xy 340.577443 -261.377642) (xy 340.539322 -261.346517) (xy 340.506687 -261.30968) (xy 340.480384 -261.268084)
			(xy 340.461093 -261.222808) (xy 340.449316 -261.175024) (xy 340.445356 -261.12597) (xy 340.116414 -261.12597)
			(xy 340.115919 -261.150577) (xy 340.108024 -261.199154) (xy 340.09244 -261.245835) (xy 340.069569 -261.289412)
			(xy 340.040004 -261.328756) (xy 340.004511 -261.362848) (xy 339.964008 -261.390804) (xy 339.919546 -261.411902)
			(xy 339.872275 -261.425594) (xy 339.82342 -261.431526) (xy 339.774245 -261.429545) (xy 339.726026 -261.419701)
			(xy 339.68001 -261.402249) (xy 339.637389 -261.377642) (xy 339.599268 -261.346517) (xy 339.566633 -261.30968)
			(xy 339.54033 -261.268084) (xy 339.521039 -261.222808) (xy 339.509262 -261.175024) (xy 339.505302 -261.12597)
			(xy 339.17636 -261.12597) (xy 339.175865 -261.150577) (xy 339.16797 -261.199154) (xy 339.152386 -261.245835)
			(xy 339.129515 -261.289412) (xy 339.09995 -261.328756) (xy 339.064457 -261.362848) (xy 339.023954 -261.390804)
			(xy 338.979492 -261.411902) (xy 338.932221 -261.425594) (xy 338.883366 -261.431526) (xy 338.834191 -261.429545)
			(xy 338.785972 -261.419701) (xy 338.739956 -261.402249) (xy 338.697335 -261.377642) (xy 338.659214 -261.346517)
			(xy 338.626579 -261.30968) (xy 338.600276 -261.268084) (xy 338.580985 -261.222808) (xy 338.569208 -261.175024)
			(xy 338.565248 -261.12597) (xy 338.236306 -261.12597) (xy 338.235811 -261.150577) (xy 338.227916 -261.199154)
			(xy 338.212332 -261.245835) (xy 338.189461 -261.289412) (xy 338.159896 -261.328756) (xy 338.124403 -261.362848)
			(xy 338.0839 -261.390804) (xy 338.039438 -261.411902) (xy 337.992167 -261.425594) (xy 337.943312 -261.431526)
			(xy 337.894137 -261.429545) (xy 337.845918 -261.419701) (xy 337.799902 -261.402249) (xy 337.757281 -261.377642)
			(xy 337.71916 -261.346517) (xy 337.686525 -261.30968) (xy 337.660222 -261.268084) (xy 337.640931 -261.222808)
			(xy 337.629154 -261.175024) (xy 337.625194 -261.12597) (xy 337.296506 -261.12597) (xy 337.296011 -261.150577)
			(xy 337.288116 -261.199154) (xy 337.272532 -261.245835) (xy 337.249661 -261.289412) (xy 337.220096 -261.328756)
			(xy 337.184603 -261.362848) (xy 337.1441 -261.390804) (xy 337.099638 -261.411902) (xy 337.052367 -261.425594)
			(xy 337.003512 -261.431526) (xy 336.954337 -261.429545) (xy 336.906118 -261.419701) (xy 336.860102 -261.402249)
			(xy 336.817481 -261.377642) (xy 336.77936 -261.346517) (xy 336.746725 -261.30968) (xy 336.720422 -261.268084)
			(xy 336.701131 -261.222808) (xy 336.689354 -261.175024) (xy 336.685394 -261.12597) (xy 336.356452 -261.12597)
			(xy 336.355957 -261.150577) (xy 336.348062 -261.199154) (xy 336.332478 -261.245835) (xy 336.309607 -261.289412)
			(xy 336.280042 -261.328756) (xy 336.244549 -261.362848) (xy 336.204046 -261.390804) (xy 336.159584 -261.411902)
			(xy 336.112313 -261.425594) (xy 336.063458 -261.431526) (xy 336.014283 -261.429545) (xy 335.966064 -261.419701)
			(xy 335.920048 -261.402249) (xy 335.877427 -261.377642) (xy 335.839306 -261.346517) (xy 335.806671 -261.30968)
			(xy 335.780368 -261.268084) (xy 335.761077 -261.222808) (xy 335.7493 -261.175024) (xy 335.74534 -261.12597)
			(xy 334.476344 -261.12597) (xy 334.475849 -261.150577) (xy 334.467954 -261.199154) (xy 334.45237 -261.245835)
			(xy 334.429499 -261.289412) (xy 334.399934 -261.328756) (xy 334.364441 -261.362848) (xy 334.323938 -261.390804)
			(xy 334.279476 -261.411902) (xy 334.232205 -261.425594) (xy 334.18335 -261.431526) (xy 334.134175 -261.429545)
			(xy 334.085956 -261.419701) (xy 334.03994 -261.402249) (xy 333.997319 -261.377642) (xy 333.959198 -261.346517)
			(xy 333.926563 -261.30968) (xy 333.90026 -261.268084) (xy 333.880969 -261.222808) (xy 333.869192 -261.175024)
			(xy 333.865232 -261.12597) (xy 333.53629 -261.12597) (xy 333.535795 -261.150577) (xy 333.5279 -261.199154)
			(xy 333.512316 -261.245835) (xy 333.489445 -261.289412) (xy 333.45988 -261.328756) (xy 333.424387 -261.362848)
			(xy 333.383884 -261.390804) (xy 333.339422 -261.411902) (xy 333.292151 -261.425594) (xy 333.243296 -261.431526)
			(xy 333.194121 -261.429545) (xy 333.145902 -261.419701) (xy 333.099886 -261.402249) (xy 333.057265 -261.377642)
			(xy 333.019144 -261.346517) (xy 332.986509 -261.30968) (xy 332.960206 -261.268084) (xy 332.940915 -261.222808)
			(xy 332.929138 -261.175024) (xy 332.925178 -261.12597) (xy 332.59649 -261.12597) (xy 332.595995 -261.150577)
			(xy 332.5881 -261.199154) (xy 332.572516 -261.245835) (xy 332.549645 -261.289412) (xy 332.52008 -261.328756)
			(xy 332.484587 -261.362848) (xy 332.444084 -261.390804) (xy 332.399622 -261.411902) (xy 332.352351 -261.425594)
			(xy 332.303496 -261.431526) (xy 332.254321 -261.429545) (xy 332.206102 -261.419701) (xy 332.160086 -261.402249)
			(xy 332.117465 -261.377642) (xy 332.079344 -261.346517) (xy 332.046709 -261.30968) (xy 332.020406 -261.268084)
			(xy 332.001115 -261.222808) (xy 331.989338 -261.175024) (xy 331.985378 -261.12597) (xy 331.656436 -261.12597)
			(xy 331.655941 -261.150577) (xy 331.648046 -261.199154) (xy 331.632462 -261.245835) (xy 331.609591 -261.289412)
			(xy 331.580026 -261.328756) (xy 331.544533 -261.362848) (xy 331.50403 -261.390804) (xy 331.459568 -261.411902)
			(xy 331.412297 -261.425594) (xy 331.363442 -261.431526) (xy 331.314267 -261.429545) (xy 331.266048 -261.419701)
			(xy 331.220032 -261.402249) (xy 331.177411 -261.377642) (xy 331.13929 -261.346517) (xy 331.106655 -261.30968)
			(xy 331.080352 -261.268084) (xy 331.061061 -261.222808) (xy 331.049284 -261.175024) (xy 331.045324 -261.12597)
			(xy 330.716382 -261.12597) (xy 330.715887 -261.150577) (xy 330.707992 -261.199154) (xy 330.692408 -261.245835)
			(xy 330.669537 -261.289412) (xy 330.639972 -261.328756) (xy 330.604479 -261.362848) (xy 330.563976 -261.390804)
			(xy 330.519514 -261.411902) (xy 330.472243 -261.425594) (xy 330.423388 -261.431526) (xy 330.374213 -261.429545)
			(xy 330.325994 -261.419701) (xy 330.279978 -261.402249) (xy 330.237357 -261.377642) (xy 330.199236 -261.346517)
			(xy 330.166601 -261.30968) (xy 330.140298 -261.268084) (xy 330.121007 -261.222808) (xy 330.10923 -261.175024)
			(xy 330.10527 -261.12597) (xy 329.776328 -261.12597) (xy 329.775833 -261.150577) (xy 329.767938 -261.199154)
			(xy 329.752354 -261.245835) (xy 329.729483 -261.289412) (xy 329.699918 -261.328756) (xy 329.664425 -261.362848)
			(xy 329.623922 -261.390804) (xy 329.57946 -261.411902) (xy 329.532189 -261.425594) (xy 329.483334 -261.431526)
			(xy 329.434159 -261.429545) (xy 329.38594 -261.419701) (xy 329.339924 -261.402249) (xy 329.297303 -261.377642)
			(xy 329.259182 -261.346517) (xy 329.226547 -261.30968) (xy 329.200244 -261.268084) (xy 329.180953 -261.222808)
			(xy 329.169176 -261.175024) (xy 329.165216 -261.12597) (xy 327.896474 -261.12597) (xy 327.895979 -261.150577)
			(xy 327.888084 -261.199154) (xy 327.8725 -261.245835) (xy 327.849629 -261.289412) (xy 327.820064 -261.328756)
			(xy 327.784571 -261.362848) (xy 327.744068 -261.390804) (xy 327.699606 -261.411902) (xy 327.652335 -261.425594)
			(xy 327.60348 -261.431526) (xy 327.554305 -261.429545) (xy 327.506086 -261.419701) (xy 327.46007 -261.402249)
			(xy 327.417449 -261.377642) (xy 327.379328 -261.346517) (xy 327.346693 -261.30968) (xy 327.32039 -261.268084)
			(xy 327.301099 -261.222808) (xy 327.289322 -261.175024) (xy 327.285362 -261.12597) (xy 326.95642 -261.12597)
			(xy 326.955925 -261.150577) (xy 326.94803 -261.199154) (xy 326.932446 -261.245835) (xy 326.909575 -261.289412)
			(xy 326.88001 -261.328756) (xy 326.844517 -261.362848) (xy 326.804014 -261.390804) (xy 326.759552 -261.411902)
			(xy 326.712281 -261.425594) (xy 326.663426 -261.431526) (xy 326.614251 -261.429545) (xy 326.566032 -261.419701)
			(xy 326.520016 -261.402249) (xy 326.477395 -261.377642) (xy 326.439274 -261.346517) (xy 326.406639 -261.30968)
			(xy 326.380336 -261.268084) (xy 326.361045 -261.222808) (xy 326.349268 -261.175024) (xy 326.345308 -261.12597)
			(xy 318.901759 -261.12597) (xy 318.900622 -261.126584) (xy 318.771713 -261.187066) (xy 318.639589 -261.240157)
			(xy 318.504673 -261.285689) (xy 318.367397 -261.323515) (xy 318.2282 -261.353515) (xy 318.08753 -261.375591)
			(xy 317.945836 -261.389673) (xy 317.803572 -261.395716) (xy 317.661194 -261.393701) (xy 317.519158 -261.383634)
			(xy 317.377919 -261.365548) (xy 317.237929 -261.3395) (xy 317.099638 -261.305574) (xy 316.963487 -261.263878)
			(xy 316.829913 -261.214546) (xy 316.699344 -261.157737) (xy 316.572198 -261.093631) (xy 316.448883 -261.022435)
			(xy 316.329793 -260.944377) (xy 316.21531 -260.859705) (xy 316.105801 -260.768693) (xy 316.001616 -260.671631)
			(xy 315.903089 -260.56883) (xy 315.810536 -260.460619) (xy 315.724254 -260.347346) (xy 315.644517 -260.229373)
			(xy 315.571583 -260.107077) (xy 315.505685 -259.980851) (xy 315.447034 -259.851099) (xy 315.395817 -259.718237)
			(xy 315.352199 -259.58269) (xy 315.316319 -259.444892) (xy 315.288292 -259.305285) (xy 315.268209 -259.164317)
			(xy 315.256134 -259.022437) (xy 315.252104 -258.880102) (xy 310.45912 -258.880102) (xy 310.45912 -261.670038)
			(xy 324.74714 -261.670038) (xy 324.7511 -261.620984) (xy 324.762877 -261.5732) (xy 324.782168 -261.527924)
			(xy 324.808471 -261.486328) (xy 324.841106 -261.449491) (xy 324.879227 -261.418366) (xy 324.921848 -261.393759)
			(xy 324.967864 -261.376307) (xy 325.016083 -261.366463) (xy 325.065258 -261.364482) (xy 325.114113 -261.370414)
			(xy 325.161384 -261.384106) (xy 325.205846 -261.405204) (xy 325.246349 -261.43316) (xy 325.281842 -261.467252)
			(xy 325.311407 -261.506596) (xy 325.334278 -261.550173) (xy 325.349862 -261.596854) (xy 325.357757 -261.645431)
			(xy 325.358252 -261.670038) (xy 325.357757 -261.694645) (xy 325.349862 -261.743222) (xy 325.334278 -261.789903)
			(xy 325.311407 -261.83348) (xy 325.281842 -261.872824) (xy 325.246349 -261.906916) (xy 325.205846 -261.934872)
			(xy 325.203519 -261.935976) (xy 327.755262 -261.935976) (xy 327.759222 -261.886922) (xy 327.770999 -261.839138)
			(xy 327.79029 -261.793862) (xy 327.816593 -261.752266) (xy 327.849228 -261.715429) (xy 327.887349 -261.684304)
			(xy 327.92997 -261.659697) (xy 327.975986 -261.642245) (xy 328.024205 -261.632401) (xy 328.07338 -261.63042)
			(xy 328.122235 -261.636352) (xy 328.169506 -261.650044) (xy 328.213968 -261.671142) (xy 328.254471 -261.699098)
			(xy 328.289964 -261.73319) (xy 328.319529 -261.772534) (xy 328.3424 -261.816111) (xy 328.357984 -261.862792)
			(xy 328.365879 -261.911369) (xy 328.366374 -261.935976) (xy 328.695316 -261.935976) (xy 328.699276 -261.886922)
			(xy 328.711053 -261.839138) (xy 328.730344 -261.793862) (xy 328.756647 -261.752266) (xy 328.789282 -261.715429)
			(xy 328.827403 -261.684304) (xy 328.870024 -261.659697) (xy 328.91604 -261.642245) (xy 328.964259 -261.632401)
			(xy 329.013434 -261.63042) (xy 329.062289 -261.636352) (xy 329.10956 -261.650044) (xy 329.154022 -261.671142)
			(xy 329.194525 -261.699098) (xy 329.230018 -261.73319) (xy 329.259583 -261.772534) (xy 329.282454 -261.816111)
			(xy 329.298038 -261.862792) (xy 329.305933 -261.911369) (xy 329.306428 -261.935976) (xy 329.63537 -261.935976)
			(xy 329.63933 -261.886922) (xy 329.651107 -261.839138) (xy 329.670398 -261.793862) (xy 329.696701 -261.752266)
			(xy 329.729336 -261.715429) (xy 329.767457 -261.684304) (xy 329.810078 -261.659697) (xy 329.856094 -261.642245)
			(xy 329.904313 -261.632401) (xy 329.953488 -261.63042) (xy 330.002343 -261.636352) (xy 330.049614 -261.650044)
			(xy 330.094076 -261.671142) (xy 330.134579 -261.699098) (xy 330.170072 -261.73319) (xy 330.199637 -261.772534)
			(xy 330.222508 -261.816111) (xy 330.238092 -261.862792) (xy 330.245987 -261.911369) (xy 330.246482 -261.935976)
			(xy 330.564739 -261.935976) (xy 330.568834 -261.885248) (xy 330.581013 -261.835834) (xy 330.600961 -261.789014)
			(xy 330.628162 -261.746) (xy 330.66191 -261.707906) (xy 330.701332 -261.675719) (xy 330.745406 -261.650273)
			(xy 330.792992 -261.632226) (xy 330.842856 -261.622046) (xy 330.893708 -261.619997) (xy 330.944229 -261.626131)
			(xy 330.993113 -261.640291) (xy 331.039092 -261.662108) (xy 331.080976 -261.691018) (xy 331.11768 -261.726273)
			(xy 331.148253 -261.766959) (xy 331.171904 -261.812022) (xy 331.18802 -261.860296) (xy 331.196184 -261.91053)
			(xy 331.196696 -261.935976) (xy 331.515224 -261.935976) (xy 331.519184 -261.886922) (xy 331.530961 -261.839138)
			(xy 331.550252 -261.793862) (xy 331.576555 -261.752266) (xy 331.60919 -261.715429) (xy 331.647311 -261.684304)
			(xy 331.689932 -261.659697) (xy 331.735948 -261.642245) (xy 331.784167 -261.632401) (xy 331.833342 -261.63042)
			(xy 331.882197 -261.636352) (xy 331.929468 -261.650044) (xy 331.97393 -261.671142) (xy 332.014433 -261.699098)
			(xy 332.049926 -261.73319) (xy 332.079491 -261.772534) (xy 332.102362 -261.816111) (xy 332.117946 -261.862792)
			(xy 332.125841 -261.911369) (xy 332.126336 -261.935976) (xy 332.455278 -261.935976) (xy 332.459238 -261.886922)
			(xy 332.471015 -261.839138) (xy 332.490306 -261.793862) (xy 332.516609 -261.752266) (xy 332.549244 -261.715429)
			(xy 332.587365 -261.684304) (xy 332.629986 -261.659697) (xy 332.676002 -261.642245) (xy 332.724221 -261.632401)
			(xy 332.773396 -261.63042) (xy 332.822251 -261.636352) (xy 332.869522 -261.650044) (xy 332.913984 -261.671142)
			(xy 332.954487 -261.699098) (xy 332.98998 -261.73319) (xy 333.019545 -261.772534) (xy 333.042416 -261.816111)
			(xy 333.058 -261.862792) (xy 333.065895 -261.911369) (xy 333.06639 -261.935976) (xy 333.384901 -261.935976)
			(xy 333.388996 -261.885248) (xy 333.401175 -261.835834) (xy 333.421123 -261.789014) (xy 333.448324 -261.746)
			(xy 333.482072 -261.707906) (xy 333.521494 -261.675719) (xy 333.565568 -261.650273) (xy 333.613154 -261.632226)
			(xy 333.663018 -261.622046) (xy 333.71387 -261.619997) (xy 333.764391 -261.626131) (xy 333.813275 -261.640291)
			(xy 333.859254 -261.662108) (xy 333.901138 -261.691018) (xy 333.937842 -261.726273) (xy 333.968415 -261.766959)
			(xy 333.992066 -261.812022) (xy 334.008182 -261.860296) (xy 334.016346 -261.91053) (xy 334.016858 -261.935976)
			(xy 334.335386 -261.935976) (xy 334.339346 -261.886922) (xy 334.351123 -261.839138) (xy 334.370414 -261.793862)
			(xy 334.396717 -261.752266) (xy 334.429352 -261.715429) (xy 334.467473 -261.684304) (xy 334.510094 -261.659697)
			(xy 334.55611 -261.642245) (xy 334.604329 -261.632401) (xy 334.653504 -261.63042) (xy 334.702359 -261.636352)
			(xy 334.74963 -261.650044) (xy 334.794092 -261.671142) (xy 334.834595 -261.699098) (xy 334.870088 -261.73319)
			(xy 334.899653 -261.772534) (xy 334.922524 -261.816111) (xy 334.938108 -261.862792) (xy 334.946003 -261.911369)
			(xy 334.946498 -261.935976) (xy 335.275186 -261.935976) (xy 335.279146 -261.886922) (xy 335.290923 -261.839138)
			(xy 335.310214 -261.793862) (xy 335.336517 -261.752266) (xy 335.369152 -261.715429) (xy 335.407273 -261.684304)
			(xy 335.449894 -261.659697) (xy 335.49591 -261.642245) (xy 335.544129 -261.632401) (xy 335.593304 -261.63042)
			(xy 335.642159 -261.636352) (xy 335.68943 -261.650044) (xy 335.733892 -261.671142) (xy 335.774395 -261.699098)
			(xy 335.809888 -261.73319) (xy 335.839453 -261.772534) (xy 335.862324 -261.816111) (xy 335.877908 -261.862792)
			(xy 335.885803 -261.911369) (xy 335.886298 -261.935976) (xy 336.21524 -261.935976) (xy 336.2192 -261.886922)
			(xy 336.230977 -261.839138) (xy 336.250268 -261.793862) (xy 336.276571 -261.752266) (xy 336.309206 -261.715429)
			(xy 336.347327 -261.684304) (xy 336.389948 -261.659697) (xy 336.435964 -261.642245) (xy 336.484183 -261.632401)
			(xy 336.533358 -261.63042) (xy 336.582213 -261.636352) (xy 336.629484 -261.650044) (xy 336.673946 -261.671142)
			(xy 336.714449 -261.699098) (xy 336.749942 -261.73319) (xy 336.779507 -261.772534) (xy 336.802378 -261.816111)
			(xy 336.817962 -261.862792) (xy 336.825857 -261.911369) (xy 336.826352 -261.935976) (xy 337.144863 -261.935976)
			(xy 337.148958 -261.885248) (xy 337.161137 -261.835834) (xy 337.181085 -261.789014) (xy 337.208286 -261.746)
			(xy 337.242034 -261.707906) (xy 337.281456 -261.675719) (xy 337.32553 -261.650273) (xy 337.373116 -261.632226)
			(xy 337.42298 -261.622046) (xy 337.473832 -261.619997) (xy 337.524353 -261.626131) (xy 337.573237 -261.640291)
			(xy 337.619216 -261.662108) (xy 337.6611 -261.691018) (xy 337.697804 -261.726273) (xy 337.728377 -261.766959)
			(xy 337.752028 -261.812022) (xy 337.768144 -261.860296) (xy 337.776308 -261.91053) (xy 337.77682 -261.935976)
			(xy 338.095348 -261.935976) (xy 338.099308 -261.886922) (xy 338.111085 -261.839138) (xy 338.130376 -261.793862)
			(xy 338.156679 -261.752266) (xy 338.189314 -261.715429) (xy 338.227435 -261.684304) (xy 338.270056 -261.659697)
			(xy 338.316072 -261.642245) (xy 338.364291 -261.632401) (xy 338.413466 -261.63042) (xy 338.462321 -261.636352)
			(xy 338.509592 -261.650044) (xy 338.554054 -261.671142) (xy 338.594557 -261.699098) (xy 338.63005 -261.73319)
			(xy 338.659615 -261.772534) (xy 338.682486 -261.816111) (xy 338.69807 -261.862792) (xy 338.705965 -261.911369)
			(xy 338.70646 -261.935976) (xy 339.035402 -261.935976) (xy 339.039362 -261.886922) (xy 339.051139 -261.839138)
			(xy 339.07043 -261.793862) (xy 339.096733 -261.752266) (xy 339.129368 -261.715429) (xy 339.167489 -261.684304)
			(xy 339.21011 -261.659697) (xy 339.256126 -261.642245) (xy 339.304345 -261.632401) (xy 339.35352 -261.63042)
			(xy 339.402375 -261.636352) (xy 339.449646 -261.650044) (xy 339.494108 -261.671142) (xy 339.534611 -261.699098)
			(xy 339.570104 -261.73319) (xy 339.599669 -261.772534) (xy 339.62254 -261.816111) (xy 339.638124 -261.862792)
			(xy 339.646019 -261.911369) (xy 339.646514 -261.935976) (xy 339.964771 -261.935976) (xy 339.968866 -261.885248)
			(xy 339.981045 -261.835834) (xy 340.000993 -261.789014) (xy 340.028194 -261.746) (xy 340.061942 -261.707906)
			(xy 340.101364 -261.675719) (xy 340.145438 -261.650273) (xy 340.193024 -261.632226) (xy 340.242888 -261.622046)
			(xy 340.29374 -261.619997) (xy 340.344261 -261.626131) (xy 340.393145 -261.640291) (xy 340.439124 -261.662108)
			(xy 340.481008 -261.691018) (xy 340.517712 -261.726273) (xy 340.548285 -261.766959) (xy 340.571936 -261.812022)
			(xy 340.588052 -261.860296) (xy 340.596216 -261.91053) (xy 340.596728 -261.935976) (xy 340.915256 -261.935976)
			(xy 340.919216 -261.886922) (xy 340.930993 -261.839138) (xy 340.950284 -261.793862) (xy 340.976587 -261.752266)
			(xy 341.009222 -261.715429) (xy 341.047343 -261.684304) (xy 341.089964 -261.659697) (xy 341.13598 -261.642245)
			(xy 341.184199 -261.632401) (xy 341.233374 -261.63042) (xy 341.282229 -261.636352) (xy 341.3295 -261.650044)
			(xy 341.373962 -261.671142) (xy 341.414465 -261.699098) (xy 341.449958 -261.73319) (xy 341.479523 -261.772534)
			(xy 341.502394 -261.816111) (xy 341.517978 -261.862792) (xy 341.525873 -261.911369) (xy 341.526368 -261.935976)
			(xy 341.85531 -261.935976) (xy 341.85927 -261.886922) (xy 341.871047 -261.839138) (xy 341.890338 -261.793862)
			(xy 341.916641 -261.752266) (xy 341.949276 -261.715429) (xy 341.987397 -261.684304) (xy 342.030018 -261.659697)
			(xy 342.076034 -261.642245) (xy 342.124253 -261.632401) (xy 342.173428 -261.63042) (xy 342.222283 -261.636352)
			(xy 342.269554 -261.650044) (xy 342.314016 -261.671142) (xy 342.354519 -261.699098) (xy 342.390012 -261.73319)
			(xy 342.419577 -261.772534) (xy 342.442448 -261.816111) (xy 342.458032 -261.862792) (xy 342.465927 -261.911369)
			(xy 342.466422 -261.935976) (xy 342.795364 -261.935976) (xy 342.799324 -261.886922) (xy 342.811101 -261.839138)
			(xy 342.830392 -261.793862) (xy 342.856695 -261.752266) (xy 342.88933 -261.715429) (xy 342.927451 -261.684304)
			(xy 342.970072 -261.659697) (xy 343.016088 -261.642245) (xy 343.064307 -261.632401) (xy 343.113482 -261.63042)
			(xy 343.162337 -261.636352) (xy 343.209608 -261.650044) (xy 343.25407 -261.671142) (xy 343.294573 -261.699098)
			(xy 343.330066 -261.73319) (xy 343.359631 -261.772534) (xy 343.382502 -261.816111) (xy 343.398086 -261.862792)
			(xy 343.405981 -261.911369) (xy 343.406476 -261.935976) (xy 343.724987 -261.935976) (xy 343.729082 -261.885248)
			(xy 343.741261 -261.835834) (xy 343.761209 -261.789014) (xy 343.78841 -261.746) (xy 343.822158 -261.707906)
			(xy 343.86158 -261.675719) (xy 343.905654 -261.650273) (xy 343.95324 -261.632226) (xy 344.003104 -261.622046)
			(xy 344.053956 -261.619997) (xy 344.104477 -261.626131) (xy 344.153361 -261.640291) (xy 344.19934 -261.662108)
			(xy 344.241224 -261.691018) (xy 344.277928 -261.726273) (xy 344.308501 -261.766959) (xy 344.332152 -261.812022)
			(xy 344.348268 -261.860296) (xy 344.356432 -261.91053) (xy 344.356944 -261.935976) (xy 345.615272 -261.935976)
			(xy 345.619232 -261.886922) (xy 345.631009 -261.839138) (xy 345.6503 -261.793862) (xy 345.676603 -261.752266)
			(xy 345.709238 -261.715429) (xy 345.747359 -261.684304) (xy 345.78998 -261.659697) (xy 345.835996 -261.642245)
			(xy 345.884215 -261.632401) (xy 345.93339 -261.63042) (xy 345.982245 -261.636352) (xy 346.029516 -261.650044)
			(xy 346.073978 -261.671142) (xy 346.114481 -261.699098) (xy 346.149974 -261.73319) (xy 346.179539 -261.772534)
			(xy 346.20241 -261.816111) (xy 346.217994 -261.862792) (xy 346.225889 -261.911369) (xy 346.226384 -261.935976)
			(xy 347.49538 -261.935976) (xy 347.49934 -261.886922) (xy 347.511117 -261.839138) (xy 347.530408 -261.793862)
			(xy 347.556711 -261.752266) (xy 347.589346 -261.715429) (xy 347.627467 -261.684304) (xy 347.670088 -261.659697)
			(xy 347.716104 -261.642245) (xy 347.764323 -261.632401) (xy 347.813498 -261.63042) (xy 347.862353 -261.636352)
			(xy 347.909624 -261.650044) (xy 347.954086 -261.671142) (xy 347.994589 -261.699098) (xy 348.030082 -261.73319)
			(xy 348.059647 -261.772534) (xy 348.082518 -261.816111) (xy 348.098102 -261.862792) (xy 348.105997 -261.911369)
			(xy 348.106492 -261.935976) (xy 348.105997 -261.960583) (xy 348.098102 -262.00916) (xy 348.082518 -262.055841)
			(xy 348.059647 -262.099418) (xy 348.030082 -262.138762) (xy 347.994589 -262.172854) (xy 347.954086 -262.20081)
			(xy 347.909624 -262.221908) (xy 347.862353 -262.2356) (xy 347.813498 -262.241532) (xy 347.764323 -262.239551)
			(xy 347.716104 -262.229707) (xy 347.670088 -262.212255) (xy 347.627467 -262.187648) (xy 347.589346 -262.156523)
			(xy 347.556711 -262.119686) (xy 347.530408 -262.07809) (xy 347.511117 -262.032814) (xy 347.49934 -261.98503)
			(xy 347.49538 -261.935976) (xy 346.226384 -261.935976) (xy 346.225889 -261.960583) (xy 346.217994 -262.00916)
			(xy 346.20241 -262.055841) (xy 346.179539 -262.099418) (xy 346.149974 -262.138762) (xy 346.114481 -262.172854)
			(xy 346.073978 -262.20081) (xy 346.029516 -262.221908) (xy 345.982245 -262.2356) (xy 345.93339 -262.241532)
			(xy 345.884215 -262.239551) (xy 345.835996 -262.229707) (xy 345.78998 -262.212255) (xy 345.747359 -262.187648)
			(xy 345.709238 -262.156523) (xy 345.676603 -262.119686) (xy 345.6503 -262.07809) (xy 345.631009 -262.032814)
			(xy 345.619232 -261.98503) (xy 345.615272 -261.935976) (xy 344.356944 -261.935976) (xy 344.356432 -261.961422)
			(xy 344.348268 -262.011656) (xy 344.332152 -262.05993) (xy 344.308501 -262.104993) (xy 344.277928 -262.145679)
			(xy 344.241224 -262.180934) (xy 344.19934 -262.209844) (xy 344.153361 -262.231661) (xy 344.104477 -262.245821)
			(xy 344.053956 -262.251955) (xy 344.003104 -262.249906) (xy 343.95324 -262.239726) (xy 343.905654 -262.221679)
			(xy 343.86158 -262.196233) (xy 343.822158 -262.164046) (xy 343.78841 -262.125952) (xy 343.761209 -262.082938)
			(xy 343.741261 -262.036118) (xy 343.729082 -261.986704) (xy 343.724987 -261.935976) (xy 343.406476 -261.935976)
			(xy 343.405981 -261.960583) (xy 343.398086 -262.00916) (xy 343.382502 -262.055841) (xy 343.359631 -262.099418)
			(xy 343.330066 -262.138762) (xy 343.294573 -262.172854) (xy 343.25407 -262.20081) (xy 343.209608 -262.221908)
			(xy 343.162337 -262.2356) (xy 343.113482 -262.241532) (xy 343.064307 -262.239551) (xy 343.016088 -262.229707)
			(xy 342.970072 -262.212255) (xy 342.927451 -262.187648) (xy 342.88933 -262.156523) (xy 342.856695 -262.119686)
			(xy 342.830392 -262.07809) (xy 342.811101 -262.032814) (xy 342.799324 -261.98503) (xy 342.795364 -261.935976)
			(xy 342.466422 -261.935976) (xy 342.465927 -261.960583) (xy 342.458032 -262.00916) (xy 342.442448 -262.055841)
			(xy 342.419577 -262.099418) (xy 342.390012 -262.138762) (xy 342.354519 -262.172854) (xy 342.314016 -262.20081)
			(xy 342.269554 -262.221908) (xy 342.222283 -262.2356) (xy 342.173428 -262.241532) (xy 342.124253 -262.239551)
			(xy 342.076034 -262.229707) (xy 342.030018 -262.212255) (xy 341.987397 -262.187648) (xy 341.949276 -262.156523)
			(xy 341.916641 -262.119686) (xy 341.890338 -262.07809) (xy 341.871047 -262.032814) (xy 341.85927 -261.98503)
			(xy 341.85531 -261.935976) (xy 341.526368 -261.935976) (xy 341.525873 -261.960583) (xy 341.517978 -262.00916)
			(xy 341.502394 -262.055841) (xy 341.479523 -262.099418) (xy 341.449958 -262.138762) (xy 341.414465 -262.172854)
			(xy 341.373962 -262.20081) (xy 341.3295 -262.221908) (xy 341.282229 -262.2356) (xy 341.233374 -262.241532)
			(xy 341.184199 -262.239551) (xy 341.13598 -262.229707) (xy 341.089964 -262.212255) (xy 341.047343 -262.187648)
			(xy 341.009222 -262.156523) (xy 340.976587 -262.119686) (xy 340.950284 -262.07809) (xy 340.930993 -262.032814)
			(xy 340.919216 -261.98503) (xy 340.915256 -261.935976) (xy 340.596728 -261.935976) (xy 340.596216 -261.961422)
			(xy 340.588052 -262.011656) (xy 340.571936 -262.05993) (xy 340.548285 -262.104993) (xy 340.517712 -262.145679)
			(xy 340.481008 -262.180934) (xy 340.439124 -262.209844) (xy 340.393145 -262.231661) (xy 340.344261 -262.245821)
			(xy 340.29374 -262.251955) (xy 340.242888 -262.249906) (xy 340.193024 -262.239726) (xy 340.145438 -262.221679)
			(xy 340.101364 -262.196233) (xy 340.061942 -262.164046) (xy 340.028194 -262.125952) (xy 340.000993 -262.082938)
			(xy 339.981045 -262.036118) (xy 339.968866 -261.986704) (xy 339.964771 -261.935976) (xy 339.646514 -261.935976)
			(xy 339.646019 -261.960583) (xy 339.638124 -262.00916) (xy 339.62254 -262.055841) (xy 339.599669 -262.099418)
			(xy 339.570104 -262.138762) (xy 339.534611 -262.172854) (xy 339.494108 -262.20081) (xy 339.449646 -262.221908)
			(xy 339.402375 -262.2356) (xy 339.35352 -262.241532) (xy 339.304345 -262.239551) (xy 339.256126 -262.229707)
			(xy 339.21011 -262.212255) (xy 339.167489 -262.187648) (xy 339.129368 -262.156523) (xy 339.096733 -262.119686)
			(xy 339.07043 -262.07809) (xy 339.051139 -262.032814) (xy 339.039362 -261.98503) (xy 339.035402 -261.935976)
			(xy 338.70646 -261.935976) (xy 338.705965 -261.960583) (xy 338.69807 -262.00916) (xy 338.682486 -262.055841)
			(xy 338.659615 -262.099418) (xy 338.63005 -262.138762) (xy 338.594557 -262.172854) (xy 338.554054 -262.20081)
			(xy 338.509592 -262.221908) (xy 338.462321 -262.2356) (xy 338.413466 -262.241532) (xy 338.364291 -262.239551)
			(xy 338.316072 -262.229707) (xy 338.270056 -262.212255) (xy 338.227435 -262.187648) (xy 338.189314 -262.156523)
			(xy 338.156679 -262.119686) (xy 338.130376 -262.07809) (xy 338.111085 -262.032814) (xy 338.099308 -261.98503)
			(xy 338.095348 -261.935976) (xy 337.77682 -261.935976) (xy 337.776308 -261.961422) (xy 337.768144 -262.011656)
			(xy 337.752028 -262.05993) (xy 337.728377 -262.104993) (xy 337.697804 -262.145679) (xy 337.6611 -262.180934)
			(xy 337.619216 -262.209844) (xy 337.573237 -262.231661) (xy 337.524353 -262.245821) (xy 337.473832 -262.251955)
			(xy 337.42298 -262.249906) (xy 337.373116 -262.239726) (xy 337.32553 -262.221679) (xy 337.281456 -262.196233)
			(xy 337.242034 -262.164046) (xy 337.208286 -262.125952) (xy 337.181085 -262.082938) (xy 337.161137 -262.036118)
			(xy 337.148958 -261.986704) (xy 337.144863 -261.935976) (xy 336.826352 -261.935976) (xy 336.825857 -261.960583)
			(xy 336.817962 -262.00916) (xy 336.802378 -262.055841) (xy 336.779507 -262.099418) (xy 336.749942 -262.138762)
			(xy 336.714449 -262.172854) (xy 336.673946 -262.20081) (xy 336.629484 -262.221908) (xy 336.582213 -262.2356)
			(xy 336.533358 -262.241532) (xy 336.484183 -262.239551) (xy 336.435964 -262.229707) (xy 336.389948 -262.212255)
			(xy 336.347327 -262.187648) (xy 336.309206 -262.156523) (xy 336.276571 -262.119686) (xy 336.250268 -262.07809)
			(xy 336.230977 -262.032814) (xy 336.2192 -261.98503) (xy 336.21524 -261.935976) (xy 335.886298 -261.935976)
			(xy 335.885803 -261.960583) (xy 335.877908 -262.00916) (xy 335.862324 -262.055841) (xy 335.839453 -262.099418)
			(xy 335.809888 -262.138762) (xy 335.774395 -262.172854) (xy 335.733892 -262.20081) (xy 335.68943 -262.221908)
			(xy 335.642159 -262.2356) (xy 335.593304 -262.241532) (xy 335.544129 -262.239551) (xy 335.49591 -262.229707)
			(xy 335.449894 -262.212255) (xy 335.407273 -262.187648) (xy 335.369152 -262.156523) (xy 335.336517 -262.119686)
			(xy 335.310214 -262.07809) (xy 335.290923 -262.032814) (xy 335.279146 -261.98503) (xy 335.275186 -261.935976)
			(xy 334.946498 -261.935976) (xy 334.946003 -261.960583) (xy 334.938108 -262.00916) (xy 334.922524 -262.055841)
			(xy 334.899653 -262.099418) (xy 334.870088 -262.138762) (xy 334.834595 -262.172854) (xy 334.794092 -262.20081)
			(xy 334.74963 -262.221908) (xy 334.702359 -262.2356) (xy 334.653504 -262.241532) (xy 334.604329 -262.239551)
			(xy 334.55611 -262.229707) (xy 334.510094 -262.212255) (xy 334.467473 -262.187648) (xy 334.429352 -262.156523)
			(xy 334.396717 -262.119686) (xy 334.370414 -262.07809) (xy 334.351123 -262.032814) (xy 334.339346 -261.98503)
			(xy 334.335386 -261.935976) (xy 334.016858 -261.935976) (xy 334.016346 -261.961422) (xy 334.008182 -262.011656)
			(xy 333.992066 -262.05993) (xy 333.968415 -262.104993) (xy 333.937842 -262.145679) (xy 333.901138 -262.180934)
			(xy 333.859254 -262.209844) (xy 333.813275 -262.231661) (xy 333.764391 -262.245821) (xy 333.71387 -262.251955)
			(xy 333.663018 -262.249906) (xy 333.613154 -262.239726) (xy 333.565568 -262.221679) (xy 333.521494 -262.196233)
			(xy 333.482072 -262.164046) (xy 333.448324 -262.125952) (xy 333.421123 -262.082938) (xy 333.401175 -262.036118)
			(xy 333.388996 -261.986704) (xy 333.384901 -261.935976) (xy 333.06639 -261.935976) (xy 333.065895 -261.960583)
			(xy 333.058 -262.00916) (xy 333.042416 -262.055841) (xy 333.019545 -262.099418) (xy 332.98998 -262.138762)
			(xy 332.954487 -262.172854) (xy 332.913984 -262.20081) (xy 332.869522 -262.221908) (xy 332.822251 -262.2356)
			(xy 332.773396 -262.241532) (xy 332.724221 -262.239551) (xy 332.676002 -262.229707) (xy 332.629986 -262.212255)
			(xy 332.587365 -262.187648) (xy 332.549244 -262.156523) (xy 332.516609 -262.119686) (xy 332.490306 -262.07809)
			(xy 332.471015 -262.032814) (xy 332.459238 -261.98503) (xy 332.455278 -261.935976) (xy 332.126336 -261.935976)
			(xy 332.125841 -261.960583) (xy 332.117946 -262.00916) (xy 332.102362 -262.055841) (xy 332.079491 -262.099418)
			(xy 332.049926 -262.138762) (xy 332.014433 -262.172854) (xy 331.97393 -262.20081) (xy 331.929468 -262.221908)
			(xy 331.882197 -262.2356) (xy 331.833342 -262.241532) (xy 331.784167 -262.239551) (xy 331.735948 -262.229707)
			(xy 331.689932 -262.212255) (xy 331.647311 -262.187648) (xy 331.60919 -262.156523) (xy 331.576555 -262.119686)
			(xy 331.550252 -262.07809) (xy 331.530961 -262.032814) (xy 331.519184 -261.98503) (xy 331.515224 -261.935976)
			(xy 331.196696 -261.935976) (xy 331.196184 -261.961422) (xy 331.18802 -262.011656) (xy 331.171904 -262.05993)
			(xy 331.148253 -262.104993) (xy 331.11768 -262.145679) (xy 331.080976 -262.180934) (xy 331.039092 -262.209844)
			(xy 330.993113 -262.231661) (xy 330.944229 -262.245821) (xy 330.893708 -262.251955) (xy 330.842856 -262.249906)
			(xy 330.792992 -262.239726) (xy 330.745406 -262.221679) (xy 330.701332 -262.196233) (xy 330.66191 -262.164046)
			(xy 330.628162 -262.125952) (xy 330.600961 -262.082938) (xy 330.581013 -262.036118) (xy 330.568834 -261.986704)
			(xy 330.564739 -261.935976) (xy 330.246482 -261.935976) (xy 330.245987 -261.960583) (xy 330.238092 -262.00916)
			(xy 330.222508 -262.055841) (xy 330.199637 -262.099418) (xy 330.170072 -262.138762) (xy 330.134579 -262.172854)
			(xy 330.094076 -262.20081) (xy 330.049614 -262.221908) (xy 330.002343 -262.2356) (xy 329.953488 -262.241532)
			(xy 329.904313 -262.239551) (xy 329.856094 -262.229707) (xy 329.810078 -262.212255) (xy 329.767457 -262.187648)
			(xy 329.729336 -262.156523) (xy 329.696701 -262.119686) (xy 329.670398 -262.07809) (xy 329.651107 -262.032814)
			(xy 329.63933 -261.98503) (xy 329.63537 -261.935976) (xy 329.306428 -261.935976) (xy 329.305933 -261.960583)
			(xy 329.298038 -262.00916) (xy 329.282454 -262.055841) (xy 329.259583 -262.099418) (xy 329.230018 -262.138762)
			(xy 329.194525 -262.172854) (xy 329.154022 -262.20081) (xy 329.10956 -262.221908) (xy 329.062289 -262.2356)
			(xy 329.013434 -262.241532) (xy 328.964259 -262.239551) (xy 328.91604 -262.229707) (xy 328.870024 -262.212255)
			(xy 328.827403 -262.187648) (xy 328.789282 -262.156523) (xy 328.756647 -262.119686) (xy 328.730344 -262.07809)
			(xy 328.711053 -262.032814) (xy 328.699276 -261.98503) (xy 328.695316 -261.935976) (xy 328.366374 -261.935976)
			(xy 328.365879 -261.960583) (xy 328.357984 -262.00916) (xy 328.3424 -262.055841) (xy 328.319529 -262.099418)
			(xy 328.289964 -262.138762) (xy 328.254471 -262.172854) (xy 328.213968 -262.20081) (xy 328.169506 -262.221908)
			(xy 328.122235 -262.2356) (xy 328.07338 -262.241532) (xy 328.024205 -262.239551) (xy 327.975986 -262.229707)
			(xy 327.92997 -262.212255) (xy 327.887349 -262.187648) (xy 327.849228 -262.156523) (xy 327.816593 -262.119686)
			(xy 327.79029 -262.07809) (xy 327.770999 -262.032814) (xy 327.759222 -261.98503) (xy 327.755262 -261.935976)
			(xy 325.203519 -261.935976) (xy 325.161384 -261.95597) (xy 325.114113 -261.969662) (xy 325.065258 -261.975594)
			(xy 325.016083 -261.973613) (xy 324.967864 -261.963769) (xy 324.921848 -261.946317) (xy 324.879227 -261.92171)
			(xy 324.841106 -261.890585) (xy 324.808471 -261.853748) (xy 324.782168 -261.812152) (xy 324.762877 -261.766876)
			(xy 324.7511 -261.719092) (xy 324.74714 -261.670038) (xy 310.45912 -261.670038) (xy 310.45912 -262.745982)
			(xy 326.345308 -262.745982) (xy 326.349268 -262.696928) (xy 326.361045 -262.649144) (xy 326.380336 -262.603868)
			(xy 326.406639 -262.562272) (xy 326.439274 -262.525435) (xy 326.477395 -262.49431) (xy 326.520016 -262.469703)
			(xy 326.566032 -262.452251) (xy 326.614251 -262.442407) (xy 326.663426 -262.440426) (xy 326.712281 -262.446358)
			(xy 326.759552 -262.46005) (xy 326.804014 -262.481148) (xy 326.844517 -262.509104) (xy 326.88001 -262.543196)
			(xy 326.909575 -262.58254) (xy 326.932446 -262.626117) (xy 326.94803 -262.672798) (xy 326.955925 -262.721375)
			(xy 326.95642 -262.745982) (xy 328.225416 -262.745982) (xy 328.229376 -262.696928) (xy 328.241153 -262.649144)
			(xy 328.260444 -262.603868) (xy 328.286747 -262.562272) (xy 328.319382 -262.525435) (xy 328.357503 -262.49431)
			(xy 328.400124 -262.469703) (xy 328.44614 -262.452251) (xy 328.494359 -262.442407) (xy 328.543534 -262.440426)
			(xy 328.592389 -262.446358) (xy 328.63966 -262.46005) (xy 328.684122 -262.481148) (xy 328.724625 -262.509104)
			(xy 328.760118 -262.543196) (xy 328.789683 -262.58254) (xy 328.812554 -262.626117) (xy 328.828138 -262.672798)
			(xy 328.836033 -262.721375) (xy 328.836528 -262.745982) (xy 329.154785 -262.745982) (xy 329.15888 -262.695254)
			(xy 329.171059 -262.64584) (xy 329.191007 -262.59902) (xy 329.218208 -262.556006) (xy 329.251956 -262.517912)
			(xy 329.291378 -262.485725) (xy 329.335452 -262.460279) (xy 329.383038 -262.442232) (xy 329.432902 -262.432052)
			(xy 329.483754 -262.430003) (xy 329.534275 -262.436137) (xy 329.583159 -262.450297) (xy 329.629138 -262.472114)
			(xy 329.671022 -262.501024) (xy 329.707726 -262.536279) (xy 329.738299 -262.576965) (xy 329.76195 -262.622028)
			(xy 329.778066 -262.670302) (xy 329.78623 -262.720536) (xy 329.786742 -262.745982) (xy 330.094839 -262.745982)
			(xy 330.098934 -262.695254) (xy 330.111113 -262.64584) (xy 330.131061 -262.59902) (xy 330.158262 -262.556006)
			(xy 330.19201 -262.517912) (xy 330.231432 -262.485725) (xy 330.275506 -262.460279) (xy 330.323092 -262.442232)
			(xy 330.372956 -262.432052) (xy 330.423808 -262.430003) (xy 330.474329 -262.436137) (xy 330.523213 -262.450297)
			(xy 330.569192 -262.472114) (xy 330.611076 -262.501024) (xy 330.64778 -262.536279) (xy 330.678353 -262.576965)
			(xy 330.702004 -262.622028) (xy 330.71812 -262.670302) (xy 330.726284 -262.720536) (xy 330.726796 -262.745982)
			(xy 331.045324 -262.745982) (xy 331.049284 -262.696928) (xy 331.061061 -262.649144) (xy 331.080352 -262.603868)
			(xy 331.106655 -262.562272) (xy 331.13929 -262.525435) (xy 331.177411 -262.49431) (xy 331.220032 -262.469703)
			(xy 331.266048 -262.452251) (xy 331.314267 -262.442407) (xy 331.363442 -262.440426) (xy 331.412297 -262.446358)
			(xy 331.459568 -262.46005) (xy 331.50403 -262.481148) (xy 331.544533 -262.509104) (xy 331.580026 -262.543196)
			(xy 331.609591 -262.58254) (xy 331.632462 -262.626117) (xy 331.648046 -262.672798) (xy 331.655941 -262.721375)
			(xy 331.656436 -262.745982) (xy 331.974947 -262.745982) (xy 331.979042 -262.695254) (xy 331.991221 -262.64584)
			(xy 332.011169 -262.59902) (xy 332.03837 -262.556006) (xy 332.072118 -262.517912) (xy 332.11154 -262.485725)
			(xy 332.155614 -262.460279) (xy 332.2032 -262.442232) (xy 332.253064 -262.432052) (xy 332.303916 -262.430003)
			(xy 332.354437 -262.436137) (xy 332.403321 -262.450297) (xy 332.4493 -262.472114) (xy 332.491184 -262.501024)
			(xy 332.527888 -262.536279) (xy 332.558461 -262.576965) (xy 332.582112 -262.622028) (xy 332.598228 -262.670302)
			(xy 332.606392 -262.720536) (xy 332.606904 -262.745982) (xy 332.925178 -262.745982) (xy 332.929138 -262.696928)
			(xy 332.940915 -262.649144) (xy 332.960206 -262.603868) (xy 332.986509 -262.562272) (xy 333.019144 -262.525435)
			(xy 333.057265 -262.49431) (xy 333.099886 -262.469703) (xy 333.145902 -262.452251) (xy 333.194121 -262.442407)
			(xy 333.243296 -262.440426) (xy 333.292151 -262.446358) (xy 333.339422 -262.46005) (xy 333.383884 -262.481148)
			(xy 333.424387 -262.509104) (xy 333.45988 -262.543196) (xy 333.489445 -262.58254) (xy 333.512316 -262.626117)
			(xy 333.5279 -262.672798) (xy 333.535795 -262.721375) (xy 333.53629 -262.745982) (xy 333.854801 -262.745982)
			(xy 333.858896 -262.695254) (xy 333.871075 -262.64584) (xy 333.891023 -262.59902) (xy 333.918224 -262.556006)
			(xy 333.951972 -262.517912) (xy 333.991394 -262.485725) (xy 334.035468 -262.460279) (xy 334.083054 -262.442232)
			(xy 334.132918 -262.432052) (xy 334.18377 -262.430003) (xy 334.234291 -262.436137) (xy 334.283175 -262.450297)
			(xy 334.329154 -262.472114) (xy 334.371038 -262.501024) (xy 334.407742 -262.536279) (xy 334.438315 -262.576965)
			(xy 334.461966 -262.622028) (xy 334.478082 -262.670302) (xy 334.486246 -262.720536) (xy 334.486758 -262.745982)
			(xy 334.805286 -262.745982) (xy 334.809246 -262.696928) (xy 334.821023 -262.649144) (xy 334.840314 -262.603868)
			(xy 334.866617 -262.562272) (xy 334.899252 -262.525435) (xy 334.937373 -262.49431) (xy 334.979994 -262.469703)
			(xy 335.02601 -262.452251) (xy 335.074229 -262.442407) (xy 335.123404 -262.440426) (xy 335.172259 -262.446358)
			(xy 335.21953 -262.46005) (xy 335.263992 -262.481148) (xy 335.304495 -262.509104) (xy 335.339988 -262.543196)
			(xy 335.369553 -262.58254) (xy 335.392424 -262.626117) (xy 335.408008 -262.672798) (xy 335.415903 -262.721375)
			(xy 335.416398 -262.745982) (xy 335.734909 -262.745982) (xy 335.739004 -262.695254) (xy 335.751183 -262.64584)
			(xy 335.771131 -262.59902) (xy 335.798332 -262.556006) (xy 335.83208 -262.517912) (xy 335.871502 -262.485725)
			(xy 335.915576 -262.460279) (xy 335.963162 -262.442232) (xy 336.013026 -262.432052) (xy 336.063878 -262.430003)
			(xy 336.114399 -262.436137) (xy 336.163283 -262.450297) (xy 336.209262 -262.472114) (xy 336.251146 -262.501024)
			(xy 336.28785 -262.536279) (xy 336.318423 -262.576965) (xy 336.342074 -262.622028) (xy 336.35819 -262.670302)
			(xy 336.366354 -262.720536) (xy 336.366866 -262.745982) (xy 336.674963 -262.745982) (xy 336.679058 -262.695254)
			(xy 336.691237 -262.64584) (xy 336.711185 -262.59902) (xy 336.738386 -262.556006) (xy 336.772134 -262.517912)
			(xy 336.811556 -262.485725) (xy 336.85563 -262.460279) (xy 336.903216 -262.442232) (xy 336.95308 -262.432052)
			(xy 337.003932 -262.430003) (xy 337.054453 -262.436137) (xy 337.103337 -262.450297) (xy 337.149316 -262.472114)
			(xy 337.1912 -262.501024) (xy 337.227904 -262.536279) (xy 337.258477 -262.576965) (xy 337.282128 -262.622028)
			(xy 337.298244 -262.670302) (xy 337.306408 -262.720536) (xy 337.30692 -262.745982) (xy 337.625194 -262.745982)
			(xy 337.629154 -262.696928) (xy 337.640931 -262.649144) (xy 337.660222 -262.603868) (xy 337.686525 -262.562272)
			(xy 337.71916 -262.525435) (xy 337.757281 -262.49431) (xy 337.799902 -262.469703) (xy 337.845918 -262.452251)
			(xy 337.894137 -262.442407) (xy 337.943312 -262.440426) (xy 337.992167 -262.446358) (xy 338.039438 -262.46005)
			(xy 338.0839 -262.481148) (xy 338.124403 -262.509104) (xy 338.159896 -262.543196) (xy 338.189461 -262.58254)
			(xy 338.212332 -262.626117) (xy 338.227916 -262.672798) (xy 338.235811 -262.721375) (xy 338.236306 -262.745982)
			(xy 338.554817 -262.745982) (xy 338.558912 -262.695254) (xy 338.571091 -262.64584) (xy 338.591039 -262.59902)
			(xy 338.61824 -262.556006) (xy 338.651988 -262.517912) (xy 338.69141 -262.485725) (xy 338.735484 -262.460279)
			(xy 338.78307 -262.442232) (xy 338.832934 -262.432052) (xy 338.883786 -262.430003) (xy 338.934307 -262.436137)
			(xy 338.983191 -262.450297) (xy 339.02917 -262.472114) (xy 339.071054 -262.501024) (xy 339.107758 -262.536279)
			(xy 339.138331 -262.576965) (xy 339.161982 -262.622028) (xy 339.178098 -262.670302) (xy 339.186262 -262.720536)
			(xy 339.186774 -262.745982) (xy 339.505302 -262.745982) (xy 339.509262 -262.696928) (xy 339.521039 -262.649144)
			(xy 339.54033 -262.603868) (xy 339.566633 -262.562272) (xy 339.599268 -262.525435) (xy 339.637389 -262.49431)
			(xy 339.68001 -262.469703) (xy 339.726026 -262.452251) (xy 339.774245 -262.442407) (xy 339.82342 -262.440426)
			(xy 339.872275 -262.446358) (xy 339.919546 -262.46005) (xy 339.964008 -262.481148) (xy 340.004511 -262.509104)
			(xy 340.040004 -262.543196) (xy 340.069569 -262.58254) (xy 340.09244 -262.626117) (xy 340.108024 -262.672798)
			(xy 340.115919 -262.721375) (xy 340.116414 -262.745982) (xy 340.434925 -262.745982) (xy 340.43902 -262.695254)
			(xy 340.451199 -262.64584) (xy 340.471147 -262.59902) (xy 340.498348 -262.556006) (xy 340.532096 -262.517912)
			(xy 340.571518 -262.485725) (xy 340.615592 -262.460279) (xy 340.663178 -262.442232) (xy 340.713042 -262.432052)
			(xy 340.763894 -262.430003) (xy 340.814415 -262.436137) (xy 340.863299 -262.450297) (xy 340.909278 -262.472114)
			(xy 340.951162 -262.501024) (xy 340.987866 -262.536279) (xy 341.018439 -262.576965) (xy 341.04209 -262.622028)
			(xy 341.058206 -262.670302) (xy 341.06637 -262.720536) (xy 341.066882 -262.745982) (xy 341.38541 -262.745982)
			(xy 341.38937 -262.696928) (xy 341.401147 -262.649144) (xy 341.420438 -262.603868) (xy 341.446741 -262.562272)
			(xy 341.479376 -262.525435) (xy 341.517497 -262.49431) (xy 341.560118 -262.469703) (xy 341.606134 -262.452251)
			(xy 341.654353 -262.442407) (xy 341.703528 -262.440426) (xy 341.752383 -262.446358) (xy 341.799654 -262.46005)
			(xy 341.844116 -262.481148) (xy 341.884619 -262.509104) (xy 341.920112 -262.543196) (xy 341.949677 -262.58254)
			(xy 341.972548 -262.626117) (xy 341.988132 -262.672798) (xy 341.996027 -262.721375) (xy 341.996522 -262.745982)
			(xy 342.314779 -262.745982) (xy 342.318874 -262.695254) (xy 342.331053 -262.64584) (xy 342.351001 -262.59902)
			(xy 342.378202 -262.556006) (xy 342.41195 -262.517912) (xy 342.451372 -262.485725) (xy 342.495446 -262.460279)
			(xy 342.543032 -262.442232) (xy 342.592896 -262.432052) (xy 342.643748 -262.430003) (xy 342.694269 -262.436137)
			(xy 342.743153 -262.450297) (xy 342.789132 -262.472114) (xy 342.831016 -262.501024) (xy 342.86772 -262.536279)
			(xy 342.898293 -262.576965) (xy 342.921944 -262.622028) (xy 342.93806 -262.670302) (xy 342.946224 -262.720536)
			(xy 342.946736 -262.745982) (xy 343.254833 -262.745982) (xy 343.258928 -262.695254) (xy 343.271107 -262.64584)
			(xy 343.291055 -262.59902) (xy 343.318256 -262.556006) (xy 343.352004 -262.517912) (xy 343.391426 -262.485725)
			(xy 343.4355 -262.460279) (xy 343.483086 -262.442232) (xy 343.53295 -262.432052) (xy 343.583802 -262.430003)
			(xy 343.634323 -262.436137) (xy 343.683207 -262.450297) (xy 343.729186 -262.472114) (xy 343.77107 -262.501024)
			(xy 343.807774 -262.536279) (xy 343.838347 -262.576965) (xy 343.861998 -262.622028) (xy 343.878114 -262.670302)
			(xy 343.886278 -262.720536) (xy 343.88679 -262.745982) (xy 344.205318 -262.745982) (xy 344.209278 -262.696928)
			(xy 344.221055 -262.649144) (xy 344.240346 -262.603868) (xy 344.266649 -262.562272) (xy 344.299284 -262.525435)
			(xy 344.337405 -262.49431) (xy 344.380026 -262.469703) (xy 344.426042 -262.452251) (xy 344.474261 -262.442407)
			(xy 344.523436 -262.440426) (xy 344.572291 -262.446358) (xy 344.619562 -262.46005) (xy 344.664024 -262.481148)
			(xy 344.704527 -262.509104) (xy 344.74002 -262.543196) (xy 344.769585 -262.58254) (xy 344.792456 -262.626117)
			(xy 344.80804 -262.672798) (xy 344.815935 -262.721375) (xy 344.81643 -262.745982) (xy 346.085426 -262.745982)
			(xy 346.089386 -262.696928) (xy 346.101163 -262.649144) (xy 346.120454 -262.603868) (xy 346.146757 -262.562272)
			(xy 346.179392 -262.525435) (xy 346.217513 -262.49431) (xy 346.260134 -262.469703) (xy 346.30615 -262.452251)
			(xy 346.354369 -262.442407) (xy 346.403544 -262.440426) (xy 346.452399 -262.446358) (xy 346.49967 -262.46005)
			(xy 346.544132 -262.481148) (xy 346.584635 -262.509104) (xy 346.620128 -262.543196) (xy 346.649693 -262.58254)
			(xy 346.672564 -262.626117) (xy 346.688148 -262.672798) (xy 346.696043 -262.721375) (xy 346.696538 -262.745982)
			(xy 347.96528 -262.745982) (xy 347.96924 -262.696928) (xy 347.981017 -262.649144) (xy 348.000308 -262.603868)
			(xy 348.026611 -262.562272) (xy 348.059246 -262.525435) (xy 348.097367 -262.49431) (xy 348.139988 -262.469703)
			(xy 348.186004 -262.452251) (xy 348.234223 -262.442407) (xy 348.283398 -262.440426) (xy 348.332253 -262.446358)
			(xy 348.379524 -262.46005) (xy 348.423986 -262.481148) (xy 348.464489 -262.509104) (xy 348.499982 -262.543196)
			(xy 348.529547 -262.58254) (xy 348.552418 -262.626117) (xy 348.568002 -262.672798) (xy 348.575897 -262.721375)
			(xy 348.576392 -262.745982) (xy 348.575897 -262.770589) (xy 348.568002 -262.819166) (xy 348.552418 -262.865847)
			(xy 348.529547 -262.909424) (xy 348.499982 -262.948768) (xy 348.464489 -262.98286) (xy 348.423986 -263.010816)
			(xy 348.379524 -263.031914) (xy 348.332253 -263.045606) (xy 348.283398 -263.051538) (xy 348.234223 -263.049557)
			(xy 348.186004 -263.039713) (xy 348.139988 -263.022261) (xy 348.097367 -262.997654) (xy 348.059246 -262.966529)
			(xy 348.026611 -262.929692) (xy 348.000308 -262.888096) (xy 347.981017 -262.84282) (xy 347.96924 -262.795036)
			(xy 347.96528 -262.745982) (xy 346.696538 -262.745982) (xy 346.696043 -262.770589) (xy 346.688148 -262.819166)
			(xy 346.672564 -262.865847) (xy 346.649693 -262.909424) (xy 346.620128 -262.948768) (xy 346.584635 -262.98286)
			(xy 346.544132 -263.010816) (xy 346.49967 -263.031914) (xy 346.452399 -263.045606) (xy 346.403544 -263.051538)
			(xy 346.354369 -263.049557) (xy 346.30615 -263.039713) (xy 346.260134 -263.022261) (xy 346.217513 -262.997654)
			(xy 346.179392 -262.966529) (xy 346.146757 -262.929692) (xy 346.120454 -262.888096) (xy 346.101163 -262.84282)
			(xy 346.089386 -262.795036) (xy 346.085426 -262.745982) (xy 344.81643 -262.745982) (xy 344.815935 -262.770589)
			(xy 344.80804 -262.819166) (xy 344.792456 -262.865847) (xy 344.769585 -262.909424) (xy 344.74002 -262.948768)
			(xy 344.704527 -262.98286) (xy 344.664024 -263.010816) (xy 344.619562 -263.031914) (xy 344.572291 -263.045606)
			(xy 344.523436 -263.051538) (xy 344.474261 -263.049557) (xy 344.426042 -263.039713) (xy 344.380026 -263.022261)
			(xy 344.337405 -262.997654) (xy 344.299284 -262.966529) (xy 344.266649 -262.929692) (xy 344.240346 -262.888096)
			(xy 344.221055 -262.84282) (xy 344.209278 -262.795036) (xy 344.205318 -262.745982) (xy 343.88679 -262.745982)
			(xy 343.886278 -262.771428) (xy 343.878114 -262.821662) (xy 343.861998 -262.869936) (xy 343.838347 -262.914999)
			(xy 343.807774 -262.955685) (xy 343.77107 -262.99094) (xy 343.729186 -263.01985) (xy 343.683207 -263.041667)
			(xy 343.634323 -263.055827) (xy 343.583802 -263.061961) (xy 343.53295 -263.059912) (xy 343.483086 -263.049732)
			(xy 343.4355 -263.031685) (xy 343.391426 -263.006239) (xy 343.352004 -262.974052) (xy 343.318256 -262.935958)
			(xy 343.291055 -262.892944) (xy 343.271107 -262.846124) (xy 343.258928 -262.79671) (xy 343.254833 -262.745982)
			(xy 342.946736 -262.745982) (xy 342.946224 -262.771428) (xy 342.93806 -262.821662) (xy 342.921944 -262.869936)
			(xy 342.898293 -262.914999) (xy 342.86772 -262.955685) (xy 342.831016 -262.99094) (xy 342.789132 -263.01985)
			(xy 342.743153 -263.041667) (xy 342.694269 -263.055827) (xy 342.643748 -263.061961) (xy 342.592896 -263.059912)
			(xy 342.543032 -263.049732) (xy 342.495446 -263.031685) (xy 342.451372 -263.006239) (xy 342.41195 -262.974052)
			(xy 342.378202 -262.935958) (xy 342.351001 -262.892944) (xy 342.331053 -262.846124) (xy 342.318874 -262.79671)
			(xy 342.314779 -262.745982) (xy 341.996522 -262.745982) (xy 341.996027 -262.770589) (xy 341.988132 -262.819166)
			(xy 341.972548 -262.865847) (xy 341.949677 -262.909424) (xy 341.920112 -262.948768) (xy 341.884619 -262.98286)
			(xy 341.844116 -263.010816) (xy 341.799654 -263.031914) (xy 341.752383 -263.045606) (xy 341.703528 -263.051538)
			(xy 341.654353 -263.049557) (xy 341.606134 -263.039713) (xy 341.560118 -263.022261) (xy 341.517497 -262.997654)
			(xy 341.479376 -262.966529) (xy 341.446741 -262.929692) (xy 341.420438 -262.888096) (xy 341.401147 -262.84282)
			(xy 341.38937 -262.795036) (xy 341.38541 -262.745982) (xy 341.066882 -262.745982) (xy 341.06637 -262.771428)
			(xy 341.058206 -262.821662) (xy 341.04209 -262.869936) (xy 341.018439 -262.914999) (xy 340.987866 -262.955685)
			(xy 340.951162 -262.99094) (xy 340.909278 -263.01985) (xy 340.863299 -263.041667) (xy 340.814415 -263.055827)
			(xy 340.763894 -263.061961) (xy 340.713042 -263.059912) (xy 340.663178 -263.049732) (xy 340.615592 -263.031685)
			(xy 340.571518 -263.006239) (xy 340.532096 -262.974052) (xy 340.498348 -262.935958) (xy 340.471147 -262.892944)
			(xy 340.451199 -262.846124) (xy 340.43902 -262.79671) (xy 340.434925 -262.745982) (xy 340.116414 -262.745982)
			(xy 340.115919 -262.770589) (xy 340.108024 -262.819166) (xy 340.09244 -262.865847) (xy 340.069569 -262.909424)
			(xy 340.040004 -262.948768) (xy 340.004511 -262.98286) (xy 339.964008 -263.010816) (xy 339.919546 -263.031914)
			(xy 339.872275 -263.045606) (xy 339.82342 -263.051538) (xy 339.774245 -263.049557) (xy 339.726026 -263.039713)
			(xy 339.68001 -263.022261) (xy 339.637389 -262.997654) (xy 339.599268 -262.966529) (xy 339.566633 -262.929692)
			(xy 339.54033 -262.888096) (xy 339.521039 -262.84282) (xy 339.509262 -262.795036) (xy 339.505302 -262.745982)
			(xy 339.186774 -262.745982) (xy 339.186262 -262.771428) (xy 339.178098 -262.821662) (xy 339.161982 -262.869936)
			(xy 339.138331 -262.914999) (xy 339.107758 -262.955685) (xy 339.071054 -262.99094) (xy 339.02917 -263.01985)
			(xy 338.983191 -263.041667) (xy 338.934307 -263.055827) (xy 338.883786 -263.061961) (xy 338.832934 -263.059912)
			(xy 338.78307 -263.049732) (xy 338.735484 -263.031685) (xy 338.69141 -263.006239) (xy 338.651988 -262.974052)
			(xy 338.61824 -262.935958) (xy 338.591039 -262.892944) (xy 338.571091 -262.846124) (xy 338.558912 -262.79671)
			(xy 338.554817 -262.745982) (xy 338.236306 -262.745982) (xy 338.235811 -262.770589) (xy 338.227916 -262.819166)
			(xy 338.212332 -262.865847) (xy 338.189461 -262.909424) (xy 338.159896 -262.948768) (xy 338.124403 -262.98286)
			(xy 338.0839 -263.010816) (xy 338.039438 -263.031914) (xy 337.992167 -263.045606) (xy 337.943312 -263.051538)
			(xy 337.894137 -263.049557) (xy 337.845918 -263.039713) (xy 337.799902 -263.022261) (xy 337.757281 -262.997654)
			(xy 337.71916 -262.966529) (xy 337.686525 -262.929692) (xy 337.660222 -262.888096) (xy 337.640931 -262.84282)
			(xy 337.629154 -262.795036) (xy 337.625194 -262.745982) (xy 337.30692 -262.745982) (xy 337.306408 -262.771428)
			(xy 337.298244 -262.821662) (xy 337.282128 -262.869936) (xy 337.258477 -262.914999) (xy 337.227904 -262.955685)
			(xy 337.1912 -262.99094) (xy 337.149316 -263.01985) (xy 337.103337 -263.041667) (xy 337.054453 -263.055827)
			(xy 337.003932 -263.061961) (xy 336.95308 -263.059912) (xy 336.903216 -263.049732) (xy 336.85563 -263.031685)
			(xy 336.811556 -263.006239) (xy 336.772134 -262.974052) (xy 336.738386 -262.935958) (xy 336.711185 -262.892944)
			(xy 336.691237 -262.846124) (xy 336.679058 -262.79671) (xy 336.674963 -262.745982) (xy 336.366866 -262.745982)
			(xy 336.366354 -262.771428) (xy 336.35819 -262.821662) (xy 336.342074 -262.869936) (xy 336.318423 -262.914999)
			(xy 336.28785 -262.955685) (xy 336.251146 -262.99094) (xy 336.209262 -263.01985) (xy 336.163283 -263.041667)
			(xy 336.114399 -263.055827) (xy 336.063878 -263.061961) (xy 336.013026 -263.059912) (xy 335.963162 -263.049732)
			(xy 335.915576 -263.031685) (xy 335.871502 -263.006239) (xy 335.83208 -262.974052) (xy 335.798332 -262.935958)
			(xy 335.771131 -262.892944) (xy 335.751183 -262.846124) (xy 335.739004 -262.79671) (xy 335.734909 -262.745982)
			(xy 335.416398 -262.745982) (xy 335.415903 -262.770589) (xy 335.408008 -262.819166) (xy 335.392424 -262.865847)
			(xy 335.369553 -262.909424) (xy 335.339988 -262.948768) (xy 335.304495 -262.98286) (xy 335.263992 -263.010816)
			(xy 335.21953 -263.031914) (xy 335.172259 -263.045606) (xy 335.123404 -263.051538) (xy 335.074229 -263.049557)
			(xy 335.02601 -263.039713) (xy 334.979994 -263.022261) (xy 334.937373 -262.997654) (xy 334.899252 -262.966529)
			(xy 334.866617 -262.929692) (xy 334.840314 -262.888096) (xy 334.821023 -262.84282) (xy 334.809246 -262.795036)
			(xy 334.805286 -262.745982) (xy 334.486758 -262.745982) (xy 334.486246 -262.771428) (xy 334.478082 -262.821662)
			(xy 334.461966 -262.869936) (xy 334.438315 -262.914999) (xy 334.407742 -262.955685) (xy 334.371038 -262.99094)
			(xy 334.329154 -263.01985) (xy 334.283175 -263.041667) (xy 334.234291 -263.055827) (xy 334.18377 -263.061961)
			(xy 334.132918 -263.059912) (xy 334.083054 -263.049732) (xy 334.035468 -263.031685) (xy 333.991394 -263.006239)
			(xy 333.951972 -262.974052) (xy 333.918224 -262.935958) (xy 333.891023 -262.892944) (xy 333.871075 -262.846124)
			(xy 333.858896 -262.79671) (xy 333.854801 -262.745982) (xy 333.53629 -262.745982) (xy 333.535795 -262.770589)
			(xy 333.5279 -262.819166) (xy 333.512316 -262.865847) (xy 333.489445 -262.909424) (xy 333.45988 -262.948768)
			(xy 333.424387 -262.98286) (xy 333.383884 -263.010816) (xy 333.339422 -263.031914) (xy 333.292151 -263.045606)
			(xy 333.243296 -263.051538) (xy 333.194121 -263.049557) (xy 333.145902 -263.039713) (xy 333.099886 -263.022261)
			(xy 333.057265 -262.997654) (xy 333.019144 -262.966529) (xy 332.986509 -262.929692) (xy 332.960206 -262.888096)
			(xy 332.940915 -262.84282) (xy 332.929138 -262.795036) (xy 332.925178 -262.745982) (xy 332.606904 -262.745982)
			(xy 332.606392 -262.771428) (xy 332.598228 -262.821662) (xy 332.582112 -262.869936) (xy 332.558461 -262.914999)
			(xy 332.527888 -262.955685) (xy 332.491184 -262.99094) (xy 332.4493 -263.01985) (xy 332.403321 -263.041667)
			(xy 332.354437 -263.055827) (xy 332.303916 -263.061961) (xy 332.253064 -263.059912) (xy 332.2032 -263.049732)
			(xy 332.155614 -263.031685) (xy 332.11154 -263.006239) (xy 332.072118 -262.974052) (xy 332.03837 -262.935958)
			(xy 332.011169 -262.892944) (xy 331.991221 -262.846124) (xy 331.979042 -262.79671) (xy 331.974947 -262.745982)
			(xy 331.656436 -262.745982) (xy 331.655941 -262.770589) (xy 331.648046 -262.819166) (xy 331.632462 -262.865847)
			(xy 331.609591 -262.909424) (xy 331.580026 -262.948768) (xy 331.544533 -262.98286) (xy 331.50403 -263.010816)
			(xy 331.459568 -263.031914) (xy 331.412297 -263.045606) (xy 331.363442 -263.051538) (xy 331.314267 -263.049557)
			(xy 331.266048 -263.039713) (xy 331.220032 -263.022261) (xy 331.177411 -262.997654) (xy 331.13929 -262.966529)
			(xy 331.106655 -262.929692) (xy 331.080352 -262.888096) (xy 331.061061 -262.84282) (xy 331.049284 -262.795036)
			(xy 331.045324 -262.745982) (xy 330.726796 -262.745982) (xy 330.726284 -262.771428) (xy 330.71812 -262.821662)
			(xy 330.702004 -262.869936) (xy 330.678353 -262.914999) (xy 330.64778 -262.955685) (xy 330.611076 -262.99094)
			(xy 330.569192 -263.01985) (xy 330.523213 -263.041667) (xy 330.474329 -263.055827) (xy 330.423808 -263.061961)
			(xy 330.372956 -263.059912) (xy 330.323092 -263.049732) (xy 330.275506 -263.031685) (xy 330.231432 -263.006239)
			(xy 330.19201 -262.974052) (xy 330.158262 -262.935958) (xy 330.131061 -262.892944) (xy 330.111113 -262.846124)
			(xy 330.098934 -262.79671) (xy 330.094839 -262.745982) (xy 329.786742 -262.745982) (xy 329.78623 -262.771428)
			(xy 329.778066 -262.821662) (xy 329.76195 -262.869936) (xy 329.738299 -262.914999) (xy 329.707726 -262.955685)
			(xy 329.671022 -262.99094) (xy 329.629138 -263.01985) (xy 329.583159 -263.041667) (xy 329.534275 -263.055827)
			(xy 329.483754 -263.061961) (xy 329.432902 -263.059912) (xy 329.383038 -263.049732) (xy 329.335452 -263.031685)
			(xy 329.291378 -263.006239) (xy 329.251956 -262.974052) (xy 329.218208 -262.935958) (xy 329.191007 -262.892944)
			(xy 329.171059 -262.846124) (xy 329.15888 -262.79671) (xy 329.154785 -262.745982) (xy 328.836528 -262.745982)
			(xy 328.836033 -262.770589) (xy 328.828138 -262.819166) (xy 328.812554 -262.865847) (xy 328.789683 -262.909424)
			(xy 328.760118 -262.948768) (xy 328.724625 -262.98286) (xy 328.684122 -263.010816) (xy 328.63966 -263.031914)
			(xy 328.592389 -263.045606) (xy 328.543534 -263.051538) (xy 328.494359 -263.049557) (xy 328.44614 -263.039713)
			(xy 328.400124 -263.022261) (xy 328.357503 -262.997654) (xy 328.319382 -262.966529) (xy 328.286747 -262.929692)
			(xy 328.260444 -262.888096) (xy 328.241153 -262.84282) (xy 328.229376 -262.795036) (xy 328.225416 -262.745982)
			(xy 326.95642 -262.745982) (xy 326.955925 -262.770589) (xy 326.94803 -262.819166) (xy 326.932446 -262.865847)
			(xy 326.909575 -262.909424) (xy 326.88001 -262.948768) (xy 326.844517 -262.98286) (xy 326.804014 -263.010816)
			(xy 326.759552 -263.031914) (xy 326.712281 -263.045606) (xy 326.663426 -263.051538) (xy 326.614251 -263.049557)
			(xy 326.566032 -263.039713) (xy 326.520016 -263.022261) (xy 326.477395 -262.997654) (xy 326.439274 -262.966529)
			(xy 326.406639 -262.929692) (xy 326.380336 -262.888096) (xy 326.361045 -262.84282) (xy 326.349268 -262.795036)
			(xy 326.345308 -262.745982) (xy 310.45912 -262.745982) (xy 310.45912 -263.29005) (xy 324.74714 -263.29005)
			(xy 324.7511 -263.240996) (xy 324.762877 -263.193212) (xy 324.782168 -263.147936) (xy 324.808471 -263.10634)
			(xy 324.841106 -263.069503) (xy 324.879227 -263.038378) (xy 324.921848 -263.013771) (xy 324.967864 -262.996319)
			(xy 325.016083 -262.986475) (xy 325.065258 -262.984494) (xy 325.114113 -262.990426) (xy 325.161384 -263.004118)
			(xy 325.205846 -263.025216) (xy 325.246349 -263.053172) (xy 325.281842 -263.087264) (xy 325.311407 -263.126608)
			(xy 325.334278 -263.170185) (xy 325.349862 -263.216866) (xy 325.357757 -263.265443) (xy 325.358252 -263.29005)
			(xy 325.357757 -263.314657) (xy 325.349862 -263.363234) (xy 325.334278 -263.409915) (xy 325.311407 -263.453492)
			(xy 325.281842 -263.492836) (xy 325.246349 -263.526928) (xy 325.205846 -263.554884) (xy 325.203519 -263.555988)
			(xy 328.684885 -263.555988) (xy 328.68898 -263.50526) (xy 328.701159 -263.455846) (xy 328.721107 -263.409026)
			(xy 328.748308 -263.366012) (xy 328.782056 -263.327918) (xy 328.821478 -263.295731) (xy 328.865552 -263.270285)
			(xy 328.913138 -263.252238) (xy 328.963002 -263.242058) (xy 329.013854 -263.240009) (xy 329.064375 -263.246143)
			(xy 329.113259 -263.260303) (xy 329.159238 -263.28212) (xy 329.201122 -263.31103) (xy 329.237826 -263.346285)
			(xy 329.268399 -263.386971) (xy 329.29205 -263.432034) (xy 329.308166 -263.480308) (xy 329.31633 -263.530542)
			(xy 329.316842 -263.555988) (xy 329.63537 -263.555988) (xy 329.63933 -263.506934) (xy 329.651107 -263.45915)
			(xy 329.670398 -263.413874) (xy 329.696701 -263.372278) (xy 329.729336 -263.335441) (xy 329.767457 -263.304316)
			(xy 329.810078 -263.279709) (xy 329.856094 -263.262257) (xy 329.904313 -263.252413) (xy 329.953488 -263.250432)
			(xy 330.002343 -263.256364) (xy 330.049614 -263.270056) (xy 330.094076 -263.291154) (xy 330.134579 -263.31911)
			(xy 330.170072 -263.353202) (xy 330.199637 -263.392546) (xy 330.222508 -263.436123) (xy 330.238092 -263.482804)
			(xy 330.245987 -263.531381) (xy 330.246482 -263.555988) (xy 330.564739 -263.555988) (xy 330.568834 -263.50526)
			(xy 330.581013 -263.455846) (xy 330.600961 -263.409026) (xy 330.628162 -263.366012) (xy 330.66191 -263.327918)
			(xy 330.701332 -263.295731) (xy 330.745406 -263.270285) (xy 330.792992 -263.252238) (xy 330.842856 -263.242058)
			(xy 330.893708 -263.240009) (xy 330.944229 -263.246143) (xy 330.993113 -263.260303) (xy 331.039092 -263.28212)
			(xy 331.080976 -263.31103) (xy 331.11768 -263.346285) (xy 331.148253 -263.386971) (xy 331.171904 -263.432034)
			(xy 331.18802 -263.480308) (xy 331.196184 -263.530542) (xy 331.196696 -263.555988) (xy 331.515224 -263.555988)
			(xy 331.519184 -263.506934) (xy 331.530961 -263.45915) (xy 331.550252 -263.413874) (xy 331.576555 -263.372278)
			(xy 331.60919 -263.335441) (xy 331.647311 -263.304316) (xy 331.689932 -263.279709) (xy 331.735948 -263.262257)
			(xy 331.784167 -263.252413) (xy 331.833342 -263.250432) (xy 331.882197 -263.256364) (xy 331.929468 -263.270056)
			(xy 331.97393 -263.291154) (xy 332.014433 -263.31911) (xy 332.049926 -263.353202) (xy 332.079491 -263.392546)
			(xy 332.102362 -263.436123) (xy 332.117946 -263.482804) (xy 332.125841 -263.531381) (xy 332.126336 -263.555988)
			(xy 332.444847 -263.555988) (xy 332.448942 -263.50526) (xy 332.461121 -263.455846) (xy 332.481069 -263.409026)
			(xy 332.50827 -263.366012) (xy 332.542018 -263.327918) (xy 332.58144 -263.295731) (xy 332.625514 -263.270285)
			(xy 332.6731 -263.252238) (xy 332.722964 -263.242058) (xy 332.773816 -263.240009) (xy 332.824337 -263.246143)
			(xy 332.873221 -263.260303) (xy 332.9192 -263.28212) (xy 332.961084 -263.31103) (xy 332.997788 -263.346285)
			(xy 333.028361 -263.386971) (xy 333.052012 -263.432034) (xy 333.068128 -263.480308) (xy 333.076292 -263.530542)
			(xy 333.076804 -263.555988) (xy 333.384901 -263.555988) (xy 333.388996 -263.50526) (xy 333.401175 -263.455846)
			(xy 333.421123 -263.409026) (xy 333.448324 -263.366012) (xy 333.482072 -263.327918) (xy 333.521494 -263.295731)
			(xy 333.565568 -263.270285) (xy 333.613154 -263.252238) (xy 333.663018 -263.242058) (xy 333.71387 -263.240009)
			(xy 333.764391 -263.246143) (xy 333.813275 -263.260303) (xy 333.859254 -263.28212) (xy 333.901138 -263.31103)
			(xy 333.937842 -263.346285) (xy 333.968415 -263.386971) (xy 333.992066 -263.432034) (xy 334.008182 -263.480308)
			(xy 334.016346 -263.530542) (xy 334.016858 -263.555988) (xy 335.264755 -263.555988) (xy 335.26885 -263.50526)
			(xy 335.281029 -263.455846) (xy 335.300977 -263.409026) (xy 335.328178 -263.366012) (xy 335.361926 -263.327918)
			(xy 335.401348 -263.295731) (xy 335.445422 -263.270285) (xy 335.493008 -263.252238) (xy 335.542872 -263.242058)
			(xy 335.593724 -263.240009) (xy 335.644245 -263.246143) (xy 335.693129 -263.260303) (xy 335.739108 -263.28212)
			(xy 335.780992 -263.31103) (xy 335.817696 -263.346285) (xy 335.848269 -263.386971) (xy 335.87192 -263.432034)
			(xy 335.888036 -263.480308) (xy 335.8962 -263.530542) (xy 335.896712 -263.555988) (xy 336.21524 -263.555988)
			(xy 336.2192 -263.506934) (xy 336.230977 -263.45915) (xy 336.250268 -263.413874) (xy 336.276571 -263.372278)
			(xy 336.309206 -263.335441) (xy 336.347327 -263.304316) (xy 336.389948 -263.279709) (xy 336.435964 -263.262257)
			(xy 336.484183 -263.252413) (xy 336.533358 -263.250432) (xy 336.582213 -263.256364) (xy 336.629484 -263.270056)
			(xy 336.673946 -263.291154) (xy 336.714449 -263.31911) (xy 336.749942 -263.353202) (xy 336.779507 -263.392546)
			(xy 336.802378 -263.436123) (xy 336.817962 -263.482804) (xy 336.825857 -263.531381) (xy 336.826352 -263.555988)
			(xy 337.144863 -263.555988) (xy 337.148958 -263.50526) (xy 337.161137 -263.455846) (xy 337.181085 -263.409026)
			(xy 337.208286 -263.366012) (xy 337.242034 -263.327918) (xy 337.281456 -263.295731) (xy 337.32553 -263.270285)
			(xy 337.373116 -263.252238) (xy 337.42298 -263.242058) (xy 337.473832 -263.240009) (xy 337.524353 -263.246143)
			(xy 337.573237 -263.260303) (xy 337.619216 -263.28212) (xy 337.6611 -263.31103) (xy 337.697804 -263.346285)
			(xy 337.728377 -263.386971) (xy 337.752028 -263.432034) (xy 337.768144 -263.480308) (xy 337.776308 -263.530542)
			(xy 337.77682 -263.555988) (xy 338.095348 -263.555988) (xy 338.099308 -263.506934) (xy 338.111085 -263.45915)
			(xy 338.130376 -263.413874) (xy 338.156679 -263.372278) (xy 338.189314 -263.335441) (xy 338.227435 -263.304316)
			(xy 338.270056 -263.279709) (xy 338.316072 -263.262257) (xy 338.364291 -263.252413) (xy 338.413466 -263.250432)
			(xy 338.462321 -263.256364) (xy 338.509592 -263.270056) (xy 338.554054 -263.291154) (xy 338.594557 -263.31911)
			(xy 338.63005 -263.353202) (xy 338.659615 -263.392546) (xy 338.682486 -263.436123) (xy 338.69807 -263.482804)
			(xy 338.705965 -263.531381) (xy 338.70646 -263.555988) (xy 339.024971 -263.555988) (xy 339.029066 -263.50526)
			(xy 339.041245 -263.455846) (xy 339.061193 -263.409026) (xy 339.088394 -263.366012) (xy 339.122142 -263.327918)
			(xy 339.161564 -263.295731) (xy 339.205638 -263.270285) (xy 339.253224 -263.252238) (xy 339.303088 -263.242058)
			(xy 339.35394 -263.240009) (xy 339.404461 -263.246143) (xy 339.453345 -263.260303) (xy 339.499324 -263.28212)
			(xy 339.541208 -263.31103) (xy 339.577912 -263.346285) (xy 339.608485 -263.386971) (xy 339.632136 -263.432034)
			(xy 339.648252 -263.480308) (xy 339.656416 -263.530542) (xy 339.656928 -263.555988) (xy 339.964771 -263.555988)
			(xy 339.968866 -263.50526) (xy 339.981045 -263.455846) (xy 340.000993 -263.409026) (xy 340.028194 -263.366012)
			(xy 340.061942 -263.327918) (xy 340.101364 -263.295731) (xy 340.145438 -263.270285) (xy 340.193024 -263.252238)
			(xy 340.242888 -263.242058) (xy 340.29374 -263.240009) (xy 340.344261 -263.246143) (xy 340.393145 -263.260303)
			(xy 340.439124 -263.28212) (xy 340.481008 -263.31103) (xy 340.517712 -263.346285) (xy 340.548285 -263.386971)
			(xy 340.571936 -263.432034) (xy 340.588052 -263.480308) (xy 340.596216 -263.530542) (xy 340.596728 -263.555988)
			(xy 341.844879 -263.555988) (xy 341.848974 -263.50526) (xy 341.861153 -263.455846) (xy 341.881101 -263.409026)
			(xy 341.908302 -263.366012) (xy 341.94205 -263.327918) (xy 341.981472 -263.295731) (xy 342.025546 -263.270285)
			(xy 342.073132 -263.252238) (xy 342.122996 -263.242058) (xy 342.173848 -263.240009) (xy 342.224369 -263.246143)
			(xy 342.273253 -263.260303) (xy 342.319232 -263.28212) (xy 342.361116 -263.31103) (xy 342.39782 -263.346285)
			(xy 342.428393 -263.386971) (xy 342.452044 -263.432034) (xy 342.46816 -263.480308) (xy 342.476324 -263.530542)
			(xy 342.476836 -263.555988) (xy 342.795364 -263.555988) (xy 342.799324 -263.506934) (xy 342.811101 -263.45915)
			(xy 342.830392 -263.413874) (xy 342.856695 -263.372278) (xy 342.88933 -263.335441) (xy 342.927451 -263.304316)
			(xy 342.970072 -263.279709) (xy 343.016088 -263.262257) (xy 343.064307 -263.252413) (xy 343.113482 -263.250432)
			(xy 343.162337 -263.256364) (xy 343.209608 -263.270056) (xy 343.25407 -263.291154) (xy 343.294573 -263.31911)
			(xy 343.330066 -263.353202) (xy 343.359631 -263.392546) (xy 343.382502 -263.436123) (xy 343.398086 -263.482804)
			(xy 343.405981 -263.531381) (xy 343.406476 -263.555988) (xy 343.724987 -263.555988) (xy 343.729082 -263.50526)
			(xy 343.741261 -263.455846) (xy 343.761209 -263.409026) (xy 343.78841 -263.366012) (xy 343.822158 -263.327918)
			(xy 343.86158 -263.295731) (xy 343.905654 -263.270285) (xy 343.95324 -263.252238) (xy 344.003104 -263.242058)
			(xy 344.053956 -263.240009) (xy 344.104477 -263.246143) (xy 344.153361 -263.260303) (xy 344.19934 -263.28212)
			(xy 344.241224 -263.31103) (xy 344.277928 -263.346285) (xy 344.308501 -263.386971) (xy 344.332152 -263.432034)
			(xy 344.348268 -263.480308) (xy 344.356432 -263.530542) (xy 344.356944 -263.555988) (xy 345.615272 -263.555988)
			(xy 345.619232 -263.506934) (xy 345.631009 -263.45915) (xy 345.6503 -263.413874) (xy 345.676603 -263.372278)
			(xy 345.709238 -263.335441) (xy 345.747359 -263.304316) (xy 345.78998 -263.279709) (xy 345.835996 -263.262257)
			(xy 345.884215 -263.252413) (xy 345.93339 -263.250432) (xy 345.982245 -263.256364) (xy 346.029516 -263.270056)
			(xy 346.073978 -263.291154) (xy 346.114481 -263.31911) (xy 346.149974 -263.353202) (xy 346.179539 -263.392546)
			(xy 346.20241 -263.436123) (xy 346.217994 -263.482804) (xy 346.225889 -263.531381) (xy 346.226384 -263.555988)
			(xy 347.49538 -263.555988) (xy 347.49934 -263.506934) (xy 347.511117 -263.45915) (xy 347.530408 -263.413874)
			(xy 347.556711 -263.372278) (xy 347.589346 -263.335441) (xy 347.627467 -263.304316) (xy 347.670088 -263.279709)
			(xy 347.716104 -263.262257) (xy 347.764323 -263.252413) (xy 347.813498 -263.250432) (xy 347.862353 -263.256364)
			(xy 347.909624 -263.270056) (xy 347.954086 -263.291154) (xy 347.994589 -263.31911) (xy 348.030082 -263.353202)
			(xy 348.059647 -263.392546) (xy 348.082518 -263.436123) (xy 348.098102 -263.482804) (xy 348.105997 -263.531381)
			(xy 348.106492 -263.555988) (xy 348.105997 -263.580595) (xy 348.098102 -263.629172) (xy 348.082518 -263.675853)
			(xy 348.059647 -263.71943) (xy 348.030082 -263.758774) (xy 347.994589 -263.792866) (xy 347.954086 -263.820822)
			(xy 347.909624 -263.84192) (xy 347.862353 -263.855612) (xy 347.813498 -263.861544) (xy 347.764323 -263.859563)
			(xy 347.716104 -263.849719) (xy 347.670088 -263.832267) (xy 347.627467 -263.80766) (xy 347.589346 -263.776535)
			(xy 347.556711 -263.739698) (xy 347.530408 -263.698102) (xy 347.511117 -263.652826) (xy 347.49934 -263.605042)
			(xy 347.49538 -263.555988) (xy 346.226384 -263.555988) (xy 346.225889 -263.580595) (xy 346.217994 -263.629172)
			(xy 346.20241 -263.675853) (xy 346.179539 -263.71943) (xy 346.149974 -263.758774) (xy 346.114481 -263.792866)
			(xy 346.073978 -263.820822) (xy 346.029516 -263.84192) (xy 345.982245 -263.855612) (xy 345.93339 -263.861544)
			(xy 345.884215 -263.859563) (xy 345.835996 -263.849719) (xy 345.78998 -263.832267) (xy 345.747359 -263.80766)
			(xy 345.709238 -263.776535) (xy 345.676603 -263.739698) (xy 345.6503 -263.698102) (xy 345.631009 -263.652826)
			(xy 345.619232 -263.605042) (xy 345.615272 -263.555988) (xy 344.356944 -263.555988) (xy 344.356432 -263.581434)
			(xy 344.348268 -263.631668) (xy 344.332152 -263.679942) (xy 344.308501 -263.725005) (xy 344.277928 -263.765691)
			(xy 344.241224 -263.800946) (xy 344.19934 -263.829856) (xy 344.153361 -263.851673) (xy 344.104477 -263.865833)
			(xy 344.053956 -263.871967) (xy 344.003104 -263.869918) (xy 343.95324 -263.859738) (xy 343.905654 -263.841691)
			(xy 343.86158 -263.816245) (xy 343.822158 -263.784058) (xy 343.78841 -263.745964) (xy 343.761209 -263.70295)
			(xy 343.741261 -263.65613) (xy 343.729082 -263.606716) (xy 343.724987 -263.555988) (xy 343.406476 -263.555988)
			(xy 343.405981 -263.580595) (xy 343.398086 -263.629172) (xy 343.382502 -263.675853) (xy 343.359631 -263.71943)
			(xy 343.330066 -263.758774) (xy 343.294573 -263.792866) (xy 343.25407 -263.820822) (xy 343.209608 -263.84192)
			(xy 343.162337 -263.855612) (xy 343.113482 -263.861544) (xy 343.064307 -263.859563) (xy 343.016088 -263.849719)
			(xy 342.970072 -263.832267) (xy 342.927451 -263.80766) (xy 342.88933 -263.776535) (xy 342.856695 -263.739698)
			(xy 342.830392 -263.698102) (xy 342.811101 -263.652826) (xy 342.799324 -263.605042) (xy 342.795364 -263.555988)
			(xy 342.476836 -263.555988) (xy 342.476324 -263.581434) (xy 342.46816 -263.631668) (xy 342.452044 -263.679942)
			(xy 342.428393 -263.725005) (xy 342.39782 -263.765691) (xy 342.361116 -263.800946) (xy 342.319232 -263.829856)
			(xy 342.273253 -263.851673) (xy 342.224369 -263.865833) (xy 342.173848 -263.871967) (xy 342.122996 -263.869918)
			(xy 342.073132 -263.859738) (xy 342.025546 -263.841691) (xy 341.981472 -263.816245) (xy 341.94205 -263.784058)
			(xy 341.908302 -263.745964) (xy 341.881101 -263.70295) (xy 341.861153 -263.65613) (xy 341.848974 -263.606716)
			(xy 341.844879 -263.555988) (xy 340.596728 -263.555988) (xy 340.596216 -263.581434) (xy 340.588052 -263.631668)
			(xy 340.571936 -263.679942) (xy 340.548285 -263.725005) (xy 340.517712 -263.765691) (xy 340.481008 -263.800946)
			(xy 340.439124 -263.829856) (xy 340.393145 -263.851673) (xy 340.344261 -263.865833) (xy 340.29374 -263.871967)
			(xy 340.242888 -263.869918) (xy 340.193024 -263.859738) (xy 340.145438 -263.841691) (xy 340.101364 -263.816245)
			(xy 340.061942 -263.784058) (xy 340.028194 -263.745964) (xy 340.000993 -263.70295) (xy 339.981045 -263.65613)
			(xy 339.968866 -263.606716) (xy 339.964771 -263.555988) (xy 339.656928 -263.555988) (xy 339.656416 -263.581434)
			(xy 339.648252 -263.631668) (xy 339.632136 -263.679942) (xy 339.608485 -263.725005) (xy 339.577912 -263.765691)
			(xy 339.541208 -263.800946) (xy 339.499324 -263.829856) (xy 339.453345 -263.851673) (xy 339.404461 -263.865833)
			(xy 339.35394 -263.871967) (xy 339.303088 -263.869918) (xy 339.253224 -263.859738) (xy 339.205638 -263.841691)
			(xy 339.161564 -263.816245) (xy 339.122142 -263.784058) (xy 339.088394 -263.745964) (xy 339.061193 -263.70295)
			(xy 339.041245 -263.65613) (xy 339.029066 -263.606716) (xy 339.024971 -263.555988) (xy 338.70646 -263.555988)
			(xy 338.705965 -263.580595) (xy 338.69807 -263.629172) (xy 338.682486 -263.675853) (xy 338.659615 -263.71943)
			(xy 338.63005 -263.758774) (xy 338.594557 -263.792866) (xy 338.554054 -263.820822) (xy 338.509592 -263.84192)
			(xy 338.462321 -263.855612) (xy 338.413466 -263.861544) (xy 338.364291 -263.859563) (xy 338.316072 -263.849719)
			(xy 338.270056 -263.832267) (xy 338.227435 -263.80766) (xy 338.189314 -263.776535) (xy 338.156679 -263.739698)
			(xy 338.130376 -263.698102) (xy 338.111085 -263.652826) (xy 338.099308 -263.605042) (xy 338.095348 -263.555988)
			(xy 337.77682 -263.555988) (xy 337.776308 -263.581434) (xy 337.768144 -263.631668) (xy 337.752028 -263.679942)
			(xy 337.728377 -263.725005) (xy 337.697804 -263.765691) (xy 337.6611 -263.800946) (xy 337.619216 -263.829856)
			(xy 337.573237 -263.851673) (xy 337.524353 -263.865833) (xy 337.473832 -263.871967) (xy 337.42298 -263.869918)
			(xy 337.373116 -263.859738) (xy 337.32553 -263.841691) (xy 337.281456 -263.816245) (xy 337.242034 -263.784058)
			(xy 337.208286 -263.745964) (xy 337.181085 -263.70295) (xy 337.161137 -263.65613) (xy 337.148958 -263.606716)
			(xy 337.144863 -263.555988) (xy 336.826352 -263.555988) (xy 336.825857 -263.580595) (xy 336.817962 -263.629172)
			(xy 336.802378 -263.675853) (xy 336.779507 -263.71943) (xy 336.749942 -263.758774) (xy 336.714449 -263.792866)
			(xy 336.673946 -263.820822) (xy 336.629484 -263.84192) (xy 336.582213 -263.855612) (xy 336.533358 -263.861544)
			(xy 336.484183 -263.859563) (xy 336.435964 -263.849719) (xy 336.389948 -263.832267) (xy 336.347327 -263.80766)
			(xy 336.309206 -263.776535) (xy 336.276571 -263.739698) (xy 336.250268 -263.698102) (xy 336.230977 -263.652826)
			(xy 336.2192 -263.605042) (xy 336.21524 -263.555988) (xy 335.896712 -263.555988) (xy 335.8962 -263.581434)
			(xy 335.888036 -263.631668) (xy 335.87192 -263.679942) (xy 335.848269 -263.725005) (xy 335.817696 -263.765691)
			(xy 335.780992 -263.800946) (xy 335.739108 -263.829856) (xy 335.693129 -263.851673) (xy 335.644245 -263.865833)
			(xy 335.593724 -263.871967) (xy 335.542872 -263.869918) (xy 335.493008 -263.859738) (xy 335.445422 -263.841691)
			(xy 335.401348 -263.816245) (xy 335.361926 -263.784058) (xy 335.328178 -263.745964) (xy 335.300977 -263.70295)
			(xy 335.281029 -263.65613) (xy 335.26885 -263.606716) (xy 335.264755 -263.555988) (xy 334.016858 -263.555988)
			(xy 334.016346 -263.581434) (xy 334.008182 -263.631668) (xy 333.992066 -263.679942) (xy 333.968415 -263.725005)
			(xy 333.937842 -263.765691) (xy 333.901138 -263.800946) (xy 333.859254 -263.829856) (xy 333.813275 -263.851673)
			(xy 333.764391 -263.865833) (xy 333.71387 -263.871967) (xy 333.663018 -263.869918) (xy 333.613154 -263.859738)
			(xy 333.565568 -263.841691) (xy 333.521494 -263.816245) (xy 333.482072 -263.784058) (xy 333.448324 -263.745964)
			(xy 333.421123 -263.70295) (xy 333.401175 -263.65613) (xy 333.388996 -263.606716) (xy 333.384901 -263.555988)
			(xy 333.076804 -263.555988) (xy 333.076292 -263.581434) (xy 333.068128 -263.631668) (xy 333.052012 -263.679942)
			(xy 333.028361 -263.725005) (xy 332.997788 -263.765691) (xy 332.961084 -263.800946) (xy 332.9192 -263.829856)
			(xy 332.873221 -263.851673) (xy 332.824337 -263.865833) (xy 332.773816 -263.871967) (xy 332.722964 -263.869918)
			(xy 332.6731 -263.859738) (xy 332.625514 -263.841691) (xy 332.58144 -263.816245) (xy 332.542018 -263.784058)
			(xy 332.50827 -263.745964) (xy 332.481069 -263.70295) (xy 332.461121 -263.65613) (xy 332.448942 -263.606716)
			(xy 332.444847 -263.555988) (xy 332.126336 -263.555988) (xy 332.125841 -263.580595) (xy 332.117946 -263.629172)
			(xy 332.102362 -263.675853) (xy 332.079491 -263.71943) (xy 332.049926 -263.758774) (xy 332.014433 -263.792866)
			(xy 331.97393 -263.820822) (xy 331.929468 -263.84192) (xy 331.882197 -263.855612) (xy 331.833342 -263.861544)
			(xy 331.784167 -263.859563) (xy 331.735948 -263.849719) (xy 331.689932 -263.832267) (xy 331.647311 -263.80766)
			(xy 331.60919 -263.776535) (xy 331.576555 -263.739698) (xy 331.550252 -263.698102) (xy 331.530961 -263.652826)
			(xy 331.519184 -263.605042) (xy 331.515224 -263.555988) (xy 331.196696 -263.555988) (xy 331.196184 -263.581434)
			(xy 331.18802 -263.631668) (xy 331.171904 -263.679942) (xy 331.148253 -263.725005) (xy 331.11768 -263.765691)
			(xy 331.080976 -263.800946) (xy 331.039092 -263.829856) (xy 330.993113 -263.851673) (xy 330.944229 -263.865833)
			(xy 330.893708 -263.871967) (xy 330.842856 -263.869918) (xy 330.792992 -263.859738) (xy 330.745406 -263.841691)
			(xy 330.701332 -263.816245) (xy 330.66191 -263.784058) (xy 330.628162 -263.745964) (xy 330.600961 -263.70295)
			(xy 330.581013 -263.65613) (xy 330.568834 -263.606716) (xy 330.564739 -263.555988) (xy 330.246482 -263.555988)
			(xy 330.245987 -263.580595) (xy 330.238092 -263.629172) (xy 330.222508 -263.675853) (xy 330.199637 -263.71943)
			(xy 330.170072 -263.758774) (xy 330.134579 -263.792866) (xy 330.094076 -263.820822) (xy 330.049614 -263.84192)
			(xy 330.002343 -263.855612) (xy 329.953488 -263.861544) (xy 329.904313 -263.859563) (xy 329.856094 -263.849719)
			(xy 329.810078 -263.832267) (xy 329.767457 -263.80766) (xy 329.729336 -263.776535) (xy 329.696701 -263.739698)
			(xy 329.670398 -263.698102) (xy 329.651107 -263.652826) (xy 329.63933 -263.605042) (xy 329.63537 -263.555988)
			(xy 329.316842 -263.555988) (xy 329.31633 -263.581434) (xy 329.308166 -263.631668) (xy 329.29205 -263.679942)
			(xy 329.268399 -263.725005) (xy 329.237826 -263.765691) (xy 329.201122 -263.800946) (xy 329.159238 -263.829856)
			(xy 329.113259 -263.851673) (xy 329.064375 -263.865833) (xy 329.013854 -263.871967) (xy 328.963002 -263.869918)
			(xy 328.913138 -263.859738) (xy 328.865552 -263.841691) (xy 328.821478 -263.816245) (xy 328.782056 -263.784058)
			(xy 328.748308 -263.745964) (xy 328.721107 -263.70295) (xy 328.701159 -263.65613) (xy 328.68898 -263.606716)
			(xy 328.684885 -263.555988) (xy 325.203519 -263.555988) (xy 325.161384 -263.575982) (xy 325.114113 -263.589674)
			(xy 325.065258 -263.595606) (xy 325.016083 -263.593625) (xy 324.967864 -263.583781) (xy 324.921848 -263.566329)
			(xy 324.879227 -263.541722) (xy 324.841106 -263.510597) (xy 324.808471 -263.47376) (xy 324.782168 -263.432164)
			(xy 324.762877 -263.386888) (xy 324.7511 -263.339104) (xy 324.74714 -263.29005) (xy 310.45912 -263.29005)
			(xy 310.45912 -264.365994) (xy 326.345308 -264.365994) (xy 326.349268 -264.31694) (xy 326.361045 -264.269156)
			(xy 326.380336 -264.22388) (xy 326.406639 -264.182284) (xy 326.439274 -264.145447) (xy 326.477395 -264.114322)
			(xy 326.520016 -264.089715) (xy 326.566032 -264.072263) (xy 326.614251 -264.062419) (xy 326.663426 -264.060438)
			(xy 326.712281 -264.06637) (xy 326.759552 -264.080062) (xy 326.804014 -264.10116) (xy 326.844517 -264.129116)
			(xy 326.88001 -264.163208) (xy 326.909575 -264.202552) (xy 326.932446 -264.246129) (xy 326.94803 -264.29281)
			(xy 326.955925 -264.341387) (xy 326.95642 -264.365994) (xy 328.225416 -264.365994) (xy 328.229376 -264.31694)
			(xy 328.241153 -264.269156) (xy 328.260444 -264.22388) (xy 328.286747 -264.182284) (xy 328.319382 -264.145447)
			(xy 328.357503 -264.114322) (xy 328.400124 -264.089715) (xy 328.44614 -264.072263) (xy 328.494359 -264.062419)
			(xy 328.543534 -264.060438) (xy 328.592389 -264.06637) (xy 328.63966 -264.080062) (xy 328.684122 -264.10116)
			(xy 328.724625 -264.129116) (xy 328.760118 -264.163208) (xy 328.789683 -264.202552) (xy 328.812554 -264.246129)
			(xy 328.828138 -264.29281) (xy 328.836033 -264.341387) (xy 328.836528 -264.365994) (xy 329.154785 -264.365994)
			(xy 329.15888 -264.315266) (xy 329.171059 -264.265852) (xy 329.191007 -264.219032) (xy 329.218208 -264.176018)
			(xy 329.251956 -264.137924) (xy 329.291378 -264.105737) (xy 329.335452 -264.080291) (xy 329.383038 -264.062244)
			(xy 329.432902 -264.052064) (xy 329.483754 -264.050015) (xy 329.534275 -264.056149) (xy 329.583159 -264.070309)
			(xy 329.629138 -264.092126) (xy 329.671022 -264.121036) (xy 329.707726 -264.156291) (xy 329.738299 -264.196977)
			(xy 329.76195 -264.24204) (xy 329.778066 -264.290314) (xy 329.78623 -264.340548) (xy 329.786742 -264.365994)
			(xy 330.094839 -264.365994) (xy 330.098934 -264.315266) (xy 330.111113 -264.265852) (xy 330.131061 -264.219032)
			(xy 330.158262 -264.176018) (xy 330.19201 -264.137924) (xy 330.231432 -264.105737) (xy 330.275506 -264.080291)
			(xy 330.323092 -264.062244) (xy 330.372956 -264.052064) (xy 330.423808 -264.050015) (xy 330.474329 -264.056149)
			(xy 330.523213 -264.070309) (xy 330.569192 -264.092126) (xy 330.611076 -264.121036) (xy 330.64778 -264.156291)
			(xy 330.678353 -264.196977) (xy 330.702004 -264.24204) (xy 330.71812 -264.290314) (xy 330.726284 -264.340548)
			(xy 330.726796 -264.365994) (xy 331.045324 -264.365994) (xy 331.049284 -264.31694) (xy 331.061061 -264.269156)
			(xy 331.080352 -264.22388) (xy 331.106655 -264.182284) (xy 331.13929 -264.145447) (xy 331.177411 -264.114322)
			(xy 331.220032 -264.089715) (xy 331.266048 -264.072263) (xy 331.314267 -264.062419) (xy 331.363442 -264.060438)
			(xy 331.412297 -264.06637) (xy 331.459568 -264.080062) (xy 331.50403 -264.10116) (xy 331.544533 -264.129116)
			(xy 331.580026 -264.163208) (xy 331.609591 -264.202552) (xy 331.632462 -264.246129) (xy 331.648046 -264.29281)
			(xy 331.655941 -264.341387) (xy 331.656436 -264.365994) (xy 331.974947 -264.365994) (xy 331.979042 -264.315266)
			(xy 331.991221 -264.265852) (xy 332.011169 -264.219032) (xy 332.03837 -264.176018) (xy 332.072118 -264.137924)
			(xy 332.11154 -264.105737) (xy 332.155614 -264.080291) (xy 332.2032 -264.062244) (xy 332.253064 -264.052064)
			(xy 332.303916 -264.050015) (xy 332.354437 -264.056149) (xy 332.403321 -264.070309) (xy 332.4493 -264.092126)
			(xy 332.491184 -264.121036) (xy 332.527888 -264.156291) (xy 332.558461 -264.196977) (xy 332.582112 -264.24204)
			(xy 332.598228 -264.290314) (xy 332.606392 -264.340548) (xy 332.606904 -264.365994) (xy 332.925178 -264.365994)
			(xy 332.929138 -264.31694) (xy 332.940915 -264.269156) (xy 332.960206 -264.22388) (xy 332.986509 -264.182284)
			(xy 333.019144 -264.145447) (xy 333.057265 -264.114322) (xy 333.099886 -264.089715) (xy 333.145902 -264.072263)
			(xy 333.194121 -264.062419) (xy 333.243296 -264.060438) (xy 333.292151 -264.06637) (xy 333.339422 -264.080062)
			(xy 333.383884 -264.10116) (xy 333.424387 -264.129116) (xy 333.45988 -264.163208) (xy 333.489445 -264.202552)
			(xy 333.512316 -264.246129) (xy 333.5279 -264.29281) (xy 333.535795 -264.341387) (xy 333.53629 -264.365994)
			(xy 333.854801 -264.365994) (xy 333.858896 -264.315266) (xy 333.871075 -264.265852) (xy 333.891023 -264.219032)
			(xy 333.918224 -264.176018) (xy 333.951972 -264.137924) (xy 333.991394 -264.105737) (xy 334.035468 -264.080291)
			(xy 334.083054 -264.062244) (xy 334.132918 -264.052064) (xy 334.18377 -264.050015) (xy 334.234291 -264.056149)
			(xy 334.283175 -264.070309) (xy 334.329154 -264.092126) (xy 334.371038 -264.121036) (xy 334.407742 -264.156291)
			(xy 334.438315 -264.196977) (xy 334.461966 -264.24204) (xy 334.478082 -264.290314) (xy 334.486246 -264.340548)
			(xy 334.486758 -264.365994) (xy 334.805286 -264.365994) (xy 334.809246 -264.31694) (xy 334.821023 -264.269156)
			(xy 334.840314 -264.22388) (xy 334.866617 -264.182284) (xy 334.899252 -264.145447) (xy 334.937373 -264.114322)
			(xy 334.979994 -264.089715) (xy 335.02601 -264.072263) (xy 335.074229 -264.062419) (xy 335.123404 -264.060438)
			(xy 335.172259 -264.06637) (xy 335.21953 -264.080062) (xy 335.263992 -264.10116) (xy 335.304495 -264.129116)
			(xy 335.339988 -264.163208) (xy 335.369553 -264.202552) (xy 335.392424 -264.246129) (xy 335.408008 -264.29281)
			(xy 335.415903 -264.341387) (xy 335.416398 -264.365994) (xy 335.734909 -264.365994) (xy 335.739004 -264.315266)
			(xy 335.751183 -264.265852) (xy 335.771131 -264.219032) (xy 335.798332 -264.176018) (xy 335.83208 -264.137924)
			(xy 335.871502 -264.105737) (xy 335.915576 -264.080291) (xy 335.963162 -264.062244) (xy 336.013026 -264.052064)
			(xy 336.063878 -264.050015) (xy 336.114399 -264.056149) (xy 336.163283 -264.070309) (xy 336.209262 -264.092126)
			(xy 336.251146 -264.121036) (xy 336.28785 -264.156291) (xy 336.318423 -264.196977) (xy 336.342074 -264.24204)
			(xy 336.35819 -264.290314) (xy 336.366354 -264.340548) (xy 336.366866 -264.365994) (xy 336.674963 -264.365994)
			(xy 336.679058 -264.315266) (xy 336.691237 -264.265852) (xy 336.711185 -264.219032) (xy 336.738386 -264.176018)
			(xy 336.772134 -264.137924) (xy 336.811556 -264.105737) (xy 336.85563 -264.080291) (xy 336.903216 -264.062244)
			(xy 336.95308 -264.052064) (xy 337.003932 -264.050015) (xy 337.054453 -264.056149) (xy 337.103337 -264.070309)
			(xy 337.149316 -264.092126) (xy 337.1912 -264.121036) (xy 337.227904 -264.156291) (xy 337.258477 -264.196977)
			(xy 337.282128 -264.24204) (xy 337.298244 -264.290314) (xy 337.306408 -264.340548) (xy 337.30692 -264.365994)
			(xy 337.625194 -264.365994) (xy 337.629154 -264.31694) (xy 337.640931 -264.269156) (xy 337.660222 -264.22388)
			(xy 337.686525 -264.182284) (xy 337.71916 -264.145447) (xy 337.757281 -264.114322) (xy 337.799902 -264.089715)
			(xy 337.845918 -264.072263) (xy 337.894137 -264.062419) (xy 337.943312 -264.060438) (xy 337.992167 -264.06637)
			(xy 338.039438 -264.080062) (xy 338.0839 -264.10116) (xy 338.124403 -264.129116) (xy 338.159896 -264.163208)
			(xy 338.189461 -264.202552) (xy 338.212332 -264.246129) (xy 338.227916 -264.29281) (xy 338.235811 -264.341387)
			(xy 338.236306 -264.365994) (xy 338.554817 -264.365994) (xy 338.558912 -264.315266) (xy 338.571091 -264.265852)
			(xy 338.591039 -264.219032) (xy 338.61824 -264.176018) (xy 338.651988 -264.137924) (xy 338.69141 -264.105737)
			(xy 338.735484 -264.080291) (xy 338.78307 -264.062244) (xy 338.832934 -264.052064) (xy 338.883786 -264.050015)
			(xy 338.934307 -264.056149) (xy 338.983191 -264.070309) (xy 339.02917 -264.092126) (xy 339.071054 -264.121036)
			(xy 339.107758 -264.156291) (xy 339.138331 -264.196977) (xy 339.161982 -264.24204) (xy 339.178098 -264.290314)
			(xy 339.186262 -264.340548) (xy 339.186774 -264.365994) (xy 339.505302 -264.365994) (xy 339.509262 -264.31694)
			(xy 339.521039 -264.269156) (xy 339.54033 -264.22388) (xy 339.566633 -264.182284) (xy 339.599268 -264.145447)
			(xy 339.637389 -264.114322) (xy 339.68001 -264.089715) (xy 339.726026 -264.072263) (xy 339.774245 -264.062419)
			(xy 339.82342 -264.060438) (xy 339.872275 -264.06637) (xy 339.919546 -264.080062) (xy 339.964008 -264.10116)
			(xy 340.004511 -264.129116) (xy 340.040004 -264.163208) (xy 340.069569 -264.202552) (xy 340.09244 -264.246129)
			(xy 340.108024 -264.29281) (xy 340.115919 -264.341387) (xy 340.116414 -264.365994) (xy 340.434925 -264.365994)
			(xy 340.43902 -264.315266) (xy 340.451199 -264.265852) (xy 340.471147 -264.219032) (xy 340.498348 -264.176018)
			(xy 340.532096 -264.137924) (xy 340.571518 -264.105737) (xy 340.615592 -264.080291) (xy 340.663178 -264.062244)
			(xy 340.713042 -264.052064) (xy 340.763894 -264.050015) (xy 340.814415 -264.056149) (xy 340.863299 -264.070309)
			(xy 340.909278 -264.092126) (xy 340.951162 -264.121036) (xy 340.987866 -264.156291) (xy 341.018439 -264.196977)
			(xy 341.04209 -264.24204) (xy 341.058206 -264.290314) (xy 341.06637 -264.340548) (xy 341.066882 -264.365994)
			(xy 341.38541 -264.365994) (xy 341.38937 -264.31694) (xy 341.401147 -264.269156) (xy 341.420438 -264.22388)
			(xy 341.446741 -264.182284) (xy 341.479376 -264.145447) (xy 341.517497 -264.114322) (xy 341.560118 -264.089715)
			(xy 341.606134 -264.072263) (xy 341.654353 -264.062419) (xy 341.703528 -264.060438) (xy 341.752383 -264.06637)
			(xy 341.799654 -264.080062) (xy 341.844116 -264.10116) (xy 341.884619 -264.129116) (xy 341.920112 -264.163208)
			(xy 341.949677 -264.202552) (xy 341.972548 -264.246129) (xy 341.988132 -264.29281) (xy 341.996027 -264.341387)
			(xy 341.996522 -264.365994) (xy 342.314779 -264.365994) (xy 342.318874 -264.315266) (xy 342.331053 -264.265852)
			(xy 342.351001 -264.219032) (xy 342.378202 -264.176018) (xy 342.41195 -264.137924) (xy 342.451372 -264.105737)
			(xy 342.495446 -264.080291) (xy 342.543032 -264.062244) (xy 342.592896 -264.052064) (xy 342.643748 -264.050015)
			(xy 342.694269 -264.056149) (xy 342.743153 -264.070309) (xy 342.789132 -264.092126) (xy 342.831016 -264.121036)
			(xy 342.86772 -264.156291) (xy 342.898293 -264.196977) (xy 342.921944 -264.24204) (xy 342.93806 -264.290314)
			(xy 342.946224 -264.340548) (xy 342.946736 -264.365994) (xy 343.254833 -264.365994) (xy 343.258928 -264.315266)
			(xy 343.271107 -264.265852) (xy 343.291055 -264.219032) (xy 343.318256 -264.176018) (xy 343.352004 -264.137924)
			(xy 343.391426 -264.105737) (xy 343.4355 -264.080291) (xy 343.483086 -264.062244) (xy 343.53295 -264.052064)
			(xy 343.583802 -264.050015) (xy 343.634323 -264.056149) (xy 343.683207 -264.070309) (xy 343.729186 -264.092126)
			(xy 343.77107 -264.121036) (xy 343.807774 -264.156291) (xy 343.838347 -264.196977) (xy 343.861998 -264.24204)
			(xy 343.878114 -264.290314) (xy 343.886278 -264.340548) (xy 343.88679 -264.365994) (xy 344.205318 -264.365994)
			(xy 344.209278 -264.31694) (xy 344.221055 -264.269156) (xy 344.240346 -264.22388) (xy 344.266649 -264.182284)
			(xy 344.299284 -264.145447) (xy 344.337405 -264.114322) (xy 344.380026 -264.089715) (xy 344.426042 -264.072263)
			(xy 344.474261 -264.062419) (xy 344.523436 -264.060438) (xy 344.572291 -264.06637) (xy 344.619562 -264.080062)
			(xy 344.664024 -264.10116) (xy 344.704527 -264.129116) (xy 344.74002 -264.163208) (xy 344.769585 -264.202552)
			(xy 344.792456 -264.246129) (xy 344.80804 -264.29281) (xy 344.815935 -264.341387) (xy 344.81643 -264.365994)
			(xy 346.085426 -264.365994) (xy 346.089386 -264.31694) (xy 346.101163 -264.269156) (xy 346.120454 -264.22388)
			(xy 346.146757 -264.182284) (xy 346.179392 -264.145447) (xy 346.217513 -264.114322) (xy 346.260134 -264.089715)
			(xy 346.30615 -264.072263) (xy 346.354369 -264.062419) (xy 346.403544 -264.060438) (xy 346.452399 -264.06637)
			(xy 346.49967 -264.080062) (xy 346.544132 -264.10116) (xy 346.584635 -264.129116) (xy 346.620128 -264.163208)
			(xy 346.649693 -264.202552) (xy 346.672564 -264.246129) (xy 346.688148 -264.29281) (xy 346.696043 -264.341387)
			(xy 346.696538 -264.365994) (xy 347.96528 -264.365994) (xy 347.96924 -264.31694) (xy 347.981017 -264.269156)
			(xy 348.000308 -264.22388) (xy 348.026611 -264.182284) (xy 348.059246 -264.145447) (xy 348.097367 -264.114322)
			(xy 348.139988 -264.089715) (xy 348.186004 -264.072263) (xy 348.234223 -264.062419) (xy 348.283398 -264.060438)
			(xy 348.332253 -264.06637) (xy 348.379524 -264.080062) (xy 348.423986 -264.10116) (xy 348.464489 -264.129116)
			(xy 348.499982 -264.163208) (xy 348.529547 -264.202552) (xy 348.552418 -264.246129) (xy 348.568002 -264.29281)
			(xy 348.575897 -264.341387) (xy 348.576392 -264.365994) (xy 348.575897 -264.390601) (xy 348.568002 -264.439178)
			(xy 348.552418 -264.485859) (xy 348.529547 -264.529436) (xy 348.499982 -264.56878) (xy 348.464489 -264.602872)
			(xy 348.423986 -264.630828) (xy 348.379524 -264.651926) (xy 348.332253 -264.665618) (xy 348.283398 -264.67155)
			(xy 348.234223 -264.669569) (xy 348.186004 -264.659725) (xy 348.139988 -264.642273) (xy 348.097367 -264.617666)
			(xy 348.059246 -264.586541) (xy 348.026611 -264.549704) (xy 348.000308 -264.508108) (xy 347.981017 -264.462832)
			(xy 347.96924 -264.415048) (xy 347.96528 -264.365994) (xy 346.696538 -264.365994) (xy 346.696043 -264.390601)
			(xy 346.688148 -264.439178) (xy 346.672564 -264.485859) (xy 346.649693 -264.529436) (xy 346.620128 -264.56878)
			(xy 346.584635 -264.602872) (xy 346.544132 -264.630828) (xy 346.49967 -264.651926) (xy 346.452399 -264.665618)
			(xy 346.403544 -264.67155) (xy 346.354369 -264.669569) (xy 346.30615 -264.659725) (xy 346.260134 -264.642273)
			(xy 346.217513 -264.617666) (xy 346.179392 -264.586541) (xy 346.146757 -264.549704) (xy 346.120454 -264.508108)
			(xy 346.101163 -264.462832) (xy 346.089386 -264.415048) (xy 346.085426 -264.365994) (xy 344.81643 -264.365994)
			(xy 344.815935 -264.390601) (xy 344.80804 -264.439178) (xy 344.792456 -264.485859) (xy 344.769585 -264.529436)
			(xy 344.74002 -264.56878) (xy 344.704527 -264.602872) (xy 344.664024 -264.630828) (xy 344.619562 -264.651926)
			(xy 344.572291 -264.665618) (xy 344.523436 -264.67155) (xy 344.474261 -264.669569) (xy 344.426042 -264.659725)
			(xy 344.380026 -264.642273) (xy 344.337405 -264.617666) (xy 344.299284 -264.586541) (xy 344.266649 -264.549704)
			(xy 344.240346 -264.508108) (xy 344.221055 -264.462832) (xy 344.209278 -264.415048) (xy 344.205318 -264.365994)
			(xy 343.88679 -264.365994) (xy 343.886278 -264.39144) (xy 343.878114 -264.441674) (xy 343.861998 -264.489948)
			(xy 343.838347 -264.535011) (xy 343.807774 -264.575697) (xy 343.77107 -264.610952) (xy 343.729186 -264.639862)
			(xy 343.683207 -264.661679) (xy 343.634323 -264.675839) (xy 343.583802 -264.681973) (xy 343.53295 -264.679924)
			(xy 343.483086 -264.669744) (xy 343.4355 -264.651697) (xy 343.391426 -264.626251) (xy 343.352004 -264.594064)
			(xy 343.318256 -264.55597) (xy 343.291055 -264.512956) (xy 343.271107 -264.466136) (xy 343.258928 -264.416722)
			(xy 343.254833 -264.365994) (xy 342.946736 -264.365994) (xy 342.946224 -264.39144) (xy 342.93806 -264.441674)
			(xy 342.921944 -264.489948) (xy 342.898293 -264.535011) (xy 342.86772 -264.575697) (xy 342.831016 -264.610952)
			(xy 342.789132 -264.639862) (xy 342.743153 -264.661679) (xy 342.694269 -264.675839) (xy 342.643748 -264.681973)
			(xy 342.592896 -264.679924) (xy 342.543032 -264.669744) (xy 342.495446 -264.651697) (xy 342.451372 -264.626251)
			(xy 342.41195 -264.594064) (xy 342.378202 -264.55597) (xy 342.351001 -264.512956) (xy 342.331053 -264.466136)
			(xy 342.318874 -264.416722) (xy 342.314779 -264.365994) (xy 341.996522 -264.365994) (xy 341.996027 -264.390601)
			(xy 341.988132 -264.439178) (xy 341.972548 -264.485859) (xy 341.949677 -264.529436) (xy 341.920112 -264.56878)
			(xy 341.884619 -264.602872) (xy 341.844116 -264.630828) (xy 341.799654 -264.651926) (xy 341.752383 -264.665618)
			(xy 341.703528 -264.67155) (xy 341.654353 -264.669569) (xy 341.606134 -264.659725) (xy 341.560118 -264.642273)
			(xy 341.517497 -264.617666) (xy 341.479376 -264.586541) (xy 341.446741 -264.549704) (xy 341.420438 -264.508108)
			(xy 341.401147 -264.462832) (xy 341.38937 -264.415048) (xy 341.38541 -264.365994) (xy 341.066882 -264.365994)
			(xy 341.06637 -264.39144) (xy 341.058206 -264.441674) (xy 341.04209 -264.489948) (xy 341.018439 -264.535011)
			(xy 340.987866 -264.575697) (xy 340.951162 -264.610952) (xy 340.909278 -264.639862) (xy 340.863299 -264.661679)
			(xy 340.814415 -264.675839) (xy 340.763894 -264.681973) (xy 340.713042 -264.679924) (xy 340.663178 -264.669744)
			(xy 340.615592 -264.651697) (xy 340.571518 -264.626251) (xy 340.532096 -264.594064) (xy 340.498348 -264.55597)
			(xy 340.471147 -264.512956) (xy 340.451199 -264.466136) (xy 340.43902 -264.416722) (xy 340.434925 -264.365994)
			(xy 340.116414 -264.365994) (xy 340.115919 -264.390601) (xy 340.108024 -264.439178) (xy 340.09244 -264.485859)
			(xy 340.069569 -264.529436) (xy 340.040004 -264.56878) (xy 340.004511 -264.602872) (xy 339.964008 -264.630828)
			(xy 339.919546 -264.651926) (xy 339.872275 -264.665618) (xy 339.82342 -264.67155) (xy 339.774245 -264.669569)
			(xy 339.726026 -264.659725) (xy 339.68001 -264.642273) (xy 339.637389 -264.617666) (xy 339.599268 -264.586541)
			(xy 339.566633 -264.549704) (xy 339.54033 -264.508108) (xy 339.521039 -264.462832) (xy 339.509262 -264.415048)
			(xy 339.505302 -264.365994) (xy 339.186774 -264.365994) (xy 339.186262 -264.39144) (xy 339.178098 -264.441674)
			(xy 339.161982 -264.489948) (xy 339.138331 -264.535011) (xy 339.107758 -264.575697) (xy 339.071054 -264.610952)
			(xy 339.02917 -264.639862) (xy 338.983191 -264.661679) (xy 338.934307 -264.675839) (xy 338.883786 -264.681973)
			(xy 338.832934 -264.679924) (xy 338.78307 -264.669744) (xy 338.735484 -264.651697) (xy 338.69141 -264.626251)
			(xy 338.651988 -264.594064) (xy 338.61824 -264.55597) (xy 338.591039 -264.512956) (xy 338.571091 -264.466136)
			(xy 338.558912 -264.416722) (xy 338.554817 -264.365994) (xy 338.236306 -264.365994) (xy 338.235811 -264.390601)
			(xy 338.227916 -264.439178) (xy 338.212332 -264.485859) (xy 338.189461 -264.529436) (xy 338.159896 -264.56878)
			(xy 338.124403 -264.602872) (xy 338.0839 -264.630828) (xy 338.039438 -264.651926) (xy 337.992167 -264.665618)
			(xy 337.943312 -264.67155) (xy 337.894137 -264.669569) (xy 337.845918 -264.659725) (xy 337.799902 -264.642273)
			(xy 337.757281 -264.617666) (xy 337.71916 -264.586541) (xy 337.686525 -264.549704) (xy 337.660222 -264.508108)
			(xy 337.640931 -264.462832) (xy 337.629154 -264.415048) (xy 337.625194 -264.365994) (xy 337.30692 -264.365994)
			(xy 337.306408 -264.39144) (xy 337.298244 -264.441674) (xy 337.282128 -264.489948) (xy 337.258477 -264.535011)
			(xy 337.227904 -264.575697) (xy 337.1912 -264.610952) (xy 337.149316 -264.639862) (xy 337.103337 -264.661679)
			(xy 337.054453 -264.675839) (xy 337.003932 -264.681973) (xy 336.95308 -264.679924) (xy 336.903216 -264.669744)
			(xy 336.85563 -264.651697) (xy 336.811556 -264.626251) (xy 336.772134 -264.594064) (xy 336.738386 -264.55597)
			(xy 336.711185 -264.512956) (xy 336.691237 -264.466136) (xy 336.679058 -264.416722) (xy 336.674963 -264.365994)
			(xy 336.366866 -264.365994) (xy 336.366354 -264.39144) (xy 336.35819 -264.441674) (xy 336.342074 -264.489948)
			(xy 336.318423 -264.535011) (xy 336.28785 -264.575697) (xy 336.251146 -264.610952) (xy 336.209262 -264.639862)
			(xy 336.163283 -264.661679) (xy 336.114399 -264.675839) (xy 336.063878 -264.681973) (xy 336.013026 -264.679924)
			(xy 335.963162 -264.669744) (xy 335.915576 -264.651697) (xy 335.871502 -264.626251) (xy 335.83208 -264.594064)
			(xy 335.798332 -264.55597) (xy 335.771131 -264.512956) (xy 335.751183 -264.466136) (xy 335.739004 -264.416722)
			(xy 335.734909 -264.365994) (xy 335.416398 -264.365994) (xy 335.415903 -264.390601) (xy 335.408008 -264.439178)
			(xy 335.392424 -264.485859) (xy 335.369553 -264.529436) (xy 335.339988 -264.56878) (xy 335.304495 -264.602872)
			(xy 335.263992 -264.630828) (xy 335.21953 -264.651926) (xy 335.172259 -264.665618) (xy 335.123404 -264.67155)
			(xy 335.074229 -264.669569) (xy 335.02601 -264.659725) (xy 334.979994 -264.642273) (xy 334.937373 -264.617666)
			(xy 334.899252 -264.586541) (xy 334.866617 -264.549704) (xy 334.840314 -264.508108) (xy 334.821023 -264.462832)
			(xy 334.809246 -264.415048) (xy 334.805286 -264.365994) (xy 334.486758 -264.365994) (xy 334.486246 -264.39144)
			(xy 334.478082 -264.441674) (xy 334.461966 -264.489948) (xy 334.438315 -264.535011) (xy 334.407742 -264.575697)
			(xy 334.371038 -264.610952) (xy 334.329154 -264.639862) (xy 334.283175 -264.661679) (xy 334.234291 -264.675839)
			(xy 334.18377 -264.681973) (xy 334.132918 -264.679924) (xy 334.083054 -264.669744) (xy 334.035468 -264.651697)
			(xy 333.991394 -264.626251) (xy 333.951972 -264.594064) (xy 333.918224 -264.55597) (xy 333.891023 -264.512956)
			(xy 333.871075 -264.466136) (xy 333.858896 -264.416722) (xy 333.854801 -264.365994) (xy 333.53629 -264.365994)
			(xy 333.535795 -264.390601) (xy 333.5279 -264.439178) (xy 333.512316 -264.485859) (xy 333.489445 -264.529436)
			(xy 333.45988 -264.56878) (xy 333.424387 -264.602872) (xy 333.383884 -264.630828) (xy 333.339422 -264.651926)
			(xy 333.292151 -264.665618) (xy 333.243296 -264.67155) (xy 333.194121 -264.669569) (xy 333.145902 -264.659725)
			(xy 333.099886 -264.642273) (xy 333.057265 -264.617666) (xy 333.019144 -264.586541) (xy 332.986509 -264.549704)
			(xy 332.960206 -264.508108) (xy 332.940915 -264.462832) (xy 332.929138 -264.415048) (xy 332.925178 -264.365994)
			(xy 332.606904 -264.365994) (xy 332.606392 -264.39144) (xy 332.598228 -264.441674) (xy 332.582112 -264.489948)
			(xy 332.558461 -264.535011) (xy 332.527888 -264.575697) (xy 332.491184 -264.610952) (xy 332.4493 -264.639862)
			(xy 332.403321 -264.661679) (xy 332.354437 -264.675839) (xy 332.303916 -264.681973) (xy 332.253064 -264.679924)
			(xy 332.2032 -264.669744) (xy 332.155614 -264.651697) (xy 332.11154 -264.626251) (xy 332.072118 -264.594064)
			(xy 332.03837 -264.55597) (xy 332.011169 -264.512956) (xy 331.991221 -264.466136) (xy 331.979042 -264.416722)
			(xy 331.974947 -264.365994) (xy 331.656436 -264.365994) (xy 331.655941 -264.390601) (xy 331.648046 -264.439178)
			(xy 331.632462 -264.485859) (xy 331.609591 -264.529436) (xy 331.580026 -264.56878) (xy 331.544533 -264.602872)
			(xy 331.50403 -264.630828) (xy 331.459568 -264.651926) (xy 331.412297 -264.665618) (xy 331.363442 -264.67155)
			(xy 331.314267 -264.669569) (xy 331.266048 -264.659725) (xy 331.220032 -264.642273) (xy 331.177411 -264.617666)
			(xy 331.13929 -264.586541) (xy 331.106655 -264.549704) (xy 331.080352 -264.508108) (xy 331.061061 -264.462832)
			(xy 331.049284 -264.415048) (xy 331.045324 -264.365994) (xy 330.726796 -264.365994) (xy 330.726284 -264.39144)
			(xy 330.71812 -264.441674) (xy 330.702004 -264.489948) (xy 330.678353 -264.535011) (xy 330.64778 -264.575697)
			(xy 330.611076 -264.610952) (xy 330.569192 -264.639862) (xy 330.523213 -264.661679) (xy 330.474329 -264.675839)
			(xy 330.423808 -264.681973) (xy 330.372956 -264.679924) (xy 330.323092 -264.669744) (xy 330.275506 -264.651697)
			(xy 330.231432 -264.626251) (xy 330.19201 -264.594064) (xy 330.158262 -264.55597) (xy 330.131061 -264.512956)
			(xy 330.111113 -264.466136) (xy 330.098934 -264.416722) (xy 330.094839 -264.365994) (xy 329.786742 -264.365994)
			(xy 329.78623 -264.39144) (xy 329.778066 -264.441674) (xy 329.76195 -264.489948) (xy 329.738299 -264.535011)
			(xy 329.707726 -264.575697) (xy 329.671022 -264.610952) (xy 329.629138 -264.639862) (xy 329.583159 -264.661679)
			(xy 329.534275 -264.675839) (xy 329.483754 -264.681973) (xy 329.432902 -264.679924) (xy 329.383038 -264.669744)
			(xy 329.335452 -264.651697) (xy 329.291378 -264.626251) (xy 329.251956 -264.594064) (xy 329.218208 -264.55597)
			(xy 329.191007 -264.512956) (xy 329.171059 -264.466136) (xy 329.15888 -264.416722) (xy 329.154785 -264.365994)
			(xy 328.836528 -264.365994) (xy 328.836033 -264.390601) (xy 328.828138 -264.439178) (xy 328.812554 -264.485859)
			(xy 328.789683 -264.529436) (xy 328.760118 -264.56878) (xy 328.724625 -264.602872) (xy 328.684122 -264.630828)
			(xy 328.63966 -264.651926) (xy 328.592389 -264.665618) (xy 328.543534 -264.67155) (xy 328.494359 -264.669569)
			(xy 328.44614 -264.659725) (xy 328.400124 -264.642273) (xy 328.357503 -264.617666) (xy 328.319382 -264.586541)
			(xy 328.286747 -264.549704) (xy 328.260444 -264.508108) (xy 328.241153 -264.462832) (xy 328.229376 -264.415048)
			(xy 328.225416 -264.365994) (xy 326.95642 -264.365994) (xy 326.955925 -264.390601) (xy 326.94803 -264.439178)
			(xy 326.932446 -264.485859) (xy 326.909575 -264.529436) (xy 326.88001 -264.56878) (xy 326.844517 -264.602872)
			(xy 326.804014 -264.630828) (xy 326.759552 -264.651926) (xy 326.712281 -264.665618) (xy 326.663426 -264.67155)
			(xy 326.614251 -264.669569) (xy 326.566032 -264.659725) (xy 326.520016 -264.642273) (xy 326.477395 -264.617666)
			(xy 326.439274 -264.586541) (xy 326.406639 -264.549704) (xy 326.380336 -264.508108) (xy 326.361045 -264.462832)
			(xy 326.349268 -264.415048) (xy 326.345308 -264.365994) (xy 310.45912 -264.365994) (xy 310.45912 -264.910062)
			(xy 324.74714 -264.910062) (xy 324.7511 -264.861008) (xy 324.762877 -264.813224) (xy 324.782168 -264.767948)
			(xy 324.808471 -264.726352) (xy 324.841106 -264.689515) (xy 324.879227 -264.65839) (xy 324.921848 -264.633783)
			(xy 324.967864 -264.616331) (xy 325.016083 -264.606487) (xy 325.065258 -264.604506) (xy 325.114113 -264.610438)
			(xy 325.161384 -264.62413) (xy 325.205846 -264.645228) (xy 325.246349 -264.673184) (xy 325.281842 -264.707276)
			(xy 325.311407 -264.74662) (xy 325.334278 -264.790197) (xy 325.349862 -264.836878) (xy 325.357757 -264.885455)
			(xy 325.358252 -264.910062) (xy 325.357757 -264.934669) (xy 325.349862 -264.983246) (xy 325.334278 -265.029927)
			(xy 325.311407 -265.073504) (xy 325.281842 -265.112848) (xy 325.246349 -265.14694) (xy 325.205846 -265.174896)
			(xy 325.203519 -265.176) (xy 327.755262 -265.176) (xy 327.759222 -265.126946) (xy 327.770999 -265.079162)
			(xy 327.79029 -265.033886) (xy 327.816593 -264.99229) (xy 327.849228 -264.955453) (xy 327.887349 -264.924328)
			(xy 327.92997 -264.899721) (xy 327.975986 -264.882269) (xy 328.024205 -264.872425) (xy 328.07338 -264.870444)
			(xy 328.122235 -264.876376) (xy 328.169506 -264.890068) (xy 328.213968 -264.911166) (xy 328.254471 -264.939122)
			(xy 328.289964 -264.973214) (xy 328.319529 -265.012558) (xy 328.3424 -265.056135) (xy 328.357984 -265.102816)
			(xy 328.365879 -265.151393) (xy 328.366374 -265.176) (xy 328.684885 -265.176) (xy 328.68898 -265.125272)
			(xy 328.701159 -265.075858) (xy 328.721107 -265.029038) (xy 328.748308 -264.986024) (xy 328.782056 -264.94793)
			(xy 328.821478 -264.915743) (xy 328.865552 -264.890297) (xy 328.913138 -264.87225) (xy 328.963002 -264.86207)
			(xy 329.013854 -264.860021) (xy 329.064375 -264.866155) (xy 329.113259 -264.880315) (xy 329.159238 -264.902132)
			(xy 329.201122 -264.931042) (xy 329.237826 -264.966297) (xy 329.268399 -265.006983) (xy 329.29205 -265.052046)
			(xy 329.308166 -265.10032) (xy 329.31633 -265.150554) (xy 329.316842 -265.176) (xy 329.63537 -265.176)
			(xy 329.63933 -265.126946) (xy 329.651107 -265.079162) (xy 329.670398 -265.033886) (xy 329.696701 -264.99229)
			(xy 329.729336 -264.955453) (xy 329.767457 -264.924328) (xy 329.810078 -264.899721) (xy 329.856094 -264.882269)
			(xy 329.904313 -264.872425) (xy 329.953488 -264.870444) (xy 330.002343 -264.876376) (xy 330.049614 -264.890068)
			(xy 330.094076 -264.911166) (xy 330.134579 -264.939122) (xy 330.170072 -264.973214) (xy 330.199637 -265.012558)
			(xy 330.222508 -265.056135) (xy 330.238092 -265.102816) (xy 330.245987 -265.151393) (xy 330.246482 -265.176)
			(xy 330.575424 -265.176) (xy 330.579384 -265.126946) (xy 330.591161 -265.079162) (xy 330.610452 -265.033886)
			(xy 330.636755 -264.99229) (xy 330.66939 -264.955453) (xy 330.707511 -264.924328) (xy 330.750132 -264.899721)
			(xy 330.796148 -264.882269) (xy 330.844367 -264.872425) (xy 330.893542 -264.870444) (xy 330.942397 -264.876376)
			(xy 330.989668 -264.890068) (xy 331.03413 -264.911166) (xy 331.074633 -264.939122) (xy 331.110126 -264.973214)
			(xy 331.139691 -265.012558) (xy 331.162562 -265.056135) (xy 331.178146 -265.102816) (xy 331.186041 -265.151393)
			(xy 331.186536 -265.176) (xy 331.515224 -265.176) (xy 331.519184 -265.126946) (xy 331.530961 -265.079162)
			(xy 331.550252 -265.033886) (xy 331.576555 -264.99229) (xy 331.60919 -264.955453) (xy 331.647311 -264.924328)
			(xy 331.689932 -264.899721) (xy 331.735948 -264.882269) (xy 331.784167 -264.872425) (xy 331.833342 -264.870444)
			(xy 331.882197 -264.876376) (xy 331.929468 -264.890068) (xy 331.97393 -264.911166) (xy 332.014433 -264.939122)
			(xy 332.049926 -264.973214) (xy 332.079491 -265.012558) (xy 332.102362 -265.056135) (xy 332.117946 -265.102816)
			(xy 332.125841 -265.151393) (xy 332.126336 -265.176) (xy 332.444847 -265.176) (xy 332.448942 -265.125272)
			(xy 332.461121 -265.075858) (xy 332.481069 -265.029038) (xy 332.50827 -264.986024) (xy 332.542018 -264.94793)
			(xy 332.58144 -264.915743) (xy 332.625514 -264.890297) (xy 332.6731 -264.87225) (xy 332.722964 -264.86207)
			(xy 332.773816 -264.860021) (xy 332.824337 -264.866155) (xy 332.873221 -264.880315) (xy 332.9192 -264.902132)
			(xy 332.961084 -264.931042) (xy 332.997788 -264.966297) (xy 333.028361 -265.006983) (xy 333.052012 -265.052046)
			(xy 333.068128 -265.10032) (xy 333.076292 -265.150554) (xy 333.076804 -265.176) (xy 333.395332 -265.176)
			(xy 333.399292 -265.126946) (xy 333.411069 -265.079162) (xy 333.43036 -265.033886) (xy 333.456663 -264.99229)
			(xy 333.489298 -264.955453) (xy 333.527419 -264.924328) (xy 333.57004 -264.899721) (xy 333.616056 -264.882269)
			(xy 333.664275 -264.872425) (xy 333.71345 -264.870444) (xy 333.762305 -264.876376) (xy 333.809576 -264.890068)
			(xy 333.854038 -264.911166) (xy 333.894541 -264.939122) (xy 333.930034 -264.973214) (xy 333.959599 -265.012558)
			(xy 333.98247 -265.056135) (xy 333.998054 -265.102816) (xy 334.005949 -265.151393) (xy 334.006444 -265.176)
			(xy 334.335386 -265.176) (xy 334.339346 -265.126946) (xy 334.351123 -265.079162) (xy 334.370414 -265.033886)
			(xy 334.396717 -264.99229) (xy 334.429352 -264.955453) (xy 334.467473 -264.924328) (xy 334.510094 -264.899721)
			(xy 334.55611 -264.882269) (xy 334.604329 -264.872425) (xy 334.653504 -264.870444) (xy 334.702359 -264.876376)
			(xy 334.74963 -264.890068) (xy 334.794092 -264.911166) (xy 334.834595 -264.939122) (xy 334.870088 -264.973214)
			(xy 334.899653 -265.012558) (xy 334.922524 -265.056135) (xy 334.938108 -265.102816) (xy 334.946003 -265.151393)
			(xy 334.946498 -265.176) (xy 335.264755 -265.176) (xy 335.26885 -265.125272) (xy 335.281029 -265.075858)
			(xy 335.300977 -265.029038) (xy 335.328178 -264.986024) (xy 335.361926 -264.94793) (xy 335.401348 -264.915743)
			(xy 335.445422 -264.890297) (xy 335.493008 -264.87225) (xy 335.542872 -264.86207) (xy 335.593724 -264.860021)
			(xy 335.644245 -264.866155) (xy 335.693129 -264.880315) (xy 335.739108 -264.902132) (xy 335.780992 -264.931042)
			(xy 335.817696 -264.966297) (xy 335.848269 -265.006983) (xy 335.87192 -265.052046) (xy 335.888036 -265.10032)
			(xy 335.8962 -265.150554) (xy 335.896712 -265.176) (xy 336.21524 -265.176) (xy 336.2192 -265.126946)
			(xy 336.230977 -265.079162) (xy 336.250268 -265.033886) (xy 336.276571 -264.99229) (xy 336.309206 -264.955453)
			(xy 336.347327 -264.924328) (xy 336.389948 -264.899721) (xy 336.435964 -264.882269) (xy 336.484183 -264.872425)
			(xy 336.533358 -264.870444) (xy 336.582213 -264.876376) (xy 336.629484 -264.890068) (xy 336.673946 -264.911166)
			(xy 336.714449 -264.939122) (xy 336.749942 -264.973214) (xy 336.779507 -265.012558) (xy 336.802378 -265.056135)
			(xy 336.817962 -265.102816) (xy 336.825857 -265.151393) (xy 336.826352 -265.176) (xy 337.155294 -265.176)
			(xy 337.159254 -265.126946) (xy 337.171031 -265.079162) (xy 337.190322 -265.033886) (xy 337.216625 -264.99229)
			(xy 337.24926 -264.955453) (xy 337.287381 -264.924328) (xy 337.330002 -264.899721) (xy 337.376018 -264.882269)
			(xy 337.424237 -264.872425) (xy 337.473412 -264.870444) (xy 337.522267 -264.876376) (xy 337.569538 -264.890068)
			(xy 337.614 -264.911166) (xy 337.654503 -264.939122) (xy 337.689996 -264.973214) (xy 337.719561 -265.012558)
			(xy 337.742432 -265.056135) (xy 337.758016 -265.102816) (xy 337.765911 -265.151393) (xy 337.766406 -265.176)
			(xy 338.095348 -265.176) (xy 338.099308 -265.126946) (xy 338.111085 -265.079162) (xy 338.130376 -265.033886)
			(xy 338.156679 -264.99229) (xy 338.189314 -264.955453) (xy 338.227435 -264.924328) (xy 338.270056 -264.899721)
			(xy 338.316072 -264.882269) (xy 338.364291 -264.872425) (xy 338.413466 -264.870444) (xy 338.462321 -264.876376)
			(xy 338.509592 -264.890068) (xy 338.554054 -264.911166) (xy 338.594557 -264.939122) (xy 338.63005 -264.973214)
			(xy 338.659615 -265.012558) (xy 338.682486 -265.056135) (xy 338.69807 -265.102816) (xy 338.705965 -265.151393)
			(xy 338.70646 -265.176) (xy 339.024971 -265.176) (xy 339.029066 -265.125272) (xy 339.041245 -265.075858)
			(xy 339.061193 -265.029038) (xy 339.088394 -264.986024) (xy 339.122142 -264.94793) (xy 339.161564 -264.915743)
			(xy 339.205638 -264.890297) (xy 339.253224 -264.87225) (xy 339.303088 -264.86207) (xy 339.35394 -264.860021)
			(xy 339.404461 -264.866155) (xy 339.453345 -264.880315) (xy 339.499324 -264.902132) (xy 339.541208 -264.931042)
			(xy 339.577912 -264.966297) (xy 339.608485 -265.006983) (xy 339.632136 -265.052046) (xy 339.648252 -265.10032)
			(xy 339.656416 -265.150554) (xy 339.656928 -265.176) (xy 339.975202 -265.176) (xy 339.979162 -265.126946)
			(xy 339.990939 -265.079162) (xy 340.01023 -265.033886) (xy 340.036533 -264.99229) (xy 340.069168 -264.955453)
			(xy 340.107289 -264.924328) (xy 340.14991 -264.899721) (xy 340.195926 -264.882269) (xy 340.244145 -264.872425)
			(xy 340.29332 -264.870444) (xy 340.342175 -264.876376) (xy 340.389446 -264.890068) (xy 340.433908 -264.911166)
			(xy 340.474411 -264.939122) (xy 340.509904 -264.973214) (xy 340.539469 -265.012558) (xy 340.56234 -265.056135)
			(xy 340.577924 -265.102816) (xy 340.585819 -265.151393) (xy 340.586314 -265.176) (xy 340.915256 -265.176)
			(xy 340.919216 -265.126946) (xy 340.930993 -265.079162) (xy 340.950284 -265.033886) (xy 340.976587 -264.99229)
			(xy 341.009222 -264.955453) (xy 341.047343 -264.924328) (xy 341.089964 -264.899721) (xy 341.13598 -264.882269)
			(xy 341.184199 -264.872425) (xy 341.233374 -264.870444) (xy 341.282229 -264.876376) (xy 341.3295 -264.890068)
			(xy 341.373962 -264.911166) (xy 341.414465 -264.939122) (xy 341.449958 -264.973214) (xy 341.479523 -265.012558)
			(xy 341.502394 -265.056135) (xy 341.517978 -265.102816) (xy 341.525873 -265.151393) (xy 341.526368 -265.176)
			(xy 341.844879 -265.176) (xy 341.848974 -265.125272) (xy 341.861153 -265.075858) (xy 341.881101 -265.029038)
			(xy 341.908302 -264.986024) (xy 341.94205 -264.94793) (xy 341.981472 -264.915743) (xy 342.025546 -264.890297)
			(xy 342.073132 -264.87225) (xy 342.122996 -264.86207) (xy 342.173848 -264.860021) (xy 342.224369 -264.866155)
			(xy 342.273253 -264.880315) (xy 342.319232 -264.902132) (xy 342.361116 -264.931042) (xy 342.39782 -264.966297)
			(xy 342.428393 -265.006983) (xy 342.452044 -265.052046) (xy 342.46816 -265.10032) (xy 342.476324 -265.150554)
			(xy 342.476836 -265.176) (xy 342.795364 -265.176) (xy 342.799324 -265.126946) (xy 342.811101 -265.079162)
			(xy 342.830392 -265.033886) (xy 342.856695 -264.99229) (xy 342.88933 -264.955453) (xy 342.927451 -264.924328)
			(xy 342.970072 -264.899721) (xy 343.016088 -264.882269) (xy 343.064307 -264.872425) (xy 343.113482 -264.870444)
			(xy 343.162337 -264.876376) (xy 343.209608 -264.890068) (xy 343.25407 -264.911166) (xy 343.294573 -264.939122)
			(xy 343.330066 -264.973214) (xy 343.359631 -265.012558) (xy 343.382502 -265.056135) (xy 343.398086 -265.102816)
			(xy 343.405981 -265.151393) (xy 343.406476 -265.176) (xy 343.735418 -265.176) (xy 343.739378 -265.126946)
			(xy 343.751155 -265.079162) (xy 343.770446 -265.033886) (xy 343.796749 -264.99229) (xy 343.829384 -264.955453)
			(xy 343.867505 -264.924328) (xy 343.910126 -264.899721) (xy 343.956142 -264.882269) (xy 344.004361 -264.872425)
			(xy 344.053536 -264.870444) (xy 344.102391 -264.876376) (xy 344.149662 -264.890068) (xy 344.194124 -264.911166)
			(xy 344.234627 -264.939122) (xy 344.27012 -264.973214) (xy 344.299685 -265.012558) (xy 344.322556 -265.056135)
			(xy 344.33814 -265.102816) (xy 344.346035 -265.151393) (xy 344.34653 -265.176) (xy 345.615272 -265.176)
			(xy 345.619232 -265.126946) (xy 345.631009 -265.079162) (xy 345.6503 -265.033886) (xy 345.676603 -264.99229)
			(xy 345.709238 -264.955453) (xy 345.747359 -264.924328) (xy 345.78998 -264.899721) (xy 345.835996 -264.882269)
			(xy 345.884215 -264.872425) (xy 345.93339 -264.870444) (xy 345.982245 -264.876376) (xy 346.029516 -264.890068)
			(xy 346.073978 -264.911166) (xy 346.114481 -264.939122) (xy 346.149974 -264.973214) (xy 346.179539 -265.012558)
			(xy 346.20241 -265.056135) (xy 346.217994 -265.102816) (xy 346.225889 -265.151393) (xy 346.226384 -265.176)
			(xy 347.49538 -265.176) (xy 347.49934 -265.126946) (xy 347.511117 -265.079162) (xy 347.530408 -265.033886)
			(xy 347.556711 -264.99229) (xy 347.589346 -264.955453) (xy 347.627467 -264.924328) (xy 347.670088 -264.899721)
			(xy 347.716104 -264.882269) (xy 347.764323 -264.872425) (xy 347.813498 -264.870444) (xy 347.862353 -264.876376)
			(xy 347.909624 -264.890068) (xy 347.954086 -264.911166) (xy 347.994589 -264.939122) (xy 348.030082 -264.973214)
			(xy 348.059647 -265.012558) (xy 348.082518 -265.056135) (xy 348.098102 -265.102816) (xy 348.105997 -265.151393)
			(xy 348.106492 -265.176) (xy 348.105997 -265.200607) (xy 348.098102 -265.249184) (xy 348.082518 -265.295865)
			(xy 348.059647 -265.339442) (xy 348.030082 -265.378786) (xy 347.994589 -265.412878) (xy 347.954086 -265.440834)
			(xy 347.909624 -265.461932) (xy 347.862353 -265.475624) (xy 347.813498 -265.481556) (xy 347.764323 -265.479575)
			(xy 347.716104 -265.469731) (xy 347.670088 -265.452279) (xy 347.627467 -265.427672) (xy 347.589346 -265.396547)
			(xy 347.556711 -265.35971) (xy 347.530408 -265.318114) (xy 347.511117 -265.272838) (xy 347.49934 -265.225054)
			(xy 347.49538 -265.176) (xy 346.226384 -265.176) (xy 346.225889 -265.200607) (xy 346.217994 -265.249184)
			(xy 346.20241 -265.295865) (xy 346.179539 -265.339442) (xy 346.149974 -265.378786) (xy 346.114481 -265.412878)
			(xy 346.073978 -265.440834) (xy 346.029516 -265.461932) (xy 345.982245 -265.475624) (xy 345.93339 -265.481556)
			(xy 345.884215 -265.479575) (xy 345.835996 -265.469731) (xy 345.78998 -265.452279) (xy 345.747359 -265.427672)
			(xy 345.709238 -265.396547) (xy 345.676603 -265.35971) (xy 345.6503 -265.318114) (xy 345.631009 -265.272838)
			(xy 345.619232 -265.225054) (xy 345.615272 -265.176) (xy 344.34653 -265.176) (xy 344.346035 -265.200607)
			(xy 344.33814 -265.249184) (xy 344.322556 -265.295865) (xy 344.299685 -265.339442) (xy 344.27012 -265.378786)
			(xy 344.234627 -265.412878) (xy 344.194124 -265.440834) (xy 344.149662 -265.461932) (xy 344.102391 -265.475624)
			(xy 344.053536 -265.481556) (xy 344.004361 -265.479575) (xy 343.956142 -265.469731) (xy 343.910126 -265.452279)
			(xy 343.867505 -265.427672) (xy 343.829384 -265.396547) (xy 343.796749 -265.35971) (xy 343.770446 -265.318114)
			(xy 343.751155 -265.272838) (xy 343.739378 -265.225054) (xy 343.735418 -265.176) (xy 343.406476 -265.176)
			(xy 343.405981 -265.200607) (xy 343.398086 -265.249184) (xy 343.382502 -265.295865) (xy 343.359631 -265.339442)
			(xy 343.330066 -265.378786) (xy 343.294573 -265.412878) (xy 343.25407 -265.440834) (xy 343.209608 -265.461932)
			(xy 343.162337 -265.475624) (xy 343.113482 -265.481556) (xy 343.064307 -265.479575) (xy 343.016088 -265.469731)
			(xy 342.970072 -265.452279) (xy 342.927451 -265.427672) (xy 342.88933 -265.396547) (xy 342.856695 -265.35971)
			(xy 342.830392 -265.318114) (xy 342.811101 -265.272838) (xy 342.799324 -265.225054) (xy 342.795364 -265.176)
			(xy 342.476836 -265.176) (xy 342.476324 -265.201446) (xy 342.46816 -265.25168) (xy 342.452044 -265.299954)
			(xy 342.428393 -265.345017) (xy 342.39782 -265.385703) (xy 342.361116 -265.420958) (xy 342.319232 -265.449868)
			(xy 342.273253 -265.471685) (xy 342.224369 -265.485845) (xy 342.173848 -265.491979) (xy 342.122996 -265.48993)
			(xy 342.073132 -265.47975) (xy 342.025546 -265.461703) (xy 341.981472 -265.436257) (xy 341.94205 -265.40407)
			(xy 341.908302 -265.365976) (xy 341.881101 -265.322962) (xy 341.861153 -265.276142) (xy 341.848974 -265.226728)
			(xy 341.844879 -265.176) (xy 341.526368 -265.176) (xy 341.525873 -265.200607) (xy 341.517978 -265.249184)
			(xy 341.502394 -265.295865) (xy 341.479523 -265.339442) (xy 341.449958 -265.378786) (xy 341.414465 -265.412878)
			(xy 341.373962 -265.440834) (xy 341.3295 -265.461932) (xy 341.282229 -265.475624) (xy 341.233374 -265.481556)
			(xy 341.184199 -265.479575) (xy 341.13598 -265.469731) (xy 341.089964 -265.452279) (xy 341.047343 -265.427672)
			(xy 341.009222 -265.396547) (xy 340.976587 -265.35971) (xy 340.950284 -265.318114) (xy 340.930993 -265.272838)
			(xy 340.919216 -265.225054) (xy 340.915256 -265.176) (xy 340.586314 -265.176) (xy 340.585819 -265.200607)
			(xy 340.577924 -265.249184) (xy 340.56234 -265.295865) (xy 340.539469 -265.339442) (xy 340.509904 -265.378786)
			(xy 340.474411 -265.412878) (xy 340.433908 -265.440834) (xy 340.389446 -265.461932) (xy 340.342175 -265.475624)
			(xy 340.29332 -265.481556) (xy 340.244145 -265.479575) (xy 340.195926 -265.469731) (xy 340.14991 -265.452279)
			(xy 340.107289 -265.427672) (xy 340.069168 -265.396547) (xy 340.036533 -265.35971) (xy 340.01023 -265.318114)
			(xy 339.990939 -265.272838) (xy 339.979162 -265.225054) (xy 339.975202 -265.176) (xy 339.656928 -265.176)
			(xy 339.656416 -265.201446) (xy 339.648252 -265.25168) (xy 339.632136 -265.299954) (xy 339.608485 -265.345017)
			(xy 339.577912 -265.385703) (xy 339.541208 -265.420958) (xy 339.499324 -265.449868) (xy 339.453345 -265.471685)
			(xy 339.404461 -265.485845) (xy 339.35394 -265.491979) (xy 339.303088 -265.48993) (xy 339.253224 -265.47975)
			(xy 339.205638 -265.461703) (xy 339.161564 -265.436257) (xy 339.122142 -265.40407) (xy 339.088394 -265.365976)
			(xy 339.061193 -265.322962) (xy 339.041245 -265.276142) (xy 339.029066 -265.226728) (xy 339.024971 -265.176)
			(xy 338.70646 -265.176) (xy 338.705965 -265.200607) (xy 338.69807 -265.249184) (xy 338.682486 -265.295865)
			(xy 338.659615 -265.339442) (xy 338.63005 -265.378786) (xy 338.594557 -265.412878) (xy 338.554054 -265.440834)
			(xy 338.509592 -265.461932) (xy 338.462321 -265.475624) (xy 338.413466 -265.481556) (xy 338.364291 -265.479575)
			(xy 338.316072 -265.469731) (xy 338.270056 -265.452279) (xy 338.227435 -265.427672) (xy 338.189314 -265.396547)
			(xy 338.156679 -265.35971) (xy 338.130376 -265.318114) (xy 338.111085 -265.272838) (xy 338.099308 -265.225054)
			(xy 338.095348 -265.176) (xy 337.766406 -265.176) (xy 337.765911 -265.200607) (xy 337.758016 -265.249184)
			(xy 337.742432 -265.295865) (xy 337.719561 -265.339442) (xy 337.689996 -265.378786) (xy 337.654503 -265.412878)
			(xy 337.614 -265.440834) (xy 337.569538 -265.461932) (xy 337.522267 -265.475624) (xy 337.473412 -265.481556)
			(xy 337.424237 -265.479575) (xy 337.376018 -265.469731) (xy 337.330002 -265.452279) (xy 337.287381 -265.427672)
			(xy 337.24926 -265.396547) (xy 337.216625 -265.35971) (xy 337.190322 -265.318114) (xy 337.171031 -265.272838)
			(xy 337.159254 -265.225054) (xy 337.155294 -265.176) (xy 336.826352 -265.176) (xy 336.825857 -265.200607)
			(xy 336.817962 -265.249184) (xy 336.802378 -265.295865) (xy 336.779507 -265.339442) (xy 336.749942 -265.378786)
			(xy 336.714449 -265.412878) (xy 336.673946 -265.440834) (xy 336.629484 -265.461932) (xy 336.582213 -265.475624)
			(xy 336.533358 -265.481556) (xy 336.484183 -265.479575) (xy 336.435964 -265.469731) (xy 336.389948 -265.452279)
			(xy 336.347327 -265.427672) (xy 336.309206 -265.396547) (xy 336.276571 -265.35971) (xy 336.250268 -265.318114)
			(xy 336.230977 -265.272838) (xy 336.2192 -265.225054) (xy 336.21524 -265.176) (xy 335.896712 -265.176)
			(xy 335.8962 -265.201446) (xy 335.888036 -265.25168) (xy 335.87192 -265.299954) (xy 335.848269 -265.345017)
			(xy 335.817696 -265.385703) (xy 335.780992 -265.420958) (xy 335.739108 -265.449868) (xy 335.693129 -265.471685)
			(xy 335.644245 -265.485845) (xy 335.593724 -265.491979) (xy 335.542872 -265.48993) (xy 335.493008 -265.47975)
			(xy 335.445422 -265.461703) (xy 335.401348 -265.436257) (xy 335.361926 -265.40407) (xy 335.328178 -265.365976)
			(xy 335.300977 -265.322962) (xy 335.281029 -265.276142) (xy 335.26885 -265.226728) (xy 335.264755 -265.176)
			(xy 334.946498 -265.176) (xy 334.946003 -265.200607) (xy 334.938108 -265.249184) (xy 334.922524 -265.295865)
			(xy 334.899653 -265.339442) (xy 334.870088 -265.378786) (xy 334.834595 -265.412878) (xy 334.794092 -265.440834)
			(xy 334.74963 -265.461932) (xy 334.702359 -265.475624) (xy 334.653504 -265.481556) (xy 334.604329 -265.479575)
			(xy 334.55611 -265.469731) (xy 334.510094 -265.452279) (xy 334.467473 -265.427672) (xy 334.429352 -265.396547)
			(xy 334.396717 -265.35971) (xy 334.370414 -265.318114) (xy 334.351123 -265.272838) (xy 334.339346 -265.225054)
			(xy 334.335386 -265.176) (xy 334.006444 -265.176) (xy 334.005949 -265.200607) (xy 333.998054 -265.249184)
			(xy 333.98247 -265.295865) (xy 333.959599 -265.339442) (xy 333.930034 -265.378786) (xy 333.894541 -265.412878)
			(xy 333.854038 -265.440834) (xy 333.809576 -265.461932) (xy 333.762305 -265.475624) (xy 333.71345 -265.481556)
			(xy 333.664275 -265.479575) (xy 333.616056 -265.469731) (xy 333.57004 -265.452279) (xy 333.527419 -265.427672)
			(xy 333.489298 -265.396547) (xy 333.456663 -265.35971) (xy 333.43036 -265.318114) (xy 333.411069 -265.272838)
			(xy 333.399292 -265.225054) (xy 333.395332 -265.176) (xy 333.076804 -265.176) (xy 333.076292 -265.201446)
			(xy 333.068128 -265.25168) (xy 333.052012 -265.299954) (xy 333.028361 -265.345017) (xy 332.997788 -265.385703)
			(xy 332.961084 -265.420958) (xy 332.9192 -265.449868) (xy 332.873221 -265.471685) (xy 332.824337 -265.485845)
			(xy 332.773816 -265.491979) (xy 332.722964 -265.48993) (xy 332.6731 -265.47975) (xy 332.625514 -265.461703)
			(xy 332.58144 -265.436257) (xy 332.542018 -265.40407) (xy 332.50827 -265.365976) (xy 332.481069 -265.322962)
			(xy 332.461121 -265.276142) (xy 332.448942 -265.226728) (xy 332.444847 -265.176) (xy 332.126336 -265.176)
			(xy 332.125841 -265.200607) (xy 332.117946 -265.249184) (xy 332.102362 -265.295865) (xy 332.079491 -265.339442)
			(xy 332.049926 -265.378786) (xy 332.014433 -265.412878) (xy 331.97393 -265.440834) (xy 331.929468 -265.461932)
			(xy 331.882197 -265.475624) (xy 331.833342 -265.481556) (xy 331.784167 -265.479575) (xy 331.735948 -265.469731)
			(xy 331.689932 -265.452279) (xy 331.647311 -265.427672) (xy 331.60919 -265.396547) (xy 331.576555 -265.35971)
			(xy 331.550252 -265.318114) (xy 331.530961 -265.272838) (xy 331.519184 -265.225054) (xy 331.515224 -265.176)
			(xy 331.186536 -265.176) (xy 331.186041 -265.200607) (xy 331.178146 -265.249184) (xy 331.162562 -265.295865)
			(xy 331.139691 -265.339442) (xy 331.110126 -265.378786) (xy 331.074633 -265.412878) (xy 331.03413 -265.440834)
			(xy 330.989668 -265.461932) (xy 330.942397 -265.475624) (xy 330.893542 -265.481556) (xy 330.844367 -265.479575)
			(xy 330.796148 -265.469731) (xy 330.750132 -265.452279) (xy 330.707511 -265.427672) (xy 330.66939 -265.396547)
			(xy 330.636755 -265.35971) (xy 330.610452 -265.318114) (xy 330.591161 -265.272838) (xy 330.579384 -265.225054)
			(xy 330.575424 -265.176) (xy 330.246482 -265.176) (xy 330.245987 -265.200607) (xy 330.238092 -265.249184)
			(xy 330.222508 -265.295865) (xy 330.199637 -265.339442) (xy 330.170072 -265.378786) (xy 330.134579 -265.412878)
			(xy 330.094076 -265.440834) (xy 330.049614 -265.461932) (xy 330.002343 -265.475624) (xy 329.953488 -265.481556)
			(xy 329.904313 -265.479575) (xy 329.856094 -265.469731) (xy 329.810078 -265.452279) (xy 329.767457 -265.427672)
			(xy 329.729336 -265.396547) (xy 329.696701 -265.35971) (xy 329.670398 -265.318114) (xy 329.651107 -265.272838)
			(xy 329.63933 -265.225054) (xy 329.63537 -265.176) (xy 329.316842 -265.176) (xy 329.31633 -265.201446)
			(xy 329.308166 -265.25168) (xy 329.29205 -265.299954) (xy 329.268399 -265.345017) (xy 329.237826 -265.385703)
			(xy 329.201122 -265.420958) (xy 329.159238 -265.449868) (xy 329.113259 -265.471685) (xy 329.064375 -265.485845)
			(xy 329.013854 -265.491979) (xy 328.963002 -265.48993) (xy 328.913138 -265.47975) (xy 328.865552 -265.461703)
			(xy 328.821478 -265.436257) (xy 328.782056 -265.40407) (xy 328.748308 -265.365976) (xy 328.721107 -265.322962)
			(xy 328.701159 -265.276142) (xy 328.68898 -265.226728) (xy 328.684885 -265.176) (xy 328.366374 -265.176)
			(xy 328.365879 -265.200607) (xy 328.357984 -265.249184) (xy 328.3424 -265.295865) (xy 328.319529 -265.339442)
			(xy 328.289964 -265.378786) (xy 328.254471 -265.412878) (xy 328.213968 -265.440834) (xy 328.169506 -265.461932)
			(xy 328.122235 -265.475624) (xy 328.07338 -265.481556) (xy 328.024205 -265.479575) (xy 327.975986 -265.469731)
			(xy 327.92997 -265.452279) (xy 327.887349 -265.427672) (xy 327.849228 -265.396547) (xy 327.816593 -265.35971)
			(xy 327.79029 -265.318114) (xy 327.770999 -265.272838) (xy 327.759222 -265.225054) (xy 327.755262 -265.176)
			(xy 325.203519 -265.176) (xy 325.161384 -265.195994) (xy 325.114113 -265.209686) (xy 325.065258 -265.215618)
			(xy 325.016083 -265.213637) (xy 324.967864 -265.203793) (xy 324.921848 -265.186341) (xy 324.879227 -265.161734)
			(xy 324.841106 -265.130609) (xy 324.808471 -265.093772) (xy 324.782168 -265.052176) (xy 324.762877 -265.0069)
			(xy 324.7511 -264.959116) (xy 324.74714 -264.910062) (xy 310.45912 -264.910062) (xy 310.45912 -265.986006)
			(xy 326.345308 -265.986006) (xy 326.349268 -265.936952) (xy 326.361045 -265.889168) (xy 326.380336 -265.843892)
			(xy 326.406639 -265.802296) (xy 326.439274 -265.765459) (xy 326.477395 -265.734334) (xy 326.520016 -265.709727)
			(xy 326.566032 -265.692275) (xy 326.614251 -265.682431) (xy 326.663426 -265.68045) (xy 326.712281 -265.686382)
			(xy 326.759552 -265.700074) (xy 326.804014 -265.721172) (xy 326.844517 -265.749128) (xy 326.88001 -265.78322)
			(xy 326.909575 -265.822564) (xy 326.932446 -265.866141) (xy 326.94803 -265.912822) (xy 326.955925 -265.961399)
			(xy 326.95642 -265.986006) (xy 329.165216 -265.986006) (xy 329.169176 -265.936952) (xy 329.180953 -265.889168)
			(xy 329.200244 -265.843892) (xy 329.226547 -265.802296) (xy 329.259182 -265.765459) (xy 329.297303 -265.734334)
			(xy 329.339924 -265.709727) (xy 329.38594 -265.692275) (xy 329.434159 -265.682431) (xy 329.483334 -265.68045)
			(xy 329.532189 -265.686382) (xy 329.57946 -265.700074) (xy 329.623922 -265.721172) (xy 329.664425 -265.749128)
			(xy 329.699918 -265.78322) (xy 329.729483 -265.822564) (xy 329.752354 -265.866141) (xy 329.767938 -265.912822)
			(xy 329.775833 -265.961399) (xy 329.776328 -265.986006) (xy 330.094839 -265.986006) (xy 330.098934 -265.935278)
			(xy 330.111113 -265.885864) (xy 330.131061 -265.839044) (xy 330.158262 -265.79603) (xy 330.19201 -265.757936)
			(xy 330.231432 -265.725749) (xy 330.275506 -265.700303) (xy 330.323092 -265.682256) (xy 330.372956 -265.672076)
			(xy 330.423808 -265.670027) (xy 330.474329 -265.676161) (xy 330.523213 -265.690321) (xy 330.569192 -265.712138)
			(xy 330.611076 -265.741048) (xy 330.64778 -265.776303) (xy 330.678353 -265.816989) (xy 330.702004 -265.862052)
			(xy 330.71812 -265.910326) (xy 330.726284 -265.96056) (xy 330.726796 -265.986006) (xy 331.045324 -265.986006)
			(xy 331.049284 -265.936952) (xy 331.061061 -265.889168) (xy 331.080352 -265.843892) (xy 331.106655 -265.802296)
			(xy 331.13929 -265.765459) (xy 331.177411 -265.734334) (xy 331.220032 -265.709727) (xy 331.266048 -265.692275)
			(xy 331.314267 -265.682431) (xy 331.363442 -265.68045) (xy 331.412297 -265.686382) (xy 331.459568 -265.700074)
			(xy 331.50403 -265.721172) (xy 331.544533 -265.749128) (xy 331.580026 -265.78322) (xy 331.609591 -265.822564)
			(xy 331.632462 -265.866141) (xy 331.648046 -265.912822) (xy 331.655941 -265.961399) (xy 331.656436 -265.986006)
			(xy 331.985378 -265.986006) (xy 331.989338 -265.936952) (xy 332.001115 -265.889168) (xy 332.020406 -265.843892)
			(xy 332.046709 -265.802296) (xy 332.079344 -265.765459) (xy 332.117465 -265.734334) (xy 332.160086 -265.709727)
			(xy 332.206102 -265.692275) (xy 332.254321 -265.682431) (xy 332.303496 -265.68045) (xy 332.352351 -265.686382)
			(xy 332.399622 -265.700074) (xy 332.444084 -265.721172) (xy 332.484587 -265.749128) (xy 332.52008 -265.78322)
			(xy 332.549645 -265.822564) (xy 332.572516 -265.866141) (xy 332.5881 -265.912822) (xy 332.595995 -265.961399)
			(xy 332.59649 -265.986006) (xy 332.925178 -265.986006) (xy 332.929138 -265.936952) (xy 332.940915 -265.889168)
			(xy 332.960206 -265.843892) (xy 332.986509 -265.802296) (xy 333.019144 -265.765459) (xy 333.057265 -265.734334)
			(xy 333.099886 -265.709727) (xy 333.145902 -265.692275) (xy 333.194121 -265.682431) (xy 333.243296 -265.68045)
			(xy 333.292151 -265.686382) (xy 333.339422 -265.700074) (xy 333.383884 -265.721172) (xy 333.424387 -265.749128)
			(xy 333.45988 -265.78322) (xy 333.489445 -265.822564) (xy 333.512316 -265.866141) (xy 333.5279 -265.912822)
			(xy 333.535795 -265.961399) (xy 333.53629 -265.986006) (xy 333.854801 -265.986006) (xy 333.858896 -265.935278)
			(xy 333.871075 -265.885864) (xy 333.891023 -265.839044) (xy 333.918224 -265.79603) (xy 333.951972 -265.757936)
			(xy 333.991394 -265.725749) (xy 334.035468 -265.700303) (xy 334.083054 -265.682256) (xy 334.132918 -265.672076)
			(xy 334.18377 -265.670027) (xy 334.234291 -265.676161) (xy 334.283175 -265.690321) (xy 334.329154 -265.712138)
			(xy 334.371038 -265.741048) (xy 334.407742 -265.776303) (xy 334.438315 -265.816989) (xy 334.461966 -265.862052)
			(xy 334.478082 -265.910326) (xy 334.486246 -265.96056) (xy 334.486758 -265.986006) (xy 335.74534 -265.986006)
			(xy 335.7493 -265.936952) (xy 335.761077 -265.889168) (xy 335.780368 -265.843892) (xy 335.806671 -265.802296)
			(xy 335.839306 -265.765459) (xy 335.877427 -265.734334) (xy 335.920048 -265.709727) (xy 335.966064 -265.692275)
			(xy 336.014283 -265.682431) (xy 336.063458 -265.68045) (xy 336.112313 -265.686382) (xy 336.159584 -265.700074)
			(xy 336.204046 -265.721172) (xy 336.244549 -265.749128) (xy 336.280042 -265.78322) (xy 336.309607 -265.822564)
			(xy 336.332478 -265.866141) (xy 336.348062 -265.912822) (xy 336.355957 -265.961399) (xy 336.356452 -265.986006)
			(xy 336.674963 -265.986006) (xy 336.679058 -265.935278) (xy 336.691237 -265.885864) (xy 336.711185 -265.839044)
			(xy 336.738386 -265.79603) (xy 336.772134 -265.757936) (xy 336.811556 -265.725749) (xy 336.85563 -265.700303)
			(xy 336.903216 -265.682256) (xy 336.95308 -265.672076) (xy 337.003932 -265.670027) (xy 337.054453 -265.676161)
			(xy 337.103337 -265.690321) (xy 337.149316 -265.712138) (xy 337.1912 -265.741048) (xy 337.227904 -265.776303)
			(xy 337.258477 -265.816989) (xy 337.282128 -265.862052) (xy 337.298244 -265.910326) (xy 337.306408 -265.96056)
			(xy 337.30692 -265.986006) (xy 337.625194 -265.986006) (xy 337.629154 -265.936952) (xy 337.640931 -265.889168)
			(xy 337.660222 -265.843892) (xy 337.686525 -265.802296) (xy 337.71916 -265.765459) (xy 337.757281 -265.734334)
			(xy 337.799902 -265.709727) (xy 337.845918 -265.692275) (xy 337.894137 -265.682431) (xy 337.943312 -265.68045)
			(xy 337.992167 -265.686382) (xy 338.039438 -265.700074) (xy 338.0839 -265.721172) (xy 338.124403 -265.749128)
			(xy 338.159896 -265.78322) (xy 338.189461 -265.822564) (xy 338.212332 -265.866141) (xy 338.227916 -265.912822)
			(xy 338.235811 -265.961399) (xy 338.236306 -265.986006) (xy 338.565248 -265.986006) (xy 338.569208 -265.936952)
			(xy 338.580985 -265.889168) (xy 338.600276 -265.843892) (xy 338.626579 -265.802296) (xy 338.659214 -265.765459)
			(xy 338.697335 -265.734334) (xy 338.739956 -265.709727) (xy 338.785972 -265.692275) (xy 338.834191 -265.682431)
			(xy 338.883366 -265.68045) (xy 338.932221 -265.686382) (xy 338.979492 -265.700074) (xy 339.023954 -265.721172)
			(xy 339.064457 -265.749128) (xy 339.09995 -265.78322) (xy 339.129515 -265.822564) (xy 339.152386 -265.866141)
			(xy 339.16797 -265.912822) (xy 339.175865 -265.961399) (xy 339.17636 -265.986006) (xy 339.505302 -265.986006)
			(xy 339.509262 -265.936952) (xy 339.521039 -265.889168) (xy 339.54033 -265.843892) (xy 339.566633 -265.802296)
			(xy 339.599268 -265.765459) (xy 339.637389 -265.734334) (xy 339.68001 -265.709727) (xy 339.726026 -265.692275)
			(xy 339.774245 -265.682431) (xy 339.82342 -265.68045) (xy 339.872275 -265.686382) (xy 339.919546 -265.700074)
			(xy 339.964008 -265.721172) (xy 340.004511 -265.749128) (xy 340.040004 -265.78322) (xy 340.069569 -265.822564)
			(xy 340.09244 -265.866141) (xy 340.108024 -265.912822) (xy 340.115919 -265.961399) (xy 340.116414 -265.986006)
			(xy 340.434925 -265.986006) (xy 340.43902 -265.935278) (xy 340.451199 -265.885864) (xy 340.471147 -265.839044)
			(xy 340.498348 -265.79603) (xy 340.532096 -265.757936) (xy 340.571518 -265.725749) (xy 340.615592 -265.700303)
			(xy 340.663178 -265.682256) (xy 340.713042 -265.672076) (xy 340.763894 -265.670027) (xy 340.814415 -265.676161)
			(xy 340.863299 -265.690321) (xy 340.909278 -265.712138) (xy 340.951162 -265.741048) (xy 340.987866 -265.776303)
			(xy 341.018439 -265.816989) (xy 341.04209 -265.862052) (xy 341.058206 -265.910326) (xy 341.06637 -265.96056)
			(xy 341.066882 -265.986006) (xy 342.32521 -265.986006) (xy 342.32917 -265.936952) (xy 342.340947 -265.889168)
			(xy 342.360238 -265.843892) (xy 342.386541 -265.802296) (xy 342.419176 -265.765459) (xy 342.457297 -265.734334)
			(xy 342.499918 -265.709727) (xy 342.545934 -265.692275) (xy 342.594153 -265.682431) (xy 342.643328 -265.68045)
			(xy 342.692183 -265.686382) (xy 342.739454 -265.700074) (xy 342.783916 -265.721172) (xy 342.824419 -265.749128)
			(xy 342.859912 -265.78322) (xy 342.889477 -265.822564) (xy 342.912348 -265.866141) (xy 342.927932 -265.912822)
			(xy 342.935827 -265.961399) (xy 342.936322 -265.986006) (xy 343.254833 -265.986006) (xy 343.258928 -265.935278)
			(xy 343.271107 -265.885864) (xy 343.291055 -265.839044) (xy 343.318256 -265.79603) (xy 343.352004 -265.757936)
			(xy 343.391426 -265.725749) (xy 343.4355 -265.700303) (xy 343.483086 -265.682256) (xy 343.53295 -265.672076)
			(xy 343.583802 -265.670027) (xy 343.634323 -265.676161) (xy 343.683207 -265.690321) (xy 343.729186 -265.712138)
			(xy 343.77107 -265.741048) (xy 343.807774 -265.776303) (xy 343.838347 -265.816989) (xy 343.861998 -265.862052)
			(xy 343.878114 -265.910326) (xy 343.886278 -265.96056) (xy 343.88679 -265.986006) (xy 344.205318 -265.986006)
			(xy 344.209278 -265.936952) (xy 344.221055 -265.889168) (xy 344.240346 -265.843892) (xy 344.266649 -265.802296)
			(xy 344.299284 -265.765459) (xy 344.337405 -265.734334) (xy 344.380026 -265.709727) (xy 344.426042 -265.692275)
			(xy 344.474261 -265.682431) (xy 344.523436 -265.68045) (xy 344.572291 -265.686382) (xy 344.619562 -265.700074)
			(xy 344.664024 -265.721172) (xy 344.704527 -265.749128) (xy 344.74002 -265.78322) (xy 344.769585 -265.822564)
			(xy 344.792456 -265.866141) (xy 344.80804 -265.912822) (xy 344.815935 -265.961399) (xy 344.81643 -265.986006)
			(xy 346.085426 -265.986006) (xy 346.089386 -265.936952) (xy 346.101163 -265.889168) (xy 346.120454 -265.843892)
			(xy 346.146757 -265.802296) (xy 346.179392 -265.765459) (xy 346.217513 -265.734334) (xy 346.260134 -265.709727)
			(xy 346.30615 -265.692275) (xy 346.354369 -265.682431) (xy 346.403544 -265.68045) (xy 346.452399 -265.686382)
			(xy 346.49967 -265.700074) (xy 346.544132 -265.721172) (xy 346.584635 -265.749128) (xy 346.620128 -265.78322)
			(xy 346.649693 -265.822564) (xy 346.672564 -265.866141) (xy 346.688148 -265.912822) (xy 346.696043 -265.961399)
			(xy 346.696538 -265.986006) (xy 346.696043 -266.010613) (xy 346.688148 -266.05919) (xy 346.672564 -266.105871)
			(xy 346.649693 -266.149448) (xy 346.620128 -266.188792) (xy 346.584635 -266.222884) (xy 346.544132 -266.25084)
			(xy 346.49967 -266.271938) (xy 346.452399 -266.28563) (xy 346.403544 -266.291562) (xy 346.354369 -266.289581)
			(xy 346.30615 -266.279737) (xy 346.260134 -266.262285) (xy 346.217513 -266.237678) (xy 346.179392 -266.206553)
			(xy 346.146757 -266.169716) (xy 346.120454 -266.12812) (xy 346.101163 -266.082844) (xy 346.089386 -266.03506)
			(xy 346.085426 -265.986006) (xy 344.81643 -265.986006) (xy 344.815935 -266.010613) (xy 344.80804 -266.05919)
			(xy 344.792456 -266.105871) (xy 344.769585 -266.149448) (xy 344.74002 -266.188792) (xy 344.704527 -266.222884)
			(xy 344.664024 -266.25084) (xy 344.619562 -266.271938) (xy 344.572291 -266.28563) (xy 344.523436 -266.291562)
			(xy 344.474261 -266.289581) (xy 344.426042 -266.279737) (xy 344.380026 -266.262285) (xy 344.337405 -266.237678)
			(xy 344.299284 -266.206553) (xy 344.266649 -266.169716) (xy 344.240346 -266.12812) (xy 344.221055 -266.082844)
			(xy 344.209278 -266.03506) (xy 344.205318 -265.986006) (xy 343.88679 -265.986006) (xy 343.886278 -266.011452)
			(xy 343.878114 -266.061686) (xy 343.861998 -266.10996) (xy 343.838347 -266.155023) (xy 343.807774 -266.195709)
			(xy 343.77107 -266.230964) (xy 343.729186 -266.259874) (xy 343.683207 -266.281691) (xy 343.634323 -266.295851)
			(xy 343.583802 -266.301985) (xy 343.53295 -266.299936) (xy 343.483086 -266.289756) (xy 343.4355 -266.271709)
			(xy 343.391426 -266.246263) (xy 343.352004 -266.214076) (xy 343.318256 -266.175982) (xy 343.291055 -266.132968)
			(xy 343.271107 -266.086148) (xy 343.258928 -266.036734) (xy 343.254833 -265.986006) (xy 342.936322 -265.986006)
			(xy 342.935827 -266.010613) (xy 342.927932 -266.05919) (xy 342.912348 -266.105871) (xy 342.889477 -266.149448)
			(xy 342.859912 -266.188792) (xy 342.824419 -266.222884) (xy 342.783916 -266.25084) (xy 342.739454 -266.271938)
			(xy 342.692183 -266.28563) (xy 342.643328 -266.291562) (xy 342.594153 -266.289581) (xy 342.545934 -266.279737)
			(xy 342.499918 -266.262285) (xy 342.457297 -266.237678) (xy 342.419176 -266.206553) (xy 342.386541 -266.169716)
			(xy 342.360238 -266.12812) (xy 342.340947 -266.082844) (xy 342.32917 -266.03506) (xy 342.32521 -265.986006)
			(xy 341.066882 -265.986006) (xy 341.06637 -266.011452) (xy 341.058206 -266.061686) (xy 341.04209 -266.10996)
			(xy 341.018439 -266.155023) (xy 340.987866 -266.195709) (xy 340.951162 -266.230964) (xy 340.909278 -266.259874)
			(xy 340.863299 -266.281691) (xy 340.814415 -266.295851) (xy 340.763894 -266.301985) (xy 340.713042 -266.299936)
			(xy 340.663178 -266.289756) (xy 340.615592 -266.271709) (xy 340.571518 -266.246263) (xy 340.532096 -266.214076)
			(xy 340.498348 -266.175982) (xy 340.471147 -266.132968) (xy 340.451199 -266.086148) (xy 340.43902 -266.036734)
			(xy 340.434925 -265.986006) (xy 340.116414 -265.986006) (xy 340.115919 -266.010613) (xy 340.108024 -266.05919)
			(xy 340.09244 -266.105871) (xy 340.069569 -266.149448) (xy 340.040004 -266.188792) (xy 340.004511 -266.222884)
			(xy 339.964008 -266.25084) (xy 339.919546 -266.271938) (xy 339.872275 -266.28563) (xy 339.82342 -266.291562)
			(xy 339.774245 -266.289581) (xy 339.726026 -266.279737) (xy 339.68001 -266.262285) (xy 339.637389 -266.237678)
			(xy 339.599268 -266.206553) (xy 339.566633 -266.169716) (xy 339.54033 -266.12812) (xy 339.521039 -266.082844)
			(xy 339.509262 -266.03506) (xy 339.505302 -265.986006) (xy 339.17636 -265.986006) (xy 339.175865 -266.010613)
			(xy 339.16797 -266.05919) (xy 339.152386 -266.105871) (xy 339.129515 -266.149448) (xy 339.09995 -266.188792)
			(xy 339.064457 -266.222884) (xy 339.023954 -266.25084) (xy 338.979492 -266.271938) (xy 338.932221 -266.28563)
			(xy 338.883366 -266.291562) (xy 338.834191 -266.289581) (xy 338.785972 -266.279737) (xy 338.739956 -266.262285)
			(xy 338.697335 -266.237678) (xy 338.659214 -266.206553) (xy 338.626579 -266.169716) (xy 338.600276 -266.12812)
			(xy 338.580985 -266.082844) (xy 338.569208 -266.03506) (xy 338.565248 -265.986006) (xy 338.236306 -265.986006)
			(xy 338.235811 -266.010613) (xy 338.227916 -266.05919) (xy 338.212332 -266.105871) (xy 338.189461 -266.149448)
			(xy 338.159896 -266.188792) (xy 338.124403 -266.222884) (xy 338.0839 -266.25084) (xy 338.039438 -266.271938)
			(xy 337.992167 -266.28563) (xy 337.943312 -266.291562) (xy 337.894137 -266.289581) (xy 337.845918 -266.279737)
			(xy 337.799902 -266.262285) (xy 337.757281 -266.237678) (xy 337.71916 -266.206553) (xy 337.686525 -266.169716)
			(xy 337.660222 -266.12812) (xy 337.640931 -266.082844) (xy 337.629154 -266.03506) (xy 337.625194 -265.986006)
			(xy 337.30692 -265.986006) (xy 337.306408 -266.011452) (xy 337.298244 -266.061686) (xy 337.282128 -266.10996)
			(xy 337.258477 -266.155023) (xy 337.227904 -266.195709) (xy 337.1912 -266.230964) (xy 337.149316 -266.259874)
			(xy 337.103337 -266.281691) (xy 337.054453 -266.295851) (xy 337.003932 -266.301985) (xy 336.95308 -266.299936)
			(xy 336.903216 -266.289756) (xy 336.85563 -266.271709) (xy 336.811556 -266.246263) (xy 336.772134 -266.214076)
			(xy 336.738386 -266.175982) (xy 336.711185 -266.132968) (xy 336.691237 -266.086148) (xy 336.679058 -266.036734)
			(xy 336.674963 -265.986006) (xy 336.356452 -265.986006) (xy 336.355957 -266.010613) (xy 336.348062 -266.05919)
			(xy 336.332478 -266.105871) (xy 336.309607 -266.149448) (xy 336.280042 -266.188792) (xy 336.244549 -266.222884)
			(xy 336.204046 -266.25084) (xy 336.159584 -266.271938) (xy 336.112313 -266.28563) (xy 336.063458 -266.291562)
			(xy 336.014283 -266.289581) (xy 335.966064 -266.279737) (xy 335.920048 -266.262285) (xy 335.877427 -266.237678)
			(xy 335.839306 -266.206553) (xy 335.806671 -266.169716) (xy 335.780368 -266.12812) (xy 335.761077 -266.082844)
			(xy 335.7493 -266.03506) (xy 335.74534 -265.986006) (xy 334.486758 -265.986006) (xy 334.486246 -266.011452)
			(xy 334.478082 -266.061686) (xy 334.461966 -266.10996) (xy 334.438315 -266.155023) (xy 334.407742 -266.195709)
			(xy 334.371038 -266.230964) (xy 334.329154 -266.259874) (xy 334.283175 -266.281691) (xy 334.234291 -266.295851)
			(xy 334.18377 -266.301985) (xy 334.132918 -266.299936) (xy 334.083054 -266.289756) (xy 334.035468 -266.271709)
			(xy 333.991394 -266.246263) (xy 333.951972 -266.214076) (xy 333.918224 -266.175982) (xy 333.891023 -266.132968)
			(xy 333.871075 -266.086148) (xy 333.858896 -266.036734) (xy 333.854801 -265.986006) (xy 333.53629 -265.986006)
			(xy 333.535795 -266.010613) (xy 333.5279 -266.05919) (xy 333.512316 -266.105871) (xy 333.489445 -266.149448)
			(xy 333.45988 -266.188792) (xy 333.424387 -266.222884) (xy 333.383884 -266.25084) (xy 333.339422 -266.271938)
			(xy 333.292151 -266.28563) (xy 333.243296 -266.291562) (xy 333.194121 -266.289581) (xy 333.145902 -266.279737)
			(xy 333.099886 -266.262285) (xy 333.057265 -266.237678) (xy 333.019144 -266.206553) (xy 332.986509 -266.169716)
			(xy 332.960206 -266.12812) (xy 332.940915 -266.082844) (xy 332.929138 -266.03506) (xy 332.925178 -265.986006)
			(xy 332.59649 -265.986006) (xy 332.595995 -266.010613) (xy 332.5881 -266.05919) (xy 332.572516 -266.105871)
			(xy 332.549645 -266.149448) (xy 332.52008 -266.188792) (xy 332.484587 -266.222884) (xy 332.444084 -266.25084)
			(xy 332.399622 -266.271938) (xy 332.352351 -266.28563) (xy 332.303496 -266.291562) (xy 332.254321 -266.289581)
			(xy 332.206102 -266.279737) (xy 332.160086 -266.262285) (xy 332.117465 -266.237678) (xy 332.079344 -266.206553)
			(xy 332.046709 -266.169716) (xy 332.020406 -266.12812) (xy 332.001115 -266.082844) (xy 331.989338 -266.03506)
			(xy 331.985378 -265.986006) (xy 331.656436 -265.986006) (xy 331.655941 -266.010613) (xy 331.648046 -266.05919)
			(xy 331.632462 -266.105871) (xy 331.609591 -266.149448) (xy 331.580026 -266.188792) (xy 331.544533 -266.222884)
			(xy 331.50403 -266.25084) (xy 331.459568 -266.271938) (xy 331.412297 -266.28563) (xy 331.363442 -266.291562)
			(xy 331.314267 -266.289581) (xy 331.266048 -266.279737) (xy 331.220032 -266.262285) (xy 331.177411 -266.237678)
			(xy 331.13929 -266.206553) (xy 331.106655 -266.169716) (xy 331.080352 -266.12812) (xy 331.061061 -266.082844)
			(xy 331.049284 -266.03506) (xy 331.045324 -265.986006) (xy 330.726796 -265.986006) (xy 330.726284 -266.011452)
			(xy 330.71812 -266.061686) (xy 330.702004 -266.10996) (xy 330.678353 -266.155023) (xy 330.64778 -266.195709)
			(xy 330.611076 -266.230964) (xy 330.569192 -266.259874) (xy 330.523213 -266.281691) (xy 330.474329 -266.295851)
			(xy 330.423808 -266.301985) (xy 330.372956 -266.299936) (xy 330.323092 -266.289756) (xy 330.275506 -266.271709)
			(xy 330.231432 -266.246263) (xy 330.19201 -266.214076) (xy 330.158262 -266.175982) (xy 330.131061 -266.132968)
			(xy 330.111113 -266.086148) (xy 330.098934 -266.036734) (xy 330.094839 -265.986006) (xy 329.776328 -265.986006)
			(xy 329.775833 -266.010613) (xy 329.767938 -266.05919) (xy 329.752354 -266.105871) (xy 329.729483 -266.149448)
			(xy 329.699918 -266.188792) (xy 329.664425 -266.222884) (xy 329.623922 -266.25084) (xy 329.57946 -266.271938)
			(xy 329.532189 -266.28563) (xy 329.483334 -266.291562) (xy 329.434159 -266.289581) (xy 329.38594 -266.279737)
			(xy 329.339924 -266.262285) (xy 329.297303 -266.237678) (xy 329.259182 -266.206553) (xy 329.226547 -266.169716)
			(xy 329.200244 -266.12812) (xy 329.180953 -266.082844) (xy 329.169176 -266.03506) (xy 329.165216 -265.986006)
			(xy 326.95642 -265.986006) (xy 326.955925 -266.010613) (xy 326.94803 -266.05919) (xy 326.932446 -266.105871)
			(xy 326.909575 -266.149448) (xy 326.88001 -266.188792) (xy 326.844517 -266.222884) (xy 326.804014 -266.25084)
			(xy 326.759552 -266.271938) (xy 326.712281 -266.28563) (xy 326.663426 -266.291562) (xy 326.614251 -266.289581)
			(xy 326.566032 -266.279737) (xy 326.520016 -266.262285) (xy 326.477395 -266.237678) (xy 326.439274 -266.206553)
			(xy 326.406639 -266.169716) (xy 326.380336 -266.12812) (xy 326.361045 -266.082844) (xy 326.349268 -266.03506)
			(xy 326.345308 -265.986006) (xy 310.45912 -265.986006) (xy 310.45912 -266.530074) (xy 324.74714 -266.530074)
			(xy 324.7511 -266.48102) (xy 324.762877 -266.433236) (xy 324.782168 -266.38796) (xy 324.808471 -266.346364)
			(xy 324.841106 -266.309527) (xy 324.879227 -266.278402) (xy 324.921848 -266.253795) (xy 324.967864 -266.236343)
			(xy 325.016083 -266.226499) (xy 325.065258 -266.224518) (xy 325.114113 -266.23045) (xy 325.161384 -266.244142)
			(xy 325.205846 -266.26524) (xy 325.246349 -266.293196) (xy 325.281842 -266.327288) (xy 325.311407 -266.366632)
			(xy 325.334278 -266.410209) (xy 325.349862 -266.45689) (xy 325.357757 -266.505467) (xy 325.358252 -266.530074)
			(xy 325.357757 -266.554681) (xy 325.349862 -266.603258) (xy 325.334278 -266.649939) (xy 325.311407 -266.693516)
			(xy 325.281842 -266.73286) (xy 325.246349 -266.766952) (xy 325.205846 -266.794908) (xy 325.203519 -266.796012)
			(xy 327.755262 -266.796012) (xy 327.759222 -266.746958) (xy 327.770999 -266.699174) (xy 327.79029 -266.653898)
			(xy 327.816593 -266.612302) (xy 327.849228 -266.575465) (xy 327.887349 -266.54434) (xy 327.92997 -266.519733)
			(xy 327.975986 -266.502281) (xy 328.024205 -266.492437) (xy 328.07338 -266.490456) (xy 328.122235 -266.496388)
			(xy 328.169506 -266.51008) (xy 328.213968 -266.531178) (xy 328.254471 -266.559134) (xy 328.289964 -266.593226)
			(xy 328.319529 -266.63257) (xy 328.3424 -266.676147) (xy 328.357984 -266.722828) (xy 328.365879 -266.771405)
			(xy 328.366374 -266.796012) (xy 328.684885 -266.796012) (xy 328.68898 -266.745284) (xy 328.701159 -266.69587)
			(xy 328.721107 -266.64905) (xy 328.748308 -266.606036) (xy 328.782056 -266.567942) (xy 328.821478 -266.535755)
			(xy 328.865552 -266.510309) (xy 328.913138 -266.492262) (xy 328.963002 -266.482082) (xy 329.013854 -266.480033)
			(xy 329.064375 -266.486167) (xy 329.113259 -266.500327) (xy 329.159238 -266.522144) (xy 329.201122 -266.551054)
			(xy 329.237826 -266.586309) (xy 329.268399 -266.626995) (xy 329.29205 -266.672058) (xy 329.308166 -266.720332)
			(xy 329.31633 -266.770566) (xy 329.316842 -266.796012) (xy 329.63537 -266.796012) (xy 329.63933 -266.746958)
			(xy 329.651107 -266.699174) (xy 329.670398 -266.653898) (xy 329.696701 -266.612302) (xy 329.729336 -266.575465)
			(xy 329.767457 -266.54434) (xy 329.810078 -266.519733) (xy 329.856094 -266.502281) (xy 329.904313 -266.492437)
			(xy 329.953488 -266.490456) (xy 330.002343 -266.496388) (xy 330.049614 -266.51008) (xy 330.094076 -266.531178)
			(xy 330.134579 -266.559134) (xy 330.170072 -266.593226) (xy 330.199637 -266.63257) (xy 330.222508 -266.676147)
			(xy 330.238092 -266.722828) (xy 330.245987 -266.771405) (xy 330.246482 -266.796012) (xy 330.564739 -266.796012)
			(xy 330.568834 -266.745284) (xy 330.581013 -266.69587) (xy 330.600961 -266.64905) (xy 330.628162 -266.606036)
			(xy 330.66191 -266.567942) (xy 330.701332 -266.535755) (xy 330.745406 -266.510309) (xy 330.792992 -266.492262)
			(xy 330.842856 -266.482082) (xy 330.893708 -266.480033) (xy 330.944229 -266.486167) (xy 330.993113 -266.500327)
			(xy 331.039092 -266.522144) (xy 331.080976 -266.551054) (xy 331.11768 -266.586309) (xy 331.148253 -266.626995)
			(xy 331.171904 -266.672058) (xy 331.18802 -266.720332) (xy 331.196184 -266.770566) (xy 331.196696 -266.796012)
			(xy 331.515224 -266.796012) (xy 331.519184 -266.746958) (xy 331.530961 -266.699174) (xy 331.550252 -266.653898)
			(xy 331.576555 -266.612302) (xy 331.60919 -266.575465) (xy 331.647311 -266.54434) (xy 331.689932 -266.519733)
			(xy 331.735948 -266.502281) (xy 331.784167 -266.492437) (xy 331.833342 -266.490456) (xy 331.882197 -266.496388)
			(xy 331.929468 -266.51008) (xy 331.97393 -266.531178) (xy 332.014433 -266.559134) (xy 332.049926 -266.593226)
			(xy 332.079491 -266.63257) (xy 332.102362 -266.676147) (xy 332.117946 -266.722828) (xy 332.125841 -266.771405)
			(xy 332.126336 -266.796012) (xy 332.444847 -266.796012) (xy 332.448942 -266.745284) (xy 332.461121 -266.69587)
			(xy 332.481069 -266.64905) (xy 332.50827 -266.606036) (xy 332.542018 -266.567942) (xy 332.58144 -266.535755)
			(xy 332.625514 -266.510309) (xy 332.6731 -266.492262) (xy 332.722964 -266.482082) (xy 332.773816 -266.480033)
			(xy 332.824337 -266.486167) (xy 332.873221 -266.500327) (xy 332.9192 -266.522144) (xy 332.961084 -266.551054)
			(xy 332.997788 -266.586309) (xy 333.028361 -266.626995) (xy 333.052012 -266.672058) (xy 333.068128 -266.720332)
			(xy 333.076292 -266.770566) (xy 333.076804 -266.796012) (xy 333.384901 -266.796012) (xy 333.388996 -266.745284)
			(xy 333.401175 -266.69587) (xy 333.421123 -266.64905) (xy 333.448324 -266.606036) (xy 333.482072 -266.567942)
			(xy 333.521494 -266.535755) (xy 333.565568 -266.510309) (xy 333.613154 -266.492262) (xy 333.663018 -266.482082)
			(xy 333.71387 -266.480033) (xy 333.764391 -266.486167) (xy 333.813275 -266.500327) (xy 333.859254 -266.522144)
			(xy 333.901138 -266.551054) (xy 333.937842 -266.586309) (xy 333.968415 -266.626995) (xy 333.992066 -266.672058)
			(xy 334.008182 -266.720332) (xy 334.016346 -266.770566) (xy 334.016858 -266.796012) (xy 334.335386 -266.796012)
			(xy 334.339346 -266.746958) (xy 334.351123 -266.699174) (xy 334.370414 -266.653898) (xy 334.396717 -266.612302)
			(xy 334.429352 -266.575465) (xy 334.467473 -266.54434) (xy 334.510094 -266.519733) (xy 334.55611 -266.502281)
			(xy 334.604329 -266.492437) (xy 334.653504 -266.490456) (xy 334.702359 -266.496388) (xy 334.74963 -266.51008)
			(xy 334.794092 -266.531178) (xy 334.834595 -266.559134) (xy 334.870088 -266.593226) (xy 334.899653 -266.63257)
			(xy 334.922524 -266.676147) (xy 334.938108 -266.722828) (xy 334.946003 -266.771405) (xy 334.946498 -266.796012)
			(xy 335.264755 -266.796012) (xy 335.26885 -266.745284) (xy 335.281029 -266.69587) (xy 335.300977 -266.64905)
			(xy 335.328178 -266.606036) (xy 335.361926 -266.567942) (xy 335.401348 -266.535755) (xy 335.445422 -266.510309)
			(xy 335.493008 -266.492262) (xy 335.542872 -266.482082) (xy 335.593724 -266.480033) (xy 335.644245 -266.486167)
			(xy 335.693129 -266.500327) (xy 335.739108 -266.522144) (xy 335.780992 -266.551054) (xy 335.817696 -266.586309)
			(xy 335.848269 -266.626995) (xy 335.87192 -266.672058) (xy 335.888036 -266.720332) (xy 335.8962 -266.770566)
			(xy 335.896712 -266.796012) (xy 336.21524 -266.796012) (xy 336.2192 -266.746958) (xy 336.230977 -266.699174)
			(xy 336.250268 -266.653898) (xy 336.276571 -266.612302) (xy 336.309206 -266.575465) (xy 336.347327 -266.54434)
			(xy 336.389948 -266.519733) (xy 336.435964 -266.502281) (xy 336.484183 -266.492437) (xy 336.533358 -266.490456)
			(xy 336.582213 -266.496388) (xy 336.629484 -266.51008) (xy 336.673946 -266.531178) (xy 336.714449 -266.559134)
			(xy 336.749942 -266.593226) (xy 336.779507 -266.63257) (xy 336.802378 -266.676147) (xy 336.817962 -266.722828)
			(xy 336.825857 -266.771405) (xy 336.826352 -266.796012) (xy 337.144863 -266.796012) (xy 337.148958 -266.745284)
			(xy 337.161137 -266.69587) (xy 337.181085 -266.64905) (xy 337.208286 -266.606036) (xy 337.242034 -266.567942)
			(xy 337.281456 -266.535755) (xy 337.32553 -266.510309) (xy 337.373116 -266.492262) (xy 337.42298 -266.482082)
			(xy 337.473832 -266.480033) (xy 337.524353 -266.486167) (xy 337.573237 -266.500327) (xy 337.619216 -266.522144)
			(xy 337.6611 -266.551054) (xy 337.697804 -266.586309) (xy 337.728377 -266.626995) (xy 337.752028 -266.672058)
			(xy 337.768144 -266.720332) (xy 337.776308 -266.770566) (xy 337.77682 -266.796012) (xy 338.095348 -266.796012)
			(xy 338.099308 -266.746958) (xy 338.111085 -266.699174) (xy 338.130376 -266.653898) (xy 338.156679 -266.612302)
			(xy 338.189314 -266.575465) (xy 338.227435 -266.54434) (xy 338.270056 -266.519733) (xy 338.316072 -266.502281)
			(xy 338.364291 -266.492437) (xy 338.413466 -266.490456) (xy 338.462321 -266.496388) (xy 338.509592 -266.51008)
			(xy 338.554054 -266.531178) (xy 338.594557 -266.559134) (xy 338.63005 -266.593226) (xy 338.659615 -266.63257)
			(xy 338.682486 -266.676147) (xy 338.69807 -266.722828) (xy 338.705965 -266.771405) (xy 338.70646 -266.796012)
			(xy 339.024971 -266.796012) (xy 339.029066 -266.745284) (xy 339.041245 -266.69587) (xy 339.061193 -266.64905)
			(xy 339.088394 -266.606036) (xy 339.122142 -266.567942) (xy 339.161564 -266.535755) (xy 339.205638 -266.510309)
			(xy 339.253224 -266.492262) (xy 339.303088 -266.482082) (xy 339.35394 -266.480033) (xy 339.404461 -266.486167)
			(xy 339.453345 -266.500327) (xy 339.499324 -266.522144) (xy 339.541208 -266.551054) (xy 339.577912 -266.586309)
			(xy 339.608485 -266.626995) (xy 339.632136 -266.672058) (xy 339.648252 -266.720332) (xy 339.656416 -266.770566)
			(xy 339.656928 -266.796012) (xy 339.964771 -266.796012) (xy 339.968866 -266.745284) (xy 339.981045 -266.69587)
			(xy 340.000993 -266.64905) (xy 340.028194 -266.606036) (xy 340.061942 -266.567942) (xy 340.101364 -266.535755)
			(xy 340.145438 -266.510309) (xy 340.193024 -266.492262) (xy 340.242888 -266.482082) (xy 340.29374 -266.480033)
			(xy 340.344261 -266.486167) (xy 340.393145 -266.500327) (xy 340.439124 -266.522144) (xy 340.481008 -266.551054)
			(xy 340.517712 -266.586309) (xy 340.548285 -266.626995) (xy 340.571936 -266.672058) (xy 340.588052 -266.720332)
			(xy 340.596216 -266.770566) (xy 340.596728 -266.796012) (xy 340.915256 -266.796012) (xy 340.919216 -266.746958)
			(xy 340.930993 -266.699174) (xy 340.950284 -266.653898) (xy 340.976587 -266.612302) (xy 341.009222 -266.575465)
			(xy 341.047343 -266.54434) (xy 341.089964 -266.519733) (xy 341.13598 -266.502281) (xy 341.184199 -266.492437)
			(xy 341.233374 -266.490456) (xy 341.282229 -266.496388) (xy 341.3295 -266.51008) (xy 341.373962 -266.531178)
			(xy 341.414465 -266.559134) (xy 341.449958 -266.593226) (xy 341.479523 -266.63257) (xy 341.502394 -266.676147)
			(xy 341.517978 -266.722828) (xy 341.525873 -266.771405) (xy 341.526368 -266.796012) (xy 341.844879 -266.796012)
			(xy 341.848974 -266.745284) (xy 341.861153 -266.69587) (xy 341.881101 -266.64905) (xy 341.908302 -266.606036)
			(xy 341.94205 -266.567942) (xy 341.981472 -266.535755) (xy 342.025546 -266.510309) (xy 342.073132 -266.492262)
			(xy 342.122996 -266.482082) (xy 342.173848 -266.480033) (xy 342.224369 -266.486167) (xy 342.273253 -266.500327)
			(xy 342.319232 -266.522144) (xy 342.361116 -266.551054) (xy 342.39782 -266.586309) (xy 342.428393 -266.626995)
			(xy 342.452044 -266.672058) (xy 342.46816 -266.720332) (xy 342.476324 -266.770566) (xy 342.476836 -266.796012)
			(xy 342.795364 -266.796012) (xy 342.799324 -266.746958) (xy 342.811101 -266.699174) (xy 342.830392 -266.653898)
			(xy 342.856695 -266.612302) (xy 342.88933 -266.575465) (xy 342.927451 -266.54434) (xy 342.970072 -266.519733)
			(xy 343.016088 -266.502281) (xy 343.064307 -266.492437) (xy 343.113482 -266.490456) (xy 343.162337 -266.496388)
			(xy 343.209608 -266.51008) (xy 343.25407 -266.531178) (xy 343.294573 -266.559134) (xy 343.330066 -266.593226)
			(xy 343.359631 -266.63257) (xy 343.382502 -266.676147) (xy 343.398086 -266.722828) (xy 343.405981 -266.771405)
			(xy 343.406476 -266.796012) (xy 343.724987 -266.796012) (xy 343.729082 -266.745284) (xy 343.741261 -266.69587)
			(xy 343.761209 -266.64905) (xy 343.78841 -266.606036) (xy 343.822158 -266.567942) (xy 343.86158 -266.535755)
			(xy 343.905654 -266.510309) (xy 343.95324 -266.492262) (xy 344.003104 -266.482082) (xy 344.053956 -266.480033)
			(xy 344.104477 -266.486167) (xy 344.153361 -266.500327) (xy 344.19934 -266.522144) (xy 344.241224 -266.551054)
			(xy 344.277928 -266.586309) (xy 344.308501 -266.626995) (xy 344.332152 -266.672058) (xy 344.348268 -266.720332)
			(xy 344.356432 -266.770566) (xy 344.356944 -266.796012) (xy 344.356432 -266.821458) (xy 344.348268 -266.871692)
			(xy 344.332152 -266.919966) (xy 344.308501 -266.965029) (xy 344.277928 -267.005715) (xy 344.241224 -267.04097)
			(xy 344.19934 -267.06988) (xy 344.153361 -267.091697) (xy 344.104477 -267.105857) (xy 344.053956 -267.111991)
			(xy 344.003104 -267.109942) (xy 343.95324 -267.099762) (xy 343.905654 -267.081715) (xy 343.86158 -267.056269)
			(xy 343.822158 -267.024082) (xy 343.78841 -266.985988) (xy 343.761209 -266.942974) (xy 343.741261 -266.896154)
			(xy 343.729082 -266.84674) (xy 343.724987 -266.796012) (xy 343.406476 -266.796012) (xy 343.405981 -266.820619)
			(xy 343.398086 -266.869196) (xy 343.382502 -266.915877) (xy 343.359631 -266.959454) (xy 343.330066 -266.998798)
			(xy 343.294573 -267.03289) (xy 343.25407 -267.060846) (xy 343.209608 -267.081944) (xy 343.162337 -267.095636)
			(xy 343.113482 -267.101568) (xy 343.064307 -267.099587) (xy 343.016088 -267.089743) (xy 342.970072 -267.072291)
			(xy 342.927451 -267.047684) (xy 342.88933 -267.016559) (xy 342.856695 -266.979722) (xy 342.830392 -266.938126)
			(xy 342.811101 -266.89285) (xy 342.799324 -266.845066) (xy 342.795364 -266.796012) (xy 342.476836 -266.796012)
			(xy 342.476324 -266.821458) (xy 342.46816 -266.871692) (xy 342.452044 -266.919966) (xy 342.428393 -266.965029)
			(xy 342.39782 -267.005715) (xy 342.361116 -267.04097) (xy 342.319232 -267.06988) (xy 342.273253 -267.091697)
			(xy 342.224369 -267.105857) (xy 342.173848 -267.111991) (xy 342.122996 -267.109942) (xy 342.073132 -267.099762)
			(xy 342.025546 -267.081715) (xy 341.981472 -267.056269) (xy 341.94205 -267.024082) (xy 341.908302 -266.985988)
			(xy 341.881101 -266.942974) (xy 341.861153 -266.896154) (xy 341.848974 -266.84674) (xy 341.844879 -266.796012)
			(xy 341.526368 -266.796012) (xy 341.525873 -266.820619) (xy 341.517978 -266.869196) (xy 341.502394 -266.915877)
			(xy 341.479523 -266.959454) (xy 341.449958 -266.998798) (xy 341.414465 -267.03289) (xy 341.373962 -267.060846)
			(xy 341.3295 -267.081944) (xy 341.282229 -267.095636) (xy 341.233374 -267.101568) (xy 341.184199 -267.099587)
			(xy 341.13598 -267.089743) (xy 341.089964 -267.072291) (xy 341.047343 -267.047684) (xy 341.009222 -267.016559)
			(xy 340.976587 -266.979722) (xy 340.950284 -266.938126) (xy 340.930993 -266.89285) (xy 340.919216 -266.845066)
			(xy 340.915256 -266.796012) (xy 340.596728 -266.796012) (xy 340.596216 -266.821458) (xy 340.588052 -266.871692)
			(xy 340.571936 -266.919966) (xy 340.548285 -266.965029) (xy 340.517712 -267.005715) (xy 340.481008 -267.04097)
			(xy 340.439124 -267.06988) (xy 340.393145 -267.091697) (xy 340.344261 -267.105857) (xy 340.29374 -267.111991)
			(xy 340.242888 -267.109942) (xy 340.193024 -267.099762) (xy 340.145438 -267.081715) (xy 340.101364 -267.056269)
			(xy 340.061942 -267.024082) (xy 340.028194 -266.985988) (xy 340.000993 -266.942974) (xy 339.981045 -266.896154)
			(xy 339.968866 -266.84674) (xy 339.964771 -266.796012) (xy 339.656928 -266.796012) (xy 339.656416 -266.821458)
			(xy 339.648252 -266.871692) (xy 339.632136 -266.919966) (xy 339.608485 -266.965029) (xy 339.577912 -267.005715)
			(xy 339.541208 -267.04097) (xy 339.499324 -267.06988) (xy 339.453345 -267.091697) (xy 339.404461 -267.105857)
			(xy 339.35394 -267.111991) (xy 339.303088 -267.109942) (xy 339.253224 -267.099762) (xy 339.205638 -267.081715)
			(xy 339.161564 -267.056269) (xy 339.122142 -267.024082) (xy 339.088394 -266.985988) (xy 339.061193 -266.942974)
			(xy 339.041245 -266.896154) (xy 339.029066 -266.84674) (xy 339.024971 -266.796012) (xy 338.70646 -266.796012)
			(xy 338.705965 -266.820619) (xy 338.69807 -266.869196) (xy 338.682486 -266.915877) (xy 338.659615 -266.959454)
			(xy 338.63005 -266.998798) (xy 338.594557 -267.03289) (xy 338.554054 -267.060846) (xy 338.509592 -267.081944)
			(xy 338.462321 -267.095636) (xy 338.413466 -267.101568) (xy 338.364291 -267.099587) (xy 338.316072 -267.089743)
			(xy 338.270056 -267.072291) (xy 338.227435 -267.047684) (xy 338.189314 -267.016559) (xy 338.156679 -266.979722)
			(xy 338.130376 -266.938126) (xy 338.111085 -266.89285) (xy 338.099308 -266.845066) (xy 338.095348 -266.796012)
			(xy 337.77682 -266.796012) (xy 337.776308 -266.821458) (xy 337.768144 -266.871692) (xy 337.752028 -266.919966)
			(xy 337.728377 -266.965029) (xy 337.697804 -267.005715) (xy 337.6611 -267.04097) (xy 337.619216 -267.06988)
			(xy 337.573237 -267.091697) (xy 337.524353 -267.105857) (xy 337.473832 -267.111991) (xy 337.42298 -267.109942)
			(xy 337.373116 -267.099762) (xy 337.32553 -267.081715) (xy 337.281456 -267.056269) (xy 337.242034 -267.024082)
			(xy 337.208286 -266.985988) (xy 337.181085 -266.942974) (xy 337.161137 -266.896154) (xy 337.148958 -266.84674)
			(xy 337.144863 -266.796012) (xy 336.826352 -266.796012) (xy 336.825857 -266.820619) (xy 336.817962 -266.869196)
			(xy 336.802378 -266.915877) (xy 336.779507 -266.959454) (xy 336.749942 -266.998798) (xy 336.714449 -267.03289)
			(xy 336.673946 -267.060846) (xy 336.629484 -267.081944) (xy 336.582213 -267.095636) (xy 336.533358 -267.101568)
			(xy 336.484183 -267.099587) (xy 336.435964 -267.089743) (xy 336.389948 -267.072291) (xy 336.347327 -267.047684)
			(xy 336.309206 -267.016559) (xy 336.276571 -266.979722) (xy 336.250268 -266.938126) (xy 336.230977 -266.89285)
			(xy 336.2192 -266.845066) (xy 336.21524 -266.796012) (xy 335.896712 -266.796012) (xy 335.8962 -266.821458)
			(xy 335.888036 -266.871692) (xy 335.87192 -266.919966) (xy 335.848269 -266.965029) (xy 335.817696 -267.005715)
			(xy 335.780992 -267.04097) (xy 335.739108 -267.06988) (xy 335.693129 -267.091697) (xy 335.644245 -267.105857)
			(xy 335.593724 -267.111991) (xy 335.542872 -267.109942) (xy 335.493008 -267.099762) (xy 335.445422 -267.081715)
			(xy 335.401348 -267.056269) (xy 335.361926 -267.024082) (xy 335.328178 -266.985988) (xy 335.300977 -266.942974)
			(xy 335.281029 -266.896154) (xy 335.26885 -266.84674) (xy 335.264755 -266.796012) (xy 334.946498 -266.796012)
			(xy 334.946003 -266.820619) (xy 334.938108 -266.869196) (xy 334.922524 -266.915877) (xy 334.899653 -266.959454)
			(xy 334.870088 -266.998798) (xy 334.834595 -267.03289) (xy 334.794092 -267.060846) (xy 334.74963 -267.081944)
			(xy 334.702359 -267.095636) (xy 334.653504 -267.101568) (xy 334.604329 -267.099587) (xy 334.55611 -267.089743)
			(xy 334.510094 -267.072291) (xy 334.467473 -267.047684) (xy 334.429352 -267.016559) (xy 334.396717 -266.979722)
			(xy 334.370414 -266.938126) (xy 334.351123 -266.89285) (xy 334.339346 -266.845066) (xy 334.335386 -266.796012)
			(xy 334.016858 -266.796012) (xy 334.016346 -266.821458) (xy 334.008182 -266.871692) (xy 333.992066 -266.919966)
			(xy 333.968415 -266.965029) (xy 333.937842 -267.005715) (xy 333.901138 -267.04097) (xy 333.859254 -267.06988)
			(xy 333.813275 -267.091697) (xy 333.764391 -267.105857) (xy 333.71387 -267.111991) (xy 333.663018 -267.109942)
			(xy 333.613154 -267.099762) (xy 333.565568 -267.081715) (xy 333.521494 -267.056269) (xy 333.482072 -267.024082)
			(xy 333.448324 -266.985988) (xy 333.421123 -266.942974) (xy 333.401175 -266.896154) (xy 333.388996 -266.84674)
			(xy 333.384901 -266.796012) (xy 333.076804 -266.796012) (xy 333.076292 -266.821458) (xy 333.068128 -266.871692)
			(xy 333.052012 -266.919966) (xy 333.028361 -266.965029) (xy 332.997788 -267.005715) (xy 332.961084 -267.04097)
			(xy 332.9192 -267.06988) (xy 332.873221 -267.091697) (xy 332.824337 -267.105857) (xy 332.773816 -267.111991)
			(xy 332.722964 -267.109942) (xy 332.6731 -267.099762) (xy 332.625514 -267.081715) (xy 332.58144 -267.056269)
			(xy 332.542018 -267.024082) (xy 332.50827 -266.985988) (xy 332.481069 -266.942974) (xy 332.461121 -266.896154)
			(xy 332.448942 -266.84674) (xy 332.444847 -266.796012) (xy 332.126336 -266.796012) (xy 332.125841 -266.820619)
			(xy 332.117946 -266.869196) (xy 332.102362 -266.915877) (xy 332.079491 -266.959454) (xy 332.049926 -266.998798)
			(xy 332.014433 -267.03289) (xy 331.97393 -267.060846) (xy 331.929468 -267.081944) (xy 331.882197 -267.095636)
			(xy 331.833342 -267.101568) (xy 331.784167 -267.099587) (xy 331.735948 -267.089743) (xy 331.689932 -267.072291)
			(xy 331.647311 -267.047684) (xy 331.60919 -267.016559) (xy 331.576555 -266.979722) (xy 331.550252 -266.938126)
			(xy 331.530961 -266.89285) (xy 331.519184 -266.845066) (xy 331.515224 -266.796012) (xy 331.196696 -266.796012)
			(xy 331.196184 -266.821458) (xy 331.18802 -266.871692) (xy 331.171904 -266.919966) (xy 331.148253 -266.965029)
			(xy 331.11768 -267.005715) (xy 331.080976 -267.04097) (xy 331.039092 -267.06988) (xy 330.993113 -267.091697)
			(xy 330.944229 -267.105857) (xy 330.893708 -267.111991) (xy 330.842856 -267.109942) (xy 330.792992 -267.099762)
			(xy 330.745406 -267.081715) (xy 330.701332 -267.056269) (xy 330.66191 -267.024082) (xy 330.628162 -266.985988)
			(xy 330.600961 -266.942974) (xy 330.581013 -266.896154) (xy 330.568834 -266.84674) (xy 330.564739 -266.796012)
			(xy 330.246482 -266.796012) (xy 330.245987 -266.820619) (xy 330.238092 -266.869196) (xy 330.222508 -266.915877)
			(xy 330.199637 -266.959454) (xy 330.170072 -266.998798) (xy 330.134579 -267.03289) (xy 330.094076 -267.060846)
			(xy 330.049614 -267.081944) (xy 330.002343 -267.095636) (xy 329.953488 -267.101568) (xy 329.904313 -267.099587)
			(xy 329.856094 -267.089743) (xy 329.810078 -267.072291) (xy 329.767457 -267.047684) (xy 329.729336 -267.016559)
			(xy 329.696701 -266.979722) (xy 329.670398 -266.938126) (xy 329.651107 -266.89285) (xy 329.63933 -266.845066)
			(xy 329.63537 -266.796012) (xy 329.316842 -266.796012) (xy 329.31633 -266.821458) (xy 329.308166 -266.871692)
			(xy 329.29205 -266.919966) (xy 329.268399 -266.965029) (xy 329.237826 -267.005715) (xy 329.201122 -267.04097)
			(xy 329.159238 -267.06988) (xy 329.113259 -267.091697) (xy 329.064375 -267.105857) (xy 329.013854 -267.111991)
			(xy 328.963002 -267.109942) (xy 328.913138 -267.099762) (xy 328.865552 -267.081715) (xy 328.821478 -267.056269)
			(xy 328.782056 -267.024082) (xy 328.748308 -266.985988) (xy 328.721107 -266.942974) (xy 328.701159 -266.896154)
			(xy 328.68898 -266.84674) (xy 328.684885 -266.796012) (xy 328.366374 -266.796012) (xy 328.365879 -266.820619)
			(xy 328.357984 -266.869196) (xy 328.3424 -266.915877) (xy 328.319529 -266.959454) (xy 328.289964 -266.998798)
			(xy 328.254471 -267.03289) (xy 328.213968 -267.060846) (xy 328.169506 -267.081944) (xy 328.122235 -267.095636)
			(xy 328.07338 -267.101568) (xy 328.024205 -267.099587) (xy 327.975986 -267.089743) (xy 327.92997 -267.072291)
			(xy 327.887349 -267.047684) (xy 327.849228 -267.016559) (xy 327.816593 -266.979722) (xy 327.79029 -266.938126)
			(xy 327.770999 -266.89285) (xy 327.759222 -266.845066) (xy 327.755262 -266.796012) (xy 325.203519 -266.796012)
			(xy 325.161384 -266.816006) (xy 325.114113 -266.829698) (xy 325.065258 -266.83563) (xy 325.016083 -266.833649)
			(xy 324.967864 -266.823805) (xy 324.921848 -266.806353) (xy 324.879227 -266.781746) (xy 324.841106 -266.750621)
			(xy 324.808471 -266.713784) (xy 324.782168 -266.672188) (xy 324.762877 -266.626912) (xy 324.7511 -266.579128)
			(xy 324.74714 -266.530074) (xy 310.45912 -266.530074) (xy 310.45912 -267.606018) (xy 326.345308 -267.606018)
			(xy 326.349268 -267.556964) (xy 326.361045 -267.50918) (xy 326.380336 -267.463904) (xy 326.406639 -267.422308)
			(xy 326.439274 -267.385471) (xy 326.477395 -267.354346) (xy 326.520016 -267.329739) (xy 326.566032 -267.312287)
			(xy 326.614251 -267.302443) (xy 326.663426 -267.300462) (xy 326.712281 -267.306394) (xy 326.759552 -267.320086)
			(xy 326.804014 -267.341184) (xy 326.844517 -267.36914) (xy 326.88001 -267.403232) (xy 326.909575 -267.442576)
			(xy 326.932446 -267.486153) (xy 326.94803 -267.532834) (xy 326.955925 -267.581411) (xy 326.95642 -267.606018)
			(xy 328.225416 -267.606018) (xy 328.229376 -267.556964) (xy 328.241153 -267.50918) (xy 328.260444 -267.463904)
			(xy 328.286747 -267.422308) (xy 328.319382 -267.385471) (xy 328.357503 -267.354346) (xy 328.400124 -267.329739)
			(xy 328.44614 -267.312287) (xy 328.494359 -267.302443) (xy 328.543534 -267.300462) (xy 328.592389 -267.306394)
			(xy 328.63966 -267.320086) (xy 328.684122 -267.341184) (xy 328.724625 -267.36914) (xy 328.760118 -267.403232)
			(xy 328.789683 -267.442576) (xy 328.812554 -267.486153) (xy 328.828138 -267.532834) (xy 328.836033 -267.581411)
			(xy 328.836528 -267.606018) (xy 329.154785 -267.606018) (xy 329.15888 -267.55529) (xy 329.171059 -267.505876)
			(xy 329.191007 -267.459056) (xy 329.218208 -267.416042) (xy 329.251956 -267.377948) (xy 329.291378 -267.345761)
			(xy 329.335452 -267.320315) (xy 329.383038 -267.302268) (xy 329.432902 -267.292088) (xy 329.483754 -267.290039)
			(xy 329.534275 -267.296173) (xy 329.583159 -267.310333) (xy 329.629138 -267.33215) (xy 329.671022 -267.36106)
			(xy 329.707726 -267.396315) (xy 329.738299 -267.437001) (xy 329.76195 -267.482064) (xy 329.778066 -267.530338)
			(xy 329.78623 -267.580572) (xy 329.786742 -267.606018) (xy 330.10527 -267.606018) (xy 330.10923 -267.556964)
			(xy 330.121007 -267.50918) (xy 330.140298 -267.463904) (xy 330.166601 -267.422308) (xy 330.199236 -267.385471)
			(xy 330.237357 -267.354346) (xy 330.279978 -267.329739) (xy 330.325994 -267.312287) (xy 330.374213 -267.302443)
			(xy 330.423388 -267.300462) (xy 330.472243 -267.306394) (xy 330.519514 -267.320086) (xy 330.563976 -267.341184)
			(xy 330.604479 -267.36914) (xy 330.639972 -267.403232) (xy 330.669537 -267.442576) (xy 330.692408 -267.486153)
			(xy 330.707992 -267.532834) (xy 330.715887 -267.581411) (xy 330.716382 -267.606018) (xy 331.045324 -267.606018)
			(xy 331.049284 -267.556964) (xy 331.061061 -267.50918) (xy 331.080352 -267.463904) (xy 331.106655 -267.422308)
			(xy 331.13929 -267.385471) (xy 331.177411 -267.354346) (xy 331.220032 -267.329739) (xy 331.266048 -267.312287)
			(xy 331.314267 -267.302443) (xy 331.363442 -267.300462) (xy 331.412297 -267.306394) (xy 331.459568 -267.320086)
			(xy 331.50403 -267.341184) (xy 331.544533 -267.36914) (xy 331.580026 -267.403232) (xy 331.609591 -267.442576)
			(xy 331.632462 -267.486153) (xy 331.648046 -267.532834) (xy 331.655941 -267.581411) (xy 331.656436 -267.606018)
			(xy 331.974947 -267.606018) (xy 331.979042 -267.55529) (xy 331.991221 -267.505876) (xy 332.011169 -267.459056)
			(xy 332.03837 -267.416042) (xy 332.072118 -267.377948) (xy 332.11154 -267.345761) (xy 332.155614 -267.320315)
			(xy 332.2032 -267.302268) (xy 332.253064 -267.292088) (xy 332.303916 -267.290039) (xy 332.354437 -267.296173)
			(xy 332.403321 -267.310333) (xy 332.4493 -267.33215) (xy 332.491184 -267.36106) (xy 332.527888 -267.396315)
			(xy 332.558461 -267.437001) (xy 332.582112 -267.482064) (xy 332.598228 -267.530338) (xy 332.606392 -267.580572)
			(xy 332.606904 -267.606018) (xy 332.925178 -267.606018) (xy 332.929138 -267.556964) (xy 332.940915 -267.50918)
			(xy 332.960206 -267.463904) (xy 332.986509 -267.422308) (xy 333.019144 -267.385471) (xy 333.057265 -267.354346)
			(xy 333.099886 -267.329739) (xy 333.145902 -267.312287) (xy 333.194121 -267.302443) (xy 333.243296 -267.300462)
			(xy 333.292151 -267.306394) (xy 333.339422 -267.320086) (xy 333.383884 -267.341184) (xy 333.424387 -267.36914)
			(xy 333.45988 -267.403232) (xy 333.489445 -267.442576) (xy 333.512316 -267.486153) (xy 333.5279 -267.532834)
			(xy 333.535795 -267.581411) (xy 333.53629 -267.606018) (xy 333.865232 -267.606018) (xy 333.869192 -267.556964)
			(xy 333.880969 -267.50918) (xy 333.90026 -267.463904) (xy 333.926563 -267.422308) (xy 333.959198 -267.385471)
			(xy 333.997319 -267.354346) (xy 334.03994 -267.329739) (xy 334.085956 -267.312287) (xy 334.134175 -267.302443)
			(xy 334.18335 -267.300462) (xy 334.232205 -267.306394) (xy 334.279476 -267.320086) (xy 334.323938 -267.341184)
			(xy 334.364441 -267.36914) (xy 334.399934 -267.403232) (xy 334.429499 -267.442576) (xy 334.45237 -267.486153)
			(xy 334.467954 -267.532834) (xy 334.475849 -267.581411) (xy 334.476344 -267.606018) (xy 334.805286 -267.606018)
			(xy 334.809246 -267.556964) (xy 334.821023 -267.50918) (xy 334.840314 -267.463904) (xy 334.866617 -267.422308)
			(xy 334.899252 -267.385471) (xy 334.937373 -267.354346) (xy 334.979994 -267.329739) (xy 335.02601 -267.312287)
			(xy 335.074229 -267.302443) (xy 335.123404 -267.300462) (xy 335.172259 -267.306394) (xy 335.21953 -267.320086)
			(xy 335.263992 -267.341184) (xy 335.304495 -267.36914) (xy 335.339988 -267.403232) (xy 335.369553 -267.442576)
			(xy 335.392424 -267.486153) (xy 335.408008 -267.532834) (xy 335.415903 -267.581411) (xy 335.416398 -267.606018)
			(xy 335.734909 -267.606018) (xy 335.739004 -267.55529) (xy 335.751183 -267.505876) (xy 335.771131 -267.459056)
			(xy 335.798332 -267.416042) (xy 335.83208 -267.377948) (xy 335.871502 -267.345761) (xy 335.915576 -267.320315)
			(xy 335.963162 -267.302268) (xy 336.013026 -267.292088) (xy 336.063878 -267.290039) (xy 336.114399 -267.296173)
			(xy 336.163283 -267.310333) (xy 336.209262 -267.33215) (xy 336.251146 -267.36106) (xy 336.28785 -267.396315)
			(xy 336.318423 -267.437001) (xy 336.342074 -267.482064) (xy 336.35819 -267.530338) (xy 336.366354 -267.580572)
			(xy 336.366866 -267.606018) (xy 336.685394 -267.606018) (xy 336.689354 -267.556964) (xy 336.701131 -267.50918)
			(xy 336.720422 -267.463904) (xy 336.746725 -267.422308) (xy 336.77936 -267.385471) (xy 336.817481 -267.354346)
			(xy 336.860102 -267.329739) (xy 336.906118 -267.312287) (xy 336.954337 -267.302443) (xy 337.003512 -267.300462)
			(xy 337.052367 -267.306394) (xy 337.099638 -267.320086) (xy 337.1441 -267.341184) (xy 337.184603 -267.36914)
			(xy 337.220096 -267.403232) (xy 337.249661 -267.442576) (xy 337.272532 -267.486153) (xy 337.288116 -267.532834)
			(xy 337.296011 -267.581411) (xy 337.296506 -267.606018) (xy 337.625194 -267.606018) (xy 337.629154 -267.556964)
			(xy 337.640931 -267.50918) (xy 337.660222 -267.463904) (xy 337.686525 -267.422308) (xy 337.71916 -267.385471)
			(xy 337.757281 -267.354346) (xy 337.799902 -267.329739) (xy 337.845918 -267.312287) (xy 337.894137 -267.302443)
			(xy 337.943312 -267.300462) (xy 337.992167 -267.306394) (xy 338.039438 -267.320086) (xy 338.0839 -267.341184)
			(xy 338.124403 -267.36914) (xy 338.159896 -267.403232) (xy 338.189461 -267.442576) (xy 338.212332 -267.486153)
			(xy 338.227916 -267.532834) (xy 338.235811 -267.581411) (xy 338.236306 -267.606018) (xy 338.554817 -267.606018)
			(xy 338.558912 -267.55529) (xy 338.571091 -267.505876) (xy 338.591039 -267.459056) (xy 338.61824 -267.416042)
			(xy 338.651988 -267.377948) (xy 338.69141 -267.345761) (xy 338.735484 -267.320315) (xy 338.78307 -267.302268)
			(xy 338.832934 -267.292088) (xy 338.883786 -267.290039) (xy 338.934307 -267.296173) (xy 338.983191 -267.310333)
			(xy 339.02917 -267.33215) (xy 339.071054 -267.36106) (xy 339.107758 -267.396315) (xy 339.138331 -267.437001)
			(xy 339.161982 -267.482064) (xy 339.178098 -267.530338) (xy 339.186262 -267.580572) (xy 339.186774 -267.606018)
			(xy 339.505302 -267.606018) (xy 339.509262 -267.556964) (xy 339.521039 -267.50918) (xy 339.54033 -267.463904)
			(xy 339.566633 -267.422308) (xy 339.599268 -267.385471) (xy 339.637389 -267.354346) (xy 339.68001 -267.329739)
			(xy 339.726026 -267.312287) (xy 339.774245 -267.302443) (xy 339.82342 -267.300462) (xy 339.872275 -267.306394)
			(xy 339.919546 -267.320086) (xy 339.964008 -267.341184) (xy 340.004511 -267.36914) (xy 340.040004 -267.403232)
			(xy 340.069569 -267.442576) (xy 340.09244 -267.486153) (xy 340.108024 -267.532834) (xy 340.115919 -267.581411)
			(xy 340.116414 -267.606018) (xy 340.445356 -267.606018) (xy 340.449316 -267.556964) (xy 340.461093 -267.50918)
			(xy 340.480384 -267.463904) (xy 340.506687 -267.422308) (xy 340.539322 -267.385471) (xy 340.577443 -267.354346)
			(xy 340.620064 -267.329739) (xy 340.66608 -267.312287) (xy 340.714299 -267.302443) (xy 340.763474 -267.300462)
			(xy 340.812329 -267.306394) (xy 340.8596 -267.320086) (xy 340.904062 -267.341184) (xy 340.944565 -267.36914)
			(xy 340.980058 -267.403232) (xy 341.009623 -267.442576) (xy 341.032494 -267.486153) (xy 341.048078 -267.532834)
			(xy 341.055973 -267.581411) (xy 341.056468 -267.606018) (xy 341.38541 -267.606018) (xy 341.38937 -267.556964)
			(xy 341.401147 -267.50918) (xy 341.420438 -267.463904) (xy 341.446741 -267.422308) (xy 341.479376 -267.385471)
			(xy 341.517497 -267.354346) (xy 341.560118 -267.329739) (xy 341.606134 -267.312287) (xy 341.654353 -267.302443)
			(xy 341.703528 -267.300462) (xy 341.752383 -267.306394) (xy 341.799654 -267.320086) (xy 341.844116 -267.341184)
			(xy 341.884619 -267.36914) (xy 341.920112 -267.403232) (xy 341.949677 -267.442576) (xy 341.972548 -267.486153)
			(xy 341.988132 -267.532834) (xy 341.996027 -267.581411) (xy 341.996522 -267.606018) (xy 342.314779 -267.606018)
			(xy 342.318874 -267.55529) (xy 342.331053 -267.505876) (xy 342.351001 -267.459056) (xy 342.378202 -267.416042)
			(xy 342.41195 -267.377948) (xy 342.451372 -267.345761) (xy 342.495446 -267.320315) (xy 342.543032 -267.302268)
			(xy 342.592896 -267.292088) (xy 342.643748 -267.290039) (xy 342.694269 -267.296173) (xy 342.743153 -267.310333)
			(xy 342.789132 -267.33215) (xy 342.831016 -267.36106) (xy 342.86772 -267.396315) (xy 342.898293 -267.437001)
			(xy 342.921944 -267.482064) (xy 342.93806 -267.530338) (xy 342.946224 -267.580572) (xy 342.946736 -267.606018)
			(xy 343.265264 -267.606018) (xy 343.269224 -267.556964) (xy 343.281001 -267.50918) (xy 343.300292 -267.463904)
			(xy 343.326595 -267.422308) (xy 343.35923 -267.385471) (xy 343.397351 -267.354346) (xy 343.439972 -267.329739)
			(xy 343.485988 -267.312287) (xy 343.534207 -267.302443) (xy 343.583382 -267.300462) (xy 343.632237 -267.306394)
			(xy 343.679508 -267.320086) (xy 343.72397 -267.341184) (xy 343.764473 -267.36914) (xy 343.799966 -267.403232)
			(xy 343.829531 -267.442576) (xy 343.852402 -267.486153) (xy 343.867986 -267.532834) (xy 343.875881 -267.581411)
			(xy 343.876376 -267.606018) (xy 344.205318 -267.606018) (xy 344.209278 -267.556964) (xy 344.221055 -267.50918)
			(xy 344.240346 -267.463904) (xy 344.266649 -267.422308) (xy 344.299284 -267.385471) (xy 344.337405 -267.354346)
			(xy 344.380026 -267.329739) (xy 344.426042 -267.312287) (xy 344.474261 -267.302443) (xy 344.523436 -267.300462)
			(xy 344.572291 -267.306394) (xy 344.619562 -267.320086) (xy 344.664024 -267.341184) (xy 344.704527 -267.36914)
			(xy 344.74002 -267.403232) (xy 344.769585 -267.442576) (xy 344.792456 -267.486153) (xy 344.80804 -267.532834)
			(xy 344.815935 -267.581411) (xy 344.81643 -267.606018) (xy 344.815935 -267.630625) (xy 344.80804 -267.679202)
			(xy 344.792456 -267.725883) (xy 344.769585 -267.76946) (xy 344.74002 -267.808804) (xy 344.704527 -267.842896)
			(xy 344.664024 -267.870852) (xy 344.619562 -267.89195) (xy 344.572291 -267.905642) (xy 344.523436 -267.911574)
			(xy 344.474261 -267.909593) (xy 344.426042 -267.899749) (xy 344.380026 -267.882297) (xy 344.337405 -267.85769)
			(xy 344.299284 -267.826565) (xy 344.266649 -267.789728) (xy 344.240346 -267.748132) (xy 344.221055 -267.702856)
			(xy 344.209278 -267.655072) (xy 344.205318 -267.606018) (xy 343.876376 -267.606018) (xy 343.875881 -267.630625)
			(xy 343.867986 -267.679202) (xy 343.852402 -267.725883) (xy 343.829531 -267.76946) (xy 343.799966 -267.808804)
			(xy 343.764473 -267.842896) (xy 343.72397 -267.870852) (xy 343.679508 -267.89195) (xy 343.632237 -267.905642)
			(xy 343.583382 -267.911574) (xy 343.534207 -267.909593) (xy 343.485988 -267.899749) (xy 343.439972 -267.882297)
			(xy 343.397351 -267.85769) (xy 343.35923 -267.826565) (xy 343.326595 -267.789728) (xy 343.300292 -267.748132)
			(xy 343.281001 -267.702856) (xy 343.269224 -267.655072) (xy 343.265264 -267.606018) (xy 342.946736 -267.606018)
			(xy 342.946224 -267.631464) (xy 342.93806 -267.681698) (xy 342.921944 -267.729972) (xy 342.898293 -267.775035)
			(xy 342.86772 -267.815721) (xy 342.831016 -267.850976) (xy 342.789132 -267.879886) (xy 342.743153 -267.901703)
			(xy 342.694269 -267.915863) (xy 342.643748 -267.921997) (xy 342.592896 -267.919948) (xy 342.543032 -267.909768)
			(xy 342.495446 -267.891721) (xy 342.451372 -267.866275) (xy 342.41195 -267.834088) (xy 342.378202 -267.795994)
			(xy 342.351001 -267.75298) (xy 342.331053 -267.70616) (xy 342.318874 -267.656746) (xy 342.314779 -267.606018)
			(xy 341.996522 -267.606018) (xy 341.996027 -267.630625) (xy 341.988132 -267.679202) (xy 341.972548 -267.725883)
			(xy 341.949677 -267.76946) (xy 341.920112 -267.808804) (xy 341.884619 -267.842896) (xy 341.844116 -267.870852)
			(xy 341.799654 -267.89195) (xy 341.752383 -267.905642) (xy 341.703528 -267.911574) (xy 341.654353 -267.909593)
			(xy 341.606134 -267.899749) (xy 341.560118 -267.882297) (xy 341.517497 -267.85769) (xy 341.479376 -267.826565)
			(xy 341.446741 -267.789728) (xy 341.420438 -267.748132) (xy 341.401147 -267.702856) (xy 341.38937 -267.655072)
			(xy 341.38541 -267.606018) (xy 341.056468 -267.606018) (xy 341.055973 -267.630625) (xy 341.048078 -267.679202)
			(xy 341.032494 -267.725883) (xy 341.009623 -267.76946) (xy 340.980058 -267.808804) (xy 340.944565 -267.842896)
			(xy 340.904062 -267.870852) (xy 340.8596 -267.89195) (xy 340.812329 -267.905642) (xy 340.763474 -267.911574)
			(xy 340.714299 -267.909593) (xy 340.66608 -267.899749) (xy 340.620064 -267.882297) (xy 340.577443 -267.85769)
			(xy 340.539322 -267.826565) (xy 340.506687 -267.789728) (xy 340.480384 -267.748132) (xy 340.461093 -267.702856)
			(xy 340.449316 -267.655072) (xy 340.445356 -267.606018) (xy 340.116414 -267.606018) (xy 340.115919 -267.630625)
			(xy 340.108024 -267.679202) (xy 340.09244 -267.725883) (xy 340.069569 -267.76946) (xy 340.040004 -267.808804)
			(xy 340.004511 -267.842896) (xy 339.964008 -267.870852) (xy 339.919546 -267.89195) (xy 339.872275 -267.905642)
			(xy 339.82342 -267.911574) (xy 339.774245 -267.909593) (xy 339.726026 -267.899749) (xy 339.68001 -267.882297)
			(xy 339.637389 -267.85769) (xy 339.599268 -267.826565) (xy 339.566633 -267.789728) (xy 339.54033 -267.748132)
			(xy 339.521039 -267.702856) (xy 339.509262 -267.655072) (xy 339.505302 -267.606018) (xy 339.186774 -267.606018)
			(xy 339.186262 -267.631464) (xy 339.178098 -267.681698) (xy 339.161982 -267.729972) (xy 339.138331 -267.775035)
			(xy 339.107758 -267.815721) (xy 339.071054 -267.850976) (xy 339.02917 -267.879886) (xy 338.983191 -267.901703)
			(xy 338.934307 -267.915863) (xy 338.883786 -267.921997) (xy 338.832934 -267.919948) (xy 338.78307 -267.909768)
			(xy 338.735484 -267.891721) (xy 338.69141 -267.866275) (xy 338.651988 -267.834088) (xy 338.61824 -267.795994)
			(xy 338.591039 -267.75298) (xy 338.571091 -267.70616) (xy 338.558912 -267.656746) (xy 338.554817 -267.606018)
			(xy 338.236306 -267.606018) (xy 338.235811 -267.630625) (xy 338.227916 -267.679202) (xy 338.212332 -267.725883)
			(xy 338.189461 -267.76946) (xy 338.159896 -267.808804) (xy 338.124403 -267.842896) (xy 338.0839 -267.870852)
			(xy 338.039438 -267.89195) (xy 337.992167 -267.905642) (xy 337.943312 -267.911574) (xy 337.894137 -267.909593)
			(xy 337.845918 -267.899749) (xy 337.799902 -267.882297) (xy 337.757281 -267.85769) (xy 337.71916 -267.826565)
			(xy 337.686525 -267.789728) (xy 337.660222 -267.748132) (xy 337.640931 -267.702856) (xy 337.629154 -267.655072)
			(xy 337.625194 -267.606018) (xy 337.296506 -267.606018) (xy 337.296011 -267.630625) (xy 337.288116 -267.679202)
			(xy 337.272532 -267.725883) (xy 337.249661 -267.76946) (xy 337.220096 -267.808804) (xy 337.184603 -267.842896)
			(xy 337.1441 -267.870852) (xy 337.099638 -267.89195) (xy 337.052367 -267.905642) (xy 337.003512 -267.911574)
			(xy 336.954337 -267.909593) (xy 336.906118 -267.899749) (xy 336.860102 -267.882297) (xy 336.817481 -267.85769)
			(xy 336.77936 -267.826565) (xy 336.746725 -267.789728) (xy 336.720422 -267.748132) (xy 336.701131 -267.702856)
			(xy 336.689354 -267.655072) (xy 336.685394 -267.606018) (xy 336.366866 -267.606018) (xy 336.366354 -267.631464)
			(xy 336.35819 -267.681698) (xy 336.342074 -267.729972) (xy 336.318423 -267.775035) (xy 336.28785 -267.815721)
			(xy 336.251146 -267.850976) (xy 336.209262 -267.879886) (xy 336.163283 -267.901703) (xy 336.114399 -267.915863)
			(xy 336.063878 -267.921997) (xy 336.013026 -267.919948) (xy 335.963162 -267.909768) (xy 335.915576 -267.891721)
			(xy 335.871502 -267.866275) (xy 335.83208 -267.834088) (xy 335.798332 -267.795994) (xy 335.771131 -267.75298)
			(xy 335.751183 -267.70616) (xy 335.739004 -267.656746) (xy 335.734909 -267.606018) (xy 335.416398 -267.606018)
			(xy 335.415903 -267.630625) (xy 335.408008 -267.679202) (xy 335.392424 -267.725883) (xy 335.369553 -267.76946)
			(xy 335.339988 -267.808804) (xy 335.304495 -267.842896) (xy 335.263992 -267.870852) (xy 335.21953 -267.89195)
			(xy 335.172259 -267.905642) (xy 335.123404 -267.911574) (xy 335.074229 -267.909593) (xy 335.02601 -267.899749)
			(xy 334.979994 -267.882297) (xy 334.937373 -267.85769) (xy 334.899252 -267.826565) (xy 334.866617 -267.789728)
			(xy 334.840314 -267.748132) (xy 334.821023 -267.702856) (xy 334.809246 -267.655072) (xy 334.805286 -267.606018)
			(xy 334.476344 -267.606018) (xy 334.475849 -267.630625) (xy 334.467954 -267.679202) (xy 334.45237 -267.725883)
			(xy 334.429499 -267.76946) (xy 334.399934 -267.808804) (xy 334.364441 -267.842896) (xy 334.323938 -267.870852)
			(xy 334.279476 -267.89195) (xy 334.232205 -267.905642) (xy 334.18335 -267.911574) (xy 334.134175 -267.909593)
			(xy 334.085956 -267.899749) (xy 334.03994 -267.882297) (xy 333.997319 -267.85769) (xy 333.959198 -267.826565)
			(xy 333.926563 -267.789728) (xy 333.90026 -267.748132) (xy 333.880969 -267.702856) (xy 333.869192 -267.655072)
			(xy 333.865232 -267.606018) (xy 333.53629 -267.606018) (xy 333.535795 -267.630625) (xy 333.5279 -267.679202)
			(xy 333.512316 -267.725883) (xy 333.489445 -267.76946) (xy 333.45988 -267.808804) (xy 333.424387 -267.842896)
			(xy 333.383884 -267.870852) (xy 333.339422 -267.89195) (xy 333.292151 -267.905642) (xy 333.243296 -267.911574)
			(xy 333.194121 -267.909593) (xy 333.145902 -267.899749) (xy 333.099886 -267.882297) (xy 333.057265 -267.85769)
			(xy 333.019144 -267.826565) (xy 332.986509 -267.789728) (xy 332.960206 -267.748132) (xy 332.940915 -267.702856)
			(xy 332.929138 -267.655072) (xy 332.925178 -267.606018) (xy 332.606904 -267.606018) (xy 332.606392 -267.631464)
			(xy 332.598228 -267.681698) (xy 332.582112 -267.729972) (xy 332.558461 -267.775035) (xy 332.527888 -267.815721)
			(xy 332.491184 -267.850976) (xy 332.4493 -267.879886) (xy 332.403321 -267.901703) (xy 332.354437 -267.915863)
			(xy 332.303916 -267.921997) (xy 332.253064 -267.919948) (xy 332.2032 -267.909768) (xy 332.155614 -267.891721)
			(xy 332.11154 -267.866275) (xy 332.072118 -267.834088) (xy 332.03837 -267.795994) (xy 332.011169 -267.75298)
			(xy 331.991221 -267.70616) (xy 331.979042 -267.656746) (xy 331.974947 -267.606018) (xy 331.656436 -267.606018)
			(xy 331.655941 -267.630625) (xy 331.648046 -267.679202) (xy 331.632462 -267.725883) (xy 331.609591 -267.76946)
			(xy 331.580026 -267.808804) (xy 331.544533 -267.842896) (xy 331.50403 -267.870852) (xy 331.459568 -267.89195)
			(xy 331.412297 -267.905642) (xy 331.363442 -267.911574) (xy 331.314267 -267.909593) (xy 331.266048 -267.899749)
			(xy 331.220032 -267.882297) (xy 331.177411 -267.85769) (xy 331.13929 -267.826565) (xy 331.106655 -267.789728)
			(xy 331.080352 -267.748132) (xy 331.061061 -267.702856) (xy 331.049284 -267.655072) (xy 331.045324 -267.606018)
			(xy 330.716382 -267.606018) (xy 330.715887 -267.630625) (xy 330.707992 -267.679202) (xy 330.692408 -267.725883)
			(xy 330.669537 -267.76946) (xy 330.639972 -267.808804) (xy 330.604479 -267.842896) (xy 330.563976 -267.870852)
			(xy 330.519514 -267.89195) (xy 330.472243 -267.905642) (xy 330.423388 -267.911574) (xy 330.374213 -267.909593)
			(xy 330.325994 -267.899749) (xy 330.279978 -267.882297) (xy 330.237357 -267.85769) (xy 330.199236 -267.826565)
			(xy 330.166601 -267.789728) (xy 330.140298 -267.748132) (xy 330.121007 -267.702856) (xy 330.10923 -267.655072)
			(xy 330.10527 -267.606018) (xy 329.786742 -267.606018) (xy 329.78623 -267.631464) (xy 329.778066 -267.681698)
			(xy 329.76195 -267.729972) (xy 329.738299 -267.775035) (xy 329.707726 -267.815721) (xy 329.671022 -267.850976)
			(xy 329.629138 -267.879886) (xy 329.583159 -267.901703) (xy 329.534275 -267.915863) (xy 329.483754 -267.921997)
			(xy 329.432902 -267.919948) (xy 329.383038 -267.909768) (xy 329.335452 -267.891721) (xy 329.291378 -267.866275)
			(xy 329.251956 -267.834088) (xy 329.218208 -267.795994) (xy 329.191007 -267.75298) (xy 329.171059 -267.70616)
			(xy 329.15888 -267.656746) (xy 329.154785 -267.606018) (xy 328.836528 -267.606018) (xy 328.836033 -267.630625)
			(xy 328.828138 -267.679202) (xy 328.812554 -267.725883) (xy 328.789683 -267.76946) (xy 328.760118 -267.808804)
			(xy 328.724625 -267.842896) (xy 328.684122 -267.870852) (xy 328.63966 -267.89195) (xy 328.592389 -267.905642)
			(xy 328.543534 -267.911574) (xy 328.494359 -267.909593) (xy 328.44614 -267.899749) (xy 328.400124 -267.882297)
			(xy 328.357503 -267.85769) (xy 328.319382 -267.826565) (xy 328.286747 -267.789728) (xy 328.260444 -267.748132)
			(xy 328.241153 -267.702856) (xy 328.229376 -267.655072) (xy 328.225416 -267.606018) (xy 326.95642 -267.606018)
			(xy 326.955925 -267.630625) (xy 326.94803 -267.679202) (xy 326.932446 -267.725883) (xy 326.909575 -267.76946)
			(xy 326.88001 -267.808804) (xy 326.844517 -267.842896) (xy 326.804014 -267.870852) (xy 326.759552 -267.89195)
			(xy 326.712281 -267.905642) (xy 326.663426 -267.911574) (xy 326.614251 -267.909593) (xy 326.566032 -267.899749)
			(xy 326.520016 -267.882297) (xy 326.477395 -267.85769) (xy 326.439274 -267.826565) (xy 326.406639 -267.789728)
			(xy 326.380336 -267.748132) (xy 326.361045 -267.702856) (xy 326.349268 -267.655072) (xy 326.345308 -267.606018)
			(xy 310.45912 -267.606018) (xy 310.45912 -268.150086) (xy 324.74714 -268.150086) (xy 324.7511 -268.101032)
			(xy 324.762877 -268.053248) (xy 324.782168 -268.007972) (xy 324.808471 -267.966376) (xy 324.841106 -267.929539)
			(xy 324.879227 -267.898414) (xy 324.921848 -267.873807) (xy 324.967864 -267.856355) (xy 325.016083 -267.846511)
			(xy 325.065258 -267.84453) (xy 325.114113 -267.850462) (xy 325.161384 -267.864154) (xy 325.205846 -267.885252)
			(xy 325.246349 -267.913208) (xy 325.281842 -267.9473) (xy 325.311407 -267.986644) (xy 325.334278 -268.030221)
			(xy 325.349862 -268.076902) (xy 325.357757 -268.125479) (xy 325.358252 -268.150086) (xy 325.357757 -268.174693)
			(xy 325.349862 -268.22327) (xy 325.334278 -268.269951) (xy 325.311407 -268.313528) (xy 325.281842 -268.352872)
			(xy 325.246349 -268.386964) (xy 325.205846 -268.41492) (xy 325.203519 -268.416024) (xy 326.815208 -268.416024)
			(xy 326.819168 -268.36697) (xy 326.830945 -268.319186) (xy 326.850236 -268.27391) (xy 326.876539 -268.232314)
			(xy 326.909174 -268.195477) (xy 326.947295 -268.164352) (xy 326.989916 -268.139745) (xy 327.035932 -268.122293)
			(xy 327.084151 -268.112449) (xy 327.133326 -268.110468) (xy 327.182181 -268.1164) (xy 327.229452 -268.130092)
			(xy 327.273914 -268.15119) (xy 327.314417 -268.179146) (xy 327.34991 -268.213238) (xy 327.379475 -268.252582)
			(xy 327.402346 -268.296159) (xy 327.41793 -268.34284) (xy 327.425825 -268.391417) (xy 327.42632 -268.416024)
			(xy 328.695316 -268.416024) (xy 328.699276 -268.36697) (xy 328.711053 -268.319186) (xy 328.730344 -268.27391)
			(xy 328.756647 -268.232314) (xy 328.789282 -268.195477) (xy 328.827403 -268.164352) (xy 328.870024 -268.139745)
			(xy 328.91604 -268.122293) (xy 328.964259 -268.112449) (xy 329.013434 -268.110468) (xy 329.062289 -268.1164)
			(xy 329.10956 -268.130092) (xy 329.154022 -268.15119) (xy 329.194525 -268.179146) (xy 329.230018 -268.213238)
			(xy 329.259583 -268.252582) (xy 329.282454 -268.296159) (xy 329.298038 -268.34284) (xy 329.305933 -268.391417)
			(xy 329.306428 -268.416024) (xy 329.63537 -268.416024) (xy 329.63933 -268.36697) (xy 329.651107 -268.319186)
			(xy 329.670398 -268.27391) (xy 329.696701 -268.232314) (xy 329.729336 -268.195477) (xy 329.767457 -268.164352)
			(xy 329.810078 -268.139745) (xy 329.856094 -268.122293) (xy 329.904313 -268.112449) (xy 329.953488 -268.110468)
			(xy 330.002343 -268.1164) (xy 330.049614 -268.130092) (xy 330.094076 -268.15119) (xy 330.134579 -268.179146)
			(xy 330.170072 -268.213238) (xy 330.199637 -268.252582) (xy 330.222508 -268.296159) (xy 330.238092 -268.34284)
			(xy 330.245987 -268.391417) (xy 330.246482 -268.416024) (xy 330.57517 -268.416024) (xy 330.57913 -268.36697)
			(xy 330.590907 -268.319186) (xy 330.610198 -268.27391) (xy 330.636501 -268.232314) (xy 330.669136 -268.195477)
			(xy 330.707257 -268.164352) (xy 330.749878 -268.139745) (xy 330.795894 -268.122293) (xy 330.844113 -268.112449)
			(xy 330.893288 -268.110468) (xy 330.942143 -268.1164) (xy 330.989414 -268.130092) (xy 331.033876 -268.15119)
			(xy 331.074379 -268.179146) (xy 331.109872 -268.213238) (xy 331.139437 -268.252582) (xy 331.162308 -268.296159)
			(xy 331.177892 -268.34284) (xy 331.185787 -268.391417) (xy 331.186282 -268.416024) (xy 331.515224 -268.416024)
			(xy 331.519184 -268.36697) (xy 331.530961 -268.319186) (xy 331.550252 -268.27391) (xy 331.576555 -268.232314)
			(xy 331.60919 -268.195477) (xy 331.647311 -268.164352) (xy 331.689932 -268.139745) (xy 331.735948 -268.122293)
			(xy 331.784167 -268.112449) (xy 331.833342 -268.110468) (xy 331.882197 -268.1164) (xy 331.929468 -268.130092)
			(xy 331.97393 -268.15119) (xy 332.014433 -268.179146) (xy 332.049926 -268.213238) (xy 332.079491 -268.252582)
			(xy 332.102362 -268.296159) (xy 332.117946 -268.34284) (xy 332.125841 -268.391417) (xy 332.126336 -268.416024)
			(xy 332.455278 -268.416024) (xy 332.459238 -268.36697) (xy 332.471015 -268.319186) (xy 332.490306 -268.27391)
			(xy 332.516609 -268.232314) (xy 332.549244 -268.195477) (xy 332.587365 -268.164352) (xy 332.629986 -268.139745)
			(xy 332.676002 -268.122293) (xy 332.724221 -268.112449) (xy 332.773396 -268.110468) (xy 332.822251 -268.1164)
			(xy 332.869522 -268.130092) (xy 332.913984 -268.15119) (xy 332.954487 -268.179146) (xy 332.98998 -268.213238)
			(xy 333.019545 -268.252582) (xy 333.042416 -268.296159) (xy 333.058 -268.34284) (xy 333.065895 -268.391417)
			(xy 333.06639 -268.416024) (xy 333.395332 -268.416024) (xy 333.399292 -268.36697) (xy 333.411069 -268.319186)
			(xy 333.43036 -268.27391) (xy 333.456663 -268.232314) (xy 333.489298 -268.195477) (xy 333.527419 -268.164352)
			(xy 333.57004 -268.139745) (xy 333.616056 -268.122293) (xy 333.664275 -268.112449) (xy 333.71345 -268.110468)
			(xy 333.762305 -268.1164) (xy 333.809576 -268.130092) (xy 333.854038 -268.15119) (xy 333.894541 -268.179146)
			(xy 333.930034 -268.213238) (xy 333.959599 -268.252582) (xy 333.98247 -268.296159) (xy 333.998054 -268.34284)
			(xy 334.005949 -268.391417) (xy 334.006444 -268.416024) (xy 335.275186 -268.416024) (xy 335.279146 -268.36697)
			(xy 335.290923 -268.319186) (xy 335.310214 -268.27391) (xy 335.336517 -268.232314) (xy 335.369152 -268.195477)
			(xy 335.407273 -268.164352) (xy 335.449894 -268.139745) (xy 335.49591 -268.122293) (xy 335.544129 -268.112449)
			(xy 335.593304 -268.110468) (xy 335.642159 -268.1164) (xy 335.68943 -268.130092) (xy 335.733892 -268.15119)
			(xy 335.774395 -268.179146) (xy 335.809888 -268.213238) (xy 335.839453 -268.252582) (xy 335.862324 -268.296159)
			(xy 335.877908 -268.34284) (xy 335.885803 -268.391417) (xy 335.886298 -268.416024) (xy 336.21524 -268.416024)
			(xy 336.2192 -268.36697) (xy 336.230977 -268.319186) (xy 336.250268 -268.27391) (xy 336.276571 -268.232314)
			(xy 336.309206 -268.195477) (xy 336.347327 -268.164352) (xy 336.389948 -268.139745) (xy 336.435964 -268.122293)
			(xy 336.484183 -268.112449) (xy 336.533358 -268.110468) (xy 336.582213 -268.1164) (xy 336.629484 -268.130092)
			(xy 336.673946 -268.15119) (xy 336.714449 -268.179146) (xy 336.749942 -268.213238) (xy 336.779507 -268.252582)
			(xy 336.802378 -268.296159) (xy 336.817962 -268.34284) (xy 336.825857 -268.391417) (xy 336.826352 -268.416024)
			(xy 337.155294 -268.416024) (xy 337.159254 -268.36697) (xy 337.171031 -268.319186) (xy 337.190322 -268.27391)
			(xy 337.216625 -268.232314) (xy 337.24926 -268.195477) (xy 337.287381 -268.164352) (xy 337.330002 -268.139745)
			(xy 337.376018 -268.122293) (xy 337.424237 -268.112449) (xy 337.473412 -268.110468) (xy 337.522267 -268.1164)
			(xy 337.569538 -268.130092) (xy 337.614 -268.15119) (xy 337.654503 -268.179146) (xy 337.689996 -268.213238)
			(xy 337.719561 -268.252582) (xy 337.742432 -268.296159) (xy 337.758016 -268.34284) (xy 337.765911 -268.391417)
			(xy 337.766406 -268.416024) (xy 338.095348 -268.416024) (xy 338.099308 -268.36697) (xy 338.111085 -268.319186)
			(xy 338.130376 -268.27391) (xy 338.156679 -268.232314) (xy 338.189314 -268.195477) (xy 338.227435 -268.164352)
			(xy 338.270056 -268.139745) (xy 338.316072 -268.122293) (xy 338.364291 -268.112449) (xy 338.413466 -268.110468)
			(xy 338.462321 -268.1164) (xy 338.509592 -268.130092) (xy 338.554054 -268.15119) (xy 338.594557 -268.179146)
			(xy 338.63005 -268.213238) (xy 338.659615 -268.252582) (xy 338.682486 -268.296159) (xy 338.69807 -268.34284)
			(xy 338.705965 -268.391417) (xy 338.70646 -268.416024) (xy 339.035402 -268.416024) (xy 339.039362 -268.36697)
			(xy 339.051139 -268.319186) (xy 339.07043 -268.27391) (xy 339.096733 -268.232314) (xy 339.129368 -268.195477)
			(xy 339.167489 -268.164352) (xy 339.21011 -268.139745) (xy 339.256126 -268.122293) (xy 339.304345 -268.112449)
			(xy 339.35352 -268.110468) (xy 339.402375 -268.1164) (xy 339.449646 -268.130092) (xy 339.494108 -268.15119)
			(xy 339.534611 -268.179146) (xy 339.570104 -268.213238) (xy 339.599669 -268.252582) (xy 339.62254 -268.296159)
			(xy 339.638124 -268.34284) (xy 339.646019 -268.391417) (xy 339.646514 -268.416024) (xy 339.975202 -268.416024)
			(xy 339.979162 -268.36697) (xy 339.990939 -268.319186) (xy 340.01023 -268.27391) (xy 340.036533 -268.232314)
			(xy 340.069168 -268.195477) (xy 340.107289 -268.164352) (xy 340.14991 -268.139745) (xy 340.195926 -268.122293)
			(xy 340.244145 -268.112449) (xy 340.29332 -268.110468) (xy 340.342175 -268.1164) (xy 340.389446 -268.130092)
			(xy 340.433908 -268.15119) (xy 340.474411 -268.179146) (xy 340.509904 -268.213238) (xy 340.539469 -268.252582)
			(xy 340.56234 -268.296159) (xy 340.577924 -268.34284) (xy 340.585819 -268.391417) (xy 340.586314 -268.416024)
			(xy 341.85531 -268.416024) (xy 341.85927 -268.36697) (xy 341.871047 -268.319186) (xy 341.890338 -268.27391)
			(xy 341.916641 -268.232314) (xy 341.949276 -268.195477) (xy 341.987397 -268.164352) (xy 342.030018 -268.139745)
			(xy 342.076034 -268.122293) (xy 342.124253 -268.112449) (xy 342.173428 -268.110468) (xy 342.222283 -268.1164)
			(xy 342.269554 -268.130092) (xy 342.314016 -268.15119) (xy 342.354519 -268.179146) (xy 342.390012 -268.213238)
			(xy 342.419577 -268.252582) (xy 342.442448 -268.296159) (xy 342.458032 -268.34284) (xy 342.465927 -268.391417)
			(xy 342.466422 -268.416024) (xy 342.795364 -268.416024) (xy 342.799324 -268.36697) (xy 342.811101 -268.319186)
			(xy 342.830392 -268.27391) (xy 342.856695 -268.232314) (xy 342.88933 -268.195477) (xy 342.927451 -268.164352)
			(xy 342.970072 -268.139745) (xy 343.016088 -268.122293) (xy 343.064307 -268.112449) (xy 343.113482 -268.110468)
			(xy 343.162337 -268.1164) (xy 343.209608 -268.130092) (xy 343.25407 -268.15119) (xy 343.294573 -268.179146)
			(xy 343.330066 -268.213238) (xy 343.359631 -268.252582) (xy 343.382502 -268.296159) (xy 343.398086 -268.34284)
			(xy 343.405981 -268.391417) (xy 343.406476 -268.416024) (xy 343.735418 -268.416024) (xy 343.739378 -268.36697)
			(xy 343.751155 -268.319186) (xy 343.770446 -268.27391) (xy 343.796749 -268.232314) (xy 343.829384 -268.195477)
			(xy 343.867505 -268.164352) (xy 343.910126 -268.139745) (xy 343.956142 -268.122293) (xy 344.004361 -268.112449)
			(xy 344.053536 -268.110468) (xy 344.102391 -268.1164) (xy 344.149662 -268.130092) (xy 344.194124 -268.15119)
			(xy 344.234627 -268.179146) (xy 344.27012 -268.213238) (xy 344.299685 -268.252582) (xy 344.322556 -268.296159)
			(xy 344.33814 -268.34284) (xy 344.346035 -268.391417) (xy 344.34653 -268.416024) (xy 344.346035 -268.440631)
			(xy 344.33814 -268.489208) (xy 344.322556 -268.535889) (xy 344.299685 -268.579466) (xy 344.27012 -268.61881)
			(xy 344.234627 -268.652902) (xy 344.194124 -268.680858) (xy 344.149662 -268.701956) (xy 344.102391 -268.715648)
			(xy 344.053536 -268.72158) (xy 344.004361 -268.719599) (xy 343.956142 -268.709755) (xy 343.910126 -268.692303)
			(xy 343.867505 -268.667696) (xy 343.829384 -268.636571) (xy 343.796749 -268.599734) (xy 343.770446 -268.558138)
			(xy 343.751155 -268.512862) (xy 343.739378 -268.465078) (xy 343.735418 -268.416024) (xy 343.406476 -268.416024)
			(xy 343.405981 -268.440631) (xy 343.398086 -268.489208) (xy 343.382502 -268.535889) (xy 343.359631 -268.579466)
			(xy 343.330066 -268.61881) (xy 343.294573 -268.652902) (xy 343.25407 -268.680858) (xy 343.209608 -268.701956)
			(xy 343.162337 -268.715648) (xy 343.113482 -268.72158) (xy 343.064307 -268.719599) (xy 343.016088 -268.709755)
			(xy 342.970072 -268.692303) (xy 342.927451 -268.667696) (xy 342.88933 -268.636571) (xy 342.856695 -268.599734)
			(xy 342.830392 -268.558138) (xy 342.811101 -268.512862) (xy 342.799324 -268.465078) (xy 342.795364 -268.416024)
			(xy 342.466422 -268.416024) (xy 342.465927 -268.440631) (xy 342.458032 -268.489208) (xy 342.442448 -268.535889)
			(xy 342.419577 -268.579466) (xy 342.390012 -268.61881) (xy 342.354519 -268.652902) (xy 342.314016 -268.680858)
			(xy 342.269554 -268.701956) (xy 342.222283 -268.715648) (xy 342.173428 -268.72158) (xy 342.124253 -268.719599)
			(xy 342.076034 -268.709755) (xy 342.030018 -268.692303) (xy 341.987397 -268.667696) (xy 341.949276 -268.636571)
			(xy 341.916641 -268.599734) (xy 341.890338 -268.558138) (xy 341.871047 -268.512862) (xy 341.85927 -268.465078)
			(xy 341.85531 -268.416024) (xy 340.586314 -268.416024) (xy 340.585819 -268.440631) (xy 340.577924 -268.489208)
			(xy 340.56234 -268.535889) (xy 340.539469 -268.579466) (xy 340.509904 -268.61881) (xy 340.474411 -268.652902)
			(xy 340.433908 -268.680858) (xy 340.389446 -268.701956) (xy 340.342175 -268.715648) (xy 340.29332 -268.72158)
			(xy 340.244145 -268.719599) (xy 340.195926 -268.709755) (xy 340.14991 -268.692303) (xy 340.107289 -268.667696)
			(xy 340.069168 -268.636571) (xy 340.036533 -268.599734) (xy 340.01023 -268.558138) (xy 339.990939 -268.512862)
			(xy 339.979162 -268.465078) (xy 339.975202 -268.416024) (xy 339.646514 -268.416024) (xy 339.646019 -268.440631)
			(xy 339.638124 -268.489208) (xy 339.62254 -268.535889) (xy 339.599669 -268.579466) (xy 339.570104 -268.61881)
			(xy 339.534611 -268.652902) (xy 339.494108 -268.680858) (xy 339.449646 -268.701956) (xy 339.402375 -268.715648)
			(xy 339.35352 -268.72158) (xy 339.304345 -268.719599) (xy 339.256126 -268.709755) (xy 339.21011 -268.692303)
			(xy 339.167489 -268.667696) (xy 339.129368 -268.636571) (xy 339.096733 -268.599734) (xy 339.07043 -268.558138)
			(xy 339.051139 -268.512862) (xy 339.039362 -268.465078) (xy 339.035402 -268.416024) (xy 338.70646 -268.416024)
			(xy 338.705965 -268.440631) (xy 338.69807 -268.489208) (xy 338.682486 -268.535889) (xy 338.659615 -268.579466)
			(xy 338.63005 -268.61881) (xy 338.594557 -268.652902) (xy 338.554054 -268.680858) (xy 338.509592 -268.701956)
			(xy 338.462321 -268.715648) (xy 338.413466 -268.72158) (xy 338.364291 -268.719599) (xy 338.316072 -268.709755)
			(xy 338.270056 -268.692303) (xy 338.227435 -268.667696) (xy 338.189314 -268.636571) (xy 338.156679 -268.599734)
			(xy 338.130376 -268.558138) (xy 338.111085 -268.512862) (xy 338.099308 -268.465078) (xy 338.095348 -268.416024)
			(xy 337.766406 -268.416024) (xy 337.765911 -268.440631) (xy 337.758016 -268.489208) (xy 337.742432 -268.535889)
			(xy 337.719561 -268.579466) (xy 337.689996 -268.61881) (xy 337.654503 -268.652902) (xy 337.614 -268.680858)
			(xy 337.569538 -268.701956) (xy 337.522267 -268.715648) (xy 337.473412 -268.72158) (xy 337.424237 -268.719599)
			(xy 337.376018 -268.709755) (xy 337.330002 -268.692303) (xy 337.287381 -268.667696) (xy 337.24926 -268.636571)
			(xy 337.216625 -268.599734) (xy 337.190322 -268.558138) (xy 337.171031 -268.512862) (xy 337.159254 -268.465078)
			(xy 337.155294 -268.416024) (xy 336.826352 -268.416024) (xy 336.825857 -268.440631) (xy 336.817962 -268.489208)
			(xy 336.802378 -268.535889) (xy 336.779507 -268.579466) (xy 336.749942 -268.61881) (xy 336.714449 -268.652902)
			(xy 336.673946 -268.680858) (xy 336.629484 -268.701956) (xy 336.582213 -268.715648) (xy 336.533358 -268.72158)
			(xy 336.484183 -268.719599) (xy 336.435964 -268.709755) (xy 336.389948 -268.692303) (xy 336.347327 -268.667696)
			(xy 336.309206 -268.636571) (xy 336.276571 -268.599734) (xy 336.250268 -268.558138) (xy 336.230977 -268.512862)
			(xy 336.2192 -268.465078) (xy 336.21524 -268.416024) (xy 335.886298 -268.416024) (xy 335.885803 -268.440631)
			(xy 335.877908 -268.489208) (xy 335.862324 -268.535889) (xy 335.839453 -268.579466) (xy 335.809888 -268.61881)
			(xy 335.774395 -268.652902) (xy 335.733892 -268.680858) (xy 335.68943 -268.701956) (xy 335.642159 -268.715648)
			(xy 335.593304 -268.72158) (xy 335.544129 -268.719599) (xy 335.49591 -268.709755) (xy 335.449894 -268.692303)
			(xy 335.407273 -268.667696) (xy 335.369152 -268.636571) (xy 335.336517 -268.599734) (xy 335.310214 -268.558138)
			(xy 335.290923 -268.512862) (xy 335.279146 -268.465078) (xy 335.275186 -268.416024) (xy 334.006444 -268.416024)
			(xy 334.005949 -268.440631) (xy 333.998054 -268.489208) (xy 333.98247 -268.535889) (xy 333.959599 -268.579466)
			(xy 333.930034 -268.61881) (xy 333.894541 -268.652902) (xy 333.854038 -268.680858) (xy 333.809576 -268.701956)
			(xy 333.762305 -268.715648) (xy 333.71345 -268.72158) (xy 333.664275 -268.719599) (xy 333.616056 -268.709755)
			(xy 333.57004 -268.692303) (xy 333.527419 -268.667696) (xy 333.489298 -268.636571) (xy 333.456663 -268.599734)
			(xy 333.43036 -268.558138) (xy 333.411069 -268.512862) (xy 333.399292 -268.465078) (xy 333.395332 -268.416024)
			(xy 333.06639 -268.416024) (xy 333.065895 -268.440631) (xy 333.058 -268.489208) (xy 333.042416 -268.535889)
			(xy 333.019545 -268.579466) (xy 332.98998 -268.61881) (xy 332.954487 -268.652902) (xy 332.913984 -268.680858)
			(xy 332.869522 -268.701956) (xy 332.822251 -268.715648) (xy 332.773396 -268.72158) (xy 332.724221 -268.719599)
			(xy 332.676002 -268.709755) (xy 332.629986 -268.692303) (xy 332.587365 -268.667696) (xy 332.549244 -268.636571)
			(xy 332.516609 -268.599734) (xy 332.490306 -268.558138) (xy 332.471015 -268.512862) (xy 332.459238 -268.465078)
			(xy 332.455278 -268.416024) (xy 332.126336 -268.416024) (xy 332.125841 -268.440631) (xy 332.117946 -268.489208)
			(xy 332.102362 -268.535889) (xy 332.079491 -268.579466) (xy 332.049926 -268.61881) (xy 332.014433 -268.652902)
			(xy 331.97393 -268.680858) (xy 331.929468 -268.701956) (xy 331.882197 -268.715648) (xy 331.833342 -268.72158)
			(xy 331.784167 -268.719599) (xy 331.735948 -268.709755) (xy 331.689932 -268.692303) (xy 331.647311 -268.667696)
			(xy 331.60919 -268.636571) (xy 331.576555 -268.599734) (xy 331.550252 -268.558138) (xy 331.530961 -268.512862)
			(xy 331.519184 -268.465078) (xy 331.515224 -268.416024) (xy 331.186282 -268.416024) (xy 331.185787 -268.440631)
			(xy 331.177892 -268.489208) (xy 331.162308 -268.535889) (xy 331.139437 -268.579466) (xy 331.109872 -268.61881)
			(xy 331.074379 -268.652902) (xy 331.033876 -268.680858) (xy 330.989414 -268.701956) (xy 330.942143 -268.715648)
			(xy 330.893288 -268.72158) (xy 330.844113 -268.719599) (xy 330.795894 -268.709755) (xy 330.749878 -268.692303)
			(xy 330.707257 -268.667696) (xy 330.669136 -268.636571) (xy 330.636501 -268.599734) (xy 330.610198 -268.558138)
			(xy 330.590907 -268.512862) (xy 330.57913 -268.465078) (xy 330.57517 -268.416024) (xy 330.246482 -268.416024)
			(xy 330.245987 -268.440631) (xy 330.238092 -268.489208) (xy 330.222508 -268.535889) (xy 330.199637 -268.579466)
			(xy 330.170072 -268.61881) (xy 330.134579 -268.652902) (xy 330.094076 -268.680858) (xy 330.049614 -268.701956)
			(xy 330.002343 -268.715648) (xy 329.953488 -268.72158) (xy 329.904313 -268.719599) (xy 329.856094 -268.709755)
			(xy 329.810078 -268.692303) (xy 329.767457 -268.667696) (xy 329.729336 -268.636571) (xy 329.696701 -268.599734)
			(xy 329.670398 -268.558138) (xy 329.651107 -268.512862) (xy 329.63933 -268.465078) (xy 329.63537 -268.416024)
			(xy 329.306428 -268.416024) (xy 329.305933 -268.440631) (xy 329.298038 -268.489208) (xy 329.282454 -268.535889)
			(xy 329.259583 -268.579466) (xy 329.230018 -268.61881) (xy 329.194525 -268.652902) (xy 329.154022 -268.680858)
			(xy 329.10956 -268.701956) (xy 329.062289 -268.715648) (xy 329.013434 -268.72158) (xy 328.964259 -268.719599)
			(xy 328.91604 -268.709755) (xy 328.870024 -268.692303) (xy 328.827403 -268.667696) (xy 328.789282 -268.636571)
			(xy 328.756647 -268.599734) (xy 328.730344 -268.558138) (xy 328.711053 -268.512862) (xy 328.699276 -268.465078)
			(xy 328.695316 -268.416024) (xy 327.42632 -268.416024) (xy 327.425825 -268.440631) (xy 327.41793 -268.489208)
			(xy 327.402346 -268.535889) (xy 327.379475 -268.579466) (xy 327.34991 -268.61881) (xy 327.314417 -268.652902)
			(xy 327.273914 -268.680858) (xy 327.229452 -268.701956) (xy 327.182181 -268.715648) (xy 327.133326 -268.72158)
			(xy 327.084151 -268.719599) (xy 327.035932 -268.709755) (xy 326.989916 -268.692303) (xy 326.947295 -268.667696)
			(xy 326.909174 -268.636571) (xy 326.876539 -268.599734) (xy 326.850236 -268.558138) (xy 326.830945 -268.512862)
			(xy 326.819168 -268.465078) (xy 326.815208 -268.416024) (xy 325.203519 -268.416024) (xy 325.161384 -268.436018)
			(xy 325.114113 -268.44971) (xy 325.065258 -268.455642) (xy 325.016083 -268.453661) (xy 324.967864 -268.443817)
			(xy 324.921848 -268.426365) (xy 324.879227 -268.401758) (xy 324.841106 -268.370633) (xy 324.808471 -268.333796)
			(xy 324.782168 -268.2922) (xy 324.762877 -268.246924) (xy 324.7511 -268.19914) (xy 324.74714 -268.150086)
			(xy 310.45912 -268.150086) (xy 310.45912 -269.22603) (xy 326.345308 -269.22603) (xy 326.349268 -269.176976)
			(xy 326.361045 -269.129192) (xy 326.380336 -269.083916) (xy 326.406639 -269.04232) (xy 326.439274 -269.005483)
			(xy 326.477395 -268.974358) (xy 326.520016 -268.949751) (xy 326.566032 -268.932299) (xy 326.614251 -268.922455)
			(xy 326.663426 -268.920474) (xy 326.712281 -268.926406) (xy 326.759552 -268.940098) (xy 326.804014 -268.961196)
			(xy 326.844517 -268.989152) (xy 326.88001 -269.023244) (xy 326.909575 -269.062588) (xy 326.932446 -269.106165)
			(xy 326.94803 -269.152846) (xy 326.955925 -269.201423) (xy 326.95642 -269.22603) (xy 327.285362 -269.22603)
			(xy 327.289322 -269.176976) (xy 327.301099 -269.129192) (xy 327.32039 -269.083916) (xy 327.346693 -269.04232)
			(xy 327.379328 -269.005483) (xy 327.417449 -268.974358) (xy 327.46007 -268.949751) (xy 327.506086 -268.932299)
			(xy 327.554305 -268.922455) (xy 327.60348 -268.920474) (xy 327.652335 -268.926406) (xy 327.699606 -268.940098)
			(xy 327.744068 -268.961196) (xy 327.784571 -268.989152) (xy 327.820064 -269.023244) (xy 327.849629 -269.062588)
			(xy 327.8725 -269.106165) (xy 327.888084 -269.152846) (xy 327.895979 -269.201423) (xy 327.896474 -269.22603)
			(xy 328.225416 -269.22603) (xy 328.229376 -269.176976) (xy 328.241153 -269.129192) (xy 328.260444 -269.083916)
			(xy 328.286747 -269.04232) (xy 328.319382 -269.005483) (xy 328.357503 -268.974358) (xy 328.400124 -268.949751)
			(xy 328.44614 -268.932299) (xy 328.494359 -268.922455) (xy 328.543534 -268.920474) (xy 328.592389 -268.926406)
			(xy 328.63966 -268.940098) (xy 328.684122 -268.961196) (xy 328.724625 -268.989152) (xy 328.760118 -269.023244)
			(xy 328.789683 -269.062588) (xy 328.812554 -269.106165) (xy 328.828138 -269.152846) (xy 328.836033 -269.201423)
			(xy 328.836528 -269.22603) (xy 329.154785 -269.22603) (xy 329.15888 -269.175302) (xy 329.171059 -269.125888)
			(xy 329.191007 -269.079068) (xy 329.218208 -269.036054) (xy 329.251956 -268.99796) (xy 329.291378 -268.965773)
			(xy 329.335452 -268.940327) (xy 329.383038 -268.92228) (xy 329.432902 -268.9121) (xy 329.483754 -268.910051)
			(xy 329.534275 -268.916185) (xy 329.583159 -268.930345) (xy 329.629138 -268.952162) (xy 329.671022 -268.981072)
			(xy 329.707726 -269.016327) (xy 329.738299 -269.057013) (xy 329.76195 -269.102076) (xy 329.778066 -269.15035)
			(xy 329.78623 -269.200584) (xy 329.786742 -269.22603) (xy 330.10527 -269.22603) (xy 330.10923 -269.176976)
			(xy 330.121007 -269.129192) (xy 330.140298 -269.083916) (xy 330.166601 -269.04232) (xy 330.199236 -269.005483)
			(xy 330.237357 -268.974358) (xy 330.279978 -268.949751) (xy 330.325994 -268.932299) (xy 330.374213 -268.922455)
			(xy 330.423388 -268.920474) (xy 330.472243 -268.926406) (xy 330.519514 -268.940098) (xy 330.563976 -268.961196)
			(xy 330.604479 -268.989152) (xy 330.639972 -269.023244) (xy 330.669537 -269.062588) (xy 330.692408 -269.106165)
			(xy 330.707992 -269.152846) (xy 330.715887 -269.201423) (xy 330.716382 -269.22603) (xy 331.045324 -269.22603)
			(xy 331.049284 -269.176976) (xy 331.061061 -269.129192) (xy 331.080352 -269.083916) (xy 331.106655 -269.04232)
			(xy 331.13929 -269.005483) (xy 331.177411 -268.974358) (xy 331.220032 -268.949751) (xy 331.266048 -268.932299)
			(xy 331.314267 -268.922455) (xy 331.363442 -268.920474) (xy 331.412297 -268.926406) (xy 331.459568 -268.940098)
			(xy 331.50403 -268.961196) (xy 331.544533 -268.989152) (xy 331.580026 -269.023244) (xy 331.609591 -269.062588)
			(xy 331.632462 -269.106165) (xy 331.648046 -269.152846) (xy 331.655941 -269.201423) (xy 331.656436 -269.22603)
			(xy 331.974947 -269.22603) (xy 331.979042 -269.175302) (xy 331.991221 -269.125888) (xy 332.011169 -269.079068)
			(xy 332.03837 -269.036054) (xy 332.072118 -268.99796) (xy 332.11154 -268.965773) (xy 332.155614 -268.940327)
			(xy 332.2032 -268.92228) (xy 332.253064 -268.9121) (xy 332.303916 -268.910051) (xy 332.354437 -268.916185)
			(xy 332.403321 -268.930345) (xy 332.4493 -268.952162) (xy 332.491184 -268.981072) (xy 332.527888 -269.016327)
			(xy 332.558461 -269.057013) (xy 332.582112 -269.102076) (xy 332.598228 -269.15035) (xy 332.606392 -269.200584)
			(xy 332.606904 -269.22603) (xy 332.925178 -269.22603) (xy 332.929138 -269.176976) (xy 332.940915 -269.129192)
			(xy 332.960206 -269.083916) (xy 332.986509 -269.04232) (xy 333.019144 -269.005483) (xy 333.057265 -268.974358)
			(xy 333.099886 -268.949751) (xy 333.145902 -268.932299) (xy 333.194121 -268.922455) (xy 333.243296 -268.920474)
			(xy 333.292151 -268.926406) (xy 333.339422 -268.940098) (xy 333.383884 -268.961196) (xy 333.424387 -268.989152)
			(xy 333.45988 -269.023244) (xy 333.489445 -269.062588) (xy 333.512316 -269.106165) (xy 333.5279 -269.152846)
			(xy 333.535795 -269.201423) (xy 333.53629 -269.22603) (xy 333.865232 -269.22603) (xy 333.869192 -269.176976)
			(xy 333.880969 -269.129192) (xy 333.90026 -269.083916) (xy 333.926563 -269.04232) (xy 333.959198 -269.005483)
			(xy 333.997319 -268.974358) (xy 334.03994 -268.949751) (xy 334.085956 -268.932299) (xy 334.134175 -268.922455)
			(xy 334.18335 -268.920474) (xy 334.232205 -268.926406) (xy 334.279476 -268.940098) (xy 334.323938 -268.961196)
			(xy 334.364441 -268.989152) (xy 334.399934 -269.023244) (xy 334.429499 -269.062588) (xy 334.45237 -269.106165)
			(xy 334.467954 -269.152846) (xy 334.475849 -269.201423) (xy 334.476344 -269.22603) (xy 334.805286 -269.22603)
			(xy 334.809246 -269.176976) (xy 334.821023 -269.129192) (xy 334.840314 -269.083916) (xy 334.866617 -269.04232)
			(xy 334.899252 -269.005483) (xy 334.937373 -268.974358) (xy 334.979994 -268.949751) (xy 335.02601 -268.932299)
			(xy 335.074229 -268.922455) (xy 335.123404 -268.920474) (xy 335.172259 -268.926406) (xy 335.21953 -268.940098)
			(xy 335.263992 -268.961196) (xy 335.304495 -268.989152) (xy 335.339988 -269.023244) (xy 335.369553 -269.062588)
			(xy 335.392424 -269.106165) (xy 335.408008 -269.152846) (xy 335.415903 -269.201423) (xy 335.416398 -269.22603)
			(xy 335.734909 -269.22603) (xy 335.739004 -269.175302) (xy 335.751183 -269.125888) (xy 335.771131 -269.079068)
			(xy 335.798332 -269.036054) (xy 335.83208 -268.99796) (xy 335.871502 -268.965773) (xy 335.915576 -268.940327)
			(xy 335.963162 -268.92228) (xy 336.013026 -268.9121) (xy 336.063878 -268.910051) (xy 336.114399 -268.916185)
			(xy 336.163283 -268.930345) (xy 336.209262 -268.952162) (xy 336.251146 -268.981072) (xy 336.28785 -269.016327)
			(xy 336.318423 -269.057013) (xy 336.342074 -269.102076) (xy 336.35819 -269.15035) (xy 336.366354 -269.200584)
			(xy 336.366866 -269.22603) (xy 336.685394 -269.22603) (xy 336.689354 -269.176976) (xy 336.701131 -269.129192)
			(xy 336.720422 -269.083916) (xy 336.746725 -269.04232) (xy 336.77936 -269.005483) (xy 336.817481 -268.974358)
			(xy 336.860102 -268.949751) (xy 336.906118 -268.932299) (xy 336.954337 -268.922455) (xy 337.003512 -268.920474)
			(xy 337.052367 -268.926406) (xy 337.099638 -268.940098) (xy 337.1441 -268.961196) (xy 337.184603 -268.989152)
			(xy 337.220096 -269.023244) (xy 337.249661 -269.062588) (xy 337.272532 -269.106165) (xy 337.288116 -269.152846)
			(xy 337.296011 -269.201423) (xy 337.296506 -269.22603) (xy 337.625194 -269.22603) (xy 337.629154 -269.176976)
			(xy 337.640931 -269.129192) (xy 337.660222 -269.083916) (xy 337.686525 -269.04232) (xy 337.71916 -269.005483)
			(xy 337.757281 -268.974358) (xy 337.799902 -268.949751) (xy 337.845918 -268.932299) (xy 337.894137 -268.922455)
			(xy 337.943312 -268.920474) (xy 337.992167 -268.926406) (xy 338.039438 -268.940098) (xy 338.0839 -268.961196)
			(xy 338.124403 -268.989152) (xy 338.159896 -269.023244) (xy 338.189461 -269.062588) (xy 338.212332 -269.106165)
			(xy 338.227916 -269.152846) (xy 338.235811 -269.201423) (xy 338.236306 -269.22603) (xy 338.554817 -269.22603)
			(xy 338.558912 -269.175302) (xy 338.571091 -269.125888) (xy 338.591039 -269.079068) (xy 338.61824 -269.036054)
			(xy 338.651988 -268.99796) (xy 338.69141 -268.965773) (xy 338.735484 -268.940327) (xy 338.78307 -268.92228)
			(xy 338.832934 -268.9121) (xy 338.883786 -268.910051) (xy 338.934307 -268.916185) (xy 338.983191 -268.930345)
			(xy 339.02917 -268.952162) (xy 339.071054 -268.981072) (xy 339.107758 -269.016327) (xy 339.138331 -269.057013)
			(xy 339.161982 -269.102076) (xy 339.178098 -269.15035) (xy 339.186262 -269.200584) (xy 339.186774 -269.22603)
			(xy 339.505302 -269.22603) (xy 339.509262 -269.176976) (xy 339.521039 -269.129192) (xy 339.54033 -269.083916)
			(xy 339.566633 -269.04232) (xy 339.599268 -269.005483) (xy 339.637389 -268.974358) (xy 339.68001 -268.949751)
			(xy 339.726026 -268.932299) (xy 339.774245 -268.922455) (xy 339.82342 -268.920474) (xy 339.872275 -268.926406)
			(xy 339.919546 -268.940098) (xy 339.964008 -268.961196) (xy 340.004511 -268.989152) (xy 340.040004 -269.023244)
			(xy 340.069569 -269.062588) (xy 340.09244 -269.106165) (xy 340.108024 -269.152846) (xy 340.115919 -269.201423)
			(xy 340.116414 -269.22603) (xy 340.445356 -269.22603) (xy 340.449316 -269.176976) (xy 340.461093 -269.129192)
			(xy 340.480384 -269.083916) (xy 340.506687 -269.04232) (xy 340.539322 -269.005483) (xy 340.577443 -268.974358)
			(xy 340.620064 -268.949751) (xy 340.66608 -268.932299) (xy 340.714299 -268.922455) (xy 340.763474 -268.920474)
			(xy 340.812329 -268.926406) (xy 340.8596 -268.940098) (xy 340.904062 -268.961196) (xy 340.944565 -268.989152)
			(xy 340.980058 -269.023244) (xy 341.009623 -269.062588) (xy 341.032494 -269.106165) (xy 341.048078 -269.152846)
			(xy 341.055973 -269.201423) (xy 341.056468 -269.22603) (xy 341.38541 -269.22603) (xy 341.38937 -269.176976)
			(xy 341.401147 -269.129192) (xy 341.420438 -269.083916) (xy 341.446741 -269.04232) (xy 341.479376 -269.005483)
			(xy 341.517497 -268.974358) (xy 341.560118 -268.949751) (xy 341.606134 -268.932299) (xy 341.654353 -268.922455)
			(xy 341.703528 -268.920474) (xy 341.752383 -268.926406) (xy 341.799654 -268.940098) (xy 341.844116 -268.961196)
			(xy 341.884619 -268.989152) (xy 341.920112 -269.023244) (xy 341.949677 -269.062588) (xy 341.972548 -269.106165)
			(xy 341.988132 -269.152846) (xy 341.996027 -269.201423) (xy 341.996522 -269.22603) (xy 342.314779 -269.22603)
			(xy 342.318874 -269.175302) (xy 342.331053 -269.125888) (xy 342.351001 -269.079068) (xy 342.378202 -269.036054)
			(xy 342.41195 -268.99796) (xy 342.451372 -268.965773) (xy 342.495446 -268.940327) (xy 342.543032 -268.92228)
			(xy 342.592896 -268.9121) (xy 342.643748 -268.910051) (xy 342.694269 -268.916185) (xy 342.743153 -268.930345)
			(xy 342.789132 -268.952162) (xy 342.831016 -268.981072) (xy 342.86772 -269.016327) (xy 342.898293 -269.057013)
			(xy 342.921944 -269.102076) (xy 342.93806 -269.15035) (xy 342.946224 -269.200584) (xy 342.946736 -269.22603)
			(xy 343.265264 -269.22603) (xy 343.269224 -269.176976) (xy 343.281001 -269.129192) (xy 343.300292 -269.083916)
			(xy 343.326595 -269.04232) (xy 343.35923 -269.005483) (xy 343.397351 -268.974358) (xy 343.439972 -268.949751)
			(xy 343.485988 -268.932299) (xy 343.534207 -268.922455) (xy 343.583382 -268.920474) (xy 343.632237 -268.926406)
			(xy 343.679508 -268.940098) (xy 343.72397 -268.961196) (xy 343.764473 -268.989152) (xy 343.799966 -269.023244)
			(xy 343.829531 -269.062588) (xy 343.852402 -269.106165) (xy 343.867986 -269.152846) (xy 343.875881 -269.201423)
			(xy 343.876376 -269.22603) (xy 344.205318 -269.22603) (xy 344.209278 -269.176976) (xy 344.221055 -269.129192)
			(xy 344.240346 -269.083916) (xy 344.266649 -269.04232) (xy 344.299284 -269.005483) (xy 344.337405 -268.974358)
			(xy 344.380026 -268.949751) (xy 344.426042 -268.932299) (xy 344.474261 -268.922455) (xy 344.523436 -268.920474)
			(xy 344.572291 -268.926406) (xy 344.619562 -268.940098) (xy 344.664024 -268.961196) (xy 344.704527 -268.989152)
			(xy 344.74002 -269.023244) (xy 344.769585 -269.062588) (xy 344.792456 -269.106165) (xy 344.80804 -269.152846)
			(xy 344.815935 -269.201423) (xy 344.81643 -269.22603) (xy 344.815935 -269.250637) (xy 344.80804 -269.299214)
			(xy 344.792456 -269.345895) (xy 344.769585 -269.389472) (xy 344.74002 -269.428816) (xy 344.704527 -269.462908)
			(xy 344.664024 -269.490864) (xy 344.619562 -269.511962) (xy 344.572291 -269.525654) (xy 344.523436 -269.531586)
			(xy 344.474261 -269.529605) (xy 344.426042 -269.519761) (xy 344.380026 -269.502309) (xy 344.337405 -269.477702)
			(xy 344.299284 -269.446577) (xy 344.266649 -269.40974) (xy 344.240346 -269.368144) (xy 344.221055 -269.322868)
			(xy 344.209278 -269.275084) (xy 344.205318 -269.22603) (xy 343.876376 -269.22603) (xy 343.875881 -269.250637)
			(xy 343.867986 -269.299214) (xy 343.852402 -269.345895) (xy 343.829531 -269.389472) (xy 343.799966 -269.428816)
			(xy 343.764473 -269.462908) (xy 343.72397 -269.490864) (xy 343.679508 -269.511962) (xy 343.632237 -269.525654)
			(xy 343.583382 -269.531586) (xy 343.534207 -269.529605) (xy 343.485988 -269.519761) (xy 343.439972 -269.502309)
			(xy 343.397351 -269.477702) (xy 343.35923 -269.446577) (xy 343.326595 -269.40974) (xy 343.300292 -269.368144)
			(xy 343.281001 -269.322868) (xy 343.269224 -269.275084) (xy 343.265264 -269.22603) (xy 342.946736 -269.22603)
			(xy 342.946224 -269.251476) (xy 342.93806 -269.30171) (xy 342.921944 -269.349984) (xy 342.898293 -269.395047)
			(xy 342.86772 -269.435733) (xy 342.831016 -269.470988) (xy 342.789132 -269.499898) (xy 342.743153 -269.521715)
			(xy 342.694269 -269.535875) (xy 342.643748 -269.542009) (xy 342.592896 -269.53996) (xy 342.543032 -269.52978)
			(xy 342.495446 -269.511733) (xy 342.451372 -269.486287) (xy 342.41195 -269.4541) (xy 342.378202 -269.416006)
			(xy 342.351001 -269.372992) (xy 342.331053 -269.326172) (xy 342.318874 -269.276758) (xy 342.314779 -269.22603)
			(xy 341.996522 -269.22603) (xy 341.996027 -269.250637) (xy 341.988132 -269.299214) (xy 341.972548 -269.345895)
			(xy 341.949677 -269.389472) (xy 341.920112 -269.428816) (xy 341.884619 -269.462908) (xy 341.844116 -269.490864)
			(xy 341.799654 -269.511962) (xy 341.752383 -269.525654) (xy 341.703528 -269.531586) (xy 341.654353 -269.529605)
			(xy 341.606134 -269.519761) (xy 341.560118 -269.502309) (xy 341.517497 -269.477702) (xy 341.479376 -269.446577)
			(xy 341.446741 -269.40974) (xy 341.420438 -269.368144) (xy 341.401147 -269.322868) (xy 341.38937 -269.275084)
			(xy 341.38541 -269.22603) (xy 341.056468 -269.22603) (xy 341.055973 -269.250637) (xy 341.048078 -269.299214)
			(xy 341.032494 -269.345895) (xy 341.009623 -269.389472) (xy 340.980058 -269.428816) (xy 340.944565 -269.462908)
			(xy 340.904062 -269.490864) (xy 340.8596 -269.511962) (xy 340.812329 -269.525654) (xy 340.763474 -269.531586)
			(xy 340.714299 -269.529605) (xy 340.66608 -269.519761) (xy 340.620064 -269.502309) (xy 340.577443 -269.477702)
			(xy 340.539322 -269.446577) (xy 340.506687 -269.40974) (xy 340.480384 -269.368144) (xy 340.461093 -269.322868)
			(xy 340.449316 -269.275084) (xy 340.445356 -269.22603) (xy 340.116414 -269.22603) (xy 340.115919 -269.250637)
			(xy 340.108024 -269.299214) (xy 340.09244 -269.345895) (xy 340.069569 -269.389472) (xy 340.040004 -269.428816)
			(xy 340.004511 -269.462908) (xy 339.964008 -269.490864) (xy 339.919546 -269.511962) (xy 339.872275 -269.525654)
			(xy 339.82342 -269.531586) (xy 339.774245 -269.529605) (xy 339.726026 -269.519761) (xy 339.68001 -269.502309)
			(xy 339.637389 -269.477702) (xy 339.599268 -269.446577) (xy 339.566633 -269.40974) (xy 339.54033 -269.368144)
			(xy 339.521039 -269.322868) (xy 339.509262 -269.275084) (xy 339.505302 -269.22603) (xy 339.186774 -269.22603)
			(xy 339.186262 -269.251476) (xy 339.178098 -269.30171) (xy 339.161982 -269.349984) (xy 339.138331 -269.395047)
			(xy 339.107758 -269.435733) (xy 339.071054 -269.470988) (xy 339.02917 -269.499898) (xy 338.983191 -269.521715)
			(xy 338.934307 -269.535875) (xy 338.883786 -269.542009) (xy 338.832934 -269.53996) (xy 338.78307 -269.52978)
			(xy 338.735484 -269.511733) (xy 338.69141 -269.486287) (xy 338.651988 -269.4541) (xy 338.61824 -269.416006)
			(xy 338.591039 -269.372992) (xy 338.571091 -269.326172) (xy 338.558912 -269.276758) (xy 338.554817 -269.22603)
			(xy 338.236306 -269.22603) (xy 338.235811 -269.250637) (xy 338.227916 -269.299214) (xy 338.212332 -269.345895)
			(xy 338.189461 -269.389472) (xy 338.159896 -269.428816) (xy 338.124403 -269.462908) (xy 338.0839 -269.490864)
			(xy 338.039438 -269.511962) (xy 337.992167 -269.525654) (xy 337.943312 -269.531586) (xy 337.894137 -269.529605)
			(xy 337.845918 -269.519761) (xy 337.799902 -269.502309) (xy 337.757281 -269.477702) (xy 337.71916 -269.446577)
			(xy 337.686525 -269.40974) (xy 337.660222 -269.368144) (xy 337.640931 -269.322868) (xy 337.629154 -269.275084)
			(xy 337.625194 -269.22603) (xy 337.296506 -269.22603) (xy 337.296011 -269.250637) (xy 337.288116 -269.299214)
			(xy 337.272532 -269.345895) (xy 337.249661 -269.389472) (xy 337.220096 -269.428816) (xy 337.184603 -269.462908)
			(xy 337.1441 -269.490864) (xy 337.099638 -269.511962) (xy 337.052367 -269.525654) (xy 337.003512 -269.531586)
			(xy 336.954337 -269.529605) (xy 336.906118 -269.519761) (xy 336.860102 -269.502309) (xy 336.817481 -269.477702)
			(xy 336.77936 -269.446577) (xy 336.746725 -269.40974) (xy 336.720422 -269.368144) (xy 336.701131 -269.322868)
			(xy 336.689354 -269.275084) (xy 336.685394 -269.22603) (xy 336.366866 -269.22603) (xy 336.366354 -269.251476)
			(xy 336.35819 -269.30171) (xy 336.342074 -269.349984) (xy 336.318423 -269.395047) (xy 336.28785 -269.435733)
			(xy 336.251146 -269.470988) (xy 336.209262 -269.499898) (xy 336.163283 -269.521715) (xy 336.114399 -269.535875)
			(xy 336.063878 -269.542009) (xy 336.013026 -269.53996) (xy 335.963162 -269.52978) (xy 335.915576 -269.511733)
			(xy 335.871502 -269.486287) (xy 335.83208 -269.4541) (xy 335.798332 -269.416006) (xy 335.771131 -269.372992)
			(xy 335.751183 -269.326172) (xy 335.739004 -269.276758) (xy 335.734909 -269.22603) (xy 335.416398 -269.22603)
			(xy 335.415903 -269.250637) (xy 335.408008 -269.299214) (xy 335.392424 -269.345895) (xy 335.369553 -269.389472)
			(xy 335.339988 -269.428816) (xy 335.304495 -269.462908) (xy 335.263992 -269.490864) (xy 335.21953 -269.511962)
			(xy 335.172259 -269.525654) (xy 335.123404 -269.531586) (xy 335.074229 -269.529605) (xy 335.02601 -269.519761)
			(xy 334.979994 -269.502309) (xy 334.937373 -269.477702) (xy 334.899252 -269.446577) (xy 334.866617 -269.40974)
			(xy 334.840314 -269.368144) (xy 334.821023 -269.322868) (xy 334.809246 -269.275084) (xy 334.805286 -269.22603)
			(xy 334.476344 -269.22603) (xy 334.475849 -269.250637) (xy 334.467954 -269.299214) (xy 334.45237 -269.345895)
			(xy 334.429499 -269.389472) (xy 334.399934 -269.428816) (xy 334.364441 -269.462908) (xy 334.323938 -269.490864)
			(xy 334.279476 -269.511962) (xy 334.232205 -269.525654) (xy 334.18335 -269.531586) (xy 334.134175 -269.529605)
			(xy 334.085956 -269.519761) (xy 334.03994 -269.502309) (xy 333.997319 -269.477702) (xy 333.959198 -269.446577)
			(xy 333.926563 -269.40974) (xy 333.90026 -269.368144) (xy 333.880969 -269.322868) (xy 333.869192 -269.275084)
			(xy 333.865232 -269.22603) (xy 333.53629 -269.22603) (xy 333.535795 -269.250637) (xy 333.5279 -269.299214)
			(xy 333.512316 -269.345895) (xy 333.489445 -269.389472) (xy 333.45988 -269.428816) (xy 333.424387 -269.462908)
			(xy 333.383884 -269.490864) (xy 333.339422 -269.511962) (xy 333.292151 -269.525654) (xy 333.243296 -269.531586)
			(xy 333.194121 -269.529605) (xy 333.145902 -269.519761) (xy 333.099886 -269.502309) (xy 333.057265 -269.477702)
			(xy 333.019144 -269.446577) (xy 332.986509 -269.40974) (xy 332.960206 -269.368144) (xy 332.940915 -269.322868)
			(xy 332.929138 -269.275084) (xy 332.925178 -269.22603) (xy 332.606904 -269.22603) (xy 332.606392 -269.251476)
			(xy 332.598228 -269.30171) (xy 332.582112 -269.349984) (xy 332.558461 -269.395047) (xy 332.527888 -269.435733)
			(xy 332.491184 -269.470988) (xy 332.4493 -269.499898) (xy 332.403321 -269.521715) (xy 332.354437 -269.535875)
			(xy 332.303916 -269.542009) (xy 332.253064 -269.53996) (xy 332.2032 -269.52978) (xy 332.155614 -269.511733)
			(xy 332.11154 -269.486287) (xy 332.072118 -269.4541) (xy 332.03837 -269.416006) (xy 332.011169 -269.372992)
			(xy 331.991221 -269.326172) (xy 331.979042 -269.276758) (xy 331.974947 -269.22603) (xy 331.656436 -269.22603)
			(xy 331.655941 -269.250637) (xy 331.648046 -269.299214) (xy 331.632462 -269.345895) (xy 331.609591 -269.389472)
			(xy 331.580026 -269.428816) (xy 331.544533 -269.462908) (xy 331.50403 -269.490864) (xy 331.459568 -269.511962)
			(xy 331.412297 -269.525654) (xy 331.363442 -269.531586) (xy 331.314267 -269.529605) (xy 331.266048 -269.519761)
			(xy 331.220032 -269.502309) (xy 331.177411 -269.477702) (xy 331.13929 -269.446577) (xy 331.106655 -269.40974)
			(xy 331.080352 -269.368144) (xy 331.061061 -269.322868) (xy 331.049284 -269.275084) (xy 331.045324 -269.22603)
			(xy 330.716382 -269.22603) (xy 330.715887 -269.250637) (xy 330.707992 -269.299214) (xy 330.692408 -269.345895)
			(xy 330.669537 -269.389472) (xy 330.639972 -269.428816) (xy 330.604479 -269.462908) (xy 330.563976 -269.490864)
			(xy 330.519514 -269.511962) (xy 330.472243 -269.525654) (xy 330.423388 -269.531586) (xy 330.374213 -269.529605)
			(xy 330.325994 -269.519761) (xy 330.279978 -269.502309) (xy 330.237357 -269.477702) (xy 330.199236 -269.446577)
			(xy 330.166601 -269.40974) (xy 330.140298 -269.368144) (xy 330.121007 -269.322868) (xy 330.10923 -269.275084)
			(xy 330.10527 -269.22603) (xy 329.786742 -269.22603) (xy 329.78623 -269.251476) (xy 329.778066 -269.30171)
			(xy 329.76195 -269.349984) (xy 329.738299 -269.395047) (xy 329.707726 -269.435733) (xy 329.671022 -269.470988)
			(xy 329.629138 -269.499898) (xy 329.583159 -269.521715) (xy 329.534275 -269.535875) (xy 329.483754 -269.542009)
			(xy 329.432902 -269.53996) (xy 329.383038 -269.52978) (xy 329.335452 -269.511733) (xy 329.291378 -269.486287)
			(xy 329.251956 -269.4541) (xy 329.218208 -269.416006) (xy 329.191007 -269.372992) (xy 329.171059 -269.326172)
			(xy 329.15888 -269.276758) (xy 329.154785 -269.22603) (xy 328.836528 -269.22603) (xy 328.836033 -269.250637)
			(xy 328.828138 -269.299214) (xy 328.812554 -269.345895) (xy 328.789683 -269.389472) (xy 328.760118 -269.428816)
			(xy 328.724625 -269.462908) (xy 328.684122 -269.490864) (xy 328.63966 -269.511962) (xy 328.592389 -269.525654)
			(xy 328.543534 -269.531586) (xy 328.494359 -269.529605) (xy 328.44614 -269.519761) (xy 328.400124 -269.502309)
			(xy 328.357503 -269.477702) (xy 328.319382 -269.446577) (xy 328.286747 -269.40974) (xy 328.260444 -269.368144)
			(xy 328.241153 -269.322868) (xy 328.229376 -269.275084) (xy 328.225416 -269.22603) (xy 327.896474 -269.22603)
			(xy 327.895979 -269.250637) (xy 327.888084 -269.299214) (xy 327.8725 -269.345895) (xy 327.849629 -269.389472)
			(xy 327.820064 -269.428816) (xy 327.784571 -269.462908) (xy 327.744068 -269.490864) (xy 327.699606 -269.511962)
			(xy 327.652335 -269.525654) (xy 327.60348 -269.531586) (xy 327.554305 -269.529605) (xy 327.506086 -269.519761)
			(xy 327.46007 -269.502309) (xy 327.417449 -269.477702) (xy 327.379328 -269.446577) (xy 327.346693 -269.40974)
			(xy 327.32039 -269.368144) (xy 327.301099 -269.322868) (xy 327.289322 -269.275084) (xy 327.285362 -269.22603)
			(xy 326.95642 -269.22603) (xy 326.955925 -269.250637) (xy 326.94803 -269.299214) (xy 326.932446 -269.345895)
			(xy 326.909575 -269.389472) (xy 326.88001 -269.428816) (xy 326.844517 -269.462908) (xy 326.804014 -269.490864)
			(xy 326.759552 -269.511962) (xy 326.712281 -269.525654) (xy 326.663426 -269.531586) (xy 326.614251 -269.529605)
			(xy 326.566032 -269.519761) (xy 326.520016 -269.502309) (xy 326.477395 -269.477702) (xy 326.439274 -269.446577)
			(xy 326.406639 -269.40974) (xy 326.380336 -269.368144) (xy 326.361045 -269.322868) (xy 326.349268 -269.275084)
			(xy 326.345308 -269.22603) (xy 310.45912 -269.22603) (xy 310.45912 -269.770098) (xy 324.74714 -269.770098)
			(xy 324.7511 -269.721044) (xy 324.762877 -269.67326) (xy 324.782168 -269.627984) (xy 324.808471 -269.586388)
			(xy 324.841106 -269.549551) (xy 324.879227 -269.518426) (xy 324.921848 -269.493819) (xy 324.967864 -269.476367)
			(xy 325.016083 -269.466523) (xy 325.065258 -269.464542) (xy 325.114113 -269.470474) (xy 325.161384 -269.484166)
			(xy 325.205846 -269.505264) (xy 325.246349 -269.53322) (xy 325.281842 -269.567312) (xy 325.311407 -269.606656)
			(xy 325.334278 -269.650233) (xy 325.349862 -269.696914) (xy 325.357757 -269.745491) (xy 325.358252 -269.770098)
			(xy 325.357757 -269.794705) (xy 325.349862 -269.843282) (xy 325.334278 -269.889963) (xy 325.311407 -269.93354)
			(xy 325.281842 -269.972884) (xy 325.246349 -270.006976) (xy 325.205846 -270.034932) (xy 325.203519 -270.036036)
			(xy 327.755262 -270.036036) (xy 327.759222 -269.986982) (xy 327.770999 -269.939198) (xy 327.79029 -269.893922)
			(xy 327.816593 -269.852326) (xy 327.849228 -269.815489) (xy 327.887349 -269.784364) (xy 327.92997 -269.759757)
			(xy 327.975986 -269.742305) (xy 328.024205 -269.732461) (xy 328.07338 -269.73048) (xy 328.122235 -269.736412)
			(xy 328.169506 -269.750104) (xy 328.213968 -269.771202) (xy 328.254471 -269.799158) (xy 328.289964 -269.83325)
			(xy 328.319529 -269.872594) (xy 328.3424 -269.916171) (xy 328.357984 -269.962852) (xy 328.365879 -270.011429)
			(xy 328.366374 -270.036036) (xy 328.684885 -270.036036) (xy 328.68898 -269.985308) (xy 328.701159 -269.935894)
			(xy 328.721107 -269.889074) (xy 328.748308 -269.84606) (xy 328.782056 -269.807966) (xy 328.821478 -269.775779)
			(xy 328.865552 -269.750333) (xy 328.913138 -269.732286) (xy 328.963002 -269.722106) (xy 329.013854 -269.720057)
			(xy 329.064375 -269.726191) (xy 329.113259 -269.740351) (xy 329.159238 -269.762168) (xy 329.201122 -269.791078)
			(xy 329.237826 -269.826333) (xy 329.268399 -269.867019) (xy 329.29205 -269.912082) (xy 329.308166 -269.960356)
			(xy 329.31633 -270.01059) (xy 329.316842 -270.036036) (xy 329.63537 -270.036036) (xy 329.63933 -269.986982)
			(xy 329.651107 -269.939198) (xy 329.670398 -269.893922) (xy 329.696701 -269.852326) (xy 329.729336 -269.815489)
			(xy 329.767457 -269.784364) (xy 329.810078 -269.759757) (xy 329.856094 -269.742305) (xy 329.904313 -269.732461)
			(xy 329.953488 -269.73048) (xy 330.002343 -269.736412) (xy 330.049614 -269.750104) (xy 330.094076 -269.771202)
			(xy 330.134579 -269.799158) (xy 330.170072 -269.83325) (xy 330.199637 -269.872594) (xy 330.222508 -269.916171)
			(xy 330.238092 -269.962852) (xy 330.245987 -270.011429) (xy 330.246482 -270.036036) (xy 330.564739 -270.036036)
			(xy 330.568834 -269.985308) (xy 330.581013 -269.935894) (xy 330.600961 -269.889074) (xy 330.628162 -269.84606)
			(xy 330.66191 -269.807966) (xy 330.701332 -269.775779) (xy 330.745406 -269.750333) (xy 330.792992 -269.732286)
			(xy 330.842856 -269.722106) (xy 330.893708 -269.720057) (xy 330.944229 -269.726191) (xy 330.993113 -269.740351)
			(xy 331.039092 -269.762168) (xy 331.080976 -269.791078) (xy 331.11768 -269.826333) (xy 331.148253 -269.867019)
			(xy 331.171904 -269.912082) (xy 331.18802 -269.960356) (xy 331.196184 -270.01059) (xy 331.196696 -270.036036)
			(xy 331.515224 -270.036036) (xy 331.519184 -269.986982) (xy 331.530961 -269.939198) (xy 331.550252 -269.893922)
			(xy 331.576555 -269.852326) (xy 331.60919 -269.815489) (xy 331.647311 -269.784364) (xy 331.689932 -269.759757)
			(xy 331.735948 -269.742305) (xy 331.784167 -269.732461) (xy 331.833342 -269.73048) (xy 331.882197 -269.736412)
			(xy 331.929468 -269.750104) (xy 331.97393 -269.771202) (xy 332.014433 -269.799158) (xy 332.049926 -269.83325)
			(xy 332.079491 -269.872594) (xy 332.102362 -269.916171) (xy 332.117946 -269.962852) (xy 332.125841 -270.011429)
			(xy 332.126336 -270.036036) (xy 332.444847 -270.036036) (xy 332.448942 -269.985308) (xy 332.461121 -269.935894)
			(xy 332.481069 -269.889074) (xy 332.50827 -269.84606) (xy 332.542018 -269.807966) (xy 332.58144 -269.775779)
			(xy 332.625514 -269.750333) (xy 332.6731 -269.732286) (xy 332.722964 -269.722106) (xy 332.773816 -269.720057)
			(xy 332.824337 -269.726191) (xy 332.873221 -269.740351) (xy 332.9192 -269.762168) (xy 332.961084 -269.791078)
			(xy 332.997788 -269.826333) (xy 333.028361 -269.867019) (xy 333.052012 -269.912082) (xy 333.068128 -269.960356)
			(xy 333.076292 -270.01059) (xy 333.076804 -270.036036) (xy 333.384901 -270.036036) (xy 333.388996 -269.985308)
			(xy 333.401175 -269.935894) (xy 333.421123 -269.889074) (xy 333.448324 -269.84606) (xy 333.482072 -269.807966)
			(xy 333.521494 -269.775779) (xy 333.565568 -269.750333) (xy 333.613154 -269.732286) (xy 333.663018 -269.722106)
			(xy 333.71387 -269.720057) (xy 333.764391 -269.726191) (xy 333.813275 -269.740351) (xy 333.859254 -269.762168)
			(xy 333.901138 -269.791078) (xy 333.937842 -269.826333) (xy 333.968415 -269.867019) (xy 333.992066 -269.912082)
			(xy 334.008182 -269.960356) (xy 334.016346 -270.01059) (xy 334.016858 -270.036036) (xy 334.335386 -270.036036)
			(xy 334.339346 -269.986982) (xy 334.351123 -269.939198) (xy 334.370414 -269.893922) (xy 334.396717 -269.852326)
			(xy 334.429352 -269.815489) (xy 334.467473 -269.784364) (xy 334.510094 -269.759757) (xy 334.55611 -269.742305)
			(xy 334.604329 -269.732461) (xy 334.653504 -269.73048) (xy 334.702359 -269.736412) (xy 334.74963 -269.750104)
			(xy 334.794092 -269.771202) (xy 334.834595 -269.799158) (xy 334.870088 -269.83325) (xy 334.899653 -269.872594)
			(xy 334.922524 -269.916171) (xy 334.938108 -269.962852) (xy 334.946003 -270.011429) (xy 334.946498 -270.036036)
			(xy 335.264755 -270.036036) (xy 335.26885 -269.985308) (xy 335.281029 -269.935894) (xy 335.300977 -269.889074)
			(xy 335.328178 -269.84606) (xy 335.361926 -269.807966) (xy 335.401348 -269.775779) (xy 335.445422 -269.750333)
			(xy 335.493008 -269.732286) (xy 335.542872 -269.722106) (xy 335.593724 -269.720057) (xy 335.644245 -269.726191)
			(xy 335.693129 -269.740351) (xy 335.739108 -269.762168) (xy 335.780992 -269.791078) (xy 335.817696 -269.826333)
			(xy 335.848269 -269.867019) (xy 335.87192 -269.912082) (xy 335.888036 -269.960356) (xy 335.8962 -270.01059)
			(xy 335.896712 -270.036036) (xy 336.21524 -270.036036) (xy 336.2192 -269.986982) (xy 336.230977 -269.939198)
			(xy 336.250268 -269.893922) (xy 336.276571 -269.852326) (xy 336.309206 -269.815489) (xy 336.347327 -269.784364)
			(xy 336.389948 -269.759757) (xy 336.435964 -269.742305) (xy 336.484183 -269.732461) (xy 336.533358 -269.73048)
			(xy 336.582213 -269.736412) (xy 336.629484 -269.750104) (xy 336.673946 -269.771202) (xy 336.714449 -269.799158)
			(xy 336.749942 -269.83325) (xy 336.779507 -269.872594) (xy 336.802378 -269.916171) (xy 336.817962 -269.962852)
			(xy 336.825857 -270.011429) (xy 336.826352 -270.036036) (xy 337.144863 -270.036036) (xy 337.148958 -269.985308)
			(xy 337.161137 -269.935894) (xy 337.181085 -269.889074) (xy 337.208286 -269.84606) (xy 337.242034 -269.807966)
			(xy 337.281456 -269.775779) (xy 337.32553 -269.750333) (xy 337.373116 -269.732286) (xy 337.42298 -269.722106)
			(xy 337.473832 -269.720057) (xy 337.524353 -269.726191) (xy 337.573237 -269.740351) (xy 337.619216 -269.762168)
			(xy 337.6611 -269.791078) (xy 337.697804 -269.826333) (xy 337.728377 -269.867019) (xy 337.752028 -269.912082)
			(xy 337.768144 -269.960356) (xy 337.776308 -270.01059) (xy 337.77682 -270.036036) (xy 338.095348 -270.036036)
			(xy 338.099308 -269.986982) (xy 338.111085 -269.939198) (xy 338.130376 -269.893922) (xy 338.156679 -269.852326)
			(xy 338.189314 -269.815489) (xy 338.227435 -269.784364) (xy 338.270056 -269.759757) (xy 338.316072 -269.742305)
			(xy 338.364291 -269.732461) (xy 338.413466 -269.73048) (xy 338.462321 -269.736412) (xy 338.509592 -269.750104)
			(xy 338.554054 -269.771202) (xy 338.594557 -269.799158) (xy 338.63005 -269.83325) (xy 338.659615 -269.872594)
			(xy 338.682486 -269.916171) (xy 338.69807 -269.962852) (xy 338.705965 -270.011429) (xy 338.70646 -270.036036)
			(xy 339.024971 -270.036036) (xy 339.029066 -269.985308) (xy 339.041245 -269.935894) (xy 339.061193 -269.889074)
			(xy 339.088394 -269.84606) (xy 339.122142 -269.807966) (xy 339.161564 -269.775779) (xy 339.205638 -269.750333)
			(xy 339.253224 -269.732286) (xy 339.303088 -269.722106) (xy 339.35394 -269.720057) (xy 339.404461 -269.726191)
			(xy 339.453345 -269.740351) (xy 339.499324 -269.762168) (xy 339.541208 -269.791078) (xy 339.577912 -269.826333)
			(xy 339.608485 -269.867019) (xy 339.632136 -269.912082) (xy 339.648252 -269.960356) (xy 339.656416 -270.01059)
			(xy 339.656928 -270.036036) (xy 339.964771 -270.036036) (xy 339.968866 -269.985308) (xy 339.981045 -269.935894)
			(xy 340.000993 -269.889074) (xy 340.028194 -269.84606) (xy 340.061942 -269.807966) (xy 340.101364 -269.775779)
			(xy 340.145438 -269.750333) (xy 340.193024 -269.732286) (xy 340.242888 -269.722106) (xy 340.29374 -269.720057)
			(xy 340.344261 -269.726191) (xy 340.393145 -269.740351) (xy 340.439124 -269.762168) (xy 340.481008 -269.791078)
			(xy 340.517712 -269.826333) (xy 340.548285 -269.867019) (xy 340.571936 -269.912082) (xy 340.588052 -269.960356)
			(xy 340.596216 -270.01059) (xy 340.596728 -270.036036) (xy 340.915256 -270.036036) (xy 340.919216 -269.986982)
			(xy 340.930993 -269.939198) (xy 340.950284 -269.893922) (xy 340.976587 -269.852326) (xy 341.009222 -269.815489)
			(xy 341.047343 -269.784364) (xy 341.089964 -269.759757) (xy 341.13598 -269.742305) (xy 341.184199 -269.732461)
			(xy 341.233374 -269.73048) (xy 341.282229 -269.736412) (xy 341.3295 -269.750104) (xy 341.373962 -269.771202)
			(xy 341.414465 -269.799158) (xy 341.449958 -269.83325) (xy 341.479523 -269.872594) (xy 341.502394 -269.916171)
			(xy 341.517978 -269.962852) (xy 341.525873 -270.011429) (xy 341.526368 -270.036036) (xy 341.844879 -270.036036)
			(xy 341.848974 -269.985308) (xy 341.861153 -269.935894) (xy 341.881101 -269.889074) (xy 341.908302 -269.84606)
			(xy 341.94205 -269.807966) (xy 341.981472 -269.775779) (xy 342.025546 -269.750333) (xy 342.073132 -269.732286)
			(xy 342.122996 -269.722106) (xy 342.173848 -269.720057) (xy 342.224369 -269.726191) (xy 342.273253 -269.740351)
			(xy 342.319232 -269.762168) (xy 342.361116 -269.791078) (xy 342.39782 -269.826333) (xy 342.428393 -269.867019)
			(xy 342.452044 -269.912082) (xy 342.46816 -269.960356) (xy 342.476324 -270.01059) (xy 342.476836 -270.036036)
			(xy 342.795364 -270.036036) (xy 342.799324 -269.986982) (xy 342.811101 -269.939198) (xy 342.830392 -269.893922)
			(xy 342.856695 -269.852326) (xy 342.88933 -269.815489) (xy 342.927451 -269.784364) (xy 342.970072 -269.759757)
			(xy 343.016088 -269.742305) (xy 343.064307 -269.732461) (xy 343.113482 -269.73048) (xy 343.162337 -269.736412)
			(xy 343.209608 -269.750104) (xy 343.25407 -269.771202) (xy 343.294573 -269.799158) (xy 343.330066 -269.83325)
			(xy 343.359631 -269.872594) (xy 343.382502 -269.916171) (xy 343.398086 -269.962852) (xy 343.405981 -270.011429)
			(xy 343.406476 -270.036036) (xy 343.724987 -270.036036) (xy 343.729082 -269.985308) (xy 343.741261 -269.935894)
			(xy 343.761209 -269.889074) (xy 343.78841 -269.84606) (xy 343.822158 -269.807966) (xy 343.86158 -269.775779)
			(xy 343.905654 -269.750333) (xy 343.95324 -269.732286) (xy 344.003104 -269.722106) (xy 344.053956 -269.720057)
			(xy 344.104477 -269.726191) (xy 344.153361 -269.740351) (xy 344.19934 -269.762168) (xy 344.241224 -269.791078)
			(xy 344.277928 -269.826333) (xy 344.308501 -269.867019) (xy 344.332152 -269.912082) (xy 344.348268 -269.960356)
			(xy 344.356432 -270.01059) (xy 344.356944 -270.036036) (xy 344.356432 -270.061482) (xy 344.348268 -270.111716)
			(xy 344.332152 -270.15999) (xy 344.308501 -270.205053) (xy 344.277928 -270.245739) (xy 344.241224 -270.280994)
			(xy 344.19934 -270.309904) (xy 344.153361 -270.331721) (xy 344.104477 -270.345881) (xy 344.053956 -270.352015)
			(xy 344.003104 -270.349966) (xy 343.95324 -270.339786) (xy 343.905654 -270.321739) (xy 343.86158 -270.296293)
			(xy 343.822158 -270.264106) (xy 343.78841 -270.226012) (xy 343.761209 -270.182998) (xy 343.741261 -270.136178)
			(xy 343.729082 -270.086764) (xy 343.724987 -270.036036) (xy 343.406476 -270.036036) (xy 343.405981 -270.060643)
			(xy 343.398086 -270.10922) (xy 343.382502 -270.155901) (xy 343.359631 -270.199478) (xy 343.330066 -270.238822)
			(xy 343.294573 -270.272914) (xy 343.25407 -270.30087) (xy 343.209608 -270.321968) (xy 343.162337 -270.33566)
			(xy 343.113482 -270.341592) (xy 343.064307 -270.339611) (xy 343.016088 -270.329767) (xy 342.970072 -270.312315)
			(xy 342.927451 -270.287708) (xy 342.88933 -270.256583) (xy 342.856695 -270.219746) (xy 342.830392 -270.17815)
			(xy 342.811101 -270.132874) (xy 342.799324 -270.08509) (xy 342.795364 -270.036036) (xy 342.476836 -270.036036)
			(xy 342.476324 -270.061482) (xy 342.46816 -270.111716) (xy 342.452044 -270.15999) (xy 342.428393 -270.205053)
			(xy 342.39782 -270.245739) (xy 342.361116 -270.280994) (xy 342.319232 -270.309904) (xy 342.273253 -270.331721)
			(xy 342.224369 -270.345881) (xy 342.173848 -270.352015) (xy 342.122996 -270.349966) (xy 342.073132 -270.339786)
			(xy 342.025546 -270.321739) (xy 341.981472 -270.296293) (xy 341.94205 -270.264106) (xy 341.908302 -270.226012)
			(xy 341.881101 -270.182998) (xy 341.861153 -270.136178) (xy 341.848974 -270.086764) (xy 341.844879 -270.036036)
			(xy 341.526368 -270.036036) (xy 341.525873 -270.060643) (xy 341.517978 -270.10922) (xy 341.502394 -270.155901)
			(xy 341.479523 -270.199478) (xy 341.449958 -270.238822) (xy 341.414465 -270.272914) (xy 341.373962 -270.30087)
			(xy 341.3295 -270.321968) (xy 341.282229 -270.33566) (xy 341.233374 -270.341592) (xy 341.184199 -270.339611)
			(xy 341.13598 -270.329767) (xy 341.089964 -270.312315) (xy 341.047343 -270.287708) (xy 341.009222 -270.256583)
			(xy 340.976587 -270.219746) (xy 340.950284 -270.17815) (xy 340.930993 -270.132874) (xy 340.919216 -270.08509)
			(xy 340.915256 -270.036036) (xy 340.596728 -270.036036) (xy 340.596216 -270.061482) (xy 340.588052 -270.111716)
			(xy 340.571936 -270.15999) (xy 340.548285 -270.205053) (xy 340.517712 -270.245739) (xy 340.481008 -270.280994)
			(xy 340.439124 -270.309904) (xy 340.393145 -270.331721) (xy 340.344261 -270.345881) (xy 340.29374 -270.352015)
			(xy 340.242888 -270.349966) (xy 340.193024 -270.339786) (xy 340.145438 -270.321739) (xy 340.101364 -270.296293)
			(xy 340.061942 -270.264106) (xy 340.028194 -270.226012) (xy 340.000993 -270.182998) (xy 339.981045 -270.136178)
			(xy 339.968866 -270.086764) (xy 339.964771 -270.036036) (xy 339.656928 -270.036036) (xy 339.656416 -270.061482)
			(xy 339.648252 -270.111716) (xy 339.632136 -270.15999) (xy 339.608485 -270.205053) (xy 339.577912 -270.245739)
			(xy 339.541208 -270.280994) (xy 339.499324 -270.309904) (xy 339.453345 -270.331721) (xy 339.404461 -270.345881)
			(xy 339.35394 -270.352015) (xy 339.303088 -270.349966) (xy 339.253224 -270.339786) (xy 339.205638 -270.321739)
			(xy 339.161564 -270.296293) (xy 339.122142 -270.264106) (xy 339.088394 -270.226012) (xy 339.061193 -270.182998)
			(xy 339.041245 -270.136178) (xy 339.029066 -270.086764) (xy 339.024971 -270.036036) (xy 338.70646 -270.036036)
			(xy 338.705965 -270.060643) (xy 338.69807 -270.10922) (xy 338.682486 -270.155901) (xy 338.659615 -270.199478)
			(xy 338.63005 -270.238822) (xy 338.594557 -270.272914) (xy 338.554054 -270.30087) (xy 338.509592 -270.321968)
			(xy 338.462321 -270.33566) (xy 338.413466 -270.341592) (xy 338.364291 -270.339611) (xy 338.316072 -270.329767)
			(xy 338.270056 -270.312315) (xy 338.227435 -270.287708) (xy 338.189314 -270.256583) (xy 338.156679 -270.219746)
			(xy 338.130376 -270.17815) (xy 338.111085 -270.132874) (xy 338.099308 -270.08509) (xy 338.095348 -270.036036)
			(xy 337.77682 -270.036036) (xy 337.776308 -270.061482) (xy 337.768144 -270.111716) (xy 337.752028 -270.15999)
			(xy 337.728377 -270.205053) (xy 337.697804 -270.245739) (xy 337.6611 -270.280994) (xy 337.619216 -270.309904)
			(xy 337.573237 -270.331721) (xy 337.524353 -270.345881) (xy 337.473832 -270.352015) (xy 337.42298 -270.349966)
			(xy 337.373116 -270.339786) (xy 337.32553 -270.321739) (xy 337.281456 -270.296293) (xy 337.242034 -270.264106)
			(xy 337.208286 -270.226012) (xy 337.181085 -270.182998) (xy 337.161137 -270.136178) (xy 337.148958 -270.086764)
			(xy 337.144863 -270.036036) (xy 336.826352 -270.036036) (xy 336.825857 -270.060643) (xy 336.817962 -270.10922)
			(xy 336.802378 -270.155901) (xy 336.779507 -270.199478) (xy 336.749942 -270.238822) (xy 336.714449 -270.272914)
			(xy 336.673946 -270.30087) (xy 336.629484 -270.321968) (xy 336.582213 -270.33566) (xy 336.533358 -270.341592)
			(xy 336.484183 -270.339611) (xy 336.435964 -270.329767) (xy 336.389948 -270.312315) (xy 336.347327 -270.287708)
			(xy 336.309206 -270.256583) (xy 336.276571 -270.219746) (xy 336.250268 -270.17815) (xy 336.230977 -270.132874)
			(xy 336.2192 -270.08509) (xy 336.21524 -270.036036) (xy 335.896712 -270.036036) (xy 335.8962 -270.061482)
			(xy 335.888036 -270.111716) (xy 335.87192 -270.15999) (xy 335.848269 -270.205053) (xy 335.817696 -270.245739)
			(xy 335.780992 -270.280994) (xy 335.739108 -270.309904) (xy 335.693129 -270.331721) (xy 335.644245 -270.345881)
			(xy 335.593724 -270.352015) (xy 335.542872 -270.349966) (xy 335.493008 -270.339786) (xy 335.445422 -270.321739)
			(xy 335.401348 -270.296293) (xy 335.361926 -270.264106) (xy 335.328178 -270.226012) (xy 335.300977 -270.182998)
			(xy 335.281029 -270.136178) (xy 335.26885 -270.086764) (xy 335.264755 -270.036036) (xy 334.946498 -270.036036)
			(xy 334.946003 -270.060643) (xy 334.938108 -270.10922) (xy 334.922524 -270.155901) (xy 334.899653 -270.199478)
			(xy 334.870088 -270.238822) (xy 334.834595 -270.272914) (xy 334.794092 -270.30087) (xy 334.74963 -270.321968)
			(xy 334.702359 -270.33566) (xy 334.653504 -270.341592) (xy 334.604329 -270.339611) (xy 334.55611 -270.329767)
			(xy 334.510094 -270.312315) (xy 334.467473 -270.287708) (xy 334.429352 -270.256583) (xy 334.396717 -270.219746)
			(xy 334.370414 -270.17815) (xy 334.351123 -270.132874) (xy 334.339346 -270.08509) (xy 334.335386 -270.036036)
			(xy 334.016858 -270.036036) (xy 334.016346 -270.061482) (xy 334.008182 -270.111716) (xy 333.992066 -270.15999)
			(xy 333.968415 -270.205053) (xy 333.937842 -270.245739) (xy 333.901138 -270.280994) (xy 333.859254 -270.309904)
			(xy 333.813275 -270.331721) (xy 333.764391 -270.345881) (xy 333.71387 -270.352015) (xy 333.663018 -270.349966)
			(xy 333.613154 -270.339786) (xy 333.565568 -270.321739) (xy 333.521494 -270.296293) (xy 333.482072 -270.264106)
			(xy 333.448324 -270.226012) (xy 333.421123 -270.182998) (xy 333.401175 -270.136178) (xy 333.388996 -270.086764)
			(xy 333.384901 -270.036036) (xy 333.076804 -270.036036) (xy 333.076292 -270.061482) (xy 333.068128 -270.111716)
			(xy 333.052012 -270.15999) (xy 333.028361 -270.205053) (xy 332.997788 -270.245739) (xy 332.961084 -270.280994)
			(xy 332.9192 -270.309904) (xy 332.873221 -270.331721) (xy 332.824337 -270.345881) (xy 332.773816 -270.352015)
			(xy 332.722964 -270.349966) (xy 332.6731 -270.339786) (xy 332.625514 -270.321739) (xy 332.58144 -270.296293)
			(xy 332.542018 -270.264106) (xy 332.50827 -270.226012) (xy 332.481069 -270.182998) (xy 332.461121 -270.136178)
			(xy 332.448942 -270.086764) (xy 332.444847 -270.036036) (xy 332.126336 -270.036036) (xy 332.125841 -270.060643)
			(xy 332.117946 -270.10922) (xy 332.102362 -270.155901) (xy 332.079491 -270.199478) (xy 332.049926 -270.238822)
			(xy 332.014433 -270.272914) (xy 331.97393 -270.30087) (xy 331.929468 -270.321968) (xy 331.882197 -270.33566)
			(xy 331.833342 -270.341592) (xy 331.784167 -270.339611) (xy 331.735948 -270.329767) (xy 331.689932 -270.312315)
			(xy 331.647311 -270.287708) (xy 331.60919 -270.256583) (xy 331.576555 -270.219746) (xy 331.550252 -270.17815)
			(xy 331.530961 -270.132874) (xy 331.519184 -270.08509) (xy 331.515224 -270.036036) (xy 331.196696 -270.036036)
			(xy 331.196184 -270.061482) (xy 331.18802 -270.111716) (xy 331.171904 -270.15999) (xy 331.148253 -270.205053)
			(xy 331.11768 -270.245739) (xy 331.080976 -270.280994) (xy 331.039092 -270.309904) (xy 330.993113 -270.331721)
			(xy 330.944229 -270.345881) (xy 330.893708 -270.352015) (xy 330.842856 -270.349966) (xy 330.792992 -270.339786)
			(xy 330.745406 -270.321739) (xy 330.701332 -270.296293) (xy 330.66191 -270.264106) (xy 330.628162 -270.226012)
			(xy 330.600961 -270.182998) (xy 330.581013 -270.136178) (xy 330.568834 -270.086764) (xy 330.564739 -270.036036)
			(xy 330.246482 -270.036036) (xy 330.245987 -270.060643) (xy 330.238092 -270.10922) (xy 330.222508 -270.155901)
			(xy 330.199637 -270.199478) (xy 330.170072 -270.238822) (xy 330.134579 -270.272914) (xy 330.094076 -270.30087)
			(xy 330.049614 -270.321968) (xy 330.002343 -270.33566) (xy 329.953488 -270.341592) (xy 329.904313 -270.339611)
			(xy 329.856094 -270.329767) (xy 329.810078 -270.312315) (xy 329.767457 -270.287708) (xy 329.729336 -270.256583)
			(xy 329.696701 -270.219746) (xy 329.670398 -270.17815) (xy 329.651107 -270.132874) (xy 329.63933 -270.08509)
			(xy 329.63537 -270.036036) (xy 329.316842 -270.036036) (xy 329.31633 -270.061482) (xy 329.308166 -270.111716)
			(xy 329.29205 -270.15999) (xy 329.268399 -270.205053) (xy 329.237826 -270.245739) (xy 329.201122 -270.280994)
			(xy 329.159238 -270.309904) (xy 329.113259 -270.331721) (xy 329.064375 -270.345881) (xy 329.013854 -270.352015)
			(xy 328.963002 -270.349966) (xy 328.913138 -270.339786) (xy 328.865552 -270.321739) (xy 328.821478 -270.296293)
			(xy 328.782056 -270.264106) (xy 328.748308 -270.226012) (xy 328.721107 -270.182998) (xy 328.701159 -270.136178)
			(xy 328.68898 -270.086764) (xy 328.684885 -270.036036) (xy 328.366374 -270.036036) (xy 328.365879 -270.060643)
			(xy 328.357984 -270.10922) (xy 328.3424 -270.155901) (xy 328.319529 -270.199478) (xy 328.289964 -270.238822)
			(xy 328.254471 -270.272914) (xy 328.213968 -270.30087) (xy 328.169506 -270.321968) (xy 328.122235 -270.33566)
			(xy 328.07338 -270.341592) (xy 328.024205 -270.339611) (xy 327.975986 -270.329767) (xy 327.92997 -270.312315)
			(xy 327.887349 -270.287708) (xy 327.849228 -270.256583) (xy 327.816593 -270.219746) (xy 327.79029 -270.17815)
			(xy 327.770999 -270.132874) (xy 327.759222 -270.08509) (xy 327.755262 -270.036036) (xy 325.203519 -270.036036)
			(xy 325.161384 -270.05603) (xy 325.114113 -270.069722) (xy 325.065258 -270.075654) (xy 325.016083 -270.073673)
			(xy 324.967864 -270.063829) (xy 324.921848 -270.046377) (xy 324.879227 -270.02177) (xy 324.841106 -269.990645)
			(xy 324.808471 -269.953808) (xy 324.782168 -269.912212) (xy 324.762877 -269.866936) (xy 324.7511 -269.819152)
			(xy 324.74714 -269.770098) (xy 310.45912 -269.770098) (xy 310.45912 -270.846042) (xy 326.345308 -270.846042)
			(xy 326.349268 -270.796988) (xy 326.361045 -270.749204) (xy 326.380336 -270.703928) (xy 326.406639 -270.662332)
			(xy 326.439274 -270.625495) (xy 326.477395 -270.59437) (xy 326.520016 -270.569763) (xy 326.566032 -270.552311)
			(xy 326.614251 -270.542467) (xy 326.663426 -270.540486) (xy 326.712281 -270.546418) (xy 326.759552 -270.56011)
			(xy 326.804014 -270.581208) (xy 326.844517 -270.609164) (xy 326.88001 -270.643256) (xy 326.909575 -270.6826)
			(xy 326.932446 -270.726177) (xy 326.94803 -270.772858) (xy 326.955925 -270.821435) (xy 326.95642 -270.846042)
			(xy 329.154785 -270.846042) (xy 329.15888 -270.795314) (xy 329.171059 -270.7459) (xy 329.191007 -270.69908)
			(xy 329.218208 -270.656066) (xy 329.251956 -270.617972) (xy 329.291378 -270.585785) (xy 329.335452 -270.560339)
			(xy 329.383038 -270.542292) (xy 329.432902 -270.532112) (xy 329.483754 -270.530063) (xy 329.534275 -270.536197)
			(xy 329.583159 -270.550357) (xy 329.629138 -270.572174) (xy 329.671022 -270.601084) (xy 329.707726 -270.636339)
			(xy 329.738299 -270.677025) (xy 329.76195 -270.722088) (xy 329.778066 -270.770362) (xy 329.78623 -270.820596)
			(xy 329.786742 -270.846042) (xy 330.094839 -270.846042) (xy 330.098934 -270.795314) (xy 330.111113 -270.7459)
			(xy 330.131061 -270.69908) (xy 330.158262 -270.656066) (xy 330.19201 -270.617972) (xy 330.231432 -270.585785)
			(xy 330.275506 -270.560339) (xy 330.323092 -270.542292) (xy 330.372956 -270.532112) (xy 330.423808 -270.530063)
			(xy 330.474329 -270.536197) (xy 330.523213 -270.550357) (xy 330.569192 -270.572174) (xy 330.611076 -270.601084)
			(xy 330.64778 -270.636339) (xy 330.678353 -270.677025) (xy 330.702004 -270.722088) (xy 330.71812 -270.770362)
			(xy 330.726284 -270.820596) (xy 330.726796 -270.846042) (xy 331.045324 -270.846042) (xy 331.049284 -270.796988)
			(xy 331.061061 -270.749204) (xy 331.080352 -270.703928) (xy 331.106655 -270.662332) (xy 331.13929 -270.625495)
			(xy 331.177411 -270.59437) (xy 331.220032 -270.569763) (xy 331.266048 -270.552311) (xy 331.314267 -270.542467)
			(xy 331.363442 -270.540486) (xy 331.412297 -270.546418) (xy 331.459568 -270.56011) (xy 331.50403 -270.581208)
			(xy 331.544533 -270.609164) (xy 331.580026 -270.643256) (xy 331.609591 -270.6826) (xy 331.632462 -270.726177)
			(xy 331.648046 -270.772858) (xy 331.655941 -270.821435) (xy 331.656436 -270.846042) (xy 331.974947 -270.846042)
			(xy 331.979042 -270.795314) (xy 331.991221 -270.7459) (xy 332.011169 -270.69908) (xy 332.03837 -270.656066)
			(xy 332.072118 -270.617972) (xy 332.11154 -270.585785) (xy 332.155614 -270.560339) (xy 332.2032 -270.542292)
			(xy 332.253064 -270.532112) (xy 332.303916 -270.530063) (xy 332.354437 -270.536197) (xy 332.403321 -270.550357)
			(xy 332.4493 -270.572174) (xy 332.491184 -270.601084) (xy 332.527888 -270.636339) (xy 332.558461 -270.677025)
			(xy 332.582112 -270.722088) (xy 332.598228 -270.770362) (xy 332.606392 -270.820596) (xy 332.606904 -270.846042)
			(xy 332.925178 -270.846042) (xy 332.929138 -270.796988) (xy 332.940915 -270.749204) (xy 332.960206 -270.703928)
			(xy 332.986509 -270.662332) (xy 333.019144 -270.625495) (xy 333.057265 -270.59437) (xy 333.099886 -270.569763)
			(xy 333.145902 -270.552311) (xy 333.194121 -270.542467) (xy 333.243296 -270.540486) (xy 333.292151 -270.546418)
			(xy 333.339422 -270.56011) (xy 333.383884 -270.581208) (xy 333.424387 -270.609164) (xy 333.45988 -270.643256)
			(xy 333.489445 -270.6826) (xy 333.512316 -270.726177) (xy 333.5279 -270.772858) (xy 333.535795 -270.821435)
			(xy 333.53629 -270.846042) (xy 333.854801 -270.846042) (xy 333.858896 -270.795314) (xy 333.871075 -270.7459)
			(xy 333.891023 -270.69908) (xy 333.918224 -270.656066) (xy 333.951972 -270.617972) (xy 333.991394 -270.585785)
			(xy 334.035468 -270.560339) (xy 334.083054 -270.542292) (xy 334.132918 -270.532112) (xy 334.18377 -270.530063)
			(xy 334.234291 -270.536197) (xy 334.283175 -270.550357) (xy 334.329154 -270.572174) (xy 334.371038 -270.601084)
			(xy 334.407742 -270.636339) (xy 334.438315 -270.677025) (xy 334.461966 -270.722088) (xy 334.478082 -270.770362)
			(xy 334.486246 -270.820596) (xy 334.486758 -270.846042) (xy 335.734909 -270.846042) (xy 335.739004 -270.795314)
			(xy 335.751183 -270.7459) (xy 335.771131 -270.69908) (xy 335.798332 -270.656066) (xy 335.83208 -270.617972)
			(xy 335.871502 -270.585785) (xy 335.915576 -270.560339) (xy 335.963162 -270.542292) (xy 336.013026 -270.532112)
			(xy 336.063878 -270.530063) (xy 336.114399 -270.536197) (xy 336.163283 -270.550357) (xy 336.209262 -270.572174)
			(xy 336.251146 -270.601084) (xy 336.28785 -270.636339) (xy 336.318423 -270.677025) (xy 336.342074 -270.722088)
			(xy 336.35819 -270.770362) (xy 336.366354 -270.820596) (xy 336.366866 -270.846042) (xy 336.674963 -270.846042)
			(xy 336.679058 -270.795314) (xy 336.691237 -270.7459) (xy 336.711185 -270.69908) (xy 336.738386 -270.656066)
			(xy 336.772134 -270.617972) (xy 336.811556 -270.585785) (xy 336.85563 -270.560339) (xy 336.903216 -270.542292)
			(xy 336.95308 -270.532112) (xy 337.003932 -270.530063) (xy 337.054453 -270.536197) (xy 337.103337 -270.550357)
			(xy 337.149316 -270.572174) (xy 337.1912 -270.601084) (xy 337.227904 -270.636339) (xy 337.258477 -270.677025)
			(xy 337.282128 -270.722088) (xy 337.298244 -270.770362) (xy 337.306408 -270.820596) (xy 337.30692 -270.846042)
			(xy 337.625194 -270.846042) (xy 337.629154 -270.796988) (xy 337.640931 -270.749204) (xy 337.660222 -270.703928)
			(xy 337.686525 -270.662332) (xy 337.71916 -270.625495) (xy 337.757281 -270.59437) (xy 337.799902 -270.569763)
			(xy 337.845918 -270.552311) (xy 337.894137 -270.542467) (xy 337.943312 -270.540486) (xy 337.992167 -270.546418)
			(xy 338.039438 -270.56011) (xy 338.0839 -270.581208) (xy 338.124403 -270.609164) (xy 338.159896 -270.643256)
			(xy 338.189461 -270.6826) (xy 338.212332 -270.726177) (xy 338.227916 -270.772858) (xy 338.235811 -270.821435)
			(xy 338.236306 -270.846042) (xy 338.554817 -270.846042) (xy 338.558912 -270.795314) (xy 338.571091 -270.7459)
			(xy 338.591039 -270.69908) (xy 338.61824 -270.656066) (xy 338.651988 -270.617972) (xy 338.69141 -270.585785)
			(xy 338.735484 -270.560339) (xy 338.78307 -270.542292) (xy 338.832934 -270.532112) (xy 338.883786 -270.530063)
			(xy 338.934307 -270.536197) (xy 338.983191 -270.550357) (xy 339.02917 -270.572174) (xy 339.071054 -270.601084)
			(xy 339.107758 -270.636339) (xy 339.138331 -270.677025) (xy 339.161982 -270.722088) (xy 339.178098 -270.770362)
			(xy 339.186262 -270.820596) (xy 339.186774 -270.846042) (xy 339.505302 -270.846042) (xy 339.509262 -270.796988)
			(xy 339.521039 -270.749204) (xy 339.54033 -270.703928) (xy 339.566633 -270.662332) (xy 339.599268 -270.625495)
			(xy 339.637389 -270.59437) (xy 339.68001 -270.569763) (xy 339.726026 -270.552311) (xy 339.774245 -270.542467)
			(xy 339.82342 -270.540486) (xy 339.872275 -270.546418) (xy 339.919546 -270.56011) (xy 339.964008 -270.581208)
			(xy 340.004511 -270.609164) (xy 340.040004 -270.643256) (xy 340.069569 -270.6826) (xy 340.09244 -270.726177)
			(xy 340.108024 -270.772858) (xy 340.115919 -270.821435) (xy 340.116414 -270.846042) (xy 340.434925 -270.846042)
			(xy 340.43902 -270.795314) (xy 340.451199 -270.7459) (xy 340.471147 -270.69908) (xy 340.498348 -270.656066)
			(xy 340.532096 -270.617972) (xy 340.571518 -270.585785) (xy 340.615592 -270.560339) (xy 340.663178 -270.542292)
			(xy 340.713042 -270.532112) (xy 340.763894 -270.530063) (xy 340.814415 -270.536197) (xy 340.863299 -270.550357)
			(xy 340.909278 -270.572174) (xy 340.951162 -270.601084) (xy 340.987866 -270.636339) (xy 341.018439 -270.677025)
			(xy 341.04209 -270.722088) (xy 341.058206 -270.770362) (xy 341.06637 -270.820596) (xy 341.066882 -270.846042)
			(xy 342.314779 -270.846042) (xy 342.318874 -270.795314) (xy 342.331053 -270.7459) (xy 342.351001 -270.69908)
			(xy 342.378202 -270.656066) (xy 342.41195 -270.617972) (xy 342.451372 -270.585785) (xy 342.495446 -270.560339)
			(xy 342.543032 -270.542292) (xy 342.592896 -270.532112) (xy 342.643748 -270.530063) (xy 342.694269 -270.536197)
			(xy 342.743153 -270.550357) (xy 342.789132 -270.572174) (xy 342.831016 -270.601084) (xy 342.86772 -270.636339)
			(xy 342.898293 -270.677025) (xy 342.921944 -270.722088) (xy 342.93806 -270.770362) (xy 342.946224 -270.820596)
			(xy 342.946736 -270.846042) (xy 343.254833 -270.846042) (xy 343.258928 -270.795314) (xy 343.271107 -270.7459)
			(xy 343.291055 -270.69908) (xy 343.318256 -270.656066) (xy 343.352004 -270.617972) (xy 343.391426 -270.585785)
			(xy 343.4355 -270.560339) (xy 343.483086 -270.542292) (xy 343.53295 -270.532112) (xy 343.583802 -270.530063)
			(xy 343.634323 -270.536197) (xy 343.683207 -270.550357) (xy 343.729186 -270.572174) (xy 343.77107 -270.601084)
			(xy 343.807774 -270.636339) (xy 343.838347 -270.677025) (xy 343.861998 -270.722088) (xy 343.878114 -270.770362)
			(xy 343.886278 -270.820596) (xy 343.88679 -270.846042) (xy 345.145372 -270.846042) (xy 345.149332 -270.796988)
			(xy 345.161109 -270.749204) (xy 345.1804 -270.703928) (xy 345.206703 -270.662332) (xy 345.239338 -270.625495)
			(xy 345.277459 -270.59437) (xy 345.32008 -270.569763) (xy 345.366096 -270.552311) (xy 345.414315 -270.542467)
			(xy 345.46349 -270.540486) (xy 345.512345 -270.546418) (xy 345.559616 -270.56011) (xy 345.604078 -270.581208)
			(xy 345.644581 -270.609164) (xy 345.680074 -270.643256) (xy 345.709639 -270.6826) (xy 345.73251 -270.726177)
			(xy 345.748094 -270.772858) (xy 345.755989 -270.821435) (xy 345.756484 -270.846042) (xy 346.085426 -270.846042)
			(xy 346.089386 -270.796988) (xy 346.101163 -270.749204) (xy 346.120454 -270.703928) (xy 346.146757 -270.662332)
			(xy 346.179392 -270.625495) (xy 346.217513 -270.59437) (xy 346.260134 -270.569763) (xy 346.30615 -270.552311)
			(xy 346.354369 -270.542467) (xy 346.403544 -270.540486) (xy 346.452399 -270.546418) (xy 346.49967 -270.56011)
			(xy 346.544132 -270.581208) (xy 346.584635 -270.609164) (xy 346.620128 -270.643256) (xy 346.649693 -270.6826)
			(xy 346.672564 -270.726177) (xy 346.688148 -270.772858) (xy 346.696043 -270.821435) (xy 346.696538 -270.846042)
			(xy 347.025226 -270.846042) (xy 347.029186 -270.796988) (xy 347.040963 -270.749204) (xy 347.060254 -270.703928)
			(xy 347.086557 -270.662332) (xy 347.119192 -270.625495) (xy 347.157313 -270.59437) (xy 347.199934 -270.569763)
			(xy 347.24595 -270.552311) (xy 347.294169 -270.542467) (xy 347.343344 -270.540486) (xy 347.392199 -270.546418)
			(xy 347.43947 -270.56011) (xy 347.483932 -270.581208) (xy 347.524435 -270.609164) (xy 347.559928 -270.643256)
			(xy 347.589493 -270.6826) (xy 347.612364 -270.726177) (xy 347.627948 -270.772858) (xy 347.635843 -270.821435)
			(xy 347.636338 -270.846042) (xy 347.96528 -270.846042) (xy 347.96924 -270.796988) (xy 347.981017 -270.749204)
			(xy 348.000308 -270.703928) (xy 348.026611 -270.662332) (xy 348.059246 -270.625495) (xy 348.097367 -270.59437)
			(xy 348.139988 -270.569763) (xy 348.186004 -270.552311) (xy 348.234223 -270.542467) (xy 348.283398 -270.540486)
			(xy 348.332253 -270.546418) (xy 348.379524 -270.56011) (xy 348.423986 -270.581208) (xy 348.464489 -270.609164)
			(xy 348.499982 -270.643256) (xy 348.529547 -270.6826) (xy 348.552418 -270.726177) (xy 348.568002 -270.772858)
			(xy 348.575897 -270.821435) (xy 348.576392 -270.846042) (xy 348.905334 -270.846042) (xy 348.909294 -270.796988)
			(xy 348.921071 -270.749204) (xy 348.940362 -270.703928) (xy 348.966665 -270.662332) (xy 348.9993 -270.625495)
			(xy 349.037421 -270.59437) (xy 349.080042 -270.569763) (xy 349.126058 -270.552311) (xy 349.174277 -270.542467)
			(xy 349.223452 -270.540486) (xy 349.272307 -270.546418) (xy 349.319578 -270.56011) (xy 349.36404 -270.581208)
			(xy 349.404543 -270.609164) (xy 349.440036 -270.643256) (xy 349.469601 -270.6826) (xy 349.492472 -270.726177)
			(xy 349.508056 -270.772858) (xy 349.515951 -270.821435) (xy 349.516446 -270.846042) (xy 349.845388 -270.846042)
			(xy 349.849348 -270.796988) (xy 349.861125 -270.749204) (xy 349.880416 -270.703928) (xy 349.906719 -270.662332)
			(xy 349.939354 -270.625495) (xy 349.977475 -270.59437) (xy 350.020096 -270.569763) (xy 350.066112 -270.552311)
			(xy 350.114331 -270.542467) (xy 350.163506 -270.540486) (xy 350.212361 -270.546418) (xy 350.259632 -270.56011)
			(xy 350.304094 -270.581208) (xy 350.344597 -270.609164) (xy 350.38009 -270.643256) (xy 350.409655 -270.6826)
			(xy 350.432526 -270.726177) (xy 350.44811 -270.772858) (xy 350.456005 -270.821435) (xy 350.4565 -270.846042)
			(xy 350.456005 -270.870649) (xy 350.44811 -270.919226) (xy 350.432526 -270.965907) (xy 350.409655 -271.009484)
			(xy 350.38009 -271.048828) (xy 350.344597 -271.08292) (xy 350.304094 -271.110876) (xy 350.259632 -271.131974)
			(xy 350.212361 -271.145666) (xy 350.163506 -271.151598) (xy 350.114331 -271.149617) (xy 350.066112 -271.139773)
			(xy 350.020096 -271.122321) (xy 349.977475 -271.097714) (xy 349.939354 -271.066589) (xy 349.906719 -271.029752)
			(xy 349.880416 -270.988156) (xy 349.861125 -270.94288) (xy 349.849348 -270.895096) (xy 349.845388 -270.846042)
			(xy 349.516446 -270.846042) (xy 349.515951 -270.870649) (xy 349.508056 -270.919226) (xy 349.492472 -270.965907)
			(xy 349.469601 -271.009484) (xy 349.440036 -271.048828) (xy 349.404543 -271.08292) (xy 349.36404 -271.110876)
			(xy 349.319578 -271.131974) (xy 349.272307 -271.145666) (xy 349.223452 -271.151598) (xy 349.174277 -271.149617)
			(xy 349.126058 -271.139773) (xy 349.080042 -271.122321) (xy 349.037421 -271.097714) (xy 348.9993 -271.066589)
			(xy 348.966665 -271.029752) (xy 348.940362 -270.988156) (xy 348.921071 -270.94288) (xy 348.909294 -270.895096)
			(xy 348.905334 -270.846042) (xy 348.576392 -270.846042) (xy 348.575897 -270.870649) (xy 348.568002 -270.919226)
			(xy 348.552418 -270.965907) (xy 348.529547 -271.009484) (xy 348.499982 -271.048828) (xy 348.464489 -271.08292)
			(xy 348.423986 -271.110876) (xy 348.379524 -271.131974) (xy 348.332253 -271.145666) (xy 348.283398 -271.151598)
			(xy 348.234223 -271.149617) (xy 348.186004 -271.139773) (xy 348.139988 -271.122321) (xy 348.097367 -271.097714)
			(xy 348.059246 -271.066589) (xy 348.026611 -271.029752) (xy 348.000308 -270.988156) (xy 347.981017 -270.94288)
			(xy 347.96924 -270.895096) (xy 347.96528 -270.846042) (xy 347.636338 -270.846042) (xy 347.635843 -270.870649)
			(xy 347.627948 -270.919226) (xy 347.612364 -270.965907) (xy 347.589493 -271.009484) (xy 347.559928 -271.048828)
			(xy 347.524435 -271.08292) (xy 347.483932 -271.110876) (xy 347.43947 -271.131974) (xy 347.392199 -271.145666)
			(xy 347.343344 -271.151598) (xy 347.294169 -271.149617) (xy 347.24595 -271.139773) (xy 347.199934 -271.122321)
			(xy 347.157313 -271.097714) (xy 347.119192 -271.066589) (xy 347.086557 -271.029752) (xy 347.060254 -270.988156)
			(xy 347.040963 -270.94288) (xy 347.029186 -270.895096) (xy 347.025226 -270.846042) (xy 346.696538 -270.846042)
			(xy 346.696043 -270.870649) (xy 346.688148 -270.919226) (xy 346.672564 -270.965907) (xy 346.649693 -271.009484)
			(xy 346.620128 -271.048828) (xy 346.584635 -271.08292) (xy 346.544132 -271.110876) (xy 346.49967 -271.131974)
			(xy 346.452399 -271.145666) (xy 346.403544 -271.151598) (xy 346.354369 -271.149617) (xy 346.30615 -271.139773)
			(xy 346.260134 -271.122321) (xy 346.217513 -271.097714) (xy 346.179392 -271.066589) (xy 346.146757 -271.029752)
			(xy 346.120454 -270.988156) (xy 346.101163 -270.94288) (xy 346.089386 -270.895096) (xy 346.085426 -270.846042)
			(xy 345.756484 -270.846042) (xy 345.755989 -270.870649) (xy 345.748094 -270.919226) (xy 345.73251 -270.965907)
			(xy 345.709639 -271.009484) (xy 345.680074 -271.048828) (xy 345.644581 -271.08292) (xy 345.604078 -271.110876)
			(xy 345.559616 -271.131974) (xy 345.512345 -271.145666) (xy 345.46349 -271.151598) (xy 345.414315 -271.149617)
			(xy 345.366096 -271.139773) (xy 345.32008 -271.122321) (xy 345.277459 -271.097714) (xy 345.239338 -271.066589)
			(xy 345.206703 -271.029752) (xy 345.1804 -270.988156) (xy 345.161109 -270.94288) (xy 345.149332 -270.895096)
			(xy 345.145372 -270.846042) (xy 343.88679 -270.846042) (xy 343.886278 -270.871488) (xy 343.878114 -270.921722)
			(xy 343.861998 -270.969996) (xy 343.838347 -271.015059) (xy 343.807774 -271.055745) (xy 343.77107 -271.091)
			(xy 343.729186 -271.11991) (xy 343.683207 -271.141727) (xy 343.634323 -271.155887) (xy 343.583802 -271.162021)
			(xy 343.53295 -271.159972) (xy 343.483086 -271.149792) (xy 343.4355 -271.131745) (xy 343.391426 -271.106299)
			(xy 343.352004 -271.074112) (xy 343.318256 -271.036018) (xy 343.291055 -270.993004) (xy 343.271107 -270.946184)
			(xy 343.258928 -270.89677) (xy 343.254833 -270.846042) (xy 342.946736 -270.846042) (xy 342.946224 -270.871488)
			(xy 342.93806 -270.921722) (xy 342.921944 -270.969996) (xy 342.898293 -271.015059) (xy 342.86772 -271.055745)
			(xy 342.831016 -271.091) (xy 342.789132 -271.11991) (xy 342.743153 -271.141727) (xy 342.694269 -271.155887)
			(xy 342.643748 -271.162021) (xy 342.592896 -271.159972) (xy 342.543032 -271.149792) (xy 342.495446 -271.131745)
			(xy 342.451372 -271.106299) (xy 342.41195 -271.074112) (xy 342.378202 -271.036018) (xy 342.351001 -270.993004)
			(xy 342.331053 -270.946184) (xy 342.318874 -270.89677) (xy 342.314779 -270.846042) (xy 341.066882 -270.846042)
			(xy 341.06637 -270.871488) (xy 341.058206 -270.921722) (xy 341.04209 -270.969996) (xy 341.018439 -271.015059)
			(xy 340.987866 -271.055745) (xy 340.951162 -271.091) (xy 340.909278 -271.11991) (xy 340.863299 -271.141727)
			(xy 340.814415 -271.155887) (xy 340.763894 -271.162021) (xy 340.713042 -271.159972) (xy 340.663178 -271.149792)
			(xy 340.615592 -271.131745) (xy 340.571518 -271.106299) (xy 340.532096 -271.074112) (xy 340.498348 -271.036018)
			(xy 340.471147 -270.993004) (xy 340.451199 -270.946184) (xy 340.43902 -270.89677) (xy 340.434925 -270.846042)
			(xy 340.116414 -270.846042) (xy 340.115919 -270.870649) (xy 340.108024 -270.919226) (xy 340.09244 -270.965907)
			(xy 340.069569 -271.009484) (xy 340.040004 -271.048828) (xy 340.004511 -271.08292) (xy 339.964008 -271.110876)
			(xy 339.919546 -271.131974) (xy 339.872275 -271.145666) (xy 339.82342 -271.151598) (xy 339.774245 -271.149617)
			(xy 339.726026 -271.139773) (xy 339.68001 -271.122321) (xy 339.637389 -271.097714) (xy 339.599268 -271.066589)
			(xy 339.566633 -271.029752) (xy 339.54033 -270.988156) (xy 339.521039 -270.94288) (xy 339.509262 -270.895096)
			(xy 339.505302 -270.846042) (xy 339.186774 -270.846042) (xy 339.186262 -270.871488) (xy 339.178098 -270.921722)
			(xy 339.161982 -270.969996) (xy 339.138331 -271.015059) (xy 339.107758 -271.055745) (xy 339.071054 -271.091)
			(xy 339.02917 -271.11991) (xy 338.983191 -271.141727) (xy 338.934307 -271.155887) (xy 338.883786 -271.162021)
			(xy 338.832934 -271.159972) (xy 338.78307 -271.149792) (xy 338.735484 -271.131745) (xy 338.69141 -271.106299)
			(xy 338.651988 -271.074112) (xy 338.61824 -271.036018) (xy 338.591039 -270.993004) (xy 338.571091 -270.946184)
			(xy 338.558912 -270.89677) (xy 338.554817 -270.846042) (xy 338.236306 -270.846042) (xy 338.235811 -270.870649)
			(xy 338.227916 -270.919226) (xy 338.212332 -270.965907) (xy 338.189461 -271.009484) (xy 338.159896 -271.048828)
			(xy 338.124403 -271.08292) (xy 338.0839 -271.110876) (xy 338.039438 -271.131974) (xy 337.992167 -271.145666)
			(xy 337.943312 -271.151598) (xy 337.894137 -271.149617) (xy 337.845918 -271.139773) (xy 337.799902 -271.122321)
			(xy 337.757281 -271.097714) (xy 337.71916 -271.066589) (xy 337.686525 -271.029752) (xy 337.660222 -270.988156)
			(xy 337.640931 -270.94288) (xy 337.629154 -270.895096) (xy 337.625194 -270.846042) (xy 337.30692 -270.846042)
			(xy 337.306408 -270.871488) (xy 337.298244 -270.921722) (xy 337.282128 -270.969996) (xy 337.258477 -271.015059)
			(xy 337.227904 -271.055745) (xy 337.1912 -271.091) (xy 337.149316 -271.11991) (xy 337.103337 -271.141727)
			(xy 337.054453 -271.155887) (xy 337.003932 -271.162021) (xy 336.95308 -271.159972) (xy 336.903216 -271.149792)
			(xy 336.85563 -271.131745) (xy 336.811556 -271.106299) (xy 336.772134 -271.074112) (xy 336.738386 -271.036018)
			(xy 336.711185 -270.993004) (xy 336.691237 -270.946184) (xy 336.679058 -270.89677) (xy 336.674963 -270.846042)
			(xy 336.366866 -270.846042) (xy 336.366354 -270.871488) (xy 336.35819 -270.921722) (xy 336.342074 -270.969996)
			(xy 336.318423 -271.015059) (xy 336.28785 -271.055745) (xy 336.251146 -271.091) (xy 336.209262 -271.11991)
			(xy 336.163283 -271.141727) (xy 336.114399 -271.155887) (xy 336.063878 -271.162021) (xy 336.013026 -271.159972)
			(xy 335.963162 -271.149792) (xy 335.915576 -271.131745) (xy 335.871502 -271.106299) (xy 335.83208 -271.074112)
			(xy 335.798332 -271.036018) (xy 335.771131 -270.993004) (xy 335.751183 -270.946184) (xy 335.739004 -270.89677)
			(xy 335.734909 -270.846042) (xy 334.486758 -270.846042) (xy 334.486246 -270.871488) (xy 334.478082 -270.921722)
			(xy 334.461966 -270.969996) (xy 334.438315 -271.015059) (xy 334.407742 -271.055745) (xy 334.371038 -271.091)
			(xy 334.329154 -271.11991) (xy 334.283175 -271.141727) (xy 334.234291 -271.155887) (xy 334.18377 -271.162021)
			(xy 334.132918 -271.159972) (xy 334.083054 -271.149792) (xy 334.035468 -271.131745) (xy 333.991394 -271.106299)
			(xy 333.951972 -271.074112) (xy 333.918224 -271.036018) (xy 333.891023 -270.993004) (xy 333.871075 -270.946184)
			(xy 333.858896 -270.89677) (xy 333.854801 -270.846042) (xy 333.53629 -270.846042) (xy 333.535795 -270.870649)
			(xy 333.5279 -270.919226) (xy 333.512316 -270.965907) (xy 333.489445 -271.009484) (xy 333.45988 -271.048828)
			(xy 333.424387 -271.08292) (xy 333.383884 -271.110876) (xy 333.339422 -271.131974) (xy 333.292151 -271.145666)
			(xy 333.243296 -271.151598) (xy 333.194121 -271.149617) (xy 333.145902 -271.139773) (xy 333.099886 -271.122321)
			(xy 333.057265 -271.097714) (xy 333.019144 -271.066589) (xy 332.986509 -271.029752) (xy 332.960206 -270.988156)
			(xy 332.940915 -270.94288) (xy 332.929138 -270.895096) (xy 332.925178 -270.846042) (xy 332.606904 -270.846042)
			(xy 332.606392 -270.871488) (xy 332.598228 -270.921722) (xy 332.582112 -270.969996) (xy 332.558461 -271.015059)
			(xy 332.527888 -271.055745) (xy 332.491184 -271.091) (xy 332.4493 -271.11991) (xy 332.403321 -271.141727)
			(xy 332.354437 -271.155887) (xy 332.303916 -271.162021) (xy 332.253064 -271.159972) (xy 332.2032 -271.149792)
			(xy 332.155614 -271.131745) (xy 332.11154 -271.106299) (xy 332.072118 -271.074112) (xy 332.03837 -271.036018)
			(xy 332.011169 -270.993004) (xy 331.991221 -270.946184) (xy 331.979042 -270.89677) (xy 331.974947 -270.846042)
			(xy 331.656436 -270.846042) (xy 331.655941 -270.870649) (xy 331.648046 -270.919226) (xy 331.632462 -270.965907)
			(xy 331.609591 -271.009484) (xy 331.580026 -271.048828) (xy 331.544533 -271.08292) (xy 331.50403 -271.110876)
			(xy 331.459568 -271.131974) (xy 331.412297 -271.145666) (xy 331.363442 -271.151598) (xy 331.314267 -271.149617)
			(xy 331.266048 -271.139773) (xy 331.220032 -271.122321) (xy 331.177411 -271.097714) (xy 331.13929 -271.066589)
			(xy 331.106655 -271.029752) (xy 331.080352 -270.988156) (xy 331.061061 -270.94288) (xy 331.049284 -270.895096)
			(xy 331.045324 -270.846042) (xy 330.726796 -270.846042) (xy 330.726284 -270.871488) (xy 330.71812 -270.921722)
			(xy 330.702004 -270.969996) (xy 330.678353 -271.015059) (xy 330.64778 -271.055745) (xy 330.611076 -271.091)
			(xy 330.569192 -271.11991) (xy 330.523213 -271.141727) (xy 330.474329 -271.155887) (xy 330.423808 -271.162021)
			(xy 330.372956 -271.159972) (xy 330.323092 -271.149792) (xy 330.275506 -271.131745) (xy 330.231432 -271.106299)
			(xy 330.19201 -271.074112) (xy 330.158262 -271.036018) (xy 330.131061 -270.993004) (xy 330.111113 -270.946184)
			(xy 330.098934 -270.89677) (xy 330.094839 -270.846042) (xy 329.786742 -270.846042) (xy 329.78623 -270.871488)
			(xy 329.778066 -270.921722) (xy 329.76195 -270.969996) (xy 329.738299 -271.015059) (xy 329.707726 -271.055745)
			(xy 329.671022 -271.091) (xy 329.629138 -271.11991) (xy 329.583159 -271.141727) (xy 329.534275 -271.155887)
			(xy 329.483754 -271.162021) (xy 329.432902 -271.159972) (xy 329.383038 -271.149792) (xy 329.335452 -271.131745)
			(xy 329.291378 -271.106299) (xy 329.251956 -271.074112) (xy 329.218208 -271.036018) (xy 329.191007 -270.993004)
			(xy 329.171059 -270.946184) (xy 329.15888 -270.89677) (xy 329.154785 -270.846042) (xy 326.95642 -270.846042)
			(xy 326.955925 -270.870649) (xy 326.94803 -270.919226) (xy 326.932446 -270.965907) (xy 326.909575 -271.009484)
			(xy 326.88001 -271.048828) (xy 326.844517 -271.08292) (xy 326.804014 -271.110876) (xy 326.759552 -271.131974)
			(xy 326.712281 -271.145666) (xy 326.663426 -271.151598) (xy 326.614251 -271.149617) (xy 326.566032 -271.139773)
			(xy 326.520016 -271.122321) (xy 326.477395 -271.097714) (xy 326.439274 -271.066589) (xy 326.406639 -271.029752)
			(xy 326.380336 -270.988156) (xy 326.361045 -270.94288) (xy 326.349268 -270.895096) (xy 326.345308 -270.846042)
			(xy 310.45912 -270.846042) (xy 310.45912 -271.39011) (xy 324.74714 -271.39011) (xy 324.7511 -271.341056)
			(xy 324.762877 -271.293272) (xy 324.782168 -271.247996) (xy 324.808471 -271.2064) (xy 324.841106 -271.169563)
			(xy 324.879227 -271.138438) (xy 324.921848 -271.113831) (xy 324.967864 -271.096379) (xy 325.016083 -271.086535)
			(xy 325.065258 -271.084554) (xy 325.114113 -271.090486) (xy 325.161384 -271.104178) (xy 325.205846 -271.125276)
			(xy 325.246349 -271.153232) (xy 325.281842 -271.187324) (xy 325.311407 -271.226668) (xy 325.334278 -271.270245)
			(xy 325.349862 -271.316926) (xy 325.357757 -271.365503) (xy 325.358252 -271.39011) (xy 325.357757 -271.414717)
			(xy 325.349862 -271.463294) (xy 325.334278 -271.509975) (xy 325.311407 -271.553552) (xy 325.281842 -271.592896)
			(xy 325.246349 -271.626988) (xy 325.205846 -271.654944) (xy 325.203519 -271.656048) (xy 327.755262 -271.656048)
			(xy 327.759222 -271.606994) (xy 327.770999 -271.55921) (xy 327.79029 -271.513934) (xy 327.816593 -271.472338)
			(xy 327.849228 -271.435501) (xy 327.887349 -271.404376) (xy 327.92997 -271.379769) (xy 327.975986 -271.362317)
			(xy 328.024205 -271.352473) (xy 328.07338 -271.350492) (xy 328.122235 -271.356424) (xy 328.169506 -271.370116)
			(xy 328.213968 -271.391214) (xy 328.254471 -271.41917) (xy 328.289964 -271.453262) (xy 328.319529 -271.492606)
			(xy 328.3424 -271.536183) (xy 328.357984 -271.582864) (xy 328.365879 -271.631441) (xy 328.366374 -271.656048)
			(xy 328.684885 -271.656048) (xy 328.68898 -271.60532) (xy 328.701159 -271.555906) (xy 328.721107 -271.509086)
			(xy 328.748308 -271.466072) (xy 328.782056 -271.427978) (xy 328.821478 -271.395791) (xy 328.865552 -271.370345)
			(xy 328.913138 -271.352298) (xy 328.963002 -271.342118) (xy 329.013854 -271.340069) (xy 329.064375 -271.346203)
			(xy 329.113259 -271.360363) (xy 329.159238 -271.38218) (xy 329.201122 -271.41109) (xy 329.237826 -271.446345)
			(xy 329.268399 -271.487031) (xy 329.29205 -271.532094) (xy 329.308166 -271.580368) (xy 329.31633 -271.630602)
			(xy 329.316842 -271.656048) (xy 329.63537 -271.656048) (xy 329.63933 -271.606994) (xy 329.651107 -271.55921)
			(xy 329.670398 -271.513934) (xy 329.696701 -271.472338) (xy 329.729336 -271.435501) (xy 329.767457 -271.404376)
			(xy 329.810078 -271.379769) (xy 329.856094 -271.362317) (xy 329.904313 -271.352473) (xy 329.953488 -271.350492)
			(xy 330.002343 -271.356424) (xy 330.049614 -271.370116) (xy 330.094076 -271.391214) (xy 330.134579 -271.41917)
			(xy 330.170072 -271.453262) (xy 330.199637 -271.492606) (xy 330.222508 -271.536183) (xy 330.238092 -271.582864)
			(xy 330.245987 -271.631441) (xy 330.246482 -271.656048) (xy 330.564739 -271.656048) (xy 330.568834 -271.60532)
			(xy 330.581013 -271.555906) (xy 330.600961 -271.509086) (xy 330.628162 -271.466072) (xy 330.66191 -271.427978)
			(xy 330.701332 -271.395791) (xy 330.745406 -271.370345) (xy 330.792992 -271.352298) (xy 330.842856 -271.342118)
			(xy 330.893708 -271.340069) (xy 330.944229 -271.346203) (xy 330.993113 -271.360363) (xy 331.039092 -271.38218)
			(xy 331.080976 -271.41109) (xy 331.11768 -271.446345) (xy 331.148253 -271.487031) (xy 331.171904 -271.532094)
			(xy 331.18802 -271.580368) (xy 331.196184 -271.630602) (xy 331.196696 -271.656048) (xy 331.515224 -271.656048)
			(xy 331.519184 -271.606994) (xy 331.530961 -271.55921) (xy 331.550252 -271.513934) (xy 331.576555 -271.472338)
			(xy 331.60919 -271.435501) (xy 331.647311 -271.404376) (xy 331.689932 -271.379769) (xy 331.735948 -271.362317)
			(xy 331.784167 -271.352473) (xy 331.833342 -271.350492) (xy 331.882197 -271.356424) (xy 331.929468 -271.370116)
			(xy 331.97393 -271.391214) (xy 332.014433 -271.41917) (xy 332.049926 -271.453262) (xy 332.079491 -271.492606)
			(xy 332.102362 -271.536183) (xy 332.117946 -271.582864) (xy 332.125841 -271.631441) (xy 332.126336 -271.656048)
			(xy 332.444847 -271.656048) (xy 332.448942 -271.60532) (xy 332.461121 -271.555906) (xy 332.481069 -271.509086)
			(xy 332.50827 -271.466072) (xy 332.542018 -271.427978) (xy 332.58144 -271.395791) (xy 332.625514 -271.370345)
			(xy 332.6731 -271.352298) (xy 332.722964 -271.342118) (xy 332.773816 -271.340069) (xy 332.824337 -271.346203)
			(xy 332.873221 -271.360363) (xy 332.9192 -271.38218) (xy 332.961084 -271.41109) (xy 332.997788 -271.446345)
			(xy 333.028361 -271.487031) (xy 333.052012 -271.532094) (xy 333.068128 -271.580368) (xy 333.076292 -271.630602)
			(xy 333.076804 -271.656048) (xy 333.384901 -271.656048) (xy 333.388996 -271.60532) (xy 333.401175 -271.555906)
			(xy 333.421123 -271.509086) (xy 333.448324 -271.466072) (xy 333.482072 -271.427978) (xy 333.521494 -271.395791)
			(xy 333.565568 -271.370345) (xy 333.613154 -271.352298) (xy 333.663018 -271.342118) (xy 333.71387 -271.340069)
			(xy 333.764391 -271.346203) (xy 333.813275 -271.360363) (xy 333.859254 -271.38218) (xy 333.901138 -271.41109)
			(xy 333.937842 -271.446345) (xy 333.968415 -271.487031) (xy 333.992066 -271.532094) (xy 334.008182 -271.580368)
			(xy 334.016346 -271.630602) (xy 334.016858 -271.656048) (xy 334.335386 -271.656048) (xy 334.339346 -271.606994)
			(xy 334.351123 -271.55921) (xy 334.370414 -271.513934) (xy 334.396717 -271.472338) (xy 334.429352 -271.435501)
			(xy 334.467473 -271.404376) (xy 334.510094 -271.379769) (xy 334.55611 -271.362317) (xy 334.604329 -271.352473)
			(xy 334.653504 -271.350492) (xy 334.702359 -271.356424) (xy 334.74963 -271.370116) (xy 334.794092 -271.391214)
			(xy 334.834595 -271.41917) (xy 334.870088 -271.453262) (xy 334.899653 -271.492606) (xy 334.922524 -271.536183)
			(xy 334.938108 -271.582864) (xy 334.946003 -271.631441) (xy 334.946498 -271.656048) (xy 335.264755 -271.656048)
			(xy 335.26885 -271.60532) (xy 335.281029 -271.555906) (xy 335.300977 -271.509086) (xy 335.328178 -271.466072)
			(xy 335.361926 -271.427978) (xy 335.401348 -271.395791) (xy 335.445422 -271.370345) (xy 335.493008 -271.352298)
			(xy 335.542872 -271.342118) (xy 335.593724 -271.340069) (xy 335.644245 -271.346203) (xy 335.693129 -271.360363)
			(xy 335.739108 -271.38218) (xy 335.780992 -271.41109) (xy 335.817696 -271.446345) (xy 335.848269 -271.487031)
			(xy 335.87192 -271.532094) (xy 335.888036 -271.580368) (xy 335.8962 -271.630602) (xy 335.896712 -271.656048)
			(xy 336.21524 -271.656048) (xy 336.2192 -271.606994) (xy 336.230977 -271.55921) (xy 336.250268 -271.513934)
			(xy 336.276571 -271.472338) (xy 336.309206 -271.435501) (xy 336.347327 -271.404376) (xy 336.389948 -271.379769)
			(xy 336.435964 -271.362317) (xy 336.484183 -271.352473) (xy 336.533358 -271.350492) (xy 336.582213 -271.356424)
			(xy 336.629484 -271.370116) (xy 336.673946 -271.391214) (xy 336.714449 -271.41917) (xy 336.749942 -271.453262)
			(xy 336.779507 -271.492606) (xy 336.802378 -271.536183) (xy 336.817962 -271.582864) (xy 336.825857 -271.631441)
			(xy 336.826352 -271.656048) (xy 337.144863 -271.656048) (xy 337.148958 -271.60532) (xy 337.161137 -271.555906)
			(xy 337.181085 -271.509086) (xy 337.208286 -271.466072) (xy 337.242034 -271.427978) (xy 337.281456 -271.395791)
			(xy 337.32553 -271.370345) (xy 337.373116 -271.352298) (xy 337.42298 -271.342118) (xy 337.473832 -271.340069)
			(xy 337.524353 -271.346203) (xy 337.573237 -271.360363) (xy 337.619216 -271.38218) (xy 337.6611 -271.41109)
			(xy 337.697804 -271.446345) (xy 337.728377 -271.487031) (xy 337.752028 -271.532094) (xy 337.768144 -271.580368)
			(xy 337.776308 -271.630602) (xy 337.77682 -271.656048) (xy 338.095348 -271.656048) (xy 338.099308 -271.606994)
			(xy 338.111085 -271.55921) (xy 338.130376 -271.513934) (xy 338.156679 -271.472338) (xy 338.189314 -271.435501)
			(xy 338.227435 -271.404376) (xy 338.270056 -271.379769) (xy 338.316072 -271.362317) (xy 338.364291 -271.352473)
			(xy 338.413466 -271.350492) (xy 338.462321 -271.356424) (xy 338.509592 -271.370116) (xy 338.554054 -271.391214)
			(xy 338.594557 -271.41917) (xy 338.63005 -271.453262) (xy 338.659615 -271.492606) (xy 338.682486 -271.536183)
			(xy 338.69807 -271.582864) (xy 338.705965 -271.631441) (xy 338.70646 -271.656048) (xy 339.024971 -271.656048)
			(xy 339.029066 -271.60532) (xy 339.041245 -271.555906) (xy 339.061193 -271.509086) (xy 339.088394 -271.466072)
			(xy 339.122142 -271.427978) (xy 339.161564 -271.395791) (xy 339.205638 -271.370345) (xy 339.253224 -271.352298)
			(xy 339.303088 -271.342118) (xy 339.35394 -271.340069) (xy 339.404461 -271.346203) (xy 339.453345 -271.360363)
			(xy 339.499324 -271.38218) (xy 339.541208 -271.41109) (xy 339.577912 -271.446345) (xy 339.608485 -271.487031)
			(xy 339.632136 -271.532094) (xy 339.648252 -271.580368) (xy 339.656416 -271.630602) (xy 339.656928 -271.656048)
			(xy 339.964771 -271.656048) (xy 339.968866 -271.60532) (xy 339.981045 -271.555906) (xy 340.000993 -271.509086)
			(xy 340.028194 -271.466072) (xy 340.061942 -271.427978) (xy 340.101364 -271.395791) (xy 340.145438 -271.370345)
			(xy 340.193024 -271.352298) (xy 340.242888 -271.342118) (xy 340.29374 -271.340069) (xy 340.344261 -271.346203)
			(xy 340.393145 -271.360363) (xy 340.439124 -271.38218) (xy 340.481008 -271.41109) (xy 340.517712 -271.446345)
			(xy 340.548285 -271.487031) (xy 340.571936 -271.532094) (xy 340.588052 -271.580368) (xy 340.596216 -271.630602)
			(xy 340.596728 -271.656048) (xy 340.915256 -271.656048) (xy 340.919216 -271.606994) (xy 340.930993 -271.55921)
			(xy 340.950284 -271.513934) (xy 340.976587 -271.472338) (xy 341.009222 -271.435501) (xy 341.047343 -271.404376)
			(xy 341.089964 -271.379769) (xy 341.13598 -271.362317) (xy 341.184199 -271.352473) (xy 341.233374 -271.350492)
			(xy 341.282229 -271.356424) (xy 341.3295 -271.370116) (xy 341.373962 -271.391214) (xy 341.414465 -271.41917)
			(xy 341.449958 -271.453262) (xy 341.479523 -271.492606) (xy 341.502394 -271.536183) (xy 341.517978 -271.582864)
			(xy 341.525873 -271.631441) (xy 341.526368 -271.656048) (xy 341.844879 -271.656048) (xy 341.848974 -271.60532)
			(xy 341.861153 -271.555906) (xy 341.881101 -271.509086) (xy 341.908302 -271.466072) (xy 341.94205 -271.427978)
			(xy 341.981472 -271.395791) (xy 342.025546 -271.370345) (xy 342.073132 -271.352298) (xy 342.122996 -271.342118)
			(xy 342.173848 -271.340069) (xy 342.224369 -271.346203) (xy 342.273253 -271.360363) (xy 342.319232 -271.38218)
			(xy 342.361116 -271.41109) (xy 342.39782 -271.446345) (xy 342.428393 -271.487031) (xy 342.452044 -271.532094)
			(xy 342.46816 -271.580368) (xy 342.476324 -271.630602) (xy 342.476836 -271.656048) (xy 342.795364 -271.656048)
			(xy 342.799324 -271.606994) (xy 342.811101 -271.55921) (xy 342.830392 -271.513934) (xy 342.856695 -271.472338)
			(xy 342.88933 -271.435501) (xy 342.927451 -271.404376) (xy 342.970072 -271.379769) (xy 343.016088 -271.362317)
			(xy 343.064307 -271.352473) (xy 343.113482 -271.350492) (xy 343.162337 -271.356424) (xy 343.209608 -271.370116)
			(xy 343.25407 -271.391214) (xy 343.294573 -271.41917) (xy 343.330066 -271.453262) (xy 343.359631 -271.492606)
			(xy 343.382502 -271.536183) (xy 343.398086 -271.582864) (xy 343.405981 -271.631441) (xy 343.406476 -271.656048)
			(xy 343.724987 -271.656048) (xy 343.729082 -271.60532) (xy 343.741261 -271.555906) (xy 343.761209 -271.509086)
			(xy 343.78841 -271.466072) (xy 343.822158 -271.427978) (xy 343.86158 -271.395791) (xy 343.905654 -271.370345)
			(xy 343.95324 -271.352298) (xy 344.003104 -271.342118) (xy 344.053956 -271.340069) (xy 344.104477 -271.346203)
			(xy 344.153361 -271.360363) (xy 344.19934 -271.38218) (xy 344.241224 -271.41109) (xy 344.277928 -271.446345)
			(xy 344.308501 -271.487031) (xy 344.332152 -271.532094) (xy 344.348268 -271.580368) (xy 344.356432 -271.630602)
			(xy 344.356944 -271.656048) (xy 344.675218 -271.656048) (xy 344.679178 -271.606994) (xy 344.690955 -271.55921)
			(xy 344.710246 -271.513934) (xy 344.736549 -271.472338) (xy 344.769184 -271.435501) (xy 344.807305 -271.404376)
			(xy 344.849926 -271.379769) (xy 344.895942 -271.362317) (xy 344.944161 -271.352473) (xy 344.993336 -271.350492)
			(xy 345.042191 -271.356424) (xy 345.089462 -271.370116) (xy 345.133924 -271.391214) (xy 345.174427 -271.41917)
			(xy 345.20992 -271.453262) (xy 345.239485 -271.492606) (xy 345.262356 -271.536183) (xy 345.27794 -271.582864)
			(xy 345.285835 -271.631441) (xy 345.28633 -271.656048) (xy 345.604841 -271.656048) (xy 345.608936 -271.60532)
			(xy 345.621115 -271.555906) (xy 345.641063 -271.509086) (xy 345.668264 -271.466072) (xy 345.702012 -271.427978)
			(xy 345.741434 -271.395791) (xy 345.785508 -271.370345) (xy 345.833094 -271.352298) (xy 345.882958 -271.342118)
			(xy 345.93381 -271.340069) (xy 345.984331 -271.346203) (xy 346.033215 -271.360363) (xy 346.079194 -271.38218)
			(xy 346.121078 -271.41109) (xy 346.157782 -271.446345) (xy 346.188355 -271.487031) (xy 346.212006 -271.532094)
			(xy 346.228122 -271.580368) (xy 346.236286 -271.630602) (xy 346.236798 -271.656048) (xy 346.544895 -271.656048)
			(xy 346.54899 -271.60532) (xy 346.561169 -271.555906) (xy 346.581117 -271.509086) (xy 346.608318 -271.466072)
			(xy 346.642066 -271.427978) (xy 346.681488 -271.395791) (xy 346.725562 -271.370345) (xy 346.773148 -271.352298)
			(xy 346.823012 -271.342118) (xy 346.873864 -271.340069) (xy 346.924385 -271.346203) (xy 346.973269 -271.360363)
			(xy 347.019248 -271.38218) (xy 347.061132 -271.41109) (xy 347.097836 -271.446345) (xy 347.128409 -271.487031)
			(xy 347.15206 -271.532094) (xy 347.168176 -271.580368) (xy 347.17634 -271.630602) (xy 347.176852 -271.656048)
			(xy 347.49538 -271.656048) (xy 347.49934 -271.606994) (xy 347.511117 -271.55921) (xy 347.530408 -271.513934)
			(xy 347.556711 -271.472338) (xy 347.589346 -271.435501) (xy 347.627467 -271.404376) (xy 347.670088 -271.379769)
			(xy 347.716104 -271.362317) (xy 347.764323 -271.352473) (xy 347.813498 -271.350492) (xy 347.862353 -271.356424)
			(xy 347.909624 -271.370116) (xy 347.954086 -271.391214) (xy 347.994589 -271.41917) (xy 348.030082 -271.453262)
			(xy 348.059647 -271.492606) (xy 348.082518 -271.536183) (xy 348.098102 -271.582864) (xy 348.105997 -271.631441)
			(xy 348.106492 -271.656048) (xy 348.425003 -271.656048) (xy 348.429098 -271.60532) (xy 348.441277 -271.555906)
			(xy 348.461225 -271.509086) (xy 348.488426 -271.466072) (xy 348.522174 -271.427978) (xy 348.561596 -271.395791)
			(xy 348.60567 -271.370345) (xy 348.653256 -271.352298) (xy 348.70312 -271.342118) (xy 348.753972 -271.340069)
			(xy 348.804493 -271.346203) (xy 348.853377 -271.360363) (xy 348.899356 -271.38218) (xy 348.94124 -271.41109)
			(xy 348.977944 -271.446345) (xy 349.008517 -271.487031) (xy 349.032168 -271.532094) (xy 349.048284 -271.580368)
			(xy 349.056448 -271.630602) (xy 349.05696 -271.656048) (xy 349.364803 -271.656048) (xy 349.368898 -271.60532)
			(xy 349.381077 -271.555906) (xy 349.401025 -271.509086) (xy 349.428226 -271.466072) (xy 349.461974 -271.427978)
			(xy 349.501396 -271.395791) (xy 349.54547 -271.370345) (xy 349.593056 -271.352298) (xy 349.64292 -271.342118)
			(xy 349.693772 -271.340069) (xy 349.744293 -271.346203) (xy 349.793177 -271.360363) (xy 349.839156 -271.38218)
			(xy 349.88104 -271.41109) (xy 349.917744 -271.446345) (xy 349.948317 -271.487031) (xy 349.971968 -271.532094)
			(xy 349.988084 -271.580368) (xy 349.996248 -271.630602) (xy 349.99676 -271.656048) (xy 350.315288 -271.656048)
			(xy 350.319248 -271.606994) (xy 350.331025 -271.55921) (xy 350.350316 -271.513934) (xy 350.376619 -271.472338)
			(xy 350.409254 -271.435501) (xy 350.447375 -271.404376) (xy 350.489996 -271.379769) (xy 350.536012 -271.362317)
			(xy 350.584231 -271.352473) (xy 350.633406 -271.350492) (xy 350.682261 -271.356424) (xy 350.729532 -271.370116)
			(xy 350.773994 -271.391214) (xy 350.814497 -271.41917) (xy 350.84999 -271.453262) (xy 350.879555 -271.492606)
			(xy 350.902426 -271.536183) (xy 350.91801 -271.582864) (xy 350.925905 -271.631441) (xy 350.9264 -271.656048)
			(xy 350.925905 -271.680655) (xy 350.91801 -271.729232) (xy 350.902426 -271.775913) (xy 350.879555 -271.81949)
			(xy 350.84999 -271.858834) (xy 350.814497 -271.892926) (xy 350.773994 -271.920882) (xy 350.729532 -271.94198)
			(xy 350.682261 -271.955672) (xy 350.633406 -271.961604) (xy 350.584231 -271.959623) (xy 350.536012 -271.949779)
			(xy 350.489996 -271.932327) (xy 350.447375 -271.90772) (xy 350.409254 -271.876595) (xy 350.376619 -271.839758)
			(xy 350.350316 -271.798162) (xy 350.331025 -271.752886) (xy 350.319248 -271.705102) (xy 350.315288 -271.656048)
			(xy 349.99676 -271.656048) (xy 349.996248 -271.681494) (xy 349.988084 -271.731728) (xy 349.971968 -271.780002)
			(xy 349.948317 -271.825065) (xy 349.917744 -271.865751) (xy 349.88104 -271.901006) (xy 349.839156 -271.929916)
			(xy 349.793177 -271.951733) (xy 349.744293 -271.965893) (xy 349.693772 -271.972027) (xy 349.64292 -271.969978)
			(xy 349.593056 -271.959798) (xy 349.54547 -271.941751) (xy 349.501396 -271.916305) (xy 349.461974 -271.884118)
			(xy 349.428226 -271.846024) (xy 349.401025 -271.80301) (xy 349.381077 -271.75619) (xy 349.368898 -271.706776)
			(xy 349.364803 -271.656048) (xy 349.05696 -271.656048) (xy 349.056448 -271.681494) (xy 349.048284 -271.731728)
			(xy 349.032168 -271.780002) (xy 349.008517 -271.825065) (xy 348.977944 -271.865751) (xy 348.94124 -271.901006)
			(xy 348.899356 -271.929916) (xy 348.853377 -271.951733) (xy 348.804493 -271.965893) (xy 348.753972 -271.972027)
			(xy 348.70312 -271.969978) (xy 348.653256 -271.959798) (xy 348.60567 -271.941751) (xy 348.561596 -271.916305)
			(xy 348.522174 -271.884118) (xy 348.488426 -271.846024) (xy 348.461225 -271.80301) (xy 348.441277 -271.75619)
			(xy 348.429098 -271.706776) (xy 348.425003 -271.656048) (xy 348.106492 -271.656048) (xy 348.105997 -271.680655)
			(xy 348.098102 -271.729232) (xy 348.082518 -271.775913) (xy 348.059647 -271.81949) (xy 348.030082 -271.858834)
			(xy 347.994589 -271.892926) (xy 347.954086 -271.920882) (xy 347.909624 -271.94198) (xy 347.862353 -271.955672)
			(xy 347.813498 -271.961604) (xy 347.764323 -271.959623) (xy 347.716104 -271.949779) (xy 347.670088 -271.932327)
			(xy 347.627467 -271.90772) (xy 347.589346 -271.876595) (xy 347.556711 -271.839758) (xy 347.530408 -271.798162)
			(xy 347.511117 -271.752886) (xy 347.49934 -271.705102) (xy 347.49538 -271.656048) (xy 347.176852 -271.656048)
			(xy 347.17634 -271.681494) (xy 347.168176 -271.731728) (xy 347.15206 -271.780002) (xy 347.128409 -271.825065)
			(xy 347.097836 -271.865751) (xy 347.061132 -271.901006) (xy 347.019248 -271.929916) (xy 346.973269 -271.951733)
			(xy 346.924385 -271.965893) (xy 346.873864 -271.972027) (xy 346.823012 -271.969978) (xy 346.773148 -271.959798)
			(xy 346.725562 -271.941751) (xy 346.681488 -271.916305) (xy 346.642066 -271.884118) (xy 346.608318 -271.846024)
			(xy 346.581117 -271.80301) (xy 346.561169 -271.75619) (xy 346.54899 -271.706776) (xy 346.544895 -271.656048)
			(xy 346.236798 -271.656048) (xy 346.236286 -271.681494) (xy 346.228122 -271.731728) (xy 346.212006 -271.780002)
			(xy 346.188355 -271.825065) (xy 346.157782 -271.865751) (xy 346.121078 -271.901006) (xy 346.079194 -271.929916)
			(xy 346.033215 -271.951733) (xy 345.984331 -271.965893) (xy 345.93381 -271.972027) (xy 345.882958 -271.969978)
			(xy 345.833094 -271.959798) (xy 345.785508 -271.941751) (xy 345.741434 -271.916305) (xy 345.702012 -271.884118)
			(xy 345.668264 -271.846024) (xy 345.641063 -271.80301) (xy 345.621115 -271.75619) (xy 345.608936 -271.706776)
			(xy 345.604841 -271.656048) (xy 345.28633 -271.656048) (xy 345.285835 -271.680655) (xy 345.27794 -271.729232)
			(xy 345.262356 -271.775913) (xy 345.239485 -271.81949) (xy 345.20992 -271.858834) (xy 345.174427 -271.892926)
			(xy 345.133924 -271.920882) (xy 345.089462 -271.94198) (xy 345.042191 -271.955672) (xy 344.993336 -271.961604)
			(xy 344.944161 -271.959623) (xy 344.895942 -271.949779) (xy 344.849926 -271.932327) (xy 344.807305 -271.90772)
			(xy 344.769184 -271.876595) (xy 344.736549 -271.839758) (xy 344.710246 -271.798162) (xy 344.690955 -271.752886)
			(xy 344.679178 -271.705102) (xy 344.675218 -271.656048) (xy 344.356944 -271.656048) (xy 344.356432 -271.681494)
			(xy 344.348268 -271.731728) (xy 344.332152 -271.780002) (xy 344.308501 -271.825065) (xy 344.277928 -271.865751)
			(xy 344.241224 -271.901006) (xy 344.19934 -271.929916) (xy 344.153361 -271.951733) (xy 344.104477 -271.965893)
			(xy 344.053956 -271.972027) (xy 344.003104 -271.969978) (xy 343.95324 -271.959798) (xy 343.905654 -271.941751)
			(xy 343.86158 -271.916305) (xy 343.822158 -271.884118) (xy 343.78841 -271.846024) (xy 343.761209 -271.80301)
			(xy 343.741261 -271.75619) (xy 343.729082 -271.706776) (xy 343.724987 -271.656048) (xy 343.406476 -271.656048)
			(xy 343.405981 -271.680655) (xy 343.398086 -271.729232) (xy 343.382502 -271.775913) (xy 343.359631 -271.81949)
			(xy 343.330066 -271.858834) (xy 343.294573 -271.892926) (xy 343.25407 -271.920882) (xy 343.209608 -271.94198)
			(xy 343.162337 -271.955672) (xy 343.113482 -271.961604) (xy 343.064307 -271.959623) (xy 343.016088 -271.949779)
			(xy 342.970072 -271.932327) (xy 342.927451 -271.90772) (xy 342.88933 -271.876595) (xy 342.856695 -271.839758)
			(xy 342.830392 -271.798162) (xy 342.811101 -271.752886) (xy 342.799324 -271.705102) (xy 342.795364 -271.656048)
			(xy 342.476836 -271.656048) (xy 342.476324 -271.681494) (xy 342.46816 -271.731728) (xy 342.452044 -271.780002)
			(xy 342.428393 -271.825065) (xy 342.39782 -271.865751) (xy 342.361116 -271.901006) (xy 342.319232 -271.929916)
			(xy 342.273253 -271.951733) (xy 342.224369 -271.965893) (xy 342.173848 -271.972027) (xy 342.122996 -271.969978)
			(xy 342.073132 -271.959798) (xy 342.025546 -271.941751) (xy 341.981472 -271.916305) (xy 341.94205 -271.884118)
			(xy 341.908302 -271.846024) (xy 341.881101 -271.80301) (xy 341.861153 -271.75619) (xy 341.848974 -271.706776)
			(xy 341.844879 -271.656048) (xy 341.526368 -271.656048) (xy 341.525873 -271.680655) (xy 341.517978 -271.729232)
			(xy 341.502394 -271.775913) (xy 341.479523 -271.81949) (xy 341.449958 -271.858834) (xy 341.414465 -271.892926)
			(xy 341.373962 -271.920882) (xy 341.3295 -271.94198) (xy 341.282229 -271.955672) (xy 341.233374 -271.961604)
			(xy 341.184199 -271.959623) (xy 341.13598 -271.949779) (xy 341.089964 -271.932327) (xy 341.047343 -271.90772)
			(xy 341.009222 -271.876595) (xy 340.976587 -271.839758) (xy 340.950284 -271.798162) (xy 340.930993 -271.752886)
			(xy 340.919216 -271.705102) (xy 340.915256 -271.656048) (xy 340.596728 -271.656048) (xy 340.596216 -271.681494)
			(xy 340.588052 -271.731728) (xy 340.571936 -271.780002) (xy 340.548285 -271.825065) (xy 340.517712 -271.865751)
			(xy 340.481008 -271.901006) (xy 340.439124 -271.929916) (xy 340.393145 -271.951733) (xy 340.344261 -271.965893)
			(xy 340.29374 -271.972027) (xy 340.242888 -271.969978) (xy 340.193024 -271.959798) (xy 340.145438 -271.941751)
			(xy 340.101364 -271.916305) (xy 340.061942 -271.884118) (xy 340.028194 -271.846024) (xy 340.000993 -271.80301)
			(xy 339.981045 -271.75619) (xy 339.968866 -271.706776) (xy 339.964771 -271.656048) (xy 339.656928 -271.656048)
			(xy 339.656416 -271.681494) (xy 339.648252 -271.731728) (xy 339.632136 -271.780002) (xy 339.608485 -271.825065)
			(xy 339.577912 -271.865751) (xy 339.541208 -271.901006) (xy 339.499324 -271.929916) (xy 339.453345 -271.951733)
			(xy 339.404461 -271.965893) (xy 339.35394 -271.972027) (xy 339.303088 -271.969978) (xy 339.253224 -271.959798)
			(xy 339.205638 -271.941751) (xy 339.161564 -271.916305) (xy 339.122142 -271.884118) (xy 339.088394 -271.846024)
			(xy 339.061193 -271.80301) (xy 339.041245 -271.75619) (xy 339.029066 -271.706776) (xy 339.024971 -271.656048)
			(xy 338.70646 -271.656048) (xy 338.705965 -271.680655) (xy 338.69807 -271.729232) (xy 338.682486 -271.775913)
			(xy 338.659615 -271.81949) (xy 338.63005 -271.858834) (xy 338.594557 -271.892926) (xy 338.554054 -271.920882)
			(xy 338.509592 -271.94198) (xy 338.462321 -271.955672) (xy 338.413466 -271.961604) (xy 338.364291 -271.959623)
			(xy 338.316072 -271.949779) (xy 338.270056 -271.932327) (xy 338.227435 -271.90772) (xy 338.189314 -271.876595)
			(xy 338.156679 -271.839758) (xy 338.130376 -271.798162) (xy 338.111085 -271.752886) (xy 338.099308 -271.705102)
			(xy 338.095348 -271.656048) (xy 337.77682 -271.656048) (xy 337.776308 -271.681494) (xy 337.768144 -271.731728)
			(xy 337.752028 -271.780002) (xy 337.728377 -271.825065) (xy 337.697804 -271.865751) (xy 337.6611 -271.901006)
			(xy 337.619216 -271.929916) (xy 337.573237 -271.951733) (xy 337.524353 -271.965893) (xy 337.473832 -271.972027)
			(xy 337.42298 -271.969978) (xy 337.373116 -271.959798) (xy 337.32553 -271.941751) (xy 337.281456 -271.916305)
			(xy 337.242034 -271.884118) (xy 337.208286 -271.846024) (xy 337.181085 -271.80301) (xy 337.161137 -271.75619)
			(xy 337.148958 -271.706776) (xy 337.144863 -271.656048) (xy 336.826352 -271.656048) (xy 336.825857 -271.680655)
			(xy 336.817962 -271.729232) (xy 336.802378 -271.775913) (xy 336.779507 -271.81949) (xy 336.749942 -271.858834)
			(xy 336.714449 -271.892926) (xy 336.673946 -271.920882) (xy 336.629484 -271.94198) (xy 336.582213 -271.955672)
			(xy 336.533358 -271.961604) (xy 336.484183 -271.959623) (xy 336.435964 -271.949779) (xy 336.389948 -271.932327)
			(xy 336.347327 -271.90772) (xy 336.309206 -271.876595) (xy 336.276571 -271.839758) (xy 336.250268 -271.798162)
			(xy 336.230977 -271.752886) (xy 336.2192 -271.705102) (xy 336.21524 -271.656048) (xy 335.896712 -271.656048)
			(xy 335.8962 -271.681494) (xy 335.888036 -271.731728) (xy 335.87192 -271.780002) (xy 335.848269 -271.825065)
			(xy 335.817696 -271.865751) (xy 335.780992 -271.901006) (xy 335.739108 -271.929916) (xy 335.693129 -271.951733)
			(xy 335.644245 -271.965893) (xy 335.593724 -271.972027) (xy 335.542872 -271.969978) (xy 335.493008 -271.959798)
			(xy 335.445422 -271.941751) (xy 335.401348 -271.916305) (xy 335.361926 -271.884118) (xy 335.328178 -271.846024)
			(xy 335.300977 -271.80301) (xy 335.281029 -271.75619) (xy 335.26885 -271.706776) (xy 335.264755 -271.656048)
			(xy 334.946498 -271.656048) (xy 334.946003 -271.680655) (xy 334.938108 -271.729232) (xy 334.922524 -271.775913)
			(xy 334.899653 -271.81949) (xy 334.870088 -271.858834) (xy 334.834595 -271.892926) (xy 334.794092 -271.920882)
			(xy 334.74963 -271.94198) (xy 334.702359 -271.955672) (xy 334.653504 -271.961604) (xy 334.604329 -271.959623)
			(xy 334.55611 -271.949779) (xy 334.510094 -271.932327) (xy 334.467473 -271.90772) (xy 334.429352 -271.876595)
			(xy 334.396717 -271.839758) (xy 334.370414 -271.798162) (xy 334.351123 -271.752886) (xy 334.339346 -271.705102)
			(xy 334.335386 -271.656048) (xy 334.016858 -271.656048) (xy 334.016346 -271.681494) (xy 334.008182 -271.731728)
			(xy 333.992066 -271.780002) (xy 333.968415 -271.825065) (xy 333.937842 -271.865751) (xy 333.901138 -271.901006)
			(xy 333.859254 -271.929916) (xy 333.813275 -271.951733) (xy 333.764391 -271.965893) (xy 333.71387 -271.972027)
			(xy 333.663018 -271.969978) (xy 333.613154 -271.959798) (xy 333.565568 -271.941751) (xy 333.521494 -271.916305)
			(xy 333.482072 -271.884118) (xy 333.448324 -271.846024) (xy 333.421123 -271.80301) (xy 333.401175 -271.75619)
			(xy 333.388996 -271.706776) (xy 333.384901 -271.656048) (xy 333.076804 -271.656048) (xy 333.076292 -271.681494)
			(xy 333.068128 -271.731728) (xy 333.052012 -271.780002) (xy 333.028361 -271.825065) (xy 332.997788 -271.865751)
			(xy 332.961084 -271.901006) (xy 332.9192 -271.929916) (xy 332.873221 -271.951733) (xy 332.824337 -271.965893)
			(xy 332.773816 -271.972027) (xy 332.722964 -271.969978) (xy 332.6731 -271.959798) (xy 332.625514 -271.941751)
			(xy 332.58144 -271.916305) (xy 332.542018 -271.884118) (xy 332.50827 -271.846024) (xy 332.481069 -271.80301)
			(xy 332.461121 -271.75619) (xy 332.448942 -271.706776) (xy 332.444847 -271.656048) (xy 332.126336 -271.656048)
			(xy 332.125841 -271.680655) (xy 332.117946 -271.729232) (xy 332.102362 -271.775913) (xy 332.079491 -271.81949)
			(xy 332.049926 -271.858834) (xy 332.014433 -271.892926) (xy 331.97393 -271.920882) (xy 331.929468 -271.94198)
			(xy 331.882197 -271.955672) (xy 331.833342 -271.961604) (xy 331.784167 -271.959623) (xy 331.735948 -271.949779)
			(xy 331.689932 -271.932327) (xy 331.647311 -271.90772) (xy 331.60919 -271.876595) (xy 331.576555 -271.839758)
			(xy 331.550252 -271.798162) (xy 331.530961 -271.752886) (xy 331.519184 -271.705102) (xy 331.515224 -271.656048)
			(xy 331.196696 -271.656048) (xy 331.196184 -271.681494) (xy 331.18802 -271.731728) (xy 331.171904 -271.780002)
			(xy 331.148253 -271.825065) (xy 331.11768 -271.865751) (xy 331.080976 -271.901006) (xy 331.039092 -271.929916)
			(xy 330.993113 -271.951733) (xy 330.944229 -271.965893) (xy 330.893708 -271.972027) (xy 330.842856 -271.969978)
			(xy 330.792992 -271.959798) (xy 330.745406 -271.941751) (xy 330.701332 -271.916305) (xy 330.66191 -271.884118)
			(xy 330.628162 -271.846024) (xy 330.600961 -271.80301) (xy 330.581013 -271.75619) (xy 330.568834 -271.706776)
			(xy 330.564739 -271.656048) (xy 330.246482 -271.656048) (xy 330.245987 -271.680655) (xy 330.238092 -271.729232)
			(xy 330.222508 -271.775913) (xy 330.199637 -271.81949) (xy 330.170072 -271.858834) (xy 330.134579 -271.892926)
			(xy 330.094076 -271.920882) (xy 330.049614 -271.94198) (xy 330.002343 -271.955672) (xy 329.953488 -271.961604)
			(xy 329.904313 -271.959623) (xy 329.856094 -271.949779) (xy 329.810078 -271.932327) (xy 329.767457 -271.90772)
			(xy 329.729336 -271.876595) (xy 329.696701 -271.839758) (xy 329.670398 -271.798162) (xy 329.651107 -271.752886)
			(xy 329.63933 -271.705102) (xy 329.63537 -271.656048) (xy 329.316842 -271.656048) (xy 329.31633 -271.681494)
			(xy 329.308166 -271.731728) (xy 329.29205 -271.780002) (xy 329.268399 -271.825065) (xy 329.237826 -271.865751)
			(xy 329.201122 -271.901006) (xy 329.159238 -271.929916) (xy 329.113259 -271.951733) (xy 329.064375 -271.965893)
			(xy 329.013854 -271.972027) (xy 328.963002 -271.969978) (xy 328.913138 -271.959798) (xy 328.865552 -271.941751)
			(xy 328.821478 -271.916305) (xy 328.782056 -271.884118) (xy 328.748308 -271.846024) (xy 328.721107 -271.80301)
			(xy 328.701159 -271.75619) (xy 328.68898 -271.706776) (xy 328.684885 -271.656048) (xy 328.366374 -271.656048)
			(xy 328.365879 -271.680655) (xy 328.357984 -271.729232) (xy 328.3424 -271.775913) (xy 328.319529 -271.81949)
			(xy 328.289964 -271.858834) (xy 328.254471 -271.892926) (xy 328.213968 -271.920882) (xy 328.169506 -271.94198)
			(xy 328.122235 -271.955672) (xy 328.07338 -271.961604) (xy 328.024205 -271.959623) (xy 327.975986 -271.949779)
			(xy 327.92997 -271.932327) (xy 327.887349 -271.90772) (xy 327.849228 -271.876595) (xy 327.816593 -271.839758)
			(xy 327.79029 -271.798162) (xy 327.770999 -271.752886) (xy 327.759222 -271.705102) (xy 327.755262 -271.656048)
			(xy 325.203519 -271.656048) (xy 325.161384 -271.676042) (xy 325.114113 -271.689734) (xy 325.065258 -271.695666)
			(xy 325.016083 -271.693685) (xy 324.967864 -271.683841) (xy 324.921848 -271.666389) (xy 324.879227 -271.641782)
			(xy 324.841106 -271.610657) (xy 324.808471 -271.57382) (xy 324.782168 -271.532224) (xy 324.762877 -271.486948)
			(xy 324.7511 -271.439164) (xy 324.74714 -271.39011) (xy 310.45912 -271.39011) (xy 310.45912 -272.466054)
			(xy 326.345308 -272.466054) (xy 326.349268 -272.417) (xy 326.361045 -272.369216) (xy 326.380336 -272.32394)
			(xy 326.406639 -272.282344) (xy 326.439274 -272.245507) (xy 326.477395 -272.214382) (xy 326.520016 -272.189775)
			(xy 326.566032 -272.172323) (xy 326.614251 -272.162479) (xy 326.663426 -272.160498) (xy 326.712281 -272.16643)
			(xy 326.759552 -272.180122) (xy 326.804014 -272.20122) (xy 326.844517 -272.229176) (xy 326.88001 -272.263268)
			(xy 326.909575 -272.302612) (xy 326.932446 -272.346189) (xy 326.94803 -272.39287) (xy 326.955925 -272.441447)
			(xy 326.95642 -272.466054) (xy 328.225416 -272.466054) (xy 328.229376 -272.417) (xy 328.241153 -272.369216)
			(xy 328.260444 -272.32394) (xy 328.286747 -272.282344) (xy 328.319382 -272.245507) (xy 328.357503 -272.214382)
			(xy 328.400124 -272.189775) (xy 328.44614 -272.172323) (xy 328.494359 -272.162479) (xy 328.543534 -272.160498)
			(xy 328.592389 -272.16643) (xy 328.63966 -272.180122) (xy 328.684122 -272.20122) (xy 328.724625 -272.229176)
			(xy 328.760118 -272.263268) (xy 328.789683 -272.302612) (xy 328.812554 -272.346189) (xy 328.828138 -272.39287)
			(xy 328.836033 -272.441447) (xy 328.836528 -272.466054) (xy 329.154785 -272.466054) (xy 329.15888 -272.415326)
			(xy 329.171059 -272.365912) (xy 329.191007 -272.319092) (xy 329.218208 -272.276078) (xy 329.251956 -272.237984)
			(xy 329.291378 -272.205797) (xy 329.335452 -272.180351) (xy 329.383038 -272.162304) (xy 329.432902 -272.152124)
			(xy 329.483754 -272.150075) (xy 329.534275 -272.156209) (xy 329.583159 -272.170369) (xy 329.629138 -272.192186)
			(xy 329.671022 -272.221096) (xy 329.707726 -272.256351) (xy 329.738299 -272.297037) (xy 329.76195 -272.3421)
			(xy 329.778066 -272.390374) (xy 329.78623 -272.440608) (xy 329.786742 -272.466054) (xy 330.094839 -272.466054)
			(xy 330.098934 -272.415326) (xy 330.111113 -272.365912) (xy 330.131061 -272.319092) (xy 330.158262 -272.276078)
			(xy 330.19201 -272.237984) (xy 330.231432 -272.205797) (xy 330.275506 -272.180351) (xy 330.323092 -272.162304)
			(xy 330.372956 -272.152124) (xy 330.423808 -272.150075) (xy 330.474329 -272.156209) (xy 330.523213 -272.170369)
			(xy 330.569192 -272.192186) (xy 330.611076 -272.221096) (xy 330.64778 -272.256351) (xy 330.678353 -272.297037)
			(xy 330.702004 -272.3421) (xy 330.71812 -272.390374) (xy 330.726284 -272.440608) (xy 330.726796 -272.466054)
			(xy 331.045324 -272.466054) (xy 331.049284 -272.417) (xy 331.061061 -272.369216) (xy 331.080352 -272.32394)
			(xy 331.106655 -272.282344) (xy 331.13929 -272.245507) (xy 331.177411 -272.214382) (xy 331.220032 -272.189775)
			(xy 331.266048 -272.172323) (xy 331.314267 -272.162479) (xy 331.363442 -272.160498) (xy 331.412297 -272.16643)
			(xy 331.459568 -272.180122) (xy 331.50403 -272.20122) (xy 331.544533 -272.229176) (xy 331.580026 -272.263268)
			(xy 331.609591 -272.302612) (xy 331.632462 -272.346189) (xy 331.648046 -272.39287) (xy 331.655941 -272.441447)
			(xy 331.656436 -272.466054) (xy 331.974947 -272.466054) (xy 331.979042 -272.415326) (xy 331.991221 -272.365912)
			(xy 332.011169 -272.319092) (xy 332.03837 -272.276078) (xy 332.072118 -272.237984) (xy 332.11154 -272.205797)
			(xy 332.155614 -272.180351) (xy 332.2032 -272.162304) (xy 332.253064 -272.152124) (xy 332.303916 -272.150075)
			(xy 332.354437 -272.156209) (xy 332.403321 -272.170369) (xy 332.4493 -272.192186) (xy 332.491184 -272.221096)
			(xy 332.527888 -272.256351) (xy 332.558461 -272.297037) (xy 332.582112 -272.3421) (xy 332.598228 -272.390374)
			(xy 332.606392 -272.440608) (xy 332.606904 -272.466054) (xy 332.925178 -272.466054) (xy 332.929138 -272.417)
			(xy 332.940915 -272.369216) (xy 332.960206 -272.32394) (xy 332.986509 -272.282344) (xy 333.019144 -272.245507)
			(xy 333.057265 -272.214382) (xy 333.099886 -272.189775) (xy 333.145902 -272.172323) (xy 333.194121 -272.162479)
			(xy 333.243296 -272.160498) (xy 333.292151 -272.16643) (xy 333.339422 -272.180122) (xy 333.383884 -272.20122)
			(xy 333.424387 -272.229176) (xy 333.45988 -272.263268) (xy 333.489445 -272.302612) (xy 333.512316 -272.346189)
			(xy 333.5279 -272.39287) (xy 333.535795 -272.441447) (xy 333.53629 -272.466054) (xy 333.854801 -272.466054)
			(xy 333.858896 -272.415326) (xy 333.871075 -272.365912) (xy 333.891023 -272.319092) (xy 333.918224 -272.276078)
			(xy 333.951972 -272.237984) (xy 333.991394 -272.205797) (xy 334.035468 -272.180351) (xy 334.083054 -272.162304)
			(xy 334.132918 -272.152124) (xy 334.18377 -272.150075) (xy 334.234291 -272.156209) (xy 334.283175 -272.170369)
			(xy 334.329154 -272.192186) (xy 334.371038 -272.221096) (xy 334.407742 -272.256351) (xy 334.438315 -272.297037)
			(xy 334.461966 -272.3421) (xy 334.478082 -272.390374) (xy 334.486246 -272.440608) (xy 334.486758 -272.466054)
			(xy 334.805286 -272.466054) (xy 334.809246 -272.417) (xy 334.821023 -272.369216) (xy 334.840314 -272.32394)
			(xy 334.866617 -272.282344) (xy 334.899252 -272.245507) (xy 334.937373 -272.214382) (xy 334.979994 -272.189775)
			(xy 335.02601 -272.172323) (xy 335.074229 -272.162479) (xy 335.123404 -272.160498) (xy 335.172259 -272.16643)
			(xy 335.21953 -272.180122) (xy 335.263992 -272.20122) (xy 335.304495 -272.229176) (xy 335.339988 -272.263268)
			(xy 335.369553 -272.302612) (xy 335.392424 -272.346189) (xy 335.408008 -272.39287) (xy 335.415903 -272.441447)
			(xy 335.416398 -272.466054) (xy 335.734909 -272.466054) (xy 335.739004 -272.415326) (xy 335.751183 -272.365912)
			(xy 335.771131 -272.319092) (xy 335.798332 -272.276078) (xy 335.83208 -272.237984) (xy 335.871502 -272.205797)
			(xy 335.915576 -272.180351) (xy 335.963162 -272.162304) (xy 336.013026 -272.152124) (xy 336.063878 -272.150075)
			(xy 336.114399 -272.156209) (xy 336.163283 -272.170369) (xy 336.209262 -272.192186) (xy 336.251146 -272.221096)
			(xy 336.28785 -272.256351) (xy 336.318423 -272.297037) (xy 336.342074 -272.3421) (xy 336.35819 -272.390374)
			(xy 336.366354 -272.440608) (xy 336.366866 -272.466054) (xy 336.674963 -272.466054) (xy 336.679058 -272.415326)
			(xy 336.691237 -272.365912) (xy 336.711185 -272.319092) (xy 336.738386 -272.276078) (xy 336.772134 -272.237984)
			(xy 336.811556 -272.205797) (xy 336.85563 -272.180351) (xy 336.903216 -272.162304) (xy 336.95308 -272.152124)
			(xy 337.003932 -272.150075) (xy 337.054453 -272.156209) (xy 337.103337 -272.170369) (xy 337.149316 -272.192186)
			(xy 337.1912 -272.221096) (xy 337.227904 -272.256351) (xy 337.258477 -272.297037) (xy 337.282128 -272.3421)
			(xy 337.298244 -272.390374) (xy 337.306408 -272.440608) (xy 337.30692 -272.466054) (xy 337.625194 -272.466054)
			(xy 337.629154 -272.417) (xy 337.640931 -272.369216) (xy 337.660222 -272.32394) (xy 337.686525 -272.282344)
			(xy 337.71916 -272.245507) (xy 337.757281 -272.214382) (xy 337.799902 -272.189775) (xy 337.845918 -272.172323)
			(xy 337.894137 -272.162479) (xy 337.943312 -272.160498) (xy 337.992167 -272.16643) (xy 338.039438 -272.180122)
			(xy 338.0839 -272.20122) (xy 338.124403 -272.229176) (xy 338.159896 -272.263268) (xy 338.189461 -272.302612)
			(xy 338.212332 -272.346189) (xy 338.227916 -272.39287) (xy 338.235811 -272.441447) (xy 338.236306 -272.466054)
			(xy 338.554817 -272.466054) (xy 338.558912 -272.415326) (xy 338.571091 -272.365912) (xy 338.591039 -272.319092)
			(xy 338.61824 -272.276078) (xy 338.651988 -272.237984) (xy 338.69141 -272.205797) (xy 338.735484 -272.180351)
			(xy 338.78307 -272.162304) (xy 338.832934 -272.152124) (xy 338.883786 -272.150075) (xy 338.934307 -272.156209)
			(xy 338.983191 -272.170369) (xy 339.02917 -272.192186) (xy 339.071054 -272.221096) (xy 339.107758 -272.256351)
			(xy 339.138331 -272.297037) (xy 339.161982 -272.3421) (xy 339.178098 -272.390374) (xy 339.186262 -272.440608)
			(xy 339.186774 -272.466054) (xy 339.505302 -272.466054) (xy 339.509262 -272.417) (xy 339.521039 -272.369216)
			(xy 339.54033 -272.32394) (xy 339.566633 -272.282344) (xy 339.599268 -272.245507) (xy 339.637389 -272.214382)
			(xy 339.68001 -272.189775) (xy 339.726026 -272.172323) (xy 339.774245 -272.162479) (xy 339.82342 -272.160498)
			(xy 339.872275 -272.16643) (xy 339.919546 -272.180122) (xy 339.964008 -272.20122) (xy 340.004511 -272.229176)
			(xy 340.040004 -272.263268) (xy 340.069569 -272.302612) (xy 340.09244 -272.346189) (xy 340.108024 -272.39287)
			(xy 340.115919 -272.441447) (xy 340.116414 -272.466054) (xy 340.434925 -272.466054) (xy 340.43902 -272.415326)
			(xy 340.451199 -272.365912) (xy 340.471147 -272.319092) (xy 340.498348 -272.276078) (xy 340.532096 -272.237984)
			(xy 340.571518 -272.205797) (xy 340.615592 -272.180351) (xy 340.663178 -272.162304) (xy 340.713042 -272.152124)
			(xy 340.763894 -272.150075) (xy 340.814415 -272.156209) (xy 340.863299 -272.170369) (xy 340.909278 -272.192186)
			(xy 340.951162 -272.221096) (xy 340.987866 -272.256351) (xy 341.018439 -272.297037) (xy 341.04209 -272.3421)
			(xy 341.058206 -272.390374) (xy 341.06637 -272.440608) (xy 341.066882 -272.466054) (xy 341.38541 -272.466054)
			(xy 341.38937 -272.417) (xy 341.401147 -272.369216) (xy 341.420438 -272.32394) (xy 341.446741 -272.282344)
			(xy 341.479376 -272.245507) (xy 341.517497 -272.214382) (xy 341.560118 -272.189775) (xy 341.606134 -272.172323)
			(xy 341.654353 -272.162479) (xy 341.703528 -272.160498) (xy 341.752383 -272.16643) (xy 341.799654 -272.180122)
			(xy 341.844116 -272.20122) (xy 341.884619 -272.229176) (xy 341.920112 -272.263268) (xy 341.949677 -272.302612)
			(xy 341.972548 -272.346189) (xy 341.988132 -272.39287) (xy 341.996027 -272.441447) (xy 341.996522 -272.466054)
			(xy 342.314779 -272.466054) (xy 342.318874 -272.415326) (xy 342.331053 -272.365912) (xy 342.351001 -272.319092)
			(xy 342.378202 -272.276078) (xy 342.41195 -272.237984) (xy 342.451372 -272.205797) (xy 342.495446 -272.180351)
			(xy 342.543032 -272.162304) (xy 342.592896 -272.152124) (xy 342.643748 -272.150075) (xy 342.694269 -272.156209)
			(xy 342.743153 -272.170369) (xy 342.789132 -272.192186) (xy 342.831016 -272.221096) (xy 342.86772 -272.256351)
			(xy 342.898293 -272.297037) (xy 342.921944 -272.3421) (xy 342.93806 -272.390374) (xy 342.946224 -272.440608)
			(xy 342.946736 -272.466054) (xy 343.254833 -272.466054) (xy 343.258928 -272.415326) (xy 343.271107 -272.365912)
			(xy 343.291055 -272.319092) (xy 343.318256 -272.276078) (xy 343.352004 -272.237984) (xy 343.391426 -272.205797)
			(xy 343.4355 -272.180351) (xy 343.483086 -272.162304) (xy 343.53295 -272.152124) (xy 343.583802 -272.150075)
			(xy 343.634323 -272.156209) (xy 343.683207 -272.170369) (xy 343.729186 -272.192186) (xy 343.77107 -272.221096)
			(xy 343.807774 -272.256351) (xy 343.838347 -272.297037) (xy 343.861998 -272.3421) (xy 343.878114 -272.390374)
			(xy 343.886278 -272.440608) (xy 343.88679 -272.466054) (xy 344.205318 -272.466054) (xy 344.209278 -272.417)
			(xy 344.221055 -272.369216) (xy 344.240346 -272.32394) (xy 344.266649 -272.282344) (xy 344.299284 -272.245507)
			(xy 344.337405 -272.214382) (xy 344.380026 -272.189775) (xy 344.426042 -272.172323) (xy 344.474261 -272.162479)
			(xy 344.523436 -272.160498) (xy 344.572291 -272.16643) (xy 344.619562 -272.180122) (xy 344.664024 -272.20122)
			(xy 344.704527 -272.229176) (xy 344.74002 -272.263268) (xy 344.769585 -272.302612) (xy 344.792456 -272.346189)
			(xy 344.80804 -272.39287) (xy 344.815935 -272.441447) (xy 344.81643 -272.466054) (xy 345.145372 -272.466054)
			(xy 345.149332 -272.417) (xy 345.161109 -272.369216) (xy 345.1804 -272.32394) (xy 345.206703 -272.282344)
			(xy 345.239338 -272.245507) (xy 345.277459 -272.214382) (xy 345.32008 -272.189775) (xy 345.366096 -272.172323)
			(xy 345.414315 -272.162479) (xy 345.46349 -272.160498) (xy 345.512345 -272.16643) (xy 345.559616 -272.180122)
			(xy 345.604078 -272.20122) (xy 345.644581 -272.229176) (xy 345.680074 -272.263268) (xy 345.709639 -272.302612)
			(xy 345.73251 -272.346189) (xy 345.748094 -272.39287) (xy 345.755989 -272.441447) (xy 345.756484 -272.466054)
			(xy 346.085426 -272.466054) (xy 346.089386 -272.417) (xy 346.101163 -272.369216) (xy 346.120454 -272.32394)
			(xy 346.146757 -272.282344) (xy 346.179392 -272.245507) (xy 346.217513 -272.214382) (xy 346.260134 -272.189775)
			(xy 346.30615 -272.172323) (xy 346.354369 -272.162479) (xy 346.403544 -272.160498) (xy 346.452399 -272.16643)
			(xy 346.49967 -272.180122) (xy 346.544132 -272.20122) (xy 346.584635 -272.229176) (xy 346.620128 -272.263268)
			(xy 346.649693 -272.302612) (xy 346.672564 -272.346189) (xy 346.688148 -272.39287) (xy 346.696043 -272.441447)
			(xy 346.696538 -272.466054) (xy 347.025226 -272.466054) (xy 347.029186 -272.417) (xy 347.040963 -272.369216)
			(xy 347.060254 -272.32394) (xy 347.086557 -272.282344) (xy 347.119192 -272.245507) (xy 347.157313 -272.214382)
			(xy 347.199934 -272.189775) (xy 347.24595 -272.172323) (xy 347.294169 -272.162479) (xy 347.343344 -272.160498)
			(xy 347.392199 -272.16643) (xy 347.43947 -272.180122) (xy 347.483932 -272.20122) (xy 347.524435 -272.229176)
			(xy 347.559928 -272.263268) (xy 347.589493 -272.302612) (xy 347.612364 -272.346189) (xy 347.627948 -272.39287)
			(xy 347.635843 -272.441447) (xy 347.636338 -272.466054) (xy 347.96528 -272.466054) (xy 347.96924 -272.417)
			(xy 347.981017 -272.369216) (xy 348.000308 -272.32394) (xy 348.026611 -272.282344) (xy 348.059246 -272.245507)
			(xy 348.097367 -272.214382) (xy 348.139988 -272.189775) (xy 348.186004 -272.172323) (xy 348.234223 -272.162479)
			(xy 348.283398 -272.160498) (xy 348.332253 -272.16643) (xy 348.379524 -272.180122) (xy 348.423986 -272.20122)
			(xy 348.464489 -272.229176) (xy 348.499982 -272.263268) (xy 348.529547 -272.302612) (xy 348.552418 -272.346189)
			(xy 348.568002 -272.39287) (xy 348.575897 -272.441447) (xy 348.576392 -272.466054) (xy 348.905334 -272.466054)
			(xy 348.909294 -272.417) (xy 348.921071 -272.369216) (xy 348.940362 -272.32394) (xy 348.966665 -272.282344)
			(xy 348.9993 -272.245507) (xy 349.037421 -272.214382) (xy 349.080042 -272.189775) (xy 349.126058 -272.172323)
			(xy 349.174277 -272.162479) (xy 349.223452 -272.160498) (xy 349.272307 -272.16643) (xy 349.319578 -272.180122)
			(xy 349.36404 -272.20122) (xy 349.404543 -272.229176) (xy 349.440036 -272.263268) (xy 349.469601 -272.302612)
			(xy 349.492472 -272.346189) (xy 349.508056 -272.39287) (xy 349.515951 -272.441447) (xy 349.516446 -272.466054)
			(xy 349.845388 -272.466054) (xy 349.849348 -272.417) (xy 349.861125 -272.369216) (xy 349.880416 -272.32394)
			(xy 349.906719 -272.282344) (xy 349.939354 -272.245507) (xy 349.977475 -272.214382) (xy 350.020096 -272.189775)
			(xy 350.066112 -272.172323) (xy 350.114331 -272.162479) (xy 350.163506 -272.160498) (xy 350.212361 -272.16643)
			(xy 350.259632 -272.180122) (xy 350.304094 -272.20122) (xy 350.344597 -272.229176) (xy 350.38009 -272.263268)
			(xy 350.409655 -272.302612) (xy 350.432526 -272.346189) (xy 350.44811 -272.39287) (xy 350.456005 -272.441447)
			(xy 350.4565 -272.466054) (xy 350.785442 -272.466054) (xy 350.789402 -272.417) (xy 350.801179 -272.369216)
			(xy 350.82047 -272.32394) (xy 350.846773 -272.282344) (xy 350.879408 -272.245507) (xy 350.917529 -272.214382)
			(xy 350.96015 -272.189775) (xy 351.006166 -272.172323) (xy 351.054385 -272.162479) (xy 351.10356 -272.160498)
			(xy 351.152415 -272.16643) (xy 351.199686 -272.180122) (xy 351.244148 -272.20122) (xy 351.284651 -272.229176)
			(xy 351.320144 -272.263268) (xy 351.349709 -272.302612) (xy 351.37258 -272.346189) (xy 351.388164 -272.39287)
			(xy 351.396059 -272.441447) (xy 351.396554 -272.466054) (xy 351.396059 -272.490661) (xy 351.388164 -272.539238)
			(xy 351.37258 -272.585919) (xy 351.349709 -272.629496) (xy 351.320144 -272.66884) (xy 351.284651 -272.702932)
			(xy 351.244148 -272.730888) (xy 351.199686 -272.751986) (xy 351.152415 -272.765678) (xy 351.10356 -272.77161)
			(xy 351.054385 -272.769629) (xy 351.006166 -272.759785) (xy 350.96015 -272.742333) (xy 350.917529 -272.717726)
			(xy 350.879408 -272.686601) (xy 350.846773 -272.649764) (xy 350.82047 -272.608168) (xy 350.801179 -272.562892)
			(xy 350.789402 -272.515108) (xy 350.785442 -272.466054) (xy 350.4565 -272.466054) (xy 350.456005 -272.490661)
			(xy 350.44811 -272.539238) (xy 350.432526 -272.585919) (xy 350.409655 -272.629496) (xy 350.38009 -272.66884)
			(xy 350.344597 -272.702932) (xy 350.304094 -272.730888) (xy 350.259632 -272.751986) (xy 350.212361 -272.765678)
			(xy 350.163506 -272.77161) (xy 350.114331 -272.769629) (xy 350.066112 -272.759785) (xy 350.020096 -272.742333)
			(xy 349.977475 -272.717726) (xy 349.939354 -272.686601) (xy 349.906719 -272.649764) (xy 349.880416 -272.608168)
			(xy 349.861125 -272.562892) (xy 349.849348 -272.515108) (xy 349.845388 -272.466054) (xy 349.516446 -272.466054)
			(xy 349.515951 -272.490661) (xy 349.508056 -272.539238) (xy 349.492472 -272.585919) (xy 349.469601 -272.629496)
			(xy 349.440036 -272.66884) (xy 349.404543 -272.702932) (xy 349.36404 -272.730888) (xy 349.319578 -272.751986)
			(xy 349.272307 -272.765678) (xy 349.223452 -272.77161) (xy 349.174277 -272.769629) (xy 349.126058 -272.759785)
			(xy 349.080042 -272.742333) (xy 349.037421 -272.717726) (xy 348.9993 -272.686601) (xy 348.966665 -272.649764)
			(xy 348.940362 -272.608168) (xy 348.921071 -272.562892) (xy 348.909294 -272.515108) (xy 348.905334 -272.466054)
			(xy 348.576392 -272.466054) (xy 348.575897 -272.490661) (xy 348.568002 -272.539238) (xy 348.552418 -272.585919)
			(xy 348.529547 -272.629496) (xy 348.499982 -272.66884) (xy 348.464489 -272.702932) (xy 348.423986 -272.730888)
			(xy 348.379524 -272.751986) (xy 348.332253 -272.765678) (xy 348.283398 -272.77161) (xy 348.234223 -272.769629)
			(xy 348.186004 -272.759785) (xy 348.139988 -272.742333) (xy 348.097367 -272.717726) (xy 348.059246 -272.686601)
			(xy 348.026611 -272.649764) (xy 348.000308 -272.608168) (xy 347.981017 -272.562892) (xy 347.96924 -272.515108)
			(xy 347.96528 -272.466054) (xy 347.636338 -272.466054) (xy 347.635843 -272.490661) (xy 347.627948 -272.539238)
			(xy 347.612364 -272.585919) (xy 347.589493 -272.629496) (xy 347.559928 -272.66884) (xy 347.524435 -272.702932)
			(xy 347.483932 -272.730888) (xy 347.43947 -272.751986) (xy 347.392199 -272.765678) (xy 347.343344 -272.77161)
			(xy 347.294169 -272.769629) (xy 347.24595 -272.759785) (xy 347.199934 -272.742333) (xy 347.157313 -272.717726)
			(xy 347.119192 -272.686601) (xy 347.086557 -272.649764) (xy 347.060254 -272.608168) (xy 347.040963 -272.562892)
			(xy 347.029186 -272.515108) (xy 347.025226 -272.466054) (xy 346.696538 -272.466054) (xy 346.696043 -272.490661)
			(xy 346.688148 -272.539238) (xy 346.672564 -272.585919) (xy 346.649693 -272.629496) (xy 346.620128 -272.66884)
			(xy 346.584635 -272.702932) (xy 346.544132 -272.730888) (xy 346.49967 -272.751986) (xy 346.452399 -272.765678)
			(xy 346.403544 -272.77161) (xy 346.354369 -272.769629) (xy 346.30615 -272.759785) (xy 346.260134 -272.742333)
			(xy 346.217513 -272.717726) (xy 346.179392 -272.686601) (xy 346.146757 -272.649764) (xy 346.120454 -272.608168)
			(xy 346.101163 -272.562892) (xy 346.089386 -272.515108) (xy 346.085426 -272.466054) (xy 345.756484 -272.466054)
			(xy 345.755989 -272.490661) (xy 345.748094 -272.539238) (xy 345.73251 -272.585919) (xy 345.709639 -272.629496)
			(xy 345.680074 -272.66884) (xy 345.644581 -272.702932) (xy 345.604078 -272.730888) (xy 345.559616 -272.751986)
			(xy 345.512345 -272.765678) (xy 345.46349 -272.77161) (xy 345.414315 -272.769629) (xy 345.366096 -272.759785)
			(xy 345.32008 -272.742333) (xy 345.277459 -272.717726) (xy 345.239338 -272.686601) (xy 345.206703 -272.649764)
			(xy 345.1804 -272.608168) (xy 345.161109 -272.562892) (xy 345.149332 -272.515108) (xy 345.145372 -272.466054)
			(xy 344.81643 -272.466054) (xy 344.815935 -272.490661) (xy 344.80804 -272.539238) (xy 344.792456 -272.585919)
			(xy 344.769585 -272.629496) (xy 344.74002 -272.66884) (xy 344.704527 -272.702932) (xy 344.664024 -272.730888)
			(xy 344.619562 -272.751986) (xy 344.572291 -272.765678) (xy 344.523436 -272.77161) (xy 344.474261 -272.769629)
			(xy 344.426042 -272.759785) (xy 344.380026 -272.742333) (xy 344.337405 -272.717726) (xy 344.299284 -272.686601)
			(xy 344.266649 -272.649764) (xy 344.240346 -272.608168) (xy 344.221055 -272.562892) (xy 344.209278 -272.515108)
			(xy 344.205318 -272.466054) (xy 343.88679 -272.466054) (xy 343.886278 -272.4915) (xy 343.878114 -272.541734)
			(xy 343.861998 -272.590008) (xy 343.838347 -272.635071) (xy 343.807774 -272.675757) (xy 343.77107 -272.711012)
			(xy 343.729186 -272.739922) (xy 343.683207 -272.761739) (xy 343.634323 -272.775899) (xy 343.583802 -272.782033)
			(xy 343.53295 -272.779984) (xy 343.483086 -272.769804) (xy 343.4355 -272.751757) (xy 343.391426 -272.726311)
			(xy 343.352004 -272.694124) (xy 343.318256 -272.65603) (xy 343.291055 -272.613016) (xy 343.271107 -272.566196)
			(xy 343.258928 -272.516782) (xy 343.254833 -272.466054) (xy 342.946736 -272.466054) (xy 342.946224 -272.4915)
			(xy 342.93806 -272.541734) (xy 342.921944 -272.590008) (xy 342.898293 -272.635071) (xy 342.86772 -272.675757)
			(xy 342.831016 -272.711012) (xy 342.789132 -272.739922) (xy 342.743153 -272.761739) (xy 342.694269 -272.775899)
			(xy 342.643748 -272.782033) (xy 342.592896 -272.779984) (xy 342.543032 -272.769804) (xy 342.495446 -272.751757)
			(xy 342.451372 -272.726311) (xy 342.41195 -272.694124) (xy 342.378202 -272.65603) (xy 342.351001 -272.613016)
			(xy 342.331053 -272.566196) (xy 342.318874 -272.516782) (xy 342.314779 -272.466054) (xy 341.996522 -272.466054)
			(xy 341.996027 -272.490661) (xy 341.988132 -272.539238) (xy 341.972548 -272.585919) (xy 341.949677 -272.629496)
			(xy 341.920112 -272.66884) (xy 341.884619 -272.702932) (xy 341.844116 -272.730888) (xy 341.799654 -272.751986)
			(xy 341.752383 -272.765678) (xy 341.703528 -272.77161) (xy 341.654353 -272.769629) (xy 341.606134 -272.759785)
			(xy 341.560118 -272.742333) (xy 341.517497 -272.717726) (xy 341.479376 -272.686601) (xy 341.446741 -272.649764)
			(xy 341.420438 -272.608168) (xy 341.401147 -272.562892) (xy 341.38937 -272.515108) (xy 341.38541 -272.466054)
			(xy 341.066882 -272.466054) (xy 341.06637 -272.4915) (xy 341.058206 -272.541734) (xy 341.04209 -272.590008)
			(xy 341.018439 -272.635071) (xy 340.987866 -272.675757) (xy 340.951162 -272.711012) (xy 340.909278 -272.739922)
			(xy 340.863299 -272.761739) (xy 340.814415 -272.775899) (xy 340.763894 -272.782033) (xy 340.713042 -272.779984)
			(xy 340.663178 -272.769804) (xy 340.615592 -272.751757) (xy 340.571518 -272.726311) (xy 340.532096 -272.694124)
			(xy 340.498348 -272.65603) (xy 340.471147 -272.613016) (xy 340.451199 -272.566196) (xy 340.43902 -272.516782)
			(xy 340.434925 -272.466054) (xy 340.116414 -272.466054) (xy 340.115919 -272.490661) (xy 340.108024 -272.539238)
			(xy 340.09244 -272.585919) (xy 340.069569 -272.629496) (xy 340.040004 -272.66884) (xy 340.004511 -272.702932)
			(xy 339.964008 -272.730888) (xy 339.919546 -272.751986) (xy 339.872275 -272.765678) (xy 339.82342 -272.77161)
			(xy 339.774245 -272.769629) (xy 339.726026 -272.759785) (xy 339.68001 -272.742333) (xy 339.637389 -272.717726)
			(xy 339.599268 -272.686601) (xy 339.566633 -272.649764) (xy 339.54033 -272.608168) (xy 339.521039 -272.562892)
			(xy 339.509262 -272.515108) (xy 339.505302 -272.466054) (xy 339.186774 -272.466054) (xy 339.186262 -272.4915)
			(xy 339.178098 -272.541734) (xy 339.161982 -272.590008) (xy 339.138331 -272.635071) (xy 339.107758 -272.675757)
			(xy 339.071054 -272.711012) (xy 339.02917 -272.739922) (xy 338.983191 -272.761739) (xy 338.934307 -272.775899)
			(xy 338.883786 -272.782033) (xy 338.832934 -272.779984) (xy 338.78307 -272.769804) (xy 338.735484 -272.751757)
			(xy 338.69141 -272.726311) (xy 338.651988 -272.694124) (xy 338.61824 -272.65603) (xy 338.591039 -272.613016)
			(xy 338.571091 -272.566196) (xy 338.558912 -272.516782) (xy 338.554817 -272.466054) (xy 338.236306 -272.466054)
			(xy 338.235811 -272.490661) (xy 338.227916 -272.539238) (xy 338.212332 -272.585919) (xy 338.189461 -272.629496)
			(xy 338.159896 -272.66884) (xy 338.124403 -272.702932) (xy 338.0839 -272.730888) (xy 338.039438 -272.751986)
			(xy 337.992167 -272.765678) (xy 337.943312 -272.77161) (xy 337.894137 -272.769629) (xy 337.845918 -272.759785)
			(xy 337.799902 -272.742333) (xy 337.757281 -272.717726) (xy 337.71916 -272.686601) (xy 337.686525 -272.649764)
			(xy 337.660222 -272.608168) (xy 337.640931 -272.562892) (xy 337.629154 -272.515108) (xy 337.625194 -272.466054)
			(xy 337.30692 -272.466054) (xy 337.306408 -272.4915) (xy 337.298244 -272.541734) (xy 337.282128 -272.590008)
			(xy 337.258477 -272.635071) (xy 337.227904 -272.675757) (xy 337.1912 -272.711012) (xy 337.149316 -272.739922)
			(xy 337.103337 -272.761739) (xy 337.054453 -272.775899) (xy 337.003932 -272.782033) (xy 336.95308 -272.779984)
			(xy 336.903216 -272.769804) (xy 336.85563 -272.751757) (xy 336.811556 -272.726311) (xy 336.772134 -272.694124)
			(xy 336.738386 -272.65603) (xy 336.711185 -272.613016) (xy 336.691237 -272.566196) (xy 336.679058 -272.516782)
			(xy 336.674963 -272.466054) (xy 336.366866 -272.466054) (xy 336.366354 -272.4915) (xy 336.35819 -272.541734)
			(xy 336.342074 -272.590008) (xy 336.318423 -272.635071) (xy 336.28785 -272.675757) (xy 336.251146 -272.711012)
			(xy 336.209262 -272.739922) (xy 336.163283 -272.761739) (xy 336.114399 -272.775899) (xy 336.063878 -272.782033)
			(xy 336.013026 -272.779984) (xy 335.963162 -272.769804) (xy 335.915576 -272.751757) (xy 335.871502 -272.726311)
			(xy 335.83208 -272.694124) (xy 335.798332 -272.65603) (xy 335.771131 -272.613016) (xy 335.751183 -272.566196)
			(xy 335.739004 -272.516782) (xy 335.734909 -272.466054) (xy 335.416398 -272.466054) (xy 335.415903 -272.490661)
			(xy 335.408008 -272.539238) (xy 335.392424 -272.585919) (xy 335.369553 -272.629496) (xy 335.339988 -272.66884)
			(xy 335.304495 -272.702932) (xy 335.263992 -272.730888) (xy 335.21953 -272.751986) (xy 335.172259 -272.765678)
			(xy 335.123404 -272.77161) (xy 335.074229 -272.769629) (xy 335.02601 -272.759785) (xy 334.979994 -272.742333)
			(xy 334.937373 -272.717726) (xy 334.899252 -272.686601) (xy 334.866617 -272.649764) (xy 334.840314 -272.608168)
			(xy 334.821023 -272.562892) (xy 334.809246 -272.515108) (xy 334.805286 -272.466054) (xy 334.486758 -272.466054)
			(xy 334.486246 -272.4915) (xy 334.478082 -272.541734) (xy 334.461966 -272.590008) (xy 334.438315 -272.635071)
			(xy 334.407742 -272.675757) (xy 334.371038 -272.711012) (xy 334.329154 -272.739922) (xy 334.283175 -272.761739)
			(xy 334.234291 -272.775899) (xy 334.18377 -272.782033) (xy 334.132918 -272.779984) (xy 334.083054 -272.769804)
			(xy 334.035468 -272.751757) (xy 333.991394 -272.726311) (xy 333.951972 -272.694124) (xy 333.918224 -272.65603)
			(xy 333.891023 -272.613016) (xy 333.871075 -272.566196) (xy 333.858896 -272.516782) (xy 333.854801 -272.466054)
			(xy 333.53629 -272.466054) (xy 333.535795 -272.490661) (xy 333.5279 -272.539238) (xy 333.512316 -272.585919)
			(xy 333.489445 -272.629496) (xy 333.45988 -272.66884) (xy 333.424387 -272.702932) (xy 333.383884 -272.730888)
			(xy 333.339422 -272.751986) (xy 333.292151 -272.765678) (xy 333.243296 -272.77161) (xy 333.194121 -272.769629)
			(xy 333.145902 -272.759785) (xy 333.099886 -272.742333) (xy 333.057265 -272.717726) (xy 333.019144 -272.686601)
			(xy 332.986509 -272.649764) (xy 332.960206 -272.608168) (xy 332.940915 -272.562892) (xy 332.929138 -272.515108)
			(xy 332.925178 -272.466054) (xy 332.606904 -272.466054) (xy 332.606392 -272.4915) (xy 332.598228 -272.541734)
			(xy 332.582112 -272.590008) (xy 332.558461 -272.635071) (xy 332.527888 -272.675757) (xy 332.491184 -272.711012)
			(xy 332.4493 -272.739922) (xy 332.403321 -272.761739) (xy 332.354437 -272.775899) (xy 332.303916 -272.782033)
			(xy 332.253064 -272.779984) (xy 332.2032 -272.769804) (xy 332.155614 -272.751757) (xy 332.11154 -272.726311)
			(xy 332.072118 -272.694124) (xy 332.03837 -272.65603) (xy 332.011169 -272.613016) (xy 331.991221 -272.566196)
			(xy 331.979042 -272.516782) (xy 331.974947 -272.466054) (xy 331.656436 -272.466054) (xy 331.655941 -272.490661)
			(xy 331.648046 -272.539238) (xy 331.632462 -272.585919) (xy 331.609591 -272.629496) (xy 331.580026 -272.66884)
			(xy 331.544533 -272.702932) (xy 331.50403 -272.730888) (xy 331.459568 -272.751986) (xy 331.412297 -272.765678)
			(xy 331.363442 -272.77161) (xy 331.314267 -272.769629) (xy 331.266048 -272.759785) (xy 331.220032 -272.742333)
			(xy 331.177411 -272.717726) (xy 331.13929 -272.686601) (xy 331.106655 -272.649764) (xy 331.080352 -272.608168)
			(xy 331.061061 -272.562892) (xy 331.049284 -272.515108) (xy 331.045324 -272.466054) (xy 330.726796 -272.466054)
			(xy 330.726284 -272.4915) (xy 330.71812 -272.541734) (xy 330.702004 -272.590008) (xy 330.678353 -272.635071)
			(xy 330.64778 -272.675757) (xy 330.611076 -272.711012) (xy 330.569192 -272.739922) (xy 330.523213 -272.761739)
			(xy 330.474329 -272.775899) (xy 330.423808 -272.782033) (xy 330.372956 -272.779984) (xy 330.323092 -272.769804)
			(xy 330.275506 -272.751757) (xy 330.231432 -272.726311) (xy 330.19201 -272.694124) (xy 330.158262 -272.65603)
			(xy 330.131061 -272.613016) (xy 330.111113 -272.566196) (xy 330.098934 -272.516782) (xy 330.094839 -272.466054)
			(xy 329.786742 -272.466054) (xy 329.78623 -272.4915) (xy 329.778066 -272.541734) (xy 329.76195 -272.590008)
			(xy 329.738299 -272.635071) (xy 329.707726 -272.675757) (xy 329.671022 -272.711012) (xy 329.629138 -272.739922)
			(xy 329.583159 -272.761739) (xy 329.534275 -272.775899) (xy 329.483754 -272.782033) (xy 329.432902 -272.779984)
			(xy 329.383038 -272.769804) (xy 329.335452 -272.751757) (xy 329.291378 -272.726311) (xy 329.251956 -272.694124)
			(xy 329.218208 -272.65603) (xy 329.191007 -272.613016) (xy 329.171059 -272.566196) (xy 329.15888 -272.516782)
			(xy 329.154785 -272.466054) (xy 328.836528 -272.466054) (xy 328.836033 -272.490661) (xy 328.828138 -272.539238)
			(xy 328.812554 -272.585919) (xy 328.789683 -272.629496) (xy 328.760118 -272.66884) (xy 328.724625 -272.702932)
			(xy 328.684122 -272.730888) (xy 328.63966 -272.751986) (xy 328.592389 -272.765678) (xy 328.543534 -272.77161)
			(xy 328.494359 -272.769629) (xy 328.44614 -272.759785) (xy 328.400124 -272.742333) (xy 328.357503 -272.717726)
			(xy 328.319382 -272.686601) (xy 328.286747 -272.649764) (xy 328.260444 -272.608168) (xy 328.241153 -272.562892)
			(xy 328.229376 -272.515108) (xy 328.225416 -272.466054) (xy 326.95642 -272.466054) (xy 326.955925 -272.490661)
			(xy 326.94803 -272.539238) (xy 326.932446 -272.585919) (xy 326.909575 -272.629496) (xy 326.88001 -272.66884)
			(xy 326.844517 -272.702932) (xy 326.804014 -272.730888) (xy 326.759552 -272.751986) (xy 326.712281 -272.765678)
			(xy 326.663426 -272.77161) (xy 326.614251 -272.769629) (xy 326.566032 -272.759785) (xy 326.520016 -272.742333)
			(xy 326.477395 -272.717726) (xy 326.439274 -272.686601) (xy 326.406639 -272.649764) (xy 326.380336 -272.608168)
			(xy 326.361045 -272.562892) (xy 326.349268 -272.515108) (xy 326.345308 -272.466054) (xy 310.45912 -272.466054)
			(xy 310.45912 -273.010122) (xy 324.74714 -273.010122) (xy 324.7511 -272.961068) (xy 324.762877 -272.913284)
			(xy 324.782168 -272.868008) (xy 324.808471 -272.826412) (xy 324.841106 -272.789575) (xy 324.879227 -272.75845)
			(xy 324.921848 -272.733843) (xy 324.967864 -272.716391) (xy 325.016083 -272.706547) (xy 325.065258 -272.704566)
			(xy 325.114113 -272.710498) (xy 325.161384 -272.72419) (xy 325.205846 -272.745288) (xy 325.246349 -272.773244)
			(xy 325.281842 -272.807336) (xy 325.311407 -272.84668) (xy 325.334278 -272.890257) (xy 325.349862 -272.936938)
			(xy 325.357757 -272.985515) (xy 325.358252 -273.010122) (xy 325.357757 -273.034729) (xy 325.349862 -273.083306)
			(xy 325.334278 -273.129987) (xy 325.311407 -273.173564) (xy 325.281842 -273.212908) (xy 325.246349 -273.247)
			(xy 325.205846 -273.274956) (xy 325.203519 -273.27606) (xy 328.684885 -273.27606) (xy 328.68898 -273.225332)
			(xy 328.701159 -273.175918) (xy 328.721107 -273.129098) (xy 328.748308 -273.086084) (xy 328.782056 -273.04799)
			(xy 328.821478 -273.015803) (xy 328.865552 -272.990357) (xy 328.913138 -272.97231) (xy 328.963002 -272.96213)
			(xy 329.013854 -272.960081) (xy 329.064375 -272.966215) (xy 329.113259 -272.980375) (xy 329.159238 -273.002192)
			(xy 329.201122 -273.031102) (xy 329.237826 -273.066357) (xy 329.268399 -273.107043) (xy 329.29205 -273.152106)
			(xy 329.308166 -273.20038) (xy 329.31633 -273.250614) (xy 329.316842 -273.27606) (xy 329.63537 -273.27606)
			(xy 329.63933 -273.227006) (xy 329.651107 -273.179222) (xy 329.670398 -273.133946) (xy 329.696701 -273.09235)
			(xy 329.729336 -273.055513) (xy 329.767457 -273.024388) (xy 329.810078 -272.999781) (xy 329.856094 -272.982329)
			(xy 329.904313 -272.972485) (xy 329.953488 -272.970504) (xy 330.002343 -272.976436) (xy 330.049614 -272.990128)
			(xy 330.094076 -273.011226) (xy 330.134579 -273.039182) (xy 330.170072 -273.073274) (xy 330.199637 -273.112618)
			(xy 330.222508 -273.156195) (xy 330.238092 -273.202876) (xy 330.245987 -273.251453) (xy 330.246482 -273.27606)
			(xy 330.564739 -273.27606) (xy 330.568834 -273.225332) (xy 330.581013 -273.175918) (xy 330.600961 -273.129098)
			(xy 330.628162 -273.086084) (xy 330.66191 -273.04799) (xy 330.701332 -273.015803) (xy 330.745406 -272.990357)
			(xy 330.792992 -272.97231) (xy 330.842856 -272.96213) (xy 330.893708 -272.960081) (xy 330.944229 -272.966215)
			(xy 330.993113 -272.980375) (xy 331.039092 -273.002192) (xy 331.080976 -273.031102) (xy 331.11768 -273.066357)
			(xy 331.148253 -273.107043) (xy 331.171904 -273.152106) (xy 331.18802 -273.20038) (xy 331.196184 -273.250614)
			(xy 331.196696 -273.27606) (xy 331.515224 -273.27606) (xy 331.519184 -273.227006) (xy 331.530961 -273.179222)
			(xy 331.550252 -273.133946) (xy 331.576555 -273.09235) (xy 331.60919 -273.055513) (xy 331.647311 -273.024388)
			(xy 331.689932 -272.999781) (xy 331.735948 -272.982329) (xy 331.784167 -272.972485) (xy 331.833342 -272.970504)
			(xy 331.882197 -272.976436) (xy 331.929468 -272.990128) (xy 331.97393 -273.011226) (xy 332.014433 -273.039182)
			(xy 332.049926 -273.073274) (xy 332.079491 -273.112618) (xy 332.102362 -273.156195) (xy 332.117946 -273.202876)
			(xy 332.125841 -273.251453) (xy 332.126336 -273.27606) (xy 332.444847 -273.27606) (xy 332.448942 -273.225332)
			(xy 332.461121 -273.175918) (xy 332.481069 -273.129098) (xy 332.50827 -273.086084) (xy 332.542018 -273.04799)
			(xy 332.58144 -273.015803) (xy 332.625514 -272.990357) (xy 332.6731 -272.97231) (xy 332.722964 -272.96213)
			(xy 332.773816 -272.960081) (xy 332.824337 -272.966215) (xy 332.873221 -272.980375) (xy 332.9192 -273.002192)
			(xy 332.961084 -273.031102) (xy 332.997788 -273.066357) (xy 333.028361 -273.107043) (xy 333.052012 -273.152106)
			(xy 333.068128 -273.20038) (xy 333.076292 -273.250614) (xy 333.076804 -273.27606) (xy 333.384901 -273.27606)
			(xy 333.388996 -273.225332) (xy 333.401175 -273.175918) (xy 333.421123 -273.129098) (xy 333.448324 -273.086084)
			(xy 333.482072 -273.04799) (xy 333.521494 -273.015803) (xy 333.565568 -272.990357) (xy 333.613154 -272.97231)
			(xy 333.663018 -272.96213) (xy 333.71387 -272.960081) (xy 333.764391 -272.966215) (xy 333.813275 -272.980375)
			(xy 333.859254 -273.002192) (xy 333.901138 -273.031102) (xy 333.937842 -273.066357) (xy 333.968415 -273.107043)
			(xy 333.992066 -273.152106) (xy 334.008182 -273.20038) (xy 334.016346 -273.250614) (xy 334.016858 -273.27606)
			(xy 335.264755 -273.27606) (xy 335.26885 -273.225332) (xy 335.281029 -273.175918) (xy 335.300977 -273.129098)
			(xy 335.328178 -273.086084) (xy 335.361926 -273.04799) (xy 335.401348 -273.015803) (xy 335.445422 -272.990357)
			(xy 335.493008 -272.97231) (xy 335.542872 -272.96213) (xy 335.593724 -272.960081) (xy 335.644245 -272.966215)
			(xy 335.693129 -272.980375) (xy 335.739108 -273.002192) (xy 335.780992 -273.031102) (xy 335.817696 -273.066357)
			(xy 335.848269 -273.107043) (xy 335.87192 -273.152106) (xy 335.888036 -273.20038) (xy 335.8962 -273.250614)
			(xy 335.896712 -273.27606) (xy 336.21524 -273.27606) (xy 336.2192 -273.227006) (xy 336.230977 -273.179222)
			(xy 336.250268 -273.133946) (xy 336.276571 -273.09235) (xy 336.309206 -273.055513) (xy 336.347327 -273.024388)
			(xy 336.389948 -272.999781) (xy 336.435964 -272.982329) (xy 336.484183 -272.972485) (xy 336.533358 -272.970504)
			(xy 336.582213 -272.976436) (xy 336.629484 -272.990128) (xy 336.673946 -273.011226) (xy 336.714449 -273.039182)
			(xy 336.749942 -273.073274) (xy 336.779507 -273.112618) (xy 336.802378 -273.156195) (xy 336.817962 -273.202876)
			(xy 336.825857 -273.251453) (xy 336.826352 -273.27606) (xy 337.144863 -273.27606) (xy 337.148958 -273.225332)
			(xy 337.161137 -273.175918) (xy 337.181085 -273.129098) (xy 337.208286 -273.086084) (xy 337.242034 -273.04799)
			(xy 337.281456 -273.015803) (xy 337.32553 -272.990357) (xy 337.373116 -272.97231) (xy 337.42298 -272.96213)
			(xy 337.473832 -272.960081) (xy 337.524353 -272.966215) (xy 337.573237 -272.980375) (xy 337.619216 -273.002192)
			(xy 337.6611 -273.031102) (xy 337.697804 -273.066357) (xy 337.728377 -273.107043) (xy 337.752028 -273.152106)
			(xy 337.768144 -273.20038) (xy 337.776308 -273.250614) (xy 337.77682 -273.27606) (xy 338.095348 -273.27606)
			(xy 338.099308 -273.227006) (xy 338.111085 -273.179222) (xy 338.130376 -273.133946) (xy 338.156679 -273.09235)
			(xy 338.189314 -273.055513) (xy 338.227435 -273.024388) (xy 338.270056 -272.999781) (xy 338.316072 -272.982329)
			(xy 338.364291 -272.972485) (xy 338.413466 -272.970504) (xy 338.462321 -272.976436) (xy 338.509592 -272.990128)
			(xy 338.554054 -273.011226) (xy 338.594557 -273.039182) (xy 338.63005 -273.073274) (xy 338.659615 -273.112618)
			(xy 338.682486 -273.156195) (xy 338.69807 -273.202876) (xy 338.705965 -273.251453) (xy 338.70646 -273.27606)
			(xy 339.024971 -273.27606) (xy 339.029066 -273.225332) (xy 339.041245 -273.175918) (xy 339.061193 -273.129098)
			(xy 339.088394 -273.086084) (xy 339.122142 -273.04799) (xy 339.161564 -273.015803) (xy 339.205638 -272.990357)
			(xy 339.253224 -272.97231) (xy 339.303088 -272.96213) (xy 339.35394 -272.960081) (xy 339.404461 -272.966215)
			(xy 339.453345 -272.980375) (xy 339.499324 -273.002192) (xy 339.541208 -273.031102) (xy 339.577912 -273.066357)
			(xy 339.608485 -273.107043) (xy 339.632136 -273.152106) (xy 339.648252 -273.20038) (xy 339.656416 -273.250614)
			(xy 339.656928 -273.27606) (xy 339.964771 -273.27606) (xy 339.968866 -273.225332) (xy 339.981045 -273.175918)
			(xy 340.000993 -273.129098) (xy 340.028194 -273.086084) (xy 340.061942 -273.04799) (xy 340.101364 -273.015803)
			(xy 340.145438 -272.990357) (xy 340.193024 -272.97231) (xy 340.242888 -272.96213) (xy 340.29374 -272.960081)
			(xy 340.344261 -272.966215) (xy 340.393145 -272.980375) (xy 340.439124 -273.002192) (xy 340.481008 -273.031102)
			(xy 340.517712 -273.066357) (xy 340.548285 -273.107043) (xy 340.571936 -273.152106) (xy 340.588052 -273.20038)
			(xy 340.596216 -273.250614) (xy 340.596728 -273.27606) (xy 341.844879 -273.27606) (xy 341.848974 -273.225332)
			(xy 341.861153 -273.175918) (xy 341.881101 -273.129098) (xy 341.908302 -273.086084) (xy 341.94205 -273.04799)
			(xy 341.981472 -273.015803) (xy 342.025546 -272.990357) (xy 342.073132 -272.97231) (xy 342.122996 -272.96213)
			(xy 342.173848 -272.960081) (xy 342.224369 -272.966215) (xy 342.273253 -272.980375) (xy 342.319232 -273.002192)
			(xy 342.361116 -273.031102) (xy 342.39782 -273.066357) (xy 342.428393 -273.107043) (xy 342.452044 -273.152106)
			(xy 342.46816 -273.20038) (xy 342.476324 -273.250614) (xy 342.476836 -273.27606) (xy 342.795364 -273.27606)
			(xy 342.799324 -273.227006) (xy 342.811101 -273.179222) (xy 342.830392 -273.133946) (xy 342.856695 -273.09235)
			(xy 342.88933 -273.055513) (xy 342.927451 -273.024388) (xy 342.970072 -272.999781) (xy 343.016088 -272.982329)
			(xy 343.064307 -272.972485) (xy 343.113482 -272.970504) (xy 343.162337 -272.976436) (xy 343.209608 -272.990128)
			(xy 343.25407 -273.011226) (xy 343.294573 -273.039182) (xy 343.330066 -273.073274) (xy 343.359631 -273.112618)
			(xy 343.382502 -273.156195) (xy 343.398086 -273.202876) (xy 343.405981 -273.251453) (xy 343.406476 -273.27606)
			(xy 343.724987 -273.27606) (xy 343.729082 -273.225332) (xy 343.741261 -273.175918) (xy 343.761209 -273.129098)
			(xy 343.78841 -273.086084) (xy 343.822158 -273.04799) (xy 343.86158 -273.015803) (xy 343.905654 -272.990357)
			(xy 343.95324 -272.97231) (xy 344.003104 -272.96213) (xy 344.053956 -272.960081) (xy 344.104477 -272.966215)
			(xy 344.153361 -272.980375) (xy 344.19934 -273.002192) (xy 344.241224 -273.031102) (xy 344.277928 -273.066357)
			(xy 344.308501 -273.107043) (xy 344.332152 -273.152106) (xy 344.348268 -273.20038) (xy 344.356432 -273.250614)
			(xy 344.356944 -273.27606) (xy 344.675218 -273.27606) (xy 344.679178 -273.227006) (xy 344.690955 -273.179222)
			(xy 344.710246 -273.133946) (xy 344.736549 -273.09235) (xy 344.769184 -273.055513) (xy 344.807305 -273.024388)
			(xy 344.849926 -272.999781) (xy 344.895942 -272.982329) (xy 344.944161 -272.972485) (xy 344.993336 -272.970504)
			(xy 345.042191 -272.976436) (xy 345.089462 -272.990128) (xy 345.133924 -273.011226) (xy 345.174427 -273.039182)
			(xy 345.20992 -273.073274) (xy 345.239485 -273.112618) (xy 345.262356 -273.156195) (xy 345.27794 -273.202876)
			(xy 345.285835 -273.251453) (xy 345.28633 -273.27606) (xy 345.604841 -273.27606) (xy 345.608936 -273.225332)
			(xy 345.621115 -273.175918) (xy 345.641063 -273.129098) (xy 345.668264 -273.086084) (xy 345.702012 -273.04799)
			(xy 345.741434 -273.015803) (xy 345.785508 -272.990357) (xy 345.833094 -272.97231) (xy 345.882958 -272.96213)
			(xy 345.93381 -272.960081) (xy 345.984331 -272.966215) (xy 346.033215 -272.980375) (xy 346.079194 -273.002192)
			(xy 346.121078 -273.031102) (xy 346.157782 -273.066357) (xy 346.188355 -273.107043) (xy 346.212006 -273.152106)
			(xy 346.228122 -273.20038) (xy 346.236286 -273.250614) (xy 346.236798 -273.27606) (xy 346.544895 -273.27606)
			(xy 346.54899 -273.225332) (xy 346.561169 -273.175918) (xy 346.581117 -273.129098) (xy 346.608318 -273.086084)
			(xy 346.642066 -273.04799) (xy 346.681488 -273.015803) (xy 346.725562 -272.990357) (xy 346.773148 -272.97231)
			(xy 346.823012 -272.96213) (xy 346.873864 -272.960081) (xy 346.924385 -272.966215) (xy 346.973269 -272.980375)
			(xy 347.019248 -273.002192) (xy 347.061132 -273.031102) (xy 347.097836 -273.066357) (xy 347.128409 -273.107043)
			(xy 347.15206 -273.152106) (xy 347.168176 -273.20038) (xy 347.17634 -273.250614) (xy 347.176852 -273.27606)
			(xy 347.49538 -273.27606) (xy 347.49934 -273.227006) (xy 347.511117 -273.179222) (xy 347.530408 -273.133946)
			(xy 347.556711 -273.09235) (xy 347.589346 -273.055513) (xy 347.627467 -273.024388) (xy 347.670088 -272.999781)
			(xy 347.716104 -272.982329) (xy 347.764323 -272.972485) (xy 347.813498 -272.970504) (xy 347.862353 -272.976436)
			(xy 347.909624 -272.990128) (xy 347.954086 -273.011226) (xy 347.994589 -273.039182) (xy 348.030082 -273.073274)
			(xy 348.059647 -273.112618) (xy 348.082518 -273.156195) (xy 348.098102 -273.202876) (xy 348.105997 -273.251453)
			(xy 348.106492 -273.27606) (xy 348.425003 -273.27606) (xy 348.429098 -273.225332) (xy 348.441277 -273.175918)
			(xy 348.461225 -273.129098) (xy 348.488426 -273.086084) (xy 348.522174 -273.04799) (xy 348.561596 -273.015803)
			(xy 348.60567 -272.990357) (xy 348.653256 -272.97231) (xy 348.70312 -272.96213) (xy 348.753972 -272.960081)
			(xy 348.804493 -272.966215) (xy 348.853377 -272.980375) (xy 348.899356 -273.002192) (xy 348.94124 -273.031102)
			(xy 348.977944 -273.066357) (xy 349.008517 -273.107043) (xy 349.032168 -273.152106) (xy 349.048284 -273.20038)
			(xy 349.056448 -273.250614) (xy 349.05696 -273.27606) (xy 349.364803 -273.27606) (xy 349.368898 -273.225332)
			(xy 349.381077 -273.175918) (xy 349.401025 -273.129098) (xy 349.428226 -273.086084) (xy 349.461974 -273.04799)
			(xy 349.501396 -273.015803) (xy 349.54547 -272.990357) (xy 349.593056 -272.97231) (xy 349.64292 -272.96213)
			(xy 349.693772 -272.960081) (xy 349.744293 -272.966215) (xy 349.793177 -272.980375) (xy 349.839156 -273.002192)
			(xy 349.88104 -273.031102) (xy 349.917744 -273.066357) (xy 349.948317 -273.107043) (xy 349.971968 -273.152106)
			(xy 349.988084 -273.20038) (xy 349.996248 -273.250614) (xy 349.99676 -273.27606) (xy 350.315288 -273.27606)
			(xy 350.319248 -273.227006) (xy 350.331025 -273.179222) (xy 350.350316 -273.133946) (xy 350.376619 -273.09235)
			(xy 350.409254 -273.055513) (xy 350.447375 -273.024388) (xy 350.489996 -272.999781) (xy 350.536012 -272.982329)
			(xy 350.584231 -272.972485) (xy 350.633406 -272.970504) (xy 350.682261 -272.976436) (xy 350.729532 -272.990128)
			(xy 350.773994 -273.011226) (xy 350.814497 -273.039182) (xy 350.84999 -273.073274) (xy 350.879555 -273.112618)
			(xy 350.902426 -273.156195) (xy 350.91801 -273.202876) (xy 350.925905 -273.251453) (xy 350.9264 -273.27606)
			(xy 350.925905 -273.300667) (xy 350.91801 -273.349244) (xy 350.902426 -273.395925) (xy 350.879555 -273.439502)
			(xy 350.84999 -273.478846) (xy 350.814497 -273.512938) (xy 350.773994 -273.540894) (xy 350.729532 -273.561992)
			(xy 350.682261 -273.575684) (xy 350.633406 -273.581616) (xy 350.584231 -273.579635) (xy 350.536012 -273.569791)
			(xy 350.489996 -273.552339) (xy 350.447375 -273.527732) (xy 350.409254 -273.496607) (xy 350.376619 -273.45977)
			(xy 350.350316 -273.418174) (xy 350.331025 -273.372898) (xy 350.319248 -273.325114) (xy 350.315288 -273.27606)
			(xy 349.99676 -273.27606) (xy 349.996248 -273.301506) (xy 349.988084 -273.35174) (xy 349.971968 -273.400014)
			(xy 349.948317 -273.445077) (xy 349.917744 -273.485763) (xy 349.88104 -273.521018) (xy 349.839156 -273.549928)
			(xy 349.793177 -273.571745) (xy 349.744293 -273.585905) (xy 349.693772 -273.592039) (xy 349.64292 -273.58999)
			(xy 349.593056 -273.57981) (xy 349.54547 -273.561763) (xy 349.501396 -273.536317) (xy 349.461974 -273.50413)
			(xy 349.428226 -273.466036) (xy 349.401025 -273.423022) (xy 349.381077 -273.376202) (xy 349.368898 -273.326788)
			(xy 349.364803 -273.27606) (xy 349.05696 -273.27606) (xy 349.056448 -273.301506) (xy 349.048284 -273.35174)
			(xy 349.032168 -273.400014) (xy 349.008517 -273.445077) (xy 348.977944 -273.485763) (xy 348.94124 -273.521018)
			(xy 348.899356 -273.549928) (xy 348.853377 -273.571745) (xy 348.804493 -273.585905) (xy 348.753972 -273.592039)
			(xy 348.70312 -273.58999) (xy 348.653256 -273.57981) (xy 348.60567 -273.561763) (xy 348.561596 -273.536317)
			(xy 348.522174 -273.50413) (xy 348.488426 -273.466036) (xy 348.461225 -273.423022) (xy 348.441277 -273.376202)
			(xy 348.429098 -273.326788) (xy 348.425003 -273.27606) (xy 348.106492 -273.27606) (xy 348.105997 -273.300667)
			(xy 348.098102 -273.349244) (xy 348.082518 -273.395925) (xy 348.059647 -273.439502) (xy 348.030082 -273.478846)
			(xy 347.994589 -273.512938) (xy 347.954086 -273.540894) (xy 347.909624 -273.561992) (xy 347.862353 -273.575684)
			(xy 347.813498 -273.581616) (xy 347.764323 -273.579635) (xy 347.716104 -273.569791) (xy 347.670088 -273.552339)
			(xy 347.627467 -273.527732) (xy 347.589346 -273.496607) (xy 347.556711 -273.45977) (xy 347.530408 -273.418174)
			(xy 347.511117 -273.372898) (xy 347.49934 -273.325114) (xy 347.49538 -273.27606) (xy 347.176852 -273.27606)
			(xy 347.17634 -273.301506) (xy 347.168176 -273.35174) (xy 347.15206 -273.400014) (xy 347.128409 -273.445077)
			(xy 347.097836 -273.485763) (xy 347.061132 -273.521018) (xy 347.019248 -273.549928) (xy 346.973269 -273.571745)
			(xy 346.924385 -273.585905) (xy 346.873864 -273.592039) (xy 346.823012 -273.58999) (xy 346.773148 -273.57981)
			(xy 346.725562 -273.561763) (xy 346.681488 -273.536317) (xy 346.642066 -273.50413) (xy 346.608318 -273.466036)
			(xy 346.581117 -273.423022) (xy 346.561169 -273.376202) (xy 346.54899 -273.326788) (xy 346.544895 -273.27606)
			(xy 346.236798 -273.27606) (xy 346.236286 -273.301506) (xy 346.228122 -273.35174) (xy 346.212006 -273.400014)
			(xy 346.188355 -273.445077) (xy 346.157782 -273.485763) (xy 346.121078 -273.521018) (xy 346.079194 -273.549928)
			(xy 346.033215 -273.571745) (xy 345.984331 -273.585905) (xy 345.93381 -273.592039) (xy 345.882958 -273.58999)
			(xy 345.833094 -273.57981) (xy 345.785508 -273.561763) (xy 345.741434 -273.536317) (xy 345.702012 -273.50413)
			(xy 345.668264 -273.466036) (xy 345.641063 -273.423022) (xy 345.621115 -273.376202) (xy 345.608936 -273.326788)
			(xy 345.604841 -273.27606) (xy 345.28633 -273.27606) (xy 345.285835 -273.300667) (xy 345.27794 -273.349244)
			(xy 345.262356 -273.395925) (xy 345.239485 -273.439502) (xy 345.20992 -273.478846) (xy 345.174427 -273.512938)
			(xy 345.133924 -273.540894) (xy 345.089462 -273.561992) (xy 345.042191 -273.575684) (xy 344.993336 -273.581616)
			(xy 344.944161 -273.579635) (xy 344.895942 -273.569791) (xy 344.849926 -273.552339) (xy 344.807305 -273.527732)
			(xy 344.769184 -273.496607) (xy 344.736549 -273.45977) (xy 344.710246 -273.418174) (xy 344.690955 -273.372898)
			(xy 344.679178 -273.325114) (xy 344.675218 -273.27606) (xy 344.356944 -273.27606) (xy 344.356432 -273.301506)
			(xy 344.348268 -273.35174) (xy 344.332152 -273.400014) (xy 344.308501 -273.445077) (xy 344.277928 -273.485763)
			(xy 344.241224 -273.521018) (xy 344.19934 -273.549928) (xy 344.153361 -273.571745) (xy 344.104477 -273.585905)
			(xy 344.053956 -273.592039) (xy 344.003104 -273.58999) (xy 343.95324 -273.57981) (xy 343.905654 -273.561763)
			(xy 343.86158 -273.536317) (xy 343.822158 -273.50413) (xy 343.78841 -273.466036) (xy 343.761209 -273.423022)
			(xy 343.741261 -273.376202) (xy 343.729082 -273.326788) (xy 343.724987 -273.27606) (xy 343.406476 -273.27606)
			(xy 343.405981 -273.300667) (xy 343.398086 -273.349244) (xy 343.382502 -273.395925) (xy 343.359631 -273.439502)
			(xy 343.330066 -273.478846) (xy 343.294573 -273.512938) (xy 343.25407 -273.540894) (xy 343.209608 -273.561992)
			(xy 343.162337 -273.575684) (xy 343.113482 -273.581616) (xy 343.064307 -273.579635) (xy 343.016088 -273.569791)
			(xy 342.970072 -273.552339) (xy 342.927451 -273.527732) (xy 342.88933 -273.496607) (xy 342.856695 -273.45977)
			(xy 342.830392 -273.418174) (xy 342.811101 -273.372898) (xy 342.799324 -273.325114) (xy 342.795364 -273.27606)
			(xy 342.476836 -273.27606) (xy 342.476324 -273.301506) (xy 342.46816 -273.35174) (xy 342.452044 -273.400014)
			(xy 342.428393 -273.445077) (xy 342.39782 -273.485763) (xy 342.361116 -273.521018) (xy 342.319232 -273.549928)
			(xy 342.273253 -273.571745) (xy 342.224369 -273.585905) (xy 342.173848 -273.592039) (xy 342.122996 -273.58999)
			(xy 342.073132 -273.57981) (xy 342.025546 -273.561763) (xy 341.981472 -273.536317) (xy 341.94205 -273.50413)
			(xy 341.908302 -273.466036) (xy 341.881101 -273.423022) (xy 341.861153 -273.376202) (xy 341.848974 -273.326788)
			(xy 341.844879 -273.27606) (xy 340.596728 -273.27606) (xy 340.596216 -273.301506) (xy 340.588052 -273.35174)
			(xy 340.571936 -273.400014) (xy 340.548285 -273.445077) (xy 340.517712 -273.485763) (xy 340.481008 -273.521018)
			(xy 340.439124 -273.549928) (xy 340.393145 -273.571745) (xy 340.344261 -273.585905) (xy 340.29374 -273.592039)
			(xy 340.242888 -273.58999) (xy 340.193024 -273.57981) (xy 340.145438 -273.561763) (xy 340.101364 -273.536317)
			(xy 340.061942 -273.50413) (xy 340.028194 -273.466036) (xy 340.000993 -273.423022) (xy 339.981045 -273.376202)
			(xy 339.968866 -273.326788) (xy 339.964771 -273.27606) (xy 339.656928 -273.27606) (xy 339.656416 -273.301506)
			(xy 339.648252 -273.35174) (xy 339.632136 -273.400014) (xy 339.608485 -273.445077) (xy 339.577912 -273.485763)
			(xy 339.541208 -273.521018) (xy 339.499324 -273.549928) (xy 339.453345 -273.571745) (xy 339.404461 -273.585905)
			(xy 339.35394 -273.592039) (xy 339.303088 -273.58999) (xy 339.253224 -273.57981) (xy 339.205638 -273.561763)
			(xy 339.161564 -273.536317) (xy 339.122142 -273.50413) (xy 339.088394 -273.466036) (xy 339.061193 -273.423022)
			(xy 339.041245 -273.376202) (xy 339.029066 -273.326788) (xy 339.024971 -273.27606) (xy 338.70646 -273.27606)
			(xy 338.705965 -273.300667) (xy 338.69807 -273.349244) (xy 338.682486 -273.395925) (xy 338.659615 -273.439502)
			(xy 338.63005 -273.478846) (xy 338.594557 -273.512938) (xy 338.554054 -273.540894) (xy 338.509592 -273.561992)
			(xy 338.462321 -273.575684) (xy 338.413466 -273.581616) (xy 338.364291 -273.579635) (xy 338.316072 -273.569791)
			(xy 338.270056 -273.552339) (xy 338.227435 -273.527732) (xy 338.189314 -273.496607) (xy 338.156679 -273.45977)
			(xy 338.130376 -273.418174) (xy 338.111085 -273.372898) (xy 338.099308 -273.325114) (xy 338.095348 -273.27606)
			(xy 337.77682 -273.27606) (xy 337.776308 -273.301506) (xy 337.768144 -273.35174) (xy 337.752028 -273.400014)
			(xy 337.728377 -273.445077) (xy 337.697804 -273.485763) (xy 337.6611 -273.521018) (xy 337.619216 -273.549928)
			(xy 337.573237 -273.571745) (xy 337.524353 -273.585905) (xy 337.473832 -273.592039) (xy 337.42298 -273.58999)
			(xy 337.373116 -273.57981) (xy 337.32553 -273.561763) (xy 337.281456 -273.536317) (xy 337.242034 -273.50413)
			(xy 337.208286 -273.466036) (xy 337.181085 -273.423022) (xy 337.161137 -273.376202) (xy 337.148958 -273.326788)
			(xy 337.144863 -273.27606) (xy 336.826352 -273.27606) (xy 336.825857 -273.300667) (xy 336.817962 -273.349244)
			(xy 336.802378 -273.395925) (xy 336.779507 -273.439502) (xy 336.749942 -273.478846) (xy 336.714449 -273.512938)
			(xy 336.673946 -273.540894) (xy 336.629484 -273.561992) (xy 336.582213 -273.575684) (xy 336.533358 -273.581616)
			(xy 336.484183 -273.579635) (xy 336.435964 -273.569791) (xy 336.389948 -273.552339) (xy 336.347327 -273.527732)
			(xy 336.309206 -273.496607) (xy 336.276571 -273.45977) (xy 336.250268 -273.418174) (xy 336.230977 -273.372898)
			(xy 336.2192 -273.325114) (xy 336.21524 -273.27606) (xy 335.896712 -273.27606) (xy 335.8962 -273.301506)
			(xy 335.888036 -273.35174) (xy 335.87192 -273.400014) (xy 335.848269 -273.445077) (xy 335.817696 -273.485763)
			(xy 335.780992 -273.521018) (xy 335.739108 -273.549928) (xy 335.693129 -273.571745) (xy 335.644245 -273.585905)
			(xy 335.593724 -273.592039) (xy 335.542872 -273.58999) (xy 335.493008 -273.57981) (xy 335.445422 -273.561763)
			(xy 335.401348 -273.536317) (xy 335.361926 -273.50413) (xy 335.328178 -273.466036) (xy 335.300977 -273.423022)
			(xy 335.281029 -273.376202) (xy 335.26885 -273.326788) (xy 335.264755 -273.27606) (xy 334.016858 -273.27606)
			(xy 334.016346 -273.301506) (xy 334.008182 -273.35174) (xy 333.992066 -273.400014) (xy 333.968415 -273.445077)
			(xy 333.937842 -273.485763) (xy 333.901138 -273.521018) (xy 333.859254 -273.549928) (xy 333.813275 -273.571745)
			(xy 333.764391 -273.585905) (xy 333.71387 -273.592039) (xy 333.663018 -273.58999) (xy 333.613154 -273.57981)
			(xy 333.565568 -273.561763) (xy 333.521494 -273.536317) (xy 333.482072 -273.50413) (xy 333.448324 -273.466036)
			(xy 333.421123 -273.423022) (xy 333.401175 -273.376202) (xy 333.388996 -273.326788) (xy 333.384901 -273.27606)
			(xy 333.076804 -273.27606) (xy 333.076292 -273.301506) (xy 333.068128 -273.35174) (xy 333.052012 -273.400014)
			(xy 333.028361 -273.445077) (xy 332.997788 -273.485763) (xy 332.961084 -273.521018) (xy 332.9192 -273.549928)
			(xy 332.873221 -273.571745) (xy 332.824337 -273.585905) (xy 332.773816 -273.592039) (xy 332.722964 -273.58999)
			(xy 332.6731 -273.57981) (xy 332.625514 -273.561763) (xy 332.58144 -273.536317) (xy 332.542018 -273.50413)
			(xy 332.50827 -273.466036) (xy 332.481069 -273.423022) (xy 332.461121 -273.376202) (xy 332.448942 -273.326788)
			(xy 332.444847 -273.27606) (xy 332.126336 -273.27606) (xy 332.125841 -273.300667) (xy 332.117946 -273.349244)
			(xy 332.102362 -273.395925) (xy 332.079491 -273.439502) (xy 332.049926 -273.478846) (xy 332.014433 -273.512938)
			(xy 331.97393 -273.540894) (xy 331.929468 -273.561992) (xy 331.882197 -273.575684) (xy 331.833342 -273.581616)
			(xy 331.784167 -273.579635) (xy 331.735948 -273.569791) (xy 331.689932 -273.552339) (xy 331.647311 -273.527732)
			(xy 331.60919 -273.496607) (xy 331.576555 -273.45977) (xy 331.550252 -273.418174) (xy 331.530961 -273.372898)
			(xy 331.519184 -273.325114) (xy 331.515224 -273.27606) (xy 331.196696 -273.27606) (xy 331.196184 -273.301506)
			(xy 331.18802 -273.35174) (xy 331.171904 -273.400014) (xy 331.148253 -273.445077) (xy 331.11768 -273.485763)
			(xy 331.080976 -273.521018) (xy 331.039092 -273.549928) (xy 330.993113 -273.571745) (xy 330.944229 -273.585905)
			(xy 330.893708 -273.592039) (xy 330.842856 -273.58999) (xy 330.792992 -273.57981) (xy 330.745406 -273.561763)
			(xy 330.701332 -273.536317) (xy 330.66191 -273.50413) (xy 330.628162 -273.466036) (xy 330.600961 -273.423022)
			(xy 330.581013 -273.376202) (xy 330.568834 -273.326788) (xy 330.564739 -273.27606) (xy 330.246482 -273.27606)
			(xy 330.245987 -273.300667) (xy 330.238092 -273.349244) (xy 330.222508 -273.395925) (xy 330.199637 -273.439502)
			(xy 330.170072 -273.478846) (xy 330.134579 -273.512938) (xy 330.094076 -273.540894) (xy 330.049614 -273.561992)
			(xy 330.002343 -273.575684) (xy 329.953488 -273.581616) (xy 329.904313 -273.579635) (xy 329.856094 -273.569791)
			(xy 329.810078 -273.552339) (xy 329.767457 -273.527732) (xy 329.729336 -273.496607) (xy 329.696701 -273.45977)
			(xy 329.670398 -273.418174) (xy 329.651107 -273.372898) (xy 329.63933 -273.325114) (xy 329.63537 -273.27606)
			(xy 329.316842 -273.27606) (xy 329.31633 -273.301506) (xy 329.308166 -273.35174) (xy 329.29205 -273.400014)
			(xy 329.268399 -273.445077) (xy 329.237826 -273.485763) (xy 329.201122 -273.521018) (xy 329.159238 -273.549928)
			(xy 329.113259 -273.571745) (xy 329.064375 -273.585905) (xy 329.013854 -273.592039) (xy 328.963002 -273.58999)
			(xy 328.913138 -273.57981) (xy 328.865552 -273.561763) (xy 328.821478 -273.536317) (xy 328.782056 -273.50413)
			(xy 328.748308 -273.466036) (xy 328.721107 -273.423022) (xy 328.701159 -273.376202) (xy 328.68898 -273.326788)
			(xy 328.684885 -273.27606) (xy 325.203519 -273.27606) (xy 325.161384 -273.296054) (xy 325.114113 -273.309746)
			(xy 325.065258 -273.315678) (xy 325.016083 -273.313697) (xy 324.967864 -273.303853) (xy 324.921848 -273.286401)
			(xy 324.879227 -273.261794) (xy 324.841106 -273.230669) (xy 324.808471 -273.193832) (xy 324.782168 -273.152236)
			(xy 324.762877 -273.10696) (xy 324.7511 -273.059176) (xy 324.74714 -273.010122) (xy 310.45912 -273.010122)
			(xy 310.45912 -274.086066) (xy 326.345308 -274.086066) (xy 326.349268 -274.037012) (xy 326.361045 -273.989228)
			(xy 326.380336 -273.943952) (xy 326.406639 -273.902356) (xy 326.439274 -273.865519) (xy 326.477395 -273.834394)
			(xy 326.520016 -273.809787) (xy 326.566032 -273.792335) (xy 326.614251 -273.782491) (xy 326.663426 -273.78051)
			(xy 326.712281 -273.786442) (xy 326.759552 -273.800134) (xy 326.804014 -273.821232) (xy 326.844517 -273.849188)
			(xy 326.88001 -273.88328) (xy 326.909575 -273.922624) (xy 326.932446 -273.966201) (xy 326.94803 -274.012882)
			(xy 326.955925 -274.061459) (xy 326.95642 -274.086066) (xy 328.225416 -274.086066) (xy 328.229376 -274.037012)
			(xy 328.241153 -273.989228) (xy 328.260444 -273.943952) (xy 328.286747 -273.902356) (xy 328.319382 -273.865519)
			(xy 328.357503 -273.834394) (xy 328.400124 -273.809787) (xy 328.44614 -273.792335) (xy 328.494359 -273.782491)
			(xy 328.543534 -273.78051) (xy 328.592389 -273.786442) (xy 328.63966 -273.800134) (xy 328.684122 -273.821232)
			(xy 328.724625 -273.849188) (xy 328.760118 -273.88328) (xy 328.789683 -273.922624) (xy 328.812554 -273.966201)
			(xy 328.828138 -274.012882) (xy 328.836033 -274.061459) (xy 328.836528 -274.086066) (xy 329.154785 -274.086066)
			(xy 329.15888 -274.035338) (xy 329.171059 -273.985924) (xy 329.191007 -273.939104) (xy 329.218208 -273.89609)
			(xy 329.251956 -273.857996) (xy 329.291378 -273.825809) (xy 329.335452 -273.800363) (xy 329.383038 -273.782316)
			(xy 329.432902 -273.772136) (xy 329.483754 -273.770087) (xy 329.534275 -273.776221) (xy 329.583159 -273.790381)
			(xy 329.629138 -273.812198) (xy 329.671022 -273.841108) (xy 329.707726 -273.876363) (xy 329.738299 -273.917049)
			(xy 329.76195 -273.962112) (xy 329.778066 -274.010386) (xy 329.78623 -274.06062) (xy 329.786742 -274.086066)
			(xy 330.094839 -274.086066) (xy 330.098934 -274.035338) (xy 330.111113 -273.985924) (xy 330.131061 -273.939104)
			(xy 330.158262 -273.89609) (xy 330.19201 -273.857996) (xy 330.231432 -273.825809) (xy 330.275506 -273.800363)
			(xy 330.323092 -273.782316) (xy 330.372956 -273.772136) (xy 330.423808 -273.770087) (xy 330.474329 -273.776221)
			(xy 330.523213 -273.790381) (xy 330.569192 -273.812198) (xy 330.611076 -273.841108) (xy 330.64778 -273.876363)
			(xy 330.678353 -273.917049) (xy 330.702004 -273.962112) (xy 330.71812 -274.010386) (xy 330.726284 -274.06062)
			(xy 330.726796 -274.086066) (xy 331.045324 -274.086066) (xy 331.049284 -274.037012) (xy 331.061061 -273.989228)
			(xy 331.080352 -273.943952) (xy 331.106655 -273.902356) (xy 331.13929 -273.865519) (xy 331.177411 -273.834394)
			(xy 331.220032 -273.809787) (xy 331.266048 -273.792335) (xy 331.314267 -273.782491) (xy 331.363442 -273.78051)
			(xy 331.412297 -273.786442) (xy 331.459568 -273.800134) (xy 331.50403 -273.821232) (xy 331.544533 -273.849188)
			(xy 331.580026 -273.88328) (xy 331.609591 -273.922624) (xy 331.632462 -273.966201) (xy 331.648046 -274.012882)
			(xy 331.655941 -274.061459) (xy 331.656436 -274.086066) (xy 331.974947 -274.086066) (xy 331.979042 -274.035338)
			(xy 331.991221 -273.985924) (xy 332.011169 -273.939104) (xy 332.03837 -273.89609) (xy 332.072118 -273.857996)
			(xy 332.11154 -273.825809) (xy 332.155614 -273.800363) (xy 332.2032 -273.782316) (xy 332.253064 -273.772136)
			(xy 332.303916 -273.770087) (xy 332.354437 -273.776221) (xy 332.403321 -273.790381) (xy 332.4493 -273.812198)
			(xy 332.491184 -273.841108) (xy 332.527888 -273.876363) (xy 332.558461 -273.917049) (xy 332.582112 -273.962112)
			(xy 332.598228 -274.010386) (xy 332.606392 -274.06062) (xy 332.606904 -274.086066) (xy 332.925178 -274.086066)
			(xy 332.929138 -274.037012) (xy 332.940915 -273.989228) (xy 332.960206 -273.943952) (xy 332.986509 -273.902356)
			(xy 333.019144 -273.865519) (xy 333.057265 -273.834394) (xy 333.099886 -273.809787) (xy 333.145902 -273.792335)
			(xy 333.194121 -273.782491) (xy 333.243296 -273.78051) (xy 333.292151 -273.786442) (xy 333.339422 -273.800134)
			(xy 333.383884 -273.821232) (xy 333.424387 -273.849188) (xy 333.45988 -273.88328) (xy 333.489445 -273.922624)
			(xy 333.512316 -273.966201) (xy 333.5279 -274.012882) (xy 333.535795 -274.061459) (xy 333.53629 -274.086066)
			(xy 333.854801 -274.086066) (xy 333.858896 -274.035338) (xy 333.871075 -273.985924) (xy 333.891023 -273.939104)
			(xy 333.918224 -273.89609) (xy 333.951972 -273.857996) (xy 333.991394 -273.825809) (xy 334.035468 -273.800363)
			(xy 334.083054 -273.782316) (xy 334.132918 -273.772136) (xy 334.18377 -273.770087) (xy 334.234291 -273.776221)
			(xy 334.283175 -273.790381) (xy 334.329154 -273.812198) (xy 334.371038 -273.841108) (xy 334.407742 -273.876363)
			(xy 334.438315 -273.917049) (xy 334.461966 -273.962112) (xy 334.478082 -274.010386) (xy 334.486246 -274.06062)
			(xy 334.486758 -274.086066) (xy 334.805286 -274.086066) (xy 334.809246 -274.037012) (xy 334.821023 -273.989228)
			(xy 334.840314 -273.943952) (xy 334.866617 -273.902356) (xy 334.899252 -273.865519) (xy 334.937373 -273.834394)
			(xy 334.979994 -273.809787) (xy 335.02601 -273.792335) (xy 335.074229 -273.782491) (xy 335.123404 -273.78051)
			(xy 335.172259 -273.786442) (xy 335.21953 -273.800134) (xy 335.263992 -273.821232) (xy 335.304495 -273.849188)
			(xy 335.339988 -273.88328) (xy 335.369553 -273.922624) (xy 335.392424 -273.966201) (xy 335.408008 -274.012882)
			(xy 335.415903 -274.061459) (xy 335.416398 -274.086066) (xy 335.734909 -274.086066) (xy 335.739004 -274.035338)
			(xy 335.751183 -273.985924) (xy 335.771131 -273.939104) (xy 335.798332 -273.89609) (xy 335.83208 -273.857996)
			(xy 335.871502 -273.825809) (xy 335.915576 -273.800363) (xy 335.963162 -273.782316) (xy 336.013026 -273.772136)
			(xy 336.063878 -273.770087) (xy 336.114399 -273.776221) (xy 336.163283 -273.790381) (xy 336.209262 -273.812198)
			(xy 336.251146 -273.841108) (xy 336.28785 -273.876363) (xy 336.318423 -273.917049) (xy 336.342074 -273.962112)
			(xy 336.35819 -274.010386) (xy 336.366354 -274.06062) (xy 336.366866 -274.086066) (xy 336.674963 -274.086066)
			(xy 336.679058 -274.035338) (xy 336.691237 -273.985924) (xy 336.711185 -273.939104) (xy 336.738386 -273.89609)
			(xy 336.772134 -273.857996) (xy 336.811556 -273.825809) (xy 336.85563 -273.800363) (xy 336.903216 -273.782316)
			(xy 336.95308 -273.772136) (xy 337.003932 -273.770087) (xy 337.054453 -273.776221) (xy 337.103337 -273.790381)
			(xy 337.149316 -273.812198) (xy 337.1912 -273.841108) (xy 337.227904 -273.876363) (xy 337.258477 -273.917049)
			(xy 337.282128 -273.962112) (xy 337.298244 -274.010386) (xy 337.306408 -274.06062) (xy 337.30692 -274.086066)
			(xy 337.625194 -274.086066) (xy 337.629154 -274.037012) (xy 337.640931 -273.989228) (xy 337.660222 -273.943952)
			(xy 337.686525 -273.902356) (xy 337.71916 -273.865519) (xy 337.757281 -273.834394) (xy 337.799902 -273.809787)
			(xy 337.845918 -273.792335) (xy 337.894137 -273.782491) (xy 337.943312 -273.78051) (xy 337.992167 -273.786442)
			(xy 338.039438 -273.800134) (xy 338.0839 -273.821232) (xy 338.124403 -273.849188) (xy 338.159896 -273.88328)
			(xy 338.189461 -273.922624) (xy 338.212332 -273.966201) (xy 338.227916 -274.012882) (xy 338.235811 -274.061459)
			(xy 338.236306 -274.086066) (xy 338.554817 -274.086066) (xy 338.558912 -274.035338) (xy 338.571091 -273.985924)
			(xy 338.591039 -273.939104) (xy 338.61824 -273.89609) (xy 338.651988 -273.857996) (xy 338.69141 -273.825809)
			(xy 338.735484 -273.800363) (xy 338.78307 -273.782316) (xy 338.832934 -273.772136) (xy 338.883786 -273.770087)
			(xy 338.934307 -273.776221) (xy 338.983191 -273.790381) (xy 339.02917 -273.812198) (xy 339.071054 -273.841108)
			(xy 339.107758 -273.876363) (xy 339.138331 -273.917049) (xy 339.161982 -273.962112) (xy 339.178098 -274.010386)
			(xy 339.186262 -274.06062) (xy 339.186774 -274.086066) (xy 339.505302 -274.086066) (xy 339.509262 -274.037012)
			(xy 339.521039 -273.989228) (xy 339.54033 -273.943952) (xy 339.566633 -273.902356) (xy 339.599268 -273.865519)
			(xy 339.637389 -273.834394) (xy 339.68001 -273.809787) (xy 339.726026 -273.792335) (xy 339.774245 -273.782491)
			(xy 339.82342 -273.78051) (xy 339.872275 -273.786442) (xy 339.919546 -273.800134) (xy 339.964008 -273.821232)
			(xy 340.004511 -273.849188) (xy 340.040004 -273.88328) (xy 340.069569 -273.922624) (xy 340.09244 -273.966201)
			(xy 340.108024 -274.012882) (xy 340.115919 -274.061459) (xy 340.116414 -274.086066) (xy 340.434925 -274.086066)
			(xy 340.43902 -274.035338) (xy 340.451199 -273.985924) (xy 340.471147 -273.939104) (xy 340.498348 -273.89609)
			(xy 340.532096 -273.857996) (xy 340.571518 -273.825809) (xy 340.615592 -273.800363) (xy 340.663178 -273.782316)
			(xy 340.713042 -273.772136) (xy 340.763894 -273.770087) (xy 340.814415 -273.776221) (xy 340.863299 -273.790381)
			(xy 340.909278 -273.812198) (xy 340.951162 -273.841108) (xy 340.987866 -273.876363) (xy 341.018439 -273.917049)
			(xy 341.04209 -273.962112) (xy 341.058206 -274.010386) (xy 341.06637 -274.06062) (xy 341.066882 -274.086066)
			(xy 341.38541 -274.086066) (xy 341.38937 -274.037012) (xy 341.401147 -273.989228) (xy 341.420438 -273.943952)
			(xy 341.446741 -273.902356) (xy 341.479376 -273.865519) (xy 341.517497 -273.834394) (xy 341.560118 -273.809787)
			(xy 341.606134 -273.792335) (xy 341.654353 -273.782491) (xy 341.703528 -273.78051) (xy 341.752383 -273.786442)
			(xy 341.799654 -273.800134) (xy 341.844116 -273.821232) (xy 341.884619 -273.849188) (xy 341.920112 -273.88328)
			(xy 341.949677 -273.922624) (xy 341.972548 -273.966201) (xy 341.988132 -274.012882) (xy 341.996027 -274.061459)
			(xy 341.996522 -274.086066) (xy 342.314779 -274.086066) (xy 342.318874 -274.035338) (xy 342.331053 -273.985924)
			(xy 342.351001 -273.939104) (xy 342.378202 -273.89609) (xy 342.41195 -273.857996) (xy 342.451372 -273.825809)
			(xy 342.495446 -273.800363) (xy 342.543032 -273.782316) (xy 342.592896 -273.772136) (xy 342.643748 -273.770087)
			(xy 342.694269 -273.776221) (xy 342.743153 -273.790381) (xy 342.789132 -273.812198) (xy 342.831016 -273.841108)
			(xy 342.86772 -273.876363) (xy 342.898293 -273.917049) (xy 342.921944 -273.962112) (xy 342.93806 -274.010386)
			(xy 342.946224 -274.06062) (xy 342.946736 -274.086066) (xy 343.254833 -274.086066) (xy 343.258928 -274.035338)
			(xy 343.271107 -273.985924) (xy 343.291055 -273.939104) (xy 343.318256 -273.89609) (xy 343.352004 -273.857996)
			(xy 343.391426 -273.825809) (xy 343.4355 -273.800363) (xy 343.483086 -273.782316) (xy 343.53295 -273.772136)
			(xy 343.583802 -273.770087) (xy 343.634323 -273.776221) (xy 343.683207 -273.790381) (xy 343.729186 -273.812198)
			(xy 343.77107 -273.841108) (xy 343.807774 -273.876363) (xy 343.838347 -273.917049) (xy 343.861998 -273.962112)
			(xy 343.878114 -274.010386) (xy 343.886278 -274.06062) (xy 343.88679 -274.086066) (xy 345.145372 -274.086066)
			(xy 345.149332 -274.037012) (xy 345.161109 -273.989228) (xy 345.1804 -273.943952) (xy 345.206703 -273.902356)
			(xy 345.239338 -273.865519) (xy 345.277459 -273.834394) (xy 345.32008 -273.809787) (xy 345.366096 -273.792335)
			(xy 345.414315 -273.782491) (xy 345.46349 -273.78051) (xy 345.512345 -273.786442) (xy 345.559616 -273.800134)
			(xy 345.604078 -273.821232) (xy 345.644581 -273.849188) (xy 345.680074 -273.88328) (xy 345.709639 -273.922624)
			(xy 345.73251 -273.966201) (xy 345.748094 -274.012882) (xy 345.755989 -274.061459) (xy 345.756484 -274.086066)
			(xy 346.085426 -274.086066) (xy 346.089386 -274.037012) (xy 346.101163 -273.989228) (xy 346.120454 -273.943952)
			(xy 346.146757 -273.902356) (xy 346.179392 -273.865519) (xy 346.217513 -273.834394) (xy 346.260134 -273.809787)
			(xy 346.30615 -273.792335) (xy 346.354369 -273.782491) (xy 346.403544 -273.78051) (xy 346.452399 -273.786442)
			(xy 346.49967 -273.800134) (xy 346.544132 -273.821232) (xy 346.584635 -273.849188) (xy 346.620128 -273.88328)
			(xy 346.649693 -273.922624) (xy 346.672564 -273.966201) (xy 346.688148 -274.012882) (xy 346.696043 -274.061459)
			(xy 346.696538 -274.086066) (xy 347.025226 -274.086066) (xy 347.029186 -274.037012) (xy 347.040963 -273.989228)
			(xy 347.060254 -273.943952) (xy 347.086557 -273.902356) (xy 347.119192 -273.865519) (xy 347.157313 -273.834394)
			(xy 347.199934 -273.809787) (xy 347.24595 -273.792335) (xy 347.294169 -273.782491) (xy 347.343344 -273.78051)
			(xy 347.392199 -273.786442) (xy 347.43947 -273.800134) (xy 347.483932 -273.821232) (xy 347.524435 -273.849188)
			(xy 347.559928 -273.88328) (xy 347.589493 -273.922624) (xy 347.612364 -273.966201) (xy 347.627948 -274.012882)
			(xy 347.635843 -274.061459) (xy 347.636338 -274.086066) (xy 347.96528 -274.086066) (xy 347.96924 -274.037012)
			(xy 347.981017 -273.989228) (xy 348.000308 -273.943952) (xy 348.026611 -273.902356) (xy 348.059246 -273.865519)
			(xy 348.097367 -273.834394) (xy 348.139988 -273.809787) (xy 348.186004 -273.792335) (xy 348.234223 -273.782491)
			(xy 348.283398 -273.78051) (xy 348.332253 -273.786442) (xy 348.379524 -273.800134) (xy 348.423986 -273.821232)
			(xy 348.464489 -273.849188) (xy 348.499982 -273.88328) (xy 348.529547 -273.922624) (xy 348.552418 -273.966201)
			(xy 348.568002 -274.012882) (xy 348.575897 -274.061459) (xy 348.576392 -274.086066) (xy 348.905334 -274.086066)
			(xy 348.909294 -274.037012) (xy 348.921071 -273.989228) (xy 348.940362 -273.943952) (xy 348.966665 -273.902356)
			(xy 348.9993 -273.865519) (xy 349.037421 -273.834394) (xy 349.080042 -273.809787) (xy 349.126058 -273.792335)
			(xy 349.174277 -273.782491) (xy 349.223452 -273.78051) (xy 349.272307 -273.786442) (xy 349.319578 -273.800134)
			(xy 349.36404 -273.821232) (xy 349.404543 -273.849188) (xy 349.440036 -273.88328) (xy 349.469601 -273.922624)
			(xy 349.492472 -273.966201) (xy 349.508056 -274.012882) (xy 349.515951 -274.061459) (xy 349.516446 -274.086066)
			(xy 349.845388 -274.086066) (xy 349.849348 -274.037012) (xy 349.861125 -273.989228) (xy 349.880416 -273.943952)
			(xy 349.906719 -273.902356) (xy 349.939354 -273.865519) (xy 349.977475 -273.834394) (xy 350.020096 -273.809787)
			(xy 350.066112 -273.792335) (xy 350.114331 -273.782491) (xy 350.163506 -273.78051) (xy 350.212361 -273.786442)
			(xy 350.259632 -273.800134) (xy 350.304094 -273.821232) (xy 350.344597 -273.849188) (xy 350.38009 -273.88328)
			(xy 350.409655 -273.922624) (xy 350.432526 -273.966201) (xy 350.44811 -274.012882) (xy 350.456005 -274.061459)
			(xy 350.4565 -274.086066) (xy 350.785442 -274.086066) (xy 350.789402 -274.037012) (xy 350.801179 -273.989228)
			(xy 350.82047 -273.943952) (xy 350.846773 -273.902356) (xy 350.879408 -273.865519) (xy 350.917529 -273.834394)
			(xy 350.96015 -273.809787) (xy 351.006166 -273.792335) (xy 351.054385 -273.782491) (xy 351.10356 -273.78051)
			(xy 351.152415 -273.786442) (xy 351.199686 -273.800134) (xy 351.244148 -273.821232) (xy 351.284651 -273.849188)
			(xy 351.320144 -273.88328) (xy 351.349709 -273.922624) (xy 351.37258 -273.966201) (xy 351.388164 -274.012882)
			(xy 351.396059 -274.061459) (xy 351.396554 -274.086066) (xy 351.396059 -274.110673) (xy 351.388164 -274.15925)
			(xy 351.37258 -274.205931) (xy 351.349709 -274.249508) (xy 351.320144 -274.288852) (xy 351.284651 -274.322944)
			(xy 351.244148 -274.3509) (xy 351.199686 -274.371998) (xy 351.152415 -274.38569) (xy 351.10356 -274.391622)
			(xy 351.054385 -274.389641) (xy 351.006166 -274.379797) (xy 350.96015 -274.362345) (xy 350.917529 -274.337738)
			(xy 350.879408 -274.306613) (xy 350.846773 -274.269776) (xy 350.82047 -274.22818) (xy 350.801179 -274.182904)
			(xy 350.789402 -274.13512) (xy 350.785442 -274.086066) (xy 350.4565 -274.086066) (xy 350.456005 -274.110673)
			(xy 350.44811 -274.15925) (xy 350.432526 -274.205931) (xy 350.409655 -274.249508) (xy 350.38009 -274.288852)
			(xy 350.344597 -274.322944) (xy 350.304094 -274.3509) (xy 350.259632 -274.371998) (xy 350.212361 -274.38569)
			(xy 350.163506 -274.391622) (xy 350.114331 -274.389641) (xy 350.066112 -274.379797) (xy 350.020096 -274.362345)
			(xy 349.977475 -274.337738) (xy 349.939354 -274.306613) (xy 349.906719 -274.269776) (xy 349.880416 -274.22818)
			(xy 349.861125 -274.182904) (xy 349.849348 -274.13512) (xy 349.845388 -274.086066) (xy 349.516446 -274.086066)
			(xy 349.515951 -274.110673) (xy 349.508056 -274.15925) (xy 349.492472 -274.205931) (xy 349.469601 -274.249508)
			(xy 349.440036 -274.288852) (xy 349.404543 -274.322944) (xy 349.36404 -274.3509) (xy 349.319578 -274.371998)
			(xy 349.272307 -274.38569) (xy 349.223452 -274.391622) (xy 349.174277 -274.389641) (xy 349.126058 -274.379797)
			(xy 349.080042 -274.362345) (xy 349.037421 -274.337738) (xy 348.9993 -274.306613) (xy 348.966665 -274.269776)
			(xy 348.940362 -274.22818) (xy 348.921071 -274.182904) (xy 348.909294 -274.13512) (xy 348.905334 -274.086066)
			(xy 348.576392 -274.086066) (xy 348.575897 -274.110673) (xy 348.568002 -274.15925) (xy 348.552418 -274.205931)
			(xy 348.529547 -274.249508) (xy 348.499982 -274.288852) (xy 348.464489 -274.322944) (xy 348.423986 -274.3509)
			(xy 348.379524 -274.371998) (xy 348.332253 -274.38569) (xy 348.283398 -274.391622) (xy 348.234223 -274.389641)
			(xy 348.186004 -274.379797) (xy 348.139988 -274.362345) (xy 348.097367 -274.337738) (xy 348.059246 -274.306613)
			(xy 348.026611 -274.269776) (xy 348.000308 -274.22818) (xy 347.981017 -274.182904) (xy 347.96924 -274.13512)
			(xy 347.96528 -274.086066) (xy 347.636338 -274.086066) (xy 347.635843 -274.110673) (xy 347.627948 -274.15925)
			(xy 347.612364 -274.205931) (xy 347.589493 -274.249508) (xy 347.559928 -274.288852) (xy 347.524435 -274.322944)
			(xy 347.483932 -274.3509) (xy 347.43947 -274.371998) (xy 347.392199 -274.38569) (xy 347.343344 -274.391622)
			(xy 347.294169 -274.389641) (xy 347.24595 -274.379797) (xy 347.199934 -274.362345) (xy 347.157313 -274.337738)
			(xy 347.119192 -274.306613) (xy 347.086557 -274.269776) (xy 347.060254 -274.22818) (xy 347.040963 -274.182904)
			(xy 347.029186 -274.13512) (xy 347.025226 -274.086066) (xy 346.696538 -274.086066) (xy 346.696043 -274.110673)
			(xy 346.688148 -274.15925) (xy 346.672564 -274.205931) (xy 346.649693 -274.249508) (xy 346.620128 -274.288852)
			(xy 346.584635 -274.322944) (xy 346.544132 -274.3509) (xy 346.49967 -274.371998) (xy 346.452399 -274.38569)
			(xy 346.403544 -274.391622) (xy 346.354369 -274.389641) (xy 346.30615 -274.379797) (xy 346.260134 -274.362345)
			(xy 346.217513 -274.337738) (xy 346.179392 -274.306613) (xy 346.146757 -274.269776) (xy 346.120454 -274.22818)
			(xy 346.101163 -274.182904) (xy 346.089386 -274.13512) (xy 346.085426 -274.086066) (xy 345.756484 -274.086066)
			(xy 345.755989 -274.110673) (xy 345.748094 -274.15925) (xy 345.73251 -274.205931) (xy 345.709639 -274.249508)
			(xy 345.680074 -274.288852) (xy 345.644581 -274.322944) (xy 345.604078 -274.3509) (xy 345.559616 -274.371998)
			(xy 345.512345 -274.38569) (xy 345.46349 -274.391622) (xy 345.414315 -274.389641) (xy 345.366096 -274.379797)
			(xy 345.32008 -274.362345) (xy 345.277459 -274.337738) (xy 345.239338 -274.306613) (xy 345.206703 -274.269776)
			(xy 345.1804 -274.22818) (xy 345.161109 -274.182904) (xy 345.149332 -274.13512) (xy 345.145372 -274.086066)
			(xy 343.88679 -274.086066) (xy 343.886278 -274.111512) (xy 343.878114 -274.161746) (xy 343.861998 -274.21002)
			(xy 343.838347 -274.255083) (xy 343.807774 -274.295769) (xy 343.77107 -274.331024) (xy 343.729186 -274.359934)
			(xy 343.683207 -274.381751) (xy 343.634323 -274.395911) (xy 343.583802 -274.402045) (xy 343.53295 -274.399996)
			(xy 343.483086 -274.389816) (xy 343.4355 -274.371769) (xy 343.391426 -274.346323) (xy 343.352004 -274.314136)
			(xy 343.318256 -274.276042) (xy 343.291055 -274.233028) (xy 343.271107 -274.186208) (xy 343.258928 -274.136794)
			(xy 343.254833 -274.086066) (xy 342.946736 -274.086066) (xy 342.946224 -274.111512) (xy 342.93806 -274.161746)
			(xy 342.921944 -274.21002) (xy 342.898293 -274.255083) (xy 342.86772 -274.295769) (xy 342.831016 -274.331024)
			(xy 342.789132 -274.359934) (xy 342.743153 -274.381751) (xy 342.694269 -274.395911) (xy 342.643748 -274.402045)
			(xy 342.592896 -274.399996) (xy 342.543032 -274.389816) (xy 342.495446 -274.371769) (xy 342.451372 -274.346323)
			(xy 342.41195 -274.314136) (xy 342.378202 -274.276042) (xy 342.351001 -274.233028) (xy 342.331053 -274.186208)
			(xy 342.318874 -274.136794) (xy 342.314779 -274.086066) (xy 341.996522 -274.086066) (xy 341.996027 -274.110673)
			(xy 341.988132 -274.15925) (xy 341.972548 -274.205931) (xy 341.949677 -274.249508) (xy 341.920112 -274.288852)
			(xy 341.884619 -274.322944) (xy 341.844116 -274.3509) (xy 341.799654 -274.371998) (xy 341.752383 -274.38569)
			(xy 341.703528 -274.391622) (xy 341.654353 -274.389641) (xy 341.606134 -274.379797) (xy 341.560118 -274.362345)
			(xy 341.517497 -274.337738) (xy 341.479376 -274.306613) (xy 341.446741 -274.269776) (xy 341.420438 -274.22818)
			(xy 341.401147 -274.182904) (xy 341.38937 -274.13512) (xy 341.38541 -274.086066) (xy 341.066882 -274.086066)
			(xy 341.06637 -274.111512) (xy 341.058206 -274.161746) (xy 341.04209 -274.21002) (xy 341.018439 -274.255083)
			(xy 340.987866 -274.295769) (xy 340.951162 -274.331024) (xy 340.909278 -274.359934) (xy 340.863299 -274.381751)
			(xy 340.814415 -274.395911) (xy 340.763894 -274.402045) (xy 340.713042 -274.399996) (xy 340.663178 -274.389816)
			(xy 340.615592 -274.371769) (xy 340.571518 -274.346323) (xy 340.532096 -274.314136) (xy 340.498348 -274.276042)
			(xy 340.471147 -274.233028) (xy 340.451199 -274.186208) (xy 340.43902 -274.136794) (xy 340.434925 -274.086066)
			(xy 340.116414 -274.086066) (xy 340.115919 -274.110673) (xy 340.108024 -274.15925) (xy 340.09244 -274.205931)
			(xy 340.069569 -274.249508) (xy 340.040004 -274.288852) (xy 340.004511 -274.322944) (xy 339.964008 -274.3509)
			(xy 339.919546 -274.371998) (xy 339.872275 -274.38569) (xy 339.82342 -274.391622) (xy 339.774245 -274.389641)
			(xy 339.726026 -274.379797) (xy 339.68001 -274.362345) (xy 339.637389 -274.337738) (xy 339.599268 -274.306613)
			(xy 339.566633 -274.269776) (xy 339.54033 -274.22818) (xy 339.521039 -274.182904) (xy 339.509262 -274.13512)
			(xy 339.505302 -274.086066) (xy 339.186774 -274.086066) (xy 339.186262 -274.111512) (xy 339.178098 -274.161746)
			(xy 339.161982 -274.21002) (xy 339.138331 -274.255083) (xy 339.107758 -274.295769) (xy 339.071054 -274.331024)
			(xy 339.02917 -274.359934) (xy 338.983191 -274.381751) (xy 338.934307 -274.395911) (xy 338.883786 -274.402045)
			(xy 338.832934 -274.399996) (xy 338.78307 -274.389816) (xy 338.735484 -274.371769) (xy 338.69141 -274.346323)
			(xy 338.651988 -274.314136) (xy 338.61824 -274.276042) (xy 338.591039 -274.233028) (xy 338.571091 -274.186208)
			(xy 338.558912 -274.136794) (xy 338.554817 -274.086066) (xy 338.236306 -274.086066) (xy 338.235811 -274.110673)
			(xy 338.227916 -274.15925) (xy 338.212332 -274.205931) (xy 338.189461 -274.249508) (xy 338.159896 -274.288852)
			(xy 338.124403 -274.322944) (xy 338.0839 -274.3509) (xy 338.039438 -274.371998) (xy 337.992167 -274.38569)
			(xy 337.943312 -274.391622) (xy 337.894137 -274.389641) (xy 337.845918 -274.379797) (xy 337.799902 -274.362345)
			(xy 337.757281 -274.337738) (xy 337.71916 -274.306613) (xy 337.686525 -274.269776) (xy 337.660222 -274.22818)
			(xy 337.640931 -274.182904) (xy 337.629154 -274.13512) (xy 337.625194 -274.086066) (xy 337.30692 -274.086066)
			(xy 337.306408 -274.111512) (xy 337.298244 -274.161746) (xy 337.282128 -274.21002) (xy 337.258477 -274.255083)
			(xy 337.227904 -274.295769) (xy 337.1912 -274.331024) (xy 337.149316 -274.359934) (xy 337.103337 -274.381751)
			(xy 337.054453 -274.395911) (xy 337.003932 -274.402045) (xy 336.95308 -274.399996) (xy 336.903216 -274.389816)
			(xy 336.85563 -274.371769) (xy 336.811556 -274.346323) (xy 336.772134 -274.314136) (xy 336.738386 -274.276042)
			(xy 336.711185 -274.233028) (xy 336.691237 -274.186208) (xy 336.679058 -274.136794) (xy 336.674963 -274.086066)
			(xy 336.366866 -274.086066) (xy 336.366354 -274.111512) (xy 336.35819 -274.161746) (xy 336.342074 -274.21002)
			(xy 336.318423 -274.255083) (xy 336.28785 -274.295769) (xy 336.251146 -274.331024) (xy 336.209262 -274.359934)
			(xy 336.163283 -274.381751) (xy 336.114399 -274.395911) (xy 336.063878 -274.402045) (xy 336.013026 -274.399996)
			(xy 335.963162 -274.389816) (xy 335.915576 -274.371769) (xy 335.871502 -274.346323) (xy 335.83208 -274.314136)
			(xy 335.798332 -274.276042) (xy 335.771131 -274.233028) (xy 335.751183 -274.186208) (xy 335.739004 -274.136794)
			(xy 335.734909 -274.086066) (xy 335.416398 -274.086066) (xy 335.415903 -274.110673) (xy 335.408008 -274.15925)
			(xy 335.392424 -274.205931) (xy 335.369553 -274.249508) (xy 335.339988 -274.288852) (xy 335.304495 -274.322944)
			(xy 335.263992 -274.3509) (xy 335.21953 -274.371998) (xy 335.172259 -274.38569) (xy 335.123404 -274.391622)
			(xy 335.074229 -274.389641) (xy 335.02601 -274.379797) (xy 334.979994 -274.362345) (xy 334.937373 -274.337738)
			(xy 334.899252 -274.306613) (xy 334.866617 -274.269776) (xy 334.840314 -274.22818) (xy 334.821023 -274.182904)
			(xy 334.809246 -274.13512) (xy 334.805286 -274.086066) (xy 334.486758 -274.086066) (xy 334.486246 -274.111512)
			(xy 334.478082 -274.161746) (xy 334.461966 -274.21002) (xy 334.438315 -274.255083) (xy 334.407742 -274.295769)
			(xy 334.371038 -274.331024) (xy 334.329154 -274.359934) (xy 334.283175 -274.381751) (xy 334.234291 -274.395911)
			(xy 334.18377 -274.402045) (xy 334.132918 -274.399996) (xy 334.083054 -274.389816) (xy 334.035468 -274.371769)
			(xy 333.991394 -274.346323) (xy 333.951972 -274.314136) (xy 333.918224 -274.276042) (xy 333.891023 -274.233028)
			(xy 333.871075 -274.186208) (xy 333.858896 -274.136794) (xy 333.854801 -274.086066) (xy 333.53629 -274.086066)
			(xy 333.535795 -274.110673) (xy 333.5279 -274.15925) (xy 333.512316 -274.205931) (xy 333.489445 -274.249508)
			(xy 333.45988 -274.288852) (xy 333.424387 -274.322944) (xy 333.383884 -274.3509) (xy 333.339422 -274.371998)
			(xy 333.292151 -274.38569) (xy 333.243296 -274.391622) (xy 333.194121 -274.389641) (xy 333.145902 -274.379797)
			(xy 333.099886 -274.362345) (xy 333.057265 -274.337738) (xy 333.019144 -274.306613) (xy 332.986509 -274.269776)
			(xy 332.960206 -274.22818) (xy 332.940915 -274.182904) (xy 332.929138 -274.13512) (xy 332.925178 -274.086066)
			(xy 332.606904 -274.086066) (xy 332.606392 -274.111512) (xy 332.598228 -274.161746) (xy 332.582112 -274.21002)
			(xy 332.558461 -274.255083) (xy 332.527888 -274.295769) (xy 332.491184 -274.331024) (xy 332.4493 -274.359934)
			(xy 332.403321 -274.381751) (xy 332.354437 -274.395911) (xy 332.303916 -274.402045) (xy 332.253064 -274.399996)
			(xy 332.2032 -274.389816) (xy 332.155614 -274.371769) (xy 332.11154 -274.346323) (xy 332.072118 -274.314136)
			(xy 332.03837 -274.276042) (xy 332.011169 -274.233028) (xy 331.991221 -274.186208) (xy 331.979042 -274.136794)
			(xy 331.974947 -274.086066) (xy 331.656436 -274.086066) (xy 331.655941 -274.110673) (xy 331.648046 -274.15925)
			(xy 331.632462 -274.205931) (xy 331.609591 -274.249508) (xy 331.580026 -274.288852) (xy 331.544533 -274.322944)
			(xy 331.50403 -274.3509) (xy 331.459568 -274.371998) (xy 331.412297 -274.38569) (xy 331.363442 -274.391622)
			(xy 331.314267 -274.389641) (xy 331.266048 -274.379797) (xy 331.220032 -274.362345) (xy 331.177411 -274.337738)
			(xy 331.13929 -274.306613) (xy 331.106655 -274.269776) (xy 331.080352 -274.22818) (xy 331.061061 -274.182904)
			(xy 331.049284 -274.13512) (xy 331.045324 -274.086066) (xy 330.726796 -274.086066) (xy 330.726284 -274.111512)
			(xy 330.71812 -274.161746) (xy 330.702004 -274.21002) (xy 330.678353 -274.255083) (xy 330.64778 -274.295769)
			(xy 330.611076 -274.331024) (xy 330.569192 -274.359934) (xy 330.523213 -274.381751) (xy 330.474329 -274.395911)
			(xy 330.423808 -274.402045) (xy 330.372956 -274.399996) (xy 330.323092 -274.389816) (xy 330.275506 -274.371769)
			(xy 330.231432 -274.346323) (xy 330.19201 -274.314136) (xy 330.158262 -274.276042) (xy 330.131061 -274.233028)
			(xy 330.111113 -274.186208) (xy 330.098934 -274.136794) (xy 330.094839 -274.086066) (xy 329.786742 -274.086066)
			(xy 329.78623 -274.111512) (xy 329.778066 -274.161746) (xy 329.76195 -274.21002) (xy 329.738299 -274.255083)
			(xy 329.707726 -274.295769) (xy 329.671022 -274.331024) (xy 329.629138 -274.359934) (xy 329.583159 -274.381751)
			(xy 329.534275 -274.395911) (xy 329.483754 -274.402045) (xy 329.432902 -274.399996) (xy 329.383038 -274.389816)
			(xy 329.335452 -274.371769) (xy 329.291378 -274.346323) (xy 329.251956 -274.314136) (xy 329.218208 -274.276042)
			(xy 329.191007 -274.233028) (xy 329.171059 -274.186208) (xy 329.15888 -274.136794) (xy 329.154785 -274.086066)
			(xy 328.836528 -274.086066) (xy 328.836033 -274.110673) (xy 328.828138 -274.15925) (xy 328.812554 -274.205931)
			(xy 328.789683 -274.249508) (xy 328.760118 -274.288852) (xy 328.724625 -274.322944) (xy 328.684122 -274.3509)
			(xy 328.63966 -274.371998) (xy 328.592389 -274.38569) (xy 328.543534 -274.391622) (xy 328.494359 -274.389641)
			(xy 328.44614 -274.379797) (xy 328.400124 -274.362345) (xy 328.357503 -274.337738) (xy 328.319382 -274.306613)
			(xy 328.286747 -274.269776) (xy 328.260444 -274.22818) (xy 328.241153 -274.182904) (xy 328.229376 -274.13512)
			(xy 328.225416 -274.086066) (xy 326.95642 -274.086066) (xy 326.955925 -274.110673) (xy 326.94803 -274.15925)
			(xy 326.932446 -274.205931) (xy 326.909575 -274.249508) (xy 326.88001 -274.288852) (xy 326.844517 -274.322944)
			(xy 326.804014 -274.3509) (xy 326.759552 -274.371998) (xy 326.712281 -274.38569) (xy 326.663426 -274.391622)
			(xy 326.614251 -274.389641) (xy 326.566032 -274.379797) (xy 326.520016 -274.362345) (xy 326.477395 -274.337738)
			(xy 326.439274 -274.306613) (xy 326.406639 -274.269776) (xy 326.380336 -274.22818) (xy 326.361045 -274.182904)
			(xy 326.349268 -274.13512) (xy 326.345308 -274.086066) (xy 310.45912 -274.086066) (xy 310.45912 -274.630134)
			(xy 324.74714 -274.630134) (xy 324.7511 -274.58108) (xy 324.762877 -274.533296) (xy 324.782168 -274.48802)
			(xy 324.808471 -274.446424) (xy 324.841106 -274.409587) (xy 324.879227 -274.378462) (xy 324.921848 -274.353855)
			(xy 324.967864 -274.336403) (xy 325.016083 -274.326559) (xy 325.065258 -274.324578) (xy 325.114113 -274.33051)
			(xy 325.161384 -274.344202) (xy 325.205846 -274.3653) (xy 325.246349 -274.393256) (xy 325.281842 -274.427348)
			(xy 325.311407 -274.466692) (xy 325.334278 -274.510269) (xy 325.349862 -274.55695) (xy 325.357757 -274.605527)
			(xy 325.358252 -274.630134) (xy 325.357757 -274.654741) (xy 325.349862 -274.703318) (xy 325.334278 -274.749999)
			(xy 325.311407 -274.793576) (xy 325.281842 -274.83292) (xy 325.246349 -274.867012) (xy 325.205846 -274.894968)
			(xy 325.203519 -274.896072) (xy 327.755262 -274.896072) (xy 327.759222 -274.847018) (xy 327.770999 -274.799234)
			(xy 327.79029 -274.753958) (xy 327.816593 -274.712362) (xy 327.849228 -274.675525) (xy 327.887349 -274.6444)
			(xy 327.92997 -274.619793) (xy 327.975986 -274.602341) (xy 328.024205 -274.592497) (xy 328.07338 -274.590516)
			(xy 328.122235 -274.596448) (xy 328.169506 -274.61014) (xy 328.213968 -274.631238) (xy 328.254471 -274.659194)
			(xy 328.289964 -274.693286) (xy 328.319529 -274.73263) (xy 328.3424 -274.776207) (xy 328.357984 -274.822888)
			(xy 328.365879 -274.871465) (xy 328.366374 -274.896072) (xy 328.684885 -274.896072) (xy 328.68898 -274.845344)
			(xy 328.701159 -274.79593) (xy 328.721107 -274.74911) (xy 328.748308 -274.706096) (xy 328.782056 -274.668002)
			(xy 328.821478 -274.635815) (xy 328.865552 -274.610369) (xy 328.913138 -274.592322) (xy 328.963002 -274.582142)
			(xy 329.013854 -274.580093) (xy 329.064375 -274.586227) (xy 329.113259 -274.600387) (xy 329.159238 -274.622204)
			(xy 329.201122 -274.651114) (xy 329.237826 -274.686369) (xy 329.268399 -274.727055) (xy 329.29205 -274.772118)
			(xy 329.308166 -274.820392) (xy 329.31633 -274.870626) (xy 329.316842 -274.896072) (xy 329.63537 -274.896072)
			(xy 329.63933 -274.847018) (xy 329.651107 -274.799234) (xy 329.670398 -274.753958) (xy 329.696701 -274.712362)
			(xy 329.729336 -274.675525) (xy 329.767457 -274.6444) (xy 329.810078 -274.619793) (xy 329.856094 -274.602341)
			(xy 329.904313 -274.592497) (xy 329.953488 -274.590516) (xy 330.002343 -274.596448) (xy 330.049614 -274.61014)
			(xy 330.094076 -274.631238) (xy 330.134579 -274.659194) (xy 330.170072 -274.693286) (xy 330.199637 -274.73263)
			(xy 330.222508 -274.776207) (xy 330.238092 -274.822888) (xy 330.245987 -274.871465) (xy 330.246482 -274.896072)
			(xy 330.564739 -274.896072) (xy 330.568834 -274.845344) (xy 330.581013 -274.79593) (xy 330.600961 -274.74911)
			(xy 330.628162 -274.706096) (xy 330.66191 -274.668002) (xy 330.701332 -274.635815) (xy 330.745406 -274.610369)
			(xy 330.792992 -274.592322) (xy 330.842856 -274.582142) (xy 330.893708 -274.580093) (xy 330.944229 -274.586227)
			(xy 330.993113 -274.600387) (xy 331.039092 -274.622204) (xy 331.080976 -274.651114) (xy 331.11768 -274.686369)
			(xy 331.148253 -274.727055) (xy 331.171904 -274.772118) (xy 331.18802 -274.820392) (xy 331.196184 -274.870626)
			(xy 331.196696 -274.896072) (xy 331.515224 -274.896072) (xy 331.519184 -274.847018) (xy 331.530961 -274.799234)
			(xy 331.550252 -274.753958) (xy 331.576555 -274.712362) (xy 331.60919 -274.675525) (xy 331.647311 -274.6444)
			(xy 331.689932 -274.619793) (xy 331.735948 -274.602341) (xy 331.784167 -274.592497) (xy 331.833342 -274.590516)
			(xy 331.882197 -274.596448) (xy 331.929468 -274.61014) (xy 331.97393 -274.631238) (xy 332.014433 -274.659194)
			(xy 332.049926 -274.693286) (xy 332.079491 -274.73263) (xy 332.102362 -274.776207) (xy 332.117946 -274.822888)
			(xy 332.125841 -274.871465) (xy 332.126336 -274.896072) (xy 332.444847 -274.896072) (xy 332.448942 -274.845344)
			(xy 332.461121 -274.79593) (xy 332.481069 -274.74911) (xy 332.50827 -274.706096) (xy 332.542018 -274.668002)
			(xy 332.58144 -274.635815) (xy 332.625514 -274.610369) (xy 332.6731 -274.592322) (xy 332.722964 -274.582142)
			(xy 332.773816 -274.580093) (xy 332.824337 -274.586227) (xy 332.873221 -274.600387) (xy 332.9192 -274.622204)
			(xy 332.961084 -274.651114) (xy 332.997788 -274.686369) (xy 333.028361 -274.727055) (xy 333.052012 -274.772118)
			(xy 333.068128 -274.820392) (xy 333.076292 -274.870626) (xy 333.076804 -274.896072) (xy 333.384901 -274.896072)
			(xy 333.388996 -274.845344) (xy 333.401175 -274.79593) (xy 333.421123 -274.74911) (xy 333.448324 -274.706096)
			(xy 333.482072 -274.668002) (xy 333.521494 -274.635815) (xy 333.565568 -274.610369) (xy 333.613154 -274.592322)
			(xy 333.663018 -274.582142) (xy 333.71387 -274.580093) (xy 333.764391 -274.586227) (xy 333.813275 -274.600387)
			(xy 333.859254 -274.622204) (xy 333.901138 -274.651114) (xy 333.937842 -274.686369) (xy 333.968415 -274.727055)
			(xy 333.992066 -274.772118) (xy 334.008182 -274.820392) (xy 334.016346 -274.870626) (xy 334.016858 -274.896072)
			(xy 334.335386 -274.896072) (xy 334.339346 -274.847018) (xy 334.351123 -274.799234) (xy 334.370414 -274.753958)
			(xy 334.396717 -274.712362) (xy 334.429352 -274.675525) (xy 334.467473 -274.6444) (xy 334.510094 -274.619793)
			(xy 334.55611 -274.602341) (xy 334.604329 -274.592497) (xy 334.653504 -274.590516) (xy 334.702359 -274.596448)
			(xy 334.74963 -274.61014) (xy 334.794092 -274.631238) (xy 334.834595 -274.659194) (xy 334.870088 -274.693286)
			(xy 334.899653 -274.73263) (xy 334.922524 -274.776207) (xy 334.938108 -274.822888) (xy 334.946003 -274.871465)
			(xy 334.946498 -274.896072) (xy 335.264755 -274.896072) (xy 335.26885 -274.845344) (xy 335.281029 -274.79593)
			(xy 335.300977 -274.74911) (xy 335.328178 -274.706096) (xy 335.361926 -274.668002) (xy 335.401348 -274.635815)
			(xy 335.445422 -274.610369) (xy 335.493008 -274.592322) (xy 335.542872 -274.582142) (xy 335.593724 -274.580093)
			(xy 335.644245 -274.586227) (xy 335.693129 -274.600387) (xy 335.739108 -274.622204) (xy 335.780992 -274.651114)
			(xy 335.817696 -274.686369) (xy 335.848269 -274.727055) (xy 335.87192 -274.772118) (xy 335.888036 -274.820392)
			(xy 335.8962 -274.870626) (xy 335.896712 -274.896072) (xy 336.21524 -274.896072) (xy 336.2192 -274.847018)
			(xy 336.230977 -274.799234) (xy 336.250268 -274.753958) (xy 336.276571 -274.712362) (xy 336.309206 -274.675525)
			(xy 336.347327 -274.6444) (xy 336.389948 -274.619793) (xy 336.435964 -274.602341) (xy 336.484183 -274.592497)
			(xy 336.533358 -274.590516) (xy 336.582213 -274.596448) (xy 336.629484 -274.61014) (xy 336.673946 -274.631238)
			(xy 336.714449 -274.659194) (xy 336.749942 -274.693286) (xy 336.779507 -274.73263) (xy 336.802378 -274.776207)
			(xy 336.817962 -274.822888) (xy 336.825857 -274.871465) (xy 336.826352 -274.896072) (xy 337.144863 -274.896072)
			(xy 337.148958 -274.845344) (xy 337.161137 -274.79593) (xy 337.181085 -274.74911) (xy 337.208286 -274.706096)
			(xy 337.242034 -274.668002) (xy 337.281456 -274.635815) (xy 337.32553 -274.610369) (xy 337.373116 -274.592322)
			(xy 337.42298 -274.582142) (xy 337.473832 -274.580093) (xy 337.524353 -274.586227) (xy 337.573237 -274.600387)
			(xy 337.619216 -274.622204) (xy 337.6611 -274.651114) (xy 337.697804 -274.686369) (xy 337.728377 -274.727055)
			(xy 337.752028 -274.772118) (xy 337.768144 -274.820392) (xy 337.776308 -274.870626) (xy 337.77682 -274.896072)
			(xy 338.095348 -274.896072) (xy 338.099308 -274.847018) (xy 338.111085 -274.799234) (xy 338.130376 -274.753958)
			(xy 338.156679 -274.712362) (xy 338.189314 -274.675525) (xy 338.227435 -274.6444) (xy 338.270056 -274.619793)
			(xy 338.316072 -274.602341) (xy 338.364291 -274.592497) (xy 338.413466 -274.590516) (xy 338.462321 -274.596448)
			(xy 338.509592 -274.61014) (xy 338.554054 -274.631238) (xy 338.594557 -274.659194) (xy 338.63005 -274.693286)
			(xy 338.659615 -274.73263) (xy 338.682486 -274.776207) (xy 338.69807 -274.822888) (xy 338.705965 -274.871465)
			(xy 338.70646 -274.896072) (xy 339.024971 -274.896072) (xy 339.029066 -274.845344) (xy 339.041245 -274.79593)
			(xy 339.061193 -274.74911) (xy 339.088394 -274.706096) (xy 339.122142 -274.668002) (xy 339.161564 -274.635815)
			(xy 339.205638 -274.610369) (xy 339.253224 -274.592322) (xy 339.303088 -274.582142) (xy 339.35394 -274.580093)
			(xy 339.404461 -274.586227) (xy 339.453345 -274.600387) (xy 339.499324 -274.622204) (xy 339.541208 -274.651114)
			(xy 339.577912 -274.686369) (xy 339.608485 -274.727055) (xy 339.632136 -274.772118) (xy 339.648252 -274.820392)
			(xy 339.656416 -274.870626) (xy 339.656928 -274.896072) (xy 339.964771 -274.896072) (xy 339.968866 -274.845344)
			(xy 339.981045 -274.79593) (xy 340.000993 -274.74911) (xy 340.028194 -274.706096) (xy 340.061942 -274.668002)
			(xy 340.101364 -274.635815) (xy 340.145438 -274.610369) (xy 340.193024 -274.592322) (xy 340.242888 -274.582142)
			(xy 340.29374 -274.580093) (xy 340.344261 -274.586227) (xy 340.393145 -274.600387) (xy 340.439124 -274.622204)
			(xy 340.481008 -274.651114) (xy 340.517712 -274.686369) (xy 340.548285 -274.727055) (xy 340.571936 -274.772118)
			(xy 340.588052 -274.820392) (xy 340.596216 -274.870626) (xy 340.596728 -274.896072) (xy 340.915256 -274.896072)
			(xy 340.919216 -274.847018) (xy 340.930993 -274.799234) (xy 340.950284 -274.753958) (xy 340.976587 -274.712362)
			(xy 341.009222 -274.675525) (xy 341.047343 -274.6444) (xy 341.089964 -274.619793) (xy 341.13598 -274.602341)
			(xy 341.184199 -274.592497) (xy 341.233374 -274.590516) (xy 341.282229 -274.596448) (xy 341.3295 -274.61014)
			(xy 341.373962 -274.631238) (xy 341.414465 -274.659194) (xy 341.449958 -274.693286) (xy 341.479523 -274.73263)
			(xy 341.502394 -274.776207) (xy 341.517978 -274.822888) (xy 341.525873 -274.871465) (xy 341.526368 -274.896072)
			(xy 341.844879 -274.896072) (xy 341.848974 -274.845344) (xy 341.861153 -274.79593) (xy 341.881101 -274.74911)
			(xy 341.908302 -274.706096) (xy 341.94205 -274.668002) (xy 341.981472 -274.635815) (xy 342.025546 -274.610369)
			(xy 342.073132 -274.592322) (xy 342.122996 -274.582142) (xy 342.173848 -274.580093) (xy 342.224369 -274.586227)
			(xy 342.273253 -274.600387) (xy 342.319232 -274.622204) (xy 342.361116 -274.651114) (xy 342.39782 -274.686369)
			(xy 342.428393 -274.727055) (xy 342.452044 -274.772118) (xy 342.46816 -274.820392) (xy 342.476324 -274.870626)
			(xy 342.476836 -274.896072) (xy 342.795364 -274.896072) (xy 342.799324 -274.847018) (xy 342.811101 -274.799234)
			(xy 342.830392 -274.753958) (xy 342.856695 -274.712362) (xy 342.88933 -274.675525) (xy 342.927451 -274.6444)
			(xy 342.970072 -274.619793) (xy 343.016088 -274.602341) (xy 343.064307 -274.592497) (xy 343.113482 -274.590516)
			(xy 343.162337 -274.596448) (xy 343.209608 -274.61014) (xy 343.25407 -274.631238) (xy 343.294573 -274.659194)
			(xy 343.330066 -274.693286) (xy 343.359631 -274.73263) (xy 343.382502 -274.776207) (xy 343.398086 -274.822888)
			(xy 343.405981 -274.871465) (xy 343.406476 -274.896072) (xy 343.724987 -274.896072) (xy 343.729082 -274.845344)
			(xy 343.741261 -274.79593) (xy 343.761209 -274.74911) (xy 343.78841 -274.706096) (xy 343.822158 -274.668002)
			(xy 343.86158 -274.635815) (xy 343.905654 -274.610369) (xy 343.95324 -274.592322) (xy 344.003104 -274.582142)
			(xy 344.053956 -274.580093) (xy 344.104477 -274.586227) (xy 344.153361 -274.600387) (xy 344.19934 -274.622204)
			(xy 344.241224 -274.651114) (xy 344.277928 -274.686369) (xy 344.308501 -274.727055) (xy 344.332152 -274.772118)
			(xy 344.348268 -274.820392) (xy 344.356432 -274.870626) (xy 344.356944 -274.896072) (xy 344.675218 -274.896072)
			(xy 344.679178 -274.847018) (xy 344.690955 -274.799234) (xy 344.710246 -274.753958) (xy 344.736549 -274.712362)
			(xy 344.769184 -274.675525) (xy 344.807305 -274.6444) (xy 344.849926 -274.619793) (xy 344.895942 -274.602341)
			(xy 344.944161 -274.592497) (xy 344.993336 -274.590516) (xy 345.042191 -274.596448) (xy 345.089462 -274.61014)
			(xy 345.133924 -274.631238) (xy 345.174427 -274.659194) (xy 345.20992 -274.693286) (xy 345.239485 -274.73263)
			(xy 345.262356 -274.776207) (xy 345.27794 -274.822888) (xy 345.285835 -274.871465) (xy 345.28633 -274.896072)
			(xy 345.604841 -274.896072) (xy 345.608936 -274.845344) (xy 345.621115 -274.79593) (xy 345.641063 -274.74911)
			(xy 345.668264 -274.706096) (xy 345.702012 -274.668002) (xy 345.741434 -274.635815) (xy 345.785508 -274.610369)
			(xy 345.833094 -274.592322) (xy 345.882958 -274.582142) (xy 345.93381 -274.580093) (xy 345.984331 -274.586227)
			(xy 346.033215 -274.600387) (xy 346.079194 -274.622204) (xy 346.121078 -274.651114) (xy 346.157782 -274.686369)
			(xy 346.188355 -274.727055) (xy 346.212006 -274.772118) (xy 346.228122 -274.820392) (xy 346.236286 -274.870626)
			(xy 346.236798 -274.896072) (xy 346.544895 -274.896072) (xy 346.54899 -274.845344) (xy 346.561169 -274.79593)
			(xy 346.581117 -274.74911) (xy 346.608318 -274.706096) (xy 346.642066 -274.668002) (xy 346.681488 -274.635815)
			(xy 346.725562 -274.610369) (xy 346.773148 -274.592322) (xy 346.823012 -274.582142) (xy 346.873864 -274.580093)
			(xy 346.924385 -274.586227) (xy 346.973269 -274.600387) (xy 347.019248 -274.622204) (xy 347.061132 -274.651114)
			(xy 347.097836 -274.686369) (xy 347.128409 -274.727055) (xy 347.15206 -274.772118) (xy 347.168176 -274.820392)
			(xy 347.17634 -274.870626) (xy 347.176852 -274.896072) (xy 347.49538 -274.896072) (xy 347.49934 -274.847018)
			(xy 347.511117 -274.799234) (xy 347.530408 -274.753958) (xy 347.556711 -274.712362) (xy 347.589346 -274.675525)
			(xy 347.627467 -274.6444) (xy 347.670088 -274.619793) (xy 347.716104 -274.602341) (xy 347.764323 -274.592497)
			(xy 347.813498 -274.590516) (xy 347.862353 -274.596448) (xy 347.909624 -274.61014) (xy 347.954086 -274.631238)
			(xy 347.994589 -274.659194) (xy 348.030082 -274.693286) (xy 348.059647 -274.73263) (xy 348.082518 -274.776207)
			(xy 348.098102 -274.822888) (xy 348.105997 -274.871465) (xy 348.106492 -274.896072) (xy 348.425003 -274.896072)
			(xy 348.429098 -274.845344) (xy 348.441277 -274.79593) (xy 348.461225 -274.74911) (xy 348.488426 -274.706096)
			(xy 348.522174 -274.668002) (xy 348.561596 -274.635815) (xy 348.60567 -274.610369) (xy 348.653256 -274.592322)
			(xy 348.70312 -274.582142) (xy 348.753972 -274.580093) (xy 348.804493 -274.586227) (xy 348.853377 -274.600387)
			(xy 348.899356 -274.622204) (xy 348.94124 -274.651114) (xy 348.977944 -274.686369) (xy 349.008517 -274.727055)
			(xy 349.032168 -274.772118) (xy 349.048284 -274.820392) (xy 349.056448 -274.870626) (xy 349.05696 -274.896072)
			(xy 349.364803 -274.896072) (xy 349.368898 -274.845344) (xy 349.381077 -274.79593) (xy 349.401025 -274.74911)
			(xy 349.428226 -274.706096) (xy 349.461974 -274.668002) (xy 349.501396 -274.635815) (xy 349.54547 -274.610369)
			(xy 349.593056 -274.592322) (xy 349.64292 -274.582142) (xy 349.693772 -274.580093) (xy 349.744293 -274.586227)
			(xy 349.793177 -274.600387) (xy 349.839156 -274.622204) (xy 349.88104 -274.651114) (xy 349.917744 -274.686369)
			(xy 349.948317 -274.727055) (xy 349.971968 -274.772118) (xy 349.988084 -274.820392) (xy 349.996248 -274.870626)
			(xy 349.99676 -274.896072) (xy 350.315288 -274.896072) (xy 350.319248 -274.847018) (xy 350.331025 -274.799234)
			(xy 350.350316 -274.753958) (xy 350.376619 -274.712362) (xy 350.409254 -274.675525) (xy 350.447375 -274.6444)
			(xy 350.489996 -274.619793) (xy 350.536012 -274.602341) (xy 350.584231 -274.592497) (xy 350.633406 -274.590516)
			(xy 350.682261 -274.596448) (xy 350.729532 -274.61014) (xy 350.773994 -274.631238) (xy 350.814497 -274.659194)
			(xy 350.84999 -274.693286) (xy 350.879555 -274.73263) (xy 350.902426 -274.776207) (xy 350.91801 -274.822888)
			(xy 350.925905 -274.871465) (xy 350.9264 -274.896072) (xy 350.925905 -274.920679) (xy 350.91801 -274.969256)
			(xy 350.902426 -275.015937) (xy 350.879555 -275.059514) (xy 350.84999 -275.098858) (xy 350.814497 -275.13295)
			(xy 350.773994 -275.160906) (xy 350.729532 -275.182004) (xy 350.682261 -275.195696) (xy 350.633406 -275.201628)
			(xy 350.584231 -275.199647) (xy 350.536012 -275.189803) (xy 350.489996 -275.172351) (xy 350.447375 -275.147744)
			(xy 350.409254 -275.116619) (xy 350.376619 -275.079782) (xy 350.350316 -275.038186) (xy 350.331025 -274.99291)
			(xy 350.319248 -274.945126) (xy 350.315288 -274.896072) (xy 349.99676 -274.896072) (xy 349.996248 -274.921518)
			(xy 349.988084 -274.971752) (xy 349.971968 -275.020026) (xy 349.948317 -275.065089) (xy 349.917744 -275.105775)
			(xy 349.88104 -275.14103) (xy 349.839156 -275.16994) (xy 349.793177 -275.191757) (xy 349.744293 -275.205917)
			(xy 349.693772 -275.212051) (xy 349.64292 -275.210002) (xy 349.593056 -275.199822) (xy 349.54547 -275.181775)
			(xy 349.501396 -275.156329) (xy 349.461974 -275.124142) (xy 349.428226 -275.086048) (xy 349.401025 -275.043034)
			(xy 349.381077 -274.996214) (xy 349.368898 -274.9468) (xy 349.364803 -274.896072) (xy 349.05696 -274.896072)
			(xy 349.056448 -274.921518) (xy 349.048284 -274.971752) (xy 349.032168 -275.020026) (xy 349.008517 -275.065089)
			(xy 348.977944 -275.105775) (xy 348.94124 -275.14103) (xy 348.899356 -275.16994) (xy 348.853377 -275.191757)
			(xy 348.804493 -275.205917) (xy 348.753972 -275.212051) (xy 348.70312 -275.210002) (xy 348.653256 -275.199822)
			(xy 348.60567 -275.181775) (xy 348.561596 -275.156329) (xy 348.522174 -275.124142) (xy 348.488426 -275.086048)
			(xy 348.461225 -275.043034) (xy 348.441277 -274.996214) (xy 348.429098 -274.9468) (xy 348.425003 -274.896072)
			(xy 348.106492 -274.896072) (xy 348.105997 -274.920679) (xy 348.098102 -274.969256) (xy 348.082518 -275.015937)
			(xy 348.059647 -275.059514) (xy 348.030082 -275.098858) (xy 347.994589 -275.13295) (xy 347.954086 -275.160906)
			(xy 347.909624 -275.182004) (xy 347.862353 -275.195696) (xy 347.813498 -275.201628) (xy 347.764323 -275.199647)
			(xy 347.716104 -275.189803) (xy 347.670088 -275.172351) (xy 347.627467 -275.147744) (xy 347.589346 -275.116619)
			(xy 347.556711 -275.079782) (xy 347.530408 -275.038186) (xy 347.511117 -274.99291) (xy 347.49934 -274.945126)
			(xy 347.49538 -274.896072) (xy 347.176852 -274.896072) (xy 347.17634 -274.921518) (xy 347.168176 -274.971752)
			(xy 347.15206 -275.020026) (xy 347.128409 -275.065089) (xy 347.097836 -275.105775) (xy 347.061132 -275.14103)
			(xy 347.019248 -275.16994) (xy 346.973269 -275.191757) (xy 346.924385 -275.205917) (xy 346.873864 -275.212051)
			(xy 346.823012 -275.210002) (xy 346.773148 -275.199822) (xy 346.725562 -275.181775) (xy 346.681488 -275.156329)
			(xy 346.642066 -275.124142) (xy 346.608318 -275.086048) (xy 346.581117 -275.043034) (xy 346.561169 -274.996214)
			(xy 346.54899 -274.9468) (xy 346.544895 -274.896072) (xy 346.236798 -274.896072) (xy 346.236286 -274.921518)
			(xy 346.228122 -274.971752) (xy 346.212006 -275.020026) (xy 346.188355 -275.065089) (xy 346.157782 -275.105775)
			(xy 346.121078 -275.14103) (xy 346.079194 -275.16994) (xy 346.033215 -275.191757) (xy 345.984331 -275.205917)
			(xy 345.93381 -275.212051) (xy 345.882958 -275.210002) (xy 345.833094 -275.199822) (xy 345.785508 -275.181775)
			(xy 345.741434 -275.156329) (xy 345.702012 -275.124142) (xy 345.668264 -275.086048) (xy 345.641063 -275.043034)
			(xy 345.621115 -274.996214) (xy 345.608936 -274.9468) (xy 345.604841 -274.896072) (xy 345.28633 -274.896072)
			(xy 345.285835 -274.920679) (xy 345.27794 -274.969256) (xy 345.262356 -275.015937) (xy 345.239485 -275.059514)
			(xy 345.20992 -275.098858) (xy 345.174427 -275.13295) (xy 345.133924 -275.160906) (xy 345.089462 -275.182004)
			(xy 345.042191 -275.195696) (xy 344.993336 -275.201628) (xy 344.944161 -275.199647) (xy 344.895942 -275.189803)
			(xy 344.849926 -275.172351) (xy 344.807305 -275.147744) (xy 344.769184 -275.116619) (xy 344.736549 -275.079782)
			(xy 344.710246 -275.038186) (xy 344.690955 -274.99291) (xy 344.679178 -274.945126) (xy 344.675218 -274.896072)
			(xy 344.356944 -274.896072) (xy 344.356432 -274.921518) (xy 344.348268 -274.971752) (xy 344.332152 -275.020026)
			(xy 344.308501 -275.065089) (xy 344.277928 -275.105775) (xy 344.241224 -275.14103) (xy 344.19934 -275.16994)
			(xy 344.153361 -275.191757) (xy 344.104477 -275.205917) (xy 344.053956 -275.212051) (xy 344.003104 -275.210002)
			(xy 343.95324 -275.199822) (xy 343.905654 -275.181775) (xy 343.86158 -275.156329) (xy 343.822158 -275.124142)
			(xy 343.78841 -275.086048) (xy 343.761209 -275.043034) (xy 343.741261 -274.996214) (xy 343.729082 -274.9468)
			(xy 343.724987 -274.896072) (xy 343.406476 -274.896072) (xy 343.405981 -274.920679) (xy 343.398086 -274.969256)
			(xy 343.382502 -275.015937) (xy 343.359631 -275.059514) (xy 343.330066 -275.098858) (xy 343.294573 -275.13295)
			(xy 343.25407 -275.160906) (xy 343.209608 -275.182004) (xy 343.162337 -275.195696) (xy 343.113482 -275.201628)
			(xy 343.064307 -275.199647) (xy 343.016088 -275.189803) (xy 342.970072 -275.172351) (xy 342.927451 -275.147744)
			(xy 342.88933 -275.116619) (xy 342.856695 -275.079782) (xy 342.830392 -275.038186) (xy 342.811101 -274.99291)
			(xy 342.799324 -274.945126) (xy 342.795364 -274.896072) (xy 342.476836 -274.896072) (xy 342.476324 -274.921518)
			(xy 342.46816 -274.971752) (xy 342.452044 -275.020026) (xy 342.428393 -275.065089) (xy 342.39782 -275.105775)
			(xy 342.361116 -275.14103) (xy 342.319232 -275.16994) (xy 342.273253 -275.191757) (xy 342.224369 -275.205917)
			(xy 342.173848 -275.212051) (xy 342.122996 -275.210002) (xy 342.073132 -275.199822) (xy 342.025546 -275.181775)
			(xy 341.981472 -275.156329) (xy 341.94205 -275.124142) (xy 341.908302 -275.086048) (xy 341.881101 -275.043034)
			(xy 341.861153 -274.996214) (xy 341.848974 -274.9468) (xy 341.844879 -274.896072) (xy 341.526368 -274.896072)
			(xy 341.525873 -274.920679) (xy 341.517978 -274.969256) (xy 341.502394 -275.015937) (xy 341.479523 -275.059514)
			(xy 341.449958 -275.098858) (xy 341.414465 -275.13295) (xy 341.373962 -275.160906) (xy 341.3295 -275.182004)
			(xy 341.282229 -275.195696) (xy 341.233374 -275.201628) (xy 341.184199 -275.199647) (xy 341.13598 -275.189803)
			(xy 341.089964 -275.172351) (xy 341.047343 -275.147744) (xy 341.009222 -275.116619) (xy 340.976587 -275.079782)
			(xy 340.950284 -275.038186) (xy 340.930993 -274.99291) (xy 340.919216 -274.945126) (xy 340.915256 -274.896072)
			(xy 340.596728 -274.896072) (xy 340.596216 -274.921518) (xy 340.588052 -274.971752) (xy 340.571936 -275.020026)
			(xy 340.548285 -275.065089) (xy 340.517712 -275.105775) (xy 340.481008 -275.14103) (xy 340.439124 -275.16994)
			(xy 340.393145 -275.191757) (xy 340.344261 -275.205917) (xy 340.29374 -275.212051) (xy 340.242888 -275.210002)
			(xy 340.193024 -275.199822) (xy 340.145438 -275.181775) (xy 340.101364 -275.156329) (xy 340.061942 -275.124142)
			(xy 340.028194 -275.086048) (xy 340.000993 -275.043034) (xy 339.981045 -274.996214) (xy 339.968866 -274.9468)
			(xy 339.964771 -274.896072) (xy 339.656928 -274.896072) (xy 339.656416 -274.921518) (xy 339.648252 -274.971752)
			(xy 339.632136 -275.020026) (xy 339.608485 -275.065089) (xy 339.577912 -275.105775) (xy 339.541208 -275.14103)
			(xy 339.499324 -275.16994) (xy 339.453345 -275.191757) (xy 339.404461 -275.205917) (xy 339.35394 -275.212051)
			(xy 339.303088 -275.210002) (xy 339.253224 -275.199822) (xy 339.205638 -275.181775) (xy 339.161564 -275.156329)
			(xy 339.122142 -275.124142) (xy 339.088394 -275.086048) (xy 339.061193 -275.043034) (xy 339.041245 -274.996214)
			(xy 339.029066 -274.9468) (xy 339.024971 -274.896072) (xy 338.70646 -274.896072) (xy 338.705965 -274.920679)
			(xy 338.69807 -274.969256) (xy 338.682486 -275.015937) (xy 338.659615 -275.059514) (xy 338.63005 -275.098858)
			(xy 338.594557 -275.13295) (xy 338.554054 -275.160906) (xy 338.509592 -275.182004) (xy 338.462321 -275.195696)
			(xy 338.413466 -275.201628) (xy 338.364291 -275.199647) (xy 338.316072 -275.189803) (xy 338.270056 -275.172351)
			(xy 338.227435 -275.147744) (xy 338.189314 -275.116619) (xy 338.156679 -275.079782) (xy 338.130376 -275.038186)
			(xy 338.111085 -274.99291) (xy 338.099308 -274.945126) (xy 338.095348 -274.896072) (xy 337.77682 -274.896072)
			(xy 337.776308 -274.921518) (xy 337.768144 -274.971752) (xy 337.752028 -275.020026) (xy 337.728377 -275.065089)
			(xy 337.697804 -275.105775) (xy 337.6611 -275.14103) (xy 337.619216 -275.16994) (xy 337.573237 -275.191757)
			(xy 337.524353 -275.205917) (xy 337.473832 -275.212051) (xy 337.42298 -275.210002) (xy 337.373116 -275.199822)
			(xy 337.32553 -275.181775) (xy 337.281456 -275.156329) (xy 337.242034 -275.124142) (xy 337.208286 -275.086048)
			(xy 337.181085 -275.043034) (xy 337.161137 -274.996214) (xy 337.148958 -274.9468) (xy 337.144863 -274.896072)
			(xy 336.826352 -274.896072) (xy 336.825857 -274.920679) (xy 336.817962 -274.969256) (xy 336.802378 -275.015937)
			(xy 336.779507 -275.059514) (xy 336.749942 -275.098858) (xy 336.714449 -275.13295) (xy 336.673946 -275.160906)
			(xy 336.629484 -275.182004) (xy 336.582213 -275.195696) (xy 336.533358 -275.201628) (xy 336.484183 -275.199647)
			(xy 336.435964 -275.189803) (xy 336.389948 -275.172351) (xy 336.347327 -275.147744) (xy 336.309206 -275.116619)
			(xy 336.276571 -275.079782) (xy 336.250268 -275.038186) (xy 336.230977 -274.99291) (xy 336.2192 -274.945126)
			(xy 336.21524 -274.896072) (xy 335.896712 -274.896072) (xy 335.8962 -274.921518) (xy 335.888036 -274.971752)
			(xy 335.87192 -275.020026) (xy 335.848269 -275.065089) (xy 335.817696 -275.105775) (xy 335.780992 -275.14103)
			(xy 335.739108 -275.16994) (xy 335.693129 -275.191757) (xy 335.644245 -275.205917) (xy 335.593724 -275.212051)
			(xy 335.542872 -275.210002) (xy 335.493008 -275.199822) (xy 335.445422 -275.181775) (xy 335.401348 -275.156329)
			(xy 335.361926 -275.124142) (xy 335.328178 -275.086048) (xy 335.300977 -275.043034) (xy 335.281029 -274.996214)
			(xy 335.26885 -274.9468) (xy 335.264755 -274.896072) (xy 334.946498 -274.896072) (xy 334.946003 -274.920679)
			(xy 334.938108 -274.969256) (xy 334.922524 -275.015937) (xy 334.899653 -275.059514) (xy 334.870088 -275.098858)
			(xy 334.834595 -275.13295) (xy 334.794092 -275.160906) (xy 334.74963 -275.182004) (xy 334.702359 -275.195696)
			(xy 334.653504 -275.201628) (xy 334.604329 -275.199647) (xy 334.55611 -275.189803) (xy 334.510094 -275.172351)
			(xy 334.467473 -275.147744) (xy 334.429352 -275.116619) (xy 334.396717 -275.079782) (xy 334.370414 -275.038186)
			(xy 334.351123 -274.99291) (xy 334.339346 -274.945126) (xy 334.335386 -274.896072) (xy 334.016858 -274.896072)
			(xy 334.016346 -274.921518) (xy 334.008182 -274.971752) (xy 333.992066 -275.020026) (xy 333.968415 -275.065089)
			(xy 333.937842 -275.105775) (xy 333.901138 -275.14103) (xy 333.859254 -275.16994) (xy 333.813275 -275.191757)
			(xy 333.764391 -275.205917) (xy 333.71387 -275.212051) (xy 333.663018 -275.210002) (xy 333.613154 -275.199822)
			(xy 333.565568 -275.181775) (xy 333.521494 -275.156329) (xy 333.482072 -275.124142) (xy 333.448324 -275.086048)
			(xy 333.421123 -275.043034) (xy 333.401175 -274.996214) (xy 333.388996 -274.9468) (xy 333.384901 -274.896072)
			(xy 333.076804 -274.896072) (xy 333.076292 -274.921518) (xy 333.068128 -274.971752) (xy 333.052012 -275.020026)
			(xy 333.028361 -275.065089) (xy 332.997788 -275.105775) (xy 332.961084 -275.14103) (xy 332.9192 -275.16994)
			(xy 332.873221 -275.191757) (xy 332.824337 -275.205917) (xy 332.773816 -275.212051) (xy 332.722964 -275.210002)
			(xy 332.6731 -275.199822) (xy 332.625514 -275.181775) (xy 332.58144 -275.156329) (xy 332.542018 -275.124142)
			(xy 332.50827 -275.086048) (xy 332.481069 -275.043034) (xy 332.461121 -274.996214) (xy 332.448942 -274.9468)
			(xy 332.444847 -274.896072) (xy 332.126336 -274.896072) (xy 332.125841 -274.920679) (xy 332.117946 -274.969256)
			(xy 332.102362 -275.015937) (xy 332.079491 -275.059514) (xy 332.049926 -275.098858) (xy 332.014433 -275.13295)
			(xy 331.97393 -275.160906) (xy 331.929468 -275.182004) (xy 331.882197 -275.195696) (xy 331.833342 -275.201628)
			(xy 331.784167 -275.199647) (xy 331.735948 -275.189803) (xy 331.689932 -275.172351) (xy 331.647311 -275.147744)
			(xy 331.60919 -275.116619) (xy 331.576555 -275.079782) (xy 331.550252 -275.038186) (xy 331.530961 -274.99291)
			(xy 331.519184 -274.945126) (xy 331.515224 -274.896072) (xy 331.196696 -274.896072) (xy 331.196184 -274.921518)
			(xy 331.18802 -274.971752) (xy 331.171904 -275.020026) (xy 331.148253 -275.065089) (xy 331.11768 -275.105775)
			(xy 331.080976 -275.14103) (xy 331.039092 -275.16994) (xy 330.993113 -275.191757) (xy 330.944229 -275.205917)
			(xy 330.893708 -275.212051) (xy 330.842856 -275.210002) (xy 330.792992 -275.199822) (xy 330.745406 -275.181775)
			(xy 330.701332 -275.156329) (xy 330.66191 -275.124142) (xy 330.628162 -275.086048) (xy 330.600961 -275.043034)
			(xy 330.581013 -274.996214) (xy 330.568834 -274.9468) (xy 330.564739 -274.896072) (xy 330.246482 -274.896072)
			(xy 330.245987 -274.920679) (xy 330.238092 -274.969256) (xy 330.222508 -275.015937) (xy 330.199637 -275.059514)
			(xy 330.170072 -275.098858) (xy 330.134579 -275.13295) (xy 330.094076 -275.160906) (xy 330.049614 -275.182004)
			(xy 330.002343 -275.195696) (xy 329.953488 -275.201628) (xy 329.904313 -275.199647) (xy 329.856094 -275.189803)
			(xy 329.810078 -275.172351) (xy 329.767457 -275.147744) (xy 329.729336 -275.116619) (xy 329.696701 -275.079782)
			(xy 329.670398 -275.038186) (xy 329.651107 -274.99291) (xy 329.63933 -274.945126) (xy 329.63537 -274.896072)
			(xy 329.316842 -274.896072) (xy 329.31633 -274.921518) (xy 329.308166 -274.971752) (xy 329.29205 -275.020026)
			(xy 329.268399 -275.065089) (xy 329.237826 -275.105775) (xy 329.201122 -275.14103) (xy 329.159238 -275.16994)
			(xy 329.113259 -275.191757) (xy 329.064375 -275.205917) (xy 329.013854 -275.212051) (xy 328.963002 -275.210002)
			(xy 328.913138 -275.199822) (xy 328.865552 -275.181775) (xy 328.821478 -275.156329) (xy 328.782056 -275.124142)
			(xy 328.748308 -275.086048) (xy 328.721107 -275.043034) (xy 328.701159 -274.996214) (xy 328.68898 -274.9468)
			(xy 328.684885 -274.896072) (xy 328.366374 -274.896072) (xy 328.365879 -274.920679) (xy 328.357984 -274.969256)
			(xy 328.3424 -275.015937) (xy 328.319529 -275.059514) (xy 328.289964 -275.098858) (xy 328.254471 -275.13295)
			(xy 328.213968 -275.160906) (xy 328.169506 -275.182004) (xy 328.122235 -275.195696) (xy 328.07338 -275.201628)
			(xy 328.024205 -275.199647) (xy 327.975986 -275.189803) (xy 327.92997 -275.172351) (xy 327.887349 -275.147744)
			(xy 327.849228 -275.116619) (xy 327.816593 -275.079782) (xy 327.79029 -275.038186) (xy 327.770999 -274.99291)
			(xy 327.759222 -274.945126) (xy 327.755262 -274.896072) (xy 325.203519 -274.896072) (xy 325.161384 -274.916066)
			(xy 325.114113 -274.929758) (xy 325.065258 -274.93569) (xy 325.016083 -274.933709) (xy 324.967864 -274.923865)
			(xy 324.921848 -274.906413) (xy 324.879227 -274.881806) (xy 324.841106 -274.850681) (xy 324.808471 -274.813844)
			(xy 324.782168 -274.772248) (xy 324.762877 -274.726972) (xy 324.7511 -274.679188) (xy 324.74714 -274.630134)
			(xy 310.45912 -274.630134) (xy 310.45912 -275.706078) (xy 326.345308 -275.706078) (xy 326.349268 -275.657024)
			(xy 326.361045 -275.60924) (xy 326.380336 -275.563964) (xy 326.406639 -275.522368) (xy 326.439274 -275.485531)
			(xy 326.477395 -275.454406) (xy 326.520016 -275.429799) (xy 326.566032 -275.412347) (xy 326.614251 -275.402503)
			(xy 326.663426 -275.400522) (xy 326.712281 -275.406454) (xy 326.759552 -275.420146) (xy 326.804014 -275.441244)
			(xy 326.844517 -275.4692) (xy 326.88001 -275.503292) (xy 326.909575 -275.542636) (xy 326.932446 -275.586213)
			(xy 326.94803 -275.632894) (xy 326.955925 -275.681471) (xy 326.95642 -275.706078) (xy 329.154785 -275.706078)
			(xy 329.15888 -275.65535) (xy 329.171059 -275.605936) (xy 329.191007 -275.559116) (xy 329.218208 -275.516102)
			(xy 329.251956 -275.478008) (xy 329.291378 -275.445821) (xy 329.335452 -275.420375) (xy 329.383038 -275.402328)
			(xy 329.432902 -275.392148) (xy 329.483754 -275.390099) (xy 329.534275 -275.396233) (xy 329.583159 -275.410393)
			(xy 329.629138 -275.43221) (xy 329.671022 -275.46112) (xy 329.707726 -275.496375) (xy 329.738299 -275.537061)
			(xy 329.76195 -275.582124) (xy 329.778066 -275.630398) (xy 329.78623 -275.680632) (xy 329.786742 -275.706078)
			(xy 330.094839 -275.706078) (xy 330.098934 -275.65535) (xy 330.111113 -275.605936) (xy 330.131061 -275.559116)
			(xy 330.158262 -275.516102) (xy 330.19201 -275.478008) (xy 330.231432 -275.445821) (xy 330.275506 -275.420375)
			(xy 330.323092 -275.402328) (xy 330.372956 -275.392148) (xy 330.423808 -275.390099) (xy 330.474329 -275.396233)
			(xy 330.523213 -275.410393) (xy 330.569192 -275.43221) (xy 330.611076 -275.46112) (xy 330.64778 -275.496375)
			(xy 330.678353 -275.537061) (xy 330.702004 -275.582124) (xy 330.71812 -275.630398) (xy 330.726284 -275.680632)
			(xy 330.726796 -275.706078) (xy 331.045324 -275.706078) (xy 331.049284 -275.657024) (xy 331.061061 -275.60924)
			(xy 331.080352 -275.563964) (xy 331.106655 -275.522368) (xy 331.13929 -275.485531) (xy 331.177411 -275.454406)
			(xy 331.220032 -275.429799) (xy 331.266048 -275.412347) (xy 331.314267 -275.402503) (xy 331.363442 -275.400522)
			(xy 331.412297 -275.406454) (xy 331.459568 -275.420146) (xy 331.50403 -275.441244) (xy 331.544533 -275.4692)
			(xy 331.580026 -275.503292) (xy 331.609591 -275.542636) (xy 331.632462 -275.586213) (xy 331.648046 -275.632894)
			(xy 331.655941 -275.681471) (xy 331.656436 -275.706078) (xy 331.974947 -275.706078) (xy 331.979042 -275.65535)
			(xy 331.991221 -275.605936) (xy 332.011169 -275.559116) (xy 332.03837 -275.516102) (xy 332.072118 -275.478008)
			(xy 332.11154 -275.445821) (xy 332.155614 -275.420375) (xy 332.2032 -275.402328) (xy 332.253064 -275.392148)
			(xy 332.303916 -275.390099) (xy 332.354437 -275.396233) (xy 332.403321 -275.410393) (xy 332.4493 -275.43221)
			(xy 332.491184 -275.46112) (xy 332.527888 -275.496375) (xy 332.558461 -275.537061) (xy 332.582112 -275.582124)
			(xy 332.598228 -275.630398) (xy 332.606392 -275.680632) (xy 332.606904 -275.706078) (xy 332.925178 -275.706078)
			(xy 332.929138 -275.657024) (xy 332.940915 -275.60924) (xy 332.960206 -275.563964) (xy 332.986509 -275.522368)
			(xy 333.019144 -275.485531) (xy 333.057265 -275.454406) (xy 333.099886 -275.429799) (xy 333.145902 -275.412347)
			(xy 333.194121 -275.402503) (xy 333.243296 -275.400522) (xy 333.292151 -275.406454) (xy 333.339422 -275.420146)
			(xy 333.383884 -275.441244) (xy 333.424387 -275.4692) (xy 333.45988 -275.503292) (xy 333.489445 -275.542636)
			(xy 333.512316 -275.586213) (xy 333.5279 -275.632894) (xy 333.535795 -275.681471) (xy 333.53629 -275.706078)
			(xy 333.854801 -275.706078) (xy 333.858896 -275.65535) (xy 333.871075 -275.605936) (xy 333.891023 -275.559116)
			(xy 333.918224 -275.516102) (xy 333.951972 -275.478008) (xy 333.991394 -275.445821) (xy 334.035468 -275.420375)
			(xy 334.083054 -275.402328) (xy 334.132918 -275.392148) (xy 334.18377 -275.390099) (xy 334.234291 -275.396233)
			(xy 334.283175 -275.410393) (xy 334.329154 -275.43221) (xy 334.371038 -275.46112) (xy 334.407742 -275.496375)
			(xy 334.438315 -275.537061) (xy 334.461966 -275.582124) (xy 334.478082 -275.630398) (xy 334.486246 -275.680632)
			(xy 334.486758 -275.706078) (xy 335.734909 -275.706078) (xy 335.739004 -275.65535) (xy 335.751183 -275.605936)
			(xy 335.771131 -275.559116) (xy 335.798332 -275.516102) (xy 335.83208 -275.478008) (xy 335.871502 -275.445821)
			(xy 335.915576 -275.420375) (xy 335.963162 -275.402328) (xy 336.013026 -275.392148) (xy 336.063878 -275.390099)
			(xy 336.114399 -275.396233) (xy 336.163283 -275.410393) (xy 336.209262 -275.43221) (xy 336.251146 -275.46112)
			(xy 336.28785 -275.496375) (xy 336.318423 -275.537061) (xy 336.342074 -275.582124) (xy 336.35819 -275.630398)
			(xy 336.366354 -275.680632) (xy 336.366866 -275.706078) (xy 336.674963 -275.706078) (xy 336.679058 -275.65535)
			(xy 336.691237 -275.605936) (xy 336.711185 -275.559116) (xy 336.738386 -275.516102) (xy 336.772134 -275.478008)
			(xy 336.811556 -275.445821) (xy 336.85563 -275.420375) (xy 336.903216 -275.402328) (xy 336.95308 -275.392148)
			(xy 337.003932 -275.390099) (xy 337.054453 -275.396233) (xy 337.103337 -275.410393) (xy 337.149316 -275.43221)
			(xy 337.1912 -275.46112) (xy 337.227904 -275.496375) (xy 337.258477 -275.537061) (xy 337.282128 -275.582124)
			(xy 337.298244 -275.630398) (xy 337.306408 -275.680632) (xy 337.30692 -275.706078) (xy 337.625194 -275.706078)
			(xy 337.629154 -275.657024) (xy 337.640931 -275.60924) (xy 337.660222 -275.563964) (xy 337.686525 -275.522368)
			(xy 337.71916 -275.485531) (xy 337.757281 -275.454406) (xy 337.799902 -275.429799) (xy 337.845918 -275.412347)
			(xy 337.894137 -275.402503) (xy 337.943312 -275.400522) (xy 337.992167 -275.406454) (xy 338.039438 -275.420146)
			(xy 338.0839 -275.441244) (xy 338.124403 -275.4692) (xy 338.159896 -275.503292) (xy 338.189461 -275.542636)
			(xy 338.212332 -275.586213) (xy 338.227916 -275.632894) (xy 338.235811 -275.681471) (xy 338.236306 -275.706078)
			(xy 338.554817 -275.706078) (xy 338.558912 -275.65535) (xy 338.571091 -275.605936) (xy 338.591039 -275.559116)
			(xy 338.61824 -275.516102) (xy 338.651988 -275.478008) (xy 338.69141 -275.445821) (xy 338.735484 -275.420375)
			(xy 338.78307 -275.402328) (xy 338.832934 -275.392148) (xy 338.883786 -275.390099) (xy 338.934307 -275.396233)
			(xy 338.983191 -275.410393) (xy 339.02917 -275.43221) (xy 339.071054 -275.46112) (xy 339.107758 -275.496375)
			(xy 339.138331 -275.537061) (xy 339.161982 -275.582124) (xy 339.178098 -275.630398) (xy 339.186262 -275.680632)
			(xy 339.186774 -275.706078) (xy 339.505302 -275.706078) (xy 339.509262 -275.657024) (xy 339.521039 -275.60924)
			(xy 339.54033 -275.563964) (xy 339.566633 -275.522368) (xy 339.599268 -275.485531) (xy 339.637389 -275.454406)
			(xy 339.68001 -275.429799) (xy 339.726026 -275.412347) (xy 339.774245 -275.402503) (xy 339.82342 -275.400522)
			(xy 339.872275 -275.406454) (xy 339.919546 -275.420146) (xy 339.964008 -275.441244) (xy 340.004511 -275.4692)
			(xy 340.040004 -275.503292) (xy 340.069569 -275.542636) (xy 340.09244 -275.586213) (xy 340.108024 -275.632894)
			(xy 340.115919 -275.681471) (xy 340.116414 -275.706078) (xy 340.434925 -275.706078) (xy 340.43902 -275.65535)
			(xy 340.451199 -275.605936) (xy 340.471147 -275.559116) (xy 340.498348 -275.516102) (xy 340.532096 -275.478008)
			(xy 340.571518 -275.445821) (xy 340.615592 -275.420375) (xy 340.663178 -275.402328) (xy 340.713042 -275.392148)
			(xy 340.763894 -275.390099) (xy 340.814415 -275.396233) (xy 340.863299 -275.410393) (xy 340.909278 -275.43221)
			(xy 340.951162 -275.46112) (xy 340.987866 -275.496375) (xy 341.018439 -275.537061) (xy 341.04209 -275.582124)
			(xy 341.058206 -275.630398) (xy 341.06637 -275.680632) (xy 341.066882 -275.706078) (xy 342.314779 -275.706078)
			(xy 342.318874 -275.65535) (xy 342.331053 -275.605936) (xy 342.351001 -275.559116) (xy 342.378202 -275.516102)
			(xy 342.41195 -275.478008) (xy 342.451372 -275.445821) (xy 342.495446 -275.420375) (xy 342.543032 -275.402328)
			(xy 342.592896 -275.392148) (xy 342.643748 -275.390099) (xy 342.694269 -275.396233) (xy 342.743153 -275.410393)
			(xy 342.789132 -275.43221) (xy 342.831016 -275.46112) (xy 342.86772 -275.496375) (xy 342.898293 -275.537061)
			(xy 342.921944 -275.582124) (xy 342.93806 -275.630398) (xy 342.946224 -275.680632) (xy 342.946736 -275.706078)
			(xy 343.254833 -275.706078) (xy 343.258928 -275.65535) (xy 343.271107 -275.605936) (xy 343.291055 -275.559116)
			(xy 343.318256 -275.516102) (xy 343.352004 -275.478008) (xy 343.391426 -275.445821) (xy 343.4355 -275.420375)
			(xy 343.483086 -275.402328) (xy 343.53295 -275.392148) (xy 343.583802 -275.390099) (xy 343.634323 -275.396233)
			(xy 343.683207 -275.410393) (xy 343.729186 -275.43221) (xy 343.77107 -275.46112) (xy 343.807774 -275.496375)
			(xy 343.838347 -275.537061) (xy 343.861998 -275.582124) (xy 343.878114 -275.630398) (xy 343.886278 -275.680632)
			(xy 343.88679 -275.706078) (xy 344.205318 -275.706078) (xy 344.209278 -275.657024) (xy 344.221055 -275.60924)
			(xy 344.240346 -275.563964) (xy 344.266649 -275.522368) (xy 344.299284 -275.485531) (xy 344.337405 -275.454406)
			(xy 344.380026 -275.429799) (xy 344.426042 -275.412347) (xy 344.474261 -275.402503) (xy 344.523436 -275.400522)
			(xy 344.572291 -275.406454) (xy 344.619562 -275.420146) (xy 344.664024 -275.441244) (xy 344.704527 -275.4692)
			(xy 344.74002 -275.503292) (xy 344.769585 -275.542636) (xy 344.792456 -275.586213) (xy 344.80804 -275.632894)
			(xy 344.815935 -275.681471) (xy 344.81643 -275.706078) (xy 345.145372 -275.706078) (xy 345.149332 -275.657024)
			(xy 345.161109 -275.60924) (xy 345.1804 -275.563964) (xy 345.206703 -275.522368) (xy 345.239338 -275.485531)
			(xy 345.277459 -275.454406) (xy 345.32008 -275.429799) (xy 345.366096 -275.412347) (xy 345.414315 -275.402503)
			(xy 345.46349 -275.400522) (xy 345.512345 -275.406454) (xy 345.559616 -275.420146) (xy 345.604078 -275.441244)
			(xy 345.644581 -275.4692) (xy 345.680074 -275.503292) (xy 345.709639 -275.542636) (xy 345.73251 -275.586213)
			(xy 345.748094 -275.632894) (xy 345.755989 -275.681471) (xy 345.756484 -275.706078) (xy 346.085426 -275.706078)
			(xy 346.089386 -275.657024) (xy 346.101163 -275.60924) (xy 346.120454 -275.563964) (xy 346.146757 -275.522368)
			(xy 346.179392 -275.485531) (xy 346.217513 -275.454406) (xy 346.260134 -275.429799) (xy 346.30615 -275.412347)
			(xy 346.354369 -275.402503) (xy 346.403544 -275.400522) (xy 346.452399 -275.406454) (xy 346.49967 -275.420146)
			(xy 346.544132 -275.441244) (xy 346.584635 -275.4692) (xy 346.620128 -275.503292) (xy 346.649693 -275.542636)
			(xy 346.672564 -275.586213) (xy 346.688148 -275.632894) (xy 346.696043 -275.681471) (xy 346.696538 -275.706078)
			(xy 347.025226 -275.706078) (xy 347.029186 -275.657024) (xy 347.040963 -275.60924) (xy 347.060254 -275.563964)
			(xy 347.086557 -275.522368) (xy 347.119192 -275.485531) (xy 347.157313 -275.454406) (xy 347.199934 -275.429799)
			(xy 347.24595 -275.412347) (xy 347.294169 -275.402503) (xy 347.343344 -275.400522) (xy 347.392199 -275.406454)
			(xy 347.43947 -275.420146) (xy 347.483932 -275.441244) (xy 347.524435 -275.4692) (xy 347.559928 -275.503292)
			(xy 347.589493 -275.542636) (xy 347.612364 -275.586213) (xy 347.627948 -275.632894) (xy 347.635843 -275.681471)
			(xy 347.636338 -275.706078) (xy 347.96528 -275.706078) (xy 347.96924 -275.657024) (xy 347.981017 -275.60924)
			(xy 348.000308 -275.563964) (xy 348.026611 -275.522368) (xy 348.059246 -275.485531) (xy 348.097367 -275.454406)
			(xy 348.139988 -275.429799) (xy 348.186004 -275.412347) (xy 348.234223 -275.402503) (xy 348.283398 -275.400522)
			(xy 348.332253 -275.406454) (xy 348.379524 -275.420146) (xy 348.423986 -275.441244) (xy 348.464489 -275.4692)
			(xy 348.499982 -275.503292) (xy 348.529547 -275.542636) (xy 348.552418 -275.586213) (xy 348.568002 -275.632894)
			(xy 348.575897 -275.681471) (xy 348.576392 -275.706078) (xy 348.905334 -275.706078) (xy 348.909294 -275.657024)
			(xy 348.921071 -275.60924) (xy 348.940362 -275.563964) (xy 348.966665 -275.522368) (xy 348.9993 -275.485531)
			(xy 349.037421 -275.454406) (xy 349.080042 -275.429799) (xy 349.126058 -275.412347) (xy 349.174277 -275.402503)
			(xy 349.223452 -275.400522) (xy 349.272307 -275.406454) (xy 349.319578 -275.420146) (xy 349.36404 -275.441244)
			(xy 349.404543 -275.4692) (xy 349.440036 -275.503292) (xy 349.469601 -275.542636) (xy 349.492472 -275.586213)
			(xy 349.508056 -275.632894) (xy 349.515951 -275.681471) (xy 349.516446 -275.706078) (xy 349.845388 -275.706078)
			(xy 349.849348 -275.657024) (xy 349.861125 -275.60924) (xy 349.880416 -275.563964) (xy 349.906719 -275.522368)
			(xy 349.939354 -275.485531) (xy 349.977475 -275.454406) (xy 350.020096 -275.429799) (xy 350.066112 -275.412347)
			(xy 350.114331 -275.402503) (xy 350.163506 -275.400522) (xy 350.212361 -275.406454) (xy 350.259632 -275.420146)
			(xy 350.304094 -275.441244) (xy 350.344597 -275.4692) (xy 350.38009 -275.503292) (xy 350.409655 -275.542636)
			(xy 350.432526 -275.586213) (xy 350.44811 -275.632894) (xy 350.456005 -275.681471) (xy 350.4565 -275.706078)
			(xy 350.785442 -275.706078) (xy 350.789402 -275.657024) (xy 350.801179 -275.60924) (xy 350.82047 -275.563964)
			(xy 350.846773 -275.522368) (xy 350.879408 -275.485531) (xy 350.917529 -275.454406) (xy 350.96015 -275.429799)
			(xy 351.006166 -275.412347) (xy 351.054385 -275.402503) (xy 351.10356 -275.400522) (xy 351.152415 -275.406454)
			(xy 351.199686 -275.420146) (xy 351.244148 -275.441244) (xy 351.284651 -275.4692) (xy 351.320144 -275.503292)
			(xy 351.349709 -275.542636) (xy 351.37258 -275.586213) (xy 351.388164 -275.632894) (xy 351.396059 -275.681471)
			(xy 351.396554 -275.706078) (xy 351.396059 -275.730685) (xy 351.388164 -275.779262) (xy 351.37258 -275.825943)
			(xy 351.349709 -275.86952) (xy 351.320144 -275.908864) (xy 351.284651 -275.942956) (xy 351.244148 -275.970912)
			(xy 351.199686 -275.99201) (xy 351.152415 -276.005702) (xy 351.10356 -276.011634) (xy 351.054385 -276.009653)
			(xy 351.006166 -275.999809) (xy 350.96015 -275.982357) (xy 350.917529 -275.95775) (xy 350.879408 -275.926625)
			(xy 350.846773 -275.889788) (xy 350.82047 -275.848192) (xy 350.801179 -275.802916) (xy 350.789402 -275.755132)
			(xy 350.785442 -275.706078) (xy 350.4565 -275.706078) (xy 350.456005 -275.730685) (xy 350.44811 -275.779262)
			(xy 350.432526 -275.825943) (xy 350.409655 -275.86952) (xy 350.38009 -275.908864) (xy 350.344597 -275.942956)
			(xy 350.304094 -275.970912) (xy 350.259632 -275.99201) (xy 350.212361 -276.005702) (xy 350.163506 -276.011634)
			(xy 350.114331 -276.009653) (xy 350.066112 -275.999809) (xy 350.020096 -275.982357) (xy 349.977475 -275.95775)
			(xy 349.939354 -275.926625) (xy 349.906719 -275.889788) (xy 349.880416 -275.848192) (xy 349.861125 -275.802916)
			(xy 349.849348 -275.755132) (xy 349.845388 -275.706078) (xy 349.516446 -275.706078) (xy 349.515951 -275.730685)
			(xy 349.508056 -275.779262) (xy 349.492472 -275.825943) (xy 349.469601 -275.86952) (xy 349.440036 -275.908864)
			(xy 349.404543 -275.942956) (xy 349.36404 -275.970912) (xy 349.319578 -275.99201) (xy 349.272307 -276.005702)
			(xy 349.223452 -276.011634) (xy 349.174277 -276.009653) (xy 349.126058 -275.999809) (xy 349.080042 -275.982357)
			(xy 349.037421 -275.95775) (xy 348.9993 -275.926625) (xy 348.966665 -275.889788) (xy 348.940362 -275.848192)
			(xy 348.921071 -275.802916) (xy 348.909294 -275.755132) (xy 348.905334 -275.706078) (xy 348.576392 -275.706078)
			(xy 348.575897 -275.730685) (xy 348.568002 -275.779262) (xy 348.552418 -275.825943) (xy 348.529547 -275.86952)
			(xy 348.499982 -275.908864) (xy 348.464489 -275.942956) (xy 348.423986 -275.970912) (xy 348.379524 -275.99201)
			(xy 348.332253 -276.005702) (xy 348.283398 -276.011634) (xy 348.234223 -276.009653) (xy 348.186004 -275.999809)
			(xy 348.139988 -275.982357) (xy 348.097367 -275.95775) (xy 348.059246 -275.926625) (xy 348.026611 -275.889788)
			(xy 348.000308 -275.848192) (xy 347.981017 -275.802916) (xy 347.96924 -275.755132) (xy 347.96528 -275.706078)
			(xy 347.636338 -275.706078) (xy 347.635843 -275.730685) (xy 347.627948 -275.779262) (xy 347.612364 -275.825943)
			(xy 347.589493 -275.86952) (xy 347.559928 -275.908864) (xy 347.524435 -275.942956) (xy 347.483932 -275.970912)
			(xy 347.43947 -275.99201) (xy 347.392199 -276.005702) (xy 347.343344 -276.011634) (xy 347.294169 -276.009653)
			(xy 347.24595 -275.999809) (xy 347.199934 -275.982357) (xy 347.157313 -275.95775) (xy 347.119192 -275.926625)
			(xy 347.086557 -275.889788) (xy 347.060254 -275.848192) (xy 347.040963 -275.802916) (xy 347.029186 -275.755132)
			(xy 347.025226 -275.706078) (xy 346.696538 -275.706078) (xy 346.696043 -275.730685) (xy 346.688148 -275.779262)
			(xy 346.672564 -275.825943) (xy 346.649693 -275.86952) (xy 346.620128 -275.908864) (xy 346.584635 -275.942956)
			(xy 346.544132 -275.970912) (xy 346.49967 -275.99201) (xy 346.452399 -276.005702) (xy 346.403544 -276.011634)
			(xy 346.354369 -276.009653) (xy 346.30615 -275.999809) (xy 346.260134 -275.982357) (xy 346.217513 -275.95775)
			(xy 346.179392 -275.926625) (xy 346.146757 -275.889788) (xy 346.120454 -275.848192) (xy 346.101163 -275.802916)
			(xy 346.089386 -275.755132) (xy 346.085426 -275.706078) (xy 345.756484 -275.706078) (xy 345.755989 -275.730685)
			(xy 345.748094 -275.779262) (xy 345.73251 -275.825943) (xy 345.709639 -275.86952) (xy 345.680074 -275.908864)
			(xy 345.644581 -275.942956) (xy 345.604078 -275.970912) (xy 345.559616 -275.99201) (xy 345.512345 -276.005702)
			(xy 345.46349 -276.011634) (xy 345.414315 -276.009653) (xy 345.366096 -275.999809) (xy 345.32008 -275.982357)
			(xy 345.277459 -275.95775) (xy 345.239338 -275.926625) (xy 345.206703 -275.889788) (xy 345.1804 -275.848192)
			(xy 345.161109 -275.802916) (xy 345.149332 -275.755132) (xy 345.145372 -275.706078) (xy 344.81643 -275.706078)
			(xy 344.815935 -275.730685) (xy 344.80804 -275.779262) (xy 344.792456 -275.825943) (xy 344.769585 -275.86952)
			(xy 344.74002 -275.908864) (xy 344.704527 -275.942956) (xy 344.664024 -275.970912) (xy 344.619562 -275.99201)
			(xy 344.572291 -276.005702) (xy 344.523436 -276.011634) (xy 344.474261 -276.009653) (xy 344.426042 -275.999809)
			(xy 344.380026 -275.982357) (xy 344.337405 -275.95775) (xy 344.299284 -275.926625) (xy 344.266649 -275.889788)
			(xy 344.240346 -275.848192) (xy 344.221055 -275.802916) (xy 344.209278 -275.755132) (xy 344.205318 -275.706078)
			(xy 343.88679 -275.706078) (xy 343.886278 -275.731524) (xy 343.878114 -275.781758) (xy 343.861998 -275.830032)
			(xy 343.838347 -275.875095) (xy 343.807774 -275.915781) (xy 343.77107 -275.951036) (xy 343.729186 -275.979946)
			(xy 343.683207 -276.001763) (xy 343.634323 -276.015923) (xy 343.583802 -276.022057) (xy 343.53295 -276.020008)
			(xy 343.483086 -276.009828) (xy 343.4355 -275.991781) (xy 343.391426 -275.966335) (xy 343.352004 -275.934148)
			(xy 343.318256 -275.896054) (xy 343.291055 -275.85304) (xy 343.271107 -275.80622) (xy 343.258928 -275.756806)
			(xy 343.254833 -275.706078) (xy 342.946736 -275.706078) (xy 342.946224 -275.731524) (xy 342.93806 -275.781758)
			(xy 342.921944 -275.830032) (xy 342.898293 -275.875095) (xy 342.86772 -275.915781) (xy 342.831016 -275.951036)
			(xy 342.789132 -275.979946) (xy 342.743153 -276.001763) (xy 342.694269 -276.015923) (xy 342.643748 -276.022057)
			(xy 342.592896 -276.020008) (xy 342.543032 -276.009828) (xy 342.495446 -275.991781) (xy 342.451372 -275.966335)
			(xy 342.41195 -275.934148) (xy 342.378202 -275.896054) (xy 342.351001 -275.85304) (xy 342.331053 -275.80622)
			(xy 342.318874 -275.756806) (xy 342.314779 -275.706078) (xy 341.066882 -275.706078) (xy 341.06637 -275.731524)
			(xy 341.058206 -275.781758) (xy 341.04209 -275.830032) (xy 341.018439 -275.875095) (xy 340.987866 -275.915781)
			(xy 340.951162 -275.951036) (xy 340.909278 -275.979946) (xy 340.863299 -276.001763) (xy 340.814415 -276.015923)
			(xy 340.763894 -276.022057) (xy 340.713042 -276.020008) (xy 340.663178 -276.009828) (xy 340.615592 -275.991781)
			(xy 340.571518 -275.966335) (xy 340.532096 -275.934148) (xy 340.498348 -275.896054) (xy 340.471147 -275.85304)
			(xy 340.451199 -275.80622) (xy 340.43902 -275.756806) (xy 340.434925 -275.706078) (xy 340.116414 -275.706078)
			(xy 340.115919 -275.730685) (xy 340.108024 -275.779262) (xy 340.09244 -275.825943) (xy 340.069569 -275.86952)
			(xy 340.040004 -275.908864) (xy 340.004511 -275.942956) (xy 339.964008 -275.970912) (xy 339.919546 -275.99201)
			(xy 339.872275 -276.005702) (xy 339.82342 -276.011634) (xy 339.774245 -276.009653) (xy 339.726026 -275.999809)
			(xy 339.68001 -275.982357) (xy 339.637389 -275.95775) (xy 339.599268 -275.926625) (xy 339.566633 -275.889788)
			(xy 339.54033 -275.848192) (xy 339.521039 -275.802916) (xy 339.509262 -275.755132) (xy 339.505302 -275.706078)
			(xy 339.186774 -275.706078) (xy 339.186262 -275.731524) (xy 339.178098 -275.781758) (xy 339.161982 -275.830032)
			(xy 339.138331 -275.875095) (xy 339.107758 -275.915781) (xy 339.071054 -275.951036) (xy 339.02917 -275.979946)
			(xy 338.983191 -276.001763) (xy 338.934307 -276.015923) (xy 338.883786 -276.022057) (xy 338.832934 -276.020008)
			(xy 338.78307 -276.009828) (xy 338.735484 -275.991781) (xy 338.69141 -275.966335) (xy 338.651988 -275.934148)
			(xy 338.61824 -275.896054) (xy 338.591039 -275.85304) (xy 338.571091 -275.80622) (xy 338.558912 -275.756806)
			(xy 338.554817 -275.706078) (xy 338.236306 -275.706078) (xy 338.235811 -275.730685) (xy 338.227916 -275.779262)
			(xy 338.212332 -275.825943) (xy 338.189461 -275.86952) (xy 338.159896 -275.908864) (xy 338.124403 -275.942956)
			(xy 338.0839 -275.970912) (xy 338.039438 -275.99201) (xy 337.992167 -276.005702) (xy 337.943312 -276.011634)
			(xy 337.894137 -276.009653) (xy 337.845918 -275.999809) (xy 337.799902 -275.982357) (xy 337.757281 -275.95775)
			(xy 337.71916 -275.926625) (xy 337.686525 -275.889788) (xy 337.660222 -275.848192) (xy 337.640931 -275.802916)
			(xy 337.629154 -275.755132) (xy 337.625194 -275.706078) (xy 337.30692 -275.706078) (xy 337.306408 -275.731524)
			(xy 337.298244 -275.781758) (xy 337.282128 -275.830032) (xy 337.258477 -275.875095) (xy 337.227904 -275.915781)
			(xy 337.1912 -275.951036) (xy 337.149316 -275.979946) (xy 337.103337 -276.001763) (xy 337.054453 -276.015923)
			(xy 337.003932 -276.022057) (xy 336.95308 -276.020008) (xy 336.903216 -276.009828) (xy 336.85563 -275.991781)
			(xy 336.811556 -275.966335) (xy 336.772134 -275.934148) (xy 336.738386 -275.896054) (xy 336.711185 -275.85304)
			(xy 336.691237 -275.80622) (xy 336.679058 -275.756806) (xy 336.674963 -275.706078) (xy 336.366866 -275.706078)
			(xy 336.366354 -275.731524) (xy 336.35819 -275.781758) (xy 336.342074 -275.830032) (xy 336.318423 -275.875095)
			(xy 336.28785 -275.915781) (xy 336.251146 -275.951036) (xy 336.209262 -275.979946) (xy 336.163283 -276.001763)
			(xy 336.114399 -276.015923) (xy 336.063878 -276.022057) (xy 336.013026 -276.020008) (xy 335.963162 -276.009828)
			(xy 335.915576 -275.991781) (xy 335.871502 -275.966335) (xy 335.83208 -275.934148) (xy 335.798332 -275.896054)
			(xy 335.771131 -275.85304) (xy 335.751183 -275.80622) (xy 335.739004 -275.756806) (xy 335.734909 -275.706078)
			(xy 334.486758 -275.706078) (xy 334.486246 -275.731524) (xy 334.478082 -275.781758) (xy 334.461966 -275.830032)
			(xy 334.438315 -275.875095) (xy 334.407742 -275.915781) (xy 334.371038 -275.951036) (xy 334.329154 -275.979946)
			(xy 334.283175 -276.001763) (xy 334.234291 -276.015923) (xy 334.18377 -276.022057) (xy 334.132918 -276.020008)
			(xy 334.083054 -276.009828) (xy 334.035468 -275.991781) (xy 333.991394 -275.966335) (xy 333.951972 -275.934148)
			(xy 333.918224 -275.896054) (xy 333.891023 -275.85304) (xy 333.871075 -275.80622) (xy 333.858896 -275.756806)
			(xy 333.854801 -275.706078) (xy 333.53629 -275.706078) (xy 333.535795 -275.730685) (xy 333.5279 -275.779262)
			(xy 333.512316 -275.825943) (xy 333.489445 -275.86952) (xy 333.45988 -275.908864) (xy 333.424387 -275.942956)
			(xy 333.383884 -275.970912) (xy 333.339422 -275.99201) (xy 333.292151 -276.005702) (xy 333.243296 -276.011634)
			(xy 333.194121 -276.009653) (xy 333.145902 -275.999809) (xy 333.099886 -275.982357) (xy 333.057265 -275.95775)
			(xy 333.019144 -275.926625) (xy 332.986509 -275.889788) (xy 332.960206 -275.848192) (xy 332.940915 -275.802916)
			(xy 332.929138 -275.755132) (xy 332.925178 -275.706078) (xy 332.606904 -275.706078) (xy 332.606392 -275.731524)
			(xy 332.598228 -275.781758) (xy 332.582112 -275.830032) (xy 332.558461 -275.875095) (xy 332.527888 -275.915781)
			(xy 332.491184 -275.951036) (xy 332.4493 -275.979946) (xy 332.403321 -276.001763) (xy 332.354437 -276.015923)
			(xy 332.303916 -276.022057) (xy 332.253064 -276.020008) (xy 332.2032 -276.009828) (xy 332.155614 -275.991781)
			(xy 332.11154 -275.966335) (xy 332.072118 -275.934148) (xy 332.03837 -275.896054) (xy 332.011169 -275.85304)
			(xy 331.991221 -275.80622) (xy 331.979042 -275.756806) (xy 331.974947 -275.706078) (xy 331.656436 -275.706078)
			(xy 331.655941 -275.730685) (xy 331.648046 -275.779262) (xy 331.632462 -275.825943) (xy 331.609591 -275.86952)
			(xy 331.580026 -275.908864) (xy 331.544533 -275.942956) (xy 331.50403 -275.970912) (xy 331.459568 -275.99201)
			(xy 331.412297 -276.005702) (xy 331.363442 -276.011634) (xy 331.314267 -276.009653) (xy 331.266048 -275.999809)
			(xy 331.220032 -275.982357) (xy 331.177411 -275.95775) (xy 331.13929 -275.926625) (xy 331.106655 -275.889788)
			(xy 331.080352 -275.848192) (xy 331.061061 -275.802916) (xy 331.049284 -275.755132) (xy 331.045324 -275.706078)
			(xy 330.726796 -275.706078) (xy 330.726284 -275.731524) (xy 330.71812 -275.781758) (xy 330.702004 -275.830032)
			(xy 330.678353 -275.875095) (xy 330.64778 -275.915781) (xy 330.611076 -275.951036) (xy 330.569192 -275.979946)
			(xy 330.523213 -276.001763) (xy 330.474329 -276.015923) (xy 330.423808 -276.022057) (xy 330.372956 -276.020008)
			(xy 330.323092 -276.009828) (xy 330.275506 -275.991781) (xy 330.231432 -275.966335) (xy 330.19201 -275.934148)
			(xy 330.158262 -275.896054) (xy 330.131061 -275.85304) (xy 330.111113 -275.80622) (xy 330.098934 -275.756806)
			(xy 330.094839 -275.706078) (xy 329.786742 -275.706078) (xy 329.78623 -275.731524) (xy 329.778066 -275.781758)
			(xy 329.76195 -275.830032) (xy 329.738299 -275.875095) (xy 329.707726 -275.915781) (xy 329.671022 -275.951036)
			(xy 329.629138 -275.979946) (xy 329.583159 -276.001763) (xy 329.534275 -276.015923) (xy 329.483754 -276.022057)
			(xy 329.432902 -276.020008) (xy 329.383038 -276.009828) (xy 329.335452 -275.991781) (xy 329.291378 -275.966335)
			(xy 329.251956 -275.934148) (xy 329.218208 -275.896054) (xy 329.191007 -275.85304) (xy 329.171059 -275.80622)
			(xy 329.15888 -275.756806) (xy 329.154785 -275.706078) (xy 326.95642 -275.706078) (xy 326.955925 -275.730685)
			(xy 326.94803 -275.779262) (xy 326.932446 -275.825943) (xy 326.909575 -275.86952) (xy 326.88001 -275.908864)
			(xy 326.844517 -275.942956) (xy 326.804014 -275.970912) (xy 326.759552 -275.99201) (xy 326.712281 -276.005702)
			(xy 326.663426 -276.011634) (xy 326.614251 -276.009653) (xy 326.566032 -275.999809) (xy 326.520016 -275.982357)
			(xy 326.477395 -275.95775) (xy 326.439274 -275.926625) (xy 326.406639 -275.889788) (xy 326.380336 -275.848192)
			(xy 326.361045 -275.802916) (xy 326.349268 -275.755132) (xy 326.345308 -275.706078) (xy 310.45912 -275.706078)
			(xy 310.45912 -276.250146) (xy 324.74714 -276.250146) (xy 324.7511 -276.201092) (xy 324.762877 -276.153308)
			(xy 324.782168 -276.108032) (xy 324.808471 -276.066436) (xy 324.841106 -276.029599) (xy 324.879227 -275.998474)
			(xy 324.921848 -275.973867) (xy 324.967864 -275.956415) (xy 325.016083 -275.946571) (xy 325.065258 -275.94459)
			(xy 325.114113 -275.950522) (xy 325.161384 -275.964214) (xy 325.205846 -275.985312) (xy 325.246349 -276.013268)
			(xy 325.281842 -276.04736) (xy 325.311407 -276.086704) (xy 325.334278 -276.130281) (xy 325.349862 -276.176962)
			(xy 325.357757 -276.225539) (xy 325.358252 -276.250146) (xy 325.357757 -276.274753) (xy 325.349862 -276.32333)
			(xy 325.334278 -276.370011) (xy 325.311407 -276.413588) (xy 325.281842 -276.452932) (xy 325.246349 -276.487024)
			(xy 325.205846 -276.51498) (xy 325.203519 -276.516084) (xy 327.755262 -276.516084) (xy 327.759222 -276.46703)
			(xy 327.770999 -276.419246) (xy 327.79029 -276.37397) (xy 327.816593 -276.332374) (xy 327.849228 -276.295537)
			(xy 327.887349 -276.264412) (xy 327.92997 -276.239805) (xy 327.975986 -276.222353) (xy 328.024205 -276.212509)
			(xy 328.07338 -276.210528) (xy 328.122235 -276.21646) (xy 328.169506 -276.230152) (xy 328.213968 -276.25125)
			(xy 328.254471 -276.279206) (xy 328.289964 -276.313298) (xy 328.319529 -276.352642) (xy 328.3424 -276.396219)
			(xy 328.357984 -276.4429) (xy 328.365879 -276.491477) (xy 328.366374 -276.516084) (xy 328.684885 -276.516084)
			(xy 328.68898 -276.465356) (xy 328.701159 -276.415942) (xy 328.721107 -276.369122) (xy 328.748308 -276.326108)
			(xy 328.782056 -276.288014) (xy 328.821478 -276.255827) (xy 328.865552 -276.230381) (xy 328.913138 -276.212334)
			(xy 328.963002 -276.202154) (xy 329.013854 -276.200105) (xy 329.064375 -276.206239) (xy 329.113259 -276.220399)
			(xy 329.159238 -276.242216) (xy 329.201122 -276.271126) (xy 329.237826 -276.306381) (xy 329.268399 -276.347067)
			(xy 329.29205 -276.39213) (xy 329.308166 -276.440404) (xy 329.31633 -276.490638) (xy 329.316842 -276.516084)
			(xy 329.63537 -276.516084) (xy 329.63933 -276.46703) (xy 329.651107 -276.419246) (xy 329.670398 -276.37397)
			(xy 329.696701 -276.332374) (xy 329.729336 -276.295537) (xy 329.767457 -276.264412) (xy 329.810078 -276.239805)
			(xy 329.856094 -276.222353) (xy 329.904313 -276.212509) (xy 329.953488 -276.210528) (xy 330.002343 -276.21646)
			(xy 330.049614 -276.230152) (xy 330.094076 -276.25125) (xy 330.134579 -276.279206) (xy 330.170072 -276.313298)
			(xy 330.199637 -276.352642) (xy 330.222508 -276.396219) (xy 330.238092 -276.4429) (xy 330.245987 -276.491477)
			(xy 330.246482 -276.516084) (xy 330.564739 -276.516084) (xy 330.568834 -276.465356) (xy 330.581013 -276.415942)
			(xy 330.600961 -276.369122) (xy 330.628162 -276.326108) (xy 330.66191 -276.288014) (xy 330.701332 -276.255827)
			(xy 330.745406 -276.230381) (xy 330.792992 -276.212334) (xy 330.842856 -276.202154) (xy 330.893708 -276.200105)
			(xy 330.944229 -276.206239) (xy 330.993113 -276.220399) (xy 331.039092 -276.242216) (xy 331.080976 -276.271126)
			(xy 331.11768 -276.306381) (xy 331.148253 -276.347067) (xy 331.171904 -276.39213) (xy 331.18802 -276.440404)
			(xy 331.196184 -276.490638) (xy 331.196696 -276.516084) (xy 331.515224 -276.516084) (xy 331.519184 -276.46703)
			(xy 331.530961 -276.419246) (xy 331.550252 -276.37397) (xy 331.576555 -276.332374) (xy 331.60919 -276.295537)
			(xy 331.647311 -276.264412) (xy 331.689932 -276.239805) (xy 331.735948 -276.222353) (xy 331.784167 -276.212509)
			(xy 331.833342 -276.210528) (xy 331.882197 -276.21646) (xy 331.929468 -276.230152) (xy 331.97393 -276.25125)
			(xy 332.014433 -276.279206) (xy 332.049926 -276.313298) (xy 332.079491 -276.352642) (xy 332.102362 -276.396219)
			(xy 332.117946 -276.4429) (xy 332.125841 -276.491477) (xy 332.126336 -276.516084) (xy 332.444847 -276.516084)
			(xy 332.448942 -276.465356) (xy 332.461121 -276.415942) (xy 332.481069 -276.369122) (xy 332.50827 -276.326108)
			(xy 332.542018 -276.288014) (xy 332.58144 -276.255827) (xy 332.625514 -276.230381) (xy 332.6731 -276.212334)
			(xy 332.722964 -276.202154) (xy 332.773816 -276.200105) (xy 332.824337 -276.206239) (xy 332.873221 -276.220399)
			(xy 332.9192 -276.242216) (xy 332.961084 -276.271126) (xy 332.997788 -276.306381) (xy 333.028361 -276.347067)
			(xy 333.052012 -276.39213) (xy 333.068128 -276.440404) (xy 333.076292 -276.490638) (xy 333.076804 -276.516084)
			(xy 333.384901 -276.516084) (xy 333.388996 -276.465356) (xy 333.401175 -276.415942) (xy 333.421123 -276.369122)
			(xy 333.448324 -276.326108) (xy 333.482072 -276.288014) (xy 333.521494 -276.255827) (xy 333.565568 -276.230381)
			(xy 333.613154 -276.212334) (xy 333.663018 -276.202154) (xy 333.71387 -276.200105) (xy 333.764391 -276.206239)
			(xy 333.813275 -276.220399) (xy 333.859254 -276.242216) (xy 333.901138 -276.271126) (xy 333.937842 -276.306381)
			(xy 333.968415 -276.347067) (xy 333.992066 -276.39213) (xy 334.008182 -276.440404) (xy 334.016346 -276.490638)
			(xy 334.016858 -276.516084) (xy 334.335386 -276.516084) (xy 334.339346 -276.46703) (xy 334.351123 -276.419246)
			(xy 334.370414 -276.37397) (xy 334.396717 -276.332374) (xy 334.429352 -276.295537) (xy 334.467473 -276.264412)
			(xy 334.510094 -276.239805) (xy 334.55611 -276.222353) (xy 334.604329 -276.212509) (xy 334.653504 -276.210528)
			(xy 334.702359 -276.21646) (xy 334.74963 -276.230152) (xy 334.794092 -276.25125) (xy 334.834595 -276.279206)
			(xy 334.870088 -276.313298) (xy 334.899653 -276.352642) (xy 334.922524 -276.396219) (xy 334.938108 -276.4429)
			(xy 334.946003 -276.491477) (xy 334.946498 -276.516084) (xy 335.264755 -276.516084) (xy 335.26885 -276.465356)
			(xy 335.281029 -276.415942) (xy 335.300977 -276.369122) (xy 335.328178 -276.326108) (xy 335.361926 -276.288014)
			(xy 335.401348 -276.255827) (xy 335.445422 -276.230381) (xy 335.493008 -276.212334) (xy 335.542872 -276.202154)
			(xy 335.593724 -276.200105) (xy 335.644245 -276.206239) (xy 335.693129 -276.220399) (xy 335.739108 -276.242216)
			(xy 335.780992 -276.271126) (xy 335.817696 -276.306381) (xy 335.848269 -276.347067) (xy 335.87192 -276.39213)
			(xy 335.888036 -276.440404) (xy 335.8962 -276.490638) (xy 335.896712 -276.516084) (xy 336.21524 -276.516084)
			(xy 336.2192 -276.46703) (xy 336.230977 -276.419246) (xy 336.250268 -276.37397) (xy 336.276571 -276.332374)
			(xy 336.309206 -276.295537) (xy 336.347327 -276.264412) (xy 336.389948 -276.239805) (xy 336.435964 -276.222353)
			(xy 336.484183 -276.212509) (xy 336.533358 -276.210528) (xy 336.582213 -276.21646) (xy 336.629484 -276.230152)
			(xy 336.673946 -276.25125) (xy 336.714449 -276.279206) (xy 336.749942 -276.313298) (xy 336.779507 -276.352642)
			(xy 336.802378 -276.396219) (xy 336.817962 -276.4429) (xy 336.825857 -276.491477) (xy 336.826352 -276.516084)
			(xy 337.144863 -276.516084) (xy 337.148958 -276.465356) (xy 337.161137 -276.415942) (xy 337.181085 -276.369122)
			(xy 337.208286 -276.326108) (xy 337.242034 -276.288014) (xy 337.281456 -276.255827) (xy 337.32553 -276.230381)
			(xy 337.373116 -276.212334) (xy 337.42298 -276.202154) (xy 337.473832 -276.200105) (xy 337.524353 -276.206239)
			(xy 337.573237 -276.220399) (xy 337.619216 -276.242216) (xy 337.6611 -276.271126) (xy 337.697804 -276.306381)
			(xy 337.728377 -276.347067) (xy 337.752028 -276.39213) (xy 337.768144 -276.440404) (xy 337.776308 -276.490638)
			(xy 337.77682 -276.516084) (xy 338.095348 -276.516084) (xy 338.099308 -276.46703) (xy 338.111085 -276.419246)
			(xy 338.130376 -276.37397) (xy 338.156679 -276.332374) (xy 338.189314 -276.295537) (xy 338.227435 -276.264412)
			(xy 338.270056 -276.239805) (xy 338.316072 -276.222353) (xy 338.364291 -276.212509) (xy 338.413466 -276.210528)
			(xy 338.462321 -276.21646) (xy 338.509592 -276.230152) (xy 338.554054 -276.25125) (xy 338.594557 -276.279206)
			(xy 338.63005 -276.313298) (xy 338.659615 -276.352642) (xy 338.682486 -276.396219) (xy 338.69807 -276.4429)
			(xy 338.705965 -276.491477) (xy 338.70646 -276.516084) (xy 339.024971 -276.516084) (xy 339.029066 -276.465356)
			(xy 339.041245 -276.415942) (xy 339.061193 -276.369122) (xy 339.088394 -276.326108) (xy 339.122142 -276.288014)
			(xy 339.161564 -276.255827) (xy 339.205638 -276.230381) (xy 339.253224 -276.212334) (xy 339.303088 -276.202154)
			(xy 339.35394 -276.200105) (xy 339.404461 -276.206239) (xy 339.453345 -276.220399) (xy 339.499324 -276.242216)
			(xy 339.541208 -276.271126) (xy 339.577912 -276.306381) (xy 339.608485 -276.347067) (xy 339.632136 -276.39213)
			(xy 339.648252 -276.440404) (xy 339.656416 -276.490638) (xy 339.656928 -276.516084) (xy 339.964771 -276.516084)
			(xy 339.968866 -276.465356) (xy 339.981045 -276.415942) (xy 340.000993 -276.369122) (xy 340.028194 -276.326108)
			(xy 340.061942 -276.288014) (xy 340.101364 -276.255827) (xy 340.145438 -276.230381) (xy 340.193024 -276.212334)
			(xy 340.242888 -276.202154) (xy 340.29374 -276.200105) (xy 340.344261 -276.206239) (xy 340.393145 -276.220399)
			(xy 340.439124 -276.242216) (xy 340.481008 -276.271126) (xy 340.517712 -276.306381) (xy 340.548285 -276.347067)
			(xy 340.571936 -276.39213) (xy 340.588052 -276.440404) (xy 340.596216 -276.490638) (xy 340.596728 -276.516084)
			(xy 340.915256 -276.516084) (xy 340.919216 -276.46703) (xy 340.930993 -276.419246) (xy 340.950284 -276.37397)
			(xy 340.976587 -276.332374) (xy 341.009222 -276.295537) (xy 341.047343 -276.264412) (xy 341.089964 -276.239805)
			(xy 341.13598 -276.222353) (xy 341.184199 -276.212509) (xy 341.233374 -276.210528) (xy 341.282229 -276.21646)
			(xy 341.3295 -276.230152) (xy 341.373962 -276.25125) (xy 341.414465 -276.279206) (xy 341.449958 -276.313298)
			(xy 341.479523 -276.352642) (xy 341.502394 -276.396219) (xy 341.517978 -276.4429) (xy 341.525873 -276.491477)
			(xy 341.526368 -276.516084) (xy 341.844879 -276.516084) (xy 341.848974 -276.465356) (xy 341.861153 -276.415942)
			(xy 341.881101 -276.369122) (xy 341.908302 -276.326108) (xy 341.94205 -276.288014) (xy 341.981472 -276.255827)
			(xy 342.025546 -276.230381) (xy 342.073132 -276.212334) (xy 342.122996 -276.202154) (xy 342.173848 -276.200105)
			(xy 342.224369 -276.206239) (xy 342.273253 -276.220399) (xy 342.319232 -276.242216) (xy 342.361116 -276.271126)
			(xy 342.39782 -276.306381) (xy 342.428393 -276.347067) (xy 342.452044 -276.39213) (xy 342.46816 -276.440404)
			(xy 342.476324 -276.490638) (xy 342.476836 -276.516084) (xy 342.795364 -276.516084) (xy 342.799324 -276.46703)
			(xy 342.811101 -276.419246) (xy 342.830392 -276.37397) (xy 342.856695 -276.332374) (xy 342.88933 -276.295537)
			(xy 342.927451 -276.264412) (xy 342.970072 -276.239805) (xy 343.016088 -276.222353) (xy 343.064307 -276.212509)
			(xy 343.113482 -276.210528) (xy 343.162337 -276.21646) (xy 343.209608 -276.230152) (xy 343.25407 -276.25125)
			(xy 343.294573 -276.279206) (xy 343.330066 -276.313298) (xy 343.359631 -276.352642) (xy 343.382502 -276.396219)
			(xy 343.398086 -276.4429) (xy 343.405981 -276.491477) (xy 343.406476 -276.516084) (xy 343.724987 -276.516084)
			(xy 343.729082 -276.465356) (xy 343.741261 -276.415942) (xy 343.761209 -276.369122) (xy 343.78841 -276.326108)
			(xy 343.822158 -276.288014) (xy 343.86158 -276.255827) (xy 343.905654 -276.230381) (xy 343.95324 -276.212334)
			(xy 344.003104 -276.202154) (xy 344.053956 -276.200105) (xy 344.104477 -276.206239) (xy 344.153361 -276.220399)
			(xy 344.19934 -276.242216) (xy 344.241224 -276.271126) (xy 344.277928 -276.306381) (xy 344.308501 -276.347067)
			(xy 344.332152 -276.39213) (xy 344.348268 -276.440404) (xy 344.356432 -276.490638) (xy 344.356944 -276.516084)
			(xy 344.675218 -276.516084) (xy 344.679178 -276.46703) (xy 344.690955 -276.419246) (xy 344.710246 -276.37397)
			(xy 344.736549 -276.332374) (xy 344.769184 -276.295537) (xy 344.807305 -276.264412) (xy 344.849926 -276.239805)
			(xy 344.895942 -276.222353) (xy 344.944161 -276.212509) (xy 344.993336 -276.210528) (xy 345.042191 -276.21646)
			(xy 345.089462 -276.230152) (xy 345.133924 -276.25125) (xy 345.174427 -276.279206) (xy 345.20992 -276.313298)
			(xy 345.239485 -276.352642) (xy 345.262356 -276.396219) (xy 345.27794 -276.4429) (xy 345.285835 -276.491477)
			(xy 345.28633 -276.516084) (xy 345.604841 -276.516084) (xy 345.608936 -276.465356) (xy 345.621115 -276.415942)
			(xy 345.641063 -276.369122) (xy 345.668264 -276.326108) (xy 345.702012 -276.288014) (xy 345.741434 -276.255827)
			(xy 345.785508 -276.230381) (xy 345.833094 -276.212334) (xy 345.882958 -276.202154) (xy 345.93381 -276.200105)
			(xy 345.984331 -276.206239) (xy 346.033215 -276.220399) (xy 346.079194 -276.242216) (xy 346.121078 -276.271126)
			(xy 346.157782 -276.306381) (xy 346.188355 -276.347067) (xy 346.212006 -276.39213) (xy 346.228122 -276.440404)
			(xy 346.236286 -276.490638) (xy 346.236798 -276.516084) (xy 346.544895 -276.516084) (xy 346.54899 -276.465356)
			(xy 346.561169 -276.415942) (xy 346.581117 -276.369122) (xy 346.608318 -276.326108) (xy 346.642066 -276.288014)
			(xy 346.681488 -276.255827) (xy 346.725562 -276.230381) (xy 346.773148 -276.212334) (xy 346.823012 -276.202154)
			(xy 346.873864 -276.200105) (xy 346.924385 -276.206239) (xy 346.973269 -276.220399) (xy 347.019248 -276.242216)
			(xy 347.061132 -276.271126) (xy 347.097836 -276.306381) (xy 347.128409 -276.347067) (xy 347.15206 -276.39213)
			(xy 347.168176 -276.440404) (xy 347.17634 -276.490638) (xy 347.176852 -276.516084) (xy 347.49538 -276.516084)
			(xy 347.49934 -276.46703) (xy 347.511117 -276.419246) (xy 347.530408 -276.37397) (xy 347.556711 -276.332374)
			(xy 347.589346 -276.295537) (xy 347.627467 -276.264412) (xy 347.670088 -276.239805) (xy 347.716104 -276.222353)
			(xy 347.764323 -276.212509) (xy 347.813498 -276.210528) (xy 347.862353 -276.21646) (xy 347.909624 -276.230152)
			(xy 347.954086 -276.25125) (xy 347.994589 -276.279206) (xy 348.030082 -276.313298) (xy 348.059647 -276.352642)
			(xy 348.082518 -276.396219) (xy 348.098102 -276.4429) (xy 348.105997 -276.491477) (xy 348.106492 -276.516084)
			(xy 348.425003 -276.516084) (xy 348.429098 -276.465356) (xy 348.441277 -276.415942) (xy 348.461225 -276.369122)
			(xy 348.488426 -276.326108) (xy 348.522174 -276.288014) (xy 348.561596 -276.255827) (xy 348.60567 -276.230381)
			(xy 348.653256 -276.212334) (xy 348.70312 -276.202154) (xy 348.753972 -276.200105) (xy 348.804493 -276.206239)
			(xy 348.853377 -276.220399) (xy 348.899356 -276.242216) (xy 348.94124 -276.271126) (xy 348.977944 -276.306381)
			(xy 349.008517 -276.347067) (xy 349.032168 -276.39213) (xy 349.048284 -276.440404) (xy 349.056448 -276.490638)
			(xy 349.05696 -276.516084) (xy 349.364803 -276.516084) (xy 349.368898 -276.465356) (xy 349.381077 -276.415942)
			(xy 349.401025 -276.369122) (xy 349.428226 -276.326108) (xy 349.461974 -276.288014) (xy 349.501396 -276.255827)
			(xy 349.54547 -276.230381) (xy 349.593056 -276.212334) (xy 349.64292 -276.202154) (xy 349.693772 -276.200105)
			(xy 349.744293 -276.206239) (xy 349.793177 -276.220399) (xy 349.839156 -276.242216) (xy 349.88104 -276.271126)
			(xy 349.917744 -276.306381) (xy 349.948317 -276.347067) (xy 349.971968 -276.39213) (xy 349.988084 -276.440404)
			(xy 349.996248 -276.490638) (xy 349.99676 -276.516084) (xy 350.315288 -276.516084) (xy 350.319248 -276.46703)
			(xy 350.331025 -276.419246) (xy 350.350316 -276.37397) (xy 350.376619 -276.332374) (xy 350.409254 -276.295537)
			(xy 350.447375 -276.264412) (xy 350.489996 -276.239805) (xy 350.536012 -276.222353) (xy 350.584231 -276.212509)
			(xy 350.633406 -276.210528) (xy 350.682261 -276.21646) (xy 350.729532 -276.230152) (xy 350.773994 -276.25125)
			(xy 350.814497 -276.279206) (xy 350.84999 -276.313298) (xy 350.879555 -276.352642) (xy 350.902426 -276.396219)
			(xy 350.91801 -276.4429) (xy 350.925905 -276.491477) (xy 350.9264 -276.516084) (xy 350.925905 -276.540691)
			(xy 350.91801 -276.589268) (xy 350.902426 -276.635949) (xy 350.879555 -276.679526) (xy 350.84999 -276.71887)
			(xy 350.814497 -276.752962) (xy 350.773994 -276.780918) (xy 350.729532 -276.802016) (xy 350.682261 -276.815708)
			(xy 350.633406 -276.82164) (xy 350.584231 -276.819659) (xy 350.536012 -276.809815) (xy 350.489996 -276.792363)
			(xy 350.447375 -276.767756) (xy 350.409254 -276.736631) (xy 350.376619 -276.699794) (xy 350.350316 -276.658198)
			(xy 350.331025 -276.612922) (xy 350.319248 -276.565138) (xy 350.315288 -276.516084) (xy 349.99676 -276.516084)
			(xy 349.996248 -276.54153) (xy 349.988084 -276.591764) (xy 349.971968 -276.640038) (xy 349.948317 -276.685101)
			(xy 349.917744 -276.725787) (xy 349.88104 -276.761042) (xy 349.839156 -276.789952) (xy 349.793177 -276.811769)
			(xy 349.744293 -276.825929) (xy 349.693772 -276.832063) (xy 349.64292 -276.830014) (xy 349.593056 -276.819834)
			(xy 349.54547 -276.801787) (xy 349.501396 -276.776341) (xy 349.461974 -276.744154) (xy 349.428226 -276.70606)
			(xy 349.401025 -276.663046) (xy 349.381077 -276.616226) (xy 349.368898 -276.566812) (xy 349.364803 -276.516084)
			(xy 349.05696 -276.516084) (xy 349.056448 -276.54153) (xy 349.048284 -276.591764) (xy 349.032168 -276.640038)
			(xy 349.008517 -276.685101) (xy 348.977944 -276.725787) (xy 348.94124 -276.761042) (xy 348.899356 -276.789952)
			(xy 348.853377 -276.811769) (xy 348.804493 -276.825929) (xy 348.753972 -276.832063) (xy 348.70312 -276.830014)
			(xy 348.653256 -276.819834) (xy 348.60567 -276.801787) (xy 348.561596 -276.776341) (xy 348.522174 -276.744154)
			(xy 348.488426 -276.70606) (xy 348.461225 -276.663046) (xy 348.441277 -276.616226) (xy 348.429098 -276.566812)
			(xy 348.425003 -276.516084) (xy 348.106492 -276.516084) (xy 348.105997 -276.540691) (xy 348.098102 -276.589268)
			(xy 348.082518 -276.635949) (xy 348.059647 -276.679526) (xy 348.030082 -276.71887) (xy 347.994589 -276.752962)
			(xy 347.954086 -276.780918) (xy 347.909624 -276.802016) (xy 347.862353 -276.815708) (xy 347.813498 -276.82164)
			(xy 347.764323 -276.819659) (xy 347.716104 -276.809815) (xy 347.670088 -276.792363) (xy 347.627467 -276.767756)
			(xy 347.589346 -276.736631) (xy 347.556711 -276.699794) (xy 347.530408 -276.658198) (xy 347.511117 -276.612922)
			(xy 347.49934 -276.565138) (xy 347.49538 -276.516084) (xy 347.176852 -276.516084) (xy 347.17634 -276.54153)
			(xy 347.168176 -276.591764) (xy 347.15206 -276.640038) (xy 347.128409 -276.685101) (xy 347.097836 -276.725787)
			(xy 347.061132 -276.761042) (xy 347.019248 -276.789952) (xy 346.973269 -276.811769) (xy 346.924385 -276.825929)
			(xy 346.873864 -276.832063) (xy 346.823012 -276.830014) (xy 346.773148 -276.819834) (xy 346.725562 -276.801787)
			(xy 346.681488 -276.776341) (xy 346.642066 -276.744154) (xy 346.608318 -276.70606) (xy 346.581117 -276.663046)
			(xy 346.561169 -276.616226) (xy 346.54899 -276.566812) (xy 346.544895 -276.516084) (xy 346.236798 -276.516084)
			(xy 346.236286 -276.54153) (xy 346.228122 -276.591764) (xy 346.212006 -276.640038) (xy 346.188355 -276.685101)
			(xy 346.157782 -276.725787) (xy 346.121078 -276.761042) (xy 346.079194 -276.789952) (xy 346.033215 -276.811769)
			(xy 345.984331 -276.825929) (xy 345.93381 -276.832063) (xy 345.882958 -276.830014) (xy 345.833094 -276.819834)
			(xy 345.785508 -276.801787) (xy 345.741434 -276.776341) (xy 345.702012 -276.744154) (xy 345.668264 -276.70606)
			(xy 345.641063 -276.663046) (xy 345.621115 -276.616226) (xy 345.608936 -276.566812) (xy 345.604841 -276.516084)
			(xy 345.28633 -276.516084) (xy 345.285835 -276.540691) (xy 345.27794 -276.589268) (xy 345.262356 -276.635949)
			(xy 345.239485 -276.679526) (xy 345.20992 -276.71887) (xy 345.174427 -276.752962) (xy 345.133924 -276.780918)
			(xy 345.089462 -276.802016) (xy 345.042191 -276.815708) (xy 344.993336 -276.82164) (xy 344.944161 -276.819659)
			(xy 344.895942 -276.809815) (xy 344.849926 -276.792363) (xy 344.807305 -276.767756) (xy 344.769184 -276.736631)
			(xy 344.736549 -276.699794) (xy 344.710246 -276.658198) (xy 344.690955 -276.612922) (xy 344.679178 -276.565138)
			(xy 344.675218 -276.516084) (xy 344.356944 -276.516084) (xy 344.356432 -276.54153) (xy 344.348268 -276.591764)
			(xy 344.332152 -276.640038) (xy 344.308501 -276.685101) (xy 344.277928 -276.725787) (xy 344.241224 -276.761042)
			(xy 344.19934 -276.789952) (xy 344.153361 -276.811769) (xy 344.104477 -276.825929) (xy 344.053956 -276.832063)
			(xy 344.003104 -276.830014) (xy 343.95324 -276.819834) (xy 343.905654 -276.801787) (xy 343.86158 -276.776341)
			(xy 343.822158 -276.744154) (xy 343.78841 -276.70606) (xy 343.761209 -276.663046) (xy 343.741261 -276.616226)
			(xy 343.729082 -276.566812) (xy 343.724987 -276.516084) (xy 343.406476 -276.516084) (xy 343.405981 -276.540691)
			(xy 343.398086 -276.589268) (xy 343.382502 -276.635949) (xy 343.359631 -276.679526) (xy 343.330066 -276.71887)
			(xy 343.294573 -276.752962) (xy 343.25407 -276.780918) (xy 343.209608 -276.802016) (xy 343.162337 -276.815708)
			(xy 343.113482 -276.82164) (xy 343.064307 -276.819659) (xy 343.016088 -276.809815) (xy 342.970072 -276.792363)
			(xy 342.927451 -276.767756) (xy 342.88933 -276.736631) (xy 342.856695 -276.699794) (xy 342.830392 -276.658198)
			(xy 342.811101 -276.612922) (xy 342.799324 -276.565138) (xy 342.795364 -276.516084) (xy 342.476836 -276.516084)
			(xy 342.476324 -276.54153) (xy 342.46816 -276.591764) (xy 342.452044 -276.640038) (xy 342.428393 -276.685101)
			(xy 342.39782 -276.725787) (xy 342.361116 -276.761042) (xy 342.319232 -276.789952) (xy 342.273253 -276.811769)
			(xy 342.224369 -276.825929) (xy 342.173848 -276.832063) (xy 342.122996 -276.830014) (xy 342.073132 -276.819834)
			(xy 342.025546 -276.801787) (xy 341.981472 -276.776341) (xy 341.94205 -276.744154) (xy 341.908302 -276.70606)
			(xy 341.881101 -276.663046) (xy 341.861153 -276.616226) (xy 341.848974 -276.566812) (xy 341.844879 -276.516084)
			(xy 341.526368 -276.516084) (xy 341.525873 -276.540691) (xy 341.517978 -276.589268) (xy 341.502394 -276.635949)
			(xy 341.479523 -276.679526) (xy 341.449958 -276.71887) (xy 341.414465 -276.752962) (xy 341.373962 -276.780918)
			(xy 341.3295 -276.802016) (xy 341.282229 -276.815708) (xy 341.233374 -276.82164) (xy 341.184199 -276.819659)
			(xy 341.13598 -276.809815) (xy 341.089964 -276.792363) (xy 341.047343 -276.767756) (xy 341.009222 -276.736631)
			(xy 340.976587 -276.699794) (xy 340.950284 -276.658198) (xy 340.930993 -276.612922) (xy 340.919216 -276.565138)
			(xy 340.915256 -276.516084) (xy 340.596728 -276.516084) (xy 340.596216 -276.54153) (xy 340.588052 -276.591764)
			(xy 340.571936 -276.640038) (xy 340.548285 -276.685101) (xy 340.517712 -276.725787) (xy 340.481008 -276.761042)
			(xy 340.439124 -276.789952) (xy 340.393145 -276.811769) (xy 340.344261 -276.825929) (xy 340.29374 -276.832063)
			(xy 340.242888 -276.830014) (xy 340.193024 -276.819834) (xy 340.145438 -276.801787) (xy 340.101364 -276.776341)
			(xy 340.061942 -276.744154) (xy 340.028194 -276.70606) (xy 340.000993 -276.663046) (xy 339.981045 -276.616226)
			(xy 339.968866 -276.566812) (xy 339.964771 -276.516084) (xy 339.656928 -276.516084) (xy 339.656416 -276.54153)
			(xy 339.648252 -276.591764) (xy 339.632136 -276.640038) (xy 339.608485 -276.685101) (xy 339.577912 -276.725787)
			(xy 339.541208 -276.761042) (xy 339.499324 -276.789952) (xy 339.453345 -276.811769) (xy 339.404461 -276.825929)
			(xy 339.35394 -276.832063) (xy 339.303088 -276.830014) (xy 339.253224 -276.819834) (xy 339.205638 -276.801787)
			(xy 339.161564 -276.776341) (xy 339.122142 -276.744154) (xy 339.088394 -276.70606) (xy 339.061193 -276.663046)
			(xy 339.041245 -276.616226) (xy 339.029066 -276.566812) (xy 339.024971 -276.516084) (xy 338.70646 -276.516084)
			(xy 338.705965 -276.540691) (xy 338.69807 -276.589268) (xy 338.682486 -276.635949) (xy 338.659615 -276.679526)
			(xy 338.63005 -276.71887) (xy 338.594557 -276.752962) (xy 338.554054 -276.780918) (xy 338.509592 -276.802016)
			(xy 338.462321 -276.815708) (xy 338.413466 -276.82164) (xy 338.364291 -276.819659) (xy 338.316072 -276.809815)
			(xy 338.270056 -276.792363) (xy 338.227435 -276.767756) (xy 338.189314 -276.736631) (xy 338.156679 -276.699794)
			(xy 338.130376 -276.658198) (xy 338.111085 -276.612922) (xy 338.099308 -276.565138) (xy 338.095348 -276.516084)
			(xy 337.77682 -276.516084) (xy 337.776308 -276.54153) (xy 337.768144 -276.591764) (xy 337.752028 -276.640038)
			(xy 337.728377 -276.685101) (xy 337.697804 -276.725787) (xy 337.6611 -276.761042) (xy 337.619216 -276.789952)
			(xy 337.573237 -276.811769) (xy 337.524353 -276.825929) (xy 337.473832 -276.832063) (xy 337.42298 -276.830014)
			(xy 337.373116 -276.819834) (xy 337.32553 -276.801787) (xy 337.281456 -276.776341) (xy 337.242034 -276.744154)
			(xy 337.208286 -276.70606) (xy 337.181085 -276.663046) (xy 337.161137 -276.616226) (xy 337.148958 -276.566812)
			(xy 337.144863 -276.516084) (xy 336.826352 -276.516084) (xy 336.825857 -276.540691) (xy 336.817962 -276.589268)
			(xy 336.802378 -276.635949) (xy 336.779507 -276.679526) (xy 336.749942 -276.71887) (xy 336.714449 -276.752962)
			(xy 336.673946 -276.780918) (xy 336.629484 -276.802016) (xy 336.582213 -276.815708) (xy 336.533358 -276.82164)
			(xy 336.484183 -276.819659) (xy 336.435964 -276.809815) (xy 336.389948 -276.792363) (xy 336.347327 -276.767756)
			(xy 336.309206 -276.736631) (xy 336.276571 -276.699794) (xy 336.250268 -276.658198) (xy 336.230977 -276.612922)
			(xy 336.2192 -276.565138) (xy 336.21524 -276.516084) (xy 335.896712 -276.516084) (xy 335.8962 -276.54153)
			(xy 335.888036 -276.591764) (xy 335.87192 -276.640038) (xy 335.848269 -276.685101) (xy 335.817696 -276.725787)
			(xy 335.780992 -276.761042) (xy 335.739108 -276.789952) (xy 335.693129 -276.811769) (xy 335.644245 -276.825929)
			(xy 335.593724 -276.832063) (xy 335.542872 -276.830014) (xy 335.493008 -276.819834) (xy 335.445422 -276.801787)
			(xy 335.401348 -276.776341) (xy 335.361926 -276.744154) (xy 335.328178 -276.70606) (xy 335.300977 -276.663046)
			(xy 335.281029 -276.616226) (xy 335.26885 -276.566812) (xy 335.264755 -276.516084) (xy 334.946498 -276.516084)
			(xy 334.946003 -276.540691) (xy 334.938108 -276.589268) (xy 334.922524 -276.635949) (xy 334.899653 -276.679526)
			(xy 334.870088 -276.71887) (xy 334.834595 -276.752962) (xy 334.794092 -276.780918) (xy 334.74963 -276.802016)
			(xy 334.702359 -276.815708) (xy 334.653504 -276.82164) (xy 334.604329 -276.819659) (xy 334.55611 -276.809815)
			(xy 334.510094 -276.792363) (xy 334.467473 -276.767756) (xy 334.429352 -276.736631) (xy 334.396717 -276.699794)
			(xy 334.370414 -276.658198) (xy 334.351123 -276.612922) (xy 334.339346 -276.565138) (xy 334.335386 -276.516084)
			(xy 334.016858 -276.516084) (xy 334.016346 -276.54153) (xy 334.008182 -276.591764) (xy 333.992066 -276.640038)
			(xy 333.968415 -276.685101) (xy 333.937842 -276.725787) (xy 333.901138 -276.761042) (xy 333.859254 -276.789952)
			(xy 333.813275 -276.811769) (xy 333.764391 -276.825929) (xy 333.71387 -276.832063) (xy 333.663018 -276.830014)
			(xy 333.613154 -276.819834) (xy 333.565568 -276.801787) (xy 333.521494 -276.776341) (xy 333.482072 -276.744154)
			(xy 333.448324 -276.70606) (xy 333.421123 -276.663046) (xy 333.401175 -276.616226) (xy 333.388996 -276.566812)
			(xy 333.384901 -276.516084) (xy 333.076804 -276.516084) (xy 333.076292 -276.54153) (xy 333.068128 -276.591764)
			(xy 333.052012 -276.640038) (xy 333.028361 -276.685101) (xy 332.997788 -276.725787) (xy 332.961084 -276.761042)
			(xy 332.9192 -276.789952) (xy 332.873221 -276.811769) (xy 332.824337 -276.825929) (xy 332.773816 -276.832063)
			(xy 332.722964 -276.830014) (xy 332.6731 -276.819834) (xy 332.625514 -276.801787) (xy 332.58144 -276.776341)
			(xy 332.542018 -276.744154) (xy 332.50827 -276.70606) (xy 332.481069 -276.663046) (xy 332.461121 -276.616226)
			(xy 332.448942 -276.566812) (xy 332.444847 -276.516084) (xy 332.126336 -276.516084) (xy 332.125841 -276.540691)
			(xy 332.117946 -276.589268) (xy 332.102362 -276.635949) (xy 332.079491 -276.679526) (xy 332.049926 -276.71887)
			(xy 332.014433 -276.752962) (xy 331.97393 -276.780918) (xy 331.929468 -276.802016) (xy 331.882197 -276.815708)
			(xy 331.833342 -276.82164) (xy 331.784167 -276.819659) (xy 331.735948 -276.809815) (xy 331.689932 -276.792363)
			(xy 331.647311 -276.767756) (xy 331.60919 -276.736631) (xy 331.576555 -276.699794) (xy 331.550252 -276.658198)
			(xy 331.530961 -276.612922) (xy 331.519184 -276.565138) (xy 331.515224 -276.516084) (xy 331.196696 -276.516084)
			(xy 331.196184 -276.54153) (xy 331.18802 -276.591764) (xy 331.171904 -276.640038) (xy 331.148253 -276.685101)
			(xy 331.11768 -276.725787) (xy 331.080976 -276.761042) (xy 331.039092 -276.789952) (xy 330.993113 -276.811769)
			(xy 330.944229 -276.825929) (xy 330.893708 -276.832063) (xy 330.842856 -276.830014) (xy 330.792992 -276.819834)
			(xy 330.745406 -276.801787) (xy 330.701332 -276.776341) (xy 330.66191 -276.744154) (xy 330.628162 -276.70606)
			(xy 330.600961 -276.663046) (xy 330.581013 -276.616226) (xy 330.568834 -276.566812) (xy 330.564739 -276.516084)
			(xy 330.246482 -276.516084) (xy 330.245987 -276.540691) (xy 330.238092 -276.589268) (xy 330.222508 -276.635949)
			(xy 330.199637 -276.679526) (xy 330.170072 -276.71887) (xy 330.134579 -276.752962) (xy 330.094076 -276.780918)
			(xy 330.049614 -276.802016) (xy 330.002343 -276.815708) (xy 329.953488 -276.82164) (xy 329.904313 -276.819659)
			(xy 329.856094 -276.809815) (xy 329.810078 -276.792363) (xy 329.767457 -276.767756) (xy 329.729336 -276.736631)
			(xy 329.696701 -276.699794) (xy 329.670398 -276.658198) (xy 329.651107 -276.612922) (xy 329.63933 -276.565138)
			(xy 329.63537 -276.516084) (xy 329.316842 -276.516084) (xy 329.31633 -276.54153) (xy 329.308166 -276.591764)
			(xy 329.29205 -276.640038) (xy 329.268399 -276.685101) (xy 329.237826 -276.725787) (xy 329.201122 -276.761042)
			(xy 329.159238 -276.789952) (xy 329.113259 -276.811769) (xy 329.064375 -276.825929) (xy 329.013854 -276.832063)
			(xy 328.963002 -276.830014) (xy 328.913138 -276.819834) (xy 328.865552 -276.801787) (xy 328.821478 -276.776341)
			(xy 328.782056 -276.744154) (xy 328.748308 -276.70606) (xy 328.721107 -276.663046) (xy 328.701159 -276.616226)
			(xy 328.68898 -276.566812) (xy 328.684885 -276.516084) (xy 328.366374 -276.516084) (xy 328.365879 -276.540691)
			(xy 328.357984 -276.589268) (xy 328.3424 -276.635949) (xy 328.319529 -276.679526) (xy 328.289964 -276.71887)
			(xy 328.254471 -276.752962) (xy 328.213968 -276.780918) (xy 328.169506 -276.802016) (xy 328.122235 -276.815708)
			(xy 328.07338 -276.82164) (xy 328.024205 -276.819659) (xy 327.975986 -276.809815) (xy 327.92997 -276.792363)
			(xy 327.887349 -276.767756) (xy 327.849228 -276.736631) (xy 327.816593 -276.699794) (xy 327.79029 -276.658198)
			(xy 327.770999 -276.612922) (xy 327.759222 -276.565138) (xy 327.755262 -276.516084) (xy 325.203519 -276.516084)
			(xy 325.161384 -276.536078) (xy 325.114113 -276.54977) (xy 325.065258 -276.555702) (xy 325.016083 -276.553721)
			(xy 324.967864 -276.543877) (xy 324.921848 -276.526425) (xy 324.879227 -276.501818) (xy 324.841106 -276.470693)
			(xy 324.808471 -276.433856) (xy 324.782168 -276.39226) (xy 324.762877 -276.346984) (xy 324.7511 -276.2992)
			(xy 324.74714 -276.250146) (xy 310.45912 -276.250146) (xy 310.45912 -277.32609) (xy 326.345308 -277.32609)
			(xy 326.349268 -277.277036) (xy 326.361045 -277.229252) (xy 326.380336 -277.183976) (xy 326.406639 -277.14238)
			(xy 326.439274 -277.105543) (xy 326.477395 -277.074418) (xy 326.520016 -277.049811) (xy 326.566032 -277.032359)
			(xy 326.614251 -277.022515) (xy 326.663426 -277.020534) (xy 326.712281 -277.026466) (xy 326.759552 -277.040158)
			(xy 326.804014 -277.061256) (xy 326.844517 -277.089212) (xy 326.88001 -277.123304) (xy 326.909575 -277.162648)
			(xy 326.932446 -277.206225) (xy 326.94803 -277.252906) (xy 326.955925 -277.301483) (xy 326.95642 -277.32609)
			(xy 328.225416 -277.32609) (xy 328.229376 -277.277036) (xy 328.241153 -277.229252) (xy 328.260444 -277.183976)
			(xy 328.286747 -277.14238) (xy 328.319382 -277.105543) (xy 328.357503 -277.074418) (xy 328.400124 -277.049811)
			(xy 328.44614 -277.032359) (xy 328.494359 -277.022515) (xy 328.543534 -277.020534) (xy 328.592389 -277.026466)
			(xy 328.63966 -277.040158) (xy 328.684122 -277.061256) (xy 328.724625 -277.089212) (xy 328.760118 -277.123304)
			(xy 328.789683 -277.162648) (xy 328.812554 -277.206225) (xy 328.828138 -277.252906) (xy 328.836033 -277.301483)
			(xy 328.836528 -277.32609) (xy 329.154785 -277.32609) (xy 329.15888 -277.275362) (xy 329.171059 -277.225948)
			(xy 329.191007 -277.179128) (xy 329.218208 -277.136114) (xy 329.251956 -277.09802) (xy 329.291378 -277.065833)
			(xy 329.335452 -277.040387) (xy 329.383038 -277.02234) (xy 329.432902 -277.01216) (xy 329.483754 -277.010111)
			(xy 329.534275 -277.016245) (xy 329.583159 -277.030405) (xy 329.629138 -277.052222) (xy 329.671022 -277.081132)
			(xy 329.707726 -277.116387) (xy 329.738299 -277.157073) (xy 329.76195 -277.202136) (xy 329.778066 -277.25041)
			(xy 329.78623 -277.300644) (xy 329.786742 -277.32609) (xy 330.094839 -277.32609) (xy 330.098934 -277.275362)
			(xy 330.111113 -277.225948) (xy 330.131061 -277.179128) (xy 330.158262 -277.136114) (xy 330.19201 -277.09802)
			(xy 330.231432 -277.065833) (xy 330.275506 -277.040387) (xy 330.323092 -277.02234) (xy 330.372956 -277.01216)
			(xy 330.423808 -277.010111) (xy 330.474329 -277.016245) (xy 330.523213 -277.030405) (xy 330.569192 -277.052222)
			(xy 330.611076 -277.081132) (xy 330.64778 -277.116387) (xy 330.678353 -277.157073) (xy 330.702004 -277.202136)
			(xy 330.71812 -277.25041) (xy 330.726284 -277.300644) (xy 330.726796 -277.32609) (xy 331.045324 -277.32609)
			(xy 331.049284 -277.277036) (xy 331.061061 -277.229252) (xy 331.080352 -277.183976) (xy 331.106655 -277.14238)
			(xy 331.13929 -277.105543) (xy 331.177411 -277.074418) (xy 331.220032 -277.049811) (xy 331.266048 -277.032359)
			(xy 331.314267 -277.022515) (xy 331.363442 -277.020534) (xy 331.412297 -277.026466) (xy 331.459568 -277.040158)
			(xy 331.50403 -277.061256) (xy 331.544533 -277.089212) (xy 331.580026 -277.123304) (xy 331.609591 -277.162648)
			(xy 331.632462 -277.206225) (xy 331.648046 -277.252906) (xy 331.655941 -277.301483) (xy 331.656436 -277.32609)
			(xy 331.974947 -277.32609) (xy 331.979042 -277.275362) (xy 331.991221 -277.225948) (xy 332.011169 -277.179128)
			(xy 332.03837 -277.136114) (xy 332.072118 -277.09802) (xy 332.11154 -277.065833) (xy 332.155614 -277.040387)
			(xy 332.2032 -277.02234) (xy 332.253064 -277.01216) (xy 332.303916 -277.010111) (xy 332.354437 -277.016245)
			(xy 332.403321 -277.030405) (xy 332.4493 -277.052222) (xy 332.491184 -277.081132) (xy 332.527888 -277.116387)
			(xy 332.558461 -277.157073) (xy 332.582112 -277.202136) (xy 332.598228 -277.25041) (xy 332.606392 -277.300644)
			(xy 332.606904 -277.32609) (xy 332.925178 -277.32609) (xy 332.929138 -277.277036) (xy 332.940915 -277.229252)
			(xy 332.960206 -277.183976) (xy 332.986509 -277.14238) (xy 333.019144 -277.105543) (xy 333.057265 -277.074418)
			(xy 333.099886 -277.049811) (xy 333.145902 -277.032359) (xy 333.194121 -277.022515) (xy 333.243296 -277.020534)
			(xy 333.292151 -277.026466) (xy 333.339422 -277.040158) (xy 333.383884 -277.061256) (xy 333.424387 -277.089212)
			(xy 333.45988 -277.123304) (xy 333.489445 -277.162648) (xy 333.512316 -277.206225) (xy 333.5279 -277.252906)
			(xy 333.535795 -277.301483) (xy 333.53629 -277.32609) (xy 333.854801 -277.32609) (xy 333.858896 -277.275362)
			(xy 333.871075 -277.225948) (xy 333.891023 -277.179128) (xy 333.918224 -277.136114) (xy 333.951972 -277.09802)
			(xy 333.991394 -277.065833) (xy 334.035468 -277.040387) (xy 334.083054 -277.02234) (xy 334.132918 -277.01216)
			(xy 334.18377 -277.010111) (xy 334.234291 -277.016245) (xy 334.283175 -277.030405) (xy 334.329154 -277.052222)
			(xy 334.371038 -277.081132) (xy 334.407742 -277.116387) (xy 334.438315 -277.157073) (xy 334.461966 -277.202136)
			(xy 334.478082 -277.25041) (xy 334.486246 -277.300644) (xy 334.486758 -277.32609) (xy 334.805286 -277.32609)
			(xy 334.809246 -277.277036) (xy 334.821023 -277.229252) (xy 334.840314 -277.183976) (xy 334.866617 -277.14238)
			(xy 334.899252 -277.105543) (xy 334.937373 -277.074418) (xy 334.979994 -277.049811) (xy 335.02601 -277.032359)
			(xy 335.074229 -277.022515) (xy 335.123404 -277.020534) (xy 335.172259 -277.026466) (xy 335.21953 -277.040158)
			(xy 335.263992 -277.061256) (xy 335.304495 -277.089212) (xy 335.339988 -277.123304) (xy 335.369553 -277.162648)
			(xy 335.392424 -277.206225) (xy 335.408008 -277.252906) (xy 335.415903 -277.301483) (xy 335.416398 -277.32609)
			(xy 335.734909 -277.32609) (xy 335.739004 -277.275362) (xy 335.751183 -277.225948) (xy 335.771131 -277.179128)
			(xy 335.798332 -277.136114) (xy 335.83208 -277.09802) (xy 335.871502 -277.065833) (xy 335.915576 -277.040387)
			(xy 335.963162 -277.02234) (xy 336.013026 -277.01216) (xy 336.063878 -277.010111) (xy 336.114399 -277.016245)
			(xy 336.163283 -277.030405) (xy 336.209262 -277.052222) (xy 336.251146 -277.081132) (xy 336.28785 -277.116387)
			(xy 336.318423 -277.157073) (xy 336.342074 -277.202136) (xy 336.35819 -277.25041) (xy 336.366354 -277.300644)
			(xy 336.366866 -277.32609) (xy 336.674963 -277.32609) (xy 336.679058 -277.275362) (xy 336.691237 -277.225948)
			(xy 336.711185 -277.179128) (xy 336.738386 -277.136114) (xy 336.772134 -277.09802) (xy 336.811556 -277.065833)
			(xy 336.85563 -277.040387) (xy 336.903216 -277.02234) (xy 336.95308 -277.01216) (xy 337.003932 -277.010111)
			(xy 337.054453 -277.016245) (xy 337.103337 -277.030405) (xy 337.149316 -277.052222) (xy 337.1912 -277.081132)
			(xy 337.227904 -277.116387) (xy 337.258477 -277.157073) (xy 337.282128 -277.202136) (xy 337.298244 -277.25041)
			(xy 337.306408 -277.300644) (xy 337.30692 -277.32609) (xy 337.625194 -277.32609) (xy 337.629154 -277.277036)
			(xy 337.640931 -277.229252) (xy 337.660222 -277.183976) (xy 337.686525 -277.14238) (xy 337.71916 -277.105543)
			(xy 337.757281 -277.074418) (xy 337.799902 -277.049811) (xy 337.845918 -277.032359) (xy 337.894137 -277.022515)
			(xy 337.943312 -277.020534) (xy 337.992167 -277.026466) (xy 338.039438 -277.040158) (xy 338.0839 -277.061256)
			(xy 338.124403 -277.089212) (xy 338.159896 -277.123304) (xy 338.189461 -277.162648) (xy 338.212332 -277.206225)
			(xy 338.227916 -277.252906) (xy 338.235811 -277.301483) (xy 338.236306 -277.32609) (xy 338.554817 -277.32609)
			(xy 338.558912 -277.275362) (xy 338.571091 -277.225948) (xy 338.591039 -277.179128) (xy 338.61824 -277.136114)
			(xy 338.651988 -277.09802) (xy 338.69141 -277.065833) (xy 338.735484 -277.040387) (xy 338.78307 -277.02234)
			(xy 338.832934 -277.01216) (xy 338.883786 -277.010111) (xy 338.934307 -277.016245) (xy 338.983191 -277.030405)
			(xy 339.02917 -277.052222) (xy 339.071054 -277.081132) (xy 339.107758 -277.116387) (xy 339.138331 -277.157073)
			(xy 339.161982 -277.202136) (xy 339.178098 -277.25041) (xy 339.186262 -277.300644) (xy 339.186774 -277.32609)
			(xy 339.505302 -277.32609) (xy 339.509262 -277.277036) (xy 339.521039 -277.229252) (xy 339.54033 -277.183976)
			(xy 339.566633 -277.14238) (xy 339.599268 -277.105543) (xy 339.637389 -277.074418) (xy 339.68001 -277.049811)
			(xy 339.726026 -277.032359) (xy 339.774245 -277.022515) (xy 339.82342 -277.020534) (xy 339.872275 -277.026466)
			(xy 339.919546 -277.040158) (xy 339.964008 -277.061256) (xy 340.004511 -277.089212) (xy 340.040004 -277.123304)
			(xy 340.069569 -277.162648) (xy 340.09244 -277.206225) (xy 340.108024 -277.252906) (xy 340.115919 -277.301483)
			(xy 340.116414 -277.32609) (xy 340.434925 -277.32609) (xy 340.43902 -277.275362) (xy 340.451199 -277.225948)
			(xy 340.471147 -277.179128) (xy 340.498348 -277.136114) (xy 340.532096 -277.09802) (xy 340.571518 -277.065833)
			(xy 340.615592 -277.040387) (xy 340.663178 -277.02234) (xy 340.713042 -277.01216) (xy 340.763894 -277.010111)
			(xy 340.814415 -277.016245) (xy 340.863299 -277.030405) (xy 340.909278 -277.052222) (xy 340.951162 -277.081132)
			(xy 340.987866 -277.116387) (xy 341.018439 -277.157073) (xy 341.04209 -277.202136) (xy 341.058206 -277.25041)
			(xy 341.06637 -277.300644) (xy 341.066882 -277.32609) (xy 341.38541 -277.32609) (xy 341.38937 -277.277036)
			(xy 341.401147 -277.229252) (xy 341.420438 -277.183976) (xy 341.446741 -277.14238) (xy 341.479376 -277.105543)
			(xy 341.517497 -277.074418) (xy 341.560118 -277.049811) (xy 341.606134 -277.032359) (xy 341.654353 -277.022515)
			(xy 341.703528 -277.020534) (xy 341.752383 -277.026466) (xy 341.799654 -277.040158) (xy 341.844116 -277.061256)
			(xy 341.884619 -277.089212) (xy 341.920112 -277.123304) (xy 341.949677 -277.162648) (xy 341.972548 -277.206225)
			(xy 341.988132 -277.252906) (xy 341.996027 -277.301483) (xy 341.996522 -277.32609) (xy 342.314779 -277.32609)
			(xy 342.318874 -277.275362) (xy 342.331053 -277.225948) (xy 342.351001 -277.179128) (xy 342.378202 -277.136114)
			(xy 342.41195 -277.09802) (xy 342.451372 -277.065833) (xy 342.495446 -277.040387) (xy 342.543032 -277.02234)
			(xy 342.592896 -277.01216) (xy 342.643748 -277.010111) (xy 342.694269 -277.016245) (xy 342.743153 -277.030405)
			(xy 342.789132 -277.052222) (xy 342.831016 -277.081132) (xy 342.86772 -277.116387) (xy 342.898293 -277.157073)
			(xy 342.921944 -277.202136) (xy 342.93806 -277.25041) (xy 342.946224 -277.300644) (xy 342.946736 -277.32609)
			(xy 343.254833 -277.32609) (xy 343.258928 -277.275362) (xy 343.271107 -277.225948) (xy 343.291055 -277.179128)
			(xy 343.318256 -277.136114) (xy 343.352004 -277.09802) (xy 343.391426 -277.065833) (xy 343.4355 -277.040387)
			(xy 343.483086 -277.02234) (xy 343.53295 -277.01216) (xy 343.583802 -277.010111) (xy 343.634323 -277.016245)
			(xy 343.683207 -277.030405) (xy 343.729186 -277.052222) (xy 343.77107 -277.081132) (xy 343.807774 -277.116387)
			(xy 343.838347 -277.157073) (xy 343.861998 -277.202136) (xy 343.878114 -277.25041) (xy 343.886278 -277.300644)
			(xy 343.88679 -277.32609) (xy 345.145372 -277.32609) (xy 345.149332 -277.277036) (xy 345.161109 -277.229252)
			(xy 345.1804 -277.183976) (xy 345.206703 -277.14238) (xy 345.239338 -277.105543) (xy 345.277459 -277.074418)
			(xy 345.32008 -277.049811) (xy 345.366096 -277.032359) (xy 345.414315 -277.022515) (xy 345.46349 -277.020534)
			(xy 345.512345 -277.026466) (xy 345.559616 -277.040158) (xy 345.604078 -277.061256) (xy 345.644581 -277.089212)
			(xy 345.680074 -277.123304) (xy 345.709639 -277.162648) (xy 345.73251 -277.206225) (xy 345.748094 -277.252906)
			(xy 345.755989 -277.301483) (xy 345.756484 -277.32609) (xy 346.085426 -277.32609) (xy 346.089386 -277.277036)
			(xy 346.101163 -277.229252) (xy 346.120454 -277.183976) (xy 346.146757 -277.14238) (xy 346.179392 -277.105543)
			(xy 346.217513 -277.074418) (xy 346.260134 -277.049811) (xy 346.30615 -277.032359) (xy 346.354369 -277.022515)
			(xy 346.403544 -277.020534) (xy 346.452399 -277.026466) (xy 346.49967 -277.040158) (xy 346.544132 -277.061256)
			(xy 346.584635 -277.089212) (xy 346.620128 -277.123304) (xy 346.649693 -277.162648) (xy 346.672564 -277.206225)
			(xy 346.688148 -277.252906) (xy 346.696043 -277.301483) (xy 346.696538 -277.32609) (xy 347.025226 -277.32609)
			(xy 347.029186 -277.277036) (xy 347.040963 -277.229252) (xy 347.060254 -277.183976) (xy 347.086557 -277.14238)
			(xy 347.119192 -277.105543) (xy 347.157313 -277.074418) (xy 347.199934 -277.049811) (xy 347.24595 -277.032359)
			(xy 347.294169 -277.022515) (xy 347.343344 -277.020534) (xy 347.392199 -277.026466) (xy 347.43947 -277.040158)
			(xy 347.483932 -277.061256) (xy 347.524435 -277.089212) (xy 347.559928 -277.123304) (xy 347.589493 -277.162648)
			(xy 347.612364 -277.206225) (xy 347.627948 -277.252906) (xy 347.635843 -277.301483) (xy 347.636338 -277.32609)
			(xy 347.96528 -277.32609) (xy 347.96924 -277.277036) (xy 347.981017 -277.229252) (xy 348.000308 -277.183976)
			(xy 348.026611 -277.14238) (xy 348.059246 -277.105543) (xy 348.097367 -277.074418) (xy 348.139988 -277.049811)
			(xy 348.186004 -277.032359) (xy 348.234223 -277.022515) (xy 348.283398 -277.020534) (xy 348.332253 -277.026466)
			(xy 348.379524 -277.040158) (xy 348.423986 -277.061256) (xy 348.464489 -277.089212) (xy 348.499982 -277.123304)
			(xy 348.529547 -277.162648) (xy 348.552418 -277.206225) (xy 348.568002 -277.252906) (xy 348.575897 -277.301483)
			(xy 348.576392 -277.32609) (xy 348.905334 -277.32609) (xy 348.909294 -277.277036) (xy 348.921071 -277.229252)
			(xy 348.940362 -277.183976) (xy 348.966665 -277.14238) (xy 348.9993 -277.105543) (xy 349.037421 -277.074418)
			(xy 349.080042 -277.049811) (xy 349.126058 -277.032359) (xy 349.174277 -277.022515) (xy 349.223452 -277.020534)
			(xy 349.272307 -277.026466) (xy 349.319578 -277.040158) (xy 349.36404 -277.061256) (xy 349.404543 -277.089212)
			(xy 349.440036 -277.123304) (xy 349.469601 -277.162648) (xy 349.492472 -277.206225) (xy 349.508056 -277.252906)
			(xy 349.515951 -277.301483) (xy 349.516446 -277.32609) (xy 349.845388 -277.32609) (xy 349.849348 -277.277036)
			(xy 349.861125 -277.229252) (xy 349.880416 -277.183976) (xy 349.906719 -277.14238) (xy 349.939354 -277.105543)
			(xy 349.977475 -277.074418) (xy 350.020096 -277.049811) (xy 350.066112 -277.032359) (xy 350.114331 -277.022515)
			(xy 350.163506 -277.020534) (xy 350.212361 -277.026466) (xy 350.259632 -277.040158) (xy 350.304094 -277.061256)
			(xy 350.344597 -277.089212) (xy 350.38009 -277.123304) (xy 350.409655 -277.162648) (xy 350.432526 -277.206225)
			(xy 350.44811 -277.252906) (xy 350.456005 -277.301483) (xy 350.4565 -277.32609) (xy 350.785442 -277.32609)
			(xy 350.789402 -277.277036) (xy 350.801179 -277.229252) (xy 350.82047 -277.183976) (xy 350.846773 -277.14238)
			(xy 350.879408 -277.105543) (xy 350.917529 -277.074418) (xy 350.96015 -277.049811) (xy 351.006166 -277.032359)
			(xy 351.054385 -277.022515) (xy 351.10356 -277.020534) (xy 351.152415 -277.026466) (xy 351.199686 -277.040158)
			(xy 351.244148 -277.061256) (xy 351.284651 -277.089212) (xy 351.320144 -277.123304) (xy 351.349709 -277.162648)
			(xy 351.37258 -277.206225) (xy 351.388164 -277.252906) (xy 351.396059 -277.301483) (xy 351.396554 -277.32609)
			(xy 351.396059 -277.350697) (xy 351.388164 -277.399274) (xy 351.37258 -277.445955) (xy 351.349709 -277.489532)
			(xy 351.320144 -277.528876) (xy 351.284651 -277.562968) (xy 351.244148 -277.590924) (xy 351.199686 -277.612022)
			(xy 351.152415 -277.625714) (xy 351.10356 -277.631646) (xy 351.054385 -277.629665) (xy 351.006166 -277.619821)
			(xy 350.96015 -277.602369) (xy 350.917529 -277.577762) (xy 350.879408 -277.546637) (xy 350.846773 -277.5098)
			(xy 350.82047 -277.468204) (xy 350.801179 -277.422928) (xy 350.789402 -277.375144) (xy 350.785442 -277.32609)
			(xy 350.4565 -277.32609) (xy 350.456005 -277.350697) (xy 350.44811 -277.399274) (xy 350.432526 -277.445955)
			(xy 350.409655 -277.489532) (xy 350.38009 -277.528876) (xy 350.344597 -277.562968) (xy 350.304094 -277.590924)
			(xy 350.259632 -277.612022) (xy 350.212361 -277.625714) (xy 350.163506 -277.631646) (xy 350.114331 -277.629665)
			(xy 350.066112 -277.619821) (xy 350.020096 -277.602369) (xy 349.977475 -277.577762) (xy 349.939354 -277.546637)
			(xy 349.906719 -277.5098) (xy 349.880416 -277.468204) (xy 349.861125 -277.422928) (xy 349.849348 -277.375144)
			(xy 349.845388 -277.32609) (xy 349.516446 -277.32609) (xy 349.515951 -277.350697) (xy 349.508056 -277.399274)
			(xy 349.492472 -277.445955) (xy 349.469601 -277.489532) (xy 349.440036 -277.528876) (xy 349.404543 -277.562968)
			(xy 349.36404 -277.590924) (xy 349.319578 -277.612022) (xy 349.272307 -277.625714) (xy 349.223452 -277.631646)
			(xy 349.174277 -277.629665) (xy 349.126058 -277.619821) (xy 349.080042 -277.602369) (xy 349.037421 -277.577762)
			(xy 348.9993 -277.546637) (xy 348.966665 -277.5098) (xy 348.940362 -277.468204) (xy 348.921071 -277.422928)
			(xy 348.909294 -277.375144) (xy 348.905334 -277.32609) (xy 348.576392 -277.32609) (xy 348.575897 -277.350697)
			(xy 348.568002 -277.399274) (xy 348.552418 -277.445955) (xy 348.529547 -277.489532) (xy 348.499982 -277.528876)
			(xy 348.464489 -277.562968) (xy 348.423986 -277.590924) (xy 348.379524 -277.612022) (xy 348.332253 -277.625714)
			(xy 348.283398 -277.631646) (xy 348.234223 -277.629665) (xy 348.186004 -277.619821) (xy 348.139988 -277.602369)
			(xy 348.097367 -277.577762) (xy 348.059246 -277.546637) (xy 348.026611 -277.5098) (xy 348.000308 -277.468204)
			(xy 347.981017 -277.422928) (xy 347.96924 -277.375144) (xy 347.96528 -277.32609) (xy 347.636338 -277.32609)
			(xy 347.635843 -277.350697) (xy 347.627948 -277.399274) (xy 347.612364 -277.445955) (xy 347.589493 -277.489532)
			(xy 347.559928 -277.528876) (xy 347.524435 -277.562968) (xy 347.483932 -277.590924) (xy 347.43947 -277.612022)
			(xy 347.392199 -277.625714) (xy 347.343344 -277.631646) (xy 347.294169 -277.629665) (xy 347.24595 -277.619821)
			(xy 347.199934 -277.602369) (xy 347.157313 -277.577762) (xy 347.119192 -277.546637) (xy 347.086557 -277.5098)
			(xy 347.060254 -277.468204) (xy 347.040963 -277.422928) (xy 347.029186 -277.375144) (xy 347.025226 -277.32609)
			(xy 346.696538 -277.32609) (xy 346.696043 -277.350697) (xy 346.688148 -277.399274) (xy 346.672564 -277.445955)
			(xy 346.649693 -277.489532) (xy 346.620128 -277.528876) (xy 346.584635 -277.562968) (xy 346.544132 -277.590924)
			(xy 346.49967 -277.612022) (xy 346.452399 -277.625714) (xy 346.403544 -277.631646) (xy 346.354369 -277.629665)
			(xy 346.30615 -277.619821) (xy 346.260134 -277.602369) (xy 346.217513 -277.577762) (xy 346.179392 -277.546637)
			(xy 346.146757 -277.5098) (xy 346.120454 -277.468204) (xy 346.101163 -277.422928) (xy 346.089386 -277.375144)
			(xy 346.085426 -277.32609) (xy 345.756484 -277.32609) (xy 345.755989 -277.350697) (xy 345.748094 -277.399274)
			(xy 345.73251 -277.445955) (xy 345.709639 -277.489532) (xy 345.680074 -277.528876) (xy 345.644581 -277.562968)
			(xy 345.604078 -277.590924) (xy 345.559616 -277.612022) (xy 345.512345 -277.625714) (xy 345.46349 -277.631646)
			(xy 345.414315 -277.629665) (xy 345.366096 -277.619821) (xy 345.32008 -277.602369) (xy 345.277459 -277.577762)
			(xy 345.239338 -277.546637) (xy 345.206703 -277.5098) (xy 345.1804 -277.468204) (xy 345.161109 -277.422928)
			(xy 345.149332 -277.375144) (xy 345.145372 -277.32609) (xy 343.88679 -277.32609) (xy 343.886278 -277.351536)
			(xy 343.878114 -277.40177) (xy 343.861998 -277.450044) (xy 343.838347 -277.495107) (xy 343.807774 -277.535793)
			(xy 343.77107 -277.571048) (xy 343.729186 -277.599958) (xy 343.683207 -277.621775) (xy 343.634323 -277.635935)
			(xy 343.583802 -277.642069) (xy 343.53295 -277.64002) (xy 343.483086 -277.62984) (xy 343.4355 -277.611793)
			(xy 343.391426 -277.586347) (xy 343.352004 -277.55416) (xy 343.318256 -277.516066) (xy 343.291055 -277.473052)
			(xy 343.271107 -277.426232) (xy 343.258928 -277.376818) (xy 343.254833 -277.32609) (xy 342.946736 -277.32609)
			(xy 342.946224 -277.351536) (xy 342.93806 -277.40177) (xy 342.921944 -277.450044) (xy 342.898293 -277.495107)
			(xy 342.86772 -277.535793) (xy 342.831016 -277.571048) (xy 342.789132 -277.599958) (xy 342.743153 -277.621775)
			(xy 342.694269 -277.635935) (xy 342.643748 -277.642069) (xy 342.592896 -277.64002) (xy 342.543032 -277.62984)
			(xy 342.495446 -277.611793) (xy 342.451372 -277.586347) (xy 342.41195 -277.55416) (xy 342.378202 -277.516066)
			(xy 342.351001 -277.473052) (xy 342.331053 -277.426232) (xy 342.318874 -277.376818) (xy 342.314779 -277.32609)
			(xy 341.996522 -277.32609) (xy 341.996027 -277.350697) (xy 341.988132 -277.399274) (xy 341.972548 -277.445955)
			(xy 341.949677 -277.489532) (xy 341.920112 -277.528876) (xy 341.884619 -277.562968) (xy 341.844116 -277.590924)
			(xy 341.799654 -277.612022) (xy 341.752383 -277.625714) (xy 341.703528 -277.631646) (xy 341.654353 -277.629665)
			(xy 341.606134 -277.619821) (xy 341.560118 -277.602369) (xy 341.517497 -277.577762) (xy 341.479376 -277.546637)
			(xy 341.446741 -277.5098) (xy 341.420438 -277.468204) (xy 341.401147 -277.422928) (xy 341.38937 -277.375144)
			(xy 341.38541 -277.32609) (xy 341.066882 -277.32609) (xy 341.06637 -277.351536) (xy 341.058206 -277.40177)
			(xy 341.04209 -277.450044) (xy 341.018439 -277.495107) (xy 340.987866 -277.535793) (xy 340.951162 -277.571048)
			(xy 340.909278 -277.599958) (xy 340.863299 -277.621775) (xy 340.814415 -277.635935) (xy 340.763894 -277.642069)
			(xy 340.713042 -277.64002) (xy 340.663178 -277.62984) (xy 340.615592 -277.611793) (xy 340.571518 -277.586347)
			(xy 340.532096 -277.55416) (xy 340.498348 -277.516066) (xy 340.471147 -277.473052) (xy 340.451199 -277.426232)
			(xy 340.43902 -277.376818) (xy 340.434925 -277.32609) (xy 340.116414 -277.32609) (xy 340.115919 -277.350697)
			(xy 340.108024 -277.399274) (xy 340.09244 -277.445955) (xy 340.069569 -277.489532) (xy 340.040004 -277.528876)
			(xy 340.004511 -277.562968) (xy 339.964008 -277.590924) (xy 339.919546 -277.612022) (xy 339.872275 -277.625714)
			(xy 339.82342 -277.631646) (xy 339.774245 -277.629665) (xy 339.726026 -277.619821) (xy 339.68001 -277.602369)
			(xy 339.637389 -277.577762) (xy 339.599268 -277.546637) (xy 339.566633 -277.5098) (xy 339.54033 -277.468204)
			(xy 339.521039 -277.422928) (xy 339.509262 -277.375144) (xy 339.505302 -277.32609) (xy 339.186774 -277.32609)
			(xy 339.186262 -277.351536) (xy 339.178098 -277.40177) (xy 339.161982 -277.450044) (xy 339.138331 -277.495107)
			(xy 339.107758 -277.535793) (xy 339.071054 -277.571048) (xy 339.02917 -277.599958) (xy 338.983191 -277.621775)
			(xy 338.934307 -277.635935) (xy 338.883786 -277.642069) (xy 338.832934 -277.64002) (xy 338.78307 -277.62984)
			(xy 338.735484 -277.611793) (xy 338.69141 -277.586347) (xy 338.651988 -277.55416) (xy 338.61824 -277.516066)
			(xy 338.591039 -277.473052) (xy 338.571091 -277.426232) (xy 338.558912 -277.376818) (xy 338.554817 -277.32609)
			(xy 338.236306 -277.32609) (xy 338.235811 -277.350697) (xy 338.227916 -277.399274) (xy 338.212332 -277.445955)
			(xy 338.189461 -277.489532) (xy 338.159896 -277.528876) (xy 338.124403 -277.562968) (xy 338.0839 -277.590924)
			(xy 338.039438 -277.612022) (xy 337.992167 -277.625714) (xy 337.943312 -277.631646) (xy 337.894137 -277.629665)
			(xy 337.845918 -277.619821) (xy 337.799902 -277.602369) (xy 337.757281 -277.577762) (xy 337.71916 -277.546637)
			(xy 337.686525 -277.5098) (xy 337.660222 -277.468204) (xy 337.640931 -277.422928) (xy 337.629154 -277.375144)
			(xy 337.625194 -277.32609) (xy 337.30692 -277.32609) (xy 337.306408 -277.351536) (xy 337.298244 -277.40177)
			(xy 337.282128 -277.450044) (xy 337.258477 -277.495107) (xy 337.227904 -277.535793) (xy 337.1912 -277.571048)
			(xy 337.149316 -277.599958) (xy 337.103337 -277.621775) (xy 337.054453 -277.635935) (xy 337.003932 -277.642069)
			(xy 336.95308 -277.64002) (xy 336.903216 -277.62984) (xy 336.85563 -277.611793) (xy 336.811556 -277.586347)
			(xy 336.772134 -277.55416) (xy 336.738386 -277.516066) (xy 336.711185 -277.473052) (xy 336.691237 -277.426232)
			(xy 336.679058 -277.376818) (xy 336.674963 -277.32609) (xy 336.366866 -277.32609) (xy 336.366354 -277.351536)
			(xy 336.35819 -277.40177) (xy 336.342074 -277.450044) (xy 336.318423 -277.495107) (xy 336.28785 -277.535793)
			(xy 336.251146 -277.571048) (xy 336.209262 -277.599958) (xy 336.163283 -277.621775) (xy 336.114399 -277.635935)
			(xy 336.063878 -277.642069) (xy 336.013026 -277.64002) (xy 335.963162 -277.62984) (xy 335.915576 -277.611793)
			(xy 335.871502 -277.586347) (xy 335.83208 -277.55416) (xy 335.798332 -277.516066) (xy 335.771131 -277.473052)
			(xy 335.751183 -277.426232) (xy 335.739004 -277.376818) (xy 335.734909 -277.32609) (xy 335.416398 -277.32609)
			(xy 335.415903 -277.350697) (xy 335.408008 -277.399274) (xy 335.392424 -277.445955) (xy 335.369553 -277.489532)
			(xy 335.339988 -277.528876) (xy 335.304495 -277.562968) (xy 335.263992 -277.590924) (xy 335.21953 -277.612022)
			(xy 335.172259 -277.625714) (xy 335.123404 -277.631646) (xy 335.074229 -277.629665) (xy 335.02601 -277.619821)
			(xy 334.979994 -277.602369) (xy 334.937373 -277.577762) (xy 334.899252 -277.546637) (xy 334.866617 -277.5098)
			(xy 334.840314 -277.468204) (xy 334.821023 -277.422928) (xy 334.809246 -277.375144) (xy 334.805286 -277.32609)
			(xy 334.486758 -277.32609) (xy 334.486246 -277.351536) (xy 334.478082 -277.40177) (xy 334.461966 -277.450044)
			(xy 334.438315 -277.495107) (xy 334.407742 -277.535793) (xy 334.371038 -277.571048) (xy 334.329154 -277.599958)
			(xy 334.283175 -277.621775) (xy 334.234291 -277.635935) (xy 334.18377 -277.642069) (xy 334.132918 -277.64002)
			(xy 334.083054 -277.62984) (xy 334.035468 -277.611793) (xy 333.991394 -277.586347) (xy 333.951972 -277.55416)
			(xy 333.918224 -277.516066) (xy 333.891023 -277.473052) (xy 333.871075 -277.426232) (xy 333.858896 -277.376818)
			(xy 333.854801 -277.32609) (xy 333.53629 -277.32609) (xy 333.535795 -277.350697) (xy 333.5279 -277.399274)
			(xy 333.512316 -277.445955) (xy 333.489445 -277.489532) (xy 333.45988 -277.528876) (xy 333.424387 -277.562968)
			(xy 333.383884 -277.590924) (xy 333.339422 -277.612022) (xy 333.292151 -277.625714) (xy 333.243296 -277.631646)
			(xy 333.194121 -277.629665) (xy 333.145902 -277.619821) (xy 333.099886 -277.602369) (xy 333.057265 -277.577762)
			(xy 333.019144 -277.546637) (xy 332.986509 -277.5098) (xy 332.960206 -277.468204) (xy 332.940915 -277.422928)
			(xy 332.929138 -277.375144) (xy 332.925178 -277.32609) (xy 332.606904 -277.32609) (xy 332.606392 -277.351536)
			(xy 332.598228 -277.40177) (xy 332.582112 -277.450044) (xy 332.558461 -277.495107) (xy 332.527888 -277.535793)
			(xy 332.491184 -277.571048) (xy 332.4493 -277.599958) (xy 332.403321 -277.621775) (xy 332.354437 -277.635935)
			(xy 332.303916 -277.642069) (xy 332.253064 -277.64002) (xy 332.2032 -277.62984) (xy 332.155614 -277.611793)
			(xy 332.11154 -277.586347) (xy 332.072118 -277.55416) (xy 332.03837 -277.516066) (xy 332.011169 -277.473052)
			(xy 331.991221 -277.426232) (xy 331.979042 -277.376818) (xy 331.974947 -277.32609) (xy 331.656436 -277.32609)
			(xy 331.655941 -277.350697) (xy 331.648046 -277.399274) (xy 331.632462 -277.445955) (xy 331.609591 -277.489532)
			(xy 331.580026 -277.528876) (xy 331.544533 -277.562968) (xy 331.50403 -277.590924) (xy 331.459568 -277.612022)
			(xy 331.412297 -277.625714) (xy 331.363442 -277.631646) (xy 331.314267 -277.629665) (xy 331.266048 -277.619821)
			(xy 331.220032 -277.602369) (xy 331.177411 -277.577762) (xy 331.13929 -277.546637) (xy 331.106655 -277.5098)
			(xy 331.080352 -277.468204) (xy 331.061061 -277.422928) (xy 331.049284 -277.375144) (xy 331.045324 -277.32609)
			(xy 330.726796 -277.32609) (xy 330.726284 -277.351536) (xy 330.71812 -277.40177) (xy 330.702004 -277.450044)
			(xy 330.678353 -277.495107) (xy 330.64778 -277.535793) (xy 330.611076 -277.571048) (xy 330.569192 -277.599958)
			(xy 330.523213 -277.621775) (xy 330.474329 -277.635935) (xy 330.423808 -277.642069) (xy 330.372956 -277.64002)
			(xy 330.323092 -277.62984) (xy 330.275506 -277.611793) (xy 330.231432 -277.586347) (xy 330.19201 -277.55416)
			(xy 330.158262 -277.516066) (xy 330.131061 -277.473052) (xy 330.111113 -277.426232) (xy 330.098934 -277.376818)
			(xy 330.094839 -277.32609) (xy 329.786742 -277.32609) (xy 329.78623 -277.351536) (xy 329.778066 -277.40177)
			(xy 329.76195 -277.450044) (xy 329.738299 -277.495107) (xy 329.707726 -277.535793) (xy 329.671022 -277.571048)
			(xy 329.629138 -277.599958) (xy 329.583159 -277.621775) (xy 329.534275 -277.635935) (xy 329.483754 -277.642069)
			(xy 329.432902 -277.64002) (xy 329.383038 -277.62984) (xy 329.335452 -277.611793) (xy 329.291378 -277.586347)
			(xy 329.251956 -277.55416) (xy 329.218208 -277.516066) (xy 329.191007 -277.473052) (xy 329.171059 -277.426232)
			(xy 329.15888 -277.376818) (xy 329.154785 -277.32609) (xy 328.836528 -277.32609) (xy 328.836033 -277.350697)
			(xy 328.828138 -277.399274) (xy 328.812554 -277.445955) (xy 328.789683 -277.489532) (xy 328.760118 -277.528876)
			(xy 328.724625 -277.562968) (xy 328.684122 -277.590924) (xy 328.63966 -277.612022) (xy 328.592389 -277.625714)
			(xy 328.543534 -277.631646) (xy 328.494359 -277.629665) (xy 328.44614 -277.619821) (xy 328.400124 -277.602369)
			(xy 328.357503 -277.577762) (xy 328.319382 -277.546637) (xy 328.286747 -277.5098) (xy 328.260444 -277.468204)
			(xy 328.241153 -277.422928) (xy 328.229376 -277.375144) (xy 328.225416 -277.32609) (xy 326.95642 -277.32609)
			(xy 326.955925 -277.350697) (xy 326.94803 -277.399274) (xy 326.932446 -277.445955) (xy 326.909575 -277.489532)
			(xy 326.88001 -277.528876) (xy 326.844517 -277.562968) (xy 326.804014 -277.590924) (xy 326.759552 -277.612022)
			(xy 326.712281 -277.625714) (xy 326.663426 -277.631646) (xy 326.614251 -277.629665) (xy 326.566032 -277.619821)
			(xy 326.520016 -277.602369) (xy 326.477395 -277.577762) (xy 326.439274 -277.546637) (xy 326.406639 -277.5098)
			(xy 326.380336 -277.468204) (xy 326.361045 -277.422928) (xy 326.349268 -277.375144) (xy 326.345308 -277.32609)
			(xy 310.45912 -277.32609) (xy 310.45912 -277.870158) (xy 324.74714 -277.870158) (xy 324.7511 -277.821104)
			(xy 324.762877 -277.77332) (xy 324.782168 -277.728044) (xy 324.808471 -277.686448) (xy 324.841106 -277.649611)
			(xy 324.879227 -277.618486) (xy 324.921848 -277.593879) (xy 324.967864 -277.576427) (xy 325.016083 -277.566583)
			(xy 325.065258 -277.564602) (xy 325.114113 -277.570534) (xy 325.161384 -277.584226) (xy 325.205846 -277.605324)
			(xy 325.246349 -277.63328) (xy 325.281842 -277.667372) (xy 325.311407 -277.706716) (xy 325.334278 -277.750293)
			(xy 325.349862 -277.796974) (xy 325.357757 -277.845551) (xy 325.358252 -277.870158) (xy 325.357757 -277.894765)
			(xy 325.349862 -277.943342) (xy 325.334278 -277.990023) (xy 325.311407 -278.0336) (xy 325.281842 -278.072944)
			(xy 325.246349 -278.107036) (xy 325.205846 -278.134992) (xy 325.203519 -278.136096) (xy 328.684885 -278.136096)
			(xy 328.68898 -278.085368) (xy 328.701159 -278.035954) (xy 328.721107 -277.989134) (xy 328.748308 -277.94612)
			(xy 328.782056 -277.908026) (xy 328.821478 -277.875839) (xy 328.865552 -277.850393) (xy 328.913138 -277.832346)
			(xy 328.963002 -277.822166) (xy 329.013854 -277.820117) (xy 329.064375 -277.826251) (xy 329.113259 -277.840411)
			(xy 329.159238 -277.862228) (xy 329.201122 -277.891138) (xy 329.237826 -277.926393) (xy 329.268399 -277.967079)
			(xy 329.29205 -278.012142) (xy 329.308166 -278.060416) (xy 329.31633 -278.11065) (xy 329.316842 -278.136096)
			(xy 329.63537 -278.136096) (xy 329.63933 -278.087042) (xy 329.651107 -278.039258) (xy 329.670398 -277.993982)
			(xy 329.696701 -277.952386) (xy 329.729336 -277.915549) (xy 329.767457 -277.884424) (xy 329.810078 -277.859817)
			(xy 329.856094 -277.842365) (xy 329.904313 -277.832521) (xy 329.953488 -277.83054) (xy 330.002343 -277.836472)
			(xy 330.049614 -277.850164) (xy 330.094076 -277.871262) (xy 330.134579 -277.899218) (xy 330.170072 -277.93331)
			(xy 330.199637 -277.972654) (xy 330.222508 -278.016231) (xy 330.238092 -278.062912) (xy 330.245987 -278.111489)
			(xy 330.246482 -278.136096) (xy 330.564739 -278.136096) (xy 330.568834 -278.085368) (xy 330.581013 -278.035954)
			(xy 330.600961 -277.989134) (xy 330.628162 -277.94612) (xy 330.66191 -277.908026) (xy 330.701332 -277.875839)
			(xy 330.745406 -277.850393) (xy 330.792992 -277.832346) (xy 330.842856 -277.822166) (xy 330.893708 -277.820117)
			(xy 330.944229 -277.826251) (xy 330.993113 -277.840411) (xy 331.039092 -277.862228) (xy 331.080976 -277.891138)
			(xy 331.11768 -277.926393) (xy 331.148253 -277.967079) (xy 331.171904 -278.012142) (xy 331.18802 -278.060416)
			(xy 331.196184 -278.11065) (xy 331.196696 -278.136096) (xy 331.515224 -278.136096) (xy 331.519184 -278.087042)
			(xy 331.530961 -278.039258) (xy 331.550252 -277.993982) (xy 331.576555 -277.952386) (xy 331.60919 -277.915549)
			(xy 331.647311 -277.884424) (xy 331.689932 -277.859817) (xy 331.735948 -277.842365) (xy 331.784167 -277.832521)
			(xy 331.833342 -277.83054) (xy 331.882197 -277.836472) (xy 331.929468 -277.850164) (xy 331.97393 -277.871262)
			(xy 332.014433 -277.899218) (xy 332.049926 -277.93331) (xy 332.079491 -277.972654) (xy 332.102362 -278.016231)
			(xy 332.117946 -278.062912) (xy 332.125841 -278.111489) (xy 332.126336 -278.136096) (xy 332.444847 -278.136096)
			(xy 332.448942 -278.085368) (xy 332.461121 -278.035954) (xy 332.481069 -277.989134) (xy 332.50827 -277.94612)
			(xy 332.542018 -277.908026) (xy 332.58144 -277.875839) (xy 332.625514 -277.850393) (xy 332.6731 -277.832346)
			(xy 332.722964 -277.822166) (xy 332.773816 -277.820117) (xy 332.824337 -277.826251) (xy 332.873221 -277.840411)
			(xy 332.9192 -277.862228) (xy 332.961084 -277.891138) (xy 332.997788 -277.926393) (xy 333.028361 -277.967079)
			(xy 333.052012 -278.012142) (xy 333.068128 -278.060416) (xy 333.076292 -278.11065) (xy 333.076804 -278.136096)
			(xy 333.384901 -278.136096) (xy 333.388996 -278.085368) (xy 333.401175 -278.035954) (xy 333.421123 -277.989134)
			(xy 333.448324 -277.94612) (xy 333.482072 -277.908026) (xy 333.521494 -277.875839) (xy 333.565568 -277.850393)
			(xy 333.613154 -277.832346) (xy 333.663018 -277.822166) (xy 333.71387 -277.820117) (xy 333.764391 -277.826251)
			(xy 333.813275 -277.840411) (xy 333.859254 -277.862228) (xy 333.901138 -277.891138) (xy 333.937842 -277.926393)
			(xy 333.968415 -277.967079) (xy 333.992066 -278.012142) (xy 334.008182 -278.060416) (xy 334.016346 -278.11065)
			(xy 334.016858 -278.136096) (xy 335.264755 -278.136096) (xy 335.26885 -278.085368) (xy 335.281029 -278.035954)
			(xy 335.300977 -277.989134) (xy 335.328178 -277.94612) (xy 335.361926 -277.908026) (xy 335.401348 -277.875839)
			(xy 335.445422 -277.850393) (xy 335.493008 -277.832346) (xy 335.542872 -277.822166) (xy 335.593724 -277.820117)
			(xy 335.644245 -277.826251) (xy 335.693129 -277.840411) (xy 335.739108 -277.862228) (xy 335.780992 -277.891138)
			(xy 335.817696 -277.926393) (xy 335.848269 -277.967079) (xy 335.87192 -278.012142) (xy 335.888036 -278.060416)
			(xy 335.8962 -278.11065) (xy 335.896712 -278.136096) (xy 336.21524 -278.136096) (xy 336.2192 -278.087042)
			(xy 336.230977 -278.039258) (xy 336.250268 -277.993982) (xy 336.276571 -277.952386) (xy 336.309206 -277.915549)
			(xy 336.347327 -277.884424) (xy 336.389948 -277.859817) (xy 336.435964 -277.842365) (xy 336.484183 -277.832521)
			(xy 336.533358 -277.83054) (xy 336.582213 -277.836472) (xy 336.629484 -277.850164) (xy 336.673946 -277.871262)
			(xy 336.714449 -277.899218) (xy 336.749942 -277.93331) (xy 336.779507 -277.972654) (xy 336.802378 -278.016231)
			(xy 336.817962 -278.062912) (xy 336.825857 -278.111489) (xy 336.826352 -278.136096) (xy 337.144863 -278.136096)
			(xy 337.148958 -278.085368) (xy 337.161137 -278.035954) (xy 337.181085 -277.989134) (xy 337.208286 -277.94612)
			(xy 337.242034 -277.908026) (xy 337.281456 -277.875839) (xy 337.32553 -277.850393) (xy 337.373116 -277.832346)
			(xy 337.42298 -277.822166) (xy 337.473832 -277.820117) (xy 337.524353 -277.826251) (xy 337.573237 -277.840411)
			(xy 337.619216 -277.862228) (xy 337.6611 -277.891138) (xy 337.697804 -277.926393) (xy 337.728377 -277.967079)
			(xy 337.752028 -278.012142) (xy 337.768144 -278.060416) (xy 337.776308 -278.11065) (xy 337.77682 -278.136096)
			(xy 338.095348 -278.136096) (xy 338.099308 -278.087042) (xy 338.111085 -278.039258) (xy 338.130376 -277.993982)
			(xy 338.156679 -277.952386) (xy 338.189314 -277.915549) (xy 338.227435 -277.884424) (xy 338.270056 -277.859817)
			(xy 338.316072 -277.842365) (xy 338.364291 -277.832521) (xy 338.413466 -277.83054) (xy 338.462321 -277.836472)
			(xy 338.509592 -277.850164) (xy 338.554054 -277.871262) (xy 338.594557 -277.899218) (xy 338.63005 -277.93331)
			(xy 338.659615 -277.972654) (xy 338.682486 -278.016231) (xy 338.69807 -278.062912) (xy 338.705965 -278.111489)
			(xy 338.70646 -278.136096) (xy 339.024971 -278.136096) (xy 339.029066 -278.085368) (xy 339.041245 -278.035954)
			(xy 339.061193 -277.989134) (xy 339.088394 -277.94612) (xy 339.122142 -277.908026) (xy 339.161564 -277.875839)
			(xy 339.205638 -277.850393) (xy 339.253224 -277.832346) (xy 339.303088 -277.822166) (xy 339.35394 -277.820117)
			(xy 339.404461 -277.826251) (xy 339.453345 -277.840411) (xy 339.499324 -277.862228) (xy 339.541208 -277.891138)
			(xy 339.577912 -277.926393) (xy 339.608485 -277.967079) (xy 339.632136 -278.012142) (xy 339.648252 -278.060416)
			(xy 339.656416 -278.11065) (xy 339.656928 -278.136096) (xy 339.964771 -278.136096) (xy 339.968866 -278.085368)
			(xy 339.981045 -278.035954) (xy 340.000993 -277.989134) (xy 340.028194 -277.94612) (xy 340.061942 -277.908026)
			(xy 340.101364 -277.875839) (xy 340.145438 -277.850393) (xy 340.193024 -277.832346) (xy 340.242888 -277.822166)
			(xy 340.29374 -277.820117) (xy 340.344261 -277.826251) (xy 340.393145 -277.840411) (xy 340.439124 -277.862228)
			(xy 340.481008 -277.891138) (xy 340.517712 -277.926393) (xy 340.548285 -277.967079) (xy 340.571936 -278.012142)
			(xy 340.588052 -278.060416) (xy 340.596216 -278.11065) (xy 340.596728 -278.136096) (xy 341.844879 -278.136096)
			(xy 341.848974 -278.085368) (xy 341.861153 -278.035954) (xy 341.881101 -277.989134) (xy 341.908302 -277.94612)
			(xy 341.94205 -277.908026) (xy 341.981472 -277.875839) (xy 342.025546 -277.850393) (xy 342.073132 -277.832346)
			(xy 342.122996 -277.822166) (xy 342.173848 -277.820117) (xy 342.224369 -277.826251) (xy 342.273253 -277.840411)
			(xy 342.319232 -277.862228) (xy 342.361116 -277.891138) (xy 342.39782 -277.926393) (xy 342.428393 -277.967079)
			(xy 342.452044 -278.012142) (xy 342.46816 -278.060416) (xy 342.476324 -278.11065) (xy 342.476836 -278.136096)
			(xy 342.795364 -278.136096) (xy 342.799324 -278.087042) (xy 342.811101 -278.039258) (xy 342.830392 -277.993982)
			(xy 342.856695 -277.952386) (xy 342.88933 -277.915549) (xy 342.927451 -277.884424) (xy 342.970072 -277.859817)
			(xy 343.016088 -277.842365) (xy 343.064307 -277.832521) (xy 343.113482 -277.83054) (xy 343.162337 -277.836472)
			(xy 343.209608 -277.850164) (xy 343.25407 -277.871262) (xy 343.294573 -277.899218) (xy 343.330066 -277.93331)
			(xy 343.359631 -277.972654) (xy 343.382502 -278.016231) (xy 343.398086 -278.062912) (xy 343.405981 -278.111489)
			(xy 343.406476 -278.136096) (xy 343.724987 -278.136096) (xy 343.729082 -278.085368) (xy 343.741261 -278.035954)
			(xy 343.761209 -277.989134) (xy 343.78841 -277.94612) (xy 343.822158 -277.908026) (xy 343.86158 -277.875839)
			(xy 343.905654 -277.850393) (xy 343.95324 -277.832346) (xy 344.003104 -277.822166) (xy 344.053956 -277.820117)
			(xy 344.104477 -277.826251) (xy 344.153361 -277.840411) (xy 344.19934 -277.862228) (xy 344.241224 -277.891138)
			(xy 344.277928 -277.926393) (xy 344.308501 -277.967079) (xy 344.332152 -278.012142) (xy 344.348268 -278.060416)
			(xy 344.356432 -278.11065) (xy 344.356944 -278.136096) (xy 344.675218 -278.136096) (xy 344.679178 -278.087042)
			(xy 344.690955 -278.039258) (xy 344.710246 -277.993982) (xy 344.736549 -277.952386) (xy 344.769184 -277.915549)
			(xy 344.807305 -277.884424) (xy 344.849926 -277.859817) (xy 344.895942 -277.842365) (xy 344.944161 -277.832521)
			(xy 344.993336 -277.83054) (xy 345.042191 -277.836472) (xy 345.089462 -277.850164) (xy 345.133924 -277.871262)
			(xy 345.174427 -277.899218) (xy 345.20992 -277.93331) (xy 345.239485 -277.972654) (xy 345.262356 -278.016231)
			(xy 345.27794 -278.062912) (xy 345.285835 -278.111489) (xy 345.28633 -278.136096) (xy 345.604841 -278.136096)
			(xy 345.608936 -278.085368) (xy 345.621115 -278.035954) (xy 345.641063 -277.989134) (xy 345.668264 -277.94612)
			(xy 345.702012 -277.908026) (xy 345.741434 -277.875839) (xy 345.785508 -277.850393) (xy 345.833094 -277.832346)
			(xy 345.882958 -277.822166) (xy 345.93381 -277.820117) (xy 345.984331 -277.826251) (xy 346.033215 -277.840411)
			(xy 346.079194 -277.862228) (xy 346.121078 -277.891138) (xy 346.157782 -277.926393) (xy 346.188355 -277.967079)
			(xy 346.212006 -278.012142) (xy 346.228122 -278.060416) (xy 346.236286 -278.11065) (xy 346.236798 -278.136096)
			(xy 346.544895 -278.136096) (xy 346.54899 -278.085368) (xy 346.561169 -278.035954) (xy 346.581117 -277.989134)
			(xy 346.608318 -277.94612) (xy 346.642066 -277.908026) (xy 346.681488 -277.875839) (xy 346.725562 -277.850393)
			(xy 346.773148 -277.832346) (xy 346.823012 -277.822166) (xy 346.873864 -277.820117) (xy 346.924385 -277.826251)
			(xy 346.973269 -277.840411) (xy 347.019248 -277.862228) (xy 347.061132 -277.891138) (xy 347.097836 -277.926393)
			(xy 347.128409 -277.967079) (xy 347.15206 -278.012142) (xy 347.168176 -278.060416) (xy 347.17634 -278.11065)
			(xy 347.176852 -278.136096) (xy 347.49538 -278.136096) (xy 347.49934 -278.087042) (xy 347.511117 -278.039258)
			(xy 347.530408 -277.993982) (xy 347.556711 -277.952386) (xy 347.589346 -277.915549) (xy 347.627467 -277.884424)
			(xy 347.670088 -277.859817) (xy 347.716104 -277.842365) (xy 347.764323 -277.832521) (xy 347.813498 -277.83054)
			(xy 347.862353 -277.836472) (xy 347.909624 -277.850164) (xy 347.954086 -277.871262) (xy 347.994589 -277.899218)
			(xy 348.030082 -277.93331) (xy 348.059647 -277.972654) (xy 348.082518 -278.016231) (xy 348.098102 -278.062912)
			(xy 348.105997 -278.111489) (xy 348.106492 -278.136096) (xy 348.425003 -278.136096) (xy 348.429098 -278.085368)
			(xy 348.441277 -278.035954) (xy 348.461225 -277.989134) (xy 348.488426 -277.94612) (xy 348.522174 -277.908026)
			(xy 348.561596 -277.875839) (xy 348.60567 -277.850393) (xy 348.653256 -277.832346) (xy 348.70312 -277.822166)
			(xy 348.753972 -277.820117) (xy 348.804493 -277.826251) (xy 348.853377 -277.840411) (xy 348.899356 -277.862228)
			(xy 348.94124 -277.891138) (xy 348.977944 -277.926393) (xy 349.008517 -277.967079) (xy 349.032168 -278.012142)
			(xy 349.048284 -278.060416) (xy 349.056448 -278.11065) (xy 349.05696 -278.136096) (xy 349.364803 -278.136096)
			(xy 349.368898 -278.085368) (xy 349.381077 -278.035954) (xy 349.401025 -277.989134) (xy 349.428226 -277.94612)
			(xy 349.461974 -277.908026) (xy 349.501396 -277.875839) (xy 349.54547 -277.850393) (xy 349.593056 -277.832346)
			(xy 349.64292 -277.822166) (xy 349.693772 -277.820117) (xy 349.744293 -277.826251) (xy 349.793177 -277.840411)
			(xy 349.839156 -277.862228) (xy 349.88104 -277.891138) (xy 349.917744 -277.926393) (xy 349.948317 -277.967079)
			(xy 349.971968 -278.012142) (xy 349.988084 -278.060416) (xy 349.996248 -278.11065) (xy 349.99676 -278.136096)
			(xy 350.315288 -278.136096) (xy 350.319248 -278.087042) (xy 350.331025 -278.039258) (xy 350.350316 -277.993982)
			(xy 350.376619 -277.952386) (xy 350.409254 -277.915549) (xy 350.447375 -277.884424) (xy 350.489996 -277.859817)
			(xy 350.536012 -277.842365) (xy 350.584231 -277.832521) (xy 350.633406 -277.83054) (xy 350.682261 -277.836472)
			(xy 350.729532 -277.850164) (xy 350.773994 -277.871262) (xy 350.814497 -277.899218) (xy 350.84999 -277.93331)
			(xy 350.879555 -277.972654) (xy 350.902426 -278.016231) (xy 350.91801 -278.062912) (xy 350.925905 -278.111489)
			(xy 350.9264 -278.136096) (xy 350.925905 -278.160703) (xy 350.91801 -278.20928) (xy 350.902426 -278.255961)
			(xy 350.879555 -278.299538) (xy 350.84999 -278.338882) (xy 350.814497 -278.372974) (xy 350.773994 -278.40093)
			(xy 350.729532 -278.422028) (xy 350.682261 -278.43572) (xy 350.633406 -278.441652) (xy 350.584231 -278.439671)
			(xy 350.536012 -278.429827) (xy 350.489996 -278.412375) (xy 350.447375 -278.387768) (xy 350.409254 -278.356643)
			(xy 350.376619 -278.319806) (xy 350.350316 -278.27821) (xy 350.331025 -278.232934) (xy 350.319248 -278.18515)
			(xy 350.315288 -278.136096) (xy 349.99676 -278.136096) (xy 349.996248 -278.161542) (xy 349.988084 -278.211776)
			(xy 349.971968 -278.26005) (xy 349.948317 -278.305113) (xy 349.917744 -278.345799) (xy 349.88104 -278.381054)
			(xy 349.839156 -278.409964) (xy 349.793177 -278.431781) (xy 349.744293 -278.445941) (xy 349.693772 -278.452075)
			(xy 349.64292 -278.450026) (xy 349.593056 -278.439846) (xy 349.54547 -278.421799) (xy 349.501396 -278.396353)
			(xy 349.461974 -278.364166) (xy 349.428226 -278.326072) (xy 349.401025 -278.283058) (xy 349.381077 -278.236238)
			(xy 349.368898 -278.186824) (xy 349.364803 -278.136096) (xy 349.05696 -278.136096) (xy 349.056448 -278.161542)
			(xy 349.048284 -278.211776) (xy 349.032168 -278.26005) (xy 349.008517 -278.305113) (xy 348.977944 -278.345799)
			(xy 348.94124 -278.381054) (xy 348.899356 -278.409964) (xy 348.853377 -278.431781) (xy 348.804493 -278.445941)
			(xy 348.753972 -278.452075) (xy 348.70312 -278.450026) (xy 348.653256 -278.439846) (xy 348.60567 -278.421799)
			(xy 348.561596 -278.396353) (xy 348.522174 -278.364166) (xy 348.488426 -278.326072) (xy 348.461225 -278.283058)
			(xy 348.441277 -278.236238) (xy 348.429098 -278.186824) (xy 348.425003 -278.136096) (xy 348.106492 -278.136096)
			(xy 348.105997 -278.160703) (xy 348.098102 -278.20928) (xy 348.082518 -278.255961) (xy 348.059647 -278.299538)
			(xy 348.030082 -278.338882) (xy 347.994589 -278.372974) (xy 347.954086 -278.40093) (xy 347.909624 -278.422028)
			(xy 347.862353 -278.43572) (xy 347.813498 -278.441652) (xy 347.764323 -278.439671) (xy 347.716104 -278.429827)
			(xy 347.670088 -278.412375) (xy 347.627467 -278.387768) (xy 347.589346 -278.356643) (xy 347.556711 -278.319806)
			(xy 347.530408 -278.27821) (xy 347.511117 -278.232934) (xy 347.49934 -278.18515) (xy 347.49538 -278.136096)
			(xy 347.176852 -278.136096) (xy 347.17634 -278.161542) (xy 347.168176 -278.211776) (xy 347.15206 -278.26005)
			(xy 347.128409 -278.305113) (xy 347.097836 -278.345799) (xy 347.061132 -278.381054) (xy 347.019248 -278.409964)
			(xy 346.973269 -278.431781) (xy 346.924385 -278.445941) (xy 346.873864 -278.452075) (xy 346.823012 -278.450026)
			(xy 346.773148 -278.439846) (xy 346.725562 -278.421799) (xy 346.681488 -278.396353) (xy 346.642066 -278.364166)
			(xy 346.608318 -278.326072) (xy 346.581117 -278.283058) (xy 346.561169 -278.236238) (xy 346.54899 -278.186824)
			(xy 346.544895 -278.136096) (xy 346.236798 -278.136096) (xy 346.236286 -278.161542) (xy 346.228122 -278.211776)
			(xy 346.212006 -278.26005) (xy 346.188355 -278.305113) (xy 346.157782 -278.345799) (xy 346.121078 -278.381054)
			(xy 346.079194 -278.409964) (xy 346.033215 -278.431781) (xy 345.984331 -278.445941) (xy 345.93381 -278.452075)
			(xy 345.882958 -278.450026) (xy 345.833094 -278.439846) (xy 345.785508 -278.421799) (xy 345.741434 -278.396353)
			(xy 345.702012 -278.364166) (xy 345.668264 -278.326072) (xy 345.641063 -278.283058) (xy 345.621115 -278.236238)
			(xy 345.608936 -278.186824) (xy 345.604841 -278.136096) (xy 345.28633 -278.136096) (xy 345.285835 -278.160703)
			(xy 345.27794 -278.20928) (xy 345.262356 -278.255961) (xy 345.239485 -278.299538) (xy 345.20992 -278.338882)
			(xy 345.174427 -278.372974) (xy 345.133924 -278.40093) (xy 345.089462 -278.422028) (xy 345.042191 -278.43572)
			(xy 344.993336 -278.441652) (xy 344.944161 -278.439671) (xy 344.895942 -278.429827) (xy 344.849926 -278.412375)
			(xy 344.807305 -278.387768) (xy 344.769184 -278.356643) (xy 344.736549 -278.319806) (xy 344.710246 -278.27821)
			(xy 344.690955 -278.232934) (xy 344.679178 -278.18515) (xy 344.675218 -278.136096) (xy 344.356944 -278.136096)
			(xy 344.356432 -278.161542) (xy 344.348268 -278.211776) (xy 344.332152 -278.26005) (xy 344.308501 -278.305113)
			(xy 344.277928 -278.345799) (xy 344.241224 -278.381054) (xy 344.19934 -278.409964) (xy 344.153361 -278.431781)
			(xy 344.104477 -278.445941) (xy 344.053956 -278.452075) (xy 344.003104 -278.450026) (xy 343.95324 -278.439846)
			(xy 343.905654 -278.421799) (xy 343.86158 -278.396353) (xy 343.822158 -278.364166) (xy 343.78841 -278.326072)
			(xy 343.761209 -278.283058) (xy 343.741261 -278.236238) (xy 343.729082 -278.186824) (xy 343.724987 -278.136096)
			(xy 343.406476 -278.136096) (xy 343.405981 -278.160703) (xy 343.398086 -278.20928) (xy 343.382502 -278.255961)
			(xy 343.359631 -278.299538) (xy 343.330066 -278.338882) (xy 343.294573 -278.372974) (xy 343.25407 -278.40093)
			(xy 343.209608 -278.422028) (xy 343.162337 -278.43572) (xy 343.113482 -278.441652) (xy 343.064307 -278.439671)
			(xy 343.016088 -278.429827) (xy 342.970072 -278.412375) (xy 342.927451 -278.387768) (xy 342.88933 -278.356643)
			(xy 342.856695 -278.319806) (xy 342.830392 -278.27821) (xy 342.811101 -278.232934) (xy 342.799324 -278.18515)
			(xy 342.795364 -278.136096) (xy 342.476836 -278.136096) (xy 342.476324 -278.161542) (xy 342.46816 -278.211776)
			(xy 342.452044 -278.26005) (xy 342.428393 -278.305113) (xy 342.39782 -278.345799) (xy 342.361116 -278.381054)
			(xy 342.319232 -278.409964) (xy 342.273253 -278.431781) (xy 342.224369 -278.445941) (xy 342.173848 -278.452075)
			(xy 342.122996 -278.450026) (xy 342.073132 -278.439846) (xy 342.025546 -278.421799) (xy 341.981472 -278.396353)
			(xy 341.94205 -278.364166) (xy 341.908302 -278.326072) (xy 341.881101 -278.283058) (xy 341.861153 -278.236238)
			(xy 341.848974 -278.186824) (xy 341.844879 -278.136096) (xy 340.596728 -278.136096) (xy 340.596216 -278.161542)
			(xy 340.588052 -278.211776) (xy 340.571936 -278.26005) (xy 340.548285 -278.305113) (xy 340.517712 -278.345799)
			(xy 340.481008 -278.381054) (xy 340.439124 -278.409964) (xy 340.393145 -278.431781) (xy 340.344261 -278.445941)
			(xy 340.29374 -278.452075) (xy 340.242888 -278.450026) (xy 340.193024 -278.439846) (xy 340.145438 -278.421799)
			(xy 340.101364 -278.396353) (xy 340.061942 -278.364166) (xy 340.028194 -278.326072) (xy 340.000993 -278.283058)
			(xy 339.981045 -278.236238) (xy 339.968866 -278.186824) (xy 339.964771 -278.136096) (xy 339.656928 -278.136096)
			(xy 339.656416 -278.161542) (xy 339.648252 -278.211776) (xy 339.632136 -278.26005) (xy 339.608485 -278.305113)
			(xy 339.577912 -278.345799) (xy 339.541208 -278.381054) (xy 339.499324 -278.409964) (xy 339.453345 -278.431781)
			(xy 339.404461 -278.445941) (xy 339.35394 -278.452075) (xy 339.303088 -278.450026) (xy 339.253224 -278.439846)
			(xy 339.205638 -278.421799) (xy 339.161564 -278.396353) (xy 339.122142 -278.364166) (xy 339.088394 -278.326072)
			(xy 339.061193 -278.283058) (xy 339.041245 -278.236238) (xy 339.029066 -278.186824) (xy 339.024971 -278.136096)
			(xy 338.70646 -278.136096) (xy 338.705965 -278.160703) (xy 338.69807 -278.20928) (xy 338.682486 -278.255961)
			(xy 338.659615 -278.299538) (xy 338.63005 -278.338882) (xy 338.594557 -278.372974) (xy 338.554054 -278.40093)
			(xy 338.509592 -278.422028) (xy 338.462321 -278.43572) (xy 338.413466 -278.441652) (xy 338.364291 -278.439671)
			(xy 338.316072 -278.429827) (xy 338.270056 -278.412375) (xy 338.227435 -278.387768) (xy 338.189314 -278.356643)
			(xy 338.156679 -278.319806) (xy 338.130376 -278.27821) (xy 338.111085 -278.232934) (xy 338.099308 -278.18515)
			(xy 338.095348 -278.136096) (xy 337.77682 -278.136096) (xy 337.776308 -278.161542) (xy 337.768144 -278.211776)
			(xy 337.752028 -278.26005) (xy 337.728377 -278.305113) (xy 337.697804 -278.345799) (xy 337.6611 -278.381054)
			(xy 337.619216 -278.409964) (xy 337.573237 -278.431781) (xy 337.524353 -278.445941) (xy 337.473832 -278.452075)
			(xy 337.42298 -278.450026) (xy 337.373116 -278.439846) (xy 337.32553 -278.421799) (xy 337.281456 -278.396353)
			(xy 337.242034 -278.364166) (xy 337.208286 -278.326072) (xy 337.181085 -278.283058) (xy 337.161137 -278.236238)
			(xy 337.148958 -278.186824) (xy 337.144863 -278.136096) (xy 336.826352 -278.136096) (xy 336.825857 -278.160703)
			(xy 336.817962 -278.20928) (xy 336.802378 -278.255961) (xy 336.779507 -278.299538) (xy 336.749942 -278.338882)
			(xy 336.714449 -278.372974) (xy 336.673946 -278.40093) (xy 336.629484 -278.422028) (xy 336.582213 -278.43572)
			(xy 336.533358 -278.441652) (xy 336.484183 -278.439671) (xy 336.435964 -278.429827) (xy 336.389948 -278.412375)
			(xy 336.347327 -278.387768) (xy 336.309206 -278.356643) (xy 336.276571 -278.319806) (xy 336.250268 -278.27821)
			(xy 336.230977 -278.232934) (xy 336.2192 -278.18515) (xy 336.21524 -278.136096) (xy 335.896712 -278.136096)
			(xy 335.8962 -278.161542) (xy 335.888036 -278.211776) (xy 335.87192 -278.26005) (xy 335.848269 -278.305113)
			(xy 335.817696 -278.345799) (xy 335.780992 -278.381054) (xy 335.739108 -278.409964) (xy 335.693129 -278.431781)
			(xy 335.644245 -278.445941) (xy 335.593724 -278.452075) (xy 335.542872 -278.450026) (xy 335.493008 -278.439846)
			(xy 335.445422 -278.421799) (xy 335.401348 -278.396353) (xy 335.361926 -278.364166) (xy 335.328178 -278.326072)
			(xy 335.300977 -278.283058) (xy 335.281029 -278.236238) (xy 335.26885 -278.186824) (xy 335.264755 -278.136096)
			(xy 334.016858 -278.136096) (xy 334.016346 -278.161542) (xy 334.008182 -278.211776) (xy 333.992066 -278.26005)
			(xy 333.968415 -278.305113) (xy 333.937842 -278.345799) (xy 333.901138 -278.381054) (xy 333.859254 -278.409964)
			(xy 333.813275 -278.431781) (xy 333.764391 -278.445941) (xy 333.71387 -278.452075) (xy 333.663018 -278.450026)
			(xy 333.613154 -278.439846) (xy 333.565568 -278.421799) (xy 333.521494 -278.396353) (xy 333.482072 -278.364166)
			(xy 333.448324 -278.326072) (xy 333.421123 -278.283058) (xy 333.401175 -278.236238) (xy 333.388996 -278.186824)
			(xy 333.384901 -278.136096) (xy 333.076804 -278.136096) (xy 333.076292 -278.161542) (xy 333.068128 -278.211776)
			(xy 333.052012 -278.26005) (xy 333.028361 -278.305113) (xy 332.997788 -278.345799) (xy 332.961084 -278.381054)
			(xy 332.9192 -278.409964) (xy 332.873221 -278.431781) (xy 332.824337 -278.445941) (xy 332.773816 -278.452075)
			(xy 332.722964 -278.450026) (xy 332.6731 -278.439846) (xy 332.625514 -278.421799) (xy 332.58144 -278.396353)
			(xy 332.542018 -278.364166) (xy 332.50827 -278.326072) (xy 332.481069 -278.283058) (xy 332.461121 -278.236238)
			(xy 332.448942 -278.186824) (xy 332.444847 -278.136096) (xy 332.126336 -278.136096) (xy 332.125841 -278.160703)
			(xy 332.117946 -278.20928) (xy 332.102362 -278.255961) (xy 332.079491 -278.299538) (xy 332.049926 -278.338882)
			(xy 332.014433 -278.372974) (xy 331.97393 -278.40093) (xy 331.929468 -278.422028) (xy 331.882197 -278.43572)
			(xy 331.833342 -278.441652) (xy 331.784167 -278.439671) (xy 331.735948 -278.429827) (xy 331.689932 -278.412375)
			(xy 331.647311 -278.387768) (xy 331.60919 -278.356643) (xy 331.576555 -278.319806) (xy 331.550252 -278.27821)
			(xy 331.530961 -278.232934) (xy 331.519184 -278.18515) (xy 331.515224 -278.136096) (xy 331.196696 -278.136096)
			(xy 331.196184 -278.161542) (xy 331.18802 -278.211776) (xy 331.171904 -278.26005) (xy 331.148253 -278.305113)
			(xy 331.11768 -278.345799) (xy 331.080976 -278.381054) (xy 331.039092 -278.409964) (xy 330.993113 -278.431781)
			(xy 330.944229 -278.445941) (xy 330.893708 -278.452075) (xy 330.842856 -278.450026) (xy 330.792992 -278.439846)
			(xy 330.745406 -278.421799) (xy 330.701332 -278.396353) (xy 330.66191 -278.364166) (xy 330.628162 -278.326072)
			(xy 330.600961 -278.283058) (xy 330.581013 -278.236238) (xy 330.568834 -278.186824) (xy 330.564739 -278.136096)
			(xy 330.246482 -278.136096) (xy 330.245987 -278.160703) (xy 330.238092 -278.20928) (xy 330.222508 -278.255961)
			(xy 330.199637 -278.299538) (xy 330.170072 -278.338882) (xy 330.134579 -278.372974) (xy 330.094076 -278.40093)
			(xy 330.049614 -278.422028) (xy 330.002343 -278.43572) (xy 329.953488 -278.441652) (xy 329.904313 -278.439671)
			(xy 329.856094 -278.429827) (xy 329.810078 -278.412375) (xy 329.767457 -278.387768) (xy 329.729336 -278.356643)
			(xy 329.696701 -278.319806) (xy 329.670398 -278.27821) (xy 329.651107 -278.232934) (xy 329.63933 -278.18515)
			(xy 329.63537 -278.136096) (xy 329.316842 -278.136096) (xy 329.31633 -278.161542) (xy 329.308166 -278.211776)
			(xy 329.29205 -278.26005) (xy 329.268399 -278.305113) (xy 329.237826 -278.345799) (xy 329.201122 -278.381054)
			(xy 329.159238 -278.409964) (xy 329.113259 -278.431781) (xy 329.064375 -278.445941) (xy 329.013854 -278.452075)
			(xy 328.963002 -278.450026) (xy 328.913138 -278.439846) (xy 328.865552 -278.421799) (xy 328.821478 -278.396353)
			(xy 328.782056 -278.364166) (xy 328.748308 -278.326072) (xy 328.721107 -278.283058) (xy 328.701159 -278.236238)
			(xy 328.68898 -278.186824) (xy 328.684885 -278.136096) (xy 325.203519 -278.136096) (xy 325.161384 -278.15609)
			(xy 325.114113 -278.169782) (xy 325.065258 -278.175714) (xy 325.016083 -278.173733) (xy 324.967864 -278.163889)
			(xy 324.921848 -278.146437) (xy 324.879227 -278.12183) (xy 324.841106 -278.090705) (xy 324.808471 -278.053868)
			(xy 324.782168 -278.012272) (xy 324.762877 -277.966996) (xy 324.7511 -277.919212) (xy 324.74714 -277.870158)
			(xy 310.45912 -277.870158) (xy 310.45912 -278.946102) (xy 326.345308 -278.946102) (xy 326.349268 -278.897048)
			(xy 326.361045 -278.849264) (xy 326.380336 -278.803988) (xy 326.406639 -278.762392) (xy 326.439274 -278.725555)
			(xy 326.477395 -278.69443) (xy 326.520016 -278.669823) (xy 326.566032 -278.652371) (xy 326.614251 -278.642527)
			(xy 326.663426 -278.640546) (xy 326.712281 -278.646478) (xy 326.759552 -278.66017) (xy 326.804014 -278.681268)
			(xy 326.844517 -278.709224) (xy 326.88001 -278.743316) (xy 326.909575 -278.78266) (xy 326.932446 -278.826237)
			(xy 326.94803 -278.872918) (xy 326.955925 -278.921495) (xy 326.95642 -278.946102) (xy 328.225416 -278.946102)
			(xy 328.229376 -278.897048) (xy 328.241153 -278.849264) (xy 328.260444 -278.803988) (xy 328.286747 -278.762392)
			(xy 328.319382 -278.725555) (xy 328.357503 -278.69443) (xy 328.400124 -278.669823) (xy 328.44614 -278.652371)
			(xy 328.494359 -278.642527) (xy 328.543534 -278.640546) (xy 328.592389 -278.646478) (xy 328.63966 -278.66017)
			(xy 328.684122 -278.681268) (xy 328.724625 -278.709224) (xy 328.760118 -278.743316) (xy 328.789683 -278.78266)
			(xy 328.812554 -278.826237) (xy 328.828138 -278.872918) (xy 328.836033 -278.921495) (xy 328.836528 -278.946102)
			(xy 329.154785 -278.946102) (xy 329.15888 -278.895374) (xy 329.171059 -278.84596) (xy 329.191007 -278.79914)
			(xy 329.218208 -278.756126) (xy 329.251956 -278.718032) (xy 329.291378 -278.685845) (xy 329.335452 -278.660399)
			(xy 329.383038 -278.642352) (xy 329.432902 -278.632172) (xy 329.483754 -278.630123) (xy 329.534275 -278.636257)
			(xy 329.583159 -278.650417) (xy 329.629138 -278.672234) (xy 329.671022 -278.701144) (xy 329.707726 -278.736399)
			(xy 329.738299 -278.777085) (xy 329.76195 -278.822148) (xy 329.778066 -278.870422) (xy 329.78623 -278.920656)
			(xy 329.786742 -278.946102) (xy 330.094839 -278.946102) (xy 330.098934 -278.895374) (xy 330.111113 -278.84596)
			(xy 330.131061 -278.79914) (xy 330.158262 -278.756126) (xy 330.19201 -278.718032) (xy 330.231432 -278.685845)
			(xy 330.275506 -278.660399) (xy 330.323092 -278.642352) (xy 330.372956 -278.632172) (xy 330.423808 -278.630123)
			(xy 330.474329 -278.636257) (xy 330.523213 -278.650417) (xy 330.569192 -278.672234) (xy 330.611076 -278.701144)
			(xy 330.64778 -278.736399) (xy 330.678353 -278.777085) (xy 330.702004 -278.822148) (xy 330.71812 -278.870422)
			(xy 330.726284 -278.920656) (xy 330.726796 -278.946102) (xy 331.045324 -278.946102) (xy 331.049284 -278.897048)
			(xy 331.061061 -278.849264) (xy 331.080352 -278.803988) (xy 331.106655 -278.762392) (xy 331.13929 -278.725555)
			(xy 331.177411 -278.69443) (xy 331.220032 -278.669823) (xy 331.266048 -278.652371) (xy 331.314267 -278.642527)
			(xy 331.363442 -278.640546) (xy 331.412297 -278.646478) (xy 331.459568 -278.66017) (xy 331.50403 -278.681268)
			(xy 331.544533 -278.709224) (xy 331.580026 -278.743316) (xy 331.609591 -278.78266) (xy 331.632462 -278.826237)
			(xy 331.648046 -278.872918) (xy 331.655941 -278.921495) (xy 331.656436 -278.946102) (xy 331.974947 -278.946102)
			(xy 331.979042 -278.895374) (xy 331.991221 -278.84596) (xy 332.011169 -278.79914) (xy 332.03837 -278.756126)
			(xy 332.072118 -278.718032) (xy 332.11154 -278.685845) (xy 332.155614 -278.660399) (xy 332.2032 -278.642352)
			(xy 332.253064 -278.632172) (xy 332.303916 -278.630123) (xy 332.354437 -278.636257) (xy 332.403321 -278.650417)
			(xy 332.4493 -278.672234) (xy 332.491184 -278.701144) (xy 332.527888 -278.736399) (xy 332.558461 -278.777085)
			(xy 332.582112 -278.822148) (xy 332.598228 -278.870422) (xy 332.606392 -278.920656) (xy 332.606904 -278.946102)
			(xy 332.925178 -278.946102) (xy 332.929138 -278.897048) (xy 332.940915 -278.849264) (xy 332.960206 -278.803988)
			(xy 332.986509 -278.762392) (xy 333.019144 -278.725555) (xy 333.057265 -278.69443) (xy 333.099886 -278.669823)
			(xy 333.145902 -278.652371) (xy 333.194121 -278.642527) (xy 333.243296 -278.640546) (xy 333.292151 -278.646478)
			(xy 333.339422 -278.66017) (xy 333.383884 -278.681268) (xy 333.424387 -278.709224) (xy 333.45988 -278.743316)
			(xy 333.489445 -278.78266) (xy 333.512316 -278.826237) (xy 333.5279 -278.872918) (xy 333.535795 -278.921495)
			(xy 333.53629 -278.946102) (xy 333.854801 -278.946102) (xy 333.858896 -278.895374) (xy 333.871075 -278.84596)
			(xy 333.891023 -278.79914) (xy 333.918224 -278.756126) (xy 333.951972 -278.718032) (xy 333.991394 -278.685845)
			(xy 334.035468 -278.660399) (xy 334.083054 -278.642352) (xy 334.132918 -278.632172) (xy 334.18377 -278.630123)
			(xy 334.234291 -278.636257) (xy 334.283175 -278.650417) (xy 334.329154 -278.672234) (xy 334.371038 -278.701144)
			(xy 334.407742 -278.736399) (xy 334.438315 -278.777085) (xy 334.461966 -278.822148) (xy 334.478082 -278.870422)
			(xy 334.486246 -278.920656) (xy 334.486758 -278.946102) (xy 334.805286 -278.946102) (xy 334.809246 -278.897048)
			(xy 334.821023 -278.849264) (xy 334.840314 -278.803988) (xy 334.866617 -278.762392) (xy 334.899252 -278.725555)
			(xy 334.937373 -278.69443) (xy 334.979994 -278.669823) (xy 335.02601 -278.652371) (xy 335.074229 -278.642527)
			(xy 335.123404 -278.640546) (xy 335.172259 -278.646478) (xy 335.21953 -278.66017) (xy 335.263992 -278.681268)
			(xy 335.304495 -278.709224) (xy 335.339988 -278.743316) (xy 335.369553 -278.78266) (xy 335.392424 -278.826237)
			(xy 335.408008 -278.872918) (xy 335.415903 -278.921495) (xy 335.416398 -278.946102) (xy 335.734909 -278.946102)
			(xy 335.739004 -278.895374) (xy 335.751183 -278.84596) (xy 335.771131 -278.79914) (xy 335.798332 -278.756126)
			(xy 335.83208 -278.718032) (xy 335.871502 -278.685845) (xy 335.915576 -278.660399) (xy 335.963162 -278.642352)
			(xy 336.013026 -278.632172) (xy 336.063878 -278.630123) (xy 336.114399 -278.636257) (xy 336.163283 -278.650417)
			(xy 336.209262 -278.672234) (xy 336.251146 -278.701144) (xy 336.28785 -278.736399) (xy 336.318423 -278.777085)
			(xy 336.342074 -278.822148) (xy 336.35819 -278.870422) (xy 336.366354 -278.920656) (xy 336.366866 -278.946102)
			(xy 336.674963 -278.946102) (xy 336.679058 -278.895374) (xy 336.691237 -278.84596) (xy 336.711185 -278.79914)
			(xy 336.738386 -278.756126) (xy 336.772134 -278.718032) (xy 336.811556 -278.685845) (xy 336.85563 -278.660399)
			(xy 336.903216 -278.642352) (xy 336.95308 -278.632172) (xy 337.003932 -278.630123) (xy 337.054453 -278.636257)
			(xy 337.103337 -278.650417) (xy 337.149316 -278.672234) (xy 337.1912 -278.701144) (xy 337.227904 -278.736399)
			(xy 337.258477 -278.777085) (xy 337.282128 -278.822148) (xy 337.298244 -278.870422) (xy 337.306408 -278.920656)
			(xy 337.30692 -278.946102) (xy 337.625194 -278.946102) (xy 337.629154 -278.897048) (xy 337.640931 -278.849264)
			(xy 337.660222 -278.803988) (xy 337.686525 -278.762392) (xy 337.71916 -278.725555) (xy 337.757281 -278.69443)
			(xy 337.799902 -278.669823) (xy 337.845918 -278.652371) (xy 337.894137 -278.642527) (xy 337.943312 -278.640546)
			(xy 337.992167 -278.646478) (xy 338.039438 -278.66017) (xy 338.0839 -278.681268) (xy 338.124403 -278.709224)
			(xy 338.159896 -278.743316) (xy 338.189461 -278.78266) (xy 338.212332 -278.826237) (xy 338.227916 -278.872918)
			(xy 338.235811 -278.921495) (xy 338.236306 -278.946102) (xy 338.554817 -278.946102) (xy 338.558912 -278.895374)
			(xy 338.571091 -278.84596) (xy 338.591039 -278.79914) (xy 338.61824 -278.756126) (xy 338.651988 -278.718032)
			(xy 338.69141 -278.685845) (xy 338.735484 -278.660399) (xy 338.78307 -278.642352) (xy 338.832934 -278.632172)
			(xy 338.883786 -278.630123) (xy 338.934307 -278.636257) (xy 338.983191 -278.650417) (xy 339.02917 -278.672234)
			(xy 339.071054 -278.701144) (xy 339.107758 -278.736399) (xy 339.138331 -278.777085) (xy 339.161982 -278.822148)
			(xy 339.178098 -278.870422) (xy 339.186262 -278.920656) (xy 339.186774 -278.946102) (xy 339.505302 -278.946102)
			(xy 339.509262 -278.897048) (xy 339.521039 -278.849264) (xy 339.54033 -278.803988) (xy 339.566633 -278.762392)
			(xy 339.599268 -278.725555) (xy 339.637389 -278.69443) (xy 339.68001 -278.669823) (xy 339.726026 -278.652371)
			(xy 339.774245 -278.642527) (xy 339.82342 -278.640546) (xy 339.872275 -278.646478) (xy 339.919546 -278.66017)
			(xy 339.964008 -278.681268) (xy 340.004511 -278.709224) (xy 340.040004 -278.743316) (xy 340.069569 -278.78266)
			(xy 340.09244 -278.826237) (xy 340.108024 -278.872918) (xy 340.115919 -278.921495) (xy 340.116414 -278.946102)
			(xy 340.434925 -278.946102) (xy 340.43902 -278.895374) (xy 340.451199 -278.84596) (xy 340.471147 -278.79914)
			(xy 340.498348 -278.756126) (xy 340.532096 -278.718032) (xy 340.571518 -278.685845) (xy 340.615592 -278.660399)
			(xy 340.663178 -278.642352) (xy 340.713042 -278.632172) (xy 340.763894 -278.630123) (xy 340.814415 -278.636257)
			(xy 340.863299 -278.650417) (xy 340.909278 -278.672234) (xy 340.951162 -278.701144) (xy 340.987866 -278.736399)
			(xy 341.018439 -278.777085) (xy 341.04209 -278.822148) (xy 341.058206 -278.870422) (xy 341.06637 -278.920656)
			(xy 341.066882 -278.946102) (xy 341.38541 -278.946102) (xy 341.38937 -278.897048) (xy 341.401147 -278.849264)
			(xy 341.420438 -278.803988) (xy 341.446741 -278.762392) (xy 341.479376 -278.725555) (xy 341.517497 -278.69443)
			(xy 341.560118 -278.669823) (xy 341.606134 -278.652371) (xy 341.654353 -278.642527) (xy 341.703528 -278.640546)
			(xy 341.752383 -278.646478) (xy 341.799654 -278.66017) (xy 341.844116 -278.681268) (xy 341.884619 -278.709224)
			(xy 341.920112 -278.743316) (xy 341.949677 -278.78266) (xy 341.972548 -278.826237) (xy 341.988132 -278.872918)
			(xy 341.996027 -278.921495) (xy 341.996522 -278.946102) (xy 342.314779 -278.946102) (xy 342.318874 -278.895374)
			(xy 342.331053 -278.84596) (xy 342.351001 -278.79914) (xy 342.378202 -278.756126) (xy 342.41195 -278.718032)
			(xy 342.451372 -278.685845) (xy 342.495446 -278.660399) (xy 342.543032 -278.642352) (xy 342.592896 -278.632172)
			(xy 342.643748 -278.630123) (xy 342.694269 -278.636257) (xy 342.743153 -278.650417) (xy 342.789132 -278.672234)
			(xy 342.831016 -278.701144) (xy 342.86772 -278.736399) (xy 342.898293 -278.777085) (xy 342.921944 -278.822148)
			(xy 342.93806 -278.870422) (xy 342.946224 -278.920656) (xy 342.946736 -278.946102) (xy 343.254833 -278.946102)
			(xy 343.258928 -278.895374) (xy 343.271107 -278.84596) (xy 343.291055 -278.79914) (xy 343.318256 -278.756126)
			(xy 343.352004 -278.718032) (xy 343.391426 -278.685845) (xy 343.4355 -278.660399) (xy 343.483086 -278.642352)
			(xy 343.53295 -278.632172) (xy 343.583802 -278.630123) (xy 343.634323 -278.636257) (xy 343.683207 -278.650417)
			(xy 343.729186 -278.672234) (xy 343.77107 -278.701144) (xy 343.807774 -278.736399) (xy 343.838347 -278.777085)
			(xy 343.861998 -278.822148) (xy 343.878114 -278.870422) (xy 343.886278 -278.920656) (xy 343.88679 -278.946102)
			(xy 344.205318 -278.946102) (xy 344.209278 -278.897048) (xy 344.221055 -278.849264) (xy 344.240346 -278.803988)
			(xy 344.266649 -278.762392) (xy 344.299284 -278.725555) (xy 344.337405 -278.69443) (xy 344.380026 -278.669823)
			(xy 344.426042 -278.652371) (xy 344.474261 -278.642527) (xy 344.523436 -278.640546) (xy 344.572291 -278.646478)
			(xy 344.619562 -278.66017) (xy 344.664024 -278.681268) (xy 344.704527 -278.709224) (xy 344.74002 -278.743316)
			(xy 344.769585 -278.78266) (xy 344.792456 -278.826237) (xy 344.80804 -278.872918) (xy 344.815935 -278.921495)
			(xy 344.81643 -278.946102) (xy 345.145372 -278.946102) (xy 345.149332 -278.897048) (xy 345.161109 -278.849264)
			(xy 345.1804 -278.803988) (xy 345.206703 -278.762392) (xy 345.239338 -278.725555) (xy 345.277459 -278.69443)
			(xy 345.32008 -278.669823) (xy 345.366096 -278.652371) (xy 345.414315 -278.642527) (xy 345.46349 -278.640546)
			(xy 345.512345 -278.646478) (xy 345.559616 -278.66017) (xy 345.604078 -278.681268) (xy 345.644581 -278.709224)
			(xy 345.680074 -278.743316) (xy 345.709639 -278.78266) (xy 345.73251 -278.826237) (xy 345.748094 -278.872918)
			(xy 345.755989 -278.921495) (xy 345.756484 -278.946102) (xy 346.085426 -278.946102) (xy 346.089386 -278.897048)
			(xy 346.101163 -278.849264) (xy 346.120454 -278.803988) (xy 346.146757 -278.762392) (xy 346.179392 -278.725555)
			(xy 346.217513 -278.69443) (xy 346.260134 -278.669823) (xy 346.30615 -278.652371) (xy 346.354369 -278.642527)
			(xy 346.403544 -278.640546) (xy 346.452399 -278.646478) (xy 346.49967 -278.66017) (xy 346.544132 -278.681268)
			(xy 346.584635 -278.709224) (xy 346.620128 -278.743316) (xy 346.649693 -278.78266) (xy 346.672564 -278.826237)
			(xy 346.688148 -278.872918) (xy 346.696043 -278.921495) (xy 346.696538 -278.946102) (xy 347.025226 -278.946102)
			(xy 347.029186 -278.897048) (xy 347.040963 -278.849264) (xy 347.060254 -278.803988) (xy 347.086557 -278.762392)
			(xy 347.119192 -278.725555) (xy 347.157313 -278.69443) (xy 347.199934 -278.669823) (xy 347.24595 -278.652371)
			(xy 347.294169 -278.642527) (xy 347.343344 -278.640546) (xy 347.392199 -278.646478) (xy 347.43947 -278.66017)
			(xy 347.483932 -278.681268) (xy 347.524435 -278.709224) (xy 347.559928 -278.743316) (xy 347.589493 -278.78266)
			(xy 347.612364 -278.826237) (xy 347.627948 -278.872918) (xy 347.635843 -278.921495) (xy 347.636338 -278.946102)
			(xy 347.96528 -278.946102) (xy 347.96924 -278.897048) (xy 347.981017 -278.849264) (xy 348.000308 -278.803988)
			(xy 348.026611 -278.762392) (xy 348.059246 -278.725555) (xy 348.097367 -278.69443) (xy 348.139988 -278.669823)
			(xy 348.186004 -278.652371) (xy 348.234223 -278.642527) (xy 348.283398 -278.640546) (xy 348.332253 -278.646478)
			(xy 348.379524 -278.66017) (xy 348.423986 -278.681268) (xy 348.464489 -278.709224) (xy 348.499982 -278.743316)
			(xy 348.529547 -278.78266) (xy 348.552418 -278.826237) (xy 348.568002 -278.872918) (xy 348.575897 -278.921495)
			(xy 348.576392 -278.946102) (xy 348.905334 -278.946102) (xy 348.909294 -278.897048) (xy 348.921071 -278.849264)
			(xy 348.940362 -278.803988) (xy 348.966665 -278.762392) (xy 348.9993 -278.725555) (xy 349.037421 -278.69443)
			(xy 349.080042 -278.669823) (xy 349.126058 -278.652371) (xy 349.174277 -278.642527) (xy 349.223452 -278.640546)
			(xy 349.272307 -278.646478) (xy 349.319578 -278.66017) (xy 349.36404 -278.681268) (xy 349.404543 -278.709224)
			(xy 349.440036 -278.743316) (xy 349.469601 -278.78266) (xy 349.492472 -278.826237) (xy 349.508056 -278.872918)
			(xy 349.515951 -278.921495) (xy 349.516446 -278.946102) (xy 349.845388 -278.946102) (xy 349.849348 -278.897048)
			(xy 349.861125 -278.849264) (xy 349.880416 -278.803988) (xy 349.906719 -278.762392) (xy 349.939354 -278.725555)
			(xy 349.977475 -278.69443) (xy 350.020096 -278.669823) (xy 350.066112 -278.652371) (xy 350.114331 -278.642527)
			(xy 350.163506 -278.640546) (xy 350.212361 -278.646478) (xy 350.259632 -278.66017) (xy 350.304094 -278.681268)
			(xy 350.344597 -278.709224) (xy 350.38009 -278.743316) (xy 350.409655 -278.78266) (xy 350.432526 -278.826237)
			(xy 350.44811 -278.872918) (xy 350.456005 -278.921495) (xy 350.4565 -278.946102) (xy 350.785442 -278.946102)
			(xy 350.789402 -278.897048) (xy 350.801179 -278.849264) (xy 350.82047 -278.803988) (xy 350.846773 -278.762392)
			(xy 350.879408 -278.725555) (xy 350.917529 -278.69443) (xy 350.96015 -278.669823) (xy 351.006166 -278.652371)
			(xy 351.054385 -278.642527) (xy 351.10356 -278.640546) (xy 351.152415 -278.646478) (xy 351.199686 -278.66017)
			(xy 351.244148 -278.681268) (xy 351.284651 -278.709224) (xy 351.320144 -278.743316) (xy 351.349709 -278.78266)
			(xy 351.37258 -278.826237) (xy 351.388164 -278.872918) (xy 351.396059 -278.921495) (xy 351.396554 -278.946102)
			(xy 351.396059 -278.970709) (xy 351.388164 -279.019286) (xy 351.37258 -279.065967) (xy 351.349709 -279.109544)
			(xy 351.320144 -279.148888) (xy 351.284651 -279.18298) (xy 351.244148 -279.210936) (xy 351.199686 -279.232034)
			(xy 351.152415 -279.245726) (xy 351.10356 -279.251658) (xy 351.054385 -279.249677) (xy 351.006166 -279.239833)
			(xy 350.96015 -279.222381) (xy 350.917529 -279.197774) (xy 350.879408 -279.166649) (xy 350.846773 -279.129812)
			(xy 350.82047 -279.088216) (xy 350.801179 -279.04294) (xy 350.789402 -278.995156) (xy 350.785442 -278.946102)
			(xy 350.4565 -278.946102) (xy 350.456005 -278.970709) (xy 350.44811 -279.019286) (xy 350.432526 -279.065967)
			(xy 350.409655 -279.109544) (xy 350.38009 -279.148888) (xy 350.344597 -279.18298) (xy 350.304094 -279.210936)
			(xy 350.259632 -279.232034) (xy 350.212361 -279.245726) (xy 350.163506 -279.251658) (xy 350.114331 -279.249677)
			(xy 350.066112 -279.239833) (xy 350.020096 -279.222381) (xy 349.977475 -279.197774) (xy 349.939354 -279.166649)
			(xy 349.906719 -279.129812) (xy 349.880416 -279.088216) (xy 349.861125 -279.04294) (xy 349.849348 -278.995156)
			(xy 349.845388 -278.946102) (xy 349.516446 -278.946102) (xy 349.515951 -278.970709) (xy 349.508056 -279.019286)
			(xy 349.492472 -279.065967) (xy 349.469601 -279.109544) (xy 349.440036 -279.148888) (xy 349.404543 -279.18298)
			(xy 349.36404 -279.210936) (xy 349.319578 -279.232034) (xy 349.272307 -279.245726) (xy 349.223452 -279.251658)
			(xy 349.174277 -279.249677) (xy 349.126058 -279.239833) (xy 349.080042 -279.222381) (xy 349.037421 -279.197774)
			(xy 348.9993 -279.166649) (xy 348.966665 -279.129812) (xy 348.940362 -279.088216) (xy 348.921071 -279.04294)
			(xy 348.909294 -278.995156) (xy 348.905334 -278.946102) (xy 348.576392 -278.946102) (xy 348.575897 -278.970709)
			(xy 348.568002 -279.019286) (xy 348.552418 -279.065967) (xy 348.529547 -279.109544) (xy 348.499982 -279.148888)
			(xy 348.464489 -279.18298) (xy 348.423986 -279.210936) (xy 348.379524 -279.232034) (xy 348.332253 -279.245726)
			(xy 348.283398 -279.251658) (xy 348.234223 -279.249677) (xy 348.186004 -279.239833) (xy 348.139988 -279.222381)
			(xy 348.097367 -279.197774) (xy 348.059246 -279.166649) (xy 348.026611 -279.129812) (xy 348.000308 -279.088216)
			(xy 347.981017 -279.04294) (xy 347.96924 -278.995156) (xy 347.96528 -278.946102) (xy 347.636338 -278.946102)
			(xy 347.635843 -278.970709) (xy 347.627948 -279.019286) (xy 347.612364 -279.065967) (xy 347.589493 -279.109544)
			(xy 347.559928 -279.148888) (xy 347.524435 -279.18298) (xy 347.483932 -279.210936) (xy 347.43947 -279.232034)
			(xy 347.392199 -279.245726) (xy 347.343344 -279.251658) (xy 347.294169 -279.249677) (xy 347.24595 -279.239833)
			(xy 347.199934 -279.222381) (xy 347.157313 -279.197774) (xy 347.119192 -279.166649) (xy 347.086557 -279.129812)
			(xy 347.060254 -279.088216) (xy 347.040963 -279.04294) (xy 347.029186 -278.995156) (xy 347.025226 -278.946102)
			(xy 346.696538 -278.946102) (xy 346.696043 -278.970709) (xy 346.688148 -279.019286) (xy 346.672564 -279.065967)
			(xy 346.649693 -279.109544) (xy 346.620128 -279.148888) (xy 346.584635 -279.18298) (xy 346.544132 -279.210936)
			(xy 346.49967 -279.232034) (xy 346.452399 -279.245726) (xy 346.403544 -279.251658) (xy 346.354369 -279.249677)
			(xy 346.30615 -279.239833) (xy 346.260134 -279.222381) (xy 346.217513 -279.197774) (xy 346.179392 -279.166649)
			(xy 346.146757 -279.129812) (xy 346.120454 -279.088216) (xy 346.101163 -279.04294) (xy 346.089386 -278.995156)
			(xy 346.085426 -278.946102) (xy 345.756484 -278.946102) (xy 345.755989 -278.970709) (xy 345.748094 -279.019286)
			(xy 345.73251 -279.065967) (xy 345.709639 -279.109544) (xy 345.680074 -279.148888) (xy 345.644581 -279.18298)
			(xy 345.604078 -279.210936) (xy 345.559616 -279.232034) (xy 345.512345 -279.245726) (xy 345.46349 -279.251658)
			(xy 345.414315 -279.249677) (xy 345.366096 -279.239833) (xy 345.32008 -279.222381) (xy 345.277459 -279.197774)
			(xy 345.239338 -279.166649) (xy 345.206703 -279.129812) (xy 345.1804 -279.088216) (xy 345.161109 -279.04294)
			(xy 345.149332 -278.995156) (xy 345.145372 -278.946102) (xy 344.81643 -278.946102) (xy 344.815935 -278.970709)
			(xy 344.80804 -279.019286) (xy 344.792456 -279.065967) (xy 344.769585 -279.109544) (xy 344.74002 -279.148888)
			(xy 344.704527 -279.18298) (xy 344.664024 -279.210936) (xy 344.619562 -279.232034) (xy 344.572291 -279.245726)
			(xy 344.523436 -279.251658) (xy 344.474261 -279.249677) (xy 344.426042 -279.239833) (xy 344.380026 -279.222381)
			(xy 344.337405 -279.197774) (xy 344.299284 -279.166649) (xy 344.266649 -279.129812) (xy 344.240346 -279.088216)
			(xy 344.221055 -279.04294) (xy 344.209278 -278.995156) (xy 344.205318 -278.946102) (xy 343.88679 -278.946102)
			(xy 343.886278 -278.971548) (xy 343.878114 -279.021782) (xy 343.861998 -279.070056) (xy 343.838347 -279.115119)
			(xy 343.807774 -279.155805) (xy 343.77107 -279.19106) (xy 343.729186 -279.21997) (xy 343.683207 -279.241787)
			(xy 343.634323 -279.255947) (xy 343.583802 -279.262081) (xy 343.53295 -279.260032) (xy 343.483086 -279.249852)
			(xy 343.4355 -279.231805) (xy 343.391426 -279.206359) (xy 343.352004 -279.174172) (xy 343.318256 -279.136078)
			(xy 343.291055 -279.093064) (xy 343.271107 -279.046244) (xy 343.258928 -278.99683) (xy 343.254833 -278.946102)
			(xy 342.946736 -278.946102) (xy 342.946224 -278.971548) (xy 342.93806 -279.021782) (xy 342.921944 -279.070056)
			(xy 342.898293 -279.115119) (xy 342.86772 -279.155805) (xy 342.831016 -279.19106) (xy 342.789132 -279.21997)
			(xy 342.743153 -279.241787) (xy 342.694269 -279.255947) (xy 342.643748 -279.262081) (xy 342.592896 -279.260032)
			(xy 342.543032 -279.249852) (xy 342.495446 -279.231805) (xy 342.451372 -279.206359) (xy 342.41195 -279.174172)
			(xy 342.378202 -279.136078) (xy 342.351001 -279.093064) (xy 342.331053 -279.046244) (xy 342.318874 -278.99683)
			(xy 342.314779 -278.946102) (xy 341.996522 -278.946102) (xy 341.996027 -278.970709) (xy 341.988132 -279.019286)
			(xy 341.972548 -279.065967) (xy 341.949677 -279.109544) (xy 341.920112 -279.148888) (xy 341.884619 -279.18298)
			(xy 341.844116 -279.210936) (xy 341.799654 -279.232034) (xy 341.752383 -279.245726) (xy 341.703528 -279.251658)
			(xy 341.654353 -279.249677) (xy 341.606134 -279.239833) (xy 341.560118 -279.222381) (xy 341.517497 -279.197774)
			(xy 341.479376 -279.166649) (xy 341.446741 -279.129812) (xy 341.420438 -279.088216) (xy 341.401147 -279.04294)
			(xy 341.38937 -278.995156) (xy 341.38541 -278.946102) (xy 341.066882 -278.946102) (xy 341.06637 -278.971548)
			(xy 341.058206 -279.021782) (xy 341.04209 -279.070056) (xy 341.018439 -279.115119) (xy 340.987866 -279.155805)
			(xy 340.951162 -279.19106) (xy 340.909278 -279.21997) (xy 340.863299 -279.241787) (xy 340.814415 -279.255947)
			(xy 340.763894 -279.262081) (xy 340.713042 -279.260032) (xy 340.663178 -279.249852) (xy 340.615592 -279.231805)
			(xy 340.571518 -279.206359) (xy 340.532096 -279.174172) (xy 340.498348 -279.136078) (xy 340.471147 -279.093064)
			(xy 340.451199 -279.046244) (xy 340.43902 -278.99683) (xy 340.434925 -278.946102) (xy 340.116414 -278.946102)
			(xy 340.115919 -278.970709) (xy 340.108024 -279.019286) (xy 340.09244 -279.065967) (xy 340.069569 -279.109544)
			(xy 340.040004 -279.148888) (xy 340.004511 -279.18298) (xy 339.964008 -279.210936) (xy 339.919546 -279.232034)
			(xy 339.872275 -279.245726) (xy 339.82342 -279.251658) (xy 339.774245 -279.249677) (xy 339.726026 -279.239833)
			(xy 339.68001 -279.222381) (xy 339.637389 -279.197774) (xy 339.599268 -279.166649) (xy 339.566633 -279.129812)
			(xy 339.54033 -279.088216) (xy 339.521039 -279.04294) (xy 339.509262 -278.995156) (xy 339.505302 -278.946102)
			(xy 339.186774 -278.946102) (xy 339.186262 -278.971548) (xy 339.178098 -279.021782) (xy 339.161982 -279.070056)
			(xy 339.138331 -279.115119) (xy 339.107758 -279.155805) (xy 339.071054 -279.19106) (xy 339.02917 -279.21997)
			(xy 338.983191 -279.241787) (xy 338.934307 -279.255947) (xy 338.883786 -279.262081) (xy 338.832934 -279.260032)
			(xy 338.78307 -279.249852) (xy 338.735484 -279.231805) (xy 338.69141 -279.206359) (xy 338.651988 -279.174172)
			(xy 338.61824 -279.136078) (xy 338.591039 -279.093064) (xy 338.571091 -279.046244) (xy 338.558912 -278.99683)
			(xy 338.554817 -278.946102) (xy 338.236306 -278.946102) (xy 338.235811 -278.970709) (xy 338.227916 -279.019286)
			(xy 338.212332 -279.065967) (xy 338.189461 -279.109544) (xy 338.159896 -279.148888) (xy 338.124403 -279.18298)
			(xy 338.0839 -279.210936) (xy 338.039438 -279.232034) (xy 337.992167 -279.245726) (xy 337.943312 -279.251658)
			(xy 337.894137 -279.249677) (xy 337.845918 -279.239833) (xy 337.799902 -279.222381) (xy 337.757281 -279.197774)
			(xy 337.71916 -279.166649) (xy 337.686525 -279.129812) (xy 337.660222 -279.088216) (xy 337.640931 -279.04294)
			(xy 337.629154 -278.995156) (xy 337.625194 -278.946102) (xy 337.30692 -278.946102) (xy 337.306408 -278.971548)
			(xy 337.298244 -279.021782) (xy 337.282128 -279.070056) (xy 337.258477 -279.115119) (xy 337.227904 -279.155805)
			(xy 337.1912 -279.19106) (xy 337.149316 -279.21997) (xy 337.103337 -279.241787) (xy 337.054453 -279.255947)
			(xy 337.003932 -279.262081) (xy 336.95308 -279.260032) (xy 336.903216 -279.249852) (xy 336.85563 -279.231805)
			(xy 336.811556 -279.206359) (xy 336.772134 -279.174172) (xy 336.738386 -279.136078) (xy 336.711185 -279.093064)
			(xy 336.691237 -279.046244) (xy 336.679058 -278.99683) (xy 336.674963 -278.946102) (xy 336.366866 -278.946102)
			(xy 336.366354 -278.971548) (xy 336.35819 -279.021782) (xy 336.342074 -279.070056) (xy 336.318423 -279.115119)
			(xy 336.28785 -279.155805) (xy 336.251146 -279.19106) (xy 336.209262 -279.21997) (xy 336.163283 -279.241787)
			(xy 336.114399 -279.255947) (xy 336.063878 -279.262081) (xy 336.013026 -279.260032) (xy 335.963162 -279.249852)
			(xy 335.915576 -279.231805) (xy 335.871502 -279.206359) (xy 335.83208 -279.174172) (xy 335.798332 -279.136078)
			(xy 335.771131 -279.093064) (xy 335.751183 -279.046244) (xy 335.739004 -278.99683) (xy 335.734909 -278.946102)
			(xy 335.416398 -278.946102) (xy 335.415903 -278.970709) (xy 335.408008 -279.019286) (xy 335.392424 -279.065967)
			(xy 335.369553 -279.109544) (xy 335.339988 -279.148888) (xy 335.304495 -279.18298) (xy 335.263992 -279.210936)
			(xy 335.21953 -279.232034) (xy 335.172259 -279.245726) (xy 335.123404 -279.251658) (xy 335.074229 -279.249677)
			(xy 335.02601 -279.239833) (xy 334.979994 -279.222381) (xy 334.937373 -279.197774) (xy 334.899252 -279.166649)
			(xy 334.866617 -279.129812) (xy 334.840314 -279.088216) (xy 334.821023 -279.04294) (xy 334.809246 -278.995156)
			(xy 334.805286 -278.946102) (xy 334.486758 -278.946102) (xy 334.486246 -278.971548) (xy 334.478082 -279.021782)
			(xy 334.461966 -279.070056) (xy 334.438315 -279.115119) (xy 334.407742 -279.155805) (xy 334.371038 -279.19106)
			(xy 334.329154 -279.21997) (xy 334.283175 -279.241787) (xy 334.234291 -279.255947) (xy 334.18377 -279.262081)
			(xy 334.132918 -279.260032) (xy 334.083054 -279.249852) (xy 334.035468 -279.231805) (xy 333.991394 -279.206359)
			(xy 333.951972 -279.174172) (xy 333.918224 -279.136078) (xy 333.891023 -279.093064) (xy 333.871075 -279.046244)
			(xy 333.858896 -278.99683) (xy 333.854801 -278.946102) (xy 333.53629 -278.946102) (xy 333.535795 -278.970709)
			(xy 333.5279 -279.019286) (xy 333.512316 -279.065967) (xy 333.489445 -279.109544) (xy 333.45988 -279.148888)
			(xy 333.424387 -279.18298) (xy 333.383884 -279.210936) (xy 333.339422 -279.232034) (xy 333.292151 -279.245726)
			(xy 333.243296 -279.251658) (xy 333.194121 -279.249677) (xy 333.145902 -279.239833) (xy 333.099886 -279.222381)
			(xy 333.057265 -279.197774) (xy 333.019144 -279.166649) (xy 332.986509 -279.129812) (xy 332.960206 -279.088216)
			(xy 332.940915 -279.04294) (xy 332.929138 -278.995156) (xy 332.925178 -278.946102) (xy 332.606904 -278.946102)
			(xy 332.606392 -278.971548) (xy 332.598228 -279.021782) (xy 332.582112 -279.070056) (xy 332.558461 -279.115119)
			(xy 332.527888 -279.155805) (xy 332.491184 -279.19106) (xy 332.4493 -279.21997) (xy 332.403321 -279.241787)
			(xy 332.354437 -279.255947) (xy 332.303916 -279.262081) (xy 332.253064 -279.260032) (xy 332.2032 -279.249852)
			(xy 332.155614 -279.231805) (xy 332.11154 -279.206359) (xy 332.072118 -279.174172) (xy 332.03837 -279.136078)
			(xy 332.011169 -279.093064) (xy 331.991221 -279.046244) (xy 331.979042 -278.99683) (xy 331.974947 -278.946102)
			(xy 331.656436 -278.946102) (xy 331.655941 -278.970709) (xy 331.648046 -279.019286) (xy 331.632462 -279.065967)
			(xy 331.609591 -279.109544) (xy 331.580026 -279.148888) (xy 331.544533 -279.18298) (xy 331.50403 -279.210936)
			(xy 331.459568 -279.232034) (xy 331.412297 -279.245726) (xy 331.363442 -279.251658) (xy 331.314267 -279.249677)
			(xy 331.266048 -279.239833) (xy 331.220032 -279.222381) (xy 331.177411 -279.197774) (xy 331.13929 -279.166649)
			(xy 331.106655 -279.129812) (xy 331.080352 -279.088216) (xy 331.061061 -279.04294) (xy 331.049284 -278.995156)
			(xy 331.045324 -278.946102) (xy 330.726796 -278.946102) (xy 330.726284 -278.971548) (xy 330.71812 -279.021782)
			(xy 330.702004 -279.070056) (xy 330.678353 -279.115119) (xy 330.64778 -279.155805) (xy 330.611076 -279.19106)
			(xy 330.569192 -279.21997) (xy 330.523213 -279.241787) (xy 330.474329 -279.255947) (xy 330.423808 -279.262081)
			(xy 330.372956 -279.260032) (xy 330.323092 -279.249852) (xy 330.275506 -279.231805) (xy 330.231432 -279.206359)
			(xy 330.19201 -279.174172) (xy 330.158262 -279.136078) (xy 330.131061 -279.093064) (xy 330.111113 -279.046244)
			(xy 330.098934 -278.99683) (xy 330.094839 -278.946102) (xy 329.786742 -278.946102) (xy 329.78623 -278.971548)
			(xy 329.778066 -279.021782) (xy 329.76195 -279.070056) (xy 329.738299 -279.115119) (xy 329.707726 -279.155805)
			(xy 329.671022 -279.19106) (xy 329.629138 -279.21997) (xy 329.583159 -279.241787) (xy 329.534275 -279.255947)
			(xy 329.483754 -279.262081) (xy 329.432902 -279.260032) (xy 329.383038 -279.249852) (xy 329.335452 -279.231805)
			(xy 329.291378 -279.206359) (xy 329.251956 -279.174172) (xy 329.218208 -279.136078) (xy 329.191007 -279.093064)
			(xy 329.171059 -279.046244) (xy 329.15888 -278.99683) (xy 329.154785 -278.946102) (xy 328.836528 -278.946102)
			(xy 328.836033 -278.970709) (xy 328.828138 -279.019286) (xy 328.812554 -279.065967) (xy 328.789683 -279.109544)
			(xy 328.760118 -279.148888) (xy 328.724625 -279.18298) (xy 328.684122 -279.210936) (xy 328.63966 -279.232034)
			(xy 328.592389 -279.245726) (xy 328.543534 -279.251658) (xy 328.494359 -279.249677) (xy 328.44614 -279.239833)
			(xy 328.400124 -279.222381) (xy 328.357503 -279.197774) (xy 328.319382 -279.166649) (xy 328.286747 -279.129812)
			(xy 328.260444 -279.088216) (xy 328.241153 -279.04294) (xy 328.229376 -278.995156) (xy 328.225416 -278.946102)
			(xy 326.95642 -278.946102) (xy 326.955925 -278.970709) (xy 326.94803 -279.019286) (xy 326.932446 -279.065967)
			(xy 326.909575 -279.109544) (xy 326.88001 -279.148888) (xy 326.844517 -279.18298) (xy 326.804014 -279.210936)
			(xy 326.759552 -279.232034) (xy 326.712281 -279.245726) (xy 326.663426 -279.251658) (xy 326.614251 -279.249677)
			(xy 326.566032 -279.239833) (xy 326.520016 -279.222381) (xy 326.477395 -279.197774) (xy 326.439274 -279.166649)
			(xy 326.406639 -279.129812) (xy 326.380336 -279.088216) (xy 326.361045 -279.04294) (xy 326.349268 -278.995156)
			(xy 326.345308 -278.946102) (xy 310.45912 -278.946102) (xy 310.45912 -279.49017) (xy 324.74714 -279.49017)
			(xy 324.7511 -279.441116) (xy 324.762877 -279.393332) (xy 324.782168 -279.348056) (xy 324.808471 -279.30646)
			(xy 324.841106 -279.269623) (xy 324.879227 -279.238498) (xy 324.921848 -279.213891) (xy 324.967864 -279.196439)
			(xy 325.016083 -279.186595) (xy 325.065258 -279.184614) (xy 325.114113 -279.190546) (xy 325.161384 -279.204238)
			(xy 325.205846 -279.225336) (xy 325.246349 -279.253292) (xy 325.281842 -279.287384) (xy 325.311407 -279.326728)
			(xy 325.334278 -279.370305) (xy 325.349862 -279.416986) (xy 325.357757 -279.465563) (xy 325.358252 -279.49017)
			(xy 325.357757 -279.514777) (xy 325.349862 -279.563354) (xy 325.334278 -279.610035) (xy 325.311407 -279.653612)
			(xy 325.281842 -279.692956) (xy 325.246349 -279.727048) (xy 325.205846 -279.755004) (xy 325.203519 -279.756108)
			(xy 327.755262 -279.756108) (xy 327.759222 -279.707054) (xy 327.770999 -279.65927) (xy 327.79029 -279.613994)
			(xy 327.816593 -279.572398) (xy 327.849228 -279.535561) (xy 327.887349 -279.504436) (xy 327.92997 -279.479829)
			(xy 327.975986 -279.462377) (xy 328.024205 -279.452533) (xy 328.07338 -279.450552) (xy 328.122235 -279.456484)
			(xy 328.169506 -279.470176) (xy 328.213968 -279.491274) (xy 328.254471 -279.51923) (xy 328.289964 -279.553322)
			(xy 328.319529 -279.592666) (xy 328.3424 -279.636243) (xy 328.357984 -279.682924) (xy 328.365879 -279.731501)
			(xy 328.366374 -279.756108) (xy 328.684885 -279.756108) (xy 328.68898 -279.70538) (xy 328.701159 -279.655966)
			(xy 328.721107 -279.609146) (xy 328.748308 -279.566132) (xy 328.782056 -279.528038) (xy 328.821478 -279.495851)
			(xy 328.865552 -279.470405) (xy 328.913138 -279.452358) (xy 328.963002 -279.442178) (xy 329.013854 -279.440129)
			(xy 329.064375 -279.446263) (xy 329.113259 -279.460423) (xy 329.159238 -279.48224) (xy 329.201122 -279.51115)
			(xy 329.237826 -279.546405) (xy 329.268399 -279.587091) (xy 329.29205 -279.632154) (xy 329.308166 -279.680428)
			(xy 329.31633 -279.730662) (xy 329.316842 -279.756108) (xy 329.63537 -279.756108) (xy 329.63933 -279.707054)
			(xy 329.651107 -279.65927) (xy 329.670398 -279.613994) (xy 329.696701 -279.572398) (xy 329.729336 -279.535561)
			(xy 329.767457 -279.504436) (xy 329.810078 -279.479829) (xy 329.856094 -279.462377) (xy 329.904313 -279.452533)
			(xy 329.953488 -279.450552) (xy 330.002343 -279.456484) (xy 330.049614 -279.470176) (xy 330.094076 -279.491274)
			(xy 330.134579 -279.51923) (xy 330.170072 -279.553322) (xy 330.199637 -279.592666) (xy 330.222508 -279.636243)
			(xy 330.238092 -279.682924) (xy 330.245987 -279.731501) (xy 330.246482 -279.756108) (xy 330.564739 -279.756108)
			(xy 330.568834 -279.70538) (xy 330.581013 -279.655966) (xy 330.600961 -279.609146) (xy 330.628162 -279.566132)
			(xy 330.66191 -279.528038) (xy 330.701332 -279.495851) (xy 330.745406 -279.470405) (xy 330.792992 -279.452358)
			(xy 330.842856 -279.442178) (xy 330.893708 -279.440129) (xy 330.944229 -279.446263) (xy 330.993113 -279.460423)
			(xy 331.039092 -279.48224) (xy 331.080976 -279.51115) (xy 331.11768 -279.546405) (xy 331.148253 -279.587091)
			(xy 331.171904 -279.632154) (xy 331.18802 -279.680428) (xy 331.196184 -279.730662) (xy 331.196696 -279.756108)
			(xy 331.515224 -279.756108) (xy 331.519184 -279.707054) (xy 331.530961 -279.65927) (xy 331.550252 -279.613994)
			(xy 331.576555 -279.572398) (xy 331.60919 -279.535561) (xy 331.647311 -279.504436) (xy 331.689932 -279.479829)
			(xy 331.735948 -279.462377) (xy 331.784167 -279.452533) (xy 331.833342 -279.450552) (xy 331.882197 -279.456484)
			(xy 331.929468 -279.470176) (xy 331.97393 -279.491274) (xy 332.014433 -279.51923) (xy 332.049926 -279.553322)
			(xy 332.079491 -279.592666) (xy 332.102362 -279.636243) (xy 332.117946 -279.682924) (xy 332.125841 -279.731501)
			(xy 332.126336 -279.756108) (xy 332.444847 -279.756108) (xy 332.448942 -279.70538) (xy 332.461121 -279.655966)
			(xy 332.481069 -279.609146) (xy 332.50827 -279.566132) (xy 332.542018 -279.528038) (xy 332.58144 -279.495851)
			(xy 332.625514 -279.470405) (xy 332.6731 -279.452358) (xy 332.722964 -279.442178) (xy 332.773816 -279.440129)
			(xy 332.824337 -279.446263) (xy 332.873221 -279.460423) (xy 332.9192 -279.48224) (xy 332.961084 -279.51115)
			(xy 332.997788 -279.546405) (xy 333.028361 -279.587091) (xy 333.052012 -279.632154) (xy 333.068128 -279.680428)
			(xy 333.076292 -279.730662) (xy 333.076804 -279.756108) (xy 333.384901 -279.756108) (xy 333.388996 -279.70538)
			(xy 333.401175 -279.655966) (xy 333.421123 -279.609146) (xy 333.448324 -279.566132) (xy 333.482072 -279.528038)
			(xy 333.521494 -279.495851) (xy 333.565568 -279.470405) (xy 333.613154 -279.452358) (xy 333.663018 -279.442178)
			(xy 333.71387 -279.440129) (xy 333.764391 -279.446263) (xy 333.813275 -279.460423) (xy 333.859254 -279.48224)
			(xy 333.901138 -279.51115) (xy 333.937842 -279.546405) (xy 333.968415 -279.587091) (xy 333.992066 -279.632154)
			(xy 334.008182 -279.680428) (xy 334.016346 -279.730662) (xy 334.016858 -279.756108) (xy 334.335386 -279.756108)
			(xy 334.339346 -279.707054) (xy 334.351123 -279.65927) (xy 334.370414 -279.613994) (xy 334.396717 -279.572398)
			(xy 334.429352 -279.535561) (xy 334.467473 -279.504436) (xy 334.510094 -279.479829) (xy 334.55611 -279.462377)
			(xy 334.604329 -279.452533) (xy 334.653504 -279.450552) (xy 334.702359 -279.456484) (xy 334.74963 -279.470176)
			(xy 334.794092 -279.491274) (xy 334.834595 -279.51923) (xy 334.870088 -279.553322) (xy 334.899653 -279.592666)
			(xy 334.922524 -279.636243) (xy 334.938108 -279.682924) (xy 334.946003 -279.731501) (xy 334.946498 -279.756108)
			(xy 335.264755 -279.756108) (xy 335.26885 -279.70538) (xy 335.281029 -279.655966) (xy 335.300977 -279.609146)
			(xy 335.328178 -279.566132) (xy 335.361926 -279.528038) (xy 335.401348 -279.495851) (xy 335.445422 -279.470405)
			(xy 335.493008 -279.452358) (xy 335.542872 -279.442178) (xy 335.593724 -279.440129) (xy 335.644245 -279.446263)
			(xy 335.693129 -279.460423) (xy 335.739108 -279.48224) (xy 335.780992 -279.51115) (xy 335.817696 -279.546405)
			(xy 335.848269 -279.587091) (xy 335.87192 -279.632154) (xy 335.888036 -279.680428) (xy 335.8962 -279.730662)
			(xy 335.896712 -279.756108) (xy 336.21524 -279.756108) (xy 336.2192 -279.707054) (xy 336.230977 -279.65927)
			(xy 336.250268 -279.613994) (xy 336.276571 -279.572398) (xy 336.309206 -279.535561) (xy 336.347327 -279.504436)
			(xy 336.389948 -279.479829) (xy 336.435964 -279.462377) (xy 336.484183 -279.452533) (xy 336.533358 -279.450552)
			(xy 336.582213 -279.456484) (xy 336.629484 -279.470176) (xy 336.673946 -279.491274) (xy 336.714449 -279.51923)
			(xy 336.749942 -279.553322) (xy 336.779507 -279.592666) (xy 336.802378 -279.636243) (xy 336.817962 -279.682924)
			(xy 336.825857 -279.731501) (xy 336.826352 -279.756108) (xy 337.144863 -279.756108) (xy 337.148958 -279.70538)
			(xy 337.161137 -279.655966) (xy 337.181085 -279.609146) (xy 337.208286 -279.566132) (xy 337.242034 -279.528038)
			(xy 337.281456 -279.495851) (xy 337.32553 -279.470405) (xy 337.373116 -279.452358) (xy 337.42298 -279.442178)
			(xy 337.473832 -279.440129) (xy 337.524353 -279.446263) (xy 337.573237 -279.460423) (xy 337.619216 -279.48224)
			(xy 337.6611 -279.51115) (xy 337.697804 -279.546405) (xy 337.728377 -279.587091) (xy 337.752028 -279.632154)
			(xy 337.768144 -279.680428) (xy 337.776308 -279.730662) (xy 337.77682 -279.756108) (xy 338.095348 -279.756108)
			(xy 338.099308 -279.707054) (xy 338.111085 -279.65927) (xy 338.130376 -279.613994) (xy 338.156679 -279.572398)
			(xy 338.189314 -279.535561) (xy 338.227435 -279.504436) (xy 338.270056 -279.479829) (xy 338.316072 -279.462377)
			(xy 338.364291 -279.452533) (xy 338.413466 -279.450552) (xy 338.462321 -279.456484) (xy 338.509592 -279.470176)
			(xy 338.554054 -279.491274) (xy 338.594557 -279.51923) (xy 338.63005 -279.553322) (xy 338.659615 -279.592666)
			(xy 338.682486 -279.636243) (xy 338.69807 -279.682924) (xy 338.705965 -279.731501) (xy 338.70646 -279.756108)
			(xy 339.024971 -279.756108) (xy 339.029066 -279.70538) (xy 339.041245 -279.655966) (xy 339.061193 -279.609146)
			(xy 339.088394 -279.566132) (xy 339.122142 -279.528038) (xy 339.161564 -279.495851) (xy 339.205638 -279.470405)
			(xy 339.253224 -279.452358) (xy 339.303088 -279.442178) (xy 339.35394 -279.440129) (xy 339.404461 -279.446263)
			(xy 339.453345 -279.460423) (xy 339.499324 -279.48224) (xy 339.541208 -279.51115) (xy 339.577912 -279.546405)
			(xy 339.608485 -279.587091) (xy 339.632136 -279.632154) (xy 339.648252 -279.680428) (xy 339.656416 -279.730662)
			(xy 339.656928 -279.756108) (xy 339.964771 -279.756108) (xy 339.968866 -279.70538) (xy 339.981045 -279.655966)
			(xy 340.000993 -279.609146) (xy 340.028194 -279.566132) (xy 340.061942 -279.528038) (xy 340.101364 -279.495851)
			(xy 340.145438 -279.470405) (xy 340.193024 -279.452358) (xy 340.242888 -279.442178) (xy 340.29374 -279.440129)
			(xy 340.344261 -279.446263) (xy 340.393145 -279.460423) (xy 340.439124 -279.48224) (xy 340.481008 -279.51115)
			(xy 340.517712 -279.546405) (xy 340.548285 -279.587091) (xy 340.571936 -279.632154) (xy 340.588052 -279.680428)
			(xy 340.596216 -279.730662) (xy 340.596728 -279.756108) (xy 340.915256 -279.756108) (xy 340.919216 -279.707054)
			(xy 340.930993 -279.65927) (xy 340.950284 -279.613994) (xy 340.976587 -279.572398) (xy 341.009222 -279.535561)
			(xy 341.047343 -279.504436) (xy 341.089964 -279.479829) (xy 341.13598 -279.462377) (xy 341.184199 -279.452533)
			(xy 341.233374 -279.450552) (xy 341.282229 -279.456484) (xy 341.3295 -279.470176) (xy 341.373962 -279.491274)
			(xy 341.414465 -279.51923) (xy 341.449958 -279.553322) (xy 341.479523 -279.592666) (xy 341.502394 -279.636243)
			(xy 341.517978 -279.682924) (xy 341.525873 -279.731501) (xy 341.526368 -279.756108) (xy 341.844879 -279.756108)
			(xy 341.848974 -279.70538) (xy 341.861153 -279.655966) (xy 341.881101 -279.609146) (xy 341.908302 -279.566132)
			(xy 341.94205 -279.528038) (xy 341.981472 -279.495851) (xy 342.025546 -279.470405) (xy 342.073132 -279.452358)
			(xy 342.122996 -279.442178) (xy 342.173848 -279.440129) (xy 342.224369 -279.446263) (xy 342.273253 -279.460423)
			(xy 342.319232 -279.48224) (xy 342.361116 -279.51115) (xy 342.39782 -279.546405) (xy 342.428393 -279.587091)
			(xy 342.452044 -279.632154) (xy 342.46816 -279.680428) (xy 342.476324 -279.730662) (xy 342.476836 -279.756108)
			(xy 342.795364 -279.756108) (xy 342.799324 -279.707054) (xy 342.811101 -279.65927) (xy 342.830392 -279.613994)
			(xy 342.856695 -279.572398) (xy 342.88933 -279.535561) (xy 342.927451 -279.504436) (xy 342.970072 -279.479829)
			(xy 343.016088 -279.462377) (xy 343.064307 -279.452533) (xy 343.113482 -279.450552) (xy 343.162337 -279.456484)
			(xy 343.209608 -279.470176) (xy 343.25407 -279.491274) (xy 343.294573 -279.51923) (xy 343.330066 -279.553322)
			(xy 343.359631 -279.592666) (xy 343.382502 -279.636243) (xy 343.398086 -279.682924) (xy 343.405981 -279.731501)
			(xy 343.406476 -279.756108) (xy 343.724987 -279.756108) (xy 343.729082 -279.70538) (xy 343.741261 -279.655966)
			(xy 343.761209 -279.609146) (xy 343.78841 -279.566132) (xy 343.822158 -279.528038) (xy 343.86158 -279.495851)
			(xy 343.905654 -279.470405) (xy 343.95324 -279.452358) (xy 344.003104 -279.442178) (xy 344.053956 -279.440129)
			(xy 344.104477 -279.446263) (xy 344.153361 -279.460423) (xy 344.19934 -279.48224) (xy 344.241224 -279.51115)
			(xy 344.277928 -279.546405) (xy 344.308501 -279.587091) (xy 344.332152 -279.632154) (xy 344.348268 -279.680428)
			(xy 344.356432 -279.730662) (xy 344.356944 -279.756108) (xy 345.615272 -279.756108) (xy 345.619232 -279.707054)
			(xy 345.631009 -279.65927) (xy 345.6503 -279.613994) (xy 345.676603 -279.572398) (xy 345.709238 -279.535561)
			(xy 345.747359 -279.504436) (xy 345.78998 -279.479829) (xy 345.835996 -279.462377) (xy 345.884215 -279.452533)
			(xy 345.93339 -279.450552) (xy 345.982245 -279.456484) (xy 346.029516 -279.470176) (xy 346.073978 -279.491274)
			(xy 346.114481 -279.51923) (xy 346.149974 -279.553322) (xy 346.179539 -279.592666) (xy 346.20241 -279.636243)
			(xy 346.217994 -279.682924) (xy 346.225889 -279.731501) (xy 346.226384 -279.756108) (xy 346.555326 -279.756108)
			(xy 346.559286 -279.707054) (xy 346.571063 -279.65927) (xy 346.590354 -279.613994) (xy 346.616657 -279.572398)
			(xy 346.649292 -279.535561) (xy 346.687413 -279.504436) (xy 346.730034 -279.479829) (xy 346.77605 -279.462377)
			(xy 346.824269 -279.452533) (xy 346.873444 -279.450552) (xy 346.922299 -279.456484) (xy 346.96957 -279.470176)
			(xy 347.014032 -279.491274) (xy 347.054535 -279.51923) (xy 347.090028 -279.553322) (xy 347.119593 -279.592666)
			(xy 347.142464 -279.636243) (xy 347.158048 -279.682924) (xy 347.165943 -279.731501) (xy 347.166438 -279.756108)
			(xy 347.49538 -279.756108) (xy 347.49934 -279.707054) (xy 347.511117 -279.65927) (xy 347.530408 -279.613994)
			(xy 347.556711 -279.572398) (xy 347.589346 -279.535561) (xy 347.627467 -279.504436) (xy 347.670088 -279.479829)
			(xy 347.716104 -279.462377) (xy 347.764323 -279.452533) (xy 347.813498 -279.450552) (xy 347.862353 -279.456484)
			(xy 347.909624 -279.470176) (xy 347.954086 -279.491274) (xy 347.994589 -279.51923) (xy 348.030082 -279.553322)
			(xy 348.059647 -279.592666) (xy 348.082518 -279.636243) (xy 348.098102 -279.682924) (xy 348.105997 -279.731501)
			(xy 348.106492 -279.756108) (xy 348.435434 -279.756108) (xy 348.439394 -279.707054) (xy 348.451171 -279.65927)
			(xy 348.470462 -279.613994) (xy 348.496765 -279.572398) (xy 348.5294 -279.535561) (xy 348.567521 -279.504436)
			(xy 348.610142 -279.479829) (xy 348.656158 -279.462377) (xy 348.704377 -279.452533) (xy 348.753552 -279.450552)
			(xy 348.802407 -279.456484) (xy 348.849678 -279.470176) (xy 348.89414 -279.491274) (xy 348.934643 -279.51923)
			(xy 348.970136 -279.553322) (xy 348.999701 -279.592666) (xy 349.022572 -279.636243) (xy 349.038156 -279.682924)
			(xy 349.046051 -279.731501) (xy 349.046546 -279.756108) (xy 349.375234 -279.756108) (xy 349.379194 -279.707054)
			(xy 349.390971 -279.65927) (xy 349.410262 -279.613994) (xy 349.436565 -279.572398) (xy 349.4692 -279.535561)
			(xy 349.507321 -279.504436) (xy 349.549942 -279.479829) (xy 349.595958 -279.462377) (xy 349.644177 -279.452533)
			(xy 349.693352 -279.450552) (xy 349.742207 -279.456484) (xy 349.789478 -279.470176) (xy 349.83394 -279.491274)
			(xy 349.874443 -279.51923) (xy 349.909936 -279.553322) (xy 349.939501 -279.592666) (xy 349.962372 -279.636243)
			(xy 349.977956 -279.682924) (xy 349.985851 -279.731501) (xy 349.986346 -279.756108) (xy 350.315288 -279.756108)
			(xy 350.319248 -279.707054) (xy 350.331025 -279.65927) (xy 350.350316 -279.613994) (xy 350.376619 -279.572398)
			(xy 350.409254 -279.535561) (xy 350.447375 -279.504436) (xy 350.489996 -279.479829) (xy 350.536012 -279.462377)
			(xy 350.584231 -279.452533) (xy 350.633406 -279.450552) (xy 350.682261 -279.456484) (xy 350.729532 -279.470176)
			(xy 350.773994 -279.491274) (xy 350.814497 -279.51923) (xy 350.84999 -279.553322) (xy 350.879555 -279.592666)
			(xy 350.902426 -279.636243) (xy 350.91801 -279.682924) (xy 350.925905 -279.731501) (xy 350.9264 -279.756108)
			(xy 350.925905 -279.780715) (xy 350.91801 -279.829292) (xy 350.902426 -279.875973) (xy 350.879555 -279.91955)
			(xy 350.84999 -279.958894) (xy 350.814497 -279.992986) (xy 350.773994 -280.020942) (xy 350.729532 -280.04204)
			(xy 350.682261 -280.055732) (xy 350.633406 -280.061664) (xy 350.584231 -280.059683) (xy 350.536012 -280.049839)
			(xy 350.489996 -280.032387) (xy 350.447375 -280.00778) (xy 350.409254 -279.976655) (xy 350.376619 -279.939818)
			(xy 350.350316 -279.898222) (xy 350.331025 -279.852946) (xy 350.319248 -279.805162) (xy 350.315288 -279.756108)
			(xy 349.986346 -279.756108) (xy 349.985851 -279.780715) (xy 349.977956 -279.829292) (xy 349.962372 -279.875973)
			(xy 349.939501 -279.91955) (xy 349.909936 -279.958894) (xy 349.874443 -279.992986) (xy 349.83394 -280.020942)
			(xy 349.789478 -280.04204) (xy 349.742207 -280.055732) (xy 349.693352 -280.061664) (xy 349.644177 -280.059683)
			(xy 349.595958 -280.049839) (xy 349.549942 -280.032387) (xy 349.507321 -280.00778) (xy 349.4692 -279.976655)
			(xy 349.436565 -279.939818) (xy 349.410262 -279.898222) (xy 349.390971 -279.852946) (xy 349.379194 -279.805162)
			(xy 349.375234 -279.756108) (xy 349.046546 -279.756108) (xy 349.046051 -279.780715) (xy 349.038156 -279.829292)
			(xy 349.022572 -279.875973) (xy 348.999701 -279.91955) (xy 348.970136 -279.958894) (xy 348.934643 -279.992986)
			(xy 348.89414 -280.020942) (xy 348.849678 -280.04204) (xy 348.802407 -280.055732) (xy 348.753552 -280.061664)
			(xy 348.704377 -280.059683) (xy 348.656158 -280.049839) (xy 348.610142 -280.032387) (xy 348.567521 -280.00778)
			(xy 348.5294 -279.976655) (xy 348.496765 -279.939818) (xy 348.470462 -279.898222) (xy 348.451171 -279.852946)
			(xy 348.439394 -279.805162) (xy 348.435434 -279.756108) (xy 348.106492 -279.756108) (xy 348.105997 -279.780715)
			(xy 348.098102 -279.829292) (xy 348.082518 -279.875973) (xy 348.059647 -279.91955) (xy 348.030082 -279.958894)
			(xy 347.994589 -279.992986) (xy 347.954086 -280.020942) (xy 347.909624 -280.04204) (xy 347.862353 -280.055732)
			(xy 347.813498 -280.061664) (xy 347.764323 -280.059683) (xy 347.716104 -280.049839) (xy 347.670088 -280.032387)
			(xy 347.627467 -280.00778) (xy 347.589346 -279.976655) (xy 347.556711 -279.939818) (xy 347.530408 -279.898222)
			(xy 347.511117 -279.852946) (xy 347.49934 -279.805162) (xy 347.49538 -279.756108) (xy 347.166438 -279.756108)
			(xy 347.165943 -279.780715) (xy 347.158048 -279.829292) (xy 347.142464 -279.875973) (xy 347.119593 -279.91955)
			(xy 347.090028 -279.958894) (xy 347.054535 -279.992986) (xy 347.014032 -280.020942) (xy 346.96957 -280.04204)
			(xy 346.922299 -280.055732) (xy 346.873444 -280.061664) (xy 346.824269 -280.059683) (xy 346.77605 -280.049839)
			(xy 346.730034 -280.032387) (xy 346.687413 -280.00778) (xy 346.649292 -279.976655) (xy 346.616657 -279.939818)
			(xy 346.590354 -279.898222) (xy 346.571063 -279.852946) (xy 346.559286 -279.805162) (xy 346.555326 -279.756108)
			(xy 346.226384 -279.756108) (xy 346.225889 -279.780715) (xy 346.217994 -279.829292) (xy 346.20241 -279.875973)
			(xy 346.179539 -279.91955) (xy 346.149974 -279.958894) (xy 346.114481 -279.992986) (xy 346.073978 -280.020942)
			(xy 346.029516 -280.04204) (xy 345.982245 -280.055732) (xy 345.93339 -280.061664) (xy 345.884215 -280.059683)
			(xy 345.835996 -280.049839) (xy 345.78998 -280.032387) (xy 345.747359 -280.00778) (xy 345.709238 -279.976655)
			(xy 345.676603 -279.939818) (xy 345.6503 -279.898222) (xy 345.631009 -279.852946) (xy 345.619232 -279.805162)
			(xy 345.615272 -279.756108) (xy 344.356944 -279.756108) (xy 344.356432 -279.781554) (xy 344.348268 -279.831788)
			(xy 344.332152 -279.880062) (xy 344.308501 -279.925125) (xy 344.277928 -279.965811) (xy 344.241224 -280.001066)
			(xy 344.19934 -280.029976) (xy 344.153361 -280.051793) (xy 344.104477 -280.065953) (xy 344.053956 -280.072087)
			(xy 344.003104 -280.070038) (xy 343.95324 -280.059858) (xy 343.905654 -280.041811) (xy 343.86158 -280.016365)
			(xy 343.822158 -279.984178) (xy 343.78841 -279.946084) (xy 343.761209 -279.90307) (xy 343.741261 -279.85625)
			(xy 343.729082 -279.806836) (xy 343.724987 -279.756108) (xy 343.406476 -279.756108) (xy 343.405981 -279.780715)
			(xy 343.398086 -279.829292) (xy 343.382502 -279.875973) (xy 343.359631 -279.91955) (xy 343.330066 -279.958894)
			(xy 343.294573 -279.992986) (xy 343.25407 -280.020942) (xy 343.209608 -280.04204) (xy 343.162337 -280.055732)
			(xy 343.113482 -280.061664) (xy 343.064307 -280.059683) (xy 343.016088 -280.049839) (xy 342.970072 -280.032387)
			(xy 342.927451 -280.00778) (xy 342.88933 -279.976655) (xy 342.856695 -279.939818) (xy 342.830392 -279.898222)
			(xy 342.811101 -279.852946) (xy 342.799324 -279.805162) (xy 342.795364 -279.756108) (xy 342.476836 -279.756108)
			(xy 342.476324 -279.781554) (xy 342.46816 -279.831788) (xy 342.452044 -279.880062) (xy 342.428393 -279.925125)
			(xy 342.39782 -279.965811) (xy 342.361116 -280.001066) (xy 342.319232 -280.029976) (xy 342.273253 -280.051793)
			(xy 342.224369 -280.065953) (xy 342.173848 -280.072087) (xy 342.122996 -280.070038) (xy 342.073132 -280.059858)
			(xy 342.025546 -280.041811) (xy 341.981472 -280.016365) (xy 341.94205 -279.984178) (xy 341.908302 -279.946084)
			(xy 341.881101 -279.90307) (xy 341.861153 -279.85625) (xy 341.848974 -279.806836) (xy 341.844879 -279.756108)
			(xy 341.526368 -279.756108) (xy 341.525873 -279.780715) (xy 341.517978 -279.829292) (xy 341.502394 -279.875973)
			(xy 341.479523 -279.91955) (xy 341.449958 -279.958894) (xy 341.414465 -279.992986) (xy 341.373962 -280.020942)
			(xy 341.3295 -280.04204) (xy 341.282229 -280.055732) (xy 341.233374 -280.061664) (xy 341.184199 -280.059683)
			(xy 341.13598 -280.049839) (xy 341.089964 -280.032387) (xy 341.047343 -280.00778) (xy 341.009222 -279.976655)
			(xy 340.976587 -279.939818) (xy 340.950284 -279.898222) (xy 340.930993 -279.852946) (xy 340.919216 -279.805162)
			(xy 340.915256 -279.756108) (xy 340.596728 -279.756108) (xy 340.596216 -279.781554) (xy 340.588052 -279.831788)
			(xy 340.571936 -279.880062) (xy 340.548285 -279.925125) (xy 340.517712 -279.965811) (xy 340.481008 -280.001066)
			(xy 340.439124 -280.029976) (xy 340.393145 -280.051793) (xy 340.344261 -280.065953) (xy 340.29374 -280.072087)
			(xy 340.242888 -280.070038) (xy 340.193024 -280.059858) (xy 340.145438 -280.041811) (xy 340.101364 -280.016365)
			(xy 340.061942 -279.984178) (xy 340.028194 -279.946084) (xy 340.000993 -279.90307) (xy 339.981045 -279.85625)
			(xy 339.968866 -279.806836) (xy 339.964771 -279.756108) (xy 339.656928 -279.756108) (xy 339.656416 -279.781554)
			(xy 339.648252 -279.831788) (xy 339.632136 -279.880062) (xy 339.608485 -279.925125) (xy 339.577912 -279.965811)
			(xy 339.541208 -280.001066) (xy 339.499324 -280.029976) (xy 339.453345 -280.051793) (xy 339.404461 -280.065953)
			(xy 339.35394 -280.072087) (xy 339.303088 -280.070038) (xy 339.253224 -280.059858) (xy 339.205638 -280.041811)
			(xy 339.161564 -280.016365) (xy 339.122142 -279.984178) (xy 339.088394 -279.946084) (xy 339.061193 -279.90307)
			(xy 339.041245 -279.85625) (xy 339.029066 -279.806836) (xy 339.024971 -279.756108) (xy 338.70646 -279.756108)
			(xy 338.705965 -279.780715) (xy 338.69807 -279.829292) (xy 338.682486 -279.875973) (xy 338.659615 -279.91955)
			(xy 338.63005 -279.958894) (xy 338.594557 -279.992986) (xy 338.554054 -280.020942) (xy 338.509592 -280.04204)
			(xy 338.462321 -280.055732) (xy 338.413466 -280.061664) (xy 338.364291 -280.059683) (xy 338.316072 -280.049839)
			(xy 338.270056 -280.032387) (xy 338.227435 -280.00778) (xy 338.189314 -279.976655) (xy 338.156679 -279.939818)
			(xy 338.130376 -279.898222) (xy 338.111085 -279.852946) (xy 338.099308 -279.805162) (xy 338.095348 -279.756108)
			(xy 337.77682 -279.756108) (xy 337.776308 -279.781554) (xy 337.768144 -279.831788) (xy 337.752028 -279.880062)
			(xy 337.728377 -279.925125) (xy 337.697804 -279.965811) (xy 337.6611 -280.001066) (xy 337.619216 -280.029976)
			(xy 337.573237 -280.051793) (xy 337.524353 -280.065953) (xy 337.473832 -280.072087) (xy 337.42298 -280.070038)
			(xy 337.373116 -280.059858) (xy 337.32553 -280.041811) (xy 337.281456 -280.016365) (xy 337.242034 -279.984178)
			(xy 337.208286 -279.946084) (xy 337.181085 -279.90307) (xy 337.161137 -279.85625) (xy 337.148958 -279.806836)
			(xy 337.144863 -279.756108) (xy 336.826352 -279.756108) (xy 336.825857 -279.780715) (xy 336.817962 -279.829292)
			(xy 336.802378 -279.875973) (xy 336.779507 -279.91955) (xy 336.749942 -279.958894) (xy 336.714449 -279.992986)
			(xy 336.673946 -280.020942) (xy 336.629484 -280.04204) (xy 336.582213 -280.055732) (xy 336.533358 -280.061664)
			(xy 336.484183 -280.059683) (xy 336.435964 -280.049839) (xy 336.389948 -280.032387) (xy 336.347327 -280.00778)
			(xy 336.309206 -279.976655) (xy 336.276571 -279.939818) (xy 336.250268 -279.898222) (xy 336.230977 -279.852946)
			(xy 336.2192 -279.805162) (xy 336.21524 -279.756108) (xy 335.896712 -279.756108) (xy 335.8962 -279.781554)
			(xy 335.888036 -279.831788) (xy 335.87192 -279.880062) (xy 335.848269 -279.925125) (xy 335.817696 -279.965811)
			(xy 335.780992 -280.001066) (xy 335.739108 -280.029976) (xy 335.693129 -280.051793) (xy 335.644245 -280.065953)
			(xy 335.593724 -280.072087) (xy 335.542872 -280.070038) (xy 335.493008 -280.059858) (xy 335.445422 -280.041811)
			(xy 335.401348 -280.016365) (xy 335.361926 -279.984178) (xy 335.328178 -279.946084) (xy 335.300977 -279.90307)
			(xy 335.281029 -279.85625) (xy 335.26885 -279.806836) (xy 335.264755 -279.756108) (xy 334.946498 -279.756108)
			(xy 334.946003 -279.780715) (xy 334.938108 -279.829292) (xy 334.922524 -279.875973) (xy 334.899653 -279.91955)
			(xy 334.870088 -279.958894) (xy 334.834595 -279.992986) (xy 334.794092 -280.020942) (xy 334.74963 -280.04204)
			(xy 334.702359 -280.055732) (xy 334.653504 -280.061664) (xy 334.604329 -280.059683) (xy 334.55611 -280.049839)
			(xy 334.510094 -280.032387) (xy 334.467473 -280.00778) (xy 334.429352 -279.976655) (xy 334.396717 -279.939818)
			(xy 334.370414 -279.898222) (xy 334.351123 -279.852946) (xy 334.339346 -279.805162) (xy 334.335386 -279.756108)
			(xy 334.016858 -279.756108) (xy 334.016346 -279.781554) (xy 334.008182 -279.831788) (xy 333.992066 -279.880062)
			(xy 333.968415 -279.925125) (xy 333.937842 -279.965811) (xy 333.901138 -280.001066) (xy 333.859254 -280.029976)
			(xy 333.813275 -280.051793) (xy 333.764391 -280.065953) (xy 333.71387 -280.072087) (xy 333.663018 -280.070038)
			(xy 333.613154 -280.059858) (xy 333.565568 -280.041811) (xy 333.521494 -280.016365) (xy 333.482072 -279.984178)
			(xy 333.448324 -279.946084) (xy 333.421123 -279.90307) (xy 333.401175 -279.85625) (xy 333.388996 -279.806836)
			(xy 333.384901 -279.756108) (xy 333.076804 -279.756108) (xy 333.076292 -279.781554) (xy 333.068128 -279.831788)
			(xy 333.052012 -279.880062) (xy 333.028361 -279.925125) (xy 332.997788 -279.965811) (xy 332.961084 -280.001066)
			(xy 332.9192 -280.029976) (xy 332.873221 -280.051793) (xy 332.824337 -280.065953) (xy 332.773816 -280.072087)
			(xy 332.722964 -280.070038) (xy 332.6731 -280.059858) (xy 332.625514 -280.041811) (xy 332.58144 -280.016365)
			(xy 332.542018 -279.984178) (xy 332.50827 -279.946084) (xy 332.481069 -279.90307) (xy 332.461121 -279.85625)
			(xy 332.448942 -279.806836) (xy 332.444847 -279.756108) (xy 332.126336 -279.756108) (xy 332.125841 -279.780715)
			(xy 332.117946 -279.829292) (xy 332.102362 -279.875973) (xy 332.079491 -279.91955) (xy 332.049926 -279.958894)
			(xy 332.014433 -279.992986) (xy 331.97393 -280.020942) (xy 331.929468 -280.04204) (xy 331.882197 -280.055732)
			(xy 331.833342 -280.061664) (xy 331.784167 -280.059683) (xy 331.735948 -280.049839) (xy 331.689932 -280.032387)
			(xy 331.647311 -280.00778) (xy 331.60919 -279.976655) (xy 331.576555 -279.939818) (xy 331.550252 -279.898222)
			(xy 331.530961 -279.852946) (xy 331.519184 -279.805162) (xy 331.515224 -279.756108) (xy 331.196696 -279.756108)
			(xy 331.196184 -279.781554) (xy 331.18802 -279.831788) (xy 331.171904 -279.880062) (xy 331.148253 -279.925125)
			(xy 331.11768 -279.965811) (xy 331.080976 -280.001066) (xy 331.039092 -280.029976) (xy 330.993113 -280.051793)
			(xy 330.944229 -280.065953) (xy 330.893708 -280.072087) (xy 330.842856 -280.070038) (xy 330.792992 -280.059858)
			(xy 330.745406 -280.041811) (xy 330.701332 -280.016365) (xy 330.66191 -279.984178) (xy 330.628162 -279.946084)
			(xy 330.600961 -279.90307) (xy 330.581013 -279.85625) (xy 330.568834 -279.806836) (xy 330.564739 -279.756108)
			(xy 330.246482 -279.756108) (xy 330.245987 -279.780715) (xy 330.238092 -279.829292) (xy 330.222508 -279.875973)
			(xy 330.199637 -279.91955) (xy 330.170072 -279.958894) (xy 330.134579 -279.992986) (xy 330.094076 -280.020942)
			(xy 330.049614 -280.04204) (xy 330.002343 -280.055732) (xy 329.953488 -280.061664) (xy 329.904313 -280.059683)
			(xy 329.856094 -280.049839) (xy 329.810078 -280.032387) (xy 329.767457 -280.00778) (xy 329.729336 -279.976655)
			(xy 329.696701 -279.939818) (xy 329.670398 -279.898222) (xy 329.651107 -279.852946) (xy 329.63933 -279.805162)
			(xy 329.63537 -279.756108) (xy 329.316842 -279.756108) (xy 329.31633 -279.781554) (xy 329.308166 -279.831788)
			(xy 329.29205 -279.880062) (xy 329.268399 -279.925125) (xy 329.237826 -279.965811) (xy 329.201122 -280.001066)
			(xy 329.159238 -280.029976) (xy 329.113259 -280.051793) (xy 329.064375 -280.065953) (xy 329.013854 -280.072087)
			(xy 328.963002 -280.070038) (xy 328.913138 -280.059858) (xy 328.865552 -280.041811) (xy 328.821478 -280.016365)
			(xy 328.782056 -279.984178) (xy 328.748308 -279.946084) (xy 328.721107 -279.90307) (xy 328.701159 -279.85625)
			(xy 328.68898 -279.806836) (xy 328.684885 -279.756108) (xy 328.366374 -279.756108) (xy 328.365879 -279.780715)
			(xy 328.357984 -279.829292) (xy 328.3424 -279.875973) (xy 328.319529 -279.91955) (xy 328.289964 -279.958894)
			(xy 328.254471 -279.992986) (xy 328.213968 -280.020942) (xy 328.169506 -280.04204) (xy 328.122235 -280.055732)
			(xy 328.07338 -280.061664) (xy 328.024205 -280.059683) (xy 327.975986 -280.049839) (xy 327.92997 -280.032387)
			(xy 327.887349 -280.00778) (xy 327.849228 -279.976655) (xy 327.816593 -279.939818) (xy 327.79029 -279.898222)
			(xy 327.770999 -279.852946) (xy 327.759222 -279.805162) (xy 327.755262 -279.756108) (xy 325.203519 -279.756108)
			(xy 325.161384 -279.776102) (xy 325.114113 -279.789794) (xy 325.065258 -279.795726) (xy 325.016083 -279.793745)
			(xy 324.967864 -279.783901) (xy 324.921848 -279.766449) (xy 324.879227 -279.741842) (xy 324.841106 -279.710717)
			(xy 324.808471 -279.67388) (xy 324.782168 -279.632284) (xy 324.762877 -279.587008) (xy 324.7511 -279.539224)
			(xy 324.74714 -279.49017) (xy 310.45912 -279.49017) (xy 310.45912 -280.566114) (xy 326.345308 -280.566114)
			(xy 326.349268 -280.51706) (xy 326.361045 -280.469276) (xy 326.380336 -280.424) (xy 326.406639 -280.382404)
			(xy 326.439274 -280.345567) (xy 326.477395 -280.314442) (xy 326.520016 -280.289835) (xy 326.566032 -280.272383)
			(xy 326.614251 -280.262539) (xy 326.663426 -280.260558) (xy 326.712281 -280.26649) (xy 326.759552 -280.280182)
			(xy 326.804014 -280.30128) (xy 326.844517 -280.329236) (xy 326.88001 -280.363328) (xy 326.909575 -280.402672)
			(xy 326.932446 -280.446249) (xy 326.94803 -280.49293) (xy 326.955925 -280.541507) (xy 326.95642 -280.566114)
			(xy 329.154785 -280.566114) (xy 329.15888 -280.515386) (xy 329.171059 -280.465972) (xy 329.191007 -280.419152)
			(xy 329.218208 -280.376138) (xy 329.251956 -280.338044) (xy 329.291378 -280.305857) (xy 329.335452 -280.280411)
			(xy 329.383038 -280.262364) (xy 329.432902 -280.252184) (xy 329.483754 -280.250135) (xy 329.534275 -280.256269)
			(xy 329.583159 -280.270429) (xy 329.629138 -280.292246) (xy 329.671022 -280.321156) (xy 329.707726 -280.356411)
			(xy 329.738299 -280.397097) (xy 329.76195 -280.44216) (xy 329.778066 -280.490434) (xy 329.78623 -280.540668)
			(xy 329.786742 -280.566114) (xy 330.094839 -280.566114) (xy 330.098934 -280.515386) (xy 330.111113 -280.465972)
			(xy 330.131061 -280.419152) (xy 330.158262 -280.376138) (xy 330.19201 -280.338044) (xy 330.231432 -280.305857)
			(xy 330.275506 -280.280411) (xy 330.323092 -280.262364) (xy 330.372956 -280.252184) (xy 330.423808 -280.250135)
			(xy 330.474329 -280.256269) (xy 330.523213 -280.270429) (xy 330.569192 -280.292246) (xy 330.611076 -280.321156)
			(xy 330.64778 -280.356411) (xy 330.678353 -280.397097) (xy 330.702004 -280.44216) (xy 330.71812 -280.490434)
			(xy 330.726284 -280.540668) (xy 330.726796 -280.566114) (xy 331.045324 -280.566114) (xy 331.049284 -280.51706)
			(xy 331.061061 -280.469276) (xy 331.080352 -280.424) (xy 331.106655 -280.382404) (xy 331.13929 -280.345567)
			(xy 331.177411 -280.314442) (xy 331.220032 -280.289835) (xy 331.266048 -280.272383) (xy 331.314267 -280.262539)
			(xy 331.363442 -280.260558) (xy 331.412297 -280.26649) (xy 331.459568 -280.280182) (xy 331.50403 -280.30128)
			(xy 331.544533 -280.329236) (xy 331.580026 -280.363328) (xy 331.609591 -280.402672) (xy 331.632462 -280.446249)
			(xy 331.648046 -280.49293) (xy 331.655941 -280.541507) (xy 331.656436 -280.566114) (xy 331.974947 -280.566114)
			(xy 331.979042 -280.515386) (xy 331.991221 -280.465972) (xy 332.011169 -280.419152) (xy 332.03837 -280.376138)
			(xy 332.072118 -280.338044) (xy 332.11154 -280.305857) (xy 332.155614 -280.280411) (xy 332.2032 -280.262364)
			(xy 332.253064 -280.252184) (xy 332.303916 -280.250135) (xy 332.354437 -280.256269) (xy 332.403321 -280.270429)
			(xy 332.4493 -280.292246) (xy 332.491184 -280.321156) (xy 332.527888 -280.356411) (xy 332.558461 -280.397097)
			(xy 332.582112 -280.44216) (xy 332.598228 -280.490434) (xy 332.606392 -280.540668) (xy 332.606904 -280.566114)
			(xy 332.925178 -280.566114) (xy 332.929138 -280.51706) (xy 332.940915 -280.469276) (xy 332.960206 -280.424)
			(xy 332.986509 -280.382404) (xy 333.019144 -280.345567) (xy 333.057265 -280.314442) (xy 333.099886 -280.289835)
			(xy 333.145902 -280.272383) (xy 333.194121 -280.262539) (xy 333.243296 -280.260558) (xy 333.292151 -280.26649)
			(xy 333.339422 -280.280182) (xy 333.383884 -280.30128) (xy 333.424387 -280.329236) (xy 333.45988 -280.363328)
			(xy 333.489445 -280.402672) (xy 333.512316 -280.446249) (xy 333.5279 -280.49293) (xy 333.535795 -280.541507)
			(xy 333.53629 -280.566114) (xy 333.854801 -280.566114) (xy 333.858896 -280.515386) (xy 333.871075 -280.465972)
			(xy 333.891023 -280.419152) (xy 333.918224 -280.376138) (xy 333.951972 -280.338044) (xy 333.991394 -280.305857)
			(xy 334.035468 -280.280411) (xy 334.083054 -280.262364) (xy 334.132918 -280.252184) (xy 334.18377 -280.250135)
			(xy 334.234291 -280.256269) (xy 334.283175 -280.270429) (xy 334.329154 -280.292246) (xy 334.371038 -280.321156)
			(xy 334.407742 -280.356411) (xy 334.438315 -280.397097) (xy 334.461966 -280.44216) (xy 334.478082 -280.490434)
			(xy 334.486246 -280.540668) (xy 334.486758 -280.566114) (xy 335.734909 -280.566114) (xy 335.739004 -280.515386)
			(xy 335.751183 -280.465972) (xy 335.771131 -280.419152) (xy 335.798332 -280.376138) (xy 335.83208 -280.338044)
			(xy 335.871502 -280.305857) (xy 335.915576 -280.280411) (xy 335.963162 -280.262364) (xy 336.013026 -280.252184)
			(xy 336.063878 -280.250135) (xy 336.114399 -280.256269) (xy 336.163283 -280.270429) (xy 336.209262 -280.292246)
			(xy 336.251146 -280.321156) (xy 336.28785 -280.356411) (xy 336.318423 -280.397097) (xy 336.342074 -280.44216)
			(xy 336.35819 -280.490434) (xy 336.366354 -280.540668) (xy 336.366866 -280.566114) (xy 336.674963 -280.566114)
			(xy 336.679058 -280.515386) (xy 336.691237 -280.465972) (xy 336.711185 -280.419152) (xy 336.738386 -280.376138)
			(xy 336.772134 -280.338044) (xy 336.811556 -280.305857) (xy 336.85563 -280.280411) (xy 336.903216 -280.262364)
			(xy 336.95308 -280.252184) (xy 337.003932 -280.250135) (xy 337.054453 -280.256269) (xy 337.103337 -280.270429)
			(xy 337.149316 -280.292246) (xy 337.1912 -280.321156) (xy 337.227904 -280.356411) (xy 337.258477 -280.397097)
			(xy 337.282128 -280.44216) (xy 337.298244 -280.490434) (xy 337.306408 -280.540668) (xy 337.30692 -280.566114)
			(xy 337.625194 -280.566114) (xy 337.629154 -280.51706) (xy 337.640931 -280.469276) (xy 337.660222 -280.424)
			(xy 337.686525 -280.382404) (xy 337.71916 -280.345567) (xy 337.757281 -280.314442) (xy 337.799902 -280.289835)
			(xy 337.845918 -280.272383) (xy 337.894137 -280.262539) (xy 337.943312 -280.260558) (xy 337.992167 -280.26649)
			(xy 338.039438 -280.280182) (xy 338.0839 -280.30128) (xy 338.124403 -280.329236) (xy 338.159896 -280.363328)
			(xy 338.189461 -280.402672) (xy 338.212332 -280.446249) (xy 338.227916 -280.49293) (xy 338.235811 -280.541507)
			(xy 338.236306 -280.566114) (xy 338.554817 -280.566114) (xy 338.558912 -280.515386) (xy 338.571091 -280.465972)
			(xy 338.591039 -280.419152) (xy 338.61824 -280.376138) (xy 338.651988 -280.338044) (xy 338.69141 -280.305857)
			(xy 338.735484 -280.280411) (xy 338.78307 -280.262364) (xy 338.832934 -280.252184) (xy 338.883786 -280.250135)
			(xy 338.934307 -280.256269) (xy 338.983191 -280.270429) (xy 339.02917 -280.292246) (xy 339.071054 -280.321156)
			(xy 339.107758 -280.356411) (xy 339.138331 -280.397097) (xy 339.161982 -280.44216) (xy 339.178098 -280.490434)
			(xy 339.186262 -280.540668) (xy 339.186774 -280.566114) (xy 339.505302 -280.566114) (xy 339.509262 -280.51706)
			(xy 339.521039 -280.469276) (xy 339.54033 -280.424) (xy 339.566633 -280.382404) (xy 339.599268 -280.345567)
			(xy 339.637389 -280.314442) (xy 339.68001 -280.289835) (xy 339.726026 -280.272383) (xy 339.774245 -280.262539)
			(xy 339.82342 -280.260558) (xy 339.872275 -280.26649) (xy 339.919546 -280.280182) (xy 339.964008 -280.30128)
			(xy 340.004511 -280.329236) (xy 340.040004 -280.363328) (xy 340.069569 -280.402672) (xy 340.09244 -280.446249)
			(xy 340.108024 -280.49293) (xy 340.115919 -280.541507) (xy 340.116414 -280.566114) (xy 340.434925 -280.566114)
			(xy 340.43902 -280.515386) (xy 340.451199 -280.465972) (xy 340.471147 -280.419152) (xy 340.498348 -280.376138)
			(xy 340.532096 -280.338044) (xy 340.571518 -280.305857) (xy 340.615592 -280.280411) (xy 340.663178 -280.262364)
			(xy 340.713042 -280.252184) (xy 340.763894 -280.250135) (xy 340.814415 -280.256269) (xy 340.863299 -280.270429)
			(xy 340.909278 -280.292246) (xy 340.951162 -280.321156) (xy 340.987866 -280.356411) (xy 341.018439 -280.397097)
			(xy 341.04209 -280.44216) (xy 341.058206 -280.490434) (xy 341.06637 -280.540668) (xy 341.066882 -280.566114)
			(xy 342.314779 -280.566114) (xy 342.318874 -280.515386) (xy 342.331053 -280.465972) (xy 342.351001 -280.419152)
			(xy 342.378202 -280.376138) (xy 342.41195 -280.338044) (xy 342.451372 -280.305857) (xy 342.495446 -280.280411)
			(xy 342.543032 -280.262364) (xy 342.592896 -280.252184) (xy 342.643748 -280.250135) (xy 342.694269 -280.256269)
			(xy 342.743153 -280.270429) (xy 342.789132 -280.292246) (xy 342.831016 -280.321156) (xy 342.86772 -280.356411)
			(xy 342.898293 -280.397097) (xy 342.921944 -280.44216) (xy 342.93806 -280.490434) (xy 342.946224 -280.540668)
			(xy 342.946736 -280.566114) (xy 343.254833 -280.566114) (xy 343.258928 -280.515386) (xy 343.271107 -280.465972)
			(xy 343.291055 -280.419152) (xy 343.318256 -280.376138) (xy 343.352004 -280.338044) (xy 343.391426 -280.305857)
			(xy 343.4355 -280.280411) (xy 343.483086 -280.262364) (xy 343.53295 -280.252184) (xy 343.583802 -280.250135)
			(xy 343.634323 -280.256269) (xy 343.683207 -280.270429) (xy 343.729186 -280.292246) (xy 343.77107 -280.321156)
			(xy 343.807774 -280.356411) (xy 343.838347 -280.397097) (xy 343.861998 -280.44216) (xy 343.878114 -280.490434)
			(xy 343.886278 -280.540668) (xy 343.88679 -280.566114) (xy 344.205318 -280.566114) (xy 344.209278 -280.51706)
			(xy 344.221055 -280.469276) (xy 344.240346 -280.424) (xy 344.266649 -280.382404) (xy 344.299284 -280.345567)
			(xy 344.337405 -280.314442) (xy 344.380026 -280.289835) (xy 344.426042 -280.272383) (xy 344.474261 -280.262539)
			(xy 344.523436 -280.260558) (xy 344.572291 -280.26649) (xy 344.619562 -280.280182) (xy 344.664024 -280.30128)
			(xy 344.704527 -280.329236) (xy 344.74002 -280.363328) (xy 344.769585 -280.402672) (xy 344.792456 -280.446249)
			(xy 344.80804 -280.49293) (xy 344.815935 -280.541507) (xy 344.81643 -280.566114) (xy 345.145372 -280.566114)
			(xy 345.149332 -280.51706) (xy 345.161109 -280.469276) (xy 345.1804 -280.424) (xy 345.206703 -280.382404)
			(xy 345.239338 -280.345567) (xy 345.277459 -280.314442) (xy 345.32008 -280.289835) (xy 345.366096 -280.272383)
			(xy 345.414315 -280.262539) (xy 345.46349 -280.260558) (xy 345.512345 -280.26649) (xy 345.559616 -280.280182)
			(xy 345.604078 -280.30128) (xy 345.644581 -280.329236) (xy 345.680074 -280.363328) (xy 345.709639 -280.402672)
			(xy 345.73251 -280.446249) (xy 345.748094 -280.49293) (xy 345.755989 -280.541507) (xy 345.756484 -280.566114)
			(xy 346.085426 -280.566114) (xy 346.089386 -280.51706) (xy 346.101163 -280.469276) (xy 346.120454 -280.424)
			(xy 346.146757 -280.382404) (xy 346.179392 -280.345567) (xy 346.217513 -280.314442) (xy 346.260134 -280.289835)
			(xy 346.30615 -280.272383) (xy 346.354369 -280.262539) (xy 346.403544 -280.260558) (xy 346.452399 -280.26649)
			(xy 346.49967 -280.280182) (xy 346.544132 -280.30128) (xy 346.584635 -280.329236) (xy 346.620128 -280.363328)
			(xy 346.649693 -280.402672) (xy 346.672564 -280.446249) (xy 346.688148 -280.49293) (xy 346.696043 -280.541507)
			(xy 346.696538 -280.566114) (xy 347.025226 -280.566114) (xy 347.029186 -280.51706) (xy 347.040963 -280.469276)
			(xy 347.060254 -280.424) (xy 347.086557 -280.382404) (xy 347.119192 -280.345567) (xy 347.157313 -280.314442)
			(xy 347.199934 -280.289835) (xy 347.24595 -280.272383) (xy 347.294169 -280.262539) (xy 347.343344 -280.260558)
			(xy 347.392199 -280.26649) (xy 347.43947 -280.280182) (xy 347.483932 -280.30128) (xy 347.524435 -280.329236)
			(xy 347.559928 -280.363328) (xy 347.589493 -280.402672) (xy 347.612364 -280.446249) (xy 347.627948 -280.49293)
			(xy 347.635843 -280.541507) (xy 347.636338 -280.566114) (xy 347.96528 -280.566114) (xy 347.96924 -280.51706)
			(xy 347.981017 -280.469276) (xy 348.000308 -280.424) (xy 348.026611 -280.382404) (xy 348.059246 -280.345567)
			(xy 348.097367 -280.314442) (xy 348.139988 -280.289835) (xy 348.186004 -280.272383) (xy 348.234223 -280.262539)
			(xy 348.283398 -280.260558) (xy 348.332253 -280.26649) (xy 348.379524 -280.280182) (xy 348.423986 -280.30128)
			(xy 348.464489 -280.329236) (xy 348.499982 -280.363328) (xy 348.529547 -280.402672) (xy 348.552418 -280.446249)
			(xy 348.568002 -280.49293) (xy 348.575897 -280.541507) (xy 348.576392 -280.566114) (xy 348.905334 -280.566114)
			(xy 348.909294 -280.51706) (xy 348.921071 -280.469276) (xy 348.940362 -280.424) (xy 348.966665 -280.382404)
			(xy 348.9993 -280.345567) (xy 349.037421 -280.314442) (xy 349.080042 -280.289835) (xy 349.126058 -280.272383)
			(xy 349.174277 -280.262539) (xy 349.223452 -280.260558) (xy 349.272307 -280.26649) (xy 349.319578 -280.280182)
			(xy 349.36404 -280.30128) (xy 349.404543 -280.329236) (xy 349.440036 -280.363328) (xy 349.469601 -280.402672)
			(xy 349.492472 -280.446249) (xy 349.508056 -280.49293) (xy 349.515951 -280.541507) (xy 349.516446 -280.566114)
			(xy 349.845388 -280.566114) (xy 349.849348 -280.51706) (xy 349.861125 -280.469276) (xy 349.880416 -280.424)
			(xy 349.906719 -280.382404) (xy 349.939354 -280.345567) (xy 349.977475 -280.314442) (xy 350.020096 -280.289835)
			(xy 350.066112 -280.272383) (xy 350.114331 -280.262539) (xy 350.163506 -280.260558) (xy 350.212361 -280.26649)
			(xy 350.259632 -280.280182) (xy 350.304094 -280.30128) (xy 350.344597 -280.329236) (xy 350.38009 -280.363328)
			(xy 350.409655 -280.402672) (xy 350.432526 -280.446249) (xy 350.44811 -280.49293) (xy 350.456005 -280.541507)
			(xy 350.4565 -280.566114) (xy 350.785442 -280.566114) (xy 350.789402 -280.51706) (xy 350.801179 -280.469276)
			(xy 350.82047 -280.424) (xy 350.846773 -280.382404) (xy 350.879408 -280.345567) (xy 350.917529 -280.314442)
			(xy 350.96015 -280.289835) (xy 351.006166 -280.272383) (xy 351.054385 -280.262539) (xy 351.10356 -280.260558)
			(xy 351.152415 -280.26649) (xy 351.199686 -280.280182) (xy 351.244148 -280.30128) (xy 351.284651 -280.329236)
			(xy 351.320144 -280.363328) (xy 351.349709 -280.402672) (xy 351.37258 -280.446249) (xy 351.388164 -280.49293)
			(xy 351.396059 -280.541507) (xy 351.396554 -280.566114) (xy 351.396059 -280.590721) (xy 351.388164 -280.639298)
			(xy 351.37258 -280.685979) (xy 351.349709 -280.729556) (xy 351.320144 -280.7689) (xy 351.284651 -280.802992)
			(xy 351.244148 -280.830948) (xy 351.199686 -280.852046) (xy 351.152415 -280.865738) (xy 351.10356 -280.87167)
			(xy 351.054385 -280.869689) (xy 351.006166 -280.859845) (xy 350.96015 -280.842393) (xy 350.917529 -280.817786)
			(xy 350.879408 -280.786661) (xy 350.846773 -280.749824) (xy 350.82047 -280.708228) (xy 350.801179 -280.662952)
			(xy 350.789402 -280.615168) (xy 350.785442 -280.566114) (xy 350.4565 -280.566114) (xy 350.456005 -280.590721)
			(xy 350.44811 -280.639298) (xy 350.432526 -280.685979) (xy 350.409655 -280.729556) (xy 350.38009 -280.7689)
			(xy 350.344597 -280.802992) (xy 350.304094 -280.830948) (xy 350.259632 -280.852046) (xy 350.212361 -280.865738)
			(xy 350.163506 -280.87167) (xy 350.114331 -280.869689) (xy 350.066112 -280.859845) (xy 350.020096 -280.842393)
			(xy 349.977475 -280.817786) (xy 349.939354 -280.786661) (xy 349.906719 -280.749824) (xy 349.880416 -280.708228)
			(xy 349.861125 -280.662952) (xy 349.849348 -280.615168) (xy 349.845388 -280.566114) (xy 349.516446 -280.566114)
			(xy 349.515951 -280.590721) (xy 349.508056 -280.639298) (xy 349.492472 -280.685979) (xy 349.469601 -280.729556)
			(xy 349.440036 -280.7689) (xy 349.404543 -280.802992) (xy 349.36404 -280.830948) (xy 349.319578 -280.852046)
			(xy 349.272307 -280.865738) (xy 349.223452 -280.87167) (xy 349.174277 -280.869689) (xy 349.126058 -280.859845)
			(xy 349.080042 -280.842393) (xy 349.037421 -280.817786) (xy 348.9993 -280.786661) (xy 348.966665 -280.749824)
			(xy 348.940362 -280.708228) (xy 348.921071 -280.662952) (xy 348.909294 -280.615168) (xy 348.905334 -280.566114)
			(xy 348.576392 -280.566114) (xy 348.575897 -280.590721) (xy 348.568002 -280.639298) (xy 348.552418 -280.685979)
			(xy 348.529547 -280.729556) (xy 348.499982 -280.7689) (xy 348.464489 -280.802992) (xy 348.423986 -280.830948)
			(xy 348.379524 -280.852046) (xy 348.332253 -280.865738) (xy 348.283398 -280.87167) (xy 348.234223 -280.869689)
			(xy 348.186004 -280.859845) (xy 348.139988 -280.842393) (xy 348.097367 -280.817786) (xy 348.059246 -280.786661)
			(xy 348.026611 -280.749824) (xy 348.000308 -280.708228) (xy 347.981017 -280.662952) (xy 347.96924 -280.615168)
			(xy 347.96528 -280.566114) (xy 347.636338 -280.566114) (xy 347.635843 -280.590721) (xy 347.627948 -280.639298)
			(xy 347.612364 -280.685979) (xy 347.589493 -280.729556) (xy 347.559928 -280.7689) (xy 347.524435 -280.802992)
			(xy 347.483932 -280.830948) (xy 347.43947 -280.852046) (xy 347.392199 -280.865738) (xy 347.343344 -280.87167)
			(xy 347.294169 -280.869689) (xy 347.24595 -280.859845) (xy 347.199934 -280.842393) (xy 347.157313 -280.817786)
			(xy 347.119192 -280.786661) (xy 347.086557 -280.749824) (xy 347.060254 -280.708228) (xy 347.040963 -280.662952)
			(xy 347.029186 -280.615168) (xy 347.025226 -280.566114) (xy 346.696538 -280.566114) (xy 346.696043 -280.590721)
			(xy 346.688148 -280.639298) (xy 346.672564 -280.685979) (xy 346.649693 -280.729556) (xy 346.620128 -280.7689)
			(xy 346.584635 -280.802992) (xy 346.544132 -280.830948) (xy 346.49967 -280.852046) (xy 346.452399 -280.865738)
			(xy 346.403544 -280.87167) (xy 346.354369 -280.869689) (xy 346.30615 -280.859845) (xy 346.260134 -280.842393)
			(xy 346.217513 -280.817786) (xy 346.179392 -280.786661) (xy 346.146757 -280.749824) (xy 346.120454 -280.708228)
			(xy 346.101163 -280.662952) (xy 346.089386 -280.615168) (xy 346.085426 -280.566114) (xy 345.756484 -280.566114)
			(xy 345.755989 -280.590721) (xy 345.748094 -280.639298) (xy 345.73251 -280.685979) (xy 345.709639 -280.729556)
			(xy 345.680074 -280.7689) (xy 345.644581 -280.802992) (xy 345.604078 -280.830948) (xy 345.559616 -280.852046)
			(xy 345.512345 -280.865738) (xy 345.46349 -280.87167) (xy 345.414315 -280.869689) (xy 345.366096 -280.859845)
			(xy 345.32008 -280.842393) (xy 345.277459 -280.817786) (xy 345.239338 -280.786661) (xy 345.206703 -280.749824)
			(xy 345.1804 -280.708228) (xy 345.161109 -280.662952) (xy 345.149332 -280.615168) (xy 345.145372 -280.566114)
			(xy 344.81643 -280.566114) (xy 344.815935 -280.590721) (xy 344.80804 -280.639298) (xy 344.792456 -280.685979)
			(xy 344.769585 -280.729556) (xy 344.74002 -280.7689) (xy 344.704527 -280.802992) (xy 344.664024 -280.830948)
			(xy 344.619562 -280.852046) (xy 344.572291 -280.865738) (xy 344.523436 -280.87167) (xy 344.474261 -280.869689)
			(xy 344.426042 -280.859845) (xy 344.380026 -280.842393) (xy 344.337405 -280.817786) (xy 344.299284 -280.786661)
			(xy 344.266649 -280.749824) (xy 344.240346 -280.708228) (xy 344.221055 -280.662952) (xy 344.209278 -280.615168)
			(xy 344.205318 -280.566114) (xy 343.88679 -280.566114) (xy 343.886278 -280.59156) (xy 343.878114 -280.641794)
			(xy 343.861998 -280.690068) (xy 343.838347 -280.735131) (xy 343.807774 -280.775817) (xy 343.77107 -280.811072)
			(xy 343.729186 -280.839982) (xy 343.683207 -280.861799) (xy 343.634323 -280.875959) (xy 343.583802 -280.882093)
			(xy 343.53295 -280.880044) (xy 343.483086 -280.869864) (xy 343.4355 -280.851817) (xy 343.391426 -280.826371)
			(xy 343.352004 -280.794184) (xy 343.318256 -280.75609) (xy 343.291055 -280.713076) (xy 343.271107 -280.666256)
			(xy 343.258928 -280.616842) (xy 343.254833 -280.566114) (xy 342.946736 -280.566114) (xy 342.946224 -280.59156)
			(xy 342.93806 -280.641794) (xy 342.921944 -280.690068) (xy 342.898293 -280.735131) (xy 342.86772 -280.775817)
			(xy 342.831016 -280.811072) (xy 342.789132 -280.839982) (xy 342.743153 -280.861799) (xy 342.694269 -280.875959)
			(xy 342.643748 -280.882093) (xy 342.592896 -280.880044) (xy 342.543032 -280.869864) (xy 342.495446 -280.851817)
			(xy 342.451372 -280.826371) (xy 342.41195 -280.794184) (xy 342.378202 -280.75609) (xy 342.351001 -280.713076)
			(xy 342.331053 -280.666256) (xy 342.318874 -280.616842) (xy 342.314779 -280.566114) (xy 341.066882 -280.566114)
			(xy 341.06637 -280.59156) (xy 341.058206 -280.641794) (xy 341.04209 -280.690068) (xy 341.018439 -280.735131)
			(xy 340.987866 -280.775817) (xy 340.951162 -280.811072) (xy 340.909278 -280.839982) (xy 340.863299 -280.861799)
			(xy 340.814415 -280.875959) (xy 340.763894 -280.882093) (xy 340.713042 -280.880044) (xy 340.663178 -280.869864)
			(xy 340.615592 -280.851817) (xy 340.571518 -280.826371) (xy 340.532096 -280.794184) (xy 340.498348 -280.75609)
			(xy 340.471147 -280.713076) (xy 340.451199 -280.666256) (xy 340.43902 -280.616842) (xy 340.434925 -280.566114)
			(xy 340.116414 -280.566114) (xy 340.115919 -280.590721) (xy 340.108024 -280.639298) (xy 340.09244 -280.685979)
			(xy 340.069569 -280.729556) (xy 340.040004 -280.7689) (xy 340.004511 -280.802992) (xy 339.964008 -280.830948)
			(xy 339.919546 -280.852046) (xy 339.872275 -280.865738) (xy 339.82342 -280.87167) (xy 339.774245 -280.869689)
			(xy 339.726026 -280.859845) (xy 339.68001 -280.842393) (xy 339.637389 -280.817786) (xy 339.599268 -280.786661)
			(xy 339.566633 -280.749824) (xy 339.54033 -280.708228) (xy 339.521039 -280.662952) (xy 339.509262 -280.615168)
			(xy 339.505302 -280.566114) (xy 339.186774 -280.566114) (xy 339.186262 -280.59156) (xy 339.178098 -280.641794)
			(xy 339.161982 -280.690068) (xy 339.138331 -280.735131) (xy 339.107758 -280.775817) (xy 339.071054 -280.811072)
			(xy 339.02917 -280.839982) (xy 338.983191 -280.861799) (xy 338.934307 -280.875959) (xy 338.883786 -280.882093)
			(xy 338.832934 -280.880044) (xy 338.78307 -280.869864) (xy 338.735484 -280.851817) (xy 338.69141 -280.826371)
			(xy 338.651988 -280.794184) (xy 338.61824 -280.75609) (xy 338.591039 -280.713076) (xy 338.571091 -280.666256)
			(xy 338.558912 -280.616842) (xy 338.554817 -280.566114) (xy 338.236306 -280.566114) (xy 338.235811 -280.590721)
			(xy 338.227916 -280.639298) (xy 338.212332 -280.685979) (xy 338.189461 -280.729556) (xy 338.159896 -280.7689)
			(xy 338.124403 -280.802992) (xy 338.0839 -280.830948) (xy 338.039438 -280.852046) (xy 337.992167 -280.865738)
			(xy 337.943312 -280.87167) (xy 337.894137 -280.869689) (xy 337.845918 -280.859845) (xy 337.799902 -280.842393)
			(xy 337.757281 -280.817786) (xy 337.71916 -280.786661) (xy 337.686525 -280.749824) (xy 337.660222 -280.708228)
			(xy 337.640931 -280.662952) (xy 337.629154 -280.615168) (xy 337.625194 -280.566114) (xy 337.30692 -280.566114)
			(xy 337.306408 -280.59156) (xy 337.298244 -280.641794) (xy 337.282128 -280.690068) (xy 337.258477 -280.735131)
			(xy 337.227904 -280.775817) (xy 337.1912 -280.811072) (xy 337.149316 -280.839982) (xy 337.103337 -280.861799)
			(xy 337.054453 -280.875959) (xy 337.003932 -280.882093) (xy 336.95308 -280.880044) (xy 336.903216 -280.869864)
			(xy 336.85563 -280.851817) (xy 336.811556 -280.826371) (xy 336.772134 -280.794184) (xy 336.738386 -280.75609)
			(xy 336.711185 -280.713076) (xy 336.691237 -280.666256) (xy 336.679058 -280.616842) (xy 336.674963 -280.566114)
			(xy 336.366866 -280.566114) (xy 336.366354 -280.59156) (xy 336.35819 -280.641794) (xy 336.342074 -280.690068)
			(xy 336.318423 -280.735131) (xy 336.28785 -280.775817) (xy 336.251146 -280.811072) (xy 336.209262 -280.839982)
			(xy 336.163283 -280.861799) (xy 336.114399 -280.875959) (xy 336.063878 -280.882093) (xy 336.013026 -280.880044)
			(xy 335.963162 -280.869864) (xy 335.915576 -280.851817) (xy 335.871502 -280.826371) (xy 335.83208 -280.794184)
			(xy 335.798332 -280.75609) (xy 335.771131 -280.713076) (xy 335.751183 -280.666256) (xy 335.739004 -280.616842)
			(xy 335.734909 -280.566114) (xy 334.486758 -280.566114) (xy 334.486246 -280.59156) (xy 334.478082 -280.641794)
			(xy 334.461966 -280.690068) (xy 334.438315 -280.735131) (xy 334.407742 -280.775817) (xy 334.371038 -280.811072)
			(xy 334.329154 -280.839982) (xy 334.283175 -280.861799) (xy 334.234291 -280.875959) (xy 334.18377 -280.882093)
			(xy 334.132918 -280.880044) (xy 334.083054 -280.869864) (xy 334.035468 -280.851817) (xy 333.991394 -280.826371)
			(xy 333.951972 -280.794184) (xy 333.918224 -280.75609) (xy 333.891023 -280.713076) (xy 333.871075 -280.666256)
			(xy 333.858896 -280.616842) (xy 333.854801 -280.566114) (xy 333.53629 -280.566114) (xy 333.535795 -280.590721)
			(xy 333.5279 -280.639298) (xy 333.512316 -280.685979) (xy 333.489445 -280.729556) (xy 333.45988 -280.7689)
			(xy 333.424387 -280.802992) (xy 333.383884 -280.830948) (xy 333.339422 -280.852046) (xy 333.292151 -280.865738)
			(xy 333.243296 -280.87167) (xy 333.194121 -280.869689) (xy 333.145902 -280.859845) (xy 333.099886 -280.842393)
			(xy 333.057265 -280.817786) (xy 333.019144 -280.786661) (xy 332.986509 -280.749824) (xy 332.960206 -280.708228)
			(xy 332.940915 -280.662952) (xy 332.929138 -280.615168) (xy 332.925178 -280.566114) (xy 332.606904 -280.566114)
			(xy 332.606392 -280.59156) (xy 332.598228 -280.641794) (xy 332.582112 -280.690068) (xy 332.558461 -280.735131)
			(xy 332.527888 -280.775817) (xy 332.491184 -280.811072) (xy 332.4493 -280.839982) (xy 332.403321 -280.861799)
			(xy 332.354437 -280.875959) (xy 332.303916 -280.882093) (xy 332.253064 -280.880044) (xy 332.2032 -280.869864)
			(xy 332.155614 -280.851817) (xy 332.11154 -280.826371) (xy 332.072118 -280.794184) (xy 332.03837 -280.75609)
			(xy 332.011169 -280.713076) (xy 331.991221 -280.666256) (xy 331.979042 -280.616842) (xy 331.974947 -280.566114)
			(xy 331.656436 -280.566114) (xy 331.655941 -280.590721) (xy 331.648046 -280.639298) (xy 331.632462 -280.685979)
			(xy 331.609591 -280.729556) (xy 331.580026 -280.7689) (xy 331.544533 -280.802992) (xy 331.50403 -280.830948)
			(xy 331.459568 -280.852046) (xy 331.412297 -280.865738) (xy 331.363442 -280.87167) (xy 331.314267 -280.869689)
			(xy 331.266048 -280.859845) (xy 331.220032 -280.842393) (xy 331.177411 -280.817786) (xy 331.13929 -280.786661)
			(xy 331.106655 -280.749824) (xy 331.080352 -280.708228) (xy 331.061061 -280.662952) (xy 331.049284 -280.615168)
			(xy 331.045324 -280.566114) (xy 330.726796 -280.566114) (xy 330.726284 -280.59156) (xy 330.71812 -280.641794)
			(xy 330.702004 -280.690068) (xy 330.678353 -280.735131) (xy 330.64778 -280.775817) (xy 330.611076 -280.811072)
			(xy 330.569192 -280.839982) (xy 330.523213 -280.861799) (xy 330.474329 -280.875959) (xy 330.423808 -280.882093)
			(xy 330.372956 -280.880044) (xy 330.323092 -280.869864) (xy 330.275506 -280.851817) (xy 330.231432 -280.826371)
			(xy 330.19201 -280.794184) (xy 330.158262 -280.75609) (xy 330.131061 -280.713076) (xy 330.111113 -280.666256)
			(xy 330.098934 -280.616842) (xy 330.094839 -280.566114) (xy 329.786742 -280.566114) (xy 329.78623 -280.59156)
			(xy 329.778066 -280.641794) (xy 329.76195 -280.690068) (xy 329.738299 -280.735131) (xy 329.707726 -280.775817)
			(xy 329.671022 -280.811072) (xy 329.629138 -280.839982) (xy 329.583159 -280.861799) (xy 329.534275 -280.875959)
			(xy 329.483754 -280.882093) (xy 329.432902 -280.880044) (xy 329.383038 -280.869864) (xy 329.335452 -280.851817)
			(xy 329.291378 -280.826371) (xy 329.251956 -280.794184) (xy 329.218208 -280.75609) (xy 329.191007 -280.713076)
			(xy 329.171059 -280.666256) (xy 329.15888 -280.616842) (xy 329.154785 -280.566114) (xy 326.95642 -280.566114)
			(xy 326.955925 -280.590721) (xy 326.94803 -280.639298) (xy 326.932446 -280.685979) (xy 326.909575 -280.729556)
			(xy 326.88001 -280.7689) (xy 326.844517 -280.802992) (xy 326.804014 -280.830948) (xy 326.759552 -280.852046)
			(xy 326.712281 -280.865738) (xy 326.663426 -280.87167) (xy 326.614251 -280.869689) (xy 326.566032 -280.859845)
			(xy 326.520016 -280.842393) (xy 326.477395 -280.817786) (xy 326.439274 -280.786661) (xy 326.406639 -280.749824)
			(xy 326.380336 -280.708228) (xy 326.361045 -280.662952) (xy 326.349268 -280.615168) (xy 326.345308 -280.566114)
			(xy 310.45912 -280.566114) (xy 310.45912 -281.110182) (xy 324.74714 -281.110182) (xy 324.7511 -281.061128)
			(xy 324.762877 -281.013344) (xy 324.782168 -280.968068) (xy 324.808471 -280.926472) (xy 324.841106 -280.889635)
			(xy 324.879227 -280.85851) (xy 324.921848 -280.833903) (xy 324.967864 -280.816451) (xy 325.016083 -280.806607)
			(xy 325.065258 -280.804626) (xy 325.114113 -280.810558) (xy 325.161384 -280.82425) (xy 325.205846 -280.845348)
			(xy 325.246349 -280.873304) (xy 325.281842 -280.907396) (xy 325.311407 -280.94674) (xy 325.334278 -280.990317)
			(xy 325.349862 -281.036998) (xy 325.357757 -281.085575) (xy 325.358252 -281.110182) (xy 325.357757 -281.134789)
			(xy 325.349862 -281.183366) (xy 325.334278 -281.230047) (xy 325.311407 -281.273624) (xy 325.281842 -281.312968)
			(xy 325.246349 -281.34706) (xy 325.205846 -281.375016) (xy 325.203519 -281.37612) (xy 327.755262 -281.37612)
			(xy 327.759222 -281.327066) (xy 327.770999 -281.279282) (xy 327.79029 -281.234006) (xy 327.816593 -281.19241)
			(xy 327.849228 -281.155573) (xy 327.887349 -281.124448) (xy 327.92997 -281.099841) (xy 327.975986 -281.082389)
			(xy 328.024205 -281.072545) (xy 328.07338 -281.070564) (xy 328.122235 -281.076496) (xy 328.169506 -281.090188)
			(xy 328.213968 -281.111286) (xy 328.254471 -281.139242) (xy 328.289964 -281.173334) (xy 328.319529 -281.212678)
			(xy 328.3424 -281.256255) (xy 328.357984 -281.302936) (xy 328.365879 -281.351513) (xy 328.366374 -281.37612)
			(xy 328.684885 -281.37612) (xy 328.68898 -281.325392) (xy 328.701159 -281.275978) (xy 328.721107 -281.229158)
			(xy 328.748308 -281.186144) (xy 328.782056 -281.14805) (xy 328.821478 -281.115863) (xy 328.865552 -281.090417)
			(xy 328.913138 -281.07237) (xy 328.963002 -281.06219) (xy 329.013854 -281.060141) (xy 329.064375 -281.066275)
			(xy 329.113259 -281.080435) (xy 329.159238 -281.102252) (xy 329.201122 -281.131162) (xy 329.237826 -281.166417)
			(xy 329.268399 -281.207103) (xy 329.29205 -281.252166) (xy 329.308166 -281.30044) (xy 329.31633 -281.350674)
			(xy 329.316842 -281.37612) (xy 329.63537 -281.37612) (xy 329.63933 -281.327066) (xy 329.651107 -281.279282)
			(xy 329.670398 -281.234006) (xy 329.696701 -281.19241) (xy 329.729336 -281.155573) (xy 329.767457 -281.124448)
			(xy 329.810078 -281.099841) (xy 329.856094 -281.082389) (xy 329.904313 -281.072545) (xy 329.953488 -281.070564)
			(xy 330.002343 -281.076496) (xy 330.049614 -281.090188) (xy 330.094076 -281.111286) (xy 330.134579 -281.139242)
			(xy 330.170072 -281.173334) (xy 330.199637 -281.212678) (xy 330.222508 -281.256255) (xy 330.238092 -281.302936)
			(xy 330.245987 -281.351513) (xy 330.246482 -281.37612) (xy 330.564739 -281.37612) (xy 330.568834 -281.325392)
			(xy 330.581013 -281.275978) (xy 330.600961 -281.229158) (xy 330.628162 -281.186144) (xy 330.66191 -281.14805)
			(xy 330.701332 -281.115863) (xy 330.745406 -281.090417) (xy 330.792992 -281.07237) (xy 330.842856 -281.06219)
			(xy 330.893708 -281.060141) (xy 330.944229 -281.066275) (xy 330.993113 -281.080435) (xy 331.039092 -281.102252)
			(xy 331.080976 -281.131162) (xy 331.11768 -281.166417) (xy 331.148253 -281.207103) (xy 331.171904 -281.252166)
			(xy 331.18802 -281.30044) (xy 331.196184 -281.350674) (xy 331.196696 -281.37612) (xy 331.515224 -281.37612)
			(xy 331.519184 -281.327066) (xy 331.530961 -281.279282) (xy 331.550252 -281.234006) (xy 331.576555 -281.19241)
			(xy 331.60919 -281.155573) (xy 331.647311 -281.124448) (xy 331.689932 -281.099841) (xy 331.735948 -281.082389)
			(xy 331.784167 -281.072545) (xy 331.833342 -281.070564) (xy 331.882197 -281.076496) (xy 331.929468 -281.090188)
			(xy 331.97393 -281.111286) (xy 332.014433 -281.139242) (xy 332.049926 -281.173334) (xy 332.079491 -281.212678)
			(xy 332.102362 -281.256255) (xy 332.117946 -281.302936) (xy 332.125841 -281.351513) (xy 332.126336 -281.37612)
			(xy 332.444847 -281.37612) (xy 332.448942 -281.325392) (xy 332.461121 -281.275978) (xy 332.481069 -281.229158)
			(xy 332.50827 -281.186144) (xy 332.542018 -281.14805) (xy 332.58144 -281.115863) (xy 332.625514 -281.090417)
			(xy 332.6731 -281.07237) (xy 332.722964 -281.06219) (xy 332.773816 -281.060141) (xy 332.824337 -281.066275)
			(xy 332.873221 -281.080435) (xy 332.9192 -281.102252) (xy 332.961084 -281.131162) (xy 332.997788 -281.166417)
			(xy 333.028361 -281.207103) (xy 333.052012 -281.252166) (xy 333.068128 -281.30044) (xy 333.076292 -281.350674)
			(xy 333.076804 -281.37612) (xy 333.384901 -281.37612) (xy 333.388996 -281.325392) (xy 333.401175 -281.275978)
			(xy 333.421123 -281.229158) (xy 333.448324 -281.186144) (xy 333.482072 -281.14805) (xy 333.521494 -281.115863)
			(xy 333.565568 -281.090417) (xy 333.613154 -281.07237) (xy 333.663018 -281.06219) (xy 333.71387 -281.060141)
			(xy 333.764391 -281.066275) (xy 333.813275 -281.080435) (xy 333.859254 -281.102252) (xy 333.901138 -281.131162)
			(xy 333.937842 -281.166417) (xy 333.968415 -281.207103) (xy 333.992066 -281.252166) (xy 334.008182 -281.30044)
			(xy 334.016346 -281.350674) (xy 334.016858 -281.37612) (xy 334.335386 -281.37612) (xy 334.339346 -281.327066)
			(xy 334.351123 -281.279282) (xy 334.370414 -281.234006) (xy 334.396717 -281.19241) (xy 334.429352 -281.155573)
			(xy 334.467473 -281.124448) (xy 334.510094 -281.099841) (xy 334.55611 -281.082389) (xy 334.604329 -281.072545)
			(xy 334.653504 -281.070564) (xy 334.702359 -281.076496) (xy 334.74963 -281.090188) (xy 334.794092 -281.111286)
			(xy 334.834595 -281.139242) (xy 334.870088 -281.173334) (xy 334.899653 -281.212678) (xy 334.922524 -281.256255)
			(xy 334.938108 -281.302936) (xy 334.946003 -281.351513) (xy 334.946498 -281.37612) (xy 335.264755 -281.37612)
			(xy 335.26885 -281.325392) (xy 335.281029 -281.275978) (xy 335.300977 -281.229158) (xy 335.328178 -281.186144)
			(xy 335.361926 -281.14805) (xy 335.401348 -281.115863) (xy 335.445422 -281.090417) (xy 335.493008 -281.07237)
			(xy 335.542872 -281.06219) (xy 335.593724 -281.060141) (xy 335.644245 -281.066275) (xy 335.693129 -281.080435)
			(xy 335.739108 -281.102252) (xy 335.780992 -281.131162) (xy 335.817696 -281.166417) (xy 335.848269 -281.207103)
			(xy 335.87192 -281.252166) (xy 335.888036 -281.30044) (xy 335.8962 -281.350674) (xy 335.896712 -281.37612)
			(xy 336.21524 -281.37612) (xy 336.2192 -281.327066) (xy 336.230977 -281.279282) (xy 336.250268 -281.234006)
			(xy 336.276571 -281.19241) (xy 336.309206 -281.155573) (xy 336.347327 -281.124448) (xy 336.389948 -281.099841)
			(xy 336.435964 -281.082389) (xy 336.484183 -281.072545) (xy 336.533358 -281.070564) (xy 336.582213 -281.076496)
			(xy 336.629484 -281.090188) (xy 336.673946 -281.111286) (xy 336.714449 -281.139242) (xy 336.749942 -281.173334)
			(xy 336.779507 -281.212678) (xy 336.802378 -281.256255) (xy 336.817962 -281.302936) (xy 336.825857 -281.351513)
			(xy 336.826352 -281.37612) (xy 337.144863 -281.37612) (xy 337.148958 -281.325392) (xy 337.161137 -281.275978)
			(xy 337.181085 -281.229158) (xy 337.208286 -281.186144) (xy 337.242034 -281.14805) (xy 337.281456 -281.115863)
			(xy 337.32553 -281.090417) (xy 337.373116 -281.07237) (xy 337.42298 -281.06219) (xy 337.473832 -281.060141)
			(xy 337.524353 -281.066275) (xy 337.573237 -281.080435) (xy 337.619216 -281.102252) (xy 337.6611 -281.131162)
			(xy 337.697804 -281.166417) (xy 337.728377 -281.207103) (xy 337.752028 -281.252166) (xy 337.768144 -281.30044)
			(xy 337.776308 -281.350674) (xy 337.77682 -281.37612) (xy 338.095348 -281.37612) (xy 338.099308 -281.327066)
			(xy 338.111085 -281.279282) (xy 338.130376 -281.234006) (xy 338.156679 -281.19241) (xy 338.189314 -281.155573)
			(xy 338.227435 -281.124448) (xy 338.270056 -281.099841) (xy 338.316072 -281.082389) (xy 338.364291 -281.072545)
			(xy 338.413466 -281.070564) (xy 338.462321 -281.076496) (xy 338.509592 -281.090188) (xy 338.554054 -281.111286)
			(xy 338.594557 -281.139242) (xy 338.63005 -281.173334) (xy 338.659615 -281.212678) (xy 338.682486 -281.256255)
			(xy 338.69807 -281.302936) (xy 338.705965 -281.351513) (xy 338.70646 -281.37612) (xy 339.024971 -281.37612)
			(xy 339.029066 -281.325392) (xy 339.041245 -281.275978) (xy 339.061193 -281.229158) (xy 339.088394 -281.186144)
			(xy 339.122142 -281.14805) (xy 339.161564 -281.115863) (xy 339.205638 -281.090417) (xy 339.253224 -281.07237)
			(xy 339.303088 -281.06219) (xy 339.35394 -281.060141) (xy 339.404461 -281.066275) (xy 339.453345 -281.080435)
			(xy 339.499324 -281.102252) (xy 339.541208 -281.131162) (xy 339.577912 -281.166417) (xy 339.608485 -281.207103)
			(xy 339.632136 -281.252166) (xy 339.648252 -281.30044) (xy 339.656416 -281.350674) (xy 339.656928 -281.37612)
			(xy 339.964771 -281.37612) (xy 339.968866 -281.325392) (xy 339.981045 -281.275978) (xy 340.000993 -281.229158)
			(xy 340.028194 -281.186144) (xy 340.061942 -281.14805) (xy 340.101364 -281.115863) (xy 340.145438 -281.090417)
			(xy 340.193024 -281.07237) (xy 340.242888 -281.06219) (xy 340.29374 -281.060141) (xy 340.344261 -281.066275)
			(xy 340.393145 -281.080435) (xy 340.439124 -281.102252) (xy 340.481008 -281.131162) (xy 340.517712 -281.166417)
			(xy 340.548285 -281.207103) (xy 340.571936 -281.252166) (xy 340.588052 -281.30044) (xy 340.596216 -281.350674)
			(xy 340.596728 -281.37612) (xy 340.915256 -281.37612) (xy 340.919216 -281.327066) (xy 340.930993 -281.279282)
			(xy 340.950284 -281.234006) (xy 340.976587 -281.19241) (xy 341.009222 -281.155573) (xy 341.047343 -281.124448)
			(xy 341.089964 -281.099841) (xy 341.13598 -281.082389) (xy 341.184199 -281.072545) (xy 341.233374 -281.070564)
			(xy 341.282229 -281.076496) (xy 341.3295 -281.090188) (xy 341.373962 -281.111286) (xy 341.414465 -281.139242)
			(xy 341.449958 -281.173334) (xy 341.479523 -281.212678) (xy 341.502394 -281.256255) (xy 341.517978 -281.302936)
			(xy 341.525873 -281.351513) (xy 341.526368 -281.37612) (xy 341.844879 -281.37612) (xy 341.848974 -281.325392)
			(xy 341.861153 -281.275978) (xy 341.881101 -281.229158) (xy 341.908302 -281.186144) (xy 341.94205 -281.14805)
			(xy 341.981472 -281.115863) (xy 342.025546 -281.090417) (xy 342.073132 -281.07237) (xy 342.122996 -281.06219)
			(xy 342.173848 -281.060141) (xy 342.224369 -281.066275) (xy 342.273253 -281.080435) (xy 342.319232 -281.102252)
			(xy 342.361116 -281.131162) (xy 342.39782 -281.166417) (xy 342.428393 -281.207103) (xy 342.452044 -281.252166)
			(xy 342.46816 -281.30044) (xy 342.476324 -281.350674) (xy 342.476836 -281.37612) (xy 342.795364 -281.37612)
			(xy 342.799324 -281.327066) (xy 342.811101 -281.279282) (xy 342.830392 -281.234006) (xy 342.856695 -281.19241)
			(xy 342.88933 -281.155573) (xy 342.927451 -281.124448) (xy 342.970072 -281.099841) (xy 343.016088 -281.082389)
			(xy 343.064307 -281.072545) (xy 343.113482 -281.070564) (xy 343.162337 -281.076496) (xy 343.209608 -281.090188)
			(xy 343.25407 -281.111286) (xy 343.294573 -281.139242) (xy 343.330066 -281.173334) (xy 343.359631 -281.212678)
			(xy 343.382502 -281.256255) (xy 343.398086 -281.302936) (xy 343.405981 -281.351513) (xy 343.406476 -281.37612)
			(xy 343.724987 -281.37612) (xy 343.729082 -281.325392) (xy 343.741261 -281.275978) (xy 343.761209 -281.229158)
			(xy 343.78841 -281.186144) (xy 343.822158 -281.14805) (xy 343.86158 -281.115863) (xy 343.905654 -281.090417)
			(xy 343.95324 -281.07237) (xy 344.003104 -281.06219) (xy 344.053956 -281.060141) (xy 344.104477 -281.066275)
			(xy 344.153361 -281.080435) (xy 344.19934 -281.102252) (xy 344.241224 -281.131162) (xy 344.277928 -281.166417)
			(xy 344.308501 -281.207103) (xy 344.332152 -281.252166) (xy 344.348268 -281.30044) (xy 344.356432 -281.350674)
			(xy 344.356944 -281.37612) (xy 344.675218 -281.37612) (xy 344.679178 -281.327066) (xy 344.690955 -281.279282)
			(xy 344.710246 -281.234006) (xy 344.736549 -281.19241) (xy 344.769184 -281.155573) (xy 344.807305 -281.124448)
			(xy 344.849926 -281.099841) (xy 344.895942 -281.082389) (xy 344.944161 -281.072545) (xy 344.993336 -281.070564)
			(xy 345.042191 -281.076496) (xy 345.089462 -281.090188) (xy 345.133924 -281.111286) (xy 345.174427 -281.139242)
			(xy 345.20992 -281.173334) (xy 345.239485 -281.212678) (xy 345.262356 -281.256255) (xy 345.27794 -281.302936)
			(xy 345.285835 -281.351513) (xy 345.28633 -281.37612) (xy 345.604841 -281.37612) (xy 345.608936 -281.325392)
			(xy 345.621115 -281.275978) (xy 345.641063 -281.229158) (xy 345.668264 -281.186144) (xy 345.702012 -281.14805)
			(xy 345.741434 -281.115863) (xy 345.785508 -281.090417) (xy 345.833094 -281.07237) (xy 345.882958 -281.06219)
			(xy 345.93381 -281.060141) (xy 345.984331 -281.066275) (xy 346.033215 -281.080435) (xy 346.079194 -281.102252)
			(xy 346.121078 -281.131162) (xy 346.157782 -281.166417) (xy 346.188355 -281.207103) (xy 346.212006 -281.252166)
			(xy 346.228122 -281.30044) (xy 346.236286 -281.350674) (xy 346.236798 -281.37612) (xy 346.544895 -281.37612)
			(xy 346.54899 -281.325392) (xy 346.561169 -281.275978) (xy 346.581117 -281.229158) (xy 346.608318 -281.186144)
			(xy 346.642066 -281.14805) (xy 346.681488 -281.115863) (xy 346.725562 -281.090417) (xy 346.773148 -281.07237)
			(xy 346.823012 -281.06219) (xy 346.873864 -281.060141) (xy 346.924385 -281.066275) (xy 346.973269 -281.080435)
			(xy 347.019248 -281.102252) (xy 347.061132 -281.131162) (xy 347.097836 -281.166417) (xy 347.128409 -281.207103)
			(xy 347.15206 -281.252166) (xy 347.168176 -281.30044) (xy 347.17634 -281.350674) (xy 347.176852 -281.37612)
			(xy 347.49538 -281.37612) (xy 347.49934 -281.327066) (xy 347.511117 -281.279282) (xy 347.530408 -281.234006)
			(xy 347.556711 -281.19241) (xy 347.589346 -281.155573) (xy 347.627467 -281.124448) (xy 347.670088 -281.099841)
			(xy 347.716104 -281.082389) (xy 347.764323 -281.072545) (xy 347.813498 -281.070564) (xy 347.862353 -281.076496)
			(xy 347.909624 -281.090188) (xy 347.954086 -281.111286) (xy 347.994589 -281.139242) (xy 348.030082 -281.173334)
			(xy 348.059647 -281.212678) (xy 348.082518 -281.256255) (xy 348.098102 -281.302936) (xy 348.105997 -281.351513)
			(xy 348.106492 -281.37612) (xy 348.425003 -281.37612) (xy 348.429098 -281.325392) (xy 348.441277 -281.275978)
			(xy 348.461225 -281.229158) (xy 348.488426 -281.186144) (xy 348.522174 -281.14805) (xy 348.561596 -281.115863)
			(xy 348.60567 -281.090417) (xy 348.653256 -281.07237) (xy 348.70312 -281.06219) (xy 348.753972 -281.060141)
			(xy 348.804493 -281.066275) (xy 348.853377 -281.080435) (xy 348.899356 -281.102252) (xy 348.94124 -281.131162)
			(xy 348.977944 -281.166417) (xy 349.008517 -281.207103) (xy 349.032168 -281.252166) (xy 349.048284 -281.30044)
			(xy 349.056448 -281.350674) (xy 349.05696 -281.37612) (xy 349.364803 -281.37612) (xy 349.368898 -281.325392)
			(xy 349.381077 -281.275978) (xy 349.401025 -281.229158) (xy 349.428226 -281.186144) (xy 349.461974 -281.14805)
			(xy 349.501396 -281.115863) (xy 349.54547 -281.090417) (xy 349.593056 -281.07237) (xy 349.64292 -281.06219)
			(xy 349.693772 -281.060141) (xy 349.744293 -281.066275) (xy 349.793177 -281.080435) (xy 349.839156 -281.102252)
			(xy 349.88104 -281.131162) (xy 349.917744 -281.166417) (xy 349.948317 -281.207103) (xy 349.971968 -281.252166)
			(xy 349.988084 -281.30044) (xy 349.996248 -281.350674) (xy 349.99676 -281.37612) (xy 350.315288 -281.37612)
			(xy 350.319248 -281.327066) (xy 350.331025 -281.279282) (xy 350.350316 -281.234006) (xy 350.376619 -281.19241)
			(xy 350.409254 -281.155573) (xy 350.447375 -281.124448) (xy 350.489996 -281.099841) (xy 350.536012 -281.082389)
			(xy 350.584231 -281.072545) (xy 350.633406 -281.070564) (xy 350.682261 -281.076496) (xy 350.729532 -281.090188)
			(xy 350.773994 -281.111286) (xy 350.814497 -281.139242) (xy 350.84999 -281.173334) (xy 350.879555 -281.212678)
			(xy 350.902426 -281.256255) (xy 350.91801 -281.302936) (xy 350.925905 -281.351513) (xy 350.9264 -281.37612)
			(xy 350.925905 -281.400727) (xy 350.91801 -281.449304) (xy 350.902426 -281.495985) (xy 350.879555 -281.539562)
			(xy 350.84999 -281.578906) (xy 350.814497 -281.612998) (xy 350.773994 -281.640954) (xy 350.729532 -281.662052)
			(xy 350.682261 -281.675744) (xy 350.633406 -281.681676) (xy 350.584231 -281.679695) (xy 350.536012 -281.669851)
			(xy 350.489996 -281.652399) (xy 350.447375 -281.627792) (xy 350.409254 -281.596667) (xy 350.376619 -281.55983)
			(xy 350.350316 -281.518234) (xy 350.331025 -281.472958) (xy 350.319248 -281.425174) (xy 350.315288 -281.37612)
			(xy 349.99676 -281.37612) (xy 349.996248 -281.401566) (xy 349.988084 -281.4518) (xy 349.971968 -281.500074)
			(xy 349.948317 -281.545137) (xy 349.917744 -281.585823) (xy 349.88104 -281.621078) (xy 349.839156 -281.649988)
			(xy 349.793177 -281.671805) (xy 349.744293 -281.685965) (xy 349.693772 -281.692099) (xy 349.64292 -281.69005)
			(xy 349.593056 -281.67987) (xy 349.54547 -281.661823) (xy 349.501396 -281.636377) (xy 349.461974 -281.60419)
			(xy 349.428226 -281.566096) (xy 349.401025 -281.523082) (xy 349.381077 -281.476262) (xy 349.368898 -281.426848)
			(xy 349.364803 -281.37612) (xy 349.05696 -281.37612) (xy 349.056448 -281.401566) (xy 349.048284 -281.4518)
			(xy 349.032168 -281.500074) (xy 349.008517 -281.545137) (xy 348.977944 -281.585823) (xy 348.94124 -281.621078)
			(xy 348.899356 -281.649988) (xy 348.853377 -281.671805) (xy 348.804493 -281.685965) (xy 348.753972 -281.692099)
			(xy 348.70312 -281.69005) (xy 348.653256 -281.67987) (xy 348.60567 -281.661823) (xy 348.561596 -281.636377)
			(xy 348.522174 -281.60419) (xy 348.488426 -281.566096) (xy 348.461225 -281.523082) (xy 348.441277 -281.476262)
			(xy 348.429098 -281.426848) (xy 348.425003 -281.37612) (xy 348.106492 -281.37612) (xy 348.105997 -281.400727)
			(xy 348.098102 -281.449304) (xy 348.082518 -281.495985) (xy 348.059647 -281.539562) (xy 348.030082 -281.578906)
			(xy 347.994589 -281.612998) (xy 347.954086 -281.640954) (xy 347.909624 -281.662052) (xy 347.862353 -281.675744)
			(xy 347.813498 -281.681676) (xy 347.764323 -281.679695) (xy 347.716104 -281.669851) (xy 347.670088 -281.652399)
			(xy 347.627467 -281.627792) (xy 347.589346 -281.596667) (xy 347.556711 -281.55983) (xy 347.530408 -281.518234)
			(xy 347.511117 -281.472958) (xy 347.49934 -281.425174) (xy 347.49538 -281.37612) (xy 347.176852 -281.37612)
			(xy 347.17634 -281.401566) (xy 347.168176 -281.4518) (xy 347.15206 -281.500074) (xy 347.128409 -281.545137)
			(xy 347.097836 -281.585823) (xy 347.061132 -281.621078) (xy 347.019248 -281.649988) (xy 346.973269 -281.671805)
			(xy 346.924385 -281.685965) (xy 346.873864 -281.692099) (xy 346.823012 -281.69005) (xy 346.773148 -281.67987)
			(xy 346.725562 -281.661823) (xy 346.681488 -281.636377) (xy 346.642066 -281.60419) (xy 346.608318 -281.566096)
			(xy 346.581117 -281.523082) (xy 346.561169 -281.476262) (xy 346.54899 -281.426848) (xy 346.544895 -281.37612)
			(xy 346.236798 -281.37612) (xy 346.236286 -281.401566) (xy 346.228122 -281.4518) (xy 346.212006 -281.500074)
			(xy 346.188355 -281.545137) (xy 346.157782 -281.585823) (xy 346.121078 -281.621078) (xy 346.079194 -281.649988)
			(xy 346.033215 -281.671805) (xy 345.984331 -281.685965) (xy 345.93381 -281.692099) (xy 345.882958 -281.69005)
			(xy 345.833094 -281.67987) (xy 345.785508 -281.661823) (xy 345.741434 -281.636377) (xy 345.702012 -281.60419)
			(xy 345.668264 -281.566096) (xy 345.641063 -281.523082) (xy 345.621115 -281.476262) (xy 345.608936 -281.426848)
			(xy 345.604841 -281.37612) (xy 345.28633 -281.37612) (xy 345.285835 -281.400727) (xy 345.27794 -281.449304)
			(xy 345.262356 -281.495985) (xy 345.239485 -281.539562) (xy 345.20992 -281.578906) (xy 345.174427 -281.612998)
			(xy 345.133924 -281.640954) (xy 345.089462 -281.662052) (xy 345.042191 -281.675744) (xy 344.993336 -281.681676)
			(xy 344.944161 -281.679695) (xy 344.895942 -281.669851) (xy 344.849926 -281.652399) (xy 344.807305 -281.627792)
			(xy 344.769184 -281.596667) (xy 344.736549 -281.55983) (xy 344.710246 -281.518234) (xy 344.690955 -281.472958)
			(xy 344.679178 -281.425174) (xy 344.675218 -281.37612) (xy 344.356944 -281.37612) (xy 344.356432 -281.401566)
			(xy 344.348268 -281.4518) (xy 344.332152 -281.500074) (xy 344.308501 -281.545137) (xy 344.277928 -281.585823)
			(xy 344.241224 -281.621078) (xy 344.19934 -281.649988) (xy 344.153361 -281.671805) (xy 344.104477 -281.685965)
			(xy 344.053956 -281.692099) (xy 344.003104 -281.69005) (xy 343.95324 -281.67987) (xy 343.905654 -281.661823)
			(xy 343.86158 -281.636377) (xy 343.822158 -281.60419) (xy 343.78841 -281.566096) (xy 343.761209 -281.523082)
			(xy 343.741261 -281.476262) (xy 343.729082 -281.426848) (xy 343.724987 -281.37612) (xy 343.406476 -281.37612)
			(xy 343.405981 -281.400727) (xy 343.398086 -281.449304) (xy 343.382502 -281.495985) (xy 343.359631 -281.539562)
			(xy 343.330066 -281.578906) (xy 343.294573 -281.612998) (xy 343.25407 -281.640954) (xy 343.209608 -281.662052)
			(xy 343.162337 -281.675744) (xy 343.113482 -281.681676) (xy 343.064307 -281.679695) (xy 343.016088 -281.669851)
			(xy 342.970072 -281.652399) (xy 342.927451 -281.627792) (xy 342.88933 -281.596667) (xy 342.856695 -281.55983)
			(xy 342.830392 -281.518234) (xy 342.811101 -281.472958) (xy 342.799324 -281.425174) (xy 342.795364 -281.37612)
			(xy 342.476836 -281.37612) (xy 342.476324 -281.401566) (xy 342.46816 -281.4518) (xy 342.452044 -281.500074)
			(xy 342.428393 -281.545137) (xy 342.39782 -281.585823) (xy 342.361116 -281.621078) (xy 342.319232 -281.649988)
			(xy 342.273253 -281.671805) (xy 342.224369 -281.685965) (xy 342.173848 -281.692099) (xy 342.122996 -281.69005)
			(xy 342.073132 -281.67987) (xy 342.025546 -281.661823) (xy 341.981472 -281.636377) (xy 341.94205 -281.60419)
			(xy 341.908302 -281.566096) (xy 341.881101 -281.523082) (xy 341.861153 -281.476262) (xy 341.848974 -281.426848)
			(xy 341.844879 -281.37612) (xy 341.526368 -281.37612) (xy 341.525873 -281.400727) (xy 341.517978 -281.449304)
			(xy 341.502394 -281.495985) (xy 341.479523 -281.539562) (xy 341.449958 -281.578906) (xy 341.414465 -281.612998)
			(xy 341.373962 -281.640954) (xy 341.3295 -281.662052) (xy 341.282229 -281.675744) (xy 341.233374 -281.681676)
			(xy 341.184199 -281.679695) (xy 341.13598 -281.669851) (xy 341.089964 -281.652399) (xy 341.047343 -281.627792)
			(xy 341.009222 -281.596667) (xy 340.976587 -281.55983) (xy 340.950284 -281.518234) (xy 340.930993 -281.472958)
			(xy 340.919216 -281.425174) (xy 340.915256 -281.37612) (xy 340.596728 -281.37612) (xy 340.596216 -281.401566)
			(xy 340.588052 -281.4518) (xy 340.571936 -281.500074) (xy 340.548285 -281.545137) (xy 340.517712 -281.585823)
			(xy 340.481008 -281.621078) (xy 340.439124 -281.649988) (xy 340.393145 -281.671805) (xy 340.344261 -281.685965)
			(xy 340.29374 -281.692099) (xy 340.242888 -281.69005) (xy 340.193024 -281.67987) (xy 340.145438 -281.661823)
			(xy 340.101364 -281.636377) (xy 340.061942 -281.60419) (xy 340.028194 -281.566096) (xy 340.000993 -281.523082)
			(xy 339.981045 -281.476262) (xy 339.968866 -281.426848) (xy 339.964771 -281.37612) (xy 339.656928 -281.37612)
			(xy 339.656416 -281.401566) (xy 339.648252 -281.4518) (xy 339.632136 -281.500074) (xy 339.608485 -281.545137)
			(xy 339.577912 -281.585823) (xy 339.541208 -281.621078) (xy 339.499324 -281.649988) (xy 339.453345 -281.671805)
			(xy 339.404461 -281.685965) (xy 339.35394 -281.692099) (xy 339.303088 -281.69005) (xy 339.253224 -281.67987)
			(xy 339.205638 -281.661823) (xy 339.161564 -281.636377) (xy 339.122142 -281.60419) (xy 339.088394 -281.566096)
			(xy 339.061193 -281.523082) (xy 339.041245 -281.476262) (xy 339.029066 -281.426848) (xy 339.024971 -281.37612)
			(xy 338.70646 -281.37612) (xy 338.705965 -281.400727) (xy 338.69807 -281.449304) (xy 338.682486 -281.495985)
			(xy 338.659615 -281.539562) (xy 338.63005 -281.578906) (xy 338.594557 -281.612998) (xy 338.554054 -281.640954)
			(xy 338.509592 -281.662052) (xy 338.462321 -281.675744) (xy 338.413466 -281.681676) (xy 338.364291 -281.679695)
			(xy 338.316072 -281.669851) (xy 338.270056 -281.652399) (xy 338.227435 -281.627792) (xy 338.189314 -281.596667)
			(xy 338.156679 -281.55983) (xy 338.130376 -281.518234) (xy 338.111085 -281.472958) (xy 338.099308 -281.425174)
			(xy 338.095348 -281.37612) (xy 337.77682 -281.37612) (xy 337.776308 -281.401566) (xy 337.768144 -281.4518)
			(xy 337.752028 -281.500074) (xy 337.728377 -281.545137) (xy 337.697804 -281.585823) (xy 337.6611 -281.621078)
			(xy 337.619216 -281.649988) (xy 337.573237 -281.671805) (xy 337.524353 -281.685965) (xy 337.473832 -281.692099)
			(xy 337.42298 -281.69005) (xy 337.373116 -281.67987) (xy 337.32553 -281.661823) (xy 337.281456 -281.636377)
			(xy 337.242034 -281.60419) (xy 337.208286 -281.566096) (xy 337.181085 -281.523082) (xy 337.161137 -281.476262)
			(xy 337.148958 -281.426848) (xy 337.144863 -281.37612) (xy 336.826352 -281.37612) (xy 336.825857 -281.400727)
			(xy 336.817962 -281.449304) (xy 336.802378 -281.495985) (xy 336.779507 -281.539562) (xy 336.749942 -281.578906)
			(xy 336.714449 -281.612998) (xy 336.673946 -281.640954) (xy 336.629484 -281.662052) (xy 336.582213 -281.675744)
			(xy 336.533358 -281.681676) (xy 336.484183 -281.679695) (xy 336.435964 -281.669851) (xy 336.389948 -281.652399)
			(xy 336.347327 -281.627792) (xy 336.309206 -281.596667) (xy 336.276571 -281.55983) (xy 336.250268 -281.518234)
			(xy 336.230977 -281.472958) (xy 336.2192 -281.425174) (xy 336.21524 -281.37612) (xy 335.896712 -281.37612)
			(xy 335.8962 -281.401566) (xy 335.888036 -281.4518) (xy 335.87192 -281.500074) (xy 335.848269 -281.545137)
			(xy 335.817696 -281.585823) (xy 335.780992 -281.621078) (xy 335.739108 -281.649988) (xy 335.693129 -281.671805)
			(xy 335.644245 -281.685965) (xy 335.593724 -281.692099) (xy 335.542872 -281.69005) (xy 335.493008 -281.67987)
			(xy 335.445422 -281.661823) (xy 335.401348 -281.636377) (xy 335.361926 -281.60419) (xy 335.328178 -281.566096)
			(xy 335.300977 -281.523082) (xy 335.281029 -281.476262) (xy 335.26885 -281.426848) (xy 335.264755 -281.37612)
			(xy 334.946498 -281.37612) (xy 334.946003 -281.400727) (xy 334.938108 -281.449304) (xy 334.922524 -281.495985)
			(xy 334.899653 -281.539562) (xy 334.870088 -281.578906) (xy 334.834595 -281.612998) (xy 334.794092 -281.640954)
			(xy 334.74963 -281.662052) (xy 334.702359 -281.675744) (xy 334.653504 -281.681676) (xy 334.604329 -281.679695)
			(xy 334.55611 -281.669851) (xy 334.510094 -281.652399) (xy 334.467473 -281.627792) (xy 334.429352 -281.596667)
			(xy 334.396717 -281.55983) (xy 334.370414 -281.518234) (xy 334.351123 -281.472958) (xy 334.339346 -281.425174)
			(xy 334.335386 -281.37612) (xy 334.016858 -281.37612) (xy 334.016346 -281.401566) (xy 334.008182 -281.4518)
			(xy 333.992066 -281.500074) (xy 333.968415 -281.545137) (xy 333.937842 -281.585823) (xy 333.901138 -281.621078)
			(xy 333.859254 -281.649988) (xy 333.813275 -281.671805) (xy 333.764391 -281.685965) (xy 333.71387 -281.692099)
			(xy 333.663018 -281.69005) (xy 333.613154 -281.67987) (xy 333.565568 -281.661823) (xy 333.521494 -281.636377)
			(xy 333.482072 -281.60419) (xy 333.448324 -281.566096) (xy 333.421123 -281.523082) (xy 333.401175 -281.476262)
			(xy 333.388996 -281.426848) (xy 333.384901 -281.37612) (xy 333.076804 -281.37612) (xy 333.076292 -281.401566)
			(xy 333.068128 -281.4518) (xy 333.052012 -281.500074) (xy 333.028361 -281.545137) (xy 332.997788 -281.585823)
			(xy 332.961084 -281.621078) (xy 332.9192 -281.649988) (xy 332.873221 -281.671805) (xy 332.824337 -281.685965)
			(xy 332.773816 -281.692099) (xy 332.722964 -281.69005) (xy 332.6731 -281.67987) (xy 332.625514 -281.661823)
			(xy 332.58144 -281.636377) (xy 332.542018 -281.60419) (xy 332.50827 -281.566096) (xy 332.481069 -281.523082)
			(xy 332.461121 -281.476262) (xy 332.448942 -281.426848) (xy 332.444847 -281.37612) (xy 332.126336 -281.37612)
			(xy 332.125841 -281.400727) (xy 332.117946 -281.449304) (xy 332.102362 -281.495985) (xy 332.079491 -281.539562)
			(xy 332.049926 -281.578906) (xy 332.014433 -281.612998) (xy 331.97393 -281.640954) (xy 331.929468 -281.662052)
			(xy 331.882197 -281.675744) (xy 331.833342 -281.681676) (xy 331.784167 -281.679695) (xy 331.735948 -281.669851)
			(xy 331.689932 -281.652399) (xy 331.647311 -281.627792) (xy 331.60919 -281.596667) (xy 331.576555 -281.55983)
			(xy 331.550252 -281.518234) (xy 331.530961 -281.472958) (xy 331.519184 -281.425174) (xy 331.515224 -281.37612)
			(xy 331.196696 -281.37612) (xy 331.196184 -281.401566) (xy 331.18802 -281.4518) (xy 331.171904 -281.500074)
			(xy 331.148253 -281.545137) (xy 331.11768 -281.585823) (xy 331.080976 -281.621078) (xy 331.039092 -281.649988)
			(xy 330.993113 -281.671805) (xy 330.944229 -281.685965) (xy 330.893708 -281.692099) (xy 330.842856 -281.69005)
			(xy 330.792992 -281.67987) (xy 330.745406 -281.661823) (xy 330.701332 -281.636377) (xy 330.66191 -281.60419)
			(xy 330.628162 -281.566096) (xy 330.600961 -281.523082) (xy 330.581013 -281.476262) (xy 330.568834 -281.426848)
			(xy 330.564739 -281.37612) (xy 330.246482 -281.37612) (xy 330.245987 -281.400727) (xy 330.238092 -281.449304)
			(xy 330.222508 -281.495985) (xy 330.199637 -281.539562) (xy 330.170072 -281.578906) (xy 330.134579 -281.612998)
			(xy 330.094076 -281.640954) (xy 330.049614 -281.662052) (xy 330.002343 -281.675744) (xy 329.953488 -281.681676)
			(xy 329.904313 -281.679695) (xy 329.856094 -281.669851) (xy 329.810078 -281.652399) (xy 329.767457 -281.627792)
			(xy 329.729336 -281.596667) (xy 329.696701 -281.55983) (xy 329.670398 -281.518234) (xy 329.651107 -281.472958)
			(xy 329.63933 -281.425174) (xy 329.63537 -281.37612) (xy 329.316842 -281.37612) (xy 329.31633 -281.401566)
			(xy 329.308166 -281.4518) (xy 329.29205 -281.500074) (xy 329.268399 -281.545137) (xy 329.237826 -281.585823)
			(xy 329.201122 -281.621078) (xy 329.159238 -281.649988) (xy 329.113259 -281.671805) (xy 329.064375 -281.685965)
			(xy 329.013854 -281.692099) (xy 328.963002 -281.69005) (xy 328.913138 -281.67987) (xy 328.865552 -281.661823)
			(xy 328.821478 -281.636377) (xy 328.782056 -281.60419) (xy 328.748308 -281.566096) (xy 328.721107 -281.523082)
			(xy 328.701159 -281.476262) (xy 328.68898 -281.426848) (xy 328.684885 -281.37612) (xy 328.366374 -281.37612)
			(xy 328.365879 -281.400727) (xy 328.357984 -281.449304) (xy 328.3424 -281.495985) (xy 328.319529 -281.539562)
			(xy 328.289964 -281.578906) (xy 328.254471 -281.612998) (xy 328.213968 -281.640954) (xy 328.169506 -281.662052)
			(xy 328.122235 -281.675744) (xy 328.07338 -281.681676) (xy 328.024205 -281.679695) (xy 327.975986 -281.669851)
			(xy 327.92997 -281.652399) (xy 327.887349 -281.627792) (xy 327.849228 -281.596667) (xy 327.816593 -281.55983)
			(xy 327.79029 -281.518234) (xy 327.770999 -281.472958) (xy 327.759222 -281.425174) (xy 327.755262 -281.37612)
			(xy 325.203519 -281.37612) (xy 325.161384 -281.396114) (xy 325.114113 -281.409806) (xy 325.065258 -281.415738)
			(xy 325.016083 -281.413757) (xy 324.967864 -281.403913) (xy 324.921848 -281.386461) (xy 324.879227 -281.361854)
			(xy 324.841106 -281.330729) (xy 324.808471 -281.293892) (xy 324.782168 -281.252296) (xy 324.762877 -281.20702)
			(xy 324.7511 -281.159236) (xy 324.74714 -281.110182) (xy 310.45912 -281.110182) (xy 310.45912 -282.186126)
			(xy 326.345308 -282.186126) (xy 326.349268 -282.137072) (xy 326.361045 -282.089288) (xy 326.380336 -282.044012)
			(xy 326.406639 -282.002416) (xy 326.439274 -281.965579) (xy 326.477395 -281.934454) (xy 326.520016 -281.909847)
			(xy 326.566032 -281.892395) (xy 326.614251 -281.882551) (xy 326.663426 -281.88057) (xy 326.712281 -281.886502)
			(xy 326.759552 -281.900194) (xy 326.804014 -281.921292) (xy 326.844517 -281.949248) (xy 326.88001 -281.98334)
			(xy 326.909575 -282.022684) (xy 326.932446 -282.066261) (xy 326.94803 -282.112942) (xy 326.955925 -282.161519)
			(xy 326.95642 -282.186126) (xy 328.225416 -282.186126) (xy 328.229376 -282.137072) (xy 328.241153 -282.089288)
			(xy 328.260444 -282.044012) (xy 328.286747 -282.002416) (xy 328.319382 -281.965579) (xy 328.357503 -281.934454)
			(xy 328.400124 -281.909847) (xy 328.44614 -281.892395) (xy 328.494359 -281.882551) (xy 328.543534 -281.88057)
			(xy 328.592389 -281.886502) (xy 328.63966 -281.900194) (xy 328.684122 -281.921292) (xy 328.724625 -281.949248)
			(xy 328.760118 -281.98334) (xy 328.789683 -282.022684) (xy 328.812554 -282.066261) (xy 328.828138 -282.112942)
			(xy 328.836033 -282.161519) (xy 328.836528 -282.186126) (xy 329.154785 -282.186126) (xy 329.15888 -282.135398)
			(xy 329.171059 -282.085984) (xy 329.191007 -282.039164) (xy 329.218208 -281.99615) (xy 329.251956 -281.958056)
			(xy 329.291378 -281.925869) (xy 329.335452 -281.900423) (xy 329.383038 -281.882376) (xy 329.432902 -281.872196)
			(xy 329.483754 -281.870147) (xy 329.534275 -281.876281) (xy 329.583159 -281.890441) (xy 329.629138 -281.912258)
			(xy 329.671022 -281.941168) (xy 329.707726 -281.976423) (xy 329.738299 -282.017109) (xy 329.76195 -282.062172)
			(xy 329.778066 -282.110446) (xy 329.78623 -282.16068) (xy 329.786742 -282.186126) (xy 330.094839 -282.186126)
			(xy 330.098934 -282.135398) (xy 330.111113 -282.085984) (xy 330.131061 -282.039164) (xy 330.158262 -281.99615)
			(xy 330.19201 -281.958056) (xy 330.231432 -281.925869) (xy 330.275506 -281.900423) (xy 330.323092 -281.882376)
			(xy 330.372956 -281.872196) (xy 330.423808 -281.870147) (xy 330.474329 -281.876281) (xy 330.523213 -281.890441)
			(xy 330.569192 -281.912258) (xy 330.611076 -281.941168) (xy 330.64778 -281.976423) (xy 330.678353 -282.017109)
			(xy 330.702004 -282.062172) (xy 330.71812 -282.110446) (xy 330.726284 -282.16068) (xy 330.726796 -282.186126)
			(xy 331.045324 -282.186126) (xy 331.049284 -282.137072) (xy 331.061061 -282.089288) (xy 331.080352 -282.044012)
			(xy 331.106655 -282.002416) (xy 331.13929 -281.965579) (xy 331.177411 -281.934454) (xy 331.220032 -281.909847)
			(xy 331.266048 -281.892395) (xy 331.314267 -281.882551) (xy 331.363442 -281.88057) (xy 331.412297 -281.886502)
			(xy 331.459568 -281.900194) (xy 331.50403 -281.921292) (xy 331.544533 -281.949248) (xy 331.580026 -281.98334)
			(xy 331.609591 -282.022684) (xy 331.632462 -282.066261) (xy 331.648046 -282.112942) (xy 331.655941 -282.161519)
			(xy 331.656436 -282.186126) (xy 331.974947 -282.186126) (xy 331.979042 -282.135398) (xy 331.991221 -282.085984)
			(xy 332.011169 -282.039164) (xy 332.03837 -281.99615) (xy 332.072118 -281.958056) (xy 332.11154 -281.925869)
			(xy 332.155614 -281.900423) (xy 332.2032 -281.882376) (xy 332.253064 -281.872196) (xy 332.303916 -281.870147)
			(xy 332.354437 -281.876281) (xy 332.403321 -281.890441) (xy 332.4493 -281.912258) (xy 332.491184 -281.941168)
			(xy 332.527888 -281.976423) (xy 332.558461 -282.017109) (xy 332.582112 -282.062172) (xy 332.598228 -282.110446)
			(xy 332.606392 -282.16068) (xy 332.606904 -282.186126) (xy 332.925178 -282.186126) (xy 332.929138 -282.137072)
			(xy 332.940915 -282.089288) (xy 332.960206 -282.044012) (xy 332.986509 -282.002416) (xy 333.019144 -281.965579)
			(xy 333.057265 -281.934454) (xy 333.099886 -281.909847) (xy 333.145902 -281.892395) (xy 333.194121 -281.882551)
			(xy 333.243296 -281.88057) (xy 333.292151 -281.886502) (xy 333.339422 -281.900194) (xy 333.383884 -281.921292)
			(xy 333.424387 -281.949248) (xy 333.45988 -281.98334) (xy 333.489445 -282.022684) (xy 333.512316 -282.066261)
			(xy 333.5279 -282.112942) (xy 333.535795 -282.161519) (xy 333.53629 -282.186126) (xy 333.854801 -282.186126)
			(xy 333.858896 -282.135398) (xy 333.871075 -282.085984) (xy 333.891023 -282.039164) (xy 333.918224 -281.99615)
			(xy 333.951972 -281.958056) (xy 333.991394 -281.925869) (xy 334.035468 -281.900423) (xy 334.083054 -281.882376)
			(xy 334.132918 -281.872196) (xy 334.18377 -281.870147) (xy 334.234291 -281.876281) (xy 334.283175 -281.890441)
			(xy 334.329154 -281.912258) (xy 334.371038 -281.941168) (xy 334.407742 -281.976423) (xy 334.438315 -282.017109)
			(xy 334.461966 -282.062172) (xy 334.478082 -282.110446) (xy 334.486246 -282.16068) (xy 334.486758 -282.186126)
			(xy 334.805286 -282.186126) (xy 334.809246 -282.137072) (xy 334.821023 -282.089288) (xy 334.840314 -282.044012)
			(xy 334.866617 -282.002416) (xy 334.899252 -281.965579) (xy 334.937373 -281.934454) (xy 334.979994 -281.909847)
			(xy 335.02601 -281.892395) (xy 335.074229 -281.882551) (xy 335.123404 -281.88057) (xy 335.172259 -281.886502)
			(xy 335.21953 -281.900194) (xy 335.263992 -281.921292) (xy 335.304495 -281.949248) (xy 335.339988 -281.98334)
			(xy 335.369553 -282.022684) (xy 335.392424 -282.066261) (xy 335.408008 -282.112942) (xy 335.415903 -282.161519)
			(xy 335.416398 -282.186126) (xy 335.734909 -282.186126) (xy 335.739004 -282.135398) (xy 335.751183 -282.085984)
			(xy 335.771131 -282.039164) (xy 335.798332 -281.99615) (xy 335.83208 -281.958056) (xy 335.871502 -281.925869)
			(xy 335.915576 -281.900423) (xy 335.963162 -281.882376) (xy 336.013026 -281.872196) (xy 336.063878 -281.870147)
			(xy 336.114399 -281.876281) (xy 336.163283 -281.890441) (xy 336.209262 -281.912258) (xy 336.251146 -281.941168)
			(xy 336.28785 -281.976423) (xy 336.318423 -282.017109) (xy 336.342074 -282.062172) (xy 336.35819 -282.110446)
			(xy 336.366354 -282.16068) (xy 336.366866 -282.186126) (xy 336.674963 -282.186126) (xy 336.679058 -282.135398)
			(xy 336.691237 -282.085984) (xy 336.711185 -282.039164) (xy 336.738386 -281.99615) (xy 336.772134 -281.958056)
			(xy 336.811556 -281.925869) (xy 336.85563 -281.900423) (xy 336.903216 -281.882376) (xy 336.95308 -281.872196)
			(xy 337.003932 -281.870147) (xy 337.054453 -281.876281) (xy 337.103337 -281.890441) (xy 337.149316 -281.912258)
			(xy 337.1912 -281.941168) (xy 337.227904 -281.976423) (xy 337.258477 -282.017109) (xy 337.282128 -282.062172)
			(xy 337.298244 -282.110446) (xy 337.306408 -282.16068) (xy 337.30692 -282.186126) (xy 337.625194 -282.186126)
			(xy 337.629154 -282.137072) (xy 337.640931 -282.089288) (xy 337.660222 -282.044012) (xy 337.686525 -282.002416)
			(xy 337.71916 -281.965579) (xy 337.757281 -281.934454) (xy 337.799902 -281.909847) (xy 337.845918 -281.892395)
			(xy 337.894137 -281.882551) (xy 337.943312 -281.88057) (xy 337.992167 -281.886502) (xy 338.039438 -281.900194)
			(xy 338.0839 -281.921292) (xy 338.124403 -281.949248) (xy 338.159896 -281.98334) (xy 338.189461 -282.022684)
			(xy 338.212332 -282.066261) (xy 338.227916 -282.112942) (xy 338.235811 -282.161519) (xy 338.236306 -282.186126)
			(xy 338.554817 -282.186126) (xy 338.558912 -282.135398) (xy 338.571091 -282.085984) (xy 338.591039 -282.039164)
			(xy 338.61824 -281.99615) (xy 338.651988 -281.958056) (xy 338.69141 -281.925869) (xy 338.735484 -281.900423)
			(xy 338.78307 -281.882376) (xy 338.832934 -281.872196) (xy 338.883786 -281.870147) (xy 338.934307 -281.876281)
			(xy 338.983191 -281.890441) (xy 339.02917 -281.912258) (xy 339.071054 -281.941168) (xy 339.107758 -281.976423)
			(xy 339.138331 -282.017109) (xy 339.161982 -282.062172) (xy 339.178098 -282.110446) (xy 339.186262 -282.16068)
			(xy 339.186774 -282.186126) (xy 339.505302 -282.186126) (xy 339.509262 -282.137072) (xy 339.521039 -282.089288)
			(xy 339.54033 -282.044012) (xy 339.566633 -282.002416) (xy 339.599268 -281.965579) (xy 339.637389 -281.934454)
			(xy 339.68001 -281.909847) (xy 339.726026 -281.892395) (xy 339.774245 -281.882551) (xy 339.82342 -281.88057)
			(xy 339.872275 -281.886502) (xy 339.919546 -281.900194) (xy 339.964008 -281.921292) (xy 340.004511 -281.949248)
			(xy 340.040004 -281.98334) (xy 340.069569 -282.022684) (xy 340.09244 -282.066261) (xy 340.108024 -282.112942)
			(xy 340.115919 -282.161519) (xy 340.116414 -282.186126) (xy 340.434925 -282.186126) (xy 340.43902 -282.135398)
			(xy 340.451199 -282.085984) (xy 340.471147 -282.039164) (xy 340.498348 -281.99615) (xy 340.532096 -281.958056)
			(xy 340.571518 -281.925869) (xy 340.615592 -281.900423) (xy 340.663178 -281.882376) (xy 340.713042 -281.872196)
			(xy 340.763894 -281.870147) (xy 340.814415 -281.876281) (xy 340.863299 -281.890441) (xy 340.909278 -281.912258)
			(xy 340.951162 -281.941168) (xy 340.987866 -281.976423) (xy 341.018439 -282.017109) (xy 341.04209 -282.062172)
			(xy 341.058206 -282.110446) (xy 341.06637 -282.16068) (xy 341.066882 -282.186126) (xy 341.38541 -282.186126)
			(xy 341.38937 -282.137072) (xy 341.401147 -282.089288) (xy 341.420438 -282.044012) (xy 341.446741 -282.002416)
			(xy 341.479376 -281.965579) (xy 341.517497 -281.934454) (xy 341.560118 -281.909847) (xy 341.606134 -281.892395)
			(xy 341.654353 -281.882551) (xy 341.703528 -281.88057) (xy 341.752383 -281.886502) (xy 341.799654 -281.900194)
			(xy 341.844116 -281.921292) (xy 341.884619 -281.949248) (xy 341.920112 -281.98334) (xy 341.949677 -282.022684)
			(xy 341.972548 -282.066261) (xy 341.988132 -282.112942) (xy 341.996027 -282.161519) (xy 341.996522 -282.186126)
			(xy 342.314779 -282.186126) (xy 342.318874 -282.135398) (xy 342.331053 -282.085984) (xy 342.351001 -282.039164)
			(xy 342.378202 -281.99615) (xy 342.41195 -281.958056) (xy 342.451372 -281.925869) (xy 342.495446 -281.900423)
			(xy 342.543032 -281.882376) (xy 342.592896 -281.872196) (xy 342.643748 -281.870147) (xy 342.694269 -281.876281)
			(xy 342.743153 -281.890441) (xy 342.789132 -281.912258) (xy 342.831016 -281.941168) (xy 342.86772 -281.976423)
			(xy 342.898293 -282.017109) (xy 342.921944 -282.062172) (xy 342.93806 -282.110446) (xy 342.946224 -282.16068)
			(xy 342.946736 -282.186126) (xy 343.254833 -282.186126) (xy 343.258928 -282.135398) (xy 343.271107 -282.085984)
			(xy 343.291055 -282.039164) (xy 343.318256 -281.99615) (xy 343.352004 -281.958056) (xy 343.391426 -281.925869)
			(xy 343.4355 -281.900423) (xy 343.483086 -281.882376) (xy 343.53295 -281.872196) (xy 343.583802 -281.870147)
			(xy 343.634323 -281.876281) (xy 343.683207 -281.890441) (xy 343.729186 -281.912258) (xy 343.77107 -281.941168)
			(xy 343.807774 -281.976423) (xy 343.838347 -282.017109) (xy 343.861998 -282.062172) (xy 343.878114 -282.110446)
			(xy 343.886278 -282.16068) (xy 343.88679 -282.186126) (xy 345.145372 -282.186126) (xy 345.149332 -282.137072)
			(xy 345.161109 -282.089288) (xy 345.1804 -282.044012) (xy 345.206703 -282.002416) (xy 345.239338 -281.965579)
			(xy 345.277459 -281.934454) (xy 345.32008 -281.909847) (xy 345.366096 -281.892395) (xy 345.414315 -281.882551)
			(xy 345.46349 -281.88057) (xy 345.512345 -281.886502) (xy 345.559616 -281.900194) (xy 345.604078 -281.921292)
			(xy 345.644581 -281.949248) (xy 345.680074 -281.98334) (xy 345.709639 -282.022684) (xy 345.73251 -282.066261)
			(xy 345.748094 -282.112942) (xy 345.755989 -282.161519) (xy 345.756484 -282.186126) (xy 346.085426 -282.186126)
			(xy 346.089386 -282.137072) (xy 346.101163 -282.089288) (xy 346.120454 -282.044012) (xy 346.146757 -282.002416)
			(xy 346.179392 -281.965579) (xy 346.217513 -281.934454) (xy 346.260134 -281.909847) (xy 346.30615 -281.892395)
			(xy 346.354369 -281.882551) (xy 346.403544 -281.88057) (xy 346.452399 -281.886502) (xy 346.49967 -281.900194)
			(xy 346.544132 -281.921292) (xy 346.584635 -281.949248) (xy 346.620128 -281.98334) (xy 346.649693 -282.022684)
			(xy 346.672564 -282.066261) (xy 346.688148 -282.112942) (xy 346.696043 -282.161519) (xy 346.696538 -282.186126)
			(xy 347.025226 -282.186126) (xy 347.029186 -282.137072) (xy 347.040963 -282.089288) (xy 347.060254 -282.044012)
			(xy 347.086557 -282.002416) (xy 347.119192 -281.965579) (xy 347.157313 -281.934454) (xy 347.199934 -281.909847)
			(xy 347.24595 -281.892395) (xy 347.294169 -281.882551) (xy 347.343344 -281.88057) (xy 347.392199 -281.886502)
			(xy 347.43947 -281.900194) (xy 347.483932 -281.921292) (xy 347.524435 -281.949248) (xy 347.559928 -281.98334)
			(xy 347.589493 -282.022684) (xy 347.612364 -282.066261) (xy 347.627948 -282.112942) (xy 347.635843 -282.161519)
			(xy 347.636338 -282.186126) (xy 347.96528 -282.186126) (xy 347.96924 -282.137072) (xy 347.981017 -282.089288)
			(xy 348.000308 -282.044012) (xy 348.026611 -282.002416) (xy 348.059246 -281.965579) (xy 348.097367 -281.934454)
			(xy 348.139988 -281.909847) (xy 348.186004 -281.892395) (xy 348.234223 -281.882551) (xy 348.283398 -281.88057)
			(xy 348.332253 -281.886502) (xy 348.379524 -281.900194) (xy 348.423986 -281.921292) (xy 348.464489 -281.949248)
			(xy 348.499982 -281.98334) (xy 348.529547 -282.022684) (xy 348.552418 -282.066261) (xy 348.568002 -282.112942)
			(xy 348.575897 -282.161519) (xy 348.576392 -282.186126) (xy 348.905334 -282.186126) (xy 348.909294 -282.137072)
			(xy 348.921071 -282.089288) (xy 348.940362 -282.044012) (xy 348.966665 -282.002416) (xy 348.9993 -281.965579)
			(xy 349.037421 -281.934454) (xy 349.080042 -281.909847) (xy 349.126058 -281.892395) (xy 349.174277 -281.882551)
			(xy 349.223452 -281.88057) (xy 349.272307 -281.886502) (xy 349.319578 -281.900194) (xy 349.36404 -281.921292)
			(xy 349.404543 -281.949248) (xy 349.440036 -281.98334) (xy 349.469601 -282.022684) (xy 349.492472 -282.066261)
			(xy 349.508056 -282.112942) (xy 349.515951 -282.161519) (xy 349.516446 -282.186126) (xy 349.845388 -282.186126)
			(xy 349.849348 -282.137072) (xy 349.861125 -282.089288) (xy 349.880416 -282.044012) (xy 349.906719 -282.002416)
			(xy 349.939354 -281.965579) (xy 349.977475 -281.934454) (xy 350.020096 -281.909847) (xy 350.066112 -281.892395)
			(xy 350.114331 -281.882551) (xy 350.163506 -281.88057) (xy 350.212361 -281.886502) (xy 350.259632 -281.900194)
			(xy 350.304094 -281.921292) (xy 350.344597 -281.949248) (xy 350.38009 -281.98334) (xy 350.409655 -282.022684)
			(xy 350.432526 -282.066261) (xy 350.44811 -282.112942) (xy 350.456005 -282.161519) (xy 350.4565 -282.186126)
			(xy 350.785442 -282.186126) (xy 350.789402 -282.137072) (xy 350.801179 -282.089288) (xy 350.82047 -282.044012)
			(xy 350.846773 -282.002416) (xy 350.879408 -281.965579) (xy 350.917529 -281.934454) (xy 350.96015 -281.909847)
			(xy 351.006166 -281.892395) (xy 351.054385 -281.882551) (xy 351.10356 -281.88057) (xy 351.152415 -281.886502)
			(xy 351.199686 -281.900194) (xy 351.244148 -281.921292) (xy 351.284651 -281.949248) (xy 351.320144 -281.98334)
			(xy 351.349709 -282.022684) (xy 351.37258 -282.066261) (xy 351.388164 -282.112942) (xy 351.396059 -282.161519)
			(xy 351.396554 -282.186126) (xy 351.396059 -282.210733) (xy 351.388164 -282.25931) (xy 351.37258 -282.305991)
			(xy 351.349709 -282.349568) (xy 351.320144 -282.388912) (xy 351.284651 -282.423004) (xy 351.244148 -282.45096)
			(xy 351.199686 -282.472058) (xy 351.152415 -282.48575) (xy 351.10356 -282.491682) (xy 351.054385 -282.489701)
			(xy 351.006166 -282.479857) (xy 350.96015 -282.462405) (xy 350.917529 -282.437798) (xy 350.879408 -282.406673)
			(xy 350.846773 -282.369836) (xy 350.82047 -282.32824) (xy 350.801179 -282.282964) (xy 350.789402 -282.23518)
			(xy 350.785442 -282.186126) (xy 350.4565 -282.186126) (xy 350.456005 -282.210733) (xy 350.44811 -282.25931)
			(xy 350.432526 -282.305991) (xy 350.409655 -282.349568) (xy 350.38009 -282.388912) (xy 350.344597 -282.423004)
			(xy 350.304094 -282.45096) (xy 350.259632 -282.472058) (xy 350.212361 -282.48575) (xy 350.163506 -282.491682)
			(xy 350.114331 -282.489701) (xy 350.066112 -282.479857) (xy 350.020096 -282.462405) (xy 349.977475 -282.437798)
			(xy 349.939354 -282.406673) (xy 349.906719 -282.369836) (xy 349.880416 -282.32824) (xy 349.861125 -282.282964)
			(xy 349.849348 -282.23518) (xy 349.845388 -282.186126) (xy 349.516446 -282.186126) (xy 349.515951 -282.210733)
			(xy 349.508056 -282.25931) (xy 349.492472 -282.305991) (xy 349.469601 -282.349568) (xy 349.440036 -282.388912)
			(xy 349.404543 -282.423004) (xy 349.36404 -282.45096) (xy 349.319578 -282.472058) (xy 349.272307 -282.48575)
			(xy 349.223452 -282.491682) (xy 349.174277 -282.489701) (xy 349.126058 -282.479857) (xy 349.080042 -282.462405)
			(xy 349.037421 -282.437798) (xy 348.9993 -282.406673) (xy 348.966665 -282.369836) (xy 348.940362 -282.32824)
			(xy 348.921071 -282.282964) (xy 348.909294 -282.23518) (xy 348.905334 -282.186126) (xy 348.576392 -282.186126)
			(xy 348.575897 -282.210733) (xy 348.568002 -282.25931) (xy 348.552418 -282.305991) (xy 348.529547 -282.349568)
			(xy 348.499982 -282.388912) (xy 348.464489 -282.423004) (xy 348.423986 -282.45096) (xy 348.379524 -282.472058)
			(xy 348.332253 -282.48575) (xy 348.283398 -282.491682) (xy 348.234223 -282.489701) (xy 348.186004 -282.479857)
			(xy 348.139988 -282.462405) (xy 348.097367 -282.437798) (xy 348.059246 -282.406673) (xy 348.026611 -282.369836)
			(xy 348.000308 -282.32824) (xy 347.981017 -282.282964) (xy 347.96924 -282.23518) (xy 347.96528 -282.186126)
			(xy 347.636338 -282.186126) (xy 347.635843 -282.210733) (xy 347.627948 -282.25931) (xy 347.612364 -282.305991)
			(xy 347.589493 -282.349568) (xy 347.559928 -282.388912) (xy 347.524435 -282.423004) (xy 347.483932 -282.45096)
			(xy 347.43947 -282.472058) (xy 347.392199 -282.48575) (xy 347.343344 -282.491682) (xy 347.294169 -282.489701)
			(xy 347.24595 -282.479857) (xy 347.199934 -282.462405) (xy 347.157313 -282.437798) (xy 347.119192 -282.406673)
			(xy 347.086557 -282.369836) (xy 347.060254 -282.32824) (xy 347.040963 -282.282964) (xy 347.029186 -282.23518)
			(xy 347.025226 -282.186126) (xy 346.696538 -282.186126) (xy 346.696043 -282.210733) (xy 346.688148 -282.25931)
			(xy 346.672564 -282.305991) (xy 346.649693 -282.349568) (xy 346.620128 -282.388912) (xy 346.584635 -282.423004)
			(xy 346.544132 -282.45096) (xy 346.49967 -282.472058) (xy 346.452399 -282.48575) (xy 346.403544 -282.491682)
			(xy 346.354369 -282.489701) (xy 346.30615 -282.479857) (xy 346.260134 -282.462405) (xy 346.217513 -282.437798)
			(xy 346.179392 -282.406673) (xy 346.146757 -282.369836) (xy 346.120454 -282.32824) (xy 346.101163 -282.282964)
			(xy 346.089386 -282.23518) (xy 346.085426 -282.186126) (xy 345.756484 -282.186126) (xy 345.755989 -282.210733)
			(xy 345.748094 -282.25931) (xy 345.73251 -282.305991) (xy 345.709639 -282.349568) (xy 345.680074 -282.388912)
			(xy 345.644581 -282.423004) (xy 345.604078 -282.45096) (xy 345.559616 -282.472058) (xy 345.512345 -282.48575)
			(xy 345.46349 -282.491682) (xy 345.414315 -282.489701) (xy 345.366096 -282.479857) (xy 345.32008 -282.462405)
			(xy 345.277459 -282.437798) (xy 345.239338 -282.406673) (xy 345.206703 -282.369836) (xy 345.1804 -282.32824)
			(xy 345.161109 -282.282964) (xy 345.149332 -282.23518) (xy 345.145372 -282.186126) (xy 343.88679 -282.186126)
			(xy 343.886278 -282.211572) (xy 343.878114 -282.261806) (xy 343.861998 -282.31008) (xy 343.838347 -282.355143)
			(xy 343.807774 -282.395829) (xy 343.77107 -282.431084) (xy 343.729186 -282.459994) (xy 343.683207 -282.481811)
			(xy 343.634323 -282.495971) (xy 343.583802 -282.502105) (xy 343.53295 -282.500056) (xy 343.483086 -282.489876)
			(xy 343.4355 -282.471829) (xy 343.391426 -282.446383) (xy 343.352004 -282.414196) (xy 343.318256 -282.376102)
			(xy 343.291055 -282.333088) (xy 343.271107 -282.286268) (xy 343.258928 -282.236854) (xy 343.254833 -282.186126)
			(xy 342.946736 -282.186126) (xy 342.946224 -282.211572) (xy 342.93806 -282.261806) (xy 342.921944 -282.31008)
			(xy 342.898293 -282.355143) (xy 342.86772 -282.395829) (xy 342.831016 -282.431084) (xy 342.789132 -282.459994)
			(xy 342.743153 -282.481811) (xy 342.694269 -282.495971) (xy 342.643748 -282.502105) (xy 342.592896 -282.500056)
			(xy 342.543032 -282.489876) (xy 342.495446 -282.471829) (xy 342.451372 -282.446383) (xy 342.41195 -282.414196)
			(xy 342.378202 -282.376102) (xy 342.351001 -282.333088) (xy 342.331053 -282.286268) (xy 342.318874 -282.236854)
			(xy 342.314779 -282.186126) (xy 341.996522 -282.186126) (xy 341.996027 -282.210733) (xy 341.988132 -282.25931)
			(xy 341.972548 -282.305991) (xy 341.949677 -282.349568) (xy 341.920112 -282.388912) (xy 341.884619 -282.423004)
			(xy 341.844116 -282.45096) (xy 341.799654 -282.472058) (xy 341.752383 -282.48575) (xy 341.703528 -282.491682)
			(xy 341.654353 -282.489701) (xy 341.606134 -282.479857) (xy 341.560118 -282.462405) (xy 341.517497 -282.437798)
			(xy 341.479376 -282.406673) (xy 341.446741 -282.369836) (xy 341.420438 -282.32824) (xy 341.401147 -282.282964)
			(xy 341.38937 -282.23518) (xy 341.38541 -282.186126) (xy 341.066882 -282.186126) (xy 341.06637 -282.211572)
			(xy 341.058206 -282.261806) (xy 341.04209 -282.31008) (xy 341.018439 -282.355143) (xy 340.987866 -282.395829)
			(xy 340.951162 -282.431084) (xy 340.909278 -282.459994) (xy 340.863299 -282.481811) (xy 340.814415 -282.495971)
			(xy 340.763894 -282.502105) (xy 340.713042 -282.500056) (xy 340.663178 -282.489876) (xy 340.615592 -282.471829)
			(xy 340.571518 -282.446383) (xy 340.532096 -282.414196) (xy 340.498348 -282.376102) (xy 340.471147 -282.333088)
			(xy 340.451199 -282.286268) (xy 340.43902 -282.236854) (xy 340.434925 -282.186126) (xy 340.116414 -282.186126)
			(xy 340.115919 -282.210733) (xy 340.108024 -282.25931) (xy 340.09244 -282.305991) (xy 340.069569 -282.349568)
			(xy 340.040004 -282.388912) (xy 340.004511 -282.423004) (xy 339.964008 -282.45096) (xy 339.919546 -282.472058)
			(xy 339.872275 -282.48575) (xy 339.82342 -282.491682) (xy 339.774245 -282.489701) (xy 339.726026 -282.479857)
			(xy 339.68001 -282.462405) (xy 339.637389 -282.437798) (xy 339.599268 -282.406673) (xy 339.566633 -282.369836)
			(xy 339.54033 -282.32824) (xy 339.521039 -282.282964) (xy 339.509262 -282.23518) (xy 339.505302 -282.186126)
			(xy 339.186774 -282.186126) (xy 339.186262 -282.211572) (xy 339.178098 -282.261806) (xy 339.161982 -282.31008)
			(xy 339.138331 -282.355143) (xy 339.107758 -282.395829) (xy 339.071054 -282.431084) (xy 339.02917 -282.459994)
			(xy 338.983191 -282.481811) (xy 338.934307 -282.495971) (xy 338.883786 -282.502105) (xy 338.832934 -282.500056)
			(xy 338.78307 -282.489876) (xy 338.735484 -282.471829) (xy 338.69141 -282.446383) (xy 338.651988 -282.414196)
			(xy 338.61824 -282.376102) (xy 338.591039 -282.333088) (xy 338.571091 -282.286268) (xy 338.558912 -282.236854)
			(xy 338.554817 -282.186126) (xy 338.236306 -282.186126) (xy 338.235811 -282.210733) (xy 338.227916 -282.25931)
			(xy 338.212332 -282.305991) (xy 338.189461 -282.349568) (xy 338.159896 -282.388912) (xy 338.124403 -282.423004)
			(xy 338.0839 -282.45096) (xy 338.039438 -282.472058) (xy 337.992167 -282.48575) (xy 337.943312 -282.491682)
			(xy 337.894137 -282.489701) (xy 337.845918 -282.479857) (xy 337.799902 -282.462405) (xy 337.757281 -282.437798)
			(xy 337.71916 -282.406673) (xy 337.686525 -282.369836) (xy 337.660222 -282.32824) (xy 337.640931 -282.282964)
			(xy 337.629154 -282.23518) (xy 337.625194 -282.186126) (xy 337.30692 -282.186126) (xy 337.306408 -282.211572)
			(xy 337.298244 -282.261806) (xy 337.282128 -282.31008) (xy 337.258477 -282.355143) (xy 337.227904 -282.395829)
			(xy 337.1912 -282.431084) (xy 337.149316 -282.459994) (xy 337.103337 -282.481811) (xy 337.054453 -282.495971)
			(xy 337.003932 -282.502105) (xy 336.95308 -282.500056) (xy 336.903216 -282.489876) (xy 336.85563 -282.471829)
			(xy 336.811556 -282.446383) (xy 336.772134 -282.414196) (xy 336.738386 -282.376102) (xy 336.711185 -282.333088)
			(xy 336.691237 -282.286268) (xy 336.679058 -282.236854) (xy 336.674963 -282.186126) (xy 336.366866 -282.186126)
			(xy 336.366354 -282.211572) (xy 336.35819 -282.261806) (xy 336.342074 -282.31008) (xy 336.318423 -282.355143)
			(xy 336.28785 -282.395829) (xy 336.251146 -282.431084) (xy 336.209262 -282.459994) (xy 336.163283 -282.481811)
			(xy 336.114399 -282.495971) (xy 336.063878 -282.502105) (xy 336.013026 -282.500056) (xy 335.963162 -282.489876)
			(xy 335.915576 -282.471829) (xy 335.871502 -282.446383) (xy 335.83208 -282.414196) (xy 335.798332 -282.376102)
			(xy 335.771131 -282.333088) (xy 335.751183 -282.286268) (xy 335.739004 -282.236854) (xy 335.734909 -282.186126)
			(xy 335.416398 -282.186126) (xy 335.415903 -282.210733) (xy 335.408008 -282.25931) (xy 335.392424 -282.305991)
			(xy 335.369553 -282.349568) (xy 335.339988 -282.388912) (xy 335.304495 -282.423004) (xy 335.263992 -282.45096)
			(xy 335.21953 -282.472058) (xy 335.172259 -282.48575) (xy 335.123404 -282.491682) (xy 335.074229 -282.489701)
			(xy 335.02601 -282.479857) (xy 334.979994 -282.462405) (xy 334.937373 -282.437798) (xy 334.899252 -282.406673)
			(xy 334.866617 -282.369836) (xy 334.840314 -282.32824) (xy 334.821023 -282.282964) (xy 334.809246 -282.23518)
			(xy 334.805286 -282.186126) (xy 334.486758 -282.186126) (xy 334.486246 -282.211572) (xy 334.478082 -282.261806)
			(xy 334.461966 -282.31008) (xy 334.438315 -282.355143) (xy 334.407742 -282.395829) (xy 334.371038 -282.431084)
			(xy 334.329154 -282.459994) (xy 334.283175 -282.481811) (xy 334.234291 -282.495971) (xy 334.18377 -282.502105)
			(xy 334.132918 -282.500056) (xy 334.083054 -282.489876) (xy 334.035468 -282.471829) (xy 333.991394 -282.446383)
			(xy 333.951972 -282.414196) (xy 333.918224 -282.376102) (xy 333.891023 -282.333088) (xy 333.871075 -282.286268)
			(xy 333.858896 -282.236854) (xy 333.854801 -282.186126) (xy 333.53629 -282.186126) (xy 333.535795 -282.210733)
			(xy 333.5279 -282.25931) (xy 333.512316 -282.305991) (xy 333.489445 -282.349568) (xy 333.45988 -282.388912)
			(xy 333.424387 -282.423004) (xy 333.383884 -282.45096) (xy 333.339422 -282.472058) (xy 333.292151 -282.48575)
			(xy 333.243296 -282.491682) (xy 333.194121 -282.489701) (xy 333.145902 -282.479857) (xy 333.099886 -282.462405)
			(xy 333.057265 -282.437798) (xy 333.019144 -282.406673) (xy 332.986509 -282.369836) (xy 332.960206 -282.32824)
			(xy 332.940915 -282.282964) (xy 332.929138 -282.23518) (xy 332.925178 -282.186126) (xy 332.606904 -282.186126)
			(xy 332.606392 -282.211572) (xy 332.598228 -282.261806) (xy 332.582112 -282.31008) (xy 332.558461 -282.355143)
			(xy 332.527888 -282.395829) (xy 332.491184 -282.431084) (xy 332.4493 -282.459994) (xy 332.403321 -282.481811)
			(xy 332.354437 -282.495971) (xy 332.303916 -282.502105) (xy 332.253064 -282.500056) (xy 332.2032 -282.489876)
			(xy 332.155614 -282.471829) (xy 332.11154 -282.446383) (xy 332.072118 -282.414196) (xy 332.03837 -282.376102)
			(xy 332.011169 -282.333088) (xy 331.991221 -282.286268) (xy 331.979042 -282.236854) (xy 331.974947 -282.186126)
			(xy 331.656436 -282.186126) (xy 331.655941 -282.210733) (xy 331.648046 -282.25931) (xy 331.632462 -282.305991)
			(xy 331.609591 -282.349568) (xy 331.580026 -282.388912) (xy 331.544533 -282.423004) (xy 331.50403 -282.45096)
			(xy 331.459568 -282.472058) (xy 331.412297 -282.48575) (xy 331.363442 -282.491682) (xy 331.314267 -282.489701)
			(xy 331.266048 -282.479857) (xy 331.220032 -282.462405) (xy 331.177411 -282.437798) (xy 331.13929 -282.406673)
			(xy 331.106655 -282.369836) (xy 331.080352 -282.32824) (xy 331.061061 -282.282964) (xy 331.049284 -282.23518)
			(xy 331.045324 -282.186126) (xy 330.726796 -282.186126) (xy 330.726284 -282.211572) (xy 330.71812 -282.261806)
			(xy 330.702004 -282.31008) (xy 330.678353 -282.355143) (xy 330.64778 -282.395829) (xy 330.611076 -282.431084)
			(xy 330.569192 -282.459994) (xy 330.523213 -282.481811) (xy 330.474329 -282.495971) (xy 330.423808 -282.502105)
			(xy 330.372956 -282.500056) (xy 330.323092 -282.489876) (xy 330.275506 -282.471829) (xy 330.231432 -282.446383)
			(xy 330.19201 -282.414196) (xy 330.158262 -282.376102) (xy 330.131061 -282.333088) (xy 330.111113 -282.286268)
			(xy 330.098934 -282.236854) (xy 330.094839 -282.186126) (xy 329.786742 -282.186126) (xy 329.78623 -282.211572)
			(xy 329.778066 -282.261806) (xy 329.76195 -282.31008) (xy 329.738299 -282.355143) (xy 329.707726 -282.395829)
			(xy 329.671022 -282.431084) (xy 329.629138 -282.459994) (xy 329.583159 -282.481811) (xy 329.534275 -282.495971)
			(xy 329.483754 -282.502105) (xy 329.432902 -282.500056) (xy 329.383038 -282.489876) (xy 329.335452 -282.471829)
			(xy 329.291378 -282.446383) (xy 329.251956 -282.414196) (xy 329.218208 -282.376102) (xy 329.191007 -282.333088)
			(xy 329.171059 -282.286268) (xy 329.15888 -282.236854) (xy 329.154785 -282.186126) (xy 328.836528 -282.186126)
			(xy 328.836033 -282.210733) (xy 328.828138 -282.25931) (xy 328.812554 -282.305991) (xy 328.789683 -282.349568)
			(xy 328.760118 -282.388912) (xy 328.724625 -282.423004) (xy 328.684122 -282.45096) (xy 328.63966 -282.472058)
			(xy 328.592389 -282.48575) (xy 328.543534 -282.491682) (xy 328.494359 -282.489701) (xy 328.44614 -282.479857)
			(xy 328.400124 -282.462405) (xy 328.357503 -282.437798) (xy 328.319382 -282.406673) (xy 328.286747 -282.369836)
			(xy 328.260444 -282.32824) (xy 328.241153 -282.282964) (xy 328.229376 -282.23518) (xy 328.225416 -282.186126)
			(xy 326.95642 -282.186126) (xy 326.955925 -282.210733) (xy 326.94803 -282.25931) (xy 326.932446 -282.305991)
			(xy 326.909575 -282.349568) (xy 326.88001 -282.388912) (xy 326.844517 -282.423004) (xy 326.804014 -282.45096)
			(xy 326.759552 -282.472058) (xy 326.712281 -282.48575) (xy 326.663426 -282.491682) (xy 326.614251 -282.489701)
			(xy 326.566032 -282.479857) (xy 326.520016 -282.462405) (xy 326.477395 -282.437798) (xy 326.439274 -282.406673)
			(xy 326.406639 -282.369836) (xy 326.380336 -282.32824) (xy 326.361045 -282.282964) (xy 326.349268 -282.23518)
			(xy 326.345308 -282.186126) (xy 310.45912 -282.186126) (xy 310.45912 -282.730194) (xy 324.74714 -282.730194)
			(xy 324.7511 -282.68114) (xy 324.762877 -282.633356) (xy 324.782168 -282.58808) (xy 324.808471 -282.546484)
			(xy 324.841106 -282.509647) (xy 324.879227 -282.478522) (xy 324.921848 -282.453915) (xy 324.967864 -282.436463)
			(xy 325.016083 -282.426619) (xy 325.065258 -282.424638) (xy 325.114113 -282.43057) (xy 325.161384 -282.444262)
			(xy 325.205846 -282.46536) (xy 325.246349 -282.493316) (xy 325.281842 -282.527408) (xy 325.311407 -282.566752)
			(xy 325.334278 -282.610329) (xy 325.349862 -282.65701) (xy 325.357757 -282.705587) (xy 325.358252 -282.730194)
			(xy 325.357757 -282.754801) (xy 325.349862 -282.803378) (xy 325.334278 -282.850059) (xy 325.311407 -282.893636)
			(xy 325.281842 -282.93298) (xy 325.246349 -282.967072) (xy 325.205846 -282.995028) (xy 325.203519 -282.996132)
			(xy 328.684885 -282.996132) (xy 328.68898 -282.945404) (xy 328.701159 -282.89599) (xy 328.721107 -282.84917)
			(xy 328.748308 -282.806156) (xy 328.782056 -282.768062) (xy 328.821478 -282.735875) (xy 328.865552 -282.710429)
			(xy 328.913138 -282.692382) (xy 328.963002 -282.682202) (xy 329.013854 -282.680153) (xy 329.064375 -282.686287)
			(xy 329.113259 -282.700447) (xy 329.159238 -282.722264) (xy 329.201122 -282.751174) (xy 329.237826 -282.786429)
			(xy 329.268399 -282.827115) (xy 329.29205 -282.872178) (xy 329.308166 -282.920452) (xy 329.31633 -282.970686)
			(xy 329.316842 -282.996132) (xy 329.63537 -282.996132) (xy 329.63933 -282.947078) (xy 329.651107 -282.899294)
			(xy 329.670398 -282.854018) (xy 329.696701 -282.812422) (xy 329.729336 -282.775585) (xy 329.767457 -282.74446)
			(xy 329.810078 -282.719853) (xy 329.856094 -282.702401) (xy 329.904313 -282.692557) (xy 329.953488 -282.690576)
			(xy 330.002343 -282.696508) (xy 330.049614 -282.7102) (xy 330.094076 -282.731298) (xy 330.134579 -282.759254)
			(xy 330.170072 -282.793346) (xy 330.199637 -282.83269) (xy 330.222508 -282.876267) (xy 330.238092 -282.922948)
			(xy 330.245987 -282.971525) (xy 330.246482 -282.996132) (xy 330.564739 -282.996132) (xy 330.568834 -282.945404)
			(xy 330.581013 -282.89599) (xy 330.600961 -282.84917) (xy 330.628162 -282.806156) (xy 330.66191 -282.768062)
			(xy 330.701332 -282.735875) (xy 330.745406 -282.710429) (xy 330.792992 -282.692382) (xy 330.842856 -282.682202)
			(xy 330.893708 -282.680153) (xy 330.944229 -282.686287) (xy 330.993113 -282.700447) (xy 331.039092 -282.722264)
			(xy 331.080976 -282.751174) (xy 331.11768 -282.786429) (xy 331.148253 -282.827115) (xy 331.171904 -282.872178)
			(xy 331.18802 -282.920452) (xy 331.196184 -282.970686) (xy 331.196696 -282.996132) (xy 331.515224 -282.996132)
			(xy 331.519184 -282.947078) (xy 331.530961 -282.899294) (xy 331.550252 -282.854018) (xy 331.576555 -282.812422)
			(xy 331.60919 -282.775585) (xy 331.647311 -282.74446) (xy 331.689932 -282.719853) (xy 331.735948 -282.702401)
			(xy 331.784167 -282.692557) (xy 331.833342 -282.690576) (xy 331.882197 -282.696508) (xy 331.929468 -282.7102)
			(xy 331.97393 -282.731298) (xy 332.014433 -282.759254) (xy 332.049926 -282.793346) (xy 332.079491 -282.83269)
			(xy 332.102362 -282.876267) (xy 332.117946 -282.922948) (xy 332.125841 -282.971525) (xy 332.126336 -282.996132)
			(xy 332.444847 -282.996132) (xy 332.448942 -282.945404) (xy 332.461121 -282.89599) (xy 332.481069 -282.84917)
			(xy 332.50827 -282.806156) (xy 332.542018 -282.768062) (xy 332.58144 -282.735875) (xy 332.625514 -282.710429)
			(xy 332.6731 -282.692382) (xy 332.722964 -282.682202) (xy 332.773816 -282.680153) (xy 332.824337 -282.686287)
			(xy 332.873221 -282.700447) (xy 332.9192 -282.722264) (xy 332.961084 -282.751174) (xy 332.997788 -282.786429)
			(xy 333.028361 -282.827115) (xy 333.052012 -282.872178) (xy 333.068128 -282.920452) (xy 333.076292 -282.970686)
			(xy 333.076804 -282.996132) (xy 333.384901 -282.996132) (xy 333.388996 -282.945404) (xy 333.401175 -282.89599)
			(xy 333.421123 -282.84917) (xy 333.448324 -282.806156) (xy 333.482072 -282.768062) (xy 333.521494 -282.735875)
			(xy 333.565568 -282.710429) (xy 333.613154 -282.692382) (xy 333.663018 -282.682202) (xy 333.71387 -282.680153)
			(xy 333.764391 -282.686287) (xy 333.813275 -282.700447) (xy 333.859254 -282.722264) (xy 333.901138 -282.751174)
			(xy 333.937842 -282.786429) (xy 333.968415 -282.827115) (xy 333.992066 -282.872178) (xy 334.008182 -282.920452)
			(xy 334.016346 -282.970686) (xy 334.016858 -282.996132) (xy 335.264755 -282.996132) (xy 335.26885 -282.945404)
			(xy 335.281029 -282.89599) (xy 335.300977 -282.84917) (xy 335.328178 -282.806156) (xy 335.361926 -282.768062)
			(xy 335.401348 -282.735875) (xy 335.445422 -282.710429) (xy 335.493008 -282.692382) (xy 335.542872 -282.682202)
			(xy 335.593724 -282.680153) (xy 335.644245 -282.686287) (xy 335.693129 -282.700447) (xy 335.739108 -282.722264)
			(xy 335.780992 -282.751174) (xy 335.817696 -282.786429) (xy 335.848269 -282.827115) (xy 335.87192 -282.872178)
			(xy 335.888036 -282.920452) (xy 335.8962 -282.970686) (xy 335.896712 -282.996132) (xy 336.21524 -282.996132)
			(xy 336.2192 -282.947078) (xy 336.230977 -282.899294) (xy 336.250268 -282.854018) (xy 336.276571 -282.812422)
			(xy 336.309206 -282.775585) (xy 336.347327 -282.74446) (xy 336.389948 -282.719853) (xy 336.435964 -282.702401)
			(xy 336.484183 -282.692557) (xy 336.533358 -282.690576) (xy 336.582213 -282.696508) (xy 336.629484 -282.7102)
			(xy 336.673946 -282.731298) (xy 336.714449 -282.759254) (xy 336.749942 -282.793346) (xy 336.779507 -282.83269)
			(xy 336.802378 -282.876267) (xy 336.817962 -282.922948) (xy 336.825857 -282.971525) (xy 336.826352 -282.996132)
			(xy 337.144863 -282.996132) (xy 337.148958 -282.945404) (xy 337.161137 -282.89599) (xy 337.181085 -282.84917)
			(xy 337.208286 -282.806156) (xy 337.242034 -282.768062) (xy 337.281456 -282.735875) (xy 337.32553 -282.710429)
			(xy 337.373116 -282.692382) (xy 337.42298 -282.682202) (xy 337.473832 -282.680153) (xy 337.524353 -282.686287)
			(xy 337.573237 -282.700447) (xy 337.619216 -282.722264) (xy 337.6611 -282.751174) (xy 337.697804 -282.786429)
			(xy 337.728377 -282.827115) (xy 337.752028 -282.872178) (xy 337.768144 -282.920452) (xy 337.776308 -282.970686)
			(xy 337.77682 -282.996132) (xy 338.095348 -282.996132) (xy 338.099308 -282.947078) (xy 338.111085 -282.899294)
			(xy 338.130376 -282.854018) (xy 338.156679 -282.812422) (xy 338.189314 -282.775585) (xy 338.227435 -282.74446)
			(xy 338.270056 -282.719853) (xy 338.316072 -282.702401) (xy 338.364291 -282.692557) (xy 338.413466 -282.690576)
			(xy 338.462321 -282.696508) (xy 338.509592 -282.7102) (xy 338.554054 -282.731298) (xy 338.594557 -282.759254)
			(xy 338.63005 -282.793346) (xy 338.659615 -282.83269) (xy 338.682486 -282.876267) (xy 338.69807 -282.922948)
			(xy 338.705965 -282.971525) (xy 338.70646 -282.996132) (xy 339.024971 -282.996132) (xy 339.029066 -282.945404)
			(xy 339.041245 -282.89599) (xy 339.061193 -282.84917) (xy 339.088394 -282.806156) (xy 339.122142 -282.768062)
			(xy 339.161564 -282.735875) (xy 339.205638 -282.710429) (xy 339.253224 -282.692382) (xy 339.303088 -282.682202)
			(xy 339.35394 -282.680153) (xy 339.404461 -282.686287) (xy 339.453345 -282.700447) (xy 339.499324 -282.722264)
			(xy 339.541208 -282.751174) (xy 339.577912 -282.786429) (xy 339.608485 -282.827115) (xy 339.632136 -282.872178)
			(xy 339.648252 -282.920452) (xy 339.656416 -282.970686) (xy 339.656928 -282.996132) (xy 339.964771 -282.996132)
			(xy 339.968866 -282.945404) (xy 339.981045 -282.89599) (xy 340.000993 -282.84917) (xy 340.028194 -282.806156)
			(xy 340.061942 -282.768062) (xy 340.101364 -282.735875) (xy 340.145438 -282.710429) (xy 340.193024 -282.692382)
			(xy 340.242888 -282.682202) (xy 340.29374 -282.680153) (xy 340.344261 -282.686287) (xy 340.393145 -282.700447)
			(xy 340.439124 -282.722264) (xy 340.481008 -282.751174) (xy 340.517712 -282.786429) (xy 340.548285 -282.827115)
			(xy 340.571936 -282.872178) (xy 340.588052 -282.920452) (xy 340.596216 -282.970686) (xy 340.596728 -282.996132)
			(xy 341.844879 -282.996132) (xy 341.848974 -282.945404) (xy 341.861153 -282.89599) (xy 341.881101 -282.84917)
			(xy 341.908302 -282.806156) (xy 341.94205 -282.768062) (xy 341.981472 -282.735875) (xy 342.025546 -282.710429)
			(xy 342.073132 -282.692382) (xy 342.122996 -282.682202) (xy 342.173848 -282.680153) (xy 342.224369 -282.686287)
			(xy 342.273253 -282.700447) (xy 342.319232 -282.722264) (xy 342.361116 -282.751174) (xy 342.39782 -282.786429)
			(xy 342.428393 -282.827115) (xy 342.452044 -282.872178) (xy 342.46816 -282.920452) (xy 342.476324 -282.970686)
			(xy 342.476836 -282.996132) (xy 342.795364 -282.996132) (xy 342.799324 -282.947078) (xy 342.811101 -282.899294)
			(xy 342.830392 -282.854018) (xy 342.856695 -282.812422) (xy 342.88933 -282.775585) (xy 342.927451 -282.74446)
			(xy 342.970072 -282.719853) (xy 343.016088 -282.702401) (xy 343.064307 -282.692557) (xy 343.113482 -282.690576)
			(xy 343.162337 -282.696508) (xy 343.209608 -282.7102) (xy 343.25407 -282.731298) (xy 343.294573 -282.759254)
			(xy 343.330066 -282.793346) (xy 343.359631 -282.83269) (xy 343.382502 -282.876267) (xy 343.398086 -282.922948)
			(xy 343.405981 -282.971525) (xy 343.406476 -282.996132) (xy 343.724987 -282.996132) (xy 343.729082 -282.945404)
			(xy 343.741261 -282.89599) (xy 343.761209 -282.84917) (xy 343.78841 -282.806156) (xy 343.822158 -282.768062)
			(xy 343.86158 -282.735875) (xy 343.905654 -282.710429) (xy 343.95324 -282.692382) (xy 344.003104 -282.682202)
			(xy 344.053956 -282.680153) (xy 344.104477 -282.686287) (xy 344.153361 -282.700447) (xy 344.19934 -282.722264)
			(xy 344.241224 -282.751174) (xy 344.277928 -282.786429) (xy 344.308501 -282.827115) (xy 344.332152 -282.872178)
			(xy 344.348268 -282.920452) (xy 344.356432 -282.970686) (xy 344.356944 -282.996132) (xy 344.675218 -282.996132)
			(xy 344.679178 -282.947078) (xy 344.690955 -282.899294) (xy 344.710246 -282.854018) (xy 344.736549 -282.812422)
			(xy 344.769184 -282.775585) (xy 344.807305 -282.74446) (xy 344.849926 -282.719853) (xy 344.895942 -282.702401)
			(xy 344.944161 -282.692557) (xy 344.993336 -282.690576) (xy 345.042191 -282.696508) (xy 345.089462 -282.7102)
			(xy 345.133924 -282.731298) (xy 345.174427 -282.759254) (xy 345.20992 -282.793346) (xy 345.239485 -282.83269)
			(xy 345.262356 -282.876267) (xy 345.27794 -282.922948) (xy 345.285835 -282.971525) (xy 345.28633 -282.996132)
			(xy 345.604841 -282.996132) (xy 345.608936 -282.945404) (xy 345.621115 -282.89599) (xy 345.641063 -282.84917)
			(xy 345.668264 -282.806156) (xy 345.702012 -282.768062) (xy 345.741434 -282.735875) (xy 345.785508 -282.710429)
			(xy 345.833094 -282.692382) (xy 345.882958 -282.682202) (xy 345.93381 -282.680153) (xy 345.984331 -282.686287)
			(xy 346.033215 -282.700447) (xy 346.079194 -282.722264) (xy 346.121078 -282.751174) (xy 346.157782 -282.786429)
			(xy 346.188355 -282.827115) (xy 346.212006 -282.872178) (xy 346.228122 -282.920452) (xy 346.236286 -282.970686)
			(xy 346.236798 -282.996132) (xy 346.544895 -282.996132) (xy 346.54899 -282.945404) (xy 346.561169 -282.89599)
			(xy 346.581117 -282.84917) (xy 346.608318 -282.806156) (xy 346.642066 -282.768062) (xy 346.681488 -282.735875)
			(xy 346.725562 -282.710429) (xy 346.773148 -282.692382) (xy 346.823012 -282.682202) (xy 346.873864 -282.680153)
			(xy 346.924385 -282.686287) (xy 346.973269 -282.700447) (xy 347.019248 -282.722264) (xy 347.061132 -282.751174)
			(xy 347.097836 -282.786429) (xy 347.128409 -282.827115) (xy 347.15206 -282.872178) (xy 347.168176 -282.920452)
			(xy 347.17634 -282.970686) (xy 347.176852 -282.996132) (xy 347.49538 -282.996132) (xy 347.49934 -282.947078)
			(xy 347.511117 -282.899294) (xy 347.530408 -282.854018) (xy 347.556711 -282.812422) (xy 347.589346 -282.775585)
			(xy 347.627467 -282.74446) (xy 347.670088 -282.719853) (xy 347.716104 -282.702401) (xy 347.764323 -282.692557)
			(xy 347.813498 -282.690576) (xy 347.862353 -282.696508) (xy 347.909624 -282.7102) (xy 347.954086 -282.731298)
			(xy 347.994589 -282.759254) (xy 348.030082 -282.793346) (xy 348.059647 -282.83269) (xy 348.082518 -282.876267)
			(xy 348.098102 -282.922948) (xy 348.105997 -282.971525) (xy 348.106492 -282.996132) (xy 348.425003 -282.996132)
			(xy 348.429098 -282.945404) (xy 348.441277 -282.89599) (xy 348.461225 -282.84917) (xy 348.488426 -282.806156)
			(xy 348.522174 -282.768062) (xy 348.561596 -282.735875) (xy 348.60567 -282.710429) (xy 348.653256 -282.692382)
			(xy 348.70312 -282.682202) (xy 348.753972 -282.680153) (xy 348.804493 -282.686287) (xy 348.853377 -282.700447)
			(xy 348.899356 -282.722264) (xy 348.94124 -282.751174) (xy 348.977944 -282.786429) (xy 349.008517 -282.827115)
			(xy 349.032168 -282.872178) (xy 349.048284 -282.920452) (xy 349.056448 -282.970686) (xy 349.05696 -282.996132)
			(xy 349.364803 -282.996132) (xy 349.368898 -282.945404) (xy 349.381077 -282.89599) (xy 349.401025 -282.84917)
			(xy 349.428226 -282.806156) (xy 349.461974 -282.768062) (xy 349.501396 -282.735875) (xy 349.54547 -282.710429)
			(xy 349.593056 -282.692382) (xy 349.64292 -282.682202) (xy 349.693772 -282.680153) (xy 349.744293 -282.686287)
			(xy 349.793177 -282.700447) (xy 349.839156 -282.722264) (xy 349.88104 -282.751174) (xy 349.917744 -282.786429)
			(xy 349.948317 -282.827115) (xy 349.971968 -282.872178) (xy 349.988084 -282.920452) (xy 349.996248 -282.970686)
			(xy 349.99676 -282.996132) (xy 350.315288 -282.996132) (xy 350.319248 -282.947078) (xy 350.331025 -282.899294)
			(xy 350.350316 -282.854018) (xy 350.376619 -282.812422) (xy 350.409254 -282.775585) (xy 350.447375 -282.74446)
			(xy 350.489996 -282.719853) (xy 350.536012 -282.702401) (xy 350.584231 -282.692557) (xy 350.633406 -282.690576)
			(xy 350.682261 -282.696508) (xy 350.729532 -282.7102) (xy 350.773994 -282.731298) (xy 350.814497 -282.759254)
			(xy 350.84999 -282.793346) (xy 350.879555 -282.83269) (xy 350.902426 -282.876267) (xy 350.91801 -282.922948)
			(xy 350.925905 -282.971525) (xy 350.9264 -282.996132) (xy 350.925905 -283.020739) (xy 350.91801 -283.069316)
			(xy 350.902426 -283.115997) (xy 350.879555 -283.159574) (xy 350.84999 -283.198918) (xy 350.814497 -283.23301)
			(xy 350.773994 -283.260966) (xy 350.729532 -283.282064) (xy 350.682261 -283.295756) (xy 350.633406 -283.301688)
			(xy 350.584231 -283.299707) (xy 350.536012 -283.289863) (xy 350.489996 -283.272411) (xy 350.447375 -283.247804)
			(xy 350.409254 -283.216679) (xy 350.376619 -283.179842) (xy 350.350316 -283.138246) (xy 350.331025 -283.09297)
			(xy 350.319248 -283.045186) (xy 350.315288 -282.996132) (xy 349.99676 -282.996132) (xy 349.996248 -283.021578)
			(xy 349.988084 -283.071812) (xy 349.971968 -283.120086) (xy 349.948317 -283.165149) (xy 349.917744 -283.205835)
			(xy 349.88104 -283.24109) (xy 349.839156 -283.27) (xy 349.793177 -283.291817) (xy 349.744293 -283.305977)
			(xy 349.693772 -283.312111) (xy 349.64292 -283.310062) (xy 349.593056 -283.299882) (xy 349.54547 -283.281835)
			(xy 349.501396 -283.256389) (xy 349.461974 -283.224202) (xy 349.428226 -283.186108) (xy 349.401025 -283.143094)
			(xy 349.381077 -283.096274) (xy 349.368898 -283.04686) (xy 349.364803 -282.996132) (xy 349.05696 -282.996132)
			(xy 349.056448 -283.021578) (xy 349.048284 -283.071812) (xy 349.032168 -283.120086) (xy 349.008517 -283.165149)
			(xy 348.977944 -283.205835) (xy 348.94124 -283.24109) (xy 348.899356 -283.27) (xy 348.853377 -283.291817)
			(xy 348.804493 -283.305977) (xy 348.753972 -283.312111) (xy 348.70312 -283.310062) (xy 348.653256 -283.299882)
			(xy 348.60567 -283.281835) (xy 348.561596 -283.256389) (xy 348.522174 -283.224202) (xy 348.488426 -283.186108)
			(xy 348.461225 -283.143094) (xy 348.441277 -283.096274) (xy 348.429098 -283.04686) (xy 348.425003 -282.996132)
			(xy 348.106492 -282.996132) (xy 348.105997 -283.020739) (xy 348.098102 -283.069316) (xy 348.082518 -283.115997)
			(xy 348.059647 -283.159574) (xy 348.030082 -283.198918) (xy 347.994589 -283.23301) (xy 347.954086 -283.260966)
			(xy 347.909624 -283.282064) (xy 347.862353 -283.295756) (xy 347.813498 -283.301688) (xy 347.764323 -283.299707)
			(xy 347.716104 -283.289863) (xy 347.670088 -283.272411) (xy 347.627467 -283.247804) (xy 347.589346 -283.216679)
			(xy 347.556711 -283.179842) (xy 347.530408 -283.138246) (xy 347.511117 -283.09297) (xy 347.49934 -283.045186)
			(xy 347.49538 -282.996132) (xy 347.176852 -282.996132) (xy 347.17634 -283.021578) (xy 347.168176 -283.071812)
			(xy 347.15206 -283.120086) (xy 347.128409 -283.165149) (xy 347.097836 -283.205835) (xy 347.061132 -283.24109)
			(xy 347.019248 -283.27) (xy 346.973269 -283.291817) (xy 346.924385 -283.305977) (xy 346.873864 -283.312111)
			(xy 346.823012 -283.310062) (xy 346.773148 -283.299882) (xy 346.725562 -283.281835) (xy 346.681488 -283.256389)
			(xy 346.642066 -283.224202) (xy 346.608318 -283.186108) (xy 346.581117 -283.143094) (xy 346.561169 -283.096274)
			(xy 346.54899 -283.04686) (xy 346.544895 -282.996132) (xy 346.236798 -282.996132) (xy 346.236286 -283.021578)
			(xy 346.228122 -283.071812) (xy 346.212006 -283.120086) (xy 346.188355 -283.165149) (xy 346.157782 -283.205835)
			(xy 346.121078 -283.24109) (xy 346.079194 -283.27) (xy 346.033215 -283.291817) (xy 345.984331 -283.305977)
			(xy 345.93381 -283.312111) (xy 345.882958 -283.310062) (xy 345.833094 -283.299882) (xy 345.785508 -283.281835)
			(xy 345.741434 -283.256389) (xy 345.702012 -283.224202) (xy 345.668264 -283.186108) (xy 345.641063 -283.143094)
			(xy 345.621115 -283.096274) (xy 345.608936 -283.04686) (xy 345.604841 -282.996132) (xy 345.28633 -282.996132)
			(xy 345.285835 -283.020739) (xy 345.27794 -283.069316) (xy 345.262356 -283.115997) (xy 345.239485 -283.159574)
			(xy 345.20992 -283.198918) (xy 345.174427 -283.23301) (xy 345.133924 -283.260966) (xy 345.089462 -283.282064)
			(xy 345.042191 -283.295756) (xy 344.993336 -283.301688) (xy 344.944161 -283.299707) (xy 344.895942 -283.289863)
			(xy 344.849926 -283.272411) (xy 344.807305 -283.247804) (xy 344.769184 -283.216679) (xy 344.736549 -283.179842)
			(xy 344.710246 -283.138246) (xy 344.690955 -283.09297) (xy 344.679178 -283.045186) (xy 344.675218 -282.996132)
			(xy 344.356944 -282.996132) (xy 344.356432 -283.021578) (xy 344.348268 -283.071812) (xy 344.332152 -283.120086)
			(xy 344.308501 -283.165149) (xy 344.277928 -283.205835) (xy 344.241224 -283.24109) (xy 344.19934 -283.27)
			(xy 344.153361 -283.291817) (xy 344.104477 -283.305977) (xy 344.053956 -283.312111) (xy 344.003104 -283.310062)
			(xy 343.95324 -283.299882) (xy 343.905654 -283.281835) (xy 343.86158 -283.256389) (xy 343.822158 -283.224202)
			(xy 343.78841 -283.186108) (xy 343.761209 -283.143094) (xy 343.741261 -283.096274) (xy 343.729082 -283.04686)
			(xy 343.724987 -282.996132) (xy 343.406476 -282.996132) (xy 343.405981 -283.020739) (xy 343.398086 -283.069316)
			(xy 343.382502 -283.115997) (xy 343.359631 -283.159574) (xy 343.330066 -283.198918) (xy 343.294573 -283.23301)
			(xy 343.25407 -283.260966) (xy 343.209608 -283.282064) (xy 343.162337 -283.295756) (xy 343.113482 -283.301688)
			(xy 343.064307 -283.299707) (xy 343.016088 -283.289863) (xy 342.970072 -283.272411) (xy 342.927451 -283.247804)
			(xy 342.88933 -283.216679) (xy 342.856695 -283.179842) (xy 342.830392 -283.138246) (xy 342.811101 -283.09297)
			(xy 342.799324 -283.045186) (xy 342.795364 -282.996132) (xy 342.476836 -282.996132) (xy 342.476324 -283.021578)
			(xy 342.46816 -283.071812) (xy 342.452044 -283.120086) (xy 342.428393 -283.165149) (xy 342.39782 -283.205835)
			(xy 342.361116 -283.24109) (xy 342.319232 -283.27) (xy 342.273253 -283.291817) (xy 342.224369 -283.305977)
			(xy 342.173848 -283.312111) (xy 342.122996 -283.310062) (xy 342.073132 -283.299882) (xy 342.025546 -283.281835)
			(xy 341.981472 -283.256389) (xy 341.94205 -283.224202) (xy 341.908302 -283.186108) (xy 341.881101 -283.143094)
			(xy 341.861153 -283.096274) (xy 341.848974 -283.04686) (xy 341.844879 -282.996132) (xy 340.596728 -282.996132)
			(xy 340.596216 -283.021578) (xy 340.588052 -283.071812) (xy 340.571936 -283.120086) (xy 340.548285 -283.165149)
			(xy 340.517712 -283.205835) (xy 340.481008 -283.24109) (xy 340.439124 -283.27) (xy 340.393145 -283.291817)
			(xy 340.344261 -283.305977) (xy 340.29374 -283.312111) (xy 340.242888 -283.310062) (xy 340.193024 -283.299882)
			(xy 340.145438 -283.281835) (xy 340.101364 -283.256389) (xy 340.061942 -283.224202) (xy 340.028194 -283.186108)
			(xy 340.000993 -283.143094) (xy 339.981045 -283.096274) (xy 339.968866 -283.04686) (xy 339.964771 -282.996132)
			(xy 339.656928 -282.996132) (xy 339.656416 -283.021578) (xy 339.648252 -283.071812) (xy 339.632136 -283.120086)
			(xy 339.608485 -283.165149) (xy 339.577912 -283.205835) (xy 339.541208 -283.24109) (xy 339.499324 -283.27)
			(xy 339.453345 -283.291817) (xy 339.404461 -283.305977) (xy 339.35394 -283.312111) (xy 339.303088 -283.310062)
			(xy 339.253224 -283.299882) (xy 339.205638 -283.281835) (xy 339.161564 -283.256389) (xy 339.122142 -283.224202)
			(xy 339.088394 -283.186108) (xy 339.061193 -283.143094) (xy 339.041245 -283.096274) (xy 339.029066 -283.04686)
			(xy 339.024971 -282.996132) (xy 338.70646 -282.996132) (xy 338.705965 -283.020739) (xy 338.69807 -283.069316)
			(xy 338.682486 -283.115997) (xy 338.659615 -283.159574) (xy 338.63005 -283.198918) (xy 338.594557 -283.23301)
			(xy 338.554054 -283.260966) (xy 338.509592 -283.282064) (xy 338.462321 -283.295756) (xy 338.413466 -283.301688)
			(xy 338.364291 -283.299707) (xy 338.316072 -283.289863) (xy 338.270056 -283.272411) (xy 338.227435 -283.247804)
			(xy 338.189314 -283.216679) (xy 338.156679 -283.179842) (xy 338.130376 -283.138246) (xy 338.111085 -283.09297)
			(xy 338.099308 -283.045186) (xy 338.095348 -282.996132) (xy 337.77682 -282.996132) (xy 337.776308 -283.021578)
			(xy 337.768144 -283.071812) (xy 337.752028 -283.120086) (xy 337.728377 -283.165149) (xy 337.697804 -283.205835)
			(xy 337.6611 -283.24109) (xy 337.619216 -283.27) (xy 337.573237 -283.291817) (xy 337.524353 -283.305977)
			(xy 337.473832 -283.312111) (xy 337.42298 -283.310062) (xy 337.373116 -283.299882) (xy 337.32553 -283.281835)
			(xy 337.281456 -283.256389) (xy 337.242034 -283.224202) (xy 337.208286 -283.186108) (xy 337.181085 -283.143094)
			(xy 337.161137 -283.096274) (xy 337.148958 -283.04686) (xy 337.144863 -282.996132) (xy 336.826352 -282.996132)
			(xy 336.825857 -283.020739) (xy 336.817962 -283.069316) (xy 336.802378 -283.115997) (xy 336.779507 -283.159574)
			(xy 336.749942 -283.198918) (xy 336.714449 -283.23301) (xy 336.673946 -283.260966) (xy 336.629484 -283.282064)
			(xy 336.582213 -283.295756) (xy 336.533358 -283.301688) (xy 336.484183 -283.299707) (xy 336.435964 -283.289863)
			(xy 336.389948 -283.272411) (xy 336.347327 -283.247804) (xy 336.309206 -283.216679) (xy 336.276571 -283.179842)
			(xy 336.250268 -283.138246) (xy 336.230977 -283.09297) (xy 336.2192 -283.045186) (xy 336.21524 -282.996132)
			(xy 335.896712 -282.996132) (xy 335.8962 -283.021578) (xy 335.888036 -283.071812) (xy 335.87192 -283.120086)
			(xy 335.848269 -283.165149) (xy 335.817696 -283.205835) (xy 335.780992 -283.24109) (xy 335.739108 -283.27)
			(xy 335.693129 -283.291817) (xy 335.644245 -283.305977) (xy 335.593724 -283.312111) (xy 335.542872 -283.310062)
			(xy 335.493008 -283.299882) (xy 335.445422 -283.281835) (xy 335.401348 -283.256389) (xy 335.361926 -283.224202)
			(xy 335.328178 -283.186108) (xy 335.300977 -283.143094) (xy 335.281029 -283.096274) (xy 335.26885 -283.04686)
			(xy 335.264755 -282.996132) (xy 334.016858 -282.996132) (xy 334.016346 -283.021578) (xy 334.008182 -283.071812)
			(xy 333.992066 -283.120086) (xy 333.968415 -283.165149) (xy 333.937842 -283.205835) (xy 333.901138 -283.24109)
			(xy 333.859254 -283.27) (xy 333.813275 -283.291817) (xy 333.764391 -283.305977) (xy 333.71387 -283.312111)
			(xy 333.663018 -283.310062) (xy 333.613154 -283.299882) (xy 333.565568 -283.281835) (xy 333.521494 -283.256389)
			(xy 333.482072 -283.224202) (xy 333.448324 -283.186108) (xy 333.421123 -283.143094) (xy 333.401175 -283.096274)
			(xy 333.388996 -283.04686) (xy 333.384901 -282.996132) (xy 333.076804 -282.996132) (xy 333.076292 -283.021578)
			(xy 333.068128 -283.071812) (xy 333.052012 -283.120086) (xy 333.028361 -283.165149) (xy 332.997788 -283.205835)
			(xy 332.961084 -283.24109) (xy 332.9192 -283.27) (xy 332.873221 -283.291817) (xy 332.824337 -283.305977)
			(xy 332.773816 -283.312111) (xy 332.722964 -283.310062) (xy 332.6731 -283.299882) (xy 332.625514 -283.281835)
			(xy 332.58144 -283.256389) (xy 332.542018 -283.224202) (xy 332.50827 -283.186108) (xy 332.481069 -283.143094)
			(xy 332.461121 -283.096274) (xy 332.448942 -283.04686) (xy 332.444847 -282.996132) (xy 332.126336 -282.996132)
			(xy 332.125841 -283.020739) (xy 332.117946 -283.069316) (xy 332.102362 -283.115997) (xy 332.079491 -283.159574)
			(xy 332.049926 -283.198918) (xy 332.014433 -283.23301) (xy 331.97393 -283.260966) (xy 331.929468 -283.282064)
			(xy 331.882197 -283.295756) (xy 331.833342 -283.301688) (xy 331.784167 -283.299707) (xy 331.735948 -283.289863)
			(xy 331.689932 -283.272411) (xy 331.647311 -283.247804) (xy 331.60919 -283.216679) (xy 331.576555 -283.179842)
			(xy 331.550252 -283.138246) (xy 331.530961 -283.09297) (xy 331.519184 -283.045186) (xy 331.515224 -282.996132)
			(xy 331.196696 -282.996132) (xy 331.196184 -283.021578) (xy 331.18802 -283.071812) (xy 331.171904 -283.120086)
			(xy 331.148253 -283.165149) (xy 331.11768 -283.205835) (xy 331.080976 -283.24109) (xy 331.039092 -283.27)
			(xy 330.993113 -283.291817) (xy 330.944229 -283.305977) (xy 330.893708 -283.312111) (xy 330.842856 -283.310062)
			(xy 330.792992 -283.299882) (xy 330.745406 -283.281835) (xy 330.701332 -283.256389) (xy 330.66191 -283.224202)
			(xy 330.628162 -283.186108) (xy 330.600961 -283.143094) (xy 330.581013 -283.096274) (xy 330.568834 -283.04686)
			(xy 330.564739 -282.996132) (xy 330.246482 -282.996132) (xy 330.245987 -283.020739) (xy 330.238092 -283.069316)
			(xy 330.222508 -283.115997) (xy 330.199637 -283.159574) (xy 330.170072 -283.198918) (xy 330.134579 -283.23301)
			(xy 330.094076 -283.260966) (xy 330.049614 -283.282064) (xy 330.002343 -283.295756) (xy 329.953488 -283.301688)
			(xy 329.904313 -283.299707) (xy 329.856094 -283.289863) (xy 329.810078 -283.272411) (xy 329.767457 -283.247804)
			(xy 329.729336 -283.216679) (xy 329.696701 -283.179842) (xy 329.670398 -283.138246) (xy 329.651107 -283.09297)
			(xy 329.63933 -283.045186) (xy 329.63537 -282.996132) (xy 329.316842 -282.996132) (xy 329.31633 -283.021578)
			(xy 329.308166 -283.071812) (xy 329.29205 -283.120086) (xy 329.268399 -283.165149) (xy 329.237826 -283.205835)
			(xy 329.201122 -283.24109) (xy 329.159238 -283.27) (xy 329.113259 -283.291817) (xy 329.064375 -283.305977)
			(xy 329.013854 -283.312111) (xy 328.963002 -283.310062) (xy 328.913138 -283.299882) (xy 328.865552 -283.281835)
			(xy 328.821478 -283.256389) (xy 328.782056 -283.224202) (xy 328.748308 -283.186108) (xy 328.721107 -283.143094)
			(xy 328.701159 -283.096274) (xy 328.68898 -283.04686) (xy 328.684885 -282.996132) (xy 325.203519 -282.996132)
			(xy 325.161384 -283.016126) (xy 325.114113 -283.029818) (xy 325.065258 -283.03575) (xy 325.016083 -283.033769)
			(xy 324.967864 -283.023925) (xy 324.921848 -283.006473) (xy 324.879227 -282.981866) (xy 324.841106 -282.950741)
			(xy 324.808471 -282.913904) (xy 324.782168 -282.872308) (xy 324.762877 -282.827032) (xy 324.7511 -282.779248)
			(xy 324.74714 -282.730194) (xy 310.45912 -282.730194) (xy 310.45912 -283.806138) (xy 326.345308 -283.806138)
			(xy 326.349268 -283.757084) (xy 326.361045 -283.7093) (xy 326.380336 -283.664024) (xy 326.406639 -283.622428)
			(xy 326.439274 -283.585591) (xy 326.477395 -283.554466) (xy 326.520016 -283.529859) (xy 326.566032 -283.512407)
			(xy 326.614251 -283.502563) (xy 326.663426 -283.500582) (xy 326.712281 -283.506514) (xy 326.759552 -283.520206)
			(xy 326.804014 -283.541304) (xy 326.844517 -283.56926) (xy 326.88001 -283.603352) (xy 326.909575 -283.642696)
			(xy 326.932446 -283.686273) (xy 326.94803 -283.732954) (xy 326.955925 -283.781531) (xy 326.95642 -283.806138)
			(xy 328.225416 -283.806138) (xy 328.229376 -283.757084) (xy 328.241153 -283.7093) (xy 328.260444 -283.664024)
			(xy 328.286747 -283.622428) (xy 328.319382 -283.585591) (xy 328.357503 -283.554466) (xy 328.400124 -283.529859)
			(xy 328.44614 -283.512407) (xy 328.494359 -283.502563) (xy 328.543534 -283.500582) (xy 328.592389 -283.506514)
			(xy 328.63966 -283.520206) (xy 328.684122 -283.541304) (xy 328.724625 -283.56926) (xy 328.760118 -283.603352)
			(xy 328.789683 -283.642696) (xy 328.812554 -283.686273) (xy 328.828138 -283.732954) (xy 328.836033 -283.781531)
			(xy 328.836528 -283.806138) (xy 329.154785 -283.806138) (xy 329.15888 -283.75541) (xy 329.171059 -283.705996)
			(xy 329.191007 -283.659176) (xy 329.218208 -283.616162) (xy 329.251956 -283.578068) (xy 329.291378 -283.545881)
			(xy 329.335452 -283.520435) (xy 329.383038 -283.502388) (xy 329.432902 -283.492208) (xy 329.483754 -283.490159)
			(xy 329.534275 -283.496293) (xy 329.583159 -283.510453) (xy 329.629138 -283.53227) (xy 329.671022 -283.56118)
			(xy 329.707726 -283.596435) (xy 329.738299 -283.637121) (xy 329.76195 -283.682184) (xy 329.778066 -283.730458)
			(xy 329.78623 -283.780692) (xy 329.786742 -283.806138) (xy 330.094839 -283.806138) (xy 330.098934 -283.75541)
			(xy 330.111113 -283.705996) (xy 330.131061 -283.659176) (xy 330.158262 -283.616162) (xy 330.19201 -283.578068)
			(xy 330.231432 -283.545881) (xy 330.275506 -283.520435) (xy 330.323092 -283.502388) (xy 330.372956 -283.492208)
			(xy 330.423808 -283.490159) (xy 330.474329 -283.496293) (xy 330.523213 -283.510453) (xy 330.569192 -283.53227)
			(xy 330.611076 -283.56118) (xy 330.64778 -283.596435) (xy 330.678353 -283.637121) (xy 330.702004 -283.682184)
			(xy 330.71812 -283.730458) (xy 330.726284 -283.780692) (xy 330.726796 -283.806138) (xy 331.045324 -283.806138)
			(xy 331.049284 -283.757084) (xy 331.061061 -283.7093) (xy 331.080352 -283.664024) (xy 331.106655 -283.622428)
			(xy 331.13929 -283.585591) (xy 331.177411 -283.554466) (xy 331.220032 -283.529859) (xy 331.266048 -283.512407)
			(xy 331.314267 -283.502563) (xy 331.363442 -283.500582) (xy 331.412297 -283.506514) (xy 331.459568 -283.520206)
			(xy 331.50403 -283.541304) (xy 331.544533 -283.56926) (xy 331.580026 -283.603352) (xy 331.609591 -283.642696)
			(xy 331.632462 -283.686273) (xy 331.648046 -283.732954) (xy 331.655941 -283.781531) (xy 331.656436 -283.806138)
			(xy 331.974947 -283.806138) (xy 331.979042 -283.75541) (xy 331.991221 -283.705996) (xy 332.011169 -283.659176)
			(xy 332.03837 -283.616162) (xy 332.072118 -283.578068) (xy 332.11154 -283.545881) (xy 332.155614 -283.520435)
			(xy 332.2032 -283.502388) (xy 332.253064 -283.492208) (xy 332.303916 -283.490159) (xy 332.354437 -283.496293)
			(xy 332.403321 -283.510453) (xy 332.4493 -283.53227) (xy 332.491184 -283.56118) (xy 332.527888 -283.596435)
			(xy 332.558461 -283.637121) (xy 332.582112 -283.682184) (xy 332.598228 -283.730458) (xy 332.606392 -283.780692)
			(xy 332.606904 -283.806138) (xy 332.925178 -283.806138) (xy 332.929138 -283.757084) (xy 332.940915 -283.7093)
			(xy 332.960206 -283.664024) (xy 332.986509 -283.622428) (xy 333.019144 -283.585591) (xy 333.057265 -283.554466)
			(xy 333.099886 -283.529859) (xy 333.145902 -283.512407) (xy 333.194121 -283.502563) (xy 333.243296 -283.500582)
			(xy 333.292151 -283.506514) (xy 333.339422 -283.520206) (xy 333.383884 -283.541304) (xy 333.424387 -283.56926)
			(xy 333.45988 -283.603352) (xy 333.489445 -283.642696) (xy 333.512316 -283.686273) (xy 333.5279 -283.732954)
			(xy 333.535795 -283.781531) (xy 333.53629 -283.806138) (xy 333.854801 -283.806138) (xy 333.858896 -283.75541)
			(xy 333.871075 -283.705996) (xy 333.891023 -283.659176) (xy 333.918224 -283.616162) (xy 333.951972 -283.578068)
			(xy 333.991394 -283.545881) (xy 334.035468 -283.520435) (xy 334.083054 -283.502388) (xy 334.132918 -283.492208)
			(xy 334.18377 -283.490159) (xy 334.234291 -283.496293) (xy 334.283175 -283.510453) (xy 334.329154 -283.53227)
			(xy 334.371038 -283.56118) (xy 334.407742 -283.596435) (xy 334.438315 -283.637121) (xy 334.461966 -283.682184)
			(xy 334.478082 -283.730458) (xy 334.486246 -283.780692) (xy 334.486758 -283.806138) (xy 334.805286 -283.806138)
			(xy 334.809246 -283.757084) (xy 334.821023 -283.7093) (xy 334.840314 -283.664024) (xy 334.866617 -283.622428)
			(xy 334.899252 -283.585591) (xy 334.937373 -283.554466) (xy 334.979994 -283.529859) (xy 335.02601 -283.512407)
			(xy 335.074229 -283.502563) (xy 335.123404 -283.500582) (xy 335.172259 -283.506514) (xy 335.21953 -283.520206)
			(xy 335.263992 -283.541304) (xy 335.304495 -283.56926) (xy 335.339988 -283.603352) (xy 335.369553 -283.642696)
			(xy 335.392424 -283.686273) (xy 335.408008 -283.732954) (xy 335.415903 -283.781531) (xy 335.416398 -283.806138)
			(xy 335.734909 -283.806138) (xy 335.739004 -283.75541) (xy 335.751183 -283.705996) (xy 335.771131 -283.659176)
			(xy 335.798332 -283.616162) (xy 335.83208 -283.578068) (xy 335.871502 -283.545881) (xy 335.915576 -283.520435)
			(xy 335.963162 -283.502388) (xy 336.013026 -283.492208) (xy 336.063878 -283.490159) (xy 336.114399 -283.496293)
			(xy 336.163283 -283.510453) (xy 336.209262 -283.53227) (xy 336.251146 -283.56118) (xy 336.28785 -283.596435)
			(xy 336.318423 -283.637121) (xy 336.342074 -283.682184) (xy 336.35819 -283.730458) (xy 336.366354 -283.780692)
			(xy 336.366866 -283.806138) (xy 336.674963 -283.806138) (xy 336.679058 -283.75541) (xy 336.691237 -283.705996)
			(xy 336.711185 -283.659176) (xy 336.738386 -283.616162) (xy 336.772134 -283.578068) (xy 336.811556 -283.545881)
			(xy 336.85563 -283.520435) (xy 336.903216 -283.502388) (xy 336.95308 -283.492208) (xy 337.003932 -283.490159)
			(xy 337.054453 -283.496293) (xy 337.103337 -283.510453) (xy 337.149316 -283.53227) (xy 337.1912 -283.56118)
			(xy 337.227904 -283.596435) (xy 337.258477 -283.637121) (xy 337.282128 -283.682184) (xy 337.298244 -283.730458)
			(xy 337.306408 -283.780692) (xy 337.30692 -283.806138) (xy 337.625194 -283.806138) (xy 337.629154 -283.757084)
			(xy 337.640931 -283.7093) (xy 337.660222 -283.664024) (xy 337.686525 -283.622428) (xy 337.71916 -283.585591)
			(xy 337.757281 -283.554466) (xy 337.799902 -283.529859) (xy 337.845918 -283.512407) (xy 337.894137 -283.502563)
			(xy 337.943312 -283.500582) (xy 337.992167 -283.506514) (xy 338.039438 -283.520206) (xy 338.0839 -283.541304)
			(xy 338.124403 -283.56926) (xy 338.159896 -283.603352) (xy 338.189461 -283.642696) (xy 338.212332 -283.686273)
			(xy 338.227916 -283.732954) (xy 338.235811 -283.781531) (xy 338.236306 -283.806138) (xy 338.554817 -283.806138)
			(xy 338.558912 -283.75541) (xy 338.571091 -283.705996) (xy 338.591039 -283.659176) (xy 338.61824 -283.616162)
			(xy 338.651988 -283.578068) (xy 338.69141 -283.545881) (xy 338.735484 -283.520435) (xy 338.78307 -283.502388)
			(xy 338.832934 -283.492208) (xy 338.883786 -283.490159) (xy 338.934307 -283.496293) (xy 338.983191 -283.510453)
			(xy 339.02917 -283.53227) (xy 339.071054 -283.56118) (xy 339.107758 -283.596435) (xy 339.138331 -283.637121)
			(xy 339.161982 -283.682184) (xy 339.178098 -283.730458) (xy 339.186262 -283.780692) (xy 339.186774 -283.806138)
			(xy 339.505302 -283.806138) (xy 339.509262 -283.757084) (xy 339.521039 -283.7093) (xy 339.54033 -283.664024)
			(xy 339.566633 -283.622428) (xy 339.599268 -283.585591) (xy 339.637389 -283.554466) (xy 339.68001 -283.529859)
			(xy 339.726026 -283.512407) (xy 339.774245 -283.502563) (xy 339.82342 -283.500582) (xy 339.872275 -283.506514)
			(xy 339.919546 -283.520206) (xy 339.964008 -283.541304) (xy 340.004511 -283.56926) (xy 340.040004 -283.603352)
			(xy 340.069569 -283.642696) (xy 340.09244 -283.686273) (xy 340.108024 -283.732954) (xy 340.115919 -283.781531)
			(xy 340.116414 -283.806138) (xy 340.434925 -283.806138) (xy 340.43902 -283.75541) (xy 340.451199 -283.705996)
			(xy 340.471147 -283.659176) (xy 340.498348 -283.616162) (xy 340.532096 -283.578068) (xy 340.571518 -283.545881)
			(xy 340.615592 -283.520435) (xy 340.663178 -283.502388) (xy 340.713042 -283.492208) (xy 340.763894 -283.490159)
			(xy 340.814415 -283.496293) (xy 340.863299 -283.510453) (xy 340.909278 -283.53227) (xy 340.951162 -283.56118)
			(xy 340.987866 -283.596435) (xy 341.018439 -283.637121) (xy 341.04209 -283.682184) (xy 341.058206 -283.730458)
			(xy 341.06637 -283.780692) (xy 341.066882 -283.806138) (xy 341.38541 -283.806138) (xy 341.38937 -283.757084)
			(xy 341.401147 -283.7093) (xy 341.420438 -283.664024) (xy 341.446741 -283.622428) (xy 341.479376 -283.585591)
			(xy 341.517497 -283.554466) (xy 341.560118 -283.529859) (xy 341.606134 -283.512407) (xy 341.654353 -283.502563)
			(xy 341.703528 -283.500582) (xy 341.752383 -283.506514) (xy 341.799654 -283.520206) (xy 341.844116 -283.541304)
			(xy 341.884619 -283.56926) (xy 341.920112 -283.603352) (xy 341.949677 -283.642696) (xy 341.972548 -283.686273)
			(xy 341.988132 -283.732954) (xy 341.996027 -283.781531) (xy 341.996522 -283.806138) (xy 342.314779 -283.806138)
			(xy 342.318874 -283.75541) (xy 342.331053 -283.705996) (xy 342.351001 -283.659176) (xy 342.378202 -283.616162)
			(xy 342.41195 -283.578068) (xy 342.451372 -283.545881) (xy 342.495446 -283.520435) (xy 342.543032 -283.502388)
			(xy 342.592896 -283.492208) (xy 342.643748 -283.490159) (xy 342.694269 -283.496293) (xy 342.743153 -283.510453)
			(xy 342.789132 -283.53227) (xy 342.831016 -283.56118) (xy 342.86772 -283.596435) (xy 342.898293 -283.637121)
			(xy 342.921944 -283.682184) (xy 342.93806 -283.730458) (xy 342.946224 -283.780692) (xy 342.946736 -283.806138)
			(xy 343.254833 -283.806138) (xy 343.258928 -283.75541) (xy 343.271107 -283.705996) (xy 343.291055 -283.659176)
			(xy 343.318256 -283.616162) (xy 343.352004 -283.578068) (xy 343.391426 -283.545881) (xy 343.4355 -283.520435)
			(xy 343.483086 -283.502388) (xy 343.53295 -283.492208) (xy 343.583802 -283.490159) (xy 343.634323 -283.496293)
			(xy 343.683207 -283.510453) (xy 343.729186 -283.53227) (xy 343.77107 -283.56118) (xy 343.807774 -283.596435)
			(xy 343.838347 -283.637121) (xy 343.861998 -283.682184) (xy 343.878114 -283.730458) (xy 343.886278 -283.780692)
			(xy 343.88679 -283.806138) (xy 344.205318 -283.806138) (xy 344.209278 -283.757084) (xy 344.221055 -283.7093)
			(xy 344.240346 -283.664024) (xy 344.266649 -283.622428) (xy 344.299284 -283.585591) (xy 344.337405 -283.554466)
			(xy 344.380026 -283.529859) (xy 344.426042 -283.512407) (xy 344.474261 -283.502563) (xy 344.523436 -283.500582)
			(xy 344.572291 -283.506514) (xy 344.619562 -283.520206) (xy 344.664024 -283.541304) (xy 344.704527 -283.56926)
			(xy 344.74002 -283.603352) (xy 344.769585 -283.642696) (xy 344.792456 -283.686273) (xy 344.80804 -283.732954)
			(xy 344.815935 -283.781531) (xy 344.81643 -283.806138) (xy 345.145372 -283.806138) (xy 345.149332 -283.757084)
			(xy 345.161109 -283.7093) (xy 345.1804 -283.664024) (xy 345.206703 -283.622428) (xy 345.239338 -283.585591)
			(xy 345.277459 -283.554466) (xy 345.32008 -283.529859) (xy 345.366096 -283.512407) (xy 345.414315 -283.502563)
			(xy 345.46349 -283.500582) (xy 345.512345 -283.506514) (xy 345.559616 -283.520206) (xy 345.604078 -283.541304)
			(xy 345.644581 -283.56926) (xy 345.680074 -283.603352) (xy 345.709639 -283.642696) (xy 345.73251 -283.686273)
			(xy 345.748094 -283.732954) (xy 345.755989 -283.781531) (xy 345.756484 -283.806138) (xy 346.085426 -283.806138)
			(xy 346.089386 -283.757084) (xy 346.101163 -283.7093) (xy 346.120454 -283.664024) (xy 346.146757 -283.622428)
			(xy 346.179392 -283.585591) (xy 346.217513 -283.554466) (xy 346.260134 -283.529859) (xy 346.30615 -283.512407)
			(xy 346.354369 -283.502563) (xy 346.403544 -283.500582) (xy 346.452399 -283.506514) (xy 346.49967 -283.520206)
			(xy 346.544132 -283.541304) (xy 346.584635 -283.56926) (xy 346.620128 -283.603352) (xy 346.649693 -283.642696)
			(xy 346.672564 -283.686273) (xy 346.688148 -283.732954) (xy 346.696043 -283.781531) (xy 346.696538 -283.806138)
			(xy 347.025226 -283.806138) (xy 347.029186 -283.757084) (xy 347.040963 -283.7093) (xy 347.060254 -283.664024)
			(xy 347.086557 -283.622428) (xy 347.119192 -283.585591) (xy 347.157313 -283.554466) (xy 347.199934 -283.529859)
			(xy 347.24595 -283.512407) (xy 347.294169 -283.502563) (xy 347.343344 -283.500582) (xy 347.392199 -283.506514)
			(xy 347.43947 -283.520206) (xy 347.483932 -283.541304) (xy 347.524435 -283.56926) (xy 347.559928 -283.603352)
			(xy 347.589493 -283.642696) (xy 347.612364 -283.686273) (xy 347.627948 -283.732954) (xy 347.635843 -283.781531)
			(xy 347.636338 -283.806138) (xy 347.96528 -283.806138) (xy 347.96924 -283.757084) (xy 347.981017 -283.7093)
			(xy 348.000308 -283.664024) (xy 348.026611 -283.622428) (xy 348.059246 -283.585591) (xy 348.097367 -283.554466)
			(xy 348.139988 -283.529859) (xy 348.186004 -283.512407) (xy 348.234223 -283.502563) (xy 348.283398 -283.500582)
			(xy 348.332253 -283.506514) (xy 348.379524 -283.520206) (xy 348.423986 -283.541304) (xy 348.464489 -283.56926)
			(xy 348.499982 -283.603352) (xy 348.529547 -283.642696) (xy 348.552418 -283.686273) (xy 348.568002 -283.732954)
			(xy 348.575897 -283.781531) (xy 348.576392 -283.806138) (xy 348.905334 -283.806138) (xy 348.909294 -283.757084)
			(xy 348.921071 -283.7093) (xy 348.940362 -283.664024) (xy 348.966665 -283.622428) (xy 348.9993 -283.585591)
			(xy 349.037421 -283.554466) (xy 349.080042 -283.529859) (xy 349.126058 -283.512407) (xy 349.174277 -283.502563)
			(xy 349.223452 -283.500582) (xy 349.272307 -283.506514) (xy 349.319578 -283.520206) (xy 349.36404 -283.541304)
			(xy 349.404543 -283.56926) (xy 349.440036 -283.603352) (xy 349.469601 -283.642696) (xy 349.492472 -283.686273)
			(xy 349.508056 -283.732954) (xy 349.515951 -283.781531) (xy 349.516446 -283.806138) (xy 349.845388 -283.806138)
			(xy 349.849348 -283.757084) (xy 349.861125 -283.7093) (xy 349.880416 -283.664024) (xy 349.906719 -283.622428)
			(xy 349.939354 -283.585591) (xy 349.977475 -283.554466) (xy 350.020096 -283.529859) (xy 350.066112 -283.512407)
			(xy 350.114331 -283.502563) (xy 350.163506 -283.500582) (xy 350.212361 -283.506514) (xy 350.259632 -283.520206)
			(xy 350.304094 -283.541304) (xy 350.344597 -283.56926) (xy 350.38009 -283.603352) (xy 350.409655 -283.642696)
			(xy 350.432526 -283.686273) (xy 350.44811 -283.732954) (xy 350.456005 -283.781531) (xy 350.4565 -283.806138)
			(xy 350.785442 -283.806138) (xy 350.789402 -283.757084) (xy 350.801179 -283.7093) (xy 350.82047 -283.664024)
			(xy 350.846773 -283.622428) (xy 350.879408 -283.585591) (xy 350.917529 -283.554466) (xy 350.96015 -283.529859)
			(xy 351.006166 -283.512407) (xy 351.054385 -283.502563) (xy 351.10356 -283.500582) (xy 351.152415 -283.506514)
			(xy 351.199686 -283.520206) (xy 351.244148 -283.541304) (xy 351.284651 -283.56926) (xy 351.320144 -283.603352)
			(xy 351.349709 -283.642696) (xy 351.37258 -283.686273) (xy 351.388164 -283.732954) (xy 351.396059 -283.781531)
			(xy 351.396554 -283.806138) (xy 351.396059 -283.830745) (xy 351.388164 -283.879322) (xy 351.37258 -283.926003)
			(xy 351.349709 -283.96958) (xy 351.320144 -284.008924) (xy 351.284651 -284.043016) (xy 351.244148 -284.070972)
			(xy 351.199686 -284.09207) (xy 351.152415 -284.105762) (xy 351.10356 -284.111694) (xy 351.054385 -284.109713)
			(xy 351.006166 -284.099869) (xy 350.96015 -284.082417) (xy 350.917529 -284.05781) (xy 350.879408 -284.026685)
			(xy 350.846773 -283.989848) (xy 350.82047 -283.948252) (xy 350.801179 -283.902976) (xy 350.789402 -283.855192)
			(xy 350.785442 -283.806138) (xy 350.4565 -283.806138) (xy 350.456005 -283.830745) (xy 350.44811 -283.879322)
			(xy 350.432526 -283.926003) (xy 350.409655 -283.96958) (xy 350.38009 -284.008924) (xy 350.344597 -284.043016)
			(xy 350.304094 -284.070972) (xy 350.259632 -284.09207) (xy 350.212361 -284.105762) (xy 350.163506 -284.111694)
			(xy 350.114331 -284.109713) (xy 350.066112 -284.099869) (xy 350.020096 -284.082417) (xy 349.977475 -284.05781)
			(xy 349.939354 -284.026685) (xy 349.906719 -283.989848) (xy 349.880416 -283.948252) (xy 349.861125 -283.902976)
			(xy 349.849348 -283.855192) (xy 349.845388 -283.806138) (xy 349.516446 -283.806138) (xy 349.515951 -283.830745)
			(xy 349.508056 -283.879322) (xy 349.492472 -283.926003) (xy 349.469601 -283.96958) (xy 349.440036 -284.008924)
			(xy 349.404543 -284.043016) (xy 349.36404 -284.070972) (xy 349.319578 -284.09207) (xy 349.272307 -284.105762)
			(xy 349.223452 -284.111694) (xy 349.174277 -284.109713) (xy 349.126058 -284.099869) (xy 349.080042 -284.082417)
			(xy 349.037421 -284.05781) (xy 348.9993 -284.026685) (xy 348.966665 -283.989848) (xy 348.940362 -283.948252)
			(xy 348.921071 -283.902976) (xy 348.909294 -283.855192) (xy 348.905334 -283.806138) (xy 348.576392 -283.806138)
			(xy 348.575897 -283.830745) (xy 348.568002 -283.879322) (xy 348.552418 -283.926003) (xy 348.529547 -283.96958)
			(xy 348.499982 -284.008924) (xy 348.464489 -284.043016) (xy 348.423986 -284.070972) (xy 348.379524 -284.09207)
			(xy 348.332253 -284.105762) (xy 348.283398 -284.111694) (xy 348.234223 -284.109713) (xy 348.186004 -284.099869)
			(xy 348.139988 -284.082417) (xy 348.097367 -284.05781) (xy 348.059246 -284.026685) (xy 348.026611 -283.989848)
			(xy 348.000308 -283.948252) (xy 347.981017 -283.902976) (xy 347.96924 -283.855192) (xy 347.96528 -283.806138)
			(xy 347.636338 -283.806138) (xy 347.635843 -283.830745) (xy 347.627948 -283.879322) (xy 347.612364 -283.926003)
			(xy 347.589493 -283.96958) (xy 347.559928 -284.008924) (xy 347.524435 -284.043016) (xy 347.483932 -284.070972)
			(xy 347.43947 -284.09207) (xy 347.392199 -284.105762) (xy 347.343344 -284.111694) (xy 347.294169 -284.109713)
			(xy 347.24595 -284.099869) (xy 347.199934 -284.082417) (xy 347.157313 -284.05781) (xy 347.119192 -284.026685)
			(xy 347.086557 -283.989848) (xy 347.060254 -283.948252) (xy 347.040963 -283.902976) (xy 347.029186 -283.855192)
			(xy 347.025226 -283.806138) (xy 346.696538 -283.806138) (xy 346.696043 -283.830745) (xy 346.688148 -283.879322)
			(xy 346.672564 -283.926003) (xy 346.649693 -283.96958) (xy 346.620128 -284.008924) (xy 346.584635 -284.043016)
			(xy 346.544132 -284.070972) (xy 346.49967 -284.09207) (xy 346.452399 -284.105762) (xy 346.403544 -284.111694)
			(xy 346.354369 -284.109713) (xy 346.30615 -284.099869) (xy 346.260134 -284.082417) (xy 346.217513 -284.05781)
			(xy 346.179392 -284.026685) (xy 346.146757 -283.989848) (xy 346.120454 -283.948252) (xy 346.101163 -283.902976)
			(xy 346.089386 -283.855192) (xy 346.085426 -283.806138) (xy 345.756484 -283.806138) (xy 345.755989 -283.830745)
			(xy 345.748094 -283.879322) (xy 345.73251 -283.926003) (xy 345.709639 -283.96958) (xy 345.680074 -284.008924)
			(xy 345.644581 -284.043016) (xy 345.604078 -284.070972) (xy 345.559616 -284.09207) (xy 345.512345 -284.105762)
			(xy 345.46349 -284.111694) (xy 345.414315 -284.109713) (xy 345.366096 -284.099869) (xy 345.32008 -284.082417)
			(xy 345.277459 -284.05781) (xy 345.239338 -284.026685) (xy 345.206703 -283.989848) (xy 345.1804 -283.948252)
			(xy 345.161109 -283.902976) (xy 345.149332 -283.855192) (xy 345.145372 -283.806138) (xy 344.81643 -283.806138)
			(xy 344.815935 -283.830745) (xy 344.80804 -283.879322) (xy 344.792456 -283.926003) (xy 344.769585 -283.96958)
			(xy 344.74002 -284.008924) (xy 344.704527 -284.043016) (xy 344.664024 -284.070972) (xy 344.619562 -284.09207)
			(xy 344.572291 -284.105762) (xy 344.523436 -284.111694) (xy 344.474261 -284.109713) (xy 344.426042 -284.099869)
			(xy 344.380026 -284.082417) (xy 344.337405 -284.05781) (xy 344.299284 -284.026685) (xy 344.266649 -283.989848)
			(xy 344.240346 -283.948252) (xy 344.221055 -283.902976) (xy 344.209278 -283.855192) (xy 344.205318 -283.806138)
			(xy 343.88679 -283.806138) (xy 343.886278 -283.831584) (xy 343.878114 -283.881818) (xy 343.861998 -283.930092)
			(xy 343.838347 -283.975155) (xy 343.807774 -284.015841) (xy 343.77107 -284.051096) (xy 343.729186 -284.080006)
			(xy 343.683207 -284.101823) (xy 343.634323 -284.115983) (xy 343.583802 -284.122117) (xy 343.53295 -284.120068)
			(xy 343.483086 -284.109888) (xy 343.4355 -284.091841) (xy 343.391426 -284.066395) (xy 343.352004 -284.034208)
			(xy 343.318256 -283.996114) (xy 343.291055 -283.9531) (xy 343.271107 -283.90628) (xy 343.258928 -283.856866)
			(xy 343.254833 -283.806138) (xy 342.946736 -283.806138) (xy 342.946224 -283.831584) (xy 342.93806 -283.881818)
			(xy 342.921944 -283.930092) (xy 342.898293 -283.975155) (xy 342.86772 -284.015841) (xy 342.831016 -284.051096)
			(xy 342.789132 -284.080006) (xy 342.743153 -284.101823) (xy 342.694269 -284.115983) (xy 342.643748 -284.122117)
			(xy 342.592896 -284.120068) (xy 342.543032 -284.109888) (xy 342.495446 -284.091841) (xy 342.451372 -284.066395)
			(xy 342.41195 -284.034208) (xy 342.378202 -283.996114) (xy 342.351001 -283.9531) (xy 342.331053 -283.90628)
			(xy 342.318874 -283.856866) (xy 342.314779 -283.806138) (xy 341.996522 -283.806138) (xy 341.996027 -283.830745)
			(xy 341.988132 -283.879322) (xy 341.972548 -283.926003) (xy 341.949677 -283.96958) (xy 341.920112 -284.008924)
			(xy 341.884619 -284.043016) (xy 341.844116 -284.070972) (xy 341.799654 -284.09207) (xy 341.752383 -284.105762)
			(xy 341.703528 -284.111694) (xy 341.654353 -284.109713) (xy 341.606134 -284.099869) (xy 341.560118 -284.082417)
			(xy 341.517497 -284.05781) (xy 341.479376 -284.026685) (xy 341.446741 -283.989848) (xy 341.420438 -283.948252)
			(xy 341.401147 -283.902976) (xy 341.38937 -283.855192) (xy 341.38541 -283.806138) (xy 341.066882 -283.806138)
			(xy 341.06637 -283.831584) (xy 341.058206 -283.881818) (xy 341.04209 -283.930092) (xy 341.018439 -283.975155)
			(xy 340.987866 -284.015841) (xy 340.951162 -284.051096) (xy 340.909278 -284.080006) (xy 340.863299 -284.101823)
			(xy 340.814415 -284.115983) (xy 340.763894 -284.122117) (xy 340.713042 -284.120068) (xy 340.663178 -284.109888)
			(xy 340.615592 -284.091841) (xy 340.571518 -284.066395) (xy 340.532096 -284.034208) (xy 340.498348 -283.996114)
			(xy 340.471147 -283.9531) (xy 340.451199 -283.90628) (xy 340.43902 -283.856866) (xy 340.434925 -283.806138)
			(xy 340.116414 -283.806138) (xy 340.115919 -283.830745) (xy 340.108024 -283.879322) (xy 340.09244 -283.926003)
			(xy 340.069569 -283.96958) (xy 340.040004 -284.008924) (xy 340.004511 -284.043016) (xy 339.964008 -284.070972)
			(xy 339.919546 -284.09207) (xy 339.872275 -284.105762) (xy 339.82342 -284.111694) (xy 339.774245 -284.109713)
			(xy 339.726026 -284.099869) (xy 339.68001 -284.082417) (xy 339.637389 -284.05781) (xy 339.599268 -284.026685)
			(xy 339.566633 -283.989848) (xy 339.54033 -283.948252) (xy 339.521039 -283.902976) (xy 339.509262 -283.855192)
			(xy 339.505302 -283.806138) (xy 339.186774 -283.806138) (xy 339.186262 -283.831584) (xy 339.178098 -283.881818)
			(xy 339.161982 -283.930092) (xy 339.138331 -283.975155) (xy 339.107758 -284.015841) (xy 339.071054 -284.051096)
			(xy 339.02917 -284.080006) (xy 338.983191 -284.101823) (xy 338.934307 -284.115983) (xy 338.883786 -284.122117)
			(xy 338.832934 -284.120068) (xy 338.78307 -284.109888) (xy 338.735484 -284.091841) (xy 338.69141 -284.066395)
			(xy 338.651988 -284.034208) (xy 338.61824 -283.996114) (xy 338.591039 -283.9531) (xy 338.571091 -283.90628)
			(xy 338.558912 -283.856866) (xy 338.554817 -283.806138) (xy 338.236306 -283.806138) (xy 338.235811 -283.830745)
			(xy 338.227916 -283.879322) (xy 338.212332 -283.926003) (xy 338.189461 -283.96958) (xy 338.159896 -284.008924)
			(xy 338.124403 -284.043016) (xy 338.0839 -284.070972) (xy 338.039438 -284.09207) (xy 337.992167 -284.105762)
			(xy 337.943312 -284.111694) (xy 337.894137 -284.109713) (xy 337.845918 -284.099869) (xy 337.799902 -284.082417)
			(xy 337.757281 -284.05781) (xy 337.71916 -284.026685) (xy 337.686525 -283.989848) (xy 337.660222 -283.948252)
			(xy 337.640931 -283.902976) (xy 337.629154 -283.855192) (xy 337.625194 -283.806138) (xy 337.30692 -283.806138)
			(xy 337.306408 -283.831584) (xy 337.298244 -283.881818) (xy 337.282128 -283.930092) (xy 337.258477 -283.975155)
			(xy 337.227904 -284.015841) (xy 337.1912 -284.051096) (xy 337.149316 -284.080006) (xy 337.103337 -284.101823)
			(xy 337.054453 -284.115983) (xy 337.003932 -284.122117) (xy 336.95308 -284.120068) (xy 336.903216 -284.109888)
			(xy 336.85563 -284.091841) (xy 336.811556 -284.066395) (xy 336.772134 -284.034208) (xy 336.738386 -283.996114)
			(xy 336.711185 -283.9531) (xy 336.691237 -283.90628) (xy 336.679058 -283.856866) (xy 336.674963 -283.806138)
			(xy 336.366866 -283.806138) (xy 336.366354 -283.831584) (xy 336.35819 -283.881818) (xy 336.342074 -283.930092)
			(xy 336.318423 -283.975155) (xy 336.28785 -284.015841) (xy 336.251146 -284.051096) (xy 336.209262 -284.080006)
			(xy 336.163283 -284.101823) (xy 336.114399 -284.115983) (xy 336.063878 -284.122117) (xy 336.013026 -284.120068)
			(xy 335.963162 -284.109888) (xy 335.915576 -284.091841) (xy 335.871502 -284.066395) (xy 335.83208 -284.034208)
			(xy 335.798332 -283.996114) (xy 335.771131 -283.9531) (xy 335.751183 -283.90628) (xy 335.739004 -283.856866)
			(xy 335.734909 -283.806138) (xy 335.416398 -283.806138) (xy 335.415903 -283.830745) (xy 335.408008 -283.879322)
			(xy 335.392424 -283.926003) (xy 335.369553 -283.96958) (xy 335.339988 -284.008924) (xy 335.304495 -284.043016)
			(xy 335.263992 -284.070972) (xy 335.21953 -284.09207) (xy 335.172259 -284.105762) (xy 335.123404 -284.111694)
			(xy 335.074229 -284.109713) (xy 335.02601 -284.099869) (xy 334.979994 -284.082417) (xy 334.937373 -284.05781)
			(xy 334.899252 -284.026685) (xy 334.866617 -283.989848) (xy 334.840314 -283.948252) (xy 334.821023 -283.902976)
			(xy 334.809246 -283.855192) (xy 334.805286 -283.806138) (xy 334.486758 -283.806138) (xy 334.486246 -283.831584)
			(xy 334.478082 -283.881818) (xy 334.461966 -283.930092) (xy 334.438315 -283.975155) (xy 334.407742 -284.015841)
			(xy 334.371038 -284.051096) (xy 334.329154 -284.080006) (xy 334.283175 -284.101823) (xy 334.234291 -284.115983)
			(xy 334.18377 -284.122117) (xy 334.132918 -284.120068) (xy 334.083054 -284.109888) (xy 334.035468 -284.091841)
			(xy 333.991394 -284.066395) (xy 333.951972 -284.034208) (xy 333.918224 -283.996114) (xy 333.891023 -283.9531)
			(xy 333.871075 -283.90628) (xy 333.858896 -283.856866) (xy 333.854801 -283.806138) (xy 333.53629 -283.806138)
			(xy 333.535795 -283.830745) (xy 333.5279 -283.879322) (xy 333.512316 -283.926003) (xy 333.489445 -283.96958)
			(xy 333.45988 -284.008924) (xy 333.424387 -284.043016) (xy 333.383884 -284.070972) (xy 333.339422 -284.09207)
			(xy 333.292151 -284.105762) (xy 333.243296 -284.111694) (xy 333.194121 -284.109713) (xy 333.145902 -284.099869)
			(xy 333.099886 -284.082417) (xy 333.057265 -284.05781) (xy 333.019144 -284.026685) (xy 332.986509 -283.989848)
			(xy 332.960206 -283.948252) (xy 332.940915 -283.902976) (xy 332.929138 -283.855192) (xy 332.925178 -283.806138)
			(xy 332.606904 -283.806138) (xy 332.606392 -283.831584) (xy 332.598228 -283.881818) (xy 332.582112 -283.930092)
			(xy 332.558461 -283.975155) (xy 332.527888 -284.015841) (xy 332.491184 -284.051096) (xy 332.4493 -284.080006)
			(xy 332.403321 -284.101823) (xy 332.354437 -284.115983) (xy 332.303916 -284.122117) (xy 332.253064 -284.120068)
			(xy 332.2032 -284.109888) (xy 332.155614 -284.091841) (xy 332.11154 -284.066395) (xy 332.072118 -284.034208)
			(xy 332.03837 -283.996114) (xy 332.011169 -283.9531) (xy 331.991221 -283.90628) (xy 331.979042 -283.856866)
			(xy 331.974947 -283.806138) (xy 331.656436 -283.806138) (xy 331.655941 -283.830745) (xy 331.648046 -283.879322)
			(xy 331.632462 -283.926003) (xy 331.609591 -283.96958) (xy 331.580026 -284.008924) (xy 331.544533 -284.043016)
			(xy 331.50403 -284.070972) (xy 331.459568 -284.09207) (xy 331.412297 -284.105762) (xy 331.363442 -284.111694)
			(xy 331.314267 -284.109713) (xy 331.266048 -284.099869) (xy 331.220032 -284.082417) (xy 331.177411 -284.05781)
			(xy 331.13929 -284.026685) (xy 331.106655 -283.989848) (xy 331.080352 -283.948252) (xy 331.061061 -283.902976)
			(xy 331.049284 -283.855192) (xy 331.045324 -283.806138) (xy 330.726796 -283.806138) (xy 330.726284 -283.831584)
			(xy 330.71812 -283.881818) (xy 330.702004 -283.930092) (xy 330.678353 -283.975155) (xy 330.64778 -284.015841)
			(xy 330.611076 -284.051096) (xy 330.569192 -284.080006) (xy 330.523213 -284.101823) (xy 330.474329 -284.115983)
			(xy 330.423808 -284.122117) (xy 330.372956 -284.120068) (xy 330.323092 -284.109888) (xy 330.275506 -284.091841)
			(xy 330.231432 -284.066395) (xy 330.19201 -284.034208) (xy 330.158262 -283.996114) (xy 330.131061 -283.9531)
			(xy 330.111113 -283.90628) (xy 330.098934 -283.856866) (xy 330.094839 -283.806138) (xy 329.786742 -283.806138)
			(xy 329.78623 -283.831584) (xy 329.778066 -283.881818) (xy 329.76195 -283.930092) (xy 329.738299 -283.975155)
			(xy 329.707726 -284.015841) (xy 329.671022 -284.051096) (xy 329.629138 -284.080006) (xy 329.583159 -284.101823)
			(xy 329.534275 -284.115983) (xy 329.483754 -284.122117) (xy 329.432902 -284.120068) (xy 329.383038 -284.109888)
			(xy 329.335452 -284.091841) (xy 329.291378 -284.066395) (xy 329.251956 -284.034208) (xy 329.218208 -283.996114)
			(xy 329.191007 -283.9531) (xy 329.171059 -283.90628) (xy 329.15888 -283.856866) (xy 329.154785 -283.806138)
			(xy 328.836528 -283.806138) (xy 328.836033 -283.830745) (xy 328.828138 -283.879322) (xy 328.812554 -283.926003)
			(xy 328.789683 -283.96958) (xy 328.760118 -284.008924) (xy 328.724625 -284.043016) (xy 328.684122 -284.070972)
			(xy 328.63966 -284.09207) (xy 328.592389 -284.105762) (xy 328.543534 -284.111694) (xy 328.494359 -284.109713)
			(xy 328.44614 -284.099869) (xy 328.400124 -284.082417) (xy 328.357503 -284.05781) (xy 328.319382 -284.026685)
			(xy 328.286747 -283.989848) (xy 328.260444 -283.948252) (xy 328.241153 -283.902976) (xy 328.229376 -283.855192)
			(xy 328.225416 -283.806138) (xy 326.95642 -283.806138) (xy 326.955925 -283.830745) (xy 326.94803 -283.879322)
			(xy 326.932446 -283.926003) (xy 326.909575 -283.96958) (xy 326.88001 -284.008924) (xy 326.844517 -284.043016)
			(xy 326.804014 -284.070972) (xy 326.759552 -284.09207) (xy 326.712281 -284.105762) (xy 326.663426 -284.111694)
			(xy 326.614251 -284.109713) (xy 326.566032 -284.099869) (xy 326.520016 -284.082417) (xy 326.477395 -284.05781)
			(xy 326.439274 -284.026685) (xy 326.406639 -283.989848) (xy 326.380336 -283.948252) (xy 326.361045 -283.902976)
			(xy 326.349268 -283.855192) (xy 326.345308 -283.806138) (xy 310.45912 -283.806138) (xy 310.45912 -284.350206)
			(xy 324.74714 -284.350206) (xy 324.7511 -284.301152) (xy 324.762877 -284.253368) (xy 324.782168 -284.208092)
			(xy 324.808471 -284.166496) (xy 324.841106 -284.129659) (xy 324.879227 -284.098534) (xy 324.921848 -284.073927)
			(xy 324.967864 -284.056475) (xy 325.016083 -284.046631) (xy 325.065258 -284.04465) (xy 325.114113 -284.050582)
			(xy 325.161384 -284.064274) (xy 325.205846 -284.085372) (xy 325.246349 -284.113328) (xy 325.281842 -284.14742)
			(xy 325.311407 -284.186764) (xy 325.334278 -284.230341) (xy 325.349862 -284.277022) (xy 325.357757 -284.325599)
			(xy 325.358252 -284.350206) (xy 325.357757 -284.374813) (xy 325.349862 -284.42339) (xy 325.334278 -284.470071)
			(xy 325.311407 -284.513648) (xy 325.281842 -284.552992) (xy 325.246349 -284.587084) (xy 325.205846 -284.61504)
			(xy 325.203519 -284.616144) (xy 327.755262 -284.616144) (xy 327.759222 -284.56709) (xy 327.770999 -284.519306)
			(xy 327.79029 -284.47403) (xy 327.816593 -284.432434) (xy 327.849228 -284.395597) (xy 327.887349 -284.364472)
			(xy 327.92997 -284.339865) (xy 327.975986 -284.322413) (xy 328.024205 -284.312569) (xy 328.07338 -284.310588)
			(xy 328.122235 -284.31652) (xy 328.169506 -284.330212) (xy 328.213968 -284.35131) (xy 328.254471 -284.379266)
			(xy 328.289964 -284.413358) (xy 328.319529 -284.452702) (xy 328.3424 -284.496279) (xy 328.357984 -284.54296)
			(xy 328.365879 -284.591537) (xy 328.366374 -284.616144) (xy 328.684885 -284.616144) (xy 328.68898 -284.565416)
			(xy 328.701159 -284.516002) (xy 328.721107 -284.469182) (xy 328.748308 -284.426168) (xy 328.782056 -284.388074)
			(xy 328.821478 -284.355887) (xy 328.865552 -284.330441) (xy 328.913138 -284.312394) (xy 328.963002 -284.302214)
			(xy 329.013854 -284.300165) (xy 329.064375 -284.306299) (xy 329.113259 -284.320459) (xy 329.159238 -284.342276)
			(xy 329.201122 -284.371186) (xy 329.237826 -284.406441) (xy 329.268399 -284.447127) (xy 329.29205 -284.49219)
			(xy 329.308166 -284.540464) (xy 329.31633 -284.590698) (xy 329.316842 -284.616144) (xy 329.63537 -284.616144)
			(xy 329.63933 -284.56709) (xy 329.651107 -284.519306) (xy 329.670398 -284.47403) (xy 329.696701 -284.432434)
			(xy 329.729336 -284.395597) (xy 329.767457 -284.364472) (xy 329.810078 -284.339865) (xy 329.856094 -284.322413)
			(xy 329.904313 -284.312569) (xy 329.953488 -284.310588) (xy 330.002343 -284.31652) (xy 330.049614 -284.330212)
			(xy 330.094076 -284.35131) (xy 330.134579 -284.379266) (xy 330.170072 -284.413358) (xy 330.199637 -284.452702)
			(xy 330.222508 -284.496279) (xy 330.238092 -284.54296) (xy 330.245987 -284.591537) (xy 330.246482 -284.616144)
			(xy 330.564739 -284.616144) (xy 330.568834 -284.565416) (xy 330.581013 -284.516002) (xy 330.600961 -284.469182)
			(xy 330.628162 -284.426168) (xy 330.66191 -284.388074) (xy 330.701332 -284.355887) (xy 330.745406 -284.330441)
			(xy 330.792992 -284.312394) (xy 330.842856 -284.302214) (xy 330.893708 -284.300165) (xy 330.944229 -284.306299)
			(xy 330.993113 -284.320459) (xy 331.039092 -284.342276) (xy 331.080976 -284.371186) (xy 331.11768 -284.406441)
			(xy 331.148253 -284.447127) (xy 331.171904 -284.49219) (xy 331.18802 -284.540464) (xy 331.196184 -284.590698)
			(xy 331.196696 -284.616144) (xy 331.515224 -284.616144) (xy 331.519184 -284.56709) (xy 331.530961 -284.519306)
			(xy 331.550252 -284.47403) (xy 331.576555 -284.432434) (xy 331.60919 -284.395597) (xy 331.647311 -284.364472)
			(xy 331.689932 -284.339865) (xy 331.735948 -284.322413) (xy 331.784167 -284.312569) (xy 331.833342 -284.310588)
			(xy 331.882197 -284.31652) (xy 331.929468 -284.330212) (xy 331.97393 -284.35131) (xy 332.014433 -284.379266)
			(xy 332.049926 -284.413358) (xy 332.079491 -284.452702) (xy 332.102362 -284.496279) (xy 332.117946 -284.54296)
			(xy 332.125841 -284.591537) (xy 332.126336 -284.616144) (xy 332.444847 -284.616144) (xy 332.448942 -284.565416)
			(xy 332.461121 -284.516002) (xy 332.481069 -284.469182) (xy 332.50827 -284.426168) (xy 332.542018 -284.388074)
			(xy 332.58144 -284.355887) (xy 332.625514 -284.330441) (xy 332.6731 -284.312394) (xy 332.722964 -284.302214)
			(xy 332.773816 -284.300165) (xy 332.824337 -284.306299) (xy 332.873221 -284.320459) (xy 332.9192 -284.342276)
			(xy 332.961084 -284.371186) (xy 332.997788 -284.406441) (xy 333.028361 -284.447127) (xy 333.052012 -284.49219)
			(xy 333.068128 -284.540464) (xy 333.076292 -284.590698) (xy 333.076804 -284.616144) (xy 333.384901 -284.616144)
			(xy 333.388996 -284.565416) (xy 333.401175 -284.516002) (xy 333.421123 -284.469182) (xy 333.448324 -284.426168)
			(xy 333.482072 -284.388074) (xy 333.521494 -284.355887) (xy 333.565568 -284.330441) (xy 333.613154 -284.312394)
			(xy 333.663018 -284.302214) (xy 333.71387 -284.300165) (xy 333.764391 -284.306299) (xy 333.813275 -284.320459)
			(xy 333.859254 -284.342276) (xy 333.901138 -284.371186) (xy 333.937842 -284.406441) (xy 333.968415 -284.447127)
			(xy 333.992066 -284.49219) (xy 334.008182 -284.540464) (xy 334.016346 -284.590698) (xy 334.016858 -284.616144)
			(xy 334.335386 -284.616144) (xy 334.339346 -284.56709) (xy 334.351123 -284.519306) (xy 334.370414 -284.47403)
			(xy 334.396717 -284.432434) (xy 334.429352 -284.395597) (xy 334.467473 -284.364472) (xy 334.510094 -284.339865)
			(xy 334.55611 -284.322413) (xy 334.604329 -284.312569) (xy 334.653504 -284.310588) (xy 334.702359 -284.31652)
			(xy 334.74963 -284.330212) (xy 334.794092 -284.35131) (xy 334.834595 -284.379266) (xy 334.870088 -284.413358)
			(xy 334.899653 -284.452702) (xy 334.922524 -284.496279) (xy 334.938108 -284.54296) (xy 334.946003 -284.591537)
			(xy 334.946498 -284.616144) (xy 335.264755 -284.616144) (xy 335.26885 -284.565416) (xy 335.281029 -284.516002)
			(xy 335.300977 -284.469182) (xy 335.328178 -284.426168) (xy 335.361926 -284.388074) (xy 335.401348 -284.355887)
			(xy 335.445422 -284.330441) (xy 335.493008 -284.312394) (xy 335.542872 -284.302214) (xy 335.593724 -284.300165)
			(xy 335.644245 -284.306299) (xy 335.693129 -284.320459) (xy 335.739108 -284.342276) (xy 335.780992 -284.371186)
			(xy 335.817696 -284.406441) (xy 335.848269 -284.447127) (xy 335.87192 -284.49219) (xy 335.888036 -284.540464)
			(xy 335.8962 -284.590698) (xy 335.896712 -284.616144) (xy 336.21524 -284.616144) (xy 336.2192 -284.56709)
			(xy 336.230977 -284.519306) (xy 336.250268 -284.47403) (xy 336.276571 -284.432434) (xy 336.309206 -284.395597)
			(xy 336.347327 -284.364472) (xy 336.389948 -284.339865) (xy 336.435964 -284.322413) (xy 336.484183 -284.312569)
			(xy 336.533358 -284.310588) (xy 336.582213 -284.31652) (xy 336.629484 -284.330212) (xy 336.673946 -284.35131)
			(xy 336.714449 -284.379266) (xy 336.749942 -284.413358) (xy 336.779507 -284.452702) (xy 336.802378 -284.496279)
			(xy 336.817962 -284.54296) (xy 336.825857 -284.591537) (xy 336.826352 -284.616144) (xy 337.144863 -284.616144)
			(xy 337.148958 -284.565416) (xy 337.161137 -284.516002) (xy 337.181085 -284.469182) (xy 337.208286 -284.426168)
			(xy 337.242034 -284.388074) (xy 337.281456 -284.355887) (xy 337.32553 -284.330441) (xy 337.373116 -284.312394)
			(xy 337.42298 -284.302214) (xy 337.473832 -284.300165) (xy 337.524353 -284.306299) (xy 337.573237 -284.320459)
			(xy 337.619216 -284.342276) (xy 337.6611 -284.371186) (xy 337.697804 -284.406441) (xy 337.728377 -284.447127)
			(xy 337.752028 -284.49219) (xy 337.768144 -284.540464) (xy 337.776308 -284.590698) (xy 337.77682 -284.616144)
			(xy 338.095348 -284.616144) (xy 338.099308 -284.56709) (xy 338.111085 -284.519306) (xy 338.130376 -284.47403)
			(xy 338.156679 -284.432434) (xy 338.189314 -284.395597) (xy 338.227435 -284.364472) (xy 338.270056 -284.339865)
			(xy 338.316072 -284.322413) (xy 338.364291 -284.312569) (xy 338.413466 -284.310588) (xy 338.462321 -284.31652)
			(xy 338.509592 -284.330212) (xy 338.554054 -284.35131) (xy 338.594557 -284.379266) (xy 338.63005 -284.413358)
			(xy 338.659615 -284.452702) (xy 338.682486 -284.496279) (xy 338.69807 -284.54296) (xy 338.705965 -284.591537)
			(xy 338.70646 -284.616144) (xy 339.024971 -284.616144) (xy 339.029066 -284.565416) (xy 339.041245 -284.516002)
			(xy 339.061193 -284.469182) (xy 339.088394 -284.426168) (xy 339.122142 -284.388074) (xy 339.161564 -284.355887)
			(xy 339.205638 -284.330441) (xy 339.253224 -284.312394) (xy 339.303088 -284.302214) (xy 339.35394 -284.300165)
			(xy 339.404461 -284.306299) (xy 339.453345 -284.320459) (xy 339.499324 -284.342276) (xy 339.541208 -284.371186)
			(xy 339.577912 -284.406441) (xy 339.608485 -284.447127) (xy 339.632136 -284.49219) (xy 339.648252 -284.540464)
			(xy 339.656416 -284.590698) (xy 339.656928 -284.616144) (xy 339.964771 -284.616144) (xy 339.968866 -284.565416)
			(xy 339.981045 -284.516002) (xy 340.000993 -284.469182) (xy 340.028194 -284.426168) (xy 340.061942 -284.388074)
			(xy 340.101364 -284.355887) (xy 340.145438 -284.330441) (xy 340.193024 -284.312394) (xy 340.242888 -284.302214)
			(xy 340.29374 -284.300165) (xy 340.344261 -284.306299) (xy 340.393145 -284.320459) (xy 340.439124 -284.342276)
			(xy 340.481008 -284.371186) (xy 340.517712 -284.406441) (xy 340.548285 -284.447127) (xy 340.571936 -284.49219)
			(xy 340.588052 -284.540464) (xy 340.596216 -284.590698) (xy 340.596728 -284.616144) (xy 340.915256 -284.616144)
			(xy 340.919216 -284.56709) (xy 340.930993 -284.519306) (xy 340.950284 -284.47403) (xy 340.976587 -284.432434)
			(xy 341.009222 -284.395597) (xy 341.047343 -284.364472) (xy 341.089964 -284.339865) (xy 341.13598 -284.322413)
			(xy 341.184199 -284.312569) (xy 341.233374 -284.310588) (xy 341.282229 -284.31652) (xy 341.3295 -284.330212)
			(xy 341.373962 -284.35131) (xy 341.414465 -284.379266) (xy 341.449958 -284.413358) (xy 341.479523 -284.452702)
			(xy 341.502394 -284.496279) (xy 341.517978 -284.54296) (xy 341.525873 -284.591537) (xy 341.526368 -284.616144)
			(xy 341.844879 -284.616144) (xy 341.848974 -284.565416) (xy 341.861153 -284.516002) (xy 341.881101 -284.469182)
			(xy 341.908302 -284.426168) (xy 341.94205 -284.388074) (xy 341.981472 -284.355887) (xy 342.025546 -284.330441)
			(xy 342.073132 -284.312394) (xy 342.122996 -284.302214) (xy 342.173848 -284.300165) (xy 342.224369 -284.306299)
			(xy 342.273253 -284.320459) (xy 342.319232 -284.342276) (xy 342.361116 -284.371186) (xy 342.39782 -284.406441)
			(xy 342.428393 -284.447127) (xy 342.452044 -284.49219) (xy 342.46816 -284.540464) (xy 342.476324 -284.590698)
			(xy 342.476836 -284.616144) (xy 342.795364 -284.616144) (xy 342.799324 -284.56709) (xy 342.811101 -284.519306)
			(xy 342.830392 -284.47403) (xy 342.856695 -284.432434) (xy 342.88933 -284.395597) (xy 342.927451 -284.364472)
			(xy 342.970072 -284.339865) (xy 343.016088 -284.322413) (xy 343.064307 -284.312569) (xy 343.113482 -284.310588)
			(xy 343.162337 -284.31652) (xy 343.209608 -284.330212) (xy 343.25407 -284.35131) (xy 343.294573 -284.379266)
			(xy 343.330066 -284.413358) (xy 343.359631 -284.452702) (xy 343.382502 -284.496279) (xy 343.398086 -284.54296)
			(xy 343.405981 -284.591537) (xy 343.406476 -284.616144) (xy 343.724987 -284.616144) (xy 343.729082 -284.565416)
			(xy 343.741261 -284.516002) (xy 343.761209 -284.469182) (xy 343.78841 -284.426168) (xy 343.822158 -284.388074)
			(xy 343.86158 -284.355887) (xy 343.905654 -284.330441) (xy 343.95324 -284.312394) (xy 344.003104 -284.302214)
			(xy 344.053956 -284.300165) (xy 344.104477 -284.306299) (xy 344.153361 -284.320459) (xy 344.19934 -284.342276)
			(xy 344.241224 -284.371186) (xy 344.277928 -284.406441) (xy 344.308501 -284.447127) (xy 344.332152 -284.49219)
			(xy 344.348268 -284.540464) (xy 344.356432 -284.590698) (xy 344.356944 -284.616144) (xy 344.675218 -284.616144)
			(xy 344.679178 -284.56709) (xy 344.690955 -284.519306) (xy 344.710246 -284.47403) (xy 344.736549 -284.432434)
			(xy 344.769184 -284.395597) (xy 344.807305 -284.364472) (xy 344.849926 -284.339865) (xy 344.895942 -284.322413)
			(xy 344.944161 -284.312569) (xy 344.993336 -284.310588) (xy 345.042191 -284.31652) (xy 345.089462 -284.330212)
			(xy 345.133924 -284.35131) (xy 345.174427 -284.379266) (xy 345.20992 -284.413358) (xy 345.239485 -284.452702)
			(xy 345.262356 -284.496279) (xy 345.27794 -284.54296) (xy 345.285835 -284.591537) (xy 345.28633 -284.616144)
			(xy 345.604841 -284.616144) (xy 345.608936 -284.565416) (xy 345.621115 -284.516002) (xy 345.641063 -284.469182)
			(xy 345.668264 -284.426168) (xy 345.702012 -284.388074) (xy 345.741434 -284.355887) (xy 345.785508 -284.330441)
			(xy 345.833094 -284.312394) (xy 345.882958 -284.302214) (xy 345.93381 -284.300165) (xy 345.984331 -284.306299)
			(xy 346.033215 -284.320459) (xy 346.079194 -284.342276) (xy 346.121078 -284.371186) (xy 346.157782 -284.406441)
			(xy 346.188355 -284.447127) (xy 346.212006 -284.49219) (xy 346.228122 -284.540464) (xy 346.236286 -284.590698)
			(xy 346.236798 -284.616144) (xy 346.544895 -284.616144) (xy 346.54899 -284.565416) (xy 346.561169 -284.516002)
			(xy 346.581117 -284.469182) (xy 346.608318 -284.426168) (xy 346.642066 -284.388074) (xy 346.681488 -284.355887)
			(xy 346.725562 -284.330441) (xy 346.773148 -284.312394) (xy 346.823012 -284.302214) (xy 346.873864 -284.300165)
			(xy 346.924385 -284.306299) (xy 346.973269 -284.320459) (xy 347.019248 -284.342276) (xy 347.061132 -284.371186)
			(xy 347.097836 -284.406441) (xy 347.128409 -284.447127) (xy 347.15206 -284.49219) (xy 347.168176 -284.540464)
			(xy 347.17634 -284.590698) (xy 347.176852 -284.616144) (xy 347.49538 -284.616144) (xy 347.49934 -284.56709)
			(xy 347.511117 -284.519306) (xy 347.530408 -284.47403) (xy 347.556711 -284.432434) (xy 347.589346 -284.395597)
			(xy 347.627467 -284.364472) (xy 347.670088 -284.339865) (xy 347.716104 -284.322413) (xy 347.764323 -284.312569)
			(xy 347.813498 -284.310588) (xy 347.862353 -284.31652) (xy 347.909624 -284.330212) (xy 347.954086 -284.35131)
			(xy 347.994589 -284.379266) (xy 348.030082 -284.413358) (xy 348.059647 -284.452702) (xy 348.082518 -284.496279)
			(xy 348.098102 -284.54296) (xy 348.105997 -284.591537) (xy 348.106492 -284.616144) (xy 348.425003 -284.616144)
			(xy 348.429098 -284.565416) (xy 348.441277 -284.516002) (xy 348.461225 -284.469182) (xy 348.488426 -284.426168)
			(xy 348.522174 -284.388074) (xy 348.561596 -284.355887) (xy 348.60567 -284.330441) (xy 348.653256 -284.312394)
			(xy 348.70312 -284.302214) (xy 348.753972 -284.300165) (xy 348.804493 -284.306299) (xy 348.853377 -284.320459)
			(xy 348.899356 -284.342276) (xy 348.94124 -284.371186) (xy 348.977944 -284.406441) (xy 349.008517 -284.447127)
			(xy 349.032168 -284.49219) (xy 349.048284 -284.540464) (xy 349.056448 -284.590698) (xy 349.05696 -284.616144)
			(xy 349.364803 -284.616144) (xy 349.368898 -284.565416) (xy 349.381077 -284.516002) (xy 349.401025 -284.469182)
			(xy 349.428226 -284.426168) (xy 349.461974 -284.388074) (xy 349.501396 -284.355887) (xy 349.54547 -284.330441)
			(xy 349.593056 -284.312394) (xy 349.64292 -284.302214) (xy 349.693772 -284.300165) (xy 349.744293 -284.306299)
			(xy 349.793177 -284.320459) (xy 349.839156 -284.342276) (xy 349.88104 -284.371186) (xy 349.917744 -284.406441)
			(xy 349.948317 -284.447127) (xy 349.971968 -284.49219) (xy 349.988084 -284.540464) (xy 349.996248 -284.590698)
			(xy 349.99676 -284.616144) (xy 350.315288 -284.616144) (xy 350.319248 -284.56709) (xy 350.331025 -284.519306)
			(xy 350.350316 -284.47403) (xy 350.376619 -284.432434) (xy 350.409254 -284.395597) (xy 350.447375 -284.364472)
			(xy 350.489996 -284.339865) (xy 350.536012 -284.322413) (xy 350.584231 -284.312569) (xy 350.633406 -284.310588)
			(xy 350.682261 -284.31652) (xy 350.729532 -284.330212) (xy 350.773994 -284.35131) (xy 350.814497 -284.379266)
			(xy 350.84999 -284.413358) (xy 350.879555 -284.452702) (xy 350.902426 -284.496279) (xy 350.91801 -284.54296)
			(xy 350.925905 -284.591537) (xy 350.9264 -284.616144) (xy 350.925905 -284.640751) (xy 350.91801 -284.689328)
			(xy 350.902426 -284.736009) (xy 350.879555 -284.779586) (xy 350.84999 -284.81893) (xy 350.814497 -284.853022)
			(xy 350.773994 -284.880978) (xy 350.729532 -284.902076) (xy 350.682261 -284.915768) (xy 350.633406 -284.9217)
			(xy 350.584231 -284.919719) (xy 350.536012 -284.909875) (xy 350.489996 -284.892423) (xy 350.447375 -284.867816)
			(xy 350.409254 -284.836691) (xy 350.376619 -284.799854) (xy 350.350316 -284.758258) (xy 350.331025 -284.712982)
			(xy 350.319248 -284.665198) (xy 350.315288 -284.616144) (xy 349.99676 -284.616144) (xy 349.996248 -284.64159)
			(xy 349.988084 -284.691824) (xy 349.971968 -284.740098) (xy 349.948317 -284.785161) (xy 349.917744 -284.825847)
			(xy 349.88104 -284.861102) (xy 349.839156 -284.890012) (xy 349.793177 -284.911829) (xy 349.744293 -284.925989)
			(xy 349.693772 -284.932123) (xy 349.64292 -284.930074) (xy 349.593056 -284.919894) (xy 349.54547 -284.901847)
			(xy 349.501396 -284.876401) (xy 349.461974 -284.844214) (xy 349.428226 -284.80612) (xy 349.401025 -284.763106)
			(xy 349.381077 -284.716286) (xy 349.368898 -284.666872) (xy 349.364803 -284.616144) (xy 349.05696 -284.616144)
			(xy 349.056448 -284.64159) (xy 349.048284 -284.691824) (xy 349.032168 -284.740098) (xy 349.008517 -284.785161)
			(xy 348.977944 -284.825847) (xy 348.94124 -284.861102) (xy 348.899356 -284.890012) (xy 348.853377 -284.911829)
			(xy 348.804493 -284.925989) (xy 348.753972 -284.932123) (xy 348.70312 -284.930074) (xy 348.653256 -284.919894)
			(xy 348.60567 -284.901847) (xy 348.561596 -284.876401) (xy 348.522174 -284.844214) (xy 348.488426 -284.80612)
			(xy 348.461225 -284.763106) (xy 348.441277 -284.716286) (xy 348.429098 -284.666872) (xy 348.425003 -284.616144)
			(xy 348.106492 -284.616144) (xy 348.105997 -284.640751) (xy 348.098102 -284.689328) (xy 348.082518 -284.736009)
			(xy 348.059647 -284.779586) (xy 348.030082 -284.81893) (xy 347.994589 -284.853022) (xy 347.954086 -284.880978)
			(xy 347.909624 -284.902076) (xy 347.862353 -284.915768) (xy 347.813498 -284.9217) (xy 347.764323 -284.919719)
			(xy 347.716104 -284.909875) (xy 347.670088 -284.892423) (xy 347.627467 -284.867816) (xy 347.589346 -284.836691)
			(xy 347.556711 -284.799854) (xy 347.530408 -284.758258) (xy 347.511117 -284.712982) (xy 347.49934 -284.665198)
			(xy 347.49538 -284.616144) (xy 347.176852 -284.616144) (xy 347.17634 -284.64159) (xy 347.168176 -284.691824)
			(xy 347.15206 -284.740098) (xy 347.128409 -284.785161) (xy 347.097836 -284.825847) (xy 347.061132 -284.861102)
			(xy 347.019248 -284.890012) (xy 346.973269 -284.911829) (xy 346.924385 -284.925989) (xy 346.873864 -284.932123)
			(xy 346.823012 -284.930074) (xy 346.773148 -284.919894) (xy 346.725562 -284.901847) (xy 346.681488 -284.876401)
			(xy 346.642066 -284.844214) (xy 346.608318 -284.80612) (xy 346.581117 -284.763106) (xy 346.561169 -284.716286)
			(xy 346.54899 -284.666872) (xy 346.544895 -284.616144) (xy 346.236798 -284.616144) (xy 346.236286 -284.64159)
			(xy 346.228122 -284.691824) (xy 346.212006 -284.740098) (xy 346.188355 -284.785161) (xy 346.157782 -284.825847)
			(xy 346.121078 -284.861102) (xy 346.079194 -284.890012) (xy 346.033215 -284.911829) (xy 345.984331 -284.925989)
			(xy 345.93381 -284.932123) (xy 345.882958 -284.930074) (xy 345.833094 -284.919894) (xy 345.785508 -284.901847)
			(xy 345.741434 -284.876401) (xy 345.702012 -284.844214) (xy 345.668264 -284.80612) (xy 345.641063 -284.763106)
			(xy 345.621115 -284.716286) (xy 345.608936 -284.666872) (xy 345.604841 -284.616144) (xy 345.28633 -284.616144)
			(xy 345.285835 -284.640751) (xy 345.27794 -284.689328) (xy 345.262356 -284.736009) (xy 345.239485 -284.779586)
			(xy 345.20992 -284.81893) (xy 345.174427 -284.853022) (xy 345.133924 -284.880978) (xy 345.089462 -284.902076)
			(xy 345.042191 -284.915768) (xy 344.993336 -284.9217) (xy 344.944161 -284.919719) (xy 344.895942 -284.909875)
			(xy 344.849926 -284.892423) (xy 344.807305 -284.867816) (xy 344.769184 -284.836691) (xy 344.736549 -284.799854)
			(xy 344.710246 -284.758258) (xy 344.690955 -284.712982) (xy 344.679178 -284.665198) (xy 344.675218 -284.616144)
			(xy 344.356944 -284.616144) (xy 344.356432 -284.64159) (xy 344.348268 -284.691824) (xy 344.332152 -284.740098)
			(xy 344.308501 -284.785161) (xy 344.277928 -284.825847) (xy 344.241224 -284.861102) (xy 344.19934 -284.890012)
			(xy 344.153361 -284.911829) (xy 344.104477 -284.925989) (xy 344.053956 -284.932123) (xy 344.003104 -284.930074)
			(xy 343.95324 -284.919894) (xy 343.905654 -284.901847) (xy 343.86158 -284.876401) (xy 343.822158 -284.844214)
			(xy 343.78841 -284.80612) (xy 343.761209 -284.763106) (xy 343.741261 -284.716286) (xy 343.729082 -284.666872)
			(xy 343.724987 -284.616144) (xy 343.406476 -284.616144) (xy 343.405981 -284.640751) (xy 343.398086 -284.689328)
			(xy 343.382502 -284.736009) (xy 343.359631 -284.779586) (xy 343.330066 -284.81893) (xy 343.294573 -284.853022)
			(xy 343.25407 -284.880978) (xy 343.209608 -284.902076) (xy 343.162337 -284.915768) (xy 343.113482 -284.9217)
			(xy 343.064307 -284.919719) (xy 343.016088 -284.909875) (xy 342.970072 -284.892423) (xy 342.927451 -284.867816)
			(xy 342.88933 -284.836691) (xy 342.856695 -284.799854) (xy 342.830392 -284.758258) (xy 342.811101 -284.712982)
			(xy 342.799324 -284.665198) (xy 342.795364 -284.616144) (xy 342.476836 -284.616144) (xy 342.476324 -284.64159)
			(xy 342.46816 -284.691824) (xy 342.452044 -284.740098) (xy 342.428393 -284.785161) (xy 342.39782 -284.825847)
			(xy 342.361116 -284.861102) (xy 342.319232 -284.890012) (xy 342.273253 -284.911829) (xy 342.224369 -284.925989)
			(xy 342.173848 -284.932123) (xy 342.122996 -284.930074) (xy 342.073132 -284.919894) (xy 342.025546 -284.901847)
			(xy 341.981472 -284.876401) (xy 341.94205 -284.844214) (xy 341.908302 -284.80612) (xy 341.881101 -284.763106)
			(xy 341.861153 -284.716286) (xy 341.848974 -284.666872) (xy 341.844879 -284.616144) (xy 341.526368 -284.616144)
			(xy 341.525873 -284.640751) (xy 341.517978 -284.689328) (xy 341.502394 -284.736009) (xy 341.479523 -284.779586)
			(xy 341.449958 -284.81893) (xy 341.414465 -284.853022) (xy 341.373962 -284.880978) (xy 341.3295 -284.902076)
			(xy 341.282229 -284.915768) (xy 341.233374 -284.9217) (xy 341.184199 -284.919719) (xy 341.13598 -284.909875)
			(xy 341.089964 -284.892423) (xy 341.047343 -284.867816) (xy 341.009222 -284.836691) (xy 340.976587 -284.799854)
			(xy 340.950284 -284.758258) (xy 340.930993 -284.712982) (xy 340.919216 -284.665198) (xy 340.915256 -284.616144)
			(xy 340.596728 -284.616144) (xy 340.596216 -284.64159) (xy 340.588052 -284.691824) (xy 340.571936 -284.740098)
			(xy 340.548285 -284.785161) (xy 340.517712 -284.825847) (xy 340.481008 -284.861102) (xy 340.439124 -284.890012)
			(xy 340.393145 -284.911829) (xy 340.344261 -284.925989) (xy 340.29374 -284.932123) (xy 340.242888 -284.930074)
			(xy 340.193024 -284.919894) (xy 340.145438 -284.901847) (xy 340.101364 -284.876401) (xy 340.061942 -284.844214)
			(xy 340.028194 -284.80612) (xy 340.000993 -284.763106) (xy 339.981045 -284.716286) (xy 339.968866 -284.666872)
			(xy 339.964771 -284.616144) (xy 339.656928 -284.616144) (xy 339.656416 -284.64159) (xy 339.648252 -284.691824)
			(xy 339.632136 -284.740098) (xy 339.608485 -284.785161) (xy 339.577912 -284.825847) (xy 339.541208 -284.861102)
			(xy 339.499324 -284.890012) (xy 339.453345 -284.911829) (xy 339.404461 -284.925989) (xy 339.35394 -284.932123)
			(xy 339.303088 -284.930074) (xy 339.253224 -284.919894) (xy 339.205638 -284.901847) (xy 339.161564 -284.876401)
			(xy 339.122142 -284.844214) (xy 339.088394 -284.80612) (xy 339.061193 -284.763106) (xy 339.041245 -284.716286)
			(xy 339.029066 -284.666872) (xy 339.024971 -284.616144) (xy 338.70646 -284.616144) (xy 338.705965 -284.640751)
			(xy 338.69807 -284.689328) (xy 338.682486 -284.736009) (xy 338.659615 -284.779586) (xy 338.63005 -284.81893)
			(xy 338.594557 -284.853022) (xy 338.554054 -284.880978) (xy 338.509592 -284.902076) (xy 338.462321 -284.915768)
			(xy 338.413466 -284.9217) (xy 338.364291 -284.919719) (xy 338.316072 -284.909875) (xy 338.270056 -284.892423)
			(xy 338.227435 -284.867816) (xy 338.189314 -284.836691) (xy 338.156679 -284.799854) (xy 338.130376 -284.758258)
			(xy 338.111085 -284.712982) (xy 338.099308 -284.665198) (xy 338.095348 -284.616144) (xy 337.77682 -284.616144)
			(xy 337.776308 -284.64159) (xy 337.768144 -284.691824) (xy 337.752028 -284.740098) (xy 337.728377 -284.785161)
			(xy 337.697804 -284.825847) (xy 337.6611 -284.861102) (xy 337.619216 -284.890012) (xy 337.573237 -284.911829)
			(xy 337.524353 -284.925989) (xy 337.473832 -284.932123) (xy 337.42298 -284.930074) (xy 337.373116 -284.919894)
			(xy 337.32553 -284.901847) (xy 337.281456 -284.876401) (xy 337.242034 -284.844214) (xy 337.208286 -284.80612)
			(xy 337.181085 -284.763106) (xy 337.161137 -284.716286) (xy 337.148958 -284.666872) (xy 337.144863 -284.616144)
			(xy 336.826352 -284.616144) (xy 336.825857 -284.640751) (xy 336.817962 -284.689328) (xy 336.802378 -284.736009)
			(xy 336.779507 -284.779586) (xy 336.749942 -284.81893) (xy 336.714449 -284.853022) (xy 336.673946 -284.880978)
			(xy 336.629484 -284.902076) (xy 336.582213 -284.915768) (xy 336.533358 -284.9217) (xy 336.484183 -284.919719)
			(xy 336.435964 -284.909875) (xy 336.389948 -284.892423) (xy 336.347327 -284.867816) (xy 336.309206 -284.836691)
			(xy 336.276571 -284.799854) (xy 336.250268 -284.758258) (xy 336.230977 -284.712982) (xy 336.2192 -284.665198)
			(xy 336.21524 -284.616144) (xy 335.896712 -284.616144) (xy 335.8962 -284.64159) (xy 335.888036 -284.691824)
			(xy 335.87192 -284.740098) (xy 335.848269 -284.785161) (xy 335.817696 -284.825847) (xy 335.780992 -284.861102)
			(xy 335.739108 -284.890012) (xy 335.693129 -284.911829) (xy 335.644245 -284.925989) (xy 335.593724 -284.932123)
			(xy 335.542872 -284.930074) (xy 335.493008 -284.919894) (xy 335.445422 -284.901847) (xy 335.401348 -284.876401)
			(xy 335.361926 -284.844214) (xy 335.328178 -284.80612) (xy 335.300977 -284.763106) (xy 335.281029 -284.716286)
			(xy 335.26885 -284.666872) (xy 335.264755 -284.616144) (xy 334.946498 -284.616144) (xy 334.946003 -284.640751)
			(xy 334.938108 -284.689328) (xy 334.922524 -284.736009) (xy 334.899653 -284.779586) (xy 334.870088 -284.81893)
			(xy 334.834595 -284.853022) (xy 334.794092 -284.880978) (xy 334.74963 -284.902076) (xy 334.702359 -284.915768)
			(xy 334.653504 -284.9217) (xy 334.604329 -284.919719) (xy 334.55611 -284.909875) (xy 334.510094 -284.892423)
			(xy 334.467473 -284.867816) (xy 334.429352 -284.836691) (xy 334.396717 -284.799854) (xy 334.370414 -284.758258)
			(xy 334.351123 -284.712982) (xy 334.339346 -284.665198) (xy 334.335386 -284.616144) (xy 334.016858 -284.616144)
			(xy 334.016346 -284.64159) (xy 334.008182 -284.691824) (xy 333.992066 -284.740098) (xy 333.968415 -284.785161)
			(xy 333.937842 -284.825847) (xy 333.901138 -284.861102) (xy 333.859254 -284.890012) (xy 333.813275 -284.911829)
			(xy 333.764391 -284.925989) (xy 333.71387 -284.932123) (xy 333.663018 -284.930074) (xy 333.613154 -284.919894)
			(xy 333.565568 -284.901847) (xy 333.521494 -284.876401) (xy 333.482072 -284.844214) (xy 333.448324 -284.80612)
			(xy 333.421123 -284.763106) (xy 333.401175 -284.716286) (xy 333.388996 -284.666872) (xy 333.384901 -284.616144)
			(xy 333.076804 -284.616144) (xy 333.076292 -284.64159) (xy 333.068128 -284.691824) (xy 333.052012 -284.740098)
			(xy 333.028361 -284.785161) (xy 332.997788 -284.825847) (xy 332.961084 -284.861102) (xy 332.9192 -284.890012)
			(xy 332.873221 -284.911829) (xy 332.824337 -284.925989) (xy 332.773816 -284.932123) (xy 332.722964 -284.930074)
			(xy 332.6731 -284.919894) (xy 332.625514 -284.901847) (xy 332.58144 -284.876401) (xy 332.542018 -284.844214)
			(xy 332.50827 -284.80612) (xy 332.481069 -284.763106) (xy 332.461121 -284.716286) (xy 332.448942 -284.666872)
			(xy 332.444847 -284.616144) (xy 332.126336 -284.616144) (xy 332.125841 -284.640751) (xy 332.117946 -284.689328)
			(xy 332.102362 -284.736009) (xy 332.079491 -284.779586) (xy 332.049926 -284.81893) (xy 332.014433 -284.853022)
			(xy 331.97393 -284.880978) (xy 331.929468 -284.902076) (xy 331.882197 -284.915768) (xy 331.833342 -284.9217)
			(xy 331.784167 -284.919719) (xy 331.735948 -284.909875) (xy 331.689932 -284.892423) (xy 331.647311 -284.867816)
			(xy 331.60919 -284.836691) (xy 331.576555 -284.799854) (xy 331.550252 -284.758258) (xy 331.530961 -284.712982)
			(xy 331.519184 -284.665198) (xy 331.515224 -284.616144) (xy 331.196696 -284.616144) (xy 331.196184 -284.64159)
			(xy 331.18802 -284.691824) (xy 331.171904 -284.740098) (xy 331.148253 -284.785161) (xy 331.11768 -284.825847)
			(xy 331.080976 -284.861102) (xy 331.039092 -284.890012) (xy 330.993113 -284.911829) (xy 330.944229 -284.925989)
			(xy 330.893708 -284.932123) (xy 330.842856 -284.930074) (xy 330.792992 -284.919894) (xy 330.745406 -284.901847)
			(xy 330.701332 -284.876401) (xy 330.66191 -284.844214) (xy 330.628162 -284.80612) (xy 330.600961 -284.763106)
			(xy 330.581013 -284.716286) (xy 330.568834 -284.666872) (xy 330.564739 -284.616144) (xy 330.246482 -284.616144)
			(xy 330.245987 -284.640751) (xy 330.238092 -284.689328) (xy 330.222508 -284.736009) (xy 330.199637 -284.779586)
			(xy 330.170072 -284.81893) (xy 330.134579 -284.853022) (xy 330.094076 -284.880978) (xy 330.049614 -284.902076)
			(xy 330.002343 -284.915768) (xy 329.953488 -284.9217) (xy 329.904313 -284.919719) (xy 329.856094 -284.909875)
			(xy 329.810078 -284.892423) (xy 329.767457 -284.867816) (xy 329.729336 -284.836691) (xy 329.696701 -284.799854)
			(xy 329.670398 -284.758258) (xy 329.651107 -284.712982) (xy 329.63933 -284.665198) (xy 329.63537 -284.616144)
			(xy 329.316842 -284.616144) (xy 329.31633 -284.64159) (xy 329.308166 -284.691824) (xy 329.29205 -284.740098)
			(xy 329.268399 -284.785161) (xy 329.237826 -284.825847) (xy 329.201122 -284.861102) (xy 329.159238 -284.890012)
			(xy 329.113259 -284.911829) (xy 329.064375 -284.925989) (xy 329.013854 -284.932123) (xy 328.963002 -284.930074)
			(xy 328.913138 -284.919894) (xy 328.865552 -284.901847) (xy 328.821478 -284.876401) (xy 328.782056 -284.844214)
			(xy 328.748308 -284.80612) (xy 328.721107 -284.763106) (xy 328.701159 -284.716286) (xy 328.68898 -284.666872)
			(xy 328.684885 -284.616144) (xy 328.366374 -284.616144) (xy 328.365879 -284.640751) (xy 328.357984 -284.689328)
			(xy 328.3424 -284.736009) (xy 328.319529 -284.779586) (xy 328.289964 -284.81893) (xy 328.254471 -284.853022)
			(xy 328.213968 -284.880978) (xy 328.169506 -284.902076) (xy 328.122235 -284.915768) (xy 328.07338 -284.9217)
			(xy 328.024205 -284.919719) (xy 327.975986 -284.909875) (xy 327.92997 -284.892423) (xy 327.887349 -284.867816)
			(xy 327.849228 -284.836691) (xy 327.816593 -284.799854) (xy 327.79029 -284.758258) (xy 327.770999 -284.712982)
			(xy 327.759222 -284.665198) (xy 327.755262 -284.616144) (xy 325.203519 -284.616144) (xy 325.161384 -284.636138)
			(xy 325.114113 -284.64983) (xy 325.065258 -284.655762) (xy 325.016083 -284.653781) (xy 324.967864 -284.643937)
			(xy 324.921848 -284.626485) (xy 324.879227 -284.601878) (xy 324.841106 -284.570753) (xy 324.808471 -284.533916)
			(xy 324.782168 -284.49232) (xy 324.762877 -284.447044) (xy 324.7511 -284.39926) (xy 324.74714 -284.350206)
			(xy 310.45912 -284.350206) (xy 310.45912 -285.42615) (xy 326.345308 -285.42615) (xy 326.349268 -285.377096)
			(xy 326.361045 -285.329312) (xy 326.380336 -285.284036) (xy 326.406639 -285.24244) (xy 326.439274 -285.205603)
			(xy 326.477395 -285.174478) (xy 326.520016 -285.149871) (xy 326.566032 -285.132419) (xy 326.614251 -285.122575)
			(xy 326.663426 -285.120594) (xy 326.712281 -285.126526) (xy 326.759552 -285.140218) (xy 326.804014 -285.161316)
			(xy 326.844517 -285.189272) (xy 326.88001 -285.223364) (xy 326.909575 -285.262708) (xy 326.932446 -285.306285)
			(xy 326.94803 -285.352966) (xy 326.955925 -285.401543) (xy 326.95642 -285.42615) (xy 329.154785 -285.42615)
			(xy 329.15888 -285.375422) (xy 329.171059 -285.326008) (xy 329.191007 -285.279188) (xy 329.218208 -285.236174)
			(xy 329.251956 -285.19808) (xy 329.291378 -285.165893) (xy 329.335452 -285.140447) (xy 329.383038 -285.1224)
			(xy 329.432902 -285.11222) (xy 329.483754 -285.110171) (xy 329.534275 -285.116305) (xy 329.583159 -285.130465)
			(xy 329.629138 -285.152282) (xy 329.671022 -285.181192) (xy 329.707726 -285.216447) (xy 329.738299 -285.257133)
			(xy 329.76195 -285.302196) (xy 329.778066 -285.35047) (xy 329.78623 -285.400704) (xy 329.786742 -285.42615)
			(xy 330.094839 -285.42615) (xy 330.098934 -285.375422) (xy 330.111113 -285.326008) (xy 330.131061 -285.279188)
			(xy 330.158262 -285.236174) (xy 330.19201 -285.19808) (xy 330.231432 -285.165893) (xy 330.275506 -285.140447)
			(xy 330.323092 -285.1224) (xy 330.372956 -285.11222) (xy 330.423808 -285.110171) (xy 330.474329 -285.116305)
			(xy 330.523213 -285.130465) (xy 330.569192 -285.152282) (xy 330.611076 -285.181192) (xy 330.64778 -285.216447)
			(xy 330.678353 -285.257133) (xy 330.702004 -285.302196) (xy 330.71812 -285.35047) (xy 330.726284 -285.400704)
			(xy 330.726796 -285.42615) (xy 331.045324 -285.42615) (xy 331.049284 -285.377096) (xy 331.061061 -285.329312)
			(xy 331.080352 -285.284036) (xy 331.106655 -285.24244) (xy 331.13929 -285.205603) (xy 331.177411 -285.174478)
			(xy 331.220032 -285.149871) (xy 331.266048 -285.132419) (xy 331.314267 -285.122575) (xy 331.363442 -285.120594)
			(xy 331.412297 -285.126526) (xy 331.459568 -285.140218) (xy 331.50403 -285.161316) (xy 331.544533 -285.189272)
			(xy 331.580026 -285.223364) (xy 331.609591 -285.262708) (xy 331.632462 -285.306285) (xy 331.648046 -285.352966)
			(xy 331.655941 -285.401543) (xy 331.656436 -285.42615) (xy 331.974947 -285.42615) (xy 331.979042 -285.375422)
			(xy 331.991221 -285.326008) (xy 332.011169 -285.279188) (xy 332.03837 -285.236174) (xy 332.072118 -285.19808)
			(xy 332.11154 -285.165893) (xy 332.155614 -285.140447) (xy 332.2032 -285.1224) (xy 332.253064 -285.11222)
			(xy 332.303916 -285.110171) (xy 332.354437 -285.116305) (xy 332.403321 -285.130465) (xy 332.4493 -285.152282)
			(xy 332.491184 -285.181192) (xy 332.527888 -285.216447) (xy 332.558461 -285.257133) (xy 332.582112 -285.302196)
			(xy 332.598228 -285.35047) (xy 332.606392 -285.400704) (xy 332.606904 -285.42615) (xy 332.925178 -285.42615)
			(xy 332.929138 -285.377096) (xy 332.940915 -285.329312) (xy 332.960206 -285.284036) (xy 332.986509 -285.24244)
			(xy 333.019144 -285.205603) (xy 333.057265 -285.174478) (xy 333.099886 -285.149871) (xy 333.145902 -285.132419)
			(xy 333.194121 -285.122575) (xy 333.243296 -285.120594) (xy 333.292151 -285.126526) (xy 333.339422 -285.140218)
			(xy 333.383884 -285.161316) (xy 333.424387 -285.189272) (xy 333.45988 -285.223364) (xy 333.489445 -285.262708)
			(xy 333.512316 -285.306285) (xy 333.5279 -285.352966) (xy 333.535795 -285.401543) (xy 333.53629 -285.42615)
			(xy 333.854801 -285.42615) (xy 333.858896 -285.375422) (xy 333.871075 -285.326008) (xy 333.891023 -285.279188)
			(xy 333.918224 -285.236174) (xy 333.951972 -285.19808) (xy 333.991394 -285.165893) (xy 334.035468 -285.140447)
			(xy 334.083054 -285.1224) (xy 334.132918 -285.11222) (xy 334.18377 -285.110171) (xy 334.234291 -285.116305)
			(xy 334.283175 -285.130465) (xy 334.329154 -285.152282) (xy 334.371038 -285.181192) (xy 334.407742 -285.216447)
			(xy 334.438315 -285.257133) (xy 334.461966 -285.302196) (xy 334.478082 -285.35047) (xy 334.486246 -285.400704)
			(xy 334.486758 -285.42615) (xy 335.734909 -285.42615) (xy 335.739004 -285.375422) (xy 335.751183 -285.326008)
			(xy 335.771131 -285.279188) (xy 335.798332 -285.236174) (xy 335.83208 -285.19808) (xy 335.871502 -285.165893)
			(xy 335.915576 -285.140447) (xy 335.963162 -285.1224) (xy 336.013026 -285.11222) (xy 336.063878 -285.110171)
			(xy 336.114399 -285.116305) (xy 336.163283 -285.130465) (xy 336.209262 -285.152282) (xy 336.251146 -285.181192)
			(xy 336.28785 -285.216447) (xy 336.318423 -285.257133) (xy 336.342074 -285.302196) (xy 336.35819 -285.35047)
			(xy 336.366354 -285.400704) (xy 336.366866 -285.42615) (xy 336.674963 -285.42615) (xy 336.679058 -285.375422)
			(xy 336.691237 -285.326008) (xy 336.711185 -285.279188) (xy 336.738386 -285.236174) (xy 336.772134 -285.19808)
			(xy 336.811556 -285.165893) (xy 336.85563 -285.140447) (xy 336.903216 -285.1224) (xy 336.95308 -285.11222)
			(xy 337.003932 -285.110171) (xy 337.054453 -285.116305) (xy 337.103337 -285.130465) (xy 337.149316 -285.152282)
			(xy 337.1912 -285.181192) (xy 337.227904 -285.216447) (xy 337.258477 -285.257133) (xy 337.282128 -285.302196)
			(xy 337.298244 -285.35047) (xy 337.306408 -285.400704) (xy 337.30692 -285.42615) (xy 337.625194 -285.42615)
			(xy 337.629154 -285.377096) (xy 337.640931 -285.329312) (xy 337.660222 -285.284036) (xy 337.686525 -285.24244)
			(xy 337.71916 -285.205603) (xy 337.757281 -285.174478) (xy 337.799902 -285.149871) (xy 337.845918 -285.132419)
			(xy 337.894137 -285.122575) (xy 337.943312 -285.120594) (xy 337.992167 -285.126526) (xy 338.039438 -285.140218)
			(xy 338.0839 -285.161316) (xy 338.124403 -285.189272) (xy 338.159896 -285.223364) (xy 338.189461 -285.262708)
			(xy 338.212332 -285.306285) (xy 338.227916 -285.352966) (xy 338.235811 -285.401543) (xy 338.236306 -285.42615)
			(xy 338.554817 -285.42615) (xy 338.558912 -285.375422) (xy 338.571091 -285.326008) (xy 338.591039 -285.279188)
			(xy 338.61824 -285.236174) (xy 338.651988 -285.19808) (xy 338.69141 -285.165893) (xy 338.735484 -285.140447)
			(xy 338.78307 -285.1224) (xy 338.832934 -285.11222) (xy 338.883786 -285.110171) (xy 338.934307 -285.116305)
			(xy 338.983191 -285.130465) (xy 339.02917 -285.152282) (xy 339.071054 -285.181192) (xy 339.107758 -285.216447)
			(xy 339.138331 -285.257133) (xy 339.161982 -285.302196) (xy 339.178098 -285.35047) (xy 339.186262 -285.400704)
			(xy 339.186774 -285.42615) (xy 339.505302 -285.42615) (xy 339.509262 -285.377096) (xy 339.521039 -285.329312)
			(xy 339.54033 -285.284036) (xy 339.566633 -285.24244) (xy 339.599268 -285.205603) (xy 339.637389 -285.174478)
			(xy 339.68001 -285.149871) (xy 339.726026 -285.132419) (xy 339.774245 -285.122575) (xy 339.82342 -285.120594)
			(xy 339.872275 -285.126526) (xy 339.919546 -285.140218) (xy 339.964008 -285.161316) (xy 340.004511 -285.189272)
			(xy 340.040004 -285.223364) (xy 340.069569 -285.262708) (xy 340.09244 -285.306285) (xy 340.108024 -285.352966)
			(xy 340.115919 -285.401543) (xy 340.116414 -285.42615) (xy 340.434925 -285.42615) (xy 340.43902 -285.375422)
			(xy 340.451199 -285.326008) (xy 340.471147 -285.279188) (xy 340.498348 -285.236174) (xy 340.532096 -285.19808)
			(xy 340.571518 -285.165893) (xy 340.615592 -285.140447) (xy 340.663178 -285.1224) (xy 340.713042 -285.11222)
			(xy 340.763894 -285.110171) (xy 340.814415 -285.116305) (xy 340.863299 -285.130465) (xy 340.909278 -285.152282)
			(xy 340.951162 -285.181192) (xy 340.987866 -285.216447) (xy 341.018439 -285.257133) (xy 341.04209 -285.302196)
			(xy 341.058206 -285.35047) (xy 341.06637 -285.400704) (xy 341.066882 -285.42615) (xy 342.314779 -285.42615)
			(xy 342.318874 -285.375422) (xy 342.331053 -285.326008) (xy 342.351001 -285.279188) (xy 342.378202 -285.236174)
			(xy 342.41195 -285.19808) (xy 342.451372 -285.165893) (xy 342.495446 -285.140447) (xy 342.543032 -285.1224)
			(xy 342.592896 -285.11222) (xy 342.643748 -285.110171) (xy 342.694269 -285.116305) (xy 342.743153 -285.130465)
			(xy 342.789132 -285.152282) (xy 342.831016 -285.181192) (xy 342.86772 -285.216447) (xy 342.898293 -285.257133)
			(xy 342.921944 -285.302196) (xy 342.93806 -285.35047) (xy 342.946224 -285.400704) (xy 342.946736 -285.42615)
			(xy 343.254833 -285.42615) (xy 343.258928 -285.375422) (xy 343.271107 -285.326008) (xy 343.291055 -285.279188)
			(xy 343.318256 -285.236174) (xy 343.352004 -285.19808) (xy 343.391426 -285.165893) (xy 343.4355 -285.140447)
			(xy 343.483086 -285.1224) (xy 343.53295 -285.11222) (xy 343.583802 -285.110171) (xy 343.634323 -285.116305)
			(xy 343.683207 -285.130465) (xy 343.729186 -285.152282) (xy 343.77107 -285.181192) (xy 343.807774 -285.216447)
			(xy 343.838347 -285.257133) (xy 343.861998 -285.302196) (xy 343.878114 -285.35047) (xy 343.886278 -285.400704)
			(xy 343.88679 -285.42615) (xy 345.145372 -285.42615) (xy 345.149332 -285.377096) (xy 345.161109 -285.329312)
			(xy 345.1804 -285.284036) (xy 345.206703 -285.24244) (xy 345.239338 -285.205603) (xy 345.277459 -285.174478)
			(xy 345.32008 -285.149871) (xy 345.366096 -285.132419) (xy 345.414315 -285.122575) (xy 345.46349 -285.120594)
			(xy 345.512345 -285.126526) (xy 345.559616 -285.140218) (xy 345.604078 -285.161316) (xy 345.644581 -285.189272)
			(xy 345.680074 -285.223364) (xy 345.709639 -285.262708) (xy 345.73251 -285.306285) (xy 345.748094 -285.352966)
			(xy 345.755989 -285.401543) (xy 345.756484 -285.42615) (xy 346.085426 -285.42615) (xy 346.089386 -285.377096)
			(xy 346.101163 -285.329312) (xy 346.120454 -285.284036) (xy 346.146757 -285.24244) (xy 346.179392 -285.205603)
			(xy 346.217513 -285.174478) (xy 346.260134 -285.149871) (xy 346.30615 -285.132419) (xy 346.354369 -285.122575)
			(xy 346.403544 -285.120594) (xy 346.452399 -285.126526) (xy 346.49967 -285.140218) (xy 346.544132 -285.161316)
			(xy 346.584635 -285.189272) (xy 346.620128 -285.223364) (xy 346.649693 -285.262708) (xy 346.672564 -285.306285)
			(xy 346.688148 -285.352966) (xy 346.696043 -285.401543) (xy 346.696538 -285.42615) (xy 347.025226 -285.42615)
			(xy 347.029186 -285.377096) (xy 347.040963 -285.329312) (xy 347.060254 -285.284036) (xy 347.086557 -285.24244)
			(xy 347.119192 -285.205603) (xy 347.157313 -285.174478) (xy 347.199934 -285.149871) (xy 347.24595 -285.132419)
			(xy 347.294169 -285.122575) (xy 347.343344 -285.120594) (xy 347.392199 -285.126526) (xy 347.43947 -285.140218)
			(xy 347.483932 -285.161316) (xy 347.524435 -285.189272) (xy 347.559928 -285.223364) (xy 347.589493 -285.262708)
			(xy 347.612364 -285.306285) (xy 347.627948 -285.352966) (xy 347.635843 -285.401543) (xy 347.636338 -285.42615)
			(xy 347.96528 -285.42615) (xy 347.96924 -285.377096) (xy 347.981017 -285.329312) (xy 348.000308 -285.284036)
			(xy 348.026611 -285.24244) (xy 348.059246 -285.205603) (xy 348.097367 -285.174478) (xy 348.139988 -285.149871)
			(xy 348.186004 -285.132419) (xy 348.234223 -285.122575) (xy 348.283398 -285.120594) (xy 348.332253 -285.126526)
			(xy 348.379524 -285.140218) (xy 348.423986 -285.161316) (xy 348.464489 -285.189272) (xy 348.499982 -285.223364)
			(xy 348.529547 -285.262708) (xy 348.552418 -285.306285) (xy 348.568002 -285.352966) (xy 348.575897 -285.401543)
			(xy 348.576392 -285.42615) (xy 348.905334 -285.42615) (xy 348.909294 -285.377096) (xy 348.921071 -285.329312)
			(xy 348.940362 -285.284036) (xy 348.966665 -285.24244) (xy 348.9993 -285.205603) (xy 349.037421 -285.174478)
			(xy 349.080042 -285.149871) (xy 349.126058 -285.132419) (xy 349.174277 -285.122575) (xy 349.223452 -285.120594)
			(xy 349.272307 -285.126526) (xy 349.319578 -285.140218) (xy 349.36404 -285.161316) (xy 349.404543 -285.189272)
			(xy 349.440036 -285.223364) (xy 349.469601 -285.262708) (xy 349.492472 -285.306285) (xy 349.508056 -285.352966)
			(xy 349.515951 -285.401543) (xy 349.516446 -285.42615) (xy 349.845388 -285.42615) (xy 349.849348 -285.377096)
			(xy 349.861125 -285.329312) (xy 349.880416 -285.284036) (xy 349.906719 -285.24244) (xy 349.939354 -285.205603)
			(xy 349.977475 -285.174478) (xy 350.020096 -285.149871) (xy 350.066112 -285.132419) (xy 350.114331 -285.122575)
			(xy 350.163506 -285.120594) (xy 350.212361 -285.126526) (xy 350.259632 -285.140218) (xy 350.304094 -285.161316)
			(xy 350.344597 -285.189272) (xy 350.38009 -285.223364) (xy 350.409655 -285.262708) (xy 350.432526 -285.306285)
			(xy 350.44811 -285.352966) (xy 350.456005 -285.401543) (xy 350.4565 -285.42615) (xy 350.785442 -285.42615)
			(xy 350.789402 -285.377096) (xy 350.801179 -285.329312) (xy 350.82047 -285.284036) (xy 350.846773 -285.24244)
			(xy 350.879408 -285.205603) (xy 350.917529 -285.174478) (xy 350.96015 -285.149871) (xy 351.006166 -285.132419)
			(xy 351.054385 -285.122575) (xy 351.10356 -285.120594) (xy 351.152415 -285.126526) (xy 351.199686 -285.140218)
			(xy 351.244148 -285.161316) (xy 351.284651 -285.189272) (xy 351.320144 -285.223364) (xy 351.349709 -285.262708)
			(xy 351.37258 -285.306285) (xy 351.388164 -285.352966) (xy 351.396059 -285.401543) (xy 351.396554 -285.42615)
			(xy 351.396059 -285.450757) (xy 351.388164 -285.499334) (xy 351.37258 -285.546015) (xy 351.349709 -285.589592)
			(xy 351.320144 -285.628936) (xy 351.284651 -285.663028) (xy 351.244148 -285.690984) (xy 351.199686 -285.712082)
			(xy 351.152415 -285.725774) (xy 351.10356 -285.731706) (xy 351.054385 -285.729725) (xy 351.006166 -285.719881)
			(xy 350.96015 -285.702429) (xy 350.917529 -285.677822) (xy 350.879408 -285.646697) (xy 350.846773 -285.60986)
			(xy 350.82047 -285.568264) (xy 350.801179 -285.522988) (xy 350.789402 -285.475204) (xy 350.785442 -285.42615)
			(xy 350.4565 -285.42615) (xy 350.456005 -285.450757) (xy 350.44811 -285.499334) (xy 350.432526 -285.546015)
			(xy 350.409655 -285.589592) (xy 350.38009 -285.628936) (xy 350.344597 -285.663028) (xy 350.304094 -285.690984)
			(xy 350.259632 -285.712082) (xy 350.212361 -285.725774) (xy 350.163506 -285.731706) (xy 350.114331 -285.729725)
			(xy 350.066112 -285.719881) (xy 350.020096 -285.702429) (xy 349.977475 -285.677822) (xy 349.939354 -285.646697)
			(xy 349.906719 -285.60986) (xy 349.880416 -285.568264) (xy 349.861125 -285.522988) (xy 349.849348 -285.475204)
			(xy 349.845388 -285.42615) (xy 349.516446 -285.42615) (xy 349.515951 -285.450757) (xy 349.508056 -285.499334)
			(xy 349.492472 -285.546015) (xy 349.469601 -285.589592) (xy 349.440036 -285.628936) (xy 349.404543 -285.663028)
			(xy 349.36404 -285.690984) (xy 349.319578 -285.712082) (xy 349.272307 -285.725774) (xy 349.223452 -285.731706)
			(xy 349.174277 -285.729725) (xy 349.126058 -285.719881) (xy 349.080042 -285.702429) (xy 349.037421 -285.677822)
			(xy 348.9993 -285.646697) (xy 348.966665 -285.60986) (xy 348.940362 -285.568264) (xy 348.921071 -285.522988)
			(xy 348.909294 -285.475204) (xy 348.905334 -285.42615) (xy 348.576392 -285.42615) (xy 348.575897 -285.450757)
			(xy 348.568002 -285.499334) (xy 348.552418 -285.546015) (xy 348.529547 -285.589592) (xy 348.499982 -285.628936)
			(xy 348.464489 -285.663028) (xy 348.423986 -285.690984) (xy 348.379524 -285.712082) (xy 348.332253 -285.725774)
			(xy 348.283398 -285.731706) (xy 348.234223 -285.729725) (xy 348.186004 -285.719881) (xy 348.139988 -285.702429)
			(xy 348.097367 -285.677822) (xy 348.059246 -285.646697) (xy 348.026611 -285.60986) (xy 348.000308 -285.568264)
			(xy 347.981017 -285.522988) (xy 347.96924 -285.475204) (xy 347.96528 -285.42615) (xy 347.636338 -285.42615)
			(xy 347.635843 -285.450757) (xy 347.627948 -285.499334) (xy 347.612364 -285.546015) (xy 347.589493 -285.589592)
			(xy 347.559928 -285.628936) (xy 347.524435 -285.663028) (xy 347.483932 -285.690984) (xy 347.43947 -285.712082)
			(xy 347.392199 -285.725774) (xy 347.343344 -285.731706) (xy 347.294169 -285.729725) (xy 347.24595 -285.719881)
			(xy 347.199934 -285.702429) (xy 347.157313 -285.677822) (xy 347.119192 -285.646697) (xy 347.086557 -285.60986)
			(xy 347.060254 -285.568264) (xy 347.040963 -285.522988) (xy 347.029186 -285.475204) (xy 347.025226 -285.42615)
			(xy 346.696538 -285.42615) (xy 346.696043 -285.450757) (xy 346.688148 -285.499334) (xy 346.672564 -285.546015)
			(xy 346.649693 -285.589592) (xy 346.620128 -285.628936) (xy 346.584635 -285.663028) (xy 346.544132 -285.690984)
			(xy 346.49967 -285.712082) (xy 346.452399 -285.725774) (xy 346.403544 -285.731706) (xy 346.354369 -285.729725)
			(xy 346.30615 -285.719881) (xy 346.260134 -285.702429) (xy 346.217513 -285.677822) (xy 346.179392 -285.646697)
			(xy 346.146757 -285.60986) (xy 346.120454 -285.568264) (xy 346.101163 -285.522988) (xy 346.089386 -285.475204)
			(xy 346.085426 -285.42615) (xy 345.756484 -285.42615) (xy 345.755989 -285.450757) (xy 345.748094 -285.499334)
			(xy 345.73251 -285.546015) (xy 345.709639 -285.589592) (xy 345.680074 -285.628936) (xy 345.644581 -285.663028)
			(xy 345.604078 -285.690984) (xy 345.559616 -285.712082) (xy 345.512345 -285.725774) (xy 345.46349 -285.731706)
			(xy 345.414315 -285.729725) (xy 345.366096 -285.719881) (xy 345.32008 -285.702429) (xy 345.277459 -285.677822)
			(xy 345.239338 -285.646697) (xy 345.206703 -285.60986) (xy 345.1804 -285.568264) (xy 345.161109 -285.522988)
			(xy 345.149332 -285.475204) (xy 345.145372 -285.42615) (xy 343.88679 -285.42615) (xy 343.886278 -285.451596)
			(xy 343.878114 -285.50183) (xy 343.861998 -285.550104) (xy 343.838347 -285.595167) (xy 343.807774 -285.635853)
			(xy 343.77107 -285.671108) (xy 343.729186 -285.700018) (xy 343.683207 -285.721835) (xy 343.634323 -285.735995)
			(xy 343.583802 -285.742129) (xy 343.53295 -285.74008) (xy 343.483086 -285.7299) (xy 343.4355 -285.711853)
			(xy 343.391426 -285.686407) (xy 343.352004 -285.65422) (xy 343.318256 -285.616126) (xy 343.291055 -285.573112)
			(xy 343.271107 -285.526292) (xy 343.258928 -285.476878) (xy 343.254833 -285.42615) (xy 342.946736 -285.42615)
			(xy 342.946224 -285.451596) (xy 342.93806 -285.50183) (xy 342.921944 -285.550104) (xy 342.898293 -285.595167)
			(xy 342.86772 -285.635853) (xy 342.831016 -285.671108) (xy 342.789132 -285.700018) (xy 342.743153 -285.721835)
			(xy 342.694269 -285.735995) (xy 342.643748 -285.742129) (xy 342.592896 -285.74008) (xy 342.543032 -285.7299)
			(xy 342.495446 -285.711853) (xy 342.451372 -285.686407) (xy 342.41195 -285.65422) (xy 342.378202 -285.616126)
			(xy 342.351001 -285.573112) (xy 342.331053 -285.526292) (xy 342.318874 -285.476878) (xy 342.314779 -285.42615)
			(xy 341.066882 -285.42615) (xy 341.06637 -285.451596) (xy 341.058206 -285.50183) (xy 341.04209 -285.550104)
			(xy 341.018439 -285.595167) (xy 340.987866 -285.635853) (xy 340.951162 -285.671108) (xy 340.909278 -285.700018)
			(xy 340.863299 -285.721835) (xy 340.814415 -285.735995) (xy 340.763894 -285.742129) (xy 340.713042 -285.74008)
			(xy 340.663178 -285.7299) (xy 340.615592 -285.711853) (xy 340.571518 -285.686407) (xy 340.532096 -285.65422)
			(xy 340.498348 -285.616126) (xy 340.471147 -285.573112) (xy 340.451199 -285.526292) (xy 340.43902 -285.476878)
			(xy 340.434925 -285.42615) (xy 340.116414 -285.42615) (xy 340.115919 -285.450757) (xy 340.108024 -285.499334)
			(xy 340.09244 -285.546015) (xy 340.069569 -285.589592) (xy 340.040004 -285.628936) (xy 340.004511 -285.663028)
			(xy 339.964008 -285.690984) (xy 339.919546 -285.712082) (xy 339.872275 -285.725774) (xy 339.82342 -285.731706)
			(xy 339.774245 -285.729725) (xy 339.726026 -285.719881) (xy 339.68001 -285.702429) (xy 339.637389 -285.677822)
			(xy 339.599268 -285.646697) (xy 339.566633 -285.60986) (xy 339.54033 -285.568264) (xy 339.521039 -285.522988)
			(xy 339.509262 -285.475204) (xy 339.505302 -285.42615) (xy 339.186774 -285.42615) (xy 339.186262 -285.451596)
			(xy 339.178098 -285.50183) (xy 339.161982 -285.550104) (xy 339.138331 -285.595167) (xy 339.107758 -285.635853)
			(xy 339.071054 -285.671108) (xy 339.02917 -285.700018) (xy 338.983191 -285.721835) (xy 338.934307 -285.735995)
			(xy 338.883786 -285.742129) (xy 338.832934 -285.74008) (xy 338.78307 -285.7299) (xy 338.735484 -285.711853)
			(xy 338.69141 -285.686407) (xy 338.651988 -285.65422) (xy 338.61824 -285.616126) (xy 338.591039 -285.573112)
			(xy 338.571091 -285.526292) (xy 338.558912 -285.476878) (xy 338.554817 -285.42615) (xy 338.236306 -285.42615)
			(xy 338.235811 -285.450757) (xy 338.227916 -285.499334) (xy 338.212332 -285.546015) (xy 338.189461 -285.589592)
			(xy 338.159896 -285.628936) (xy 338.124403 -285.663028) (xy 338.0839 -285.690984) (xy 338.039438 -285.712082)
			(xy 337.992167 -285.725774) (xy 337.943312 -285.731706) (xy 337.894137 -285.729725) (xy 337.845918 -285.719881)
			(xy 337.799902 -285.702429) (xy 337.757281 -285.677822) (xy 337.71916 -285.646697) (xy 337.686525 -285.60986)
			(xy 337.660222 -285.568264) (xy 337.640931 -285.522988) (xy 337.629154 -285.475204) (xy 337.625194 -285.42615)
			(xy 337.30692 -285.42615) (xy 337.306408 -285.451596) (xy 337.298244 -285.50183) (xy 337.282128 -285.550104)
			(xy 337.258477 -285.595167) (xy 337.227904 -285.635853) (xy 337.1912 -285.671108) (xy 337.149316 -285.700018)
			(xy 337.103337 -285.721835) (xy 337.054453 -285.735995) (xy 337.003932 -285.742129) (xy 336.95308 -285.74008)
			(xy 336.903216 -285.7299) (xy 336.85563 -285.711853) (xy 336.811556 -285.686407) (xy 336.772134 -285.65422)
			(xy 336.738386 -285.616126) (xy 336.711185 -285.573112) (xy 336.691237 -285.526292) (xy 336.679058 -285.476878)
			(xy 336.674963 -285.42615) (xy 336.366866 -285.42615) (xy 336.366354 -285.451596) (xy 336.35819 -285.50183)
			(xy 336.342074 -285.550104) (xy 336.318423 -285.595167) (xy 336.28785 -285.635853) (xy 336.251146 -285.671108)
			(xy 336.209262 -285.700018) (xy 336.163283 -285.721835) (xy 336.114399 -285.735995) (xy 336.063878 -285.742129)
			(xy 336.013026 -285.74008) (xy 335.963162 -285.7299) (xy 335.915576 -285.711853) (xy 335.871502 -285.686407)
			(xy 335.83208 -285.65422) (xy 335.798332 -285.616126) (xy 335.771131 -285.573112) (xy 335.751183 -285.526292)
			(xy 335.739004 -285.476878) (xy 335.734909 -285.42615) (xy 334.486758 -285.42615) (xy 334.486246 -285.451596)
			(xy 334.478082 -285.50183) (xy 334.461966 -285.550104) (xy 334.438315 -285.595167) (xy 334.407742 -285.635853)
			(xy 334.371038 -285.671108) (xy 334.329154 -285.700018) (xy 334.283175 -285.721835) (xy 334.234291 -285.735995)
			(xy 334.18377 -285.742129) (xy 334.132918 -285.74008) (xy 334.083054 -285.7299) (xy 334.035468 -285.711853)
			(xy 333.991394 -285.686407) (xy 333.951972 -285.65422) (xy 333.918224 -285.616126) (xy 333.891023 -285.573112)
			(xy 333.871075 -285.526292) (xy 333.858896 -285.476878) (xy 333.854801 -285.42615) (xy 333.53629 -285.42615)
			(xy 333.535795 -285.450757) (xy 333.5279 -285.499334) (xy 333.512316 -285.546015) (xy 333.489445 -285.589592)
			(xy 333.45988 -285.628936) (xy 333.424387 -285.663028) (xy 333.383884 -285.690984) (xy 333.339422 -285.712082)
			(xy 333.292151 -285.725774) (xy 333.243296 -285.731706) (xy 333.194121 -285.729725) (xy 333.145902 -285.719881)
			(xy 333.099886 -285.702429) (xy 333.057265 -285.677822) (xy 333.019144 -285.646697) (xy 332.986509 -285.60986)
			(xy 332.960206 -285.568264) (xy 332.940915 -285.522988) (xy 332.929138 -285.475204) (xy 332.925178 -285.42615)
			(xy 332.606904 -285.42615) (xy 332.606392 -285.451596) (xy 332.598228 -285.50183) (xy 332.582112 -285.550104)
			(xy 332.558461 -285.595167) (xy 332.527888 -285.635853) (xy 332.491184 -285.671108) (xy 332.4493 -285.700018)
			(xy 332.403321 -285.721835) (xy 332.354437 -285.735995) (xy 332.303916 -285.742129) (xy 332.253064 -285.74008)
			(xy 332.2032 -285.7299) (xy 332.155614 -285.711853) (xy 332.11154 -285.686407) (xy 332.072118 -285.65422)
			(xy 332.03837 -285.616126) (xy 332.011169 -285.573112) (xy 331.991221 -285.526292) (xy 331.979042 -285.476878)
			(xy 331.974947 -285.42615) (xy 331.656436 -285.42615) (xy 331.655941 -285.450757) (xy 331.648046 -285.499334)
			(xy 331.632462 -285.546015) (xy 331.609591 -285.589592) (xy 331.580026 -285.628936) (xy 331.544533 -285.663028)
			(xy 331.50403 -285.690984) (xy 331.459568 -285.712082) (xy 331.412297 -285.725774) (xy 331.363442 -285.731706)
			(xy 331.314267 -285.729725) (xy 331.266048 -285.719881) (xy 331.220032 -285.702429) (xy 331.177411 -285.677822)
			(xy 331.13929 -285.646697) (xy 331.106655 -285.60986) (xy 331.080352 -285.568264) (xy 331.061061 -285.522988)
			(xy 331.049284 -285.475204) (xy 331.045324 -285.42615) (xy 330.726796 -285.42615) (xy 330.726284 -285.451596)
			(xy 330.71812 -285.50183) (xy 330.702004 -285.550104) (xy 330.678353 -285.595167) (xy 330.64778 -285.635853)
			(xy 330.611076 -285.671108) (xy 330.569192 -285.700018) (xy 330.523213 -285.721835) (xy 330.474329 -285.735995)
			(xy 330.423808 -285.742129) (xy 330.372956 -285.74008) (xy 330.323092 -285.7299) (xy 330.275506 -285.711853)
			(xy 330.231432 -285.686407) (xy 330.19201 -285.65422) (xy 330.158262 -285.616126) (xy 330.131061 -285.573112)
			(xy 330.111113 -285.526292) (xy 330.098934 -285.476878) (xy 330.094839 -285.42615) (xy 329.786742 -285.42615)
			(xy 329.78623 -285.451596) (xy 329.778066 -285.50183) (xy 329.76195 -285.550104) (xy 329.738299 -285.595167)
			(xy 329.707726 -285.635853) (xy 329.671022 -285.671108) (xy 329.629138 -285.700018) (xy 329.583159 -285.721835)
			(xy 329.534275 -285.735995) (xy 329.483754 -285.742129) (xy 329.432902 -285.74008) (xy 329.383038 -285.7299)
			(xy 329.335452 -285.711853) (xy 329.291378 -285.686407) (xy 329.251956 -285.65422) (xy 329.218208 -285.616126)
			(xy 329.191007 -285.573112) (xy 329.171059 -285.526292) (xy 329.15888 -285.476878) (xy 329.154785 -285.42615)
			(xy 326.95642 -285.42615) (xy 326.955925 -285.450757) (xy 326.94803 -285.499334) (xy 326.932446 -285.546015)
			(xy 326.909575 -285.589592) (xy 326.88001 -285.628936) (xy 326.844517 -285.663028) (xy 326.804014 -285.690984)
			(xy 326.759552 -285.712082) (xy 326.712281 -285.725774) (xy 326.663426 -285.731706) (xy 326.614251 -285.729725)
			(xy 326.566032 -285.719881) (xy 326.520016 -285.702429) (xy 326.477395 -285.677822) (xy 326.439274 -285.646697)
			(xy 326.406639 -285.60986) (xy 326.380336 -285.568264) (xy 326.361045 -285.522988) (xy 326.349268 -285.475204)
			(xy 326.345308 -285.42615) (xy 310.45912 -285.42615) (xy 310.45912 -285.970218) (xy 324.74714 -285.970218)
			(xy 324.7511 -285.921164) (xy 324.762877 -285.87338) (xy 324.782168 -285.828104) (xy 324.808471 -285.786508)
			(xy 324.841106 -285.749671) (xy 324.879227 -285.718546) (xy 324.921848 -285.693939) (xy 324.967864 -285.676487)
			(xy 325.016083 -285.666643) (xy 325.065258 -285.664662) (xy 325.114113 -285.670594) (xy 325.161384 -285.684286)
			(xy 325.205846 -285.705384) (xy 325.246349 -285.73334) (xy 325.281842 -285.767432) (xy 325.311407 -285.806776)
			(xy 325.334278 -285.850353) (xy 325.349862 -285.897034) (xy 325.357757 -285.945611) (xy 325.358252 -285.970218)
			(xy 325.357757 -285.994825) (xy 325.349862 -286.043402) (xy 325.334278 -286.090083) (xy 325.311407 -286.13366)
			(xy 325.281842 -286.173004) (xy 325.246349 -286.207096) (xy 325.205846 -286.235052) (xy 325.203519 -286.236156)
			(xy 327.755262 -286.236156) (xy 327.759222 -286.187102) (xy 327.770999 -286.139318) (xy 327.79029 -286.094042)
			(xy 327.816593 -286.052446) (xy 327.849228 -286.015609) (xy 327.887349 -285.984484) (xy 327.92997 -285.959877)
			(xy 327.975986 -285.942425) (xy 328.024205 -285.932581) (xy 328.07338 -285.9306) (xy 328.122235 -285.936532)
			(xy 328.169506 -285.950224) (xy 328.213968 -285.971322) (xy 328.254471 -285.999278) (xy 328.289964 -286.03337)
			(xy 328.319529 -286.072714) (xy 328.3424 -286.116291) (xy 328.357984 -286.162972) (xy 328.365879 -286.211549)
			(xy 328.366374 -286.236156) (xy 328.684885 -286.236156) (xy 328.68898 -286.185428) (xy 328.701159 -286.136014)
			(xy 328.721107 -286.089194) (xy 328.748308 -286.04618) (xy 328.782056 -286.008086) (xy 328.821478 -285.975899)
			(xy 328.865552 -285.950453) (xy 328.913138 -285.932406) (xy 328.963002 -285.922226) (xy 329.013854 -285.920177)
			(xy 329.064375 -285.926311) (xy 329.113259 -285.940471) (xy 329.159238 -285.962288) (xy 329.201122 -285.991198)
			(xy 329.237826 -286.026453) (xy 329.268399 -286.067139) (xy 329.29205 -286.112202) (xy 329.308166 -286.160476)
			(xy 329.31633 -286.21071) (xy 329.316842 -286.236156) (xy 329.63537 -286.236156) (xy 329.63933 -286.187102)
			(xy 329.651107 -286.139318) (xy 329.670398 -286.094042) (xy 329.696701 -286.052446) (xy 329.729336 -286.015609)
			(xy 329.767457 -285.984484) (xy 329.810078 -285.959877) (xy 329.856094 -285.942425) (xy 329.904313 -285.932581)
			(xy 329.953488 -285.9306) (xy 330.002343 -285.936532) (xy 330.049614 -285.950224) (xy 330.094076 -285.971322)
			(xy 330.134579 -285.999278) (xy 330.170072 -286.03337) (xy 330.199637 -286.072714) (xy 330.222508 -286.116291)
			(xy 330.238092 -286.162972) (xy 330.245987 -286.211549) (xy 330.246482 -286.236156) (xy 330.564739 -286.236156)
			(xy 330.568834 -286.185428) (xy 330.581013 -286.136014) (xy 330.600961 -286.089194) (xy 330.628162 -286.04618)
			(xy 330.66191 -286.008086) (xy 330.701332 -285.975899) (xy 330.745406 -285.950453) (xy 330.792992 -285.932406)
			(xy 330.842856 -285.922226) (xy 330.893708 -285.920177) (xy 330.944229 -285.926311) (xy 330.993113 -285.940471)
			(xy 331.039092 -285.962288) (xy 331.080976 -285.991198) (xy 331.11768 -286.026453) (xy 331.148253 -286.067139)
			(xy 331.171904 -286.112202) (xy 331.18802 -286.160476) (xy 331.196184 -286.21071) (xy 331.196696 -286.236156)
			(xy 331.515224 -286.236156) (xy 331.519184 -286.187102) (xy 331.530961 -286.139318) (xy 331.550252 -286.094042)
			(xy 331.576555 -286.052446) (xy 331.60919 -286.015609) (xy 331.647311 -285.984484) (xy 331.689932 -285.959877)
			(xy 331.735948 -285.942425) (xy 331.784167 -285.932581) (xy 331.833342 -285.9306) (xy 331.882197 -285.936532)
			(xy 331.929468 -285.950224) (xy 331.97393 -285.971322) (xy 332.014433 -285.999278) (xy 332.049926 -286.03337)
			(xy 332.079491 -286.072714) (xy 332.102362 -286.116291) (xy 332.117946 -286.162972) (xy 332.125841 -286.211549)
			(xy 332.126336 -286.236156) (xy 332.444847 -286.236156) (xy 332.448942 -286.185428) (xy 332.461121 -286.136014)
			(xy 332.481069 -286.089194) (xy 332.50827 -286.04618) (xy 332.542018 -286.008086) (xy 332.58144 -285.975899)
			(xy 332.625514 -285.950453) (xy 332.6731 -285.932406) (xy 332.722964 -285.922226) (xy 332.773816 -285.920177)
			(xy 332.824337 -285.926311) (xy 332.873221 -285.940471) (xy 332.9192 -285.962288) (xy 332.961084 -285.991198)
			(xy 332.997788 -286.026453) (xy 333.028361 -286.067139) (xy 333.052012 -286.112202) (xy 333.068128 -286.160476)
			(xy 333.076292 -286.21071) (xy 333.076804 -286.236156) (xy 333.384901 -286.236156) (xy 333.388996 -286.185428)
			(xy 333.401175 -286.136014) (xy 333.421123 -286.089194) (xy 333.448324 -286.04618) (xy 333.482072 -286.008086)
			(xy 333.521494 -285.975899) (xy 333.565568 -285.950453) (xy 333.613154 -285.932406) (xy 333.663018 -285.922226)
			(xy 333.71387 -285.920177) (xy 333.764391 -285.926311) (xy 333.813275 -285.940471) (xy 333.859254 -285.962288)
			(xy 333.901138 -285.991198) (xy 333.937842 -286.026453) (xy 333.968415 -286.067139) (xy 333.992066 -286.112202)
			(xy 334.008182 -286.160476) (xy 334.016346 -286.21071) (xy 334.016858 -286.236156) (xy 334.335386 -286.236156)
			(xy 334.339346 -286.187102) (xy 334.351123 -286.139318) (xy 334.370414 -286.094042) (xy 334.396717 -286.052446)
			(xy 334.429352 -286.015609) (xy 334.467473 -285.984484) (xy 334.510094 -285.959877) (xy 334.55611 -285.942425)
			(xy 334.604329 -285.932581) (xy 334.653504 -285.9306) (xy 334.702359 -285.936532) (xy 334.74963 -285.950224)
			(xy 334.794092 -285.971322) (xy 334.834595 -285.999278) (xy 334.870088 -286.03337) (xy 334.899653 -286.072714)
			(xy 334.922524 -286.116291) (xy 334.938108 -286.162972) (xy 334.946003 -286.211549) (xy 334.946498 -286.236156)
			(xy 335.264755 -286.236156) (xy 335.26885 -286.185428) (xy 335.281029 -286.136014) (xy 335.300977 -286.089194)
			(xy 335.328178 -286.04618) (xy 335.361926 -286.008086) (xy 335.401348 -285.975899) (xy 335.445422 -285.950453)
			(xy 335.493008 -285.932406) (xy 335.542872 -285.922226) (xy 335.593724 -285.920177) (xy 335.644245 -285.926311)
			(xy 335.693129 -285.940471) (xy 335.739108 -285.962288) (xy 335.780992 -285.991198) (xy 335.817696 -286.026453)
			(xy 335.848269 -286.067139) (xy 335.87192 -286.112202) (xy 335.888036 -286.160476) (xy 335.8962 -286.21071)
			(xy 335.896712 -286.236156) (xy 336.21524 -286.236156) (xy 336.2192 -286.187102) (xy 336.230977 -286.139318)
			(xy 336.250268 -286.094042) (xy 336.276571 -286.052446) (xy 336.309206 -286.015609) (xy 336.347327 -285.984484)
			(xy 336.389948 -285.959877) (xy 336.435964 -285.942425) (xy 336.484183 -285.932581) (xy 336.533358 -285.9306)
			(xy 336.582213 -285.936532) (xy 336.629484 -285.950224) (xy 336.673946 -285.971322) (xy 336.714449 -285.999278)
			(xy 336.749942 -286.03337) (xy 336.779507 -286.072714) (xy 336.802378 -286.116291) (xy 336.817962 -286.162972)
			(xy 336.825857 -286.211549) (xy 336.826352 -286.236156) (xy 337.144863 -286.236156) (xy 337.148958 -286.185428)
			(xy 337.161137 -286.136014) (xy 337.181085 -286.089194) (xy 337.208286 -286.04618) (xy 337.242034 -286.008086)
			(xy 337.281456 -285.975899) (xy 337.32553 -285.950453) (xy 337.373116 -285.932406) (xy 337.42298 -285.922226)
			(xy 337.473832 -285.920177) (xy 337.524353 -285.926311) (xy 337.573237 -285.940471) (xy 337.619216 -285.962288)
			(xy 337.6611 -285.991198) (xy 337.697804 -286.026453) (xy 337.728377 -286.067139) (xy 337.752028 -286.112202)
			(xy 337.768144 -286.160476) (xy 337.776308 -286.21071) (xy 337.77682 -286.236156) (xy 338.095348 -286.236156)
			(xy 338.099308 -286.187102) (xy 338.111085 -286.139318) (xy 338.130376 -286.094042) (xy 338.156679 -286.052446)
			(xy 338.189314 -286.015609) (xy 338.227435 -285.984484) (xy 338.270056 -285.959877) (xy 338.316072 -285.942425)
			(xy 338.364291 -285.932581) (xy 338.413466 -285.9306) (xy 338.462321 -285.936532) (xy 338.509592 -285.950224)
			(xy 338.554054 -285.971322) (xy 338.594557 -285.999278) (xy 338.63005 -286.03337) (xy 338.659615 -286.072714)
			(xy 338.682486 -286.116291) (xy 338.69807 -286.162972) (xy 338.705965 -286.211549) (xy 338.70646 -286.236156)
			(xy 339.024971 -286.236156) (xy 339.029066 -286.185428) (xy 339.041245 -286.136014) (xy 339.061193 -286.089194)
			(xy 339.088394 -286.04618) (xy 339.122142 -286.008086) (xy 339.161564 -285.975899) (xy 339.205638 -285.950453)
			(xy 339.253224 -285.932406) (xy 339.303088 -285.922226) (xy 339.35394 -285.920177) (xy 339.404461 -285.926311)
			(xy 339.453345 -285.940471) (xy 339.499324 -285.962288) (xy 339.541208 -285.991198) (xy 339.577912 -286.026453)
			(xy 339.608485 -286.067139) (xy 339.632136 -286.112202) (xy 339.648252 -286.160476) (xy 339.656416 -286.21071)
			(xy 339.656928 -286.236156) (xy 339.964771 -286.236156) (xy 339.968866 -286.185428) (xy 339.981045 -286.136014)
			(xy 340.000993 -286.089194) (xy 340.028194 -286.04618) (xy 340.061942 -286.008086) (xy 340.101364 -285.975899)
			(xy 340.145438 -285.950453) (xy 340.193024 -285.932406) (xy 340.242888 -285.922226) (xy 340.29374 -285.920177)
			(xy 340.344261 -285.926311) (xy 340.393145 -285.940471) (xy 340.439124 -285.962288) (xy 340.481008 -285.991198)
			(xy 340.517712 -286.026453) (xy 340.548285 -286.067139) (xy 340.571936 -286.112202) (xy 340.588052 -286.160476)
			(xy 340.596216 -286.21071) (xy 340.596728 -286.236156) (xy 340.915256 -286.236156) (xy 340.919216 -286.187102)
			(xy 340.930993 -286.139318) (xy 340.950284 -286.094042) (xy 340.976587 -286.052446) (xy 341.009222 -286.015609)
			(xy 341.047343 -285.984484) (xy 341.089964 -285.959877) (xy 341.13598 -285.942425) (xy 341.184199 -285.932581)
			(xy 341.233374 -285.9306) (xy 341.282229 -285.936532) (xy 341.3295 -285.950224) (xy 341.373962 -285.971322)
			(xy 341.414465 -285.999278) (xy 341.449958 -286.03337) (xy 341.479523 -286.072714) (xy 341.502394 -286.116291)
			(xy 341.517978 -286.162972) (xy 341.525873 -286.211549) (xy 341.526368 -286.236156) (xy 341.844879 -286.236156)
			(xy 341.848974 -286.185428) (xy 341.861153 -286.136014) (xy 341.881101 -286.089194) (xy 341.908302 -286.04618)
			(xy 341.94205 -286.008086) (xy 341.981472 -285.975899) (xy 342.025546 -285.950453) (xy 342.073132 -285.932406)
			(xy 342.122996 -285.922226) (xy 342.173848 -285.920177) (xy 342.224369 -285.926311) (xy 342.273253 -285.940471)
			(xy 342.319232 -285.962288) (xy 342.361116 -285.991198) (xy 342.39782 -286.026453) (xy 342.428393 -286.067139)
			(xy 342.452044 -286.112202) (xy 342.46816 -286.160476) (xy 342.476324 -286.21071) (xy 342.476836 -286.236156)
			(xy 342.795364 -286.236156) (xy 342.799324 -286.187102) (xy 342.811101 -286.139318) (xy 342.830392 -286.094042)
			(xy 342.856695 -286.052446) (xy 342.88933 -286.015609) (xy 342.927451 -285.984484) (xy 342.970072 -285.959877)
			(xy 343.016088 -285.942425) (xy 343.064307 -285.932581) (xy 343.113482 -285.9306) (xy 343.162337 -285.936532)
			(xy 343.209608 -285.950224) (xy 343.25407 -285.971322) (xy 343.294573 -285.999278) (xy 343.330066 -286.03337)
			(xy 343.359631 -286.072714) (xy 343.382502 -286.116291) (xy 343.398086 -286.162972) (xy 343.405981 -286.211549)
			(xy 343.406476 -286.236156) (xy 343.724987 -286.236156) (xy 343.729082 -286.185428) (xy 343.741261 -286.136014)
			(xy 343.761209 -286.089194) (xy 343.78841 -286.04618) (xy 343.822158 -286.008086) (xy 343.86158 -285.975899)
			(xy 343.905654 -285.950453) (xy 343.95324 -285.932406) (xy 344.003104 -285.922226) (xy 344.053956 -285.920177)
			(xy 344.104477 -285.926311) (xy 344.153361 -285.940471) (xy 344.19934 -285.962288) (xy 344.241224 -285.991198)
			(xy 344.277928 -286.026453) (xy 344.308501 -286.067139) (xy 344.332152 -286.112202) (xy 344.348268 -286.160476)
			(xy 344.356432 -286.21071) (xy 344.356944 -286.236156) (xy 344.675218 -286.236156) (xy 344.679178 -286.187102)
			(xy 344.690955 -286.139318) (xy 344.710246 -286.094042) (xy 344.736549 -286.052446) (xy 344.769184 -286.015609)
			(xy 344.807305 -285.984484) (xy 344.849926 -285.959877) (xy 344.895942 -285.942425) (xy 344.944161 -285.932581)
			(xy 344.993336 -285.9306) (xy 345.042191 -285.936532) (xy 345.089462 -285.950224) (xy 345.133924 -285.971322)
			(xy 345.174427 -285.999278) (xy 345.20992 -286.03337) (xy 345.239485 -286.072714) (xy 345.262356 -286.116291)
			(xy 345.27794 -286.162972) (xy 345.285835 -286.211549) (xy 345.28633 -286.236156) (xy 345.604841 -286.236156)
			(xy 345.608936 -286.185428) (xy 345.621115 -286.136014) (xy 345.641063 -286.089194) (xy 345.668264 -286.04618)
			(xy 345.702012 -286.008086) (xy 345.741434 -285.975899) (xy 345.785508 -285.950453) (xy 345.833094 -285.932406)
			(xy 345.882958 -285.922226) (xy 345.93381 -285.920177) (xy 345.984331 -285.926311) (xy 346.033215 -285.940471)
			(xy 346.079194 -285.962288) (xy 346.121078 -285.991198) (xy 346.157782 -286.026453) (xy 346.188355 -286.067139)
			(xy 346.212006 -286.112202) (xy 346.228122 -286.160476) (xy 346.236286 -286.21071) (xy 346.236798 -286.236156)
			(xy 346.544895 -286.236156) (xy 346.54899 -286.185428) (xy 346.561169 -286.136014) (xy 346.581117 -286.089194)
			(xy 346.608318 -286.04618) (xy 346.642066 -286.008086) (xy 346.681488 -285.975899) (xy 346.725562 -285.950453)
			(xy 346.773148 -285.932406) (xy 346.823012 -285.922226) (xy 346.873864 -285.920177) (xy 346.924385 -285.926311)
			(xy 346.973269 -285.940471) (xy 347.019248 -285.962288) (xy 347.061132 -285.991198) (xy 347.097836 -286.026453)
			(xy 347.128409 -286.067139) (xy 347.15206 -286.112202) (xy 347.168176 -286.160476) (xy 347.17634 -286.21071)
			(xy 347.176852 -286.236156) (xy 347.49538 -286.236156) (xy 347.49934 -286.187102) (xy 347.511117 -286.139318)
			(xy 347.530408 -286.094042) (xy 347.556711 -286.052446) (xy 347.589346 -286.015609) (xy 347.627467 -285.984484)
			(xy 347.670088 -285.959877) (xy 347.716104 -285.942425) (xy 347.764323 -285.932581) (xy 347.813498 -285.9306)
			(xy 347.862353 -285.936532) (xy 347.909624 -285.950224) (xy 347.954086 -285.971322) (xy 347.994589 -285.999278)
			(xy 348.030082 -286.03337) (xy 348.059647 -286.072714) (xy 348.082518 -286.116291) (xy 348.098102 -286.162972)
			(xy 348.105997 -286.211549) (xy 348.106492 -286.236156) (xy 348.425003 -286.236156) (xy 348.429098 -286.185428)
			(xy 348.441277 -286.136014) (xy 348.461225 -286.089194) (xy 348.488426 -286.04618) (xy 348.522174 -286.008086)
			(xy 348.561596 -285.975899) (xy 348.60567 -285.950453) (xy 348.653256 -285.932406) (xy 348.70312 -285.922226)
			(xy 348.753972 -285.920177) (xy 348.804493 -285.926311) (xy 348.853377 -285.940471) (xy 348.899356 -285.962288)
			(xy 348.94124 -285.991198) (xy 348.977944 -286.026453) (xy 349.008517 -286.067139) (xy 349.032168 -286.112202)
			(xy 349.048284 -286.160476) (xy 349.056448 -286.21071) (xy 349.05696 -286.236156) (xy 349.364803 -286.236156)
			(xy 349.368898 -286.185428) (xy 349.381077 -286.136014) (xy 349.401025 -286.089194) (xy 349.428226 -286.04618)
			(xy 349.461974 -286.008086) (xy 349.501396 -285.975899) (xy 349.54547 -285.950453) (xy 349.593056 -285.932406)
			(xy 349.64292 -285.922226) (xy 349.693772 -285.920177) (xy 349.744293 -285.926311) (xy 349.793177 -285.940471)
			(xy 349.839156 -285.962288) (xy 349.88104 -285.991198) (xy 349.917744 -286.026453) (xy 349.948317 -286.067139)
			(xy 349.971968 -286.112202) (xy 349.988084 -286.160476) (xy 349.996248 -286.21071) (xy 349.99676 -286.236156)
			(xy 350.315288 -286.236156) (xy 350.319248 -286.187102) (xy 350.331025 -286.139318) (xy 350.350316 -286.094042)
			(xy 350.376619 -286.052446) (xy 350.409254 -286.015609) (xy 350.447375 -285.984484) (xy 350.489996 -285.959877)
			(xy 350.536012 -285.942425) (xy 350.584231 -285.932581) (xy 350.633406 -285.9306) (xy 350.682261 -285.936532)
			(xy 350.729532 -285.950224) (xy 350.773994 -285.971322) (xy 350.814497 -285.999278) (xy 350.84999 -286.03337)
			(xy 350.879555 -286.072714) (xy 350.902426 -286.116291) (xy 350.91801 -286.162972) (xy 350.925905 -286.211549)
			(xy 350.9264 -286.236156) (xy 350.925905 -286.260763) (xy 350.91801 -286.30934) (xy 350.902426 -286.356021)
			(xy 350.879555 -286.399598) (xy 350.84999 -286.438942) (xy 350.814497 -286.473034) (xy 350.773994 -286.50099)
			(xy 350.729532 -286.522088) (xy 350.682261 -286.53578) (xy 350.633406 -286.541712) (xy 350.584231 -286.539731)
			(xy 350.536012 -286.529887) (xy 350.489996 -286.512435) (xy 350.447375 -286.487828) (xy 350.409254 -286.456703)
			(xy 350.376619 -286.419866) (xy 350.350316 -286.37827) (xy 350.331025 -286.332994) (xy 350.319248 -286.28521)
			(xy 350.315288 -286.236156) (xy 349.99676 -286.236156) (xy 349.996248 -286.261602) (xy 349.988084 -286.311836)
			(xy 349.971968 -286.36011) (xy 349.948317 -286.405173) (xy 349.917744 -286.445859) (xy 349.88104 -286.481114)
			(xy 349.839156 -286.510024) (xy 349.793177 -286.531841) (xy 349.744293 -286.546001) (xy 349.693772 -286.552135)
			(xy 349.64292 -286.550086) (xy 349.593056 -286.539906) (xy 349.54547 -286.521859) (xy 349.501396 -286.496413)
			(xy 349.461974 -286.464226) (xy 349.428226 -286.426132) (xy 349.401025 -286.383118) (xy 349.381077 -286.336298)
			(xy 349.368898 -286.286884) (xy 349.364803 -286.236156) (xy 349.05696 -286.236156) (xy 349.056448 -286.261602)
			(xy 349.048284 -286.311836) (xy 349.032168 -286.36011) (xy 349.008517 -286.405173) (xy 348.977944 -286.445859)
			(xy 348.94124 -286.481114) (xy 348.899356 -286.510024) (xy 348.853377 -286.531841) (xy 348.804493 -286.546001)
			(xy 348.753972 -286.552135) (xy 348.70312 -286.550086) (xy 348.653256 -286.539906) (xy 348.60567 -286.521859)
			(xy 348.561596 -286.496413) (xy 348.522174 -286.464226) (xy 348.488426 -286.426132) (xy 348.461225 -286.383118)
			(xy 348.441277 -286.336298) (xy 348.429098 -286.286884) (xy 348.425003 -286.236156) (xy 348.106492 -286.236156)
			(xy 348.105997 -286.260763) (xy 348.098102 -286.30934) (xy 348.082518 -286.356021) (xy 348.059647 -286.399598)
			(xy 348.030082 -286.438942) (xy 347.994589 -286.473034) (xy 347.954086 -286.50099) (xy 347.909624 -286.522088)
			(xy 347.862353 -286.53578) (xy 347.813498 -286.541712) (xy 347.764323 -286.539731) (xy 347.716104 -286.529887)
			(xy 347.670088 -286.512435) (xy 347.627467 -286.487828) (xy 347.589346 -286.456703) (xy 347.556711 -286.419866)
			(xy 347.530408 -286.37827) (xy 347.511117 -286.332994) (xy 347.49934 -286.28521) (xy 347.49538 -286.236156)
			(xy 347.176852 -286.236156) (xy 347.17634 -286.261602) (xy 347.168176 -286.311836) (xy 347.15206 -286.36011)
			(xy 347.128409 -286.405173) (xy 347.097836 -286.445859) (xy 347.061132 -286.481114) (xy 347.019248 -286.510024)
			(xy 346.973269 -286.531841) (xy 346.924385 -286.546001) (xy 346.873864 -286.552135) (xy 346.823012 -286.550086)
			(xy 346.773148 -286.539906) (xy 346.725562 -286.521859) (xy 346.681488 -286.496413) (xy 346.642066 -286.464226)
			(xy 346.608318 -286.426132) (xy 346.581117 -286.383118) (xy 346.561169 -286.336298) (xy 346.54899 -286.286884)
			(xy 346.544895 -286.236156) (xy 346.236798 -286.236156) (xy 346.236286 -286.261602) (xy 346.228122 -286.311836)
			(xy 346.212006 -286.36011) (xy 346.188355 -286.405173) (xy 346.157782 -286.445859) (xy 346.121078 -286.481114)
			(xy 346.079194 -286.510024) (xy 346.033215 -286.531841) (xy 345.984331 -286.546001) (xy 345.93381 -286.552135)
			(xy 345.882958 -286.550086) (xy 345.833094 -286.539906) (xy 345.785508 -286.521859) (xy 345.741434 -286.496413)
			(xy 345.702012 -286.464226) (xy 345.668264 -286.426132) (xy 345.641063 -286.383118) (xy 345.621115 -286.336298)
			(xy 345.608936 -286.286884) (xy 345.604841 -286.236156) (xy 345.28633 -286.236156) (xy 345.285835 -286.260763)
			(xy 345.27794 -286.30934) (xy 345.262356 -286.356021) (xy 345.239485 -286.399598) (xy 345.20992 -286.438942)
			(xy 345.174427 -286.473034) (xy 345.133924 -286.50099) (xy 345.089462 -286.522088) (xy 345.042191 -286.53578)
			(xy 344.993336 -286.541712) (xy 344.944161 -286.539731) (xy 344.895942 -286.529887) (xy 344.849926 -286.512435)
			(xy 344.807305 -286.487828) (xy 344.769184 -286.456703) (xy 344.736549 -286.419866) (xy 344.710246 -286.37827)
			(xy 344.690955 -286.332994) (xy 344.679178 -286.28521) (xy 344.675218 -286.236156) (xy 344.356944 -286.236156)
			(xy 344.356432 -286.261602) (xy 344.348268 -286.311836) (xy 344.332152 -286.36011) (xy 344.308501 -286.405173)
			(xy 344.277928 -286.445859) (xy 344.241224 -286.481114) (xy 344.19934 -286.510024) (xy 344.153361 -286.531841)
			(xy 344.104477 -286.546001) (xy 344.053956 -286.552135) (xy 344.003104 -286.550086) (xy 343.95324 -286.539906)
			(xy 343.905654 -286.521859) (xy 343.86158 -286.496413) (xy 343.822158 -286.464226) (xy 343.78841 -286.426132)
			(xy 343.761209 -286.383118) (xy 343.741261 -286.336298) (xy 343.729082 -286.286884) (xy 343.724987 -286.236156)
			(xy 343.406476 -286.236156) (xy 343.405981 -286.260763) (xy 343.398086 -286.30934) (xy 343.382502 -286.356021)
			(xy 343.359631 -286.399598) (xy 343.330066 -286.438942) (xy 343.294573 -286.473034) (xy 343.25407 -286.50099)
			(xy 343.209608 -286.522088) (xy 343.162337 -286.53578) (xy 343.113482 -286.541712) (xy 343.064307 -286.539731)
			(xy 343.016088 -286.529887) (xy 342.970072 -286.512435) (xy 342.927451 -286.487828) (xy 342.88933 -286.456703)
			(xy 342.856695 -286.419866) (xy 342.830392 -286.37827) (xy 342.811101 -286.332994) (xy 342.799324 -286.28521)
			(xy 342.795364 -286.236156) (xy 342.476836 -286.236156) (xy 342.476324 -286.261602) (xy 342.46816 -286.311836)
			(xy 342.452044 -286.36011) (xy 342.428393 -286.405173) (xy 342.39782 -286.445859) (xy 342.361116 -286.481114)
			(xy 342.319232 -286.510024) (xy 342.273253 -286.531841) (xy 342.224369 -286.546001) (xy 342.173848 -286.552135)
			(xy 342.122996 -286.550086) (xy 342.073132 -286.539906) (xy 342.025546 -286.521859) (xy 341.981472 -286.496413)
			(xy 341.94205 -286.464226) (xy 341.908302 -286.426132) (xy 341.881101 -286.383118) (xy 341.861153 -286.336298)
			(xy 341.848974 -286.286884) (xy 341.844879 -286.236156) (xy 341.526368 -286.236156) (xy 341.525873 -286.260763)
			(xy 341.517978 -286.30934) (xy 341.502394 -286.356021) (xy 341.479523 -286.399598) (xy 341.449958 -286.438942)
			(xy 341.414465 -286.473034) (xy 341.373962 -286.50099) (xy 341.3295 -286.522088) (xy 341.282229 -286.53578)
			(xy 341.233374 -286.541712) (xy 341.184199 -286.539731) (xy 341.13598 -286.529887) (xy 341.089964 -286.512435)
			(xy 341.047343 -286.487828) (xy 341.009222 -286.456703) (xy 340.976587 -286.419866) (xy 340.950284 -286.37827)
			(xy 340.930993 -286.332994) (xy 340.919216 -286.28521) (xy 340.915256 -286.236156) (xy 340.596728 -286.236156)
			(xy 340.596216 -286.261602) (xy 340.588052 -286.311836) (xy 340.571936 -286.36011) (xy 340.548285 -286.405173)
			(xy 340.517712 -286.445859) (xy 340.481008 -286.481114) (xy 340.439124 -286.510024) (xy 340.393145 -286.531841)
			(xy 340.344261 -286.546001) (xy 340.29374 -286.552135) (xy 340.242888 -286.550086) (xy 340.193024 -286.539906)
			(xy 340.145438 -286.521859) (xy 340.101364 -286.496413) (xy 340.061942 -286.464226) (xy 340.028194 -286.426132)
			(xy 340.000993 -286.383118) (xy 339.981045 -286.336298) (xy 339.968866 -286.286884) (xy 339.964771 -286.236156)
			(xy 339.656928 -286.236156) (xy 339.656416 -286.261602) (xy 339.648252 -286.311836) (xy 339.632136 -286.36011)
			(xy 339.608485 -286.405173) (xy 339.577912 -286.445859) (xy 339.541208 -286.481114) (xy 339.499324 -286.510024)
			(xy 339.453345 -286.531841) (xy 339.404461 -286.546001) (xy 339.35394 -286.552135) (xy 339.303088 -286.550086)
			(xy 339.253224 -286.539906) (xy 339.205638 -286.521859) (xy 339.161564 -286.496413) (xy 339.122142 -286.464226)
			(xy 339.088394 -286.426132) (xy 339.061193 -286.383118) (xy 339.041245 -286.336298) (xy 339.029066 -286.286884)
			(xy 339.024971 -286.236156) (xy 338.70646 -286.236156) (xy 338.705965 -286.260763) (xy 338.69807 -286.30934)
			(xy 338.682486 -286.356021) (xy 338.659615 -286.399598) (xy 338.63005 -286.438942) (xy 338.594557 -286.473034)
			(xy 338.554054 -286.50099) (xy 338.509592 -286.522088) (xy 338.462321 -286.53578) (xy 338.413466 -286.541712)
			(xy 338.364291 -286.539731) (xy 338.316072 -286.529887) (xy 338.270056 -286.512435) (xy 338.227435 -286.487828)
			(xy 338.189314 -286.456703) (xy 338.156679 -286.419866) (xy 338.130376 -286.37827) (xy 338.111085 -286.332994)
			(xy 338.099308 -286.28521) (xy 338.095348 -286.236156) (xy 337.77682 -286.236156) (xy 337.776308 -286.261602)
			(xy 337.768144 -286.311836) (xy 337.752028 -286.36011) (xy 337.728377 -286.405173) (xy 337.697804 -286.445859)
			(xy 337.6611 -286.481114) (xy 337.619216 -286.510024) (xy 337.573237 -286.531841) (xy 337.524353 -286.546001)
			(xy 337.473832 -286.552135) (xy 337.42298 -286.550086) (xy 337.373116 -286.539906) (xy 337.32553 -286.521859)
			(xy 337.281456 -286.496413) (xy 337.242034 -286.464226) (xy 337.208286 -286.426132) (xy 337.181085 -286.383118)
			(xy 337.161137 -286.336298) (xy 337.148958 -286.286884) (xy 337.144863 -286.236156) (xy 336.826352 -286.236156)
			(xy 336.825857 -286.260763) (xy 336.817962 -286.30934) (xy 336.802378 -286.356021) (xy 336.779507 -286.399598)
			(xy 336.749942 -286.438942) (xy 336.714449 -286.473034) (xy 336.673946 -286.50099) (xy 336.629484 -286.522088)
			(xy 336.582213 -286.53578) (xy 336.533358 -286.541712) (xy 336.484183 -286.539731) (xy 336.435964 -286.529887)
			(xy 336.389948 -286.512435) (xy 336.347327 -286.487828) (xy 336.309206 -286.456703) (xy 336.276571 -286.419866)
			(xy 336.250268 -286.37827) (xy 336.230977 -286.332994) (xy 336.2192 -286.28521) (xy 336.21524 -286.236156)
			(xy 335.896712 -286.236156) (xy 335.8962 -286.261602) (xy 335.888036 -286.311836) (xy 335.87192 -286.36011)
			(xy 335.848269 -286.405173) (xy 335.817696 -286.445859) (xy 335.780992 -286.481114) (xy 335.739108 -286.510024)
			(xy 335.693129 -286.531841) (xy 335.644245 -286.546001) (xy 335.593724 -286.552135) (xy 335.542872 -286.550086)
			(xy 335.493008 -286.539906) (xy 335.445422 -286.521859) (xy 335.401348 -286.496413) (xy 335.361926 -286.464226)
			(xy 335.328178 -286.426132) (xy 335.300977 -286.383118) (xy 335.281029 -286.336298) (xy 335.26885 -286.286884)
			(xy 335.264755 -286.236156) (xy 334.946498 -286.236156) (xy 334.946003 -286.260763) (xy 334.938108 -286.30934)
			(xy 334.922524 -286.356021) (xy 334.899653 -286.399598) (xy 334.870088 -286.438942) (xy 334.834595 -286.473034)
			(xy 334.794092 -286.50099) (xy 334.74963 -286.522088) (xy 334.702359 -286.53578) (xy 334.653504 -286.541712)
			(xy 334.604329 -286.539731) (xy 334.55611 -286.529887) (xy 334.510094 -286.512435) (xy 334.467473 -286.487828)
			(xy 334.429352 -286.456703) (xy 334.396717 -286.419866) (xy 334.370414 -286.37827) (xy 334.351123 -286.332994)
			(xy 334.339346 -286.28521) (xy 334.335386 -286.236156) (xy 334.016858 -286.236156) (xy 334.016346 -286.261602)
			(xy 334.008182 -286.311836) (xy 333.992066 -286.36011) (xy 333.968415 -286.405173) (xy 333.937842 -286.445859)
			(xy 333.901138 -286.481114) (xy 333.859254 -286.510024) (xy 333.813275 -286.531841) (xy 333.764391 -286.546001)
			(xy 333.71387 -286.552135) (xy 333.663018 -286.550086) (xy 333.613154 -286.539906) (xy 333.565568 -286.521859)
			(xy 333.521494 -286.496413) (xy 333.482072 -286.464226) (xy 333.448324 -286.426132) (xy 333.421123 -286.383118)
			(xy 333.401175 -286.336298) (xy 333.388996 -286.286884) (xy 333.384901 -286.236156) (xy 333.076804 -286.236156)
			(xy 333.076292 -286.261602) (xy 333.068128 -286.311836) (xy 333.052012 -286.36011) (xy 333.028361 -286.405173)
			(xy 332.997788 -286.445859) (xy 332.961084 -286.481114) (xy 332.9192 -286.510024) (xy 332.873221 -286.531841)
			(xy 332.824337 -286.546001) (xy 332.773816 -286.552135) (xy 332.722964 -286.550086) (xy 332.6731 -286.539906)
			(xy 332.625514 -286.521859) (xy 332.58144 -286.496413) (xy 332.542018 -286.464226) (xy 332.50827 -286.426132)
			(xy 332.481069 -286.383118) (xy 332.461121 -286.336298) (xy 332.448942 -286.286884) (xy 332.444847 -286.236156)
			(xy 332.126336 -286.236156) (xy 332.125841 -286.260763) (xy 332.117946 -286.30934) (xy 332.102362 -286.356021)
			(xy 332.079491 -286.399598) (xy 332.049926 -286.438942) (xy 332.014433 -286.473034) (xy 331.97393 -286.50099)
			(xy 331.929468 -286.522088) (xy 331.882197 -286.53578) (xy 331.833342 -286.541712) (xy 331.784167 -286.539731)
			(xy 331.735948 -286.529887) (xy 331.689932 -286.512435) (xy 331.647311 -286.487828) (xy 331.60919 -286.456703)
			(xy 331.576555 -286.419866) (xy 331.550252 -286.37827) (xy 331.530961 -286.332994) (xy 331.519184 -286.28521)
			(xy 331.515224 -286.236156) (xy 331.196696 -286.236156) (xy 331.196184 -286.261602) (xy 331.18802 -286.311836)
			(xy 331.171904 -286.36011) (xy 331.148253 -286.405173) (xy 331.11768 -286.445859) (xy 331.080976 -286.481114)
			(xy 331.039092 -286.510024) (xy 330.993113 -286.531841) (xy 330.944229 -286.546001) (xy 330.893708 -286.552135)
			(xy 330.842856 -286.550086) (xy 330.792992 -286.539906) (xy 330.745406 -286.521859) (xy 330.701332 -286.496413)
			(xy 330.66191 -286.464226) (xy 330.628162 -286.426132) (xy 330.600961 -286.383118) (xy 330.581013 -286.336298)
			(xy 330.568834 -286.286884) (xy 330.564739 -286.236156) (xy 330.246482 -286.236156) (xy 330.245987 -286.260763)
			(xy 330.238092 -286.30934) (xy 330.222508 -286.356021) (xy 330.199637 -286.399598) (xy 330.170072 -286.438942)
			(xy 330.134579 -286.473034) (xy 330.094076 -286.50099) (xy 330.049614 -286.522088) (xy 330.002343 -286.53578)
			(xy 329.953488 -286.541712) (xy 329.904313 -286.539731) (xy 329.856094 -286.529887) (xy 329.810078 -286.512435)
			(xy 329.767457 -286.487828) (xy 329.729336 -286.456703) (xy 329.696701 -286.419866) (xy 329.670398 -286.37827)
			(xy 329.651107 -286.332994) (xy 329.63933 -286.28521) (xy 329.63537 -286.236156) (xy 329.316842 -286.236156)
			(xy 329.31633 -286.261602) (xy 329.308166 -286.311836) (xy 329.29205 -286.36011) (xy 329.268399 -286.405173)
			(xy 329.237826 -286.445859) (xy 329.201122 -286.481114) (xy 329.159238 -286.510024) (xy 329.113259 -286.531841)
			(xy 329.064375 -286.546001) (xy 329.013854 -286.552135) (xy 328.963002 -286.550086) (xy 328.913138 -286.539906)
			(xy 328.865552 -286.521859) (xy 328.821478 -286.496413) (xy 328.782056 -286.464226) (xy 328.748308 -286.426132)
			(xy 328.721107 -286.383118) (xy 328.701159 -286.336298) (xy 328.68898 -286.286884) (xy 328.684885 -286.236156)
			(xy 328.366374 -286.236156) (xy 328.365879 -286.260763) (xy 328.357984 -286.30934) (xy 328.3424 -286.356021)
			(xy 328.319529 -286.399598) (xy 328.289964 -286.438942) (xy 328.254471 -286.473034) (xy 328.213968 -286.50099)
			(xy 328.169506 -286.522088) (xy 328.122235 -286.53578) (xy 328.07338 -286.541712) (xy 328.024205 -286.539731)
			(xy 327.975986 -286.529887) (xy 327.92997 -286.512435) (xy 327.887349 -286.487828) (xy 327.849228 -286.456703)
			(xy 327.816593 -286.419866) (xy 327.79029 -286.37827) (xy 327.770999 -286.332994) (xy 327.759222 -286.28521)
			(xy 327.755262 -286.236156) (xy 325.203519 -286.236156) (xy 325.161384 -286.25615) (xy 325.114113 -286.269842)
			(xy 325.065258 -286.275774) (xy 325.016083 -286.273793) (xy 324.967864 -286.263949) (xy 324.921848 -286.246497)
			(xy 324.879227 -286.22189) (xy 324.841106 -286.190765) (xy 324.808471 -286.153928) (xy 324.782168 -286.112332)
			(xy 324.762877 -286.067056) (xy 324.7511 -286.019272) (xy 324.74714 -285.970218) (xy 310.45912 -285.970218)
			(xy 310.45912 -287.045908) (xy 326.345308 -287.045908) (xy 326.349268 -286.996854) (xy 326.361045 -286.94907)
			(xy 326.380336 -286.903794) (xy 326.406639 -286.862198) (xy 326.439274 -286.825361) (xy 326.477395 -286.794236)
			(xy 326.520016 -286.769629) (xy 326.566032 -286.752177) (xy 326.614251 -286.742333) (xy 326.663426 -286.740352)
			(xy 326.712281 -286.746284) (xy 326.759552 -286.759976) (xy 326.804014 -286.781074) (xy 326.844517 -286.80903)
			(xy 326.88001 -286.843122) (xy 326.909575 -286.882466) (xy 326.932446 -286.926043) (xy 326.94803 -286.972724)
			(xy 326.955925 -287.021301) (xy 326.95642 -287.045908) (xy 328.225416 -287.045908) (xy 328.229376 -286.996854)
			(xy 328.241153 -286.94907) (xy 328.260444 -286.903794) (xy 328.286747 -286.862198) (xy 328.319382 -286.825361)
			(xy 328.357503 -286.794236) (xy 328.400124 -286.769629) (xy 328.44614 -286.752177) (xy 328.494359 -286.742333)
			(xy 328.543534 -286.740352) (xy 328.592389 -286.746284) (xy 328.63966 -286.759976) (xy 328.684122 -286.781074)
			(xy 328.724625 -286.80903) (xy 328.760118 -286.843122) (xy 328.789683 -286.882466) (xy 328.812554 -286.926043)
			(xy 328.828138 -286.972724) (xy 328.836033 -287.021301) (xy 328.836528 -287.045908) (xy 329.154785 -287.045908)
			(xy 329.15888 -286.99518) (xy 329.171059 -286.945766) (xy 329.191007 -286.898946) (xy 329.218208 -286.855932)
			(xy 329.251956 -286.817838) (xy 329.291378 -286.785651) (xy 329.335452 -286.760205) (xy 329.383038 -286.742158)
			(xy 329.432902 -286.731978) (xy 329.483754 -286.729929) (xy 329.534275 -286.736063) (xy 329.583159 -286.750223)
			(xy 329.629138 -286.77204) (xy 329.671022 -286.80095) (xy 329.707726 -286.836205) (xy 329.738299 -286.876891)
			(xy 329.76195 -286.921954) (xy 329.778066 -286.970228) (xy 329.78623 -287.020462) (xy 329.786742 -287.045908)
			(xy 330.094839 -287.045908) (xy 330.098934 -286.99518) (xy 330.111113 -286.945766) (xy 330.131061 -286.898946)
			(xy 330.158262 -286.855932) (xy 330.19201 -286.817838) (xy 330.231432 -286.785651) (xy 330.275506 -286.760205)
			(xy 330.323092 -286.742158) (xy 330.372956 -286.731978) (xy 330.423808 -286.729929) (xy 330.474329 -286.736063)
			(xy 330.523213 -286.750223) (xy 330.569192 -286.77204) (xy 330.611076 -286.80095) (xy 330.64778 -286.836205)
			(xy 330.678353 -286.876891) (xy 330.702004 -286.921954) (xy 330.71812 -286.970228) (xy 330.726284 -287.020462)
			(xy 330.726796 -287.045908) (xy 331.045324 -287.045908) (xy 331.049284 -286.996854) (xy 331.061061 -286.94907)
			(xy 331.080352 -286.903794) (xy 331.106655 -286.862198) (xy 331.13929 -286.825361) (xy 331.177411 -286.794236)
			(xy 331.220032 -286.769629) (xy 331.266048 -286.752177) (xy 331.314267 -286.742333) (xy 331.363442 -286.740352)
			(xy 331.412297 -286.746284) (xy 331.459568 -286.759976) (xy 331.50403 -286.781074) (xy 331.544533 -286.80903)
			(xy 331.580026 -286.843122) (xy 331.609591 -286.882466) (xy 331.632462 -286.926043) (xy 331.648046 -286.972724)
			(xy 331.655941 -287.021301) (xy 331.656436 -287.045908) (xy 331.974947 -287.045908) (xy 331.979042 -286.99518)
			(xy 331.991221 -286.945766) (xy 332.011169 -286.898946) (xy 332.03837 -286.855932) (xy 332.072118 -286.817838)
			(xy 332.11154 -286.785651) (xy 332.155614 -286.760205) (xy 332.2032 -286.742158) (xy 332.253064 -286.731978)
			(xy 332.303916 -286.729929) (xy 332.354437 -286.736063) (xy 332.403321 -286.750223) (xy 332.4493 -286.77204)
			(xy 332.491184 -286.80095) (xy 332.527888 -286.836205) (xy 332.558461 -286.876891) (xy 332.582112 -286.921954)
			(xy 332.598228 -286.970228) (xy 332.606392 -287.020462) (xy 332.606904 -287.045908) (xy 332.606899 -287.046162)
			(xy 332.925178 -287.046162) (xy 332.929138 -286.997108) (xy 332.940915 -286.949324) (xy 332.960206 -286.904048)
			(xy 332.986509 -286.862452) (xy 333.019144 -286.825615) (xy 333.057265 -286.79449) (xy 333.099886 -286.769883)
			(xy 333.145902 -286.752431) (xy 333.194121 -286.742587) (xy 333.243296 -286.740606) (xy 333.292151 -286.746538)
			(xy 333.339422 -286.76023) (xy 333.383884 -286.781328) (xy 333.424387 -286.809284) (xy 333.45988 -286.843376)
			(xy 333.489445 -286.88272) (xy 333.512316 -286.926297) (xy 333.5279 -286.972978) (xy 333.535795 -287.021555)
			(xy 333.536285 -287.045908) (xy 333.854801 -287.045908) (xy 333.858896 -286.99518) (xy 333.871075 -286.945766)
			(xy 333.891023 -286.898946) (xy 333.918224 -286.855932) (xy 333.951972 -286.817838) (xy 333.991394 -286.785651)
			(xy 334.035468 -286.760205) (xy 334.083054 -286.742158) (xy 334.132918 -286.731978) (xy 334.18377 -286.729929)
			(xy 334.234291 -286.736063) (xy 334.283175 -286.750223) (xy 334.329154 -286.77204) (xy 334.371038 -286.80095)
			(xy 334.407742 -286.836205) (xy 334.438315 -286.876891) (xy 334.461966 -286.921954) (xy 334.478082 -286.970228)
			(xy 334.486246 -287.020462) (xy 334.486758 -287.045908) (xy 334.805286 -287.045908) (xy 334.809246 -286.996854)
			(xy 334.821023 -286.94907) (xy 334.840314 -286.903794) (xy 334.866617 -286.862198) (xy 334.899252 -286.825361)
			(xy 334.937373 -286.794236) (xy 334.979994 -286.769629) (xy 335.02601 -286.752177) (xy 335.074229 -286.742333)
			(xy 335.123404 -286.740352) (xy 335.172259 -286.746284) (xy 335.21953 -286.759976) (xy 335.263992 -286.781074)
			(xy 335.304495 -286.80903) (xy 335.339988 -286.843122) (xy 335.369553 -286.882466) (xy 335.392424 -286.926043)
			(xy 335.408008 -286.972724) (xy 335.415903 -287.021301) (xy 335.416398 -287.045908) (xy 335.734909 -287.045908)
			(xy 335.739004 -286.99518) (xy 335.751183 -286.945766) (xy 335.771131 -286.898946) (xy 335.798332 -286.855932)
			(xy 335.83208 -286.817838) (xy 335.871502 -286.785651) (xy 335.915576 -286.760205) (xy 335.963162 -286.742158)
			(xy 336.013026 -286.731978) (xy 336.063878 -286.729929) (xy 336.114399 -286.736063) (xy 336.163283 -286.750223)
			(xy 336.209262 -286.77204) (xy 336.251146 -286.80095) (xy 336.28785 -286.836205) (xy 336.318423 -286.876891)
			(xy 336.342074 -286.921954) (xy 336.35819 -286.970228) (xy 336.366354 -287.020462) (xy 336.366866 -287.045908)
			(xy 336.674963 -287.045908) (xy 336.679058 -286.99518) (xy 336.691237 -286.945766) (xy 336.711185 -286.898946)
			(xy 336.738386 -286.855932) (xy 336.772134 -286.817838) (xy 336.811556 -286.785651) (xy 336.85563 -286.760205)
			(xy 336.903216 -286.742158) (xy 336.95308 -286.731978) (xy 337.003932 -286.729929) (xy 337.054453 -286.736063)
			(xy 337.103337 -286.750223) (xy 337.149316 -286.77204) (xy 337.1912 -286.80095) (xy 337.227904 -286.836205)
			(xy 337.258477 -286.876891) (xy 337.282128 -286.921954) (xy 337.298244 -286.970228) (xy 337.306408 -287.020462)
			(xy 337.30692 -287.045908) (xy 337.625702 -287.045908) (xy 337.629662 -286.996854) (xy 337.641439 -286.94907)
			(xy 337.66073 -286.903794) (xy 337.687033 -286.862198) (xy 337.719668 -286.825361) (xy 337.757789 -286.794236)
			(xy 337.80041 -286.769629) (xy 337.846426 -286.752177) (xy 337.894645 -286.742333) (xy 337.94382 -286.740352)
			(xy 337.992675 -286.746284) (xy 338.039946 -286.759976) (xy 338.084408 -286.781074) (xy 338.124911 -286.80903)
			(xy 338.160404 -286.843122) (xy 338.189969 -286.882466) (xy 338.21284 -286.926043) (xy 338.228424 -286.972724)
			(xy 338.236319 -287.021301) (xy 338.236814 -287.045908) (xy 338.554817 -287.045908) (xy 338.558912 -286.99518)
			(xy 338.571091 -286.945766) (xy 338.591039 -286.898946) (xy 338.61824 -286.855932) (xy 338.651988 -286.817838)
			(xy 338.69141 -286.785651) (xy 338.735484 -286.760205) (xy 338.78307 -286.742158) (xy 338.832934 -286.731978)
			(xy 338.883786 -286.729929) (xy 338.934307 -286.736063) (xy 338.983191 -286.750223) (xy 339.02917 -286.77204)
			(xy 339.071054 -286.80095) (xy 339.107758 -286.836205) (xy 339.138331 -286.876891) (xy 339.161982 -286.921954)
			(xy 339.178098 -286.970228) (xy 339.186262 -287.020462) (xy 339.186774 -287.045908) (xy 339.505302 -287.045908)
			(xy 339.509262 -286.996854) (xy 339.521039 -286.94907) (xy 339.54033 -286.903794) (xy 339.566633 -286.862198)
			(xy 339.599268 -286.825361) (xy 339.637389 -286.794236) (xy 339.68001 -286.769629) (xy 339.726026 -286.752177)
			(xy 339.774245 -286.742333) (xy 339.82342 -286.740352) (xy 339.872275 -286.746284) (xy 339.919546 -286.759976)
			(xy 339.964008 -286.781074) (xy 340.004511 -286.80903) (xy 340.040004 -286.843122) (xy 340.069569 -286.882466)
			(xy 340.09244 -286.926043) (xy 340.108024 -286.972724) (xy 340.115919 -287.021301) (xy 340.116414 -287.045908)
			(xy 340.434925 -287.045908) (xy 340.43902 -286.99518) (xy 340.451199 -286.945766) (xy 340.471147 -286.898946)
			(xy 340.498348 -286.855932) (xy 340.532096 -286.817838) (xy 340.571518 -286.785651) (xy 340.615592 -286.760205)
			(xy 340.663178 -286.742158) (xy 340.713042 -286.731978) (xy 340.763894 -286.729929) (xy 340.814415 -286.736063)
			(xy 340.863299 -286.750223) (xy 340.909278 -286.77204) (xy 340.951162 -286.80095) (xy 340.987866 -286.836205)
			(xy 341.018439 -286.876891) (xy 341.04209 -286.921954) (xy 341.058206 -286.970228) (xy 341.06637 -287.020462)
			(xy 341.066882 -287.045908) (xy 341.38541 -287.045908) (xy 341.38937 -286.996854) (xy 341.401147 -286.94907)
			(xy 341.420438 -286.903794) (xy 341.446741 -286.862198) (xy 341.479376 -286.825361) (xy 341.517497 -286.794236)
			(xy 341.560118 -286.769629) (xy 341.606134 -286.752177) (xy 341.654353 -286.742333) (xy 341.703528 -286.740352)
			(xy 341.752383 -286.746284) (xy 341.799654 -286.759976) (xy 341.844116 -286.781074) (xy 341.884619 -286.80903)
			(xy 341.920112 -286.843122) (xy 341.949677 -286.882466) (xy 341.972548 -286.926043) (xy 341.988132 -286.972724)
			(xy 341.996027 -287.021301) (xy 341.996522 -287.045908) (xy 342.314779 -287.045908) (xy 342.318874 -286.99518)
			(xy 342.331053 -286.945766) (xy 342.351001 -286.898946) (xy 342.378202 -286.855932) (xy 342.41195 -286.817838)
			(xy 342.451372 -286.785651) (xy 342.495446 -286.760205) (xy 342.543032 -286.742158) (xy 342.592896 -286.731978)
			(xy 342.643748 -286.729929) (xy 342.694269 -286.736063) (xy 342.743153 -286.750223) (xy 342.789132 -286.77204)
			(xy 342.831016 -286.80095) (xy 342.86772 -286.836205) (xy 342.898293 -286.876891) (xy 342.921944 -286.921954)
			(xy 342.93806 -286.970228) (xy 342.946224 -287.020462) (xy 342.946736 -287.045908) (xy 343.254833 -287.045908)
			(xy 343.258928 -286.99518) (xy 343.271107 -286.945766) (xy 343.291055 -286.898946) (xy 343.318256 -286.855932)
			(xy 343.352004 -286.817838) (xy 343.391426 -286.785651) (xy 343.4355 -286.760205) (xy 343.483086 -286.742158)
			(xy 343.53295 -286.731978) (xy 343.583802 -286.729929) (xy 343.634323 -286.736063) (xy 343.683207 -286.750223)
			(xy 343.729186 -286.77204) (xy 343.77107 -286.80095) (xy 343.807774 -286.836205) (xy 343.838347 -286.876891)
			(xy 343.861998 -286.921954) (xy 343.878114 -286.970228) (xy 343.886278 -287.020462) (xy 343.88679 -287.045908)
			(xy 344.205318 -287.045908) (xy 344.209278 -286.996854) (xy 344.221055 -286.94907) (xy 344.240346 -286.903794)
			(xy 344.266649 -286.862198) (xy 344.299284 -286.825361) (xy 344.337405 -286.794236) (xy 344.380026 -286.769629)
			(xy 344.426042 -286.752177) (xy 344.474261 -286.742333) (xy 344.523436 -286.740352) (xy 344.572291 -286.746284)
			(xy 344.619562 -286.759976) (xy 344.664024 -286.781074) (xy 344.704527 -286.80903) (xy 344.74002 -286.843122)
			(xy 344.769585 -286.882466) (xy 344.792456 -286.926043) (xy 344.80804 -286.972724) (xy 344.815935 -287.021301)
			(xy 344.81643 -287.045908) (xy 345.145372 -287.045908) (xy 345.149332 -286.996854) (xy 345.161109 -286.94907)
			(xy 345.1804 -286.903794) (xy 345.206703 -286.862198) (xy 345.239338 -286.825361) (xy 345.277459 -286.794236)
			(xy 345.32008 -286.769629) (xy 345.366096 -286.752177) (xy 345.414315 -286.742333) (xy 345.46349 -286.740352)
			(xy 345.512345 -286.746284) (xy 345.559616 -286.759976) (xy 345.604078 -286.781074) (xy 345.644581 -286.80903)
			(xy 345.680074 -286.843122) (xy 345.709639 -286.882466) (xy 345.73251 -286.926043) (xy 345.748094 -286.972724)
			(xy 345.755989 -287.021301) (xy 345.756484 -287.045908) (xy 346.085426 -287.045908) (xy 346.089386 -286.996854)
			(xy 346.101163 -286.94907) (xy 346.120454 -286.903794) (xy 346.146757 -286.862198) (xy 346.179392 -286.825361)
			(xy 346.217513 -286.794236) (xy 346.260134 -286.769629) (xy 346.30615 -286.752177) (xy 346.354369 -286.742333)
			(xy 346.403544 -286.740352) (xy 346.452399 -286.746284) (xy 346.49967 -286.759976) (xy 346.544132 -286.781074)
			(xy 346.584635 -286.80903) (xy 346.620128 -286.843122) (xy 346.649693 -286.882466) (xy 346.672564 -286.926043)
			(xy 346.688148 -286.972724) (xy 346.696043 -287.021301) (xy 346.696538 -287.045908) (xy 346.696533 -287.046162)
			(xy 347.025226 -287.046162) (xy 347.029186 -286.997108) (xy 347.040963 -286.949324) (xy 347.060254 -286.904048)
			(xy 347.086557 -286.862452) (xy 347.119192 -286.825615) (xy 347.157313 -286.79449) (xy 347.199934 -286.769883)
			(xy 347.24595 -286.752431) (xy 347.294169 -286.742587) (xy 347.343344 -286.740606) (xy 347.392199 -286.746538)
			(xy 347.43947 -286.76023) (xy 347.483932 -286.781328) (xy 347.524435 -286.809284) (xy 347.559928 -286.843376)
			(xy 347.589493 -286.88272) (xy 347.612364 -286.926297) (xy 347.627948 -286.972978) (xy 347.635843 -287.021555)
			(xy 347.636333 -287.045908) (xy 347.96528 -287.045908) (xy 347.96924 -286.996854) (xy 347.981017 -286.94907)
			(xy 348.000308 -286.903794) (xy 348.026611 -286.862198) (xy 348.059246 -286.825361) (xy 348.097367 -286.794236)
			(xy 348.139988 -286.769629) (xy 348.186004 -286.752177) (xy 348.234223 -286.742333) (xy 348.283398 -286.740352)
			(xy 348.332253 -286.746284) (xy 348.379524 -286.759976) (xy 348.423986 -286.781074) (xy 348.464489 -286.80903)
			(xy 348.499982 -286.843122) (xy 348.529547 -286.882466) (xy 348.552418 -286.926043) (xy 348.568002 -286.972724)
			(xy 348.575897 -287.021301) (xy 348.576392 -287.045908) (xy 348.905334 -287.045908) (xy 348.909294 -286.996854)
			(xy 348.921071 -286.94907) (xy 348.940362 -286.903794) (xy 348.966665 -286.862198) (xy 348.9993 -286.825361)
			(xy 349.037421 -286.794236) (xy 349.080042 -286.769629) (xy 349.126058 -286.752177) (xy 349.174277 -286.742333)
			(xy 349.223452 -286.740352) (xy 349.272307 -286.746284) (xy 349.319578 -286.759976) (xy 349.36404 -286.781074)
			(xy 349.404543 -286.80903) (xy 349.440036 -286.843122) (xy 349.469601 -286.882466) (xy 349.492472 -286.926043)
			(xy 349.508056 -286.972724) (xy 349.515951 -287.021301) (xy 349.516446 -287.045908) (xy 349.845388 -287.045908)
			(xy 349.849348 -286.996854) (xy 349.861125 -286.94907) (xy 349.880416 -286.903794) (xy 349.906719 -286.862198)
			(xy 349.939354 -286.825361) (xy 349.977475 -286.794236) (xy 350.020096 -286.769629) (xy 350.066112 -286.752177)
			(xy 350.114331 -286.742333) (xy 350.163506 -286.740352) (xy 350.212361 -286.746284) (xy 350.259632 -286.759976)
			(xy 350.304094 -286.781074) (xy 350.344597 -286.80903) (xy 350.38009 -286.843122) (xy 350.409655 -286.882466)
			(xy 350.432526 -286.926043) (xy 350.44811 -286.972724) (xy 350.456005 -287.021301) (xy 350.4565 -287.045908)
			(xy 350.785442 -287.045908) (xy 350.789402 -286.996854) (xy 350.801179 -286.94907) (xy 350.82047 -286.903794)
			(xy 350.846773 -286.862198) (xy 350.879408 -286.825361) (xy 350.917529 -286.794236) (xy 350.96015 -286.769629)
			(xy 351.006166 -286.752177) (xy 351.054385 -286.742333) (xy 351.10356 -286.740352) (xy 351.152415 -286.746284)
			(xy 351.199686 -286.759976) (xy 351.244148 -286.781074) (xy 351.284651 -286.80903) (xy 351.320144 -286.843122)
			(xy 351.349709 -286.882466) (xy 351.37258 -286.926043) (xy 351.388164 -286.972724) (xy 351.396059 -287.021301)
			(xy 351.396554 -287.045908) (xy 351.396059 -287.070515) (xy 351.388164 -287.119092) (xy 351.37258 -287.165773)
			(xy 351.349709 -287.20935) (xy 351.320144 -287.248694) (xy 351.284651 -287.282786) (xy 351.244148 -287.310742)
			(xy 351.199686 -287.33184) (xy 351.152415 -287.345532) (xy 351.10356 -287.351464) (xy 351.054385 -287.349483)
			(xy 351.006166 -287.339639) (xy 350.96015 -287.322187) (xy 350.917529 -287.29758) (xy 350.879408 -287.266455)
			(xy 350.846773 -287.229618) (xy 350.82047 -287.188022) (xy 350.801179 -287.142746) (xy 350.789402 -287.094962)
			(xy 350.785442 -287.045908) (xy 350.4565 -287.045908) (xy 350.456005 -287.070515) (xy 350.44811 -287.119092)
			(xy 350.432526 -287.165773) (xy 350.409655 -287.20935) (xy 350.38009 -287.248694) (xy 350.344597 -287.282786)
			(xy 350.304094 -287.310742) (xy 350.259632 -287.33184) (xy 350.212361 -287.345532) (xy 350.163506 -287.351464)
			(xy 350.114331 -287.349483) (xy 350.066112 -287.339639) (xy 350.020096 -287.322187) (xy 349.977475 -287.29758)
			(xy 349.939354 -287.266455) (xy 349.906719 -287.229618) (xy 349.880416 -287.188022) (xy 349.861125 -287.142746)
			(xy 349.849348 -287.094962) (xy 349.845388 -287.045908) (xy 349.516446 -287.045908) (xy 349.515951 -287.070515)
			(xy 349.508056 -287.119092) (xy 349.492472 -287.165773) (xy 349.469601 -287.20935) (xy 349.440036 -287.248694)
			(xy 349.404543 -287.282786) (xy 349.36404 -287.310742) (xy 349.319578 -287.33184) (xy 349.272307 -287.345532)
			(xy 349.223452 -287.351464) (xy 349.174277 -287.349483) (xy 349.126058 -287.339639) (xy 349.080042 -287.322187)
			(xy 349.037421 -287.29758) (xy 348.9993 -287.266455) (xy 348.966665 -287.229618) (xy 348.940362 -287.188022)
			(xy 348.921071 -287.142746) (xy 348.909294 -287.094962) (xy 348.905334 -287.045908) (xy 348.576392 -287.045908)
			(xy 348.575897 -287.070515) (xy 348.568002 -287.119092) (xy 348.552418 -287.165773) (xy 348.529547 -287.20935)
			(xy 348.499982 -287.248694) (xy 348.464489 -287.282786) (xy 348.423986 -287.310742) (xy 348.379524 -287.33184)
			(xy 348.332253 -287.345532) (xy 348.283398 -287.351464) (xy 348.234223 -287.349483) (xy 348.186004 -287.339639)
			(xy 348.139988 -287.322187) (xy 348.097367 -287.29758) (xy 348.059246 -287.266455) (xy 348.026611 -287.229618)
			(xy 348.000308 -287.188022) (xy 347.981017 -287.142746) (xy 347.96924 -287.094962) (xy 347.96528 -287.045908)
			(xy 347.636333 -287.045908) (xy 347.636338 -287.046162) (xy 347.635843 -287.070769) (xy 347.627948 -287.119346)
			(xy 347.612364 -287.166027) (xy 347.589493 -287.209604) (xy 347.559928 -287.248948) (xy 347.524435 -287.28304)
			(xy 347.483932 -287.310996) (xy 347.43947 -287.332094) (xy 347.392199 -287.345786) (xy 347.343344 -287.351718)
			(xy 347.294169 -287.349737) (xy 347.24595 -287.339893) (xy 347.199934 -287.322441) (xy 347.157313 -287.297834)
			(xy 347.119192 -287.266709) (xy 347.086557 -287.229872) (xy 347.060254 -287.188276) (xy 347.040963 -287.143)
			(xy 347.029186 -287.095216) (xy 347.025226 -287.046162) (xy 346.696533 -287.046162) (xy 346.696043 -287.070515)
			(xy 346.688148 -287.119092) (xy 346.672564 -287.165773) (xy 346.649693 -287.20935) (xy 346.620128 -287.248694)
			(xy 346.584635 -287.282786) (xy 346.544132 -287.310742) (xy 346.49967 -287.33184) (xy 346.452399 -287.345532)
			(xy 346.403544 -287.351464) (xy 346.354369 -287.349483) (xy 346.30615 -287.339639) (xy 346.260134 -287.322187)
			(xy 346.217513 -287.29758) (xy 346.179392 -287.266455) (xy 346.146757 -287.229618) (xy 346.120454 -287.188022)
			(xy 346.101163 -287.142746) (xy 346.089386 -287.094962) (xy 346.085426 -287.045908) (xy 345.756484 -287.045908)
			(xy 345.755989 -287.070515) (xy 345.748094 -287.119092) (xy 345.73251 -287.165773) (xy 345.709639 -287.20935)
			(xy 345.680074 -287.248694) (xy 345.644581 -287.282786) (xy 345.604078 -287.310742) (xy 345.559616 -287.33184)
			(xy 345.512345 -287.345532) (xy 345.46349 -287.351464) (xy 345.414315 -287.349483) (xy 345.366096 -287.339639)
			(xy 345.32008 -287.322187) (xy 345.277459 -287.29758) (xy 345.239338 -287.266455) (xy 345.206703 -287.229618)
			(xy 345.1804 -287.188022) (xy 345.161109 -287.142746) (xy 345.149332 -287.094962) (xy 345.145372 -287.045908)
			(xy 344.81643 -287.045908) (xy 344.815935 -287.070515) (xy 344.80804 -287.119092) (xy 344.792456 -287.165773)
			(xy 344.769585 -287.20935) (xy 344.74002 -287.248694) (xy 344.704527 -287.282786) (xy 344.664024 -287.310742)
			(xy 344.619562 -287.33184) (xy 344.572291 -287.345532) (xy 344.523436 -287.351464) (xy 344.474261 -287.349483)
			(xy 344.426042 -287.339639) (xy 344.380026 -287.322187) (xy 344.337405 -287.29758) (xy 344.299284 -287.266455)
			(xy 344.266649 -287.229618) (xy 344.240346 -287.188022) (xy 344.221055 -287.142746) (xy 344.209278 -287.094962)
			(xy 344.205318 -287.045908) (xy 343.88679 -287.045908) (xy 343.886278 -287.071354) (xy 343.878114 -287.121588)
			(xy 343.861998 -287.169862) (xy 343.838347 -287.214925) (xy 343.807774 -287.255611) (xy 343.77107 -287.290866)
			(xy 343.729186 -287.319776) (xy 343.683207 -287.341593) (xy 343.634323 -287.355753) (xy 343.583802 -287.361887)
			(xy 343.53295 -287.359838) (xy 343.483086 -287.349658) (xy 343.4355 -287.331611) (xy 343.391426 -287.306165)
			(xy 343.352004 -287.273978) (xy 343.318256 -287.235884) (xy 343.291055 -287.19287) (xy 343.271107 -287.14605)
			(xy 343.258928 -287.096636) (xy 343.254833 -287.045908) (xy 342.946736 -287.045908) (xy 342.946224 -287.071354)
			(xy 342.93806 -287.121588) (xy 342.921944 -287.169862) (xy 342.898293 -287.214925) (xy 342.86772 -287.255611)
			(xy 342.831016 -287.290866) (xy 342.789132 -287.319776) (xy 342.743153 -287.341593) (xy 342.694269 -287.355753)
			(xy 342.643748 -287.361887) (xy 342.592896 -287.359838) (xy 342.543032 -287.349658) (xy 342.495446 -287.331611)
			(xy 342.451372 -287.306165) (xy 342.41195 -287.273978) (xy 342.378202 -287.235884) (xy 342.351001 -287.19287)
			(xy 342.331053 -287.14605) (xy 342.318874 -287.096636) (xy 342.314779 -287.045908) (xy 341.996522 -287.045908)
			(xy 341.996027 -287.070515) (xy 341.988132 -287.119092) (xy 341.972548 -287.165773) (xy 341.949677 -287.20935)
			(xy 341.920112 -287.248694) (xy 341.884619 -287.282786) (xy 341.844116 -287.310742) (xy 341.799654 -287.33184)
			(xy 341.752383 -287.345532) (xy 341.703528 -287.351464) (xy 341.654353 -287.349483) (xy 341.606134 -287.339639)
			(xy 341.560118 -287.322187) (xy 341.517497 -287.29758) (xy 341.479376 -287.266455) (xy 341.446741 -287.229618)
			(xy 341.420438 -287.188022) (xy 341.401147 -287.142746) (xy 341.38937 -287.094962) (xy 341.38541 -287.045908)
			(xy 341.066882 -287.045908) (xy 341.06637 -287.071354) (xy 341.058206 -287.121588) (xy 341.04209 -287.169862)
			(xy 341.018439 -287.214925) (xy 340.987866 -287.255611) (xy 340.951162 -287.290866) (xy 340.909278 -287.319776)
			(xy 340.863299 -287.341593) (xy 340.814415 -287.355753) (xy 340.763894 -287.361887) (xy 340.713042 -287.359838)
			(xy 340.663178 -287.349658) (xy 340.615592 -287.331611) (xy 340.571518 -287.306165) (xy 340.532096 -287.273978)
			(xy 340.498348 -287.235884) (xy 340.471147 -287.19287) (xy 340.451199 -287.14605) (xy 340.43902 -287.096636)
			(xy 340.434925 -287.045908) (xy 340.116414 -287.045908) (xy 340.115919 -287.070515) (xy 340.108024 -287.119092)
			(xy 340.09244 -287.165773) (xy 340.069569 -287.20935) (xy 340.040004 -287.248694) (xy 340.004511 -287.282786)
			(xy 339.964008 -287.310742) (xy 339.919546 -287.33184) (xy 339.872275 -287.345532) (xy 339.82342 -287.351464)
			(xy 339.774245 -287.349483) (xy 339.726026 -287.339639) (xy 339.68001 -287.322187) (xy 339.637389 -287.29758)
			(xy 339.599268 -287.266455) (xy 339.566633 -287.229618) (xy 339.54033 -287.188022) (xy 339.521039 -287.142746)
			(xy 339.509262 -287.094962) (xy 339.505302 -287.045908) (xy 339.186774 -287.045908) (xy 339.186262 -287.071354)
			(xy 339.178098 -287.121588) (xy 339.161982 -287.169862) (xy 339.138331 -287.214925) (xy 339.107758 -287.255611)
			(xy 339.071054 -287.290866) (xy 339.02917 -287.319776) (xy 338.983191 -287.341593) (xy 338.934307 -287.355753)
			(xy 338.883786 -287.361887) (xy 338.832934 -287.359838) (xy 338.78307 -287.349658) (xy 338.735484 -287.331611)
			(xy 338.69141 -287.306165) (xy 338.651988 -287.273978) (xy 338.61824 -287.235884) (xy 338.591039 -287.19287)
			(xy 338.571091 -287.14605) (xy 338.558912 -287.096636) (xy 338.554817 -287.045908) (xy 338.236814 -287.045908)
			(xy 338.236319 -287.070515) (xy 338.228424 -287.119092) (xy 338.21284 -287.165773) (xy 338.189969 -287.20935)
			(xy 338.160404 -287.248694) (xy 338.124911 -287.282786) (xy 338.084408 -287.310742) (xy 338.039946 -287.33184)
			(xy 337.992675 -287.345532) (xy 337.94382 -287.351464) (xy 337.894645 -287.349483) (xy 337.846426 -287.339639)
			(xy 337.80041 -287.322187) (xy 337.757789 -287.29758) (xy 337.719668 -287.266455) (xy 337.687033 -287.229618)
			(xy 337.66073 -287.188022) (xy 337.641439 -287.142746) (xy 337.629662 -287.094962) (xy 337.625702 -287.045908)
			(xy 337.30692 -287.045908) (xy 337.306408 -287.071354) (xy 337.298244 -287.121588) (xy 337.282128 -287.169862)
			(xy 337.258477 -287.214925) (xy 337.227904 -287.255611) (xy 337.1912 -287.290866) (xy 337.149316 -287.319776)
			(xy 337.103337 -287.341593) (xy 337.054453 -287.355753) (xy 337.003932 -287.361887) (xy 336.95308 -287.359838)
			(xy 336.903216 -287.349658) (xy 336.85563 -287.331611) (xy 336.811556 -287.306165) (xy 336.772134 -287.273978)
			(xy 336.738386 -287.235884) (xy 336.711185 -287.19287) (xy 336.691237 -287.14605) (xy 336.679058 -287.096636)
			(xy 336.674963 -287.045908) (xy 336.366866 -287.045908) (xy 336.366354 -287.071354) (xy 336.35819 -287.121588)
			(xy 336.342074 -287.169862) (xy 336.318423 -287.214925) (xy 336.28785 -287.255611) (xy 336.251146 -287.290866)
			(xy 336.209262 -287.319776) (xy 336.163283 -287.341593) (xy 336.114399 -287.355753) (xy 336.063878 -287.361887)
			(xy 336.013026 -287.359838) (xy 335.963162 -287.349658) (xy 335.915576 -287.331611) (xy 335.871502 -287.306165)
			(xy 335.83208 -287.273978) (xy 335.798332 -287.235884) (xy 335.771131 -287.19287) (xy 335.751183 -287.14605)
			(xy 335.739004 -287.096636) (xy 335.734909 -287.045908) (xy 335.416398 -287.045908) (xy 335.415903 -287.070515)
			(xy 335.408008 -287.119092) (xy 335.392424 -287.165773) (xy 335.369553 -287.20935) (xy 335.339988 -287.248694)
			(xy 335.304495 -287.282786) (xy 335.263992 -287.310742) (xy 335.21953 -287.33184) (xy 335.172259 -287.345532)
			(xy 335.123404 -287.351464) (xy 335.074229 -287.349483) (xy 335.02601 -287.339639) (xy 334.979994 -287.322187)
			(xy 334.937373 -287.29758) (xy 334.899252 -287.266455) (xy 334.866617 -287.229618) (xy 334.840314 -287.188022)
			(xy 334.821023 -287.142746) (xy 334.809246 -287.094962) (xy 334.805286 -287.045908) (xy 334.486758 -287.045908)
			(xy 334.486246 -287.071354) (xy 334.478082 -287.121588) (xy 334.461966 -287.169862) (xy 334.438315 -287.214925)
			(xy 334.407742 -287.255611) (xy 334.371038 -287.290866) (xy 334.329154 -287.319776) (xy 334.283175 -287.341593)
			(xy 334.234291 -287.355753) (xy 334.18377 -287.361887) (xy 334.132918 -287.359838) (xy 334.083054 -287.349658)
			(xy 334.035468 -287.331611) (xy 333.991394 -287.306165) (xy 333.951972 -287.273978) (xy 333.918224 -287.235884)
			(xy 333.891023 -287.19287) (xy 333.871075 -287.14605) (xy 333.858896 -287.096636) (xy 333.854801 -287.045908)
			(xy 333.536285 -287.045908) (xy 333.53629 -287.046162) (xy 333.535795 -287.070769) (xy 333.5279 -287.119346)
			(xy 333.512316 -287.166027) (xy 333.489445 -287.209604) (xy 333.45988 -287.248948) (xy 333.424387 -287.28304)
			(xy 333.383884 -287.310996) (xy 333.339422 -287.332094) (xy 333.292151 -287.345786) (xy 333.243296 -287.351718)
			(xy 333.194121 -287.349737) (xy 333.145902 -287.339893) (xy 333.099886 -287.322441) (xy 333.057265 -287.297834)
			(xy 333.019144 -287.266709) (xy 332.986509 -287.229872) (xy 332.960206 -287.188276) (xy 332.940915 -287.143)
			(xy 332.929138 -287.095216) (xy 332.925178 -287.046162) (xy 332.606899 -287.046162) (xy 332.606392 -287.071354)
			(xy 332.598228 -287.121588) (xy 332.582112 -287.169862) (xy 332.558461 -287.214925) (xy 332.527888 -287.255611)
			(xy 332.491184 -287.290866) (xy 332.4493 -287.319776) (xy 332.403321 -287.341593) (xy 332.354437 -287.355753)
			(xy 332.303916 -287.361887) (xy 332.253064 -287.359838) (xy 332.2032 -287.349658) (xy 332.155614 -287.331611)
			(xy 332.11154 -287.306165) (xy 332.072118 -287.273978) (xy 332.03837 -287.235884) (xy 332.011169 -287.19287)
			(xy 331.991221 -287.14605) (xy 331.979042 -287.096636) (xy 331.974947 -287.045908) (xy 331.656436 -287.045908)
			(xy 331.655941 -287.070515) (xy 331.648046 -287.119092) (xy 331.632462 -287.165773) (xy 331.609591 -287.20935)
			(xy 331.580026 -287.248694) (xy 331.544533 -287.282786) (xy 331.50403 -287.310742) (xy 331.459568 -287.33184)
			(xy 331.412297 -287.345532) (xy 331.363442 -287.351464) (xy 331.314267 -287.349483) (xy 331.266048 -287.339639)
			(xy 331.220032 -287.322187) (xy 331.177411 -287.29758) (xy 331.13929 -287.266455) (xy 331.106655 -287.229618)
			(xy 331.080352 -287.188022) (xy 331.061061 -287.142746) (xy 331.049284 -287.094962) (xy 331.045324 -287.045908)
			(xy 330.726796 -287.045908) (xy 330.726284 -287.071354) (xy 330.71812 -287.121588) (xy 330.702004 -287.169862)
			(xy 330.678353 -287.214925) (xy 330.64778 -287.255611) (xy 330.611076 -287.290866) (xy 330.569192 -287.319776)
			(xy 330.523213 -287.341593) (xy 330.474329 -287.355753) (xy 330.423808 -287.361887) (xy 330.372956 -287.359838)
			(xy 330.323092 -287.349658) (xy 330.275506 -287.331611) (xy 330.231432 -287.306165) (xy 330.19201 -287.273978)
			(xy 330.158262 -287.235884) (xy 330.131061 -287.19287) (xy 330.111113 -287.14605) (xy 330.098934 -287.096636)
			(xy 330.094839 -287.045908) (xy 329.786742 -287.045908) (xy 329.78623 -287.071354) (xy 329.778066 -287.121588)
			(xy 329.76195 -287.169862) (xy 329.738299 -287.214925) (xy 329.707726 -287.255611) (xy 329.671022 -287.290866)
			(xy 329.629138 -287.319776) (xy 329.583159 -287.341593) (xy 329.534275 -287.355753) (xy 329.483754 -287.361887)
			(xy 329.432902 -287.359838) (xy 329.383038 -287.349658) (xy 329.335452 -287.331611) (xy 329.291378 -287.306165)
			(xy 329.251956 -287.273978) (xy 329.218208 -287.235884) (xy 329.191007 -287.19287) (xy 329.171059 -287.14605)
			(xy 329.15888 -287.096636) (xy 329.154785 -287.045908) (xy 328.836528 -287.045908) (xy 328.836033 -287.070515)
			(xy 328.828138 -287.119092) (xy 328.812554 -287.165773) (xy 328.789683 -287.20935) (xy 328.760118 -287.248694)
			(xy 328.724625 -287.282786) (xy 328.684122 -287.310742) (xy 328.63966 -287.33184) (xy 328.592389 -287.345532)
			(xy 328.543534 -287.351464) (xy 328.494359 -287.349483) (xy 328.44614 -287.339639) (xy 328.400124 -287.322187)
			(xy 328.357503 -287.29758) (xy 328.319382 -287.266455) (xy 328.286747 -287.229618) (xy 328.260444 -287.188022)
			(xy 328.241153 -287.142746) (xy 328.229376 -287.094962) (xy 328.225416 -287.045908) (xy 326.95642 -287.045908)
			(xy 326.955925 -287.070515) (xy 326.94803 -287.119092) (xy 326.932446 -287.165773) (xy 326.909575 -287.20935)
			(xy 326.88001 -287.248694) (xy 326.844517 -287.282786) (xy 326.804014 -287.310742) (xy 326.759552 -287.33184)
			(xy 326.712281 -287.345532) (xy 326.663426 -287.351464) (xy 326.614251 -287.349483) (xy 326.566032 -287.339639)
			(xy 326.520016 -287.322187) (xy 326.477395 -287.29758) (xy 326.439274 -287.266455) (xy 326.406639 -287.229618)
			(xy 326.380336 -287.188022) (xy 326.361045 -287.142746) (xy 326.349268 -287.094962) (xy 326.345308 -287.045908)
			(xy 310.45912 -287.045908) (xy 310.45912 -287.59023) (xy 324.74714 -287.59023) (xy 324.7511 -287.541176)
			(xy 324.762877 -287.493392) (xy 324.782168 -287.448116) (xy 324.808471 -287.40652) (xy 324.841106 -287.369683)
			(xy 324.879227 -287.338558) (xy 324.921848 -287.313951) (xy 324.967864 -287.296499) (xy 325.016083 -287.286655)
			(xy 325.065258 -287.284674) (xy 325.114113 -287.290606) (xy 325.161384 -287.304298) (xy 325.205846 -287.325396)
			(xy 325.246349 -287.353352) (xy 325.281842 -287.387444) (xy 325.311407 -287.426788) (xy 325.334278 -287.470365)
			(xy 325.349862 -287.517046) (xy 325.357757 -287.565623) (xy 325.358252 -287.59023) (xy 325.357757 -287.614837)
			(xy 325.349862 -287.663414) (xy 325.334278 -287.710095) (xy 325.311407 -287.753672) (xy 325.281842 -287.793016)
			(xy 325.246349 -287.827108) (xy 325.205846 -287.855064) (xy 325.203519 -287.856168) (xy 328.684885 -287.856168)
			(xy 328.68898 -287.80544) (xy 328.701159 -287.756026) (xy 328.721107 -287.709206) (xy 328.748308 -287.666192)
			(xy 328.782056 -287.628098) (xy 328.821478 -287.595911) (xy 328.865552 -287.570465) (xy 328.913138 -287.552418)
			(xy 328.963002 -287.542238) (xy 329.013854 -287.540189) (xy 329.064375 -287.546323) (xy 329.113259 -287.560483)
			(xy 329.159238 -287.5823) (xy 329.201122 -287.61121) (xy 329.237826 -287.646465) (xy 329.268399 -287.687151)
			(xy 329.29205 -287.732214) (xy 329.308166 -287.780488) (xy 329.31633 -287.830722) (xy 329.316842 -287.856168)
			(xy 329.63537 -287.856168) (xy 329.63933 -287.807114) (xy 329.651107 -287.75933) (xy 329.670398 -287.714054)
			(xy 329.696701 -287.672458) (xy 329.729336 -287.635621) (xy 329.767457 -287.604496) (xy 329.810078 -287.579889)
			(xy 329.856094 -287.562437) (xy 329.904313 -287.552593) (xy 329.953488 -287.550612) (xy 330.002343 -287.556544)
			(xy 330.049614 -287.570236) (xy 330.094076 -287.591334) (xy 330.134579 -287.61929) (xy 330.170072 -287.653382)
			(xy 330.199637 -287.692726) (xy 330.222508 -287.736303) (xy 330.238092 -287.782984) (xy 330.245987 -287.831561)
			(xy 330.246482 -287.856168) (xy 330.564739 -287.856168) (xy 330.568834 -287.80544) (xy 330.581013 -287.756026)
			(xy 330.600961 -287.709206) (xy 330.628162 -287.666192) (xy 330.66191 -287.628098) (xy 330.701332 -287.595911)
			(xy 330.745406 -287.570465) (xy 330.792992 -287.552418) (xy 330.842856 -287.542238) (xy 330.893708 -287.540189)
			(xy 330.944229 -287.546323) (xy 330.993113 -287.560483) (xy 331.039092 -287.5823) (xy 331.080976 -287.61121)
			(xy 331.11768 -287.646465) (xy 331.148253 -287.687151) (xy 331.171904 -287.732214) (xy 331.18802 -287.780488)
			(xy 331.196184 -287.830722) (xy 331.196696 -287.856168) (xy 331.515224 -287.856168) (xy 331.519184 -287.807114)
			(xy 331.530961 -287.75933) (xy 331.550252 -287.714054) (xy 331.576555 -287.672458) (xy 331.60919 -287.635621)
			(xy 331.647311 -287.604496) (xy 331.689932 -287.579889) (xy 331.735948 -287.562437) (xy 331.784167 -287.552593)
			(xy 331.833342 -287.550612) (xy 331.882197 -287.556544) (xy 331.929468 -287.570236) (xy 331.97393 -287.591334)
			(xy 332.014433 -287.61929) (xy 332.049926 -287.653382) (xy 332.079491 -287.692726) (xy 332.102362 -287.736303)
			(xy 332.117946 -287.782984) (xy 332.125841 -287.831561) (xy 332.126336 -287.856168) (xy 332.444847 -287.856168)
			(xy 332.448942 -287.80544) (xy 332.461121 -287.756026) (xy 332.481069 -287.709206) (xy 332.50827 -287.666192)
			(xy 332.542018 -287.628098) (xy 332.58144 -287.595911) (xy 332.625514 -287.570465) (xy 332.6731 -287.552418)
			(xy 332.722964 -287.542238) (xy 332.773816 -287.540189) (xy 332.824337 -287.546323) (xy 332.873221 -287.560483)
			(xy 332.9192 -287.5823) (xy 332.961084 -287.61121) (xy 332.997788 -287.646465) (xy 333.028361 -287.687151)
			(xy 333.052012 -287.732214) (xy 333.068128 -287.780488) (xy 333.076292 -287.830722) (xy 333.076804 -287.856168)
			(xy 333.384901 -287.856168) (xy 333.388996 -287.80544) (xy 333.401175 -287.756026) (xy 333.421123 -287.709206)
			(xy 333.448324 -287.666192) (xy 333.482072 -287.628098) (xy 333.521494 -287.595911) (xy 333.565568 -287.570465)
			(xy 333.613154 -287.552418) (xy 333.663018 -287.542238) (xy 333.71387 -287.540189) (xy 333.764391 -287.546323)
			(xy 333.813275 -287.560483) (xy 333.859254 -287.5823) (xy 333.901138 -287.61121) (xy 333.937842 -287.646465)
			(xy 333.968415 -287.687151) (xy 333.992066 -287.732214) (xy 334.008182 -287.780488) (xy 334.016346 -287.830722)
			(xy 334.016858 -287.856168) (xy 335.264755 -287.856168) (xy 335.26885 -287.80544) (xy 335.281029 -287.756026)
			(xy 335.300977 -287.709206) (xy 335.328178 -287.666192) (xy 335.361926 -287.628098) (xy 335.401348 -287.595911)
			(xy 335.445422 -287.570465) (xy 335.493008 -287.552418) (xy 335.542872 -287.542238) (xy 335.593724 -287.540189)
			(xy 335.644245 -287.546323) (xy 335.693129 -287.560483) (xy 335.739108 -287.5823) (xy 335.780992 -287.61121)
			(xy 335.817696 -287.646465) (xy 335.848269 -287.687151) (xy 335.87192 -287.732214) (xy 335.888036 -287.780488)
			(xy 335.8962 -287.830722) (xy 335.896712 -287.856168) (xy 336.21524 -287.856168) (xy 336.2192 -287.807114)
			(xy 336.230977 -287.75933) (xy 336.250268 -287.714054) (xy 336.276571 -287.672458) (xy 336.309206 -287.635621)
			(xy 336.347327 -287.604496) (xy 336.389948 -287.579889) (xy 336.435964 -287.562437) (xy 336.484183 -287.552593)
			(xy 336.533358 -287.550612) (xy 336.582213 -287.556544) (xy 336.629484 -287.570236) (xy 336.673946 -287.591334)
			(xy 336.714449 -287.61929) (xy 336.749942 -287.653382) (xy 336.779507 -287.692726) (xy 336.802378 -287.736303)
			(xy 336.817962 -287.782984) (xy 336.825857 -287.831561) (xy 336.826352 -287.856168) (xy 337.144863 -287.856168)
			(xy 337.148958 -287.80544) (xy 337.161137 -287.756026) (xy 337.181085 -287.709206) (xy 337.208286 -287.666192)
			(xy 337.242034 -287.628098) (xy 337.281456 -287.595911) (xy 337.32553 -287.570465) (xy 337.373116 -287.552418)
			(xy 337.42298 -287.542238) (xy 337.473832 -287.540189) (xy 337.524353 -287.546323) (xy 337.573237 -287.560483)
			(xy 337.619216 -287.5823) (xy 337.6611 -287.61121) (xy 337.697804 -287.646465) (xy 337.728377 -287.687151)
			(xy 337.752028 -287.732214) (xy 337.768144 -287.780488) (xy 337.776308 -287.830722) (xy 337.77682 -287.856168)
			(xy 338.095348 -287.856168) (xy 338.099308 -287.807114) (xy 338.111085 -287.75933) (xy 338.130376 -287.714054)
			(xy 338.156679 -287.672458) (xy 338.189314 -287.635621) (xy 338.227435 -287.604496) (xy 338.270056 -287.579889)
			(xy 338.316072 -287.562437) (xy 338.364291 -287.552593) (xy 338.413466 -287.550612) (xy 338.462321 -287.556544)
			(xy 338.509592 -287.570236) (xy 338.554054 -287.591334) (xy 338.594557 -287.61929) (xy 338.63005 -287.653382)
			(xy 338.659615 -287.692726) (xy 338.682486 -287.736303) (xy 338.69807 -287.782984) (xy 338.705965 -287.831561)
			(xy 338.70646 -287.856168) (xy 339.024971 -287.856168) (xy 339.029066 -287.80544) (xy 339.041245 -287.756026)
			(xy 339.061193 -287.709206) (xy 339.088394 -287.666192) (xy 339.122142 -287.628098) (xy 339.161564 -287.595911)
			(xy 339.205638 -287.570465) (xy 339.253224 -287.552418) (xy 339.303088 -287.542238) (xy 339.35394 -287.540189)
			(xy 339.404461 -287.546323) (xy 339.453345 -287.560483) (xy 339.499324 -287.5823) (xy 339.541208 -287.61121)
			(xy 339.577912 -287.646465) (xy 339.608485 -287.687151) (xy 339.632136 -287.732214) (xy 339.648252 -287.780488)
			(xy 339.656416 -287.830722) (xy 339.656928 -287.856168) (xy 339.964771 -287.856168) (xy 339.968866 -287.80544)
			(xy 339.981045 -287.756026) (xy 340.000993 -287.709206) (xy 340.028194 -287.666192) (xy 340.061942 -287.628098)
			(xy 340.101364 -287.595911) (xy 340.145438 -287.570465) (xy 340.193024 -287.552418) (xy 340.242888 -287.542238)
			(xy 340.29374 -287.540189) (xy 340.344261 -287.546323) (xy 340.393145 -287.560483) (xy 340.439124 -287.5823)
			(xy 340.481008 -287.61121) (xy 340.517712 -287.646465) (xy 340.548285 -287.687151) (xy 340.571936 -287.732214)
			(xy 340.588052 -287.780488) (xy 340.596216 -287.830722) (xy 340.596728 -287.856168) (xy 341.844879 -287.856168)
			(xy 341.848974 -287.80544) (xy 341.861153 -287.756026) (xy 341.881101 -287.709206) (xy 341.908302 -287.666192)
			(xy 341.94205 -287.628098) (xy 341.981472 -287.595911) (xy 342.025546 -287.570465) (xy 342.073132 -287.552418)
			(xy 342.122996 -287.542238) (xy 342.173848 -287.540189) (xy 342.224369 -287.546323) (xy 342.273253 -287.560483)
			(xy 342.319232 -287.5823) (xy 342.361116 -287.61121) (xy 342.39782 -287.646465) (xy 342.428393 -287.687151)
			(xy 342.452044 -287.732214) (xy 342.46816 -287.780488) (xy 342.476324 -287.830722) (xy 342.476836 -287.856168)
			(xy 342.795364 -287.856168) (xy 342.799324 -287.807114) (xy 342.811101 -287.75933) (xy 342.830392 -287.714054)
			(xy 342.856695 -287.672458) (xy 342.88933 -287.635621) (xy 342.927451 -287.604496) (xy 342.970072 -287.579889)
			(xy 343.016088 -287.562437) (xy 343.064307 -287.552593) (xy 343.113482 -287.550612) (xy 343.162337 -287.556544)
			(xy 343.209608 -287.570236) (xy 343.25407 -287.591334) (xy 343.294573 -287.61929) (xy 343.330066 -287.653382)
			(xy 343.359631 -287.692726) (xy 343.382502 -287.736303) (xy 343.398086 -287.782984) (xy 343.405981 -287.831561)
			(xy 343.406476 -287.856168) (xy 343.724987 -287.856168) (xy 343.729082 -287.80544) (xy 343.741261 -287.756026)
			(xy 343.761209 -287.709206) (xy 343.78841 -287.666192) (xy 343.822158 -287.628098) (xy 343.86158 -287.595911)
			(xy 343.905654 -287.570465) (xy 343.95324 -287.552418) (xy 344.003104 -287.542238) (xy 344.053956 -287.540189)
			(xy 344.104477 -287.546323) (xy 344.153361 -287.560483) (xy 344.19934 -287.5823) (xy 344.241224 -287.61121)
			(xy 344.277928 -287.646465) (xy 344.308501 -287.687151) (xy 344.332152 -287.732214) (xy 344.348268 -287.780488)
			(xy 344.356432 -287.830722) (xy 344.356944 -287.856168) (xy 344.675218 -287.856168) (xy 344.679178 -287.807114)
			(xy 344.690955 -287.75933) (xy 344.710246 -287.714054) (xy 344.736549 -287.672458) (xy 344.769184 -287.635621)
			(xy 344.807305 -287.604496) (xy 344.849926 -287.579889) (xy 344.895942 -287.562437) (xy 344.944161 -287.552593)
			(xy 344.993336 -287.550612) (xy 345.042191 -287.556544) (xy 345.089462 -287.570236) (xy 345.133924 -287.591334)
			(xy 345.174427 -287.61929) (xy 345.20992 -287.653382) (xy 345.239485 -287.692726) (xy 345.262356 -287.736303)
			(xy 345.27794 -287.782984) (xy 345.285835 -287.831561) (xy 345.28633 -287.856168) (xy 345.604841 -287.856168)
			(xy 345.608936 -287.80544) (xy 345.621115 -287.756026) (xy 345.641063 -287.709206) (xy 345.668264 -287.666192)
			(xy 345.702012 -287.628098) (xy 345.741434 -287.595911) (xy 345.785508 -287.570465) (xy 345.833094 -287.552418)
			(xy 345.882958 -287.542238) (xy 345.93381 -287.540189) (xy 345.984331 -287.546323) (xy 346.033215 -287.560483)
			(xy 346.079194 -287.5823) (xy 346.121078 -287.61121) (xy 346.157782 -287.646465) (xy 346.188355 -287.687151)
			(xy 346.212006 -287.732214) (xy 346.228122 -287.780488) (xy 346.236286 -287.830722) (xy 346.236798 -287.856168)
			(xy 346.544895 -287.856168) (xy 346.54899 -287.80544) (xy 346.561169 -287.756026) (xy 346.581117 -287.709206)
			(xy 346.608318 -287.666192) (xy 346.642066 -287.628098) (xy 346.681488 -287.595911) (xy 346.725562 -287.570465)
			(xy 346.773148 -287.552418) (xy 346.823012 -287.542238) (xy 346.873864 -287.540189) (xy 346.924385 -287.546323)
			(xy 346.973269 -287.560483) (xy 347.019248 -287.5823) (xy 347.061132 -287.61121) (xy 347.097836 -287.646465)
			(xy 347.128409 -287.687151) (xy 347.15206 -287.732214) (xy 347.168176 -287.780488) (xy 347.17634 -287.830722)
			(xy 347.176852 -287.856168) (xy 347.49538 -287.856168) (xy 347.49934 -287.807114) (xy 347.511117 -287.75933)
			(xy 347.530408 -287.714054) (xy 347.556711 -287.672458) (xy 347.589346 -287.635621) (xy 347.627467 -287.604496)
			(xy 347.670088 -287.579889) (xy 347.716104 -287.562437) (xy 347.764323 -287.552593) (xy 347.813498 -287.550612)
			(xy 347.862353 -287.556544) (xy 347.909624 -287.570236) (xy 347.954086 -287.591334) (xy 347.994589 -287.61929)
			(xy 348.030082 -287.653382) (xy 348.059647 -287.692726) (xy 348.082518 -287.736303) (xy 348.098102 -287.782984)
			(xy 348.105997 -287.831561) (xy 348.106492 -287.856168) (xy 348.425003 -287.856168) (xy 348.429098 -287.80544)
			(xy 348.441277 -287.756026) (xy 348.461225 -287.709206) (xy 348.488426 -287.666192) (xy 348.522174 -287.628098)
			(xy 348.561596 -287.595911) (xy 348.60567 -287.570465) (xy 348.653256 -287.552418) (xy 348.70312 -287.542238)
			(xy 348.753972 -287.540189) (xy 348.804493 -287.546323) (xy 348.853377 -287.560483) (xy 348.899356 -287.5823)
			(xy 348.94124 -287.61121) (xy 348.977944 -287.646465) (xy 349.008517 -287.687151) (xy 349.032168 -287.732214)
			(xy 349.048284 -287.780488) (xy 349.056448 -287.830722) (xy 349.05696 -287.856168) (xy 349.364803 -287.856168)
			(xy 349.368898 -287.80544) (xy 349.381077 -287.756026) (xy 349.401025 -287.709206) (xy 349.428226 -287.666192)
			(xy 349.461974 -287.628098) (xy 349.501396 -287.595911) (xy 349.54547 -287.570465) (xy 349.593056 -287.552418)
			(xy 349.64292 -287.542238) (xy 349.693772 -287.540189) (xy 349.744293 -287.546323) (xy 349.793177 -287.560483)
			(xy 349.839156 -287.5823) (xy 349.88104 -287.61121) (xy 349.917744 -287.646465) (xy 349.948317 -287.687151)
			(xy 349.971968 -287.732214) (xy 349.988084 -287.780488) (xy 349.996248 -287.830722) (xy 349.99676 -287.856168)
			(xy 350.315288 -287.856168) (xy 350.319248 -287.807114) (xy 350.331025 -287.75933) (xy 350.350316 -287.714054)
			(xy 350.376619 -287.672458) (xy 350.409254 -287.635621) (xy 350.447375 -287.604496) (xy 350.489996 -287.579889)
			(xy 350.536012 -287.562437) (xy 350.584231 -287.552593) (xy 350.633406 -287.550612) (xy 350.682261 -287.556544)
			(xy 350.729532 -287.570236) (xy 350.773994 -287.591334) (xy 350.814497 -287.61929) (xy 350.84999 -287.653382)
			(xy 350.879555 -287.692726) (xy 350.902426 -287.736303) (xy 350.91801 -287.782984) (xy 350.925905 -287.831561)
			(xy 350.9264 -287.856168) (xy 350.925905 -287.880775) (xy 350.91801 -287.929352) (xy 350.902426 -287.976033)
			(xy 350.879555 -288.01961) (xy 350.84999 -288.058954) (xy 350.814497 -288.093046) (xy 350.773994 -288.121002)
			(xy 350.729532 -288.1421) (xy 350.682261 -288.155792) (xy 350.633406 -288.161724) (xy 350.584231 -288.159743)
			(xy 350.536012 -288.149899) (xy 350.489996 -288.132447) (xy 350.447375 -288.10784) (xy 350.409254 -288.076715)
			(xy 350.376619 -288.039878) (xy 350.350316 -287.998282) (xy 350.331025 -287.953006) (xy 350.319248 -287.905222)
			(xy 350.315288 -287.856168) (xy 349.99676 -287.856168) (xy 349.996248 -287.881614) (xy 349.988084 -287.931848)
			(xy 349.971968 -287.980122) (xy 349.948317 -288.025185) (xy 349.917744 -288.065871) (xy 349.88104 -288.101126)
			(xy 349.839156 -288.130036) (xy 349.793177 -288.151853) (xy 349.744293 -288.166013) (xy 349.693772 -288.172147)
			(xy 349.64292 -288.170098) (xy 349.593056 -288.159918) (xy 349.54547 -288.141871) (xy 349.501396 -288.116425)
			(xy 349.461974 -288.084238) (xy 349.428226 -288.046144) (xy 349.401025 -288.00313) (xy 349.381077 -287.95631)
			(xy 349.368898 -287.906896) (xy 349.364803 -287.856168) (xy 349.05696 -287.856168) (xy 349.056448 -287.881614)
			(xy 349.048284 -287.931848) (xy 349.032168 -287.980122) (xy 349.008517 -288.025185) (xy 348.977944 -288.065871)
			(xy 348.94124 -288.101126) (xy 348.899356 -288.130036) (xy 348.853377 -288.151853) (xy 348.804493 -288.166013)
			(xy 348.753972 -288.172147) (xy 348.70312 -288.170098) (xy 348.653256 -288.159918) (xy 348.60567 -288.141871)
			(xy 348.561596 -288.116425) (xy 348.522174 -288.084238) (xy 348.488426 -288.046144) (xy 348.461225 -288.00313)
			(xy 348.441277 -287.95631) (xy 348.429098 -287.906896) (xy 348.425003 -287.856168) (xy 348.106492 -287.856168)
			(xy 348.105997 -287.880775) (xy 348.098102 -287.929352) (xy 348.082518 -287.976033) (xy 348.059647 -288.01961)
			(xy 348.030082 -288.058954) (xy 347.994589 -288.093046) (xy 347.954086 -288.121002) (xy 347.909624 -288.1421)
			(xy 347.862353 -288.155792) (xy 347.813498 -288.161724) (xy 347.764323 -288.159743) (xy 347.716104 -288.149899)
			(xy 347.670088 -288.132447) (xy 347.627467 -288.10784) (xy 347.589346 -288.076715) (xy 347.556711 -288.039878)
			(xy 347.530408 -287.998282) (xy 347.511117 -287.953006) (xy 347.49934 -287.905222) (xy 347.49538 -287.856168)
			(xy 347.176852 -287.856168) (xy 347.17634 -287.881614) (xy 347.168176 -287.931848) (xy 347.15206 -287.980122)
			(xy 347.128409 -288.025185) (xy 347.097836 -288.065871) (xy 347.061132 -288.101126) (xy 347.019248 -288.130036)
			(xy 346.973269 -288.151853) (xy 346.924385 -288.166013) (xy 346.873864 -288.172147) (xy 346.823012 -288.170098)
			(xy 346.773148 -288.159918) (xy 346.725562 -288.141871) (xy 346.681488 -288.116425) (xy 346.642066 -288.084238)
			(xy 346.608318 -288.046144) (xy 346.581117 -288.00313) (xy 346.561169 -287.95631) (xy 346.54899 -287.906896)
			(xy 346.544895 -287.856168) (xy 346.236798 -287.856168) (xy 346.236286 -287.881614) (xy 346.228122 -287.931848)
			(xy 346.212006 -287.980122) (xy 346.188355 -288.025185) (xy 346.157782 -288.065871) (xy 346.121078 -288.101126)
			(xy 346.079194 -288.130036) (xy 346.033215 -288.151853) (xy 345.984331 -288.166013) (xy 345.93381 -288.172147)
			(xy 345.882958 -288.170098) (xy 345.833094 -288.159918) (xy 345.785508 -288.141871) (xy 345.741434 -288.116425)
			(xy 345.702012 -288.084238) (xy 345.668264 -288.046144) (xy 345.641063 -288.00313) (xy 345.621115 -287.95631)
			(xy 345.608936 -287.906896) (xy 345.604841 -287.856168) (xy 345.28633 -287.856168) (xy 345.285835 -287.880775)
			(xy 345.27794 -287.929352) (xy 345.262356 -287.976033) (xy 345.239485 -288.01961) (xy 345.20992 -288.058954)
			(xy 345.174427 -288.093046) (xy 345.133924 -288.121002) (xy 345.089462 -288.1421) (xy 345.042191 -288.155792)
			(xy 344.993336 -288.161724) (xy 344.944161 -288.159743) (xy 344.895942 -288.149899) (xy 344.849926 -288.132447)
			(xy 344.807305 -288.10784) (xy 344.769184 -288.076715) (xy 344.736549 -288.039878) (xy 344.710246 -287.998282)
			(xy 344.690955 -287.953006) (xy 344.679178 -287.905222) (xy 344.675218 -287.856168) (xy 344.356944 -287.856168)
			(xy 344.356432 -287.881614) (xy 344.348268 -287.931848) (xy 344.332152 -287.980122) (xy 344.308501 -288.025185)
			(xy 344.277928 -288.065871) (xy 344.241224 -288.101126) (xy 344.19934 -288.130036) (xy 344.153361 -288.151853)
			(xy 344.104477 -288.166013) (xy 344.053956 -288.172147) (xy 344.003104 -288.170098) (xy 343.95324 -288.159918)
			(xy 343.905654 -288.141871) (xy 343.86158 -288.116425) (xy 343.822158 -288.084238) (xy 343.78841 -288.046144)
			(xy 343.761209 -288.00313) (xy 343.741261 -287.95631) (xy 343.729082 -287.906896) (xy 343.724987 -287.856168)
			(xy 343.406476 -287.856168) (xy 343.405981 -287.880775) (xy 343.398086 -287.929352) (xy 343.382502 -287.976033)
			(xy 343.359631 -288.01961) (xy 343.330066 -288.058954) (xy 343.294573 -288.093046) (xy 343.25407 -288.121002)
			(xy 343.209608 -288.1421) (xy 343.162337 -288.155792) (xy 343.113482 -288.161724) (xy 343.064307 -288.159743)
			(xy 343.016088 -288.149899) (xy 342.970072 -288.132447) (xy 342.927451 -288.10784) (xy 342.88933 -288.076715)
			(xy 342.856695 -288.039878) (xy 342.830392 -287.998282) (xy 342.811101 -287.953006) (xy 342.799324 -287.905222)
			(xy 342.795364 -287.856168) (xy 342.476836 -287.856168) (xy 342.476324 -287.881614) (xy 342.46816 -287.931848)
			(xy 342.452044 -287.980122) (xy 342.428393 -288.025185) (xy 342.39782 -288.065871) (xy 342.361116 -288.101126)
			(xy 342.319232 -288.130036) (xy 342.273253 -288.151853) (xy 342.224369 -288.166013) (xy 342.173848 -288.172147)
			(xy 342.122996 -288.170098) (xy 342.073132 -288.159918) (xy 342.025546 -288.141871) (xy 341.981472 -288.116425)
			(xy 341.94205 -288.084238) (xy 341.908302 -288.046144) (xy 341.881101 -288.00313) (xy 341.861153 -287.95631)
			(xy 341.848974 -287.906896) (xy 341.844879 -287.856168) (xy 340.596728 -287.856168) (xy 340.596216 -287.881614)
			(xy 340.588052 -287.931848) (xy 340.571936 -287.980122) (xy 340.548285 -288.025185) (xy 340.517712 -288.065871)
			(xy 340.481008 -288.101126) (xy 340.439124 -288.130036) (xy 340.393145 -288.151853) (xy 340.344261 -288.166013)
			(xy 340.29374 -288.172147) (xy 340.242888 -288.170098) (xy 340.193024 -288.159918) (xy 340.145438 -288.141871)
			(xy 340.101364 -288.116425) (xy 340.061942 -288.084238) (xy 340.028194 -288.046144) (xy 340.000993 -288.00313)
			(xy 339.981045 -287.95631) (xy 339.968866 -287.906896) (xy 339.964771 -287.856168) (xy 339.656928 -287.856168)
			(xy 339.656416 -287.881614) (xy 339.648252 -287.931848) (xy 339.632136 -287.980122) (xy 339.608485 -288.025185)
			(xy 339.577912 -288.065871) (xy 339.541208 -288.101126) (xy 339.499324 -288.130036) (xy 339.453345 -288.151853)
			(xy 339.404461 -288.166013) (xy 339.35394 -288.172147) (xy 339.303088 -288.170098) (xy 339.253224 -288.159918)
			(xy 339.205638 -288.141871) (xy 339.161564 -288.116425) (xy 339.122142 -288.084238) (xy 339.088394 -288.046144)
			(xy 339.061193 -288.00313) (xy 339.041245 -287.95631) (xy 339.029066 -287.906896) (xy 339.024971 -287.856168)
			(xy 338.70646 -287.856168) (xy 338.705965 -287.880775) (xy 338.69807 -287.929352) (xy 338.682486 -287.976033)
			(xy 338.659615 -288.01961) (xy 338.63005 -288.058954) (xy 338.594557 -288.093046) (xy 338.554054 -288.121002)
			(xy 338.509592 -288.1421) (xy 338.462321 -288.155792) (xy 338.413466 -288.161724) (xy 338.364291 -288.159743)
			(xy 338.316072 -288.149899) (xy 338.270056 -288.132447) (xy 338.227435 -288.10784) (xy 338.189314 -288.076715)
			(xy 338.156679 -288.039878) (xy 338.130376 -287.998282) (xy 338.111085 -287.953006) (xy 338.099308 -287.905222)
			(xy 338.095348 -287.856168) (xy 337.77682 -287.856168) (xy 337.776308 -287.881614) (xy 337.768144 -287.931848)
			(xy 337.752028 -287.980122) (xy 337.728377 -288.025185) (xy 337.697804 -288.065871) (xy 337.6611 -288.101126)
			(xy 337.619216 -288.130036) (xy 337.573237 -288.151853) (xy 337.524353 -288.166013) (xy 337.473832 -288.172147)
			(xy 337.42298 -288.170098) (xy 337.373116 -288.159918) (xy 337.32553 -288.141871) (xy 337.281456 -288.116425)
			(xy 337.242034 -288.084238) (xy 337.208286 -288.046144) (xy 337.181085 -288.00313) (xy 337.161137 -287.95631)
			(xy 337.148958 -287.906896) (xy 337.144863 -287.856168) (xy 336.826352 -287.856168) (xy 336.825857 -287.880775)
			(xy 336.817962 -287.929352) (xy 336.802378 -287.976033) (xy 336.779507 -288.01961) (xy 336.749942 -288.058954)
			(xy 336.714449 -288.093046) (xy 336.673946 -288.121002) (xy 336.629484 -288.1421) (xy 336.582213 -288.155792)
			(xy 336.533358 -288.161724) (xy 336.484183 -288.159743) (xy 336.435964 -288.149899) (xy 336.389948 -288.132447)
			(xy 336.347327 -288.10784) (xy 336.309206 -288.076715) (xy 336.276571 -288.039878) (xy 336.250268 -287.998282)
			(xy 336.230977 -287.953006) (xy 336.2192 -287.905222) (xy 336.21524 -287.856168) (xy 335.896712 -287.856168)
			(xy 335.8962 -287.881614) (xy 335.888036 -287.931848) (xy 335.87192 -287.980122) (xy 335.848269 -288.025185)
			(xy 335.817696 -288.065871) (xy 335.780992 -288.101126) (xy 335.739108 -288.130036) (xy 335.693129 -288.151853)
			(xy 335.644245 -288.166013) (xy 335.593724 -288.172147) (xy 335.542872 -288.170098) (xy 335.493008 -288.159918)
			(xy 335.445422 -288.141871) (xy 335.401348 -288.116425) (xy 335.361926 -288.084238) (xy 335.328178 -288.046144)
			(xy 335.300977 -288.00313) (xy 335.281029 -287.95631) (xy 335.26885 -287.906896) (xy 335.264755 -287.856168)
			(xy 334.016858 -287.856168) (xy 334.016346 -287.881614) (xy 334.008182 -287.931848) (xy 333.992066 -287.980122)
			(xy 333.968415 -288.025185) (xy 333.937842 -288.065871) (xy 333.901138 -288.101126) (xy 333.859254 -288.130036)
			(xy 333.813275 -288.151853) (xy 333.764391 -288.166013) (xy 333.71387 -288.172147) (xy 333.663018 -288.170098)
			(xy 333.613154 -288.159918) (xy 333.565568 -288.141871) (xy 333.521494 -288.116425) (xy 333.482072 -288.084238)
			(xy 333.448324 -288.046144) (xy 333.421123 -288.00313) (xy 333.401175 -287.95631) (xy 333.388996 -287.906896)
			(xy 333.384901 -287.856168) (xy 333.076804 -287.856168) (xy 333.076292 -287.881614) (xy 333.068128 -287.931848)
			(xy 333.052012 -287.980122) (xy 333.028361 -288.025185) (xy 332.997788 -288.065871) (xy 332.961084 -288.101126)
			(xy 332.9192 -288.130036) (xy 332.873221 -288.151853) (xy 332.824337 -288.166013) (xy 332.773816 -288.172147)
			(xy 332.722964 -288.170098) (xy 332.6731 -288.159918) (xy 332.625514 -288.141871) (xy 332.58144 -288.116425)
			(xy 332.542018 -288.084238) (xy 332.50827 -288.046144) (xy 332.481069 -288.00313) (xy 332.461121 -287.95631)
			(xy 332.448942 -287.906896) (xy 332.444847 -287.856168) (xy 332.126336 -287.856168) (xy 332.125841 -287.880775)
			(xy 332.117946 -287.929352) (xy 332.102362 -287.976033) (xy 332.079491 -288.01961) (xy 332.049926 -288.058954)
			(xy 332.014433 -288.093046) (xy 331.97393 -288.121002) (xy 331.929468 -288.1421) (xy 331.882197 -288.155792)
			(xy 331.833342 -288.161724) (xy 331.784167 -288.159743) (xy 331.735948 -288.149899) (xy 331.689932 -288.132447)
			(xy 331.647311 -288.10784) (xy 331.60919 -288.076715) (xy 331.576555 -288.039878) (xy 331.550252 -287.998282)
			(xy 331.530961 -287.953006) (xy 331.519184 -287.905222) (xy 331.515224 -287.856168) (xy 331.196696 -287.856168)
			(xy 331.196184 -287.881614) (xy 331.18802 -287.931848) (xy 331.171904 -287.980122) (xy 331.148253 -288.025185)
			(xy 331.11768 -288.065871) (xy 331.080976 -288.101126) (xy 331.039092 -288.130036) (xy 330.993113 -288.151853)
			(xy 330.944229 -288.166013) (xy 330.893708 -288.172147) (xy 330.842856 -288.170098) (xy 330.792992 -288.159918)
			(xy 330.745406 -288.141871) (xy 330.701332 -288.116425) (xy 330.66191 -288.084238) (xy 330.628162 -288.046144)
			(xy 330.600961 -288.00313) (xy 330.581013 -287.95631) (xy 330.568834 -287.906896) (xy 330.564739 -287.856168)
			(xy 330.246482 -287.856168) (xy 330.245987 -287.880775) (xy 330.238092 -287.929352) (xy 330.222508 -287.976033)
			(xy 330.199637 -288.01961) (xy 330.170072 -288.058954) (xy 330.134579 -288.093046) (xy 330.094076 -288.121002)
			(xy 330.049614 -288.1421) (xy 330.002343 -288.155792) (xy 329.953488 -288.161724) (xy 329.904313 -288.159743)
			(xy 329.856094 -288.149899) (xy 329.810078 -288.132447) (xy 329.767457 -288.10784) (xy 329.729336 -288.076715)
			(xy 329.696701 -288.039878) (xy 329.670398 -287.998282) (xy 329.651107 -287.953006) (xy 329.63933 -287.905222)
			(xy 329.63537 -287.856168) (xy 329.316842 -287.856168) (xy 329.31633 -287.881614) (xy 329.308166 -287.931848)
			(xy 329.29205 -287.980122) (xy 329.268399 -288.025185) (xy 329.237826 -288.065871) (xy 329.201122 -288.101126)
			(xy 329.159238 -288.130036) (xy 329.113259 -288.151853) (xy 329.064375 -288.166013) (xy 329.013854 -288.172147)
			(xy 328.963002 -288.170098) (xy 328.913138 -288.159918) (xy 328.865552 -288.141871) (xy 328.821478 -288.116425)
			(xy 328.782056 -288.084238) (xy 328.748308 -288.046144) (xy 328.721107 -288.00313) (xy 328.701159 -287.95631)
			(xy 328.68898 -287.906896) (xy 328.684885 -287.856168) (xy 325.203519 -287.856168) (xy 325.161384 -287.876162)
			(xy 325.114113 -287.889854) (xy 325.065258 -287.895786) (xy 325.016083 -287.893805) (xy 324.967864 -287.883961)
			(xy 324.921848 -287.866509) (xy 324.879227 -287.841902) (xy 324.841106 -287.810777) (xy 324.808471 -287.77394)
			(xy 324.782168 -287.732344) (xy 324.762877 -287.687068) (xy 324.7511 -287.639284) (xy 324.74714 -287.59023)
			(xy 310.45912 -287.59023) (xy 310.45912 -288.66592) (xy 326.345308 -288.66592) (xy 326.349268 -288.616866)
			(xy 326.361045 -288.569082) (xy 326.380336 -288.523806) (xy 326.406639 -288.48221) (xy 326.439274 -288.445373)
			(xy 326.477395 -288.414248) (xy 326.520016 -288.389641) (xy 326.566032 -288.372189) (xy 326.614251 -288.362345)
			(xy 326.663426 -288.360364) (xy 326.712281 -288.366296) (xy 326.759552 -288.379988) (xy 326.804014 -288.401086)
			(xy 326.844517 -288.429042) (xy 326.88001 -288.463134) (xy 326.909575 -288.502478) (xy 326.932446 -288.546055)
			(xy 326.94803 -288.592736) (xy 326.955925 -288.641313) (xy 326.95642 -288.66592) (xy 328.225416 -288.66592)
			(xy 328.229376 -288.616866) (xy 328.241153 -288.569082) (xy 328.260444 -288.523806) (xy 328.286747 -288.48221)
			(xy 328.319382 -288.445373) (xy 328.357503 -288.414248) (xy 328.400124 -288.389641) (xy 328.44614 -288.372189)
			(xy 328.494359 -288.362345) (xy 328.543534 -288.360364) (xy 328.592389 -288.366296) (xy 328.63966 -288.379988)
			(xy 328.684122 -288.401086) (xy 328.724625 -288.429042) (xy 328.760118 -288.463134) (xy 328.789683 -288.502478)
			(xy 328.812554 -288.546055) (xy 328.828138 -288.592736) (xy 328.836033 -288.641313) (xy 328.836528 -288.66592)
			(xy 329.154785 -288.66592) (xy 329.15888 -288.615192) (xy 329.171059 -288.565778) (xy 329.191007 -288.518958)
			(xy 329.218208 -288.475944) (xy 329.251956 -288.43785) (xy 329.291378 -288.405663) (xy 329.335452 -288.380217)
			(xy 329.383038 -288.36217) (xy 329.432902 -288.35199) (xy 329.483754 -288.349941) (xy 329.534275 -288.356075)
			(xy 329.583159 -288.370235) (xy 329.629138 -288.392052) (xy 329.671022 -288.420962) (xy 329.707726 -288.456217)
			(xy 329.738299 -288.496903) (xy 329.76195 -288.541966) (xy 329.778066 -288.59024) (xy 329.78623 -288.640474)
			(xy 329.786742 -288.66592) (xy 330.094839 -288.66592) (xy 330.098934 -288.615192) (xy 330.111113 -288.565778)
			(xy 330.131061 -288.518958) (xy 330.158262 -288.475944) (xy 330.19201 -288.43785) (xy 330.231432 -288.405663)
			(xy 330.275506 -288.380217) (xy 330.323092 -288.36217) (xy 330.372956 -288.35199) (xy 330.423808 -288.349941)
			(xy 330.474329 -288.356075) (xy 330.523213 -288.370235) (xy 330.569192 -288.392052) (xy 330.611076 -288.420962)
			(xy 330.64778 -288.456217) (xy 330.678353 -288.496903) (xy 330.702004 -288.541966) (xy 330.71812 -288.59024)
			(xy 330.726284 -288.640474) (xy 330.726796 -288.66592) (xy 331.045324 -288.66592) (xy 331.049284 -288.616866)
			(xy 331.061061 -288.569082) (xy 331.080352 -288.523806) (xy 331.106655 -288.48221) (xy 331.13929 -288.445373)
			(xy 331.177411 -288.414248) (xy 331.220032 -288.389641) (xy 331.266048 -288.372189) (xy 331.314267 -288.362345)
			(xy 331.363442 -288.360364) (xy 331.412297 -288.366296) (xy 331.459568 -288.379988) (xy 331.50403 -288.401086)
			(xy 331.544533 -288.429042) (xy 331.580026 -288.463134) (xy 331.609591 -288.502478) (xy 331.632462 -288.546055)
			(xy 331.648046 -288.592736) (xy 331.655941 -288.641313) (xy 331.656436 -288.66592) (xy 331.974947 -288.66592)
			(xy 331.979042 -288.615192) (xy 331.991221 -288.565778) (xy 332.011169 -288.518958) (xy 332.03837 -288.475944)
			(xy 332.072118 -288.43785) (xy 332.11154 -288.405663) (xy 332.155614 -288.380217) (xy 332.2032 -288.36217)
			(xy 332.253064 -288.35199) (xy 332.303916 -288.349941) (xy 332.354437 -288.356075) (xy 332.403321 -288.370235)
			(xy 332.4493 -288.392052) (xy 332.491184 -288.420962) (xy 332.527888 -288.456217) (xy 332.558461 -288.496903)
			(xy 332.582112 -288.541966) (xy 332.598228 -288.59024) (xy 332.606392 -288.640474) (xy 332.606904 -288.66592)
			(xy 332.925178 -288.66592) (xy 332.929138 -288.616866) (xy 332.940915 -288.569082) (xy 332.960206 -288.523806)
			(xy 332.986509 -288.48221) (xy 333.019144 -288.445373) (xy 333.057265 -288.414248) (xy 333.099886 -288.389641)
			(xy 333.145902 -288.372189) (xy 333.194121 -288.362345) (xy 333.243296 -288.360364) (xy 333.292151 -288.366296)
			(xy 333.339422 -288.379988) (xy 333.383884 -288.401086) (xy 333.424387 -288.429042) (xy 333.45988 -288.463134)
			(xy 333.489445 -288.502478) (xy 333.512316 -288.546055) (xy 333.5279 -288.592736) (xy 333.535795 -288.641313)
			(xy 333.53629 -288.66592) (xy 333.854801 -288.66592) (xy 333.858896 -288.615192) (xy 333.871075 -288.565778)
			(xy 333.891023 -288.518958) (xy 333.918224 -288.475944) (xy 333.951972 -288.43785) (xy 333.991394 -288.405663)
			(xy 334.035468 -288.380217) (xy 334.083054 -288.36217) (xy 334.132918 -288.35199) (xy 334.18377 -288.349941)
			(xy 334.234291 -288.356075) (xy 334.283175 -288.370235) (xy 334.329154 -288.392052) (xy 334.371038 -288.420962)
			(xy 334.407742 -288.456217) (xy 334.438315 -288.496903) (xy 334.461966 -288.541966) (xy 334.478082 -288.59024)
			(xy 334.486246 -288.640474) (xy 334.486758 -288.66592) (xy 334.805286 -288.66592) (xy 334.809246 -288.616866)
			(xy 334.821023 -288.569082) (xy 334.840314 -288.523806) (xy 334.866617 -288.48221) (xy 334.899252 -288.445373)
			(xy 334.937373 -288.414248) (xy 334.979994 -288.389641) (xy 335.02601 -288.372189) (xy 335.074229 -288.362345)
			(xy 335.123404 -288.360364) (xy 335.172259 -288.366296) (xy 335.21953 -288.379988) (xy 335.263992 -288.401086)
			(xy 335.304495 -288.429042) (xy 335.339988 -288.463134) (xy 335.369553 -288.502478) (xy 335.392424 -288.546055)
			(xy 335.408008 -288.592736) (xy 335.415903 -288.641313) (xy 335.416398 -288.66592) (xy 335.734909 -288.66592)
			(xy 335.739004 -288.615192) (xy 335.751183 -288.565778) (xy 335.771131 -288.518958) (xy 335.798332 -288.475944)
			(xy 335.83208 -288.43785) (xy 335.871502 -288.405663) (xy 335.915576 -288.380217) (xy 335.963162 -288.36217)
			(xy 336.013026 -288.35199) (xy 336.063878 -288.349941) (xy 336.114399 -288.356075) (xy 336.163283 -288.370235)
			(xy 336.209262 -288.392052) (xy 336.251146 -288.420962) (xy 336.28785 -288.456217) (xy 336.318423 -288.496903)
			(xy 336.342074 -288.541966) (xy 336.35819 -288.59024) (xy 336.366354 -288.640474) (xy 336.366866 -288.66592)
			(xy 336.674963 -288.66592) (xy 336.679058 -288.615192) (xy 336.691237 -288.565778) (xy 336.711185 -288.518958)
			(xy 336.738386 -288.475944) (xy 336.772134 -288.43785) (xy 336.811556 -288.405663) (xy 336.85563 -288.380217)
			(xy 336.903216 -288.36217) (xy 336.95308 -288.35199) (xy 337.003932 -288.349941) (xy 337.054453 -288.356075)
			(xy 337.103337 -288.370235) (xy 337.149316 -288.392052) (xy 337.1912 -288.420962) (xy 337.227904 -288.456217)
			(xy 337.258477 -288.496903) (xy 337.282128 -288.541966) (xy 337.298244 -288.59024) (xy 337.306408 -288.640474)
			(xy 337.30692 -288.66592) (xy 337.625194 -288.66592) (xy 337.629154 -288.616866) (xy 337.640931 -288.569082)
			(xy 337.660222 -288.523806) (xy 337.686525 -288.48221) (xy 337.71916 -288.445373) (xy 337.757281 -288.414248)
			(xy 337.799902 -288.389641) (xy 337.845918 -288.372189) (xy 337.894137 -288.362345) (xy 337.943312 -288.360364)
			(xy 337.992167 -288.366296) (xy 338.039438 -288.379988) (xy 338.0839 -288.401086) (xy 338.124403 -288.429042)
			(xy 338.159896 -288.463134) (xy 338.189461 -288.502478) (xy 338.212332 -288.546055) (xy 338.227916 -288.592736)
			(xy 338.235811 -288.641313) (xy 338.236306 -288.66592) (xy 338.554817 -288.66592) (xy 338.558912 -288.615192)
			(xy 338.571091 -288.565778) (xy 338.591039 -288.518958) (xy 338.61824 -288.475944) (xy 338.651988 -288.43785)
			(xy 338.69141 -288.405663) (xy 338.735484 -288.380217) (xy 338.78307 -288.36217) (xy 338.832934 -288.35199)
			(xy 338.883786 -288.349941) (xy 338.934307 -288.356075) (xy 338.983191 -288.370235) (xy 339.02917 -288.392052)
			(xy 339.071054 -288.420962) (xy 339.107758 -288.456217) (xy 339.138331 -288.496903) (xy 339.161982 -288.541966)
			(xy 339.178098 -288.59024) (xy 339.186262 -288.640474) (xy 339.186774 -288.66592) (xy 339.505302 -288.66592)
			(xy 339.509262 -288.616866) (xy 339.521039 -288.569082) (xy 339.54033 -288.523806) (xy 339.566633 -288.48221)
			(xy 339.599268 -288.445373) (xy 339.637389 -288.414248) (xy 339.68001 -288.389641) (xy 339.726026 -288.372189)
			(xy 339.774245 -288.362345) (xy 339.82342 -288.360364) (xy 339.872275 -288.366296) (xy 339.919546 -288.379988)
			(xy 339.964008 -288.401086) (xy 340.004511 -288.429042) (xy 340.040004 -288.463134) (xy 340.069569 -288.502478)
			(xy 340.09244 -288.546055) (xy 340.108024 -288.592736) (xy 340.115919 -288.641313) (xy 340.116414 -288.66592)
			(xy 340.434925 -288.66592) (xy 340.43902 -288.615192) (xy 340.451199 -288.565778) (xy 340.471147 -288.518958)
			(xy 340.498348 -288.475944) (xy 340.532096 -288.43785) (xy 340.571518 -288.405663) (xy 340.615592 -288.380217)
			(xy 340.663178 -288.36217) (xy 340.713042 -288.35199) (xy 340.763894 -288.349941) (xy 340.814415 -288.356075)
			(xy 340.863299 -288.370235) (xy 340.909278 -288.392052) (xy 340.951162 -288.420962) (xy 340.987866 -288.456217)
			(xy 341.018439 -288.496903) (xy 341.04209 -288.541966) (xy 341.058206 -288.59024) (xy 341.06637 -288.640474)
			(xy 341.066882 -288.66592) (xy 341.38541 -288.66592) (xy 341.38937 -288.616866) (xy 341.401147 -288.569082)
			(xy 341.420438 -288.523806) (xy 341.446741 -288.48221) (xy 341.479376 -288.445373) (xy 341.517497 -288.414248)
			(xy 341.560118 -288.389641) (xy 341.606134 -288.372189) (xy 341.654353 -288.362345) (xy 341.703528 -288.360364)
			(xy 341.752383 -288.366296) (xy 341.799654 -288.379988) (xy 341.844116 -288.401086) (xy 341.884619 -288.429042)
			(xy 341.920112 -288.463134) (xy 341.949677 -288.502478) (xy 341.972548 -288.546055) (xy 341.988132 -288.592736)
			(xy 341.996027 -288.641313) (xy 341.996522 -288.66592) (xy 342.314779 -288.66592) (xy 342.318874 -288.615192)
			(xy 342.331053 -288.565778) (xy 342.351001 -288.518958) (xy 342.378202 -288.475944) (xy 342.41195 -288.43785)
			(xy 342.451372 -288.405663) (xy 342.495446 -288.380217) (xy 342.543032 -288.36217) (xy 342.592896 -288.35199)
			(xy 342.643748 -288.349941) (xy 342.694269 -288.356075) (xy 342.743153 -288.370235) (xy 342.789132 -288.392052)
			(xy 342.831016 -288.420962) (xy 342.86772 -288.456217) (xy 342.898293 -288.496903) (xy 342.921944 -288.541966)
			(xy 342.93806 -288.59024) (xy 342.946224 -288.640474) (xy 342.946736 -288.66592) (xy 343.254833 -288.66592)
			(xy 343.258928 -288.615192) (xy 343.271107 -288.565778) (xy 343.291055 -288.518958) (xy 343.318256 -288.475944)
			(xy 343.352004 -288.43785) (xy 343.391426 -288.405663) (xy 343.4355 -288.380217) (xy 343.483086 -288.36217)
			(xy 343.53295 -288.35199) (xy 343.583802 -288.349941) (xy 343.634323 -288.356075) (xy 343.683207 -288.370235)
			(xy 343.729186 -288.392052) (xy 343.77107 -288.420962) (xy 343.807774 -288.456217) (xy 343.838347 -288.496903)
			(xy 343.861998 -288.541966) (xy 343.878114 -288.59024) (xy 343.886278 -288.640474) (xy 343.88679 -288.66592)
			(xy 345.145372 -288.66592) (xy 345.149332 -288.616866) (xy 345.161109 -288.569082) (xy 345.1804 -288.523806)
			(xy 345.206703 -288.48221) (xy 345.239338 -288.445373) (xy 345.277459 -288.414248) (xy 345.32008 -288.389641)
			(xy 345.366096 -288.372189) (xy 345.414315 -288.362345) (xy 345.46349 -288.360364) (xy 345.512345 -288.366296)
			(xy 345.559616 -288.379988) (xy 345.604078 -288.401086) (xy 345.644581 -288.429042) (xy 345.680074 -288.463134)
			(xy 345.709639 -288.502478) (xy 345.73251 -288.546055) (xy 345.748094 -288.592736) (xy 345.755989 -288.641313)
			(xy 345.756484 -288.66592) (xy 346.085426 -288.66592) (xy 346.089386 -288.616866) (xy 346.101163 -288.569082)
			(xy 346.120454 -288.523806) (xy 346.146757 -288.48221) (xy 346.179392 -288.445373) (xy 346.217513 -288.414248)
			(xy 346.260134 -288.389641) (xy 346.30615 -288.372189) (xy 346.354369 -288.362345) (xy 346.403544 -288.360364)
			(xy 346.452399 -288.366296) (xy 346.49967 -288.379988) (xy 346.544132 -288.401086) (xy 346.584635 -288.429042)
			(xy 346.620128 -288.463134) (xy 346.649693 -288.502478) (xy 346.672564 -288.546055) (xy 346.688148 -288.592736)
			(xy 346.696043 -288.641313) (xy 346.696538 -288.66592) (xy 347.025226 -288.66592) (xy 347.029186 -288.616866)
			(xy 347.040963 -288.569082) (xy 347.060254 -288.523806) (xy 347.086557 -288.48221) (xy 347.119192 -288.445373)
			(xy 347.157313 -288.414248) (xy 347.199934 -288.389641) (xy 347.24595 -288.372189) (xy 347.294169 -288.362345)
			(xy 347.343344 -288.360364) (xy 347.392199 -288.366296) (xy 347.43947 -288.379988) (xy 347.483932 -288.401086)
			(xy 347.524435 -288.429042) (xy 347.559928 -288.463134) (xy 347.589493 -288.502478) (xy 347.612364 -288.546055)
			(xy 347.627948 -288.592736) (xy 347.635843 -288.641313) (xy 347.636338 -288.66592) (xy 347.96528 -288.66592)
			(xy 347.96924 -288.616866) (xy 347.981017 -288.569082) (xy 348.000308 -288.523806) (xy 348.026611 -288.48221)
			(xy 348.059246 -288.445373) (xy 348.097367 -288.414248) (xy 348.139988 -288.389641) (xy 348.186004 -288.372189)
			(xy 348.234223 -288.362345) (xy 348.283398 -288.360364) (xy 348.332253 -288.366296) (xy 348.379524 -288.379988)
			(xy 348.423986 -288.401086) (xy 348.464489 -288.429042) (xy 348.499982 -288.463134) (xy 348.529547 -288.502478)
			(xy 348.552418 -288.546055) (xy 348.568002 -288.592736) (xy 348.575897 -288.641313) (xy 348.576392 -288.66592)
			(xy 348.905334 -288.66592) (xy 348.909294 -288.616866) (xy 348.921071 -288.569082) (xy 348.940362 -288.523806)
			(xy 348.966665 -288.48221) (xy 348.9993 -288.445373) (xy 349.037421 -288.414248) (xy 349.080042 -288.389641)
			(xy 349.126058 -288.372189) (xy 349.174277 -288.362345) (xy 349.223452 -288.360364) (xy 349.272307 -288.366296)
			(xy 349.319578 -288.379988) (xy 349.36404 -288.401086) (xy 349.404543 -288.429042) (xy 349.440036 -288.463134)
			(xy 349.469601 -288.502478) (xy 349.492472 -288.546055) (xy 349.508056 -288.592736) (xy 349.515951 -288.641313)
			(xy 349.516446 -288.66592) (xy 349.845388 -288.66592) (xy 349.849348 -288.616866) (xy 349.861125 -288.569082)
			(xy 349.880416 -288.523806) (xy 349.906719 -288.48221) (xy 349.939354 -288.445373) (xy 349.977475 -288.414248)
			(xy 350.020096 -288.389641) (xy 350.066112 -288.372189) (xy 350.114331 -288.362345) (xy 350.163506 -288.360364)
			(xy 350.212361 -288.366296) (xy 350.259632 -288.379988) (xy 350.304094 -288.401086) (xy 350.344597 -288.429042)
			(xy 350.38009 -288.463134) (xy 350.409655 -288.502478) (xy 350.432526 -288.546055) (xy 350.44811 -288.592736)
			(xy 350.456005 -288.641313) (xy 350.4565 -288.66592) (xy 350.785442 -288.66592) (xy 350.789402 -288.616866)
			(xy 350.801179 -288.569082) (xy 350.82047 -288.523806) (xy 350.846773 -288.48221) (xy 350.879408 -288.445373)
			(xy 350.917529 -288.414248) (xy 350.96015 -288.389641) (xy 351.006166 -288.372189) (xy 351.054385 -288.362345)
			(xy 351.10356 -288.360364) (xy 351.152415 -288.366296) (xy 351.199686 -288.379988) (xy 351.244148 -288.401086)
			(xy 351.284651 -288.429042) (xy 351.320144 -288.463134) (xy 351.349709 -288.502478) (xy 351.37258 -288.546055)
			(xy 351.388164 -288.592736) (xy 351.396059 -288.641313) (xy 351.396554 -288.66592) (xy 351.396059 -288.690527)
			(xy 351.388164 -288.739104) (xy 351.37258 -288.785785) (xy 351.349709 -288.829362) (xy 351.320144 -288.868706)
			(xy 351.284651 -288.902798) (xy 351.244148 -288.930754) (xy 351.199686 -288.951852) (xy 351.152415 -288.965544)
			(xy 351.10356 -288.971476) (xy 351.054385 -288.969495) (xy 351.006166 -288.959651) (xy 350.96015 -288.942199)
			(xy 350.917529 -288.917592) (xy 350.879408 -288.886467) (xy 350.846773 -288.84963) (xy 350.82047 -288.808034)
			(xy 350.801179 -288.762758) (xy 350.789402 -288.714974) (xy 350.785442 -288.66592) (xy 350.4565 -288.66592)
			(xy 350.456005 -288.690527) (xy 350.44811 -288.739104) (xy 350.432526 -288.785785) (xy 350.409655 -288.829362)
			(xy 350.38009 -288.868706) (xy 350.344597 -288.902798) (xy 350.304094 -288.930754) (xy 350.259632 -288.951852)
			(xy 350.212361 -288.965544) (xy 350.163506 -288.971476) (xy 350.114331 -288.969495) (xy 350.066112 -288.959651)
			(xy 350.020096 -288.942199) (xy 349.977475 -288.917592) (xy 349.939354 -288.886467) (xy 349.906719 -288.84963)
			(xy 349.880416 -288.808034) (xy 349.861125 -288.762758) (xy 349.849348 -288.714974) (xy 349.845388 -288.66592)
			(xy 349.516446 -288.66592) (xy 349.515951 -288.690527) (xy 349.508056 -288.739104) (xy 349.492472 -288.785785)
			(xy 349.469601 -288.829362) (xy 349.440036 -288.868706) (xy 349.404543 -288.902798) (xy 349.36404 -288.930754)
			(xy 349.319578 -288.951852) (xy 349.272307 -288.965544) (xy 349.223452 -288.971476) (xy 349.174277 -288.969495)
			(xy 349.126058 -288.959651) (xy 349.080042 -288.942199) (xy 349.037421 -288.917592) (xy 348.9993 -288.886467)
			(xy 348.966665 -288.84963) (xy 348.940362 -288.808034) (xy 348.921071 -288.762758) (xy 348.909294 -288.714974)
			(xy 348.905334 -288.66592) (xy 348.576392 -288.66592) (xy 348.575897 -288.690527) (xy 348.568002 -288.739104)
			(xy 348.552418 -288.785785) (xy 348.529547 -288.829362) (xy 348.499982 -288.868706) (xy 348.464489 -288.902798)
			(xy 348.423986 -288.930754) (xy 348.379524 -288.951852) (xy 348.332253 -288.965544) (xy 348.283398 -288.971476)
			(xy 348.234223 -288.969495) (xy 348.186004 -288.959651) (xy 348.139988 -288.942199) (xy 348.097367 -288.917592)
			(xy 348.059246 -288.886467) (xy 348.026611 -288.84963) (xy 348.000308 -288.808034) (xy 347.981017 -288.762758)
			(xy 347.96924 -288.714974) (xy 347.96528 -288.66592) (xy 347.636338 -288.66592) (xy 347.635843 -288.690527)
			(xy 347.627948 -288.739104) (xy 347.612364 -288.785785) (xy 347.589493 -288.829362) (xy 347.559928 -288.868706)
			(xy 347.524435 -288.902798) (xy 347.483932 -288.930754) (xy 347.43947 -288.951852) (xy 347.392199 -288.965544)
			(xy 347.343344 -288.971476) (xy 347.294169 -288.969495) (xy 347.24595 -288.959651) (xy 347.199934 -288.942199)
			(xy 347.157313 -288.917592) (xy 347.119192 -288.886467) (xy 347.086557 -288.84963) (xy 347.060254 -288.808034)
			(xy 347.040963 -288.762758) (xy 347.029186 -288.714974) (xy 347.025226 -288.66592) (xy 346.696538 -288.66592)
			(xy 346.696043 -288.690527) (xy 346.688148 -288.739104) (xy 346.672564 -288.785785) (xy 346.649693 -288.829362)
			(xy 346.620128 -288.868706) (xy 346.584635 -288.902798) (xy 346.544132 -288.930754) (xy 346.49967 -288.951852)
			(xy 346.452399 -288.965544) (xy 346.403544 -288.971476) (xy 346.354369 -288.969495) (xy 346.30615 -288.959651)
			(xy 346.260134 -288.942199) (xy 346.217513 -288.917592) (xy 346.179392 -288.886467) (xy 346.146757 -288.84963)
			(xy 346.120454 -288.808034) (xy 346.101163 -288.762758) (xy 346.089386 -288.714974) (xy 346.085426 -288.66592)
			(xy 345.756484 -288.66592) (xy 345.755989 -288.690527) (xy 345.748094 -288.739104) (xy 345.73251 -288.785785)
			(xy 345.709639 -288.829362) (xy 345.680074 -288.868706) (xy 345.644581 -288.902798) (xy 345.604078 -288.930754)
			(xy 345.559616 -288.951852) (xy 345.512345 -288.965544) (xy 345.46349 -288.971476) (xy 345.414315 -288.969495)
			(xy 345.366096 -288.959651) (xy 345.32008 -288.942199) (xy 345.277459 -288.917592) (xy 345.239338 -288.886467)
			(xy 345.206703 -288.84963) (xy 345.1804 -288.808034) (xy 345.161109 -288.762758) (xy 345.149332 -288.714974)
			(xy 345.145372 -288.66592) (xy 343.88679 -288.66592) (xy 343.886278 -288.691366) (xy 343.878114 -288.7416)
			(xy 343.861998 -288.789874) (xy 343.838347 -288.834937) (xy 343.807774 -288.875623) (xy 343.77107 -288.910878)
			(xy 343.729186 -288.939788) (xy 343.683207 -288.961605) (xy 343.634323 -288.975765) (xy 343.583802 -288.981899)
			(xy 343.53295 -288.97985) (xy 343.483086 -288.96967) (xy 343.4355 -288.951623) (xy 343.391426 -288.926177)
			(xy 343.352004 -288.89399) (xy 343.318256 -288.855896) (xy 343.291055 -288.812882) (xy 343.271107 -288.766062)
			(xy 343.258928 -288.716648) (xy 343.254833 -288.66592) (xy 342.946736 -288.66592) (xy 342.946224 -288.691366)
			(xy 342.93806 -288.7416) (xy 342.921944 -288.789874) (xy 342.898293 -288.834937) (xy 342.86772 -288.875623)
			(xy 342.831016 -288.910878) (xy 342.789132 -288.939788) (xy 342.743153 -288.961605) (xy 342.694269 -288.975765)
			(xy 342.643748 -288.981899) (xy 342.592896 -288.97985) (xy 342.543032 -288.96967) (xy 342.495446 -288.951623)
			(xy 342.451372 -288.926177) (xy 342.41195 -288.89399) (xy 342.378202 -288.855896) (xy 342.351001 -288.812882)
			(xy 342.331053 -288.766062) (xy 342.318874 -288.716648) (xy 342.314779 -288.66592) (xy 341.996522 -288.66592)
			(xy 341.996027 -288.690527) (xy 341.988132 -288.739104) (xy 341.972548 -288.785785) (xy 341.949677 -288.829362)
			(xy 341.920112 -288.868706) (xy 341.884619 -288.902798) (xy 341.844116 -288.930754) (xy 341.799654 -288.951852)
			(xy 341.752383 -288.965544) (xy 341.703528 -288.971476) (xy 341.654353 -288.969495) (xy 341.606134 -288.959651)
			(xy 341.560118 -288.942199) (xy 341.517497 -288.917592) (xy 341.479376 -288.886467) (xy 341.446741 -288.84963)
			(xy 341.420438 -288.808034) (xy 341.401147 -288.762758) (xy 341.38937 -288.714974) (xy 341.38541 -288.66592)
			(xy 341.066882 -288.66592) (xy 341.06637 -288.691366) (xy 341.058206 -288.7416) (xy 341.04209 -288.789874)
			(xy 341.018439 -288.834937) (xy 340.987866 -288.875623) (xy 340.951162 -288.910878) (xy 340.909278 -288.939788)
			(xy 340.863299 -288.961605) (xy 340.814415 -288.975765) (xy 340.763894 -288.981899) (xy 340.713042 -288.97985)
			(xy 340.663178 -288.96967) (xy 340.615592 -288.951623) (xy 340.571518 -288.926177) (xy 340.532096 -288.89399)
			(xy 340.498348 -288.855896) (xy 340.471147 -288.812882) (xy 340.451199 -288.766062) (xy 340.43902 -288.716648)
			(xy 340.434925 -288.66592) (xy 340.116414 -288.66592) (xy 340.115919 -288.690527) (xy 340.108024 -288.739104)
			(xy 340.09244 -288.785785) (xy 340.069569 -288.829362) (xy 340.040004 -288.868706) (xy 340.004511 -288.902798)
			(xy 339.964008 -288.930754) (xy 339.919546 -288.951852) (xy 339.872275 -288.965544) (xy 339.82342 -288.971476)
			(xy 339.774245 -288.969495) (xy 339.726026 -288.959651) (xy 339.68001 -288.942199) (xy 339.637389 -288.917592)
			(xy 339.599268 -288.886467) (xy 339.566633 -288.84963) (xy 339.54033 -288.808034) (xy 339.521039 -288.762758)
			(xy 339.509262 -288.714974) (xy 339.505302 -288.66592) (xy 339.186774 -288.66592) (xy 339.186262 -288.691366)
			(xy 339.178098 -288.7416) (xy 339.161982 -288.789874) (xy 339.138331 -288.834937) (xy 339.107758 -288.875623)
			(xy 339.071054 -288.910878) (xy 339.02917 -288.939788) (xy 338.983191 -288.961605) (xy 338.934307 -288.975765)
			(xy 338.883786 -288.981899) (xy 338.832934 -288.97985) (xy 338.78307 -288.96967) (xy 338.735484 -288.951623)
			(xy 338.69141 -288.926177) (xy 338.651988 -288.89399) (xy 338.61824 -288.855896) (xy 338.591039 -288.812882)
			(xy 338.571091 -288.766062) (xy 338.558912 -288.716648) (xy 338.554817 -288.66592) (xy 338.236306 -288.66592)
			(xy 338.235811 -288.690527) (xy 338.227916 -288.739104) (xy 338.212332 -288.785785) (xy 338.189461 -288.829362)
			(xy 338.159896 -288.868706) (xy 338.124403 -288.902798) (xy 338.0839 -288.930754) (xy 338.039438 -288.951852)
			(xy 337.992167 -288.965544) (xy 337.943312 -288.971476) (xy 337.894137 -288.969495) (xy 337.845918 -288.959651)
			(xy 337.799902 -288.942199) (xy 337.757281 -288.917592) (xy 337.71916 -288.886467) (xy 337.686525 -288.84963)
			(xy 337.660222 -288.808034) (xy 337.640931 -288.762758) (xy 337.629154 -288.714974) (xy 337.625194 -288.66592)
			(xy 337.30692 -288.66592) (xy 337.306408 -288.691366) (xy 337.298244 -288.7416) (xy 337.282128 -288.789874)
			(xy 337.258477 -288.834937) (xy 337.227904 -288.875623) (xy 337.1912 -288.910878) (xy 337.149316 -288.939788)
			(xy 337.103337 -288.961605) (xy 337.054453 -288.975765) (xy 337.003932 -288.981899) (xy 336.95308 -288.97985)
			(xy 336.903216 -288.96967) (xy 336.85563 -288.951623) (xy 336.811556 -288.926177) (xy 336.772134 -288.89399)
			(xy 336.738386 -288.855896) (xy 336.711185 -288.812882) (xy 336.691237 -288.766062) (xy 336.679058 -288.716648)
			(xy 336.674963 -288.66592) (xy 336.366866 -288.66592) (xy 336.366354 -288.691366) (xy 336.35819 -288.7416)
			(xy 336.342074 -288.789874) (xy 336.318423 -288.834937) (xy 336.28785 -288.875623) (xy 336.251146 -288.910878)
			(xy 336.209262 -288.939788) (xy 336.163283 -288.961605) (xy 336.114399 -288.975765) (xy 336.063878 -288.981899)
			(xy 336.013026 -288.97985) (xy 335.963162 -288.96967) (xy 335.915576 -288.951623) (xy 335.871502 -288.926177)
			(xy 335.83208 -288.89399) (xy 335.798332 -288.855896) (xy 335.771131 -288.812882) (xy 335.751183 -288.766062)
			(xy 335.739004 -288.716648) (xy 335.734909 -288.66592) (xy 335.416398 -288.66592) (xy 335.415903 -288.690527)
			(xy 335.408008 -288.739104) (xy 335.392424 -288.785785) (xy 335.369553 -288.829362) (xy 335.339988 -288.868706)
			(xy 335.304495 -288.902798) (xy 335.263992 -288.930754) (xy 335.21953 -288.951852) (xy 335.172259 -288.965544)
			(xy 335.123404 -288.971476) (xy 335.074229 -288.969495) (xy 335.02601 -288.959651) (xy 334.979994 -288.942199)
			(xy 334.937373 -288.917592) (xy 334.899252 -288.886467) (xy 334.866617 -288.84963) (xy 334.840314 -288.808034)
			(xy 334.821023 -288.762758) (xy 334.809246 -288.714974) (xy 334.805286 -288.66592) (xy 334.486758 -288.66592)
			(xy 334.486246 -288.691366) (xy 334.478082 -288.7416) (xy 334.461966 -288.789874) (xy 334.438315 -288.834937)
			(xy 334.407742 -288.875623) (xy 334.371038 -288.910878) (xy 334.329154 -288.939788) (xy 334.283175 -288.961605)
			(xy 334.234291 -288.975765) (xy 334.18377 -288.981899) (xy 334.132918 -288.97985) (xy 334.083054 -288.96967)
			(xy 334.035468 -288.951623) (xy 333.991394 -288.926177) (xy 333.951972 -288.89399) (xy 333.918224 -288.855896)
			(xy 333.891023 -288.812882) (xy 333.871075 -288.766062) (xy 333.858896 -288.716648) (xy 333.854801 -288.66592)
			(xy 333.53629 -288.66592) (xy 333.535795 -288.690527) (xy 333.5279 -288.739104) (xy 333.512316 -288.785785)
			(xy 333.489445 -288.829362) (xy 333.45988 -288.868706) (xy 333.424387 -288.902798) (xy 333.383884 -288.930754)
			(xy 333.339422 -288.951852) (xy 333.292151 -288.965544) (xy 333.243296 -288.971476) (xy 333.194121 -288.969495)
			(xy 333.145902 -288.959651) (xy 333.099886 -288.942199) (xy 333.057265 -288.917592) (xy 333.019144 -288.886467)
			(xy 332.986509 -288.84963) (xy 332.960206 -288.808034) (xy 332.940915 -288.762758) (xy 332.929138 -288.714974)
			(xy 332.925178 -288.66592) (xy 332.606904 -288.66592) (xy 332.606392 -288.691366) (xy 332.598228 -288.7416)
			(xy 332.582112 -288.789874) (xy 332.558461 -288.834937) (xy 332.527888 -288.875623) (xy 332.491184 -288.910878)
			(xy 332.4493 -288.939788) (xy 332.403321 -288.961605) (xy 332.354437 -288.975765) (xy 332.303916 -288.981899)
			(xy 332.253064 -288.97985) (xy 332.2032 -288.96967) (xy 332.155614 -288.951623) (xy 332.11154 -288.926177)
			(xy 332.072118 -288.89399) (xy 332.03837 -288.855896) (xy 332.011169 -288.812882) (xy 331.991221 -288.766062)
			(xy 331.979042 -288.716648) (xy 331.974947 -288.66592) (xy 331.656436 -288.66592) (xy 331.655941 -288.690527)
			(xy 331.648046 -288.739104) (xy 331.632462 -288.785785) (xy 331.609591 -288.829362) (xy 331.580026 -288.868706)
			(xy 331.544533 -288.902798) (xy 331.50403 -288.930754) (xy 331.459568 -288.951852) (xy 331.412297 -288.965544)
			(xy 331.363442 -288.971476) (xy 331.314267 -288.969495) (xy 331.266048 -288.959651) (xy 331.220032 -288.942199)
			(xy 331.177411 -288.917592) (xy 331.13929 -288.886467) (xy 331.106655 -288.84963) (xy 331.080352 -288.808034)
			(xy 331.061061 -288.762758) (xy 331.049284 -288.714974) (xy 331.045324 -288.66592) (xy 330.726796 -288.66592)
			(xy 330.726284 -288.691366) (xy 330.71812 -288.7416) (xy 330.702004 -288.789874) (xy 330.678353 -288.834937)
			(xy 330.64778 -288.875623) (xy 330.611076 -288.910878) (xy 330.569192 -288.939788) (xy 330.523213 -288.961605)
			(xy 330.474329 -288.975765) (xy 330.423808 -288.981899) (xy 330.372956 -288.97985) (xy 330.323092 -288.96967)
			(xy 330.275506 -288.951623) (xy 330.231432 -288.926177) (xy 330.19201 -288.89399) (xy 330.158262 -288.855896)
			(xy 330.131061 -288.812882) (xy 330.111113 -288.766062) (xy 330.098934 -288.716648) (xy 330.094839 -288.66592)
			(xy 329.786742 -288.66592) (xy 329.78623 -288.691366) (xy 329.778066 -288.7416) (xy 329.76195 -288.789874)
			(xy 329.738299 -288.834937) (xy 329.707726 -288.875623) (xy 329.671022 -288.910878) (xy 329.629138 -288.939788)
			(xy 329.583159 -288.961605) (xy 329.534275 -288.975765) (xy 329.483754 -288.981899) (xy 329.432902 -288.97985)
			(xy 329.383038 -288.96967) (xy 329.335452 -288.951623) (xy 329.291378 -288.926177) (xy 329.251956 -288.89399)
			(xy 329.218208 -288.855896) (xy 329.191007 -288.812882) (xy 329.171059 -288.766062) (xy 329.15888 -288.716648)
			(xy 329.154785 -288.66592) (xy 328.836528 -288.66592) (xy 328.836033 -288.690527) (xy 328.828138 -288.739104)
			(xy 328.812554 -288.785785) (xy 328.789683 -288.829362) (xy 328.760118 -288.868706) (xy 328.724625 -288.902798)
			(xy 328.684122 -288.930754) (xy 328.63966 -288.951852) (xy 328.592389 -288.965544) (xy 328.543534 -288.971476)
			(xy 328.494359 -288.969495) (xy 328.44614 -288.959651) (xy 328.400124 -288.942199) (xy 328.357503 -288.917592)
			(xy 328.319382 -288.886467) (xy 328.286747 -288.84963) (xy 328.260444 -288.808034) (xy 328.241153 -288.762758)
			(xy 328.229376 -288.714974) (xy 328.225416 -288.66592) (xy 326.95642 -288.66592) (xy 326.955925 -288.690527)
			(xy 326.94803 -288.739104) (xy 326.932446 -288.785785) (xy 326.909575 -288.829362) (xy 326.88001 -288.868706)
			(xy 326.844517 -288.902798) (xy 326.804014 -288.930754) (xy 326.759552 -288.951852) (xy 326.712281 -288.965544)
			(xy 326.663426 -288.971476) (xy 326.614251 -288.969495) (xy 326.566032 -288.959651) (xy 326.520016 -288.942199)
			(xy 326.477395 -288.917592) (xy 326.439274 -288.886467) (xy 326.406639 -288.84963) (xy 326.380336 -288.808034)
			(xy 326.361045 -288.762758) (xy 326.349268 -288.714974) (xy 326.345308 -288.66592) (xy 310.45912 -288.66592)
			(xy 310.45912 -289.209988) (xy 324.74714 -289.209988) (xy 324.7511 -289.160934) (xy 324.762877 -289.11315)
			(xy 324.782168 -289.067874) (xy 324.808471 -289.026278) (xy 324.841106 -288.989441) (xy 324.879227 -288.958316)
			(xy 324.921848 -288.933709) (xy 324.967864 -288.916257) (xy 325.016083 -288.906413) (xy 325.065258 -288.904432)
			(xy 325.114113 -288.910364) (xy 325.161384 -288.924056) (xy 325.205846 -288.945154) (xy 325.246349 -288.97311)
			(xy 325.281842 -289.007202) (xy 325.311407 -289.046546) (xy 325.334278 -289.090123) (xy 325.349862 -289.136804)
			(xy 325.357757 -289.185381) (xy 325.358252 -289.209988) (xy 325.357757 -289.234595) (xy 325.349862 -289.283172)
			(xy 325.334278 -289.329853) (xy 325.311407 -289.37343) (xy 325.281842 -289.412774) (xy 325.246349 -289.446866)
			(xy 325.205846 -289.474822) (xy 325.203519 -289.475926) (xy 327.755262 -289.475926) (xy 327.759222 -289.426872)
			(xy 327.770999 -289.379088) (xy 327.79029 -289.333812) (xy 327.816593 -289.292216) (xy 327.849228 -289.255379)
			(xy 327.887349 -289.224254) (xy 327.92997 -289.199647) (xy 327.975986 -289.182195) (xy 328.024205 -289.172351)
			(xy 328.07338 -289.17037) (xy 328.122235 -289.176302) (xy 328.169506 -289.189994) (xy 328.213968 -289.211092)
			(xy 328.254471 -289.239048) (xy 328.289964 -289.27314) (xy 328.319529 -289.312484) (xy 328.3424 -289.356061)
			(xy 328.357984 -289.402742) (xy 328.365879 -289.451319) (xy 328.366374 -289.475926) (xy 328.684885 -289.475926)
			(xy 328.68898 -289.425198) (xy 328.701159 -289.375784) (xy 328.721107 -289.328964) (xy 328.748308 -289.28595)
			(xy 328.782056 -289.247856) (xy 328.821478 -289.215669) (xy 328.865552 -289.190223) (xy 328.913138 -289.172176)
			(xy 328.963002 -289.161996) (xy 329.013854 -289.159947) (xy 329.064375 -289.166081) (xy 329.113259 -289.180241)
			(xy 329.159238 -289.202058) (xy 329.201122 -289.230968) (xy 329.237826 -289.266223) (xy 329.268399 -289.306909)
			(xy 329.29205 -289.351972) (xy 329.308166 -289.400246) (xy 329.31633 -289.45048) (xy 329.316842 -289.475926)
			(xy 329.63537 -289.475926) (xy 329.63933 -289.426872) (xy 329.651107 -289.379088) (xy 329.670398 -289.333812)
			(xy 329.696701 -289.292216) (xy 329.729336 -289.255379) (xy 329.767457 -289.224254) (xy 329.810078 -289.199647)
			(xy 329.856094 -289.182195) (xy 329.904313 -289.172351) (xy 329.953488 -289.17037) (xy 330.002343 -289.176302)
			(xy 330.049614 -289.189994) (xy 330.094076 -289.211092) (xy 330.134579 -289.239048) (xy 330.170072 -289.27314)
			(xy 330.199637 -289.312484) (xy 330.222508 -289.356061) (xy 330.238092 -289.402742) (xy 330.245987 -289.451319)
			(xy 330.246482 -289.475926) (xy 330.564739 -289.475926) (xy 330.568834 -289.425198) (xy 330.581013 -289.375784)
			(xy 330.600961 -289.328964) (xy 330.628162 -289.28595) (xy 330.66191 -289.247856) (xy 330.701332 -289.215669)
			(xy 330.745406 -289.190223) (xy 330.792992 -289.172176) (xy 330.842856 -289.161996) (xy 330.893708 -289.159947)
			(xy 330.944229 -289.166081) (xy 330.993113 -289.180241) (xy 331.039092 -289.202058) (xy 331.080976 -289.230968)
			(xy 331.11768 -289.266223) (xy 331.148253 -289.306909) (xy 331.171904 -289.351972) (xy 331.18802 -289.400246)
			(xy 331.196184 -289.45048) (xy 331.196696 -289.475926) (xy 331.515224 -289.475926) (xy 331.519184 -289.426872)
			(xy 331.530961 -289.379088) (xy 331.550252 -289.333812) (xy 331.576555 -289.292216) (xy 331.60919 -289.255379)
			(xy 331.647311 -289.224254) (xy 331.689932 -289.199647) (xy 331.735948 -289.182195) (xy 331.784167 -289.172351)
			(xy 331.833342 -289.17037) (xy 331.882197 -289.176302) (xy 331.929468 -289.189994) (xy 331.97393 -289.211092)
			(xy 332.014433 -289.239048) (xy 332.049926 -289.27314) (xy 332.079491 -289.312484) (xy 332.102362 -289.356061)
			(xy 332.117946 -289.402742) (xy 332.125841 -289.451319) (xy 332.126336 -289.475926) (xy 332.444847 -289.475926)
			(xy 332.448942 -289.425198) (xy 332.461121 -289.375784) (xy 332.481069 -289.328964) (xy 332.50827 -289.28595)
			(xy 332.542018 -289.247856) (xy 332.58144 -289.215669) (xy 332.625514 -289.190223) (xy 332.6731 -289.172176)
			(xy 332.722964 -289.161996) (xy 332.773816 -289.159947) (xy 332.824337 -289.166081) (xy 332.873221 -289.180241)
			(xy 332.9192 -289.202058) (xy 332.961084 -289.230968) (xy 332.997788 -289.266223) (xy 333.028361 -289.306909)
			(xy 333.052012 -289.351972) (xy 333.068128 -289.400246) (xy 333.076292 -289.45048) (xy 333.076804 -289.475926)
			(xy 333.384901 -289.475926) (xy 333.388996 -289.425198) (xy 333.401175 -289.375784) (xy 333.421123 -289.328964)
			(xy 333.448324 -289.28595) (xy 333.482072 -289.247856) (xy 333.521494 -289.215669) (xy 333.565568 -289.190223)
			(xy 333.613154 -289.172176) (xy 333.663018 -289.161996) (xy 333.71387 -289.159947) (xy 333.764391 -289.166081)
			(xy 333.813275 -289.180241) (xy 333.859254 -289.202058) (xy 333.901138 -289.230968) (xy 333.937842 -289.266223)
			(xy 333.968415 -289.306909) (xy 333.992066 -289.351972) (xy 334.008182 -289.400246) (xy 334.016346 -289.45048)
			(xy 334.016858 -289.475926) (xy 334.335386 -289.475926) (xy 334.339346 -289.426872) (xy 334.351123 -289.379088)
			(xy 334.370414 -289.333812) (xy 334.396717 -289.292216) (xy 334.429352 -289.255379) (xy 334.467473 -289.224254)
			(xy 334.510094 -289.199647) (xy 334.55611 -289.182195) (xy 334.604329 -289.172351) (xy 334.653504 -289.17037)
			(xy 334.702359 -289.176302) (xy 334.74963 -289.189994) (xy 334.794092 -289.211092) (xy 334.834595 -289.239048)
			(xy 334.870088 -289.27314) (xy 334.899653 -289.312484) (xy 334.922524 -289.356061) (xy 334.938108 -289.402742)
			(xy 334.946003 -289.451319) (xy 334.946498 -289.475926) (xy 335.264755 -289.475926) (xy 335.26885 -289.425198)
			(xy 335.281029 -289.375784) (xy 335.300977 -289.328964) (xy 335.328178 -289.28595) (xy 335.361926 -289.247856)
			(xy 335.401348 -289.215669) (xy 335.445422 -289.190223) (xy 335.493008 -289.172176) (xy 335.542872 -289.161996)
			(xy 335.593724 -289.159947) (xy 335.644245 -289.166081) (xy 335.693129 -289.180241) (xy 335.739108 -289.202058)
			(xy 335.780992 -289.230968) (xy 335.817696 -289.266223) (xy 335.848269 -289.306909) (xy 335.87192 -289.351972)
			(xy 335.888036 -289.400246) (xy 335.8962 -289.45048) (xy 335.896712 -289.475926) (xy 336.21524 -289.475926)
			(xy 336.2192 -289.426872) (xy 336.230977 -289.379088) (xy 336.250268 -289.333812) (xy 336.276571 -289.292216)
			(xy 336.309206 -289.255379) (xy 336.347327 -289.224254) (xy 336.389948 -289.199647) (xy 336.435964 -289.182195)
			(xy 336.484183 -289.172351) (xy 336.533358 -289.17037) (xy 336.582213 -289.176302) (xy 336.629484 -289.189994)
			(xy 336.673946 -289.211092) (xy 336.714449 -289.239048) (xy 336.749942 -289.27314) (xy 336.779507 -289.312484)
			(xy 336.802378 -289.356061) (xy 336.817962 -289.402742) (xy 336.825857 -289.451319) (xy 336.826352 -289.475926)
			(xy 337.144863 -289.475926) (xy 337.148958 -289.425198) (xy 337.161137 -289.375784) (xy 337.181085 -289.328964)
			(xy 337.208286 -289.28595) (xy 337.242034 -289.247856) (xy 337.281456 -289.215669) (xy 337.32553 -289.190223)
			(xy 337.373116 -289.172176) (xy 337.42298 -289.161996) (xy 337.473832 -289.159947) (xy 337.524353 -289.166081)
			(xy 337.573237 -289.180241) (xy 337.619216 -289.202058) (xy 337.6611 -289.230968) (xy 337.697804 -289.266223)
			(xy 337.728377 -289.306909) (xy 337.752028 -289.351972) (xy 337.768144 -289.400246) (xy 337.776308 -289.45048)
			(xy 337.77682 -289.475926) (xy 338.095348 -289.475926) (xy 338.099308 -289.426872) (xy 338.111085 -289.379088)
			(xy 338.130376 -289.333812) (xy 338.156679 -289.292216) (xy 338.189314 -289.255379) (xy 338.227435 -289.224254)
			(xy 338.270056 -289.199647) (xy 338.316072 -289.182195) (xy 338.364291 -289.172351) (xy 338.413466 -289.17037)
			(xy 338.462321 -289.176302) (xy 338.509592 -289.189994) (xy 338.554054 -289.211092) (xy 338.594557 -289.239048)
			(xy 338.63005 -289.27314) (xy 338.659615 -289.312484) (xy 338.682486 -289.356061) (xy 338.69807 -289.402742)
			(xy 338.705965 -289.451319) (xy 338.70646 -289.475926) (xy 339.024971 -289.475926) (xy 339.029066 -289.425198)
			(xy 339.041245 -289.375784) (xy 339.061193 -289.328964) (xy 339.088394 -289.28595) (xy 339.122142 -289.247856)
			(xy 339.161564 -289.215669) (xy 339.205638 -289.190223) (xy 339.253224 -289.172176) (xy 339.303088 -289.161996)
			(xy 339.35394 -289.159947) (xy 339.404461 -289.166081) (xy 339.453345 -289.180241) (xy 339.499324 -289.202058)
			(xy 339.541208 -289.230968) (xy 339.577912 -289.266223) (xy 339.608485 -289.306909) (xy 339.632136 -289.351972)
			(xy 339.648252 -289.400246) (xy 339.656416 -289.45048) (xy 339.656928 -289.475926) (xy 339.964771 -289.475926)
			(xy 339.968866 -289.425198) (xy 339.981045 -289.375784) (xy 340.000993 -289.328964) (xy 340.028194 -289.28595)
			(xy 340.061942 -289.247856) (xy 340.101364 -289.215669) (xy 340.145438 -289.190223) (xy 340.193024 -289.172176)
			(xy 340.242888 -289.161996) (xy 340.29374 -289.159947) (xy 340.344261 -289.166081) (xy 340.393145 -289.180241)
			(xy 340.439124 -289.202058) (xy 340.481008 -289.230968) (xy 340.517712 -289.266223) (xy 340.548285 -289.306909)
			(xy 340.571936 -289.351972) (xy 340.588052 -289.400246) (xy 340.596216 -289.45048) (xy 340.596728 -289.475926)
			(xy 340.915256 -289.475926) (xy 340.919216 -289.426872) (xy 340.930993 -289.379088) (xy 340.950284 -289.333812)
			(xy 340.976587 -289.292216) (xy 341.009222 -289.255379) (xy 341.047343 -289.224254) (xy 341.089964 -289.199647)
			(xy 341.13598 -289.182195) (xy 341.184199 -289.172351) (xy 341.233374 -289.17037) (xy 341.282229 -289.176302)
			(xy 341.3295 -289.189994) (xy 341.373962 -289.211092) (xy 341.414465 -289.239048) (xy 341.449958 -289.27314)
			(xy 341.479523 -289.312484) (xy 341.502394 -289.356061) (xy 341.517978 -289.402742) (xy 341.525873 -289.451319)
			(xy 341.526368 -289.475926) (xy 341.844879 -289.475926) (xy 341.848974 -289.425198) (xy 341.861153 -289.375784)
			(xy 341.881101 -289.328964) (xy 341.908302 -289.28595) (xy 341.94205 -289.247856) (xy 341.981472 -289.215669)
			(xy 342.025546 -289.190223) (xy 342.073132 -289.172176) (xy 342.122996 -289.161996) (xy 342.173848 -289.159947)
			(xy 342.224369 -289.166081) (xy 342.273253 -289.180241) (xy 342.319232 -289.202058) (xy 342.361116 -289.230968)
			(xy 342.39782 -289.266223) (xy 342.428393 -289.306909) (xy 342.452044 -289.351972) (xy 342.46816 -289.400246)
			(xy 342.476324 -289.45048) (xy 342.476836 -289.475926) (xy 342.795364 -289.475926) (xy 342.799324 -289.426872)
			(xy 342.811101 -289.379088) (xy 342.830392 -289.333812) (xy 342.856695 -289.292216) (xy 342.88933 -289.255379)
			(xy 342.927451 -289.224254) (xy 342.970072 -289.199647) (xy 343.016088 -289.182195) (xy 343.064307 -289.172351)
			(xy 343.113482 -289.17037) (xy 343.162337 -289.176302) (xy 343.209608 -289.189994) (xy 343.25407 -289.211092)
			(xy 343.294573 -289.239048) (xy 343.330066 -289.27314) (xy 343.359631 -289.312484) (xy 343.382502 -289.356061)
			(xy 343.398086 -289.402742) (xy 343.405981 -289.451319) (xy 343.406476 -289.475926) (xy 343.724987 -289.475926)
			(xy 343.729082 -289.425198) (xy 343.741261 -289.375784) (xy 343.761209 -289.328964) (xy 343.78841 -289.28595)
			(xy 343.822158 -289.247856) (xy 343.86158 -289.215669) (xy 343.905654 -289.190223) (xy 343.95324 -289.172176)
			(xy 344.003104 -289.161996) (xy 344.053956 -289.159947) (xy 344.104477 -289.166081) (xy 344.153361 -289.180241)
			(xy 344.19934 -289.202058) (xy 344.241224 -289.230968) (xy 344.277928 -289.266223) (xy 344.308501 -289.306909)
			(xy 344.332152 -289.351972) (xy 344.348268 -289.400246) (xy 344.356432 -289.45048) (xy 344.356944 -289.475926)
			(xy 344.675218 -289.475926) (xy 344.679178 -289.426872) (xy 344.690955 -289.379088) (xy 344.710246 -289.333812)
			(xy 344.736549 -289.292216) (xy 344.769184 -289.255379) (xy 344.807305 -289.224254) (xy 344.849926 -289.199647)
			(xy 344.895942 -289.182195) (xy 344.944161 -289.172351) (xy 344.993336 -289.17037) (xy 345.042191 -289.176302)
			(xy 345.089462 -289.189994) (xy 345.133924 -289.211092) (xy 345.174427 -289.239048) (xy 345.20992 -289.27314)
			(xy 345.239485 -289.312484) (xy 345.262356 -289.356061) (xy 345.27794 -289.402742) (xy 345.285835 -289.451319)
			(xy 345.28633 -289.475926) (xy 345.604841 -289.475926) (xy 345.608936 -289.425198) (xy 345.621115 -289.375784)
			(xy 345.641063 -289.328964) (xy 345.668264 -289.28595) (xy 345.702012 -289.247856) (xy 345.741434 -289.215669)
			(xy 345.785508 -289.190223) (xy 345.833094 -289.172176) (xy 345.882958 -289.161996) (xy 345.93381 -289.159947)
			(xy 345.984331 -289.166081) (xy 346.033215 -289.180241) (xy 346.079194 -289.202058) (xy 346.121078 -289.230968)
			(xy 346.157782 -289.266223) (xy 346.188355 -289.306909) (xy 346.212006 -289.351972) (xy 346.228122 -289.400246)
			(xy 346.236286 -289.45048) (xy 346.236798 -289.475926) (xy 346.544895 -289.475926) (xy 346.54899 -289.425198)
			(xy 346.561169 -289.375784) (xy 346.581117 -289.328964) (xy 346.608318 -289.28595) (xy 346.642066 -289.247856)
			(xy 346.681488 -289.215669) (xy 346.725562 -289.190223) (xy 346.773148 -289.172176) (xy 346.823012 -289.161996)
			(xy 346.873864 -289.159947) (xy 346.924385 -289.166081) (xy 346.973269 -289.180241) (xy 347.019248 -289.202058)
			(xy 347.061132 -289.230968) (xy 347.097836 -289.266223) (xy 347.128409 -289.306909) (xy 347.15206 -289.351972)
			(xy 347.168176 -289.400246) (xy 347.17634 -289.45048) (xy 347.176852 -289.475926) (xy 347.49538 -289.475926)
			(xy 347.49934 -289.426872) (xy 347.511117 -289.379088) (xy 347.530408 -289.333812) (xy 347.556711 -289.292216)
			(xy 347.589346 -289.255379) (xy 347.627467 -289.224254) (xy 347.670088 -289.199647) (xy 347.716104 -289.182195)
			(xy 347.764323 -289.172351) (xy 347.813498 -289.17037) (xy 347.862353 -289.176302) (xy 347.909624 -289.189994)
			(xy 347.954086 -289.211092) (xy 347.994589 -289.239048) (xy 348.030082 -289.27314) (xy 348.059647 -289.312484)
			(xy 348.082518 -289.356061) (xy 348.098102 -289.402742) (xy 348.105997 -289.451319) (xy 348.106492 -289.475926)
			(xy 348.425003 -289.475926) (xy 348.429098 -289.425198) (xy 348.441277 -289.375784) (xy 348.461225 -289.328964)
			(xy 348.488426 -289.28595) (xy 348.522174 -289.247856) (xy 348.561596 -289.215669) (xy 348.60567 -289.190223)
			(xy 348.653256 -289.172176) (xy 348.70312 -289.161996) (xy 348.753972 -289.159947) (xy 348.804493 -289.166081)
			(xy 348.853377 -289.180241) (xy 348.899356 -289.202058) (xy 348.94124 -289.230968) (xy 348.977944 -289.266223)
			(xy 349.008517 -289.306909) (xy 349.032168 -289.351972) (xy 349.048284 -289.400246) (xy 349.056448 -289.45048)
			(xy 349.05696 -289.475926) (xy 349.364803 -289.475926) (xy 349.368898 -289.425198) (xy 349.381077 -289.375784)
			(xy 349.401025 -289.328964) (xy 349.428226 -289.28595) (xy 349.461974 -289.247856) (xy 349.501396 -289.215669)
			(xy 349.54547 -289.190223) (xy 349.593056 -289.172176) (xy 349.64292 -289.161996) (xy 349.693772 -289.159947)
			(xy 349.744293 -289.166081) (xy 349.793177 -289.180241) (xy 349.839156 -289.202058) (xy 349.88104 -289.230968)
			(xy 349.917744 -289.266223) (xy 349.948317 -289.306909) (xy 349.971968 -289.351972) (xy 349.988084 -289.400246)
			(xy 349.996248 -289.45048) (xy 349.99676 -289.475926) (xy 350.315288 -289.475926) (xy 350.319248 -289.426872)
			(xy 350.331025 -289.379088) (xy 350.350316 -289.333812) (xy 350.376619 -289.292216) (xy 350.409254 -289.255379)
			(xy 350.447375 -289.224254) (xy 350.489996 -289.199647) (xy 350.536012 -289.182195) (xy 350.584231 -289.172351)
			(xy 350.633406 -289.17037) (xy 350.682261 -289.176302) (xy 350.729532 -289.189994) (xy 350.773994 -289.211092)
			(xy 350.814497 -289.239048) (xy 350.84999 -289.27314) (xy 350.879555 -289.312484) (xy 350.902426 -289.356061)
			(xy 350.91801 -289.402742) (xy 350.925905 -289.451319) (xy 350.9264 -289.475926) (xy 350.925905 -289.500533)
			(xy 350.91801 -289.54911) (xy 350.902426 -289.595791) (xy 350.879555 -289.639368) (xy 350.84999 -289.678712)
			(xy 350.814497 -289.712804) (xy 350.773994 -289.74076) (xy 350.729532 -289.761858) (xy 350.682261 -289.77555)
			(xy 350.633406 -289.781482) (xy 350.584231 -289.779501) (xy 350.536012 -289.769657) (xy 350.489996 -289.752205)
			(xy 350.447375 -289.727598) (xy 350.409254 -289.696473) (xy 350.376619 -289.659636) (xy 350.350316 -289.61804)
			(xy 350.331025 -289.572764) (xy 350.319248 -289.52498) (xy 350.315288 -289.475926) (xy 349.99676 -289.475926)
			(xy 349.996248 -289.501372) (xy 349.988084 -289.551606) (xy 349.971968 -289.59988) (xy 349.948317 -289.644943)
			(xy 349.917744 -289.685629) (xy 349.88104 -289.720884) (xy 349.839156 -289.749794) (xy 349.793177 -289.771611)
			(xy 349.744293 -289.785771) (xy 349.693772 -289.791905) (xy 349.64292 -289.789856) (xy 349.593056 -289.779676)
			(xy 349.54547 -289.761629) (xy 349.501396 -289.736183) (xy 349.461974 -289.703996) (xy 349.428226 -289.665902)
			(xy 349.401025 -289.622888) (xy 349.381077 -289.576068) (xy 349.368898 -289.526654) (xy 349.364803 -289.475926)
			(xy 349.05696 -289.475926) (xy 349.056448 -289.501372) (xy 349.048284 -289.551606) (xy 349.032168 -289.59988)
			(xy 349.008517 -289.644943) (xy 348.977944 -289.685629) (xy 348.94124 -289.720884) (xy 348.899356 -289.749794)
			(xy 348.853377 -289.771611) (xy 348.804493 -289.785771) (xy 348.753972 -289.791905) (xy 348.70312 -289.789856)
			(xy 348.653256 -289.779676) (xy 348.60567 -289.761629) (xy 348.561596 -289.736183) (xy 348.522174 -289.703996)
			(xy 348.488426 -289.665902) (xy 348.461225 -289.622888) (xy 348.441277 -289.576068) (xy 348.429098 -289.526654)
			(xy 348.425003 -289.475926) (xy 348.106492 -289.475926) (xy 348.105997 -289.500533) (xy 348.098102 -289.54911)
			(xy 348.082518 -289.595791) (xy 348.059647 -289.639368) (xy 348.030082 -289.678712) (xy 347.994589 -289.712804)
			(xy 347.954086 -289.74076) (xy 347.909624 -289.761858) (xy 347.862353 -289.77555) (xy 347.813498 -289.781482)
			(xy 347.764323 -289.779501) (xy 347.716104 -289.769657) (xy 347.670088 -289.752205) (xy 347.627467 -289.727598)
			(xy 347.589346 -289.696473) (xy 347.556711 -289.659636) (xy 347.530408 -289.61804) (xy 347.511117 -289.572764)
			(xy 347.49934 -289.52498) (xy 347.49538 -289.475926) (xy 347.176852 -289.475926) (xy 347.17634 -289.501372)
			(xy 347.168176 -289.551606) (xy 347.15206 -289.59988) (xy 347.128409 -289.644943) (xy 347.097836 -289.685629)
			(xy 347.061132 -289.720884) (xy 347.019248 -289.749794) (xy 346.973269 -289.771611) (xy 346.924385 -289.785771)
			(xy 346.873864 -289.791905) (xy 346.823012 -289.789856) (xy 346.773148 -289.779676) (xy 346.725562 -289.761629)
			(xy 346.681488 -289.736183) (xy 346.642066 -289.703996) (xy 346.608318 -289.665902) (xy 346.581117 -289.622888)
			(xy 346.561169 -289.576068) (xy 346.54899 -289.526654) (xy 346.544895 -289.475926) (xy 346.236798 -289.475926)
			(xy 346.236286 -289.501372) (xy 346.228122 -289.551606) (xy 346.212006 -289.59988) (xy 346.188355 -289.644943)
			(xy 346.157782 -289.685629) (xy 346.121078 -289.720884) (xy 346.079194 -289.749794) (xy 346.033215 -289.771611)
			(xy 345.984331 -289.785771) (xy 345.93381 -289.791905) (xy 345.882958 -289.789856) (xy 345.833094 -289.779676)
			(xy 345.785508 -289.761629) (xy 345.741434 -289.736183) (xy 345.702012 -289.703996) (xy 345.668264 -289.665902)
			(xy 345.641063 -289.622888) (xy 345.621115 -289.576068) (xy 345.608936 -289.526654) (xy 345.604841 -289.475926)
			(xy 345.28633 -289.475926) (xy 345.285835 -289.500533) (xy 345.27794 -289.54911) (xy 345.262356 -289.595791)
			(xy 345.239485 -289.639368) (xy 345.20992 -289.678712) (xy 345.174427 -289.712804) (xy 345.133924 -289.74076)
			(xy 345.089462 -289.761858) (xy 345.042191 -289.77555) (xy 344.993336 -289.781482) (xy 344.944161 -289.779501)
			(xy 344.895942 -289.769657) (xy 344.849926 -289.752205) (xy 344.807305 -289.727598) (xy 344.769184 -289.696473)
			(xy 344.736549 -289.659636) (xy 344.710246 -289.61804) (xy 344.690955 -289.572764) (xy 344.679178 -289.52498)
			(xy 344.675218 -289.475926) (xy 344.356944 -289.475926) (xy 344.356432 -289.501372) (xy 344.348268 -289.551606)
			(xy 344.332152 -289.59988) (xy 344.308501 -289.644943) (xy 344.277928 -289.685629) (xy 344.241224 -289.720884)
			(xy 344.19934 -289.749794) (xy 344.153361 -289.771611) (xy 344.104477 -289.785771) (xy 344.053956 -289.791905)
			(xy 344.003104 -289.789856) (xy 343.95324 -289.779676) (xy 343.905654 -289.761629) (xy 343.86158 -289.736183)
			(xy 343.822158 -289.703996) (xy 343.78841 -289.665902) (xy 343.761209 -289.622888) (xy 343.741261 -289.576068)
			(xy 343.729082 -289.526654) (xy 343.724987 -289.475926) (xy 343.406476 -289.475926) (xy 343.405981 -289.500533)
			(xy 343.398086 -289.54911) (xy 343.382502 -289.595791) (xy 343.359631 -289.639368) (xy 343.330066 -289.678712)
			(xy 343.294573 -289.712804) (xy 343.25407 -289.74076) (xy 343.209608 -289.761858) (xy 343.162337 -289.77555)
			(xy 343.113482 -289.781482) (xy 343.064307 -289.779501) (xy 343.016088 -289.769657) (xy 342.970072 -289.752205)
			(xy 342.927451 -289.727598) (xy 342.88933 -289.696473) (xy 342.856695 -289.659636) (xy 342.830392 -289.61804)
			(xy 342.811101 -289.572764) (xy 342.799324 -289.52498) (xy 342.795364 -289.475926) (xy 342.476836 -289.475926)
			(xy 342.476324 -289.501372) (xy 342.46816 -289.551606) (xy 342.452044 -289.59988) (xy 342.428393 -289.644943)
			(xy 342.39782 -289.685629) (xy 342.361116 -289.720884) (xy 342.319232 -289.749794) (xy 342.273253 -289.771611)
			(xy 342.224369 -289.785771) (xy 342.173848 -289.791905) (xy 342.122996 -289.789856) (xy 342.073132 -289.779676)
			(xy 342.025546 -289.761629) (xy 341.981472 -289.736183) (xy 341.94205 -289.703996) (xy 341.908302 -289.665902)
			(xy 341.881101 -289.622888) (xy 341.861153 -289.576068) (xy 341.848974 -289.526654) (xy 341.844879 -289.475926)
			(xy 341.526368 -289.475926) (xy 341.525873 -289.500533) (xy 341.517978 -289.54911) (xy 341.502394 -289.595791)
			(xy 341.479523 -289.639368) (xy 341.449958 -289.678712) (xy 341.414465 -289.712804) (xy 341.373962 -289.74076)
			(xy 341.3295 -289.761858) (xy 341.282229 -289.77555) (xy 341.233374 -289.781482) (xy 341.184199 -289.779501)
			(xy 341.13598 -289.769657) (xy 341.089964 -289.752205) (xy 341.047343 -289.727598) (xy 341.009222 -289.696473)
			(xy 340.976587 -289.659636) (xy 340.950284 -289.61804) (xy 340.930993 -289.572764) (xy 340.919216 -289.52498)
			(xy 340.915256 -289.475926) (xy 340.596728 -289.475926) (xy 340.596216 -289.501372) (xy 340.588052 -289.551606)
			(xy 340.571936 -289.59988) (xy 340.548285 -289.644943) (xy 340.517712 -289.685629) (xy 340.481008 -289.720884)
			(xy 340.439124 -289.749794) (xy 340.393145 -289.771611) (xy 340.344261 -289.785771) (xy 340.29374 -289.791905)
			(xy 340.242888 -289.789856) (xy 340.193024 -289.779676) (xy 340.145438 -289.761629) (xy 340.101364 -289.736183)
			(xy 340.061942 -289.703996) (xy 340.028194 -289.665902) (xy 340.000993 -289.622888) (xy 339.981045 -289.576068)
			(xy 339.968866 -289.526654) (xy 339.964771 -289.475926) (xy 339.656928 -289.475926) (xy 339.656416 -289.501372)
			(xy 339.648252 -289.551606) (xy 339.632136 -289.59988) (xy 339.608485 -289.644943) (xy 339.577912 -289.685629)
			(xy 339.541208 -289.720884) (xy 339.499324 -289.749794) (xy 339.453345 -289.771611) (xy 339.404461 -289.785771)
			(xy 339.35394 -289.791905) (xy 339.303088 -289.789856) (xy 339.253224 -289.779676) (xy 339.205638 -289.761629)
			(xy 339.161564 -289.736183) (xy 339.122142 -289.703996) (xy 339.088394 -289.665902) (xy 339.061193 -289.622888)
			(xy 339.041245 -289.576068) (xy 339.029066 -289.526654) (xy 339.024971 -289.475926) (xy 338.70646 -289.475926)
			(xy 338.705965 -289.500533) (xy 338.69807 -289.54911) (xy 338.682486 -289.595791) (xy 338.659615 -289.639368)
			(xy 338.63005 -289.678712) (xy 338.594557 -289.712804) (xy 338.554054 -289.74076) (xy 338.509592 -289.761858)
			(xy 338.462321 -289.77555) (xy 338.413466 -289.781482) (xy 338.364291 -289.779501) (xy 338.316072 -289.769657)
			(xy 338.270056 -289.752205) (xy 338.227435 -289.727598) (xy 338.189314 -289.696473) (xy 338.156679 -289.659636)
			(xy 338.130376 -289.61804) (xy 338.111085 -289.572764) (xy 338.099308 -289.52498) (xy 338.095348 -289.475926)
			(xy 337.77682 -289.475926) (xy 337.776308 -289.501372) (xy 337.768144 -289.551606) (xy 337.752028 -289.59988)
			(xy 337.728377 -289.644943) (xy 337.697804 -289.685629) (xy 337.6611 -289.720884) (xy 337.619216 -289.749794)
			(xy 337.573237 -289.771611) (xy 337.524353 -289.785771) (xy 337.473832 -289.791905) (xy 337.42298 -289.789856)
			(xy 337.373116 -289.779676) (xy 337.32553 -289.761629) (xy 337.281456 -289.736183) (xy 337.242034 -289.703996)
			(xy 337.208286 -289.665902) (xy 337.181085 -289.622888) (xy 337.161137 -289.576068) (xy 337.148958 -289.526654)
			(xy 337.144863 -289.475926) (xy 336.826352 -289.475926) (xy 336.825857 -289.500533) (xy 336.817962 -289.54911)
			(xy 336.802378 -289.595791) (xy 336.779507 -289.639368) (xy 336.749942 -289.678712) (xy 336.714449 -289.712804)
			(xy 336.673946 -289.74076) (xy 336.629484 -289.761858) (xy 336.582213 -289.77555) (xy 336.533358 -289.781482)
			(xy 336.484183 -289.779501) (xy 336.435964 -289.769657) (xy 336.389948 -289.752205) (xy 336.347327 -289.727598)
			(xy 336.309206 -289.696473) (xy 336.276571 -289.659636) (xy 336.250268 -289.61804) (xy 336.230977 -289.572764)
			(xy 336.2192 -289.52498) (xy 336.21524 -289.475926) (xy 335.896712 -289.475926) (xy 335.8962 -289.501372)
			(xy 335.888036 -289.551606) (xy 335.87192 -289.59988) (xy 335.848269 -289.644943) (xy 335.817696 -289.685629)
			(xy 335.780992 -289.720884) (xy 335.739108 -289.749794) (xy 335.693129 -289.771611) (xy 335.644245 -289.785771)
			(xy 335.593724 -289.791905) (xy 335.542872 -289.789856) (xy 335.493008 -289.779676) (xy 335.445422 -289.761629)
			(xy 335.401348 -289.736183) (xy 335.361926 -289.703996) (xy 335.328178 -289.665902) (xy 335.300977 -289.622888)
			(xy 335.281029 -289.576068) (xy 335.26885 -289.526654) (xy 335.264755 -289.475926) (xy 334.946498 -289.475926)
			(xy 334.946003 -289.500533) (xy 334.938108 -289.54911) (xy 334.922524 -289.595791) (xy 334.899653 -289.639368)
			(xy 334.870088 -289.678712) (xy 334.834595 -289.712804) (xy 334.794092 -289.74076) (xy 334.74963 -289.761858)
			(xy 334.702359 -289.77555) (xy 334.653504 -289.781482) (xy 334.604329 -289.779501) (xy 334.55611 -289.769657)
			(xy 334.510094 -289.752205) (xy 334.467473 -289.727598) (xy 334.429352 -289.696473) (xy 334.396717 -289.659636)
			(xy 334.370414 -289.61804) (xy 334.351123 -289.572764) (xy 334.339346 -289.52498) (xy 334.335386 -289.475926)
			(xy 334.016858 -289.475926) (xy 334.016346 -289.501372) (xy 334.008182 -289.551606) (xy 333.992066 -289.59988)
			(xy 333.968415 -289.644943) (xy 333.937842 -289.685629) (xy 333.901138 -289.720884) (xy 333.859254 -289.749794)
			(xy 333.813275 -289.771611) (xy 333.764391 -289.785771) (xy 333.71387 -289.791905) (xy 333.663018 -289.789856)
			(xy 333.613154 -289.779676) (xy 333.565568 -289.761629) (xy 333.521494 -289.736183) (xy 333.482072 -289.703996)
			(xy 333.448324 -289.665902) (xy 333.421123 -289.622888) (xy 333.401175 -289.576068) (xy 333.388996 -289.526654)
			(xy 333.384901 -289.475926) (xy 333.076804 -289.475926) (xy 333.076292 -289.501372) (xy 333.068128 -289.551606)
			(xy 333.052012 -289.59988) (xy 333.028361 -289.644943) (xy 332.997788 -289.685629) (xy 332.961084 -289.720884)
			(xy 332.9192 -289.749794) (xy 332.873221 -289.771611) (xy 332.824337 -289.785771) (xy 332.773816 -289.791905)
			(xy 332.722964 -289.789856) (xy 332.6731 -289.779676) (xy 332.625514 -289.761629) (xy 332.58144 -289.736183)
			(xy 332.542018 -289.703996) (xy 332.50827 -289.665902) (xy 332.481069 -289.622888) (xy 332.461121 -289.576068)
			(xy 332.448942 -289.526654) (xy 332.444847 -289.475926) (xy 332.126336 -289.475926) (xy 332.125841 -289.500533)
			(xy 332.117946 -289.54911) (xy 332.102362 -289.595791) (xy 332.079491 -289.639368) (xy 332.049926 -289.678712)
			(xy 332.014433 -289.712804) (xy 331.97393 -289.74076) (xy 331.929468 -289.761858) (xy 331.882197 -289.77555)
			(xy 331.833342 -289.781482) (xy 331.784167 -289.779501) (xy 331.735948 -289.769657) (xy 331.689932 -289.752205)
			(xy 331.647311 -289.727598) (xy 331.60919 -289.696473) (xy 331.576555 -289.659636) (xy 331.550252 -289.61804)
			(xy 331.530961 -289.572764) (xy 331.519184 -289.52498) (xy 331.515224 -289.475926) (xy 331.196696 -289.475926)
			(xy 331.196184 -289.501372) (xy 331.18802 -289.551606) (xy 331.171904 -289.59988) (xy 331.148253 -289.644943)
			(xy 331.11768 -289.685629) (xy 331.080976 -289.720884) (xy 331.039092 -289.749794) (xy 330.993113 -289.771611)
			(xy 330.944229 -289.785771) (xy 330.893708 -289.791905) (xy 330.842856 -289.789856) (xy 330.792992 -289.779676)
			(xy 330.745406 -289.761629) (xy 330.701332 -289.736183) (xy 330.66191 -289.703996) (xy 330.628162 -289.665902)
			(xy 330.600961 -289.622888) (xy 330.581013 -289.576068) (xy 330.568834 -289.526654) (xy 330.564739 -289.475926)
			(xy 330.246482 -289.475926) (xy 330.245987 -289.500533) (xy 330.238092 -289.54911) (xy 330.222508 -289.595791)
			(xy 330.199637 -289.639368) (xy 330.170072 -289.678712) (xy 330.134579 -289.712804) (xy 330.094076 -289.74076)
			(xy 330.049614 -289.761858) (xy 330.002343 -289.77555) (xy 329.953488 -289.781482) (xy 329.904313 -289.779501)
			(xy 329.856094 -289.769657) (xy 329.810078 -289.752205) (xy 329.767457 -289.727598) (xy 329.729336 -289.696473)
			(xy 329.696701 -289.659636) (xy 329.670398 -289.61804) (xy 329.651107 -289.572764) (xy 329.63933 -289.52498)
			(xy 329.63537 -289.475926) (xy 329.316842 -289.475926) (xy 329.31633 -289.501372) (xy 329.308166 -289.551606)
			(xy 329.29205 -289.59988) (xy 329.268399 -289.644943) (xy 329.237826 -289.685629) (xy 329.201122 -289.720884)
			(xy 329.159238 -289.749794) (xy 329.113259 -289.771611) (xy 329.064375 -289.785771) (xy 329.013854 -289.791905)
			(xy 328.963002 -289.789856) (xy 328.913138 -289.779676) (xy 328.865552 -289.761629) (xy 328.821478 -289.736183)
			(xy 328.782056 -289.703996) (xy 328.748308 -289.665902) (xy 328.721107 -289.622888) (xy 328.701159 -289.576068)
			(xy 328.68898 -289.526654) (xy 328.684885 -289.475926) (xy 328.366374 -289.475926) (xy 328.365879 -289.500533)
			(xy 328.357984 -289.54911) (xy 328.3424 -289.595791) (xy 328.319529 -289.639368) (xy 328.289964 -289.678712)
			(xy 328.254471 -289.712804) (xy 328.213968 -289.74076) (xy 328.169506 -289.761858) (xy 328.122235 -289.77555)
			(xy 328.07338 -289.781482) (xy 328.024205 -289.779501) (xy 327.975986 -289.769657) (xy 327.92997 -289.752205)
			(xy 327.887349 -289.727598) (xy 327.849228 -289.696473) (xy 327.816593 -289.659636) (xy 327.79029 -289.61804)
			(xy 327.770999 -289.572764) (xy 327.759222 -289.52498) (xy 327.755262 -289.475926) (xy 325.203519 -289.475926)
			(xy 325.161384 -289.49592) (xy 325.114113 -289.509612) (xy 325.065258 -289.515544) (xy 325.016083 -289.513563)
			(xy 324.967864 -289.503719) (xy 324.921848 -289.486267) (xy 324.879227 -289.46166) (xy 324.841106 -289.430535)
			(xy 324.808471 -289.393698) (xy 324.782168 -289.352102) (xy 324.762877 -289.306826) (xy 324.7511 -289.259042)
			(xy 324.74714 -289.209988) (xy 310.45912 -289.209988) (xy 310.45912 -290.285932) (xy 326.345308 -290.285932)
			(xy 326.349268 -290.236878) (xy 326.361045 -290.189094) (xy 326.380336 -290.143818) (xy 326.406639 -290.102222)
			(xy 326.439274 -290.065385) (xy 326.477395 -290.03426) (xy 326.520016 -290.009653) (xy 326.566032 -289.992201)
			(xy 326.614251 -289.982357) (xy 326.663426 -289.980376) (xy 326.712281 -289.986308) (xy 326.759552 -290)
			(xy 326.804014 -290.021098) (xy 326.844517 -290.049054) (xy 326.88001 -290.083146) (xy 326.909575 -290.12249)
			(xy 326.932446 -290.166067) (xy 326.94803 -290.212748) (xy 326.955925 -290.261325) (xy 326.95642 -290.285932)
			(xy 329.154785 -290.285932) (xy 329.15888 -290.235204) (xy 329.171059 -290.18579) (xy 329.191007 -290.13897)
			(xy 329.218208 -290.095956) (xy 329.251956 -290.057862) (xy 329.291378 -290.025675) (xy 329.335452 -290.000229)
			(xy 329.383038 -289.982182) (xy 329.432902 -289.972002) (xy 329.483754 -289.969953) (xy 329.534275 -289.976087)
			(xy 329.583159 -289.990247) (xy 329.629138 -290.012064) (xy 329.671022 -290.040974) (xy 329.707726 -290.076229)
			(xy 329.738299 -290.116915) (xy 329.76195 -290.161978) (xy 329.778066 -290.210252) (xy 329.78623 -290.260486)
			(xy 329.786742 -290.285932) (xy 330.094839 -290.285932) (xy 330.098934 -290.235204) (xy 330.111113 -290.18579)
			(xy 330.131061 -290.13897) (xy 330.158262 -290.095956) (xy 330.19201 -290.057862) (xy 330.231432 -290.025675)
			(xy 330.275506 -290.000229) (xy 330.323092 -289.982182) (xy 330.372956 -289.972002) (xy 330.423808 -289.969953)
			(xy 330.474329 -289.976087) (xy 330.523213 -289.990247) (xy 330.569192 -290.012064) (xy 330.611076 -290.040974)
			(xy 330.64778 -290.076229) (xy 330.678353 -290.116915) (xy 330.702004 -290.161978) (xy 330.71812 -290.210252)
			(xy 330.726284 -290.260486) (xy 330.726796 -290.285932) (xy 331.045324 -290.285932) (xy 331.049284 -290.236878)
			(xy 331.061061 -290.189094) (xy 331.080352 -290.143818) (xy 331.106655 -290.102222) (xy 331.13929 -290.065385)
			(xy 331.177411 -290.03426) (xy 331.220032 -290.009653) (xy 331.266048 -289.992201) (xy 331.314267 -289.982357)
			(xy 331.363442 -289.980376) (xy 331.412297 -289.986308) (xy 331.459568 -290) (xy 331.50403 -290.021098)
			(xy 331.544533 -290.049054) (xy 331.580026 -290.083146) (xy 331.609591 -290.12249) (xy 331.632462 -290.166067)
			(xy 331.648046 -290.212748) (xy 331.655941 -290.261325) (xy 331.656436 -290.285932) (xy 331.974947 -290.285932)
			(xy 331.979042 -290.235204) (xy 331.991221 -290.18579) (xy 332.011169 -290.13897) (xy 332.03837 -290.095956)
			(xy 332.072118 -290.057862) (xy 332.11154 -290.025675) (xy 332.155614 -290.000229) (xy 332.2032 -289.982182)
			(xy 332.253064 -289.972002) (xy 332.303916 -289.969953) (xy 332.354437 -289.976087) (xy 332.403321 -289.990247)
			(xy 332.4493 -290.012064) (xy 332.491184 -290.040974) (xy 332.527888 -290.076229) (xy 332.558461 -290.116915)
			(xy 332.582112 -290.161978) (xy 332.598228 -290.210252) (xy 332.606392 -290.260486) (xy 332.606904 -290.285932)
			(xy 332.925178 -290.285932) (xy 332.929138 -290.236878) (xy 332.940915 -290.189094) (xy 332.960206 -290.143818)
			(xy 332.986509 -290.102222) (xy 333.019144 -290.065385) (xy 333.057265 -290.03426) (xy 333.099886 -290.009653)
			(xy 333.145902 -289.992201) (xy 333.194121 -289.982357) (xy 333.243296 -289.980376) (xy 333.292151 -289.986308)
			(xy 333.339422 -290) (xy 333.383884 -290.021098) (xy 333.424387 -290.049054) (xy 333.45988 -290.083146)
			(xy 333.489445 -290.12249) (xy 333.512316 -290.166067) (xy 333.5279 -290.212748) (xy 333.535795 -290.261325)
			(xy 333.53629 -290.285932) (xy 333.854801 -290.285932) (xy 333.858896 -290.235204) (xy 333.871075 -290.18579)
			(xy 333.891023 -290.13897) (xy 333.918224 -290.095956) (xy 333.951972 -290.057862) (xy 333.991394 -290.025675)
			(xy 334.035468 -290.000229) (xy 334.083054 -289.982182) (xy 334.132918 -289.972002) (xy 334.18377 -289.969953)
			(xy 334.234291 -289.976087) (xy 334.283175 -289.990247) (xy 334.329154 -290.012064) (xy 334.371038 -290.040974)
			(xy 334.407742 -290.076229) (xy 334.438315 -290.116915) (xy 334.461966 -290.161978) (xy 334.478082 -290.210252)
			(xy 334.486246 -290.260486) (xy 334.486758 -290.285932) (xy 335.734909 -290.285932) (xy 335.739004 -290.235204)
			(xy 335.751183 -290.18579) (xy 335.771131 -290.13897) (xy 335.798332 -290.095956) (xy 335.83208 -290.057862)
			(xy 335.871502 -290.025675) (xy 335.915576 -290.000229) (xy 335.963162 -289.982182) (xy 336.013026 -289.972002)
			(xy 336.063878 -289.969953) (xy 336.114399 -289.976087) (xy 336.163283 -289.990247) (xy 336.209262 -290.012064)
			(xy 336.251146 -290.040974) (xy 336.28785 -290.076229) (xy 336.318423 -290.116915) (xy 336.342074 -290.161978)
			(xy 336.35819 -290.210252) (xy 336.366354 -290.260486) (xy 336.366866 -290.285932) (xy 336.674963 -290.285932)
			(xy 336.679058 -290.235204) (xy 336.691237 -290.18579) (xy 336.711185 -290.13897) (xy 336.738386 -290.095956)
			(xy 336.772134 -290.057862) (xy 336.811556 -290.025675) (xy 336.85563 -290.000229) (xy 336.903216 -289.982182)
			(xy 336.95308 -289.972002) (xy 337.003932 -289.969953) (xy 337.054453 -289.976087) (xy 337.103337 -289.990247)
			(xy 337.149316 -290.012064) (xy 337.1912 -290.040974) (xy 337.227904 -290.076229) (xy 337.258477 -290.116915)
			(xy 337.282128 -290.161978) (xy 337.298244 -290.210252) (xy 337.306408 -290.260486) (xy 337.30692 -290.285932)
			(xy 337.625194 -290.285932) (xy 337.629154 -290.236878) (xy 337.640931 -290.189094) (xy 337.660222 -290.143818)
			(xy 337.686525 -290.102222) (xy 337.71916 -290.065385) (xy 337.757281 -290.03426) (xy 337.799902 -290.009653)
			(xy 337.845918 -289.992201) (xy 337.894137 -289.982357) (xy 337.943312 -289.980376) (xy 337.992167 -289.986308)
			(xy 338.039438 -290) (xy 338.0839 -290.021098) (xy 338.124403 -290.049054) (xy 338.159896 -290.083146)
			(xy 338.189461 -290.12249) (xy 338.212332 -290.166067) (xy 338.227916 -290.212748) (xy 338.235811 -290.261325)
			(xy 338.236306 -290.285932) (xy 338.554817 -290.285932) (xy 338.558912 -290.235204) (xy 338.571091 -290.18579)
			(xy 338.591039 -290.13897) (xy 338.61824 -290.095956) (xy 338.651988 -290.057862) (xy 338.69141 -290.025675)
			(xy 338.735484 -290.000229) (xy 338.78307 -289.982182) (xy 338.832934 -289.972002) (xy 338.883786 -289.969953)
			(xy 338.934307 -289.976087) (xy 338.983191 -289.990247) (xy 339.02917 -290.012064) (xy 339.071054 -290.040974)
			(xy 339.107758 -290.076229) (xy 339.138331 -290.116915) (xy 339.161982 -290.161978) (xy 339.178098 -290.210252)
			(xy 339.186262 -290.260486) (xy 339.186774 -290.285932) (xy 339.505302 -290.285932) (xy 339.509262 -290.236878)
			(xy 339.521039 -290.189094) (xy 339.54033 -290.143818) (xy 339.566633 -290.102222) (xy 339.599268 -290.065385)
			(xy 339.637389 -290.03426) (xy 339.68001 -290.009653) (xy 339.726026 -289.992201) (xy 339.774245 -289.982357)
			(xy 339.82342 -289.980376) (xy 339.872275 -289.986308) (xy 339.919546 -290) (xy 339.964008 -290.021098)
			(xy 340.004511 -290.049054) (xy 340.040004 -290.083146) (xy 340.069569 -290.12249) (xy 340.09244 -290.166067)
			(xy 340.108024 -290.212748) (xy 340.115919 -290.261325) (xy 340.116414 -290.285932) (xy 340.434925 -290.285932)
			(xy 340.43902 -290.235204) (xy 340.451199 -290.18579) (xy 340.471147 -290.13897) (xy 340.498348 -290.095956)
			(xy 340.532096 -290.057862) (xy 340.571518 -290.025675) (xy 340.615592 -290.000229) (xy 340.663178 -289.982182)
			(xy 340.713042 -289.972002) (xy 340.763894 -289.969953) (xy 340.814415 -289.976087) (xy 340.863299 -289.990247)
			(xy 340.909278 -290.012064) (xy 340.951162 -290.040974) (xy 340.987866 -290.076229) (xy 341.018439 -290.116915)
			(xy 341.04209 -290.161978) (xy 341.058206 -290.210252) (xy 341.06637 -290.260486) (xy 341.066882 -290.285932)
			(xy 342.314779 -290.285932) (xy 342.318874 -290.235204) (xy 342.331053 -290.18579) (xy 342.351001 -290.13897)
			(xy 342.378202 -290.095956) (xy 342.41195 -290.057862) (xy 342.451372 -290.025675) (xy 342.495446 -290.000229)
			(xy 342.543032 -289.982182) (xy 342.592896 -289.972002) (xy 342.643748 -289.969953) (xy 342.694269 -289.976087)
			(xy 342.743153 -289.990247) (xy 342.789132 -290.012064) (xy 342.831016 -290.040974) (xy 342.86772 -290.076229)
			(xy 342.898293 -290.116915) (xy 342.921944 -290.161978) (xy 342.93806 -290.210252) (xy 342.946224 -290.260486)
			(xy 342.946736 -290.285932) (xy 343.254833 -290.285932) (xy 343.258928 -290.235204) (xy 343.271107 -290.18579)
			(xy 343.291055 -290.13897) (xy 343.318256 -290.095956) (xy 343.352004 -290.057862) (xy 343.391426 -290.025675)
			(xy 343.4355 -290.000229) (xy 343.483086 -289.982182) (xy 343.53295 -289.972002) (xy 343.583802 -289.969953)
			(xy 343.634323 -289.976087) (xy 343.683207 -289.990247) (xy 343.729186 -290.012064) (xy 343.77107 -290.040974)
			(xy 343.807774 -290.076229) (xy 343.838347 -290.116915) (xy 343.861998 -290.161978) (xy 343.878114 -290.210252)
			(xy 343.886278 -290.260486) (xy 343.88679 -290.285932) (xy 344.205318 -290.285932) (xy 344.209278 -290.236878)
			(xy 344.221055 -290.189094) (xy 344.240346 -290.143818) (xy 344.266649 -290.102222) (xy 344.299284 -290.065385)
			(xy 344.337405 -290.03426) (xy 344.380026 -290.009653) (xy 344.426042 -289.992201) (xy 344.474261 -289.982357)
			(xy 344.523436 -289.980376) (xy 344.572291 -289.986308) (xy 344.619562 -290) (xy 344.664024 -290.021098)
			(xy 344.704527 -290.049054) (xy 344.74002 -290.083146) (xy 344.769585 -290.12249) (xy 344.792456 -290.166067)
			(xy 344.80804 -290.212748) (xy 344.815935 -290.261325) (xy 344.81643 -290.285932) (xy 345.145372 -290.285932)
			(xy 345.149332 -290.236878) (xy 345.161109 -290.189094) (xy 345.1804 -290.143818) (xy 345.206703 -290.102222)
			(xy 345.239338 -290.065385) (xy 345.277459 -290.03426) (xy 345.32008 -290.009653) (xy 345.366096 -289.992201)
			(xy 345.414315 -289.982357) (xy 345.46349 -289.980376) (xy 345.512345 -289.986308) (xy 345.559616 -290)
			(xy 345.604078 -290.021098) (xy 345.644581 -290.049054) (xy 345.680074 -290.083146) (xy 345.709639 -290.12249)
			(xy 345.73251 -290.166067) (xy 345.748094 -290.212748) (xy 345.755989 -290.261325) (xy 345.756484 -290.285932)
			(xy 346.085426 -290.285932) (xy 346.089386 -290.236878) (xy 346.101163 -290.189094) (xy 346.120454 -290.143818)
			(xy 346.146757 -290.102222) (xy 346.179392 -290.065385) (xy 346.217513 -290.03426) (xy 346.260134 -290.009653)
			(xy 346.30615 -289.992201) (xy 346.354369 -289.982357) (xy 346.403544 -289.980376) (xy 346.452399 -289.986308)
			(xy 346.49967 -290) (xy 346.544132 -290.021098) (xy 346.584635 -290.049054) (xy 346.620128 -290.083146)
			(xy 346.649693 -290.12249) (xy 346.672564 -290.166067) (xy 346.688148 -290.212748) (xy 346.696043 -290.261325)
			(xy 346.696538 -290.285932) (xy 347.025226 -290.285932) (xy 347.029186 -290.236878) (xy 347.040963 -290.189094)
			(xy 347.060254 -290.143818) (xy 347.086557 -290.102222) (xy 347.119192 -290.065385) (xy 347.157313 -290.03426)
			(xy 347.199934 -290.009653) (xy 347.24595 -289.992201) (xy 347.294169 -289.982357) (xy 347.343344 -289.980376)
			(xy 347.392199 -289.986308) (xy 347.43947 -290) (xy 347.483932 -290.021098) (xy 347.524435 -290.049054)
			(xy 347.559928 -290.083146) (xy 347.589493 -290.12249) (xy 347.612364 -290.166067) (xy 347.627948 -290.212748)
			(xy 347.635843 -290.261325) (xy 347.636338 -290.285932) (xy 347.96528 -290.285932) (xy 347.96924 -290.236878)
			(xy 347.981017 -290.189094) (xy 348.000308 -290.143818) (xy 348.026611 -290.102222) (xy 348.059246 -290.065385)
			(xy 348.097367 -290.03426) (xy 348.139988 -290.009653) (xy 348.186004 -289.992201) (xy 348.234223 -289.982357)
			(xy 348.283398 -289.980376) (xy 348.332253 -289.986308) (xy 348.379524 -290) (xy 348.423986 -290.021098)
			(xy 348.464489 -290.049054) (xy 348.499982 -290.083146) (xy 348.529547 -290.12249) (xy 348.552418 -290.166067)
			(xy 348.568002 -290.212748) (xy 348.575897 -290.261325) (xy 348.576392 -290.285932) (xy 348.905334 -290.285932)
			(xy 348.909294 -290.236878) (xy 348.921071 -290.189094) (xy 348.940362 -290.143818) (xy 348.966665 -290.102222)
			(xy 348.9993 -290.065385) (xy 349.037421 -290.03426) (xy 349.080042 -290.009653) (xy 349.126058 -289.992201)
			(xy 349.174277 -289.982357) (xy 349.223452 -289.980376) (xy 349.272307 -289.986308) (xy 349.319578 -290)
			(xy 349.36404 -290.021098) (xy 349.404543 -290.049054) (xy 349.440036 -290.083146) (xy 349.469601 -290.12249)
			(xy 349.492472 -290.166067) (xy 349.508056 -290.212748) (xy 349.515951 -290.261325) (xy 349.516446 -290.285932)
			(xy 349.845388 -290.285932) (xy 349.849348 -290.236878) (xy 349.861125 -290.189094) (xy 349.880416 -290.143818)
			(xy 349.906719 -290.102222) (xy 349.939354 -290.065385) (xy 349.977475 -290.03426) (xy 350.020096 -290.009653)
			(xy 350.066112 -289.992201) (xy 350.114331 -289.982357) (xy 350.163506 -289.980376) (xy 350.212361 -289.986308)
			(xy 350.259632 -290) (xy 350.304094 -290.021098) (xy 350.344597 -290.049054) (xy 350.38009 -290.083146)
			(xy 350.409655 -290.12249) (xy 350.432526 -290.166067) (xy 350.44811 -290.212748) (xy 350.456005 -290.261325)
			(xy 350.4565 -290.285932) (xy 350.785442 -290.285932) (xy 350.789402 -290.236878) (xy 350.801179 -290.189094)
			(xy 350.82047 -290.143818) (xy 350.846773 -290.102222) (xy 350.879408 -290.065385) (xy 350.917529 -290.03426)
			(xy 350.96015 -290.009653) (xy 351.006166 -289.992201) (xy 351.054385 -289.982357) (xy 351.10356 -289.980376)
			(xy 351.152415 -289.986308) (xy 351.199686 -290) (xy 351.244148 -290.021098) (xy 351.284651 -290.049054)
			(xy 351.320144 -290.083146) (xy 351.349709 -290.12249) (xy 351.37258 -290.166067) (xy 351.388164 -290.212748)
			(xy 351.396059 -290.261325) (xy 351.396554 -290.285932) (xy 351.396059 -290.310539) (xy 351.388164 -290.359116)
			(xy 351.37258 -290.405797) (xy 351.349709 -290.449374) (xy 351.320144 -290.488718) (xy 351.284651 -290.52281)
			(xy 351.244148 -290.550766) (xy 351.199686 -290.571864) (xy 351.152415 -290.585556) (xy 351.10356 -290.591488)
			(xy 351.054385 -290.589507) (xy 351.006166 -290.579663) (xy 350.96015 -290.562211) (xy 350.917529 -290.537604)
			(xy 350.879408 -290.506479) (xy 350.846773 -290.469642) (xy 350.82047 -290.428046) (xy 350.801179 -290.38277)
			(xy 350.789402 -290.334986) (xy 350.785442 -290.285932) (xy 350.4565 -290.285932) (xy 350.456005 -290.310539)
			(xy 350.44811 -290.359116) (xy 350.432526 -290.405797) (xy 350.409655 -290.449374) (xy 350.38009 -290.488718)
			(xy 350.344597 -290.52281) (xy 350.304094 -290.550766) (xy 350.259632 -290.571864) (xy 350.212361 -290.585556)
			(xy 350.163506 -290.591488) (xy 350.114331 -290.589507) (xy 350.066112 -290.579663) (xy 350.020096 -290.562211)
			(xy 349.977475 -290.537604) (xy 349.939354 -290.506479) (xy 349.906719 -290.469642) (xy 349.880416 -290.428046)
			(xy 349.861125 -290.38277) (xy 349.849348 -290.334986) (xy 349.845388 -290.285932) (xy 349.516446 -290.285932)
			(xy 349.515951 -290.310539) (xy 349.508056 -290.359116) (xy 349.492472 -290.405797) (xy 349.469601 -290.449374)
			(xy 349.440036 -290.488718) (xy 349.404543 -290.52281) (xy 349.36404 -290.550766) (xy 349.319578 -290.571864)
			(xy 349.272307 -290.585556) (xy 349.223452 -290.591488) (xy 349.174277 -290.589507) (xy 349.126058 -290.579663)
			(xy 349.080042 -290.562211) (xy 349.037421 -290.537604) (xy 348.9993 -290.506479) (xy 348.966665 -290.469642)
			(xy 348.940362 -290.428046) (xy 348.921071 -290.38277) (xy 348.909294 -290.334986) (xy 348.905334 -290.285932)
			(xy 348.576392 -290.285932) (xy 348.575897 -290.310539) (xy 348.568002 -290.359116) (xy 348.552418 -290.405797)
			(xy 348.529547 -290.449374) (xy 348.499982 -290.488718) (xy 348.464489 -290.52281) (xy 348.423986 -290.550766)
			(xy 348.379524 -290.571864) (xy 348.332253 -290.585556) (xy 348.283398 -290.591488) (xy 348.234223 -290.589507)
			(xy 348.186004 -290.579663) (xy 348.139988 -290.562211) (xy 348.097367 -290.537604) (xy 348.059246 -290.506479)
			(xy 348.026611 -290.469642) (xy 348.000308 -290.428046) (xy 347.981017 -290.38277) (xy 347.96924 -290.334986)
			(xy 347.96528 -290.285932) (xy 347.636338 -290.285932) (xy 347.635843 -290.310539) (xy 347.627948 -290.359116)
			(xy 347.612364 -290.405797) (xy 347.589493 -290.449374) (xy 347.559928 -290.488718) (xy 347.524435 -290.52281)
			(xy 347.483932 -290.550766) (xy 347.43947 -290.571864) (xy 347.392199 -290.585556) (xy 347.343344 -290.591488)
			(xy 347.294169 -290.589507) (xy 347.24595 -290.579663) (xy 347.199934 -290.562211) (xy 347.157313 -290.537604)
			(xy 347.119192 -290.506479) (xy 347.086557 -290.469642) (xy 347.060254 -290.428046) (xy 347.040963 -290.38277)
			(xy 347.029186 -290.334986) (xy 347.025226 -290.285932) (xy 346.696538 -290.285932) (xy 346.696043 -290.310539)
			(xy 346.688148 -290.359116) (xy 346.672564 -290.405797) (xy 346.649693 -290.449374) (xy 346.620128 -290.488718)
			(xy 346.584635 -290.52281) (xy 346.544132 -290.550766) (xy 346.49967 -290.571864) (xy 346.452399 -290.585556)
			(xy 346.403544 -290.591488) (xy 346.354369 -290.589507) (xy 346.30615 -290.579663) (xy 346.260134 -290.562211)
			(xy 346.217513 -290.537604) (xy 346.179392 -290.506479) (xy 346.146757 -290.469642) (xy 346.120454 -290.428046)
			(xy 346.101163 -290.38277) (xy 346.089386 -290.334986) (xy 346.085426 -290.285932) (xy 345.756484 -290.285932)
			(xy 345.755989 -290.310539) (xy 345.748094 -290.359116) (xy 345.73251 -290.405797) (xy 345.709639 -290.449374)
			(xy 345.680074 -290.488718) (xy 345.644581 -290.52281) (xy 345.604078 -290.550766) (xy 345.559616 -290.571864)
			(xy 345.512345 -290.585556) (xy 345.46349 -290.591488) (xy 345.414315 -290.589507) (xy 345.366096 -290.579663)
			(xy 345.32008 -290.562211) (xy 345.277459 -290.537604) (xy 345.239338 -290.506479) (xy 345.206703 -290.469642)
			(xy 345.1804 -290.428046) (xy 345.161109 -290.38277) (xy 345.149332 -290.334986) (xy 345.145372 -290.285932)
			(xy 344.81643 -290.285932) (xy 344.815935 -290.310539) (xy 344.80804 -290.359116) (xy 344.792456 -290.405797)
			(xy 344.769585 -290.449374) (xy 344.74002 -290.488718) (xy 344.704527 -290.52281) (xy 344.664024 -290.550766)
			(xy 344.619562 -290.571864) (xy 344.572291 -290.585556) (xy 344.523436 -290.591488) (xy 344.474261 -290.589507)
			(xy 344.426042 -290.579663) (xy 344.380026 -290.562211) (xy 344.337405 -290.537604) (xy 344.299284 -290.506479)
			(xy 344.266649 -290.469642) (xy 344.240346 -290.428046) (xy 344.221055 -290.38277) (xy 344.209278 -290.334986)
			(xy 344.205318 -290.285932) (xy 343.88679 -290.285932) (xy 343.886278 -290.311378) (xy 343.878114 -290.361612)
			(xy 343.861998 -290.409886) (xy 343.838347 -290.454949) (xy 343.807774 -290.495635) (xy 343.77107 -290.53089)
			(xy 343.729186 -290.5598) (xy 343.683207 -290.581617) (xy 343.634323 -290.595777) (xy 343.583802 -290.601911)
			(xy 343.53295 -290.599862) (xy 343.483086 -290.589682) (xy 343.4355 -290.571635) (xy 343.391426 -290.546189)
			(xy 343.352004 -290.514002) (xy 343.318256 -290.475908) (xy 343.291055 -290.432894) (xy 343.271107 -290.386074)
			(xy 343.258928 -290.33666) (xy 343.254833 -290.285932) (xy 342.946736 -290.285932) (xy 342.946224 -290.311378)
			(xy 342.93806 -290.361612) (xy 342.921944 -290.409886) (xy 342.898293 -290.454949) (xy 342.86772 -290.495635)
			(xy 342.831016 -290.53089) (xy 342.789132 -290.5598) (xy 342.743153 -290.581617) (xy 342.694269 -290.595777)
			(xy 342.643748 -290.601911) (xy 342.592896 -290.599862) (xy 342.543032 -290.589682) (xy 342.495446 -290.571635)
			(xy 342.451372 -290.546189) (xy 342.41195 -290.514002) (xy 342.378202 -290.475908) (xy 342.351001 -290.432894)
			(xy 342.331053 -290.386074) (xy 342.318874 -290.33666) (xy 342.314779 -290.285932) (xy 341.066882 -290.285932)
			(xy 341.06637 -290.311378) (xy 341.058206 -290.361612) (xy 341.04209 -290.409886) (xy 341.018439 -290.454949)
			(xy 340.987866 -290.495635) (xy 340.951162 -290.53089) (xy 340.909278 -290.5598) (xy 340.863299 -290.581617)
			(xy 340.814415 -290.595777) (xy 340.763894 -290.601911) (xy 340.713042 -290.599862) (xy 340.663178 -290.589682)
			(xy 340.615592 -290.571635) (xy 340.571518 -290.546189) (xy 340.532096 -290.514002) (xy 340.498348 -290.475908)
			(xy 340.471147 -290.432894) (xy 340.451199 -290.386074) (xy 340.43902 -290.33666) (xy 340.434925 -290.285932)
			(xy 340.116414 -290.285932) (xy 340.115919 -290.310539) (xy 340.108024 -290.359116) (xy 340.09244 -290.405797)
			(xy 340.069569 -290.449374) (xy 340.040004 -290.488718) (xy 340.004511 -290.52281) (xy 339.964008 -290.550766)
			(xy 339.919546 -290.571864) (xy 339.872275 -290.585556) (xy 339.82342 -290.591488) (xy 339.774245 -290.589507)
			(xy 339.726026 -290.579663) (xy 339.68001 -290.562211) (xy 339.637389 -290.537604) (xy 339.599268 -290.506479)
			(xy 339.566633 -290.469642) (xy 339.54033 -290.428046) (xy 339.521039 -290.38277) (xy 339.509262 -290.334986)
			(xy 339.505302 -290.285932) (xy 339.186774 -290.285932) (xy 339.186262 -290.311378) (xy 339.178098 -290.361612)
			(xy 339.161982 -290.409886) (xy 339.138331 -290.454949) (xy 339.107758 -290.495635) (xy 339.071054 -290.53089)
			(xy 339.02917 -290.5598) (xy 338.983191 -290.581617) (xy 338.934307 -290.595777) (xy 338.883786 -290.601911)
			(xy 338.832934 -290.599862) (xy 338.78307 -290.589682) (xy 338.735484 -290.571635) (xy 338.69141 -290.546189)
			(xy 338.651988 -290.514002) (xy 338.61824 -290.475908) (xy 338.591039 -290.432894) (xy 338.571091 -290.386074)
			(xy 338.558912 -290.33666) (xy 338.554817 -290.285932) (xy 338.236306 -290.285932) (xy 338.235811 -290.310539)
			(xy 338.227916 -290.359116) (xy 338.212332 -290.405797) (xy 338.189461 -290.449374) (xy 338.159896 -290.488718)
			(xy 338.124403 -290.52281) (xy 338.0839 -290.550766) (xy 338.039438 -290.571864) (xy 337.992167 -290.585556)
			(xy 337.943312 -290.591488) (xy 337.894137 -290.589507) (xy 337.845918 -290.579663) (xy 337.799902 -290.562211)
			(xy 337.757281 -290.537604) (xy 337.71916 -290.506479) (xy 337.686525 -290.469642) (xy 337.660222 -290.428046)
			(xy 337.640931 -290.38277) (xy 337.629154 -290.334986) (xy 337.625194 -290.285932) (xy 337.30692 -290.285932)
			(xy 337.306408 -290.311378) (xy 337.298244 -290.361612) (xy 337.282128 -290.409886) (xy 337.258477 -290.454949)
			(xy 337.227904 -290.495635) (xy 337.1912 -290.53089) (xy 337.149316 -290.5598) (xy 337.103337 -290.581617)
			(xy 337.054453 -290.595777) (xy 337.003932 -290.601911) (xy 336.95308 -290.599862) (xy 336.903216 -290.589682)
			(xy 336.85563 -290.571635) (xy 336.811556 -290.546189) (xy 336.772134 -290.514002) (xy 336.738386 -290.475908)
			(xy 336.711185 -290.432894) (xy 336.691237 -290.386074) (xy 336.679058 -290.33666) (xy 336.674963 -290.285932)
			(xy 336.366866 -290.285932) (xy 336.366354 -290.311378) (xy 336.35819 -290.361612) (xy 336.342074 -290.409886)
			(xy 336.318423 -290.454949) (xy 336.28785 -290.495635) (xy 336.251146 -290.53089) (xy 336.209262 -290.5598)
			(xy 336.163283 -290.581617) (xy 336.114399 -290.595777) (xy 336.063878 -290.601911) (xy 336.013026 -290.599862)
			(xy 335.963162 -290.589682) (xy 335.915576 -290.571635) (xy 335.871502 -290.546189) (xy 335.83208 -290.514002)
			(xy 335.798332 -290.475908) (xy 335.771131 -290.432894) (xy 335.751183 -290.386074) (xy 335.739004 -290.33666)
			(xy 335.734909 -290.285932) (xy 334.486758 -290.285932) (xy 334.486246 -290.311378) (xy 334.478082 -290.361612)
			(xy 334.461966 -290.409886) (xy 334.438315 -290.454949) (xy 334.407742 -290.495635) (xy 334.371038 -290.53089)
			(xy 334.329154 -290.5598) (xy 334.283175 -290.581617) (xy 334.234291 -290.595777) (xy 334.18377 -290.601911)
			(xy 334.132918 -290.599862) (xy 334.083054 -290.589682) (xy 334.035468 -290.571635) (xy 333.991394 -290.546189)
			(xy 333.951972 -290.514002) (xy 333.918224 -290.475908) (xy 333.891023 -290.432894) (xy 333.871075 -290.386074)
			(xy 333.858896 -290.33666) (xy 333.854801 -290.285932) (xy 333.53629 -290.285932) (xy 333.535795 -290.310539)
			(xy 333.5279 -290.359116) (xy 333.512316 -290.405797) (xy 333.489445 -290.449374) (xy 333.45988 -290.488718)
			(xy 333.424387 -290.52281) (xy 333.383884 -290.550766) (xy 333.339422 -290.571864) (xy 333.292151 -290.585556)
			(xy 333.243296 -290.591488) (xy 333.194121 -290.589507) (xy 333.145902 -290.579663) (xy 333.099886 -290.562211)
			(xy 333.057265 -290.537604) (xy 333.019144 -290.506479) (xy 332.986509 -290.469642) (xy 332.960206 -290.428046)
			(xy 332.940915 -290.38277) (xy 332.929138 -290.334986) (xy 332.925178 -290.285932) (xy 332.606904 -290.285932)
			(xy 332.606392 -290.311378) (xy 332.598228 -290.361612) (xy 332.582112 -290.409886) (xy 332.558461 -290.454949)
			(xy 332.527888 -290.495635) (xy 332.491184 -290.53089) (xy 332.4493 -290.5598) (xy 332.403321 -290.581617)
			(xy 332.354437 -290.595777) (xy 332.303916 -290.601911) (xy 332.253064 -290.599862) (xy 332.2032 -290.589682)
			(xy 332.155614 -290.571635) (xy 332.11154 -290.546189) (xy 332.072118 -290.514002) (xy 332.03837 -290.475908)
			(xy 332.011169 -290.432894) (xy 331.991221 -290.386074) (xy 331.979042 -290.33666) (xy 331.974947 -290.285932)
			(xy 331.656436 -290.285932) (xy 331.655941 -290.310539) (xy 331.648046 -290.359116) (xy 331.632462 -290.405797)
			(xy 331.609591 -290.449374) (xy 331.580026 -290.488718) (xy 331.544533 -290.52281) (xy 331.50403 -290.550766)
			(xy 331.459568 -290.571864) (xy 331.412297 -290.585556) (xy 331.363442 -290.591488) (xy 331.314267 -290.589507)
			(xy 331.266048 -290.579663) (xy 331.220032 -290.562211) (xy 331.177411 -290.537604) (xy 331.13929 -290.506479)
			(xy 331.106655 -290.469642) (xy 331.080352 -290.428046) (xy 331.061061 -290.38277) (xy 331.049284 -290.334986)
			(xy 331.045324 -290.285932) (xy 330.726796 -290.285932) (xy 330.726284 -290.311378) (xy 330.71812 -290.361612)
			(xy 330.702004 -290.409886) (xy 330.678353 -290.454949) (xy 330.64778 -290.495635) (xy 330.611076 -290.53089)
			(xy 330.569192 -290.5598) (xy 330.523213 -290.581617) (xy 330.474329 -290.595777) (xy 330.423808 -290.601911)
			(xy 330.372956 -290.599862) (xy 330.323092 -290.589682) (xy 330.275506 -290.571635) (xy 330.231432 -290.546189)
			(xy 330.19201 -290.514002) (xy 330.158262 -290.475908) (xy 330.131061 -290.432894) (xy 330.111113 -290.386074)
			(xy 330.098934 -290.33666) (xy 330.094839 -290.285932) (xy 329.786742 -290.285932) (xy 329.78623 -290.311378)
			(xy 329.778066 -290.361612) (xy 329.76195 -290.409886) (xy 329.738299 -290.454949) (xy 329.707726 -290.495635)
			(xy 329.671022 -290.53089) (xy 329.629138 -290.5598) (xy 329.583159 -290.581617) (xy 329.534275 -290.595777)
			(xy 329.483754 -290.601911) (xy 329.432902 -290.599862) (xy 329.383038 -290.589682) (xy 329.335452 -290.571635)
			(xy 329.291378 -290.546189) (xy 329.251956 -290.514002) (xy 329.218208 -290.475908) (xy 329.191007 -290.432894)
			(xy 329.171059 -290.386074) (xy 329.15888 -290.33666) (xy 329.154785 -290.285932) (xy 326.95642 -290.285932)
			(xy 326.955925 -290.310539) (xy 326.94803 -290.359116) (xy 326.932446 -290.405797) (xy 326.909575 -290.449374)
			(xy 326.88001 -290.488718) (xy 326.844517 -290.52281) (xy 326.804014 -290.550766) (xy 326.759552 -290.571864)
			(xy 326.712281 -290.585556) (xy 326.663426 -290.591488) (xy 326.614251 -290.589507) (xy 326.566032 -290.579663)
			(xy 326.520016 -290.562211) (xy 326.477395 -290.537604) (xy 326.439274 -290.506479) (xy 326.406639 -290.469642)
			(xy 326.380336 -290.428046) (xy 326.361045 -290.38277) (xy 326.349268 -290.334986) (xy 326.345308 -290.285932)
			(xy 310.45912 -290.285932) (xy 310.45912 -290.83) (xy 324.74714 -290.83) (xy 324.7511 -290.780946)
			(xy 324.762877 -290.733162) (xy 324.782168 -290.687886) (xy 324.808471 -290.64629) (xy 324.841106 -290.609453)
			(xy 324.879227 -290.578328) (xy 324.921848 -290.553721) (xy 324.967864 -290.536269) (xy 325.016083 -290.526425)
			(xy 325.065258 -290.524444) (xy 325.114113 -290.530376) (xy 325.161384 -290.544068) (xy 325.205846 -290.565166)
			(xy 325.246349 -290.593122) (xy 325.281842 -290.627214) (xy 325.311407 -290.666558) (xy 325.334278 -290.710135)
			(xy 325.349862 -290.756816) (xy 325.357757 -290.805393) (xy 325.358252 -290.83) (xy 325.357757 -290.854607)
			(xy 325.349862 -290.903184) (xy 325.334278 -290.949865) (xy 325.311407 -290.993442) (xy 325.281842 -291.032786)
			(xy 325.246349 -291.066878) (xy 325.205846 -291.094834) (xy 325.203519 -291.095938) (xy 327.755262 -291.095938)
			(xy 327.759222 -291.046884) (xy 327.770999 -290.9991) (xy 327.79029 -290.953824) (xy 327.816593 -290.912228)
			(xy 327.849228 -290.875391) (xy 327.887349 -290.844266) (xy 327.92997 -290.819659) (xy 327.975986 -290.802207)
			(xy 328.024205 -290.792363) (xy 328.07338 -290.790382) (xy 328.122235 -290.796314) (xy 328.169506 -290.810006)
			(xy 328.213968 -290.831104) (xy 328.254471 -290.85906) (xy 328.289964 -290.893152) (xy 328.319529 -290.932496)
			(xy 328.3424 -290.976073) (xy 328.357984 -291.022754) (xy 328.365879 -291.071331) (xy 328.366374 -291.095938)
			(xy 328.684885 -291.095938) (xy 328.68898 -291.04521) (xy 328.701159 -290.995796) (xy 328.721107 -290.948976)
			(xy 328.748308 -290.905962) (xy 328.782056 -290.867868) (xy 328.821478 -290.835681) (xy 328.865552 -290.810235)
			(xy 328.913138 -290.792188) (xy 328.963002 -290.782008) (xy 329.013854 -290.779959) (xy 329.064375 -290.786093)
			(xy 329.113259 -290.800253) (xy 329.159238 -290.82207) (xy 329.201122 -290.85098) (xy 329.237826 -290.886235)
			(xy 329.268399 -290.926921) (xy 329.29205 -290.971984) (xy 329.308166 -291.020258) (xy 329.31633 -291.070492)
			(xy 329.316842 -291.095938) (xy 329.63537 -291.095938) (xy 329.63933 -291.046884) (xy 329.651107 -290.9991)
			(xy 329.670398 -290.953824) (xy 329.696701 -290.912228) (xy 329.729336 -290.875391) (xy 329.767457 -290.844266)
			(xy 329.810078 -290.819659) (xy 329.856094 -290.802207) (xy 329.904313 -290.792363) (xy 329.953488 -290.790382)
			(xy 330.002343 -290.796314) (xy 330.049614 -290.810006) (xy 330.094076 -290.831104) (xy 330.134579 -290.85906)
			(xy 330.170072 -290.893152) (xy 330.199637 -290.932496) (xy 330.222508 -290.976073) (xy 330.238092 -291.022754)
			(xy 330.245987 -291.071331) (xy 330.246482 -291.095938) (xy 330.564739 -291.095938) (xy 330.568834 -291.04521)
			(xy 330.581013 -290.995796) (xy 330.600961 -290.948976) (xy 330.628162 -290.905962) (xy 330.66191 -290.867868)
			(xy 330.701332 -290.835681) (xy 330.745406 -290.810235) (xy 330.792992 -290.792188) (xy 330.842856 -290.782008)
			(xy 330.893708 -290.779959) (xy 330.944229 -290.786093) (xy 330.993113 -290.800253) (xy 331.039092 -290.82207)
			(xy 331.080976 -290.85098) (xy 331.11768 -290.886235) (xy 331.148253 -290.926921) (xy 331.171904 -290.971984)
			(xy 331.18802 -291.020258) (xy 331.196184 -291.070492) (xy 331.196696 -291.095938) (xy 331.515224 -291.095938)
			(xy 331.519184 -291.046884) (xy 331.530961 -290.9991) (xy 331.550252 -290.953824) (xy 331.576555 -290.912228)
			(xy 331.60919 -290.875391) (xy 331.647311 -290.844266) (xy 331.689932 -290.819659) (xy 331.735948 -290.802207)
			(xy 331.784167 -290.792363) (xy 331.833342 -290.790382) (xy 331.882197 -290.796314) (xy 331.929468 -290.810006)
			(xy 331.97393 -290.831104) (xy 332.014433 -290.85906) (xy 332.049926 -290.893152) (xy 332.079491 -290.932496)
			(xy 332.102362 -290.976073) (xy 332.117946 -291.022754) (xy 332.125841 -291.071331) (xy 332.126336 -291.095938)
			(xy 332.444847 -291.095938) (xy 332.448942 -291.04521) (xy 332.461121 -290.995796) (xy 332.481069 -290.948976)
			(xy 332.50827 -290.905962) (xy 332.542018 -290.867868) (xy 332.58144 -290.835681) (xy 332.625514 -290.810235)
			(xy 332.6731 -290.792188) (xy 332.722964 -290.782008) (xy 332.773816 -290.779959) (xy 332.824337 -290.786093)
			(xy 332.873221 -290.800253) (xy 332.9192 -290.82207) (xy 332.961084 -290.85098) (xy 332.997788 -290.886235)
			(xy 333.028361 -290.926921) (xy 333.052012 -290.971984) (xy 333.068128 -291.020258) (xy 333.076292 -291.070492)
			(xy 333.076804 -291.095938) (xy 333.384901 -291.095938) (xy 333.388996 -291.04521) (xy 333.401175 -290.995796)
			(xy 333.421123 -290.948976) (xy 333.448324 -290.905962) (xy 333.482072 -290.867868) (xy 333.521494 -290.835681)
			(xy 333.565568 -290.810235) (xy 333.613154 -290.792188) (xy 333.663018 -290.782008) (xy 333.71387 -290.779959)
			(xy 333.764391 -290.786093) (xy 333.813275 -290.800253) (xy 333.859254 -290.82207) (xy 333.901138 -290.85098)
			(xy 333.937842 -290.886235) (xy 333.968415 -290.926921) (xy 333.992066 -290.971984) (xy 334.008182 -291.020258)
			(xy 334.016346 -291.070492) (xy 334.016858 -291.095938) (xy 334.335386 -291.095938) (xy 334.339346 -291.046884)
			(xy 334.351123 -290.9991) (xy 334.370414 -290.953824) (xy 334.396717 -290.912228) (xy 334.429352 -290.875391)
			(xy 334.467473 -290.844266) (xy 334.510094 -290.819659) (xy 334.55611 -290.802207) (xy 334.604329 -290.792363)
			(xy 334.653504 -290.790382) (xy 334.702359 -290.796314) (xy 334.74963 -290.810006) (xy 334.794092 -290.831104)
			(xy 334.834595 -290.85906) (xy 334.870088 -290.893152) (xy 334.899653 -290.932496) (xy 334.922524 -290.976073)
			(xy 334.938108 -291.022754) (xy 334.946003 -291.071331) (xy 334.946498 -291.095938) (xy 335.264755 -291.095938)
			(xy 335.26885 -291.04521) (xy 335.281029 -290.995796) (xy 335.300977 -290.948976) (xy 335.328178 -290.905962)
			(xy 335.361926 -290.867868) (xy 335.401348 -290.835681) (xy 335.445422 -290.810235) (xy 335.493008 -290.792188)
			(xy 335.542872 -290.782008) (xy 335.593724 -290.779959) (xy 335.644245 -290.786093) (xy 335.693129 -290.800253)
			(xy 335.739108 -290.82207) (xy 335.780992 -290.85098) (xy 335.817696 -290.886235) (xy 335.848269 -290.926921)
			(xy 335.87192 -290.971984) (xy 335.888036 -291.020258) (xy 335.8962 -291.070492) (xy 335.896712 -291.095938)
			(xy 336.21524 -291.095938) (xy 336.2192 -291.046884) (xy 336.230977 -290.9991) (xy 336.250268 -290.953824)
			(xy 336.276571 -290.912228) (xy 336.309206 -290.875391) (xy 336.347327 -290.844266) (xy 336.389948 -290.819659)
			(xy 336.435964 -290.802207) (xy 336.484183 -290.792363) (xy 336.533358 -290.790382) (xy 336.582213 -290.796314)
			(xy 336.629484 -290.810006) (xy 336.673946 -290.831104) (xy 336.714449 -290.85906) (xy 336.749942 -290.893152)
			(xy 336.779507 -290.932496) (xy 336.802378 -290.976073) (xy 336.817962 -291.022754) (xy 336.825857 -291.071331)
			(xy 336.826352 -291.095938) (xy 337.144863 -291.095938) (xy 337.148958 -291.04521) (xy 337.161137 -290.995796)
			(xy 337.181085 -290.948976) (xy 337.208286 -290.905962) (xy 337.242034 -290.867868) (xy 337.281456 -290.835681)
			(xy 337.32553 -290.810235) (xy 337.373116 -290.792188) (xy 337.42298 -290.782008) (xy 337.473832 -290.779959)
			(xy 337.524353 -290.786093) (xy 337.573237 -290.800253) (xy 337.619216 -290.82207) (xy 337.6611 -290.85098)
			(xy 337.697804 -290.886235) (xy 337.728377 -290.926921) (xy 337.752028 -290.971984) (xy 337.768144 -291.020258)
			(xy 337.776308 -291.070492) (xy 337.77682 -291.095938) (xy 338.095348 -291.095938) (xy 338.099308 -291.046884)
			(xy 338.111085 -290.9991) (xy 338.130376 -290.953824) (xy 338.156679 -290.912228) (xy 338.189314 -290.875391)
			(xy 338.227435 -290.844266) (xy 338.270056 -290.819659) (xy 338.316072 -290.802207) (xy 338.364291 -290.792363)
			(xy 338.413466 -290.790382) (xy 338.462321 -290.796314) (xy 338.509592 -290.810006) (xy 338.554054 -290.831104)
			(xy 338.594557 -290.85906) (xy 338.63005 -290.893152) (xy 338.659615 -290.932496) (xy 338.682486 -290.976073)
			(xy 338.69807 -291.022754) (xy 338.705965 -291.071331) (xy 338.70646 -291.095938) (xy 339.024971 -291.095938)
			(xy 339.029066 -291.04521) (xy 339.041245 -290.995796) (xy 339.061193 -290.948976) (xy 339.088394 -290.905962)
			(xy 339.122142 -290.867868) (xy 339.161564 -290.835681) (xy 339.205638 -290.810235) (xy 339.253224 -290.792188)
			(xy 339.303088 -290.782008) (xy 339.35394 -290.779959) (xy 339.404461 -290.786093) (xy 339.453345 -290.800253)
			(xy 339.499324 -290.82207) (xy 339.541208 -290.85098) (xy 339.577912 -290.886235) (xy 339.608485 -290.926921)
			(xy 339.632136 -290.971984) (xy 339.648252 -291.020258) (xy 339.656416 -291.070492) (xy 339.656928 -291.095938)
			(xy 339.964771 -291.095938) (xy 339.968866 -291.04521) (xy 339.981045 -290.995796) (xy 340.000993 -290.948976)
			(xy 340.028194 -290.905962) (xy 340.061942 -290.867868) (xy 340.101364 -290.835681) (xy 340.145438 -290.810235)
			(xy 340.193024 -290.792188) (xy 340.242888 -290.782008) (xy 340.29374 -290.779959) (xy 340.344261 -290.786093)
			(xy 340.393145 -290.800253) (xy 340.439124 -290.82207) (xy 340.481008 -290.85098) (xy 340.517712 -290.886235)
			(xy 340.548285 -290.926921) (xy 340.571936 -290.971984) (xy 340.588052 -291.020258) (xy 340.596216 -291.070492)
			(xy 340.596728 -291.095938) (xy 340.915256 -291.095938) (xy 340.919216 -291.046884) (xy 340.930993 -290.9991)
			(xy 340.950284 -290.953824) (xy 340.976587 -290.912228) (xy 341.009222 -290.875391) (xy 341.047343 -290.844266)
			(xy 341.089964 -290.819659) (xy 341.13598 -290.802207) (xy 341.184199 -290.792363) (xy 341.233374 -290.790382)
			(xy 341.282229 -290.796314) (xy 341.3295 -290.810006) (xy 341.373962 -290.831104) (xy 341.414465 -290.85906)
			(xy 341.449958 -290.893152) (xy 341.479523 -290.932496) (xy 341.502394 -290.976073) (xy 341.517978 -291.022754)
			(xy 341.525873 -291.071331) (xy 341.526368 -291.095938) (xy 341.844879 -291.095938) (xy 341.848974 -291.04521)
			(xy 341.861153 -290.995796) (xy 341.881101 -290.948976) (xy 341.908302 -290.905962) (xy 341.94205 -290.867868)
			(xy 341.981472 -290.835681) (xy 342.025546 -290.810235) (xy 342.073132 -290.792188) (xy 342.122996 -290.782008)
			(xy 342.173848 -290.779959) (xy 342.224369 -290.786093) (xy 342.273253 -290.800253) (xy 342.319232 -290.82207)
			(xy 342.361116 -290.85098) (xy 342.39782 -290.886235) (xy 342.428393 -290.926921) (xy 342.452044 -290.971984)
			(xy 342.46816 -291.020258) (xy 342.476324 -291.070492) (xy 342.476836 -291.095938) (xy 342.795364 -291.095938)
			(xy 342.799324 -291.046884) (xy 342.811101 -290.9991) (xy 342.830392 -290.953824) (xy 342.856695 -290.912228)
			(xy 342.88933 -290.875391) (xy 342.927451 -290.844266) (xy 342.970072 -290.819659) (xy 343.016088 -290.802207)
			(xy 343.064307 -290.792363) (xy 343.113482 -290.790382) (xy 343.162337 -290.796314) (xy 343.209608 -290.810006)
			(xy 343.25407 -290.831104) (xy 343.294573 -290.85906) (xy 343.330066 -290.893152) (xy 343.359631 -290.932496)
			(xy 343.382502 -290.976073) (xy 343.398086 -291.022754) (xy 343.405981 -291.071331) (xy 343.406476 -291.095938)
			(xy 343.724987 -291.095938) (xy 343.729082 -291.04521) (xy 343.741261 -290.995796) (xy 343.761209 -290.948976)
			(xy 343.78841 -290.905962) (xy 343.822158 -290.867868) (xy 343.86158 -290.835681) (xy 343.905654 -290.810235)
			(xy 343.95324 -290.792188) (xy 344.003104 -290.782008) (xy 344.053956 -290.779959) (xy 344.104477 -290.786093)
			(xy 344.153361 -290.800253) (xy 344.19934 -290.82207) (xy 344.241224 -290.85098) (xy 344.277928 -290.886235)
			(xy 344.308501 -290.926921) (xy 344.332152 -290.971984) (xy 344.348268 -291.020258) (xy 344.356432 -291.070492)
			(xy 344.356944 -291.095938) (xy 344.675218 -291.095938) (xy 344.679178 -291.046884) (xy 344.690955 -290.9991)
			(xy 344.710246 -290.953824) (xy 344.736549 -290.912228) (xy 344.769184 -290.875391) (xy 344.807305 -290.844266)
			(xy 344.849926 -290.819659) (xy 344.895942 -290.802207) (xy 344.944161 -290.792363) (xy 344.993336 -290.790382)
			(xy 345.042191 -290.796314) (xy 345.089462 -290.810006) (xy 345.133924 -290.831104) (xy 345.174427 -290.85906)
			(xy 345.20992 -290.893152) (xy 345.239485 -290.932496) (xy 345.262356 -290.976073) (xy 345.27794 -291.022754)
			(xy 345.285835 -291.071331) (xy 345.28633 -291.095938) (xy 345.604841 -291.095938) (xy 345.608936 -291.04521)
			(xy 345.621115 -290.995796) (xy 345.641063 -290.948976) (xy 345.668264 -290.905962) (xy 345.702012 -290.867868)
			(xy 345.741434 -290.835681) (xy 345.785508 -290.810235) (xy 345.833094 -290.792188) (xy 345.882958 -290.782008)
			(xy 345.93381 -290.779959) (xy 345.984331 -290.786093) (xy 346.033215 -290.800253) (xy 346.079194 -290.82207)
			(xy 346.121078 -290.85098) (xy 346.157782 -290.886235) (xy 346.188355 -290.926921) (xy 346.212006 -290.971984)
			(xy 346.228122 -291.020258) (xy 346.236286 -291.070492) (xy 346.236798 -291.095938) (xy 346.544895 -291.095938)
			(xy 346.54899 -291.04521) (xy 346.561169 -290.995796) (xy 346.581117 -290.948976) (xy 346.608318 -290.905962)
			(xy 346.642066 -290.867868) (xy 346.681488 -290.835681) (xy 346.725562 -290.810235) (xy 346.773148 -290.792188)
			(xy 346.823012 -290.782008) (xy 346.873864 -290.779959) (xy 346.924385 -290.786093) (xy 346.973269 -290.800253)
			(xy 347.019248 -290.82207) (xy 347.061132 -290.85098) (xy 347.097836 -290.886235) (xy 347.128409 -290.926921)
			(xy 347.15206 -290.971984) (xy 347.168176 -291.020258) (xy 347.17634 -291.070492) (xy 347.176852 -291.095938)
			(xy 347.49538 -291.095938) (xy 347.49934 -291.046884) (xy 347.511117 -290.9991) (xy 347.530408 -290.953824)
			(xy 347.556711 -290.912228) (xy 347.589346 -290.875391) (xy 347.627467 -290.844266) (xy 347.670088 -290.819659)
			(xy 347.716104 -290.802207) (xy 347.764323 -290.792363) (xy 347.813498 -290.790382) (xy 347.862353 -290.796314)
			(xy 347.909624 -290.810006) (xy 347.954086 -290.831104) (xy 347.994589 -290.85906) (xy 348.030082 -290.893152)
			(xy 348.059647 -290.932496) (xy 348.082518 -290.976073) (xy 348.098102 -291.022754) (xy 348.105997 -291.071331)
			(xy 348.106492 -291.095938) (xy 348.425003 -291.095938) (xy 348.429098 -291.04521) (xy 348.441277 -290.995796)
			(xy 348.461225 -290.948976) (xy 348.488426 -290.905962) (xy 348.522174 -290.867868) (xy 348.561596 -290.835681)
			(xy 348.60567 -290.810235) (xy 348.653256 -290.792188) (xy 348.70312 -290.782008) (xy 348.753972 -290.779959)
			(xy 348.804493 -290.786093) (xy 348.853377 -290.800253) (xy 348.899356 -290.82207) (xy 348.94124 -290.85098)
			(xy 348.977944 -290.886235) (xy 349.008517 -290.926921) (xy 349.032168 -290.971984) (xy 349.048284 -291.020258)
			(xy 349.056448 -291.070492) (xy 349.05696 -291.095938) (xy 349.364803 -291.095938) (xy 349.368898 -291.04521)
			(xy 349.381077 -290.995796) (xy 349.401025 -290.948976) (xy 349.428226 -290.905962) (xy 349.461974 -290.867868)
			(xy 349.501396 -290.835681) (xy 349.54547 -290.810235) (xy 349.593056 -290.792188) (xy 349.64292 -290.782008)
			(xy 349.693772 -290.779959) (xy 349.744293 -290.786093) (xy 349.793177 -290.800253) (xy 349.839156 -290.82207)
			(xy 349.88104 -290.85098) (xy 349.917744 -290.886235) (xy 349.948317 -290.926921) (xy 349.971968 -290.971984)
			(xy 349.988084 -291.020258) (xy 349.996248 -291.070492) (xy 349.99676 -291.095938) (xy 350.315288 -291.095938)
			(xy 350.319248 -291.046884) (xy 350.331025 -290.9991) (xy 350.350316 -290.953824) (xy 350.376619 -290.912228)
			(xy 350.409254 -290.875391) (xy 350.447375 -290.844266) (xy 350.489996 -290.819659) (xy 350.536012 -290.802207)
			(xy 350.584231 -290.792363) (xy 350.633406 -290.790382) (xy 350.682261 -290.796314) (xy 350.729532 -290.810006)
			(xy 350.773994 -290.831104) (xy 350.814497 -290.85906) (xy 350.84999 -290.893152) (xy 350.879555 -290.932496)
			(xy 350.902426 -290.976073) (xy 350.91801 -291.022754) (xy 350.925905 -291.071331) (xy 350.9264 -291.095938)
			(xy 350.925905 -291.120545) (xy 350.91801 -291.169122) (xy 350.902426 -291.215803) (xy 350.879555 -291.25938)
			(xy 350.84999 -291.298724) (xy 350.814497 -291.332816) (xy 350.773994 -291.360772) (xy 350.729532 -291.38187)
			(xy 350.682261 -291.395562) (xy 350.633406 -291.401494) (xy 350.584231 -291.399513) (xy 350.536012 -291.389669)
			(xy 350.489996 -291.372217) (xy 350.447375 -291.34761) (xy 350.409254 -291.316485) (xy 350.376619 -291.279648)
			(xy 350.350316 -291.238052) (xy 350.331025 -291.192776) (xy 350.319248 -291.144992) (xy 350.315288 -291.095938)
			(xy 349.99676 -291.095938) (xy 349.996248 -291.121384) (xy 349.988084 -291.171618) (xy 349.971968 -291.219892)
			(xy 349.948317 -291.264955) (xy 349.917744 -291.305641) (xy 349.88104 -291.340896) (xy 349.839156 -291.369806)
			(xy 349.793177 -291.391623) (xy 349.744293 -291.405783) (xy 349.693772 -291.411917) (xy 349.64292 -291.409868)
			(xy 349.593056 -291.399688) (xy 349.54547 -291.381641) (xy 349.501396 -291.356195) (xy 349.461974 -291.324008)
			(xy 349.428226 -291.285914) (xy 349.401025 -291.2429) (xy 349.381077 -291.19608) (xy 349.368898 -291.146666)
			(xy 349.364803 -291.095938) (xy 349.05696 -291.095938) (xy 349.056448 -291.121384) (xy 349.048284 -291.171618)
			(xy 349.032168 -291.219892) (xy 349.008517 -291.264955) (xy 348.977944 -291.305641) (xy 348.94124 -291.340896)
			(xy 348.899356 -291.369806) (xy 348.853377 -291.391623) (xy 348.804493 -291.405783) (xy 348.753972 -291.411917)
			(xy 348.70312 -291.409868) (xy 348.653256 -291.399688) (xy 348.60567 -291.381641) (xy 348.561596 -291.356195)
			(xy 348.522174 -291.324008) (xy 348.488426 -291.285914) (xy 348.461225 -291.2429) (xy 348.441277 -291.19608)
			(xy 348.429098 -291.146666) (xy 348.425003 -291.095938) (xy 348.106492 -291.095938) (xy 348.105997 -291.120545)
			(xy 348.098102 -291.169122) (xy 348.082518 -291.215803) (xy 348.059647 -291.25938) (xy 348.030082 -291.298724)
			(xy 347.994589 -291.332816) (xy 347.954086 -291.360772) (xy 347.909624 -291.38187) (xy 347.862353 -291.395562)
			(xy 347.813498 -291.401494) (xy 347.764323 -291.399513) (xy 347.716104 -291.389669) (xy 347.670088 -291.372217)
			(xy 347.627467 -291.34761) (xy 347.589346 -291.316485) (xy 347.556711 -291.279648) (xy 347.530408 -291.238052)
			(xy 347.511117 -291.192776) (xy 347.49934 -291.144992) (xy 347.49538 -291.095938) (xy 347.176852 -291.095938)
			(xy 347.17634 -291.121384) (xy 347.168176 -291.171618) (xy 347.15206 -291.219892) (xy 347.128409 -291.264955)
			(xy 347.097836 -291.305641) (xy 347.061132 -291.340896) (xy 347.019248 -291.369806) (xy 346.973269 -291.391623)
			(xy 346.924385 -291.405783) (xy 346.873864 -291.411917) (xy 346.823012 -291.409868) (xy 346.773148 -291.399688)
			(xy 346.725562 -291.381641) (xy 346.681488 -291.356195) (xy 346.642066 -291.324008) (xy 346.608318 -291.285914)
			(xy 346.581117 -291.2429) (xy 346.561169 -291.19608) (xy 346.54899 -291.146666) (xy 346.544895 -291.095938)
			(xy 346.236798 -291.095938) (xy 346.236286 -291.121384) (xy 346.228122 -291.171618) (xy 346.212006 -291.219892)
			(xy 346.188355 -291.264955) (xy 346.157782 -291.305641) (xy 346.121078 -291.340896) (xy 346.079194 -291.369806)
			(xy 346.033215 -291.391623) (xy 345.984331 -291.405783) (xy 345.93381 -291.411917) (xy 345.882958 -291.409868)
			(xy 345.833094 -291.399688) (xy 345.785508 -291.381641) (xy 345.741434 -291.356195) (xy 345.702012 -291.324008)
			(xy 345.668264 -291.285914) (xy 345.641063 -291.2429) (xy 345.621115 -291.19608) (xy 345.608936 -291.146666)
			(xy 345.604841 -291.095938) (xy 345.28633 -291.095938) (xy 345.285835 -291.120545) (xy 345.27794 -291.169122)
			(xy 345.262356 -291.215803) (xy 345.239485 -291.25938) (xy 345.20992 -291.298724) (xy 345.174427 -291.332816)
			(xy 345.133924 -291.360772) (xy 345.089462 -291.38187) (xy 345.042191 -291.395562) (xy 344.993336 -291.401494)
			(xy 344.944161 -291.399513) (xy 344.895942 -291.389669) (xy 344.849926 -291.372217) (xy 344.807305 -291.34761)
			(xy 344.769184 -291.316485) (xy 344.736549 -291.279648) (xy 344.710246 -291.238052) (xy 344.690955 -291.192776)
			(xy 344.679178 -291.144992) (xy 344.675218 -291.095938) (xy 344.356944 -291.095938) (xy 344.356432 -291.121384)
			(xy 344.348268 -291.171618) (xy 344.332152 -291.219892) (xy 344.308501 -291.264955) (xy 344.277928 -291.305641)
			(xy 344.241224 -291.340896) (xy 344.19934 -291.369806) (xy 344.153361 -291.391623) (xy 344.104477 -291.405783)
			(xy 344.053956 -291.411917) (xy 344.003104 -291.409868) (xy 343.95324 -291.399688) (xy 343.905654 -291.381641)
			(xy 343.86158 -291.356195) (xy 343.822158 -291.324008) (xy 343.78841 -291.285914) (xy 343.761209 -291.2429)
			(xy 343.741261 -291.19608) (xy 343.729082 -291.146666) (xy 343.724987 -291.095938) (xy 343.406476 -291.095938)
			(xy 343.405981 -291.120545) (xy 343.398086 -291.169122) (xy 343.382502 -291.215803) (xy 343.359631 -291.25938)
			(xy 343.330066 -291.298724) (xy 343.294573 -291.332816) (xy 343.25407 -291.360772) (xy 343.209608 -291.38187)
			(xy 343.162337 -291.395562) (xy 343.113482 -291.401494) (xy 343.064307 -291.399513) (xy 343.016088 -291.389669)
			(xy 342.970072 -291.372217) (xy 342.927451 -291.34761) (xy 342.88933 -291.316485) (xy 342.856695 -291.279648)
			(xy 342.830392 -291.238052) (xy 342.811101 -291.192776) (xy 342.799324 -291.144992) (xy 342.795364 -291.095938)
			(xy 342.476836 -291.095938) (xy 342.476324 -291.121384) (xy 342.46816 -291.171618) (xy 342.452044 -291.219892)
			(xy 342.428393 -291.264955) (xy 342.39782 -291.305641) (xy 342.361116 -291.340896) (xy 342.319232 -291.369806)
			(xy 342.273253 -291.391623) (xy 342.224369 -291.405783) (xy 342.173848 -291.411917) (xy 342.122996 -291.409868)
			(xy 342.073132 -291.399688) (xy 342.025546 -291.381641) (xy 341.981472 -291.356195) (xy 341.94205 -291.324008)
			(xy 341.908302 -291.285914) (xy 341.881101 -291.2429) (xy 341.861153 -291.19608) (xy 341.848974 -291.146666)
			(xy 341.844879 -291.095938) (xy 341.526368 -291.095938) (xy 341.525873 -291.120545) (xy 341.517978 -291.169122)
			(xy 341.502394 -291.215803) (xy 341.479523 -291.25938) (xy 341.449958 -291.298724) (xy 341.414465 -291.332816)
			(xy 341.373962 -291.360772) (xy 341.3295 -291.38187) (xy 341.282229 -291.395562) (xy 341.233374 -291.401494)
			(xy 341.184199 -291.399513) (xy 341.13598 -291.389669) (xy 341.089964 -291.372217) (xy 341.047343 -291.34761)
			(xy 341.009222 -291.316485) (xy 340.976587 -291.279648) (xy 340.950284 -291.238052) (xy 340.930993 -291.192776)
			(xy 340.919216 -291.144992) (xy 340.915256 -291.095938) (xy 340.596728 -291.095938) (xy 340.596216 -291.121384)
			(xy 340.588052 -291.171618) (xy 340.571936 -291.219892) (xy 340.548285 -291.264955) (xy 340.517712 -291.305641)
			(xy 340.481008 -291.340896) (xy 340.439124 -291.369806) (xy 340.393145 -291.391623) (xy 340.344261 -291.405783)
			(xy 340.29374 -291.411917) (xy 340.242888 -291.409868) (xy 340.193024 -291.399688) (xy 340.145438 -291.381641)
			(xy 340.101364 -291.356195) (xy 340.061942 -291.324008) (xy 340.028194 -291.285914) (xy 340.000993 -291.2429)
			(xy 339.981045 -291.19608) (xy 339.968866 -291.146666) (xy 339.964771 -291.095938) (xy 339.656928 -291.095938)
			(xy 339.656416 -291.121384) (xy 339.648252 -291.171618) (xy 339.632136 -291.219892) (xy 339.608485 -291.264955)
			(xy 339.577912 -291.305641) (xy 339.541208 -291.340896) (xy 339.499324 -291.369806) (xy 339.453345 -291.391623)
			(xy 339.404461 -291.405783) (xy 339.35394 -291.411917) (xy 339.303088 -291.409868) (xy 339.253224 -291.399688)
			(xy 339.205638 -291.381641) (xy 339.161564 -291.356195) (xy 339.122142 -291.324008) (xy 339.088394 -291.285914)
			(xy 339.061193 -291.2429) (xy 339.041245 -291.19608) (xy 339.029066 -291.146666) (xy 339.024971 -291.095938)
			(xy 338.70646 -291.095938) (xy 338.705965 -291.120545) (xy 338.69807 -291.169122) (xy 338.682486 -291.215803)
			(xy 338.659615 -291.25938) (xy 338.63005 -291.298724) (xy 338.594557 -291.332816) (xy 338.554054 -291.360772)
			(xy 338.509592 -291.38187) (xy 338.462321 -291.395562) (xy 338.413466 -291.401494) (xy 338.364291 -291.399513)
			(xy 338.316072 -291.389669) (xy 338.270056 -291.372217) (xy 338.227435 -291.34761) (xy 338.189314 -291.316485)
			(xy 338.156679 -291.279648) (xy 338.130376 -291.238052) (xy 338.111085 -291.192776) (xy 338.099308 -291.144992)
			(xy 338.095348 -291.095938) (xy 337.77682 -291.095938) (xy 337.776308 -291.121384) (xy 337.768144 -291.171618)
			(xy 337.752028 -291.219892) (xy 337.728377 -291.264955) (xy 337.697804 -291.305641) (xy 337.6611 -291.340896)
			(xy 337.619216 -291.369806) (xy 337.573237 -291.391623) (xy 337.524353 -291.405783) (xy 337.473832 -291.411917)
			(xy 337.42298 -291.409868) (xy 337.373116 -291.399688) (xy 337.32553 -291.381641) (xy 337.281456 -291.356195)
			(xy 337.242034 -291.324008) (xy 337.208286 -291.285914) (xy 337.181085 -291.2429) (xy 337.161137 -291.19608)
			(xy 337.148958 -291.146666) (xy 337.144863 -291.095938) (xy 336.826352 -291.095938) (xy 336.825857 -291.120545)
			(xy 336.817962 -291.169122) (xy 336.802378 -291.215803) (xy 336.779507 -291.25938) (xy 336.749942 -291.298724)
			(xy 336.714449 -291.332816) (xy 336.673946 -291.360772) (xy 336.629484 -291.38187) (xy 336.582213 -291.395562)
			(xy 336.533358 -291.401494) (xy 336.484183 -291.399513) (xy 336.435964 -291.389669) (xy 336.389948 -291.372217)
			(xy 336.347327 -291.34761) (xy 336.309206 -291.316485) (xy 336.276571 -291.279648) (xy 336.250268 -291.238052)
			(xy 336.230977 -291.192776) (xy 336.2192 -291.144992) (xy 336.21524 -291.095938) (xy 335.896712 -291.095938)
			(xy 335.8962 -291.121384) (xy 335.888036 -291.171618) (xy 335.87192 -291.219892) (xy 335.848269 -291.264955)
			(xy 335.817696 -291.305641) (xy 335.780992 -291.340896) (xy 335.739108 -291.369806) (xy 335.693129 -291.391623)
			(xy 335.644245 -291.405783) (xy 335.593724 -291.411917) (xy 335.542872 -291.409868) (xy 335.493008 -291.399688)
			(xy 335.445422 -291.381641) (xy 335.401348 -291.356195) (xy 335.361926 -291.324008) (xy 335.328178 -291.285914)
			(xy 335.300977 -291.2429) (xy 335.281029 -291.19608) (xy 335.26885 -291.146666) (xy 335.264755 -291.095938)
			(xy 334.946498 -291.095938) (xy 334.946003 -291.120545) (xy 334.938108 -291.169122) (xy 334.922524 -291.215803)
			(xy 334.899653 -291.25938) (xy 334.870088 -291.298724) (xy 334.834595 -291.332816) (xy 334.794092 -291.360772)
			(xy 334.74963 -291.38187) (xy 334.702359 -291.395562) (xy 334.653504 -291.401494) (xy 334.604329 -291.399513)
			(xy 334.55611 -291.389669) (xy 334.510094 -291.372217) (xy 334.467473 -291.34761) (xy 334.429352 -291.316485)
			(xy 334.396717 -291.279648) (xy 334.370414 -291.238052) (xy 334.351123 -291.192776) (xy 334.339346 -291.144992)
			(xy 334.335386 -291.095938) (xy 334.016858 -291.095938) (xy 334.016346 -291.121384) (xy 334.008182 -291.171618)
			(xy 333.992066 -291.219892) (xy 333.968415 -291.264955) (xy 333.937842 -291.305641) (xy 333.901138 -291.340896)
			(xy 333.859254 -291.369806) (xy 333.813275 -291.391623) (xy 333.764391 -291.405783) (xy 333.71387 -291.411917)
			(xy 333.663018 -291.409868) (xy 333.613154 -291.399688) (xy 333.565568 -291.381641) (xy 333.521494 -291.356195)
			(xy 333.482072 -291.324008) (xy 333.448324 -291.285914) (xy 333.421123 -291.2429) (xy 333.401175 -291.19608)
			(xy 333.388996 -291.146666) (xy 333.384901 -291.095938) (xy 333.076804 -291.095938) (xy 333.076292 -291.121384)
			(xy 333.068128 -291.171618) (xy 333.052012 -291.219892) (xy 333.028361 -291.264955) (xy 332.997788 -291.305641)
			(xy 332.961084 -291.340896) (xy 332.9192 -291.369806) (xy 332.873221 -291.391623) (xy 332.824337 -291.405783)
			(xy 332.773816 -291.411917) (xy 332.722964 -291.409868) (xy 332.6731 -291.399688) (xy 332.625514 -291.381641)
			(xy 332.58144 -291.356195) (xy 332.542018 -291.324008) (xy 332.50827 -291.285914) (xy 332.481069 -291.2429)
			(xy 332.461121 -291.19608) (xy 332.448942 -291.146666) (xy 332.444847 -291.095938) (xy 332.126336 -291.095938)
			(xy 332.125841 -291.120545) (xy 332.117946 -291.169122) (xy 332.102362 -291.215803) (xy 332.079491 -291.25938)
			(xy 332.049926 -291.298724) (xy 332.014433 -291.332816) (xy 331.97393 -291.360772) (xy 331.929468 -291.38187)
			(xy 331.882197 -291.395562) (xy 331.833342 -291.401494) (xy 331.784167 -291.399513) (xy 331.735948 -291.389669)
			(xy 331.689932 -291.372217) (xy 331.647311 -291.34761) (xy 331.60919 -291.316485) (xy 331.576555 -291.279648)
			(xy 331.550252 -291.238052) (xy 331.530961 -291.192776) (xy 331.519184 -291.144992) (xy 331.515224 -291.095938)
			(xy 331.196696 -291.095938) (xy 331.196184 -291.121384) (xy 331.18802 -291.171618) (xy 331.171904 -291.219892)
			(xy 331.148253 -291.264955) (xy 331.11768 -291.305641) (xy 331.080976 -291.340896) (xy 331.039092 -291.369806)
			(xy 330.993113 -291.391623) (xy 330.944229 -291.405783) (xy 330.893708 -291.411917) (xy 330.842856 -291.409868)
			(xy 330.792992 -291.399688) (xy 330.745406 -291.381641) (xy 330.701332 -291.356195) (xy 330.66191 -291.324008)
			(xy 330.628162 -291.285914) (xy 330.600961 -291.2429) (xy 330.581013 -291.19608) (xy 330.568834 -291.146666)
			(xy 330.564739 -291.095938) (xy 330.246482 -291.095938) (xy 330.245987 -291.120545) (xy 330.238092 -291.169122)
			(xy 330.222508 -291.215803) (xy 330.199637 -291.25938) (xy 330.170072 -291.298724) (xy 330.134579 -291.332816)
			(xy 330.094076 -291.360772) (xy 330.049614 -291.38187) (xy 330.002343 -291.395562) (xy 329.953488 -291.401494)
			(xy 329.904313 -291.399513) (xy 329.856094 -291.389669) (xy 329.810078 -291.372217) (xy 329.767457 -291.34761)
			(xy 329.729336 -291.316485) (xy 329.696701 -291.279648) (xy 329.670398 -291.238052) (xy 329.651107 -291.192776)
			(xy 329.63933 -291.144992) (xy 329.63537 -291.095938) (xy 329.316842 -291.095938) (xy 329.31633 -291.121384)
			(xy 329.308166 -291.171618) (xy 329.29205 -291.219892) (xy 329.268399 -291.264955) (xy 329.237826 -291.305641)
			(xy 329.201122 -291.340896) (xy 329.159238 -291.369806) (xy 329.113259 -291.391623) (xy 329.064375 -291.405783)
			(xy 329.013854 -291.411917) (xy 328.963002 -291.409868) (xy 328.913138 -291.399688) (xy 328.865552 -291.381641)
			(xy 328.821478 -291.356195) (xy 328.782056 -291.324008) (xy 328.748308 -291.285914) (xy 328.721107 -291.2429)
			(xy 328.701159 -291.19608) (xy 328.68898 -291.146666) (xy 328.684885 -291.095938) (xy 328.366374 -291.095938)
			(xy 328.365879 -291.120545) (xy 328.357984 -291.169122) (xy 328.3424 -291.215803) (xy 328.319529 -291.25938)
			(xy 328.289964 -291.298724) (xy 328.254471 -291.332816) (xy 328.213968 -291.360772) (xy 328.169506 -291.38187)
			(xy 328.122235 -291.395562) (xy 328.07338 -291.401494) (xy 328.024205 -291.399513) (xy 327.975986 -291.389669)
			(xy 327.92997 -291.372217) (xy 327.887349 -291.34761) (xy 327.849228 -291.316485) (xy 327.816593 -291.279648)
			(xy 327.79029 -291.238052) (xy 327.770999 -291.192776) (xy 327.759222 -291.144992) (xy 327.755262 -291.095938)
			(xy 325.203519 -291.095938) (xy 325.161384 -291.115932) (xy 325.114113 -291.129624) (xy 325.065258 -291.135556)
			(xy 325.016083 -291.133575) (xy 324.967864 -291.123731) (xy 324.921848 -291.106279) (xy 324.879227 -291.081672)
			(xy 324.841106 -291.050547) (xy 324.808471 -291.01371) (xy 324.782168 -290.972114) (xy 324.762877 -290.926838)
			(xy 324.7511 -290.879054) (xy 324.74714 -290.83) (xy 310.45912 -290.83) (xy 310.45912 -291.905944)
			(xy 326.345308 -291.905944) (xy 326.349268 -291.85689) (xy 326.361045 -291.809106) (xy 326.380336 -291.76383)
			(xy 326.406639 -291.722234) (xy 326.439274 -291.685397) (xy 326.477395 -291.654272) (xy 326.520016 -291.629665)
			(xy 326.566032 -291.612213) (xy 326.614251 -291.602369) (xy 326.663426 -291.600388) (xy 326.712281 -291.60632)
			(xy 326.759552 -291.620012) (xy 326.804014 -291.64111) (xy 326.844517 -291.669066) (xy 326.88001 -291.703158)
			(xy 326.909575 -291.742502) (xy 326.932446 -291.786079) (xy 326.94803 -291.83276) (xy 326.955925 -291.881337)
			(xy 326.95642 -291.905944) (xy 328.225416 -291.905944) (xy 328.229376 -291.85689) (xy 328.241153 -291.809106)
			(xy 328.260444 -291.76383) (xy 328.286747 -291.722234) (xy 328.319382 -291.685397) (xy 328.357503 -291.654272)
			(xy 328.400124 -291.629665) (xy 328.44614 -291.612213) (xy 328.494359 -291.602369) (xy 328.543534 -291.600388)
			(xy 328.592389 -291.60632) (xy 328.63966 -291.620012) (xy 328.684122 -291.64111) (xy 328.724625 -291.669066)
			(xy 328.760118 -291.703158) (xy 328.789683 -291.742502) (xy 328.812554 -291.786079) (xy 328.828138 -291.83276)
			(xy 328.836033 -291.881337) (xy 328.836528 -291.905944) (xy 329.154785 -291.905944) (xy 329.15888 -291.855216)
			(xy 329.171059 -291.805802) (xy 329.191007 -291.758982) (xy 329.218208 -291.715968) (xy 329.251956 -291.677874)
			(xy 329.291378 -291.645687) (xy 329.335452 -291.620241) (xy 329.383038 -291.602194) (xy 329.432902 -291.592014)
			(xy 329.483754 -291.589965) (xy 329.534275 -291.596099) (xy 329.583159 -291.610259) (xy 329.629138 -291.632076)
			(xy 329.671022 -291.660986) (xy 329.707726 -291.696241) (xy 329.738299 -291.736927) (xy 329.76195 -291.78199)
			(xy 329.778066 -291.830264) (xy 329.78623 -291.880498) (xy 329.786742 -291.905944) (xy 330.094839 -291.905944)
			(xy 330.098934 -291.855216) (xy 330.111113 -291.805802) (xy 330.131061 -291.758982) (xy 330.158262 -291.715968)
			(xy 330.19201 -291.677874) (xy 330.231432 -291.645687) (xy 330.275506 -291.620241) (xy 330.323092 -291.602194)
			(xy 330.372956 -291.592014) (xy 330.423808 -291.589965) (xy 330.474329 -291.596099) (xy 330.523213 -291.610259)
			(xy 330.569192 -291.632076) (xy 330.611076 -291.660986) (xy 330.64778 -291.696241) (xy 330.678353 -291.736927)
			(xy 330.702004 -291.78199) (xy 330.71812 -291.830264) (xy 330.726284 -291.880498) (xy 330.726796 -291.905944)
			(xy 331.045324 -291.905944) (xy 331.049284 -291.85689) (xy 331.061061 -291.809106) (xy 331.080352 -291.76383)
			(xy 331.106655 -291.722234) (xy 331.13929 -291.685397) (xy 331.177411 -291.654272) (xy 331.220032 -291.629665)
			(xy 331.266048 -291.612213) (xy 331.314267 -291.602369) (xy 331.363442 -291.600388) (xy 331.412297 -291.60632)
			(xy 331.459568 -291.620012) (xy 331.50403 -291.64111) (xy 331.544533 -291.669066) (xy 331.580026 -291.703158)
			(xy 331.609591 -291.742502) (xy 331.632462 -291.786079) (xy 331.648046 -291.83276) (xy 331.655941 -291.881337)
			(xy 331.656436 -291.905944) (xy 331.974947 -291.905944) (xy 331.979042 -291.855216) (xy 331.991221 -291.805802)
			(xy 332.011169 -291.758982) (xy 332.03837 -291.715968) (xy 332.072118 -291.677874) (xy 332.11154 -291.645687)
			(xy 332.155614 -291.620241) (xy 332.2032 -291.602194) (xy 332.253064 -291.592014) (xy 332.303916 -291.589965)
			(xy 332.354437 -291.596099) (xy 332.403321 -291.610259) (xy 332.4493 -291.632076) (xy 332.491184 -291.660986)
			(xy 332.527888 -291.696241) (xy 332.558461 -291.736927) (xy 332.582112 -291.78199) (xy 332.598228 -291.830264)
			(xy 332.606392 -291.880498) (xy 332.606904 -291.905944) (xy 332.925178 -291.905944) (xy 332.929138 -291.85689)
			(xy 332.940915 -291.809106) (xy 332.960206 -291.76383) (xy 332.986509 -291.722234) (xy 333.019144 -291.685397)
			(xy 333.057265 -291.654272) (xy 333.099886 -291.629665) (xy 333.145902 -291.612213) (xy 333.194121 -291.602369)
			(xy 333.243296 -291.600388) (xy 333.292151 -291.60632) (xy 333.339422 -291.620012) (xy 333.383884 -291.64111)
			(xy 333.424387 -291.669066) (xy 333.45988 -291.703158) (xy 333.489445 -291.742502) (xy 333.512316 -291.786079)
			(xy 333.5279 -291.83276) (xy 333.535795 -291.881337) (xy 333.53629 -291.905944) (xy 333.854801 -291.905944)
			(xy 333.858896 -291.855216) (xy 333.871075 -291.805802) (xy 333.891023 -291.758982) (xy 333.918224 -291.715968)
			(xy 333.951972 -291.677874) (xy 333.991394 -291.645687) (xy 334.035468 -291.620241) (xy 334.083054 -291.602194)
			(xy 334.132918 -291.592014) (xy 334.18377 -291.589965) (xy 334.234291 -291.596099) (xy 334.283175 -291.610259)
			(xy 334.329154 -291.632076) (xy 334.371038 -291.660986) (xy 334.407742 -291.696241) (xy 334.438315 -291.736927)
			(xy 334.461966 -291.78199) (xy 334.478082 -291.830264) (xy 334.486246 -291.880498) (xy 334.486758 -291.905944)
			(xy 334.805286 -291.905944) (xy 334.809246 -291.85689) (xy 334.821023 -291.809106) (xy 334.840314 -291.76383)
			(xy 334.866617 -291.722234) (xy 334.899252 -291.685397) (xy 334.937373 -291.654272) (xy 334.979994 -291.629665)
			(xy 335.02601 -291.612213) (xy 335.074229 -291.602369) (xy 335.123404 -291.600388) (xy 335.172259 -291.60632)
			(xy 335.21953 -291.620012) (xy 335.263992 -291.64111) (xy 335.304495 -291.669066) (xy 335.339988 -291.703158)
			(xy 335.369553 -291.742502) (xy 335.392424 -291.786079) (xy 335.408008 -291.83276) (xy 335.415903 -291.881337)
			(xy 335.416398 -291.905944) (xy 335.734909 -291.905944) (xy 335.739004 -291.855216) (xy 335.751183 -291.805802)
			(xy 335.771131 -291.758982) (xy 335.798332 -291.715968) (xy 335.83208 -291.677874) (xy 335.871502 -291.645687)
			(xy 335.915576 -291.620241) (xy 335.963162 -291.602194) (xy 336.013026 -291.592014) (xy 336.063878 -291.589965)
			(xy 336.114399 -291.596099) (xy 336.163283 -291.610259) (xy 336.209262 -291.632076) (xy 336.251146 -291.660986)
			(xy 336.28785 -291.696241) (xy 336.318423 -291.736927) (xy 336.342074 -291.78199) (xy 336.35819 -291.830264)
			(xy 336.366354 -291.880498) (xy 336.366866 -291.905944) (xy 336.674963 -291.905944) (xy 336.679058 -291.855216)
			(xy 336.691237 -291.805802) (xy 336.711185 -291.758982) (xy 336.738386 -291.715968) (xy 336.772134 -291.677874)
			(xy 336.811556 -291.645687) (xy 336.85563 -291.620241) (xy 336.903216 -291.602194) (xy 336.95308 -291.592014)
			(xy 337.003932 -291.589965) (xy 337.054453 -291.596099) (xy 337.103337 -291.610259) (xy 337.149316 -291.632076)
			(xy 337.1912 -291.660986) (xy 337.227904 -291.696241) (xy 337.258477 -291.736927) (xy 337.282128 -291.78199)
			(xy 337.298244 -291.830264) (xy 337.306408 -291.880498) (xy 337.30692 -291.905944) (xy 337.625194 -291.905944)
			(xy 337.629154 -291.85689) (xy 337.640931 -291.809106) (xy 337.660222 -291.76383) (xy 337.686525 -291.722234)
			(xy 337.71916 -291.685397) (xy 337.757281 -291.654272) (xy 337.799902 -291.629665) (xy 337.845918 -291.612213)
			(xy 337.894137 -291.602369) (xy 337.943312 -291.600388) (xy 337.992167 -291.60632) (xy 338.039438 -291.620012)
			(xy 338.0839 -291.64111) (xy 338.124403 -291.669066) (xy 338.159896 -291.703158) (xy 338.189461 -291.742502)
			(xy 338.212332 -291.786079) (xy 338.227916 -291.83276) (xy 338.235811 -291.881337) (xy 338.236306 -291.905944)
			(xy 338.554817 -291.905944) (xy 338.558912 -291.855216) (xy 338.571091 -291.805802) (xy 338.591039 -291.758982)
			(xy 338.61824 -291.715968) (xy 338.651988 -291.677874) (xy 338.69141 -291.645687) (xy 338.735484 -291.620241)
			(xy 338.78307 -291.602194) (xy 338.832934 -291.592014) (xy 338.883786 -291.589965) (xy 338.934307 -291.596099)
			(xy 338.983191 -291.610259) (xy 339.02917 -291.632076) (xy 339.071054 -291.660986) (xy 339.107758 -291.696241)
			(xy 339.138331 -291.736927) (xy 339.161982 -291.78199) (xy 339.178098 -291.830264) (xy 339.186262 -291.880498)
			(xy 339.186774 -291.905944) (xy 339.505302 -291.905944) (xy 339.509262 -291.85689) (xy 339.521039 -291.809106)
			(xy 339.54033 -291.76383) (xy 339.566633 -291.722234) (xy 339.599268 -291.685397) (xy 339.637389 -291.654272)
			(xy 339.68001 -291.629665) (xy 339.726026 -291.612213) (xy 339.774245 -291.602369) (xy 339.82342 -291.600388)
			(xy 339.872275 -291.60632) (xy 339.919546 -291.620012) (xy 339.964008 -291.64111) (xy 340.004511 -291.669066)
			(xy 340.040004 -291.703158) (xy 340.069569 -291.742502) (xy 340.09244 -291.786079) (xy 340.108024 -291.83276)
			(xy 340.115919 -291.881337) (xy 340.116414 -291.905944) (xy 340.434925 -291.905944) (xy 340.43902 -291.855216)
			(xy 340.451199 -291.805802) (xy 340.471147 -291.758982) (xy 340.498348 -291.715968) (xy 340.532096 -291.677874)
			(xy 340.571518 -291.645687) (xy 340.615592 -291.620241) (xy 340.663178 -291.602194) (xy 340.713042 -291.592014)
			(xy 340.763894 -291.589965) (xy 340.814415 -291.596099) (xy 340.863299 -291.610259) (xy 340.909278 -291.632076)
			(xy 340.951162 -291.660986) (xy 340.987866 -291.696241) (xy 341.018439 -291.736927) (xy 341.04209 -291.78199)
			(xy 341.058206 -291.830264) (xy 341.06637 -291.880498) (xy 341.066882 -291.905944) (xy 341.38541 -291.905944)
			(xy 341.38937 -291.85689) (xy 341.401147 -291.809106) (xy 341.420438 -291.76383) (xy 341.446741 -291.722234)
			(xy 341.479376 -291.685397) (xy 341.517497 -291.654272) (xy 341.560118 -291.629665) (xy 341.606134 -291.612213)
			(xy 341.654353 -291.602369) (xy 341.703528 -291.600388) (xy 341.752383 -291.60632) (xy 341.799654 -291.620012)
			(xy 341.844116 -291.64111) (xy 341.884619 -291.669066) (xy 341.920112 -291.703158) (xy 341.949677 -291.742502)
			(xy 341.972548 -291.786079) (xy 341.988132 -291.83276) (xy 341.996027 -291.881337) (xy 341.996522 -291.905944)
			(xy 342.314779 -291.905944) (xy 342.318874 -291.855216) (xy 342.331053 -291.805802) (xy 342.351001 -291.758982)
			(xy 342.378202 -291.715968) (xy 342.41195 -291.677874) (xy 342.451372 -291.645687) (xy 342.495446 -291.620241)
			(xy 342.543032 -291.602194) (xy 342.592896 -291.592014) (xy 342.643748 -291.589965) (xy 342.694269 -291.596099)
			(xy 342.743153 -291.610259) (xy 342.789132 -291.632076) (xy 342.831016 -291.660986) (xy 342.86772 -291.696241)
			(xy 342.898293 -291.736927) (xy 342.921944 -291.78199) (xy 342.93806 -291.830264) (xy 342.946224 -291.880498)
			(xy 342.946736 -291.905944) (xy 343.254833 -291.905944) (xy 343.258928 -291.855216) (xy 343.271107 -291.805802)
			(xy 343.291055 -291.758982) (xy 343.318256 -291.715968) (xy 343.352004 -291.677874) (xy 343.391426 -291.645687)
			(xy 343.4355 -291.620241) (xy 343.483086 -291.602194) (xy 343.53295 -291.592014) (xy 343.583802 -291.589965)
			(xy 343.634323 -291.596099) (xy 343.683207 -291.610259) (xy 343.729186 -291.632076) (xy 343.77107 -291.660986)
			(xy 343.807774 -291.696241) (xy 343.838347 -291.736927) (xy 343.861998 -291.78199) (xy 343.878114 -291.830264)
			(xy 343.886278 -291.880498) (xy 343.88679 -291.905944) (xy 344.205318 -291.905944) (xy 344.209278 -291.85689)
			(xy 344.221055 -291.809106) (xy 344.240346 -291.76383) (xy 344.266649 -291.722234) (xy 344.299284 -291.685397)
			(xy 344.337405 -291.654272) (xy 344.380026 -291.629665) (xy 344.426042 -291.612213) (xy 344.474261 -291.602369)
			(xy 344.523436 -291.600388) (xy 344.572291 -291.60632) (xy 344.619562 -291.620012) (xy 344.664024 -291.64111)
			(xy 344.704527 -291.669066) (xy 344.74002 -291.703158) (xy 344.769585 -291.742502) (xy 344.792456 -291.786079)
			(xy 344.80804 -291.83276) (xy 344.815935 -291.881337) (xy 344.81643 -291.905944) (xy 345.145372 -291.905944)
			(xy 345.149332 -291.85689) (xy 345.161109 -291.809106) (xy 345.1804 -291.76383) (xy 345.206703 -291.722234)
			(xy 345.239338 -291.685397) (xy 345.277459 -291.654272) (xy 345.32008 -291.629665) (xy 345.366096 -291.612213)
			(xy 345.414315 -291.602369) (xy 345.46349 -291.600388) (xy 345.512345 -291.60632) (xy 345.559616 -291.620012)
			(xy 345.604078 -291.64111) (xy 345.644581 -291.669066) (xy 345.680074 -291.703158) (xy 345.709639 -291.742502)
			(xy 345.73251 -291.786079) (xy 345.748094 -291.83276) (xy 345.755989 -291.881337) (xy 345.756484 -291.905944)
			(xy 346.085426 -291.905944) (xy 346.089386 -291.85689) (xy 346.101163 -291.809106) (xy 346.120454 -291.76383)
			(xy 346.146757 -291.722234) (xy 346.179392 -291.685397) (xy 346.217513 -291.654272) (xy 346.260134 -291.629665)
			(xy 346.30615 -291.612213) (xy 346.354369 -291.602369) (xy 346.403544 -291.600388) (xy 346.452399 -291.60632)
			(xy 346.49967 -291.620012) (xy 346.544132 -291.64111) (xy 346.584635 -291.669066) (xy 346.620128 -291.703158)
			(xy 346.649693 -291.742502) (xy 346.672564 -291.786079) (xy 346.688148 -291.83276) (xy 346.696043 -291.881337)
			(xy 346.696538 -291.905944) (xy 347.025226 -291.905944) (xy 347.029186 -291.85689) (xy 347.040963 -291.809106)
			(xy 347.060254 -291.76383) (xy 347.086557 -291.722234) (xy 347.119192 -291.685397) (xy 347.157313 -291.654272)
			(xy 347.199934 -291.629665) (xy 347.24595 -291.612213) (xy 347.294169 -291.602369) (xy 347.343344 -291.600388)
			(xy 347.392199 -291.60632) (xy 347.43947 -291.620012) (xy 347.483932 -291.64111) (xy 347.524435 -291.669066)
			(xy 347.559928 -291.703158) (xy 347.589493 -291.742502) (xy 347.612364 -291.786079) (xy 347.627948 -291.83276)
			(xy 347.635843 -291.881337) (xy 347.636338 -291.905944) (xy 347.96528 -291.905944) (xy 347.96924 -291.85689)
			(xy 347.981017 -291.809106) (xy 348.000308 -291.76383) (xy 348.026611 -291.722234) (xy 348.059246 -291.685397)
			(xy 348.097367 -291.654272) (xy 348.139988 -291.629665) (xy 348.186004 -291.612213) (xy 348.234223 -291.602369)
			(xy 348.283398 -291.600388) (xy 348.332253 -291.60632) (xy 348.379524 -291.620012) (xy 348.423986 -291.64111)
			(xy 348.464489 -291.669066) (xy 348.499982 -291.703158) (xy 348.529547 -291.742502) (xy 348.552418 -291.786079)
			(xy 348.568002 -291.83276) (xy 348.575897 -291.881337) (xy 348.576392 -291.905944) (xy 348.905334 -291.905944)
			(xy 348.909294 -291.85689) (xy 348.921071 -291.809106) (xy 348.940362 -291.76383) (xy 348.966665 -291.722234)
			(xy 348.9993 -291.685397) (xy 349.037421 -291.654272) (xy 349.080042 -291.629665) (xy 349.126058 -291.612213)
			(xy 349.174277 -291.602369) (xy 349.223452 -291.600388) (xy 349.272307 -291.60632) (xy 349.319578 -291.620012)
			(xy 349.36404 -291.64111) (xy 349.404543 -291.669066) (xy 349.440036 -291.703158) (xy 349.469601 -291.742502)
			(xy 349.492472 -291.786079) (xy 349.508056 -291.83276) (xy 349.515951 -291.881337) (xy 349.516446 -291.905944)
			(xy 349.845388 -291.905944) (xy 349.849348 -291.85689) (xy 349.861125 -291.809106) (xy 349.880416 -291.76383)
			(xy 349.906719 -291.722234) (xy 349.939354 -291.685397) (xy 349.977475 -291.654272) (xy 350.020096 -291.629665)
			(xy 350.066112 -291.612213) (xy 350.114331 -291.602369) (xy 350.163506 -291.600388) (xy 350.212361 -291.60632)
			(xy 350.259632 -291.620012) (xy 350.304094 -291.64111) (xy 350.344597 -291.669066) (xy 350.38009 -291.703158)
			(xy 350.409655 -291.742502) (xy 350.432526 -291.786079) (xy 350.44811 -291.83276) (xy 350.456005 -291.881337)
			(xy 350.4565 -291.905944) (xy 350.785442 -291.905944) (xy 350.789402 -291.85689) (xy 350.801179 -291.809106)
			(xy 350.82047 -291.76383) (xy 350.846773 -291.722234) (xy 350.879408 -291.685397) (xy 350.917529 -291.654272)
			(xy 350.96015 -291.629665) (xy 351.006166 -291.612213) (xy 351.054385 -291.602369) (xy 351.10356 -291.600388)
			(xy 351.152415 -291.60632) (xy 351.199686 -291.620012) (xy 351.244148 -291.64111) (xy 351.284651 -291.669066)
			(xy 351.320144 -291.703158) (xy 351.349709 -291.742502) (xy 351.37258 -291.786079) (xy 351.388164 -291.83276)
			(xy 351.396059 -291.881337) (xy 351.396554 -291.905944) (xy 351.396059 -291.930551) (xy 351.388164 -291.979128)
			(xy 351.37258 -292.025809) (xy 351.349709 -292.069386) (xy 351.320144 -292.10873) (xy 351.284651 -292.142822)
			(xy 351.244148 -292.170778) (xy 351.199686 -292.191876) (xy 351.152415 -292.205568) (xy 351.10356 -292.2115)
			(xy 351.054385 -292.209519) (xy 351.006166 -292.199675) (xy 350.96015 -292.182223) (xy 350.917529 -292.157616)
			(xy 350.879408 -292.126491) (xy 350.846773 -292.089654) (xy 350.82047 -292.048058) (xy 350.801179 -292.002782)
			(xy 350.789402 -291.954998) (xy 350.785442 -291.905944) (xy 350.4565 -291.905944) (xy 350.456005 -291.930551)
			(xy 350.44811 -291.979128) (xy 350.432526 -292.025809) (xy 350.409655 -292.069386) (xy 350.38009 -292.10873)
			(xy 350.344597 -292.142822) (xy 350.304094 -292.170778) (xy 350.259632 -292.191876) (xy 350.212361 -292.205568)
			(xy 350.163506 -292.2115) (xy 350.114331 -292.209519) (xy 350.066112 -292.199675) (xy 350.020096 -292.182223)
			(xy 349.977475 -292.157616) (xy 349.939354 -292.126491) (xy 349.906719 -292.089654) (xy 349.880416 -292.048058)
			(xy 349.861125 -292.002782) (xy 349.849348 -291.954998) (xy 349.845388 -291.905944) (xy 349.516446 -291.905944)
			(xy 349.515951 -291.930551) (xy 349.508056 -291.979128) (xy 349.492472 -292.025809) (xy 349.469601 -292.069386)
			(xy 349.440036 -292.10873) (xy 349.404543 -292.142822) (xy 349.36404 -292.170778) (xy 349.319578 -292.191876)
			(xy 349.272307 -292.205568) (xy 349.223452 -292.2115) (xy 349.174277 -292.209519) (xy 349.126058 -292.199675)
			(xy 349.080042 -292.182223) (xy 349.037421 -292.157616) (xy 348.9993 -292.126491) (xy 348.966665 -292.089654)
			(xy 348.940362 -292.048058) (xy 348.921071 -292.002782) (xy 348.909294 -291.954998) (xy 348.905334 -291.905944)
			(xy 348.576392 -291.905944) (xy 348.575897 -291.930551) (xy 348.568002 -291.979128) (xy 348.552418 -292.025809)
			(xy 348.529547 -292.069386) (xy 348.499982 -292.10873) (xy 348.464489 -292.142822) (xy 348.423986 -292.170778)
			(xy 348.379524 -292.191876) (xy 348.332253 -292.205568) (xy 348.283398 -292.2115) (xy 348.234223 -292.209519)
			(xy 348.186004 -292.199675) (xy 348.139988 -292.182223) (xy 348.097367 -292.157616) (xy 348.059246 -292.126491)
			(xy 348.026611 -292.089654) (xy 348.000308 -292.048058) (xy 347.981017 -292.002782) (xy 347.96924 -291.954998)
			(xy 347.96528 -291.905944) (xy 347.636338 -291.905944) (xy 347.635843 -291.930551) (xy 347.627948 -291.979128)
			(xy 347.612364 -292.025809) (xy 347.589493 -292.069386) (xy 347.559928 -292.10873) (xy 347.524435 -292.142822)
			(xy 347.483932 -292.170778) (xy 347.43947 -292.191876) (xy 347.392199 -292.205568) (xy 347.343344 -292.2115)
			(xy 347.294169 -292.209519) (xy 347.24595 -292.199675) (xy 347.199934 -292.182223) (xy 347.157313 -292.157616)
			(xy 347.119192 -292.126491) (xy 347.086557 -292.089654) (xy 347.060254 -292.048058) (xy 347.040963 -292.002782)
			(xy 347.029186 -291.954998) (xy 347.025226 -291.905944) (xy 346.696538 -291.905944) (xy 346.696043 -291.930551)
			(xy 346.688148 -291.979128) (xy 346.672564 -292.025809) (xy 346.649693 -292.069386) (xy 346.620128 -292.10873)
			(xy 346.584635 -292.142822) (xy 346.544132 -292.170778) (xy 346.49967 -292.191876) (xy 346.452399 -292.205568)
			(xy 346.403544 -292.2115) (xy 346.354369 -292.209519) (xy 346.30615 -292.199675) (xy 346.260134 -292.182223)
			(xy 346.217513 -292.157616) (xy 346.179392 -292.126491) (xy 346.146757 -292.089654) (xy 346.120454 -292.048058)
			(xy 346.101163 -292.002782) (xy 346.089386 -291.954998) (xy 346.085426 -291.905944) (xy 345.756484 -291.905944)
			(xy 345.755989 -291.930551) (xy 345.748094 -291.979128) (xy 345.73251 -292.025809) (xy 345.709639 -292.069386)
			(xy 345.680074 -292.10873) (xy 345.644581 -292.142822) (xy 345.604078 -292.170778) (xy 345.559616 -292.191876)
			(xy 345.512345 -292.205568) (xy 345.46349 -292.2115) (xy 345.414315 -292.209519) (xy 345.366096 -292.199675)
			(xy 345.32008 -292.182223) (xy 345.277459 -292.157616) (xy 345.239338 -292.126491) (xy 345.206703 -292.089654)
			(xy 345.1804 -292.048058) (xy 345.161109 -292.002782) (xy 345.149332 -291.954998) (xy 345.145372 -291.905944)
			(xy 344.81643 -291.905944) (xy 344.815935 -291.930551) (xy 344.80804 -291.979128) (xy 344.792456 -292.025809)
			(xy 344.769585 -292.069386) (xy 344.74002 -292.10873) (xy 344.704527 -292.142822) (xy 344.664024 -292.170778)
			(xy 344.619562 -292.191876) (xy 344.572291 -292.205568) (xy 344.523436 -292.2115) (xy 344.474261 -292.209519)
			(xy 344.426042 -292.199675) (xy 344.380026 -292.182223) (xy 344.337405 -292.157616) (xy 344.299284 -292.126491)
			(xy 344.266649 -292.089654) (xy 344.240346 -292.048058) (xy 344.221055 -292.002782) (xy 344.209278 -291.954998)
			(xy 344.205318 -291.905944) (xy 343.88679 -291.905944) (xy 343.886278 -291.93139) (xy 343.878114 -291.981624)
			(xy 343.861998 -292.029898) (xy 343.838347 -292.074961) (xy 343.807774 -292.115647) (xy 343.77107 -292.150902)
			(xy 343.729186 -292.179812) (xy 343.683207 -292.201629) (xy 343.634323 -292.215789) (xy 343.583802 -292.221923)
			(xy 343.53295 -292.219874) (xy 343.483086 -292.209694) (xy 343.4355 -292.191647) (xy 343.391426 -292.166201)
			(xy 343.352004 -292.134014) (xy 343.318256 -292.09592) (xy 343.291055 -292.052906) (xy 343.271107 -292.006086)
			(xy 343.258928 -291.956672) (xy 343.254833 -291.905944) (xy 342.946736 -291.905944) (xy 342.946224 -291.93139)
			(xy 342.93806 -291.981624) (xy 342.921944 -292.029898) (xy 342.898293 -292.074961) (xy 342.86772 -292.115647)
			(xy 342.831016 -292.150902) (xy 342.789132 -292.179812) (xy 342.743153 -292.201629) (xy 342.694269 -292.215789)
			(xy 342.643748 -292.221923) (xy 342.592896 -292.219874) (xy 342.543032 -292.209694) (xy 342.495446 -292.191647)
			(xy 342.451372 -292.166201) (xy 342.41195 -292.134014) (xy 342.378202 -292.09592) (xy 342.351001 -292.052906)
			(xy 342.331053 -292.006086) (xy 342.318874 -291.956672) (xy 342.314779 -291.905944) (xy 341.996522 -291.905944)
			(xy 341.996027 -291.930551) (xy 341.988132 -291.979128) (xy 341.972548 -292.025809) (xy 341.949677 -292.069386)
			(xy 341.920112 -292.10873) (xy 341.884619 -292.142822) (xy 341.844116 -292.170778) (xy 341.799654 -292.191876)
			(xy 341.752383 -292.205568) (xy 341.703528 -292.2115) (xy 341.654353 -292.209519) (xy 341.606134 -292.199675)
			(xy 341.560118 -292.182223) (xy 341.517497 -292.157616) (xy 341.479376 -292.126491) (xy 341.446741 -292.089654)
			(xy 341.420438 -292.048058) (xy 341.401147 -292.002782) (xy 341.38937 -291.954998) (xy 341.38541 -291.905944)
			(xy 341.066882 -291.905944) (xy 341.06637 -291.93139) (xy 341.058206 -291.981624) (xy 341.04209 -292.029898)
			(xy 341.018439 -292.074961) (xy 340.987866 -292.115647) (xy 340.951162 -292.150902) (xy 340.909278 -292.179812)
			(xy 340.863299 -292.201629) (xy 340.814415 -292.215789) (xy 340.763894 -292.221923) (xy 340.713042 -292.219874)
			(xy 340.663178 -292.209694) (xy 340.615592 -292.191647) (xy 340.571518 -292.166201) (xy 340.532096 -292.134014)
			(xy 340.498348 -292.09592) (xy 340.471147 -292.052906) (xy 340.451199 -292.006086) (xy 340.43902 -291.956672)
			(xy 340.434925 -291.905944) (xy 340.116414 -291.905944) (xy 340.115919 -291.930551) (xy 340.108024 -291.979128)
			(xy 340.09244 -292.025809) (xy 340.069569 -292.069386) (xy 340.040004 -292.10873) (xy 340.004511 -292.142822)
			(xy 339.964008 -292.170778) (xy 339.919546 -292.191876) (xy 339.872275 -292.205568) (xy 339.82342 -292.2115)
			(xy 339.774245 -292.209519) (xy 339.726026 -292.199675) (xy 339.68001 -292.182223) (xy 339.637389 -292.157616)
			(xy 339.599268 -292.126491) (xy 339.566633 -292.089654) (xy 339.54033 -292.048058) (xy 339.521039 -292.002782)
			(xy 339.509262 -291.954998) (xy 339.505302 -291.905944) (xy 339.186774 -291.905944) (xy 339.186262 -291.93139)
			(xy 339.178098 -291.981624) (xy 339.161982 -292.029898) (xy 339.138331 -292.074961) (xy 339.107758 -292.115647)
			(xy 339.071054 -292.150902) (xy 339.02917 -292.179812) (xy 338.983191 -292.201629) (xy 338.934307 -292.215789)
			(xy 338.883786 -292.221923) (xy 338.832934 -292.219874) (xy 338.78307 -292.209694) (xy 338.735484 -292.191647)
			(xy 338.69141 -292.166201) (xy 338.651988 -292.134014) (xy 338.61824 -292.09592) (xy 338.591039 -292.052906)
			(xy 338.571091 -292.006086) (xy 338.558912 -291.956672) (xy 338.554817 -291.905944) (xy 338.236306 -291.905944)
			(xy 338.235811 -291.930551) (xy 338.227916 -291.979128) (xy 338.212332 -292.025809) (xy 338.189461 -292.069386)
			(xy 338.159896 -292.10873) (xy 338.124403 -292.142822) (xy 338.0839 -292.170778) (xy 338.039438 -292.191876)
			(xy 337.992167 -292.205568) (xy 337.943312 -292.2115) (xy 337.894137 -292.209519) (xy 337.845918 -292.199675)
			(xy 337.799902 -292.182223) (xy 337.757281 -292.157616) (xy 337.71916 -292.126491) (xy 337.686525 -292.089654)
			(xy 337.660222 -292.048058) (xy 337.640931 -292.002782) (xy 337.629154 -291.954998) (xy 337.625194 -291.905944)
			(xy 337.30692 -291.905944) (xy 337.306408 -291.93139) (xy 337.298244 -291.981624) (xy 337.282128 -292.029898)
			(xy 337.258477 -292.074961) (xy 337.227904 -292.115647) (xy 337.1912 -292.150902) (xy 337.149316 -292.179812)
			(xy 337.103337 -292.201629) (xy 337.054453 -292.215789) (xy 337.003932 -292.221923) (xy 336.95308 -292.219874)
			(xy 336.903216 -292.209694) (xy 336.85563 -292.191647) (xy 336.811556 -292.166201) (xy 336.772134 -292.134014)
			(xy 336.738386 -292.09592) (xy 336.711185 -292.052906) (xy 336.691237 -292.006086) (xy 336.679058 -291.956672)
			(xy 336.674963 -291.905944) (xy 336.366866 -291.905944) (xy 336.366354 -291.93139) (xy 336.35819 -291.981624)
			(xy 336.342074 -292.029898) (xy 336.318423 -292.074961) (xy 336.28785 -292.115647) (xy 336.251146 -292.150902)
			(xy 336.209262 -292.179812) (xy 336.163283 -292.201629) (xy 336.114399 -292.215789) (xy 336.063878 -292.221923)
			(xy 336.013026 -292.219874) (xy 335.963162 -292.209694) (xy 335.915576 -292.191647) (xy 335.871502 -292.166201)
			(xy 335.83208 -292.134014) (xy 335.798332 -292.09592) (xy 335.771131 -292.052906) (xy 335.751183 -292.006086)
			(xy 335.739004 -291.956672) (xy 335.734909 -291.905944) (xy 335.416398 -291.905944) (xy 335.415903 -291.930551)
			(xy 335.408008 -291.979128) (xy 335.392424 -292.025809) (xy 335.369553 -292.069386) (xy 335.339988 -292.10873)
			(xy 335.304495 -292.142822) (xy 335.263992 -292.170778) (xy 335.21953 -292.191876) (xy 335.172259 -292.205568)
			(xy 335.123404 -292.2115) (xy 335.074229 -292.209519) (xy 335.02601 -292.199675) (xy 334.979994 -292.182223)
			(xy 334.937373 -292.157616) (xy 334.899252 -292.126491) (xy 334.866617 -292.089654) (xy 334.840314 -292.048058)
			(xy 334.821023 -292.002782) (xy 334.809246 -291.954998) (xy 334.805286 -291.905944) (xy 334.486758 -291.905944)
			(xy 334.486246 -291.93139) (xy 334.478082 -291.981624) (xy 334.461966 -292.029898) (xy 334.438315 -292.074961)
			(xy 334.407742 -292.115647) (xy 334.371038 -292.150902) (xy 334.329154 -292.179812) (xy 334.283175 -292.201629)
			(xy 334.234291 -292.215789) (xy 334.18377 -292.221923) (xy 334.132918 -292.219874) (xy 334.083054 -292.209694)
			(xy 334.035468 -292.191647) (xy 333.991394 -292.166201) (xy 333.951972 -292.134014) (xy 333.918224 -292.09592)
			(xy 333.891023 -292.052906) (xy 333.871075 -292.006086) (xy 333.858896 -291.956672) (xy 333.854801 -291.905944)
			(xy 333.53629 -291.905944) (xy 333.535795 -291.930551) (xy 333.5279 -291.979128) (xy 333.512316 -292.025809)
			(xy 333.489445 -292.069386) (xy 333.45988 -292.10873) (xy 333.424387 -292.142822) (xy 333.383884 -292.170778)
			(xy 333.339422 -292.191876) (xy 333.292151 -292.205568) (xy 333.243296 -292.2115) (xy 333.194121 -292.209519)
			(xy 333.145902 -292.199675) (xy 333.099886 -292.182223) (xy 333.057265 -292.157616) (xy 333.019144 -292.126491)
			(xy 332.986509 -292.089654) (xy 332.960206 -292.048058) (xy 332.940915 -292.002782) (xy 332.929138 -291.954998)
			(xy 332.925178 -291.905944) (xy 332.606904 -291.905944) (xy 332.606392 -291.93139) (xy 332.598228 -291.981624)
			(xy 332.582112 -292.029898) (xy 332.558461 -292.074961) (xy 332.527888 -292.115647) (xy 332.491184 -292.150902)
			(xy 332.4493 -292.179812) (xy 332.403321 -292.201629) (xy 332.354437 -292.215789) (xy 332.303916 -292.221923)
			(xy 332.253064 -292.219874) (xy 332.2032 -292.209694) (xy 332.155614 -292.191647) (xy 332.11154 -292.166201)
			(xy 332.072118 -292.134014) (xy 332.03837 -292.09592) (xy 332.011169 -292.052906) (xy 331.991221 -292.006086)
			(xy 331.979042 -291.956672) (xy 331.974947 -291.905944) (xy 331.656436 -291.905944) (xy 331.655941 -291.930551)
			(xy 331.648046 -291.979128) (xy 331.632462 -292.025809) (xy 331.609591 -292.069386) (xy 331.580026 -292.10873)
			(xy 331.544533 -292.142822) (xy 331.50403 -292.170778) (xy 331.459568 -292.191876) (xy 331.412297 -292.205568)
			(xy 331.363442 -292.2115) (xy 331.314267 -292.209519) (xy 331.266048 -292.199675) (xy 331.220032 -292.182223)
			(xy 331.177411 -292.157616) (xy 331.13929 -292.126491) (xy 331.106655 -292.089654) (xy 331.080352 -292.048058)
			(xy 331.061061 -292.002782) (xy 331.049284 -291.954998) (xy 331.045324 -291.905944) (xy 330.726796 -291.905944)
			(xy 330.726284 -291.93139) (xy 330.71812 -291.981624) (xy 330.702004 -292.029898) (xy 330.678353 -292.074961)
			(xy 330.64778 -292.115647) (xy 330.611076 -292.150902) (xy 330.569192 -292.179812) (xy 330.523213 -292.201629)
			(xy 330.474329 -292.215789) (xy 330.423808 -292.221923) (xy 330.372956 -292.219874) (xy 330.323092 -292.209694)
			(xy 330.275506 -292.191647) (xy 330.231432 -292.166201) (xy 330.19201 -292.134014) (xy 330.158262 -292.09592)
			(xy 330.131061 -292.052906) (xy 330.111113 -292.006086) (xy 330.098934 -291.956672) (xy 330.094839 -291.905944)
			(xy 329.786742 -291.905944) (xy 329.78623 -291.93139) (xy 329.778066 -291.981624) (xy 329.76195 -292.029898)
			(xy 329.738299 -292.074961) (xy 329.707726 -292.115647) (xy 329.671022 -292.150902) (xy 329.629138 -292.179812)
			(xy 329.583159 -292.201629) (xy 329.534275 -292.215789) (xy 329.483754 -292.221923) (xy 329.432902 -292.219874)
			(xy 329.383038 -292.209694) (xy 329.335452 -292.191647) (xy 329.291378 -292.166201) (xy 329.251956 -292.134014)
			(xy 329.218208 -292.09592) (xy 329.191007 -292.052906) (xy 329.171059 -292.006086) (xy 329.15888 -291.956672)
			(xy 329.154785 -291.905944) (xy 328.836528 -291.905944) (xy 328.836033 -291.930551) (xy 328.828138 -291.979128)
			(xy 328.812554 -292.025809) (xy 328.789683 -292.069386) (xy 328.760118 -292.10873) (xy 328.724625 -292.142822)
			(xy 328.684122 -292.170778) (xy 328.63966 -292.191876) (xy 328.592389 -292.205568) (xy 328.543534 -292.2115)
			(xy 328.494359 -292.209519) (xy 328.44614 -292.199675) (xy 328.400124 -292.182223) (xy 328.357503 -292.157616)
			(xy 328.319382 -292.126491) (xy 328.286747 -292.089654) (xy 328.260444 -292.048058) (xy 328.241153 -292.002782)
			(xy 328.229376 -291.954998) (xy 328.225416 -291.905944) (xy 326.95642 -291.905944) (xy 326.955925 -291.930551)
			(xy 326.94803 -291.979128) (xy 326.932446 -292.025809) (xy 326.909575 -292.069386) (xy 326.88001 -292.10873)
			(xy 326.844517 -292.142822) (xy 326.804014 -292.170778) (xy 326.759552 -292.191876) (xy 326.712281 -292.205568)
			(xy 326.663426 -292.2115) (xy 326.614251 -292.209519) (xy 326.566032 -292.199675) (xy 326.520016 -292.182223)
			(xy 326.477395 -292.157616) (xy 326.439274 -292.126491) (xy 326.406639 -292.089654) (xy 326.380336 -292.048058)
			(xy 326.361045 -292.002782) (xy 326.349268 -291.954998) (xy 326.345308 -291.905944) (xy 310.45912 -291.905944)
			(xy 310.45912 -292.450012) (xy 324.74714 -292.450012) (xy 324.7511 -292.400958) (xy 324.762877 -292.353174)
			(xy 324.782168 -292.307898) (xy 324.808471 -292.266302) (xy 324.841106 -292.229465) (xy 324.879227 -292.19834)
			(xy 324.921848 -292.173733) (xy 324.967864 -292.156281) (xy 325.016083 -292.146437) (xy 325.065258 -292.144456)
			(xy 325.114113 -292.150388) (xy 325.161384 -292.16408) (xy 325.205846 -292.185178) (xy 325.246349 -292.213134)
			(xy 325.281842 -292.247226) (xy 325.311407 -292.28657) (xy 325.334278 -292.330147) (xy 325.349862 -292.376828)
			(xy 325.357757 -292.425405) (xy 325.358252 -292.450012) (xy 325.357757 -292.474619) (xy 325.349862 -292.523196)
			(xy 325.334278 -292.569877) (xy 325.311407 -292.613454) (xy 325.281842 -292.652798) (xy 325.246349 -292.68689)
			(xy 325.205846 -292.714846) (xy 325.203519 -292.71595) (xy 328.684885 -292.71595) (xy 328.68898 -292.665222)
			(xy 328.701159 -292.615808) (xy 328.721107 -292.568988) (xy 328.748308 -292.525974) (xy 328.782056 -292.48788)
			(xy 328.821478 -292.455693) (xy 328.865552 -292.430247) (xy 328.913138 -292.4122) (xy 328.963002 -292.40202)
			(xy 329.013854 -292.399971) (xy 329.064375 -292.406105) (xy 329.113259 -292.420265) (xy 329.159238 -292.442082)
			(xy 329.201122 -292.470992) (xy 329.237826 -292.506247) (xy 329.268399 -292.546933) (xy 329.29205 -292.591996)
			(xy 329.308166 -292.64027) (xy 329.31633 -292.690504) (xy 329.316842 -292.71595) (xy 329.63537 -292.71595)
			(xy 329.63933 -292.666896) (xy 329.651107 -292.619112) (xy 329.670398 -292.573836) (xy 329.696701 -292.53224)
			(xy 329.729336 -292.495403) (xy 329.767457 -292.464278) (xy 329.810078 -292.439671) (xy 329.856094 -292.422219)
			(xy 329.904313 -292.412375) (xy 329.953488 -292.410394) (xy 330.002343 -292.416326) (xy 330.049614 -292.430018)
			(xy 330.094076 -292.451116) (xy 330.134579 -292.479072) (xy 330.170072 -292.513164) (xy 330.199637 -292.552508)
			(xy 330.222508 -292.596085) (xy 330.238092 -292.642766) (xy 330.245987 -292.691343) (xy 330.246482 -292.71595)
			(xy 330.564739 -292.71595) (xy 330.568834 -292.665222) (xy 330.581013 -292.615808) (xy 330.600961 -292.568988)
			(xy 330.628162 -292.525974) (xy 330.66191 -292.48788) (xy 330.701332 -292.455693) (xy 330.745406 -292.430247)
			(xy 330.792992 -292.4122) (xy 330.842856 -292.40202) (xy 330.893708 -292.399971) (xy 330.944229 -292.406105)
			(xy 330.993113 -292.420265) (xy 331.039092 -292.442082) (xy 331.080976 -292.470992) (xy 331.11768 -292.506247)
			(xy 331.148253 -292.546933) (xy 331.171904 -292.591996) (xy 331.18802 -292.64027) (xy 331.196184 -292.690504)
			(xy 331.196696 -292.71595) (xy 331.515224 -292.71595) (xy 331.519184 -292.666896) (xy 331.530961 -292.619112)
			(xy 331.550252 -292.573836) (xy 331.576555 -292.53224) (xy 331.60919 -292.495403) (xy 331.647311 -292.464278)
			(xy 331.689932 -292.439671) (xy 331.735948 -292.422219) (xy 331.784167 -292.412375) (xy 331.833342 -292.410394)
			(xy 331.882197 -292.416326) (xy 331.929468 -292.430018) (xy 331.97393 -292.451116) (xy 332.014433 -292.479072)
			(xy 332.049926 -292.513164) (xy 332.079491 -292.552508) (xy 332.102362 -292.596085) (xy 332.117946 -292.642766)
			(xy 332.125841 -292.691343) (xy 332.126336 -292.71595) (xy 332.444847 -292.71595) (xy 332.448942 -292.665222)
			(xy 332.461121 -292.615808) (xy 332.481069 -292.568988) (xy 332.50827 -292.525974) (xy 332.542018 -292.48788)
			(xy 332.58144 -292.455693) (xy 332.625514 -292.430247) (xy 332.6731 -292.4122) (xy 332.722964 -292.40202)
			(xy 332.773816 -292.399971) (xy 332.824337 -292.406105) (xy 332.873221 -292.420265) (xy 332.9192 -292.442082)
			(xy 332.961084 -292.470992) (xy 332.997788 -292.506247) (xy 333.028361 -292.546933) (xy 333.052012 -292.591996)
			(xy 333.068128 -292.64027) (xy 333.076292 -292.690504) (xy 333.076804 -292.71595) (xy 333.384901 -292.71595)
			(xy 333.388996 -292.665222) (xy 333.401175 -292.615808) (xy 333.421123 -292.568988) (xy 333.448324 -292.525974)
			(xy 333.482072 -292.48788) (xy 333.521494 -292.455693) (xy 333.565568 -292.430247) (xy 333.613154 -292.4122)
			(xy 333.663018 -292.40202) (xy 333.71387 -292.399971) (xy 333.764391 -292.406105) (xy 333.813275 -292.420265)
			(xy 333.859254 -292.442082) (xy 333.901138 -292.470992) (xy 333.937842 -292.506247) (xy 333.968415 -292.546933)
			(xy 333.992066 -292.591996) (xy 334.008182 -292.64027) (xy 334.016346 -292.690504) (xy 334.016858 -292.71595)
			(xy 335.264755 -292.71595) (xy 335.26885 -292.665222) (xy 335.281029 -292.615808) (xy 335.300977 -292.568988)
			(xy 335.328178 -292.525974) (xy 335.361926 -292.48788) (xy 335.401348 -292.455693) (xy 335.445422 -292.430247)
			(xy 335.493008 -292.4122) (xy 335.542872 -292.40202) (xy 335.593724 -292.399971) (xy 335.644245 -292.406105)
			(xy 335.693129 -292.420265) (xy 335.739108 -292.442082) (xy 335.780992 -292.470992) (xy 335.817696 -292.506247)
			(xy 335.848269 -292.546933) (xy 335.87192 -292.591996) (xy 335.888036 -292.64027) (xy 335.8962 -292.690504)
			(xy 335.896712 -292.71595) (xy 336.21524 -292.71595) (xy 336.2192 -292.666896) (xy 336.230977 -292.619112)
			(xy 336.250268 -292.573836) (xy 336.276571 -292.53224) (xy 336.309206 -292.495403) (xy 336.347327 -292.464278)
			(xy 336.389948 -292.439671) (xy 336.435964 -292.422219) (xy 336.484183 -292.412375) (xy 336.533358 -292.410394)
			(xy 336.582213 -292.416326) (xy 336.629484 -292.430018) (xy 336.673946 -292.451116) (xy 336.714449 -292.479072)
			(xy 336.749942 -292.513164) (xy 336.779507 -292.552508) (xy 336.802378 -292.596085) (xy 336.817962 -292.642766)
			(xy 336.825857 -292.691343) (xy 336.826352 -292.71595) (xy 337.144863 -292.71595) (xy 337.148958 -292.665222)
			(xy 337.161137 -292.615808) (xy 337.181085 -292.568988) (xy 337.208286 -292.525974) (xy 337.242034 -292.48788)
			(xy 337.281456 -292.455693) (xy 337.32553 -292.430247) (xy 337.373116 -292.4122) (xy 337.42298 -292.40202)
			(xy 337.473832 -292.399971) (xy 337.524353 -292.406105) (xy 337.573237 -292.420265) (xy 337.619216 -292.442082)
			(xy 337.6611 -292.470992) (xy 337.697804 -292.506247) (xy 337.728377 -292.546933) (xy 337.752028 -292.591996)
			(xy 337.768144 -292.64027) (xy 337.776308 -292.690504) (xy 337.77682 -292.71595) (xy 338.095348 -292.71595)
			(xy 338.099308 -292.666896) (xy 338.111085 -292.619112) (xy 338.130376 -292.573836) (xy 338.156679 -292.53224)
			(xy 338.189314 -292.495403) (xy 338.227435 -292.464278) (xy 338.270056 -292.439671) (xy 338.316072 -292.422219)
			(xy 338.364291 -292.412375) (xy 338.413466 -292.410394) (xy 338.462321 -292.416326) (xy 338.509592 -292.430018)
			(xy 338.554054 -292.451116) (xy 338.594557 -292.479072) (xy 338.63005 -292.513164) (xy 338.659615 -292.552508)
			(xy 338.682486 -292.596085) (xy 338.69807 -292.642766) (xy 338.705965 -292.691343) (xy 338.70646 -292.71595)
			(xy 339.024971 -292.71595) (xy 339.029066 -292.665222) (xy 339.041245 -292.615808) (xy 339.061193 -292.568988)
			(xy 339.088394 -292.525974) (xy 339.122142 -292.48788) (xy 339.161564 -292.455693) (xy 339.205638 -292.430247)
			(xy 339.253224 -292.4122) (xy 339.303088 -292.40202) (xy 339.35394 -292.399971) (xy 339.404461 -292.406105)
			(xy 339.453345 -292.420265) (xy 339.499324 -292.442082) (xy 339.541208 -292.470992) (xy 339.577912 -292.506247)
			(xy 339.608485 -292.546933) (xy 339.632136 -292.591996) (xy 339.648252 -292.64027) (xy 339.656416 -292.690504)
			(xy 339.656928 -292.71595) (xy 339.964771 -292.71595) (xy 339.968866 -292.665222) (xy 339.981045 -292.615808)
			(xy 340.000993 -292.568988) (xy 340.028194 -292.525974) (xy 340.061942 -292.48788) (xy 340.101364 -292.455693)
			(xy 340.145438 -292.430247) (xy 340.193024 -292.4122) (xy 340.242888 -292.40202) (xy 340.29374 -292.399971)
			(xy 340.344261 -292.406105) (xy 340.393145 -292.420265) (xy 340.439124 -292.442082) (xy 340.481008 -292.470992)
			(xy 340.517712 -292.506247) (xy 340.548285 -292.546933) (xy 340.571936 -292.591996) (xy 340.588052 -292.64027)
			(xy 340.596216 -292.690504) (xy 340.596728 -292.71595) (xy 341.844879 -292.71595) (xy 341.848974 -292.665222)
			(xy 341.861153 -292.615808) (xy 341.881101 -292.568988) (xy 341.908302 -292.525974) (xy 341.94205 -292.48788)
			(xy 341.981472 -292.455693) (xy 342.025546 -292.430247) (xy 342.073132 -292.4122) (xy 342.122996 -292.40202)
			(xy 342.173848 -292.399971) (xy 342.224369 -292.406105) (xy 342.273253 -292.420265) (xy 342.319232 -292.442082)
			(xy 342.361116 -292.470992) (xy 342.39782 -292.506247) (xy 342.428393 -292.546933) (xy 342.452044 -292.591996)
			(xy 342.46816 -292.64027) (xy 342.476324 -292.690504) (xy 342.476836 -292.71595) (xy 342.795364 -292.71595)
			(xy 342.799324 -292.666896) (xy 342.811101 -292.619112) (xy 342.830392 -292.573836) (xy 342.856695 -292.53224)
			(xy 342.88933 -292.495403) (xy 342.927451 -292.464278) (xy 342.970072 -292.439671) (xy 343.016088 -292.422219)
			(xy 343.064307 -292.412375) (xy 343.113482 -292.410394) (xy 343.162337 -292.416326) (xy 343.209608 -292.430018)
			(xy 343.25407 -292.451116) (xy 343.294573 -292.479072) (xy 343.330066 -292.513164) (xy 343.359631 -292.552508)
			(xy 343.382502 -292.596085) (xy 343.398086 -292.642766) (xy 343.405981 -292.691343) (xy 343.406476 -292.71595)
			(xy 343.724987 -292.71595) (xy 343.729082 -292.665222) (xy 343.741261 -292.615808) (xy 343.761209 -292.568988)
			(xy 343.78841 -292.525974) (xy 343.822158 -292.48788) (xy 343.86158 -292.455693) (xy 343.905654 -292.430247)
			(xy 343.95324 -292.4122) (xy 344.003104 -292.40202) (xy 344.053956 -292.399971) (xy 344.104477 -292.406105)
			(xy 344.153361 -292.420265) (xy 344.19934 -292.442082) (xy 344.241224 -292.470992) (xy 344.277928 -292.506247)
			(xy 344.308501 -292.546933) (xy 344.332152 -292.591996) (xy 344.348268 -292.64027) (xy 344.356432 -292.690504)
			(xy 344.356944 -292.71595) (xy 344.675218 -292.71595) (xy 344.679178 -292.666896) (xy 344.690955 -292.619112)
			(xy 344.710246 -292.573836) (xy 344.736549 -292.53224) (xy 344.769184 -292.495403) (xy 344.807305 -292.464278)
			(xy 344.849926 -292.439671) (xy 344.895942 -292.422219) (xy 344.944161 -292.412375) (xy 344.993336 -292.410394)
			(xy 345.042191 -292.416326) (xy 345.089462 -292.430018) (xy 345.133924 -292.451116) (xy 345.174427 -292.479072)
			(xy 345.20992 -292.513164) (xy 345.239485 -292.552508) (xy 345.262356 -292.596085) (xy 345.27794 -292.642766)
			(xy 345.285835 -292.691343) (xy 345.28633 -292.71595) (xy 345.604841 -292.71595) (xy 345.608936 -292.665222)
			(xy 345.621115 -292.615808) (xy 345.641063 -292.568988) (xy 345.668264 -292.525974) (xy 345.702012 -292.48788)
			(xy 345.741434 -292.455693) (xy 345.785508 -292.430247) (xy 345.833094 -292.4122) (xy 345.882958 -292.40202)
			(xy 345.93381 -292.399971) (xy 345.984331 -292.406105) (xy 346.033215 -292.420265) (xy 346.079194 -292.442082)
			(xy 346.121078 -292.470992) (xy 346.157782 -292.506247) (xy 346.188355 -292.546933) (xy 346.212006 -292.591996)
			(xy 346.228122 -292.64027) (xy 346.236286 -292.690504) (xy 346.236798 -292.71595) (xy 346.544895 -292.71595)
			(xy 346.54899 -292.665222) (xy 346.561169 -292.615808) (xy 346.581117 -292.568988) (xy 346.608318 -292.525974)
			(xy 346.642066 -292.48788) (xy 346.681488 -292.455693) (xy 346.725562 -292.430247) (xy 346.773148 -292.4122)
			(xy 346.823012 -292.40202) (xy 346.873864 -292.399971) (xy 346.924385 -292.406105) (xy 346.973269 -292.420265)
			(xy 347.019248 -292.442082) (xy 347.061132 -292.470992) (xy 347.097836 -292.506247) (xy 347.128409 -292.546933)
			(xy 347.15206 -292.591996) (xy 347.168176 -292.64027) (xy 347.17634 -292.690504) (xy 347.176852 -292.71595)
			(xy 347.49538 -292.71595) (xy 347.49934 -292.666896) (xy 347.511117 -292.619112) (xy 347.530408 -292.573836)
			(xy 347.556711 -292.53224) (xy 347.589346 -292.495403) (xy 347.627467 -292.464278) (xy 347.670088 -292.439671)
			(xy 347.716104 -292.422219) (xy 347.764323 -292.412375) (xy 347.813498 -292.410394) (xy 347.862353 -292.416326)
			(xy 347.909624 -292.430018) (xy 347.954086 -292.451116) (xy 347.994589 -292.479072) (xy 348.030082 -292.513164)
			(xy 348.059647 -292.552508) (xy 348.082518 -292.596085) (xy 348.098102 -292.642766) (xy 348.105997 -292.691343)
			(xy 348.106492 -292.71595) (xy 348.425003 -292.71595) (xy 348.429098 -292.665222) (xy 348.441277 -292.615808)
			(xy 348.461225 -292.568988) (xy 348.488426 -292.525974) (xy 348.522174 -292.48788) (xy 348.561596 -292.455693)
			(xy 348.60567 -292.430247) (xy 348.653256 -292.4122) (xy 348.70312 -292.40202) (xy 348.753972 -292.399971)
			(xy 348.804493 -292.406105) (xy 348.853377 -292.420265) (xy 348.899356 -292.442082) (xy 348.94124 -292.470992)
			(xy 348.977944 -292.506247) (xy 349.008517 -292.546933) (xy 349.032168 -292.591996) (xy 349.048284 -292.64027)
			(xy 349.056448 -292.690504) (xy 349.05696 -292.71595) (xy 349.364803 -292.71595) (xy 349.368898 -292.665222)
			(xy 349.381077 -292.615808) (xy 349.401025 -292.568988) (xy 349.428226 -292.525974) (xy 349.461974 -292.48788)
			(xy 349.501396 -292.455693) (xy 349.54547 -292.430247) (xy 349.593056 -292.4122) (xy 349.64292 -292.40202)
			(xy 349.693772 -292.399971) (xy 349.744293 -292.406105) (xy 349.793177 -292.420265) (xy 349.839156 -292.442082)
			(xy 349.88104 -292.470992) (xy 349.917744 -292.506247) (xy 349.948317 -292.546933) (xy 349.971968 -292.591996)
			(xy 349.988084 -292.64027) (xy 349.996248 -292.690504) (xy 349.99676 -292.71595) (xy 350.315288 -292.71595)
			(xy 350.319248 -292.666896) (xy 350.331025 -292.619112) (xy 350.350316 -292.573836) (xy 350.376619 -292.53224)
			(xy 350.409254 -292.495403) (xy 350.447375 -292.464278) (xy 350.489996 -292.439671) (xy 350.536012 -292.422219)
			(xy 350.584231 -292.412375) (xy 350.633406 -292.410394) (xy 350.682261 -292.416326) (xy 350.729532 -292.430018)
			(xy 350.773994 -292.451116) (xy 350.814497 -292.479072) (xy 350.84999 -292.513164) (xy 350.879555 -292.552508)
			(xy 350.902426 -292.596085) (xy 350.91801 -292.642766) (xy 350.925905 -292.691343) (xy 350.9264 -292.71595)
			(xy 350.925905 -292.740557) (xy 350.91801 -292.789134) (xy 350.902426 -292.835815) (xy 350.879555 -292.879392)
			(xy 350.84999 -292.918736) (xy 350.814497 -292.952828) (xy 350.773994 -292.980784) (xy 350.729532 -293.001882)
			(xy 350.682261 -293.015574) (xy 350.633406 -293.021506) (xy 350.584231 -293.019525) (xy 350.536012 -293.009681)
			(xy 350.489996 -292.992229) (xy 350.447375 -292.967622) (xy 350.409254 -292.936497) (xy 350.376619 -292.89966)
			(xy 350.350316 -292.858064) (xy 350.331025 -292.812788) (xy 350.319248 -292.765004) (xy 350.315288 -292.71595)
			(xy 349.99676 -292.71595) (xy 349.996248 -292.741396) (xy 349.988084 -292.79163) (xy 349.971968 -292.839904)
			(xy 349.948317 -292.884967) (xy 349.917744 -292.925653) (xy 349.88104 -292.960908) (xy 349.839156 -292.989818)
			(xy 349.793177 -293.011635) (xy 349.744293 -293.025795) (xy 349.693772 -293.031929) (xy 349.64292 -293.02988)
			(xy 349.593056 -293.0197) (xy 349.54547 -293.001653) (xy 349.501396 -292.976207) (xy 349.461974 -292.94402)
			(xy 349.428226 -292.905926) (xy 349.401025 -292.862912) (xy 349.381077 -292.816092) (xy 349.368898 -292.766678)
			(xy 349.364803 -292.71595) (xy 349.05696 -292.71595) (xy 349.056448 -292.741396) (xy 349.048284 -292.79163)
			(xy 349.032168 -292.839904) (xy 349.008517 -292.884967) (xy 348.977944 -292.925653) (xy 348.94124 -292.960908)
			(xy 348.899356 -292.989818) (xy 348.853377 -293.011635) (xy 348.804493 -293.025795) (xy 348.753972 -293.031929)
			(xy 348.70312 -293.02988) (xy 348.653256 -293.0197) (xy 348.60567 -293.001653) (xy 348.561596 -292.976207)
			(xy 348.522174 -292.94402) (xy 348.488426 -292.905926) (xy 348.461225 -292.862912) (xy 348.441277 -292.816092)
			(xy 348.429098 -292.766678) (xy 348.425003 -292.71595) (xy 348.106492 -292.71595) (xy 348.105997 -292.740557)
			(xy 348.098102 -292.789134) (xy 348.082518 -292.835815) (xy 348.059647 -292.879392) (xy 348.030082 -292.918736)
			(xy 347.994589 -292.952828) (xy 347.954086 -292.980784) (xy 347.909624 -293.001882) (xy 347.862353 -293.015574)
			(xy 347.813498 -293.021506) (xy 347.764323 -293.019525) (xy 347.716104 -293.009681) (xy 347.670088 -292.992229)
			(xy 347.627467 -292.967622) (xy 347.589346 -292.936497) (xy 347.556711 -292.89966) (xy 347.530408 -292.858064)
			(xy 347.511117 -292.812788) (xy 347.49934 -292.765004) (xy 347.49538 -292.71595) (xy 347.176852 -292.71595)
			(xy 347.17634 -292.741396) (xy 347.168176 -292.79163) (xy 347.15206 -292.839904) (xy 347.128409 -292.884967)
			(xy 347.097836 -292.925653) (xy 347.061132 -292.960908) (xy 347.019248 -292.989818) (xy 346.973269 -293.011635)
			(xy 346.924385 -293.025795) (xy 346.873864 -293.031929) (xy 346.823012 -293.02988) (xy 346.773148 -293.0197)
			(xy 346.725562 -293.001653) (xy 346.681488 -292.976207) (xy 346.642066 -292.94402) (xy 346.608318 -292.905926)
			(xy 346.581117 -292.862912) (xy 346.561169 -292.816092) (xy 346.54899 -292.766678) (xy 346.544895 -292.71595)
			(xy 346.236798 -292.71595) (xy 346.236286 -292.741396) (xy 346.228122 -292.79163) (xy 346.212006 -292.839904)
			(xy 346.188355 -292.884967) (xy 346.157782 -292.925653) (xy 346.121078 -292.960908) (xy 346.079194 -292.989818)
			(xy 346.033215 -293.011635) (xy 345.984331 -293.025795) (xy 345.93381 -293.031929) (xy 345.882958 -293.02988)
			(xy 345.833094 -293.0197) (xy 345.785508 -293.001653) (xy 345.741434 -292.976207) (xy 345.702012 -292.94402)
			(xy 345.668264 -292.905926) (xy 345.641063 -292.862912) (xy 345.621115 -292.816092) (xy 345.608936 -292.766678)
			(xy 345.604841 -292.71595) (xy 345.28633 -292.71595) (xy 345.285835 -292.740557) (xy 345.27794 -292.789134)
			(xy 345.262356 -292.835815) (xy 345.239485 -292.879392) (xy 345.20992 -292.918736) (xy 345.174427 -292.952828)
			(xy 345.133924 -292.980784) (xy 345.089462 -293.001882) (xy 345.042191 -293.015574) (xy 344.993336 -293.021506)
			(xy 344.944161 -293.019525) (xy 344.895942 -293.009681) (xy 344.849926 -292.992229) (xy 344.807305 -292.967622)
			(xy 344.769184 -292.936497) (xy 344.736549 -292.89966) (xy 344.710246 -292.858064) (xy 344.690955 -292.812788)
			(xy 344.679178 -292.765004) (xy 344.675218 -292.71595) (xy 344.356944 -292.71595) (xy 344.356432 -292.741396)
			(xy 344.348268 -292.79163) (xy 344.332152 -292.839904) (xy 344.308501 -292.884967) (xy 344.277928 -292.925653)
			(xy 344.241224 -292.960908) (xy 344.19934 -292.989818) (xy 344.153361 -293.011635) (xy 344.104477 -293.025795)
			(xy 344.053956 -293.031929) (xy 344.003104 -293.02988) (xy 343.95324 -293.0197) (xy 343.905654 -293.001653)
			(xy 343.86158 -292.976207) (xy 343.822158 -292.94402) (xy 343.78841 -292.905926) (xy 343.761209 -292.862912)
			(xy 343.741261 -292.816092) (xy 343.729082 -292.766678) (xy 343.724987 -292.71595) (xy 343.406476 -292.71595)
			(xy 343.405981 -292.740557) (xy 343.398086 -292.789134) (xy 343.382502 -292.835815) (xy 343.359631 -292.879392)
			(xy 343.330066 -292.918736) (xy 343.294573 -292.952828) (xy 343.25407 -292.980784) (xy 343.209608 -293.001882)
			(xy 343.162337 -293.015574) (xy 343.113482 -293.021506) (xy 343.064307 -293.019525) (xy 343.016088 -293.009681)
			(xy 342.970072 -292.992229) (xy 342.927451 -292.967622) (xy 342.88933 -292.936497) (xy 342.856695 -292.89966)
			(xy 342.830392 -292.858064) (xy 342.811101 -292.812788) (xy 342.799324 -292.765004) (xy 342.795364 -292.71595)
			(xy 342.476836 -292.71595) (xy 342.476324 -292.741396) (xy 342.46816 -292.79163) (xy 342.452044 -292.839904)
			(xy 342.428393 -292.884967) (xy 342.39782 -292.925653) (xy 342.361116 -292.960908) (xy 342.319232 -292.989818)
			(xy 342.273253 -293.011635) (xy 342.224369 -293.025795) (xy 342.173848 -293.031929) (xy 342.122996 -293.02988)
			(xy 342.073132 -293.0197) (xy 342.025546 -293.001653) (xy 341.981472 -292.976207) (xy 341.94205 -292.94402)
			(xy 341.908302 -292.905926) (xy 341.881101 -292.862912) (xy 341.861153 -292.816092) (xy 341.848974 -292.766678)
			(xy 341.844879 -292.71595) (xy 340.596728 -292.71595) (xy 340.596216 -292.741396) (xy 340.588052 -292.79163)
			(xy 340.571936 -292.839904) (xy 340.548285 -292.884967) (xy 340.517712 -292.925653) (xy 340.481008 -292.960908)
			(xy 340.439124 -292.989818) (xy 340.393145 -293.011635) (xy 340.344261 -293.025795) (xy 340.29374 -293.031929)
			(xy 340.242888 -293.02988) (xy 340.193024 -293.0197) (xy 340.145438 -293.001653) (xy 340.101364 -292.976207)
			(xy 340.061942 -292.94402) (xy 340.028194 -292.905926) (xy 340.000993 -292.862912) (xy 339.981045 -292.816092)
			(xy 339.968866 -292.766678) (xy 339.964771 -292.71595) (xy 339.656928 -292.71595) (xy 339.656416 -292.741396)
			(xy 339.648252 -292.79163) (xy 339.632136 -292.839904) (xy 339.608485 -292.884967) (xy 339.577912 -292.925653)
			(xy 339.541208 -292.960908) (xy 339.499324 -292.989818) (xy 339.453345 -293.011635) (xy 339.404461 -293.025795)
			(xy 339.35394 -293.031929) (xy 339.303088 -293.02988) (xy 339.253224 -293.0197) (xy 339.205638 -293.001653)
			(xy 339.161564 -292.976207) (xy 339.122142 -292.94402) (xy 339.088394 -292.905926) (xy 339.061193 -292.862912)
			(xy 339.041245 -292.816092) (xy 339.029066 -292.766678) (xy 339.024971 -292.71595) (xy 338.70646 -292.71595)
			(xy 338.705965 -292.740557) (xy 338.69807 -292.789134) (xy 338.682486 -292.835815) (xy 338.659615 -292.879392)
			(xy 338.63005 -292.918736) (xy 338.594557 -292.952828) (xy 338.554054 -292.980784) (xy 338.509592 -293.001882)
			(xy 338.462321 -293.015574) (xy 338.413466 -293.021506) (xy 338.364291 -293.019525) (xy 338.316072 -293.009681)
			(xy 338.270056 -292.992229) (xy 338.227435 -292.967622) (xy 338.189314 -292.936497) (xy 338.156679 -292.89966)
			(xy 338.130376 -292.858064) (xy 338.111085 -292.812788) (xy 338.099308 -292.765004) (xy 338.095348 -292.71595)
			(xy 337.77682 -292.71595) (xy 337.776308 -292.741396) (xy 337.768144 -292.79163) (xy 337.752028 -292.839904)
			(xy 337.728377 -292.884967) (xy 337.697804 -292.925653) (xy 337.6611 -292.960908) (xy 337.619216 -292.989818)
			(xy 337.573237 -293.011635) (xy 337.524353 -293.025795) (xy 337.473832 -293.031929) (xy 337.42298 -293.02988)
			(xy 337.373116 -293.0197) (xy 337.32553 -293.001653) (xy 337.281456 -292.976207) (xy 337.242034 -292.94402)
			(xy 337.208286 -292.905926) (xy 337.181085 -292.862912) (xy 337.161137 -292.816092) (xy 337.148958 -292.766678)
			(xy 337.144863 -292.71595) (xy 336.826352 -292.71595) (xy 336.825857 -292.740557) (xy 336.817962 -292.789134)
			(xy 336.802378 -292.835815) (xy 336.779507 -292.879392) (xy 336.749942 -292.918736) (xy 336.714449 -292.952828)
			(xy 336.673946 -292.980784) (xy 336.629484 -293.001882) (xy 336.582213 -293.015574) (xy 336.533358 -293.021506)
			(xy 336.484183 -293.019525) (xy 336.435964 -293.009681) (xy 336.389948 -292.992229) (xy 336.347327 -292.967622)
			(xy 336.309206 -292.936497) (xy 336.276571 -292.89966) (xy 336.250268 -292.858064) (xy 336.230977 -292.812788)
			(xy 336.2192 -292.765004) (xy 336.21524 -292.71595) (xy 335.896712 -292.71595) (xy 335.8962 -292.741396)
			(xy 335.888036 -292.79163) (xy 335.87192 -292.839904) (xy 335.848269 -292.884967) (xy 335.817696 -292.925653)
			(xy 335.780992 -292.960908) (xy 335.739108 -292.989818) (xy 335.693129 -293.011635) (xy 335.644245 -293.025795)
			(xy 335.593724 -293.031929) (xy 335.542872 -293.02988) (xy 335.493008 -293.0197) (xy 335.445422 -293.001653)
			(xy 335.401348 -292.976207) (xy 335.361926 -292.94402) (xy 335.328178 -292.905926) (xy 335.300977 -292.862912)
			(xy 335.281029 -292.816092) (xy 335.26885 -292.766678) (xy 335.264755 -292.71595) (xy 334.016858 -292.71595)
			(xy 334.016346 -292.741396) (xy 334.008182 -292.79163) (xy 333.992066 -292.839904) (xy 333.968415 -292.884967)
			(xy 333.937842 -292.925653) (xy 333.901138 -292.960908) (xy 333.859254 -292.989818) (xy 333.813275 -293.011635)
			(xy 333.764391 -293.025795) (xy 333.71387 -293.031929) (xy 333.663018 -293.02988) (xy 333.613154 -293.0197)
			(xy 333.565568 -293.001653) (xy 333.521494 -292.976207) (xy 333.482072 -292.94402) (xy 333.448324 -292.905926)
			(xy 333.421123 -292.862912) (xy 333.401175 -292.816092) (xy 333.388996 -292.766678) (xy 333.384901 -292.71595)
			(xy 333.076804 -292.71595) (xy 333.076292 -292.741396) (xy 333.068128 -292.79163) (xy 333.052012 -292.839904)
			(xy 333.028361 -292.884967) (xy 332.997788 -292.925653) (xy 332.961084 -292.960908) (xy 332.9192 -292.989818)
			(xy 332.873221 -293.011635) (xy 332.824337 -293.025795) (xy 332.773816 -293.031929) (xy 332.722964 -293.02988)
			(xy 332.6731 -293.0197) (xy 332.625514 -293.001653) (xy 332.58144 -292.976207) (xy 332.542018 -292.94402)
			(xy 332.50827 -292.905926) (xy 332.481069 -292.862912) (xy 332.461121 -292.816092) (xy 332.448942 -292.766678)
			(xy 332.444847 -292.71595) (xy 332.126336 -292.71595) (xy 332.125841 -292.740557) (xy 332.117946 -292.789134)
			(xy 332.102362 -292.835815) (xy 332.079491 -292.879392) (xy 332.049926 -292.918736) (xy 332.014433 -292.952828)
			(xy 331.97393 -292.980784) (xy 331.929468 -293.001882) (xy 331.882197 -293.015574) (xy 331.833342 -293.021506)
			(xy 331.784167 -293.019525) (xy 331.735948 -293.009681) (xy 331.689932 -292.992229) (xy 331.647311 -292.967622)
			(xy 331.60919 -292.936497) (xy 331.576555 -292.89966) (xy 331.550252 -292.858064) (xy 331.530961 -292.812788)
			(xy 331.519184 -292.765004) (xy 331.515224 -292.71595) (xy 331.196696 -292.71595) (xy 331.196184 -292.741396)
			(xy 331.18802 -292.79163) (xy 331.171904 -292.839904) (xy 331.148253 -292.884967) (xy 331.11768 -292.925653)
			(xy 331.080976 -292.960908) (xy 331.039092 -292.989818) (xy 330.993113 -293.011635) (xy 330.944229 -293.025795)
			(xy 330.893708 -293.031929) (xy 330.842856 -293.02988) (xy 330.792992 -293.0197) (xy 330.745406 -293.001653)
			(xy 330.701332 -292.976207) (xy 330.66191 -292.94402) (xy 330.628162 -292.905926) (xy 330.600961 -292.862912)
			(xy 330.581013 -292.816092) (xy 330.568834 -292.766678) (xy 330.564739 -292.71595) (xy 330.246482 -292.71595)
			(xy 330.245987 -292.740557) (xy 330.238092 -292.789134) (xy 330.222508 -292.835815) (xy 330.199637 -292.879392)
			(xy 330.170072 -292.918736) (xy 330.134579 -292.952828) (xy 330.094076 -292.980784) (xy 330.049614 -293.001882)
			(xy 330.002343 -293.015574) (xy 329.953488 -293.021506) (xy 329.904313 -293.019525) (xy 329.856094 -293.009681)
			(xy 329.810078 -292.992229) (xy 329.767457 -292.967622) (xy 329.729336 -292.936497) (xy 329.696701 -292.89966)
			(xy 329.670398 -292.858064) (xy 329.651107 -292.812788) (xy 329.63933 -292.765004) (xy 329.63537 -292.71595)
			(xy 329.316842 -292.71595) (xy 329.31633 -292.741396) (xy 329.308166 -292.79163) (xy 329.29205 -292.839904)
			(xy 329.268399 -292.884967) (xy 329.237826 -292.925653) (xy 329.201122 -292.960908) (xy 329.159238 -292.989818)
			(xy 329.113259 -293.011635) (xy 329.064375 -293.025795) (xy 329.013854 -293.031929) (xy 328.963002 -293.02988)
			(xy 328.913138 -293.0197) (xy 328.865552 -293.001653) (xy 328.821478 -292.976207) (xy 328.782056 -292.94402)
			(xy 328.748308 -292.905926) (xy 328.721107 -292.862912) (xy 328.701159 -292.816092) (xy 328.68898 -292.766678)
			(xy 328.684885 -292.71595) (xy 325.203519 -292.71595) (xy 325.161384 -292.735944) (xy 325.114113 -292.749636)
			(xy 325.065258 -292.755568) (xy 325.016083 -292.753587) (xy 324.967864 -292.743743) (xy 324.921848 -292.726291)
			(xy 324.879227 -292.701684) (xy 324.841106 -292.670559) (xy 324.808471 -292.633722) (xy 324.782168 -292.592126)
			(xy 324.762877 -292.54685) (xy 324.7511 -292.499066) (xy 324.74714 -292.450012) (xy 310.45912 -292.450012)
			(xy 310.45912 -293.525956) (xy 326.345308 -293.525956) (xy 326.349268 -293.476902) (xy 326.361045 -293.429118)
			(xy 326.380336 -293.383842) (xy 326.406639 -293.342246) (xy 326.439274 -293.305409) (xy 326.477395 -293.274284)
			(xy 326.520016 -293.249677) (xy 326.566032 -293.232225) (xy 326.614251 -293.222381) (xy 326.663426 -293.2204)
			(xy 326.712281 -293.226332) (xy 326.759552 -293.240024) (xy 326.804014 -293.261122) (xy 326.844517 -293.289078)
			(xy 326.88001 -293.32317) (xy 326.909575 -293.362514) (xy 326.932446 -293.406091) (xy 326.94803 -293.452772)
			(xy 326.955925 -293.501349) (xy 326.95642 -293.525956) (xy 327.285362 -293.525956) (xy 327.289322 -293.476902)
			(xy 327.301099 -293.429118) (xy 327.32039 -293.383842) (xy 327.346693 -293.342246) (xy 327.379328 -293.305409)
			(xy 327.417449 -293.274284) (xy 327.46007 -293.249677) (xy 327.506086 -293.232225) (xy 327.554305 -293.222381)
			(xy 327.60348 -293.2204) (xy 327.652335 -293.226332) (xy 327.699606 -293.240024) (xy 327.744068 -293.261122)
			(xy 327.784571 -293.289078) (xy 327.820064 -293.32317) (xy 327.849629 -293.362514) (xy 327.8725 -293.406091)
			(xy 327.888084 -293.452772) (xy 327.895979 -293.501349) (xy 327.896474 -293.525956) (xy 328.225416 -293.525956)
			(xy 328.229376 -293.476902) (xy 328.241153 -293.429118) (xy 328.260444 -293.383842) (xy 328.286747 -293.342246)
			(xy 328.319382 -293.305409) (xy 328.357503 -293.274284) (xy 328.400124 -293.249677) (xy 328.44614 -293.232225)
			(xy 328.494359 -293.222381) (xy 328.543534 -293.2204) (xy 328.592389 -293.226332) (xy 328.63966 -293.240024)
			(xy 328.684122 -293.261122) (xy 328.724625 -293.289078) (xy 328.760118 -293.32317) (xy 328.789683 -293.362514)
			(xy 328.812554 -293.406091) (xy 328.828138 -293.452772) (xy 328.836033 -293.501349) (xy 328.836528 -293.525956)
			(xy 329.165216 -293.525956) (xy 329.169176 -293.476902) (xy 329.180953 -293.429118) (xy 329.200244 -293.383842)
			(xy 329.226547 -293.342246) (xy 329.259182 -293.305409) (xy 329.297303 -293.274284) (xy 329.339924 -293.249677)
			(xy 329.38594 -293.232225) (xy 329.434159 -293.222381) (xy 329.483334 -293.2204) (xy 329.532189 -293.226332)
			(xy 329.57946 -293.240024) (xy 329.623922 -293.261122) (xy 329.664425 -293.289078) (xy 329.699918 -293.32317)
			(xy 329.729483 -293.362514) (xy 329.752354 -293.406091) (xy 329.767938 -293.452772) (xy 329.775833 -293.501349)
			(xy 329.776328 -293.525956) (xy 330.094839 -293.525956) (xy 330.098934 -293.475228) (xy 330.111113 -293.425814)
			(xy 330.131061 -293.378994) (xy 330.158262 -293.33598) (xy 330.19201 -293.297886) (xy 330.231432 -293.265699)
			(xy 330.275506 -293.240253) (xy 330.323092 -293.222206) (xy 330.372956 -293.212026) (xy 330.423808 -293.209977)
			(xy 330.474329 -293.216111) (xy 330.523213 -293.230271) (xy 330.569192 -293.252088) (xy 330.611076 -293.280998)
			(xy 330.64778 -293.316253) (xy 330.678353 -293.356939) (xy 330.702004 -293.402002) (xy 330.71812 -293.450276)
			(xy 330.726284 -293.50051) (xy 330.726796 -293.525956) (xy 331.045324 -293.525956) (xy 331.049284 -293.476902)
			(xy 331.061061 -293.429118) (xy 331.080352 -293.383842) (xy 331.106655 -293.342246) (xy 331.13929 -293.305409)
			(xy 331.177411 -293.274284) (xy 331.220032 -293.249677) (xy 331.266048 -293.232225) (xy 331.314267 -293.222381)
			(xy 331.363442 -293.2204) (xy 331.412297 -293.226332) (xy 331.459568 -293.240024) (xy 331.50403 -293.261122)
			(xy 331.544533 -293.289078) (xy 331.580026 -293.32317) (xy 331.609591 -293.362514) (xy 331.632462 -293.406091)
			(xy 331.648046 -293.452772) (xy 331.655941 -293.501349) (xy 331.656436 -293.525956) (xy 331.974947 -293.525956)
			(xy 331.979042 -293.475228) (xy 331.991221 -293.425814) (xy 332.011169 -293.378994) (xy 332.03837 -293.33598)
			(xy 332.072118 -293.297886) (xy 332.11154 -293.265699) (xy 332.155614 -293.240253) (xy 332.2032 -293.222206)
			(xy 332.253064 -293.212026) (xy 332.303916 -293.209977) (xy 332.354437 -293.216111) (xy 332.403321 -293.230271)
			(xy 332.4493 -293.252088) (xy 332.491184 -293.280998) (xy 332.527888 -293.316253) (xy 332.558461 -293.356939)
			(xy 332.582112 -293.402002) (xy 332.598228 -293.450276) (xy 332.606392 -293.50051) (xy 332.606904 -293.525956)
			(xy 332.925178 -293.525956) (xy 332.929138 -293.476902) (xy 332.940915 -293.429118) (xy 332.960206 -293.383842)
			(xy 332.986509 -293.342246) (xy 333.019144 -293.305409) (xy 333.057265 -293.274284) (xy 333.099886 -293.249677)
			(xy 333.145902 -293.232225) (xy 333.194121 -293.222381) (xy 333.243296 -293.2204) (xy 333.292151 -293.226332)
			(xy 333.339422 -293.240024) (xy 333.383884 -293.261122) (xy 333.424387 -293.289078) (xy 333.45988 -293.32317)
			(xy 333.489445 -293.362514) (xy 333.512316 -293.406091) (xy 333.5279 -293.452772) (xy 333.535795 -293.501349)
			(xy 333.53629 -293.525956) (xy 333.865232 -293.525956) (xy 333.869192 -293.476902) (xy 333.880969 -293.429118)
			(xy 333.90026 -293.383842) (xy 333.926563 -293.342246) (xy 333.959198 -293.305409) (xy 333.997319 -293.274284)
			(xy 334.03994 -293.249677) (xy 334.085956 -293.232225) (xy 334.134175 -293.222381) (xy 334.18335 -293.2204)
			(xy 334.232205 -293.226332) (xy 334.279476 -293.240024) (xy 334.323938 -293.261122) (xy 334.364441 -293.289078)
			(xy 334.399934 -293.32317) (xy 334.429499 -293.362514) (xy 334.45237 -293.406091) (xy 334.467954 -293.452772)
			(xy 334.475849 -293.501349) (xy 334.476344 -293.525956) (xy 334.805286 -293.525956) (xy 334.809246 -293.476902)
			(xy 334.821023 -293.429118) (xy 334.840314 -293.383842) (xy 334.866617 -293.342246) (xy 334.899252 -293.305409)
			(xy 334.937373 -293.274284) (xy 334.979994 -293.249677) (xy 335.02601 -293.232225) (xy 335.074229 -293.222381)
			(xy 335.123404 -293.2204) (xy 335.172259 -293.226332) (xy 335.21953 -293.240024) (xy 335.263992 -293.261122)
			(xy 335.304495 -293.289078) (xy 335.339988 -293.32317) (xy 335.369553 -293.362514) (xy 335.392424 -293.406091)
			(xy 335.408008 -293.452772) (xy 335.415903 -293.501349) (xy 335.416398 -293.525956) (xy 335.74534 -293.525956)
			(xy 335.7493 -293.476902) (xy 335.761077 -293.429118) (xy 335.780368 -293.383842) (xy 335.806671 -293.342246)
			(xy 335.839306 -293.305409) (xy 335.877427 -293.274284) (xy 335.920048 -293.249677) (xy 335.966064 -293.232225)
			(xy 336.014283 -293.222381) (xy 336.063458 -293.2204) (xy 336.112313 -293.226332) (xy 336.159584 -293.240024)
			(xy 336.204046 -293.261122) (xy 336.244549 -293.289078) (xy 336.280042 -293.32317) (xy 336.309607 -293.362514)
			(xy 336.332478 -293.406091) (xy 336.348062 -293.452772) (xy 336.355957 -293.501349) (xy 336.356452 -293.525956)
			(xy 336.674963 -293.525956) (xy 336.679058 -293.475228) (xy 336.691237 -293.425814) (xy 336.711185 -293.378994)
			(xy 336.738386 -293.33598) (xy 336.772134 -293.297886) (xy 336.811556 -293.265699) (xy 336.85563 -293.240253)
			(xy 336.903216 -293.222206) (xy 336.95308 -293.212026) (xy 337.003932 -293.209977) (xy 337.054453 -293.216111)
			(xy 337.103337 -293.230271) (xy 337.149316 -293.252088) (xy 337.1912 -293.280998) (xy 337.227904 -293.316253)
			(xy 337.258477 -293.356939) (xy 337.282128 -293.402002) (xy 337.298244 -293.450276) (xy 337.306408 -293.50051)
			(xy 337.30692 -293.525956) (xy 337.625194 -293.525956) (xy 337.629154 -293.476902) (xy 337.640931 -293.429118)
			(xy 337.660222 -293.383842) (xy 337.686525 -293.342246) (xy 337.71916 -293.305409) (xy 337.757281 -293.274284)
			(xy 337.799902 -293.249677) (xy 337.845918 -293.232225) (xy 337.894137 -293.222381) (xy 337.943312 -293.2204)
			(xy 337.992167 -293.226332) (xy 338.039438 -293.240024) (xy 338.0839 -293.261122) (xy 338.124403 -293.289078)
			(xy 338.159896 -293.32317) (xy 338.189461 -293.362514) (xy 338.212332 -293.406091) (xy 338.227916 -293.452772)
			(xy 338.235811 -293.501349) (xy 338.236306 -293.525956) (xy 338.554817 -293.525956) (xy 338.558912 -293.475228)
			(xy 338.571091 -293.425814) (xy 338.591039 -293.378994) (xy 338.61824 -293.33598) (xy 338.651988 -293.297886)
			(xy 338.69141 -293.265699) (xy 338.735484 -293.240253) (xy 338.78307 -293.222206) (xy 338.832934 -293.212026)
			(xy 338.883786 -293.209977) (xy 338.934307 -293.216111) (xy 338.983191 -293.230271) (xy 339.02917 -293.252088)
			(xy 339.071054 -293.280998) (xy 339.107758 -293.316253) (xy 339.138331 -293.356939) (xy 339.161982 -293.402002)
			(xy 339.178098 -293.450276) (xy 339.186262 -293.50051) (xy 339.186774 -293.525956) (xy 339.505302 -293.525956)
			(xy 339.509262 -293.476902) (xy 339.521039 -293.429118) (xy 339.54033 -293.383842) (xy 339.566633 -293.342246)
			(xy 339.599268 -293.305409) (xy 339.637389 -293.274284) (xy 339.68001 -293.249677) (xy 339.726026 -293.232225)
			(xy 339.774245 -293.222381) (xy 339.82342 -293.2204) (xy 339.872275 -293.226332) (xy 339.919546 -293.240024)
			(xy 339.964008 -293.261122) (xy 340.004511 -293.289078) (xy 340.040004 -293.32317) (xy 340.069569 -293.362514)
			(xy 340.09244 -293.406091) (xy 340.108024 -293.452772) (xy 340.115919 -293.501349) (xy 340.116414 -293.525956)
			(xy 340.445356 -293.525956) (xy 340.449316 -293.476902) (xy 340.461093 -293.429118) (xy 340.480384 -293.383842)
			(xy 340.506687 -293.342246) (xy 340.539322 -293.305409) (xy 340.577443 -293.274284) (xy 340.620064 -293.249677)
			(xy 340.66608 -293.232225) (xy 340.714299 -293.222381) (xy 340.763474 -293.2204) (xy 340.812329 -293.226332)
			(xy 340.8596 -293.240024) (xy 340.904062 -293.261122) (xy 340.944565 -293.289078) (xy 340.980058 -293.32317)
			(xy 341.009623 -293.362514) (xy 341.032494 -293.406091) (xy 341.048078 -293.452772) (xy 341.055973 -293.501349)
			(xy 341.056468 -293.525956) (xy 341.38541 -293.525956) (xy 341.38937 -293.476902) (xy 341.401147 -293.429118)
			(xy 341.420438 -293.383842) (xy 341.446741 -293.342246) (xy 341.479376 -293.305409) (xy 341.517497 -293.274284)
			(xy 341.560118 -293.249677) (xy 341.606134 -293.232225) (xy 341.654353 -293.222381) (xy 341.703528 -293.2204)
			(xy 341.752383 -293.226332) (xy 341.799654 -293.240024) (xy 341.844116 -293.261122) (xy 341.884619 -293.289078)
			(xy 341.920112 -293.32317) (xy 341.949677 -293.362514) (xy 341.972548 -293.406091) (xy 341.988132 -293.452772)
			(xy 341.996027 -293.501349) (xy 341.996522 -293.525956) (xy 342.32521 -293.525956) (xy 342.32917 -293.476902)
			(xy 342.340947 -293.429118) (xy 342.360238 -293.383842) (xy 342.386541 -293.342246) (xy 342.419176 -293.305409)
			(xy 342.457297 -293.274284) (xy 342.499918 -293.249677) (xy 342.545934 -293.232225) (xy 342.594153 -293.222381)
			(xy 342.643328 -293.2204) (xy 342.692183 -293.226332) (xy 342.739454 -293.240024) (xy 342.783916 -293.261122)
			(xy 342.824419 -293.289078) (xy 342.859912 -293.32317) (xy 342.889477 -293.362514) (xy 342.912348 -293.406091)
			(xy 342.927932 -293.452772) (xy 342.935827 -293.501349) (xy 342.936322 -293.525956) (xy 343.254833 -293.525956)
			(xy 343.258928 -293.475228) (xy 343.271107 -293.425814) (xy 343.291055 -293.378994) (xy 343.318256 -293.33598)
			(xy 343.352004 -293.297886) (xy 343.391426 -293.265699) (xy 343.4355 -293.240253) (xy 343.483086 -293.222206)
			(xy 343.53295 -293.212026) (xy 343.583802 -293.209977) (xy 343.634323 -293.216111) (xy 343.683207 -293.230271)
			(xy 343.729186 -293.252088) (xy 343.77107 -293.280998) (xy 343.807774 -293.316253) (xy 343.838347 -293.356939)
			(xy 343.861998 -293.402002) (xy 343.878114 -293.450276) (xy 343.886278 -293.50051) (xy 343.88679 -293.525956)
			(xy 344.205318 -293.525956) (xy 344.209278 -293.476902) (xy 344.221055 -293.429118) (xy 344.240346 -293.383842)
			(xy 344.266649 -293.342246) (xy 344.299284 -293.305409) (xy 344.337405 -293.274284) (xy 344.380026 -293.249677)
			(xy 344.426042 -293.232225) (xy 344.474261 -293.222381) (xy 344.523436 -293.2204) (xy 344.572291 -293.226332)
			(xy 344.619562 -293.240024) (xy 344.664024 -293.261122) (xy 344.704527 -293.289078) (xy 344.74002 -293.32317)
			(xy 344.769585 -293.362514) (xy 344.792456 -293.406091) (xy 344.80804 -293.452772) (xy 344.815935 -293.501349)
			(xy 344.81643 -293.525956) (xy 345.145372 -293.525956) (xy 345.149332 -293.476902) (xy 345.161109 -293.429118)
			(xy 345.1804 -293.383842) (xy 345.206703 -293.342246) (xy 345.239338 -293.305409) (xy 345.277459 -293.274284)
			(xy 345.32008 -293.249677) (xy 345.366096 -293.232225) (xy 345.414315 -293.222381) (xy 345.46349 -293.2204)
			(xy 345.512345 -293.226332) (xy 345.559616 -293.240024) (xy 345.604078 -293.261122) (xy 345.644581 -293.289078)
			(xy 345.680074 -293.32317) (xy 345.709639 -293.362514) (xy 345.73251 -293.406091) (xy 345.748094 -293.452772)
			(xy 345.755989 -293.501349) (xy 345.756484 -293.525956) (xy 346.085426 -293.525956) (xy 346.089386 -293.476902)
			(xy 346.101163 -293.429118) (xy 346.120454 -293.383842) (xy 346.146757 -293.342246) (xy 346.179392 -293.305409)
			(xy 346.217513 -293.274284) (xy 346.260134 -293.249677) (xy 346.30615 -293.232225) (xy 346.354369 -293.222381)
			(xy 346.403544 -293.2204) (xy 346.452399 -293.226332) (xy 346.49967 -293.240024) (xy 346.544132 -293.261122)
			(xy 346.584635 -293.289078) (xy 346.620128 -293.32317) (xy 346.649693 -293.362514) (xy 346.672564 -293.406091)
			(xy 346.688148 -293.452772) (xy 346.696043 -293.501349) (xy 346.696538 -293.525956) (xy 347.025226 -293.525956)
			(xy 347.029186 -293.476902) (xy 347.040963 -293.429118) (xy 347.060254 -293.383842) (xy 347.086557 -293.342246)
			(xy 347.119192 -293.305409) (xy 347.157313 -293.274284) (xy 347.199934 -293.249677) (xy 347.24595 -293.232225)
			(xy 347.294169 -293.222381) (xy 347.343344 -293.2204) (xy 347.392199 -293.226332) (xy 347.43947 -293.240024)
			(xy 347.483932 -293.261122) (xy 347.524435 -293.289078) (xy 347.559928 -293.32317) (xy 347.589493 -293.362514)
			(xy 347.612364 -293.406091) (xy 347.627948 -293.452772) (xy 347.635843 -293.501349) (xy 347.636338 -293.525956)
			(xy 347.96528 -293.525956) (xy 347.96924 -293.476902) (xy 347.981017 -293.429118) (xy 348.000308 -293.383842)
			(xy 348.026611 -293.342246) (xy 348.059246 -293.305409) (xy 348.097367 -293.274284) (xy 348.139988 -293.249677)
			(xy 348.186004 -293.232225) (xy 348.234223 -293.222381) (xy 348.283398 -293.2204) (xy 348.332253 -293.226332)
			(xy 348.379524 -293.240024) (xy 348.423986 -293.261122) (xy 348.464489 -293.289078) (xy 348.499982 -293.32317)
			(xy 348.529547 -293.362514) (xy 348.552418 -293.406091) (xy 348.568002 -293.452772) (xy 348.575897 -293.501349)
			(xy 348.576392 -293.525956) (xy 348.905334 -293.525956) (xy 348.909294 -293.476902) (xy 348.921071 -293.429118)
			(xy 348.940362 -293.383842) (xy 348.966665 -293.342246) (xy 348.9993 -293.305409) (xy 349.037421 -293.274284)
			(xy 349.080042 -293.249677) (xy 349.126058 -293.232225) (xy 349.174277 -293.222381) (xy 349.223452 -293.2204)
			(xy 349.272307 -293.226332) (xy 349.319578 -293.240024) (xy 349.36404 -293.261122) (xy 349.404543 -293.289078)
			(xy 349.440036 -293.32317) (xy 349.469601 -293.362514) (xy 349.492472 -293.406091) (xy 349.508056 -293.452772)
			(xy 349.515951 -293.501349) (xy 349.516446 -293.525956) (xy 349.845388 -293.525956) (xy 349.849348 -293.476902)
			(xy 349.861125 -293.429118) (xy 349.880416 -293.383842) (xy 349.906719 -293.342246) (xy 349.939354 -293.305409)
			(xy 349.977475 -293.274284) (xy 350.020096 -293.249677) (xy 350.066112 -293.232225) (xy 350.114331 -293.222381)
			(xy 350.163506 -293.2204) (xy 350.212361 -293.226332) (xy 350.259632 -293.240024) (xy 350.304094 -293.261122)
			(xy 350.344597 -293.289078) (xy 350.38009 -293.32317) (xy 350.409655 -293.362514) (xy 350.432526 -293.406091)
			(xy 350.44811 -293.452772) (xy 350.456005 -293.501349) (xy 350.4565 -293.525956) (xy 350.785442 -293.525956)
			(xy 350.789402 -293.476902) (xy 350.801179 -293.429118) (xy 350.82047 -293.383842) (xy 350.846773 -293.342246)
			(xy 350.879408 -293.305409) (xy 350.917529 -293.274284) (xy 350.96015 -293.249677) (xy 351.006166 -293.232225)
			(xy 351.054385 -293.222381) (xy 351.10356 -293.2204) (xy 351.152415 -293.226332) (xy 351.199686 -293.240024)
			(xy 351.244148 -293.261122) (xy 351.284651 -293.289078) (xy 351.320144 -293.32317) (xy 351.349709 -293.362514)
			(xy 351.37258 -293.406091) (xy 351.388164 -293.452772) (xy 351.396059 -293.501349) (xy 351.396554 -293.525956)
			(xy 351.396059 -293.550563) (xy 351.388164 -293.59914) (xy 351.37258 -293.645821) (xy 351.349709 -293.689398)
			(xy 351.320144 -293.728742) (xy 351.284651 -293.762834) (xy 351.244148 -293.79079) (xy 351.199686 -293.811888)
			(xy 351.152415 -293.82558) (xy 351.10356 -293.831512) (xy 351.054385 -293.829531) (xy 351.006166 -293.819687)
			(xy 350.96015 -293.802235) (xy 350.917529 -293.777628) (xy 350.879408 -293.746503) (xy 350.846773 -293.709666)
			(xy 350.82047 -293.66807) (xy 350.801179 -293.622794) (xy 350.789402 -293.57501) (xy 350.785442 -293.525956)
			(xy 350.4565 -293.525956) (xy 350.456005 -293.550563) (xy 350.44811 -293.59914) (xy 350.432526 -293.645821)
			(xy 350.409655 -293.689398) (xy 350.38009 -293.728742) (xy 350.344597 -293.762834) (xy 350.304094 -293.79079)
			(xy 350.259632 -293.811888) (xy 350.212361 -293.82558) (xy 350.163506 -293.831512) (xy 350.114331 -293.829531)
			(xy 350.066112 -293.819687) (xy 350.020096 -293.802235) (xy 349.977475 -293.777628) (xy 349.939354 -293.746503)
			(xy 349.906719 -293.709666) (xy 349.880416 -293.66807) (xy 349.861125 -293.622794) (xy 349.849348 -293.57501)
			(xy 349.845388 -293.525956) (xy 349.516446 -293.525956) (xy 349.515951 -293.550563) (xy 349.508056 -293.59914)
			(xy 349.492472 -293.645821) (xy 349.469601 -293.689398) (xy 349.440036 -293.728742) (xy 349.404543 -293.762834)
			(xy 349.36404 -293.79079) (xy 349.319578 -293.811888) (xy 349.272307 -293.82558) (xy 349.223452 -293.831512)
			(xy 349.174277 -293.829531) (xy 349.126058 -293.819687) (xy 349.080042 -293.802235) (xy 349.037421 -293.777628)
			(xy 348.9993 -293.746503) (xy 348.966665 -293.709666) (xy 348.940362 -293.66807) (xy 348.921071 -293.622794)
			(xy 348.909294 -293.57501) (xy 348.905334 -293.525956) (xy 348.576392 -293.525956) (xy 348.575897 -293.550563)
			(xy 348.568002 -293.59914) (xy 348.552418 -293.645821) (xy 348.529547 -293.689398) (xy 348.499982 -293.728742)
			(xy 348.464489 -293.762834) (xy 348.423986 -293.79079) (xy 348.379524 -293.811888) (xy 348.332253 -293.82558)
			(xy 348.283398 -293.831512) (xy 348.234223 -293.829531) (xy 348.186004 -293.819687) (xy 348.139988 -293.802235)
			(xy 348.097367 -293.777628) (xy 348.059246 -293.746503) (xy 348.026611 -293.709666) (xy 348.000308 -293.66807)
			(xy 347.981017 -293.622794) (xy 347.96924 -293.57501) (xy 347.96528 -293.525956) (xy 347.636338 -293.525956)
			(xy 347.635843 -293.550563) (xy 347.627948 -293.59914) (xy 347.612364 -293.645821) (xy 347.589493 -293.689398)
			(xy 347.559928 -293.728742) (xy 347.524435 -293.762834) (xy 347.483932 -293.79079) (xy 347.43947 -293.811888)
			(xy 347.392199 -293.82558) (xy 347.343344 -293.831512) (xy 347.294169 -293.829531) (xy 347.24595 -293.819687)
			(xy 347.199934 -293.802235) (xy 347.157313 -293.777628) (xy 347.119192 -293.746503) (xy 347.086557 -293.709666)
			(xy 347.060254 -293.66807) (xy 347.040963 -293.622794) (xy 347.029186 -293.57501) (xy 347.025226 -293.525956)
			(xy 346.696538 -293.525956) (xy 346.696043 -293.550563) (xy 346.688148 -293.59914) (xy 346.672564 -293.645821)
			(xy 346.649693 -293.689398) (xy 346.620128 -293.728742) (xy 346.584635 -293.762834) (xy 346.544132 -293.79079)
			(xy 346.49967 -293.811888) (xy 346.452399 -293.82558) (xy 346.403544 -293.831512) (xy 346.354369 -293.829531)
			(xy 346.30615 -293.819687) (xy 346.260134 -293.802235) (xy 346.217513 -293.777628) (xy 346.179392 -293.746503)
			(xy 346.146757 -293.709666) (xy 346.120454 -293.66807) (xy 346.101163 -293.622794) (xy 346.089386 -293.57501)
			(xy 346.085426 -293.525956) (xy 345.756484 -293.525956) (xy 345.755989 -293.550563) (xy 345.748094 -293.59914)
			(xy 345.73251 -293.645821) (xy 345.709639 -293.689398) (xy 345.680074 -293.728742) (xy 345.644581 -293.762834)
			(xy 345.604078 -293.79079) (xy 345.559616 -293.811888) (xy 345.512345 -293.82558) (xy 345.46349 -293.831512)
			(xy 345.414315 -293.829531) (xy 345.366096 -293.819687) (xy 345.32008 -293.802235) (xy 345.277459 -293.777628)
			(xy 345.239338 -293.746503) (xy 345.206703 -293.709666) (xy 345.1804 -293.66807) (xy 345.161109 -293.622794)
			(xy 345.149332 -293.57501) (xy 345.145372 -293.525956) (xy 344.81643 -293.525956) (xy 344.815935 -293.550563)
			(xy 344.80804 -293.59914) (xy 344.792456 -293.645821) (xy 344.769585 -293.689398) (xy 344.74002 -293.728742)
			(xy 344.704527 -293.762834) (xy 344.664024 -293.79079) (xy 344.619562 -293.811888) (xy 344.572291 -293.82558)
			(xy 344.523436 -293.831512) (xy 344.474261 -293.829531) (xy 344.426042 -293.819687) (xy 344.380026 -293.802235)
			(xy 344.337405 -293.777628) (xy 344.299284 -293.746503) (xy 344.266649 -293.709666) (xy 344.240346 -293.66807)
			(xy 344.221055 -293.622794) (xy 344.209278 -293.57501) (xy 344.205318 -293.525956) (xy 343.88679 -293.525956)
			(xy 343.886278 -293.551402) (xy 343.878114 -293.601636) (xy 343.861998 -293.64991) (xy 343.838347 -293.694973)
			(xy 343.807774 -293.735659) (xy 343.77107 -293.770914) (xy 343.729186 -293.799824) (xy 343.683207 -293.821641)
			(xy 343.634323 -293.835801) (xy 343.583802 -293.841935) (xy 343.53295 -293.839886) (xy 343.483086 -293.829706)
			(xy 343.4355 -293.811659) (xy 343.391426 -293.786213) (xy 343.352004 -293.754026) (xy 343.318256 -293.715932)
			(xy 343.291055 -293.672918) (xy 343.271107 -293.626098) (xy 343.258928 -293.576684) (xy 343.254833 -293.525956)
			(xy 342.936322 -293.525956) (xy 342.935827 -293.550563) (xy 342.927932 -293.59914) (xy 342.912348 -293.645821)
			(xy 342.889477 -293.689398) (xy 342.859912 -293.728742) (xy 342.824419 -293.762834) (xy 342.783916 -293.79079)
			(xy 342.739454 -293.811888) (xy 342.692183 -293.82558) (xy 342.643328 -293.831512) (xy 342.594153 -293.829531)
			(xy 342.545934 -293.819687) (xy 342.499918 -293.802235) (xy 342.457297 -293.777628) (xy 342.419176 -293.746503)
			(xy 342.386541 -293.709666) (xy 342.360238 -293.66807) (xy 342.340947 -293.622794) (xy 342.32917 -293.57501)
			(xy 342.32521 -293.525956) (xy 341.996522 -293.525956) (xy 341.996027 -293.550563) (xy 341.988132 -293.59914)
			(xy 341.972548 -293.645821) (xy 341.949677 -293.689398) (xy 341.920112 -293.728742) (xy 341.884619 -293.762834)
			(xy 341.844116 -293.79079) (xy 341.799654 -293.811888) (xy 341.752383 -293.82558) (xy 341.703528 -293.831512)
			(xy 341.654353 -293.829531) (xy 341.606134 -293.819687) (xy 341.560118 -293.802235) (xy 341.517497 -293.777628)
			(xy 341.479376 -293.746503) (xy 341.446741 -293.709666) (xy 341.420438 -293.66807) (xy 341.401147 -293.622794)
			(xy 341.38937 -293.57501) (xy 341.38541 -293.525956) (xy 341.056468 -293.525956) (xy 341.055973 -293.550563)
			(xy 341.048078 -293.59914) (xy 341.032494 -293.645821) (xy 341.009623 -293.689398) (xy 340.980058 -293.728742)
			(xy 340.944565 -293.762834) (xy 340.904062 -293.79079) (xy 340.8596 -293.811888) (xy 340.812329 -293.82558)
			(xy 340.763474 -293.831512) (xy 340.714299 -293.829531) (xy 340.66608 -293.819687) (xy 340.620064 -293.802235)
			(xy 340.577443 -293.777628) (xy 340.539322 -293.746503) (xy 340.506687 -293.709666) (xy 340.480384 -293.66807)
			(xy 340.461093 -293.622794) (xy 340.449316 -293.57501) (xy 340.445356 -293.525956) (xy 340.116414 -293.525956)
			(xy 340.115919 -293.550563) (xy 340.108024 -293.59914) (xy 340.09244 -293.645821) (xy 340.069569 -293.689398)
			(xy 340.040004 -293.728742) (xy 340.004511 -293.762834) (xy 339.964008 -293.79079) (xy 339.919546 -293.811888)
			(xy 339.872275 -293.82558) (xy 339.82342 -293.831512) (xy 339.774245 -293.829531) (xy 339.726026 -293.819687)
			(xy 339.68001 -293.802235) (xy 339.637389 -293.777628) (xy 339.599268 -293.746503) (xy 339.566633 -293.709666)
			(xy 339.54033 -293.66807) (xy 339.521039 -293.622794) (xy 339.509262 -293.57501) (xy 339.505302 -293.525956)
			(xy 339.186774 -293.525956) (xy 339.186262 -293.551402) (xy 339.178098 -293.601636) (xy 339.161982 -293.64991)
			(xy 339.138331 -293.694973) (xy 339.107758 -293.735659) (xy 339.071054 -293.770914) (xy 339.02917 -293.799824)
			(xy 338.983191 -293.821641) (xy 338.934307 -293.835801) (xy 338.883786 -293.841935) (xy 338.832934 -293.839886)
			(xy 338.78307 -293.829706) (xy 338.735484 -293.811659) (xy 338.69141 -293.786213) (xy 338.651988 -293.754026)
			(xy 338.61824 -293.715932) (xy 338.591039 -293.672918) (xy 338.571091 -293.626098) (xy 338.558912 -293.576684)
			(xy 338.554817 -293.525956) (xy 338.236306 -293.525956) (xy 338.235811 -293.550563) (xy 338.227916 -293.59914)
			(xy 338.212332 -293.645821) (xy 338.189461 -293.689398) (xy 338.159896 -293.728742) (xy 338.124403 -293.762834)
			(xy 338.0839 -293.79079) (xy 338.039438 -293.811888) (xy 337.992167 -293.82558) (xy 337.943312 -293.831512)
			(xy 337.894137 -293.829531) (xy 337.845918 -293.819687) (xy 337.799902 -293.802235) (xy 337.757281 -293.777628)
			(xy 337.71916 -293.746503) (xy 337.686525 -293.709666) (xy 337.660222 -293.66807) (xy 337.640931 -293.622794)
			(xy 337.629154 -293.57501) (xy 337.625194 -293.525956) (xy 337.30692 -293.525956) (xy 337.306408 -293.551402)
			(xy 337.298244 -293.601636) (xy 337.282128 -293.64991) (xy 337.258477 -293.694973) (xy 337.227904 -293.735659)
			(xy 337.1912 -293.770914) (xy 337.149316 -293.799824) (xy 337.103337 -293.821641) (xy 337.054453 -293.835801)
			(xy 337.003932 -293.841935) (xy 336.95308 -293.839886) (xy 336.903216 -293.829706) (xy 336.85563 -293.811659)
			(xy 336.811556 -293.786213) (xy 336.772134 -293.754026) (xy 336.738386 -293.715932) (xy 336.711185 -293.672918)
			(xy 336.691237 -293.626098) (xy 336.679058 -293.576684) (xy 336.674963 -293.525956) (xy 336.356452 -293.525956)
			(xy 336.355957 -293.550563) (xy 336.348062 -293.59914) (xy 336.332478 -293.645821) (xy 336.309607 -293.689398)
			(xy 336.280042 -293.728742) (xy 336.244549 -293.762834) (xy 336.204046 -293.79079) (xy 336.159584 -293.811888)
			(xy 336.112313 -293.82558) (xy 336.063458 -293.831512) (xy 336.014283 -293.829531) (xy 335.966064 -293.819687)
			(xy 335.920048 -293.802235) (xy 335.877427 -293.777628) (xy 335.839306 -293.746503) (xy 335.806671 -293.709666)
			(xy 335.780368 -293.66807) (xy 335.761077 -293.622794) (xy 335.7493 -293.57501) (xy 335.74534 -293.525956)
			(xy 335.416398 -293.525956) (xy 335.415903 -293.550563) (xy 335.408008 -293.59914) (xy 335.392424 -293.645821)
			(xy 335.369553 -293.689398) (xy 335.339988 -293.728742) (xy 335.304495 -293.762834) (xy 335.263992 -293.79079)
			(xy 335.21953 -293.811888) (xy 335.172259 -293.82558) (xy 335.123404 -293.831512) (xy 335.074229 -293.829531)
			(xy 335.02601 -293.819687) (xy 334.979994 -293.802235) (xy 334.937373 -293.777628) (xy 334.899252 -293.746503)
			(xy 334.866617 -293.709666) (xy 334.840314 -293.66807) (xy 334.821023 -293.622794) (xy 334.809246 -293.57501)
			(xy 334.805286 -293.525956) (xy 334.476344 -293.525956) (xy 334.475849 -293.550563) (xy 334.467954 -293.59914)
			(xy 334.45237 -293.645821) (xy 334.429499 -293.689398) (xy 334.399934 -293.728742) (xy 334.364441 -293.762834)
			(xy 334.323938 -293.79079) (xy 334.279476 -293.811888) (xy 334.232205 -293.82558) (xy 334.18335 -293.831512)
			(xy 334.134175 -293.829531) (xy 334.085956 -293.819687) (xy 334.03994 -293.802235) (xy 333.997319 -293.777628)
			(xy 333.959198 -293.746503) (xy 333.926563 -293.709666) (xy 333.90026 -293.66807) (xy 333.880969 -293.622794)
			(xy 333.869192 -293.57501) (xy 333.865232 -293.525956) (xy 333.53629 -293.525956) (xy 333.535795 -293.550563)
			(xy 333.5279 -293.59914) (xy 333.512316 -293.645821) (xy 333.489445 -293.689398) (xy 333.45988 -293.728742)
			(xy 333.424387 -293.762834) (xy 333.383884 -293.79079) (xy 333.339422 -293.811888) (xy 333.292151 -293.82558)
			(xy 333.243296 -293.831512) (xy 333.194121 -293.829531) (xy 333.145902 -293.819687) (xy 333.099886 -293.802235)
			(xy 333.057265 -293.777628) (xy 333.019144 -293.746503) (xy 332.986509 -293.709666) (xy 332.960206 -293.66807)
			(xy 332.940915 -293.622794) (xy 332.929138 -293.57501) (xy 332.925178 -293.525956) (xy 332.606904 -293.525956)
			(xy 332.606392 -293.551402) (xy 332.598228 -293.601636) (xy 332.582112 -293.64991) (xy 332.558461 -293.694973)
			(xy 332.527888 -293.735659) (xy 332.491184 -293.770914) (xy 332.4493 -293.799824) (xy 332.403321 -293.821641)
			(xy 332.354437 -293.835801) (xy 332.303916 -293.841935) (xy 332.253064 -293.839886) (xy 332.2032 -293.829706)
			(xy 332.155614 -293.811659) (xy 332.11154 -293.786213) (xy 332.072118 -293.754026) (xy 332.03837 -293.715932)
			(xy 332.011169 -293.672918) (xy 331.991221 -293.626098) (xy 331.979042 -293.576684) (xy 331.974947 -293.525956)
			(xy 331.656436 -293.525956) (xy 331.655941 -293.550563) (xy 331.648046 -293.59914) (xy 331.632462 -293.645821)
			(xy 331.609591 -293.689398) (xy 331.580026 -293.728742) (xy 331.544533 -293.762834) (xy 331.50403 -293.79079)
			(xy 331.459568 -293.811888) (xy 331.412297 -293.82558) (xy 331.363442 -293.831512) (xy 331.314267 -293.829531)
			(xy 331.266048 -293.819687) (xy 331.220032 -293.802235) (xy 331.177411 -293.777628) (xy 331.13929 -293.746503)
			(xy 331.106655 -293.709666) (xy 331.080352 -293.66807) (xy 331.061061 -293.622794) (xy 331.049284 -293.57501)
			(xy 331.045324 -293.525956) (xy 330.726796 -293.525956) (xy 330.726284 -293.551402) (xy 330.71812 -293.601636)
			(xy 330.702004 -293.64991) (xy 330.678353 -293.694973) (xy 330.64778 -293.735659) (xy 330.611076 -293.770914)
			(xy 330.569192 -293.799824) (xy 330.523213 -293.821641) (xy 330.474329 -293.835801) (xy 330.423808 -293.841935)
			(xy 330.372956 -293.839886) (xy 330.323092 -293.829706) (xy 330.275506 -293.811659) (xy 330.231432 -293.786213)
			(xy 330.19201 -293.754026) (xy 330.158262 -293.715932) (xy 330.131061 -293.672918) (xy 330.111113 -293.626098)
			(xy 330.098934 -293.576684) (xy 330.094839 -293.525956) (xy 329.776328 -293.525956) (xy 329.775833 -293.550563)
			(xy 329.767938 -293.59914) (xy 329.752354 -293.645821) (xy 329.729483 -293.689398) (xy 329.699918 -293.728742)
			(xy 329.664425 -293.762834) (xy 329.623922 -293.79079) (xy 329.57946 -293.811888) (xy 329.532189 -293.82558)
			(xy 329.483334 -293.831512) (xy 329.434159 -293.829531) (xy 329.38594 -293.819687) (xy 329.339924 -293.802235)
			(xy 329.297303 -293.777628) (xy 329.259182 -293.746503) (xy 329.226547 -293.709666) (xy 329.200244 -293.66807)
			(xy 329.180953 -293.622794) (xy 329.169176 -293.57501) (xy 329.165216 -293.525956) (xy 328.836528 -293.525956)
			(xy 328.836033 -293.550563) (xy 328.828138 -293.59914) (xy 328.812554 -293.645821) (xy 328.789683 -293.689398)
			(xy 328.760118 -293.728742) (xy 328.724625 -293.762834) (xy 328.684122 -293.79079) (xy 328.63966 -293.811888)
			(xy 328.592389 -293.82558) (xy 328.543534 -293.831512) (xy 328.494359 -293.829531) (xy 328.44614 -293.819687)
			(xy 328.400124 -293.802235) (xy 328.357503 -293.777628) (xy 328.319382 -293.746503) (xy 328.286747 -293.709666)
			(xy 328.260444 -293.66807) (xy 328.241153 -293.622794) (xy 328.229376 -293.57501) (xy 328.225416 -293.525956)
			(xy 327.896474 -293.525956) (xy 327.895979 -293.550563) (xy 327.888084 -293.59914) (xy 327.8725 -293.645821)
			(xy 327.849629 -293.689398) (xy 327.820064 -293.728742) (xy 327.784571 -293.762834) (xy 327.744068 -293.79079)
			(xy 327.699606 -293.811888) (xy 327.652335 -293.82558) (xy 327.60348 -293.831512) (xy 327.554305 -293.829531)
			(xy 327.506086 -293.819687) (xy 327.46007 -293.802235) (xy 327.417449 -293.777628) (xy 327.379328 -293.746503)
			(xy 327.346693 -293.709666) (xy 327.32039 -293.66807) (xy 327.301099 -293.622794) (xy 327.289322 -293.57501)
			(xy 327.285362 -293.525956) (xy 326.95642 -293.525956) (xy 326.955925 -293.550563) (xy 326.94803 -293.59914)
			(xy 326.932446 -293.645821) (xy 326.909575 -293.689398) (xy 326.88001 -293.728742) (xy 326.844517 -293.762834)
			(xy 326.804014 -293.79079) (xy 326.759552 -293.811888) (xy 326.712281 -293.82558) (xy 326.663426 -293.831512)
			(xy 326.614251 -293.829531) (xy 326.566032 -293.819687) (xy 326.520016 -293.802235) (xy 326.477395 -293.777628)
			(xy 326.439274 -293.746503) (xy 326.406639 -293.709666) (xy 326.380336 -293.66807) (xy 326.361045 -293.622794)
			(xy 326.349268 -293.57501) (xy 326.345308 -293.525956) (xy 310.45912 -293.525956) (xy 310.45912 -294.070024)
			(xy 324.74714 -294.070024) (xy 324.7511 -294.02097) (xy 324.762877 -293.973186) (xy 324.782168 -293.92791)
			(xy 324.808471 -293.886314) (xy 324.841106 -293.849477) (xy 324.879227 -293.818352) (xy 324.921848 -293.793745)
			(xy 324.967864 -293.776293) (xy 325.016083 -293.766449) (xy 325.065258 -293.764468) (xy 325.114113 -293.7704)
			(xy 325.161384 -293.784092) (xy 325.205846 -293.80519) (xy 325.246349 -293.833146) (xy 325.281842 -293.867238)
			(xy 325.311407 -293.906582) (xy 325.334278 -293.950159) (xy 325.349862 -293.99684) (xy 325.357757 -294.045417)
			(xy 325.358252 -294.070024) (xy 325.357757 -294.094631) (xy 325.349862 -294.143208) (xy 325.334278 -294.189889)
			(xy 325.311407 -294.233466) (xy 325.281842 -294.27281) (xy 325.246349 -294.306902) (xy 325.205846 -294.334858)
			(xy 325.203519 -294.335962) (xy 325.875408 -294.335962) (xy 325.879368 -294.286908) (xy 325.891145 -294.239124)
			(xy 325.910436 -294.193848) (xy 325.936739 -294.152252) (xy 325.969374 -294.115415) (xy 326.007495 -294.08429)
			(xy 326.050116 -294.059683) (xy 326.096132 -294.042231) (xy 326.144351 -294.032387) (xy 326.193526 -294.030406)
			(xy 326.242381 -294.036338) (xy 326.289652 -294.05003) (xy 326.334114 -294.071128) (xy 326.374617 -294.099084)
			(xy 326.41011 -294.133176) (xy 326.439675 -294.17252) (xy 326.462546 -294.216097) (xy 326.47813 -294.262778)
			(xy 326.486025 -294.311355) (xy 326.48652 -294.335962) (xy 327.755262 -294.335962) (xy 327.759222 -294.286908)
			(xy 327.770999 -294.239124) (xy 327.79029 -294.193848) (xy 327.816593 -294.152252) (xy 327.849228 -294.115415)
			(xy 327.887349 -294.08429) (xy 327.92997 -294.059683) (xy 327.975986 -294.042231) (xy 328.024205 -294.032387)
			(xy 328.07338 -294.030406) (xy 328.122235 -294.036338) (xy 328.169506 -294.05003) (xy 328.213968 -294.071128)
			(xy 328.254471 -294.099084) (xy 328.289964 -294.133176) (xy 328.319529 -294.17252) (xy 328.3424 -294.216097)
			(xy 328.357984 -294.262778) (xy 328.365879 -294.311355) (xy 328.366374 -294.335962) (xy 329.63537 -294.335962)
			(xy 329.63933 -294.286908) (xy 329.651107 -294.239124) (xy 329.670398 -294.193848) (xy 329.696701 -294.152252)
			(xy 329.729336 -294.115415) (xy 329.767457 -294.08429) (xy 329.810078 -294.059683) (xy 329.856094 -294.042231)
			(xy 329.904313 -294.032387) (xy 329.953488 -294.030406) (xy 330.002343 -294.036338) (xy 330.049614 -294.05003)
			(xy 330.094076 -294.071128) (xy 330.134579 -294.099084) (xy 330.170072 -294.133176) (xy 330.199637 -294.17252)
			(xy 330.222508 -294.216097) (xy 330.238092 -294.262778) (xy 330.245987 -294.311355) (xy 330.246482 -294.335962)
			(xy 330.57517 -294.335962) (xy 330.57913 -294.286908) (xy 330.590907 -294.239124) (xy 330.610198 -294.193848)
			(xy 330.636501 -294.152252) (xy 330.669136 -294.115415) (xy 330.707257 -294.08429) (xy 330.749878 -294.059683)
			(xy 330.795894 -294.042231) (xy 330.844113 -294.032387) (xy 330.893288 -294.030406) (xy 330.942143 -294.036338)
			(xy 330.989414 -294.05003) (xy 331.033876 -294.071128) (xy 331.074379 -294.099084) (xy 331.109872 -294.133176)
			(xy 331.139437 -294.17252) (xy 331.162308 -294.216097) (xy 331.177892 -294.262778) (xy 331.185787 -294.311355)
			(xy 331.186282 -294.335962) (xy 331.515224 -294.335962) (xy 331.519184 -294.286908) (xy 331.530961 -294.239124)
			(xy 331.550252 -294.193848) (xy 331.576555 -294.152252) (xy 331.60919 -294.115415) (xy 331.647311 -294.08429)
			(xy 331.689932 -294.059683) (xy 331.735948 -294.042231) (xy 331.784167 -294.032387) (xy 331.833342 -294.030406)
			(xy 331.882197 -294.036338) (xy 331.929468 -294.05003) (xy 331.97393 -294.071128) (xy 332.014433 -294.099084)
			(xy 332.049926 -294.133176) (xy 332.079491 -294.17252) (xy 332.102362 -294.216097) (xy 332.117946 -294.262778)
			(xy 332.125841 -294.311355) (xy 332.126336 -294.335962) (xy 332.455278 -294.335962) (xy 332.459238 -294.286908)
			(xy 332.471015 -294.239124) (xy 332.490306 -294.193848) (xy 332.516609 -294.152252) (xy 332.549244 -294.115415)
			(xy 332.587365 -294.08429) (xy 332.629986 -294.059683) (xy 332.676002 -294.042231) (xy 332.724221 -294.032387)
			(xy 332.773396 -294.030406) (xy 332.822251 -294.036338) (xy 332.869522 -294.05003) (xy 332.913984 -294.071128)
			(xy 332.954487 -294.099084) (xy 332.98998 -294.133176) (xy 333.019545 -294.17252) (xy 333.042416 -294.216097)
			(xy 333.058 -294.262778) (xy 333.065895 -294.311355) (xy 333.06639 -294.335962) (xy 333.395332 -294.335962)
			(xy 333.399292 -294.286908) (xy 333.411069 -294.239124) (xy 333.43036 -294.193848) (xy 333.456663 -294.152252)
			(xy 333.489298 -294.115415) (xy 333.527419 -294.08429) (xy 333.57004 -294.059683) (xy 333.616056 -294.042231)
			(xy 333.664275 -294.032387) (xy 333.71345 -294.030406) (xy 333.762305 -294.036338) (xy 333.809576 -294.05003)
			(xy 333.854038 -294.071128) (xy 333.894541 -294.099084) (xy 333.930034 -294.133176) (xy 333.959599 -294.17252)
			(xy 333.98247 -294.216097) (xy 333.998054 -294.262778) (xy 334.005949 -294.311355) (xy 334.006444 -294.335962)
			(xy 334.335386 -294.335962) (xy 334.339346 -294.286908) (xy 334.351123 -294.239124) (xy 334.370414 -294.193848)
			(xy 334.396717 -294.152252) (xy 334.429352 -294.115415) (xy 334.467473 -294.08429) (xy 334.510094 -294.059683)
			(xy 334.55611 -294.042231) (xy 334.604329 -294.032387) (xy 334.653504 -294.030406) (xy 334.702359 -294.036338)
			(xy 334.74963 -294.05003) (xy 334.794092 -294.071128) (xy 334.834595 -294.099084) (xy 334.870088 -294.133176)
			(xy 334.899653 -294.17252) (xy 334.922524 -294.216097) (xy 334.938108 -294.262778) (xy 334.946003 -294.311355)
			(xy 334.946498 -294.335962) (xy 336.21524 -294.335962) (xy 336.2192 -294.286908) (xy 336.230977 -294.239124)
			(xy 336.250268 -294.193848) (xy 336.276571 -294.152252) (xy 336.309206 -294.115415) (xy 336.347327 -294.08429)
			(xy 336.389948 -294.059683) (xy 336.435964 -294.042231) (xy 336.484183 -294.032387) (xy 336.533358 -294.030406)
			(xy 336.582213 -294.036338) (xy 336.629484 -294.05003) (xy 336.673946 -294.071128) (xy 336.714449 -294.099084)
			(xy 336.749942 -294.133176) (xy 336.779507 -294.17252) (xy 336.802378 -294.216097) (xy 336.817962 -294.262778)
			(xy 336.825857 -294.311355) (xy 336.826352 -294.335962) (xy 337.155294 -294.335962) (xy 337.159254 -294.286908)
			(xy 337.171031 -294.239124) (xy 337.190322 -294.193848) (xy 337.216625 -294.152252) (xy 337.24926 -294.115415)
			(xy 337.287381 -294.08429) (xy 337.330002 -294.059683) (xy 337.376018 -294.042231) (xy 337.424237 -294.032387)
			(xy 337.473412 -294.030406) (xy 337.522267 -294.036338) (xy 337.569538 -294.05003) (xy 337.614 -294.071128)
			(xy 337.654503 -294.099084) (xy 337.689996 -294.133176) (xy 337.719561 -294.17252) (xy 337.742432 -294.216097)
			(xy 337.758016 -294.262778) (xy 337.765911 -294.311355) (xy 337.766406 -294.335962) (xy 338.095348 -294.335962)
			(xy 338.099308 -294.286908) (xy 338.111085 -294.239124) (xy 338.130376 -294.193848) (xy 338.156679 -294.152252)
			(xy 338.189314 -294.115415) (xy 338.227435 -294.08429) (xy 338.270056 -294.059683) (xy 338.316072 -294.042231)
			(xy 338.364291 -294.032387) (xy 338.413466 -294.030406) (xy 338.462321 -294.036338) (xy 338.509592 -294.05003)
			(xy 338.554054 -294.071128) (xy 338.594557 -294.099084) (xy 338.63005 -294.133176) (xy 338.659615 -294.17252)
			(xy 338.682486 -294.216097) (xy 338.69807 -294.262778) (xy 338.705965 -294.311355) (xy 338.70646 -294.335962)
			(xy 339.035402 -294.335962) (xy 339.039362 -294.286908) (xy 339.051139 -294.239124) (xy 339.07043 -294.193848)
			(xy 339.096733 -294.152252) (xy 339.129368 -294.115415) (xy 339.167489 -294.08429) (xy 339.21011 -294.059683)
			(xy 339.256126 -294.042231) (xy 339.304345 -294.032387) (xy 339.35352 -294.030406) (xy 339.402375 -294.036338)
			(xy 339.449646 -294.05003) (xy 339.494108 -294.071128) (xy 339.534611 -294.099084) (xy 339.570104 -294.133176)
			(xy 339.599669 -294.17252) (xy 339.62254 -294.216097) (xy 339.638124 -294.262778) (xy 339.646019 -294.311355)
			(xy 339.646514 -294.335962) (xy 339.975202 -294.335962) (xy 339.979162 -294.286908) (xy 339.990939 -294.239124)
			(xy 340.01023 -294.193848) (xy 340.036533 -294.152252) (xy 340.069168 -294.115415) (xy 340.107289 -294.08429)
			(xy 340.14991 -294.059683) (xy 340.195926 -294.042231) (xy 340.244145 -294.032387) (xy 340.29332 -294.030406)
			(xy 340.342175 -294.036338) (xy 340.389446 -294.05003) (xy 340.433908 -294.071128) (xy 340.474411 -294.099084)
			(xy 340.509904 -294.133176) (xy 340.539469 -294.17252) (xy 340.56234 -294.216097) (xy 340.577924 -294.262778)
			(xy 340.585819 -294.311355) (xy 340.586314 -294.335962) (xy 340.915256 -294.335962) (xy 340.919216 -294.286908)
			(xy 340.930993 -294.239124) (xy 340.950284 -294.193848) (xy 340.976587 -294.152252) (xy 341.009222 -294.115415)
			(xy 341.047343 -294.08429) (xy 341.089964 -294.059683) (xy 341.13598 -294.042231) (xy 341.184199 -294.032387)
			(xy 341.233374 -294.030406) (xy 341.282229 -294.036338) (xy 341.3295 -294.05003) (xy 341.373962 -294.071128)
			(xy 341.414465 -294.099084) (xy 341.449958 -294.133176) (xy 341.479523 -294.17252) (xy 341.502394 -294.216097)
			(xy 341.517978 -294.262778) (xy 341.525873 -294.311355) (xy 341.526368 -294.335962) (xy 341.85531 -294.335962)
			(xy 341.85927 -294.286908) (xy 341.871047 -294.239124) (xy 341.890338 -294.193848) (xy 341.916641 -294.152252)
			(xy 341.949276 -294.115415) (xy 341.987397 -294.08429) (xy 342.030018 -294.059683) (xy 342.076034 -294.042231)
			(xy 342.124253 -294.032387) (xy 342.173428 -294.030406) (xy 342.222283 -294.036338) (xy 342.269554 -294.05003)
			(xy 342.314016 -294.071128) (xy 342.354519 -294.099084) (xy 342.390012 -294.133176) (xy 342.419577 -294.17252)
			(xy 342.442448 -294.216097) (xy 342.458032 -294.262778) (xy 342.465927 -294.311355) (xy 342.466422 -294.335962)
			(xy 342.795364 -294.335962) (xy 342.799324 -294.286908) (xy 342.811101 -294.239124) (xy 342.830392 -294.193848)
			(xy 342.856695 -294.152252) (xy 342.88933 -294.115415) (xy 342.927451 -294.08429) (xy 342.970072 -294.059683)
			(xy 343.016088 -294.042231) (xy 343.064307 -294.032387) (xy 343.113482 -294.030406) (xy 343.162337 -294.036338)
			(xy 343.209608 -294.05003) (xy 343.25407 -294.071128) (xy 343.294573 -294.099084) (xy 343.330066 -294.133176)
			(xy 343.359631 -294.17252) (xy 343.382502 -294.216097) (xy 343.398086 -294.262778) (xy 343.405981 -294.311355)
			(xy 343.406476 -294.335962) (xy 343.735418 -294.335962) (xy 343.739378 -294.286908) (xy 343.751155 -294.239124)
			(xy 343.770446 -294.193848) (xy 343.796749 -294.152252) (xy 343.829384 -294.115415) (xy 343.867505 -294.08429)
			(xy 343.910126 -294.059683) (xy 343.956142 -294.042231) (xy 344.004361 -294.032387) (xy 344.053536 -294.030406)
			(xy 344.102391 -294.036338) (xy 344.149662 -294.05003) (xy 344.194124 -294.071128) (xy 344.234627 -294.099084)
			(xy 344.27012 -294.133176) (xy 344.299685 -294.17252) (xy 344.322556 -294.216097) (xy 344.33814 -294.262778)
			(xy 344.346035 -294.311355) (xy 344.34653 -294.335962) (xy 344.664787 -294.335962) (xy 344.668882 -294.285234)
			(xy 344.681061 -294.23582) (xy 344.701009 -294.189) (xy 344.72821 -294.145986) (xy 344.761958 -294.107892)
			(xy 344.80138 -294.075705) (xy 344.845454 -294.050259) (xy 344.89304 -294.032212) (xy 344.942904 -294.022032)
			(xy 344.993756 -294.019983) (xy 345.044277 -294.026117) (xy 345.093161 -294.040277) (xy 345.13914 -294.062094)
			(xy 345.181024 -294.091004) (xy 345.217728 -294.126259) (xy 345.248301 -294.166945) (xy 345.271952 -294.212008)
			(xy 345.288068 -294.260282) (xy 345.296232 -294.310516) (xy 345.296744 -294.335962) (xy 345.604841 -294.335962)
			(xy 345.608936 -294.285234) (xy 345.621115 -294.23582) (xy 345.641063 -294.189) (xy 345.668264 -294.145986)
			(xy 345.702012 -294.107892) (xy 345.741434 -294.075705) (xy 345.785508 -294.050259) (xy 345.833094 -294.032212)
			(xy 345.882958 -294.022032) (xy 345.93381 -294.019983) (xy 345.984331 -294.026117) (xy 346.033215 -294.040277)
			(xy 346.079194 -294.062094) (xy 346.121078 -294.091004) (xy 346.157782 -294.126259) (xy 346.188355 -294.166945)
			(xy 346.212006 -294.212008) (xy 346.228122 -294.260282) (xy 346.236286 -294.310516) (xy 346.236798 -294.335962)
			(xy 346.555326 -294.335962) (xy 346.559286 -294.286908) (xy 346.571063 -294.239124) (xy 346.590354 -294.193848)
			(xy 346.616657 -294.152252) (xy 346.649292 -294.115415) (xy 346.687413 -294.08429) (xy 346.730034 -294.059683)
			(xy 346.77605 -294.042231) (xy 346.824269 -294.032387) (xy 346.873444 -294.030406) (xy 346.922299 -294.036338)
			(xy 346.96957 -294.05003) (xy 347.014032 -294.071128) (xy 347.054535 -294.099084) (xy 347.090028 -294.133176)
			(xy 347.119593 -294.17252) (xy 347.142464 -294.216097) (xy 347.158048 -294.262778) (xy 347.165943 -294.311355)
			(xy 347.166438 -294.335962) (xy 347.484949 -294.335962) (xy 347.489044 -294.285234) (xy 347.501223 -294.23582)
			(xy 347.521171 -294.189) (xy 347.548372 -294.145986) (xy 347.58212 -294.107892) (xy 347.621542 -294.075705)
			(xy 347.665616 -294.050259) (xy 347.713202 -294.032212) (xy 347.763066 -294.022032) (xy 347.813918 -294.019983)
			(xy 347.864439 -294.026117) (xy 347.913323 -294.040277) (xy 347.959302 -294.062094) (xy 348.001186 -294.091004)
			(xy 348.03789 -294.126259) (xy 348.068463 -294.166945) (xy 348.092114 -294.212008) (xy 348.10823 -294.260282)
			(xy 348.116394 -294.310516) (xy 348.116906 -294.335962) (xy 348.425003 -294.335962) (xy 348.429098 -294.285234)
			(xy 348.441277 -294.23582) (xy 348.461225 -294.189) (xy 348.488426 -294.145986) (xy 348.522174 -294.107892)
			(xy 348.561596 -294.075705) (xy 348.60567 -294.050259) (xy 348.653256 -294.032212) (xy 348.70312 -294.022032)
			(xy 348.753972 -294.019983) (xy 348.804493 -294.026117) (xy 348.853377 -294.040277) (xy 348.899356 -294.062094)
			(xy 348.94124 -294.091004) (xy 348.977944 -294.126259) (xy 349.008517 -294.166945) (xy 349.032168 -294.212008)
			(xy 349.048284 -294.260282) (xy 349.056448 -294.310516) (xy 349.05696 -294.335962) (xy 349.375234 -294.335962)
			(xy 349.379194 -294.286908) (xy 349.390971 -294.239124) (xy 349.410262 -294.193848) (xy 349.436565 -294.152252)
			(xy 349.4692 -294.115415) (xy 349.507321 -294.08429) (xy 349.549942 -294.059683) (xy 349.595958 -294.042231)
			(xy 349.644177 -294.032387) (xy 349.693352 -294.030406) (xy 349.742207 -294.036338) (xy 349.789478 -294.05003)
			(xy 349.83394 -294.071128) (xy 349.874443 -294.099084) (xy 349.909936 -294.133176) (xy 349.939501 -294.17252)
			(xy 349.962372 -294.216097) (xy 349.977956 -294.262778) (xy 349.985851 -294.311355) (xy 349.986346 -294.335962)
			(xy 350.304857 -294.335962) (xy 350.308952 -294.285234) (xy 350.321131 -294.23582) (xy 350.341079 -294.189)
			(xy 350.36828 -294.145986) (xy 350.402028 -294.107892) (xy 350.44145 -294.075705) (xy 350.485524 -294.050259)
			(xy 350.53311 -294.032212) (xy 350.582974 -294.022032) (xy 350.633826 -294.019983) (xy 350.684347 -294.026117)
			(xy 350.733231 -294.040277) (xy 350.77921 -294.062094) (xy 350.821094 -294.091004) (xy 350.857798 -294.126259)
			(xy 350.888371 -294.166945) (xy 350.912022 -294.212008) (xy 350.928138 -294.260282) (xy 350.936302 -294.310516)
			(xy 350.936814 -294.335962) (xy 350.936302 -294.361408) (xy 350.928138 -294.411642) (xy 350.912022 -294.459916)
			(xy 350.888371 -294.504979) (xy 350.857798 -294.545665) (xy 350.821094 -294.58092) (xy 350.77921 -294.60983)
			(xy 350.733231 -294.631647) (xy 350.684347 -294.645807) (xy 350.633826 -294.651941) (xy 350.582974 -294.649892)
			(xy 350.53311 -294.639712) (xy 350.485524 -294.621665) (xy 350.44145 -294.596219) (xy 350.402028 -294.564032)
			(xy 350.36828 -294.525938) (xy 350.341079 -294.482924) (xy 350.321131 -294.436104) (xy 350.308952 -294.38669)
			(xy 350.304857 -294.335962) (xy 349.986346 -294.335962) (xy 349.985851 -294.360569) (xy 349.977956 -294.409146)
			(xy 349.962372 -294.455827) (xy 349.939501 -294.499404) (xy 349.909936 -294.538748) (xy 349.874443 -294.57284)
			(xy 349.83394 -294.600796) (xy 349.789478 -294.621894) (xy 349.742207 -294.635586) (xy 349.693352 -294.641518)
			(xy 349.644177 -294.639537) (xy 349.595958 -294.629693) (xy 349.549942 -294.612241) (xy 349.507321 -294.587634)
			(xy 349.4692 -294.556509) (xy 349.436565 -294.519672) (xy 349.410262 -294.478076) (xy 349.390971 -294.4328)
			(xy 349.379194 -294.385016) (xy 349.375234 -294.335962) (xy 349.05696 -294.335962) (xy 349.056448 -294.361408)
			(xy 349.048284 -294.411642) (xy 349.032168 -294.459916) (xy 349.008517 -294.504979) (xy 348.977944 -294.545665)
			(xy 348.94124 -294.58092) (xy 348.899356 -294.60983) (xy 348.853377 -294.631647) (xy 348.804493 -294.645807)
			(xy 348.753972 -294.651941) (xy 348.70312 -294.649892) (xy 348.653256 -294.639712) (xy 348.60567 -294.621665)
			(xy 348.561596 -294.596219) (xy 348.522174 -294.564032) (xy 348.488426 -294.525938) (xy 348.461225 -294.482924)
			(xy 348.441277 -294.436104) (xy 348.429098 -294.38669) (xy 348.425003 -294.335962) (xy 348.116906 -294.335962)
			(xy 348.116394 -294.361408) (xy 348.10823 -294.411642) (xy 348.092114 -294.459916) (xy 348.068463 -294.504979)
			(xy 348.03789 -294.545665) (xy 348.001186 -294.58092) (xy 347.959302 -294.60983) (xy 347.913323 -294.631647)
			(xy 347.864439 -294.645807) (xy 347.813918 -294.651941) (xy 347.763066 -294.649892) (xy 347.713202 -294.639712)
			(xy 347.665616 -294.621665) (xy 347.621542 -294.596219) (xy 347.58212 -294.564032) (xy 347.548372 -294.525938)
			(xy 347.521171 -294.482924) (xy 347.501223 -294.436104) (xy 347.489044 -294.38669) (xy 347.484949 -294.335962)
			(xy 347.166438 -294.335962) (xy 347.165943 -294.360569) (xy 347.158048 -294.409146) (xy 347.142464 -294.455827)
			(xy 347.119593 -294.499404) (xy 347.090028 -294.538748) (xy 347.054535 -294.57284) (xy 347.014032 -294.600796)
			(xy 346.96957 -294.621894) (xy 346.922299 -294.635586) (xy 346.873444 -294.641518) (xy 346.824269 -294.639537)
			(xy 346.77605 -294.629693) (xy 346.730034 -294.612241) (xy 346.687413 -294.587634) (xy 346.649292 -294.556509)
			(xy 346.616657 -294.519672) (xy 346.590354 -294.478076) (xy 346.571063 -294.4328) (xy 346.559286 -294.385016)
			(xy 346.555326 -294.335962) (xy 346.236798 -294.335962) (xy 346.236286 -294.361408) (xy 346.228122 -294.411642)
			(xy 346.212006 -294.459916) (xy 346.188355 -294.504979) (xy 346.157782 -294.545665) (xy 346.121078 -294.58092)
			(xy 346.079194 -294.60983) (xy 346.033215 -294.631647) (xy 345.984331 -294.645807) (xy 345.93381 -294.651941)
			(xy 345.882958 -294.649892) (xy 345.833094 -294.639712) (xy 345.785508 -294.621665) (xy 345.741434 -294.596219)
			(xy 345.702012 -294.564032) (xy 345.668264 -294.525938) (xy 345.641063 -294.482924) (xy 345.621115 -294.436104)
			(xy 345.608936 -294.38669) (xy 345.604841 -294.335962) (xy 345.296744 -294.335962) (xy 345.296232 -294.361408)
			(xy 345.288068 -294.411642) (xy 345.271952 -294.459916) (xy 345.248301 -294.504979) (xy 345.217728 -294.545665)
			(xy 345.181024 -294.58092) (xy 345.13914 -294.60983) (xy 345.093161 -294.631647) (xy 345.044277 -294.645807)
			(xy 344.993756 -294.651941) (xy 344.942904 -294.649892) (xy 344.89304 -294.639712) (xy 344.845454 -294.621665)
			(xy 344.80138 -294.596219) (xy 344.761958 -294.564032) (xy 344.72821 -294.525938) (xy 344.701009 -294.482924)
			(xy 344.681061 -294.436104) (xy 344.668882 -294.38669) (xy 344.664787 -294.335962) (xy 344.34653 -294.335962)
			(xy 344.346035 -294.360569) (xy 344.33814 -294.409146) (xy 344.322556 -294.455827) (xy 344.299685 -294.499404)
			(xy 344.27012 -294.538748) (xy 344.234627 -294.57284) (xy 344.194124 -294.600796) (xy 344.149662 -294.621894)
			(xy 344.102391 -294.635586) (xy 344.053536 -294.641518) (xy 344.004361 -294.639537) (xy 343.956142 -294.629693)
			(xy 343.910126 -294.612241) (xy 343.867505 -294.587634) (xy 343.829384 -294.556509) (xy 343.796749 -294.519672)
			(xy 343.770446 -294.478076) (xy 343.751155 -294.4328) (xy 343.739378 -294.385016) (xy 343.735418 -294.335962)
			(xy 343.406476 -294.335962) (xy 343.405981 -294.360569) (xy 343.398086 -294.409146) (xy 343.382502 -294.455827)
			(xy 343.359631 -294.499404) (xy 343.330066 -294.538748) (xy 343.294573 -294.57284) (xy 343.25407 -294.600796)
			(xy 343.209608 -294.621894) (xy 343.162337 -294.635586) (xy 343.113482 -294.641518) (xy 343.064307 -294.639537)
			(xy 343.016088 -294.629693) (xy 342.970072 -294.612241) (xy 342.927451 -294.587634) (xy 342.88933 -294.556509)
			(xy 342.856695 -294.519672) (xy 342.830392 -294.478076) (xy 342.811101 -294.4328) (xy 342.799324 -294.385016)
			(xy 342.795364 -294.335962) (xy 342.466422 -294.335962) (xy 342.465927 -294.360569) (xy 342.458032 -294.409146)
			(xy 342.442448 -294.455827) (xy 342.419577 -294.499404) (xy 342.390012 -294.538748) (xy 342.354519 -294.57284)
			(xy 342.314016 -294.600796) (xy 342.269554 -294.621894) (xy 342.222283 -294.635586) (xy 342.173428 -294.641518)
			(xy 342.124253 -294.639537) (xy 342.076034 -294.629693) (xy 342.030018 -294.612241) (xy 341.987397 -294.587634)
			(xy 341.949276 -294.556509) (xy 341.916641 -294.519672) (xy 341.890338 -294.478076) (xy 341.871047 -294.4328)
			(xy 341.85927 -294.385016) (xy 341.85531 -294.335962) (xy 341.526368 -294.335962) (xy 341.525873 -294.360569)
			(xy 341.517978 -294.409146) (xy 341.502394 -294.455827) (xy 341.479523 -294.499404) (xy 341.449958 -294.538748)
			(xy 341.414465 -294.57284) (xy 341.373962 -294.600796) (xy 341.3295 -294.621894) (xy 341.282229 -294.635586)
			(xy 341.233374 -294.641518) (xy 341.184199 -294.639537) (xy 341.13598 -294.629693) (xy 341.089964 -294.612241)
			(xy 341.047343 -294.587634) (xy 341.009222 -294.556509) (xy 340.976587 -294.519672) (xy 340.950284 -294.478076)
			(xy 340.930993 -294.4328) (xy 340.919216 -294.385016) (xy 340.915256 -294.335962) (xy 340.586314 -294.335962)
			(xy 340.585819 -294.360569) (xy 340.577924 -294.409146) (xy 340.56234 -294.455827) (xy 340.539469 -294.499404)
			(xy 340.509904 -294.538748) (xy 340.474411 -294.57284) (xy 340.433908 -294.600796) (xy 340.389446 -294.621894)
			(xy 340.342175 -294.635586) (xy 340.29332 -294.641518) (xy 340.244145 -294.639537) (xy 340.195926 -294.629693)
			(xy 340.14991 -294.612241) (xy 340.107289 -294.587634) (xy 340.069168 -294.556509) (xy 340.036533 -294.519672)
			(xy 340.01023 -294.478076) (xy 339.990939 -294.4328) (xy 339.979162 -294.385016) (xy 339.975202 -294.335962)
			(xy 339.646514 -294.335962) (xy 339.646019 -294.360569) (xy 339.638124 -294.409146) (xy 339.62254 -294.455827)
			(xy 339.599669 -294.499404) (xy 339.570104 -294.538748) (xy 339.534611 -294.57284) (xy 339.494108 -294.600796)
			(xy 339.449646 -294.621894) (xy 339.402375 -294.635586) (xy 339.35352 -294.641518) (xy 339.304345 -294.639537)
			(xy 339.256126 -294.629693) (xy 339.21011 -294.612241) (xy 339.167489 -294.587634) (xy 339.129368 -294.556509)
			(xy 339.096733 -294.519672) (xy 339.07043 -294.478076) (xy 339.051139 -294.4328) (xy 339.039362 -294.385016)
			(xy 339.035402 -294.335962) (xy 338.70646 -294.335962) (xy 338.705965 -294.360569) (xy 338.69807 -294.409146)
			(xy 338.682486 -294.455827) (xy 338.659615 -294.499404) (xy 338.63005 -294.538748) (xy 338.594557 -294.57284)
			(xy 338.554054 -294.600796) (xy 338.509592 -294.621894) (xy 338.462321 -294.635586) (xy 338.413466 -294.641518)
			(xy 338.364291 -294.639537) (xy 338.316072 -294.629693) (xy 338.270056 -294.612241) (xy 338.227435 -294.587634)
			(xy 338.189314 -294.556509) (xy 338.156679 -294.519672) (xy 338.130376 -294.478076) (xy 338.111085 -294.4328)
			(xy 338.099308 -294.385016) (xy 338.095348 -294.335962) (xy 337.766406 -294.335962) (xy 337.765911 -294.360569)
			(xy 337.758016 -294.409146) (xy 337.742432 -294.455827) (xy 337.719561 -294.499404) (xy 337.689996 -294.538748)
			(xy 337.654503 -294.57284) (xy 337.614 -294.600796) (xy 337.569538 -294.621894) (xy 337.522267 -294.635586)
			(xy 337.473412 -294.641518) (xy 337.424237 -294.639537) (xy 337.376018 -294.629693) (xy 337.330002 -294.612241)
			(xy 337.287381 -294.587634) (xy 337.24926 -294.556509) (xy 337.216625 -294.519672) (xy 337.190322 -294.478076)
			(xy 337.171031 -294.4328) (xy 337.159254 -294.385016) (xy 337.155294 -294.335962) (xy 336.826352 -294.335962)
			(xy 336.825857 -294.360569) (xy 336.817962 -294.409146) (xy 336.802378 -294.455827) (xy 336.779507 -294.499404)
			(xy 336.749942 -294.538748) (xy 336.714449 -294.57284) (xy 336.673946 -294.600796) (xy 336.629484 -294.621894)
			(xy 336.582213 -294.635586) (xy 336.533358 -294.641518) (xy 336.484183 -294.639537) (xy 336.435964 -294.629693)
			(xy 336.389948 -294.612241) (xy 336.347327 -294.587634) (xy 336.309206 -294.556509) (xy 336.276571 -294.519672)
			(xy 336.250268 -294.478076) (xy 336.230977 -294.4328) (xy 336.2192 -294.385016) (xy 336.21524 -294.335962)
			(xy 334.946498 -294.335962) (xy 334.946003 -294.360569) (xy 334.938108 -294.409146) (xy 334.922524 -294.455827)
			(xy 334.899653 -294.499404) (xy 334.870088 -294.538748) (xy 334.834595 -294.57284) (xy 334.794092 -294.600796)
			(xy 334.74963 -294.621894) (xy 334.702359 -294.635586) (xy 334.653504 -294.641518) (xy 334.604329 -294.639537)
			(xy 334.55611 -294.629693) (xy 334.510094 -294.612241) (xy 334.467473 -294.587634) (xy 334.429352 -294.556509)
			(xy 334.396717 -294.519672) (xy 334.370414 -294.478076) (xy 334.351123 -294.4328) (xy 334.339346 -294.385016)
			(xy 334.335386 -294.335962) (xy 334.006444 -294.335962) (xy 334.005949 -294.360569) (xy 333.998054 -294.409146)
			(xy 333.98247 -294.455827) (xy 333.959599 -294.499404) (xy 333.930034 -294.538748) (xy 333.894541 -294.57284)
			(xy 333.854038 -294.600796) (xy 333.809576 -294.621894) (xy 333.762305 -294.635586) (xy 333.71345 -294.641518)
			(xy 333.664275 -294.639537) (xy 333.616056 -294.629693) (xy 333.57004 -294.612241) (xy 333.527419 -294.587634)
			(xy 333.489298 -294.556509) (xy 333.456663 -294.519672) (xy 333.43036 -294.478076) (xy 333.411069 -294.4328)
			(xy 333.399292 -294.385016) (xy 333.395332 -294.335962) (xy 333.06639 -294.335962) (xy 333.065895 -294.360569)
			(xy 333.058 -294.409146) (xy 333.042416 -294.455827) (xy 333.019545 -294.499404) (xy 332.98998 -294.538748)
			(xy 332.954487 -294.57284) (xy 332.913984 -294.600796) (xy 332.869522 -294.621894) (xy 332.822251 -294.635586)
			(xy 332.773396 -294.641518) (xy 332.724221 -294.639537) (xy 332.676002 -294.629693) (xy 332.629986 -294.612241)
			(xy 332.587365 -294.587634) (xy 332.549244 -294.556509) (xy 332.516609 -294.519672) (xy 332.490306 -294.478076)
			(xy 332.471015 -294.4328) (xy 332.459238 -294.385016) (xy 332.455278 -294.335962) (xy 332.126336 -294.335962)
			(xy 332.125841 -294.360569) (xy 332.117946 -294.409146) (xy 332.102362 -294.455827) (xy 332.079491 -294.499404)
			(xy 332.049926 -294.538748) (xy 332.014433 -294.57284) (xy 331.97393 -294.600796) (xy 331.929468 -294.621894)
			(xy 331.882197 -294.635586) (xy 331.833342 -294.641518) (xy 331.784167 -294.639537) (xy 331.735948 -294.629693)
			(xy 331.689932 -294.612241) (xy 331.647311 -294.587634) (xy 331.60919 -294.556509) (xy 331.576555 -294.519672)
			(xy 331.550252 -294.478076) (xy 331.530961 -294.4328) (xy 331.519184 -294.385016) (xy 331.515224 -294.335962)
			(xy 331.186282 -294.335962) (xy 331.185787 -294.360569) (xy 331.177892 -294.409146) (xy 331.162308 -294.455827)
			(xy 331.139437 -294.499404) (xy 331.109872 -294.538748) (xy 331.074379 -294.57284) (xy 331.033876 -294.600796)
			(xy 330.989414 -294.621894) (xy 330.942143 -294.635586) (xy 330.893288 -294.641518) (xy 330.844113 -294.639537)
			(xy 330.795894 -294.629693) (xy 330.749878 -294.612241) (xy 330.707257 -294.587634) (xy 330.669136 -294.556509)
			(xy 330.636501 -294.519672) (xy 330.610198 -294.478076) (xy 330.590907 -294.4328) (xy 330.57913 -294.385016)
			(xy 330.57517 -294.335962) (xy 330.246482 -294.335962) (xy 330.245987 -294.360569) (xy 330.238092 -294.409146)
			(xy 330.222508 -294.455827) (xy 330.199637 -294.499404) (xy 330.170072 -294.538748) (xy 330.134579 -294.57284)
			(xy 330.094076 -294.600796) (xy 330.049614 -294.621894) (xy 330.002343 -294.635586) (xy 329.953488 -294.641518)
			(xy 329.904313 -294.639537) (xy 329.856094 -294.629693) (xy 329.810078 -294.612241) (xy 329.767457 -294.587634)
			(xy 329.729336 -294.556509) (xy 329.696701 -294.519672) (xy 329.670398 -294.478076) (xy 329.651107 -294.4328)
			(xy 329.63933 -294.385016) (xy 329.63537 -294.335962) (xy 328.366374 -294.335962) (xy 328.365879 -294.360569)
			(xy 328.357984 -294.409146) (xy 328.3424 -294.455827) (xy 328.319529 -294.499404) (xy 328.289964 -294.538748)
			(xy 328.254471 -294.57284) (xy 328.213968 -294.600796) (xy 328.169506 -294.621894) (xy 328.122235 -294.635586)
			(xy 328.07338 -294.641518) (xy 328.024205 -294.639537) (xy 327.975986 -294.629693) (xy 327.92997 -294.612241)
			(xy 327.887349 -294.587634) (xy 327.849228 -294.556509) (xy 327.816593 -294.519672) (xy 327.79029 -294.478076)
			(xy 327.770999 -294.4328) (xy 327.759222 -294.385016) (xy 327.755262 -294.335962) (xy 326.48652 -294.335962)
			(xy 326.486025 -294.360569) (xy 326.47813 -294.409146) (xy 326.462546 -294.455827) (xy 326.439675 -294.499404)
			(xy 326.41011 -294.538748) (xy 326.374617 -294.57284) (xy 326.334114 -294.600796) (xy 326.289652 -294.621894)
			(xy 326.242381 -294.635586) (xy 326.193526 -294.641518) (xy 326.144351 -294.639537) (xy 326.096132 -294.629693)
			(xy 326.050116 -294.612241) (xy 326.007495 -294.587634) (xy 325.969374 -294.556509) (xy 325.936739 -294.519672)
			(xy 325.910436 -294.478076) (xy 325.891145 -294.4328) (xy 325.879368 -294.385016) (xy 325.875408 -294.335962)
			(xy 325.203519 -294.335962) (xy 325.161384 -294.355956) (xy 325.114113 -294.369648) (xy 325.065258 -294.37558)
			(xy 325.016083 -294.373599) (xy 324.967864 -294.363755) (xy 324.921848 -294.346303) (xy 324.879227 -294.321696)
			(xy 324.841106 -294.290571) (xy 324.808471 -294.253734) (xy 324.782168 -294.212138) (xy 324.762877 -294.166862)
			(xy 324.7511 -294.119078) (xy 324.74714 -294.070024) (xy 310.45912 -294.070024) (xy 310.45912 -295.145968)
			(xy 329.165216 -295.145968) (xy 329.169176 -295.096914) (xy 329.180953 -295.04913) (xy 329.200244 -295.003854)
			(xy 329.226547 -294.962258) (xy 329.259182 -294.925421) (xy 329.297303 -294.894296) (xy 329.339924 -294.869689)
			(xy 329.38594 -294.852237) (xy 329.434159 -294.842393) (xy 329.483334 -294.840412) (xy 329.532189 -294.846344)
			(xy 329.57946 -294.860036) (xy 329.623922 -294.881134) (xy 329.664425 -294.90909) (xy 329.699918 -294.943182)
			(xy 329.729483 -294.982526) (xy 329.752354 -295.026103) (xy 329.767938 -295.072784) (xy 329.775833 -295.121361)
			(xy 329.776328 -295.145968) (xy 330.10527 -295.145968) (xy 330.10923 -295.096914) (xy 330.121007 -295.04913)
			(xy 330.140298 -295.003854) (xy 330.166601 -294.962258) (xy 330.199236 -294.925421) (xy 330.237357 -294.894296)
			(xy 330.279978 -294.869689) (xy 330.325994 -294.852237) (xy 330.374213 -294.842393) (xy 330.423388 -294.840412)
			(xy 330.472243 -294.846344) (xy 330.519514 -294.860036) (xy 330.563976 -294.881134) (xy 330.604479 -294.90909)
			(xy 330.639972 -294.943182) (xy 330.669537 -294.982526) (xy 330.692408 -295.026103) (xy 330.707992 -295.072784)
			(xy 330.715887 -295.121361) (xy 330.716382 -295.145968) (xy 331.045324 -295.145968) (xy 331.049284 -295.096914)
			(xy 331.061061 -295.04913) (xy 331.080352 -295.003854) (xy 331.106655 -294.962258) (xy 331.13929 -294.925421)
			(xy 331.177411 -294.894296) (xy 331.220032 -294.869689) (xy 331.266048 -294.852237) (xy 331.314267 -294.842393)
			(xy 331.363442 -294.840412) (xy 331.412297 -294.846344) (xy 331.459568 -294.860036) (xy 331.50403 -294.881134)
			(xy 331.544533 -294.90909) (xy 331.580026 -294.943182) (xy 331.609591 -294.982526) (xy 331.632462 -295.026103)
			(xy 331.648046 -295.072784) (xy 331.655941 -295.121361) (xy 331.656436 -295.145968) (xy 331.985378 -295.145968)
			(xy 331.989338 -295.096914) (xy 332.001115 -295.04913) (xy 332.020406 -295.003854) (xy 332.046709 -294.962258)
			(xy 332.079344 -294.925421) (xy 332.117465 -294.894296) (xy 332.160086 -294.869689) (xy 332.206102 -294.852237)
			(xy 332.254321 -294.842393) (xy 332.303496 -294.840412) (xy 332.352351 -294.846344) (xy 332.399622 -294.860036)
			(xy 332.444084 -294.881134) (xy 332.484587 -294.90909) (xy 332.52008 -294.943182) (xy 332.549645 -294.982526)
			(xy 332.572516 -295.026103) (xy 332.5881 -295.072784) (xy 332.595995 -295.121361) (xy 332.59649 -295.145968)
			(xy 332.925178 -295.145968) (xy 332.929138 -295.096914) (xy 332.940915 -295.04913) (xy 332.960206 -295.003854)
			(xy 332.986509 -294.962258) (xy 333.019144 -294.925421) (xy 333.057265 -294.894296) (xy 333.099886 -294.869689)
			(xy 333.145902 -294.852237) (xy 333.194121 -294.842393) (xy 333.243296 -294.840412) (xy 333.292151 -294.846344)
			(xy 333.339422 -294.860036) (xy 333.383884 -294.881134) (xy 333.424387 -294.90909) (xy 333.45988 -294.943182)
			(xy 333.489445 -294.982526) (xy 333.512316 -295.026103) (xy 333.5279 -295.072784) (xy 333.535795 -295.121361)
			(xy 333.53629 -295.145968) (xy 333.865232 -295.145968) (xy 333.869192 -295.096914) (xy 333.880969 -295.04913)
			(xy 333.90026 -295.003854) (xy 333.926563 -294.962258) (xy 333.959198 -294.925421) (xy 333.997319 -294.894296)
			(xy 334.03994 -294.869689) (xy 334.085956 -294.852237) (xy 334.134175 -294.842393) (xy 334.18335 -294.840412)
			(xy 334.232205 -294.846344) (xy 334.279476 -294.860036) (xy 334.323938 -294.881134) (xy 334.364441 -294.90909)
			(xy 334.399934 -294.943182) (xy 334.429499 -294.982526) (xy 334.45237 -295.026103) (xy 334.467954 -295.072784)
			(xy 334.475849 -295.121361) (xy 334.476344 -295.145968) (xy 334.805286 -295.145968) (xy 334.809246 -295.096914)
			(xy 334.821023 -295.04913) (xy 334.840314 -295.003854) (xy 334.866617 -294.962258) (xy 334.899252 -294.925421)
			(xy 334.937373 -294.894296) (xy 334.979994 -294.869689) (xy 335.02601 -294.852237) (xy 335.074229 -294.842393)
			(xy 335.123404 -294.840412) (xy 335.172259 -294.846344) (xy 335.21953 -294.860036) (xy 335.263992 -294.881134)
			(xy 335.304495 -294.90909) (xy 335.339988 -294.943182) (xy 335.369553 -294.982526) (xy 335.392424 -295.026103)
			(xy 335.408008 -295.072784) (xy 335.415903 -295.121361) (xy 335.416398 -295.145968) (xy 335.74534 -295.145968)
			(xy 335.7493 -295.096914) (xy 335.761077 -295.04913) (xy 335.780368 -295.003854) (xy 335.806671 -294.962258)
			(xy 335.839306 -294.925421) (xy 335.877427 -294.894296) (xy 335.920048 -294.869689) (xy 335.966064 -294.852237)
			(xy 336.014283 -294.842393) (xy 336.063458 -294.840412) (xy 336.112313 -294.846344) (xy 336.159584 -294.860036)
			(xy 336.204046 -294.881134) (xy 336.244549 -294.90909) (xy 336.280042 -294.943182) (xy 336.309607 -294.982526)
			(xy 336.332478 -295.026103) (xy 336.348062 -295.072784) (xy 336.355957 -295.121361) (xy 336.356452 -295.145968)
			(xy 337.625194 -295.145968) (xy 337.629154 -295.096914) (xy 337.640931 -295.04913) (xy 337.660222 -295.003854)
			(xy 337.686525 -294.962258) (xy 337.71916 -294.925421) (xy 337.757281 -294.894296) (xy 337.799902 -294.869689)
			(xy 337.845918 -294.852237) (xy 337.894137 -294.842393) (xy 337.943312 -294.840412) (xy 337.992167 -294.846344)
			(xy 338.039438 -294.860036) (xy 338.0839 -294.881134) (xy 338.124403 -294.90909) (xy 338.159896 -294.943182)
			(xy 338.189461 -294.982526) (xy 338.212332 -295.026103) (xy 338.227916 -295.072784) (xy 338.235811 -295.121361)
			(xy 338.236306 -295.145968) (xy 338.565248 -295.145968) (xy 338.569208 -295.096914) (xy 338.580985 -295.04913)
			(xy 338.600276 -295.003854) (xy 338.626579 -294.962258) (xy 338.659214 -294.925421) (xy 338.697335 -294.894296)
			(xy 338.739956 -294.869689) (xy 338.785972 -294.852237) (xy 338.834191 -294.842393) (xy 338.883366 -294.840412)
			(xy 338.932221 -294.846344) (xy 338.979492 -294.860036) (xy 339.023954 -294.881134) (xy 339.064457 -294.90909)
			(xy 339.09995 -294.943182) (xy 339.129515 -294.982526) (xy 339.152386 -295.026103) (xy 339.16797 -295.072784)
			(xy 339.175865 -295.121361) (xy 339.17636 -295.145968) (xy 339.505302 -295.145968) (xy 339.509262 -295.096914)
			(xy 339.521039 -295.04913) (xy 339.54033 -295.003854) (xy 339.566633 -294.962258) (xy 339.599268 -294.925421)
			(xy 339.637389 -294.894296) (xy 339.68001 -294.869689) (xy 339.726026 -294.852237) (xy 339.774245 -294.842393)
			(xy 339.82342 -294.840412) (xy 339.872275 -294.846344) (xy 339.919546 -294.860036) (xy 339.964008 -294.881134)
			(xy 340.004511 -294.90909) (xy 340.040004 -294.943182) (xy 340.069569 -294.982526) (xy 340.09244 -295.026103)
			(xy 340.108024 -295.072784) (xy 340.115919 -295.121361) (xy 340.116414 -295.145968) (xy 340.445356 -295.145968)
			(xy 340.449316 -295.096914) (xy 340.461093 -295.04913) (xy 340.480384 -295.003854) (xy 340.506687 -294.962258)
			(xy 340.539322 -294.925421) (xy 340.577443 -294.894296) (xy 340.620064 -294.869689) (xy 340.66608 -294.852237)
			(xy 340.714299 -294.842393) (xy 340.763474 -294.840412) (xy 340.812329 -294.846344) (xy 340.8596 -294.860036)
			(xy 340.904062 -294.881134) (xy 340.944565 -294.90909) (xy 340.980058 -294.943182) (xy 341.009623 -294.982526)
			(xy 341.032494 -295.026103) (xy 341.048078 -295.072784) (xy 341.055973 -295.121361) (xy 341.056468 -295.145968)
			(xy 341.38541 -295.145968) (xy 341.38937 -295.096914) (xy 341.401147 -295.04913) (xy 341.420438 -295.003854)
			(xy 341.446741 -294.962258) (xy 341.479376 -294.925421) (xy 341.517497 -294.894296) (xy 341.560118 -294.869689)
			(xy 341.606134 -294.852237) (xy 341.654353 -294.842393) (xy 341.703528 -294.840412) (xy 341.752383 -294.846344)
			(xy 341.799654 -294.860036) (xy 341.844116 -294.881134) (xy 341.884619 -294.90909) (xy 341.920112 -294.943182)
			(xy 341.949677 -294.982526) (xy 341.972548 -295.026103) (xy 341.988132 -295.072784) (xy 341.996027 -295.121361)
			(xy 341.996522 -295.145968) (xy 342.32521 -295.145968) (xy 342.32917 -295.096914) (xy 342.340947 -295.04913)
			(xy 342.360238 -295.003854) (xy 342.386541 -294.962258) (xy 342.419176 -294.925421) (xy 342.457297 -294.894296)
			(xy 342.499918 -294.869689) (xy 342.545934 -294.852237) (xy 342.594153 -294.842393) (xy 342.643328 -294.840412)
			(xy 342.692183 -294.846344) (xy 342.739454 -294.860036) (xy 342.783916 -294.881134) (xy 342.824419 -294.90909)
			(xy 342.859912 -294.943182) (xy 342.889477 -294.982526) (xy 342.912348 -295.026103) (xy 342.927932 -295.072784)
			(xy 342.935827 -295.121361) (xy 342.936322 -295.145968) (xy 343.265264 -295.145968) (xy 343.269224 -295.096914)
			(xy 343.281001 -295.04913) (xy 343.300292 -295.003854) (xy 343.326595 -294.962258) (xy 343.35923 -294.925421)
			(xy 343.397351 -294.894296) (xy 343.439972 -294.869689) (xy 343.485988 -294.852237) (xy 343.534207 -294.842393)
			(xy 343.583382 -294.840412) (xy 343.632237 -294.846344) (xy 343.679508 -294.860036) (xy 343.72397 -294.881134)
			(xy 343.764473 -294.90909) (xy 343.799966 -294.943182) (xy 343.829531 -294.982526) (xy 343.852402 -295.026103)
			(xy 343.867986 -295.072784) (xy 343.875881 -295.121361) (xy 343.876376 -295.145968) (xy 344.205318 -295.145968)
			(xy 344.209278 -295.096914) (xy 344.221055 -295.04913) (xy 344.240346 -295.003854) (xy 344.266649 -294.962258)
			(xy 344.299284 -294.925421) (xy 344.337405 -294.894296) (xy 344.380026 -294.869689) (xy 344.426042 -294.852237)
			(xy 344.474261 -294.842393) (xy 344.523436 -294.840412) (xy 344.572291 -294.846344) (xy 344.619562 -294.860036)
			(xy 344.664024 -294.881134) (xy 344.704527 -294.90909) (xy 344.74002 -294.943182) (xy 344.769585 -294.982526)
			(xy 344.792456 -295.026103) (xy 344.80804 -295.072784) (xy 344.815935 -295.121361) (xy 344.81643 -295.145968)
			(xy 345.145372 -295.145968) (xy 345.149332 -295.096914) (xy 345.161109 -295.04913) (xy 345.1804 -295.003854)
			(xy 345.206703 -294.962258) (xy 345.239338 -294.925421) (xy 345.277459 -294.894296) (xy 345.32008 -294.869689)
			(xy 345.366096 -294.852237) (xy 345.414315 -294.842393) (xy 345.46349 -294.840412) (xy 345.512345 -294.846344)
			(xy 345.559616 -294.860036) (xy 345.604078 -294.881134) (xy 345.644581 -294.90909) (xy 345.680074 -294.943182)
			(xy 345.709639 -294.982526) (xy 345.73251 -295.026103) (xy 345.748094 -295.072784) (xy 345.755989 -295.121361)
			(xy 345.756484 -295.145968) (xy 346.085426 -295.145968) (xy 346.089386 -295.096914) (xy 346.101163 -295.04913)
			(xy 346.120454 -295.003854) (xy 346.146757 -294.962258) (xy 346.179392 -294.925421) (xy 346.217513 -294.894296)
			(xy 346.260134 -294.869689) (xy 346.30615 -294.852237) (xy 346.354369 -294.842393) (xy 346.403544 -294.840412)
			(xy 346.452399 -294.846344) (xy 346.49967 -294.860036) (xy 346.544132 -294.881134) (xy 346.584635 -294.90909)
			(xy 346.620128 -294.943182) (xy 346.649693 -294.982526) (xy 346.672564 -295.026103) (xy 346.688148 -295.072784)
			(xy 346.696043 -295.121361) (xy 346.696538 -295.145968) (xy 347.025226 -295.145968) (xy 347.029186 -295.096914)
			(xy 347.040963 -295.04913) (xy 347.060254 -295.003854) (xy 347.086557 -294.962258) (xy 347.119192 -294.925421)
			(xy 347.157313 -294.894296) (xy 347.199934 -294.869689) (xy 347.24595 -294.852237) (xy 347.294169 -294.842393)
			(xy 347.343344 -294.840412) (xy 347.392199 -294.846344) (xy 347.43947 -294.860036) (xy 347.483932 -294.881134)
			(xy 347.524435 -294.90909) (xy 347.559928 -294.943182) (xy 347.589493 -294.982526) (xy 347.612364 -295.026103)
			(xy 347.627948 -295.072784) (xy 347.635843 -295.121361) (xy 347.636338 -295.145968) (xy 347.96528 -295.145968)
			(xy 347.96924 -295.096914) (xy 347.981017 -295.04913) (xy 348.000308 -295.003854) (xy 348.026611 -294.962258)
			(xy 348.059246 -294.925421) (xy 348.097367 -294.894296) (xy 348.139988 -294.869689) (xy 348.186004 -294.852237)
			(xy 348.234223 -294.842393) (xy 348.283398 -294.840412) (xy 348.332253 -294.846344) (xy 348.379524 -294.860036)
			(xy 348.423986 -294.881134) (xy 348.464489 -294.90909) (xy 348.499982 -294.943182) (xy 348.529547 -294.982526)
			(xy 348.552418 -295.026103) (xy 348.568002 -295.072784) (xy 348.575897 -295.121361) (xy 348.576392 -295.145968)
			(xy 348.905334 -295.145968) (xy 348.909294 -295.096914) (xy 348.921071 -295.04913) (xy 348.940362 -295.003854)
			(xy 348.966665 -294.962258) (xy 348.9993 -294.925421) (xy 349.037421 -294.894296) (xy 349.080042 -294.869689)
			(xy 349.126058 -294.852237) (xy 349.174277 -294.842393) (xy 349.223452 -294.840412) (xy 349.272307 -294.846344)
			(xy 349.319578 -294.860036) (xy 349.36404 -294.881134) (xy 349.404543 -294.90909) (xy 349.440036 -294.943182)
			(xy 349.469601 -294.982526) (xy 349.492472 -295.026103) (xy 349.508056 -295.072784) (xy 349.515951 -295.121361)
			(xy 349.516446 -295.145968) (xy 349.845388 -295.145968) (xy 349.849348 -295.096914) (xy 349.861125 -295.04913)
			(xy 349.880416 -295.003854) (xy 349.906719 -294.962258) (xy 349.939354 -294.925421) (xy 349.977475 -294.894296)
			(xy 350.020096 -294.869689) (xy 350.066112 -294.852237) (xy 350.114331 -294.842393) (xy 350.163506 -294.840412)
			(xy 350.212361 -294.846344) (xy 350.259632 -294.860036) (xy 350.304094 -294.881134) (xy 350.344597 -294.90909)
			(xy 350.38009 -294.943182) (xy 350.409655 -294.982526) (xy 350.432526 -295.026103) (xy 350.44811 -295.072784)
			(xy 350.456005 -295.121361) (xy 350.4565 -295.145968) (xy 350.785442 -295.145968) (xy 350.789402 -295.096914)
			(xy 350.801179 -295.04913) (xy 350.82047 -295.003854) (xy 350.846773 -294.962258) (xy 350.879408 -294.925421)
			(xy 350.917529 -294.894296) (xy 350.96015 -294.869689) (xy 351.006166 -294.852237) (xy 351.054385 -294.842393)
			(xy 351.10356 -294.840412) (xy 351.152415 -294.846344) (xy 351.199686 -294.860036) (xy 351.244148 -294.881134)
			(xy 351.284651 -294.90909) (xy 351.320144 -294.943182) (xy 351.349709 -294.982526) (xy 351.37258 -295.026103)
			(xy 351.388164 -295.072784) (xy 351.396059 -295.121361) (xy 351.396554 -295.145968) (xy 351.396059 -295.170575)
			(xy 351.388164 -295.219152) (xy 351.37258 -295.265833) (xy 351.349709 -295.30941) (xy 351.320144 -295.348754)
			(xy 351.284651 -295.382846) (xy 351.244148 -295.410802) (xy 351.199686 -295.4319) (xy 351.152415 -295.445592)
			(xy 351.10356 -295.451524) (xy 351.054385 -295.449543) (xy 351.006166 -295.439699) (xy 350.96015 -295.422247)
			(xy 350.917529 -295.39764) (xy 350.879408 -295.366515) (xy 350.846773 -295.329678) (xy 350.82047 -295.288082)
			(xy 350.801179 -295.242806) (xy 350.789402 -295.195022) (xy 350.785442 -295.145968) (xy 350.4565 -295.145968)
			(xy 350.456005 -295.170575) (xy 350.44811 -295.219152) (xy 350.432526 -295.265833) (xy 350.409655 -295.30941)
			(xy 350.38009 -295.348754) (xy 350.344597 -295.382846) (xy 350.304094 -295.410802) (xy 350.259632 -295.4319)
			(xy 350.212361 -295.445592) (xy 350.163506 -295.451524) (xy 350.114331 -295.449543) (xy 350.066112 -295.439699)
			(xy 350.020096 -295.422247) (xy 349.977475 -295.39764) (xy 349.939354 -295.366515) (xy 349.906719 -295.329678)
			(xy 349.880416 -295.288082) (xy 349.861125 -295.242806) (xy 349.849348 -295.195022) (xy 349.845388 -295.145968)
			(xy 349.516446 -295.145968) (xy 349.515951 -295.170575) (xy 349.508056 -295.219152) (xy 349.492472 -295.265833)
			(xy 349.469601 -295.30941) (xy 349.440036 -295.348754) (xy 349.404543 -295.382846) (xy 349.36404 -295.410802)
			(xy 349.319578 -295.4319) (xy 349.272307 -295.445592) (xy 349.223452 -295.451524) (xy 349.174277 -295.449543)
			(xy 349.126058 -295.439699) (xy 349.080042 -295.422247) (xy 349.037421 -295.39764) (xy 348.9993 -295.366515)
			(xy 348.966665 -295.329678) (xy 348.940362 -295.288082) (xy 348.921071 -295.242806) (xy 348.909294 -295.195022)
			(xy 348.905334 -295.145968) (xy 348.576392 -295.145968) (xy 348.575897 -295.170575) (xy 348.568002 -295.219152)
			(xy 348.552418 -295.265833) (xy 348.529547 -295.30941) (xy 348.499982 -295.348754) (xy 348.464489 -295.382846)
			(xy 348.423986 -295.410802) (xy 348.379524 -295.4319) (xy 348.332253 -295.445592) (xy 348.283398 -295.451524)
			(xy 348.234223 -295.449543) (xy 348.186004 -295.439699) (xy 348.139988 -295.422247) (xy 348.097367 -295.39764)
			(xy 348.059246 -295.366515) (xy 348.026611 -295.329678) (xy 348.000308 -295.288082) (xy 347.981017 -295.242806)
			(xy 347.96924 -295.195022) (xy 347.96528 -295.145968) (xy 347.636338 -295.145968) (xy 347.635843 -295.170575)
			(xy 347.627948 -295.219152) (xy 347.612364 -295.265833) (xy 347.589493 -295.30941) (xy 347.559928 -295.348754)
			(xy 347.524435 -295.382846) (xy 347.483932 -295.410802) (xy 347.43947 -295.4319) (xy 347.392199 -295.445592)
			(xy 347.343344 -295.451524) (xy 347.294169 -295.449543) (xy 347.24595 -295.439699) (xy 347.199934 -295.422247)
			(xy 347.157313 -295.39764) (xy 347.119192 -295.366515) (xy 347.086557 -295.329678) (xy 347.060254 -295.288082)
			(xy 347.040963 -295.242806) (xy 347.029186 -295.195022) (xy 347.025226 -295.145968) (xy 346.696538 -295.145968)
			(xy 346.696043 -295.170575) (xy 346.688148 -295.219152) (xy 346.672564 -295.265833) (xy 346.649693 -295.30941)
			(xy 346.620128 -295.348754) (xy 346.584635 -295.382846) (xy 346.544132 -295.410802) (xy 346.49967 -295.4319)
			(xy 346.452399 -295.445592) (xy 346.403544 -295.451524) (xy 346.354369 -295.449543) (xy 346.30615 -295.439699)
			(xy 346.260134 -295.422247) (xy 346.217513 -295.39764) (xy 346.179392 -295.366515) (xy 346.146757 -295.329678)
			(xy 346.120454 -295.288082) (xy 346.101163 -295.242806) (xy 346.089386 -295.195022) (xy 346.085426 -295.145968)
			(xy 345.756484 -295.145968) (xy 345.755989 -295.170575) (xy 345.748094 -295.219152) (xy 345.73251 -295.265833)
			(xy 345.709639 -295.30941) (xy 345.680074 -295.348754) (xy 345.644581 -295.382846) (xy 345.604078 -295.410802)
			(xy 345.559616 -295.4319) (xy 345.512345 -295.445592) (xy 345.46349 -295.451524) (xy 345.414315 -295.449543)
			(xy 345.366096 -295.439699) (xy 345.32008 -295.422247) (xy 345.277459 -295.39764) (xy 345.239338 -295.366515)
			(xy 345.206703 -295.329678) (xy 345.1804 -295.288082) (xy 345.161109 -295.242806) (xy 345.149332 -295.195022)
			(xy 345.145372 -295.145968) (xy 344.81643 -295.145968) (xy 344.815935 -295.170575) (xy 344.80804 -295.219152)
			(xy 344.792456 -295.265833) (xy 344.769585 -295.30941) (xy 344.74002 -295.348754) (xy 344.704527 -295.382846)
			(xy 344.664024 -295.410802) (xy 344.619562 -295.4319) (xy 344.572291 -295.445592) (xy 344.523436 -295.451524)
			(xy 344.474261 -295.449543) (xy 344.426042 -295.439699) (xy 344.380026 -295.422247) (xy 344.337405 -295.39764)
			(xy 344.299284 -295.366515) (xy 344.266649 -295.329678) (xy 344.240346 -295.288082) (xy 344.221055 -295.242806)
			(xy 344.209278 -295.195022) (xy 344.205318 -295.145968) (xy 343.876376 -295.145968) (xy 343.875881 -295.170575)
			(xy 343.867986 -295.219152) (xy 343.852402 -295.265833) (xy 343.829531 -295.30941) (xy 343.799966 -295.348754)
			(xy 343.764473 -295.382846) (xy 343.72397 -295.410802) (xy 343.679508 -295.4319) (xy 343.632237 -295.445592)
			(xy 343.583382 -295.451524) (xy 343.534207 -295.449543) (xy 343.485988 -295.439699) (xy 343.439972 -295.422247)
			(xy 343.397351 -295.39764) (xy 343.35923 -295.366515) (xy 343.326595 -295.329678) (xy 343.300292 -295.288082)
			(xy 343.281001 -295.242806) (xy 343.269224 -295.195022) (xy 343.265264 -295.145968) (xy 342.936322 -295.145968)
			(xy 342.935827 -295.170575) (xy 342.927932 -295.219152) (xy 342.912348 -295.265833) (xy 342.889477 -295.30941)
			(xy 342.859912 -295.348754) (xy 342.824419 -295.382846) (xy 342.783916 -295.410802) (xy 342.739454 -295.4319)
			(xy 342.692183 -295.445592) (xy 342.643328 -295.451524) (xy 342.594153 -295.449543) (xy 342.545934 -295.439699)
			(xy 342.499918 -295.422247) (xy 342.457297 -295.39764) (xy 342.419176 -295.366515) (xy 342.386541 -295.329678)
			(xy 342.360238 -295.288082) (xy 342.340947 -295.242806) (xy 342.32917 -295.195022) (xy 342.32521 -295.145968)
			(xy 341.996522 -295.145968) (xy 341.996027 -295.170575) (xy 341.988132 -295.219152) (xy 341.972548 -295.265833)
			(xy 341.949677 -295.30941) (xy 341.920112 -295.348754) (xy 341.884619 -295.382846) (xy 341.844116 -295.410802)
			(xy 341.799654 -295.4319) (xy 341.752383 -295.445592) (xy 341.703528 -295.451524) (xy 341.654353 -295.449543)
			(xy 341.606134 -295.439699) (xy 341.560118 -295.422247) (xy 341.517497 -295.39764) (xy 341.479376 -295.366515)
			(xy 341.446741 -295.329678) (xy 341.420438 -295.288082) (xy 341.401147 -295.242806) (xy 341.38937 -295.195022)
			(xy 341.38541 -295.145968) (xy 341.056468 -295.145968) (xy 341.055973 -295.170575) (xy 341.048078 -295.219152)
			(xy 341.032494 -295.265833) (xy 341.009623 -295.30941) (xy 340.980058 -295.348754) (xy 340.944565 -295.382846)
			(xy 340.904062 -295.410802) (xy 340.8596 -295.4319) (xy 340.812329 -295.445592) (xy 340.763474 -295.451524)
			(xy 340.714299 -295.449543) (xy 340.66608 -295.439699) (xy 340.620064 -295.422247) (xy 340.577443 -295.39764)
			(xy 340.539322 -295.366515) (xy 340.506687 -295.329678) (xy 340.480384 -295.288082) (xy 340.461093 -295.242806)
			(xy 340.449316 -295.195022) (xy 340.445356 -295.145968) (xy 340.116414 -295.145968) (xy 340.115919 -295.170575)
			(xy 340.108024 -295.219152) (xy 340.09244 -295.265833) (xy 340.069569 -295.30941) (xy 340.040004 -295.348754)
			(xy 340.004511 -295.382846) (xy 339.964008 -295.410802) (xy 339.919546 -295.4319) (xy 339.872275 -295.445592)
			(xy 339.82342 -295.451524) (xy 339.774245 -295.449543) (xy 339.726026 -295.439699) (xy 339.68001 -295.422247)
			(xy 339.637389 -295.39764) (xy 339.599268 -295.366515) (xy 339.566633 -295.329678) (xy 339.54033 -295.288082)
			(xy 339.521039 -295.242806) (xy 339.509262 -295.195022) (xy 339.505302 -295.145968) (xy 339.17636 -295.145968)
			(xy 339.175865 -295.170575) (xy 339.16797 -295.219152) (xy 339.152386 -295.265833) (xy 339.129515 -295.30941)
			(xy 339.09995 -295.348754) (xy 339.064457 -295.382846) (xy 339.023954 -295.410802) (xy 338.979492 -295.4319)
			(xy 338.932221 -295.445592) (xy 338.883366 -295.451524) (xy 338.834191 -295.449543) (xy 338.785972 -295.439699)
			(xy 338.739956 -295.422247) (xy 338.697335 -295.39764) (xy 338.659214 -295.366515) (xy 338.626579 -295.329678)
			(xy 338.600276 -295.288082) (xy 338.580985 -295.242806) (xy 338.569208 -295.195022) (xy 338.565248 -295.145968)
			(xy 338.236306 -295.145968) (xy 338.235811 -295.170575) (xy 338.227916 -295.219152) (xy 338.212332 -295.265833)
			(xy 338.189461 -295.30941) (xy 338.159896 -295.348754) (xy 338.124403 -295.382846) (xy 338.0839 -295.410802)
			(xy 338.039438 -295.4319) (xy 337.992167 -295.445592) (xy 337.943312 -295.451524) (xy 337.894137 -295.449543)
			(xy 337.845918 -295.439699) (xy 337.799902 -295.422247) (xy 337.757281 -295.39764) (xy 337.71916 -295.366515)
			(xy 337.686525 -295.329678) (xy 337.660222 -295.288082) (xy 337.640931 -295.242806) (xy 337.629154 -295.195022)
			(xy 337.625194 -295.145968) (xy 336.356452 -295.145968) (xy 336.355957 -295.170575) (xy 336.348062 -295.219152)
			(xy 336.332478 -295.265833) (xy 336.309607 -295.30941) (xy 336.280042 -295.348754) (xy 336.244549 -295.382846)
			(xy 336.204046 -295.410802) (xy 336.159584 -295.4319) (xy 336.112313 -295.445592) (xy 336.063458 -295.451524)
			(xy 336.014283 -295.449543) (xy 335.966064 -295.439699) (xy 335.920048 -295.422247) (xy 335.877427 -295.39764)
			(xy 335.839306 -295.366515) (xy 335.806671 -295.329678) (xy 335.780368 -295.288082) (xy 335.761077 -295.242806)
			(xy 335.7493 -295.195022) (xy 335.74534 -295.145968) (xy 335.416398 -295.145968) (xy 335.415903 -295.170575)
			(xy 335.408008 -295.219152) (xy 335.392424 -295.265833) (xy 335.369553 -295.30941) (xy 335.339988 -295.348754)
			(xy 335.304495 -295.382846) (xy 335.263992 -295.410802) (xy 335.21953 -295.4319) (xy 335.172259 -295.445592)
			(xy 335.123404 -295.451524) (xy 335.074229 -295.449543) (xy 335.02601 -295.439699) (xy 334.979994 -295.422247)
			(xy 334.937373 -295.39764) (xy 334.899252 -295.366515) (xy 334.866617 -295.329678) (xy 334.840314 -295.288082)
			(xy 334.821023 -295.242806) (xy 334.809246 -295.195022) (xy 334.805286 -295.145968) (xy 334.476344 -295.145968)
			(xy 334.475849 -295.170575) (xy 334.467954 -295.219152) (xy 334.45237 -295.265833) (xy 334.429499 -295.30941)
			(xy 334.399934 -295.348754) (xy 334.364441 -295.382846) (xy 334.323938 -295.410802) (xy 334.279476 -295.4319)
			(xy 334.232205 -295.445592) (xy 334.18335 -295.451524) (xy 334.134175 -295.449543) (xy 334.085956 -295.439699)
			(xy 334.03994 -295.422247) (xy 333.997319 -295.39764) (xy 333.959198 -295.366515) (xy 333.926563 -295.329678)
			(xy 333.90026 -295.288082) (xy 333.880969 -295.242806) (xy 333.869192 -295.195022) (xy 333.865232 -295.145968)
			(xy 333.53629 -295.145968) (xy 333.535795 -295.170575) (xy 333.5279 -295.219152) (xy 333.512316 -295.265833)
			(xy 333.489445 -295.30941) (xy 333.45988 -295.348754) (xy 333.424387 -295.382846) (xy 333.383884 -295.410802)
			(xy 333.339422 -295.4319) (xy 333.292151 -295.445592) (xy 333.243296 -295.451524) (xy 333.194121 -295.449543)
			(xy 333.145902 -295.439699) (xy 333.099886 -295.422247) (xy 333.057265 -295.39764) (xy 333.019144 -295.366515)
			(xy 332.986509 -295.329678) (xy 332.960206 -295.288082) (xy 332.940915 -295.242806) (xy 332.929138 -295.195022)
			(xy 332.925178 -295.145968) (xy 332.59649 -295.145968) (xy 332.595995 -295.170575) (xy 332.5881 -295.219152)
			(xy 332.572516 -295.265833) (xy 332.549645 -295.30941) (xy 332.52008 -295.348754) (xy 332.484587 -295.382846)
			(xy 332.444084 -295.410802) (xy 332.399622 -295.4319) (xy 332.352351 -295.445592) (xy 332.303496 -295.451524)
			(xy 332.254321 -295.449543) (xy 332.206102 -295.439699) (xy 332.160086 -295.422247) (xy 332.117465 -295.39764)
			(xy 332.079344 -295.366515) (xy 332.046709 -295.329678) (xy 332.020406 -295.288082) (xy 332.001115 -295.242806)
			(xy 331.989338 -295.195022) (xy 331.985378 -295.145968) (xy 331.656436 -295.145968) (xy 331.655941 -295.170575)
			(xy 331.648046 -295.219152) (xy 331.632462 -295.265833) (xy 331.609591 -295.30941) (xy 331.580026 -295.348754)
			(xy 331.544533 -295.382846) (xy 331.50403 -295.410802) (xy 331.459568 -295.4319) (xy 331.412297 -295.445592)
			(xy 331.363442 -295.451524) (xy 331.314267 -295.449543) (xy 331.266048 -295.439699) (xy 331.220032 -295.422247)
			(xy 331.177411 -295.39764) (xy 331.13929 -295.366515) (xy 331.106655 -295.329678) (xy 331.080352 -295.288082)
			(xy 331.061061 -295.242806) (xy 331.049284 -295.195022) (xy 331.045324 -295.145968) (xy 330.716382 -295.145968)
			(xy 330.715887 -295.170575) (xy 330.707992 -295.219152) (xy 330.692408 -295.265833) (xy 330.669537 -295.30941)
			(xy 330.639972 -295.348754) (xy 330.604479 -295.382846) (xy 330.563976 -295.410802) (xy 330.519514 -295.4319)
			(xy 330.472243 -295.445592) (xy 330.423388 -295.451524) (xy 330.374213 -295.449543) (xy 330.325994 -295.439699)
			(xy 330.279978 -295.422247) (xy 330.237357 -295.39764) (xy 330.199236 -295.366515) (xy 330.166601 -295.329678)
			(xy 330.140298 -295.288082) (xy 330.121007 -295.242806) (xy 330.10923 -295.195022) (xy 330.10527 -295.145968)
			(xy 329.776328 -295.145968) (xy 329.775833 -295.170575) (xy 329.767938 -295.219152) (xy 329.752354 -295.265833)
			(xy 329.729483 -295.30941) (xy 329.699918 -295.348754) (xy 329.664425 -295.382846) (xy 329.623922 -295.410802)
			(xy 329.57946 -295.4319) (xy 329.532189 -295.445592) (xy 329.483334 -295.451524) (xy 329.434159 -295.449543)
			(xy 329.38594 -295.439699) (xy 329.339924 -295.422247) (xy 329.297303 -295.39764) (xy 329.259182 -295.366515)
			(xy 329.226547 -295.329678) (xy 329.200244 -295.288082) (xy 329.180953 -295.242806) (xy 329.169176 -295.195022)
			(xy 329.165216 -295.145968) (xy 310.45912 -295.145968) (xy 310.45912 -295.955974) (xy 326.815208 -295.955974)
			(xy 326.819168 -295.90692) (xy 326.830945 -295.859136) (xy 326.850236 -295.81386) (xy 326.876539 -295.772264)
			(xy 326.909174 -295.735427) (xy 326.947295 -295.704302) (xy 326.989916 -295.679695) (xy 327.035932 -295.662243)
			(xy 327.084151 -295.652399) (xy 327.133326 -295.650418) (xy 327.182181 -295.65635) (xy 327.229452 -295.670042)
			(xy 327.273914 -295.69114) (xy 327.314417 -295.719096) (xy 327.34991 -295.753188) (xy 327.379475 -295.792532)
			(xy 327.402346 -295.836109) (xy 327.41793 -295.88279) (xy 327.425825 -295.931367) (xy 327.42632 -295.955974)
			(xy 330.575424 -295.955974) (xy 330.579384 -295.90692) (xy 330.591161 -295.859136) (xy 330.610452 -295.81386)
			(xy 330.636755 -295.772264) (xy 330.66939 -295.735427) (xy 330.707511 -295.704302) (xy 330.750132 -295.679695)
			(xy 330.796148 -295.662243) (xy 330.844367 -295.652399) (xy 330.893542 -295.650418) (xy 330.942397 -295.65635)
			(xy 330.989668 -295.670042) (xy 331.03413 -295.69114) (xy 331.074633 -295.719096) (xy 331.110126 -295.753188)
			(xy 331.139691 -295.792532) (xy 331.162562 -295.836109) (xy 331.178146 -295.88279) (xy 331.186041 -295.931367)
			(xy 331.186536 -295.955974) (xy 331.515224 -295.955974) (xy 331.519184 -295.90692) (xy 331.530961 -295.859136)
			(xy 331.550252 -295.81386) (xy 331.576555 -295.772264) (xy 331.60919 -295.735427) (xy 331.647311 -295.704302)
			(xy 331.689932 -295.679695) (xy 331.735948 -295.662243) (xy 331.784167 -295.652399) (xy 331.833342 -295.650418)
			(xy 331.882197 -295.65635) (xy 331.929468 -295.670042) (xy 331.97393 -295.69114) (xy 332.014433 -295.719096)
			(xy 332.049926 -295.753188) (xy 332.079491 -295.792532) (xy 332.102362 -295.836109) (xy 332.117946 -295.88279)
			(xy 332.125841 -295.931367) (xy 332.126336 -295.955974) (xy 332.455278 -295.955974) (xy 332.459238 -295.90692)
			(xy 332.471015 -295.859136) (xy 332.490306 -295.81386) (xy 332.516609 -295.772264) (xy 332.549244 -295.735427)
			(xy 332.587365 -295.704302) (xy 332.629986 -295.679695) (xy 332.676002 -295.662243) (xy 332.724221 -295.652399)
			(xy 332.773396 -295.650418) (xy 332.822251 -295.65635) (xy 332.869522 -295.670042) (xy 332.913984 -295.69114)
			(xy 332.954487 -295.719096) (xy 332.98998 -295.753188) (xy 333.019545 -295.792532) (xy 333.042416 -295.836109)
			(xy 333.058 -295.88279) (xy 333.065895 -295.931367) (xy 333.06639 -295.955974) (xy 333.395332 -295.955974)
			(xy 333.399292 -295.90692) (xy 333.411069 -295.859136) (xy 333.43036 -295.81386) (xy 333.456663 -295.772264)
			(xy 333.489298 -295.735427) (xy 333.527419 -295.704302) (xy 333.57004 -295.679695) (xy 333.616056 -295.662243)
			(xy 333.664275 -295.652399) (xy 333.71345 -295.650418) (xy 333.762305 -295.65635) (xy 333.809576 -295.670042)
			(xy 333.854038 -295.69114) (xy 333.894541 -295.719096) (xy 333.930034 -295.753188) (xy 333.959599 -295.792532)
			(xy 333.98247 -295.836109) (xy 333.998054 -295.88279) (xy 334.005949 -295.931367) (xy 334.006444 -295.955974)
			(xy 334.335386 -295.955974) (xy 334.339346 -295.90692) (xy 334.351123 -295.859136) (xy 334.370414 -295.81386)
			(xy 334.396717 -295.772264) (xy 334.429352 -295.735427) (xy 334.467473 -295.704302) (xy 334.510094 -295.679695)
			(xy 334.55611 -295.662243) (xy 334.604329 -295.652399) (xy 334.653504 -295.650418) (xy 334.702359 -295.65635)
			(xy 334.74963 -295.670042) (xy 334.794092 -295.69114) (xy 334.834595 -295.719096) (xy 334.870088 -295.753188)
			(xy 334.899653 -295.792532) (xy 334.922524 -295.836109) (xy 334.938108 -295.88279) (xy 334.946003 -295.931367)
			(xy 334.946498 -295.955974) (xy 336.21524 -295.955974) (xy 336.2192 -295.90692) (xy 336.230977 -295.859136)
			(xy 336.250268 -295.81386) (xy 336.276571 -295.772264) (xy 336.309206 -295.735427) (xy 336.347327 -295.704302)
			(xy 336.389948 -295.679695) (xy 336.435964 -295.662243) (xy 336.484183 -295.652399) (xy 336.533358 -295.650418)
			(xy 336.582213 -295.65635) (xy 336.629484 -295.670042) (xy 336.673946 -295.69114) (xy 336.714449 -295.719096)
			(xy 336.749942 -295.753188) (xy 336.779507 -295.792532) (xy 336.802378 -295.836109) (xy 336.817962 -295.88279)
			(xy 336.825857 -295.931367) (xy 336.826352 -295.955974) (xy 338.095348 -295.955974) (xy 338.099308 -295.90692)
			(xy 338.111085 -295.859136) (xy 338.130376 -295.81386) (xy 338.156679 -295.772264) (xy 338.189314 -295.735427)
			(xy 338.227435 -295.704302) (xy 338.270056 -295.679695) (xy 338.316072 -295.662243) (xy 338.364291 -295.652399)
			(xy 338.413466 -295.650418) (xy 338.462321 -295.65635) (xy 338.509592 -295.670042) (xy 338.554054 -295.69114)
			(xy 338.594557 -295.719096) (xy 338.63005 -295.753188) (xy 338.659615 -295.792532) (xy 338.682486 -295.836109)
			(xy 338.69807 -295.88279) (xy 338.705965 -295.931367) (xy 338.70646 -295.955974) (xy 339.035402 -295.955974)
			(xy 339.039362 -295.90692) (xy 339.051139 -295.859136) (xy 339.07043 -295.81386) (xy 339.096733 -295.772264)
			(xy 339.129368 -295.735427) (xy 339.167489 -295.704302) (xy 339.21011 -295.679695) (xy 339.256126 -295.662243)
			(xy 339.304345 -295.652399) (xy 339.35352 -295.650418) (xy 339.402375 -295.65635) (xy 339.449646 -295.670042)
			(xy 339.494108 -295.69114) (xy 339.534611 -295.719096) (xy 339.570104 -295.753188) (xy 339.599669 -295.792532)
			(xy 339.62254 -295.836109) (xy 339.638124 -295.88279) (xy 339.646019 -295.931367) (xy 339.646514 -295.955974)
			(xy 339.975202 -295.955974) (xy 339.979162 -295.90692) (xy 339.990939 -295.859136) (xy 340.01023 -295.81386)
			(xy 340.036533 -295.772264) (xy 340.069168 -295.735427) (xy 340.107289 -295.704302) (xy 340.14991 -295.679695)
			(xy 340.195926 -295.662243) (xy 340.244145 -295.652399) (xy 340.29332 -295.650418) (xy 340.342175 -295.65635)
			(xy 340.389446 -295.670042) (xy 340.433908 -295.69114) (xy 340.474411 -295.719096) (xy 340.509904 -295.753188)
			(xy 340.539469 -295.792532) (xy 340.56234 -295.836109) (xy 340.577924 -295.88279) (xy 340.585819 -295.931367)
			(xy 340.586314 -295.955974) (xy 349.375234 -295.955974) (xy 349.379194 -295.90692) (xy 349.390971 -295.859136)
			(xy 349.410262 -295.81386) (xy 349.436565 -295.772264) (xy 349.4692 -295.735427) (xy 349.507321 -295.704302)
			(xy 349.549942 -295.679695) (xy 349.595958 -295.662243) (xy 349.644177 -295.652399) (xy 349.693352 -295.650418)
			(xy 349.742207 -295.65635) (xy 349.789478 -295.670042) (xy 349.83394 -295.69114) (xy 349.874443 -295.719096)
			(xy 349.909936 -295.753188) (xy 349.939501 -295.792532) (xy 349.962372 -295.836109) (xy 349.977956 -295.88279)
			(xy 349.985851 -295.931367) (xy 349.986346 -295.955974) (xy 349.985851 -295.980581) (xy 349.977956 -296.029158)
			(xy 349.962372 -296.075839) (xy 349.939501 -296.119416) (xy 349.909936 -296.15876) (xy 349.874443 -296.192852)
			(xy 349.83394 -296.220808) (xy 349.789478 -296.241906) (xy 349.742207 -296.255598) (xy 349.693352 -296.26153)
			(xy 349.644177 -296.259549) (xy 349.595958 -296.249705) (xy 349.549942 -296.232253) (xy 349.507321 -296.207646)
			(xy 349.4692 -296.176521) (xy 349.436565 -296.139684) (xy 349.410262 -296.098088) (xy 349.390971 -296.052812)
			(xy 349.379194 -296.005028) (xy 349.375234 -295.955974) (xy 340.586314 -295.955974) (xy 340.585819 -295.980581)
			(xy 340.577924 -296.029158) (xy 340.56234 -296.075839) (xy 340.539469 -296.119416) (xy 340.509904 -296.15876)
			(xy 340.474411 -296.192852) (xy 340.433908 -296.220808) (xy 340.389446 -296.241906) (xy 340.342175 -296.255598)
			(xy 340.29332 -296.26153) (xy 340.244145 -296.259549) (xy 340.195926 -296.249705) (xy 340.14991 -296.232253)
			(xy 340.107289 -296.207646) (xy 340.069168 -296.176521) (xy 340.036533 -296.139684) (xy 340.01023 -296.098088)
			(xy 339.990939 -296.052812) (xy 339.979162 -296.005028) (xy 339.975202 -295.955974) (xy 339.646514 -295.955974)
			(xy 339.646019 -295.980581) (xy 339.638124 -296.029158) (xy 339.62254 -296.075839) (xy 339.599669 -296.119416)
			(xy 339.570104 -296.15876) (xy 339.534611 -296.192852) (xy 339.494108 -296.220808) (xy 339.449646 -296.241906)
			(xy 339.402375 -296.255598) (xy 339.35352 -296.26153) (xy 339.304345 -296.259549) (xy 339.256126 -296.249705)
			(xy 339.21011 -296.232253) (xy 339.167489 -296.207646) (xy 339.129368 -296.176521) (xy 339.096733 -296.139684)
			(xy 339.07043 -296.098088) (xy 339.051139 -296.052812) (xy 339.039362 -296.005028) (xy 339.035402 -295.955974)
			(xy 338.70646 -295.955974) (xy 338.705965 -295.980581) (xy 338.69807 -296.029158) (xy 338.682486 -296.075839)
			(xy 338.659615 -296.119416) (xy 338.63005 -296.15876) (xy 338.594557 -296.192852) (xy 338.554054 -296.220808)
			(xy 338.509592 -296.241906) (xy 338.462321 -296.255598) (xy 338.413466 -296.26153) (xy 338.364291 -296.259549)
			(xy 338.316072 -296.249705) (xy 338.270056 -296.232253) (xy 338.227435 -296.207646) (xy 338.189314 -296.176521)
			(xy 338.156679 -296.139684) (xy 338.130376 -296.098088) (xy 338.111085 -296.052812) (xy 338.099308 -296.005028)
			(xy 338.095348 -295.955974) (xy 336.826352 -295.955974) (xy 336.825857 -295.980581) (xy 336.817962 -296.029158)
			(xy 336.802378 -296.075839) (xy 336.779507 -296.119416) (xy 336.749942 -296.15876) (xy 336.714449 -296.192852)
			(xy 336.673946 -296.220808) (xy 336.629484 -296.241906) (xy 336.582213 -296.255598) (xy 336.533358 -296.26153)
			(xy 336.484183 -296.259549) (xy 336.435964 -296.249705) (xy 336.389948 -296.232253) (xy 336.347327 -296.207646)
			(xy 336.309206 -296.176521) (xy 336.276571 -296.139684) (xy 336.250268 -296.098088) (xy 336.230977 -296.052812)
			(xy 336.2192 -296.005028) (xy 336.21524 -295.955974) (xy 334.946498 -295.955974) (xy 334.946003 -295.980581)
			(xy 334.938108 -296.029158) (xy 334.922524 -296.075839) (xy 334.899653 -296.119416) (xy 334.870088 -296.15876)
			(xy 334.834595 -296.192852) (xy 334.794092 -296.220808) (xy 334.74963 -296.241906) (xy 334.702359 -296.255598)
			(xy 334.653504 -296.26153) (xy 334.604329 -296.259549) (xy 334.55611 -296.249705) (xy 334.510094 -296.232253)
			(xy 334.467473 -296.207646) (xy 334.429352 -296.176521) (xy 334.396717 -296.139684) (xy 334.370414 -296.098088)
			(xy 334.351123 -296.052812) (xy 334.339346 -296.005028) (xy 334.335386 -295.955974) (xy 334.006444 -295.955974)
			(xy 334.005949 -295.980581) (xy 333.998054 -296.029158) (xy 333.98247 -296.075839) (xy 333.959599 -296.119416)
			(xy 333.930034 -296.15876) (xy 333.894541 -296.192852) (xy 333.854038 -296.220808) (xy 333.809576 -296.241906)
			(xy 333.762305 -296.255598) (xy 333.71345 -296.26153) (xy 333.664275 -296.259549) (xy 333.616056 -296.249705)
			(xy 333.57004 -296.232253) (xy 333.527419 -296.207646) (xy 333.489298 -296.176521) (xy 333.456663 -296.139684)
			(xy 333.43036 -296.098088) (xy 333.411069 -296.052812) (xy 333.399292 -296.005028) (xy 333.395332 -295.955974)
			(xy 333.06639 -295.955974) (xy 333.065895 -295.980581) (xy 333.058 -296.029158) (xy 333.042416 -296.075839)
			(xy 333.019545 -296.119416) (xy 332.98998 -296.15876) (xy 332.954487 -296.192852) (xy 332.913984 -296.220808)
			(xy 332.869522 -296.241906) (xy 332.822251 -296.255598) (xy 332.773396 -296.26153) (xy 332.724221 -296.259549)
			(xy 332.676002 -296.249705) (xy 332.629986 -296.232253) (xy 332.587365 -296.207646) (xy 332.549244 -296.176521)
			(xy 332.516609 -296.139684) (xy 332.490306 -296.098088) (xy 332.471015 -296.052812) (xy 332.459238 -296.005028)
			(xy 332.455278 -295.955974) (xy 332.126336 -295.955974) (xy 332.125841 -295.980581) (xy 332.117946 -296.029158)
			(xy 332.102362 -296.075839) (xy 332.079491 -296.119416) (xy 332.049926 -296.15876) (xy 332.014433 -296.192852)
			(xy 331.97393 -296.220808) (xy 331.929468 -296.241906) (xy 331.882197 -296.255598) (xy 331.833342 -296.26153)
			(xy 331.784167 -296.259549) (xy 331.735948 -296.249705) (xy 331.689932 -296.232253) (xy 331.647311 -296.207646)
			(xy 331.60919 -296.176521) (xy 331.576555 -296.139684) (xy 331.550252 -296.098088) (xy 331.530961 -296.052812)
			(xy 331.519184 -296.005028) (xy 331.515224 -295.955974) (xy 331.186536 -295.955974) (xy 331.186041 -295.980581)
			(xy 331.178146 -296.029158) (xy 331.162562 -296.075839) (xy 331.139691 -296.119416) (xy 331.110126 -296.15876)
			(xy 331.074633 -296.192852) (xy 331.03413 -296.220808) (xy 330.989668 -296.241906) (xy 330.942397 -296.255598)
			(xy 330.893542 -296.26153) (xy 330.844367 -296.259549) (xy 330.796148 -296.249705) (xy 330.750132 -296.232253)
			(xy 330.707511 -296.207646) (xy 330.66939 -296.176521) (xy 330.636755 -296.139684) (xy 330.610452 -296.098088)
			(xy 330.591161 -296.052812) (xy 330.579384 -296.005028) (xy 330.575424 -295.955974) (xy 327.42632 -295.955974)
			(xy 327.425825 -295.980581) (xy 327.41793 -296.029158) (xy 327.402346 -296.075839) (xy 327.379475 -296.119416)
			(xy 327.34991 -296.15876) (xy 327.314417 -296.192852) (xy 327.273914 -296.220808) (xy 327.229452 -296.241906)
			(xy 327.182181 -296.255598) (xy 327.133326 -296.26153) (xy 327.084151 -296.259549) (xy 327.035932 -296.249705)
			(xy 326.989916 -296.232253) (xy 326.947295 -296.207646) (xy 326.909174 -296.176521) (xy 326.876539 -296.139684)
			(xy 326.850236 -296.098088) (xy 326.830945 -296.052812) (xy 326.819168 -296.005028) (xy 326.815208 -295.955974)
			(xy 310.45912 -295.955974) (xy 310.45912 -297.761406) (xy 310.459545 -297.771475) (xy 310.467263 -297.790076)
			(xy 310.474106 -297.797474) (xy 311.915578 -299.238946) (xy 339.464724 -299.238946) (xy 339.464724 -299.184454)
			(xy 339.472478 -299.130518) (xy 339.487829 -299.078233) (xy 339.510464 -299.028665) (xy 339.539922 -298.982823)
			(xy 339.575604 -298.941639) (xy 339.616783 -298.905952) (xy 339.662621 -298.876488) (xy 339.712186 -298.853847)
			(xy 339.764469 -298.838489) (xy 339.818404 -298.830728) (xy 339.84565 -298.830238) (xy 339.87107 -298.83063)
			(xy 339.921462 -298.837361) (xy 339.970511 -298.850735) (xy 340.017345 -298.870516) (xy 340.039452 -298.88307)
			(xy 340.048088 -298.88815) (xy 340.067138 -298.891198) (xy 340.154768 -298.870878) (xy 340.170516 -298.859702)
			(xy 340.176104 -298.851574) (xy 340.193776 -298.825571) (xy 340.234518 -298.777686) (xy 340.280856 -298.735193)
			(xy 340.332082 -298.698741) (xy 340.387414 -298.668888) (xy 340.446007 -298.64609) (xy 340.506965 -298.630694)
			(xy 340.569356 -298.622936) (xy 340.600792 -298.622466) (xy 340.631522 -298.622964) (xy 340.692533 -298.630371)
			(xy 340.752208 -298.645078) (xy 340.809674 -298.66687) (xy 340.864094 -298.69543) (xy 340.914676 -298.730342)
			(xy 340.96068 -298.771096) (xy 341.001437 -298.817098) (xy 341.036352 -298.867676) (xy 341.064916 -298.922095)
			(xy 341.086712 -298.97956) (xy 341.101423 -299.039233) (xy 341.108834 -299.100244) (xy 341.1093 -299.130974)
			(xy 341.108704 -299.165929) (xy 341.099146 -299.235181) (xy 341.080192 -299.302472) (xy 341.0522 -299.366533)
			(xy 341.015698 -299.426156) (xy 340.993984 -299.453554) (xy 340.988706 -299.460566) (xy 340.98272 -299.477047)
			(xy 340.9823 -299.485812) (xy 340.9823 -299.792136) (xy 340.982643 -299.800915) (xy 340.988641 -299.817418)
			(xy 340.993984 -299.824394) (xy 341.015692 -299.851797) (xy 341.052191 -299.911422) (xy 341.080185 -299.975481)
			(xy 341.099147 -300.042769) (xy 341.108719 -300.11202) (xy 341.1093 -300.146974) (xy 341.108838 -300.177706)
			(xy 341.101432 -300.238722) (xy 341.086725 -300.2984) (xy 341.064932 -300.35587) (xy 341.03637 -300.410295)
			(xy 341.001456 -300.460879) (xy 340.960699 -300.506886) (xy 340.914693 -300.547645) (xy 340.86411 -300.582561)
			(xy 340.809687 -300.611125) (xy 340.752217 -300.63292) (xy 340.692539 -300.647629) (xy 340.631524 -300.655037)
			(xy 340.600792 -300.655482) (xy 340.568296 -300.654941) (xy 340.503832 -300.646666) (xy 340.440951 -300.630239)
			(xy 340.380676 -300.605928) (xy 340.323994 -300.57413) (xy 340.271829 -300.535364) (xy 340.225032 -300.490263)
			(xy 340.204298 -300.465236) (xy 340.197967 -300.457981) (xy 340.181254 -300.44845) (xy 340.171786 -300.446694)
			(xy 340.140798 -300.442376) (xy 340.13137 -300.441495) (xy 340.112973 -300.445928) (xy 340.104984 -300.451012)
			(xy 340.080943 -300.466974) (xy 340.029068 -300.492251) (xy 339.973974 -300.509414) (xy 339.916921 -300.518069)
			(xy 339.888068 -300.518576) (xy 339.860816 -300.518152) (xy 339.806867 -300.510391) (xy 339.754572 -300.495032)
			(xy 339.704995 -300.472387) (xy 339.659144 -300.442917) (xy 339.617954 -300.407223) (xy 339.582263 -300.36603)
			(xy 339.552798 -300.320177) (xy 339.530157 -300.270598) (xy 339.514802 -300.218302) (xy 339.507046 -300.164352)
			(xy 339.507046 -300.109848) (xy 339.514802 -300.055898) (xy 339.530157 -300.003602) (xy 339.552798 -299.954023)
			(xy 339.582263 -299.90817) (xy 339.617954 -299.866977) (xy 339.659144 -299.831283) (xy 339.704995 -299.801813)
			(xy 339.754572 -299.779168) (xy 339.806867 -299.763809) (xy 339.860816 -299.756048) (xy 339.888068 -299.75556)
			(xy 339.918245 -299.756119) (xy 339.977849 -299.765595) (xy 340.035221 -299.784331) (xy 340.088929 -299.811862)
			(xy 340.11362 -299.82922) (xy 340.121498 -299.834459) (xy 340.139736 -299.839419) (xy 340.14918 -299.838872)
			(xy 340.200742 -299.83303) (xy 340.2076 -299.824394) (xy 340.212909 -299.817403) (xy 340.218875 -299.800905)
			(xy 340.219284 -299.792136) (xy 340.219284 -299.611034) (xy 340.218927 -299.601799) (xy 340.212359 -299.584534)
			(xy 340.200101 -299.570717) (xy 340.192106 -299.566076) (xy 340.100158 -299.517562) (xy 340.072218 -299.519086)
			(xy 340.06028 -299.52696) (xy 340.036419 -299.542582) (xy 339.985043 -299.567341) (xy 339.930554 -299.584174)
			(xy 339.874165 -299.592704) (xy 339.84565 -299.593254) (xy 339.818404 -299.592672) (xy 339.764469 -299.584911)
			(xy 339.712186 -299.569553) (xy 339.662621 -299.546912) (xy 339.616783 -299.517448) (xy 339.575604 -299.481761)
			(xy 339.539922 -299.440577) (xy 339.510464 -299.394735) (xy 339.487829 -299.345167) (xy 339.472478 -299.292882)
			(xy 339.464724 -299.238946) (xy 311.915578 -299.238946) (xy 314.249562 -301.57293) (xy 314.25696 -301.579774)
			(xy 314.275559 -301.587497) (xy 314.28563 -301.587916) (xy 339.979254 -301.587916) (xy 339.989319 -301.588349)
			(xy 340.007908 -301.596079) (xy 340.015322 -301.602902) (xy 340.157773 -301.745353) (xy 340.488772 -301.745353)
			(xy 340.488772 -301.681431) (xy 340.496783 -301.618013) (xy 340.51268 -301.556099) (xy 340.536212 -301.496666)
			(xy 340.567006 -301.440651) (xy 340.604579 -301.388936) (xy 340.648336 -301.342339) (xy 340.697589 -301.301594)
			(xy 340.75156 -301.267343) (xy 340.809399 -301.240126) (xy 340.870192 -301.220373) (xy 340.932982 -301.208395)
			(xy 340.996778 -301.204382) (xy 341.060574 -301.208395) (xy 341.123364 -301.220373) (xy 341.184157 -301.240126)
			(xy 341.241996 -301.267343) (xy 341.295967 -301.301594) (xy 341.34522 -301.342339) (xy 341.388977 -301.388936)
			(xy 341.42655 -301.440651) (xy 341.457344 -301.496666) (xy 341.480876 -301.556099) (xy 341.496773 -301.618013)
			(xy 341.504784 -301.681431) (xy 341.505286 -301.713392) (xy 341.504784 -301.745353) (xy 341.496773 -301.808771)
			(xy 341.480876 -301.870685) (xy 341.457344 -301.930118) (xy 341.42655 -301.986133) (xy 341.388977 -302.037848)
			(xy 341.34522 -302.084445) (xy 341.295967 -302.12519) (xy 341.241996 -302.159441) (xy 341.184157 -302.186658)
			(xy 341.123364 -302.206411) (xy 341.060574 -302.218389) (xy 340.996778 -302.222403) (xy 340.932982 -302.218389)
			(xy 340.870192 -302.206411) (xy 340.809399 -302.186658) (xy 340.75156 -302.159441) (xy 340.697589 -302.12519)
			(xy 340.648336 -302.084445) (xy 340.604579 -302.037848) (xy 340.567006 -301.986133) (xy 340.536212 -301.930118)
			(xy 340.51268 -301.870685) (xy 340.496783 -301.808771) (xy 340.488772 -301.745353) (xy 340.157773 -301.745353)
			(xy 343.386875 -304.974455) (xy 343.718382 -304.974455) (xy 343.718382 -304.910533) (xy 343.726393 -304.847115)
			(xy 343.74229 -304.785201) (xy 343.765822 -304.725768) (xy 343.796616 -304.669753) (xy 343.834189 -304.618038)
			(xy 343.877946 -304.571441) (xy 343.927199 -304.530696) (xy 343.98117 -304.496445) (xy 344.039009 -304.469228)
			(xy 344.099802 -304.449475) (xy 344.162592 -304.437497) (xy 344.226388 -304.433484) (xy 344.290184 -304.437497)
			(xy 344.352974 -304.449475) (xy 344.413767 -304.469228) (xy 344.471606 -304.496445) (xy 344.525577 -304.530696)
			(xy 344.57483 -304.571441) (xy 344.618587 -304.618038) (xy 344.65616 -304.669753) (xy 344.686954 -304.725768)
			(xy 344.710486 -304.785201) (xy 344.726383 -304.847115) (xy 344.734394 -304.910533) (xy 344.734896 -304.942494)
			(xy 344.734394 -304.974455) (xy 344.726383 -305.037873) (xy 344.710486 -305.099787) (xy 344.686954 -305.15922)
			(xy 344.65616 -305.215235) (xy 344.618587 -305.26695) (xy 344.57483 -305.313547) (xy 344.525577 -305.354292)
			(xy 344.471606 -305.388543) (xy 344.413767 -305.41576) (xy 344.352974 -305.435513) (xy 344.290184 -305.447491)
			(xy 344.226388 -305.451505) (xy 344.162592 -305.447491) (xy 344.099802 -305.435513) (xy 344.039009 -305.41576)
			(xy 343.98117 -305.388543) (xy 343.927199 -305.354292) (xy 343.877946 -305.313547) (xy 343.834189 -305.26695)
			(xy 343.796616 -305.215235) (xy 343.765822 -305.15922) (xy 343.74229 -305.099787) (xy 343.726393 -305.037873)
			(xy 343.718382 -304.974455) (xy 343.386875 -304.974455) (xy 345.093036 -306.680616) (xy 345.100987 -306.687918)
			(xy 345.12112 -306.69566) (xy 345.142659 -306.694513) (xy 345.152472 -306.690014) (xy 345.25331 -306.63769)
			(xy 345.268042 -306.60848) (xy 345.264994 -306.591716) (xy 345.261635 -306.570541) (xy 345.258071 -306.527811)
			(xy 345.257882 -306.506372) (xy 345.258348 -306.475642) (xy 345.265759 -306.41463) (xy 345.28047 -306.354956)
			(xy 345.302266 -306.297491) (xy 345.33083 -306.243071) (xy 345.365745 -306.192491) (xy 345.406501 -306.146489)
			(xy 345.452506 -306.105734) (xy 345.503087 -306.070821) (xy 345.557507 -306.042259) (xy 345.614974 -306.020465)
			(xy 345.674648 -306.005756) (xy 345.73566 -305.998347) (xy 345.76639 -305.997864) (xy 345.797195 -305.998308)
			(xy 345.858354 -306.005741) (xy 345.918167 -306.020511) (xy 345.975757 -306.042402) (xy 346.030278 -306.071093)
			(xy 346.080932 -306.106163) (xy 346.126976 -306.147098) (xy 346.167735 -306.193298) (xy 346.202611 -306.244086)
			(xy 346.231094 -306.298716) (xy 346.252765 -306.356389) (xy 346.26042 -306.38623) (xy 346.26296 -306.396898)
			(xy 346.276168 -306.413662) (xy 346.361004 -306.460144) (xy 346.382086 -306.461922) (xy 346.392246 -306.458366)
			(xy 346.422431 -306.448615) (xy 346.484991 -306.438152) (xy 346.516706 -306.437538) (xy 346.543957 -306.438002)
			(xy 346.597905 -306.44576) (xy 346.6502 -306.461117) (xy 346.699776 -306.48376) (xy 346.745625 -306.513229)
			(xy 346.786813 -306.548923) (xy 346.822502 -306.590116) (xy 346.851965 -306.63597) (xy 346.874601 -306.685549)
			(xy 346.889951 -306.737846) (xy 346.897702 -306.791795) (xy 346.898214 -306.819046) (xy 346.897771 -306.845745)
			(xy 346.890335 -306.898623) (xy 346.875599 -306.949949) (xy 346.853852 -306.998718) (xy 346.825519 -307.04398)
			(xy 346.791152 -307.08485) (xy 346.751423 -307.120529) (xy 346.707109 -307.150322) (xy 346.659073 -307.173646)
			(xy 346.6338 -307.182266) (xy 346.62237 -307.185822) (xy 346.605352 -307.202332) (xy 346.570554 -307.300884)
			(xy 346.573348 -307.324252) (xy 346.579698 -307.334412) (xy 346.595386 -307.359254) (xy 346.62158 -307.411848)
			(xy 346.641547 -307.467107) (xy 346.655022 -307.524296) (xy 346.661826 -307.582656) (xy 346.662248 -307.612034)
			(xy 346.661725 -307.644624) (xy 346.653394 -307.709268) (xy 346.636874 -307.772319) (xy 346.612434 -307.832743)
			(xy 346.580475 -307.889549) (xy 346.541521 -307.941807) (xy 346.519246 -307.965602) (xy 346.512134 -307.972714)
			(xy 346.504768 -307.991256) (xy 346.50553 -308.072536) (xy 346.506102 -308.082459) (xy 346.513811 -308.100759)
			(xy 346.520516 -308.108096) (xy 348.6023 -310.18988) (xy 348.609134 -310.197283) (xy 348.616839 -310.215881)
			(xy 348.617286 -310.225948) (xy 348.617286 -310.293512) (xy 348.622112 -310.308244) (xy 348.626684 -310.314848)
			(xy 348.646929 -310.344331) (xy 348.680789 -310.407331) (xy 348.706634 -310.47402) (xy 348.724072 -310.543384)
			(xy 348.732837 -310.614367) (xy 348.733364 -310.650128) (xy 348.73285 -310.68589) (xy 348.724081 -310.756874)
			(xy 348.706642 -310.826239) (xy 348.680799 -310.89293) (xy 348.646944 -310.955934) (xy 348.626684 -310.985408)
			(xy 348.622112 -310.992012) (xy 348.617286 -311.006744) (xy 348.617286 -311.157112) (xy 348.622112 -311.171844)
			(xy 348.626684 -311.178448) (xy 348.646929 -311.207931) (xy 348.680789 -311.270931) (xy 348.706634 -311.33762)
			(xy 348.724072 -311.406984) (xy 348.732837 -311.477967) (xy 348.733364 -311.513728) (xy 348.732834 -311.548747)
			(xy 348.724391 -311.618274) (xy 348.707633 -311.686278) (xy 348.682802 -311.751766) (xy 348.650261 -311.813786)
			(xy 348.610484 -311.871432) (xy 348.564051 -311.923866) (xy 348.511639 -311.970323) (xy 348.45401 -312.010126)
			(xy 348.392005 -312.042694) (xy 348.326528 -312.067555) (xy 348.258532 -312.084344) (xy 348.189009 -312.092818)
			(xy 348.15399 -312.093356) (xy 348.123571 -312.092969) (xy 348.063066 -312.086599) (xy 348.003561 -312.073931)
			(xy 347.945709 -312.055102) (xy 347.91777 -312.043064) (xy 347.90935 -312.039675) (xy 347.891252 -312.038507)
			(xy 347.882464 -312.040778) (xy 347.853508 -312.049414) (xy 347.845046 -312.052279) (xy 347.830732 -312.062951)
			(xy 347.825568 -312.070242) (xy 347.810364 -312.092521) (xy 347.774682 -312.132968) (xy 347.733661 -312.167989)
			(xy 347.688117 -312.196884) (xy 347.638958 -312.219078) (xy 347.587164 -312.23413) (xy 347.533766 -312.241738)
			(xy 347.506798 -312.2422) (xy 347.480002 -312.241746) (xy 347.426938 -312.234243) (xy 347.375446 -312.219386)
			(xy 347.326542 -312.197467) (xy 347.281187 -312.168918) (xy 347.240276 -312.134301) (xy 347.204613 -312.094297)
			(xy 347.174902 -312.049695) (xy 347.151727 -312.001373) (xy 347.135545 -311.950283) (xy 347.130624 -311.923938)
			(xy 347.127322 -311.905396) (xy 347.099382 -311.88152) (xy 346.688918 -311.88152) (xy 346.683963 -311.881637)
			(xy 346.674239 -311.88355) (xy 346.669614 -311.88533) (xy 342.892126 -313.44997) (xy 342.852775 -313.465437)
			(xy 342.770786 -313.486093) (xy 342.728804 -313.491118) (xy 330.285598 -314.751466) (xy 330.28255 -314.751974)
			(xy 322.410582 -316.030102) (xy 322.40855 -316.03061) (xy 321.575938 -316.199266) (xy 321.567666 -316.201294)
			(xy 321.553024 -316.209978) (xy 321.542005 -316.222954) (xy 321.5386 -316.230762) (xy 321.503294 -316.322964)
			(xy 321.506596 -316.348618) (xy 321.51447 -316.359032) (xy 321.533268 -316.38536) (xy 321.564765 -316.441866)
			(xy 321.588842 -316.50191) (xy 321.605111 -316.564522) (xy 321.61331 -316.628692) (xy 321.613784 -316.661038)
			(xy 321.613303 -316.691732) (xy 321.605878 -316.752671) (xy 321.591178 -316.812275) (xy 321.569415 -316.869677)
			(xy 321.540905 -316.924045) (xy 321.523868 -316.949582) (xy 321.518406 -316.958334) (xy 321.514294 -316.978532)
			(xy 321.518431 -316.998724) (xy 321.523868 -317.007494) (xy 321.540924 -317.033021) (xy 321.569454 -317.087383)
			(xy 321.591225 -317.144787) (xy 321.60592 -317.204396) (xy 321.613326 -317.265341) (xy 321.613784 -317.296038)
			(xy 321.613303 -317.326732) (xy 321.605878 -317.387671) (xy 321.591178 -317.447275) (xy 321.569415 -317.504677)
			(xy 321.540905 -317.559045) (xy 321.523868 -317.584582) (xy 321.518406 -317.593334) (xy 321.514294 -317.613532)
			(xy 321.518431 -317.633724) (xy 321.523868 -317.642494) (xy 321.540924 -317.668021) (xy 321.569454 -317.722383)
			(xy 321.591225 -317.779787) (xy 321.60592 -317.839396) (xy 321.613326 -317.900341) (xy 321.613784 -317.931038)
			(xy 321.613303 -317.961732) (xy 321.605878 -318.022671) (xy 321.591178 -318.082275) (xy 321.569415 -318.139677)
			(xy 321.540905 -318.194045) (xy 321.523868 -318.219582) (xy 321.518406 -318.228334) (xy 321.514294 -318.248532)
			(xy 321.518431 -318.268724) (xy 321.523868 -318.277494) (xy 321.540924 -318.303021) (xy 321.569454 -318.357383)
			(xy 321.591225 -318.414787) (xy 321.60592 -318.474396) (xy 321.613326 -318.535341) (xy 321.613784 -318.566038)
			(xy 321.613303 -318.596732) (xy 321.605878 -318.657671) (xy 321.591178 -318.717275) (xy 321.569415 -318.774677)
			(xy 321.540905 -318.829045) (xy 321.523868 -318.854582) (xy 321.518406 -318.863334) (xy 321.514294 -318.883532)
			(xy 321.518431 -318.903724) (xy 321.523868 -318.912494) (xy 321.540924 -318.938021) (xy 321.569454 -318.992383)
			(xy 321.591225 -319.049787) (xy 321.60592 -319.109396) (xy 321.613326 -319.170341) (xy 321.613784 -319.201038)
			(xy 321.613303 -319.231732) (xy 321.605878 -319.292671) (xy 321.591178 -319.352275) (xy 321.569415 -319.409677)
			(xy 321.540905 -319.464045) (xy 321.523868 -319.489582) (xy 321.518406 -319.498334) (xy 321.514294 -319.518532)
			(xy 321.518431 -319.538724) (xy 321.523868 -319.547494) (xy 321.540924 -319.573021) (xy 321.569454 -319.627383)
			(xy 321.591225 -319.684787) (xy 321.60592 -319.744396) (xy 321.613326 -319.805341) (xy 321.613784 -319.836038)
			(xy 321.613303 -319.866732) (xy 321.605878 -319.927671) (xy 321.591178 -319.987275) (xy 321.569415 -320.044677)
			(xy 321.540905 -320.099045) (xy 321.523868 -320.124582) (xy 321.518406 -320.133334) (xy 321.514294 -320.153532)
			(xy 321.518431 -320.173724) (xy 321.523868 -320.182494) (xy 321.540924 -320.208021) (xy 321.569454 -320.262383)
			(xy 321.591225 -320.319787) (xy 321.60592 -320.379396) (xy 321.613326 -320.440341) (xy 321.613784 -320.471038)
			(xy 321.613303 -320.501732) (xy 321.605878 -320.562671) (xy 321.591178 -320.622275) (xy 321.569415 -320.679677)
			(xy 321.540905 -320.734045) (xy 321.523868 -320.759582) (xy 321.518406 -320.768334) (xy 321.514294 -320.788532)
			(xy 321.518431 -320.808724) (xy 321.523868 -320.817494) (xy 321.540924 -320.843021) (xy 321.569454 -320.897383)
			(xy 321.591225 -320.954787) (xy 321.60592 -321.014396) (xy 321.613326 -321.075341) (xy 321.613784 -321.106038)
			(xy 321.613303 -321.136732) (xy 321.605878 -321.197671) (xy 321.591178 -321.257275) (xy 321.569415 -321.314677)
			(xy 321.540905 -321.369045) (xy 321.523868 -321.394582) (xy 321.518406 -321.403334) (xy 321.514294 -321.423532)
			(xy 321.518431 -321.443724) (xy 321.523868 -321.452494) (xy 321.540924 -321.478021) (xy 321.569454 -321.532383)
			(xy 321.591225 -321.589787) (xy 321.60592 -321.649396) (xy 321.613326 -321.710341) (xy 321.613784 -321.741038)
			(xy 321.613303 -321.771732) (xy 321.605878 -321.832671) (xy 321.591178 -321.892275) (xy 321.569415 -321.949677)
			(xy 321.540905 -322.004045) (xy 321.523868 -322.029582) (xy 321.518406 -322.038334) (xy 321.514294 -322.058532)
			(xy 321.518431 -322.078724) (xy 321.523868 -322.087494) (xy 321.540924 -322.113021) (xy 321.569454 -322.167383)
			(xy 321.591225 -322.224787) (xy 321.60592 -322.284396) (xy 321.613326 -322.345341) (xy 321.613462 -322.354448)
			(xy 323.643752 -322.354448) (xy 323.644209 -322.323751) (xy 323.651614 -322.262805) (xy 323.666309 -322.203196)
			(xy 323.688081 -322.145792) (xy 323.716612 -322.091431) (xy 323.733668 -322.065904) (xy 323.739102 -322.057131)
			(xy 323.743247 -322.03694) (xy 323.739133 -322.016742) (xy 323.733668 -322.007992) (xy 323.71664 -321.98245)
			(xy 323.688128 -321.928084) (xy 323.666362 -321.870683) (xy 323.65166 -321.81108) (xy 323.644234 -321.750142)
			(xy 323.643752 -321.719448) (xy 323.644209 -321.688751) (xy 323.651614 -321.627805) (xy 323.666309 -321.568196)
			(xy 323.688081 -321.510792) (xy 323.716612 -321.456431) (xy 323.733668 -321.430904) (xy 323.739102 -321.422131)
			(xy 323.743247 -321.40194) (xy 323.739133 -321.381742) (xy 323.733668 -321.372992) (xy 323.71664 -321.34745)
			(xy 323.688128 -321.293084) (xy 323.666362 -321.235683) (xy 323.65166 -321.17608) (xy 323.644234 -321.115142)
			(xy 323.643752 -321.084448) (xy 323.644209 -321.053751) (xy 323.651614 -320.992805) (xy 323.666309 -320.933196)
			(xy 323.688081 -320.875792) (xy 323.716612 -320.821431) (xy 323.733668 -320.795904) (xy 323.739102 -320.787131)
			(xy 323.743247 -320.76694) (xy 323.739133 -320.746742) (xy 323.733668 -320.737992) (xy 323.71664 -320.71245)
			(xy 323.688128 -320.658084) (xy 323.666362 -320.600683) (xy 323.65166 -320.54108) (xy 323.644234 -320.480142)
			(xy 323.643752 -320.449448) (xy 323.644209 -320.418751) (xy 323.651614 -320.357805) (xy 323.666309 -320.298196)
			(xy 323.688081 -320.240792) (xy 323.716612 -320.186431) (xy 323.733668 -320.160904) (xy 323.739102 -320.152131)
			(xy 323.743247 -320.13194) (xy 323.739133 -320.111742) (xy 323.733668 -320.102992) (xy 323.71664 -320.07745)
			(xy 323.688128 -320.023084) (xy 323.666362 -319.965683) (xy 323.65166 -319.90608) (xy 323.644234 -319.845142)
			(xy 323.643752 -319.814448) (xy 323.644209 -319.783751) (xy 323.651614 -319.722805) (xy 323.666309 -319.663196)
			(xy 323.688081 -319.605792) (xy 323.716612 -319.551431) (xy 323.733668 -319.525904) (xy 323.739102 -319.517131)
			(xy 323.743247 -319.49694) (xy 323.739133 -319.476742) (xy 323.733668 -319.467992) (xy 323.71664 -319.44245)
			(xy 323.688128 -319.388084) (xy 323.666362 -319.330683) (xy 323.65166 -319.27108) (xy 323.644234 -319.210142)
			(xy 323.643752 -319.179448) (xy 323.644209 -319.148751) (xy 323.651614 -319.087805) (xy 323.666309 -319.028196)
			(xy 323.688081 -318.970792) (xy 323.716612 -318.916431) (xy 323.733668 -318.890904) (xy 323.739102 -318.882131)
			(xy 323.743247 -318.86194) (xy 323.739133 -318.841742) (xy 323.733668 -318.832992) (xy 323.71664 -318.80745)
			(xy 323.688128 -318.753084) (xy 323.666362 -318.695683) (xy 323.65166 -318.63608) (xy 323.644234 -318.575142)
			(xy 323.643752 -318.544448) (xy 323.644209 -318.513751) (xy 323.651614 -318.452805) (xy 323.666309 -318.393196)
			(xy 323.688081 -318.335792) (xy 323.716612 -318.281431) (xy 323.733668 -318.255904) (xy 323.739102 -318.247131)
			(xy 323.743247 -318.22694) (xy 323.739133 -318.206742) (xy 323.733668 -318.197992) (xy 323.71664 -318.17245)
			(xy 323.688128 -318.118084) (xy 323.666362 -318.060683) (xy 323.65166 -318.00108) (xy 323.644234 -317.940142)
			(xy 323.643752 -317.909448) (xy 323.644209 -317.878751) (xy 323.651614 -317.817805) (xy 323.666309 -317.758196)
			(xy 323.688081 -317.700792) (xy 323.716612 -317.646431) (xy 323.733668 -317.620904) (xy 323.739102 -317.612131)
			(xy 323.743247 -317.59194) (xy 323.739133 -317.571742) (xy 323.733668 -317.562992) (xy 323.71664 -317.53745)
			(xy 323.688128 -317.483084) (xy 323.666362 -317.425683) (xy 323.65166 -317.36608) (xy 323.644234 -317.305142)
			(xy 323.643752 -317.274448) (xy 323.644209 -317.243751) (xy 323.651614 -317.182805) (xy 323.666309 -317.123196)
			(xy 323.688081 -317.065792) (xy 323.716612 -317.011431) (xy 323.733668 -316.985904) (xy 323.739102 -316.977131)
			(xy 323.743247 -316.95694) (xy 323.739133 -316.936742) (xy 323.733668 -316.927992) (xy 323.71664 -316.90245)
			(xy 323.688128 -316.848084) (xy 323.666362 -316.790683) (xy 323.65166 -316.73108) (xy 323.644234 -316.670142)
			(xy 323.643752 -316.639448) (xy 323.644283 -316.608718) (xy 323.651685 -316.547707) (xy 323.666388 -316.488032)
			(xy 323.688176 -316.430565) (xy 323.716733 -316.376143) (xy 323.751641 -316.32556) (xy 323.792392 -316.279554)
			(xy 323.838391 -316.238795) (xy 323.888968 -316.203878) (xy 323.943385 -316.175312) (xy 324.000848 -316.153514)
			(xy 324.06052 -316.138801) (xy 324.121531 -316.131388) (xy 324.15226 -316.13094) (xy 324.182957 -316.131395)
			(xy 324.243903 -316.138801) (xy 324.303512 -316.153497) (xy 324.360916 -316.175269) (xy 324.415277 -316.2038)
			(xy 324.440804 -316.220856) (xy 324.449556 -316.226327) (xy 324.46976 -316.230455) (xy 324.489964 -316.226327)
			(xy 324.498716 -316.220856) (xy 324.524255 -316.203823) (xy 324.578622 -316.175312) (xy 324.636024 -316.153548)
			(xy 324.695627 -316.138846) (xy 324.756566 -316.131421) (xy 324.78726 -316.13094) (xy 324.817957 -316.131395)
			(xy 324.878903 -316.138801) (xy 324.938512 -316.153497) (xy 324.995916 -316.175269) (xy 325.050277 -316.2038)
			(xy 325.075804 -316.220856) (xy 325.084556 -316.226327) (xy 325.10476 -316.230455) (xy 325.124964 -316.226327)
			(xy 325.133716 -316.220856) (xy 325.159255 -316.203823) (xy 325.213622 -316.175312) (xy 325.271024 -316.153548)
			(xy 325.330627 -316.138846) (xy 325.391566 -316.131421) (xy 325.42226 -316.13094) (xy 325.452993 -316.131375)
			(xy 325.514012 -316.13878) (xy 325.573692 -316.153487) (xy 325.631165 -316.175281) (xy 325.685591 -316.203844)
			(xy 325.736178 -316.23876) (xy 325.782186 -316.27952) (xy 325.822944 -316.325529) (xy 325.85786 -316.376115)
			(xy 325.886422 -316.430542) (xy 325.908215 -316.488015) (xy 325.922921 -316.547696) (xy 325.930325 -316.608715)
			(xy 325.930768 -316.639448) (xy 325.930306 -316.670145) (xy 325.922902 -316.73109) (xy 325.908207 -316.790699)
			(xy 325.886437 -316.848103) (xy 325.857907 -316.902465) (xy 325.840852 -316.927992) (xy 325.835343 -316.936723)
			(xy 325.831232 -316.95694) (xy 325.835374 -316.97715) (xy 325.840852 -316.985904) (xy 325.857881 -317.011446)
			(xy 325.886393 -317.065812) (xy 325.908157 -317.123213) (xy 325.92286 -317.182816) (xy 325.930286 -317.243754)
			(xy 325.930768 -317.274448) (xy 325.930306 -317.305145) (xy 325.922902 -317.36609) (xy 325.908207 -317.425699)
			(xy 325.886437 -317.483103) (xy 325.857907 -317.537465) (xy 325.840852 -317.562992) (xy 325.835343 -317.571723)
			(xy 325.831232 -317.59194) (xy 325.835374 -317.61215) (xy 325.840852 -317.620904) (xy 325.857881 -317.646446)
			(xy 325.886393 -317.700812) (xy 325.908157 -317.758213) (xy 325.92286 -317.817816) (xy 325.930286 -317.878754)
			(xy 325.930768 -317.909448) (xy 325.930306 -317.940145) (xy 325.922902 -318.00109) (xy 325.908207 -318.060699)
			(xy 325.886437 -318.118103) (xy 325.857907 -318.172465) (xy 325.840852 -318.197992) (xy 325.835343 -318.206723)
			(xy 325.831232 -318.22694) (xy 325.835374 -318.24715) (xy 325.840852 -318.255904) (xy 325.857881 -318.281446)
			(xy 325.886393 -318.335812) (xy 325.908157 -318.393213) (xy 325.92286 -318.452816) (xy 325.930286 -318.513754)
			(xy 325.930768 -318.544448) (xy 325.930306 -318.575145) (xy 325.922902 -318.63609) (xy 325.908207 -318.695699)
			(xy 325.886437 -318.753103) (xy 325.857907 -318.807465) (xy 325.840852 -318.832992) (xy 325.835343 -318.841723)
			(xy 325.831232 -318.86194) (xy 325.835374 -318.88215) (xy 325.840852 -318.890904) (xy 325.857881 -318.916446)
			(xy 325.886393 -318.970812) (xy 325.908157 -319.028213) (xy 325.92286 -319.087816) (xy 325.930286 -319.148754)
			(xy 325.930768 -319.179448) (xy 325.930306 -319.210145) (xy 325.922902 -319.27109) (xy 325.908207 -319.330699)
			(xy 325.886437 -319.388103) (xy 325.857907 -319.442465) (xy 325.840852 -319.467992) (xy 325.835343 -319.476723)
			(xy 325.831232 -319.49694) (xy 325.835374 -319.51715) (xy 325.840852 -319.525904) (xy 325.857881 -319.551446)
			(xy 325.886393 -319.605812) (xy 325.908157 -319.663213) (xy 325.92286 -319.722816) (xy 325.930286 -319.783754)
			(xy 325.930768 -319.814448) (xy 325.930319 -319.843401) (xy 325.923713 -319.900929) (xy 325.910624 -319.957337)
			(xy 325.891223 -320.011896) (xy 325.86576 -320.063903) (xy 325.850504 -320.088514) (xy 325.845327 -320.097519)
			(xy 325.841915 -320.117985) (xy 325.846901 -320.138125) (xy 325.85279 -320.14668) (xy 325.872335 -320.173293)
			(xy 325.905093 -320.230624) (xy 325.930155 -320.291712) (xy 325.9471 -320.35553) (xy 325.955643 -320.421005)
			(xy 325.956168 -320.45402) (xy 325.955691 -320.484716) (xy 325.948291 -320.545661) (xy 325.9336 -320.60527)
			(xy 325.911832 -320.662674) (xy 325.883306 -320.717037) (xy 325.866252 -320.742564) (xy 325.860767 -320.751308)
			(xy 325.856648 -320.771517) (xy 325.86078 -320.791723) (xy 325.866252 -320.800476) (xy 325.883312 -320.825998)
			(xy 325.911818 -320.88037) (xy 325.933577 -320.937776) (xy 325.948272 -320.997383) (xy 325.95569 -321.058325)
			(xy 325.956168 -321.08902) (xy 325.955691 -321.119716) (xy 325.948291 -321.180661) (xy 325.9336 -321.24027)
			(xy 325.911832 -321.297674) (xy 325.883306 -321.352037) (xy 325.866252 -321.377564) (xy 325.860767 -321.386308)
			(xy 325.856648 -321.406517) (xy 325.86078 -321.426723) (xy 325.866252 -321.435476) (xy 325.883312 -321.460998)
			(xy 325.911818 -321.51537) (xy 325.933577 -321.572776) (xy 325.948272 -321.632383) (xy 325.95569 -321.693325)
			(xy 325.956168 -321.72402) (xy 325.955691 -321.754716) (xy 325.948291 -321.815661) (xy 325.9336 -321.87527)
			(xy 325.911832 -321.932674) (xy 325.883306 -321.987037) (xy 325.866252 -322.012564) (xy 325.860767 -322.021308)
			(xy 325.856648 -322.041517) (xy 325.86078 -322.061723) (xy 325.866252 -322.070476) (xy 325.883312 -322.095998)
			(xy 325.911818 -322.15037) (xy 325.933577 -322.207776) (xy 325.948272 -322.267383) (xy 325.95569 -322.328325)
			(xy 325.956168 -322.35902) (xy 325.955614 -322.392034) (xy 325.947077 -322.457506) (xy 325.930137 -322.521323)
			(xy 325.905078 -322.58241) (xy 325.872322 -322.639739) (xy 325.85279 -322.66636) (xy 325.84691 -322.674972)
			(xy 325.842015 -322.695226) (xy 325.845509 -322.715767) (xy 325.850758 -322.72478) (xy 325.866621 -322.749726)
			(xy 325.893131 -322.802569) (xy 325.913344 -322.858126) (xy 325.926986 -322.91565) (xy 325.933876 -322.974367)
			(xy 325.934324 -323.003926) (xy 327.660508 -323.003926) (xy 327.661017 -322.970911) (xy 327.669562 -322.905436)
			(xy 327.686512 -322.841618) (xy 327.711582 -322.780532) (xy 327.744349 -322.723205) (xy 327.763886 -322.696586)
			(xy 327.769729 -322.687951) (xy 327.774638 -322.667711) (xy 327.771159 -322.647178) (xy 327.765918 -322.638166)
			(xy 327.750029 -322.613235) (xy 327.723524 -322.560388) (xy 327.703317 -322.504827) (xy 327.68968 -322.4473)
			(xy 327.682797 -322.38858) (xy 327.682352 -322.35902) (xy 327.682795 -322.328323) (xy 327.690203 -322.267376)
			(xy 327.704902 -322.207767) (xy 327.726677 -322.150363) (xy 327.75521 -322.096002) (xy 327.772268 -322.070476)
			(xy 327.777726 -322.061716) (xy 327.781863 -322.041517) (xy 327.777739 -322.021315) (xy 327.772268 -322.012564)
			(xy 327.755227 -321.987029) (xy 327.726717 -321.932661) (xy 327.704955 -321.875258) (xy 327.690255 -321.815654)
			(xy 327.682832 -321.754715) (xy 327.682352 -321.72402) (xy 327.682795 -321.693323) (xy 327.690203 -321.632376)
			(xy 327.704902 -321.572767) (xy 327.726677 -321.515363) (xy 327.75521 -321.461002) (xy 327.772268 -321.435476)
			(xy 327.777726 -321.426716) (xy 327.781863 -321.406517) (xy 327.777739 -321.386315) (xy 327.772268 -321.377564)
			(xy 327.755227 -321.352029) (xy 327.726717 -321.297661) (xy 327.704955 -321.240258) (xy 327.690255 -321.180654)
			(xy 327.682832 -321.119715) (xy 327.682352 -321.08902) (xy 327.682795 -321.058323) (xy 327.690203 -320.997376)
			(xy 327.704902 -320.937767) (xy 327.726677 -320.880363) (xy 327.75521 -320.826002) (xy 327.772268 -320.800476)
			(xy 327.777726 -320.791716) (xy 327.781863 -320.771517) (xy 327.777739 -320.751315) (xy 327.772268 -320.742564)
			(xy 327.755227 -320.717029) (xy 327.726717 -320.662661) (xy 327.704955 -320.605258) (xy 327.690255 -320.545654)
			(xy 327.682832 -320.484715) (xy 327.682352 -320.45402) (xy 327.682846 -320.423048) (xy 327.690371 -320.361562)
			(xy 327.705312 -320.301446) (xy 327.727448 -320.243592) (xy 327.75645 -320.188856) (xy 327.773792 -320.16319)
			(xy 327.779236 -320.154423) (xy 327.783375 -320.134228) (xy 327.779258 -320.114029) (xy 327.773792 -320.105278)
			(xy 327.756431 -320.079622) (xy 327.72742 -320.024887) (xy 327.705279 -319.967031) (xy 327.690334 -319.906912)
			(xy 327.68281 -319.845422) (xy 327.682352 -319.814448) (xy 327.682809 -319.783751) (xy 327.690214 -319.722805)
			(xy 327.704909 -319.663196) (xy 327.726681 -319.605792) (xy 327.755212 -319.551431) (xy 327.772268 -319.525904)
			(xy 327.777702 -319.517131) (xy 327.781847 -319.49694) (xy 327.777733 -319.476742) (xy 327.772268 -319.467992)
			(xy 327.75524 -319.44245) (xy 327.726728 -319.388084) (xy 327.704962 -319.330683) (xy 327.69026 -319.27108)
			(xy 327.682834 -319.210142) (xy 327.682352 -319.179448) (xy 327.682809 -319.148751) (xy 327.690214 -319.087805)
			(xy 327.704909 -319.028196) (xy 327.726681 -318.970792) (xy 327.755212 -318.916431) (xy 327.772268 -318.890904)
			(xy 327.777702 -318.882131) (xy 327.781847 -318.86194) (xy 327.777733 -318.841742) (xy 327.772268 -318.832992)
			(xy 327.75524 -318.80745) (xy 327.726728 -318.753084) (xy 327.704962 -318.695683) (xy 327.69026 -318.63608)
			(xy 327.682834 -318.575142) (xy 327.682352 -318.544448) (xy 327.682809 -318.513751) (xy 327.690214 -318.452805)
			(xy 327.704909 -318.393196) (xy 327.726681 -318.335792) (xy 327.755212 -318.281431) (xy 327.772268 -318.255904)
			(xy 327.777702 -318.247131) (xy 327.781847 -318.22694) (xy 327.777733 -318.206742) (xy 327.772268 -318.197992)
			(xy 327.75524 -318.17245) (xy 327.726728 -318.118084) (xy 327.704962 -318.060683) (xy 327.69026 -318.00108)
			(xy 327.682834 -317.940142) (xy 327.682352 -317.909448) (xy 327.682809 -317.878751) (xy 327.690214 -317.817805)
			(xy 327.704909 -317.758196) (xy 327.726681 -317.700792) (xy 327.755212 -317.646431) (xy 327.772268 -317.620904)
			(xy 327.777702 -317.612131) (xy 327.781847 -317.59194) (xy 327.777733 -317.571742) (xy 327.772268 -317.562992)
			(xy 327.75524 -317.53745) (xy 327.726728 -317.483084) (xy 327.704962 -317.425683) (xy 327.69026 -317.36608)
			(xy 327.682834 -317.305142) (xy 327.682352 -317.274448) (xy 327.682809 -317.243751) (xy 327.690214 -317.182805)
			(xy 327.704909 -317.123196) (xy 327.726681 -317.065792) (xy 327.755212 -317.011431) (xy 327.772268 -316.985904)
			(xy 327.777702 -316.977131) (xy 327.781847 -316.95694) (xy 327.777733 -316.936742) (xy 327.772268 -316.927992)
			(xy 327.75524 -316.90245) (xy 327.726728 -316.848084) (xy 327.704962 -316.790683) (xy 327.69026 -316.73108)
			(xy 327.682834 -316.670142) (xy 327.682352 -316.639448) (xy 327.682883 -316.608718) (xy 327.690285 -316.547707)
			(xy 327.704988 -316.488032) (xy 327.726776 -316.430565) (xy 327.755333 -316.376143) (xy 327.790241 -316.32556)
			(xy 327.830992 -316.279554) (xy 327.876991 -316.238795) (xy 327.927568 -316.203878) (xy 327.981985 -316.175312)
			(xy 328.039448 -316.153514) (xy 328.09912 -316.138801) (xy 328.160131 -316.131388) (xy 328.19086 -316.13094)
			(xy 328.221557 -316.131395) (xy 328.282503 -316.138801) (xy 328.342112 -316.153497) (xy 328.399516 -316.175269)
			(xy 328.453877 -316.2038) (xy 328.479404 -316.220856) (xy 328.488156 -316.226327) (xy 328.50836 -316.230455)
			(xy 328.528564 -316.226327) (xy 328.537316 -316.220856) (xy 328.562855 -316.203823) (xy 328.617222 -316.175312)
			(xy 328.674624 -316.153548) (xy 328.734227 -316.138846) (xy 328.795166 -316.131421) (xy 328.82586 -316.13094)
			(xy 328.856557 -316.131395) (xy 328.917503 -316.138801) (xy 328.977112 -316.153497) (xy 329.034516 -316.175269)
			(xy 329.088877 -316.2038) (xy 329.114404 -316.220856) (xy 329.123156 -316.226327) (xy 329.14336 -316.230455)
			(xy 329.163564 -316.226327) (xy 329.172316 -316.220856) (xy 329.197855 -316.203823) (xy 329.252222 -316.175312)
			(xy 329.309624 -316.153548) (xy 329.369227 -316.138846) (xy 329.430166 -316.131421) (xy 329.46086 -316.13094)
			(xy 329.491593 -316.131375) (xy 329.552612 -316.13878) (xy 329.612292 -316.153487) (xy 329.669765 -316.175281)
			(xy 329.724191 -316.203844) (xy 329.774778 -316.23876) (xy 329.820786 -316.27952) (xy 329.861544 -316.325529)
			(xy 329.89646 -316.376115) (xy 329.925022 -316.430542) (xy 329.946815 -316.488015) (xy 329.961521 -316.547696)
			(xy 329.968925 -316.608715) (xy 329.969368 -316.639448) (xy 329.968906 -316.670145) (xy 329.961502 -316.73109)
			(xy 329.946807 -316.790699) (xy 329.925037 -316.848103) (xy 329.896507 -316.902465) (xy 329.879452 -316.927992)
			(xy 329.873943 -316.936723) (xy 329.869832 -316.95694) (xy 329.873974 -316.97715) (xy 329.879452 -316.985904)
			(xy 329.896481 -317.011446) (xy 329.924993 -317.065812) (xy 329.946757 -317.123213) (xy 329.96146 -317.182816)
			(xy 329.968886 -317.243754) (xy 329.969368 -317.274448) (xy 329.968906 -317.305145) (xy 329.961502 -317.36609)
			(xy 329.946807 -317.425699) (xy 329.925037 -317.483103) (xy 329.896507 -317.537465) (xy 329.879452 -317.562992)
			(xy 329.873943 -317.571723) (xy 329.869832 -317.59194) (xy 329.873974 -317.61215) (xy 329.879452 -317.620904)
			(xy 329.896481 -317.646446) (xy 329.924993 -317.700812) (xy 329.946757 -317.758213) (xy 329.96146 -317.817816)
			(xy 329.968886 -317.878754) (xy 329.969368 -317.909448) (xy 329.968906 -317.940145) (xy 329.961502 -318.00109)
			(xy 329.946807 -318.060699) (xy 329.925037 -318.118103) (xy 329.896507 -318.172465) (xy 329.879452 -318.197992)
			(xy 329.873943 -318.206723) (xy 329.869832 -318.22694) (xy 329.873974 -318.24715) (xy 329.879452 -318.255904)
			(xy 329.896481 -318.281446) (xy 329.924993 -318.335812) (xy 329.946757 -318.393213) (xy 329.96146 -318.452816)
			(xy 329.968886 -318.513754) (xy 329.969368 -318.544448) (xy 329.968906 -318.575145) (xy 329.961502 -318.63609)
			(xy 329.946807 -318.695699) (xy 329.925037 -318.753103) (xy 329.896507 -318.807465) (xy 329.879452 -318.832992)
			(xy 329.873943 -318.841723) (xy 329.869832 -318.86194) (xy 329.873974 -318.88215) (xy 329.879452 -318.890904)
			(xy 329.896481 -318.916446) (xy 329.924993 -318.970812) (xy 329.946757 -319.028213) (xy 329.96146 -319.087816)
			(xy 329.968886 -319.148754) (xy 329.969368 -319.179448) (xy 329.968906 -319.210145) (xy 329.961502 -319.27109)
			(xy 329.946807 -319.330699) (xy 329.925037 -319.388103) (xy 329.896507 -319.442465) (xy 329.879452 -319.467992)
			(xy 329.873943 -319.476723) (xy 329.869832 -319.49694) (xy 329.873974 -319.51715) (xy 329.879452 -319.525904)
			(xy 329.896481 -319.551446) (xy 329.924993 -319.605812) (xy 329.946757 -319.663213) (xy 329.96146 -319.722816)
			(xy 329.968886 -319.783754) (xy 329.969368 -319.814448) (xy 329.968906 -319.845145) (xy 329.961502 -319.90609)
			(xy 329.946807 -319.965699) (xy 329.925037 -320.023103) (xy 329.896507 -320.077465) (xy 329.879452 -320.102992)
			(xy 329.873943 -320.111723) (xy 329.869832 -320.13194) (xy 329.873974 -320.15215) (xy 329.879452 -320.160904)
			(xy 329.896481 -320.186446) (xy 329.924993 -320.240812) (xy 329.946757 -320.298213) (xy 329.96146 -320.357816)
			(xy 329.968886 -320.418754) (xy 329.969368 -320.449448) (xy 329.968906 -320.480145) (xy 329.961502 -320.54109)
			(xy 329.946807 -320.600699) (xy 329.925037 -320.658103) (xy 329.896507 -320.712465) (xy 329.879452 -320.737992)
			(xy 329.873943 -320.746723) (xy 329.869832 -320.76694) (xy 329.873974 -320.78715) (xy 329.879452 -320.795904)
			(xy 329.896481 -320.821446) (xy 329.924993 -320.875812) (xy 329.946757 -320.933213) (xy 329.96146 -320.992816)
			(xy 329.968886 -321.053754) (xy 329.969368 -321.084448) (xy 329.968906 -321.115145) (xy 329.961502 -321.17609)
			(xy 329.946807 -321.235699) (xy 329.925037 -321.293103) (xy 329.896507 -321.347465) (xy 329.879452 -321.372992)
			(xy 329.873943 -321.381723) (xy 329.869832 -321.40194) (xy 329.873974 -321.42215) (xy 329.879452 -321.430904)
			(xy 329.896481 -321.456446) (xy 329.924993 -321.510812) (xy 329.946757 -321.568213) (xy 329.96146 -321.627816)
			(xy 329.968886 -321.688754) (xy 329.969368 -321.719448) (xy 329.968906 -321.750145) (xy 329.961502 -321.81109)
			(xy 329.946807 -321.870699) (xy 329.925037 -321.928103) (xy 329.896507 -321.982465) (xy 329.879452 -322.007992)
			(xy 329.873943 -322.016723) (xy 329.869832 -322.03694) (xy 329.873974 -322.05715) (xy 329.879452 -322.065904)
			(xy 329.896481 -322.091446) (xy 329.924993 -322.145812) (xy 329.946757 -322.203213) (xy 329.96146 -322.262816)
			(xy 329.968886 -322.323754) (xy 329.969368 -322.354448) (xy 329.968841 -322.387685) (xy 329.960215 -322.453595)
			(xy 329.943063 -322.517816) (xy 329.917678 -322.57925) (xy 329.884496 -322.636848) (xy 329.86472 -322.663566)
			(xy 329.858781 -322.672265) (xy 329.853762 -322.692694) (xy 329.857336 -322.713425) (xy 329.862688 -322.722494)
			(xy 329.878842 -322.747574) (xy 329.905795 -322.800798) (xy 329.926331 -322.856811) (xy 329.940168 -322.914843)
			(xy 329.947115 -322.974096) (xy 329.947524 -323.003926) (xy 332.000352 -323.003926) (xy 332.000798 -322.973229)
			(xy 332.008205 -322.912283) (xy 332.022903 -322.852673) (xy 332.044678 -322.79527) (xy 332.073211 -322.740908)
			(xy 332.090268 -322.715382) (xy 332.095721 -322.706619) (xy 332.099859 -322.686422) (xy 332.095738 -322.666221)
			(xy 332.090268 -322.65747) (xy 332.07323 -322.631934) (xy 332.04472 -322.577566) (xy 332.022956 -322.520163)
			(xy 332.008256 -322.46056) (xy 332.000832 -322.399621) (xy 332.000352 -322.368926) (xy 332.000798 -322.338229)
			(xy 332.008205 -322.277283) (xy 332.022903 -322.217673) (xy 332.044678 -322.16027) (xy 332.073211 -322.105908)
			(xy 332.090268 -322.080382) (xy 332.095721 -322.071619) (xy 332.099859 -322.051422) (xy 332.095738 -322.031221)
			(xy 332.090268 -322.02247) (xy 332.07323 -321.996934) (xy 332.04472 -321.942566) (xy 332.022956 -321.885163)
			(xy 332.008256 -321.82556) (xy 332.000832 -321.764621) (xy 332.000352 -321.733926) (xy 332.000798 -321.703229)
			(xy 332.008205 -321.642283) (xy 332.022903 -321.582673) (xy 332.044678 -321.52527) (xy 332.073211 -321.470908)
			(xy 332.090268 -321.445382) (xy 332.095721 -321.436619) (xy 332.099859 -321.416422) (xy 332.095738 -321.396221)
			(xy 332.090268 -321.38747) (xy 332.07323 -321.361934) (xy 332.04472 -321.307566) (xy 332.022956 -321.250163)
			(xy 332.008256 -321.19056) (xy 332.000832 -321.129621) (xy 332.000352 -321.098926) (xy 332.000798 -321.068229)
			(xy 332.008205 -321.007283) (xy 332.022903 -320.947673) (xy 332.044678 -320.89027) (xy 332.073211 -320.835908)
			(xy 332.090268 -320.810382) (xy 332.095721 -320.801619) (xy 332.099859 -320.781422) (xy 332.095738 -320.761221)
			(xy 332.090268 -320.75247) (xy 332.07323 -320.726934) (xy 332.04472 -320.672566) (xy 332.022956 -320.615163)
			(xy 332.008256 -320.55556) (xy 332.000832 -320.494621) (xy 332.000352 -320.463926) (xy 332.000837 -320.432331)
			(xy 332.008658 -320.369626) (xy 332.024196 -320.308376) (xy 332.047209 -320.249526) (xy 332.077344 -320.193984)
			(xy 332.095348 -320.168016) (xy 332.101061 -320.159166) (xy 332.10535 -320.13856) (xy 332.101029 -320.117962)
			(xy 332.095348 -320.109088) (xy 332.07754 -320.08318) (xy 332.047729 -320.02783) (xy 332.024963 -319.969229)
			(xy 332.009588 -319.90827) (xy 332.001839 -319.845882) (xy 332.001368 -319.814448) (xy 332.00184 -319.783752)
			(xy 332.009243 -319.722807) (xy 332.023936 -319.663198) (xy 332.045704 -319.605794) (xy 332.07423 -319.551432)
			(xy 332.091284 -319.525904) (xy 332.096717 -319.517131) (xy 332.10086 -319.49694) (xy 332.096748 -319.476743)
			(xy 332.091284 -319.467992) (xy 332.074258 -319.442448) (xy 332.045745 -319.388083) (xy 332.023979 -319.330682)
			(xy 332.009276 -319.27108) (xy 332.00185 -319.210142) (xy 332.001368 -319.179448) (xy 332.00184 -319.148752)
			(xy 332.009243 -319.087807) (xy 332.023936 -319.028198) (xy 332.045704 -318.970794) (xy 332.07423 -318.916432)
			(xy 332.091284 -318.890904) (xy 332.096717 -318.882131) (xy 332.10086 -318.86194) (xy 332.096748 -318.841743)
			(xy 332.091284 -318.832992) (xy 332.074258 -318.807448) (xy 332.045745 -318.753083) (xy 332.023979 -318.695682)
			(xy 332.009276 -318.63608) (xy 332.00185 -318.575142) (xy 332.001368 -318.544448) (xy 332.00184 -318.513752)
			(xy 332.009243 -318.452807) (xy 332.023936 -318.393198) (xy 332.045704 -318.335794) (xy 332.07423 -318.281432)
			(xy 332.091284 -318.255904) (xy 332.096717 -318.247131) (xy 332.10086 -318.22694) (xy 332.096748 -318.206743)
			(xy 332.091284 -318.197992) (xy 332.074258 -318.172448) (xy 332.045745 -318.118083) (xy 332.023979 -318.060682)
			(xy 332.009276 -318.00108) (xy 332.00185 -317.940142) (xy 332.001368 -317.909448) (xy 332.00184 -317.878752)
			(xy 332.009243 -317.817807) (xy 332.023936 -317.758198) (xy 332.045704 -317.700794) (xy 332.07423 -317.646432)
			(xy 332.091284 -317.620904) (xy 332.096717 -317.612131) (xy 332.10086 -317.59194) (xy 332.096748 -317.571743)
			(xy 332.091284 -317.562992) (xy 332.074258 -317.537448) (xy 332.045745 -317.483083) (xy 332.023979 -317.425682)
			(xy 332.009276 -317.36608) (xy 332.00185 -317.305142) (xy 332.001368 -317.274448) (xy 332.00184 -317.243752)
			(xy 332.009243 -317.182807) (xy 332.023936 -317.123198) (xy 332.045704 -317.065794) (xy 332.07423 -317.011432)
			(xy 332.091284 -316.985904) (xy 332.096717 -316.977131) (xy 332.10086 -316.95694) (xy 332.096748 -316.936743)
			(xy 332.091284 -316.927992) (xy 332.074258 -316.902448) (xy 332.045745 -316.848083) (xy 332.023979 -316.790682)
			(xy 332.009276 -316.73108) (xy 332.00185 -316.670142) (xy 332.001368 -316.639448) (xy 332.001883 -316.608718)
			(xy 332.009285 -316.547705) (xy 332.023989 -316.488029) (xy 332.045778 -316.430561) (xy 332.074336 -316.376139)
			(xy 332.109245 -316.325555) (xy 332.149997 -316.279548) (xy 332.195998 -316.23879) (xy 332.246577 -316.203873)
			(xy 332.300995 -316.175307) (xy 332.358461 -316.15351) (xy 332.418134 -316.138798) (xy 332.479146 -316.131387)
			(xy 332.509876 -316.13094) (xy 332.540573 -316.131387) (xy 332.601519 -316.138794) (xy 332.661128 -316.153492)
			(xy 332.718532 -316.175266) (xy 332.772894 -316.203799) (xy 332.79842 -316.220856) (xy 332.807172 -316.226327)
			(xy 332.827376 -316.230455) (xy 332.84758 -316.226327) (xy 332.856332 -316.220856) (xy 332.881867 -316.203816)
			(xy 332.936235 -316.175306) (xy 332.993638 -316.153543) (xy 333.053242 -316.138843) (xy 333.114181 -316.13142)
			(xy 333.144876 -316.13094) (xy 333.175573 -316.131387) (xy 333.236519 -316.138794) (xy 333.296128 -316.153492)
			(xy 333.353532 -316.175266) (xy 333.407894 -316.203799) (xy 333.43342 -316.220856) (xy 333.442172 -316.226327)
			(xy 333.462376 -316.230455) (xy 333.48258 -316.226327) (xy 333.491332 -316.220856) (xy 333.516867 -316.203816)
			(xy 333.571235 -316.175306) (xy 333.628638 -316.153543) (xy 333.688242 -316.138843) (xy 333.749181 -316.13142)
			(xy 333.779876 -316.13094) (xy 333.810609 -316.13136) (xy 333.871628 -316.138767) (xy 333.93131 -316.153476)
			(xy 333.988782 -316.175271) (xy 334.043209 -316.203836) (xy 334.093795 -316.238754) (xy 334.139803 -316.279514)
			(xy 334.180561 -316.325524) (xy 334.215476 -316.376112) (xy 334.244039 -316.43054) (xy 334.265832 -316.488013)
			(xy 334.280537 -316.547695) (xy 334.287941 -316.608715) (xy 334.288384 -316.639448) (xy 334.287919 -316.670145)
			(xy 334.280515 -316.73109) (xy 334.265821 -316.790699) (xy 334.244051 -316.848103) (xy 334.215523 -316.902465)
			(xy 334.198468 -316.927992) (xy 334.192957 -316.936723) (xy 334.188845 -316.95694) (xy 334.192989 -316.977151)
			(xy 334.198468 -316.985904) (xy 334.215499 -317.011445) (xy 334.24401 -317.065811) (xy 334.265774 -317.123213)
			(xy 334.280476 -317.182816) (xy 334.287902 -317.243754) (xy 334.288384 -317.274448) (xy 334.287919 -317.305145)
			(xy 334.280515 -317.36609) (xy 334.265821 -317.425699) (xy 334.244051 -317.483103) (xy 334.215523 -317.537465)
			(xy 334.198468 -317.562992) (xy 334.192957 -317.571723) (xy 334.188845 -317.59194) (xy 334.192989 -317.612151)
			(xy 334.198468 -317.620904) (xy 334.215499 -317.646445) (xy 334.24401 -317.700811) (xy 334.265774 -317.758213)
			(xy 334.280476 -317.817816) (xy 334.287902 -317.878754) (xy 334.288384 -317.909448) (xy 334.287919 -317.940145)
			(xy 334.280515 -318.00109) (xy 334.265821 -318.060699) (xy 334.244051 -318.118103) (xy 334.215523 -318.172465)
			(xy 334.198468 -318.197992) (xy 334.192957 -318.206723) (xy 334.188845 -318.22694) (xy 334.192989 -318.247151)
			(xy 334.198468 -318.255904) (xy 334.215499 -318.281445) (xy 334.24401 -318.335811) (xy 334.265774 -318.393213)
			(xy 334.280476 -318.452816) (xy 334.287902 -318.513754) (xy 334.288384 -318.544448) (xy 334.287919 -318.575145)
			(xy 334.280515 -318.63609) (xy 334.265821 -318.695699) (xy 334.244051 -318.753103) (xy 334.215523 -318.807465)
			(xy 334.198468 -318.832992) (xy 334.192957 -318.841723) (xy 334.188845 -318.86194) (xy 334.192989 -318.882151)
			(xy 334.198468 -318.890904) (xy 334.215499 -318.916445) (xy 334.24401 -318.970811) (xy 334.265774 -319.028213)
			(xy 334.280476 -319.087816) (xy 334.287902 -319.148754) (xy 334.288384 -319.179448) (xy 334.287919 -319.210145)
			(xy 334.280515 -319.27109) (xy 334.265821 -319.330699) (xy 334.244051 -319.388103) (xy 334.215523 -319.442465)
			(xy 334.198468 -319.467992) (xy 334.192957 -319.476723) (xy 334.188845 -319.49694) (xy 334.192989 -319.517151)
			(xy 334.198468 -319.525904) (xy 334.215499 -319.551445) (xy 334.24401 -319.605811) (xy 334.265774 -319.663213)
			(xy 334.280476 -319.722816) (xy 334.287902 -319.783754) (xy 334.288384 -319.814448) (xy 334.287933 -319.843401)
			(xy 334.281326 -319.900929) (xy 334.268239 -319.957336) (xy 334.248838 -320.011896) (xy 334.223375 -320.063903)
			(xy 334.20812 -320.088514) (xy 334.202941 -320.097519) (xy 334.199528 -320.117985) (xy 334.204516 -320.138125)
			(xy 334.210406 -320.14668) (xy 334.229953 -320.173291) (xy 334.26271 -320.230623) (xy 334.287772 -320.291712)
			(xy 334.304716 -320.35553) (xy 334.313259 -320.421005) (xy 334.313784 -320.45402) (xy 334.313305 -320.484716)
			(xy 334.305904 -320.545661) (xy 334.291214 -320.60527) (xy 334.269447 -320.662674) (xy 334.240921 -320.717037)
			(xy 334.223868 -320.742564) (xy 334.218381 -320.751307) (xy 334.214261 -320.771517) (xy 334.218394 -320.791723)
			(xy 334.223868 -320.800476) (xy 334.24093 -320.825997) (xy 334.269436 -320.880369) (xy 334.291194 -320.937776)
			(xy 334.305888 -320.997383) (xy 334.313307 -321.058324) (xy 334.313784 -321.08902) (xy 334.313305 -321.119716)
			(xy 334.305904 -321.180661) (xy 334.291214 -321.24027) (xy 334.269447 -321.297674) (xy 334.240921 -321.352037)
			(xy 334.223868 -321.377564) (xy 334.218381 -321.386307) (xy 334.214261 -321.406517) (xy 334.218394 -321.426723)
			(xy 334.223868 -321.435476) (xy 334.24093 -321.460997) (xy 334.269436 -321.515369) (xy 334.291194 -321.572776)
			(xy 334.305888 -321.632383) (xy 334.313307 -321.693324) (xy 334.313784 -321.72402) (xy 334.313305 -321.754716)
			(xy 334.305904 -321.815661) (xy 334.291214 -321.87527) (xy 334.269447 -321.932674) (xy 334.240921 -321.987037)
			(xy 334.223868 -322.012564) (xy 334.218381 -322.021307) (xy 334.214261 -322.041517) (xy 334.218394 -322.061723)
			(xy 334.223868 -322.070476) (xy 334.24093 -322.095997) (xy 334.269436 -322.150369) (xy 334.291194 -322.207776)
			(xy 334.305888 -322.267383) (xy 334.313307 -322.328324) (xy 334.313784 -322.35902) (xy 334.313223 -322.392392)
			(xy 334.304482 -322.458561) (xy 334.287154 -322.523017) (xy 334.261537 -322.584649) (xy 334.228071 -322.642397)
			(xy 334.20812 -322.669154) (xy 334.202149 -322.677773) (xy 334.197101 -322.698104) (xy 334.20056 -322.718764)
			(xy 334.205834 -322.727828) (xy 334.221366 -322.752554) (xy 334.247257 -322.804895) (xy 334.266979 -322.859858)
			(xy 334.280272 -322.916719) (xy 334.286961 -322.974729) (xy 334.287368 -323.003926) (xy 336.038952 -323.003926)
			(xy 336.03942 -322.972584) (xy 336.047128 -322.910377) (xy 336.06242 -322.849588) (xy 336.085062 -322.791137)
			(xy 336.114712 -322.73591) (xy 336.132424 -322.710048) (xy 336.137984 -322.701224) (xy 336.142231 -322.680831)
			(xy 336.138009 -322.660434) (xy 336.132424 -322.651628) (xy 336.114873 -322.625849) (xy 336.085524 -322.57082)
			(xy 336.063127 -322.512614) (xy 336.048018 -322.452106) (xy 336.040424 -322.390203) (xy 336.039968 -322.35902)
			(xy 336.040425 -322.328323) (xy 336.047832 -322.267378) (xy 336.062528 -322.207769) (xy 336.0843 -322.150366)
			(xy 336.112829 -322.096003) (xy 336.129884 -322.070476) (xy 336.13534 -322.061715) (xy 336.139476 -322.041517)
			(xy 336.135353 -322.021315) (xy 336.129884 -322.012564) (xy 336.112845 -321.987028) (xy 336.084335 -321.93266)
			(xy 336.062571 -321.875258) (xy 336.047871 -321.815654) (xy 336.040448 -321.754715) (xy 336.039968 -321.72402)
			(xy 336.040425 -321.693323) (xy 336.047832 -321.632378) (xy 336.062528 -321.572769) (xy 336.0843 -321.515366)
			(xy 336.112829 -321.461003) (xy 336.129884 -321.435476) (xy 336.13534 -321.426715) (xy 336.139476 -321.406517)
			(xy 336.135353 -321.386315) (xy 336.129884 -321.377564) (xy 336.112845 -321.352028) (xy 336.084335 -321.29766)
			(xy 336.062571 -321.240258) (xy 336.047871 -321.180654) (xy 336.040448 -321.119715) (xy 336.039968 -321.08902)
			(xy 336.040425 -321.058323) (xy 336.047832 -320.997378) (xy 336.062528 -320.937769) (xy 336.0843 -320.880366)
			(xy 336.112829 -320.826003) (xy 336.129884 -320.800476) (xy 336.13534 -320.791715) (xy 336.139476 -320.771517)
			(xy 336.135353 -320.751315) (xy 336.129884 -320.742564) (xy 336.112845 -320.717028) (xy 336.084335 -320.66266)
			(xy 336.062571 -320.605258) (xy 336.047871 -320.545654) (xy 336.040448 -320.484715) (xy 336.039968 -320.45402)
			(xy 336.040459 -320.423048) (xy 336.047984 -320.361562) (xy 336.062926 -320.301446) (xy 336.085063 -320.243592)
			(xy 336.114066 -320.188856) (xy 336.131408 -320.16319) (xy 336.136851 -320.154422) (xy 336.140988 -320.134228)
			(xy 336.136873 -320.11403) (xy 336.131408 -320.105278) (xy 336.114037 -320.079629) (xy 336.08503 -320.024891)
			(xy 336.062891 -319.967033) (xy 336.047949 -319.906913) (xy 336.040426 -319.845423) (xy 336.039968 -319.814448)
			(xy 336.04044 -319.783752) (xy 336.047843 -319.722807) (xy 336.062536 -319.663198) (xy 336.084304 -319.605794)
			(xy 336.11283 -319.551432) (xy 336.129884 -319.525904) (xy 336.135317 -319.517131) (xy 336.13946 -319.49694)
			(xy 336.135348 -319.476743) (xy 336.129884 -319.467992) (xy 336.112858 -319.442448) (xy 336.084345 -319.388083)
			(xy 336.062579 -319.330682) (xy 336.047876 -319.27108) (xy 336.04045 -319.210142) (xy 336.039968 -319.179448)
			(xy 336.04044 -319.148752) (xy 336.047843 -319.087807) (xy 336.062536 -319.028198) (xy 336.084304 -318.970794)
			(xy 336.11283 -318.916432) (xy 336.129884 -318.890904) (xy 336.135317 -318.882131) (xy 336.13946 -318.86194)
			(xy 336.135348 -318.841743) (xy 336.129884 -318.832992) (xy 336.112858 -318.807448) (xy 336.084345 -318.753083)
			(xy 336.062579 -318.695682) (xy 336.047876 -318.63608) (xy 336.04045 -318.575142) (xy 336.039968 -318.544448)
			(xy 336.04044 -318.513752) (xy 336.047843 -318.452807) (xy 336.062536 -318.393198) (xy 336.084304 -318.335794)
			(xy 336.11283 -318.281432) (xy 336.129884 -318.255904) (xy 336.135317 -318.247131) (xy 336.13946 -318.22694)
			(xy 336.135348 -318.206743) (xy 336.129884 -318.197992) (xy 336.112858 -318.172448) (xy 336.084345 -318.118083)
			(xy 336.062579 -318.060682) (xy 336.047876 -318.00108) (xy 336.04045 -317.940142) (xy 336.039968 -317.909448)
			(xy 336.04044 -317.878752) (xy 336.047843 -317.817807) (xy 336.062536 -317.758198) (xy 336.084304 -317.700794)
			(xy 336.11283 -317.646432) (xy 336.129884 -317.620904) (xy 336.135317 -317.612131) (xy 336.13946 -317.59194)
			(xy 336.135348 -317.571743) (xy 336.129884 -317.562992) (xy 336.112858 -317.537448) (xy 336.084345 -317.483083)
			(xy 336.062579 -317.425682) (xy 336.047876 -317.36608) (xy 336.04045 -317.305142) (xy 336.039968 -317.274448)
			(xy 336.04044 -317.243752) (xy 336.047843 -317.182807) (xy 336.062536 -317.123198) (xy 336.084304 -317.065794)
			(xy 336.11283 -317.011432) (xy 336.129884 -316.985904) (xy 336.135317 -316.977131) (xy 336.13946 -316.95694)
			(xy 336.135348 -316.936743) (xy 336.129884 -316.927992) (xy 336.112858 -316.902448) (xy 336.084345 -316.848083)
			(xy 336.062579 -316.790682) (xy 336.047876 -316.73108) (xy 336.04045 -316.670142) (xy 336.039968 -316.639448)
			(xy 336.040483 -316.608718) (xy 336.047885 -316.547705) (xy 336.062589 -316.488029) (xy 336.084378 -316.430561)
			(xy 336.112936 -316.376139) (xy 336.147845 -316.325555) (xy 336.188597 -316.279548) (xy 336.234598 -316.23879)
			(xy 336.285177 -316.203873) (xy 336.339595 -316.175307) (xy 336.397061 -316.15351) (xy 336.456734 -316.138798)
			(xy 336.517746 -316.131387) (xy 336.548476 -316.13094) (xy 336.579173 -316.131387) (xy 336.640119 -316.138794)
			(xy 336.699728 -316.153492) (xy 336.757132 -316.175266) (xy 336.811494 -316.203799) (xy 336.83702 -316.220856)
			(xy 336.845772 -316.226327) (xy 336.865976 -316.230455) (xy 336.88618 -316.226327) (xy 336.894932 -316.220856)
			(xy 336.920467 -316.203816) (xy 336.974835 -316.175306) (xy 337.032238 -316.153543) (xy 337.091842 -316.138843)
			(xy 337.152781 -316.13142) (xy 337.183476 -316.13094) (xy 337.214173 -316.131387) (xy 337.275119 -316.138794)
			(xy 337.334728 -316.153492) (xy 337.392132 -316.175266) (xy 337.446494 -316.203799) (xy 337.47202 -316.220856)
			(xy 337.480772 -316.226327) (xy 337.500976 -316.230455) (xy 337.52118 -316.226327) (xy 337.529932 -316.220856)
			(xy 337.555467 -316.203816) (xy 337.609835 -316.175306) (xy 337.667238 -316.153543) (xy 337.726842 -316.138843)
			(xy 337.787781 -316.13142) (xy 337.818476 -316.13094) (xy 337.849209 -316.13136) (xy 337.910228 -316.138767)
			(xy 337.96991 -316.153476) (xy 338.027382 -316.175271) (xy 338.081809 -316.203836) (xy 338.132395 -316.238754)
			(xy 338.178403 -316.279514) (xy 338.219161 -316.325524) (xy 338.254076 -316.376112) (xy 338.282639 -316.43054)
			(xy 338.304432 -316.488013) (xy 338.319137 -316.547695) (xy 338.326541 -316.608715) (xy 338.326984 -316.639448)
			(xy 338.326519 -316.670145) (xy 338.319115 -316.73109) (xy 338.304421 -316.790699) (xy 338.282651 -316.848103)
			(xy 338.254123 -316.902465) (xy 338.237068 -316.927992) (xy 338.231557 -316.936723) (xy 338.227445 -316.95694)
			(xy 338.231589 -316.977151) (xy 338.237068 -316.985904) (xy 338.254099 -317.011445) (xy 338.28261 -317.065811)
			(xy 338.304374 -317.123213) (xy 338.319076 -317.182816) (xy 338.326502 -317.243754) (xy 338.326984 -317.274448)
			(xy 338.326519 -317.305145) (xy 338.319115 -317.36609) (xy 338.304421 -317.425699) (xy 338.282651 -317.483103)
			(xy 338.254123 -317.537465) (xy 338.237068 -317.562992) (xy 338.231557 -317.571723) (xy 338.227445 -317.59194)
			(xy 338.231589 -317.612151) (xy 338.237068 -317.620904) (xy 338.254099 -317.646445) (xy 338.28261 -317.700811)
			(xy 338.304374 -317.758213) (xy 338.319076 -317.817816) (xy 338.326502 -317.878754) (xy 338.326984 -317.909448)
			(xy 338.326519 -317.940145) (xy 338.319115 -318.00109) (xy 338.304421 -318.060699) (xy 338.282651 -318.118103)
			(xy 338.254123 -318.172465) (xy 338.237068 -318.197992) (xy 338.231557 -318.206723) (xy 338.227445 -318.22694)
			(xy 338.231589 -318.247151) (xy 338.237068 -318.255904) (xy 338.254099 -318.281445) (xy 338.28261 -318.335811)
			(xy 338.304374 -318.393213) (xy 338.319076 -318.452816) (xy 338.326502 -318.513754) (xy 338.326984 -318.544448)
			(xy 338.326519 -318.575145) (xy 338.319115 -318.63609) (xy 338.304421 -318.695699) (xy 338.282651 -318.753103)
			(xy 338.254123 -318.807465) (xy 338.237068 -318.832992) (xy 338.231557 -318.841723) (xy 338.227445 -318.86194)
			(xy 338.231589 -318.882151) (xy 338.237068 -318.890904) (xy 338.254099 -318.916445) (xy 338.28261 -318.970811)
			(xy 338.304374 -319.028213) (xy 338.319076 -319.087816) (xy 338.326502 -319.148754) (xy 338.326984 -319.179448)
			(xy 338.326519 -319.210145) (xy 338.319115 -319.27109) (xy 338.304421 -319.330699) (xy 338.282651 -319.388103)
			(xy 338.254123 -319.442465) (xy 338.237068 -319.467992) (xy 338.231557 -319.476723) (xy 338.227445 -319.49694)
			(xy 338.231589 -319.517151) (xy 338.237068 -319.525904) (xy 338.254099 -319.551445) (xy 338.28261 -319.605811)
			(xy 338.304374 -319.663213) (xy 338.319076 -319.722816) (xy 338.326502 -319.783754) (xy 338.326984 -319.814448)
			(xy 338.326765 -319.828926) (xy 340.255352 -319.828926) (xy 340.255798 -319.798229) (xy 340.263205 -319.737283)
			(xy 340.277903 -319.677673) (xy 340.299678 -319.62027) (xy 340.328211 -319.565908) (xy 340.345268 -319.540382)
			(xy 340.350721 -319.531619) (xy 340.354859 -319.511422) (xy 340.350738 -319.491221) (xy 340.345268 -319.48247)
			(xy 340.32823 -319.456934) (xy 340.29972 -319.402566) (xy 340.277956 -319.345163) (xy 340.263256 -319.28556)
			(xy 340.255832 -319.224621) (xy 340.255352 -319.193926) (xy 340.255798 -319.163229) (xy 340.263205 -319.102283)
			(xy 340.277903 -319.042673) (xy 340.299678 -318.98527) (xy 340.328211 -318.930908) (xy 340.345268 -318.905382)
			(xy 340.350721 -318.896619) (xy 340.354859 -318.876422) (xy 340.350738 -318.856221) (xy 340.345268 -318.84747)
			(xy 340.32823 -318.821934) (xy 340.29972 -318.767566) (xy 340.277956 -318.710163) (xy 340.263256 -318.65056)
			(xy 340.255832 -318.589621) (xy 340.255352 -318.558926) (xy 340.255798 -318.528229) (xy 340.263205 -318.467283)
			(xy 340.277903 -318.407673) (xy 340.299678 -318.35027) (xy 340.328211 -318.295908) (xy 340.345268 -318.270382)
			(xy 340.350721 -318.261619) (xy 340.354859 -318.241422) (xy 340.350738 -318.221221) (xy 340.345268 -318.21247)
			(xy 340.32823 -318.186934) (xy 340.29972 -318.132566) (xy 340.277956 -318.075163) (xy 340.263256 -318.01556)
			(xy 340.255832 -317.954621) (xy 340.255352 -317.923926) (xy 340.255798 -317.893229) (xy 340.263205 -317.832283)
			(xy 340.277903 -317.772673) (xy 340.299678 -317.71527) (xy 340.328211 -317.660908) (xy 340.345268 -317.635382)
			(xy 340.350721 -317.626619) (xy 340.354859 -317.606422) (xy 340.350738 -317.586221) (xy 340.345268 -317.57747)
			(xy 340.32823 -317.551934) (xy 340.29972 -317.497566) (xy 340.277956 -317.440163) (xy 340.263256 -317.38056)
			(xy 340.255832 -317.319621) (xy 340.255352 -317.288926) (xy 340.255798 -317.258229) (xy 340.263205 -317.197283)
			(xy 340.277903 -317.137673) (xy 340.299678 -317.08027) (xy 340.328211 -317.025908) (xy 340.345268 -317.000382)
			(xy 340.350721 -316.991619) (xy 340.354859 -316.971422) (xy 340.350738 -316.951221) (xy 340.345268 -316.94247)
			(xy 340.32823 -316.916934) (xy 340.29972 -316.862566) (xy 340.277956 -316.805163) (xy 340.263256 -316.74556)
			(xy 340.255832 -316.684621) (xy 340.255352 -316.653926) (xy 340.25588 -316.623197) (xy 340.263285 -316.562187)
			(xy 340.27799 -316.502514) (xy 340.29978 -316.445049) (xy 340.328337 -316.390629) (xy 340.363246 -316.340048)
			(xy 340.403997 -316.294044) (xy 340.449996 -316.253287) (xy 340.500573 -316.218371) (xy 340.554989 -316.189807)
			(xy 340.612451 -316.168009) (xy 340.672122 -316.153297) (xy 340.733131 -316.145884) (xy 340.76386 -316.145418)
			(xy 340.794557 -316.145877) (xy 340.855502 -316.153282) (xy 340.915111 -316.167977) (xy 340.972515 -316.189749)
			(xy 341.026877 -316.218279) (xy 341.052404 -316.235334) (xy 341.061156 -316.240805) (xy 341.08136 -316.244933)
			(xy 341.101564 -316.240805) (xy 341.110316 -316.235334) (xy 341.135853 -316.218298) (xy 341.190221 -316.189788)
			(xy 341.247623 -316.168025) (xy 341.307227 -316.153324) (xy 341.368166 -316.145899) (xy 341.39886 -316.145418)
			(xy 341.429557 -316.145877) (xy 341.490502 -316.153282) (xy 341.550111 -316.167977) (xy 341.607515 -316.189749)
			(xy 341.661877 -316.218279) (xy 341.687404 -316.235334) (xy 341.696156 -316.240805) (xy 341.71636 -316.244933)
			(xy 341.736564 -316.240805) (xy 341.745316 -316.235334) (xy 341.770853 -316.218298) (xy 341.825221 -316.189788)
			(xy 341.882623 -316.168025) (xy 341.942227 -316.153324) (xy 342.003166 -316.145899) (xy 342.03386 -316.145418)
			(xy 342.064592 -316.145875) (xy 342.125609 -316.15328) (xy 342.185288 -316.167986) (xy 342.24276 -316.189779)
			(xy 342.297185 -316.21834) (xy 342.34777 -316.253255) (xy 342.393778 -316.294012) (xy 342.434537 -316.340019)
			(xy 342.469452 -316.390603) (xy 342.498016 -316.445028) (xy 342.51981 -316.502498) (xy 342.534518 -316.562177)
			(xy 342.541924 -316.623194) (xy 342.542368 -316.653926) (xy 342.541894 -316.684622) (xy 342.534493 -316.745567)
			(xy 342.519801 -316.805176) (xy 342.498033 -316.86258) (xy 342.469506 -316.916943) (xy 342.452452 -316.94247)
			(xy 342.446962 -316.951211) (xy 342.442844 -316.971422) (xy 342.446979 -316.991629) (xy 342.452452 -317.000382)
			(xy 342.469472 -317.02593) (xy 342.497985 -317.080295) (xy 342.519752 -317.137694) (xy 342.534456 -317.197295)
			(xy 342.541885 -317.258232) (xy 342.542368 -317.288926) (xy 342.541894 -317.319622) (xy 342.534493 -317.380567)
			(xy 342.519801 -317.440176) (xy 342.498033 -317.49758) (xy 342.469506 -317.551943) (xy 342.452452 -317.57747)
			(xy 342.446962 -317.586211) (xy 342.442844 -317.606422) (xy 342.446979 -317.626629) (xy 342.452452 -317.635382)
			(xy 342.469472 -317.66093) (xy 342.497985 -317.715295) (xy 342.519752 -317.772694) (xy 342.534456 -317.832295)
			(xy 342.541885 -317.893232) (xy 342.542368 -317.923926) (xy 342.541894 -317.954622) (xy 342.534493 -318.015567)
			(xy 342.519801 -318.075176) (xy 342.498033 -318.13258) (xy 342.469506 -318.186943) (xy 342.452452 -318.21247)
			(xy 342.446962 -318.221211) (xy 342.442844 -318.241422) (xy 342.446979 -318.261629) (xy 342.452452 -318.270382)
			(xy 342.469472 -318.29593) (xy 342.497985 -318.350295) (xy 342.519752 -318.407694) (xy 342.534456 -318.467295)
			(xy 342.541885 -318.528232) (xy 342.542368 -318.558926) (xy 342.541894 -318.589622) (xy 342.534493 -318.650567)
			(xy 342.519801 -318.710176) (xy 342.498033 -318.76758) (xy 342.469506 -318.821943) (xy 342.452452 -318.84747)
			(xy 342.446962 -318.856211) (xy 342.442844 -318.876422) (xy 342.446979 -318.896629) (xy 342.452452 -318.905382)
			(xy 342.469472 -318.93093) (xy 342.497985 -318.985295) (xy 342.519752 -319.042694) (xy 342.534456 -319.102295)
			(xy 342.541885 -319.163232) (xy 342.542368 -319.193926) (xy 342.541894 -319.224622) (xy 342.534493 -319.285567)
			(xy 342.519801 -319.345176) (xy 342.498033 -319.40258) (xy 342.469506 -319.456943) (xy 342.452452 -319.48247)
			(xy 342.446962 -319.491211) (xy 342.442844 -319.511422) (xy 342.446979 -319.531629) (xy 342.452452 -319.540382)
			(xy 342.469472 -319.56593) (xy 342.497985 -319.620295) (xy 342.519752 -319.677694) (xy 342.534456 -319.737295)
			(xy 342.541885 -319.798232) (xy 342.542368 -319.828926) (xy 342.541957 -319.85788) (xy 342.535341 -319.915409)
			(xy 342.522245 -319.971817) (xy 342.502835 -320.026376) (xy 342.477364 -320.078382) (xy 342.462104 -320.102992)
			(xy 342.456858 -320.111964) (xy 342.45347 -320.132451) (xy 342.458486 -320.152603) (xy 342.46439 -320.161158)
			(xy 342.483925 -320.187778) (xy 342.516684 -320.245107) (xy 342.541749 -320.306193) (xy 342.558696 -320.37001)
			(xy 342.567242 -320.435484) (xy 342.567768 -320.468498) (xy 342.567331 -320.499195) (xy 342.559921 -320.560142)
			(xy 342.545221 -320.619751) (xy 342.523445 -320.677155) (xy 342.49491 -320.731516) (xy 342.477852 -320.757042)
			(xy 342.472385 -320.765796) (xy 342.46826 -320.785998) (xy 342.472384 -320.806201) (xy 342.477852 -320.814954)
			(xy 342.494903 -320.840482) (xy 342.52341 -320.894852) (xy 342.545171 -320.952257) (xy 342.559868 -321.011862)
			(xy 342.567289 -321.072803) (xy 342.567768 -321.103498) (xy 342.567331 -321.134195) (xy 342.559921 -321.195142)
			(xy 342.545221 -321.254751) (xy 342.523445 -321.312155) (xy 342.49491 -321.366516) (xy 342.477852 -321.392042)
			(xy 342.472385 -321.400796) (xy 342.46826 -321.420998) (xy 342.472384 -321.441201) (xy 342.477852 -321.449954)
			(xy 342.494903 -321.475482) (xy 342.52341 -321.529852) (xy 342.545171 -321.587257) (xy 342.559868 -321.646862)
			(xy 342.567289 -321.707803) (xy 342.567768 -321.738498) (xy 342.567331 -321.769195) (xy 342.559921 -321.830142)
			(xy 342.545221 -321.889751) (xy 342.523445 -321.947155) (xy 342.49491 -322.001516) (xy 342.477852 -322.027042)
			(xy 342.472385 -322.035796) (xy 342.46826 -322.055998) (xy 342.472384 -322.076201) (xy 342.477852 -322.084954)
			(xy 342.494903 -322.110482) (xy 342.52341 -322.164852) (xy 342.545171 -322.222257) (xy 342.559868 -322.281862)
			(xy 342.567289 -322.342803) (xy 342.567768 -322.373498) (xy 342.567307 -322.405372) (xy 342.559366 -322.468624)
			(xy 342.543573 -322.530384) (xy 342.520175 -322.589682) (xy 342.48954 -322.645586) (xy 342.471248 -322.671694)
			(xy 342.465459 -322.680619) (xy 342.461065 -322.70141) (xy 342.465467 -322.722199) (xy 342.471248 -322.73113)
			(xy 342.489538 -322.757235) (xy 342.520133 -322.813155) (xy 342.543511 -322.872456) (xy 342.559305 -322.934211)
			(xy 342.56727 -322.997455) (xy 342.567768 -323.029326) (xy 344.293952 -323.029326) (xy 344.294422 -322.997452)
			(xy 344.30236 -322.934201) (xy 344.318151 -322.87244) (xy 344.341547 -322.813142) (xy 344.372181 -322.757238)
			(xy 344.390472 -322.73113) (xy 344.396238 -322.722192) (xy 344.400637 -322.70141) (xy 344.396246 -322.680626)
			(xy 344.390472 -322.671694) (xy 344.372196 -322.64558) (xy 344.341597 -322.589662) (xy 344.318216 -322.530364)
			(xy 344.302419 -322.468611) (xy 344.294452 -322.405369) (xy 344.293952 -322.373498) (xy 344.294434 -322.342802)
			(xy 344.301833 -322.281857) (xy 344.316523 -322.222248) (xy 344.338289 -322.164844) (xy 344.366814 -322.110481)
			(xy 344.383868 -322.084954) (xy 344.389344 -322.076204) (xy 344.393475 -322.055998) (xy 344.389343 -322.035793)
			(xy 344.383868 -322.027042) (xy 344.366818 -322.001514) (xy 344.33831 -321.947144) (xy 344.316549 -321.889739)
			(xy 344.301851 -321.830134) (xy 344.294431 -321.769193) (xy 344.293952 -321.738498) (xy 344.294434 -321.707802)
			(xy 344.301833 -321.646857) (xy 344.316523 -321.587248) (xy 344.338289 -321.529844) (xy 344.366814 -321.475481)
			(xy 344.383868 -321.449954) (xy 344.389344 -321.441204) (xy 344.393475 -321.420998) (xy 344.389343 -321.400793)
			(xy 344.383868 -321.392042) (xy 344.366818 -321.366514) (xy 344.33831 -321.312144) (xy 344.316549 -321.254739)
			(xy 344.301851 -321.195134) (xy 344.294431 -321.134193) (xy 344.293952 -321.103498) (xy 344.294434 -321.072802)
			(xy 344.301833 -321.011857) (xy 344.316523 -320.952248) (xy 344.338289 -320.894844) (xy 344.366814 -320.840481)
			(xy 344.383868 -320.814954) (xy 344.389344 -320.806204) (xy 344.393475 -320.785998) (xy 344.389343 -320.765793)
			(xy 344.383868 -320.757042) (xy 344.366818 -320.731514) (xy 344.33831 -320.677144) (xy 344.316549 -320.619739)
			(xy 344.301851 -320.560134) (xy 344.294431 -320.499193) (xy 344.293952 -320.468498) (xy 344.294434 -320.437525)
			(xy 344.301962 -320.376039) (xy 344.316906 -320.315923) (xy 344.339044 -320.258069) (xy 344.368049 -320.203334)
			(xy 344.385392 -320.177668) (xy 344.390855 -320.168911) (xy 344.394988 -320.14871) (xy 344.390863 -320.128507)
			(xy 344.385392 -320.119756) (xy 344.368065 -320.094078) (xy 344.339049 -320.039349) (xy 344.3169 -319.981499)
			(xy 344.301948 -319.921385) (xy 344.294414 -319.859899) (xy 344.293952 -319.828926) (xy 344.294398 -319.798229)
			(xy 344.301805 -319.737283) (xy 344.316503 -319.677673) (xy 344.338278 -319.62027) (xy 344.366811 -319.565908)
			(xy 344.383868 -319.540382) (xy 344.389321 -319.531619) (xy 344.393459 -319.511422) (xy 344.389338 -319.491221)
			(xy 344.383868 -319.48247) (xy 344.36683 -319.456934) (xy 344.33832 -319.402566) (xy 344.316556 -319.345163)
			(xy 344.301856 -319.28556) (xy 344.294432 -319.224621) (xy 344.293952 -319.193926) (xy 344.294398 -319.163229)
			(xy 344.301805 -319.102283) (xy 344.316503 -319.042673) (xy 344.338278 -318.98527) (xy 344.366811 -318.930908)
			(xy 344.383868 -318.905382) (xy 344.389321 -318.896619) (xy 344.393459 -318.876422) (xy 344.389338 -318.856221)
			(xy 344.383868 -318.84747) (xy 344.36683 -318.821934) (xy 344.33832 -318.767566) (xy 344.316556 -318.710163)
			(xy 344.301856 -318.65056) (xy 344.294432 -318.589621) (xy 344.293952 -318.558926) (xy 344.294398 -318.528229)
			(xy 344.301805 -318.467283) (xy 344.316503 -318.407673) (xy 344.338278 -318.35027) (xy 344.366811 -318.295908)
			(xy 344.383868 -318.270382) (xy 344.389321 -318.261619) (xy 344.393459 -318.241422) (xy 344.389338 -318.221221)
			(xy 344.383868 -318.21247) (xy 344.36683 -318.186934) (xy 344.33832 -318.132566) (xy 344.316556 -318.075163)
			(xy 344.301856 -318.01556) (xy 344.294432 -317.954621) (xy 344.293952 -317.923926) (xy 344.294398 -317.893229)
			(xy 344.301805 -317.832283) (xy 344.316503 -317.772673) (xy 344.338278 -317.71527) (xy 344.366811 -317.660908)
			(xy 344.383868 -317.635382) (xy 344.389321 -317.626619) (xy 344.393459 -317.606422) (xy 344.389338 -317.586221)
			(xy 344.383868 -317.57747) (xy 344.36683 -317.551934) (xy 344.33832 -317.497566) (xy 344.316556 -317.440163)
			(xy 344.301856 -317.38056) (xy 344.294432 -317.319621) (xy 344.293952 -317.288926) (xy 344.294398 -317.258229)
			(xy 344.301805 -317.197283) (xy 344.316503 -317.137673) (xy 344.338278 -317.08027) (xy 344.366811 -317.025908)
			(xy 344.383868 -317.000382) (xy 344.389321 -316.991619) (xy 344.393459 -316.971422) (xy 344.389338 -316.951221)
			(xy 344.383868 -316.94247) (xy 344.36683 -316.916934) (xy 344.33832 -316.862566) (xy 344.316556 -316.805163)
			(xy 344.301856 -316.74556) (xy 344.294432 -316.684621) (xy 344.293952 -316.653926) (xy 344.29448 -316.623197)
			(xy 344.301885 -316.562187) (xy 344.31659 -316.502514) (xy 344.33838 -316.445049) (xy 344.366937 -316.390629)
			(xy 344.401846 -316.340048) (xy 344.442597 -316.294044) (xy 344.488596 -316.253287) (xy 344.539173 -316.218371)
			(xy 344.593589 -316.189807) (xy 344.651051 -316.168009) (xy 344.710722 -316.153297) (xy 344.771731 -316.145884)
			(xy 344.80246 -316.145418) (xy 344.833157 -316.145877) (xy 344.894102 -316.153282) (xy 344.953711 -316.167977)
			(xy 345.011115 -316.189749) (xy 345.065477 -316.218279) (xy 345.091004 -316.235334) (xy 345.099756 -316.240805)
			(xy 345.11996 -316.244933) (xy 345.140164 -316.240805) (xy 345.148916 -316.235334) (xy 345.174453 -316.218298)
			(xy 345.228821 -316.189788) (xy 345.286223 -316.168025) (xy 345.345827 -316.153324) (xy 345.406766 -316.145899)
			(xy 345.43746 -316.145418) (xy 345.468157 -316.145877) (xy 345.529102 -316.153282) (xy 345.588711 -316.167977)
			(xy 345.646115 -316.189749) (xy 345.700477 -316.218279) (xy 345.726004 -316.235334) (xy 345.734756 -316.240805)
			(xy 345.75496 -316.244933) (xy 345.775164 -316.240805) (xy 345.783916 -316.235334) (xy 345.809453 -316.218298)
			(xy 345.863821 -316.189788) (xy 345.921223 -316.168025) (xy 345.980827 -316.153324) (xy 346.041766 -316.145899)
			(xy 346.07246 -316.145418) (xy 346.103192 -316.145875) (xy 346.164209 -316.15328) (xy 346.223888 -316.167986)
			(xy 346.28136 -316.189779) (xy 346.335785 -316.21834) (xy 346.38637 -316.253255) (xy 346.432378 -316.294012)
			(xy 346.473137 -316.340019) (xy 346.508052 -316.390603) (xy 346.536616 -316.445028) (xy 346.55841 -316.502498)
			(xy 346.573118 -316.562177) (xy 346.580524 -316.623194) (xy 346.580968 -316.653926) (xy 346.580494 -316.684622)
			(xy 346.573093 -316.745567) (xy 346.558401 -316.805176) (xy 346.536633 -316.86258) (xy 346.508106 -316.916943)
			(xy 346.491052 -316.94247) (xy 346.485562 -316.951211) (xy 346.481444 -316.971422) (xy 346.485579 -316.991629)
			(xy 346.491052 -317.000382) (xy 346.508072 -317.02593) (xy 346.536585 -317.080295) (xy 346.558352 -317.137694)
			(xy 346.573056 -317.197295) (xy 346.580485 -317.258232) (xy 346.580968 -317.288926) (xy 346.580494 -317.319622)
			(xy 346.573093 -317.380567) (xy 346.558401 -317.440176) (xy 346.536633 -317.49758) (xy 346.508106 -317.551943)
			(xy 346.491052 -317.57747) (xy 346.485562 -317.586211) (xy 346.481444 -317.606422) (xy 346.485579 -317.626629)
			(xy 346.491052 -317.635382) (xy 346.508072 -317.66093) (xy 346.536585 -317.715295) (xy 346.558352 -317.772694)
			(xy 346.573056 -317.832295) (xy 346.580485 -317.893232) (xy 346.580968 -317.923926) (xy 346.580494 -317.954622)
			(xy 346.573093 -318.015567) (xy 346.558401 -318.075176) (xy 346.536633 -318.13258) (xy 346.508106 -318.186943)
			(xy 346.491052 -318.21247) (xy 346.485562 -318.221211) (xy 346.481444 -318.241422) (xy 346.485579 -318.261629)
			(xy 346.491052 -318.270382) (xy 346.508072 -318.29593) (xy 346.536585 -318.350295) (xy 346.558352 -318.407694)
			(xy 346.573056 -318.467295) (xy 346.580485 -318.528232) (xy 346.580968 -318.558926) (xy 346.580494 -318.589622)
			(xy 346.573093 -318.650567) (xy 346.558401 -318.710176) (xy 346.536633 -318.76758) (xy 346.508106 -318.821943)
			(xy 346.491052 -318.84747) (xy 346.485562 -318.856211) (xy 346.481444 -318.876422) (xy 346.485579 -318.896629)
			(xy 346.491052 -318.905382) (xy 346.508072 -318.93093) (xy 346.536585 -318.985295) (xy 346.558352 -319.042694)
			(xy 346.573056 -319.102295) (xy 346.580485 -319.163232) (xy 346.580968 -319.193926) (xy 346.580494 -319.224622)
			(xy 346.573093 -319.285567) (xy 346.558401 -319.345176) (xy 346.536633 -319.40258) (xy 346.508106 -319.456943)
			(xy 346.491052 -319.48247) (xy 346.485562 -319.491211) (xy 346.481444 -319.511422) (xy 346.485579 -319.531629)
			(xy 346.491052 -319.540382) (xy 346.508072 -319.56593) (xy 346.536585 -319.620295) (xy 346.558352 -319.677694)
			(xy 346.573056 -319.737295) (xy 346.580485 -319.798232) (xy 346.580968 -319.828926) (xy 346.580459 -319.861051)
			(xy 346.572368 -319.924788) (xy 346.556318 -319.987) (xy 346.532564 -320.046697) (xy 346.501484 -320.102929)
			(xy 346.482924 -320.129154) (xy 346.476938 -320.138095) (xy 346.472446 -320.159121) (xy 346.476955 -320.180144)
			(xy 346.482924 -320.189098) (xy 346.501496 -320.215316) (xy 346.532582 -320.271547) (xy 346.55634 -320.331245)
			(xy 346.572391 -320.39346) (xy 346.580479 -320.4572) (xy 346.580968 -320.489326) (xy 346.580494 -320.520022)
			(xy 346.573093 -320.580967) (xy 346.558401 -320.640576) (xy 346.536633 -320.69798) (xy 346.508106 -320.752343)
			(xy 346.491052 -320.77787) (xy 346.485562 -320.786611) (xy 346.481444 -320.806822) (xy 346.485579 -320.827029)
			(xy 346.491052 -320.835782) (xy 346.508072 -320.86133) (xy 346.536585 -320.915695) (xy 346.558352 -320.973094)
			(xy 346.573056 -321.032695) (xy 346.580485 -321.093632) (xy 346.580968 -321.124326) (xy 346.580494 -321.155022)
			(xy 346.573093 -321.215967) (xy 346.558401 -321.275576) (xy 346.536633 -321.33298) (xy 346.508106 -321.387343)
			(xy 346.491052 -321.41287) (xy 346.485562 -321.421611) (xy 346.481444 -321.441822) (xy 346.485579 -321.462029)
			(xy 346.491052 -321.470782) (xy 346.508072 -321.49633) (xy 346.536585 -321.550695) (xy 346.558352 -321.608094)
			(xy 346.573056 -321.667695) (xy 346.580485 -321.728632) (xy 346.580968 -321.759326) (xy 346.580494 -321.790022)
			(xy 346.573093 -321.850967) (xy 346.558401 -321.910576) (xy 346.536633 -321.96798) (xy 346.508106 -322.022343)
			(xy 346.491052 -322.04787) (xy 346.485562 -322.056611) (xy 346.481444 -322.076822) (xy 346.485579 -322.097029)
			(xy 346.491052 -322.105782) (xy 346.508072 -322.13133) (xy 346.536585 -322.185695) (xy 346.558352 -322.243094)
			(xy 346.573056 -322.302695) (xy 346.580485 -322.363632) (xy 346.580968 -322.394326) (xy 346.580494 -322.425022)
			(xy 346.573093 -322.485967) (xy 346.558401 -322.545576) (xy 346.536633 -322.60298) (xy 346.508106 -322.657343)
			(xy 346.491052 -322.68287) (xy 346.485562 -322.691611) (xy 346.481444 -322.711822) (xy 346.485579 -322.732029)
			(xy 346.491052 -322.740782) (xy 346.508072 -322.76633) (xy 346.536585 -322.820695) (xy 346.558352 -322.878094)
			(xy 346.573056 -322.937695) (xy 346.580485 -322.998632) (xy 346.580968 -323.029326) (xy 346.580587 -323.06006)
			(xy 346.573174 -323.12108) (xy 346.558461 -323.180762) (xy 346.53666 -323.238234) (xy 346.508091 -323.29266)
			(xy 346.47317 -323.343246) (xy 346.432406 -323.389253) (xy 346.386394 -323.430011) (xy 346.335804 -323.464925)
			(xy 346.281374 -323.493487) (xy 346.223898 -323.51528) (xy 346.164215 -323.529986) (xy 346.103194 -323.537391)
			(xy 346.07246 -323.537834) (xy 346.041764 -323.537356) (xy 345.980819 -323.529954) (xy 345.921211 -323.515262)
			(xy 345.863807 -323.493496) (xy 345.809444 -323.464971) (xy 345.783916 -323.447918) (xy 345.775164 -323.442447)
			(xy 345.75496 -323.438319) (xy 345.734756 -323.442447) (xy 345.726004 -323.447918) (xy 345.700457 -323.46494)
			(xy 345.646093 -323.493453) (xy 345.588693 -323.51522) (xy 345.529091 -323.529924) (xy 345.468154 -323.537352)
			(xy 345.43746 -323.537834) (xy 345.406764 -323.537356) (xy 345.345819 -323.529954) (xy 345.286211 -323.515262)
			(xy 345.228807 -323.493496) (xy 345.174444 -323.464971) (xy 345.148916 -323.447918) (xy 345.140164 -323.442447)
			(xy 345.11996 -323.438319) (xy 345.099756 -323.442447) (xy 345.091004 -323.447918) (xy 345.065457 -323.46494)
			(xy 345.011093 -323.493453) (xy 344.953693 -323.51522) (xy 344.894091 -323.529924) (xy 344.833154 -323.537352)
			(xy 344.80246 -323.537834) (xy 344.771729 -323.537382) (xy 344.710716 -323.529969) (xy 344.651041 -323.515257)
			(xy 344.593574 -323.49346) (xy 344.539154 -323.464895) (xy 344.488573 -323.429979) (xy 344.442569 -323.389222)
			(xy 344.401812 -323.343216) (xy 344.366898 -323.292634) (xy 344.338335 -323.238213) (xy 344.316539 -323.180746)
			(xy 344.301828 -323.12107) (xy 344.294417 -323.060057) (xy 344.293952 -323.029326) (xy 342.567768 -323.029326)
			(xy 342.567387 -323.06006) (xy 342.559974 -323.12108) (xy 342.545261 -323.180762) (xy 342.52346 -323.238234)
			(xy 342.494891 -323.29266) (xy 342.45997 -323.343246) (xy 342.419206 -323.389253) (xy 342.373194 -323.430011)
			(xy 342.322604 -323.464925) (xy 342.268174 -323.493487) (xy 342.210698 -323.51528) (xy 342.151015 -323.529986)
			(xy 342.089994 -323.537391) (xy 342.05926 -323.537834) (xy 342.028564 -323.537356) (xy 341.967619 -323.529954)
			(xy 341.908011 -323.515262) (xy 341.850607 -323.493496) (xy 341.796244 -323.464971) (xy 341.770716 -323.447918)
			(xy 341.761964 -323.442447) (xy 341.74176 -323.438319) (xy 341.721556 -323.442447) (xy 341.712804 -323.447918)
			(xy 341.687257 -323.46494) (xy 341.632893 -323.493453) (xy 341.575493 -323.51522) (xy 341.515891 -323.529924)
			(xy 341.454954 -323.537352) (xy 341.42426 -323.537834) (xy 341.393564 -323.537356) (xy 341.332619 -323.529954)
			(xy 341.273011 -323.515262) (xy 341.215607 -323.493496) (xy 341.161244 -323.464971) (xy 341.135716 -323.447918)
			(xy 341.126964 -323.442447) (xy 341.10676 -323.438319) (xy 341.086556 -323.442447) (xy 341.077804 -323.447918)
			(xy 341.052257 -323.46494) (xy 340.997893 -323.493453) (xy 340.940493 -323.51522) (xy 340.880891 -323.529924)
			(xy 340.819954 -323.537352) (xy 340.78926 -323.537834) (xy 340.758529 -323.537382) (xy 340.697516 -323.529969)
			(xy 340.637841 -323.515257) (xy 340.580374 -323.49346) (xy 340.525954 -323.464895) (xy 340.475373 -323.429979)
			(xy 340.429369 -323.389222) (xy 340.388612 -323.343216) (xy 340.353698 -323.292634) (xy 340.325135 -323.238213)
			(xy 340.303339 -323.180746) (xy 340.288628 -323.12107) (xy 340.281217 -323.060057) (xy 340.280752 -323.029326)
			(xy 340.281198 -322.998629) (xy 340.288605 -322.937683) (xy 340.303303 -322.878073) (xy 340.325078 -322.82067)
			(xy 340.353611 -322.766308) (xy 340.370668 -322.740782) (xy 340.376121 -322.732019) (xy 340.380259 -322.711822)
			(xy 340.376138 -322.691621) (xy 340.370668 -322.68287) (xy 340.35363 -322.657334) (xy 340.32512 -322.602966)
			(xy 340.303356 -322.545563) (xy 340.288656 -322.48596) (xy 340.281232 -322.425021) (xy 340.280752 -322.394326)
			(xy 340.281198 -322.363629) (xy 340.288605 -322.302683) (xy 340.303303 -322.243073) (xy 340.325078 -322.18567)
			(xy 340.353611 -322.131308) (xy 340.370668 -322.105782) (xy 340.376121 -322.097019) (xy 340.380259 -322.076822)
			(xy 340.376138 -322.056621) (xy 340.370668 -322.04787) (xy 340.35363 -322.022334) (xy 340.32512 -321.967966)
			(xy 340.303356 -321.910563) (xy 340.288656 -321.85096) (xy 340.281232 -321.790021) (xy 340.280752 -321.759326)
			(xy 340.281198 -321.728629) (xy 340.288605 -321.667683) (xy 340.303303 -321.608073) (xy 340.325078 -321.55067)
			(xy 340.353611 -321.496308) (xy 340.370668 -321.470782) (xy 340.376121 -321.462019) (xy 340.380259 -321.441822)
			(xy 340.376138 -321.421621) (xy 340.370668 -321.41287) (xy 340.35363 -321.387334) (xy 340.32512 -321.332966)
			(xy 340.303356 -321.275563) (xy 340.288656 -321.21596) (xy 340.281232 -321.155021) (xy 340.280752 -321.124326)
			(xy 340.281198 -321.093629) (xy 340.288605 -321.032683) (xy 340.303303 -320.973073) (xy 340.325078 -320.91567)
			(xy 340.353611 -320.861308) (xy 340.370668 -320.835782) (xy 340.376121 -320.827019) (xy 340.380259 -320.806822)
			(xy 340.376138 -320.786621) (xy 340.370668 -320.77787) (xy 340.35363 -320.752334) (xy 340.32512 -320.697966)
			(xy 340.303356 -320.640563) (xy 340.288656 -320.58096) (xy 340.281232 -320.520021) (xy 340.280752 -320.489326)
			(xy 340.281194 -320.459131) (xy 340.288318 -320.399163) (xy 340.302493 -320.34046) (xy 340.32352 -320.283849)
			(xy 340.351103 -320.230126) (xy 340.36762 -320.204846) (xy 340.373212 -320.195649) (xy 340.37692 -320.17447)
			(xy 340.371632 -320.153629) (xy 340.365334 -320.144902) (xy 340.344594 -320.117824) (xy 340.309772 -320.059173)
			(xy 340.283092 -319.996399) (xy 340.265029 -319.930626) (xy 340.255907 -319.86303) (xy 340.255352 -319.828926)
			(xy 338.326765 -319.828926) (xy 338.326519 -319.845145) (xy 338.319115 -319.90609) (xy 338.304421 -319.965699)
			(xy 338.282651 -320.023103) (xy 338.254123 -320.077465) (xy 338.237068 -320.102992) (xy 338.231557 -320.111723)
			(xy 338.227445 -320.13194) (xy 338.231589 -320.152151) (xy 338.237068 -320.160904) (xy 338.254099 -320.186445)
			(xy 338.28261 -320.240811) (xy 338.304374 -320.298213) (xy 338.319076 -320.357816) (xy 338.326502 -320.418754)
			(xy 338.326984 -320.449448) (xy 338.326519 -320.480145) (xy 338.319115 -320.54109) (xy 338.304421 -320.600699)
			(xy 338.282651 -320.658103) (xy 338.254123 -320.712465) (xy 338.237068 -320.737992) (xy 338.231557 -320.746723)
			(xy 338.227445 -320.76694) (xy 338.231589 -320.787151) (xy 338.237068 -320.795904) (xy 338.254099 -320.821445)
			(xy 338.28261 -320.875811) (xy 338.304374 -320.933213) (xy 338.319076 -320.992816) (xy 338.326502 -321.053754)
			(xy 338.326984 -321.084448) (xy 338.326519 -321.115145) (xy 338.319115 -321.17609) (xy 338.304421 -321.235699)
			(xy 338.282651 -321.293103) (xy 338.254123 -321.347465) (xy 338.237068 -321.372992) (xy 338.231557 -321.381723)
			(xy 338.227445 -321.40194) (xy 338.231589 -321.422151) (xy 338.237068 -321.430904) (xy 338.254099 -321.456445)
			(xy 338.28261 -321.510811) (xy 338.304374 -321.568213) (xy 338.319076 -321.627816) (xy 338.326502 -321.688754)
			(xy 338.326984 -321.719448) (xy 338.326519 -321.750145) (xy 338.319115 -321.81109) (xy 338.304421 -321.870699)
			(xy 338.282651 -321.928103) (xy 338.254123 -321.982465) (xy 338.237068 -322.007992) (xy 338.231557 -322.016723)
			(xy 338.227445 -322.03694) (xy 338.231589 -322.057151) (xy 338.237068 -322.065904) (xy 338.254099 -322.091445)
			(xy 338.28261 -322.145811) (xy 338.304374 -322.203213) (xy 338.319076 -322.262816) (xy 338.326502 -322.323754)
			(xy 338.326984 -322.354448) (xy 338.326479 -322.386043) (xy 338.318662 -322.448746) (xy 338.303129 -322.509996)
			(xy 338.28012 -322.568847) (xy 338.24999 -322.62439) (xy 338.231988 -322.650358) (xy 338.226295 -322.65922)
			(xy 338.221995 -322.679818) (xy 338.226309 -322.700414) (xy 338.231988 -322.709286) (xy 338.249789 -322.735198)
			(xy 338.2796 -322.790548) (xy 338.302367 -322.849147) (xy 338.317744 -322.910105) (xy 338.325496 -322.972492)
			(xy 338.325968 -323.003926) (xy 338.325587 -323.03466) (xy 338.318174 -323.09568) (xy 338.303461 -323.155362)
			(xy 338.28166 -323.212834) (xy 338.253091 -323.26726) (xy 338.21817 -323.317846) (xy 338.177406 -323.363853)
			(xy 338.131394 -323.404611) (xy 338.080804 -323.439525) (xy 338.026374 -323.468087) (xy 337.968898 -323.48988)
			(xy 337.909215 -323.504586) (xy 337.848194 -323.511991) (xy 337.81746 -323.512434) (xy 337.786764 -323.511956)
			(xy 337.725819 -323.504554) (xy 337.666211 -323.489862) (xy 337.608807 -323.468096) (xy 337.554444 -323.439571)
			(xy 337.528916 -323.422518) (xy 337.520164 -323.417047) (xy 337.49996 -323.412919) (xy 337.479756 -323.417047)
			(xy 337.471004 -323.422518) (xy 337.445457 -323.43954) (xy 337.391093 -323.468053) (xy 337.333693 -323.48982)
			(xy 337.274091 -323.504524) (xy 337.213154 -323.511952) (xy 337.18246 -323.512434) (xy 337.151764 -323.511956)
			(xy 337.090819 -323.504554) (xy 337.031211 -323.489862) (xy 336.973807 -323.468096) (xy 336.919444 -323.439571)
			(xy 336.893916 -323.422518) (xy 336.885164 -323.417047) (xy 336.86496 -323.412919) (xy 336.844756 -323.417047)
			(xy 336.836004 -323.422518) (xy 336.810457 -323.43954) (xy 336.756093 -323.468053) (xy 336.698693 -323.48982)
			(xy 336.639091 -323.504524) (xy 336.578154 -323.511952) (xy 336.54746 -323.512434) (xy 336.516729 -323.511982)
			(xy 336.455716 -323.504569) (xy 336.396041 -323.489857) (xy 336.338574 -323.46806) (xy 336.284154 -323.439495)
			(xy 336.233573 -323.404579) (xy 336.187569 -323.363822) (xy 336.146812 -323.317816) (xy 336.111898 -323.267234)
			(xy 336.083335 -323.212813) (xy 336.061539 -323.155346) (xy 336.046828 -323.09567) (xy 336.039417 -323.034657)
			(xy 336.038952 -323.003926) (xy 334.287368 -323.003926) (xy 334.286987 -323.03466) (xy 334.279574 -323.09568)
			(xy 334.264861 -323.155362) (xy 334.24306 -323.212834) (xy 334.214491 -323.26726) (xy 334.17957 -323.317846)
			(xy 334.138806 -323.363853) (xy 334.092794 -323.404611) (xy 334.042204 -323.439525) (xy 333.987774 -323.468087)
			(xy 333.930298 -323.48988) (xy 333.870615 -323.504586) (xy 333.809594 -323.511991) (xy 333.77886 -323.512434)
			(xy 333.748164 -323.511956) (xy 333.687219 -323.504554) (xy 333.627611 -323.489862) (xy 333.570207 -323.468096)
			(xy 333.515844 -323.439571) (xy 333.490316 -323.422518) (xy 333.481564 -323.417047) (xy 333.46136 -323.412919)
			(xy 333.441156 -323.417047) (xy 333.432404 -323.422518) (xy 333.406857 -323.43954) (xy 333.352493 -323.468053)
			(xy 333.295093 -323.48982) (xy 333.235491 -323.504524) (xy 333.174554 -323.511952) (xy 333.14386 -323.512434)
			(xy 333.113164 -323.511956) (xy 333.052219 -323.504554) (xy 332.992611 -323.489862) (xy 332.935207 -323.468096)
			(xy 332.880844 -323.439571) (xy 332.855316 -323.422518) (xy 332.846564 -323.417047) (xy 332.82636 -323.412919)
			(xy 332.806156 -323.417047) (xy 332.797404 -323.422518) (xy 332.771857 -323.43954) (xy 332.717493 -323.468053)
			(xy 332.660093 -323.48982) (xy 332.600491 -323.504524) (xy 332.539554 -323.511952) (xy 332.50886 -323.512434)
			(xy 332.478129 -323.511982) (xy 332.417116 -323.504569) (xy 332.357441 -323.489857) (xy 332.299974 -323.46806)
			(xy 332.245554 -323.439495) (xy 332.194973 -323.404579) (xy 332.148969 -323.363822) (xy 332.108212 -323.317816)
			(xy 332.073298 -323.267234) (xy 332.044735 -323.212813) (xy 332.022939 -323.155346) (xy 332.008228 -323.09567)
			(xy 332.000817 -323.034657) (xy 332.000352 -323.003926) (xy 329.947524 -323.003926) (xy 329.947068 -323.034657)
			(xy 329.939657 -323.09567) (xy 329.924946 -323.155346) (xy 329.90315 -323.212813) (xy 329.874585 -323.267234)
			(xy 329.83967 -323.317815) (xy 329.798913 -323.36382) (xy 329.752908 -323.404576) (xy 329.702325 -323.439491)
			(xy 329.647904 -323.468054) (xy 329.590436 -323.489849) (xy 329.530761 -323.504559) (xy 329.469747 -323.511969)
			(xy 329.439016 -323.512434) (xy 329.408319 -323.511978) (xy 329.347374 -323.504571) (xy 329.287765 -323.489874)
			(xy 329.230361 -323.468103) (xy 329.175999 -323.439573) (xy 329.150472 -323.422518) (xy 329.14172 -323.417047)
			(xy 329.121516 -323.412919) (xy 329.101312 -323.417047) (xy 329.09256 -323.422518) (xy 329.067025 -323.439559)
			(xy 329.012657 -323.468069) (xy 328.955254 -323.489832) (xy 328.89565 -323.504532) (xy 328.834711 -323.511954)
			(xy 328.804016 -323.512434) (xy 328.773319 -323.511978) (xy 328.712374 -323.504571) (xy 328.652765 -323.489874)
			(xy 328.595361 -323.468103) (xy 328.540999 -323.439573) (xy 328.515472 -323.422518) (xy 328.50672 -323.417047)
			(xy 328.486516 -323.412919) (xy 328.466312 -323.417047) (xy 328.45756 -323.422518) (xy 328.432025 -323.439559)
			(xy 328.377657 -323.468069) (xy 328.320254 -323.489832) (xy 328.26065 -323.504532) (xy 328.199711 -323.511954)
			(xy 328.169016 -323.512434) (xy 328.138286 -323.511929) (xy 328.077275 -323.504523) (xy 328.017601 -323.489817)
			(xy 327.960135 -323.468025) (xy 327.905714 -323.439466) (xy 327.855133 -323.404555) (xy 327.809128 -323.363801)
			(xy 327.768371 -323.3178) (xy 327.733456 -323.267222) (xy 327.704892 -323.212804) (xy 327.683096 -323.155339)
			(xy 327.668385 -323.095666) (xy 327.660974 -323.034656) (xy 327.660508 -323.003926) (xy 325.934324 -323.003926)
			(xy 325.933868 -323.034657) (xy 325.926457 -323.09567) (xy 325.911746 -323.155346) (xy 325.88995 -323.212813)
			(xy 325.861385 -323.267234) (xy 325.82647 -323.317815) (xy 325.785713 -323.36382) (xy 325.739708 -323.404576)
			(xy 325.689125 -323.439491) (xy 325.634704 -323.468054) (xy 325.577236 -323.489849) (xy 325.517561 -323.504559)
			(xy 325.456547 -323.511969) (xy 325.425816 -323.512434) (xy 325.395119 -323.511978) (xy 325.334174 -323.504571)
			(xy 325.274565 -323.489874) (xy 325.217161 -323.468103) (xy 325.162799 -323.439573) (xy 325.137272 -323.422518)
			(xy 325.12852 -323.417047) (xy 325.108316 -323.412919) (xy 325.088112 -323.417047) (xy 325.07936 -323.422518)
			(xy 325.053825 -323.439559) (xy 324.999457 -323.468069) (xy 324.942054 -323.489832) (xy 324.88245 -323.504532)
			(xy 324.821511 -323.511954) (xy 324.790816 -323.512434) (xy 324.760119 -323.511978) (xy 324.699174 -323.504571)
			(xy 324.639565 -323.489874) (xy 324.582161 -323.468103) (xy 324.527799 -323.439573) (xy 324.502272 -323.422518)
			(xy 324.49352 -323.417047) (xy 324.473316 -323.412919) (xy 324.453112 -323.417047) (xy 324.44436 -323.422518)
			(xy 324.418825 -323.439559) (xy 324.364457 -323.468069) (xy 324.307054 -323.489832) (xy 324.24745 -323.504532)
			(xy 324.186511 -323.511954) (xy 324.155816 -323.512434) (xy 324.125086 -323.511929) (xy 324.064075 -323.504523)
			(xy 324.004401 -323.489817) (xy 323.946935 -323.468025) (xy 323.892514 -323.439466) (xy 323.841933 -323.404555)
			(xy 323.795928 -323.363801) (xy 323.755171 -323.3178) (xy 323.720256 -323.267222) (xy 323.691692 -323.212804)
			(xy 323.669896 -323.155339) (xy 323.655185 -323.095666) (xy 323.647774 -323.034656) (xy 323.647308 -323.003926)
			(xy 323.647806 -322.972702) (xy 323.655477 -322.910727) (xy 323.670681 -322.850158) (xy 323.693189 -322.791908)
			(xy 323.722663 -322.736853) (xy 323.740272 -322.711064) (xy 323.745894 -322.702099) (xy 323.750073 -322.681382)
			(xy 323.745557 -322.660735) (xy 323.739764 -322.651882) (xy 323.721566 -322.625824) (xy 323.691118 -322.570032)
			(xy 323.667859 -322.510881) (xy 323.652151 -322.449293) (xy 323.644239 -322.386228) (xy 323.643752 -322.354448)
			(xy 321.613462 -322.354448) (xy 321.613784 -322.376038) (xy 321.613237 -322.40927) (xy 321.604571 -322.475168)
			(xy 321.587404 -322.539378) (xy 321.562029 -322.600809) (xy 321.528876 -322.658416) (xy 321.509136 -322.685156)
			(xy 321.503106 -322.693813) (xy 321.498043 -322.714268) (xy 321.501702 -322.73502) (xy 321.507104 -322.744084)
			(xy 321.523242 -322.769174) (xy 321.550189 -322.822398) (xy 321.570727 -322.878409) (xy 321.584573 -322.936438)
			(xy 321.591536 -322.995687) (xy 321.59194 -323.025516) (xy 321.591475 -323.056247) (xy 321.584065 -323.117261)
			(xy 321.569355 -323.176937) (xy 321.54756 -323.234405) (xy 321.518997 -323.288827) (xy 321.484083 -323.339409)
			(xy 321.443326 -323.385415) (xy 321.397322 -323.426173) (xy 321.34674 -323.461089) (xy 321.292319 -323.489653)
			(xy 321.234852 -323.51145) (xy 321.175177 -323.526162) (xy 321.114163 -323.533574) (xy 321.083432 -323.534024)
			(xy 321.052738 -323.533541) (xy 320.9918 -323.526114) (xy 320.932198 -323.511411) (xy 320.874797 -323.489647)
			(xy 320.82043 -323.461137) (xy 320.794888 -323.444108) (xy 320.786136 -323.438637) (xy 320.765932 -323.434509)
			(xy 320.745728 -323.438637) (xy 320.736976 -323.444108) (xy 320.711448 -323.461161) (xy 320.657085 -323.489685)
			(xy 320.599681 -323.511452) (xy 320.540072 -323.526142) (xy 320.479128 -323.533544) (xy 320.448432 -323.534024)
			(xy 320.417738 -323.533541) (xy 320.3568 -323.526114) (xy 320.297198 -323.511411) (xy 320.239797 -323.489647)
			(xy 320.18543 -323.461137) (xy 320.159888 -323.444108) (xy 320.151136 -323.438637) (xy 320.130932 -323.434509)
			(xy 320.110728 -323.438637) (xy 320.101976 -323.444108) (xy 320.076448 -323.461161) (xy 320.022085 -323.489685)
			(xy 319.964681 -323.511452) (xy 319.905072 -323.526142) (xy 319.844128 -323.533544) (xy 319.813432 -323.534024)
			(xy 319.782698 -323.53358) (xy 319.721679 -323.526175) (xy 319.661997 -323.511468) (xy 319.604522 -323.489675)
			(xy 319.550094 -323.461112) (xy 319.499506 -323.426197) (xy 319.453495 -323.385439) (xy 319.412732 -323.339432)
			(xy 319.377812 -323.288847) (xy 319.349245 -323.234422) (xy 319.327446 -323.176949) (xy 319.312734 -323.117269)
			(xy 319.305323 -323.05625) (xy 319.304924 -323.025516) (xy 319.305449 -322.992501) (xy 319.313993 -322.927027)
			(xy 319.330938 -322.863208) (xy 319.356 -322.80212) (xy 319.388758 -322.744789) (xy 319.408302 -322.718176)
			(xy 319.414206 -322.709565) (xy 319.419163 -322.689304) (xy 319.415643 -322.668745) (xy 319.410334 -322.659756)
			(xy 319.394434 -322.63483) (xy 319.3679 -322.581993) (xy 319.347681 -322.526432) (xy 319.334052 -322.468899)
			(xy 319.327196 -322.410173) (xy 319.326768 -322.38061) (xy 319.327246 -322.349915) (xy 319.334666 -322.288974)
			(xy 319.349363 -322.229368) (xy 319.371124 -322.171964) (xy 319.399632 -322.117593) (xy 319.416684 -322.092066)
			(xy 319.42216 -322.083315) (xy 319.426293 -322.063108) (xy 319.422166 -322.042901) (xy 319.416684 -322.034154)
			(xy 319.399633 -322.008626) (xy 319.371111 -321.954262) (xy 319.349347 -321.896858) (xy 319.334659 -321.83725)
			(xy 319.327261 -321.776306) (xy 319.326768 -321.74561) (xy 319.327246 -321.714915) (xy 319.334666 -321.653974)
			(xy 319.349363 -321.594368) (xy 319.371124 -321.536964) (xy 319.399632 -321.482593) (xy 319.416684 -321.457066)
			(xy 319.42216 -321.448315) (xy 319.426293 -321.428108) (xy 319.422166 -321.407901) (xy 319.416684 -321.399154)
			(xy 319.399633 -321.373626) (xy 319.371111 -321.319262) (xy 319.349347 -321.261858) (xy 319.334659 -321.20225)
			(xy 319.327261 -321.141306) (xy 319.326768 -321.11061) (xy 319.327246 -321.079915) (xy 319.334666 -321.018974)
			(xy 319.349363 -320.959368) (xy 319.371124 -320.901964) (xy 319.399632 -320.847593) (xy 319.416684 -320.822066)
			(xy 319.42216 -320.813315) (xy 319.426293 -320.793108) (xy 319.422166 -320.772901) (xy 319.416684 -320.764154)
			(xy 319.399633 -320.738626) (xy 319.371111 -320.684262) (xy 319.349347 -320.626858) (xy 319.334659 -320.56725)
			(xy 319.327261 -320.506306) (xy 319.326768 -320.47561) (xy 319.327228 -320.444636) (xy 319.334757 -320.383148)
			(xy 319.349703 -320.32303) (xy 319.371845 -320.265175) (xy 319.400855 -320.210441) (xy 319.418208 -320.18478)
			(xy 319.423684 -320.176028) (xy 319.427821 -320.15582) (xy 319.4237 -320.135609) (xy 319.418208 -320.126868)
			(xy 319.400863 -320.101203) (xy 319.371853 -320.046468) (xy 319.34971 -319.988614) (xy 319.334762 -319.928498)
			(xy 319.327229 -319.867011) (xy 319.326768 -319.836038) (xy 319.32725 -319.805344) (xy 319.334678 -319.744407)
			(xy 319.349383 -319.684806) (xy 319.37115 -319.627406) (xy 319.399664 -319.573042) (xy 319.416684 -319.547494)
			(xy 319.422165 -319.538742) (xy 319.426309 -319.518532) (xy 319.42219 -319.498316) (xy 319.416684 -319.489582)
			(xy 319.399631 -319.464054) (xy 319.371106 -319.409691) (xy 319.34934 -319.352287) (xy 319.334649 -319.292679)
			(xy 319.327247 -319.231734) (xy 319.326768 -319.201038) (xy 319.32725 -319.170344) (xy 319.334678 -319.109407)
			(xy 319.349383 -319.049806) (xy 319.37115 -318.992406) (xy 319.399664 -318.938042) (xy 319.416684 -318.912494)
			(xy 319.422165 -318.903742) (xy 319.426309 -318.883532) (xy 319.42219 -318.863316) (xy 319.416684 -318.854582)
			(xy 319.399631 -318.829054) (xy 319.371106 -318.774691) (xy 319.34934 -318.717287) (xy 319.334649 -318.657679)
			(xy 319.327247 -318.596734) (xy 319.326768 -318.566038) (xy 319.32725 -318.535344) (xy 319.334678 -318.474407)
			(xy 319.349383 -318.414806) (xy 319.37115 -318.357406) (xy 319.399664 -318.303042) (xy 319.416684 -318.277494)
			(xy 319.422165 -318.268742) (xy 319.426309 -318.248532) (xy 319.42219 -318.228316) (xy 319.416684 -318.219582)
			(xy 319.399631 -318.194054) (xy 319.371106 -318.139691) (xy 319.34934 -318.082287) (xy 319.334649 -318.022679)
			(xy 319.327247 -317.961734) (xy 319.326768 -317.931038) (xy 319.32725 -317.900344) (xy 319.334678 -317.839407)
			(xy 319.349383 -317.779806) (xy 319.37115 -317.722406) (xy 319.399664 -317.668042) (xy 319.416684 -317.642494)
			(xy 319.422165 -317.633742) (xy 319.426309 -317.613532) (xy 319.42219 -317.593316) (xy 319.416684 -317.584582)
			(xy 319.399631 -317.559054) (xy 319.371106 -317.504691) (xy 319.34934 -317.447287) (xy 319.334649 -317.387679)
			(xy 319.327247 -317.326734) (xy 319.326768 -317.296038) (xy 319.32725 -317.265344) (xy 319.334678 -317.204407)
			(xy 319.349383 -317.144806) (xy 319.37115 -317.087406) (xy 319.399664 -317.033042) (xy 319.416684 -317.007494)
			(xy 319.422165 -316.998742) (xy 319.426309 -316.978532) (xy 319.42219 -316.958316) (xy 319.416684 -316.949582)
			(xy 319.41006 -316.939933) (xy 319.397608 -316.920114) (xy 319.391792 -316.909958) (xy 319.386712 -316.900814)
			(xy 319.370964 -316.888622) (xy 319.290192 -316.867032) (xy 319.28022 -316.864863) (xy 319.260032 -316.867731)
			(xy 319.251076 -316.87262) (xy 318.93383 -317.062612) (xy 318.923924 -317.070232) (xy 317.35649 -318.63792)
			(xy 317.349115 -318.646042) (xy 317.341463 -318.666579) (xy 317.341758 -318.677544) (xy 317.348362 -318.765428)
			(xy 317.35903 -318.784986) (xy 317.368174 -318.79159) (xy 317.39524 -318.812197) (xy 317.444149 -318.859477)
			(xy 317.486319 -318.912855) (xy 317.520998 -318.971378) (xy 317.547565 -319.034001) (xy 317.565548 -319.099607)
			(xy 317.574624 -319.167025) (xy 317.575184 -319.201038) (xy 317.574703 -319.231732) (xy 317.567278 -319.292671)
			(xy 317.552578 -319.352275) (xy 317.530815 -319.409677) (xy 317.502305 -319.464045) (xy 317.485268 -319.489582)
			(xy 317.479806 -319.498334) (xy 317.475694 -319.518532) (xy 317.479831 -319.538724) (xy 317.485268 -319.547494)
			(xy 317.502324 -319.573021) (xy 317.530854 -319.627383) (xy 317.552625 -319.684787) (xy 317.56732 -319.744396)
			(xy 317.574726 -319.805341) (xy 317.575184 -319.836038) (xy 317.574782 -319.864995) (xy 317.568208 -319.922535)
			(xy 317.555129 -319.978952) (xy 317.535713 -320.033514) (xy 317.510213 -320.085512) (xy 317.49492 -320.110104)
			(xy 317.489721 -320.119101) (xy 317.486316 -320.139579) (xy 317.491285 -320.159734) (xy 317.497206 -320.16827)
			(xy 317.516741 -320.19489) (xy 317.549504 -320.252218) (xy 317.57457 -320.313304) (xy 317.591519 -320.377121)
			(xy 317.600065 -320.442595) (xy 317.600584 -320.47561) (xy 317.600105 -320.506305) (xy 317.592683 -320.567245)
			(xy 317.577985 -320.62685) (xy 317.556225 -320.684255) (xy 317.527717 -320.738625) (xy 317.510668 -320.764154)
			(xy 317.505201 -320.772907) (xy 317.501078 -320.793108) (xy 317.505207 -320.813309) (xy 317.510668 -320.822066)
			(xy 317.527725 -320.847592) (xy 317.556258 -320.901954) (xy 317.578032 -320.959358) (xy 317.592731 -321.018967)
			(xy 317.60014 -321.079913) (xy 317.600584 -321.11061) (xy 317.600105 -321.141305) (xy 317.592683 -321.202245)
			(xy 317.577985 -321.26185) (xy 317.556225 -321.319255) (xy 317.527717 -321.373625) (xy 317.510668 -321.399154)
			(xy 317.505201 -321.407907) (xy 317.501078 -321.428108) (xy 317.505207 -321.448309) (xy 317.510668 -321.457066)
			(xy 317.527725 -321.482592) (xy 317.556258 -321.536954) (xy 317.578032 -321.594358) (xy 317.592731 -321.653967)
			(xy 317.60014 -321.714913) (xy 317.600584 -321.74561) (xy 317.600105 -321.776305) (xy 317.592683 -321.837245)
			(xy 317.577985 -321.89685) (xy 317.556225 -321.954255) (xy 317.527717 -322.008625) (xy 317.510668 -322.034154)
			(xy 317.505201 -322.042907) (xy 317.501078 -322.063108) (xy 317.505207 -322.083309) (xy 317.510668 -322.092066)
			(xy 317.527725 -322.117592) (xy 317.556258 -322.171954) (xy 317.578032 -322.229358) (xy 317.592731 -322.288967)
			(xy 317.60014 -322.349913) (xy 317.600584 -322.38061) (xy 317.600057 -322.413624) (xy 317.591511 -322.479097)
			(xy 317.574563 -322.542914) (xy 317.549499 -322.604) (xy 317.51674 -322.661329) (xy 317.497206 -322.68795)
			(xy 317.491306 -322.696561) (xy 317.486358 -322.716818) (xy 317.489887 -322.73737) (xy 317.495174 -322.74637)
			(xy 317.511077 -322.771295) (xy 317.537619 -322.824131) (xy 317.557846 -322.879691) (xy 317.571483 -322.937225)
			(xy 317.578348 -322.995952) (xy 317.57874 -323.025516) (xy 317.578275 -323.056247) (xy 317.570865 -323.117261)
			(xy 317.556155 -323.176937) (xy 317.53436 -323.234405) (xy 317.505797 -323.288827) (xy 317.470883 -323.339409)
			(xy 317.430126 -323.385415) (xy 317.384122 -323.426173) (xy 317.33354 -323.461089) (xy 317.279119 -323.489653)
			(xy 317.221652 -323.51145) (xy 317.161977 -323.526162) (xy 317.100963 -323.533574) (xy 317.070232 -323.534024)
			(xy 317.039538 -323.533541) (xy 316.9786 -323.526114) (xy 316.918998 -323.511411) (xy 316.861597 -323.489647)
			(xy 316.80723 -323.461137) (xy 316.781688 -323.444108) (xy 316.772936 -323.438637) (xy 316.752732 -323.434509)
			(xy 316.732528 -323.438637) (xy 316.723776 -323.444108) (xy 316.698248 -323.461161) (xy 316.643885 -323.489685)
			(xy 316.586481 -323.511452) (xy 316.526872 -323.526142) (xy 316.465928 -323.533544) (xy 316.435232 -323.534024)
			(xy 316.404538 -323.533541) (xy 316.3436 -323.526114) (xy 316.283998 -323.511411) (xy 316.226597 -323.489647)
			(xy 316.17223 -323.461137) (xy 316.146688 -323.444108) (xy 316.137936 -323.438637) (xy 316.117732 -323.434509)
			(xy 316.097528 -323.438637) (xy 316.088776 -323.444108) (xy 316.063248 -323.461161) (xy 316.008885 -323.489685)
			(xy 315.951481 -323.511452) (xy 315.891872 -323.526142) (xy 315.830928 -323.533544) (xy 315.800232 -323.534024)
			(xy 315.769498 -323.53358) (xy 315.708479 -323.526175) (xy 315.648797 -323.511468) (xy 315.591322 -323.489675)
			(xy 315.536894 -323.461112) (xy 315.486306 -323.426197) (xy 315.440295 -323.385439) (xy 315.399532 -323.339432)
			(xy 315.364612 -323.288847) (xy 315.336045 -323.234422) (xy 315.314246 -323.176949) (xy 315.299534 -323.117269)
			(xy 315.292123 -323.05625) (xy 315.291724 -323.025516) (xy 315.292216 -322.994292) (xy 315.299895 -322.932319)
			(xy 315.315104 -322.871752) (xy 315.337612 -322.813501) (xy 315.367082 -322.758445) (xy 315.384688 -322.732654)
			(xy 315.390328 -322.723699) (xy 315.394495 -322.702973) (xy 315.389985 -322.68232) (xy 315.38418 -322.673472)
			(xy 315.365999 -322.647403) (xy 315.335553 -322.591612) (xy 315.312293 -322.532464) (xy 315.29658 -322.470879)
			(xy 315.28866 -322.407817) (xy 315.288168 -322.376038) (xy 315.28865 -322.345344) (xy 315.296078 -322.284407)
			(xy 315.310783 -322.224806) (xy 315.33255 -322.167406) (xy 315.361064 -322.113042) (xy 315.378084 -322.087494)
			(xy 315.383565 -322.078742) (xy 315.387709 -322.058532) (xy 315.38359 -322.038316) (xy 315.378084 -322.029582)
			(xy 315.361031 -322.004054) (xy 315.332506 -321.949691) (xy 315.31074 -321.892287) (xy 315.296049 -321.832679)
			(xy 315.288647 -321.771734) (xy 315.288168 -321.741038) (xy 315.28865 -321.710344) (xy 315.296078 -321.649407)
			(xy 315.310783 -321.589806) (xy 315.33255 -321.532406) (xy 315.361064 -321.478042) (xy 315.378084 -321.452494)
			(xy 315.383565 -321.443742) (xy 315.387709 -321.423532) (xy 315.38359 -321.403316) (xy 315.378084 -321.394582)
			(xy 315.361031 -321.369054) (xy 315.332506 -321.314691) (xy 315.31074 -321.257287) (xy 315.296049 -321.197679)
			(xy 315.288647 -321.136734) (xy 315.288168 -321.106038) (xy 315.28865 -321.075344) (xy 315.296078 -321.014407)
			(xy 315.310783 -320.954806) (xy 315.33255 -320.897406) (xy 315.361064 -320.843042) (xy 315.378084 -320.817494)
			(xy 315.383565 -320.808742) (xy 315.387709 -320.788532) (xy 315.38359 -320.768316) (xy 315.378084 -320.759582)
			(xy 315.357256 -320.72707) (xy 315.353954 -320.721482) (xy 315.349382 -320.716656) (xy 315.341935 -320.709968)
			(xy 315.323439 -320.702372) (xy 315.303443 -320.702372) (xy 315.284947 -320.709968) (xy 315.2775 -320.716656)
			(xy 313.72302 -322.271136) (xy 313.695782 -322.297564) (xy 313.635593 -322.343795) (xy 313.56988 -322.381768)
			(xy 313.53506 -322.396866) (xy 313.17946 -322.544186) (xy 313.174897 -322.546194) (xy 313.166584 -322.551695)
			(xy 313.16295 -322.555108) (xy 312.409586 -323.308472) (xy 312.402188 -323.315319) (xy 312.38359 -323.323053)
			(xy 312.373518 -323.323458) (xy 311.143142 -323.323458) (xy 311.133236 -323.324474) (xy 309.508144 -323.64934)
			(xy 309.480054 -323.654589) (xy 309.42318 -323.660184) (xy 309.394606 -323.660516) (xy 309.392066 -323.660516)
			(xy 306.95646 -323.650102) (xy 306.94637 -323.650483) (xy 306.92771 -323.658159) (xy 306.913446 -323.672429)
			(xy 306.909216 -323.681598) (xy 306.86756 -323.783452) (xy 306.87391 -323.813424) (xy 306.885086 -323.824346)
			(xy 306.916344 -323.855372) (xy 306.973833 -323.922104) (xy 307.02517 -323.993675) (xy 307.069953 -324.069521)
			(xy 307.107825 -324.149042) (xy 307.13849 -324.231611) (xy 307.161704 -324.316577) (xy 307.177285 -324.403267)
			(xy 307.185109 -324.490998) (xy 307.185568 -324.535038) (xy 307.185053 -324.580831) (xy 307.176598 -324.672025)
			(xy 307.159764 -324.76205) (xy 307.134693 -324.850138) (xy 307.101602 -324.935536) (xy 307.06077 -325.017516)
			(xy 307.012548 -325.095379) (xy 306.957346 -325.168459) (xy 306.895637 -325.236133) (xy 306.827945 -325.297824)
			(xy 306.754849 -325.353005) (xy 306.676973 -325.401206) (xy 306.594982 -325.442014) (xy 306.509574 -325.475082)
			(xy 306.42148 -325.500127) (xy 306.33145 -325.516936) (xy 306.240253 -325.525366) (xy 306.19446 -325.525892)
			(xy 304.44186 -325.525892) (xy 304.396072 -325.525362) (xy 304.304886 -325.51691) (xy 304.214869 -325.500082)
			(xy 304.126788 -325.475022) (xy 304.041394 -325.441943) (xy 303.959416 -325.401127) (xy 303.881553 -325.352923)
			(xy 303.808469 -325.297741) (xy 303.740788 -325.236052) (xy 303.679086 -325.168383) (xy 303.623889 -325.09531)
			(xy 303.575669 -325.017457) (xy 303.534837 -324.935487) (xy 303.501741 -324.8501) (xy 303.476663 -324.762024)
			(xy 303.459817 -324.67201) (xy 303.451347 -324.580826) (xy 303.450752 -324.535038) (xy 303.451266 -324.489959)
			(xy 303.45946 -324.400175) (xy 303.475774 -324.311507) (xy 303.500074 -324.224686) (xy 303.532158 -324.140431)
			(xy 303.571762 -324.059438) (xy 303.618559 -323.982377) (xy 303.67216 -323.909884) (xy 303.732124 -323.84256)
			(xy 303.764696 -323.811392) (xy 303.776126 -323.800724) (xy 303.782984 -323.770498) (xy 303.742852 -323.667882)
			(xy 303.738737 -323.658615) (xy 303.72462 -323.644085) (xy 303.705988 -323.636131) (xy 303.695862 -323.635624)
			(xy 299.376592 -323.616828) (xy 299.366359 -323.617303) (xy 299.347515 -323.625295) (xy 299.333256 -323.639979)
			(xy 299.329094 -323.64934) (xy 299.289216 -323.753226) (xy 299.296836 -323.783706) (xy 299.308774 -323.794374)
			(xy 299.343143 -323.825669) (xy 299.406516 -323.893677) (xy 299.463242 -323.96732) (xy 299.512823 -324.045951)
			(xy 299.554824 -324.128879) (xy 299.588876 -324.215376) (xy 299.614679 -324.304681) (xy 299.632007 -324.396009)
			(xy 299.640707 -324.488559) (xy 299.64126 -324.535038) (xy 299.640729 -324.580822) (xy 299.632277 -324.672)
			(xy 299.615449 -324.76201) (xy 299.590387 -324.850082) (xy 299.557306 -324.935467) (xy 299.516488 -325.017435)
			(xy 299.468281 -325.095288) (xy 299.413097 -325.16836) (xy 299.351407 -325.236029) (xy 299.283735 -325.297718)
			(xy 299.210661 -325.3529) (xy 299.132807 -325.401104) (xy 299.050838 -325.441919) (xy 298.965452 -325.474997)
			(xy 298.877379 -325.500056) (xy 298.787369 -325.516882) (xy 298.69619 -325.525331) (xy 298.650406 -325.525892)
			(xy 296.897806 -325.525892) (xy 296.85202 -325.525363) (xy 296.760838 -325.516915) (xy 296.670824 -325.500089)
			(xy 296.582747 -325.47503) (xy 296.497357 -325.441952) (xy 296.415384 -325.401136) (xy 296.337527 -325.35293)
			(xy 296.264449 -325.297747) (xy 296.196775 -325.236056) (xy 296.135081 -325.168385) (xy 296.079895 -325.095309)
			(xy 296.031686 -325.017454) (xy 295.990866 -324.935483) (xy 295.957784 -324.850095) (xy 295.932721 -324.762019)
			(xy 295.915891 -324.672006) (xy 295.907439 -324.580824) (xy 295.906952 -324.535038) (xy 295.907394 -324.492243)
			(xy 295.914757 -324.40697) (xy 295.929449 -324.32265) (xy 295.951361 -324.239912) (xy 295.980328 -324.159372)
			(xy 296.016136 -324.081632) (xy 296.058516 -324.007271) (xy 296.107153 -323.936843) (xy 296.161685 -323.870873)
			(xy 296.221705 -323.809854) (xy 296.253916 -323.781674) (xy 296.266108 -323.77126) (xy 296.274236 -323.740526)
			(xy 296.235882 -323.636132) (xy 296.23188 -323.62659) (xy 296.217693 -323.611555) (xy 296.198719 -323.603352)
			(xy 296.188384 -323.602858) (xy 291.793422 -323.583554) (xy 291.782938 -323.584009) (xy 291.763687 -323.5923)
			(xy 291.749382 -323.607621) (xy 291.745416 -323.617336) (xy 291.707824 -323.723) (xy 291.71646 -323.753988)
			(xy 291.72916 -323.764148) (xy 291.763223 -323.792278) (xy 291.826745 -323.853682) (xy 291.884547 -323.920497)
			(xy 291.93617 -323.992194) (xy 291.981205 -324.068203) (xy 292.019294 -324.147919) (xy 292.050134 -324.23071)
			(xy 292.073479 -324.315918) (xy 292.089146 -324.402866) (xy 292.097009 -324.490864) (xy 292.09746 -324.535038)
			(xy 292.096945 -324.580831) (xy 292.08849 -324.672025) (xy 292.071656 -324.76205) (xy 292.046585 -324.850137)
			(xy 292.013493 -324.935535) (xy 291.972662 -325.017515) (xy 291.92444 -325.095377) (xy 291.869238 -325.168456)
			(xy 291.807528 -325.23613) (xy 291.739836 -325.297821) (xy 291.666741 -325.353001) (xy 291.588865 -325.401201)
			(xy 291.506873 -325.442009) (xy 291.421466 -325.475076) (xy 291.333371 -325.500121) (xy 291.243342 -325.51693)
			(xy 291.152145 -325.525358) (xy 291.106352 -325.525892) (xy 289.353752 -325.525892) (xy 289.307964 -325.525362)
			(xy 289.216779 -325.516909) (xy 289.126762 -325.500081) (xy 289.038682 -325.47502) (xy 288.953289 -325.44194)
			(xy 288.871311 -325.401124) (xy 288.793449 -325.35292) (xy 288.720366 -325.297738) (xy 288.652685 -325.236049)
			(xy 288.590983 -325.16838) (xy 288.535788 -325.095308) (xy 288.487568 -325.017455) (xy 288.446736 -324.935485)
			(xy 288.41364 -324.850099) (xy 288.388563 -324.762023) (xy 288.371717 -324.67201) (xy 288.363247 -324.580826)
			(xy 288.362644 -324.535038) (xy 288.363142 -324.489879) (xy 288.37136 -324.399935) (xy 288.387729 -324.311112)
			(xy 288.412115 -324.224148) (xy 288.444316 -324.139764) (xy 288.484063 -324.058661) (xy 288.531027 -323.981513)
			(xy 288.584817 -323.908959) (xy 288.644989 -323.841603) (xy 288.711041 -323.780003) (xy 288.746438 -323.751956)
			(xy 288.759392 -323.741796) (xy 288.76879 -323.711062) (xy 288.732722 -323.604382) (xy 288.728806 -323.594584)
			(xy 288.714543 -323.579065) (xy 288.695254 -323.570569) (xy 288.684716 -323.570092) (xy 284.206188 -323.550534)
			(xy 284.195519 -323.551045) (xy 284.175987 -323.55963) (xy 284.16162 -323.575402) (xy 284.157674 -323.585332)
			(xy 284.122368 -323.693028) (xy 284.132528 -323.72427) (xy 284.14599 -323.734176) (xy 284.183355 -323.76208)
			(xy 284.253219 -323.823861) (xy 284.316969 -323.891932) (xy 284.374042 -323.965693) (xy 284.423931 -324.044489)
			(xy 284.466197 -324.127624) (xy 284.500464 -324.214363) (xy 284.52643 -324.303938) (xy 284.543865 -324.395556)
			(xy 284.552615 -324.488407) (xy 284.553152 -324.535038) (xy 284.552621 -324.580822) (xy 284.544169 -324.672)
			(xy 284.52734 -324.762009) (xy 284.502279 -324.850081) (xy 284.469198 -324.935466) (xy 284.42838 -325.017433)
			(xy 284.380173 -325.095286) (xy 284.324989 -325.168358) (xy 284.263298 -325.236026) (xy 284.195627 -325.297715)
			(xy 284.122552 -325.352896) (xy 284.044699 -325.401099) (xy 283.962729 -325.441914) (xy 283.877343 -325.474991)
			(xy 283.78927 -325.50005) (xy 283.69926 -325.516875) (xy 283.608082 -325.525323) (xy 283.562298 -325.525892)
			(xy 281.809698 -325.525892) (xy 281.763912 -325.525363) (xy 281.67273 -325.516914) (xy 281.582717 -325.500088)
			(xy 281.494641 -325.475028) (xy 281.409252 -325.441949) (xy 281.32728 -325.401133) (xy 281.249423 -325.352927)
			(xy 281.176346 -325.297744) (xy 281.108672 -325.236053) (xy 281.046979 -325.168382) (xy 280.991793 -325.095307)
			(xy 280.943585 -325.017452) (xy 280.902765 -324.935481) (xy 280.869683 -324.850093) (xy 280.84462 -324.762018)
			(xy 280.827791 -324.672005) (xy 280.819339 -324.580824) (xy 280.818844 -324.535038) (xy 280.819304 -324.491705)
			(xy 280.826871 -324.40537) (xy 280.84195 -324.320025) (xy 280.864427 -324.236324) (xy 280.894128 -324.154907)
			(xy 280.930828 -324.076395) (xy 280.974245 -324.001388) (xy 281.024048 -323.930461) (xy 281.079856 -323.864155)
			(xy 281.141242 -323.802977) (xy 281.207738 -323.747395) (xy 281.243024 -323.722238) (xy 281.256486 -323.712586)
			(xy 281.267408 -323.68109) (xy 281.233626 -323.572886) (xy 281.229977 -323.56274) (xy 281.215742 -323.546571)
			(xy 281.196134 -323.537649) (xy 281.185366 -323.537072) (xy 276.614128 -323.51726) (xy 276.603178 -323.517657)
			(xy 276.583178 -323.526552) (xy 276.568722 -323.542986) (xy 276.565106 -323.553328) (xy 276.53234 -323.663056)
			(xy 276.544024 -323.694806) (xy 276.558248 -323.70395) (xy 276.595556 -323.728785) (xy 276.665999 -323.784205)
			(xy 276.73115 -323.84576) (xy 276.790476 -323.912946) (xy 276.843493 -323.985215) (xy 276.889768 -324.061976)
			(xy 276.928921 -324.142603) (xy 276.960635 -324.226435) (xy 276.984648 -324.312789) (xy 277.000766 -324.400958)
			(xy 277.008856 -324.490223) (xy 277.009352 -324.535038) (xy 277.008821 -324.580822) (xy 277.000369 -324.672)
			(xy 276.98354 -324.762009) (xy 276.958479 -324.850081) (xy 276.925398 -324.935466) (xy 276.88458 -325.017433)
			(xy 276.836373 -325.095286) (xy 276.781189 -325.168358) (xy 276.719498 -325.236026) (xy 276.651827 -325.297715)
			(xy 276.578752 -325.352896) (xy 276.500899 -325.401099) (xy 276.418929 -325.441914) (xy 276.333543 -325.474991)
			(xy 276.24547 -325.50005) (xy 276.15546 -325.516875) (xy 276.064282 -325.525323) (xy 276.018498 -325.525892)
			(xy 274.265898 -325.525892) (xy 274.220112 -325.525363) (xy 274.12893 -325.516914) (xy 274.038917 -325.500088)
			(xy 273.950841 -325.475028) (xy 273.865452 -325.441949) (xy 273.78348 -325.401133) (xy 273.705623 -325.352927)
			(xy 273.632546 -325.297744) (xy 273.564872 -325.236053) (xy 273.503179 -325.168382) (xy 273.447993 -325.095307)
			(xy 273.399785 -325.017452) (xy 273.358965 -324.935481) (xy 273.325883 -324.850093) (xy 273.30082 -324.762018)
			(xy 273.283991 -324.672005) (xy 273.275539 -324.580824) (xy 273.275044 -324.535038) (xy 273.275547 -324.489233)
			(xy 273.283982 -324.398013) (xy 273.300801 -324.307962) (xy 273.325863 -324.219847) (xy 273.358951 -324.134422)
			(xy 273.399784 -324.052417) (xy 273.448012 -323.974531) (xy 273.503225 -323.90143) (xy 273.564951 -323.833738)
			(xy 273.632661 -323.772033) (xy 273.705779 -323.716843) (xy 273.744436 -323.692266) (xy 273.758914 -323.683376)
			(xy 273.771106 -323.65188) (xy 273.740118 -323.54139) (xy 273.736634 -323.530923) (xy 273.722363 -323.514134)
			(xy 273.702367 -323.504876) (xy 273.69135 -323.504306) (xy 270.98625 -323.492622) (xy 270.976218 -323.49306)
			(xy 270.957644 -323.500636) (xy 270.950182 -323.507354) (xy 270.688308 -323.769228) (xy 270.681465 -323.776628)
			(xy 270.67374 -323.795226) (xy 270.673322 -323.805296) (xy 270.673322 -335.327498) (xy 270.673742 -335.337518)
			(xy 270.681412 -335.356032) (xy 270.695585 -335.370199) (xy 270.714102 -335.377862) (xy 270.724122 -335.378298)
			(xy 302.033432 -335.378298) (xy 302.037504 -335.378245) (xy 302.045546 -335.37697) (xy 302.049434 -335.375758)
			(xy 302.071786 -335.368138) (xy 302.078136 -335.36382) (xy 302.099867 -335.348752) (xy 302.146655 -335.32411)
			(xy 302.196397 -335.306164) (xy 302.24814 -335.295256) (xy 302.300894 -335.291597) (xy 302.353648 -335.295256)
			(xy 302.405391 -335.306164) (xy 302.455133 -335.32411) (xy 302.501921 -335.348752) (xy 302.523652 -335.36382)
			(xy 302.530002 -335.368138) (xy 302.552354 -335.375758) (xy 302.55625 -335.376935) (xy 302.564287 -335.378205)
			(xy 302.568356 -335.378298) (xy 302.693832 -335.378298) (xy 302.697904 -335.378245) (xy 302.705946 -335.37697)
			(xy 302.709834 -335.375758) (xy 302.732186 -335.368138) (xy 302.738536 -335.36382) (xy 302.761822 -335.347693)
			(xy 302.812179 -335.321762) (xy 302.865816 -335.303562) (xy 302.921556 -335.293493) (xy 302.978171 -335.291778)
			(xy 303.034417 -335.298453) (xy 303.061878 -335.3054) (xy 303.068516 -335.306996) (xy 303.082164 -335.306996)
			(xy 303.088802 -335.3054) (xy 303.113472 -335.299115) (xy 303.163931 -335.292362) (xy 303.189386 -335.291938)
			(xy 303.22008 -335.29255) (xy 303.280676 -335.302371) (xy 303.33892 -335.321762) (xy 303.39331 -335.350223)
			(xy 303.41824 -335.368138) (xy 303.424981 -335.372804) (xy 303.440527 -335.37798) (xy 303.44872 -335.378298)
			(xy 303.590452 -335.378298) (xy 303.598648 -335.377996) (xy 303.614203 -335.372825) (xy 303.620932 -335.368138)
			(xy 303.643046 -335.352155) (xy 303.690929 -335.325998) (xy 303.742049 -335.306924) (xy 303.795363 -335.295321)
			(xy 303.849786 -335.291427) (xy 303.904209 -335.295321) (xy 303.957523 -335.306924) (xy 304.008643 -335.325998)
			(xy 304.056526 -335.352155) (xy 304.07864 -335.368138) (xy 304.085381 -335.372804) (xy 304.100927 -335.37798)
			(xy 304.10912 -335.378298) (xy 304.27422 -335.378298) (xy 304.284289 -335.378725) (xy 304.302888 -335.386444)
			(xy 304.310288 -335.393284) (xy 304.422556 -335.505552) (xy 304.429955 -335.512395) (xy 304.448554 -335.520116)
			(xy 304.458624 -335.520538) (xy 305.109118 -335.520538)
		)
		(stroke
			(width 0)
			(type solid)
		)
		(fill yes)
		(layer "In15.Cu")
		(net "PVDDIO_P0")
	)
	(gr_line
		(start 7.069582 -108.937552)
		(end 7.081774 -108.92028)
		(stroke
			(width 0.07112)
			(type default)
		)
		(layer "In15.Cu")
	)
	(gr_line
		(start 7.081774 -108.92028)
		(end 7.483856 -108.345478)
		(stroke
			(width 0.07112)
			(type default)
		)
		(layer "In15.Cu")
	)
	(gr_line
		(start 7.300468 -109.099096)
		(end 7.31266 -109.081824)
		(stroke
			(width 0.07112)
			(type default)
		)
		(layer "In15.Cu")
	)
	(gr_line
		(start 7.314438 -109.08157)
		(end 7.503668 -109.048296)
		(stroke
			(width 0.07112)
			(type default)
		)
		(layer "In15.Cu")
	)
	(gr_line
		(start 7.503668 -109.048296)
		(end 7.748778 -108.698284)
		(stroke
			(width 0.07112)
			(type default)
		)
		(layer "In15.Cu")
	)
	(gr_line
		(start 7.748778 -108.698284)
		(end 7.71525 -108.509054)
		(stroke
			(width 0.07112)
			(type default)
		)
		(layer "In15.Cu")
	)
	(gr_line
		(start 9.397238 -178.327558)
		(end 9.106408 -178.618388)
		(stroke
			(width 0.07112)
			(type default)
		)
		(layer "In15.Cu")
	)
	(gr_line
		(start 9.397238 -178.045618)
		(end 9.106408 -177.754788)
		(stroke
			(width 0.07112)
			(type default)
		)
		(layer "In15.Cu")
	)
	(gr_line
		(start 9.397238 -175.557434)
		(end 9.106408 -175.848264)
		(stroke
			(width 0.07112)
			(type default)
		)
		(layer "In15.Cu")
	)
	(gr_line
		(start 9.397238 -175.275494)
		(end 9.106408 -174.984664)
		(stroke
			(width 0.07112)
			(type default)
		)
		(layer "In15.Cu")
	)
	(gr_line
		(start 9.397238 -172.78731)
		(end 9.106408 -173.07814)
		(stroke
			(width 0.07112)
			(type default)
		)
		(layer "In15.Cu")
	)
	(gr_line
		(start 9.397238 -172.50537)
		(end 9.106408 -172.21454)
		(stroke
			(width 0.07112)
			(type default)
		)
		(layer "In15.Cu")
	)
	(gr_line
		(start 9.397238 -170.0022)
		(end 9.106408 -170.29303)
		(stroke
			(width 0.07112)
			(type default)
		)
		(layer "In15.Cu")
	)
	(gr_line
		(start 9.397238 -169.72026)
		(end 9.106408 -169.42943)
		(stroke
			(width 0.07112)
			(type default)
		)
		(layer "In15.Cu")
	)
	(gr_line
		(start 10.109708 -181.90337)
		(end 10.109962 -181.896258)
		(stroke
			(width 0.07112)
			(type default)
		)
		(layer "In15.Cu")
	)
	(gr_line
		(start 10.109962 -181.896258)
		(end 10.109962 -181.891178)
		(stroke
			(width 0.07112)
			(type default)
		)
		(layer "In15.Cu")
	)
	(gr_line
		(start 10.304526 -425.305982)
		(end 10.286746 -425.305982)
		(stroke
			(width 0.07112)
			(type default)
		)
		(layer "In15.Cu")
	)
	(gr_line
		(start 10.586466 -425.887642)
		(end 10.288016 -425.589192)
		(stroke
			(width 0.07112)
			(type default)
		)
		(layer "In15.Cu")
	)
	(gr_line
		(start 10.586466 -425.024042)
		(end 10.304526 -425.305982)
		(stroke
			(width 0.07112)
			(type default)
		)
		(layer "In15.Cu")
	)
	(gr_line
		(start 10.680192 -420.914322)
		(end 10.394188 -421.200326)
		(stroke
			(width 0.07112)
			(type default)
		)
		(layer "In15.Cu")
	)
	(gr_line
		(start 10.688574 -420.631112)
		(end 10.394188 -420.336726)
		(stroke
			(width 0.07112)
			(type default)
		)
		(layer "In15.Cu")
	)
	(gr_line
		(start 10.689844 -420.914322)
		(end 10.680192 -420.914322)
		(stroke
			(width 0.07112)
			(type default)
		)
		(layer "In15.Cu")
	)
	(gr_line
		(start 10.748772 -183.35879)
		(end 10.748772 -183.357266)
		(stroke
			(width 0.07112)
			(type default)
		)
		(layer "In15.Cu")
	)
	(gr_line
		(start 11.030458 -183.367426)
		(end 11.030712 -183.367426)
		(stroke
			(width 0.07112)
			(type default)
		)
		(layer "In15.Cu")
	)
	(gr_line
		(start 11.030966 -183.36768)
		(end 11.030458 -183.367426)
		(stroke
			(width 0.07112)
			(type default)
		)
		(layer "In15.Cu")
	)
	(gr_line
		(start 11.571986 -307.614828)
		(end 11.548364 -306.916582)
		(stroke
			(width 0.07112)
			(type default)
		)
		(layer "In15.Cu")
	)
	(gr_line
		(start 11.610086 -308.737)
		(end 11.586464 -308.038754)
		(stroke
			(width 0.07112)
			(type default)
		)
		(layer "In15.Cu")
	)
	(gr_line
		(start 11.648186 -309.859172)
		(end 11.624564 -309.160926)
		(stroke
			(width 0.07112)
			(type default)
		)
		(layer "In15.Cu")
	)
	(gr_line
		(start 11.686286 -310.981344)
		(end 11.662664 -310.283098)
		(stroke
			(width 0.07112)
			(type default)
		)
		(layer "In15.Cu")
	)
	(gr_line
		(start 11.855196 -307.604414)
		(end 11.986768 -307.463952)
		(stroke
			(width 0.07112)
			(type default)
		)
		(layer "In15.Cu")
	)
	(gr_line
		(start 11.893296 -308.726586)
		(end 12.024868 -308.586124)
		(stroke
			(width 0.07112)
			(type default)
		)
		(layer "In15.Cu")
	)
	(gr_line
		(start 11.931396 -309.848758)
		(end 12.062968 -309.708296)
		(stroke
			(width 0.07112)
			(type default)
		)
		(layer "In15.Cu")
	)
	(gr_line
		(start 11.969496 -310.97093)
		(end 12.101068 -310.830468)
		(stroke
			(width 0.07112)
			(type default)
		)
		(layer "In15.Cu")
	)
	(gr_line
		(start 11.97229 -307.039518)
		(end 11.831574 -306.9082)
		(stroke
			(width 0.07112)
			(type default)
		)
		(layer "In15.Cu")
	)
	(gr_line
		(start 11.986768 -307.463952)
		(end 11.97229 -307.039518)
		(stroke
			(width 0.07112)
			(type default)
		)
		(layer "In15.Cu")
	)
	(gr_line
		(start 12.01039 -308.16169)
		(end 11.869674 -308.030372)
		(stroke
			(width 0.07112)
			(type default)
		)
		(layer "In15.Cu")
	)
	(gr_line
		(start 12.024868 -308.586124)
		(end 12.01039 -308.16169)
		(stroke
			(width 0.07112)
			(type default)
		)
		(layer "In15.Cu")
	)
	(gr_line
		(start 12.04849 -309.283862)
		(end 11.90752 -309.152544)
		(stroke
			(width 0.07112)
			(type default)
		)
		(layer "In15.Cu")
	)
	(gr_line
		(start 12.062968 -309.708296)
		(end 12.04849 -309.283862)
		(stroke
			(width 0.07112)
			(type default)
		)
		(layer "In15.Cu")
	)
	(gr_line
		(start 12.08659 -310.406034)
		(end 11.94562 -310.274716)
		(stroke
			(width 0.07112)
			(type default)
		)
		(layer "In15.Cu")
	)
	(gr_line
		(start 12.101068 -310.830468)
		(end 12.08659 -310.406034)
		(stroke
			(width 0.07112)
			(type default)
		)
		(layer "In15.Cu")
	)
	(gr_line
		(start 12.270232 -427.069504)
		(end 12.971272 -427.069504)
		(stroke
			(width 0.07112)
			(type default)
		)
		(layer "In15.Cu")
	)
	(gr_line
		(start 12.271502 -426.786294)
		(end 12.407392 -426.650404)
		(stroke
			(width 0.07112)
			(type default)
		)
		(layer "In15.Cu")
	)
	(gr_line
		(start 12.407392 -426.650404)
		(end 12.834112 -426.650404)
		(stroke
			(width 0.07112)
			(type default)
		)
		(layer "In15.Cu")
	)
	(gr_line
		(start 12.732258 -308.630828)
		(end 12.708636 -307.932582)
		(stroke
			(width 0.07112)
			(type default)
		)
		(layer "In15.Cu")
	)
	(gr_line
		(start 12.770358 -309.753)
		(end 12.746736 -309.054754)
		(stroke
			(width 0.07112)
			(type default)
		)
		(layer "In15.Cu")
	)
	(gr_line
		(start 12.808458 -310.875172)
		(end 12.784836 -310.176926)
		(stroke
			(width 0.07112)
			(type default)
		)
		(layer "In15.Cu")
	)
	(gr_line
		(start 12.834112 -426.650404)
		(end 12.970002 -426.786294)
		(stroke
			(width 0.07112)
			(type default)
		)
		(layer "In15.Cu")
	)
	(gr_line
		(start 12.846558 -311.997344)
		(end 12.822936 -311.299098)
		(stroke
			(width 0.07112)
			(type default)
		)
		(layer "In15.Cu")
	)
	(gr_line
		(start 13.015468 -308.620414)
		(end 13.14704 -308.479952)
		(stroke
			(width 0.07112)
			(type default)
		)
		(layer "In15.Cu")
	)
	(gr_line
		(start 13.053568 -309.742586)
		(end 13.18514 -309.602124)
		(stroke
			(width 0.07112)
			(type default)
		)
		(layer "In15.Cu")
	)
	(gr_line
		(start 13.091668 -310.864758)
		(end 13.22324 -310.724296)
		(stroke
			(width 0.07112)
			(type default)
		)
		(layer "In15.Cu")
	)
	(gr_line
		(start 13.129768 -311.98693)
		(end 13.26134 -311.846468)
		(stroke
			(width 0.07112)
			(type default)
		)
		(layer "In15.Cu")
	)
	(gr_line
		(start 13.132562 -308.055518)
		(end 12.991846 -307.9242)
		(stroke
			(width 0.07112)
			(type default)
		)
		(layer "In15.Cu")
	)
	(gr_line
		(start 13.14704 -308.479952)
		(end 13.132562 -308.055518)
		(stroke
			(width 0.07112)
			(type default)
		)
		(layer "In15.Cu")
	)
	(gr_line
		(start 13.170662 -309.17769)
		(end 13.029946 -309.046372)
		(stroke
			(width 0.07112)
			(type default)
		)
		(layer "In15.Cu")
	)
	(gr_line
		(start 13.18514 -309.602124)
		(end 13.170662 -309.17769)
		(stroke
			(width 0.07112)
			(type default)
		)
		(layer "In15.Cu")
	)
	(gr_line
		(start 13.208762 -310.299862)
		(end 13.067792 -310.168544)
		(stroke
			(width 0.07112)
			(type default)
		)
		(layer "In15.Cu")
	)
	(gr_line
		(start 13.22324 -310.724296)
		(end 13.208762 -310.299862)
		(stroke
			(width 0.07112)
			(type default)
		)
		(layer "In15.Cu")
	)
	(gr_line
		(start 13.246862 -311.422034)
		(end 13.105892 -311.290716)
		(stroke
			(width 0.07112)
			(type default)
		)
		(layer "In15.Cu")
	)
	(gr_line
		(start 13.26134 -311.846468)
		(end 13.246862 -311.422034)
		(stroke
			(width 0.07112)
			(type default)
		)
		(layer "In15.Cu")
	)
	(gr_line
		(start 13.397992 -427.069504)
		(end 14.099032 -427.069504)
		(stroke
			(width 0.07112)
			(type default)
		)
		(layer "In15.Cu")
	)
	(gr_line
		(start 13.399262 -426.786294)
		(end 13.535152 -426.650404)
		(stroke
			(width 0.07112)
			(type default)
		)
		(layer "In15.Cu")
	)
	(gr_line
		(start 13.535152 -426.650404)
		(end 13.961872 -426.650404)
		(stroke
			(width 0.07112)
			(type default)
		)
		(layer "In15.Cu")
	)
	(gr_line
		(start 13.89761 -309.209186)
		(end 13.873988 -308.51094)
		(stroke
			(width 0.07112)
			(type default)
		)
		(layer "In15.Cu")
	)
	(gr_line
		(start 13.93571 -310.331358)
		(end 13.912088 -309.633112)
		(stroke
			(width 0.07112)
			(type default)
		)
		(layer "In15.Cu")
	)
	(gr_line
		(start 13.961872 -426.650404)
		(end 14.097762 -426.786294)
		(stroke
			(width 0.07112)
			(type default)
		)
		(layer "In15.Cu")
	)
	(gr_line
		(start 13.97381 -311.45353)
		(end 13.950188 -310.755284)
		(stroke
			(width 0.07112)
			(type default)
		)
		(layer "In15.Cu")
	)
	(gr_line
		(start 14.01191 -312.575702)
		(end 13.988288 -311.877456)
		(stroke
			(width 0.07112)
			(type default)
		)
		(layer "In15.Cu")
	)
	(gr_line
		(start 14.18082 -309.198772)
		(end 14.312392 -309.05831)
		(stroke
			(width 0.07112)
			(type default)
		)
		(layer "In15.Cu")
	)
	(gr_line
		(start 14.21892 -310.320944)
		(end 14.350492 -310.180482)
		(stroke
			(width 0.07112)
			(type default)
		)
		(layer "In15.Cu")
	)
	(gr_line
		(start 14.256766 -311.443116)
		(end 14.388592 -311.302654)
		(stroke
			(width 0.07112)
			(type default)
		)
		(layer "In15.Cu")
	)
	(gr_line
		(start 14.294866 -312.565288)
		(end 14.426438 -312.424572)
		(stroke
			(width 0.07112)
			(type default)
		)
		(layer "In15.Cu")
	)
	(gr_line
		(start 14.297914 -308.633876)
		(end 14.157198 -308.502558)
		(stroke
			(width 0.07112)
			(type default)
		)
		(layer "In15.Cu")
	)
	(gr_line
		(start 14.312392 -309.05831)
		(end 14.297914 -308.633876)
		(stroke
			(width 0.07112)
			(type default)
		)
		(layer "In15.Cu")
	)
	(gr_line
		(start 14.336014 -309.756048)
		(end 14.195044 -309.62473)
		(stroke
			(width 0.07112)
			(type default)
		)
		(layer "In15.Cu")
	)
	(gr_line
		(start 14.350492 -310.180482)
		(end 14.336014 -309.756048)
		(stroke
			(width 0.07112)
			(type default)
		)
		(layer "In15.Cu")
	)
	(gr_line
		(start 14.374114 -310.87822)
		(end 14.233144 -310.746902)
		(stroke
			(width 0.07112)
			(type default)
		)
		(layer "In15.Cu")
	)
	(gr_line
		(start 14.388592 -311.302654)
		(end 14.374114 -310.87822)
		(stroke
			(width 0.07112)
			(type default)
		)
		(layer "In15.Cu")
	)
	(gr_line
		(start 14.412214 -312.000392)
		(end 14.271244 -311.869074)
		(stroke
			(width 0.07112)
			(type default)
		)
		(layer "In15.Cu")
	)
	(gr_line
		(start 14.426438 -312.424572)
		(end 14.412214 -312.000392)
		(stroke
			(width 0.07112)
			(type default)
		)
		(layer "In15.Cu")
	)
	(gr_line
		(start 14.525752 -427.069504)
		(end 15.226792 -427.069504)
		(stroke
			(width 0.07112)
			(type default)
		)
		(layer "In15.Cu")
	)
	(gr_line
		(start 14.527022 -426.786294)
		(end 14.662912 -426.650404)
		(stroke
			(width 0.07112)
			(type default)
		)
		(layer "In15.Cu")
	)
	(gr_line
		(start 14.662912 -426.650404)
		(end 15.089632 -426.650404)
		(stroke
			(width 0.07112)
			(type default)
		)
		(layer "In15.Cu")
	)
	(gr_line
		(start 15.0241 -310.093106)
		(end 15.000478 -309.39486)
		(stroke
			(width 0.07112)
			(type default)
		)
		(layer "In15.Cu")
	)
	(gr_line
		(start 15.0622 -311.215278)
		(end 15.038578 -310.517032)
		(stroke
			(width 0.07112)
			(type default)
		)
		(layer "In15.Cu")
	)
	(gr_line
		(start 15.089632 -426.650404)
		(end 15.225522 -426.786294)
		(stroke
			(width 0.07112)
			(type default)
		)
		(layer "In15.Cu")
	)
	(gr_line
		(start 15.1003 -312.33745)
		(end 15.076678 -311.639204)
		(stroke
			(width 0.07112)
			(type default)
		)
		(layer "In15.Cu")
	)
	(gr_line
		(start 15.1384 -313.459622)
		(end 15.114778 -312.761376)
		(stroke
			(width 0.07112)
			(type default)
		)
		(layer "In15.Cu")
	)
	(gr_line
		(start 15.30731 -310.082692)
		(end 15.438882 -309.94223)
		(stroke
			(width 0.07112)
			(type default)
		)
		(layer "In15.Cu")
	)
	(gr_line
		(start 15.34541 -311.204864)
		(end 15.476982 -311.064402)
		(stroke
			(width 0.07112)
			(type default)
		)
		(layer "In15.Cu")
	)
	(gr_line
		(start 15.38351 -312.327036)
		(end 15.515082 -312.186574)
		(stroke
			(width 0.07112)
			(type default)
		)
		(layer "In15.Cu")
	)
	(gr_line
		(start 15.42161 -313.449208)
		(end 15.553182 -313.308746)
		(stroke
			(width 0.07112)
			(type default)
		)
		(layer "In15.Cu")
	)
	(gr_line
		(start 15.424404 -309.517796)
		(end 15.283688 -309.386478)
		(stroke
			(width 0.07112)
			(type default)
		)
		(layer "In15.Cu")
	)
	(gr_line
		(start 15.438882 -309.94223)
		(end 15.424404 -309.517796)
		(stroke
			(width 0.07112)
			(type default)
		)
		(layer "In15.Cu")
	)
	(gr_line
		(start 15.462504 -310.639968)
		(end 15.321788 -310.50865)
		(stroke
			(width 0.07112)
			(type default)
		)
		(layer "In15.Cu")
	)
	(gr_line
		(start 15.476982 -311.064402)
		(end 15.462504 -310.639968)
		(stroke
			(width 0.07112)
			(type default)
		)
		(layer "In15.Cu")
	)
	(gr_line
		(start 15.500604 -311.76214)
		(end 15.359634 -311.630822)
		(stroke
			(width 0.07112)
			(type default)
		)
		(layer "In15.Cu")
	)
	(gr_line
		(start 15.515082 -312.186574)
		(end 15.500604 -311.76214)
		(stroke
			(width 0.07112)
			(type default)
		)
		(layer "In15.Cu")
	)
	(gr_line
		(start 15.538704 -312.884312)
		(end 15.397734 -312.752994)
		(stroke
			(width 0.07112)
			(type default)
		)
		(layer "In15.Cu")
	)
	(gr_line
		(start 15.553182 -313.308746)
		(end 15.538704 -312.884312)
		(stroke
			(width 0.07112)
			(type default)
		)
		(layer "In15.Cu")
	)
	(gr_line
		(start 15.653512 -427.069504)
		(end 16.354552 -427.069504)
		(stroke
			(width 0.07112)
			(type default)
		)
		(layer "In15.Cu")
	)
	(gr_line
		(start 15.654782 -426.786294)
		(end 15.790672 -426.650404)
		(stroke
			(width 0.07112)
			(type default)
		)
		(layer "In15.Cu")
	)
	(gr_line
		(start 15.699486 -320.667634)
		(end 15.699232 -320.667634)
		(stroke
			(width 0.07112)
			(type default)
		)
		(layer "In15.Cu")
	)
	(gr_line
		(start 15.790672 -426.650404)
		(end 16.217392 -426.650404)
		(stroke
			(width 0.07112)
			(type default)
		)
		(layer "In15.Cu")
	)
	(gr_line
		(start 15.954248 -105.1687)
		(end 15.855188 -103.35768)
		(stroke
			(width 0.2)
			(type default)
		)
		(layer "In15.Cu")
	)
	(gr_line
		(start 15.954248 -104.699308)
		(end 15.954248 -104.6734)
		(stroke
			(width 0.07112)
			(type default)
		)
		(layer "In15.Cu")
	)
	(gr_line
		(start 16.217392 -426.650404)
		(end 16.353282 -426.786294)
		(stroke
			(width 0.07112)
			(type default)
		)
		(layer "In15.Cu")
	)
	(gr_line
		(start 16.2941 -105.03916)
		(end 15.954248 -104.699308)
		(stroke
			(width 0.07112)
			(type default)
		)
		(layer "In15.Cu")
	)
	(gr_line
		(start 16.296132 -105.32237)
		(end 15.954502 -105.664)
		(stroke
			(width 0.07112)
			(type default)
		)
		(layer "In15.Cu")
	)
	(gr_line
		(start 16.297402 -105.03916)
		(end 16.2941 -105.03916)
		(stroke
			(width 0.07112)
			(type default)
		)
		(layer "In15.Cu")
	)
	(gr_line
		(start 17.057116 -427.069504)
		(end 17.753076 -427.069504)
		(stroke
			(width 0.07112)
			(type default)
		)
		(layer "In15.Cu")
	)
	(gr_line
		(start 17.058386 -426.786294)
		(end 17.191736 -426.652944)
		(stroke
			(width 0.07112)
			(type default)
		)
		(layer "In15.Cu")
	)
	(gr_line
		(start 17.191736 -426.652944)
		(end 17.618456 -426.652944)
		(stroke
			(width 0.07112)
			(type default)
		)
		(layer "In15.Cu")
	)
	(gr_line
		(start 17.618456 -426.652944)
		(end 17.751806 -426.786294)
		(stroke
			(width 0.07112)
			(type default)
		)
		(layer "In15.Cu")
	)
	(gr_line
		(start 18.179796 -427.069504)
		(end 18.875756 -427.069504)
		(stroke
			(width 0.07112)
			(type default)
		)
		(layer "In15.Cu")
	)
	(gr_line
		(start 18.181066 -426.786294)
		(end 18.314416 -426.652944)
		(stroke
			(width 0.07112)
			(type default)
		)
		(layer "In15.Cu")
	)
	(gr_line
		(start 18.314416 -426.652944)
		(end 18.741136 -426.652944)
		(stroke
			(width 0.07112)
			(type default)
		)
		(layer "In15.Cu")
	)
	(gr_line
		(start 18.741136 -426.652944)
		(end 18.874486 -426.786294)
		(stroke
			(width 0.07112)
			(type default)
		)
		(layer "In15.Cu")
	)
	(gr_line
		(start 19.302476 -427.069504)
		(end 19.998436 -427.069504)
		(stroke
			(width 0.07112)
			(type default)
		)
		(layer "In15.Cu")
	)
	(gr_line
		(start 19.303746 -426.786294)
		(end 19.437096 -426.652944)
		(stroke
			(width 0.07112)
			(type default)
		)
		(layer "In15.Cu")
	)
	(gr_line
		(start 19.437096 -426.652944)
		(end 19.863816 -426.652944)
		(stroke
			(width 0.07112)
			(type default)
		)
		(layer "In15.Cu")
	)
	(gr_line
		(start 19.863816 -426.652944)
		(end 19.997166 -426.786294)
		(stroke
			(width 0.07112)
			(type default)
		)
		(layer "In15.Cu")
	)
	(gr_line
		(start 20.400772 -138.001502)
		(end 20.400772 -137.789412)
		(stroke
			(width 0.07112)
			(type default)
		)
		(layer "In15.Cu")
	)
	(gr_line
		(start 20.400772 -137.789412)
		(end 20.543012 -137.647172)
		(stroke
			(width 0.07112)
			(type default)
		)
		(layer "In15.Cu")
	)
	(gr_line
		(start 20.400772 -137.222992)
		(end 20.543012 -137.365232)
		(stroke
			(width 0.07112)
			(type default)
		)
		(layer "In15.Cu")
	)
	(gr_line
		(start 20.400772 -137.010902)
		(end 20.400772 -137.222992)
		(stroke
			(width 0.07112)
			(type default)
		)
		(layer "In15.Cu")
	)
	(gr_line
		(start 20.44573 -427.069504)
		(end 21.12645 -427.069504)
		(stroke
			(width 0.07112)
			(type default)
		)
		(layer "In15.Cu")
	)
	(gr_line
		(start 20.447 -426.786294)
		(end 20.57273 -426.660564)
		(stroke
			(width 0.07112)
			(type default)
		)
		(layer "In15.Cu")
	)
	(gr_line
		(start 20.57273 -426.660564)
		(end 20.99945 -426.660564)
		(stroke
			(width 0.07112)
			(type default)
		)
		(layer "In15.Cu")
	)
	(gr_line
		(start 20.99945 -426.660564)
		(end 21.12518 -426.786294)
		(stroke
			(width 0.07112)
			(type default)
		)
		(layer "In15.Cu")
	)
	(gr_line
		(start 23.152862 -425.380658)
		(end 23.152862 -425.380404)
		(stroke
			(width 0.07112)
			(type default)
		)
		(layer "In15.Cu")
	)
	(gr_line
		(start 23.42642 -425.448984)
		(end 23.426928 -425.44873)
		(stroke
			(width 0.07112)
			(type default)
		)
		(layer "In15.Cu")
	)
	(gr_line
		(start 23.728426 -371.742716)
		(end 23.728426 -371.550692)
		(stroke
			(width 0.07112)
			(type default)
		)
		(layer "In15.Cu")
	)
	(gr_line
		(start 24.030432 -372.044722)
		(end 23.728426 -371.742716)
		(stroke
			(width 0.07112)
			(type default)
		)
		(layer "In15.Cu")
	)
	(gr_line
		(start 24.222456 -372.044722)
		(end 24.030432 -372.044722)
		(stroke
			(width 0.07112)
			(type default)
		)
		(layer "In15.Cu")
	)
	(gr_line
		(start 24.423624 -371.845332)
		(end 23.927816 -371.349524)
		(stroke
			(width 0.07112)
			(type default)
		)
		(layer "In15.Cu")
	)
	(gr_line
		(start 24.95931 -421.549322)
		(end 24.976074 -421.549322)
		(stroke
			(width 0.07112)
			(type default)
		)
		(layer "In15.Cu")
	)
	(gr_line
		(start 24.96058 -421.832532)
		(end 25.258522 -422.130474)
		(stroke
			(width 0.07112)
			(type default)
		)
		(layer "In15.Cu")
	)
	(gr_line
		(start 24.976074 -421.549322)
		(end 25.258522 -421.266874)
		(stroke
			(width 0.07112)
			(type default)
		)
		(layer "In15.Cu")
	)
	(gr_line
		(start 25.240742 -428.023782)
		(end 25.202642 -428.023782)
		(stroke
			(width 0.07112)
			(type default)
		)
		(layer "In15.Cu")
	)
	(gr_line
		(start 25.512522 -428.615602)
		(end 25.203912 -428.306992)
		(stroke
			(width 0.07112)
			(type default)
		)
		(layer "In15.Cu")
	)
	(gr_line
		(start 25.512522 -427.752002)
		(end 25.240742 -428.023782)
		(stroke
			(width 0.07112)
			(type default)
		)
		(layer "In15.Cu")
	)
	(gr_line
		(start 39.11854 -425.909994)
		(end 39.402258 -425.626276)
		(stroke
			(width 0.07112)
			(type default)
		)
		(layer "In15.Cu")
	)
	(gr_line
		(start 39.402258 -425.626276)
		(end 39.402258 -425.612052)
		(stroke
			(width 0.07112)
			(type default)
		)
		(layer "In15.Cu")
	)
	(gr_line
		(start 39.435024 -422.348152)
		(end 39.144194 -422.638982)
		(stroke
			(width 0.07112)
			(type default)
		)
		(layer "In15.Cu")
	)
	(gr_line
		(start 39.716964 -422.348152)
		(end 40.007794 -422.638982)
		(stroke
			(width 0.07112)
			(type default)
		)
		(layer "In15.Cu")
	)
	(gr_line
		(start 39.981124 -417.470336)
		(end 40.018716 -417.28136)
		(stroke
			(width 0.07112)
			(type default)
		)
		(layer "In15.Cu")
	)
	(gr_line
		(start 39.98214 -425.909994)
		(end 39.685468 -425.613322)
		(stroke
			(width 0.07112)
			(type default)
		)
		(layer "In15.Cu")
	)
	(gr_line
		(start 40.218614 -417.825428)
		(end 39.981124 -417.470336)
		(stroke
			(width 0.07112)
			(type default)
		)
		(layer "In15.Cu")
	)
	(gr_line
		(start 40.253666 -417.123372)
		(end 40.253412 -417.123372)
		(stroke
			(width 0.07112)
			(type default)
		)
		(layer "In15.Cu")
	)
	(gr_line
		(start 40.407082 -417.862766)
		(end 40.218614 -417.825428)
		(stroke
			(width 0.07112)
			(type default)
		)
		(layer "In15.Cu")
	)
	(gr_line
		(start 40.549068 -418.073078)
		(end 40.40886 -417.86302)
		(stroke
			(width 0.07112)
			(type default)
		)
		(layer "In15.Cu")
	)
	(gr_line
		(start 40.643302 -417.706556)
		(end 40.253666 -417.123372)
		(stroke
			(width 0.07112)
			(type default)
		)
		(layer "In15.Cu")
	)
	(gr_line
		(start 40.670226 -418.25418)
		(end 40.669718 -418.253672)
		(stroke
			(width 0.07112)
			(type default)
		)
		(layer "In15.Cu")
	)
	(gr_line
		(start 40.858948 -418.537136)
		(end 40.670226 -418.25418)
		(stroke
			(width 0.07112)
			(type default)
		)
		(layer "In15.Cu")
	)
	(gr_line
		(start 40.859456 -418.784786)
		(end 40.897048 -418.59581)
		(stroke
			(width 0.07112)
			(type default)
		)
		(layer "In15.Cu")
	)
	(gr_line
		(start 40.903906 -418.096954)
		(end 40.90416 -418.096954)
		(stroke
			(width 0.07112)
			(type default)
		)
		(layer "In15.Cu")
	)
	(gr_line
		(start 40.904414 -418.09797)
		(end 40.903906 -418.096954)
		(stroke
			(width 0.07112)
			(type default)
		)
		(layer "In15.Cu")
	)
	(gr_line
		(start 41.096692 -419.139878)
		(end 40.859456 -418.784786)
		(stroke
			(width 0.07112)
			(type default)
		)
		(layer "In15.Cu")
	)
	(gr_line
		(start 41.131998 -418.437822)
		(end 41.131744 -418.437822)
		(stroke
			(width 0.07112)
			(type default)
		)
		(layer "In15.Cu")
	)
	(gr_line
		(start 41.285414 -419.17747)
		(end 41.096692 -419.139878)
		(stroke
			(width 0.07112)
			(type default)
		)
		(layer "In15.Cu")
	)
	(gr_line
		(start 41.45661 -418.923724)
		(end 41.45661 -418.92347)
		(stroke
			(width 0.07112)
			(type default)
		)
		(layer "In15.Cu")
	)
	(gr_line
		(start 41.45661 -418.92347)
		(end 41.131998 -418.437822)
		(stroke
			(width 0.07112)
			(type default)
		)
		(layer "In15.Cu")
	)
	(gr_line
		(start 41.521634 -419.021006)
		(end 41.45661 -418.923724)
		(stroke
			(width 0.07112)
			(type default)
		)
		(layer "In15.Cu")
	)
	(gr_line
		(start 46.771814 -403.092158)
		(end 46.942248 -402.411946)
		(stroke
			(width 0.07112)
			(type default)
		)
		(layer "In15.Cu")
	)
	(gr_line
		(start 47.046896 -403.159722)
		(end 47.211996 -403.06117)
		(stroke
			(width 0.07112)
			(type default)
		)
		(layer "In15.Cu")
	)
	(gr_line
		(start 47.075598 -401.25904)
		(end 47.075598 -400.558)
		(stroke
			(width 0.07112)
			(type default)
		)
		(layer "In15.Cu")
	)
	(gr_line
		(start 47.075598 -400.13128)
		(end 47.075598 -399.43024)
		(stroke
			(width 0.07112)
			(type default)
		)
		(layer "In15.Cu")
	)
	(gr_line
		(start 47.075598 -399.00352)
		(end 47.075598 -398.30248)
		(stroke
			(width 0.07112)
			(type default)
		)
		(layer "In15.Cu")
	)
	(gr_line
		(start 47.075598 -397.87576)
		(end 47.075598 -397.17472)
		(stroke
			(width 0.07112)
			(type default)
		)
		(layer "In15.Cu")
	)
	(gr_line
		(start 47.075598 -396.748)
		(end 47.075598 -396.04696)
		(stroke
			(width 0.07112)
			(type default)
		)
		(layer "In15.Cu")
	)
	(gr_line
		(start 47.075598 -395.62024)
		(end 47.075598 -394.9192)
		(stroke
			(width 0.07112)
			(type default)
		)
		(layer "In15.Cu")
	)
	(gr_line
		(start 47.211996 -403.06117)
		(end 47.315628 -402.646896)
		(stroke
			(width 0.07112)
			(type default)
		)
		(layer "In15.Cu")
	)
	(gr_line
		(start 47.315628 -402.646896)
		(end 47.216822 -402.481796)
		(stroke
			(width 0.07112)
			(type default)
		)
		(layer "In15.Cu")
	)
	(gr_line
		(start 47.358808 -401.25777)
		(end 47.494698 -401.12188)
		(stroke
			(width 0.07112)
			(type default)
		)
		(layer "In15.Cu")
	)
	(gr_line
		(start 47.358808 -400.13001)
		(end 47.494698 -399.99412)
		(stroke
			(width 0.07112)
			(type default)
		)
		(layer "In15.Cu")
	)
	(gr_line
		(start 47.358808 -399.00225)
		(end 47.494698 -398.86636)
		(stroke
			(width 0.07112)
			(type default)
		)
		(layer "In15.Cu")
	)
	(gr_line
		(start 47.358808 -397.87449)
		(end 47.494698 -397.7386)
		(stroke
			(width 0.07112)
			(type default)
		)
		(layer "In15.Cu")
	)
	(gr_line
		(start 47.358808 -396.74673)
		(end 47.494698 -396.61084)
		(stroke
			(width 0.07112)
			(type default)
		)
		(layer "In15.Cu")
	)
	(gr_line
		(start 47.358808 -395.61897)
		(end 47.494698 -395.48308)
		(stroke
			(width 0.07112)
			(type default)
		)
		(layer "In15.Cu")
	)
	(gr_line
		(start 47.494698 -401.12188)
		(end 47.494698 -400.69516)
		(stroke
			(width 0.07112)
			(type default)
		)
		(layer "In15.Cu")
	)
	(gr_line
		(start 47.494698 -400.69516)
		(end 47.358808 -400.55927)
		(stroke
			(width 0.07112)
			(type default)
		)
		(layer "In15.Cu")
	)
	(gr_line
		(start 47.494698 -399.99412)
		(end 47.494698 -399.5674)
		(stroke
			(width 0.07112)
			(type default)
		)
		(layer "In15.Cu")
	)
	(gr_line
		(start 47.494698 -399.5674)
		(end 47.358808 -399.43151)
		(stroke
			(width 0.07112)
			(type default)
		)
		(layer "In15.Cu")
	)
	(gr_line
		(start 47.494698 -398.86636)
		(end 47.494698 -398.43964)
		(stroke
			(width 0.07112)
			(type default)
		)
		(layer "In15.Cu")
	)
	(gr_line
		(start 47.494698 -398.43964)
		(end 47.358808 -398.30375)
		(stroke
			(width 0.07112)
			(type default)
		)
		(layer "In15.Cu")
	)
	(gr_line
		(start 47.494698 -397.7386)
		(end 47.494698 -397.31188)
		(stroke
			(width 0.07112)
			(type default)
		)
		(layer "In15.Cu")
	)
	(gr_line
		(start 47.494698 -397.31188)
		(end 47.358808 -397.17599)
		(stroke
			(width 0.07112)
			(type default)
		)
		(layer "In15.Cu")
	)
	(gr_line
		(start 47.494698 -396.61084)
		(end 47.494698 -396.18412)
		(stroke
			(width 0.07112)
			(type default)
		)
		(layer "In15.Cu")
	)
	(gr_line
		(start 47.494698 -396.18412)
		(end 47.358808 -396.04823)
		(stroke
			(width 0.07112)
			(type default)
		)
		(layer "In15.Cu")
	)
	(gr_line
		(start 47.494698 -395.48308)
		(end 47.494698 -395.05636)
		(stroke
			(width 0.07112)
			(type default)
		)
		(layer "In15.Cu")
	)
	(gr_line
		(start 47.494698 -395.05636)
		(end 47.358808 -394.92047)
		(stroke
			(width 0.07112)
			(type default)
		)
		(layer "In15.Cu")
	)
	(gr_line
		(start 47.67707 -392.707622)
		(end 47.689516 -392.707622)
		(stroke
			(width 0.07112)
			(type default)
		)
		(layer "In15.Cu")
	)
	(gr_line
		(start 47.67834 -392.990832)
		(end 47.816516 -393.129008)
		(stroke
			(width 0.07112)
			(type default)
		)
		(layer "In15.Cu")
	)
	(gr_line
		(start 47.689516 -392.707622)
		(end 47.816516 -392.580622)
		(stroke
			(width 0.07112)
			(type default)
		)
		(layer "In15.Cu")
	)
	(gr_line
		(start 47.816516 -393.129008)
		(end 47.816516 -393.292838)
		(stroke
			(width 0.07112)
			(type default)
		)
		(layer "In15.Cu")
	)
	(gr_line
		(start 47.816516 -392.580622)
		(end 47.816516 -392.429238)
		(stroke
			(width 0.07112)
			(type default)
		)
		(layer "In15.Cu")
	)
	(gr_line
		(start 48.084994 -408.126692)
		(end 48.084994 -407.425652)
		(stroke
			(width 0.07112)
			(type default)
		)
		(layer "In15.Cu")
	)
	(gr_line
		(start 48.275494 -399.53819)
		(end 48.275494 -398.83715)
		(stroke
			(width 0.07112)
			(type default)
		)
		(layer "In15.Cu")
	)
	(gr_line
		(start 48.275494 -398.41043)
		(end 48.275494 -397.70939)
		(stroke
			(width 0.07112)
			(type default)
		)
		(layer "In15.Cu")
	)
	(gr_line
		(start 48.275494 -397.28267)
		(end 48.275494 -396.58163)
		(stroke
			(width 0.07112)
			(type default)
		)
		(layer "In15.Cu")
	)
	(gr_line
		(start 48.275494 -396.15491)
		(end 48.275494 -395.45387)
		(stroke
			(width 0.07112)
			(type default)
		)
		(layer "In15.Cu")
	)
	(gr_line
		(start 48.275494 -395.02715)
		(end 48.275494 -394.32611)
		(stroke
			(width 0.07112)
			(type default)
		)
		(layer "In15.Cu")
	)
	(gr_line
		(start 48.368204 -408.125422)
		(end 48.504094 -407.989532)
		(stroke
			(width 0.07112)
			(type default)
		)
		(layer "In15.Cu")
	)
	(gr_line
		(start 48.460152 -400.839686)
		(end 48.459898 -400.839686)
		(stroke
			(width 0.07112)
			(type default)
		)
		(layer "In15.Cu")
	)
	(gr_line
		(start 48.504094 -407.989532)
		(end 48.504094 -407.562812)
		(stroke
			(width 0.07112)
			(type default)
		)
		(layer "In15.Cu")
	)
	(gr_line
		(start 48.504094 -407.562812)
		(end 48.368204 -407.426922)
		(stroke
			(width 0.07112)
			(type default)
		)
		(layer "In15.Cu")
	)
	(gr_line
		(start 48.558704 -399.53692)
		(end 48.694594 -399.40103)
		(stroke
			(width 0.07112)
			(type default)
		)
		(layer "In15.Cu")
	)
	(gr_line
		(start 48.558704 -398.40916)
		(end 48.694594 -398.27327)
		(stroke
			(width 0.07112)
			(type default)
		)
		(layer "In15.Cu")
	)
	(gr_line
		(start 48.558704 -397.2814)
		(end 48.694594 -397.14551)
		(stroke
			(width 0.07112)
			(type default)
		)
		(layer "In15.Cu")
	)
	(gr_line
		(start 48.558704 -396.15364)
		(end 48.694594 -396.01775)
		(stroke
			(width 0.07112)
			(type default)
		)
		(layer "In15.Cu")
	)
	(gr_line
		(start 48.558704 -395.02588)
		(end 48.694594 -394.88999)
		(stroke
			(width 0.07112)
			(type default)
		)
		(layer "In15.Cu")
	)
	(gr_line
		(start 48.694594 -399.40103)
		(end 48.694594 -398.97431)
		(stroke
			(width 0.07112)
			(type default)
		)
		(layer "In15.Cu")
	)
	(gr_line
		(start 48.694594 -398.97431)
		(end 48.558704 -398.83842)
		(stroke
			(width 0.07112)
			(type default)
		)
		(layer "In15.Cu")
	)
	(gr_line
		(start 48.694594 -398.27327)
		(end 48.694594 -397.84655)
		(stroke
			(width 0.07112)
			(type default)
		)
		(layer "In15.Cu")
	)
	(gr_line
		(start 48.694594 -397.84655)
		(end 48.558704 -397.71066)
		(stroke
			(width 0.07112)
			(type default)
		)
		(layer "In15.Cu")
	)
	(gr_line
		(start 48.694594 -397.14551)
		(end 48.694594 -396.71879)
		(stroke
			(width 0.07112)
			(type default)
		)
		(layer "In15.Cu")
	)
	(gr_line
		(start 48.694594 -396.71879)
		(end 48.558704 -396.5829)
		(stroke
			(width 0.07112)
			(type default)
		)
		(layer "In15.Cu")
	)
	(gr_line
		(start 48.694594 -396.01775)
		(end 48.694594 -395.59103)
		(stroke
			(width 0.07112)
			(type default)
		)
		(layer "In15.Cu")
	)
	(gr_line
		(start 48.694594 -395.59103)
		(end 48.558704 -395.45514)
		(stroke
			(width 0.07112)
			(type default)
		)
		(layer "In15.Cu")
	)
	(gr_line
		(start 48.694594 -394.88999)
		(end 48.694594 -394.46327)
		(stroke
			(width 0.07112)
			(type default)
		)
		(layer "In15.Cu")
	)
	(gr_line
		(start 48.694594 -394.46327)
		(end 48.558704 -394.32738)
		(stroke
			(width 0.07112)
			(type default)
		)
		(layer "In15.Cu")
	)
	(gr_line
		(start 48.72863 -401.487894)
		(end 48.460152 -400.839686)
		(stroke
			(width 0.07112)
			(type default)
		)
		(layer "In15.Cu")
	)
	(gr_line
		(start 48.876966 -392.707622)
		(end 48.889412 -392.707622)
		(stroke
			(width 0.07112)
			(type default)
		)
		(layer "In15.Cu")
	)
	(gr_line
		(start 48.878236 -392.990832)
		(end 49.016412 -393.129008)
		(stroke
			(width 0.07112)
			(type default)
		)
		(layer "In15.Cu")
	)
	(gr_line
		(start 48.889412 -392.707622)
		(end 49.016412 -392.580622)
		(stroke
			(width 0.07112)
			(type default)
		)
		(layer "In15.Cu")
	)
	(gr_line
		(start 48.891698 -401.881848)
		(end 48.855122 -401.793202)
		(stroke
			(width 0.07112)
			(type default)
		)
		(layer "In15.Cu")
	)
	(gr_line
		(start 48.90008 -400.806158)
		(end 48.722534 -400.732752)
		(stroke
			(width 0.07112)
			(type default)
		)
		(layer "In15.Cu")
	)
	(gr_line
		(start 48.903636 -417.145978)
		(end 49.194466 -417.436808)
		(stroke
			(width 0.07112)
			(type default)
		)
		(layer "In15.Cu")
	)
	(gr_line
		(start 48.903636 -416.864038)
		(end 49.194466 -416.573208)
		(stroke
			(width 0.07112)
			(type default)
		)
		(layer "In15.Cu")
	)
	(gr_line
		(start 48.989742 -401.37842)
		(end 49.063402 -401.20062)
		(stroke
			(width 0.07112)
			(type default)
		)
		(layer "In15.Cu")
	)
	(gr_line
		(start 49.016412 -393.129008)
		(end 49.016412 -393.292838)
		(stroke
			(width 0.07112)
			(type default)
		)
		(layer "In15.Cu")
	)
	(gr_line
		(start 49.016412 -392.580622)
		(end 49.016412 -392.429238)
		(stroke
			(width 0.07112)
			(type default)
		)
		(layer "In15.Cu")
	)
	(gr_line
		(start 49.063402 -401.20062)
		(end 48.90008 -400.806158)
		(stroke
			(width 0.07112)
			(type default)
		)
		(layer "In15.Cu")
	)
	(gr_line
		(start 49.152302 -401.774152)
		(end 49.115472 -401.685506)
		(stroke
			(width 0.07112)
			(type default)
		)
		(layer "In15.Cu")
	)
	(gr_line
		(start 49.160176 -402.530056)
		(end 48.891698 -401.881848)
		(stroke
			(width 0.07112)
			(type default)
		)
		(layer "In15.Cu")
	)
	(gr_line
		(start 49.33188 -401.84832)
		(end 49.15408 -401.774914)
		(stroke
			(width 0.07112)
			(type default)
		)
		(layer "In15.Cu")
	)
	(gr_line
		(start 49.421542 -402.420582)
		(end 49.495202 -402.242782)
		(stroke
			(width 0.07112)
			(type default)
		)
		(layer "In15.Cu")
	)
	(gr_line
		(start 49.475644 -398.62887)
		(end 49.475644 -397.92783)
		(stroke
			(width 0.07112)
			(type default)
		)
		(layer "In15.Cu")
	)
	(gr_line
		(start 49.475644 -397.50111)
		(end 49.475644 -396.80007)
		(stroke
			(width 0.07112)
			(type default)
		)
		(layer "In15.Cu")
	)
	(gr_line
		(start 49.475644 -396.37335)
		(end 49.475644 -395.67231)
		(stroke
			(width 0.07112)
			(type default)
		)
		(layer "In15.Cu")
	)
	(gr_line
		(start 49.475644 -395.24559)
		(end 49.475644 -394.54455)
		(stroke
			(width 0.07112)
			(type default)
		)
		(layer "In15.Cu")
	)
	(gr_line
		(start 49.495202 -402.242782)
		(end 49.33188 -401.84832)
		(stroke
			(width 0.07112)
			(type default)
		)
		(layer "In15.Cu")
	)
	(gr_line
		(start 49.758854 -398.6276)
		(end 49.894744 -398.49171)
		(stroke
			(width 0.07112)
			(type default)
		)
		(layer "In15.Cu")
	)
	(gr_line
		(start 49.758854 -397.49984)
		(end 49.894744 -397.36395)
		(stroke
			(width 0.07112)
			(type default)
		)
		(layer "In15.Cu")
	)
	(gr_line
		(start 49.758854 -396.37208)
		(end 49.894744 -396.23619)
		(stroke
			(width 0.07112)
			(type default)
		)
		(layer "In15.Cu")
	)
	(gr_line
		(start 49.758854 -395.24432)
		(end 49.894744 -395.10843)
		(stroke
			(width 0.07112)
			(type default)
		)
		(layer "In15.Cu")
	)
	(gr_line
		(start 49.894744 -398.49171)
		(end 49.894744 -398.06499)
		(stroke
			(width 0.07112)
			(type default)
		)
		(layer "In15.Cu")
	)
	(gr_line
		(start 49.894744 -398.06499)
		(end 49.758854 -397.9291)
		(stroke
			(width 0.07112)
			(type default)
		)
		(layer "In15.Cu")
	)
	(gr_line
		(start 49.894744 -397.36395)
		(end 49.894744 -396.93723)
		(stroke
			(width 0.07112)
			(type default)
		)
		(layer "In15.Cu")
	)
	(gr_line
		(start 49.894744 -396.93723)
		(end 49.758854 -396.80134)
		(stroke
			(width 0.07112)
			(type default)
		)
		(layer "In15.Cu")
	)
	(gr_line
		(start 49.894744 -396.23619)
		(end 49.894744 -395.80947)
		(stroke
			(width 0.07112)
			(type default)
		)
		(layer "In15.Cu")
	)
	(gr_line
		(start 49.894744 -395.80947)
		(end 49.758854 -395.67358)
		(stroke
			(width 0.07112)
			(type default)
		)
		(layer "In15.Cu")
	)
	(gr_line
		(start 49.894744 -395.10843)
		(end 49.894744 -394.68171)
		(stroke
			(width 0.07112)
			(type default)
		)
		(layer "In15.Cu")
	)
	(gr_line
		(start 49.894744 -394.68171)
		(end 49.758854 -394.54582)
		(stroke
			(width 0.07112)
			(type default)
		)
		(layer "In15.Cu")
	)
	(gr_line
		(start 50.077116 -392.707622)
		(end 50.089562 -392.707622)
		(stroke
			(width 0.07112)
			(type default)
		)
		(layer "In15.Cu")
	)
	(gr_line
		(start 50.078386 -392.990832)
		(end 50.216562 -393.129008)
		(stroke
			(width 0.07112)
			(type default)
		)
		(layer "In15.Cu")
	)
	(gr_line
		(start 50.089562 -392.707622)
		(end 50.216562 -392.580622)
		(stroke
			(width 0.07112)
			(type default)
		)
		(layer "In15.Cu")
	)
	(gr_line
		(start 50.216562 -393.129008)
		(end 50.216562 -393.292838)
		(stroke
			(width 0.07112)
			(type default)
		)
		(layer "In15.Cu")
	)
	(gr_line
		(start 50.216562 -392.580622)
		(end 50.216562 -392.429238)
		(stroke
			(width 0.07112)
			(type default)
		)
		(layer "In15.Cu")
	)
	(gr_line
		(start 50.24501 -399.965164)
		(end 50.053494 -399.946368)
		(stroke
			(width 0.07112)
			(type default)
		)
		(layer "In15.Cu")
	)
	(gr_line
		(start 50.278792 -400.666966)
		(end 49.833784 -400.12493)
		(stroke
			(width 0.07112)
			(type default)
		)
		(layer "In15.Cu")
	)
	(gr_line
		(start 50.496978 -400.486626)
		(end 50.515774 -400.29511)
		(stroke
			(width 0.07112)
			(type default)
		)
		(layer "In15.Cu")
	)
	(gr_line
		(start 50.515774 -400.29511)
		(end 50.24501 -399.965164)
		(stroke
			(width 0.07112)
			(type default)
		)
		(layer "In15.Cu")
	)
	(gr_line
		(start 50.67554 -398.128998)
		(end 50.67554 -397.427958)
		(stroke
			(width 0.07112)
			(type default)
		)
		(layer "In15.Cu")
	)
	(gr_line
		(start 50.67554 -397.001238)
		(end 50.67554 -396.300198)
		(stroke
			(width 0.07112)
			(type default)
		)
		(layer "In15.Cu")
	)
	(gr_line
		(start 50.67554 -395.873478)
		(end 50.67554 -395.172438)
		(stroke
			(width 0.07112)
			(type default)
		)
		(layer "In15.Cu")
	)
	(gr_line
		(start 50.67554 -394.745718)
		(end 50.67554 -394.044678)
		(stroke
			(width 0.07112)
			(type default)
		)
		(layer "In15.Cu")
	)
	(gr_line
		(start 50.95875 -398.127728)
		(end 51.09464 -397.991838)
		(stroke
			(width 0.07112)
			(type default)
		)
		(layer "In15.Cu")
	)
	(gr_line
		(start 50.95875 -396.999968)
		(end 51.09464 -396.864078)
		(stroke
			(width 0.07112)
			(type default)
		)
		(layer "In15.Cu")
	)
	(gr_line
		(start 50.95875 -395.872208)
		(end 51.09464 -395.736318)
		(stroke
			(width 0.07112)
			(type default)
		)
		(layer "In15.Cu")
	)
	(gr_line
		(start 50.95875 -394.744448)
		(end 51.09464 -394.608558)
		(stroke
			(width 0.07112)
			(type default)
		)
		(layer "In15.Cu")
	)
	(gr_line
		(start 50.960274 -400.836892)
		(end 50.769012 -400.818096)
		(stroke
			(width 0.07112)
			(type default)
		)
		(layer "In15.Cu")
	)
	(gr_line
		(start 50.99431 -401.538948)
		(end 50.549302 -400.996658)
		(stroke
			(width 0.07112)
			(type default)
		)
		(layer "In15.Cu")
	)
	(gr_line
		(start 51.09464 -397.991838)
		(end 51.09464 -397.565118)
		(stroke
			(width 0.07112)
			(type default)
		)
		(layer "In15.Cu")
	)
	(gr_line
		(start 51.09464 -397.565118)
		(end 50.95875 -397.429228)
		(stroke
			(width 0.07112)
			(type default)
		)
		(layer "In15.Cu")
	)
	(gr_line
		(start 51.09464 -396.864078)
		(end 51.09464 -396.437358)
		(stroke
			(width 0.07112)
			(type default)
		)
		(layer "In15.Cu")
	)
	(gr_line
		(start 51.09464 -396.437358)
		(end 50.95875 -396.301468)
		(stroke
			(width 0.07112)
			(type default)
		)
		(layer "In15.Cu")
	)
	(gr_line
		(start 51.09464 -395.736318)
		(end 51.09464 -395.309598)
		(stroke
			(width 0.07112)
			(type default)
		)
		(layer "In15.Cu")
	)
	(gr_line
		(start 51.09464 -395.309598)
		(end 50.95875 -395.173708)
		(stroke
			(width 0.07112)
			(type default)
		)
		(layer "In15.Cu")
	)
	(gr_line
		(start 51.09464 -394.608558)
		(end 51.09464 -394.181838)
		(stroke
			(width 0.07112)
			(type default)
		)
		(layer "In15.Cu")
	)
	(gr_line
		(start 51.09464 -394.181838)
		(end 50.95875 -394.045948)
		(stroke
			(width 0.07112)
			(type default)
		)
		(layer "In15.Cu")
	)
	(gr_line
		(start 51.148234 -408.197304)
		(end 51.148234 -407.496264)
		(stroke
			(width 0.07112)
			(type default)
		)
		(layer "In15.Cu")
	)
	(gr_line
		(start 51.212496 -401.358354)
		(end 51.231292 -401.167092)
		(stroke
			(width 0.07112)
			(type default)
		)
		(layer "In15.Cu")
	)
	(gr_line
		(start 51.231292 -401.167092)
		(end 50.960274 -400.836892)
		(stroke
			(width 0.07112)
			(type default)
		)
		(layer "In15.Cu")
	)
	(gr_line
		(start 51.277012 -392.707622)
		(end 51.289458 -392.707622)
		(stroke
			(width 0.07112)
			(type default)
		)
		(layer "In15.Cu")
	)
	(gr_line
		(start 51.278282 -392.990832)
		(end 51.416458 -393.129008)
		(stroke
			(width 0.07112)
			(type default)
		)
		(layer "In15.Cu")
	)
	(gr_line
		(start 51.289458 -392.707622)
		(end 51.416458 -392.580622)
		(stroke
			(width 0.07112)
			(type default)
		)
		(layer "In15.Cu")
	)
	(gr_line
		(start 51.416458 -393.129008)
		(end 51.416458 -393.292838)
		(stroke
			(width 0.07112)
			(type default)
		)
		(layer "In15.Cu")
	)
	(gr_line
		(start 51.416458 -392.580622)
		(end 51.416458 -392.429238)
		(stroke
			(width 0.07112)
			(type default)
		)
		(layer "In15.Cu")
	)
	(gr_line
		(start 51.431444 -408.196034)
		(end 51.567334 -408.060144)
		(stroke
			(width 0.07112)
			(type default)
		)
		(layer "In15.Cu")
	)
	(gr_line
		(start 51.453034 -399.033238)
		(end 51.260756 -399.033238)
		(stroke
			(width 0.07112)
			(type default)
		)
		(layer "In15.Cu")
	)
	(gr_line
		(start 51.55565 -399.72869)
		(end 51.059588 -399.232628)
		(stroke
			(width 0.07112)
			(type default)
		)
		(layer "In15.Cu")
	)
	(gr_line
		(start 51.567334 -408.060144)
		(end 51.567334 -407.633424)
		(stroke
			(width 0.07112)
			(type default)
		)
		(layer "In15.Cu")
	)
	(gr_line
		(start 51.567334 -407.633424)
		(end 51.431444 -407.497534)
		(stroke
			(width 0.07112)
			(type default)
		)
		(layer "In15.Cu")
	)
	(gr_line
		(start 51.75504 -399.527522)
		(end 51.75504 -399.335244)
		(stroke
			(width 0.07112)
			(type default)
		)
		(layer "In15.Cu")
	)
	(gr_line
		(start 51.75504 -399.335244)
		(end 51.453034 -399.033238)
		(stroke
			(width 0.07112)
			(type default)
		)
		(layer "In15.Cu")
	)
	(gr_line
		(start 51.87569 -397.298164)
		(end 51.87569 -396.597124)
		(stroke
			(width 0.07112)
			(type default)
		)
		(layer "In15.Cu")
	)
	(gr_line
		(start 51.87569 -396.170404)
		(end 51.87569 -395.469364)
		(stroke
			(width 0.07112)
			(type default)
		)
		(layer "In15.Cu")
	)
	(gr_line
		(start 51.87569 -395.042644)
		(end 51.87569 -394.341604)
		(stroke
			(width 0.07112)
			(type default)
		)
		(layer "In15.Cu")
	)
	(gr_line
		(start 51.93411 -402.023326)
		(end 51.742594 -402.00453)
		(stroke
			(width 0.07112)
			(type default)
		)
		(layer "In15.Cu")
	)
	(gr_line
		(start 51.968146 -402.725636)
		(end 51.523138 -402.183346)
		(stroke
			(width 0.07112)
			(type default)
		)
		(layer "In15.Cu")
	)
	(gr_line
		(start 52.1589 -397.296894)
		(end 52.29479 -397.161004)
		(stroke
			(width 0.07112)
			(type default)
		)
		(layer "In15.Cu")
	)
	(gr_line
		(start 52.1589 -396.169134)
		(end 52.29479 -396.033244)
		(stroke
			(width 0.07112)
			(type default)
		)
		(layer "In15.Cu")
	)
	(gr_line
		(start 52.1589 -395.041374)
		(end 52.29479 -394.905484)
		(stroke
			(width 0.07112)
			(type default)
		)
		(layer "In15.Cu")
	)
	(gr_line
		(start 52.186332 -402.545042)
		(end 52.205128 -402.353526)
		(stroke
			(width 0.07112)
			(type default)
		)
		(layer "In15.Cu")
	)
	(gr_line
		(start 52.205128 -402.353526)
		(end 51.93411 -402.023326)
		(stroke
			(width 0.07112)
			(type default)
		)
		(layer "In15.Cu")
	)
	(gr_line
		(start 52.250594 -399.830798)
		(end 52.058316 -399.830798)
		(stroke
			(width 0.07112)
			(type default)
		)
		(layer "In15.Cu")
	)
	(gr_line
		(start 52.29479 -397.161004)
		(end 52.29479 -396.734284)
		(stroke
			(width 0.07112)
			(type default)
		)
		(layer "In15.Cu")
	)
	(gr_line
		(start 52.29479 -396.734284)
		(end 52.1589 -396.598394)
		(stroke
			(width 0.07112)
			(type default)
		)
		(layer "In15.Cu")
	)
	(gr_line
		(start 52.29479 -396.033244)
		(end 52.29479 -395.606524)
		(stroke
			(width 0.07112)
			(type default)
		)
		(layer "In15.Cu")
	)
	(gr_line
		(start 52.29479 -395.606524)
		(end 52.1589 -395.470634)
		(stroke
			(width 0.07112)
			(type default)
		)
		(layer "In15.Cu")
	)
	(gr_line
		(start 52.29479 -394.905484)
		(end 52.29479 -394.478764)
		(stroke
			(width 0.07112)
			(type default)
		)
		(layer "In15.Cu")
	)
	(gr_line
		(start 52.29479 -394.478764)
		(end 52.1589 -394.342874)
		(stroke
			(width 0.07112)
			(type default)
		)
		(layer "In15.Cu")
	)
	(gr_line
		(start 52.35321 -400.52625)
		(end 51.857148 -400.030188)
		(stroke
			(width 0.07112)
			(type default)
		)
		(layer "In15.Cu")
	)
	(gr_line
		(start 52.477162 -392.707622)
		(end 52.489608 -392.707622)
		(stroke
			(width 0.07112)
			(type default)
		)
		(layer "In15.Cu")
	)
	(gr_line
		(start 52.478432 -392.990832)
		(end 52.616608 -393.129008)
		(stroke
			(width 0.07112)
			(type default)
		)
		(layer "In15.Cu")
	)
	(gr_line
		(start 52.489608 -392.707622)
		(end 52.616608 -392.580622)
		(stroke
			(width 0.07112)
			(type default)
		)
		(layer "In15.Cu")
	)
	(gr_line
		(start 52.5526 -400.325082)
		(end 52.5526 -400.132804)
		(stroke
			(width 0.07112)
			(type default)
		)
		(layer "In15.Cu")
	)
	(gr_line
		(start 52.5526 -400.132804)
		(end 52.250594 -399.830798)
		(stroke
			(width 0.07112)
			(type default)
		)
		(layer "In15.Cu")
	)
	(gr_line
		(start 52.616608 -393.129008)
		(end 52.616608 -393.292838)
		(stroke
			(width 0.07112)
			(type default)
		)
		(layer "In15.Cu")
	)
	(gr_line
		(start 52.616608 -392.580622)
		(end 52.616608 -392.429238)
		(stroke
			(width 0.07112)
			(type default)
		)
		(layer "In15.Cu")
	)
	(gr_line
		(start 52.653184 -398.7038)
		(end 52.460906 -398.7038)
		(stroke
			(width 0.07112)
			(type default)
		)
		(layer "In15.Cu")
	)
	(gr_line
		(start 52.7558 -399.399252)
		(end 52.259738 -398.90319)
		(stroke
			(width 0.07112)
			(type default)
		)
		(layer "In15.Cu")
	)
	(gr_line
		(start 52.95519 -399.198084)
		(end 52.95519 -399.005806)
		(stroke
			(width 0.07112)
			(type default)
		)
		(layer "In15.Cu")
	)
	(gr_line
		(start 52.95519 -399.005806)
		(end 52.653184 -398.7038)
		(stroke
			(width 0.07112)
			(type default)
		)
		(layer "In15.Cu")
	)
	(gr_line
		(start 53.043074 -413.976058)
		(end 53.043074 -413.975804)
		(stroke
			(width 0.07112)
			(type default)
		)
		(layer "In15.Cu")
	)
	(gr_line
		(start 53.048154 -400.628358)
		(end 52.855876 -400.628358)
		(stroke
			(width 0.07112)
			(type default)
		)
		(layer "In15.Cu")
	)
	(gr_line
		(start 53.075586 -396.689072)
		(end 53.075586 -395.988032)
		(stroke
			(width 0.07112)
			(type default)
		)
		(layer "In15.Cu")
	)
	(gr_line
		(start 53.075586 -395.487398)
		(end 53.075586 -394.786358)
		(stroke
			(width 0.07112)
			(type default)
		)
		(layer "In15.Cu")
	)
	(gr_line
		(start 53.15077 -401.32381)
		(end 52.654708 -400.827748)
		(stroke
			(width 0.07112)
			(type default)
		)
		(layer "In15.Cu")
	)
	(gr_line
		(start 53.35016 -401.122642)
		(end 53.35016 -400.930364)
		(stroke
			(width 0.07112)
			(type default)
		)
		(layer "In15.Cu")
	)
	(gr_line
		(start 53.35016 -400.930364)
		(end 53.048154 -400.628358)
		(stroke
			(width 0.07112)
			(type default)
		)
		(layer "In15.Cu")
	)
	(gr_line
		(start 53.358796 -396.687802)
		(end 53.494686 -396.551912)
		(stroke
			(width 0.07112)
			(type default)
		)
		(layer "In15.Cu")
	)
	(gr_line
		(start 53.358796 -395.486128)
		(end 53.494686 -395.350238)
		(stroke
			(width 0.07112)
			(type default)
		)
		(layer "In15.Cu")
	)
	(gr_line
		(start 53.450744 -399.50136)
		(end 53.258466 -399.50136)
		(stroke
			(width 0.07112)
			(type default)
		)
		(layer "In15.Cu")
	)
	(gr_line
		(start 53.494686 -396.551912)
		(end 53.494686 -396.125192)
		(stroke
			(width 0.07112)
			(type default)
		)
		(layer "In15.Cu")
	)
	(gr_line
		(start 53.494686 -396.125192)
		(end 53.358796 -395.989302)
		(stroke
			(width 0.07112)
			(type default)
		)
		(layer "In15.Cu")
	)
	(gr_line
		(start 53.494686 -395.350238)
		(end 53.494686 -394.923518)
		(stroke
			(width 0.07112)
			(type default)
		)
		(layer "In15.Cu")
	)
	(gr_line
		(start 53.494686 -394.923518)
		(end 53.358796 -394.787628)
		(stroke
			(width 0.07112)
			(type default)
		)
		(layer "In15.Cu")
	)
	(gr_line
		(start 53.55336 -400.196812)
		(end 53.057298 -399.70075)
		(stroke
			(width 0.07112)
			(type default)
		)
		(layer "In15.Cu")
	)
	(gr_line
		(start 53.677058 -392.707622)
		(end 53.689504 -392.707622)
		(stroke
			(width 0.07112)
			(type default)
		)
		(layer "In15.Cu")
	)
	(gr_line
		(start 53.678328 -392.990832)
		(end 53.816504 -393.129008)
		(stroke
			(width 0.07112)
			(type default)
		)
		(layer "In15.Cu")
	)
	(gr_line
		(start 53.689504 -392.707622)
		(end 53.816504 -392.580622)
		(stroke
			(width 0.07112)
			(type default)
		)
		(layer "In15.Cu")
	)
	(gr_line
		(start 53.75275 -399.995644)
		(end 53.75275 -399.803366)
		(stroke
			(width 0.07112)
			(type default)
		)
		(layer "In15.Cu")
	)
	(gr_line
		(start 53.75275 -399.803366)
		(end 53.450744 -399.50136)
		(stroke
			(width 0.07112)
			(type default)
		)
		(layer "In15.Cu")
	)
	(gr_line
		(start 53.816504 -393.129008)
		(end 53.816504 -393.292838)
		(stroke
			(width 0.07112)
			(type default)
		)
		(layer "In15.Cu")
	)
	(gr_line
		(start 53.816504 -392.580622)
		(end 53.816504 -392.429238)
		(stroke
			(width 0.07112)
			(type default)
		)
		(layer "In15.Cu")
	)
	(gr_line
		(start 53.845714 -401.425918)
		(end 53.653436 -401.425918)
		(stroke
			(width 0.07112)
			(type default)
		)
		(layer "In15.Cu")
	)
	(gr_line
		(start 53.85308 -398.273778)
		(end 53.660802 -398.273778)
		(stroke
			(width 0.07112)
			(type default)
		)
		(layer "In15.Cu")
	)
	(gr_line
		(start 53.94833 -402.12137)
		(end 53.452268 -401.625308)
		(stroke
			(width 0.07112)
			(type default)
		)
		(layer "In15.Cu")
	)
	(gr_line
		(start 53.955696 -398.96923)
		(end 53.459634 -398.473168)
		(stroke
			(width 0.07112)
			(type default)
		)
		(layer "In15.Cu")
	)
	(gr_line
		(start 54.14772 -401.920202)
		(end 54.14772 -401.727924)
		(stroke
			(width 0.07112)
			(type default)
		)
		(layer "In15.Cu")
	)
	(gr_line
		(start 54.14772 -401.727924)
		(end 53.845714 -401.425918)
		(stroke
			(width 0.07112)
			(type default)
		)
		(layer "In15.Cu")
	)
	(gr_line
		(start 54.155086 -398.768062)
		(end 54.155086 -398.575784)
		(stroke
			(width 0.07112)
			(type default)
		)
		(layer "In15.Cu")
	)
	(gr_line
		(start 54.155086 -398.575784)
		(end 53.85308 -398.273778)
		(stroke
			(width 0.07112)
			(type default)
		)
		(layer "In15.Cu")
	)
	(gr_line
		(start 54.211474 -408.458162)
		(end 54.211474 -407.757122)
		(stroke
			(width 0.07112)
			(type default)
		)
		(layer "In15.Cu")
	)
	(gr_line
		(start 54.248304 -400.29892)
		(end 54.056026 -400.29892)
		(stroke
			(width 0.07112)
			(type default)
		)
		(layer "In15.Cu")
	)
	(gr_line
		(start 54.275736 -396.840202)
		(end 54.275736 -396.139162)
		(stroke
			(width 0.07112)
			(type default)
		)
		(layer "In15.Cu")
	)
	(gr_line
		(start 54.275736 -395.712442)
		(end 54.275736 -395.011402)
		(stroke
			(width 0.07112)
			(type default)
		)
		(layer "In15.Cu")
	)
	(gr_line
		(start 54.35092 -400.994372)
		(end 53.854858 -400.49831)
		(stroke
			(width 0.07112)
			(type default)
		)
		(layer "In15.Cu")
	)
	(gr_line
		(start 54.494684 -408.456892)
		(end 54.630574 -408.321002)
		(stroke
			(width 0.07112)
			(type default)
		)
		(layer "In15.Cu")
	)
	(gr_line
		(start 54.55031 -400.793204)
		(end 54.55031 -400.600926)
		(stroke
			(width 0.07112)
			(type default)
		)
		(layer "In15.Cu")
	)
	(gr_line
		(start 54.55031 -400.600926)
		(end 54.248304 -400.29892)
		(stroke
			(width 0.07112)
			(type default)
		)
		(layer "In15.Cu")
	)
	(gr_line
		(start 54.558946 -396.838932)
		(end 54.694836 -396.703042)
		(stroke
			(width 0.07112)
			(type default)
		)
		(layer "In15.Cu")
	)
	(gr_line
		(start 54.558946 -395.711172)
		(end 54.694836 -395.575282)
		(stroke
			(width 0.07112)
			(type default)
		)
		(layer "In15.Cu")
	)
	(gr_line
		(start 54.630574 -408.321002)
		(end 54.630574 -407.894282)
		(stroke
			(width 0.07112)
			(type default)
		)
		(layer "In15.Cu")
	)
	(gr_line
		(start 54.630574 -407.894282)
		(end 54.494684 -407.758392)
		(stroke
			(width 0.07112)
			(type default)
		)
		(layer "In15.Cu")
	)
	(gr_line
		(start 54.643274 -402.223478)
		(end 54.450996 -402.223478)
		(stroke
			(width 0.07112)
			(type default)
		)
		(layer "In15.Cu")
	)
	(gr_line
		(start 54.65064 -399.071338)
		(end 54.458362 -399.071338)
		(stroke
			(width 0.07112)
			(type default)
		)
		(layer "In15.Cu")
	)
	(gr_line
		(start 54.694836 -396.703042)
		(end 54.694836 -396.276322)
		(stroke
			(width 0.07112)
			(type default)
		)
		(layer "In15.Cu")
	)
	(gr_line
		(start 54.694836 -396.276322)
		(end 54.558946 -396.140432)
		(stroke
			(width 0.07112)
			(type default)
		)
		(layer "In15.Cu")
	)
	(gr_line
		(start 54.694836 -395.575282)
		(end 54.694836 -395.148562)
		(stroke
			(width 0.07112)
			(type default)
		)
		(layer "In15.Cu")
	)
	(gr_line
		(start 54.694836 -395.148562)
		(end 54.558946 -395.012672)
		(stroke
			(width 0.07112)
			(type default)
		)
		(layer "In15.Cu")
	)
	(gr_line
		(start 54.74589 -402.91893)
		(end 54.249828 -402.422868)
		(stroke
			(width 0.07112)
			(type default)
		)
		(layer "In15.Cu")
	)
	(gr_line
		(start 54.753256 -399.76679)
		(end 54.257194 -399.270728)
		(stroke
			(width 0.07112)
			(type default)
		)
		(layer "In15.Cu")
	)
	(gr_line
		(start 54.877208 -392.707622)
		(end 54.889654 -392.707622)
		(stroke
			(width 0.07112)
			(type default)
		)
		(layer "In15.Cu")
	)
	(gr_line
		(start 54.878478 -392.990832)
		(end 55.016654 -393.129008)
		(stroke
			(width 0.07112)
			(type default)
		)
		(layer "In15.Cu")
	)
	(gr_line
		(start 54.889654 -392.707622)
		(end 55.016654 -392.580622)
		(stroke
			(width 0.07112)
			(type default)
		)
		(layer "In15.Cu")
	)
	(gr_line
		(start 54.94528 -402.717762)
		(end 54.94528 -402.525484)
		(stroke
			(width 0.07112)
			(type default)
		)
		(layer "In15.Cu")
	)
	(gr_line
		(start 54.94528 -402.525484)
		(end 54.643274 -402.223478)
		(stroke
			(width 0.07112)
			(type default)
		)
		(layer "In15.Cu")
	)
	(gr_line
		(start 54.952646 -399.565622)
		(end 54.952646 -399.373344)
		(stroke
			(width 0.07112)
			(type default)
		)
		(layer "In15.Cu")
	)
	(gr_line
		(start 54.952646 -399.373344)
		(end 54.65064 -399.071338)
		(stroke
			(width 0.07112)
			(type default)
		)
		(layer "In15.Cu")
	)
	(gr_line
		(start 55.016654 -393.129008)
		(end 55.016654 -393.292838)
		(stroke
			(width 0.07112)
			(type default)
		)
		(layer "In15.Cu")
	)
	(gr_line
		(start 55.016654 -392.580622)
		(end 55.016654 -392.429238)
		(stroke
			(width 0.07112)
			(type default)
		)
		(layer "In15.Cu")
	)
	(gr_line
		(start 55.05323 -397.779748)
		(end 54.860952 -397.779748)
		(stroke
			(width 0.07112)
			(type default)
		)
		(layer "In15.Cu")
	)
	(gr_line
		(start 55.09133 -401.141946)
		(end 54.899052 -401.141946)
		(stroke
			(width 0.07112)
			(type default)
		)
		(layer "In15.Cu")
	)
	(gr_line
		(start 55.155846 -398.4752)
		(end 54.659784 -397.979138)
		(stroke
			(width 0.07112)
			(type default)
		)
		(layer "In15.Cu")
	)
	(gr_line
		(start 55.193946 -401.837398)
		(end 54.697884 -401.341336)
		(stroke
			(width 0.07112)
			(type default)
		)
		(layer "In15.Cu")
	)
	(gr_line
		(start 55.355236 -398.274032)
		(end 55.355236 -398.081754)
		(stroke
			(width 0.07112)
			(type default)
		)
		(layer "In15.Cu")
	)
	(gr_line
		(start 55.355236 -398.081754)
		(end 55.05323 -397.779748)
		(stroke
			(width 0.07112)
			(type default)
		)
		(layer "In15.Cu")
	)
	(gr_line
		(start 55.393336 -401.63623)
		(end 55.393336 -401.443952)
		(stroke
			(width 0.07112)
			(type default)
		)
		(layer "In15.Cu")
	)
	(gr_line
		(start 55.393336 -401.443952)
		(end 55.09133 -401.141946)
		(stroke
			(width 0.07112)
			(type default)
		)
		(layer "In15.Cu")
	)
	(gr_line
		(start 55.4482 -399.868898)
		(end 55.255922 -399.868898)
		(stroke
			(width 0.07112)
			(type default)
		)
		(layer "In15.Cu")
	)
	(gr_line
		(start 55.475632 -396.279624)
		(end 55.475632 -395.578584)
		(stroke
			(width 0.07112)
			(type default)
		)
		(layer "In15.Cu")
	)
	(gr_line
		(start 55.475632 -395.151864)
		(end 55.475632 -394.450824)
		(stroke
			(width 0.07112)
			(type default)
		)
		(layer "In15.Cu")
	)
	(gr_line
		(start 55.550816 -400.56435)
		(end 55.054754 -400.068288)
		(stroke
			(width 0.07112)
			(type default)
		)
		(layer "In15.Cu")
	)
	(gr_line
		(start 55.596536 -414.749996)
		(end 55.596536 -414.75025)
		(stroke
			(width 0.07112)
			(type default)
		)
		(layer "In15.Cu")
	)
	(gr_line
		(start 55.750206 -400.363182)
		(end 55.750206 -400.170904)
		(stroke
			(width 0.07112)
			(type default)
		)
		(layer "In15.Cu")
	)
	(gr_line
		(start 55.750206 -400.170904)
		(end 55.4482 -399.868898)
		(stroke
			(width 0.07112)
			(type default)
		)
		(layer "In15.Cu")
	)
	(gr_line
		(start 55.758842 -396.278354)
		(end 55.894732 -396.142464)
		(stroke
			(width 0.07112)
			(type default)
		)
		(layer "In15.Cu")
	)
	(gr_line
		(start 55.758842 -395.150594)
		(end 55.894732 -395.014704)
		(stroke
			(width 0.07112)
			(type default)
		)
		(layer "In15.Cu")
	)
	(gr_line
		(start 55.85079 -398.577308)
		(end 55.658512 -398.577308)
		(stroke
			(width 0.07112)
			(type default)
		)
		(layer "In15.Cu")
	)
	(gr_line
		(start 55.88889 -401.939506)
		(end 55.696612 -401.939506)
		(stroke
			(width 0.07112)
			(type default)
		)
		(layer "In15.Cu")
	)
	(gr_line
		(start 55.894732 -396.142464)
		(end 55.894732 -395.715744)
		(stroke
			(width 0.07112)
			(type default)
		)
		(layer "In15.Cu")
	)
	(gr_line
		(start 55.894732 -395.715744)
		(end 55.758842 -395.579854)
		(stroke
			(width 0.07112)
			(type default)
		)
		(layer "In15.Cu")
	)
	(gr_line
		(start 55.894732 -395.014704)
		(end 55.894732 -394.587984)
		(stroke
			(width 0.07112)
			(type default)
		)
		(layer "In15.Cu")
	)
	(gr_line
		(start 55.894732 -394.587984)
		(end 55.758842 -394.452094)
		(stroke
			(width 0.07112)
			(type default)
		)
		(layer "In15.Cu")
	)
	(gr_line
		(start 55.953406 -399.27276)
		(end 55.457344 -398.776698)
		(stroke
			(width 0.07112)
			(type default)
		)
		(layer "In15.Cu")
	)
	(gr_line
		(start 55.991506 -402.634958)
		(end 55.495444 -402.138896)
		(stroke
			(width 0.07112)
			(type default)
		)
		(layer "In15.Cu")
	)
	(gr_line
		(start 56.077104 -392.707622)
		(end 56.08955 -392.707622)
		(stroke
			(width 0.07112)
			(type default)
		)
		(layer "In15.Cu")
	)
	(gr_line
		(start 56.078374 -392.990832)
		(end 56.21655 -393.129008)
		(stroke
			(width 0.07112)
			(type default)
		)
		(layer "In15.Cu")
	)
	(gr_line
		(start 56.08955 -392.707622)
		(end 56.21655 -392.580622)
		(stroke
			(width 0.07112)
			(type default)
		)
		(layer "In15.Cu")
	)
	(gr_line
		(start 56.152796 -399.071846)
		(end 56.152796 -398.879314)
		(stroke
			(width 0.07112)
			(type default)
		)
		(layer "In15.Cu")
	)
	(gr_line
		(start 56.152796 -398.879314)
		(end 55.85079 -398.577308)
		(stroke
			(width 0.07112)
			(type default)
		)
		(layer "In15.Cu")
	)
	(gr_line
		(start 56.190896 -402.43379)
		(end 56.190896 -402.241512)
		(stroke
			(width 0.07112)
			(type default)
		)
		(layer "In15.Cu")
	)
	(gr_line
		(start 56.190896 -402.241512)
		(end 55.88889 -401.939506)
		(stroke
			(width 0.07112)
			(type default)
		)
		(layer "In15.Cu")
	)
	(gr_line
		(start 56.21655 -393.129008)
		(end 56.21655 -393.292838)
		(stroke
			(width 0.07112)
			(type default)
		)
		(layer "In15.Cu")
	)
	(gr_line
		(start 56.21655 -392.580622)
		(end 56.21655 -392.429238)
		(stroke
			(width 0.07112)
			(type default)
		)
		(layer "In15.Cu")
	)
	(gr_line
		(start 56.24576 -400.666458)
		(end 56.053482 -400.666458)
		(stroke
			(width 0.07112)
			(type default)
		)
		(layer "In15.Cu")
	)
	(gr_line
		(start 56.253126 -397.38808)
		(end 56.060848 -397.38808)
		(stroke
			(width 0.07112)
			(type default)
		)
		(layer "In15.Cu")
	)
	(gr_line
		(start 56.348376 -401.36191)
		(end 55.852314 -400.865848)
		(stroke
			(width 0.07112)
			(type default)
		)
		(layer "In15.Cu")
	)
	(gr_line
		(start 56.355742 -398.083532)
		(end 55.85968 -397.58747)
		(stroke
			(width 0.07112)
			(type default)
		)
		(layer "In15.Cu")
	)
	(gr_line
		(start 56.547766 -401.160742)
		(end 56.547766 -400.968464)
		(stroke
			(width 0.07112)
			(type default)
		)
		(layer "In15.Cu")
	)
	(gr_line
		(start 56.547766 -400.968464)
		(end 56.24576 -400.666458)
		(stroke
			(width 0.07112)
			(type default)
		)
		(layer "In15.Cu")
	)
	(gr_line
		(start 56.555132 -397.882364)
		(end 56.555132 -397.690086)
		(stroke
			(width 0.07112)
			(type default)
		)
		(layer "In15.Cu")
	)
	(gr_line
		(start 56.555132 -397.690086)
		(end 56.253126 -397.38808)
		(stroke
			(width 0.07112)
			(type default)
		)
		(layer "In15.Cu")
	)
	(gr_line
		(start 56.64835 -399.374868)
		(end 56.455818 -399.374868)
		(stroke
			(width 0.07112)
			(type default)
		)
		(layer "In15.Cu")
	)
	(gr_line
		(start 56.675782 -396.299944)
		(end 56.675782 -395.598904)
		(stroke
			(width 0.07112)
			(type default)
		)
		(layer "In15.Cu")
	)
	(gr_line
		(start 56.675782 -395.172184)
		(end 56.675782 -394.471144)
		(stroke
			(width 0.07112)
			(type default)
		)
		(layer "In15.Cu")
	)
	(gr_line
		(start 56.750966 -400.07032)
		(end 56.254904 -399.574258)
		(stroke
			(width 0.07112)
			(type default)
		)
		(layer "In15.Cu")
	)
	(gr_line
		(start 56.950356 -399.869406)
		(end 56.950356 -399.676874)
		(stroke
			(width 0.07112)
			(type default)
		)
		(layer "In15.Cu")
	)
	(gr_line
		(start 56.950356 -399.676874)
		(end 56.64835 -399.374868)
		(stroke
			(width 0.07112)
			(type default)
		)
		(layer "In15.Cu")
	)
	(gr_line
		(start 56.958992 -396.298674)
		(end 57.094882 -396.162784)
		(stroke
			(width 0.07112)
			(type default)
		)
		(layer "In15.Cu")
	)
	(gr_line
		(start 56.958992 -395.170914)
		(end 57.094882 -395.035024)
		(stroke
			(width 0.07112)
			(type default)
		)
		(layer "In15.Cu")
	)
	(gr_line
		(start 57.050686 -398.18564)
		(end 56.858408 -398.18564)
		(stroke
			(width 0.07112)
			(type default)
		)
		(layer "In15.Cu")
	)
	(gr_line
		(start 57.094882 -396.162784)
		(end 57.094882 -395.736064)
		(stroke
			(width 0.07112)
			(type default)
		)
		(layer "In15.Cu")
	)
	(gr_line
		(start 57.094882 -395.736064)
		(end 56.958992 -395.600174)
		(stroke
			(width 0.07112)
			(type default)
		)
		(layer "In15.Cu")
	)
	(gr_line
		(start 57.094882 -395.035024)
		(end 57.094882 -394.608304)
		(stroke
			(width 0.07112)
			(type default)
		)
		(layer "In15.Cu")
	)
	(gr_line
		(start 57.094882 -394.608304)
		(end 56.958992 -394.472414)
		(stroke
			(width 0.07112)
			(type default)
		)
		(layer "In15.Cu")
	)
	(gr_line
		(start 57.153302 -398.881092)
		(end 56.657494 -398.385284)
		(stroke
			(width 0.07112)
			(type default)
		)
		(layer "In15.Cu")
	)
	(gr_line
		(start 57.277254 -392.707622)
		(end 57.2897 -392.707622)
		(stroke
			(width 0.07112)
			(type default)
		)
		(layer "In15.Cu")
	)
	(gr_line
		(start 57.278524 -392.990832)
		(end 57.4167 -393.129008)
		(stroke
			(width 0.07112)
			(type default)
		)
		(layer "In15.Cu")
	)
	(gr_line
		(start 57.2897 -392.707622)
		(end 57.4167 -392.580622)
		(stroke
			(width 0.07112)
			(type default)
		)
		(layer "In15.Cu")
	)
	(gr_line
		(start 57.352692 -398.679924)
		(end 57.352692 -398.487646)
		(stroke
			(width 0.07112)
			(type default)
		)
		(layer "In15.Cu")
	)
	(gr_line
		(start 57.352692 -398.487646)
		(end 57.050686 -398.18564)
		(stroke
			(width 0.07112)
			(type default)
		)
		(layer "In15.Cu")
	)
	(gr_line
		(start 57.3913 -385.31038)
		(end 57.744614 -385.405376)
		(stroke
			(width 0.07112)
			(type default)
		)
		(layer "In15.Cu")
	)
	(gr_line
		(start 57.4167 -393.129008)
		(end 57.4167 -393.292838)
		(stroke
			(width 0.07112)
			(type default)
		)
		(layer "In15.Cu")
	)
	(gr_line
		(start 57.4167 -392.580622)
		(end 57.4167 -392.429238)
		(stroke
			(width 0.07112)
			(type default)
		)
		(layer "In15.Cu")
	)
	(gr_line
		(start 57.453276 -397.028162)
		(end 57.260998 -397.028162)
		(stroke
			(width 0.07112)
			(type default)
		)
		(layer "In15.Cu")
	)
	(gr_line
		(start 57.52592 -400.252438)
		(end 57.333388 -400.252438)
		(stroke
			(width 0.07112)
			(type default)
		)
		(layer "In15.Cu")
	)
	(gr_line
		(start 57.545732 -400.86534)
		(end 57.132474 -400.451828)
		(stroke
			(width 0.07112)
			(type default)
		)
		(layer "In15.Cu")
	)
	(gr_line
		(start 57.545986 -400.86534)
		(end 57.545732 -400.86534)
		(stroke
			(width 0.07112)
			(type default)
		)
		(layer "In15.Cu")
	)
	(gr_line
		(start 57.555892 -397.723614)
		(end 57.05983 -397.227552)
		(stroke
			(width 0.07112)
			(type default)
		)
		(layer "In15.Cu")
	)
	(gr_line
		(start 57.628536 -400.94789)
		(end 57.545986 -400.86534)
		(stroke
			(width 0.07112)
			(type default)
		)
		(layer "In15.Cu")
	)
	(gr_line
		(start 57.744614 -385.405376)
		(end 57.745122 -385.404868)
		(stroke
			(width 0.07112)
			(type default)
		)
		(layer "In15.Cu")
	)
	(gr_line
		(start 57.755282 -397.522446)
		(end 57.755282 -397.330168)
		(stroke
			(width 0.07112)
			(type default)
		)
		(layer "In15.Cu")
	)
	(gr_line
		(start 57.755282 -397.330168)
		(end 57.453276 -397.028162)
		(stroke
			(width 0.07112)
			(type default)
		)
		(layer "In15.Cu")
	)
	(gr_line
		(start 57.79135 -386.003292)
		(end 57.886092 -385.649724)
		(stroke
			(width 0.07112)
			(type default)
		)
		(layer "In15.Cu")
	)
	(gr_line
		(start 57.827926 -400.746722)
		(end 57.827926 -400.554444)
		(stroke
			(width 0.07112)
			(type default)
		)
		(layer "In15.Cu")
	)
	(gr_line
		(start 57.827926 -400.554444)
		(end 57.52592 -400.252438)
		(stroke
			(width 0.07112)
			(type default)
		)
		(layer "In15.Cu")
	)
	(gr_line
		(start 57.848246 -398.9832)
		(end 57.655968 -398.9832)
		(stroke
			(width 0.07112)
			(type default)
		)
		(layer "In15.Cu")
	)
	(gr_line
		(start 57.875678 -395.854428)
		(end 57.875678 -395.153388)
		(stroke
			(width 0.07112)
			(type default)
		)
		(layer "In15.Cu")
	)
	(gr_line
		(start 57.950862 -399.678652)
		(end 57.455054 -399.182844)
		(stroke
			(width 0.07112)
			(type default)
		)
		(layer "In15.Cu")
	)
	(gr_line
		(start 58.007758 -385.579112)
		(end 58.06059 -385.548632)
		(stroke
			(width 0.07112)
			(type default)
		)
		(layer "In15.Cu")
	)
	(gr_line
		(start 58.06059 -385.548632)
		(end 58.148728 -385.460494)
		(stroke
			(width 0.07112)
			(type default)
		)
		(layer "In15.Cu")
	)
	(gr_line
		(start 58.148728 -385.460494)
		(end 58.148728 -385.334764)
		(stroke
			(width 0.07112)
			(type default)
		)
		(layer "In15.Cu")
	)
	(gr_line
		(start 58.150252 -399.477484)
		(end 58.150252 -399.285206)
		(stroke
			(width 0.07112)
			(type default)
		)
		(layer "In15.Cu")
	)
	(gr_line
		(start 58.150252 -399.285206)
		(end 57.848246 -398.9832)
		(stroke
			(width 0.07112)
			(type default)
		)
		(layer "In15.Cu")
	)
	(gr_line
		(start 58.158888 -395.853158)
		(end 58.294778 -395.717268)
		(stroke
			(width 0.07112)
			(type default)
		)
		(layer "In15.Cu")
	)
	(gr_line
		(start 58.250836 -397.825722)
		(end 58.058558 -397.825722)
		(stroke
			(width 0.07112)
			(type default)
		)
		(layer "In15.Cu")
	)
	(gr_line
		(start 58.294778 -395.717268)
		(end 58.294778 -395.290548)
		(stroke
			(width 0.07112)
			(type default)
		)
		(layer "In15.Cu")
	)
	(gr_line
		(start 58.294778 -395.290548)
		(end 58.158888 -395.154658)
		(stroke
			(width 0.07112)
			(type default)
		)
		(layer "In15.Cu")
	)
	(gr_line
		(start 58.353452 -398.521174)
		(end 57.857644 -398.025366)
		(stroke
			(width 0.07112)
			(type default)
		)
		(layer "In15.Cu")
	)
	(gr_line
		(start 58.467752 -393.011406)
		(end 58.489596 -393.011406)
		(stroke
			(width 0.07112)
			(type default)
		)
		(layer "In15.Cu")
	)
	(gr_line
		(start 58.469022 -392.728196)
		(end 58.616596 -392.580622)
		(stroke
			(width 0.07112)
			(type default)
		)
		(layer "In15.Cu")
	)
	(gr_line
		(start 58.489596 -393.011406)
		(end 58.616596 -393.138406)
		(stroke
			(width 0.07112)
			(type default)
		)
		(layer "In15.Cu")
	)
	(gr_line
		(start 58.50382 -437.3372)
		(end 58.499248 -437.3372)
		(stroke
			(width 0.07112)
			(type default)
		)
		(layer "In15.Cu")
	)
	(gr_line
		(start 58.552842 -398.320006)
		(end 58.552842 -398.127728)
		(stroke
			(width 0.07112)
			(type default)
		)
		(layer "In15.Cu")
	)
	(gr_line
		(start 58.552842 -398.127728)
		(end 58.250836 -397.825722)
		(stroke
			(width 0.07112)
			(type default)
		)
		(layer "In15.Cu")
	)
	(gr_line
		(start 58.591196 -385.31038)
		(end 58.94451 -385.405376)
		(stroke
			(width 0.07112)
			(type default)
		)
		(layer "In15.Cu")
	)
	(gr_line
		(start 58.616596 -393.138406)
		(end 58.616596 -393.292838)
		(stroke
			(width 0.07112)
			(type default)
		)
		(layer "In15.Cu")
	)
	(gr_line
		(start 58.616596 -392.580622)
		(end 58.616596 -392.429238)
		(stroke
			(width 0.07112)
			(type default)
		)
		(layer "In15.Cu")
	)
	(gr_line
		(start 58.64987 -438.089802)
		(end 58.64987 -437.769762)
		(stroke
			(width 0.07112)
			(type default)
		)
		(layer "In15.Cu")
	)
	(gr_line
		(start 58.64987 -437.769762)
		(end 58.500518 -437.62041)
		(stroke
			(width 0.07112)
			(type default)
		)
		(layer "In15.Cu")
	)
	(gr_line
		(start 58.64987 -437.19115)
		(end 58.50382 -437.3372)
		(stroke
			(width 0.07112)
			(type default)
		)
		(layer "In15.Cu")
	)
	(gr_line
		(start 58.64987 -436.889906)
		(end 58.64987 -437.19115)
		(stroke
			(width 0.07112)
			(type default)
		)
		(layer "In15.Cu")
	)
	(gr_line
		(start 58.653172 -396.582646)
		(end 58.460894 -396.582646)
		(stroke
			(width 0.07112)
			(type default)
		)
		(layer "In15.Cu")
	)
	(gr_line
		(start 58.68543 -322.128134)
		(end 58.684922 -322.128134)
		(stroke
			(width 0.07112)
			(type default)
		)
		(layer "In15.Cu")
	)
	(gr_line
		(start 58.686192 -322.128134)
		(end 58.68543 -322.128134)
		(stroke
			(width 0.07112)
			(type default)
		)
		(layer "In15.Cu")
	)
	(gr_line
		(start 58.69051 -323.085714)
		(end 58.690002 -323.085714)
		(stroke
			(width 0.07112)
			(type default)
		)
		(layer "In15.Cu")
	)
	(gr_line
		(start 58.691272 -323.085714)
		(end 58.69051 -323.085714)
		(stroke
			(width 0.07112)
			(type default)
		)
		(layer "In15.Cu")
	)
	(gr_line
		(start 58.726578 -57.267856)
		(end 59.417204 -57.145936)
		(stroke
			(width 0.07112)
			(type default)
		)
		(layer "In15.Cu")
	)
	(gr_line
		(start 58.755788 -397.278098)
		(end 58.259726 -396.782036)
		(stroke
			(width 0.07112)
			(type default)
		)
		(layer "In15.Cu")
	)
	(gr_line
		(start 58.776616 -57.546494)
		(end 58.934604 -57.656984)
		(stroke
			(width 0.07112)
			(type default)
		)
		(layer "In15.Cu")
	)
	(gr_line
		(start 58.934604 -57.656984)
		(end 59.354974 -57.58307)
		(stroke
			(width 0.07112)
			(type default)
		)
		(layer "In15.Cu")
	)
	(gr_line
		(start 58.94451 -385.405376)
		(end 58.945018 -385.404868)
		(stroke
			(width 0.07112)
			(type default)
		)
		(layer "In15.Cu")
	)
	(gr_line
		(start 58.955178 -397.077184)
		(end 58.955178 -396.884652)
		(stroke
			(width 0.07112)
			(type default)
		)
		(layer "In15.Cu")
	)
	(gr_line
		(start 58.955178 -396.884652)
		(end 58.653172 -396.582646)
		(stroke
			(width 0.07112)
			(type default)
		)
		(layer "In15.Cu")
	)
	(gr_line
		(start 58.991246 -386.003292)
		(end 59.085988 -385.649724)
		(stroke
			(width 0.07112)
			(type default)
		)
		(layer "In15.Cu")
	)
	(gr_line
		(start 59.048396 -398.623282)
		(end 58.856118 -398.623282)
		(stroke
			(width 0.07112)
			(type default)
		)
		(layer "In15.Cu")
	)
	(gr_line
		(start 59.068208 -399.23593)
		(end 58.655204 -398.822926)
		(stroke
			(width 0.07112)
			(type default)
		)
		(layer "In15.Cu")
	)
	(gr_line
		(start 59.068462 -399.23593)
		(end 59.068208 -399.23593)
		(stroke
			(width 0.07112)
			(type default)
		)
		(layer "In15.Cu")
	)
	(gr_line
		(start 59.075828 -395.339062)
		(end 59.075828 -394.638022)
		(stroke
			(width 0.07112)
			(type default)
		)
		(layer "In15.Cu")
	)
	(gr_line
		(start 59.151012 -399.31848)
		(end 59.068462 -399.23593)
		(stroke
			(width 0.07112)
			(type default)
		)
		(layer "In15.Cu")
	)
	(gr_line
		(start 59.207654 -385.579112)
		(end 59.260486 -385.548632)
		(stroke
			(width 0.07112)
			(type default)
		)
		(layer "In15.Cu")
	)
	(gr_line
		(start 59.260486 -385.548632)
		(end 59.348624 -385.460494)
		(stroke
			(width 0.07112)
			(type default)
		)
		(layer "In15.Cu")
	)
	(gr_line
		(start 59.348624 -385.460494)
		(end 59.348624 -385.334764)
		(stroke
			(width 0.07112)
			(type default)
		)
		(layer "In15.Cu")
	)
	(gr_line
		(start 59.350402 -399.117312)
		(end 59.350402 -398.925288)
		(stroke
			(width 0.07112)
			(type default)
		)
		(layer "In15.Cu")
	)
	(gr_line
		(start 59.350402 -398.925288)
		(end 59.048396 -398.623282)
		(stroke
			(width 0.07112)
			(type default)
		)
		(layer "In15.Cu")
	)
	(gr_line
		(start 59.354974 -57.58307)
		(end 59.46521 -57.425082)
		(stroke
			(width 0.07112)
			(type default)
		)
		(layer "In15.Cu")
	)
	(gr_line
		(start 59.359038 -395.337792)
		(end 59.494928 -395.201902)
		(stroke
			(width 0.07112)
			(type default)
		)
		(layer "In15.Cu")
	)
	(gr_line
		(start 59.450732 -397.380206)
		(end 59.2582 -397.380206)
		(stroke
			(width 0.07112)
			(type default)
		)
		(layer "In15.Cu")
	)
	(gr_line
		(start 59.470544 -397.993108)
		(end 59.057286 -397.579596)
		(stroke
			(width 0.07112)
			(type default)
		)
		(layer "In15.Cu")
	)
	(gr_line
		(start 59.470798 -397.993108)
		(end 59.470544 -397.993108)
		(stroke
			(width 0.07112)
			(type default)
		)
		(layer "In15.Cu")
	)
	(gr_line
		(start 59.494928 -395.201902)
		(end 59.494928 -394.775182)
		(stroke
			(width 0.07112)
			(type default)
		)
		(layer "In15.Cu")
	)
	(gr_line
		(start 59.494928 -394.775182)
		(end 59.359038 -394.639292)
		(stroke
			(width 0.07112)
			(type default)
		)
		(layer "In15.Cu")
	)
	(gr_line
		(start 59.553348 -398.075658)
		(end 59.470798 -397.993108)
		(stroke
			(width 0.07112)
			(type default)
		)
		(layer "In15.Cu")
	)
	(gr_line
		(start 59.6773 -392.707622)
		(end 59.689746 -392.707622)
		(stroke
			(width 0.07112)
			(type default)
		)
		(layer "In15.Cu")
	)
	(gr_line
		(start 59.67857 -392.990832)
		(end 59.816746 -393.129008)
		(stroke
			(width 0.07112)
			(type default)
		)
		(layer "In15.Cu")
	)
	(gr_line
		(start 59.689746 -392.707622)
		(end 59.816746 -392.580622)
		(stroke
			(width 0.07112)
			(type default)
		)
		(layer "In15.Cu")
	)
	(gr_line
		(start 59.752738 -397.87449)
		(end 59.752738 -397.682212)
		(stroke
			(width 0.07112)
			(type default)
		)
		(layer "In15.Cu")
	)
	(gr_line
		(start 59.752738 -397.682212)
		(end 59.450732 -397.380206)
		(stroke
			(width 0.07112)
			(type default)
		)
		(layer "In15.Cu")
	)
	(gr_line
		(start 59.791346 -385.31038)
		(end 60.14466 -385.405376)
		(stroke
			(width 0.07112)
			(type default)
		)
		(layer "In15.Cu")
	)
	(gr_line
		(start 59.816746 -393.129008)
		(end 59.816746 -393.292838)
		(stroke
			(width 0.07112)
			(type default)
		)
		(layer "In15.Cu")
	)
	(gr_line
		(start 59.816746 -392.580622)
		(end 59.816746 -392.429238)
		(stroke
			(width 0.07112)
			(type default)
		)
		(layer "In15.Cu")
	)
	(gr_line
		(start 59.90971 -375.050304)
		(end 59.90971 -375.049542)
		(stroke
			(width 0.07112)
			(type default)
		)
		(layer "In15.Cu")
	)
	(gr_line
		(start 60.108084 -57.02427)
		(end 60.79871 -56.90235)
		(stroke
			(width 0.07112)
			(type default)
		)
		(layer "In15.Cu")
	)
	(gr_line
		(start 60.14466 -385.405376)
		(end 60.145168 -385.404868)
		(stroke
			(width 0.07112)
			(type default)
		)
		(layer "In15.Cu")
	)
	(gr_line
		(start 60.158122 -57.302908)
		(end 60.31611 -57.413398)
		(stroke
			(width 0.07112)
			(type default)
		)
		(layer "In15.Cu")
	)
	(gr_line
		(start 60.191396 -386.003292)
		(end 60.286138 -385.649724)
		(stroke
			(width 0.07112)
			(type default)
		)
		(layer "In15.Cu")
	)
	(gr_line
		(start 60.25769 -373.84609)
		(end 60.257944 -373.845328)
		(stroke
			(width 0.07112)
			(type default)
		)
		(layer "In15.Cu")
	)
	(gr_line
		(start 60.275724 -395.200124)
		(end 60.275724 -394.499084)
		(stroke
			(width 0.07112)
			(type default)
		)
		(layer "In15.Cu")
	)
	(gr_line
		(start 60.31611 -57.413398)
		(end 60.73648 -57.339484)
		(stroke
			(width 0.07112)
			(type default)
		)
		(layer "In15.Cu")
	)
	(gr_line
		(start 60.407804 -385.579112)
		(end 60.460636 -385.548632)
		(stroke
			(width 0.07112)
			(type default)
		)
		(layer "In15.Cu")
	)
	(gr_line
		(start 60.460636 -385.548632)
		(end 60.548774 -385.460494)
		(stroke
			(width 0.07112)
			(type default)
		)
		(layer "In15.Cu")
	)
	(gr_line
		(start 60.503816 -438.337198)
		(end 60.499244 -438.337198)
		(stroke
			(width 0.07112)
			(type default)
		)
		(layer "In15.Cu")
	)
	(gr_line
		(start 60.527184 -373.930164)
		(end 60.527692 -373.92864)
		(stroke
			(width 0.07112)
			(type default)
		)
		(layer "In15.Cu")
	)
	(gr_line
		(start 60.527692 -414.80613)
		(end 60.527692 -414.806384)
		(stroke
			(width 0.07112)
			(type default)
		)
		(layer "In15.Cu")
	)
	(gr_line
		(start 60.527692 -373.92864)
		(end 60.527438 -373.92864)
		(stroke
			(width 0.07112)
			(type default)
		)
		(layer "In15.Cu")
	)
	(gr_line
		(start 60.548774 -385.460494)
		(end 60.548774 -385.334764)
		(stroke
			(width 0.07112)
			(type default)
		)
		(layer "In15.Cu")
	)
	(gr_line
		(start 60.558934 -395.198854)
		(end 60.694824 -395.062964)
		(stroke
			(width 0.07112)
			(type default)
		)
		(layer "In15.Cu")
	)
	(gr_line
		(start 60.649866 -439.0898)
		(end 60.649866 -438.76976)
		(stroke
			(width 0.07112)
			(type default)
		)
		(layer "In15.Cu")
	)
	(gr_line
		(start 60.649866 -438.76976)
		(end 60.500514 -438.620408)
		(stroke
			(width 0.07112)
			(type default)
		)
		(layer "In15.Cu")
	)
	(gr_line
		(start 60.649866 -438.191148)
		(end 60.503816 -438.337198)
		(stroke
			(width 0.07112)
			(type default)
		)
		(layer "In15.Cu")
	)
	(gr_line
		(start 60.649866 -437.889904)
		(end 60.649866 -438.191148)
		(stroke
			(width 0.07112)
			(type default)
		)
		(layer "In15.Cu")
	)
	(gr_line
		(start 60.65266 -372.657624)
		(end 60.653168 -372.657116)
		(stroke
			(width 0.07112)
			(type default)
		)
		(layer "In15.Cu")
	)
	(gr_line
		(start 60.694824 -395.062964)
		(end 60.694824 -394.636244)
		(stroke
			(width 0.07112)
			(type default)
		)
		(layer "In15.Cu")
	)
	(gr_line
		(start 60.694824 -394.636244)
		(end 60.558934 -394.500354)
		(stroke
			(width 0.07112)
			(type default)
		)
		(layer "In15.Cu")
	)
	(gr_line
		(start 60.73648 -57.339484)
		(end 60.846716 -57.181496)
		(stroke
			(width 0.07112)
			(type default)
		)
		(layer "In15.Cu")
	)
	(gr_line
		(start 60.877196 -392.707622)
		(end 60.889642 -392.707622)
		(stroke
			(width 0.07112)
			(type default)
		)
		(layer "In15.Cu")
	)
	(gr_line
		(start 60.877196 -372.828312)
		(end 60.87745 -372.828058)
		(stroke
			(width 0.07112)
			(type default)
		)
		(layer "In15.Cu")
	)
	(gr_line
		(start 60.878466 -392.990832)
		(end 61.016642 -393.129008)
		(stroke
			(width 0.07112)
			(type default)
		)
		(layer "In15.Cu")
	)
	(gr_line
		(start 60.889642 -392.707622)
		(end 61.016642 -392.580622)
		(stroke
			(width 0.07112)
			(type default)
		)
		(layer "In15.Cu")
	)
	(gr_line
		(start 60.991242 -385.31038)
		(end 61.344556 -385.405376)
		(stroke
			(width 0.07112)
			(type default)
		)
		(layer "In15.Cu")
	)
	(gr_line
		(start 61.016642 -393.129008)
		(end 61.016642 -393.292838)
		(stroke
			(width 0.07112)
			(type default)
		)
		(layer "In15.Cu")
	)
	(gr_line
		(start 61.016642 -392.580622)
		(end 61.016642 -392.429238)
		(stroke
			(width 0.07112)
			(type default)
		)
		(layer "In15.Cu")
	)
	(gr_line
		(start 61.344556 -385.405376)
		(end 61.345064 -385.404868)
		(stroke
			(width 0.07112)
			(type default)
		)
		(layer "In15.Cu")
	)
	(gr_line
		(start 61.391292 -386.003292)
		(end 61.486034 -385.649724)
		(stroke
			(width 0.07112)
			(type default)
		)
		(layer "In15.Cu")
	)
	(gr_line
		(start 61.47562 -394.83665)
		(end 61.47562 -394.13561)
		(stroke
			(width 0.07112)
			(type default)
		)
		(layer "In15.Cu")
	)
	(gr_line
		(start 61.6077 -385.579112)
		(end 61.660532 -385.548632)
		(stroke
			(width 0.07112)
			(type default)
		)
		(layer "In15.Cu")
	)
	(gr_line
		(start 61.660532 -385.548632)
		(end 61.74867 -385.460494)
		(stroke
			(width 0.07112)
			(type default)
		)
		(layer "In15.Cu")
	)
	(gr_line
		(start 61.74867 -385.460494)
		(end 61.74867 -385.334764)
		(stroke
			(width 0.07112)
			(type default)
		)
		(layer "In15.Cu")
	)
	(gr_line
		(start 61.75883 -394.83538)
		(end 61.89472 -394.69949)
		(stroke
			(width 0.07112)
			(type default)
		)
		(layer "In15.Cu")
	)
	(gr_line
		(start 61.89472 -394.69949)
		(end 61.89472 -394.27277)
		(stroke
			(width 0.07112)
			(type default)
		)
		(layer "In15.Cu")
	)
	(gr_line
		(start 61.89472 -394.27277)
		(end 61.75883 -394.13688)
		(stroke
			(width 0.07112)
			(type default)
		)
		(layer "In15.Cu")
	)
	(gr_line
		(start 62.077092 -392.707622)
		(end 62.089538 -392.707622)
		(stroke
			(width 0.07112)
			(type default)
		)
		(layer "In15.Cu")
	)
	(gr_line
		(start 62.078362 -392.990832)
		(end 62.216538 -393.129008)
		(stroke
			(width 0.07112)
			(type default)
		)
		(layer "In15.Cu")
	)
	(gr_line
		(start 62.089538 -392.707622)
		(end 62.216538 -392.580622)
		(stroke
			(width 0.07112)
			(type default)
		)
		(layer "In15.Cu")
	)
	(gr_line
		(start 62.191392 -385.31038)
		(end 62.544452 -385.405376)
		(stroke
			(width 0.07112)
			(type default)
		)
		(layer "In15.Cu")
	)
	(gr_line
		(start 62.216538 -393.129008)
		(end 62.216538 -393.292838)
		(stroke
			(width 0.07112)
			(type default)
		)
		(layer "In15.Cu")
	)
	(gr_line
		(start 62.216538 -392.580622)
		(end 62.216538 -392.429238)
		(stroke
			(width 0.07112)
			(type default)
		)
		(layer "In15.Cu")
	)
	(gr_line
		(start 62.33287 -395.644878)
		(end 62.140592 -395.644878)
		(stroke
			(width 0.07112)
			(type default)
		)
		(layer "In15.Cu")
	)
	(gr_line
		(start 62.352936 -396.25778)
		(end 61.939424 -395.844268)
		(stroke
			(width 0.07112)
			(type default)
		)
		(layer "In15.Cu")
	)
	(gr_line
		(start 62.352936 -396.257526)
		(end 62.352936 -396.25778)
		(stroke
			(width 0.07112)
			(type default)
		)
		(layer "In15.Cu")
	)
	(gr_line
		(start 62.435486 -396.340076)
		(end 62.352936 -396.257526)
		(stroke
			(width 0.07112)
			(type default)
		)
		(layer "In15.Cu")
	)
	(gr_line
		(start 62.503304 -437.623204)
		(end 62.499748 -437.623204)
		(stroke
			(width 0.07112)
			(type default)
		)
		(layer "In15.Cu")
	)
	(gr_line
		(start 62.544452 -385.405376)
		(end 62.54496 -385.404868)
		(stroke
			(width 0.07112)
			(type default)
		)
		(layer "In15.Cu")
	)
	(gr_line
		(start 62.591188 -386.003292)
		(end 62.68593 -385.649724)
		(stroke
			(width 0.07112)
			(type default)
		)
		(layer "In15.Cu")
	)
	(gr_line
		(start 62.634876 -396.138908)
		(end 62.634876 -395.946884)
		(stroke
			(width 0.07112)
			(type default)
		)
		(layer "In15.Cu")
	)
	(gr_line
		(start 62.634876 -395.946884)
		(end 62.33287 -395.644878)
		(stroke
			(width 0.07112)
			(type default)
		)
		(layer "In15.Cu")
	)
	(gr_line
		(start 62.649862 -438.089802)
		(end 62.649862 -437.769762)
		(stroke
			(width 0.07112)
			(type default)
		)
		(layer "In15.Cu")
	)
	(gr_line
		(start 62.649862 -437.769762)
		(end 62.503304 -437.623204)
		(stroke
			(width 0.07112)
			(type default)
		)
		(layer "In15.Cu")
	)
	(gr_line
		(start 62.649862 -437.19115)
		(end 62.501018 -437.339994)
		(stroke
			(width 0.07112)
			(type default)
		)
		(layer "In15.Cu")
	)
	(gr_line
		(start 62.649862 -436.889906)
		(end 62.649862 -437.19115)
		(stroke
			(width 0.07112)
			(type default)
		)
		(layer "In15.Cu")
	)
	(gr_line
		(start 62.807596 -385.579112)
		(end 62.860428 -385.548632)
		(stroke
			(width 0.07112)
			(type default)
		)
		(layer "In15.Cu")
	)
	(gr_line
		(start 62.860428 -385.548632)
		(end 62.948566 -385.460494)
		(stroke
			(width 0.07112)
			(type default)
		)
		(layer "In15.Cu")
	)
	(gr_line
		(start 62.948566 -385.460494)
		(end 62.948566 -385.334764)
		(stroke
			(width 0.07112)
			(type default)
		)
		(layer "In15.Cu")
	)
	(gr_line
		(start 63.289434 -392.989562)
		(end 63.416434 -393.116562)
		(stroke
			(width 0.07112)
			(type default)
		)
		(layer "In15.Cu")
	)
	(gr_line
		(start 63.289434 -392.707622)
		(end 63.416434 -392.580622)
		(stroke
			(width 0.07112)
			(type default)
		)
		(layer "In15.Cu")
	)
	(gr_line
		(start 63.391288 -385.31038)
		(end 63.744602 -385.405376)
		(stroke
			(width 0.07112)
			(type default)
		)
		(layer "In15.Cu")
	)
	(gr_line
		(start 63.401194 -409.793186)
		(end 63.401194 -409.092146)
		(stroke
			(width 0.07112)
			(type default)
		)
		(layer "In15.Cu")
	)
	(gr_line
		(start 63.401194 -408.665426)
		(end 63.401194 -407.964386)
		(stroke
			(width 0.07112)
			(type default)
		)
		(layer "In15.Cu")
	)
	(gr_line
		(start 63.416434 -393.116562)
		(end 63.416434 -393.292838)
		(stroke
			(width 0.07112)
			(type default)
		)
		(layer "In15.Cu")
	)
	(gr_line
		(start 63.416434 -392.580622)
		(end 63.416434 -392.429238)
		(stroke
			(width 0.07112)
			(type default)
		)
		(layer "In15.Cu")
	)
	(gr_line
		(start 63.684404 -409.791916)
		(end 63.820294 -409.656026)
		(stroke
			(width 0.07112)
			(type default)
		)
		(layer "In15.Cu")
	)
	(gr_line
		(start 63.684404 -408.664156)
		(end 63.820294 -408.528266)
		(stroke
			(width 0.07112)
			(type default)
		)
		(layer "In15.Cu")
	)
	(gr_line
		(start 63.744602 -385.405376)
		(end 63.74511 -385.404868)
		(stroke
			(width 0.07112)
			(type default)
		)
		(layer "In15.Cu")
	)
	(gr_line
		(start 63.791338 -386.003292)
		(end 63.88608 -385.649724)
		(stroke
			(width 0.07112)
			(type default)
		)
		(layer "In15.Cu")
	)
	(gr_line
		(start 63.820294 -409.656026)
		(end 63.820294 -409.229306)
		(stroke
			(width 0.07112)
			(type default)
		)
		(layer "In15.Cu")
	)
	(gr_line
		(start 63.820294 -409.229306)
		(end 63.684404 -409.093416)
		(stroke
			(width 0.07112)
			(type default)
		)
		(layer "In15.Cu")
	)
	(gr_line
		(start 63.820294 -408.528266)
		(end 63.820294 -408.101546)
		(stroke
			(width 0.07112)
			(type default)
		)
		(layer "In15.Cu")
	)
	(gr_line
		(start 63.820294 -408.101546)
		(end 63.684404 -407.965656)
		(stroke
			(width 0.07112)
			(type default)
		)
		(layer "In15.Cu")
	)
	(gr_line
		(start 64.007746 -385.579112)
		(end 64.060578 -385.548632)
		(stroke
			(width 0.07112)
			(type default)
		)
		(layer "In15.Cu")
	)
	(gr_line
		(start 64.060578 -385.548632)
		(end 64.148716 -385.460494)
		(stroke
			(width 0.07112)
			(type default)
		)
		(layer "In15.Cu")
	)
	(gr_line
		(start 64.148716 -385.460494)
		(end 64.148716 -385.334764)
		(stroke
			(width 0.07112)
			(type default)
		)
		(layer "In15.Cu")
	)
	(gr_line
		(start 64.477138 -392.707622)
		(end 64.489584 -392.707622)
		(stroke
			(width 0.07112)
			(type default)
		)
		(layer "In15.Cu")
	)
	(gr_line
		(start 64.478408 -392.990832)
		(end 64.616584 -393.129008)
		(stroke
			(width 0.07112)
			(type default)
		)
		(layer "In15.Cu")
	)
	(gr_line
		(start 64.489584 -392.707622)
		(end 64.616584 -392.580622)
		(stroke
			(width 0.07112)
			(type default)
		)
		(layer "In15.Cu")
	)
	(gr_line
		(start 64.5033 -438.623202)
		(end 64.499744 -438.623202)
		(stroke
			(width 0.07112)
			(type default)
		)
		(layer "In15.Cu")
	)
	(gr_line
		(start 64.591438 -385.31038)
		(end 64.944498 -385.405376)
		(stroke
			(width 0.07112)
			(type default)
		)
		(layer "In15.Cu")
	)
	(gr_line
		(start 64.616584 -393.129008)
		(end 64.616584 -393.292838)
		(stroke
			(width 0.07112)
			(type default)
		)
		(layer "In15.Cu")
	)
	(gr_line
		(start 64.616584 -392.580622)
		(end 64.616584 -392.429238)
		(stroke
			(width 0.07112)
			(type default)
		)
		(layer "In15.Cu")
	)
	(gr_line
		(start 64.649858 -439.0898)
		(end 64.649858 -438.76976)
		(stroke
			(width 0.07112)
			(type default)
		)
		(layer "In15.Cu")
	)
	(gr_line
		(start 64.649858 -438.76976)
		(end 64.5033 -438.623202)
		(stroke
			(width 0.07112)
			(type default)
		)
		(layer "In15.Cu")
	)
	(gr_line
		(start 64.649858 -438.191148)
		(end 64.501014 -438.339992)
		(stroke
			(width 0.07112)
			(type default)
		)
		(layer "In15.Cu")
	)
	(gr_line
		(start 64.649858 -437.889904)
		(end 64.649858 -438.191148)
		(stroke
			(width 0.07112)
			(type default)
		)
		(layer "In15.Cu")
	)
	(gr_line
		(start 64.89192 -397.089376)
		(end 64.721994 -397.180054)
		(stroke
			(width 0.07112)
			(type default)
		)
		(layer "In15.Cu")
	)
	(gr_line
		(start 64.944498 -385.405376)
		(end 64.945006 -385.404868)
		(stroke
			(width 0.07112)
			(type default)
		)
		(layer "In15.Cu")
	)
	(gr_line
		(start 64.991234 -386.003292)
		(end 65.085976 -385.649724)
		(stroke
			(width 0.07112)
			(type default)
		)
		(layer "In15.Cu")
	)
	(gr_line
		(start 65.207642 -385.579112)
		(end 65.260474 -385.548632)
		(stroke
			(width 0.07112)
			(type default)
		)
		(layer "In15.Cu")
	)
	(gr_line
		(start 65.260474 -385.548632)
		(end 65.348612 -385.460494)
		(stroke
			(width 0.07112)
			(type default)
		)
		(layer "In15.Cu")
	)
	(gr_line
		(start 65.300352 -397.213074)
		(end 64.89192 -397.089376)
		(stroke
			(width 0.07112)
			(type default)
		)
		(layer "In15.Cu")
	)
	(gr_line
		(start 65.310004 -397.654272)
		(end 64.638936 -397.450818)
		(stroke
			(width 0.07112)
			(type default)
		)
		(layer "In15.Cu")
	)
	(gr_line
		(start 65.348612 -385.460494)
		(end 65.348612 -385.334764)
		(stroke
			(width 0.07112)
			(type default)
		)
		(layer "In15.Cu")
	)
	(gr_line
		(start 65.39103 -397.383)
		(end 65.300352 -397.213074)
		(stroke
			(width 0.07112)
			(type default)
		)
		(layer "In15.Cu")
	)
	(gr_line
		(start 65.677034 -392.707622)
		(end 65.68948 -392.707622)
		(stroke
			(width 0.07112)
			(type default)
		)
		(layer "In15.Cu")
	)
	(gr_line
		(start 65.678304 -392.990832)
		(end 65.81648 -393.129008)
		(stroke
			(width 0.07112)
			(type default)
		)
		(layer "In15.Cu")
	)
	(gr_line
		(start 65.68948 -392.707622)
		(end 65.81648 -392.580622)
		(stroke
			(width 0.07112)
			(type default)
		)
		(layer "In15.Cu")
	)
	(gr_line
		(start 65.7479 -402.83765)
		(end 65.748154 -402.83765)
		(stroke
			(width 0.07112)
			(type default)
		)
		(layer "In15.Cu")
	)
	(gr_line
		(start 65.791334 -385.31038)
		(end 66.144648 -385.405376)
		(stroke
			(width 0.07112)
			(type default)
		)
		(layer "In15.Cu")
	)
	(gr_line
		(start 65.81648 -393.129008)
		(end 65.81648 -393.292838)
		(stroke
			(width 0.07112)
			(type default)
		)
		(layer "In15.Cu")
	)
	(gr_line
		(start 65.81648 -392.580622)
		(end 65.81648 -392.429238)
		(stroke
			(width 0.07112)
			(type default)
		)
		(layer "In15.Cu")
	)
	(gr_line
		(start 66.03492 -402.502624)
		(end 65.857374 -402.576538)
		(stroke
			(width 0.07112)
			(type default)
		)
		(layer "In15.Cu")
	)
	(gr_line
		(start 66.144648 -385.405376)
		(end 66.145156 -385.404868)
		(stroke
			(width 0.07112)
			(type default)
		)
		(layer "In15.Cu")
	)
	(gr_line
		(start 66.191384 -386.003292)
		(end 66.286126 -385.649724)
		(stroke
			(width 0.07112)
			(type default)
		)
		(layer "In15.Cu")
	)
	(gr_line
		(start 66.396108 -403.105874)
		(end 65.7479 -402.83765)
		(stroke
			(width 0.07112)
			(type default)
		)
		(layer "In15.Cu")
	)
	(gr_line
		(start 66.407792 -385.579112)
		(end 66.460624 -385.548632)
		(stroke
			(width 0.07112)
			(type default)
		)
		(layer "In15.Cu")
	)
	(gr_line
		(start 66.429636 -402.665946)
		(end 66.03492 -402.502624)
		(stroke
			(width 0.07112)
			(type default)
		)
		(layer "In15.Cu")
	)
	(gr_line
		(start 66.457322 -394.411962)
		(end 66.292222 -394.511022)
		(stroke
			(width 0.07112)
			(type default)
		)
		(layer "In15.Cu")
	)
	(gr_line
		(start 66.460624 -385.548632)
		(end 66.548762 -385.460494)
		(stroke
			(width 0.07112)
			(type default)
		)
		(layer "In15.Cu")
	)
	(gr_line
		(start 66.464434 -409.3718)
		(end 66.464434 -408.67076)
		(stroke
			(width 0.07112)
			(type default)
		)
		(layer "In15.Cu")
	)
	(gr_line
		(start 66.464434 -408.24404)
		(end 66.464434 -407.543)
		(stroke
			(width 0.07112)
			(type default)
		)
		(layer "In15.Cu")
	)
	(gr_line
		(start 66.503042 -402.843746)
		(end 66.429636 -402.665946)
		(stroke
			(width 0.07112)
			(type default)
		)
		(layer "In15.Cu")
	)
	(gr_line
		(start 66.503296 -437.623204)
		(end 66.49974 -437.623204)
		(stroke
			(width 0.07112)
			(type default)
		)
		(layer "In15.Cu")
	)
	(gr_line
		(start 66.548762 -385.460494)
		(end 66.548762 -385.334764)
		(stroke
			(width 0.07112)
			(type default)
		)
		(layer "In15.Cu")
	)
	(gr_line
		(start 66.649854 -438.089802)
		(end 66.649854 -437.769762)
		(stroke
			(width 0.07112)
			(type default)
		)
		(layer "In15.Cu")
	)
	(gr_line
		(start 66.649854 -437.769762)
		(end 66.503296 -437.623204)
		(stroke
			(width 0.07112)
			(type default)
		)
		(layer "In15.Cu")
	)
	(gr_line
		(start 66.649854 -437.19115)
		(end 66.50101 -437.339994)
		(stroke
			(width 0.07112)
			(type default)
		)
		(layer "In15.Cu")
	)
	(gr_line
		(start 66.649854 -436.889906)
		(end 66.649854 -437.19115)
		(stroke
			(width 0.07112)
			(type default)
		)
		(layer "In15.Cu")
	)
	(gr_line
		(start 66.747644 -409.37053)
		(end 66.883534 -409.23464)
		(stroke
			(width 0.07112)
			(type default)
		)
		(layer "In15.Cu")
	)
	(gr_line
		(start 66.747644 -408.24277)
		(end 66.883534 -408.10688)
		(stroke
			(width 0.07112)
			(type default)
		)
		(layer "In15.Cu")
	)
	(gr_line
		(start 66.871596 -394.51534)
		(end 66.457322 -394.411962)
		(stroke
			(width 0.07112)
			(type default)
		)
		(layer "In15.Cu")
	)
	(gr_line
		(start 66.883534 -409.23464)
		(end 66.883534 -408.80792)
		(stroke
			(width 0.07112)
			(type default)
		)
		(layer "In15.Cu")
	)
	(gr_line
		(start 66.883534 -408.80792)
		(end 66.747644 -408.67203)
		(stroke
			(width 0.07112)
			(type default)
		)
		(layer "In15.Cu")
	)
	(gr_line
		(start 66.883534 -408.10688)
		(end 66.883534 -407.68016)
		(stroke
			(width 0.07112)
			(type default)
		)
		(layer "In15.Cu")
	)
	(gr_line
		(start 66.883534 -407.68016)
		(end 66.747644 -407.54427)
		(stroke
			(width 0.07112)
			(type default)
		)
		(layer "In15.Cu")
	)
	(gr_line
		(start 66.903092 -394.955268)
		(end 66.222626 -394.785596)
		(stroke
			(width 0.07112)
			(type default)
		)
		(layer "In15.Cu")
	)
	(gr_line
		(start 66.970402 -394.680186)
		(end 66.871596 -394.51534)
		(stroke
			(width 0.07112)
			(type default)
		)
		(layer "In15.Cu")
	)
	(gr_line
		(start 68.503292 -438.623202)
		(end 68.499736 -438.623202)
		(stroke
			(width 0.07112)
			(type default)
		)
		(layer "In15.Cu")
	)
	(gr_line
		(start 68.64985 -439.0898)
		(end 68.64985 -438.76976)
		(stroke
			(width 0.07112)
			(type default)
		)
		(layer "In15.Cu")
	)
	(gr_line
		(start 68.64985 -438.76976)
		(end 68.503292 -438.623202)
		(stroke
			(width 0.07112)
			(type default)
		)
		(layer "In15.Cu")
	)
	(gr_line
		(start 68.64985 -438.191148)
		(end 68.501006 -438.339992)
		(stroke
			(width 0.07112)
			(type default)
		)
		(layer "In15.Cu")
	)
	(gr_line
		(start 68.64985 -437.889904)
		(end 68.64985 -438.191148)
		(stroke
			(width 0.07112)
			(type default)
		)
		(layer "In15.Cu")
	)
	(gr_line
		(start 69.527674 -409.476702)
		(end 69.527674 -408.775662)
		(stroke
			(width 0.07112)
			(type default)
		)
		(layer "In15.Cu")
	)
	(gr_line
		(start 69.527674 -408.348942)
		(end 69.527674 -407.647902)
		(stroke
			(width 0.07112)
			(type default)
		)
		(layer "In15.Cu")
	)
	(gr_line
		(start 69.810884 -409.475432)
		(end 69.946774 -409.339542)
		(stroke
			(width 0.07112)
			(type default)
		)
		(layer "In15.Cu")
	)
	(gr_line
		(start 69.810884 -408.347672)
		(end 69.946774 -408.211782)
		(stroke
			(width 0.07112)
			(type default)
		)
		(layer "In15.Cu")
	)
	(gr_line
		(start 69.946774 -409.339542)
		(end 69.946774 -408.912822)
		(stroke
			(width 0.07112)
			(type default)
		)
		(layer "In15.Cu")
	)
	(gr_line
		(start 69.946774 -408.912822)
		(end 69.810884 -408.776932)
		(stroke
			(width 0.07112)
			(type default)
		)
		(layer "In15.Cu")
	)
	(gr_line
		(start 69.946774 -408.211782)
		(end 69.946774 -407.785062)
		(stroke
			(width 0.07112)
			(type default)
		)
		(layer "In15.Cu")
	)
	(gr_line
		(start 69.946774 -407.785062)
		(end 69.810884 -407.649172)
		(stroke
			(width 0.07112)
			(type default)
		)
		(layer "In15.Cu")
	)
	(gr_line
		(start 70.503288 -437.623204)
		(end 70.499732 -437.623204)
		(stroke
			(width 0.07112)
			(type default)
		)
		(layer "In15.Cu")
	)
	(gr_line
		(start 70.584314 -400.77771)
		(end 70.414388 -400.868642)
		(stroke
			(width 0.07112)
			(type default)
		)
		(layer "In15.Cu")
	)
	(gr_line
		(start 70.649846 -438.089802)
		(end 70.649846 -437.769762)
		(stroke
			(width 0.07112)
			(type default)
		)
		(layer "In15.Cu")
	)
	(gr_line
		(start 70.649846 -437.769762)
		(end 70.503288 -437.623204)
		(stroke
			(width 0.07112)
			(type default)
		)
		(layer "In15.Cu")
	)
	(gr_line
		(start 70.649846 -437.19115)
		(end 70.501002 -437.339994)
		(stroke
			(width 0.07112)
			(type default)
		)
		(layer "In15.Cu")
	)
	(gr_line
		(start 70.649846 -436.889906)
		(end 70.649846 -437.19115)
		(stroke
			(width 0.07112)
			(type default)
		)
		(layer "In15.Cu")
	)
	(gr_line
		(start 70.86981 -395.09827)
		(end 70.720966 -395.22019)
		(stroke
			(width 0.07112)
			(type default)
		)
		(layer "In15.Cu")
	)
	(gr_line
		(start 70.993 -400.901408)
		(end 70.584314 -400.77771)
		(stroke
			(width 0.07112)
			(type default)
		)
		(layer "In15.Cu")
	)
	(gr_line
		(start 71.002652 -401.34286)
		(end 70.33133 -401.139406)
		(stroke
			(width 0.07112)
			(type default)
		)
		(layer "In15.Cu")
	)
	(gr_line
		(start 71.083678 -401.071588)
		(end 70.993 -400.901408)
		(stroke
			(width 0.07112)
			(type default)
		)
		(layer "In15.Cu")
	)
	(gr_line
		(start 71.120762 -397.567404)
		(end 70.965822 -397.682212)
		(stroke
			(width 0.07112)
			(type default)
		)
		(layer "In15.Cu")
	)
	(gr_line
		(start 71.294752 -395.140434)
		(end 70.86981 -395.09827)
		(stroke
			(width 0.07112)
			(type default)
		)
		(layer "In15.Cu")
	)
	(gr_line
		(start 71.389748 -395.571218)
		(end 70.691756 -395.501876)
		(stroke
			(width 0.07112)
			(type default)
		)
		(layer "In15.Cu")
	)
	(gr_line
		(start 71.416672 -395.289278)
		(end 71.294752 -395.140434)
		(stroke
			(width 0.07112)
			(type default)
		)
		(layer "In15.Cu")
	)
	(gr_line
		(start 71.53021 -416.821366)
		(end 71.42734 -416.127692)
		(stroke
			(width 0.07112)
			(type default)
		)
		(layer "In15.Cu")
	)
	(gr_line
		(start 71.54291 -397.630142)
		(end 71.120762 -397.567404)
		(stroke
			(width 0.07112)
			(type default)
		)
		(layer "In15.Cu")
	)
	(gr_line
		(start 71.599044 -396.416276)
		(end 71.444612 -396.53083)
		(stroke
			(width 0.07112)
			(type default)
		)
		(layer "In15.Cu")
	)
	(gr_line
		(start 71.617078 -398.06499)
		(end 70.923404 -397.96212)
		(stroke
			(width 0.07112)
			(type default)
		)
		(layer "In15.Cu")
	)
	(gr_line
		(start 71.657464 -397.784828)
		(end 71.54291 -397.630142)
		(stroke
			(width 0.07112)
			(type default)
		)
		(layer "In15.Cu")
	)
	(gr_line
		(start 71.66356 -401.105116)
		(end 71.493888 -401.195794)
		(stroke
			(width 0.07112)
			(type default)
		)
		(layer "In15.Cu")
	)
	(gr_line
		(start 71.810372 -416.778694)
		(end 71.924672 -416.624008)
		(stroke
			(width 0.07112)
			(type default)
		)
		(layer "In15.Cu")
	)
	(gr_line
		(start 71.862188 -416.201606)
		(end 71.707756 -416.08756)
		(stroke
			(width 0.07112)
			(type default)
		)
		(layer "In15.Cu")
	)
	(gr_line
		(start 71.924672 -416.624008)
		(end 71.862188 -416.201606)
		(stroke
			(width 0.07112)
			(type default)
		)
		(layer "In15.Cu")
	)
	(gr_line
		(start 71.931022 -311.559448)
		(end 71.931276 -311.559702)
		(stroke
			(width 0.07112)
			(type default)
		)
		(layer "In15.Cu")
	)
	(gr_line
		(start 72.021446 -396.47876)
		(end 71.599044 -396.416276)
		(stroke
			(width 0.07112)
			(type default)
		)
		(layer "In15.Cu")
	)
	(gr_line
		(start 72.072246 -401.229068)
		(end 71.66356 -401.105116)
		(stroke
			(width 0.07112)
			(type default)
		)
		(layer "In15.Cu")
	)
	(gr_line
		(start 72.081898 -401.670266)
		(end 71.41083 -401.466558)
		(stroke
			(width 0.07112)
			(type default)
		)
		(layer "In15.Cu")
	)
	(gr_line
		(start 72.095614 -396.913862)
		(end 71.40194 -396.810738)
		(stroke
			(width 0.07112)
			(type default)
		)
		(layer "In15.Cu")
	)
	(gr_line
		(start 72.136 -396.633446)
		(end 72.021446 -396.47876)
		(stroke
			(width 0.07112)
			(type default)
		)
		(layer "In15.Cu")
	)
	(gr_line
		(start 72.140572 -396.920466)
		(end 72.095614 -396.913862)
		(stroke
			(width 0.07112)
			(type default)
		)
		(layer "In15.Cu")
	)
	(gr_line
		(start 72.162924 -401.39874)
		(end 72.072246 -401.229068)
		(stroke
			(width 0.07112)
			(type default)
		)
		(layer "In15.Cu")
	)
	(gr_line
		(start 72.181974 -396.641574)
		(end 72.137016 -396.63497)
		(stroke
			(width 0.07112)
			(type default)
		)
		(layer "In15.Cu")
	)
	(gr_line
		(start 72.21474 -311.893204)
		(end 72.040242 -311.820814)
		(stroke
			(width 0.07112)
			(type default)
		)
		(layer "In15.Cu")
	)
	(gr_line
		(start 72.477884 -400.00682)
		(end 72.315324 -400.10969)
		(stroke
			(width 0.07112)
			(type default)
		)
		(layer "In15.Cu")
	)
	(gr_line
		(start 72.503538 -438.337452)
		(end 72.499474 -438.337452)
		(stroke
			(width 0.07112)
			(type default)
		)
		(layer "In15.Cu")
	)
	(gr_line
		(start 72.574404 -311.293002)
		(end 71.931022 -311.559448)
		(stroke
			(width 0.07112)
			(type default)
		)
		(layer "In15.Cu")
	)
	(gr_line
		(start 72.590914 -409.601416)
		(end 72.590914 -408.900376)
		(stroke
			(width 0.07112)
			(type default)
		)
		(layer "In15.Cu")
	)
	(gr_line
		(start 72.590914 -408.473656)
		(end 72.590914 -407.772616)
		(stroke
			(width 0.07112)
			(type default)
		)
		(layer "In15.Cu")
	)
	(gr_line
		(start 72.609456 -311.729882)
		(end 72.21474 -311.893204)
		(stroke
			(width 0.07112)
			(type default)
		)
		(layer "In15.Cu")
	)
	(gr_line
		(start 72.649842 -439.0898)
		(end 72.649842 -438.76976)
		(stroke
			(width 0.07112)
			(type default)
		)
		(layer "In15.Cu")
	)
	(gr_line
		(start 72.649842 -438.76976)
		(end 72.500744 -438.620662)
		(stroke
			(width 0.07112)
			(type default)
		)
		(layer "In15.Cu")
	)
	(gr_line
		(start 72.649842 -438.191148)
		(end 72.503538 -438.337452)
		(stroke
			(width 0.07112)
			(type default)
		)
		(layer "In15.Cu")
	)
	(gr_line
		(start 72.649842 -437.889904)
		(end 72.649842 -438.191148)
		(stroke
			(width 0.07112)
			(type default)
		)
		(layer "In15.Cu")
	)
	(gr_line
		(start 72.681846 -311.55513)
		(end 72.609456 -311.729882)
		(stroke
			(width 0.07112)
			(type default)
		)
		(layer "In15.Cu")
	)
	(gr_line
		(start 72.74306 -401.432522)
		(end 72.573134 -401.5232)
		(stroke
			(width 0.07112)
			(type default)
		)
		(layer "In15.Cu")
	)
	(gr_line
		(start 72.874124 -409.600146)
		(end 73.010014 -409.464256)
		(stroke
			(width 0.07112)
			(type default)
		)
		(layer "In15.Cu")
	)
	(gr_line
		(start 72.874124 -408.472386)
		(end 73.010014 -408.336496)
		(stroke
			(width 0.07112)
			(type default)
		)
		(layer "In15.Cu")
	)
	(gr_line
		(start 72.894444 -400.100292)
		(end 72.477884 -400.00682)
		(stroke
			(width 0.07112)
			(type default)
		)
		(layer "In15.Cu")
	)
	(gr_line
		(start 72.936608 -400.539458)
		(end 72.252332 -400.385788)
		(stroke
			(width 0.07112)
			(type default)
		)
		(layer "In15.Cu")
	)
	(gr_line
		(start 72.997314 -400.262852)
		(end 72.894444 -400.100292)
		(stroke
			(width 0.07112)
			(type default)
		)
		(layer "In15.Cu")
	)
	(gr_line
		(start 73.010014 -409.464256)
		(end 73.010014 -409.037536)
		(stroke
			(width 0.07112)
			(type default)
		)
		(layer "In15.Cu")
	)
	(gr_line
		(start 73.010014 -409.037536)
		(end 72.874124 -408.901646)
		(stroke
			(width 0.07112)
			(type default)
		)
		(layer "In15.Cu")
	)
	(gr_line
		(start 73.010014 -408.336496)
		(end 73.010014 -407.909776)
		(stroke
			(width 0.07112)
			(type default)
		)
		(layer "In15.Cu")
	)
	(gr_line
		(start 73.010014 -407.909776)
		(end 72.874124 -407.773886)
		(stroke
			(width 0.07112)
			(type default)
		)
		(layer "In15.Cu")
	)
	(gr_line
		(start 73.151492 -401.556474)
		(end 72.74306 -401.432522)
		(stroke
			(width 0.07112)
			(type default)
		)
		(layer "In15.Cu")
	)
	(gr_line
		(start 73.161144 -401.997418)
		(end 72.490076 -401.793964)
		(stroke
			(width 0.07112)
			(type default)
		)
		(layer "In15.Cu")
	)
	(gr_line
		(start 73.2028 -396.654274)
		(end 73.048368 -396.769082)
		(stroke
			(width 0.07112)
			(type default)
		)
		(layer "In15.Cu")
	)
	(gr_line
		(start 73.24217 -401.726146)
		(end 73.151492 -401.556474)
		(stroke
			(width 0.07112)
			(type default)
		)
		(layer "In15.Cu")
	)
	(gr_line
		(start 73.475088 -395.356842)
		(end 73.326244 -395.478762)
		(stroke
			(width 0.07112)
			(type default)
		)
		(layer "In15.Cu")
	)
	(gr_line
		(start 73.625202 -396.717012)
		(end 73.2028 -396.654274)
		(stroke
			(width 0.07112)
			(type default)
		)
		(layer "In15.Cu")
	)
	(gr_line
		(start 73.69937 -397.15186)
		(end 73.005696 -397.04899)
		(stroke
			(width 0.07112)
			(type default)
		)
		(layer "In15.Cu")
	)
	(gr_line
		(start 73.739756 -396.871698)
		(end 73.625202 -396.717012)
		(stroke
			(width 0.07112)
			(type default)
		)
		(layer "In15.Cu")
	)
	(gr_line
		(start 73.90003 -395.399006)
		(end 73.475088 -395.356842)
		(stroke
			(width 0.07112)
			(type default)
		)
		(layer "In15.Cu")
	)
	(gr_line
		(start 73.962006 -311.172606)
		(end 73.783698 -311.098692)
		(stroke
			(width 0.07112)
			(type default)
		)
		(layer "In15.Cu")
	)
	(gr_line
		(start 73.985374 -397.992346)
		(end 73.830688 -398.107154)
		(stroke
			(width 0.07112)
			(type default)
		)
		(layer "In15.Cu")
	)
	(gr_line
		(start 73.995026 -395.82979)
		(end 73.297034 -395.760448)
		(stroke
			(width 0.07112)
			(type default)
		)
		(layer "In15.Cu")
	)
	(gr_line
		(start 74.02195 -395.54785)
		(end 73.90003 -395.399006)
		(stroke
			(width 0.07112)
			(type default)
		)
		(layer "In15.Cu")
	)
	(gr_line
		(start 74.27214 -417.23056)
		(end 74.27214 -416.52952)
		(stroke
			(width 0.07112)
			(type default)
		)
		(layer "In15.Cu")
	)
	(gr_line
		(start 74.27214 -416.1028)
		(end 74.27214 -415.40176)
		(stroke
			(width 0.07112)
			(type default)
		)
		(layer "In15.Cu")
	)
	(gr_line
		(start 74.32294 -310.568848)
		(end 73.674986 -310.837326)
		(stroke
			(width 0.07112)
			(type default)
		)
		(layer "In15.Cu")
	)
	(gr_line
		(start 74.356468 -311.009284)
		(end 73.962006 -311.172606)
		(stroke
			(width 0.07112)
			(type default)
		)
		(layer "In15.Cu")
	)
	(gr_line
		(start 74.390758 -401.93214)
		(end 74.220832 -402.023072)
		(stroke
			(width 0.07112)
			(type default)
		)
		(layer "In15.Cu")
	)
	(gr_line
		(start 74.407776 -398.055084)
		(end 73.985374 -397.992346)
		(stroke
			(width 0.07112)
			(type default)
		)
		(layer "In15.Cu")
	)
	(gr_line
		(start 74.430382 -310.830976)
		(end 74.356468 -311.009284)
		(stroke
			(width 0.07112)
			(type default)
		)
		(layer "In15.Cu")
	)
	(gr_line
		(start 74.481944 -398.490186)
		(end 73.78827 -398.387316)
		(stroke
			(width 0.07112)
			(type default)
		)
		(layer "In15.Cu")
	)
	(gr_line
		(start 74.522584 -398.20977)
		(end 74.407776 -398.055084)
		(stroke
			(width 0.07112)
			(type default)
		)
		(layer "In15.Cu")
	)
	(gr_line
		(start 74.55535 -417.22929)
		(end 74.69124 -417.0934)
		(stroke
			(width 0.07112)
			(type default)
		)
		(layer "In15.Cu")
	)
	(gr_line
		(start 74.55535 -416.10153)
		(end 74.69124 -415.96564)
		(stroke
			(width 0.07112)
			(type default)
		)
		(layer "In15.Cu")
	)
	(gr_line
		(start 74.69124 -417.0934)
		(end 74.69124 -416.66668)
		(stroke
			(width 0.07112)
			(type default)
		)
		(layer "In15.Cu")
	)
	(gr_line
		(start 74.69124 -416.66668)
		(end 74.55535 -416.53079)
		(stroke
			(width 0.07112)
			(type default)
		)
		(layer "In15.Cu")
	)
	(gr_line
		(start 74.69124 -415.96564)
		(end 74.69124 -415.53892)
		(stroke
			(width 0.07112)
			(type default)
		)
		(layer "In15.Cu")
	)
	(gr_line
		(start 74.69124 -415.53892)
		(end 74.55535 -415.40303)
		(stroke
			(width 0.07112)
			(type default)
		)
		(layer "In15.Cu")
	)
	(gr_line
		(start 74.799444 -402.056092)
		(end 74.390758 -401.93214)
		(stroke
			(width 0.07112)
			(type default)
		)
		(layer "In15.Cu")
	)
	(gr_line
		(start 74.809096 -402.49729)
		(end 74.137774 -402.293836)
		(stroke
			(width 0.07112)
			(type default)
		)
		(layer "In15.Cu")
	)
	(gr_line
		(start 74.890122 -402.226018)
		(end 74.799444 -402.056092)
		(stroke
			(width 0.07112)
			(type default)
		)
		(layer "In15.Cu")
	)
	(gr_line
		(start 75.004168 -310.740806)
		(end 74.826114 -310.667146)
		(stroke
			(width 0.07112)
			(type default)
		)
		(layer "In15.Cu")
	)
	(gr_line
		(start 75.100942 -398.157954)
		(end 74.946256 -398.272762)
		(stroke
			(width 0.07112)
			(type default)
		)
		(layer "In15.Cu")
	)
	(gr_line
		(start 75.21321 -400.727418)
		(end 75.03541 -400.801078)
		(stroke
			(width 0.07112)
			(type default)
		)
		(layer "In15.Cu")
	)
	(gr_line
		(start 75.240134 -396.956788)
		(end 75.085448 -397.071596)
		(stroke
			(width 0.07112)
			(type default)
		)
		(layer "In15.Cu")
	)
	(gr_line
		(start 75.31862 -51.070764)
		(end 75.319382 -51.07051)
		(stroke
			(width 0.07112)
			(type default)
		)
		(layer "In15.Cu")
	)
	(gr_line
		(start 75.365102 -310.137302)
		(end 74.717148 -310.40578)
		(stroke
			(width 0.07112)
			(type default)
		)
		(layer "In15.Cu")
	)
	(gr_line
		(start 75.367388 -51.356514)
		(end 75.367896 -51.35626)
		(stroke
			(width 0.07112)
			(type default)
		)
		(layer "In15.Cu")
	)
	(gr_line
		(start 75.39863 -310.577484)
		(end 75.004168 -310.740806)
		(stroke
			(width 0.07112)
			(type default)
		)
		(layer "In15.Cu")
	)
	(gr_line
		(start 75.470004 -402.259546)
		(end 75.300332 -402.350224)
		(stroke
			(width 0.07112)
			(type default)
		)
		(layer "In15.Cu")
	)
	(gr_line
		(start 75.472544 -310.39943)
		(end 75.39863 -310.577484)
		(stroke
			(width 0.07112)
			(type default)
		)
		(layer "In15.Cu")
	)
	(gr_line
		(start 75.50404 -437.3372)
		(end 75.499468 -437.3372)
		(stroke
			(width 0.07112)
			(type default)
		)
		(layer "In15.Cu")
	)
	(gr_line
		(start 75.523344 -398.220692)
		(end 75.100942 -398.157954)
		(stroke
			(width 0.07112)
			(type default)
		)
		(layer "In15.Cu")
	)
	(gr_line
		(start 75.57389 -401.330668)
		(end 74.925936 -401.06219)
		(stroke
			(width 0.07112)
			(type default)
		)
		(layer "In15.Cu")
	)
	(gr_line
		(start 75.597512 -398.655794)
		(end 74.903838 -398.55267)
		(stroke
			(width 0.07112)
			(type default)
		)
		(layer "In15.Cu")
	)
	(gr_line
		(start 75.607672 -400.89074)
		(end 75.21321 -400.727418)
		(stroke
			(width 0.07112)
			(type default)
		)
		(layer "In15.Cu")
	)
	(gr_line
		(start 75.637898 -398.375378)
		(end 75.523344 -398.220692)
		(stroke
			(width 0.07112)
			(type default)
		)
		(layer "In15.Cu")
	)
	(gr_line
		(start 75.65009 -438.089802)
		(end 75.65009 -437.769762)
		(stroke
			(width 0.07112)
			(type default)
		)
		(layer "In15.Cu")
	)
	(gr_line
		(start 75.65009 -437.769762)
		(end 75.500738 -437.62041)
		(stroke
			(width 0.07112)
			(type default)
		)
		(layer "In15.Cu")
	)
	(gr_line
		(start 75.65009 -437.19115)
		(end 75.50404 -437.3372)
		(stroke
			(width 0.07112)
			(type default)
		)
		(layer "In15.Cu")
	)
	(gr_line
		(start 75.65009 -436.889906)
		(end 75.65009 -437.19115)
		(stroke
			(width 0.07112)
			(type default)
		)
		(layer "In15.Cu")
	)
	(gr_line
		(start 75.654154 -409.22702)
		(end 75.654154 -408.52598)
		(stroke
			(width 0.07112)
			(type default)
		)
		(layer "In15.Cu")
	)
	(gr_line
		(start 75.654154 -408.09926)
		(end 75.654154 -407.39822)
		(stroke
			(width 0.07112)
			(type default)
		)
		(layer "In15.Cu")
	)
	(gr_line
		(start 75.662282 -397.019526)
		(end 75.240134 -396.956788)
		(stroke
			(width 0.07112)
			(type default)
		)
		(layer "In15.Cu")
	)
	(gr_line
		(start 75.681078 -401.06854)
		(end 75.607672 -400.89074)
		(stroke
			(width 0.07112)
			(type default)
		)
		(layer "In15.Cu")
	)
	(gr_line
		(start 75.73645 -397.454374)
		(end 75.042776 -397.351504)
		(stroke
			(width 0.07112)
			(type default)
		)
		(layer "In15.Cu")
	)
	(gr_line
		(start 75.776836 -397.174212)
		(end 75.662282 -397.019526)
		(stroke
			(width 0.07112)
			(type default)
		)
		(layer "In15.Cu")
	)
	(gr_line
		(start 75.87869 -402.383498)
		(end 75.470004 -402.259546)
		(stroke
			(width 0.07112)
			(type default)
		)
		(layer "In15.Cu")
	)
	(gr_line
		(start 75.888342 -402.824696)
		(end 75.217274 -402.620988)
		(stroke
			(width 0.07112)
			(type default)
		)
		(layer "In15.Cu")
	)
	(gr_line
		(start 75.937364 -409.22575)
		(end 76.073254 -409.08986)
		(stroke
			(width 0.07112)
			(type default)
		)
		(layer "In15.Cu")
	)
	(gr_line
		(start 75.937364 -408.09799)
		(end 76.073254 -407.9621)
		(stroke
			(width 0.07112)
			(type default)
		)
		(layer "In15.Cu")
	)
	(gr_line
		(start 75.969368 -402.55317)
		(end 75.87869 -402.383498)
		(stroke
			(width 0.07112)
			(type default)
		)
		(layer "In15.Cu")
	)
	(gr_line
		(start 76.043028 -310.307736)
		(end 75.868276 -310.2356)
		(stroke
			(width 0.07112)
			(type default)
		)
		(layer "In15.Cu")
	)
	(gr_line
		(start 76.073254 -409.08986)
		(end 76.073254 -408.66314)
		(stroke
			(width 0.07112)
			(type default)
		)
		(layer "In15.Cu")
	)
	(gr_line
		(start 76.073254 -408.66314)
		(end 75.937364 -408.52725)
		(stroke
			(width 0.07112)
			(type default)
		)
		(layer "In15.Cu")
	)
	(gr_line
		(start 76.073254 -407.9621)
		(end 76.073254 -407.53538)
		(stroke
			(width 0.07112)
			(type default)
		)
		(layer "In15.Cu")
	)
	(gr_line
		(start 76.073254 -407.53538)
		(end 75.937364 -407.39949)
		(stroke
			(width 0.07112)
			(type default)
		)
		(layer "In15.Cu")
	)
	(gr_line
		(start 76.100178 -411.230572)
		(end 76.078334 -411.21584)
		(stroke
			(width 0.07112)
			(type default)
		)
		(layer "In15.Cu")
	)
	(gr_line
		(start 76.126086 -411.241494)
		(end 76.100178 -411.230572)
		(stroke
			(width 0.07112)
			(type default)
		)
		(layer "In15.Cu")
	)
	(gr_line
		(start 76.12634 -411.24124)
		(end 76.12634 -411.241494)
		(stroke
			(width 0.07112)
			(type default)
		)
		(layer "In15.Cu")
	)
	(gr_line
		(start 76.402438 -309.707788)
		(end 75.75931 -309.974234)
		(stroke
			(width 0.07112)
			(type default)
		)
		(layer "In15.Cu")
	)
	(gr_line
		(start 76.43749 -310.144668)
		(end 76.043028 -310.307736)
		(stroke
			(width 0.07112)
			(type default)
		)
		(layer "In15.Cu")
	)
	(gr_line
		(start 76.509626 -309.969916)
		(end 76.43749 -310.144668)
		(stroke
			(width 0.07112)
			(type default)
		)
		(layer "In15.Cu")
	)
	(gr_line
		(start 76.693776 -401.340828)
		(end 76.515976 -401.414234)
		(stroke
			(width 0.07112)
			(type default)
		)
		(layer "In15.Cu")
	)
	(gr_line
		(start 76.69403 -418.854128)
		(end 76.69403 -418.153088)
		(stroke
			(width 0.07112)
			(type default)
		)
		(layer "In15.Cu")
	)
	(gr_line
		(start 76.806552 -416.20313)
		(end 76.893674 -415.50717)
		(stroke
			(width 0.07112)
			(type default)
		)
		(layer "In15.Cu")
	)
	(gr_line
		(start 76.971652 -414.882584)
		(end 77.05852 -414.186624)
		(stroke
			(width 0.07112)
			(type default)
		)
		(layer "In15.Cu")
	)
	(gr_line
		(start 76.97724 -418.852858)
		(end 77.11313 -418.716968)
		(stroke
			(width 0.07112)
			(type default)
		)
		(layer "In15.Cu")
	)
	(gr_line
		(start 77.054456 -401.944078)
		(end 76.406502 -401.6756)
		(stroke
			(width 0.07112)
			(type default)
		)
		(layer "In15.Cu")
	)
	(gr_line
		(start 77.08773 -416.237166)
		(end 77.239622 -416.119056)
		(stroke
			(width 0.07112)
			(type default)
		)
		(layer "In15.Cu")
	)
	(gr_line
		(start 77.088238 -401.50415)
		(end 76.693776 -401.340828)
		(stroke
			(width 0.07112)
			(type default)
		)
		(layer "In15.Cu")
	)
	(gr_line
		(start 77.11313 -418.716968)
		(end 77.11313 -418.290248)
		(stroke
			(width 0.07112)
			(type default)
		)
		(layer "In15.Cu")
	)
	(gr_line
		(start 77.11313 -418.290248)
		(end 76.97724 -418.154358)
		(stroke
			(width 0.07112)
			(type default)
		)
		(layer "In15.Cu")
	)
	(gr_line
		(start 77.161644 -401.68195)
		(end 77.088238 -401.50415)
		(stroke
			(width 0.07112)
			(type default)
		)
		(layer "In15.Cu")
	)
	(gr_line
		(start 77.239622 -416.119056)
		(end 77.292708 -415.695384)
		(stroke
			(width 0.07112)
			(type default)
		)
		(layer "In15.Cu")
	)
	(gr_line
		(start 77.25283 -414.91662)
		(end 77.404722 -414.79851)
		(stroke
			(width 0.07112)
			(type default)
		)
		(layer "In15.Cu")
	)
	(gr_line
		(start 77.292708 -415.695384)
		(end 77.174598 -415.543492)
		(stroke
			(width 0.07112)
			(type default)
		)
		(layer "In15.Cu")
	)
	(gr_line
		(start 77.404722 -414.79851)
		(end 77.457808 -414.374838)
		(stroke
			(width 0.07112)
			(type default)
		)
		(layer "In15.Cu")
	)
	(gr_line
		(start 77.457808 -414.374838)
		(end 77.339444 -414.222692)
		(stroke
			(width 0.07112)
			(type default)
		)
		(layer "In15.Cu")
	)
	(gr_line
		(start 77.503528 -438.623202)
		(end 77.499972 -438.623202)
		(stroke
			(width 0.07112)
			(type default)
		)
		(layer "In15.Cu")
	)
	(gr_line
		(start 77.551534 -50.145696)
		(end 77.552042 -50.145442)
		(stroke
			(width 0.07112)
			(type default)
		)
		(layer "In15.Cu")
	)
	(gr_line
		(start 77.650086 -439.0898)
		(end 77.650086 -438.76976)
		(stroke
			(width 0.07112)
			(type default)
		)
		(layer "In15.Cu")
	)
	(gr_line
		(start 77.650086 -438.76976)
		(end 77.503528 -438.623202)
		(stroke
			(width 0.07112)
			(type default)
		)
		(layer "In15.Cu")
	)
	(gr_line
		(start 77.650086 -438.191148)
		(end 77.501242 -438.339992)
		(stroke
			(width 0.07112)
			(type default)
		)
		(layer "In15.Cu")
	)
	(gr_line
		(start 77.650086 -437.889904)
		(end 77.650086 -438.191148)
		(stroke
			(width 0.07112)
			(type default)
		)
		(layer "In15.Cu")
	)
	(gr_line
		(start 77.656436 -395.90599)
		(end 77.49667 -396.012924)
		(stroke
			(width 0.07112)
			(type default)
		)
		(layer "In15.Cu")
	)
	(gr_line
		(start 77.659484 -50.406554)
		(end 77.659738 -50.406046)
		(stroke
			(width 0.07112)
			(type default)
		)
		(layer "In15.Cu")
	)
	(gr_line
		(start 77.672184 -397.317976)
		(end 77.517752 -397.43253)
		(stroke
			(width 0.07112)
			(type default)
		)
		(layer "In15.Cu")
	)
	(gr_line
		(start 78.075282 -395.989302)
		(end 77.656436 -395.90599)
		(stroke
			(width 0.07112)
			(type default)
		)
		(layer "In15.Cu")
	)
	(gr_line
		(start 78.094586 -397.38046)
		(end 77.672184 -397.317976)
		(stroke
			(width 0.07112)
			(type default)
		)
		(layer "In15.Cu")
	)
	(gr_line
		(start 78.128114 -396.427452)
		(end 77.440028 -396.290546)
		(stroke
			(width 0.07112)
			(type default)
		)
		(layer "In15.Cu")
	)
	(gr_line
		(start 78.168754 -397.815562)
		(end 77.47508 -397.712692)
		(stroke
			(width 0.07112)
			(type default)
		)
		(layer "In15.Cu")
	)
	(gr_line
		(start 78.181962 -396.149322)
		(end 78.075282 -395.989302)
		(stroke
			(width 0.07112)
			(type default)
		)
		(layer "In15.Cu")
	)
	(gr_line
		(start 78.20914 -397.5354)
		(end 78.094586 -397.38046)
		(stroke
			(width 0.07112)
			(type default)
		)
		(layer "In15.Cu")
	)
	(gr_line
		(start 78.648814 -402.150834)
		(end 78.471268 -402.22424)
		(stroke
			(width 0.07112)
			(type default)
		)
		(layer "In15.Cu")
	)
	(gr_line
		(start 78.717394 -409.401264)
		(end 78.717394 -408.700224)
		(stroke
			(width 0.07112)
			(type default)
		)
		(layer "In15.Cu")
	)
	(gr_line
		(start 78.717394 -408.273504)
		(end 78.717394 -407.572464)
		(stroke
			(width 0.07112)
			(type default)
		)
		(layer "In15.Cu")
	)
	(gr_line
		(start 78.8543 -396.144496)
		(end 78.69428 -396.25143)
		(stroke
			(width 0.07112)
			(type default)
		)
		(layer "In15.Cu")
	)
	(gr_line
		(start 79.000604 -409.399994)
		(end 79.136494 -409.264104)
		(stroke
			(width 0.07112)
			(type default)
		)
		(layer "In15.Cu")
	)
	(gr_line
		(start 79.000604 -408.272234)
		(end 79.136494 -408.136344)
		(stroke
			(width 0.07112)
			(type default)
		)
		(layer "In15.Cu")
	)
	(gr_line
		(start 79.009748 -402.754084)
		(end 78.361794 -402.485606)
		(stroke
			(width 0.07112)
			(type default)
		)
		(layer "In15.Cu")
	)
	(gr_line
		(start 79.04353 -402.314156)
		(end 78.648814 -402.150834)
		(stroke
			(width 0.07112)
			(type default)
		)
		(layer "In15.Cu")
	)
	(gr_line
		(start 79.116936 -402.491956)
		(end 79.04353 -402.314156)
		(stroke
			(width 0.07112)
			(type default)
		)
		(layer "In15.Cu")
	)
	(gr_line
		(start 79.136494 -409.264104)
		(end 79.136494 -408.837384)
		(stroke
			(width 0.07112)
			(type default)
		)
		(layer "In15.Cu")
	)
	(gr_line
		(start 79.136494 -408.837384)
		(end 79.000604 -408.701494)
		(stroke
			(width 0.07112)
			(type default)
		)
		(layer "In15.Cu")
	)
	(gr_line
		(start 79.136494 -408.136344)
		(end 79.136494 -407.709624)
		(stroke
			(width 0.07112)
			(type default)
		)
		(layer "In15.Cu")
	)
	(gr_line
		(start 79.136494 -407.709624)
		(end 79.000604 -407.573734)
		(stroke
			(width 0.07112)
			(type default)
		)
		(layer "In15.Cu")
	)
	(gr_line
		(start 79.272892 -396.227554)
		(end 78.8543 -396.144496)
		(stroke
			(width 0.07112)
			(type default)
		)
		(layer "In15.Cu")
	)
	(gr_line
		(start 79.325724 -396.665704)
		(end 78.638146 -396.528798)
		(stroke
			(width 0.07112)
			(type default)
		)
		(layer "In15.Cu")
	)
	(gr_line
		(start 79.379826 -396.387828)
		(end 79.272892 -396.227554)
		(stroke
			(width 0.07112)
			(type default)
		)
		(layer "In15.Cu")
	)
	(gr_line
		(start 79.408274 -397.575532)
		(end 79.253334 -397.69034)
		(stroke
			(width 0.07112)
			(type default)
		)
		(layer "In15.Cu")
	)
	(gr_line
		(start 79.503524 -437.623204)
		(end 79.499968 -437.623204)
		(stroke
			(width 0.07112)
			(type default)
		)
		(layer "In15.Cu")
	)
	(gr_line
		(start 79.574136 -309.504588)
		(end 79.283306 -309.213758)
		(stroke
			(width 0.07112)
			(type default)
		)
		(layer "In15.Cu")
	)
	(gr_line
		(start 79.574136 -308.640988)
		(end 79.283306 -308.931818)
		(stroke
			(width 0.07112)
			(type default)
		)
		(layer "In15.Cu")
	)
	(gr_line
		(start 79.650082 -438.089802)
		(end 79.650082 -437.769762)
		(stroke
			(width 0.07112)
			(type default)
		)
		(layer "In15.Cu")
	)
	(gr_line
		(start 79.650082 -437.769762)
		(end 79.503524 -437.623204)
		(stroke
			(width 0.07112)
			(type default)
		)
		(layer "In15.Cu")
	)
	(gr_line
		(start 79.650082 -437.19115)
		(end 79.501238 -437.339994)
		(stroke
			(width 0.07112)
			(type default)
		)
		(layer "In15.Cu")
	)
	(gr_line
		(start 79.650082 -436.889906)
		(end 79.650082 -437.19115)
		(stroke
			(width 0.07112)
			(type default)
		)
		(layer "In15.Cu")
	)
	(gr_line
		(start 79.830422 -397.63827)
		(end 79.408274 -397.575532)
		(stroke
			(width 0.07112)
			(type default)
		)
		(layer "In15.Cu")
	)
	(gr_line
		(start 79.906114 -397.740632)
		(end 79.830422 -397.63827)
		(stroke
			(width 0.07112)
			(type default)
		)
		(layer "In15.Cu")
	)
	(gr_arc
		(start 79.906114 -397.740632)
		(mid 79.94488 -397.777891)
		(end 79.993744 -397.800322)
		(stroke
			(width 0.07112)
			(type default)
		)
		(layer "In15.Cu")
	)
	(gr_line
		(start 79.939896 -398.078706)
		(end 79.210916 -397.970502)
		(stroke
			(width 0.07112)
			(type default)
		)
		(layer "In15.Cu")
	)
	(gr_line
		(start 80.005174 -415.307526)
		(end 80.005428 -415.307526)
		(stroke
			(width 0.07112)
			(type default)
		)
		(layer "In15.Cu")
	)
	(gr_line
		(start 80.005428 -415.306764)
		(end 80.042766 -415.056066)
		(stroke
			(width 0.07112)
			(type default)
		)
		(layer "In15.Cu")
	)
	(gr_line
		(start 80.042766 -415.056066)
		(end 80.108552 -414.61309)
		(stroke
			(width 0.07112)
			(type default)
		)
		(layer "In15.Cu")
	)
	(gr_line
		(start 80.144874 -411.771338)
		(end 80.145382 -411.771846)
		(stroke
			(width 0.07112)
			(type default)
		)
		(layer "In15.Cu")
	)
	(gr_line
		(start 80.285844 -415.34715)
		(end 80.44053 -415.232596)
		(stroke
			(width 0.07112)
			(type default)
		)
		(layer "In15.Cu")
	)
	(gr_line
		(start 80.306926 -378.375418)
		(end 81.007966 -378.375418)
		(stroke
			(width 0.07112)
			(type default)
		)
		(layer "In15.Cu")
	)
	(gr_line
		(start 80.308196 -378.092208)
		(end 80.444086 -377.956318)
		(stroke
			(width 0.07112)
			(type default)
		)
		(layer "In15.Cu")
	)
	(gr_line
		(start 80.44053 -415.232596)
		(end 80.503014 -414.810194)
		(stroke
			(width 0.07112)
			(type default)
		)
		(layer "In15.Cu")
	)
	(gr_line
		(start 80.444086 -377.956318)
		(end 80.870806 -377.956318)
		(stroke
			(width 0.07112)
			(type default)
		)
		(layer "In15.Cu")
	)
	(gr_line
		(start 80.503014 -414.810194)
		(end 80.38846 -414.655762)
		(stroke
			(width 0.07112)
			(type default)
		)
		(layer "In15.Cu")
	)
	(gr_line
		(start 80.675734 -396.506954)
		(end 80.515714 -396.613634)
		(stroke
			(width 0.07112)
			(type default)
		)
		(layer "In15.Cu")
	)
	(gr_line
		(start 80.870806 -377.956318)
		(end 81.006696 -378.092208)
		(stroke
			(width 0.07112)
			(type default)
		)
		(layer "In15.Cu")
	)
	(gr_line
		(start 80.97647 -424.38955)
		(end 80.976724 -424.389804)
		(stroke
			(width 0.07112)
			(type default)
		)
		(layer "In15.Cu")
	)
	(gr_line
		(start 81.04251 -401.307554)
		(end 80.853788 -401.345146)
		(stroke
			(width 0.07112)
			(type default)
		)
		(layer "In15.Cu")
	)
	(gr_line
		(start 81.09458 -396.590012)
		(end 80.675734 -396.506954)
		(stroke
			(width 0.07112)
			(type default)
		)
		(layer "In15.Cu")
	)
	(gr_line
		(start 81.134204 -420.814246)
		(end 81.337912 -420.142924)
		(stroke
			(width 0.07112)
			(type default)
		)
		(layer "In15.Cu")
	)
	(gr_line
		(start 81.147158 -397.028162)
		(end 80.459326 -396.891256)
		(stroke
			(width 0.07112)
			(type default)
		)
		(layer "In15.Cu")
	)
	(gr_line
		(start 81.20126 -396.750032)
		(end 81.09458 -396.590012)
		(stroke
			(width 0.07112)
			(type default)
		)
		(layer "In15.Cu")
	)
	(gr_line
		(start 81.278476 -401.969478)
		(end 80.695546 -401.579842)
		(stroke
			(width 0.07112)
			(type default)
		)
		(layer "In15.Cu")
	)
	(gr_line
		(start 81.397348 -401.54479)
		(end 81.04251 -401.307554)
		(stroke
			(width 0.07112)
			(type default)
		)
		(layer "In15.Cu")
	)
	(gr_line
		(start 81.405476 -420.895272)
		(end 81.575402 -420.804594)
		(stroke
			(width 0.07112)
			(type default)
		)
		(layer "In15.Cu")
	)
	(gr_line
		(start 81.434686 -378.375418)
		(end 82.135726 -378.375418)
		(stroke
			(width 0.07112)
			(type default)
		)
		(layer "In15.Cu")
	)
	(gr_line
		(start 81.43494 -401.733258)
		(end 81.397348 -401.54479)
		(stroke
			(width 0.07112)
			(type default)
		)
		(layer "In15.Cu")
	)
	(gr_line
		(start 81.435956 -378.092208)
		(end 81.571846 -377.956318)
		(stroke
			(width 0.07112)
			(type default)
		)
		(layer "In15.Cu")
	)
	(gr_line
		(start 81.50352 -438.623202)
		(end 81.499964 -438.623202)
		(stroke
			(width 0.07112)
			(type default)
		)
		(layer "In15.Cu")
	)
	(gr_line
		(start 81.571846 -377.956318)
		(end 81.998566 -377.956318)
		(stroke
			(width 0.07112)
			(type default)
		)
		(layer "In15.Cu")
	)
	(gr_line
		(start 81.575402 -420.804594)
		(end 81.6991 -420.395908)
		(stroke
			(width 0.07112)
			(type default)
		)
		(layer "In15.Cu")
	)
	(gr_line
		(start 81.650078 -439.0898)
		(end 81.650078 -438.76976)
		(stroke
			(width 0.07112)
			(type default)
		)
		(layer "In15.Cu")
	)
	(gr_line
		(start 81.650078 -438.76976)
		(end 81.50352 -438.623202)
		(stroke
			(width 0.07112)
			(type default)
		)
		(layer "In15.Cu")
	)
	(gr_line
		(start 81.650078 -438.191148)
		(end 81.501234 -438.339992)
		(stroke
			(width 0.07112)
			(type default)
		)
		(layer "In15.Cu")
	)
	(gr_line
		(start 81.650078 -437.889904)
		(end 81.650078 -438.191148)
		(stroke
			(width 0.07112)
			(type default)
		)
		(layer "In15.Cu")
	)
	(gr_line
		(start 81.6991 -420.395908)
		(end 81.608422 -420.22649)
		(stroke
			(width 0.07112)
			(type default)
		)
		(layer "In15.Cu")
	)
	(gr_line
		(start 81.780634 -409.382976)
		(end 81.780634 -408.681936)
		(stroke
			(width 0.07112)
			(type default)
		)
		(layer "In15.Cu")
	)
	(gr_line
		(start 81.780634 -408.255216)
		(end 81.780634 -407.554176)
		(stroke
			(width 0.07112)
			(type default)
		)
		(layer "In15.Cu")
	)
	(gr_line
		(start 81.998566 -377.956318)
		(end 82.134456 -378.092208)
		(stroke
			(width 0.07112)
			(type default)
		)
		(layer "In15.Cu")
	)
	(gr_line
		(start 82.063844 -409.381706)
		(end 82.199734 -409.245816)
		(stroke
			(width 0.07112)
			(type default)
		)
		(layer "In15.Cu")
	)
	(gr_line
		(start 82.063844 -408.253946)
		(end 82.199734 -408.118056)
		(stroke
			(width 0.07112)
			(type default)
		)
		(layer "In15.Cu")
	)
	(gr_line
		(start 82.199734 -409.245816)
		(end 82.199734 -408.819096)
		(stroke
			(width 0.07112)
			(type default)
		)
		(layer "In15.Cu")
	)
	(gr_line
		(start 82.199734 -408.819096)
		(end 82.063844 -408.683206)
		(stroke
			(width 0.07112)
			(type default)
		)
		(layer "In15.Cu")
	)
	(gr_line
		(start 82.199734 -408.118056)
		(end 82.199734 -407.691336)
		(stroke
			(width 0.07112)
			(type default)
		)
		(layer "In15.Cu")
	)
	(gr_line
		(start 82.199734 -407.691336)
		(end 82.063844 -407.555446)
		(stroke
			(width 0.07112)
			(type default)
		)
		(layer "In15.Cu")
	)
	(gr_line
		(start 82.562446 -378.375418)
		(end 83.263486 -378.375418)
		(stroke
			(width 0.07112)
			(type default)
		)
		(layer "In15.Cu")
	)
	(gr_line
		(start 82.563716 -378.092208)
		(end 82.699606 -377.956318)
		(stroke
			(width 0.07112)
			(type default)
		)
		(layer "In15.Cu")
	)
	(gr_line
		(start 82.699606 -377.956318)
		(end 83.126326 -377.956318)
		(stroke
			(width 0.07112)
			(type default)
		)
		(layer "In15.Cu")
	)
	(gr_line
		(start 83.042506 -400.581368)
		(end 82.85353 -400.61896)
		(stroke
			(width 0.07112)
			(type default)
		)
		(layer "In15.Cu")
	)
	(gr_line
		(start 83.126326 -377.956318)
		(end 83.262216 -378.092208)
		(stroke
			(width 0.07112)
			(type default)
		)
		(layer "In15.Cu")
	)
	(gr_line
		(start 83.167474 -411.654498)
		(end 83.167728 -411.654498)
		(stroke
			(width 0.07112)
			(type default)
		)
		(layer "In15.Cu")
	)
	(gr_line
		(start 83.278472 -401.243546)
		(end 82.695542 -400.85391)
		(stroke
			(width 0.07112)
			(type default)
		)
		(layer "In15.Cu")
	)
	(gr_line
		(start 83.397344 -400.818604)
		(end 83.042506 -400.581368)
		(stroke
			(width 0.07112)
			(type default)
		)
		(layer "In15.Cu")
	)
	(gr_line
		(start 83.434936 -401.007326)
		(end 83.397344 -400.818604)
		(stroke
			(width 0.07112)
			(type default)
		)
		(layer "In15.Cu")
	)
	(gr_line
		(start 83.503516 -437.623204)
		(end 83.49996 -437.623204)
		(stroke
			(width 0.07112)
			(type default)
		)
		(layer "In15.Cu")
	)
	(gr_line
		(start 83.650074 -438.089802)
		(end 83.650074 -437.769762)
		(stroke
			(width 0.07112)
			(type default)
		)
		(layer "In15.Cu")
	)
	(gr_line
		(start 83.650074 -437.769762)
		(end 83.503516 -437.623204)
		(stroke
			(width 0.07112)
			(type default)
		)
		(layer "In15.Cu")
	)
	(gr_line
		(start 83.650074 -437.19115)
		(end 83.50123 -437.339994)
		(stroke
			(width 0.07112)
			(type default)
		)
		(layer "In15.Cu")
	)
	(gr_line
		(start 83.650074 -436.889906)
		(end 83.650074 -437.19115)
		(stroke
			(width 0.07112)
			(type default)
		)
		(layer "In15.Cu")
	)
	(gr_line
		(start 84.72424 -417.214812)
		(end 84.992718 -416.567112)
		(stroke
			(width 0.07112)
			(type default)
		)
		(layer "In15.Cu")
	)
	(gr_line
		(start 84.73186 -401.710652)
		(end 84.543138 -401.748244)
		(stroke
			(width 0.07112)
			(type default)
		)
		(layer "In15.Cu")
	)
	(gr_line
		(start 84.843874 -409.476702)
		(end 84.843874 -408.775662)
		(stroke
			(width 0.07112)
			(type default)
		)
		(layer "In15.Cu")
	)
	(gr_line
		(start 84.843874 -408.348942)
		(end 84.843874 -407.647902)
		(stroke
			(width 0.07112)
			(type default)
		)
		(layer "In15.Cu")
	)
	(gr_line
		(start 84.96808 -402.37283)
		(end 84.384896 -401.98294)
		(stroke
			(width 0.07112)
			(type default)
		)
		(layer "In15.Cu")
	)
	(gr_line
		(start 84.970112 -397.638524)
		(end 84.78139 -397.676116)
		(stroke
			(width 0.07112)
			(type default)
		)
		(layer "In15.Cu")
	)
	(gr_line
		(start 84.976462 -423.888662)
		(end 84.976716 -423.888916)
		(stroke
			(width 0.07112)
			(type default)
		)
		(layer "In15.Cu")
	)
	(gr_line
		(start 84.986368 -417.322)
		(end 85.164422 -417.248594)
		(stroke
			(width 0.07112)
			(type default)
		)
		(layer "In15.Cu")
	)
	(gr_line
		(start 85.055456 -416.415474)
		(end 85.15604 -416.172904)
		(stroke
			(width 0.07112)
			(type default)
		)
		(layer "In15.Cu")
	)
	(gr_line
		(start 85.086952 -401.948142)
		(end 84.73186 -401.710652)
		(stroke
			(width 0.07112)
			(type default)
		)
		(layer "In15.Cu")
	)
	(gr_line
		(start 85.124544 -402.13661)
		(end 85.086952 -401.948142)
		(stroke
			(width 0.07112)
			(type default)
		)
		(layer "In15.Cu")
	)
	(gr_line
		(start 85.127084 -409.475432)
		(end 85.262974 -409.339542)
		(stroke
			(width 0.07112)
			(type default)
		)
		(layer "In15.Cu")
	)
	(gr_line
		(start 85.127084 -408.347672)
		(end 85.262974 -408.211782)
		(stroke
			(width 0.07112)
			(type default)
		)
		(layer "In15.Cu")
	)
	(gr_line
		(start 85.15604 -416.172904)
		(end 85.424518 -415.524696)
		(stroke
			(width 0.07112)
			(type default)
		)
		(layer "In15.Cu")
	)
	(gr_line
		(start 85.164422 -417.248594)
		(end 85.32749 -416.854132)
		(stroke
			(width 0.07112)
			(type default)
		)
		(layer "In15.Cu")
	)
	(gr_line
		(start 85.206332 -398.300702)
		(end 84.623148 -397.911066)
		(stroke
			(width 0.07112)
			(type default)
		)
		(layer "In15.Cu")
	)
	(gr_line
		(start 85.262974 -409.339542)
		(end 85.262974 -408.912822)
		(stroke
			(width 0.07112)
			(type default)
		)
		(layer "In15.Cu")
	)
	(gr_line
		(start 85.262974 -408.912822)
		(end 85.127084 -408.776932)
		(stroke
			(width 0.07112)
			(type default)
		)
		(layer "In15.Cu")
	)
	(gr_line
		(start 85.262974 -408.211782)
		(end 85.262974 -407.785062)
		(stroke
			(width 0.07112)
			(type default)
		)
		(layer "In15.Cu")
	)
	(gr_line
		(start 85.262974 -407.785062)
		(end 85.127084 -407.649172)
		(stroke
			(width 0.07112)
			(type default)
		)
		(layer "In15.Cu")
	)
	(gr_line
		(start 85.325204 -397.87576)
		(end 84.970112 -397.638524)
		(stroke
			(width 0.07112)
			(type default)
		)
		(layer "In15.Cu")
	)
	(gr_line
		(start 85.32749 -416.854132)
		(end 85.254084 -416.676332)
		(stroke
			(width 0.07112)
			(type default)
		)
		(layer "In15.Cu")
	)
	(gr_line
		(start 85.362796 -398.064736)
		(end 85.325204 -397.87576)
		(stroke
			(width 0.07112)
			(type default)
		)
		(layer "In15.Cu")
	)
	(gr_line
		(start 85.405722 -421.260524)
		(end 85.405976 -421.26027)
		(stroke
			(width 0.07112)
			(type default)
		)
		(layer "In15.Cu")
	)
	(gr_line
		(start 85.418168 -416.279838)
		(end 85.595968 -416.206432)
		(stroke
			(width 0.07112)
			(type default)
		)
		(layer "In15.Cu")
	)
	(gr_line
		(start 85.503512 -438.623202)
		(end 85.499956 -438.623202)
		(stroke
			(width 0.07112)
			(type default)
		)
		(layer "In15.Cu")
	)
	(gr_line
		(start 85.56752 -415.179002)
		(end 85.587586 -415.130742)
		(stroke
			(width 0.07112)
			(type default)
		)
		(layer "In15.Cu")
	)
	(gr_line
		(start 85.587586 -415.130742)
		(end 85.856064 -414.482534)
		(stroke
			(width 0.07112)
			(type default)
		)
		(layer "In15.Cu")
	)
	(gr_line
		(start 85.595968 -416.206432)
		(end 85.75929 -415.81197)
		(stroke
			(width 0.07112)
			(type default)
		)
		(layer "In15.Cu")
	)
	(gr_line
		(start 85.65007 -439.0898)
		(end 85.65007 -438.76976)
		(stroke
			(width 0.07112)
			(type default)
		)
		(layer "In15.Cu")
	)
	(gr_line
		(start 85.65007 -438.76976)
		(end 85.503512 -438.623202)
		(stroke
			(width 0.07112)
			(type default)
		)
		(layer "In15.Cu")
	)
	(gr_line
		(start 85.65007 -438.191148)
		(end 85.501226 -438.339992)
		(stroke
			(width 0.07112)
			(type default)
		)
		(layer "In15.Cu")
	)
	(gr_line
		(start 85.65007 -437.889904)
		(end 85.65007 -438.191148)
		(stroke
			(width 0.07112)
			(type default)
		)
		(layer "In15.Cu")
	)
	(gr_line
		(start 85.75929 -415.81197)
		(end 85.68563 -415.63417)
		(stroke
			(width 0.07112)
			(type default)
		)
		(layer "In15.Cu")
	)
	(gr_line
		(start 85.849968 -415.237676)
		(end 86.027768 -415.16427)
		(stroke
			(width 0.07112)
			(type default)
		)
		(layer "In15.Cu")
	)
	(gr_line
		(start 85.925406 -312.388758)
		(end 85.925406 -312.389012)
		(stroke
			(width 0.07112)
			(type default)
		)
		(layer "In15.Cu")
	)
	(gr_line
		(start 86.027768 -415.16427)
		(end 86.19109 -414.769808)
		(stroke
			(width 0.07112)
			(type default)
		)
		(layer "In15.Cu")
	)
	(gr_line
		(start 86.121748 -312.783982)
		(end 85.967316 -312.66892)
		(stroke
			(width 0.07112)
			(type default)
		)
		(layer "In15.Cu")
	)
	(gr_line
		(start 86.19109 -414.769808)
		(end 86.11743 -414.592008)
		(stroke
			(width 0.07112)
			(type default)
		)
		(layer "In15.Cu")
	)
	(gr_line
		(start 86.54415 -312.722006)
		(end 86.121748 -312.783982)
		(stroke
			(width 0.07112)
			(type default)
		)
		(layer "In15.Cu")
	)
	(gr_line
		(start 86.61908 -312.286904)
		(end 85.925406 -312.388758)
		(stroke
			(width 0.07112)
			(type default)
		)
		(layer "In15.Cu")
	)
	(gr_line
		(start 86.658958 -312.56732)
		(end 86.54415 -312.722006)
		(stroke
			(width 0.07112)
			(type default)
		)
		(layer "In15.Cu")
	)
	(gr_line
		(start 87.002366 -314.741052)
		(end 87.002366 -314.741306)
		(stroke
			(width 0.07112)
			(type default)
		)
		(layer "In15.Cu")
	)
	(gr_line
		(start 87.159846 -315.153294)
		(end 87.017098 -315.024008)
		(stroke
			(width 0.07112)
			(type default)
		)
		(layer "In15.Cu")
	)
	(gr_line
		(start 87.23757 -312.620152)
		(end 87.083138 -312.50509)
		(stroke
			(width 0.07112)
			(type default)
		)
		(layer "In15.Cu")
	)
	(gr_line
		(start 87.503508 -437.623204)
		(end 87.499952 -437.623204)
		(stroke
			(width 0.07112)
			(type default)
		)
		(layer "In15.Cu")
	)
	(gr_line
		(start 87.586312 -315.132466)
		(end 87.159846 -315.153294)
		(stroke
			(width 0.07112)
			(type default)
		)
		(layer "In15.Cu")
	)
	(gr_line
		(start 87.650066 -438.089802)
		(end 87.650066 -437.769762)
		(stroke
			(width 0.07112)
			(type default)
		)
		(layer "In15.Cu")
	)
	(gr_line
		(start 87.650066 -437.769762)
		(end 87.503508 -437.623204)
		(stroke
			(width 0.07112)
			(type default)
		)
		(layer "In15.Cu")
	)
	(gr_line
		(start 87.650066 -437.19115)
		(end 87.501222 -437.339994)
		(stroke
			(width 0.07112)
			(type default)
		)
		(layer "In15.Cu")
	)
	(gr_line
		(start 87.650066 -436.889906)
		(end 87.650066 -437.19115)
		(stroke
			(width 0.07112)
			(type default)
		)
		(layer "In15.Cu")
	)
	(gr_line
		(start 87.657178 -416.593528)
		(end 87.987632 -415.975038)
		(stroke
			(width 0.07112)
			(type default)
		)
		(layer "In15.Cu")
	)
	(gr_line
		(start 87.659972 -312.558176)
		(end 87.23757 -312.620152)
		(stroke
			(width 0.07112)
			(type default)
		)
		(layer "In15.Cu")
	)
	(gr_line
		(start 87.702898 -314.706762)
		(end 87.002366 -314.741052)
		(stroke
			(width 0.07112)
			(type default)
		)
		(layer "In15.Cu")
	)
	(gr_line
		(start 87.715598 -314.989464)
		(end 87.586312 -315.132466)
		(stroke
			(width 0.07112)
			(type default)
		)
		(layer "In15.Cu")
	)
	(gr_line
		(start 87.734902 -312.123074)
		(end 87.041228 -312.224928)
		(stroke
			(width 0.07112)
			(type default)
		)
		(layer "In15.Cu")
	)
	(gr_line
		(start 87.77478 -312.40349)
		(end 87.659972 -312.558176)
		(stroke
			(width 0.07112)
			(type default)
		)
		(layer "In15.Cu")
	)
	(gr_line
		(start 87.907622 -416.725862)
		(end 88.091772 -416.670236)
		(stroke
			(width 0.07112)
			(type default)
		)
		(layer "In15.Cu")
	)
	(gr_line
		(start 88.091772 -416.670236)
		(end 88.29294 -416.293554)
		(stroke
			(width 0.07112)
			(type default)
		)
		(layer "In15.Cu")
	)
	(gr_line
		(start 88.168988 -415.636202)
		(end 88.1888 -415.598864)
		(stroke
			(width 0.07112)
			(type default)
		)
		(layer "In15.Cu")
	)
	(gr_line
		(start 88.1888 -415.598864)
		(end 88.519508 -414.98012)
		(stroke
			(width 0.07112)
			(type default)
		)
		(layer "In15.Cu")
	)
	(gr_line
		(start 88.286336 -315.097922)
		(end 88.143588 -314.968636)
		(stroke
			(width 0.07112)
			(type default)
		)
		(layer "In15.Cu")
	)
	(gr_line
		(start 88.29294 -416.293554)
		(end 88.23706 -416.109404)
		(stroke
			(width 0.07112)
			(type default)
		)
		(layer "In15.Cu")
	)
	(gr_arc
		(start 88.38946 -402.561044)
		(mid 88.390095 -402.561552)
		(end 88.39073 -402.56206)
		(stroke
			(width 0.07112)
			(type default)
		)
		(layer "In15.Cu")
	)
	(gr_line
		(start 88.417654 -415.769044)
		(end 88.437466 -415.731706)
		(stroke
			(width 0.07112)
			(type default)
		)
		(layer "In15.Cu")
	)
	(gr_line
		(start 88.439244 -415.731198)
		(end 88.623394 -415.675318)
		(stroke
			(width 0.07112)
			(type default)
		)
		(layer "In15.Cu")
	)
	(gr_line
		(start 88.562942 -402.33854)
		(end 88.563196 -402.338286)
		(stroke
			(width 0.07112)
			(type default)
		)
		(layer "In15.Cu")
	)
	(gr_line
		(start 88.570054 -312.424572)
		(end 88.415368 -312.30951)
		(stroke
			(width 0.07112)
			(type default)
		)
		(layer "In15.Cu")
	)
	(gr_line
		(start 88.623394 -415.675318)
		(end 88.824562 -415.29889)
		(stroke
			(width 0.07112)
			(type default)
		)
		(layer "In15.Cu")
	)
	(gr_line
		(start 88.68918 -402.453094)
		(end 88.688672 -402.452586)
		(stroke
			(width 0.07112)
			(type default)
		)
		(layer "In15.Cu")
	)
	(gr_line
		(start 88.712802 -315.077094)
		(end 88.286336 -315.097922)
		(stroke
			(width 0.07112)
			(type default)
		)
		(layer "In15.Cu")
	)
	(gr_line
		(start 88.75141 -414.546288)
		(end 89.082118 -413.927544)
		(stroke
			(width 0.07112)
			(type default)
		)
		(layer "In15.Cu")
	)
	(gr_line
		(start 88.824562 -415.29889)
		(end 88.768936 -415.114486)
		(stroke
			(width 0.07112)
			(type default)
		)
		(layer "In15.Cu")
	)
	(gr_line
		(start 88.829388 -314.65139)
		(end 88.128856 -314.68568)
		(stroke
			(width 0.07112)
			(type default)
		)
		(layer "In15.Cu")
	)
	(gr_line
		(start 88.842088 -314.934346)
		(end 88.712802 -315.077094)
		(stroke
			(width 0.07112)
			(type default)
		)
		(layer "In15.Cu")
	)
	(gr_line
		(start 88.976454 -424.569636)
		(end 88.976708 -424.56989)
		(stroke
			(width 0.07112)
			(type default)
		)
		(layer "In15.Cu")
	)
	(gr_line
		(start 88.992456 -312.362596)
		(end 88.570054 -312.424572)
		(stroke
			(width 0.07112)
			(type default)
		)
		(layer "In15.Cu")
	)
	(gr_line
		(start 89.001854 -414.678622)
		(end 89.186258 -414.622742)
		(stroke
			(width 0.07112)
			(type default)
		)
		(layer "In15.Cu")
	)
	(gr_line
		(start 89.011506 -403.210776)
		(end 88.990678 -403.188424)
		(stroke
			(width 0.07112)
			(type default)
		)
		(layer "In15.Cu")
	)
	(gr_line
		(start 89.028778 -403.236684)
		(end 89.011506 -403.210776)
		(stroke
			(width 0.07112)
			(type default)
		)
		(layer "In15.Cu")
	)
	(gr_line
		(start 89.067386 -311.927494)
		(end 88.373458 -312.029348)
		(stroke
			(width 0.07112)
			(type default)
		)
		(layer "In15.Cu")
	)
	(gr_line
		(start 89.107518 -312.20791)
		(end 88.992456 -312.362596)
		(stroke
			(width 0.07112)
			(type default)
		)
		(layer "In15.Cu")
	)
	(gr_line
		(start 89.186258 -414.622742)
		(end 89.387426 -414.246314)
		(stroke
			(width 0.07112)
			(type default)
		)
		(layer "In15.Cu")
	)
	(gr_arc
		(start 89.216738 -403.018752)
		(mid 89.20756 -403.008129)
		(end 89.198196 -402.99767)
		(stroke
			(width 0.07112)
			(type default)
		)
		(layer "In15.Cu")
	)
	(gr_arc
		(start 89.245186 -403.054566)
		(mid 89.231225 -403.03645)
		(end 89.216738 -403.018752)
		(stroke
			(width 0.07112)
			(type default)
		)
		(layer "In15.Cu")
	)
	(gr_arc
		(start 89.26195 -403.078188)
		(mid 89.253677 -403.0663)
		(end 89.245186 -403.054566)
		(stroke
			(width 0.07112)
			(type default)
		)
		(layer "In15.Cu")
	)
	(gr_line
		(start 89.387426 -414.246314)
		(end 89.331546 -414.06191)
		(stroke
			(width 0.07112)
			(type default)
		)
		(layer "In15.Cu")
	)
	(gr_line
		(start 89.412826 -315.04255)
		(end 89.270078 -314.913264)
		(stroke
			(width 0.07112)
			(type default)
		)
		(layer "In15.Cu")
	)
	(gr_line
		(start 89.503504 -438.623202)
		(end 89.499948 -438.623202)
		(stroke
			(width 0.07112)
			(type default)
		)
		(layer "In15.Cu")
	)
	(gr_line
		(start 89.650062 -439.0898)
		(end 89.650062 -438.76976)
		(stroke
			(width 0.07112)
			(type default)
		)
		(layer "In15.Cu")
	)
	(gr_line
		(start 89.650062 -438.76976)
		(end 89.503504 -438.623202)
		(stroke
			(width 0.07112)
			(type default)
		)
		(layer "In15.Cu")
	)
	(gr_line
		(start 89.650062 -438.191148)
		(end 89.501218 -438.339992)
		(stroke
			(width 0.07112)
			(type default)
		)
		(layer "In15.Cu")
	)
	(gr_line
		(start 89.650062 -437.889904)
		(end 89.650062 -438.191148)
		(stroke
			(width 0.07112)
			(type default)
		)
		(layer "In15.Cu")
	)
	(gr_line
		(start 89.750138 -312.251344)
		(end 89.595706 -312.136282)
		(stroke
			(width 0.07112)
			(type default)
		)
		(layer "In15.Cu")
	)
	(gr_line
		(start 89.839292 -315.021722)
		(end 89.412826 -315.04255)
		(stroke
			(width 0.07112)
			(type default)
		)
		(layer "In15.Cu")
	)
	(gr_line
		(start 89.905078 -311.804558)
		(end 89.553796 -311.85612)
		(stroke
			(width 0.07112)
			(type default)
		)
		(layer "In15.Cu")
	)
	(gr_line
		(start 89.955878 -314.596018)
		(end 89.255346 -314.630308)
		(stroke
			(width 0.07112)
			(type default)
		)
		(layer "In15.Cu")
	)
	(gr_line
		(start 89.968578 -314.878974)
		(end 89.839292 -315.021722)
		(stroke
			(width 0.07112)
			(type default)
		)
		(layer "In15.Cu")
	)
	(gr_line
		(start 90.172794 -312.189368)
		(end 89.750138 -312.251344)
		(stroke
			(width 0.07112)
			(type default)
		)
		(layer "In15.Cu")
	)
	(gr_line
		(start 90.24747 -311.754266)
		(end 89.905078 -311.804558)
		(stroke
			(width 0.07112)
			(type default)
		)
		(layer "In15.Cu")
	)
	(gr_line
		(start 90.247724 -311.754266)
		(end 90.24747 -311.754266)
		(stroke
			(width 0.07112)
			(type default)
		)
		(layer "In15.Cu")
	)
	(gr_line
		(start 90.287348 -312.034682)
		(end 90.172794 -312.189368)
		(stroke
			(width 0.07112)
			(type default)
		)
		(layer "In15.Cu")
	)
	(gr_line
		(start 90.539316 -314.987178)
		(end 90.396568 -314.857892)
		(stroke
			(width 0.07112)
			(type default)
		)
		(layer "In15.Cu")
	)
	(gr_line
		(start 90.69197 -416.61588)
		(end 91.037664 -416.005518)
		(stroke
			(width 0.07112)
			(type default)
		)
		(layer "In15.Cu")
	)
	(gr_line
		(start 90.938858 -416.75431)
		(end 91.124532 -416.703002)
		(stroke
			(width 0.07112)
			(type default)
		)
		(layer "In15.Cu")
	)
	(gr_line
		(start 90.965782 -314.96635)
		(end 90.539316 -314.987178)
		(stroke
			(width 0.07112)
			(type default)
		)
		(layer "In15.Cu")
	)
	(gr_line
		(start 90.970354 -409.382976)
		(end 90.970354 -408.681936)
		(stroke
			(width 0.07112)
			(type default)
		)
		(layer "In15.Cu")
	)
	(gr_line
		(start 90.970354 -408.255216)
		(end 90.970354 -407.554176)
		(stroke
			(width 0.07112)
			(type default)
		)
		(layer "In15.Cu")
	)
	(gr_line
		(start 91.082368 -314.540646)
		(end 90.381836 -314.57519)
		(stroke
			(width 0.07112)
			(type default)
		)
		(layer "In15.Cu")
	)
	(gr_line
		(start 91.094814 -314.823602)
		(end 90.965782 -314.96635)
		(stroke
			(width 0.07112)
			(type default)
		)
		(layer "In15.Cu")
	)
	(gr_line
		(start 91.124532 -416.703002)
		(end 91.334844 -416.3314)
		(stroke
			(width 0.07112)
			(type default)
		)
		(layer "In15.Cu")
	)
	(gr_line
		(start 91.253564 -409.381706)
		(end 91.389454 -409.245816)
		(stroke
			(width 0.07112)
			(type default)
		)
		(layer "In15.Cu")
	)
	(gr_line
		(start 91.253564 -408.253946)
		(end 91.389454 -408.118056)
		(stroke
			(width 0.07112)
			(type default)
		)
		(layer "In15.Cu")
	)
	(gr_line
		(start 91.334844 -416.3314)
		(end 91.283536 -416.146234)
		(stroke
			(width 0.07112)
			(type default)
		)
		(layer "In15.Cu")
	)
	(gr_line
		(start 91.389454 -409.245816)
		(end 91.389454 -408.819096)
		(stroke
			(width 0.07112)
			(type default)
		)
		(layer "In15.Cu")
	)
	(gr_line
		(start 91.389454 -408.819096)
		(end 91.253564 -408.683206)
		(stroke
			(width 0.07112)
			(type default)
		)
		(layer "In15.Cu")
	)
	(gr_line
		(start 91.389454 -408.118056)
		(end 91.389454 -407.691336)
		(stroke
			(width 0.07112)
			(type default)
		)
		(layer "In15.Cu")
	)
	(gr_line
		(start 91.389454 -407.691336)
		(end 91.253564 -407.555446)
		(stroke
			(width 0.07112)
			(type default)
		)
		(layer "In15.Cu")
	)
	(gr_line
		(start 91.79433 -414.669732)
		(end 92.140024 -414.059624)
		(stroke
			(width 0.07112)
			(type default)
		)
		(layer "In15.Cu")
	)
	(gr_line
		(start 92.041472 -414.808162)
		(end 92.226892 -414.757108)
		(stroke
			(width 0.07112)
			(type default)
		)
		(layer "In15.Cu")
	)
	(gr_line
		(start 92.18676 -403.101048)
		(end 92.186506 -403.100286)
		(stroke
			(width 0.07112)
			(type default)
		)
		(layer "In15.Cu")
	)
	(gr_line
		(start 92.226892 -414.757108)
		(end 92.437204 -414.385506)
		(stroke
			(width 0.07112)
			(type default)
		)
		(layer "In15.Cu")
	)
	(gr_line
		(start 92.437204 -414.385506)
		(end 92.385896 -414.200086)
		(stroke
			(width 0.07112)
			(type default)
		)
		(layer "In15.Cu")
	)
	(gr_line
		(start 92.501974 -403.869398)
		(end 92.501974 -403.861524)
		(stroke
			(width 0.07112)
			(type default)
		)
		(layer "In15.Cu")
	)
	(gr_line
		(start 92.501974 -403.861524)
		(end 92.49918 -403.854666)
		(stroke
			(width 0.07112)
			(type default)
		)
		(layer "In15.Cu")
	)
	(gr_arc
		(start 92.762324 -403.753574)
		(mid 92.761196 -403.750647)
		(end 92.760038 -403.747732)
		(stroke
			(width 0.07112)
			(type default)
		)
		(layer "In15.Cu")
	)
	(gr_arc
		(start 92.783914 -403.861524)
		(mid 92.777775 -403.806617)
		(end 92.762324 -403.753574)
		(stroke
			(width 0.07112)
			(type default)
		)
		(layer "In15.Cu")
	)
	(gr_line
		(start 92.783914 -403.861524)
		(end 92.783914 -403.869398)
		(stroke
			(width 0.07112)
			(type default)
		)
		(layer "In15.Cu")
	)
	(gr_line
		(start 93.656404 -308.47157)
		(end 93.947234 -308.7624)
		(stroke
			(width 0.07112)
			(type default)
		)
		(layer "In15.Cu")
	)
	(gr_line
		(start 94.033594 -408.739086)
		(end 94.033594 -408.038046)
		(stroke
			(width 0.07112)
			(type default)
		)
		(layer "In15.Cu")
	)
	(gr_line
		(start 94.316804 -408.737816)
		(end 94.452694 -408.601926)
		(stroke
			(width 0.07112)
			(type default)
		)
		(layer "In15.Cu")
	)
	(gr_line
		(start 94.452694 -408.601926)
		(end 94.452694 -408.175206)
		(stroke
			(width 0.07112)
			(type default)
		)
		(layer "In15.Cu")
	)
	(gr_line
		(start 94.452694 -408.175206)
		(end 94.316804 -408.039316)
		(stroke
			(width 0.07112)
			(type default)
		)
		(layer "In15.Cu")
	)
	(gr_line
		(start 94.520004 -308.47157)
		(end 94.229174 -308.7624)
		(stroke
			(width 0.07112)
			(type default)
		)
		(layer "In15.Cu")
	)
	(gr_line
		(start 98.71202 -314.997338)
		(end 98.42119 -314.706508)
		(stroke
			(width 0.07112)
			(type default)
		)
		(layer "In15.Cu")
	)
	(gr_line
		(start 98.71202 -314.133738)
		(end 98.42119 -314.424568)
		(stroke
			(width 0.07112)
			(type default)
		)
		(layer "In15.Cu")
	)
	(gr_line
		(start 99.307396 -310.603646)
		(end 99.016566 -310.312816)
		(stroke
			(width 0.07112)
			(type default)
		)
		(layer "In15.Cu")
	)
	(gr_line
		(start 99.307396 -309.740046)
		(end 99.016566 -310.030876)
		(stroke
			(width 0.07112)
			(type default)
		)
		(layer "In15.Cu")
	)
	(gr_line
		(start 103.513636 -41.898824)
		(end 103.51389 -41.89857)
		(stroke
			(width 0.07112)
			(type default)
		)
		(layer "In15.Cu")
	)
	(gr_line
		(start 103.513636 -41.898062)
		(end 103.514144 -41.897808)
		(stroke
			(width 0.07112)
			(type default)
		)
		(layer "In15.Cu")
	)
	(gr_line
		(start 103.51389 -41.89857)
		(end 103.513636 -41.898062)
		(stroke
			(width 0.07112)
			(type default)
		)
		(layer "In15.Cu")
	)
	(gr_line
		(start 103.91902 -270.03629)
		(end 103.621078 -270.03629)
		(stroke
			(width 0.05715)
			(type default)
		)
		(layer "In15.Cu")
	)
	(gr_line
		(start 104.001824 -270.119094)
		(end 103.91902 -270.03629)
		(stroke
			(width 0.05715)
			(type default)
		)
		(layer "In15.Cu")
	)
	(gr_arc
		(start 104.001824 -270.119094)
		(mid 104.003611 -270.130544)
		(end 104.005634 -270.141954)
		(stroke
			(width 0.05715)
			(type default)
		)
		(layer "In15.Cu")
	)
	(gr_line
		(start 104.026716 -296.37482)
		(end 104.026716 -296.346372)
		(stroke
			(width 0.05715)
			(type default)
		)
		(layer "In15.Cu")
	)
	(gr_line
		(start 104.026716 -296.346372)
		(end 104.072436 -296.300652)
		(stroke
			(width 0.05715)
			(type default)
		)
		(layer "In15.Cu")
	)
	(gr_line
		(start 104.193848 -270.105632)
		(end 104.26319 -270.03629)
		(stroke
			(width 0.05715)
			(type default)
		)
		(layer "In15.Cu")
	)
	(gr_line
		(start 104.26319 -270.03629)
		(end 104.561132 -270.03629)
		(stroke
			(width 0.05715)
			(type default)
		)
		(layer "In15.Cu")
	)
	(gr_line
		(start 104.308656 -296.37482)
		(end 104.308656 -296.346372)
		(stroke
			(width 0.05715)
			(type default)
		)
		(layer "In15.Cu")
	)
	(gr_line
		(start 104.308656 -296.346372)
		(end 104.262936 -296.300652)
		(stroke
			(width 0.05715)
			(type default)
		)
		(layer "In15.Cu")
	)
	(gr_line
		(start 104.683052 -272.912332)
		(end 104.681274 -272.911062)
		(stroke
			(width 0.05715)
			(type default)
		)
		(layer "In15.Cu")
	)
	(gr_line
		(start 104.698546 -272.923254)
		(end 104.69753 -272.922492)
		(stroke
			(width 0.05715)
			(type default)
		)
		(layer "In15.Cu")
	)
	(gr_line
		(start 104.720136 -272.937478)
		(end 104.713278 -272.933414)
		(stroke
			(width 0.05715)
			(type default)
		)
		(layer "In15.Cu")
	)
	(gr_line
		(start 104.735122 -288.186368)
		(end 104.737154 -288.185098)
		(stroke
			(width 0.05715)
			(type default)
		)
		(layer "In15.Cu")
	)
	(gr_line
		(start 104.73563 -289.146234)
		(end 104.735122 -289.14598)
		(stroke
			(width 0.05715)
			(type default)
		)
		(layer "In15.Cu")
	)
	(gr_arc
		(start 104.736646 -294.007032)
		(mid 104.739056 -294.008435)
		(end 104.741472 -294.009826)
		(stroke
			(width 0.05715)
			(type default)
		)
		(layer "In15.Cu")
	)
	(gr_arc
		(start 104.736646 -292.38702)
		(mid 104.739056 -292.388423)
		(end 104.741472 -292.389814)
		(stroke
			(width 0.05715)
			(type default)
		)
		(layer "In15.Cu")
	)
	(gr_arc
		(start 104.736646 -290.767008)
		(mid 104.738422 -290.768027)
		(end 104.740202 -290.76904)
		(stroke
			(width 0.05715)
			(type default)
		)
		(layer "In15.Cu")
	)
	(gr_line
		(start 104.739186 -287.528)
		(end 104.73182 -287.523174)
		(stroke
			(width 0.05715)
			(type default)
		)
		(layer "In15.Cu")
	)
	(gr_line
		(start 104.747822 -293.039038)
		(end 104.748076 -293.038784)
		(stroke
			(width 0.05715)
			(type default)
		)
		(layer "In15.Cu")
	)
	(gr_line
		(start 104.747822 -291.419026)
		(end 104.748076 -291.418772)
		(stroke
			(width 0.05715)
			(type default)
		)
		(layer "In15.Cu")
	)
	(gr_line
		(start 104.747822 -289.799014)
		(end 104.748076 -289.79876)
		(stroke
			(width 0.05715)
			(type default)
		)
		(layer "In15.Cu")
	)
	(gr_line
		(start 104.748076 -294.013636)
		(end 104.747822 -294.013636)
		(stroke
			(width 0.05715)
			(type default)
		)
		(layer "In15.Cu")
	)
	(gr_line
		(start 104.748076 -292.393624)
		(end 104.747822 -292.393624)
		(stroke
			(width 0.05715)
			(type default)
		)
		(layer "In15.Cu")
	)
	(gr_line
		(start 104.748076 -290.773612)
		(end 104.747822 -290.773612)
		(stroke
			(width 0.05715)
			(type default)
		)
		(layer "In15.Cu")
	)
	(gr_line
		(start 104.748076 -284.938978)
		(end 104.748584 -284.938724)
		(stroke
			(width 0.05715)
			(type default)
		)
		(layer "In15.Cu")
	)
	(gr_line
		(start 104.748076 -281.053794)
		(end 104.748076 -281.05354)
		(stroke
			(width 0.05715)
			(type default)
		)
		(layer "In15.Cu")
	)
	(gr_line
		(start 104.748076 -273.598894)
		(end 104.748584 -273.59864)
		(stroke
			(width 0.05715)
			(type default)
		)
		(layer "In15.Cu")
	)
	(gr_line
		(start 104.74833 -275.218906)
		(end 104.7496 -275.218144)
		(stroke
			(width 0.05715)
			(type default)
		)
		(layer "In15.Cu")
	)
	(gr_line
		(start 104.748584 -281.054048)
		(end 104.748076 -281.053794)
		(stroke
			(width 0.05715)
			(type default)
		)
		(layer "In15.Cu")
	)
	(gr_line
		(start 104.748838 -285.914338)
		(end 104.748076 -285.91383)
		(stroke
			(width 0.05715)
			(type default)
		)
		(layer "In15.Cu")
	)
	(gr_line
		(start 104.748838 -284.294326)
		(end 104.748076 -284.293818)
		(stroke
			(width 0.05715)
			(type default)
		)
		(layer "In15.Cu")
	)
	(gr_line
		(start 104.748838 -282.674314)
		(end 104.748076 -282.673806)
		(stroke
			(width 0.05715)
			(type default)
		)
		(layer "In15.Cu")
	)
	(gr_line
		(start 104.748838 -279.43429)
		(end 104.748076 -279.433782)
		(stroke
			(width 0.05715)
			(type default)
		)
		(layer "In15.Cu")
	)
	(gr_line
		(start 104.748838 -277.814278)
		(end 104.748076 -277.81377)
		(stroke
			(width 0.05715)
			(type default)
		)
		(layer "In15.Cu")
	)
	(gr_line
		(start 104.748838 -276.194266)
		(end 104.748076 -276.193758)
		(stroke
			(width 0.05715)
			(type default)
		)
		(layer "In15.Cu")
	)
	(gr_line
		(start 104.748838 -274.574254)
		(end 104.748076 -274.573746)
		(stroke
			(width 0.05715)
			(type default)
		)
		(layer "In15.Cu")
	)
	(gr_line
		(start 104.748838 -272.954242)
		(end 104.748076 -272.953734)
		(stroke
			(width 0.05715)
			(type default)
		)
		(layer "In15.Cu")
	)
	(gr_line
		(start 104.7496 -294.658034)
		(end 104.750362 -294.657526)
		(stroke
			(width 0.05715)
			(type default)
		)
		(layer "In15.Cu")
	)
	(gr_line
		(start 104.7496 -275.218144)
		(end 104.750362 -275.217636)
		(stroke
			(width 0.05715)
			(type default)
		)
		(layer "In15.Cu")
	)
	(gr_line
		(start 104.750362 -294.657526)
		(end 104.751378 -294.657018)
		(stroke
			(width 0.05715)
			(type default)
		)
		(layer "In15.Cu")
	)
	(gr_line
		(start 104.750362 -276.837648)
		(end 104.751378 -276.83714)
		(stroke
			(width 0.05715)
			(type default)
		)
		(layer "In15.Cu")
	)
	(gr_line
		(start 104.751378 -294.657018)
		(end 104.75214 -294.65651)
		(stroke
			(width 0.05715)
			(type default)
		)
		(layer "In15.Cu")
	)
	(gr_line
		(start 104.751378 -276.83714)
		(end 104.75214 -276.836632)
		(stroke
			(width 0.05715)
			(type default)
		)
		(layer "In15.Cu")
	)
	(gr_line
		(start 104.75214 -294.65651)
		(end 104.753664 -294.655748)
		(stroke
			(width 0.05715)
			(type default)
		)
		(layer "In15.Cu")
	)
	(gr_line
		(start 104.75214 -276.836632)
		(end 104.753156 -276.836124)
		(stroke
			(width 0.05715)
			(type default)
		)
		(layer "In15.Cu")
	)
	(gr_line
		(start 104.75214 -275.21662)
		(end 104.75468 -275.21535)
		(stroke
			(width 0.05715)
			(type default)
		)
		(layer "In15.Cu")
	)
	(gr_line
		(start 104.753156 -276.836124)
		(end 104.753918 -276.835616)
		(stroke
			(width 0.05715)
			(type default)
		)
		(layer "In15.Cu")
	)
	(gr_line
		(start 104.75468 -275.21535)
		(end 104.755442 -275.214842)
		(stroke
			(width 0.05715)
			(type default)
		)
		(layer "In15.Cu")
	)
	(gr_line
		(start 104.755442 -275.214842)
		(end 104.756458 -275.214334)
		(stroke
			(width 0.05715)
			(type default)
		)
		(layer "In15.Cu")
	)
	(gr_line
		(start 104.756966 -294.018716)
		(end 104.755696 -294.017954)
		(stroke
			(width 0.05715)
			(type default)
		)
		(layer "In15.Cu")
	)
	(gr_line
		(start 104.840024 -294.825928)
		(end 104.843326 -294.82415)
		(stroke
			(width 0.05715)
			(type default)
		)
		(layer "In15.Cu")
	)
	(gr_line
		(start 104.843326 -294.82415)
		(end 104.844088 -294.823642)
		(stroke
			(width 0.05715)
			(type default)
		)
		(layer "In15.Cu")
	)
	(gr_line
		(start 104.843326 -284.128464)
		(end 104.840532 -284.12694)
		(stroke
			(width 0.05715)
			(type default)
		)
		(layer "In15.Cu")
	)
	(gr_line
		(start 104.843326 -282.508452)
		(end 104.840532 -282.506928)
		(stroke
			(width 0.05715)
			(type default)
		)
		(layer "In15.Cu")
	)
	(gr_line
		(start 104.843326 -280.88844)
		(end 104.842564 -280.887932)
		(stroke
			(width 0.05715)
			(type default)
		)
		(layer "In15.Cu")
	)
	(gr_line
		(start 104.843326 -279.268428)
		(end 104.840532 -279.266904)
		(stroke
			(width 0.05715)
			(type default)
		)
		(layer "In15.Cu")
	)
	(gr_line
		(start 104.843326 -277.648416)
		(end 104.840532 -277.646892)
		(stroke
			(width 0.05715)
			(type default)
		)
		(layer "In15.Cu")
	)
	(gr_line
		(start 104.843326 -276.028404)
		(end 104.840532 -276.02688)
		(stroke
			(width 0.05715)
			(type default)
		)
		(layer "In15.Cu")
	)
	(gr_line
		(start 104.843326 -272.78838)
		(end 104.840532 -272.786856)
		(stroke
			(width 0.05715)
			(type default)
		)
		(layer "In15.Cu")
	)
	(gr_line
		(start 104.844088 -294.823642)
		(end 104.845104 -294.823134)
		(stroke
			(width 0.05715)
			(type default)
		)
		(layer "In15.Cu")
	)
	(gr_line
		(start 104.844088 -284.128972)
		(end 104.843326 -284.128464)
		(stroke
			(width 0.05715)
			(type default)
		)
		(layer "In15.Cu")
	)
	(gr_line
		(start 104.844088 -282.50896)
		(end 104.843326 -282.508452)
		(stroke
			(width 0.05715)
			(type default)
		)
		(layer "In15.Cu")
	)
	(gr_line
		(start 104.844088 -279.268936)
		(end 104.843326 -279.268428)
		(stroke
			(width 0.05715)
			(type default)
		)
		(layer "In15.Cu")
	)
	(gr_line
		(start 104.844088 -277.648924)
		(end 104.843326 -277.648416)
		(stroke
			(width 0.05715)
			(type default)
		)
		(layer "In15.Cu")
	)
	(gr_line
		(start 104.844088 -276.028912)
		(end 104.843326 -276.028404)
		(stroke
			(width 0.05715)
			(type default)
		)
		(layer "In15.Cu")
	)
	(gr_line
		(start 104.844088 -272.788888)
		(end 104.843326 -272.78838)
		(stroke
			(width 0.05715)
			(type default)
		)
		(layer "In15.Cu")
	)
	(gr_line
		(start 104.844088 -271.168876)
		(end 104.84358 -271.168622)
		(stroke
			(width 0.05715)
			(type default)
		)
		(layer "In15.Cu")
	)
	(gr_line
		(start 104.844596 -272.143474)
		(end 104.852724 -272.138902)
		(stroke
			(width 0.05715)
			(type default)
		)
		(layer "In15.Cu")
	)
	(gr_line
		(start 104.845104 -294.823134)
		(end 104.850692 -294.820086)
		(stroke
			(width 0.05715)
			(type default)
		)
		(layer "In15.Cu")
	)
	(gr_line
		(start 104.845104 -284.12948)
		(end 104.844088 -284.128972)
		(stroke
			(width 0.05715)
			(type default)
		)
		(layer "In15.Cu")
	)
	(gr_line
		(start 104.845104 -283.483304)
		(end 104.852724 -283.478986)
		(stroke
			(width 0.05715)
			(type default)
		)
		(layer "In15.Cu")
	)
	(gr_line
		(start 104.845104 -282.509468)
		(end 104.844088 -282.50896)
		(stroke
			(width 0.05715)
			(type default)
		)
		(layer "In15.Cu")
	)
	(gr_line
		(start 104.845104 -281.863292)
		(end 104.852724 -281.858974)
		(stroke
			(width 0.05715)
			(type default)
		)
		(layer "In15.Cu")
	)
	(gr_line
		(start 104.845104 -279.269444)
		(end 104.844088 -279.268936)
		(stroke
			(width 0.05715)
			(type default)
		)
		(layer "In15.Cu")
	)
	(gr_line
		(start 104.845104 -278.623268)
		(end 104.852724 -278.61895)
		(stroke
			(width 0.05715)
			(type default)
		)
		(layer "In15.Cu")
	)
	(gr_line
		(start 104.845104 -277.649432)
		(end 104.844088 -277.648924)
		(stroke
			(width 0.05715)
			(type default)
		)
		(layer "In15.Cu")
	)
	(gr_line
		(start 104.845104 -277.003256)
		(end 104.849676 -277.000462)
		(stroke
			(width 0.05715)
			(type default)
		)
		(layer "In15.Cu")
	)
	(gr_line
		(start 104.845104 -276.02942)
		(end 104.844088 -276.028912)
		(stroke
			(width 0.05715)
			(type default)
		)
		(layer "In15.Cu")
	)
	(gr_line
		(start 104.845104 -275.383244)
		(end 104.846882 -275.382228)
		(stroke
			(width 0.05715)
			(type default)
		)
		(layer "In15.Cu")
	)
	(gr_line
		(start 104.845104 -272.789396)
		(end 104.844088 -272.788888)
		(stroke
			(width 0.05715)
			(type default)
		)
		(layer "In15.Cu")
	)
	(gr_line
		(start 104.846882 -275.382228)
		(end 104.847898 -275.38172)
		(stroke
			(width 0.05715)
			(type default)
		)
		(layer "In15.Cu")
	)
	(gr_line
		(start 104.847136 -284.130496)
		(end 104.845104 -284.12948)
		(stroke
			(width 0.05715)
			(type default)
		)
		(layer "In15.Cu")
	)
	(gr_line
		(start 104.847136 -282.510484)
		(end 104.845104 -282.509468)
		(stroke
			(width 0.05715)
			(type default)
		)
		(layer "In15.Cu")
	)
	(gr_line
		(start 104.847136 -279.27046)
		(end 104.845104 -279.269444)
		(stroke
			(width 0.05715)
			(type default)
		)
		(layer "In15.Cu")
	)
	(gr_line
		(start 104.847136 -277.650448)
		(end 104.845104 -277.649432)
		(stroke
			(width 0.05715)
			(type default)
		)
		(layer "In15.Cu")
	)
	(gr_line
		(start 104.847136 -276.030436)
		(end 104.845104 -276.02942)
		(stroke
			(width 0.05715)
			(type default)
		)
		(layer "In15.Cu")
	)
	(gr_line
		(start 104.847136 -272.790412)
		(end 104.845104 -272.789396)
		(stroke
			(width 0.05715)
			(type default)
		)
		(layer "In15.Cu")
	)
	(gr_line
		(start 104.847898 -293.850822)
		(end 104.84358 -293.848536)
		(stroke
			(width 0.05715)
			(type default)
		)
		(layer "In15.Cu")
	)
	(gr_line
		(start 104.847898 -275.38172)
		(end 104.850692 -275.380196)
		(stroke
			(width 0.05715)
			(type default)
		)
		(layer "In15.Cu")
	)
	(gr_line
		(start 104.84866 -292.231318)
		(end 104.84358 -292.228524)
		(stroke
			(width 0.05715)
			(type default)
		)
		(layer "In15.Cu")
	)
	(gr_line
		(start 104.849168 -285.751778)
		(end 104.848406 -285.75127)
		(stroke
			(width 0.05715)
			(type default)
		)
		(layer "In15.Cu")
	)
	(gr_line
		(start 104.849168 -274.411694)
		(end 104.848406 -274.411186)
		(stroke
			(width 0.05715)
			(type default)
		)
		(layer "In15.Cu")
	)
	(gr_line
		(start 104.849422 -292.231826)
		(end 104.84866 -292.231318)
		(stroke
			(width 0.05715)
			(type default)
		)
		(layer "In15.Cu")
	)
	(gr_line
		(start 104.850438 -292.232334)
		(end 104.849422 -292.231826)
		(stroke
			(width 0.05715)
			(type default)
		)
		(layer "In15.Cu")
	)
	(gr_line
		(start 104.850692 -294.820086)
		(end 104.851708 -294.819578)
		(stroke
			(width 0.05715)
			(type default)
		)
		(layer "In15.Cu")
	)
	(gr_line
		(start 104.850692 -275.380196)
		(end 104.851708 -275.379688)
		(stroke
			(width 0.05715)
			(type default)
		)
		(layer "In15.Cu")
	)
	(gr_line
		(start 104.851454 -292.232842)
		(end 104.850438 -292.232334)
		(stroke
			(width 0.05715)
			(type default)
		)
		(layer "In15.Cu")
	)
	(gr_line
		(start 104.851962 -290.613338)
		(end 104.84358 -290.608512)
		(stroke
			(width 0.05715)
			(type default)
		)
		(layer "In15.Cu")
	)
	(gr_line
		(start 104.852724 -293.85387)
		(end 104.850438 -293.852346)
		(stroke
			(width 0.05715)
			(type default)
		)
		(layer "In15.Cu")
	)
	(gr_line
		(start 104.864916 -293.191438)
		(end 104.86517 -293.191438)
		(stroke
			(width 0.05715)
			(type default)
		)
		(layer "In15.Cu")
	)
	(gr_line
		(start 104.864916 -291.571426)
		(end 104.86517 -291.571426)
		(stroke
			(width 0.05715)
			(type default)
		)
		(layer "In15.Cu")
	)
	(gr_line
		(start 104.864916 -289.951414)
		(end 104.86517 -289.951414)
		(stroke
			(width 0.05715)
			(type default)
		)
		(layer "In15.Cu")
	)
	(gr_line
		(start 104.873552 -293.186612)
		(end 104.875076 -293.185596)
		(stroke
			(width 0.05715)
			(type default)
		)
		(layer "In15.Cu")
	)
	(gr_line
		(start 104.873552 -291.5666)
		(end 104.875076 -291.565584)
		(stroke
			(width 0.05715)
			(type default)
		)
		(layer "In15.Cu")
	)
	(gr_line
		(start 104.873552 -289.946588)
		(end 104.875076 -289.945572)
		(stroke
			(width 0.05715)
			(type default)
		)
		(layer "In15.Cu")
	)
	(gr_line
		(start 104.875584 -285.767272)
		(end 104.874822 -285.766764)
		(stroke
			(width 0.05715)
			(type default)
		)
		(layer "In15.Cu")
	)
	(gr_line
		(start 104.875584 -284.14726)
		(end 104.874822 -284.146752)
		(stroke
			(width 0.05715)
			(type default)
		)
		(layer "In15.Cu")
	)
	(gr_line
		(start 104.875584 -282.527248)
		(end 104.874822 -282.52674)
		(stroke
			(width 0.05715)
			(type default)
		)
		(layer "In15.Cu")
	)
	(gr_line
		(start 104.875584 -279.287224)
		(end 104.874822 -279.286716)
		(stroke
			(width 0.05715)
			(type default)
		)
		(layer "In15.Cu")
	)
	(gr_line
		(start 104.875584 -277.667212)
		(end 104.874822 -277.666704)
		(stroke
			(width 0.05715)
			(type default)
		)
		(layer "In15.Cu")
	)
	(gr_line
		(start 104.875584 -276.0472)
		(end 104.874822 -276.046692)
		(stroke
			(width 0.05715)
			(type default)
		)
		(layer "In15.Cu")
	)
	(gr_line
		(start 104.875584 -274.427188)
		(end 104.874822 -274.42668)
		(stroke
			(width 0.05715)
			(type default)
		)
		(layer "In15.Cu")
	)
	(gr_line
		(start 104.875584 -272.807176)
		(end 104.874822 -272.806668)
		(stroke
			(width 0.05715)
			(type default)
		)
		(layer "In15.Cu")
	)
	(gr_line
		(start 104.876346 -285.76778)
		(end 104.875584 -285.767272)
		(stroke
			(width 0.05715)
			(type default)
		)
		(layer "In15.Cu")
	)
	(gr_line
		(start 104.876346 -284.147768)
		(end 104.875584 -284.14726)
		(stroke
			(width 0.05715)
			(type default)
		)
		(layer "In15.Cu")
	)
	(gr_line
		(start 104.876346 -282.527756)
		(end 104.875584 -282.527248)
		(stroke
			(width 0.05715)
			(type default)
		)
		(layer "In15.Cu")
	)
	(gr_line
		(start 104.876346 -279.287732)
		(end 104.875584 -279.287224)
		(stroke
			(width 0.05715)
			(type default)
		)
		(layer "In15.Cu")
	)
	(gr_line
		(start 104.876346 -277.66772)
		(end 104.875584 -277.667212)
		(stroke
			(width 0.05715)
			(type default)
		)
		(layer "In15.Cu")
	)
	(gr_line
		(start 104.876346 -276.047708)
		(end 104.875584 -276.0472)
		(stroke
			(width 0.05715)
			(type default)
		)
		(layer "In15.Cu")
	)
	(gr_line
		(start 104.876346 -274.427696)
		(end 104.875584 -274.427188)
		(stroke
			(width 0.05715)
			(type default)
		)
		(layer "In15.Cu")
	)
	(gr_line
		(start 104.876346 -272.807684)
		(end 104.875584 -272.807176)
		(stroke
			(width 0.05715)
			(type default)
		)
		(layer "In15.Cu")
	)
	(gr_line
		(start 104.878886 -287.389316)
		(end 104.875076 -287.38703)
		(stroke
			(width 0.05715)
			(type default)
		)
		(layer "In15.Cu")
	)
	(gr_line
		(start 104.882442 -293.871142)
		(end 104.87533 -293.867078)
		(stroke
			(width 0.05715)
			(type default)
		)
		(layer "In15.Cu")
	)
	(gr_arc
		(start 104.882442 -293.871142)
		(mid 104.882823 -293.871396)
		(end 104.883204 -293.87165)
		(stroke
			(width 0.05715)
			(type default)
		)
		(layer "In15.Cu")
	)
	(gr_line
		(start 104.882442 -292.25113)
		(end 104.874314 -292.246304)
		(stroke
			(width 0.05715)
			(type default)
		)
		(layer "In15.Cu")
	)
	(gr_arc
		(start 104.882442 -292.25113)
		(mid 104.882823 -292.251384)
		(end 104.883204 -292.251638)
		(stroke
			(width 0.05715)
			(type default)
		)
		(layer "In15.Cu")
	)
	(gr_line
		(start 104.882442 -290.631118)
		(end 104.875584 -290.627054)
		(stroke
			(width 0.05715)
			(type default)
		)
		(layer "In15.Cu")
	)
	(gr_arc
		(start 104.882442 -290.631118)
		(mid 104.882823 -290.631372)
		(end 104.883204 -290.631626)
		(stroke
			(width 0.05715)
			(type default)
		)
		(layer "In15.Cu")
	)
	(gr_line
		(start 104.882442 -289.011106)
		(end 104.87533 -289.007042)
		(stroke
			(width 0.05715)
			(type default)
		)
		(layer "In15.Cu")
	)
	(gr_arc
		(start 104.882442 -289.011106)
		(mid 104.882823 -289.01136)
		(end 104.883204 -289.011614)
		(stroke
			(width 0.05715)
			(type default)
		)
		(layer "In15.Cu")
	)
	(gr_line
		(start 104.882442 -287.391348)
		(end 104.878886 -287.389316)
		(stroke
			(width 0.05715)
			(type default)
		)
		(layer "In15.Cu")
	)
	(gr_line
		(start 104.882442 -287.391094)
		(end 104.882442 -287.391348)
		(stroke
			(width 0.05715)
			(type default)
		)
		(layer "In15.Cu")
	)
	(gr_line
		(start 104.883204 -285.771844)
		(end 104.876346 -285.76778)
		(stroke
			(width 0.05715)
			(type default)
		)
		(layer "In15.Cu")
	)
	(gr_line
		(start 104.883204 -284.151832)
		(end 104.876346 -284.147768)
		(stroke
			(width 0.05715)
			(type default)
		)
		(layer "In15.Cu")
	)
	(gr_line
		(start 104.883204 -282.53182)
		(end 104.876346 -282.527756)
		(stroke
			(width 0.05715)
			(type default)
		)
		(layer "In15.Cu")
	)
	(gr_line
		(start 104.883204 -279.291796)
		(end 104.876346 -279.287732)
		(stroke
			(width 0.05715)
			(type default)
		)
		(layer "In15.Cu")
	)
	(gr_line
		(start 104.883204 -277.671784)
		(end 104.876346 -277.66772)
		(stroke
			(width 0.05715)
			(type default)
		)
		(layer "In15.Cu")
	)
	(gr_line
		(start 104.883204 -276.051772)
		(end 104.876346 -276.047708)
		(stroke
			(width 0.05715)
			(type default)
		)
		(layer "In15.Cu")
	)
	(gr_line
		(start 104.883204 -274.43176)
		(end 104.876346 -274.427696)
		(stroke
			(width 0.05715)
			(type default)
		)
		(layer "In15.Cu")
	)
	(gr_line
		(start 104.883204 -272.811748)
		(end 104.876346 -272.807684)
		(stroke
			(width 0.05715)
			(type default)
		)
		(layer "In15.Cu")
	)
	(gr_arc
		(start 104.891078 -293.877238)
		(mid 104.887153 -293.874427)
		(end 104.883204 -293.87165)
		(stroke
			(width 0.05715)
			(type default)
		)
		(layer "In15.Cu")
	)
	(gr_arc
		(start 104.891078 -292.257226)
		(mid 104.887153 -292.254415)
		(end 104.883204 -292.251638)
		(stroke
			(width 0.05715)
			(type default)
		)
		(layer "In15.Cu")
	)
	(gr_arc
		(start 104.891078 -290.637214)
		(mid 104.887153 -290.634403)
		(end 104.883204 -290.631626)
		(stroke
			(width 0.05715)
			(type default)
		)
		(layer "In15.Cu")
	)
	(gr_arc
		(start 104.891078 -289.017202)
		(mid 104.887153 -289.014391)
		(end 104.883204 -289.011614)
		(stroke
			(width 0.05715)
			(type default)
		)
		(layer "In15.Cu")
	)
	(gr_arc
		(start 104.891078 -285.777432)
		(mid 104.887153 -285.774621)
		(end 104.883204 -285.771844)
		(stroke
			(width 0.05715)
			(type default)
		)
		(layer "In15.Cu")
	)
	(gr_arc
		(start 104.891078 -284.15742)
		(mid 104.887153 -284.154609)
		(end 104.883204 -284.151832)
		(stroke
			(width 0.05715)
			(type default)
		)
		(layer "In15.Cu")
	)
	(gr_arc
		(start 104.891078 -282.537408)
		(mid 104.887153 -282.534597)
		(end 104.883204 -282.53182)
		(stroke
			(width 0.05715)
			(type default)
		)
		(layer "In15.Cu")
	)
	(gr_arc
		(start 104.891078 -279.297384)
		(mid 104.887153 -279.294573)
		(end 104.883204 -279.291796)
		(stroke
			(width 0.05715)
			(type default)
		)
		(layer "In15.Cu")
	)
	(gr_arc
		(start 104.891078 -277.677372)
		(mid 104.887153 -277.674561)
		(end 104.883204 -277.671784)
		(stroke
			(width 0.05715)
			(type default)
		)
		(layer "In15.Cu")
	)
	(gr_arc
		(start 104.891078 -276.05736)
		(mid 104.887153 -276.054549)
		(end 104.883204 -276.051772)
		(stroke
			(width 0.05715)
			(type default)
		)
		(layer "In15.Cu")
	)
	(gr_arc
		(start 104.891078 -274.437348)
		(mid 104.887153 -274.434537)
		(end 104.883204 -274.43176)
		(stroke
			(width 0.05715)
			(type default)
		)
		(layer "In15.Cu")
	)
	(gr_arc
		(start 104.891078 -272.817336)
		(mid 104.887153 -272.814525)
		(end 104.883204 -272.811748)
		(stroke
			(width 0.05715)
			(type default)
		)
		(layer "In15.Cu")
	)
	(gr_arc
		(start 104.891332 -287.39719)
		(mid 104.886902 -287.39412)
		(end 104.882442 -287.391094)
		(stroke
			(width 0.05715)
			(type default)
		)
		(layer "In15.Cu")
	)
	(gr_line
		(start 104.97185 -296.37482)
		(end 104.97185 -296.346372)
		(stroke
			(width 0.05715)
			(type default)
		)
		(layer "In15.Cu")
	)
	(gr_line
		(start 104.97185 -296.346372)
		(end 105.01757 -296.300652)
		(stroke
			(width 0.05715)
			(type default)
		)
		(layer "In15.Cu")
	)
	(gr_line
		(start 105.25379 -296.37482)
		(end 105.25379 -296.346372)
		(stroke
			(width 0.05715)
			(type default)
		)
		(layer "In15.Cu")
	)
	(gr_line
		(start 105.25379 -296.346372)
		(end 105.20807 -296.300652)
		(stroke
			(width 0.05715)
			(type default)
		)
		(layer "In15.Cu")
	)
	(gr_line
		(start 105.596182 -295.239948)
		(end 105.596436 -295.239694)
		(stroke
			(width 0.05715)
			(type default)
		)
		(layer "In15.Cu")
	)
	(gr_arc
		(start 105.649014 -286.581596)
		(mid 105.644298 -286.584873)
		(end 105.639616 -286.5882)
		(stroke
			(width 0.05715)
			(type default)
		)
		(layer "In15.Cu")
	)
	(gr_line
		(start 105.649014 -286.581596)
		(end 105.651046 -286.580072)
		(stroke
			(width 0.05715)
			(type default)
		)
		(layer "In15.Cu")
	)
	(gr_line
		(start 105.651046 -286.580072)
		(end 105.655872 -286.577278)
		(stroke
			(width 0.05715)
			(type default)
		)
		(layer "In15.Cu")
	)
	(gr_line
		(start 105.78338 -286.72409)
		(end 105.783888 -286.723836)
		(stroke
			(width 0.05715)
			(type default)
		)
		(layer "In15.Cu")
	)
	(gr_line
		(start 105.916984 -296.37482)
		(end 105.916984 -296.346372)
		(stroke
			(width 0.05715)
			(type default)
		)
		(layer "In15.Cu")
	)
	(gr_line
		(start 105.916984 -296.346372)
		(end 105.962704 -296.300652)
		(stroke
			(width 0.05715)
			(type default)
		)
		(layer "In15.Cu")
	)
	(gr_line
		(start 106.198924 -296.37482)
		(end 106.198924 -296.346372)
		(stroke
			(width 0.05715)
			(type default)
		)
		(layer "In15.Cu")
	)
	(gr_line
		(start 106.198924 -296.346372)
		(end 106.153204 -296.300652)
		(stroke
			(width 0.05715)
			(type default)
		)
		(layer "In15.Cu")
	)
	(gr_line
		(start 106.222292 -272.972022)
		(end 106.222546 -272.972276)
		(stroke
			(width 0.05715)
			(type default)
		)
		(layer "In15.Cu")
	)
	(gr_line
		(start 106.345736 -295.193212)
		(end 106.345736 -295.192196)
		(stroke
			(width 0.05715)
			(type default)
		)
		(layer "In15.Cu")
	)
	(gr_line
		(start 106.512106 -374.859804)
		(end 106.512106 -374.860058)
		(stroke
			(width 0.07112)
			(type default)
		)
		(layer "In15.Cu")
	)
	(gr_arc
		(start 106.589068 -286.581596)
		(mid 106.584351 -286.584873)
		(end 106.57967 -286.5882)
		(stroke
			(width 0.05715)
			(type default)
		)
		(layer "In15.Cu")
	)
	(gr_line
		(start 106.589068 -286.581596)
		(end 106.5911 -286.580072)
		(stroke
			(width 0.05715)
			(type default)
		)
		(layer "In15.Cu")
	)
	(gr_line
		(start 106.5911 -286.580072)
		(end 106.595926 -286.577278)
		(stroke
			(width 0.05715)
			(type default)
		)
		(layer "In15.Cu")
	)
	(gr_line
		(start 106.723434 -286.72409)
		(end 106.723942 -286.723836)
		(stroke
			(width 0.05715)
			(type default)
		)
		(layer "In15.Cu")
	)
	(gr_line
		(start 106.738928 -273.276314)
		(end 106.440986 -273.276314)
		(stroke
			(width 0.05715)
			(type default)
		)
		(layer "In15.Cu")
	)
	(gr_line
		(start 106.738928 -271.656302)
		(end 106.440986 -271.656302)
		(stroke
			(width 0.05715)
			(type default)
		)
		(layer "In15.Cu")
	)
	(gr_line
		(start 106.738928 -270.03629)
		(end 106.440986 -270.03629)
		(stroke
			(width 0.05715)
			(type default)
		)
		(layer "In15.Cu")
	)
	(gr_line
		(start 106.80827 -273.345656)
		(end 106.738928 -273.276314)
		(stroke
			(width 0.05715)
			(type default)
		)
		(layer "In15.Cu")
	)
	(gr_line
		(start 106.80827 -271.725644)
		(end 106.738928 -271.656302)
		(stroke
			(width 0.05715)
			(type default)
		)
		(layer "In15.Cu")
	)
	(gr_line
		(start 106.821732 -270.119094)
		(end 106.738928 -270.03629)
		(stroke
			(width 0.05715)
			(type default)
		)
		(layer "In15.Cu")
	)
	(gr_arc
		(start 106.821732 -270.119094)
		(mid 106.823525 -270.130416)
		(end 106.825542 -270.1417)
		(stroke
			(width 0.05715)
			(type default)
		)
		(layer "In15.Cu")
	)
	(gr_arc
		(start 106.996484 -273.381978)
		(mid 106.998507 -273.370568)
		(end 107.000294 -273.359118)
		(stroke
			(width 0.05715)
			(type default)
		)
		(layer "In15.Cu")
	)
	(gr_arc
		(start 106.996484 -271.761966)
		(mid 106.998506 -271.750556)
		(end 107.000294 -271.739106)
		(stroke
			(width 0.05715)
			(type default)
		)
		(layer "In15.Cu")
	)
	(gr_line
		(start 107.000294 -273.359118)
		(end 107.083098 -273.276314)
		(stroke
			(width 0.05715)
			(type default)
		)
		(layer "In15.Cu")
	)
	(gr_line
		(start 107.000294 -271.739106)
		(end 107.083098 -271.656302)
		(stroke
			(width 0.05715)
			(type default)
		)
		(layer "In15.Cu")
	)
	(gr_line
		(start 107.013756 -270.105632)
		(end 107.083098 -270.03629)
		(stroke
			(width 0.05715)
			(type default)
		)
		(layer "In15.Cu")
	)
	(gr_line
		(start 107.014264 -296.612564)
		(end 107.014264 -296.584116)
		(stroke
			(width 0.05715)
			(type default)
		)
		(layer "In15.Cu")
	)
	(gr_line
		(start 107.014264 -296.584116)
		(end 107.059984 -296.538396)
		(stroke
			(width 0.05715)
			(type default)
		)
		(layer "In15.Cu")
	)
	(gr_line
		(start 107.035854 -374.48236)
		(end 107.036616 -374.48236)
		(stroke
			(width 0.07112)
			(type default)
		)
		(layer "In15.Cu")
	)
	(gr_arc
		(start 107.05084 -270.495268)
		(mid 107.054892 -270.49808)
		(end 107.058968 -270.500856)
		(stroke
			(width 0.05715)
			(type default)
		)
		(layer "In15.Cu")
	)
	(gr_line
		(start 107.061762 -270.502888)
		(end 107.058968 -270.500856)
		(stroke
			(width 0.05715)
			(type default)
		)
		(layer "In15.Cu")
	)
	(gr_line
		(start 107.067096 -270.505936)
		(end 107.061762 -270.502888)
		(stroke
			(width 0.05715)
			(type default)
		)
		(layer "In15.Cu")
	)
	(gr_line
		(start 107.083098 -273.276314)
		(end 107.38104 -273.276314)
		(stroke
			(width 0.05715)
			(type default)
		)
		(layer "In15.Cu")
	)
	(gr_line
		(start 107.083098 -271.656302)
		(end 107.38104 -271.656302)
		(stroke
			(width 0.05715)
			(type default)
		)
		(layer "In15.Cu")
	)
	(gr_line
		(start 107.083098 -270.03629)
		(end 107.38104 -270.03629)
		(stroke
			(width 0.05715)
			(type default)
		)
		(layer "In15.Cu")
	)
	(gr_line
		(start 107.099354 -270.524478)
		(end 107.098846 -270.524224)
		(stroke
			(width 0.05715)
			(type default)
		)
		(layer "In15.Cu")
	)
	(gr_line
		(start 107.216194 -270.37157)
		(end 107.215432 -270.371062)
		(stroke
			(width 0.05715)
			(type default)
		)
		(layer "In15.Cu")
	)
	(gr_line
		(start 107.285536 -270.867886)
		(end 107.285536 -270.864584)
		(stroke
			(width 0.05715)
			(type default)
		)
		(layer "In15.Cu")
	)
	(gr_line
		(start 107.296204 -296.612564)
		(end 107.296204 -296.584116)
		(stroke
			(width 0.05715)
			(type default)
		)
		(layer "In15.Cu")
	)
	(gr_line
		(start 107.296204 -296.584116)
		(end 107.250484 -296.538396)
		(stroke
			(width 0.05715)
			(type default)
		)
		(layer "In15.Cu")
	)
	(gr_arc
		(start 107.516422 -293.981886)
		(mid 107.523998 -293.987283)
		(end 107.531662 -293.992554)
		(stroke
			(width 0.05715)
			(type default)
		)
		(layer "In15.Cu")
	)
	(gr_arc
		(start 107.520994 -271.305274)
		(mid 107.526306 -271.308989)
		(end 107.531662 -271.31264)
		(stroke
			(width 0.05715)
			(type default)
		)
		(layer "In15.Cu")
	)
	(gr_arc
		(start 107.531662 -273.619976)
		(mid 107.523998 -273.625248)
		(end 107.516422 -273.630644)
		(stroke
			(width 0.05715)
			(type default)
		)
		(layer "In15.Cu")
	)
	(gr_line
		(start 107.531662 -273.619976)
		(end 107.533186 -273.61896)
		(stroke
			(width 0.05715)
			(type default)
		)
		(layer "In15.Cu")
	)
	(gr_line
		(start 107.533186 -293.99357)
		(end 107.531662 -293.992554)
		(stroke
			(width 0.05715)
			(type default)
		)
		(layer "In15.Cu")
	)
	(gr_line
		(start 107.533186 -273.61896)
		(end 107.53725 -273.616674)
		(stroke
			(width 0.05715)
			(type default)
		)
		(layer "In15.Cu")
	)
	(gr_line
		(start 107.53725 -293.995856)
		(end 107.533186 -293.99357)
		(stroke
			(width 0.05715)
			(type default)
		)
		(layer "In15.Cu")
	)
	(gr_line
		(start 107.53725 -271.315942)
		(end 107.531662 -271.31264)
		(stroke
			(width 0.05715)
			(type default)
		)
		(layer "In15.Cu")
	)
	(gr_line
		(start 107.552998 -294.667432)
		(end 107.556554 -294.6654)
		(stroke
			(width 0.05715)
			(type default)
		)
		(layer "In15.Cu")
	)
	(gr_line
		(start 107.55503 -288.186368)
		(end 107.557062 -288.185098)
		(stroke
			(width 0.05715)
			(type default)
		)
		(layer "In15.Cu")
	)
	(gr_line
		(start 107.555538 -289.146234)
		(end 107.55503 -289.14598)
		(stroke
			(width 0.05715)
			(type default)
		)
		(layer "In15.Cu")
	)
	(gr_arc
		(start 107.556554 -292.38702)
		(mid 107.558964 -292.388423)
		(end 107.56138 -292.389814)
		(stroke
			(width 0.05715)
			(type default)
		)
		(layer "In15.Cu")
	)
	(gr_arc
		(start 107.556554 -290.767008)
		(mid 107.558964 -290.768411)
		(end 107.56138 -290.769802)
		(stroke
			(width 0.05715)
			(type default)
		)
		(layer "In15.Cu")
	)
	(gr_line
		(start 107.559094 -287.528)
		(end 107.551728 -287.523174)
		(stroke
			(width 0.05715)
			(type default)
		)
		(layer "In15.Cu")
	)
	(gr_line
		(start 107.56773 -291.419026)
		(end 107.567984 -291.418772)
		(stroke
			(width 0.05715)
			(type default)
		)
		(layer "In15.Cu")
	)
	(gr_line
		(start 107.56773 -289.799014)
		(end 107.567984 -289.79876)
		(stroke
			(width 0.05715)
			(type default)
		)
		(layer "In15.Cu")
	)
	(gr_line
		(start 107.567984 -292.393624)
		(end 107.56773 -292.393624)
		(stroke
			(width 0.05715)
			(type default)
		)
		(layer "In15.Cu")
	)
	(gr_line
		(start 107.567984 -290.773612)
		(end 107.56773 -290.773612)
		(stroke
			(width 0.05715)
			(type default)
		)
		(layer "In15.Cu")
	)
	(gr_line
		(start 107.567984 -284.938978)
		(end 107.568492 -284.938724)
		(stroke
			(width 0.05715)
			(type default)
		)
		(layer "In15.Cu")
	)
	(gr_line
		(start 107.567984 -281.053794)
		(end 107.567984 -281.05354)
		(stroke
			(width 0.05715)
			(type default)
		)
		(layer "In15.Cu")
	)
	(gr_line
		(start 107.568238 -275.218906)
		(end 107.569508 -275.218144)
		(stroke
			(width 0.05715)
			(type default)
		)
		(layer "In15.Cu")
	)
	(gr_line
		(start 107.568238 -273.59864)
		(end 107.568746 -273.598386)
		(stroke
			(width 0.05715)
			(type default)
		)
		(layer "In15.Cu")
	)
	(gr_line
		(start 107.568238 -271.978628)
		(end 107.568746 -271.978374)
		(stroke
			(width 0.05715)
			(type default)
		)
		(layer "In15.Cu")
	)
	(gr_line
		(start 107.568492 -281.054048)
		(end 107.567984 -281.053794)
		(stroke
			(width 0.05715)
			(type default)
		)
		(layer "In15.Cu")
	)
	(gr_line
		(start 107.568746 -294.014144)
		(end 107.567984 -294.013636)
		(stroke
			(width 0.05715)
			(type default)
		)
		(layer "In15.Cu")
	)
	(gr_line
		(start 107.568746 -285.914338)
		(end 107.567984 -285.91383)
		(stroke
			(width 0.05715)
			(type default)
		)
		(layer "In15.Cu")
	)
	(gr_line
		(start 107.568746 -284.294326)
		(end 107.567984 -284.293818)
		(stroke
			(width 0.05715)
			(type default)
		)
		(layer "In15.Cu")
	)
	(gr_line
		(start 107.568746 -282.674314)
		(end 107.567984 -282.673806)
		(stroke
			(width 0.05715)
			(type default)
		)
		(layer "In15.Cu")
	)
	(gr_line
		(start 107.568746 -279.43429)
		(end 107.567984 -279.433782)
		(stroke
			(width 0.05715)
			(type default)
		)
		(layer "In15.Cu")
	)
	(gr_line
		(start 107.568746 -277.814278)
		(end 107.567984 -277.81377)
		(stroke
			(width 0.05715)
			(type default)
		)
		(layer "In15.Cu")
	)
	(gr_line
		(start 107.568746 -276.194266)
		(end 107.567984 -276.193758)
		(stroke
			(width 0.05715)
			(type default)
		)
		(layer "In15.Cu")
	)
	(gr_line
		(start 107.568746 -274.574254)
		(end 107.567984 -274.573746)
		(stroke
			(width 0.05715)
			(type default)
		)
		(layer "In15.Cu")
	)
	(gr_line
		(start 107.568746 -273.598386)
		(end 107.570016 -273.597624)
		(stroke
			(width 0.05715)
			(type default)
		)
		(layer "In15.Cu")
	)
	(gr_line
		(start 107.568746 -271.978374)
		(end 107.570016 -271.977612)
		(stroke
			(width 0.05715)
			(type default)
		)
		(layer "In15.Cu")
	)
	(gr_line
		(start 107.569508 -275.218144)
		(end 107.57027 -275.217636)
		(stroke
			(width 0.05715)
			(type default)
		)
		(layer "In15.Cu")
	)
	(gr_line
		(start 107.570016 -285.9151)
		(end 107.568746 -285.914338)
		(stroke
			(width 0.05715)
			(type default)
		)
		(layer "In15.Cu")
	)
	(gr_line
		(start 107.570016 -284.295088)
		(end 107.568746 -284.294326)
		(stroke
			(width 0.05715)
			(type default)
		)
		(layer "In15.Cu")
	)
	(gr_line
		(start 107.570016 -282.675076)
		(end 107.568746 -282.674314)
		(stroke
			(width 0.05715)
			(type default)
		)
		(layer "In15.Cu")
	)
	(gr_line
		(start 107.570016 -279.435052)
		(end 107.568746 -279.43429)
		(stroke
			(width 0.05715)
			(type default)
		)
		(layer "In15.Cu")
	)
	(gr_line
		(start 107.570016 -277.81504)
		(end 107.568746 -277.814278)
		(stroke
			(width 0.05715)
			(type default)
		)
		(layer "In15.Cu")
	)
	(gr_line
		(start 107.570016 -276.195028)
		(end 107.568746 -276.194266)
		(stroke
			(width 0.05715)
			(type default)
		)
		(layer "In15.Cu")
	)
	(gr_line
		(start 107.570016 -274.575016)
		(end 107.568746 -274.574254)
		(stroke
			(width 0.05715)
			(type default)
		)
		(layer "In15.Cu")
	)
	(gr_line
		(start 107.57027 -276.837648)
		(end 107.571286 -276.83714)
		(stroke
			(width 0.05715)
			(type default)
		)
		(layer "In15.Cu")
	)
	(gr_line
		(start 107.571286 -276.83714)
		(end 107.572048 -276.836632)
		(stroke
			(width 0.05715)
			(type default)
		)
		(layer "In15.Cu")
	)
	(gr_line
		(start 107.572048 -276.836632)
		(end 107.573064 -276.836124)
		(stroke
			(width 0.05715)
			(type default)
		)
		(layer "In15.Cu")
	)
	(gr_line
		(start 107.572048 -275.21662)
		(end 107.574588 -275.21535)
		(stroke
			(width 0.05715)
			(type default)
		)
		(layer "In15.Cu")
	)
	(gr_line
		(start 107.573064 -276.836124)
		(end 107.573826 -276.835616)
		(stroke
			(width 0.05715)
			(type default)
		)
		(layer "In15.Cu")
	)
	(gr_line
		(start 107.574588 -275.21535)
		(end 107.57535 -275.214842)
		(stroke
			(width 0.05715)
			(type default)
		)
		(layer "In15.Cu")
	)
	(gr_line
		(start 107.57535 -275.214842)
		(end 107.576366 -275.214334)
		(stroke
			(width 0.05715)
			(type default)
		)
		(layer "In15.Cu")
	)
	(gr_line
		(start 107.57662 -292.398704)
		(end 107.57408 -292.39718)
		(stroke
			(width 0.05715)
			(type default)
		)
		(layer "In15.Cu")
	)
	(gr_line
		(start 107.576874 -290.778692)
		(end 107.575604 -290.77793)
		(stroke
			(width 0.05715)
			(type default)
		)
		(layer "In15.Cu")
	)
	(gr_line
		(start 107.577128 -292.398958)
		(end 107.57662 -292.398704)
		(stroke
			(width 0.05715)
			(type default)
		)
		(layer "In15.Cu")
	)
	(gr_line
		(start 107.663234 -284.128464)
		(end 107.66044 -284.12694)
		(stroke
			(width 0.05715)
			(type default)
		)
		(layer "In15.Cu")
	)
	(gr_line
		(start 107.663234 -282.508452)
		(end 107.66044 -282.506928)
		(stroke
			(width 0.05715)
			(type default)
		)
		(layer "In15.Cu")
	)
	(gr_line
		(start 107.663234 -280.88844)
		(end 107.662472 -280.887932)
		(stroke
			(width 0.05715)
			(type default)
		)
		(layer "In15.Cu")
	)
	(gr_line
		(start 107.663234 -279.268428)
		(end 107.66044 -279.266904)
		(stroke
			(width 0.05715)
			(type default)
		)
		(layer "In15.Cu")
	)
	(gr_line
		(start 107.663234 -277.648416)
		(end 107.66044 -277.646892)
		(stroke
			(width 0.05715)
			(type default)
		)
		(layer "In15.Cu")
	)
	(gr_line
		(start 107.663234 -276.028404)
		(end 107.66044 -276.02688)
		(stroke
			(width 0.05715)
			(type default)
		)
		(layer "In15.Cu")
	)
	(gr_line
		(start 107.663234 -273.764248)
		(end 107.663996 -273.76374)
		(stroke
			(width 0.05715)
			(type default)
		)
		(layer "In15.Cu")
	)
	(gr_line
		(start 107.663996 -293.84879)
		(end 107.663234 -293.848282)
		(stroke
			(width 0.05715)
			(type default)
		)
		(layer "In15.Cu")
	)
	(gr_line
		(start 107.663996 -284.128972)
		(end 107.663234 -284.128464)
		(stroke
			(width 0.05715)
			(type default)
		)
		(layer "In15.Cu")
	)
	(gr_line
		(start 107.663996 -282.50896)
		(end 107.663234 -282.508452)
		(stroke
			(width 0.05715)
			(type default)
		)
		(layer "In15.Cu")
	)
	(gr_line
		(start 107.663996 -279.268936)
		(end 107.663234 -279.268428)
		(stroke
			(width 0.05715)
			(type default)
		)
		(layer "In15.Cu")
	)
	(gr_line
		(start 107.663996 -277.648924)
		(end 107.663234 -277.648416)
		(stroke
			(width 0.05715)
			(type default)
		)
		(layer "In15.Cu")
	)
	(gr_line
		(start 107.663996 -276.028912)
		(end 107.663234 -276.028404)
		(stroke
			(width 0.05715)
			(type default)
		)
		(layer "In15.Cu")
	)
	(gr_line
		(start 107.663996 -273.76374)
		(end 107.665012 -273.763232)
		(stroke
			(width 0.05715)
			(type default)
		)
		(layer "In15.Cu")
	)
	(gr_line
		(start 107.663996 -272.143728)
		(end 107.665012 -272.14322)
		(stroke
			(width 0.05715)
			(type default)
		)
		(layer "In15.Cu")
	)
	(gr_line
		(start 107.665012 -293.849298)
		(end 107.663996 -293.84879)
		(stroke
			(width 0.05715)
			(type default)
		)
		(layer "In15.Cu")
	)
	(gr_line
		(start 107.665012 -285.749492)
		(end 107.663996 -285.748984)
		(stroke
			(width 0.05715)
			(type default)
		)
		(layer "In15.Cu")
	)
	(gr_line
		(start 107.665012 -284.12948)
		(end 107.663996 -284.128972)
		(stroke
			(width 0.05715)
			(type default)
		)
		(layer "In15.Cu")
	)
	(gr_line
		(start 107.665012 -283.483304)
		(end 107.672632 -283.478986)
		(stroke
			(width 0.05715)
			(type default)
		)
		(layer "In15.Cu")
	)
	(gr_line
		(start 107.665012 -282.509468)
		(end 107.663996 -282.50896)
		(stroke
			(width 0.05715)
			(type default)
		)
		(layer "In15.Cu")
	)
	(gr_line
		(start 107.665012 -281.863292)
		(end 107.672632 -281.858974)
		(stroke
			(width 0.05715)
			(type default)
		)
		(layer "In15.Cu")
	)
	(gr_line
		(start 107.665012 -279.269444)
		(end 107.663996 -279.268936)
		(stroke
			(width 0.05715)
			(type default)
		)
		(layer "In15.Cu")
	)
	(gr_line
		(start 107.665012 -278.623268)
		(end 107.672632 -278.61895)
		(stroke
			(width 0.05715)
			(type default)
		)
		(layer "In15.Cu")
	)
	(gr_line
		(start 107.665012 -277.649432)
		(end 107.663996 -277.648924)
		(stroke
			(width 0.05715)
			(type default)
		)
		(layer "In15.Cu")
	)
	(gr_line
		(start 107.665012 -277.003256)
		(end 107.669584 -277.000462)
		(stroke
			(width 0.05715)
			(type default)
		)
		(layer "In15.Cu")
	)
	(gr_line
		(start 107.665012 -276.02942)
		(end 107.663996 -276.028912)
		(stroke
			(width 0.05715)
			(type default)
		)
		(layer "In15.Cu")
	)
	(gr_line
		(start 107.665012 -275.383244)
		(end 107.66679 -275.382228)
		(stroke
			(width 0.05715)
			(type default)
		)
		(layer "In15.Cu")
	)
	(gr_line
		(start 107.665012 -274.409408)
		(end 107.663996 -274.4089)
		(stroke
			(width 0.05715)
			(type default)
		)
		(layer "In15.Cu")
	)
	(gr_line
		(start 107.66679 -275.382228)
		(end 107.667806 -275.38172)
		(stroke
			(width 0.05715)
			(type default)
		)
		(layer "In15.Cu")
	)
	(gr_line
		(start 107.667044 -293.850314)
		(end 107.665012 -293.849298)
		(stroke
			(width 0.05715)
			(type default)
		)
		(layer "In15.Cu")
	)
	(gr_line
		(start 107.667806 -290.610798)
		(end 107.663488 -290.608512)
		(stroke
			(width 0.05715)
			(type default)
		)
		(layer "In15.Cu")
	)
	(gr_line
		(start 107.667806 -275.38172)
		(end 107.6706 -275.380196)
		(stroke
			(width 0.05715)
			(type default)
		)
		(layer "In15.Cu")
	)
	(gr_line
		(start 107.668568 -292.231318)
		(end 107.664504 -292.229032)
		(stroke
			(width 0.05715)
			(type default)
		)
		(layer "In15.Cu")
	)
	(gr_line
		(start 107.66933 -292.231826)
		(end 107.668568 -292.231318)
		(stroke
			(width 0.05715)
			(type default)
		)
		(layer "In15.Cu")
	)
	(gr_line
		(start 107.669584 -293.851838)
		(end 107.668314 -293.851076)
		(stroke
			(width 0.05715)
			(type default)
		)
		(layer "In15.Cu")
	)
	(gr_line
		(start 107.6706 -275.380196)
		(end 107.671616 -275.379688)
		(stroke
			(width 0.05715)
			(type default)
		)
		(layer "In15.Cu")
	)
	(gr_line
		(start 107.672124 -292.233604)
		(end 107.66933 -292.231826)
		(stroke
			(width 0.05715)
			(type default)
		)
		(layer "In15.Cu")
	)
	(gr_line
		(start 107.672632 -290.613846)
		(end 107.670346 -290.612322)
		(stroke
			(width 0.05715)
			(type default)
		)
		(layer "In15.Cu")
	)
	(gr_line
		(start 107.684824 -291.571426)
		(end 107.685078 -291.571426)
		(stroke
			(width 0.05715)
			(type default)
		)
		(layer "In15.Cu")
	)
	(gr_line
		(start 107.684824 -289.951414)
		(end 107.685078 -289.951414)
		(stroke
			(width 0.05715)
			(type default)
		)
		(layer "In15.Cu")
	)
	(gr_line
		(start 107.69346 -291.5666)
		(end 107.694984 -291.565584)
		(stroke
			(width 0.05715)
			(type default)
		)
		(layer "In15.Cu")
	)
	(gr_line
		(start 107.69346 -289.946588)
		(end 107.694984 -289.945572)
		(stroke
			(width 0.05715)
			(type default)
		)
		(layer "In15.Cu")
	)
	(gr_line
		(start 107.694984 -293.18585)
		(end 107.700318 -293.182802)
		(stroke
			(width 0.05715)
			(type default)
		)
		(layer "In15.Cu")
	)
	(gr_line
		(start 107.695492 -293.867078)
		(end 107.694222 -293.866316)
		(stroke
			(width 0.05715)
			(type default)
		)
		(layer "In15.Cu")
	)
	(gr_line
		(start 107.695492 -272.807176)
		(end 107.69473 -272.806668)
		(stroke
			(width 0.05715)
			(type default)
		)
		(layer "In15.Cu")
	)
	(gr_line
		(start 107.695492 -271.187164)
		(end 107.69473 -271.186656)
		(stroke
			(width 0.05715)
			(type default)
		)
		(layer "In15.Cu")
	)
	(gr_line
		(start 107.696 -292.24732)
		(end 107.694222 -292.246304)
		(stroke
			(width 0.05715)
			(type default)
		)
		(layer "In15.Cu")
	)
	(gr_line
		(start 107.696254 -293.867586)
		(end 107.695492 -293.867078)
		(stroke
			(width 0.05715)
			(type default)
		)
		(layer "In15.Cu")
	)
	(gr_line
		(start 107.696254 -272.807684)
		(end 107.695492 -272.807176)
		(stroke
			(width 0.05715)
			(type default)
		)
		(layer "In15.Cu")
	)
	(gr_line
		(start 107.696254 -271.187672)
		(end 107.695492 -271.187164)
		(stroke
			(width 0.05715)
			(type default)
		)
		(layer "In15.Cu")
	)
	(gr_line
		(start 107.698794 -287.389316)
		(end 107.694984 -287.38703)
		(stroke
			(width 0.05715)
			(type default)
		)
		(layer "In15.Cu")
	)
	(gr_line
		(start 107.700318 -293.182802)
		(end 107.703112 -293.18077)
		(stroke
			(width 0.05715)
			(type default)
		)
		(layer "In15.Cu")
	)
	(gr_line
		(start 107.70235 -292.25113)
		(end 107.696 -292.24732)
		(stroke
			(width 0.05715)
			(type default)
		)
		(layer "In15.Cu")
	)
	(gr_arc
		(start 107.70235 -292.25113)
		(mid 107.702731 -292.251384)
		(end 107.703112 -292.251638)
		(stroke
			(width 0.05715)
			(type default)
		)
		(layer "In15.Cu")
	)
	(gr_line
		(start 107.70235 -290.631118)
		(end 107.695238 -290.627054)
		(stroke
			(width 0.05715)
			(type default)
		)
		(layer "In15.Cu")
	)
	(gr_arc
		(start 107.70235 -290.631118)
		(mid 107.702731 -290.631372)
		(end 107.703112 -290.631626)
		(stroke
			(width 0.05715)
			(type default)
		)
		(layer "In15.Cu")
	)
	(gr_line
		(start 107.70235 -289.011106)
		(end 107.695238 -289.007042)
		(stroke
			(width 0.05715)
			(type default)
		)
		(layer "In15.Cu")
	)
	(gr_arc
		(start 107.70235 -289.011106)
		(mid 107.702731 -289.01136)
		(end 107.703112 -289.011614)
		(stroke
			(width 0.05715)
			(type default)
		)
		(layer "In15.Cu")
	)
	(gr_line
		(start 107.70235 -287.391348)
		(end 107.698794 -287.389316)
		(stroke
			(width 0.05715)
			(type default)
		)
		(layer "In15.Cu")
	)
	(gr_line
		(start 107.70235 -287.391094)
		(end 107.70235 -287.391348)
		(stroke
			(width 0.05715)
			(type default)
		)
		(layer "In15.Cu")
	)
	(gr_line
		(start 107.703112 -293.87165)
		(end 107.696254 -293.867586)
		(stroke
			(width 0.05715)
			(type default)
		)
		(layer "In15.Cu")
	)
	(gr_arc
		(start 107.703112 -293.18077)
		(mid 107.707061 -293.177993)
		(end 107.710986 -293.175182)
		(stroke
			(width 0.05715)
			(type default)
		)
		(layer "In15.Cu")
	)
	(gr_line
		(start 107.703112 -272.811748)
		(end 107.696254 -272.807684)
		(stroke
			(width 0.05715)
			(type default)
		)
		(layer "In15.Cu")
	)
	(gr_line
		(start 107.703112 -271.191736)
		(end 107.696254 -271.187672)
		(stroke
			(width 0.05715)
			(type default)
		)
		(layer "In15.Cu")
	)
	(gr_arc
		(start 107.704636 -292.252654)
		(mid 107.703874 -292.252145)
		(end 107.703112 -292.251638)
		(stroke
			(width 0.05715)
			(type default)
		)
		(layer "In15.Cu")
	)
	(gr_arc
		(start 107.710986 -293.877238)
		(mid 107.707061 -293.874427)
		(end 107.703112 -293.87165)
		(stroke
			(width 0.05715)
			(type default)
		)
		(layer "In15.Cu")
	)
	(gr_arc
		(start 107.710986 -292.257226)
		(mid 107.708198 -292.255312)
		(end 107.705398 -292.253416)
		(stroke
			(width 0.05715)
			(type default)
		)
		(layer "In15.Cu")
	)
	(gr_arc
		(start 107.710986 -290.637214)
		(mid 107.707061 -290.634403)
		(end 107.703112 -290.631626)
		(stroke
			(width 0.05715)
			(type default)
		)
		(layer "In15.Cu")
	)
	(gr_arc
		(start 107.710986 -289.017202)
		(mid 107.707061 -289.014391)
		(end 107.703112 -289.011614)
		(stroke
			(width 0.05715)
			(type default)
		)
		(layer "In15.Cu")
	)
	(gr_arc
		(start 107.710986 -272.817336)
		(mid 107.707061 -272.814525)
		(end 107.703112 -272.811748)
		(stroke
			(width 0.05715)
			(type default)
		)
		(layer "In15.Cu")
	)
	(gr_arc
		(start 107.710986 -271.197324)
		(mid 107.707061 -271.194513)
		(end 107.703112 -271.191736)
		(stroke
			(width 0.05715)
			(type default)
		)
		(layer "In15.Cu")
	)
	(gr_arc
		(start 107.71124 -287.39719)
		(mid 107.70681 -287.39412)
		(end 107.70235 -287.391094)
		(stroke
			(width 0.05715)
			(type default)
		)
		(layer "In15.Cu")
	)
	(gr_line
		(start 108.17987 -296.070782)
		(end 108.17987 -296.042334)
		(stroke
			(width 0.05715)
			(type default)
		)
		(layer "In15.Cu")
	)
	(gr_line
		(start 108.17987 -296.042334)
		(end 108.22559 -295.996614)
		(stroke
			(width 0.05715)
			(type default)
		)
		(layer "In15.Cu")
	)
	(gr_line
		(start 108.41609 -295.42359)
		(end 108.416344 -295.423336)
		(stroke
			(width 0.05715)
			(type default)
		)
		(layer "In15.Cu")
	)
	(gr_line
		(start 108.46181 -296.070782)
		(end 108.46181 -296.042334)
		(stroke
			(width 0.05715)
			(type default)
		)
		(layer "In15.Cu")
	)
	(gr_line
		(start 108.46181 -296.042334)
		(end 108.41609 -295.996614)
		(stroke
			(width 0.05715)
			(type default)
		)
		(layer "In15.Cu")
	)
	(gr_arc
		(start 108.468922 -293.061644)
		(mid 108.464973 -293.064421)
		(end 108.461048 -293.067232)
		(stroke
			(width 0.05715)
			(type default)
		)
		(layer "In15.Cu")
	)
	(gr_line
		(start 108.468922 -293.061644)
		(end 108.486702 -293.05123)
		(stroke
			(width 0.05715)
			(type default)
		)
		(layer "In15.Cu")
	)
	(gr_arc
		(start 108.468922 -291.441632)
		(mid 108.465994 -291.443655)
		(end 108.46308 -291.445696)
		(stroke
			(width 0.05715)
			(type default)
		)
		(layer "In15.Cu")
	)
	(gr_line
		(start 108.468922 -291.441632)
		(end 108.477558 -291.436552)
		(stroke
			(width 0.05715)
			(type default)
		)
		(layer "In15.Cu")
	)
	(gr_arc
		(start 108.468922 -286.581596)
		(mid 108.463566 -286.585375)
		(end 108.458254 -286.589216)
		(stroke
			(width 0.05715)
			(type default)
		)
		(layer "In15.Cu")
	)
	(gr_line
		(start 108.468922 -286.581596)
		(end 108.46943 -286.581342)
		(stroke
			(width 0.05715)
			(type default)
		)
		(layer "In15.Cu")
	)
	(gr_line
		(start 108.46943 -286.581342)
		(end 108.474256 -286.578548)
		(stroke
			(width 0.05715)
			(type default)
		)
		(layer "In15.Cu")
	)
	(gr_line
		(start 108.477558 -291.436552)
		(end 108.478574 -291.436044)
		(stroke
			(width 0.05715)
			(type default)
		)
		(layer "In15.Cu")
	)
	(gr_line
		(start 108.486702 -293.05123)
		(end 108.487718 -293.050722)
		(stroke
			(width 0.05715)
			(type default)
		)
		(layer "In15.Cu")
	)
	(gr_line
		(start 108.50118 -280.083006)
		(end 108.504482 -280.080974)
		(stroke
			(width 0.05715)
			(type default)
		)
		(layer "In15.Cu")
	)
	(gr_line
		(start 108.50118 -278.462994)
		(end 108.504482 -278.460962)
		(stroke
			(width 0.05715)
			(type default)
		)
		(layer "In15.Cu")
	)
	(gr_line
		(start 108.50118 -276.842982)
		(end 108.504482 -276.84095)
		(stroke
			(width 0.05715)
			(type default)
		)
		(layer "In15.Cu")
	)
	(gr_line
		(start 108.50118 -275.22297)
		(end 108.504482 -275.220938)
		(stroke
			(width 0.05715)
			(type default)
		)
		(layer "In15.Cu")
	)
	(gr_line
		(start 108.50118 -273.602958)
		(end 108.504482 -273.600926)
		(stroke
			(width 0.05715)
			(type default)
		)
		(layer "In15.Cu")
	)
	(gr_line
		(start 108.50245 -294.662098)
		(end 108.50372 -294.661336)
		(stroke
			(width 0.05715)
			(type default)
		)
		(layer "In15.Cu")
	)
	(gr_line
		(start 108.504482 -280.080974)
		(end 108.505498 -280.080466)
		(stroke
			(width 0.05715)
			(type default)
		)
		(layer "In15.Cu")
	)
	(gr_line
		(start 108.504482 -278.460962)
		(end 108.505498 -278.460454)
		(stroke
			(width 0.05715)
			(type default)
		)
		(layer "In15.Cu")
	)
	(gr_line
		(start 108.504482 -276.84095)
		(end 108.505498 -276.840442)
		(stroke
			(width 0.05715)
			(type default)
		)
		(layer "In15.Cu")
	)
	(gr_line
		(start 108.504482 -275.220938)
		(end 108.505498 -275.22043)
		(stroke
			(width 0.05715)
			(type default)
		)
		(layer "In15.Cu")
	)
	(gr_line
		(start 108.504482 -273.600926)
		(end 108.505498 -273.600418)
		(stroke
			(width 0.05715)
			(type default)
		)
		(layer "In15.Cu")
	)
	(gr_line
		(start 108.505498 -294.66032)
		(end 108.507022 -294.659304)
		(stroke
			(width 0.05715)
			(type default)
		)
		(layer "In15.Cu")
	)
	(gr_line
		(start 108.505498 -280.080466)
		(end 108.507022 -280.07945)
		(stroke
			(width 0.05715)
			(type default)
		)
		(layer "In15.Cu")
	)
	(gr_line
		(start 108.505498 -278.460454)
		(end 108.507022 -278.459438)
		(stroke
			(width 0.05715)
			(type default)
		)
		(layer "In15.Cu")
	)
	(gr_line
		(start 108.505498 -276.840442)
		(end 108.507022 -276.839426)
		(stroke
			(width 0.05715)
			(type default)
		)
		(layer "In15.Cu")
	)
	(gr_line
		(start 108.505498 -275.22043)
		(end 108.507022 -275.219414)
		(stroke
			(width 0.05715)
			(type default)
		)
		(layer "In15.Cu")
	)
	(gr_line
		(start 108.505498 -273.600418)
		(end 108.507022 -273.599402)
		(stroke
			(width 0.05715)
			(type default)
		)
		(layer "In15.Cu")
	)
	(gr_line
		(start 108.507022 -294.659304)
		(end 108.508038 -294.658796)
		(stroke
			(width 0.05715)
			(type default)
		)
		(layer "In15.Cu")
	)
	(gr_line
		(start 108.507022 -283.319474)
		(end 108.508038 -283.318966)
		(stroke
			(width 0.05715)
			(type default)
		)
		(layer "In15.Cu")
	)
	(gr_line
		(start 108.507022 -280.07945)
		(end 108.508038 -280.078942)
		(stroke
			(width 0.05715)
			(type default)
		)
		(layer "In15.Cu")
	)
	(gr_line
		(start 108.507022 -278.459438)
		(end 108.508038 -278.45893)
		(stroke
			(width 0.05715)
			(type default)
		)
		(layer "In15.Cu")
	)
	(gr_line
		(start 108.507022 -276.839426)
		(end 108.508038 -276.838918)
		(stroke
			(width 0.05715)
			(type default)
		)
		(layer "In15.Cu")
	)
	(gr_line
		(start 108.507022 -275.219414)
		(end 108.508038 -275.218906)
		(stroke
			(width 0.05715)
			(type default)
		)
		(layer "In15.Cu")
	)
	(gr_line
		(start 108.507022 -273.599402)
		(end 108.508038 -273.598894)
		(stroke
			(width 0.05715)
			(type default)
		)
		(layer "In15.Cu")
	)
	(gr_line
		(start 108.508038 -294.658796)
		(end 108.508546 -294.658542)
		(stroke
			(width 0.05715)
			(type default)
		)
		(layer "In15.Cu")
	)
	(gr_line
		(start 108.508038 -294.013636)
		(end 108.507022 -294.013128)
		(stroke
			(width 0.05715)
			(type default)
		)
		(layer "In15.Cu")
	)
	(gr_line
		(start 108.508038 -292.393624)
		(end 108.507022 -292.393116)
		(stroke
			(width 0.05715)
			(type default)
		)
		(layer "In15.Cu")
	)
	(gr_line
		(start 108.508038 -290.773612)
		(end 108.507022 -290.773104)
		(stroke
			(width 0.05715)
			(type default)
		)
		(layer "In15.Cu")
	)
	(gr_line
		(start 108.508038 -289.1536)
		(end 108.507022 -289.153092)
		(stroke
			(width 0.05715)
			(type default)
		)
		(layer "In15.Cu")
	)
	(gr_line
		(start 108.508038 -283.318966)
		(end 108.508546 -283.318712)
		(stroke
			(width 0.05715)
			(type default)
		)
		(layer "In15.Cu")
	)
	(gr_line
		(start 108.508038 -281.053794)
		(end 108.507022 -281.053286)
		(stroke
			(width 0.05715)
			(type default)
		)
		(layer "In15.Cu")
	)
	(gr_line
		(start 108.508038 -280.078942)
		(end 108.5088 -280.078434)
		(stroke
			(width 0.05715)
			(type default)
		)
		(layer "In15.Cu")
	)
	(gr_line
		(start 108.508038 -278.45893)
		(end 108.5088 -278.458422)
		(stroke
			(width 0.05715)
			(type default)
		)
		(layer "In15.Cu")
	)
	(gr_line
		(start 108.508038 -276.838918)
		(end 108.5088 -276.83841)
		(stroke
			(width 0.05715)
			(type default)
		)
		(layer "In15.Cu")
	)
	(gr_line
		(start 108.508038 -275.218906)
		(end 108.5088 -275.218398)
		(stroke
			(width 0.05715)
			(type default)
		)
		(layer "In15.Cu")
	)
	(gr_line
		(start 108.508038 -273.598894)
		(end 108.5088 -273.598386)
		(stroke
			(width 0.05715)
			(type default)
		)
		(layer "In15.Cu")
	)
	(gr_line
		(start 108.5088 -281.054302)
		(end 108.508038 -281.053794)
		(stroke
			(width 0.05715)
			(type default)
		)
		(layer "In15.Cu")
	)
	(gr_line
		(start 108.51007 -284.295088)
		(end 108.5088 -284.294326)
		(stroke
			(width 0.05715)
			(type default)
		)
		(layer "In15.Cu")
	)
	(gr_line
		(start 108.51007 -282.675076)
		(end 108.5088 -282.674314)
		(stroke
			(width 0.05715)
			(type default)
		)
		(layer "In15.Cu")
	)
	(gr_line
		(start 108.51007 -279.435052)
		(end 108.5088 -279.43429)
		(stroke
			(width 0.05715)
			(type default)
		)
		(layer "In15.Cu")
	)
	(gr_line
		(start 108.51007 -277.81504)
		(end 108.5088 -277.814278)
		(stroke
			(width 0.05715)
			(type default)
		)
		(layer "In15.Cu")
	)
	(gr_line
		(start 108.51261 -281.056588)
		(end 108.5088 -281.054302)
		(stroke
			(width 0.05715)
			(type default)
		)
		(layer "In15.Cu")
	)
	(gr_line
		(start 108.539788 -276.82063)
		(end 108.539534 -276.82063)
		(stroke
			(width 0.05715)
			(type default)
		)
		(layer "In15.Cu")
	)
	(gr_line
		(start 108.539788 -275.200618)
		(end 108.539534 -275.200618)
		(stroke
			(width 0.05715)
			(type default)
		)
		(layer "In15.Cu")
	)
	(gr_line
		(start 108.5723 -291.601906)
		(end 108.5723 -291.60216)
		(stroke
			(width 0.05715)
			(type default)
		)
		(layer "In15.Cu")
	)
	(gr_line
		(start 108.5723 -289.981894)
		(end 108.572554 -289.982148)
		(stroke
			(width 0.05715)
			(type default)
		)
		(layer "In15.Cu")
	)
	(gr_line
		(start 108.57484 -293.221918)
		(end 108.583222 -293.221918)
		(stroke
			(width 0.05715)
			(type default)
		)
		(layer "In15.Cu")
	)
	(gr_line
		(start 108.583222 -293.221918)
		(end 108.583222 -293.216838)
		(stroke
			(width 0.05715)
			(type default)
		)
		(layer "In15.Cu")
	)
	(gr_line
		(start 108.598462 -294.826944)
		(end 108.600494 -294.825674)
		(stroke
			(width 0.05715)
			(type default)
		)
		(layer "In15.Cu")
	)
	(gr_line
		(start 108.600494 -294.825674)
		(end 108.602018 -294.824912)
		(stroke
			(width 0.05715)
			(type default)
		)
		(layer "In15.Cu")
	)
	(gr_line
		(start 108.601002 -280.245566)
		(end 108.603288 -280.244296)
		(stroke
			(width 0.05715)
			(type default)
		)
		(layer "In15.Cu")
	)
	(gr_line
		(start 108.601002 -278.625554)
		(end 108.603288 -278.624284)
		(stroke
			(width 0.05715)
			(type default)
		)
		(layer "In15.Cu")
	)
	(gr_line
		(start 108.601002 -277.005542)
		(end 108.603288 -277.004272)
		(stroke
			(width 0.05715)
			(type default)
		)
		(layer "In15.Cu")
	)
	(gr_line
		(start 108.601002 -275.38553)
		(end 108.603288 -275.38426)
		(stroke
			(width 0.05715)
			(type default)
		)
		(layer "In15.Cu")
	)
	(gr_line
		(start 108.601002 -273.765518)
		(end 108.603288 -273.764248)
		(stroke
			(width 0.05715)
			(type default)
		)
		(layer "In15.Cu")
	)
	(gr_line
		(start 108.602018 -294.824912)
		(end 108.603288 -294.82415)
		(stroke
			(width 0.05715)
			(type default)
		)
		(layer "In15.Cu")
	)
	(gr_line
		(start 108.602018 -283.485082)
		(end 108.603288 -283.48432)
		(stroke
			(width 0.05715)
			(type default)
		)
		(layer "In15.Cu")
	)
	(gr_line
		(start 108.603288 -293.848282)
		(end 108.602018 -293.84752)
		(stroke
			(width 0.05715)
			(type default)
		)
		(layer "In15.Cu")
	)
	(gr_line
		(start 108.603288 -292.22827)
		(end 108.602018 -292.227508)
		(stroke
			(width 0.05715)
			(type default)
		)
		(layer "In15.Cu")
	)
	(gr_line
		(start 108.603288 -290.608258)
		(end 108.602018 -290.607496)
		(stroke
			(width 0.05715)
			(type default)
		)
		(layer "In15.Cu")
	)
	(gr_line
		(start 108.603288 -288.988246)
		(end 108.602018 -288.987484)
		(stroke
			(width 0.05715)
			(type default)
		)
		(layer "In15.Cu")
	)
	(gr_line
		(start 108.603288 -280.88844)
		(end 108.602018 -280.887678)
		(stroke
			(width 0.05715)
			(type default)
		)
		(layer "In15.Cu")
	)
	(gr_line
		(start 108.603288 -280.244296)
		(end 108.60405 -280.243788)
		(stroke
			(width 0.05715)
			(type default)
		)
		(layer "In15.Cu")
	)
	(gr_line
		(start 108.603288 -278.624284)
		(end 108.60405 -278.623776)
		(stroke
			(width 0.05715)
			(type default)
		)
		(layer "In15.Cu")
	)
	(gr_line
		(start 108.603288 -277.004272)
		(end 108.60405 -277.003764)
		(stroke
			(width 0.05715)
			(type default)
		)
		(layer "In15.Cu")
	)
	(gr_line
		(start 108.603288 -275.38426)
		(end 108.60405 -275.383752)
		(stroke
			(width 0.05715)
			(type default)
		)
		(layer "In15.Cu")
	)
	(gr_line
		(start 108.603288 -273.764248)
		(end 108.60405 -273.76374)
		(stroke
			(width 0.05715)
			(type default)
		)
		(layer "In15.Cu")
	)
	(gr_line
		(start 108.603796 -293.848536)
		(end 108.603288 -293.848282)
		(stroke
			(width 0.05715)
			(type default)
		)
		(layer "In15.Cu")
	)
	(gr_line
		(start 108.603796 -292.228524)
		(end 108.603288 -292.22827)
		(stroke
			(width 0.05715)
			(type default)
		)
		(layer "In15.Cu")
	)
	(gr_line
		(start 108.603796 -290.608512)
		(end 108.603288 -290.608258)
		(stroke
			(width 0.05715)
			(type default)
		)
		(layer "In15.Cu")
	)
	(gr_line
		(start 108.603796 -288.9885)
		(end 108.603288 -288.988246)
		(stroke
			(width 0.05715)
			(type default)
		)
		(layer "In15.Cu")
	)
	(gr_line
		(start 108.60405 -285.748984)
		(end 108.603542 -285.74873)
		(stroke
			(width 0.05715)
			(type default)
		)
		(layer "In15.Cu")
	)
	(gr_line
		(start 108.60405 -284.128972)
		(end 108.603542 -284.128718)
		(stroke
			(width 0.05715)
			(type default)
		)
		(layer "In15.Cu")
	)
	(gr_line
		(start 108.60405 -282.50896)
		(end 108.603542 -282.508706)
		(stroke
			(width 0.05715)
			(type default)
		)
		(layer "In15.Cu")
	)
	(gr_line
		(start 108.60405 -280.243788)
		(end 108.605066 -280.24328)
		(stroke
			(width 0.05715)
			(type default)
		)
		(layer "In15.Cu")
	)
	(gr_line
		(start 108.60405 -279.268936)
		(end 108.603542 -279.268682)
		(stroke
			(width 0.05715)
			(type default)
		)
		(layer "In15.Cu")
	)
	(gr_line
		(start 108.60405 -278.623776)
		(end 108.605066 -278.623268)
		(stroke
			(width 0.05715)
			(type default)
		)
		(layer "In15.Cu")
	)
	(gr_line
		(start 108.60405 -277.648924)
		(end 108.603542 -277.64867)
		(stroke
			(width 0.05715)
			(type default)
		)
		(layer "In15.Cu")
	)
	(gr_line
		(start 108.60405 -277.003764)
		(end 108.605066 -277.003256)
		(stroke
			(width 0.05715)
			(type default)
		)
		(layer "In15.Cu")
	)
	(gr_line
		(start 108.60405 -275.383752)
		(end 108.605066 -275.383244)
		(stroke
			(width 0.05715)
			(type default)
		)
		(layer "In15.Cu")
	)
	(gr_line
		(start 108.60405 -273.76374)
		(end 108.605066 -273.763232)
		(stroke
			(width 0.05715)
			(type default)
		)
		(layer "In15.Cu")
	)
	(gr_line
		(start 108.605066 -284.12948)
		(end 108.60405 -284.128972)
		(stroke
			(width 0.05715)
			(type default)
		)
		(layer "In15.Cu")
	)
	(gr_line
		(start 108.605066 -282.509468)
		(end 108.60405 -282.50896)
		(stroke
			(width 0.05715)
			(type default)
		)
		(layer "In15.Cu")
	)
	(gr_line
		(start 108.605066 -280.889456)
		(end 108.60405 -280.888948)
		(stroke
			(width 0.05715)
			(type default)
		)
		(layer "In15.Cu")
	)
	(gr_line
		(start 108.605066 -279.269444)
		(end 108.60405 -279.268936)
		(stroke
			(width 0.05715)
			(type default)
		)
		(layer "In15.Cu")
	)
	(gr_line
		(start 108.605066 -277.649432)
		(end 108.60405 -277.648924)
		(stroke
			(width 0.05715)
			(type default)
		)
		(layer "In15.Cu")
	)
	(gr_line
		(start 108.605828 -280.889964)
		(end 108.605066 -280.889456)
		(stroke
			(width 0.05715)
			(type default)
		)
		(layer "In15.Cu")
	)
	(gr_line
		(start 108.610146 -280.89225)
		(end 108.605828 -280.889964)
		(stroke
			(width 0.05715)
			(type default)
		)
		(layer "In15.Cu")
	)
	(gr_line
		(start 108.6231 -276.039326)
		(end 108.622338 -276.038818)
		(stroke
			(width 0.05715)
			(type default)
		)
		(layer "In15.Cu")
	)
	(gr_line
		(start 108.6231 -274.419314)
		(end 108.622338 -274.418806)
		(stroke
			(width 0.05715)
			(type default)
		)
		(layer "In15.Cu")
	)
	(gr_line
		(start 108.627164 -276.041612)
		(end 108.6231 -276.039326)
		(stroke
			(width 0.05715)
			(type default)
		)
		(layer "In15.Cu")
	)
	(gr_line
		(start 108.627164 -274.4216)
		(end 108.6231 -274.419314)
		(stroke
			(width 0.05715)
			(type default)
		)
		(layer "In15.Cu")
	)
	(gr_line
		(start 108.63453 -276.985984)
		(end 108.643166 -276.980904)
		(stroke
			(width 0.05715)
			(type default)
		)
		(layer "In15.Cu")
	)
	(gr_line
		(start 108.63453 -275.365972)
		(end 108.643166 -275.360892)
		(stroke
			(width 0.05715)
			(type default)
		)
		(layer "In15.Cu")
	)
	(gr_line
		(start 108.635038 -285.086044)
		(end 108.640372 -285.082996)
		(stroke
			(width 0.05715)
			(type default)
		)
		(layer "In15.Cu")
	)
	(gr_line
		(start 108.635038 -281.84602)
		(end 108.640372 -281.842972)
		(stroke
			(width 0.05715)
			(type default)
		)
		(layer "In15.Cu")
	)
	(gr_line
		(start 108.635546 -293.867078)
		(end 108.634784 -293.86657)
		(stroke
			(width 0.05715)
			(type default)
		)
		(layer "In15.Cu")
	)
	(gr_line
		(start 108.635546 -293.185342)
		(end 108.642658 -293.181278)
		(stroke
			(width 0.05715)
			(type default)
		)
		(layer "In15.Cu")
	)
	(gr_line
		(start 108.635546 -292.247066)
		(end 108.634784 -292.246558)
		(stroke
			(width 0.05715)
			(type default)
		)
		(layer "In15.Cu")
	)
	(gr_line
		(start 108.635546 -291.56533)
		(end 108.642658 -291.561266)
		(stroke
			(width 0.05715)
			(type default)
		)
		(layer "In15.Cu")
	)
	(gr_line
		(start 108.635546 -290.627054)
		(end 108.634784 -290.626546)
		(stroke
			(width 0.05715)
			(type default)
		)
		(layer "In15.Cu")
	)
	(gr_line
		(start 108.635546 -289.945572)
		(end 108.642912 -289.941254)
		(stroke
			(width 0.05715)
			(type default)
		)
		(layer "In15.Cu")
	)
	(gr_line
		(start 108.635546 -289.007042)
		(end 108.634784 -289.006534)
		(stroke
			(width 0.05715)
			(type default)
		)
		(layer "In15.Cu")
	)
	(gr_line
		(start 108.635546 -285.767272)
		(end 108.634784 -285.766764)
		(stroke
			(width 0.05715)
			(type default)
		)
		(layer "In15.Cu")
	)
	(gr_line
		(start 108.636308 -293.867586)
		(end 108.635546 -293.867078)
		(stroke
			(width 0.05715)
			(type default)
		)
		(layer "In15.Cu")
	)
	(gr_line
		(start 108.636308 -292.247574)
		(end 108.635546 -292.247066)
		(stroke
			(width 0.05715)
			(type default)
		)
		(layer "In15.Cu")
	)
	(gr_line
		(start 108.636308 -290.627562)
		(end 108.635546 -290.627054)
		(stroke
			(width 0.05715)
			(type default)
		)
		(layer "In15.Cu")
	)
	(gr_line
		(start 108.636308 -289.00755)
		(end 108.635546 -289.007042)
		(stroke
			(width 0.05715)
			(type default)
		)
		(layer "In15.Cu")
	)
	(gr_line
		(start 108.636308 -285.76778)
		(end 108.635546 -285.767272)
		(stroke
			(width 0.05715)
			(type default)
		)
		(layer "In15.Cu")
	)
	(gr_line
		(start 108.636308 -276.046692)
		(end 108.629196 -276.042628)
		(stroke
			(width 0.05715)
			(type default)
		)
		(layer "In15.Cu")
	)
	(gr_line
		(start 108.636308 -274.42668)
		(end 108.629196 -274.422616)
		(stroke
			(width 0.05715)
			(type default)
		)
		(layer "In15.Cu")
	)
	(gr_line
		(start 108.640372 -285.082996)
		(end 108.643166 -285.080964)
		(stroke
			(width 0.05715)
			(type default)
		)
		(layer "In15.Cu")
	)
	(gr_line
		(start 108.640372 -281.842972)
		(end 108.643166 -281.84094)
		(stroke
			(width 0.05715)
			(type default)
		)
		(layer "In15.Cu")
	)
	(gr_line
		(start 108.642658 -293.181278)
		(end 108.643166 -293.181024)
		(stroke
			(width 0.05715)
			(type default)
		)
		(layer "In15.Cu")
	)
	(gr_line
		(start 108.642658 -291.561266)
		(end 108.643166 -291.561012)
		(stroke
			(width 0.05715)
			(type default)
		)
		(layer "In15.Cu")
	)
	(gr_line
		(start 108.642912 -289.941254)
		(end 108.64342 -289.941)
		(stroke
			(width 0.05715)
			(type default)
		)
		(layer "In15.Cu")
	)
	(gr_line
		(start 108.643166 -293.87165)
		(end 108.636308 -293.867586)
		(stroke
			(width 0.05715)
			(type default)
		)
		(layer "In15.Cu")
	)
	(gr_line
		(start 108.643166 -293.181024)
		(end 108.643166 -293.18077)
		(stroke
			(width 0.05715)
			(type default)
		)
		(layer "In15.Cu")
	)
	(gr_arc
		(start 108.643166 -293.18077)
		(mid 108.647115 -293.177993)
		(end 108.65104 -293.175182)
		(stroke
			(width 0.05715)
			(type default)
		)
		(layer "In15.Cu")
	)
	(gr_line
		(start 108.643166 -292.251638)
		(end 108.636308 -292.247574)
		(stroke
			(width 0.05715)
			(type default)
		)
		(layer "In15.Cu")
	)
	(gr_line
		(start 108.643166 -291.561012)
		(end 108.643166 -291.560758)
		(stroke
			(width 0.05715)
			(type default)
		)
		(layer "In15.Cu")
	)
	(gr_arc
		(start 108.643166 -291.560758)
		(mid 108.647115 -291.557981)
		(end 108.65104 -291.55517)
		(stroke
			(width 0.05715)
			(type default)
		)
		(layer "In15.Cu")
	)
	(gr_line
		(start 108.643166 -290.631626)
		(end 108.636308 -290.627562)
		(stroke
			(width 0.05715)
			(type default)
		)
		(layer "In15.Cu")
	)
	(gr_arc
		(start 108.643166 -289.940746)
		(mid 108.647115 -289.937969)
		(end 108.65104 -289.935158)
		(stroke
			(width 0.05715)
			(type default)
		)
		(layer "In15.Cu")
	)
	(gr_line
		(start 108.643166 -289.011614)
		(end 108.636308 -289.00755)
		(stroke
			(width 0.05715)
			(type default)
		)
		(layer "In15.Cu")
	)
	(gr_line
		(start 108.643166 -285.771844)
		(end 108.636308 -285.76778)
		(stroke
			(width 0.05715)
			(type default)
		)
		(layer "In15.Cu")
	)
	(gr_arc
		(start 108.643166 -285.080964)
		(mid 108.647115 -285.078187)
		(end 108.65104 -285.075376)
		(stroke
			(width 0.05715)
			(type default)
		)
		(layer "In15.Cu")
	)
	(gr_arc
		(start 108.643166 -281.84094)
		(mid 108.647115 -281.838163)
		(end 108.65104 -281.835352)
		(stroke
			(width 0.05715)
			(type default)
		)
		(layer "In15.Cu")
	)
	(gr_arc
		(start 108.643166 -276.980904)
		(mid 108.647242 -276.978)
		(end 108.651294 -276.975062)
		(stroke
			(width 0.05715)
			(type default)
		)
		(layer "In15.Cu")
	)
	(gr_line
		(start 108.643166 -276.05101)
		(end 108.643166 -276.050502)
		(stroke
			(width 0.05715)
			(type default)
		)
		(layer "In15.Cu")
	)
	(gr_line
		(start 108.643166 -276.050502)
		(end 108.637832 -276.047454)
		(stroke
			(width 0.05715)
			(type default)
		)
		(layer "In15.Cu")
	)
	(gr_arc
		(start 108.643166 -275.360892)
		(mid 108.647242 -275.357988)
		(end 108.651294 -275.35505)
		(stroke
			(width 0.05715)
			(type default)
		)
		(layer "In15.Cu")
	)
	(gr_line
		(start 108.643166 -274.430998)
		(end 108.643166 -274.43049)
		(stroke
			(width 0.05715)
			(type default)
		)
		(layer "In15.Cu")
	)
	(gr_line
		(start 108.643166 -274.43049)
		(end 108.637832 -274.427442)
		(stroke
			(width 0.05715)
			(type default)
		)
		(layer "In15.Cu")
	)
	(gr_line
		(start 108.64342 -289.941)
		(end 108.643166 -289.940746)
		(stroke
			(width 0.05715)
			(type default)
		)
		(layer "In15.Cu")
	)
	(gr_arc
		(start 108.65104 -293.877238)
		(mid 108.647115 -293.874427)
		(end 108.643166 -293.87165)
		(stroke
			(width 0.05715)
			(type default)
		)
		(layer "In15.Cu")
	)
	(gr_arc
		(start 108.65104 -292.257226)
		(mid 108.647115 -292.254415)
		(end 108.643166 -292.251638)
		(stroke
			(width 0.05715)
			(type default)
		)
		(layer "In15.Cu")
	)
	(gr_arc
		(start 108.65104 -290.637214)
		(mid 108.647115 -290.634403)
		(end 108.643166 -290.631626)
		(stroke
			(width 0.05715)
			(type default)
		)
		(layer "In15.Cu")
	)
	(gr_arc
		(start 108.65104 -289.017202)
		(mid 108.647115 -289.014391)
		(end 108.643166 -289.011614)
		(stroke
			(width 0.05715)
			(type default)
		)
		(layer "In15.Cu")
	)
	(gr_arc
		(start 108.65104 -285.777432)
		(mid 108.647115 -285.774621)
		(end 108.643166 -285.771844)
		(stroke
			(width 0.05715)
			(type default)
		)
		(layer "In15.Cu")
	)
	(gr_line
		(start 109.088936 -274.08632)
		(end 108.790994 -274.08632)
		(stroke
			(width 0.05715)
			(type default)
		)
		(layer "In15.Cu")
	)
	(gr_line
		(start 109.088936 -272.466308)
		(end 108.790994 -272.466308)
		(stroke
			(width 0.05715)
			(type default)
		)
		(layer "In15.Cu")
	)
	(gr_line
		(start 109.088936 -270.846296)
		(end 108.790994 -270.846296)
		(stroke
			(width 0.05715)
			(type default)
		)
		(layer "In15.Cu")
	)
	(gr_line
		(start 109.088936 -269.226284)
		(end 108.790994 -269.226284)
		(stroke
			(width 0.05715)
			(type default)
		)
		(layer "In15.Cu")
	)
	(gr_line
		(start 109.119924 -295.91127)
		(end 109.119924 -295.882822)
		(stroke
			(width 0.05715)
			(type default)
		)
		(layer "In15.Cu")
	)
	(gr_line
		(start 109.119924 -295.882822)
		(end 109.165644 -295.837102)
		(stroke
			(width 0.05715)
			(type default)
		)
		(layer "In15.Cu")
	)
	(gr_line
		(start 109.158278 -272.53565)
		(end 109.088936 -272.466308)
		(stroke
			(width 0.05715)
			(type default)
		)
		(layer "In15.Cu")
	)
	(gr_line
		(start 109.17174 -274.169124)
		(end 109.088936 -274.08632)
		(stroke
			(width 0.05715)
			(type default)
		)
		(layer "In15.Cu")
	)
	(gr_arc
		(start 109.17174 -274.169124)
		(mid 109.173531 -274.180446)
		(end 109.17555 -274.19173)
		(stroke
			(width 0.05715)
			(type default)
		)
		(layer "In15.Cu")
	)
	(gr_line
		(start 109.17174 -270.9291)
		(end 109.088936 -270.846296)
		(stroke
			(width 0.05715)
			(type default)
		)
		(layer "In15.Cu")
	)
	(gr_arc
		(start 109.17174 -270.9291)
		(mid 109.173533 -270.940422)
		(end 109.17555 -270.951706)
		(stroke
			(width 0.05715)
			(type default)
		)
		(layer "In15.Cu")
	)
	(gr_line
		(start 109.17174 -269.309088)
		(end 109.088936 -269.226284)
		(stroke
			(width 0.05715)
			(type default)
		)
		(layer "In15.Cu")
	)
	(gr_arc
		(start 109.17174 -269.309088)
		(mid 109.173532 -269.32041)
		(end 109.17555 -269.331694)
		(stroke
			(width 0.05715)
			(type default)
		)
		(layer "In15.Cu")
	)
	(gr_arc
		(start 109.346492 -272.571972)
		(mid 109.348515 -272.560562)
		(end 109.350302 -272.549112)
		(stroke
			(width 0.05715)
			(type default)
		)
		(layer "In15.Cu")
	)
	(gr_line
		(start 109.350302 -272.549112)
		(end 109.433106 -272.466308)
		(stroke
			(width 0.05715)
			(type default)
		)
		(layer "In15.Cu")
	)
	(gr_line
		(start 109.356144 -295.292272)
		(end 109.356398 -295.292018)
		(stroke
			(width 0.05715)
			(type default)
		)
		(layer "In15.Cu")
	)
	(gr_line
		(start 109.356398 -287.046416)
		(end 109.356144 -287.046162)
		(stroke
			(width 0.05715)
			(type default)
		)
		(layer "In15.Cu")
	)
	(gr_line
		(start 109.363764 -274.155662)
		(end 109.433106 -274.08632)
		(stroke
			(width 0.05715)
			(type default)
		)
		(layer "In15.Cu")
	)
	(gr_line
		(start 109.363764 -270.915638)
		(end 109.433106 -270.846296)
		(stroke
			(width 0.05715)
			(type default)
		)
		(layer "In15.Cu")
	)
	(gr_line
		(start 109.363764 -269.295626)
		(end 109.433106 -269.226284)
		(stroke
			(width 0.05715)
			(type default)
		)
		(layer "In15.Cu")
	)
	(gr_arc
		(start 109.400848 -274.545298)
		(mid 109.4049 -274.54811)
		(end 109.408976 -274.550886)
		(stroke
			(width 0.05715)
			(type default)
		)
		(layer "In15.Cu")
	)
	(gr_arc
		(start 109.400848 -269.685262)
		(mid 109.4049 -269.688074)
		(end 109.408976 -269.69085)
		(stroke
			(width 0.05715)
			(type default)
		)
		(layer "In15.Cu")
	)
	(gr_arc
		(start 109.401102 -289.125152)
		(mid 109.405027 -289.127963)
		(end 109.408976 -289.13074)
		(stroke
			(width 0.05715)
			(type default)
		)
		(layer "In15.Cu")
	)
	(gr_arc
		(start 109.401102 -279.405334)
		(mid 109.405027 -279.408145)
		(end 109.408976 -279.410922)
		(stroke
			(width 0.05715)
			(type default)
		)
		(layer "In15.Cu")
	)
	(gr_line
		(start 109.401864 -295.91127)
		(end 109.401864 -295.882822)
		(stroke
			(width 0.05715)
			(type default)
		)
		(layer "In15.Cu")
	)
	(gr_line
		(start 109.401864 -295.882822)
		(end 109.356144 -295.837102)
		(stroke
			(width 0.05715)
			(type default)
		)
		(layer "In15.Cu")
	)
	(gr_arc
		(start 109.408976 -294.681656)
		(mid 109.405027 -294.684433)
		(end 109.401102 -294.687244)
		(stroke
			(width 0.05715)
			(type default)
		)
		(layer "In15.Cu")
	)
	(gr_arc
		(start 109.408976 -294.681656)
		(mid 109.409357 -294.681402)
		(end 109.409738 -294.681148)
		(stroke
			(width 0.05715)
			(type default)
		)
		(layer "In15.Cu")
	)
	(gr_line
		(start 109.409738 -294.681148)
		(end 109.41685 -294.677084)
		(stroke
			(width 0.05715)
			(type default)
		)
		(layer "In15.Cu")
	)
	(gr_arc
		(start 109.409738 -279.41143)
		(mid 109.409357 -279.411176)
		(end 109.408976 -279.410922)
		(stroke
			(width 0.05715)
			(type default)
		)
		(layer "In15.Cu")
	)
	(gr_arc
		(start 109.409738 -274.551394)
		(mid 109.409357 -274.55114)
		(end 109.408976 -274.550886)
		(stroke
			(width 0.05715)
			(type default)
		)
		(layer "In15.Cu")
	)
	(gr_arc
		(start 109.409738 -269.691358)
		(mid 109.409357 -269.691104)
		(end 109.408976 -269.69085)
		(stroke
			(width 0.05715)
			(type default)
		)
		(layer "In15.Cu")
	)
	(gr_line
		(start 109.41304 -286.57931)
		(end 109.41558 -286.577786)
		(stroke
			(width 0.05715)
			(type default)
		)
		(layer "In15.Cu")
	)
	(gr_line
		(start 109.415834 -289.134804)
		(end 109.408976 -289.13074)
		(stroke
			(width 0.05715)
			(type default)
		)
		(layer "In15.Cu")
	)
	(gr_line
		(start 109.416342 -269.695168)
		(end 109.409738 -269.691358)
		(stroke
			(width 0.05715)
			(type default)
		)
		(layer "In15.Cu")
	)
	(gr_line
		(start 109.416596 -289.135312)
		(end 109.415834 -289.134804)
		(stroke
			(width 0.05715)
			(type default)
		)
		(layer "In15.Cu")
	)
	(gr_line
		(start 109.41685 -279.415494)
		(end 109.409738 -279.41143)
		(stroke
			(width 0.05715)
			(type default)
		)
		(layer "In15.Cu")
	)
	(gr_line
		(start 109.41685 -274.555458)
		(end 109.409738 -274.551394)
		(stroke
			(width 0.05715)
			(type default)
		)
		(layer "In15.Cu")
	)
	(gr_line
		(start 109.417104 -289.135566)
		(end 109.416596 -289.135312)
		(stroke
			(width 0.05715)
			(type default)
		)
		(layer "In15.Cu")
	)
	(gr_line
		(start 109.417104 -269.695676)
		(end 109.416342 -269.695168)
		(stroke
			(width 0.05715)
			(type default)
		)
		(layer "In15.Cu")
	)
	(gr_line
		(start 109.417612 -269.69593)
		(end 109.417104 -269.695676)
		(stroke
			(width 0.05715)
			(type default)
		)
		(layer "In15.Cu")
	)
	(gr_line
		(start 109.433106 -274.08632)
		(end 109.731048 -274.08632)
		(stroke
			(width 0.05715)
			(type default)
		)
		(layer "In15.Cu")
	)
	(gr_line
		(start 109.433106 -272.466308)
		(end 109.731048 -272.466308)
		(stroke
			(width 0.05715)
			(type default)
		)
		(layer "In15.Cu")
	)
	(gr_line
		(start 109.433106 -270.846296)
		(end 109.731048 -270.846296)
		(stroke
			(width 0.05715)
			(type default)
		)
		(layer "In15.Cu")
	)
	(gr_line
		(start 109.433106 -269.226284)
		(end 109.731048 -269.226284)
		(stroke
			(width 0.05715)
			(type default)
		)
		(layer "In15.Cu")
	)
	(gr_line
		(start 109.433614 -281.045412)
		(end 109.433106 -281.045158)
		(stroke
			(width 0.05715)
			(type default)
		)
		(layer "In15.Cu")
	)
	(gr_line
		(start 109.43463 -281.04592)
		(end 109.433614 -281.045412)
		(stroke
			(width 0.05715)
			(type default)
		)
		(layer "In15.Cu")
	)
	(gr_line
		(start 109.43717 -281.047444)
		(end 109.436662 -281.04719)
		(stroke
			(width 0.05715)
			(type default)
		)
		(layer "In15.Cu")
	)
	(gr_line
		(start 109.439456 -292.388798)
		(end 109.43844 -292.38829)
		(stroke
			(width 0.05715)
			(type default)
		)
		(layer "In15.Cu")
	)
	(gr_line
		(start 109.439964 -269.708884)
		(end 109.436916 -269.707106)
		(stroke
			(width 0.05715)
			(type default)
		)
		(layer "In15.Cu")
	)
	(gr_line
		(start 109.440218 -292.389306)
		(end 109.439456 -292.388798)
		(stroke
			(width 0.05715)
			(type default)
		)
		(layer "In15.Cu")
	)
	(gr_line
		(start 109.440726 -269.709392)
		(end 109.439964 -269.708884)
		(stroke
			(width 0.05715)
			(type default)
		)
		(layer "In15.Cu")
	)
	(gr_line
		(start 109.441488 -292.390068)
		(end 109.440218 -292.389306)
		(stroke
			(width 0.05715)
			(type default)
		)
		(layer "In15.Cu")
	)
	(gr_line
		(start 109.447076 -292.393116)
		(end 109.441488 -292.390068)
		(stroke
			(width 0.05715)
			(type default)
		)
		(layer "In15.Cu")
	)
	(gr_line
		(start 109.447076 -291.41928)
		(end 109.448092 -291.418772)
		(stroke
			(width 0.05715)
			(type default)
		)
		(layer "In15.Cu")
	)
	(gr_line
		(start 109.447076 -289.799268)
		(end 109.448092 -289.79876)
		(stroke
			(width 0.05715)
			(type default)
		)
		(layer "In15.Cu")
	)
	(gr_line
		(start 109.447076 -289.153092)
		(end 109.445044 -289.151822)
		(stroke
			(width 0.05715)
			(type default)
		)
		(layer "In15.Cu")
	)
	(gr_line
		(start 109.448092 -289.79876)
		(end 109.448854 -289.798252)
		(stroke
			(width 0.05715)
			(type default)
		)
		(layer "In15.Cu")
	)
	(gr_line
		(start 109.448092 -289.1536)
		(end 109.447076 -289.153092)
		(stroke
			(width 0.05715)
			(type default)
		)
		(layer "In15.Cu")
	)
	(gr_line
		(start 109.448854 -289.798252)
		(end 109.450124 -289.79749)
		(stroke
			(width 0.05715)
			(type default)
		)
		(layer "In15.Cu")
	)
	(gr_line
		(start 109.448854 -289.154108)
		(end 109.448092 -289.1536)
		(stroke
			(width 0.05715)
			(type default)
		)
		(layer "In15.Cu")
	)
	(gr_line
		(start 109.451648 -289.155632)
		(end 109.448854 -289.154108)
		(stroke
			(width 0.05715)
			(type default)
		)
		(layer "In15.Cu")
	)
	(gr_line
		(start 109.46892 -275.206714)
		(end 109.469428 -275.20646)
		(stroke
			(width 0.05715)
			(type default)
		)
		(layer "In15.Cu")
	)
	(gr_line
		(start 109.469428 -275.20646)
		(end 109.469682 -275.20646)
		(stroke
			(width 0.05715)
			(type default)
		)
		(layer "In15.Cu")
	)
	(gr_line
		(start 109.469682 -294.026082)
		(end 109.469428 -294.026082)
		(stroke
			(width 0.05715)
			(type default)
		)
		(layer "In15.Cu")
	)
	(gr_line
		(start 109.530896 -293.84117)
		(end 109.525054 -293.837868)
		(stroke
			(width 0.05715)
			(type default)
		)
		(layer "In15.Cu")
	)
	(gr_line
		(start 109.531404 -280.881582)
		(end 109.529626 -280.880566)
		(stroke
			(width 0.05715)
			(type default)
		)
		(layer "In15.Cu")
	)
	(gr_line
		(start 109.531404 -269.541498)
		(end 109.530896 -269.541244)
		(stroke
			(width 0.05715)
			(type default)
		)
		(layer "In15.Cu")
	)
	(gr_line
		(start 109.532928 -269.54226)
		(end 109.531404 -269.541498)
		(stroke
			(width 0.05715)
			(type default)
		)
		(layer "In15.Cu")
	)
	(gr_line
		(start 109.537754 -269.5448)
		(end 109.537246 -269.544546)
		(stroke
			(width 0.05715)
			(type default)
		)
		(layer "In15.Cu")
	)
	(gr_line
		(start 109.540548 -288.986722)
		(end 109.539786 -288.986214)
		(stroke
			(width 0.05715)
			(type default)
		)
		(layer "In15.Cu")
	)
	(gr_line
		(start 109.540802 -293.205154)
		(end 109.541818 -293.204646)
		(stroke
			(width 0.05715)
			(type default)
		)
		(layer "In15.Cu")
	)
	(gr_line
		(start 109.540802 -292.227)
		(end 109.54004 -292.226492)
		(stroke
			(width 0.05715)
			(type default)
		)
		(layer "In15.Cu")
	)
	(gr_line
		(start 109.541818 -292.227508)
		(end 109.540802 -292.227)
		(stroke
			(width 0.05715)
			(type default)
		)
		(layer "In15.Cu")
	)
	(gr_line
		(start 109.542072 -291.584888)
		(end 109.543342 -291.584126)
		(stroke
			(width 0.05715)
			(type default)
		)
		(layer "In15.Cu")
	)
	(gr_line
		(start 109.542072 -289.964876)
		(end 109.543342 -289.964114)
		(stroke
			(width 0.05715)
			(type default)
		)
		(layer "In15.Cu")
	)
	(gr_line
		(start 109.542072 -288.987484)
		(end 109.540548 -288.986722)
		(stroke
			(width 0.05715)
			(type default)
		)
		(layer "In15.Cu")
	)
	(gr_line
		(start 109.542326 -269.54734)
		(end 109.537754 -269.5448)
		(stroke
			(width 0.05715)
			(type default)
		)
		(layer "In15.Cu")
	)
	(gr_line
		(start 109.54258 -292.228016)
		(end 109.541818 -292.227508)
		(stroke
			(width 0.05715)
			(type default)
		)
		(layer "In15.Cu")
	)
	(gr_line
		(start 109.542834 -288.987992)
		(end 109.542072 -288.987484)
		(stroke
			(width 0.05715)
			(type default)
		)
		(layer "In15.Cu")
	)
	(gr_line
		(start 109.543342 -291.584126)
		(end 109.544104 -291.583618)
		(stroke
			(width 0.05715)
			(type default)
		)
		(layer "In15.Cu")
	)
	(gr_line
		(start 109.543342 -289.964114)
		(end 109.54385 -289.96386)
		(stroke
			(width 0.05715)
			(type default)
		)
		(layer "In15.Cu")
	)
	(gr_line
		(start 109.544104 -290.608766)
		(end 109.543596 -290.608512)
		(stroke
			(width 0.05715)
			(type default)
		)
		(layer "In15.Cu")
	)
	(gr_line
		(start 109.544104 -288.343848)
		(end 109.54385 -288.343594)
		(stroke
			(width 0.05715)
			(type default)
		)
		(layer "In15.Cu")
	)
	(gr_line
		(start 109.544104 -280.888948)
		(end 109.54131 -280.88717)
		(stroke
			(width 0.05715)
			(type default)
		)
		(layer "In15.Cu")
	)
	(gr_line
		(start 109.544104 -269.54861)
		(end 109.543088 -269.547848)
		(stroke
			(width 0.05715)
			(type default)
		)
		(layer "In15.Cu")
	)
	(gr_line
		(start 109.54512 -293.202868)
		(end 109.546898 -293.201852)
		(stroke
			(width 0.05715)
			(type default)
		)
		(layer "In15.Cu")
	)
	(gr_line
		(start 109.549438 -293.200582)
		(end 109.551724 -293.199312)
		(stroke
			(width 0.05715)
			(type default)
		)
		(layer "In15.Cu")
	)
	(gr_line
		(start 109.551216 -269.552674)
		(end 109.549438 -269.551658)
		(stroke
			(width 0.05715)
			(type default)
		)
		(layer "In15.Cu")
	)
	(gr_line
		(start 109.551724 -293.199312)
		(end 109.553248 -293.198296)
		(stroke
			(width 0.05715)
			(type default)
		)
		(layer "In15.Cu")
	)
	(gr_line
		(start 109.551978 -269.553182)
		(end 109.551216 -269.552674)
		(stroke
			(width 0.05715)
			(type default)
		)
		(layer "In15.Cu")
	)
	(gr_arc
		(start 109.55528 -269.555214)
		(mid 109.555788 -269.555468)
		(end 109.556296 -269.555722)
		(stroke
			(width 0.05715)
			(type default)
		)
		(layer "In15.Cu")
	)
	(gr_line
		(start 109.563662 -288.332164)
		(end 109.56671 -288.330132)
		(stroke
			(width 0.05715)
			(type default)
		)
		(layer "In15.Cu")
	)
	(gr_line
		(start 109.564678 -293.860728)
		(end 109.563662 -293.86022)
		(stroke
			(width 0.05715)
			(type default)
		)
		(layer "In15.Cu")
	)
	(gr_line
		(start 109.564678 -280.23185)
		(end 109.56544 -280.231342)
		(stroke
			(width 0.05715)
			(type default)
		)
		(layer "In15.Cu")
	)
	(gr_line
		(start 109.564678 -275.371814)
		(end 109.56544 -275.371306)
		(stroke
			(width 0.05715)
			(type default)
		)
		(layer "In15.Cu")
	)
	(gr_line
		(start 109.56544 -293.861236)
		(end 109.564678 -293.860728)
		(stroke
			(width 0.05715)
			(type default)
		)
		(layer "In15.Cu")
	)
	(gr_line
		(start 109.578902 -282.529026)
		(end 109.575092 -282.52674)
		(stroke
			(width 0.05715)
			(type default)
		)
		(layer "In15.Cu")
	)
	(gr_line
		(start 109.580426 -282.530042)
		(end 109.578902 -282.529026)
		(stroke
			(width 0.05715)
			(type default)
		)
		(layer "In15.Cu")
	)
	(gr_arc
		(start 109.59465 -282.539948)
		(mid 109.587576 -282.53494)
		(end 109.580426 -282.530042)
		(stroke
			(width 0.05715)
			(type default)
		)
		(layer "In15.Cu")
	)
	(gr_line
		(start 109.635544 -287.856422)
		(end 109.635798 -287.856676)
		(stroke
			(width 0.05715)
			(type default)
		)
		(layer "In15.Cu")
	)
	(gr_line
		(start 109.635798 -271.64792)
		(end 109.635798 -271.64665)
		(stroke
			(width 0.05715)
			(type default)
		)
		(layer "In15.Cu")
	)
	(gr_line
		(start 109.639608 -271.69237)
		(end 109.639354 -271.6911)
		(stroke
			(width 0.05715)
			(type default)
		)
		(layer "In15.Cu")
	)
	(gr_line
		(start 109.826298 -286.229806)
		(end 109.826298 -286.23641)
		(stroke
			(width 0.05715)
			(type default)
		)
		(layer "In15.Cu")
	)
	(gr_line
		(start 109.917992 -270.523716)
		(end 109.917992 -270.523462)
		(stroke
			(width 0.05715)
			(type default)
		)
		(layer "In15.Cu")
	)
	(gr_line
		(start 109.918754 -270.524224)
		(end 109.917992 -270.523716)
		(stroke
			(width 0.05715)
			(type default)
		)
		(layer "In15.Cu")
	)
	(gr_line
		(start 110.014004 -270.35887)
		(end 110.013242 -270.358362)
		(stroke
			(width 0.05715)
			(type default)
		)
		(layer "In15.Cu")
	)
	(gr_line
		(start 110.01502 -270.359378)
		(end 110.014004 -270.35887)
		(stroke
			(width 0.05715)
			(type default)
		)
		(layer "In15.Cu")
	)
	(gr_line
		(start 110.017052 -270.360394)
		(end 110.01502 -270.359378)
		(stroke
			(width 0.05715)
			(type default)
		)
		(layer "In15.Cu")
	)
	(gr_line
		(start 110.019084 -270.361664)
		(end 110.018322 -270.361156)
		(stroke
			(width 0.05715)
			(type default)
		)
		(layer "In15.Cu")
	)
	(gr_line
		(start 110.0455 -270.377158)
		(end 110.044738 -270.37665)
		(stroke
			(width 0.05715)
			(type default)
		)
		(layer "In15.Cu")
	)
	(gr_line
		(start 110.046262 -270.377666)
		(end 110.0455 -270.377158)
		(stroke
			(width 0.05715)
			(type default)
		)
		(layer "In15.Cu")
	)
	(gr_line
		(start 110.05312 -270.38173)
		(end 110.046262 -270.377666)
		(stroke
			(width 0.05715)
			(type default)
		)
		(layer "In15.Cu")
	)
	(gr_line
		(start 110.059978 -295.842182)
		(end 110.059978 -295.813734)
		(stroke
			(width 0.05715)
			(type default)
		)
		(layer "In15.Cu")
	)
	(gr_line
		(start 110.059978 -295.813734)
		(end 110.105698 -295.768014)
		(stroke
			(width 0.05715)
			(type default)
		)
		(layer "In15.Cu")
	)
	(gr_arc
		(start 110.060994 -270.387318)
		(mid 110.057069 -270.384507)
		(end 110.05312 -270.38173)
		(stroke
			(width 0.05715)
			(type default)
		)
		(layer "In15.Cu")
	)
	(gr_line
		(start 110.341918 -295.842182)
		(end 110.341918 -295.813734)
		(stroke
			(width 0.05715)
			(type default)
		)
		(layer "In15.Cu")
	)
	(gr_line
		(start 110.341918 -295.813734)
		(end 110.296198 -295.768014)
		(stroke
			(width 0.05715)
			(type default)
		)
		(layer "In15.Cu")
	)
	(gr_arc
		(start 110.34268 -290.74618)
		(mid 110.345088 -290.747965)
		(end 110.347506 -290.749736)
		(stroke
			(width 0.05715)
			(type default)
		)
		(layer "In15.Cu")
	)
	(gr_arc
		(start 110.34268 -276.166326)
		(mid 110.345847 -276.168623)
		(end 110.34903 -276.170898)
		(stroke
			(width 0.05715)
			(type default)
		)
		(layer "In15.Cu")
	)
	(gr_arc
		(start 110.34268 -274.546314)
		(mid 110.345847 -274.548611)
		(end 110.34903 -274.550886)
		(stroke
			(width 0.05715)
			(type default)
		)
		(layer "In15.Cu")
	)
	(gr_arc
		(start 110.347506 -283.342842)
		(mid 110.345088 -283.344614)
		(end 110.34268 -283.346398)
		(stroke
			(width 0.05715)
			(type default)
		)
		(layer "In15.Cu")
	)
	(gr_arc
		(start 110.348268 -283.342334)
		(mid 110.348649 -283.34208)
		(end 110.34903 -283.341826)
		(stroke
			(width 0.05715)
			(type default)
		)
		(layer "In15.Cu")
	)
	(gr_arc
		(start 110.34903 -294.681656)
		(mid 110.34572 -294.683931)
		(end 110.342426 -294.686228)
		(stroke
			(width 0.05715)
			(type default)
		)
		(layer "In15.Cu")
	)
	(gr_line
		(start 110.34903 -283.341826)
		(end 110.349538 -283.341572)
		(stroke
			(width 0.05715)
			(type default)
		)
		(layer "In15.Cu")
	)
	(gr_arc
		(start 110.34903 -276.170898)
		(mid 110.349791 -276.171407)
		(end 110.350554 -276.171914)
		(stroke
			(width 0.05715)
			(type default)
		)
		(layer "In15.Cu")
	)
	(gr_arc
		(start 110.34903 -274.550886)
		(mid 110.349792 -274.551395)
		(end 110.350554 -274.551902)
		(stroke
			(width 0.05715)
			(type default)
		)
		(layer "In15.Cu")
	)
	(gr_line
		(start 110.349538 -283.341572)
		(end 110.358428 -283.336238)
		(stroke
			(width 0.05715)
			(type default)
		)
		(layer "In15.Cu")
	)
	(gr_arc
		(start 110.350554 -294.68064)
		(mid 110.349792 -294.681147)
		(end 110.34903 -294.681656)
		(stroke
			(width 0.05715)
			(type default)
		)
		(layer "In15.Cu")
	)
	(gr_line
		(start 110.350554 -294.68064)
		(end 110.357412 -294.676576)
		(stroke
			(width 0.05715)
			(type default)
		)
		(layer "In15.Cu")
	)
	(gr_line
		(start 110.35665 -274.555458)
		(end 110.350554 -274.551902)
		(stroke
			(width 0.05715)
			(type default)
		)
		(layer "In15.Cu")
	)
	(gr_line
		(start 110.359444 -276.176994)
		(end 110.350554 -276.171914)
		(stroke
			(width 0.05715)
			(type default)
		)
		(layer "In15.Cu")
	)
	(gr_arc
		(start 110.375446 -294.00627)
		(mid 110.377476 -294.007417)
		(end 110.37951 -294.008556)
		(stroke
			(width 0.05715)
			(type default)
		)
		(layer "In15.Cu")
	)
	(gr_line
		(start 110.387892 -293.039038)
		(end 110.388146 -293.038784)
		(stroke
			(width 0.05715)
			(type default)
		)
		(layer "In15.Cu")
	)
	(gr_line
		(start 110.388146 -294.013636)
		(end 110.387892 -294.013636)
		(stroke
			(width 0.05715)
			(type default)
		)
		(layer "In15.Cu")
	)
	(gr_line
		(start 110.3884 -279.434036)
		(end 110.387892 -279.433782)
		(stroke
			(width 0.05715)
			(type default)
		)
		(layer "In15.Cu")
	)
	(gr_line
		(start 110.3884 -276.194012)
		(end 110.387638 -276.193504)
		(stroke
			(width 0.05715)
			(type default)
		)
		(layer "In15.Cu")
	)
	(gr_line
		(start 110.388908 -285.914084)
		(end 110.387892 -285.913576)
		(stroke
			(width 0.05715)
			(type default)
		)
		(layer "In15.Cu")
	)
	(gr_line
		(start 110.38967 -278.463756)
		(end 110.389924 -278.463756)
		(stroke
			(width 0.05715)
			(type default)
		)
		(layer "In15.Cu")
	)
	(gr_arc
		(start 110.428278 -286.534352)
		(mid 110.429168 -286.533591)
		(end 110.430056 -286.532828)
		(stroke
			(width 0.05715)
			(type default)
		)
		(layer "In15.Cu")
	)
	(gr_line
		(start 110.45317 -294.841422)
		(end 110.453424 -294.841422)
		(stroke
			(width 0.05715)
			(type default)
		)
		(layer "In15.Cu")
	)
	(gr_line
		(start 110.453424 -272.770854)
		(end 110.453424 -272.771108)
		(stroke
			(width 0.05715)
			(type default)
		)
		(layer "In15.Cu")
	)
	(gr_line
		(start 110.463076 -279.256744)
		(end 110.461044 -279.255728)
		(stroke
			(width 0.05715)
			(type default)
		)
		(layer "In15.Cu")
	)
	(gr_line
		(start 110.463076 -276.01672)
		(end 110.461044 -276.01545)
		(stroke
			(width 0.05715)
			(type default)
		)
		(layer "In15.Cu")
	)
	(gr_line
		(start 110.4773 -280.247598)
		(end 110.477808 -280.247344)
		(stroke
			(width 0.05715)
			(type default)
		)
		(layer "In15.Cu")
	)
	(gr_line
		(start 110.4773 -277.007574)
		(end 110.477808 -277.00732)
		(stroke
			(width 0.05715)
			(type default)
		)
		(layer "In15.Cu")
	)
	(gr_line
		(start 110.477808 -280.247344)
		(end 110.481872 -280.245058)
		(stroke
			(width 0.05715)
			(type default)
		)
		(layer "In15.Cu")
	)
	(gr_line
		(start 110.477808 -277.00732)
		(end 110.481872 -277.005034)
		(stroke
			(width 0.05715)
			(type default)
		)
		(layer "In15.Cu")
	)
	(gr_line
		(start 110.483904 -280.243788)
		(end 110.484412 -280.24328)
		(stroke
			(width 0.05715)
			(type default)
		)
		(layer "In15.Cu")
	)
	(gr_line
		(start 110.483904 -277.003764)
		(end 110.484412 -277.003256)
		(stroke
			(width 0.05715)
			(type default)
		)
		(layer "In15.Cu")
	)
	(gr_line
		(start 110.484158 -285.749238)
		(end 110.484158 -285.748984)
		(stroke
			(width 0.05715)
			(type default)
		)
		(layer "In15.Cu")
	)
	(gr_line
		(start 110.484158 -285.748984)
		(end 110.483904 -285.748984)
		(stroke
			(width 0.05715)
			(type default)
		)
		(layer "In15.Cu")
	)
	(gr_line
		(start 110.50524 -293.191184)
		(end 110.505494 -293.191184)
		(stroke
			(width 0.05715)
			(type default)
		)
		(layer "In15.Cu")
	)
	(gr_line
		(start 110.515654 -293.185088)
		(end 110.516416 -293.18458)
		(stroke
			(width 0.05715)
			(type default)
		)
		(layer "In15.Cu")
	)
	(gr_line
		(start 110.516416 -293.18458)
		(end 110.52302 -293.18077)
		(stroke
			(width 0.05715)
			(type default)
		)
		(layer "In15.Cu")
	)
	(gr_line
		(start 110.521496 -293.870634)
		(end 110.516162 -293.867586)
		(stroke
			(width 0.05715)
			(type default)
		)
		(layer "In15.Cu")
	)
	(gr_arc
		(start 110.52302 -293.87165)
		(mid 110.522258 -293.871141)
		(end 110.521496 -293.870634)
		(stroke
			(width 0.05715)
			(type default)
		)
		(layer "In15.Cu")
	)
	(gr_arc
		(start 110.52302 -293.18077)
		(mid 110.524164 -293.18001)
		(end 110.525306 -293.179246)
		(stroke
			(width 0.05715)
			(type default)
		)
		(layer "In15.Cu")
	)
	(gr_arc
		(start 110.526068 -293.178738)
		(mid 110.528869 -293.176715)
		(end 110.531656 -293.174674)
		(stroke
			(width 0.05715)
			(type default)
		)
		(layer "In15.Cu")
	)
	(gr_line
		(start 110.528608 -293.87546)
		(end 110.52302 -293.87165)
		(stroke
			(width 0.05715)
			(type default)
		)
		(layer "In15.Cu")
	)
	(gr_arc
		(start 110.5408 -285.06801)
		(mid 110.542453 -285.066743)
		(end 110.544102 -285.06547)
		(stroke
			(width 0.05715)
			(type default)
		)
		(layer "In15.Cu")
	)
	(gr_arc
		(start 110.544102 -285.06547)
		(mid 110.545628 -285.064203)
		(end 110.54715 -285.06293)
		(stroke
			(width 0.05715)
			(type default)
		)
		(layer "In15.Cu")
	)
	(gr_line
		(start 110.573312 -273.232626)
		(end 110.573312 -273.233388)
		(stroke
			(width 0.05715)
			(type default)
		)
		(layer "In15.Cu")
	)
	(gr_line
		(start 110.575344 -292.730174)
		(end 110.575344 -292.729158)
		(stroke
			(width 0.05715)
			(type default)
		)
		(layer "In15.Cu")
	)
	(gr_line
		(start 110.575344 -274.910296)
		(end 110.575344 -274.90928)
		(stroke
			(width 0.05715)
			(type default)
		)
		(layer "In15.Cu")
	)
	(gr_line
		(start 110.575852 -273.276314)
		(end 110.575598 -273.276314)
		(stroke
			(width 0.05715)
			(type default)
		)
		(layer "In15.Cu")
	)
	(gr_arc
		(start 110.765844 -292.737286)
		(mid 110.765983 -292.73373)
		(end 110.766098 -292.730174)
		(stroke
			(width 0.05715)
			(type default)
		)
		(layer "In15.Cu")
	)
	(gr_arc
		(start 110.765844 -274.917408)
		(mid 110.765983 -274.913852)
		(end 110.766098 -274.910296)
		(stroke
			(width 0.05715)
			(type default)
		)
		(layer "In15.Cu")
	)
	(gr_line
		(start 110.766352 -292.716204)
		(end 110.766098 -292.716204)
		(stroke
			(width 0.05715)
			(type default)
		)
		(layer "In15.Cu")
	)
	(gr_line
		(start 110.766352 -274.896326)
		(end 110.766098 -274.896326)
		(stroke
			(width 0.05715)
			(type default)
		)
		(layer "In15.Cu")
	)
	(gr_line
		(start 110.94085 -271.93875)
		(end 110.94085 -271.874488)
		(stroke
			(width 0.05715)
			(type default)
		)
		(layer "In15.Cu")
	)
	(gr_line
		(start 110.960916 -271.958816)
		(end 110.94085 -271.93875)
		(stroke
			(width 0.05715)
			(type default)
		)
		(layer "In15.Cu")
	)
	(gr_line
		(start 111.075978 -271.73936)
		(end 111.075724 -271.738852)
		(stroke
			(width 0.05715)
			(type default)
		)
		(layer "In15.Cu")
	)
	(gr_line
		(start 111.14024 -271.73936)
		(end 111.075978 -271.73936)
		(stroke
			(width 0.05715)
			(type default)
		)
		(layer "In15.Cu")
	)
	(gr_line
		(start 111.160306 -271.759426)
		(end 111.14024 -271.73936)
		(stroke
			(width 0.05715)
			(type default)
		)
		(layer "In15.Cu")
	)
	(gr_line
		(start 114.364262 -367.149634)
		(end 115.065302 -367.149634)
		(stroke
			(width 0.07112)
			(type default)
		)
		(layer "In15.Cu")
	)
	(gr_line
		(start 114.365532 -366.866424)
		(end 114.501422 -366.730534)
		(stroke
			(width 0.07112)
			(type default)
		)
		(layer "In15.Cu")
	)
	(gr_line
		(start 114.501422 -366.730534)
		(end 114.928142 -366.730534)
		(stroke
			(width 0.07112)
			(type default)
		)
		(layer "In15.Cu")
	)
	(gr_line
		(start 114.928142 -366.730534)
		(end 115.064032 -366.866424)
		(stroke
			(width 0.07112)
			(type default)
		)
		(layer "In15.Cu")
	)
	(gr_line
		(start 115.492022 -367.149634)
		(end 116.193062 -367.149634)
		(stroke
			(width 0.07112)
			(type default)
		)
		(layer "In15.Cu")
	)
	(gr_line
		(start 115.493292 -366.866424)
		(end 115.629182 -366.730534)
		(stroke
			(width 0.07112)
			(type default)
		)
		(layer "In15.Cu")
	)
	(gr_line
		(start 115.629182 -366.730534)
		(end 116.055902 -366.730534)
		(stroke
			(width 0.07112)
			(type default)
		)
		(layer "In15.Cu")
	)
	(gr_line
		(start 116.055902 -366.730534)
		(end 116.191792 -366.866424)
		(stroke
			(width 0.07112)
			(type default)
		)
		(layer "In15.Cu")
	)
	(gr_line
		(start 117.467126 -367.149634)
		(end 118.168166 -367.149634)
		(stroke
			(width 0.07112)
			(type default)
		)
		(layer "In15.Cu")
	)
	(gr_line
		(start 117.468396 -366.866424)
		(end 117.604286 -366.730534)
		(stroke
			(width 0.07112)
			(type default)
		)
		(layer "In15.Cu")
	)
	(gr_line
		(start 117.515894 -411.225238)
		(end 117.51564 -411.225238)
		(stroke
			(width 0.07112)
			(type default)
		)
		(layer "In15.Cu")
	)
	(gr_line
		(start 117.604286 -366.730534)
		(end 118.031006 -366.730534)
		(stroke
			(width 0.07112)
			(type default)
		)
		(layer "In15.Cu")
	)
	(gr_line
		(start 118.031006 -366.730534)
		(end 118.166896 -366.866424)
		(stroke
			(width 0.07112)
			(type default)
		)
		(layer "In15.Cu")
	)
	(gr_line
		(start 118.248176 -409.208224)
		(end 118.248176 -408.507184)
		(stroke
			(width 0.07112)
			(type default)
		)
		(layer "In15.Cu")
	)
	(gr_line
		(start 118.248176 -408.080464)
		(end 118.248176 -407.379424)
		(stroke
			(width 0.07112)
			(type default)
		)
		(layer "In15.Cu")
	)
	(gr_line
		(start 118.531386 -409.206954)
		(end 118.667276 -409.071064)
		(stroke
			(width 0.07112)
			(type default)
		)
		(layer "In15.Cu")
	)
	(gr_line
		(start 118.531386 -408.079194)
		(end 118.667276 -407.943304)
		(stroke
			(width 0.07112)
			(type default)
		)
		(layer "In15.Cu")
	)
	(gr_line
		(start 118.667276 -409.071064)
		(end 118.667276 -408.644344)
		(stroke
			(width 0.07112)
			(type default)
		)
		(layer "In15.Cu")
	)
	(gr_line
		(start 118.667276 -408.644344)
		(end 118.531386 -408.508454)
		(stroke
			(width 0.07112)
			(type default)
		)
		(layer "In15.Cu")
	)
	(gr_line
		(start 118.667276 -407.943304)
		(end 118.667276 -407.516584)
		(stroke
			(width 0.07112)
			(type default)
		)
		(layer "In15.Cu")
	)
	(gr_line
		(start 118.667276 -407.516584)
		(end 118.531386 -407.380694)
		(stroke
			(width 0.07112)
			(type default)
		)
		(layer "In15.Cu")
	)
	(gr_line
		(start 118.826026 -415.57321)
		(end 118.633748 -415.57321)
		(stroke
			(width 0.07112)
			(type default)
		)
		(layer "In15.Cu")
	)
	(gr_line
		(start 118.928642 -416.268662)
		(end 118.43258 -415.7726)
		(stroke
			(width 0.07112)
			(type default)
		)
		(layer "In15.Cu")
	)
	(gr_line
		(start 119.128032 -416.067494)
		(end 119.128032 -415.875216)
		(stroke
			(width 0.07112)
			(type default)
		)
		(layer "In15.Cu")
	)
	(gr_line
		(start 119.128032 -415.875216)
		(end 118.826026 -415.57321)
		(stroke
			(width 0.07112)
			(type default)
		)
		(layer "In15.Cu")
	)
	(gr_line
		(start 119.623332 -416.37077)
		(end 119.431308 -416.37077)
		(stroke
			(width 0.07112)
			(type default)
		)
		(layer "In15.Cu")
	)
	(gr_line
		(start 119.725948 -417.065968)
		(end 119.23014 -416.57016)
		(stroke
			(width 0.07112)
			(type default)
		)
		(layer "In15.Cu")
	)
	(gr_line
		(start 119.925338 -416.8648)
		(end 119.925338 -416.672776)
		(stroke
			(width 0.07112)
			(type default)
		)
		(layer "In15.Cu")
	)
	(gr_line
		(start 119.925338 -416.672776)
		(end 119.623332 -416.37077)
		(stroke
			(width 0.07112)
			(type default)
		)
		(layer "In15.Cu")
	)
	(gr_line
		(start 120.420892 -417.168076)
		(end 120.228614 -417.168076)
		(stroke
			(width 0.07112)
			(type default)
		)
		(layer "In15.Cu")
	)
	(gr_line
		(start 120.523508 -417.863528)
		(end 120.027446 -417.367466)
		(stroke
			(width 0.07112)
			(type default)
		)
		(layer "In15.Cu")
	)
	(gr_line
		(start 120.722898 -417.66236)
		(end 120.722898 -417.470082)
		(stroke
			(width 0.07112)
			(type default)
		)
		(layer "In15.Cu")
	)
	(gr_line
		(start 120.722898 -417.470082)
		(end 120.420892 -417.168076)
		(stroke
			(width 0.07112)
			(type default)
		)
		(layer "In15.Cu")
	)
	(gr_line
		(start 120.809258 -413.877252)
		(end 120.61698 -413.877252)
		(stroke
			(width 0.07112)
			(type default)
		)
		(layer "In15.Cu")
	)
	(gr_line
		(start 120.911874 -414.572704)
		(end 120.415812 -414.076642)
		(stroke
			(width 0.07112)
			(type default)
		)
		(layer "In15.Cu")
	)
	(gr_line
		(start 121.111264 -414.371536)
		(end 121.111264 -414.179258)
		(stroke
			(width 0.07112)
			(type default)
		)
		(layer "In15.Cu")
	)
	(gr_line
		(start 121.111264 -414.179258)
		(end 120.809258 -413.877252)
		(stroke
			(width 0.07112)
			(type default)
		)
		(layer "In15.Cu")
	)
	(gr_line
		(start 121.311416 -409.302458)
		(end 121.311416 -408.601418)
		(stroke
			(width 0.07112)
			(type default)
		)
		(layer "In15.Cu")
	)
	(gr_line
		(start 121.311416 -408.105102)
		(end 121.311416 -407.404062)
		(stroke
			(width 0.07112)
			(type default)
		)
		(layer "In15.Cu")
	)
	(gr_line
		(start 121.594626 -409.301188)
		(end 121.730516 -409.165298)
		(stroke
			(width 0.07112)
			(type default)
		)
		(layer "In15.Cu")
	)
	(gr_line
		(start 121.594626 -408.103832)
		(end 121.730516 -407.967942)
		(stroke
			(width 0.07112)
			(type default)
		)
		(layer "In15.Cu")
	)
	(gr_line
		(start 121.606818 -414.674812)
		(end 121.41454 -414.674812)
		(stroke
			(width 0.07112)
			(type default)
		)
		(layer "In15.Cu")
	)
	(gr_line
		(start 121.709434 -415.370264)
		(end 121.213372 -414.874202)
		(stroke
			(width 0.07112)
			(type default)
		)
		(layer "In15.Cu")
	)
	(gr_line
		(start 121.713498 -418.460682)
		(end 121.52122 -418.460682)
		(stroke
			(width 0.07112)
			(type default)
		)
		(layer "In15.Cu")
	)
	(gr_line
		(start 121.730516 -409.165298)
		(end 121.730516 -408.738578)
		(stroke
			(width 0.07112)
			(type default)
		)
		(layer "In15.Cu")
	)
	(gr_line
		(start 121.730516 -408.738578)
		(end 121.594626 -408.602688)
		(stroke
			(width 0.07112)
			(type default)
		)
		(layer "In15.Cu")
	)
	(gr_line
		(start 121.730516 -407.967942)
		(end 121.730516 -407.541222)
		(stroke
			(width 0.07112)
			(type default)
		)
		(layer "In15.Cu")
	)
	(gr_line
		(start 121.730516 -407.541222)
		(end 121.594626 -407.405332)
		(stroke
			(width 0.07112)
			(type default)
		)
		(layer "In15.Cu")
	)
	(gr_line
		(start 121.816114 -419.156134)
		(end 121.320052 -418.660072)
		(stroke
			(width 0.07112)
			(type default)
		)
		(layer "In15.Cu")
	)
	(gr_line
		(start 121.908824 -415.169096)
		(end 121.908824 -414.976818)
		(stroke
			(width 0.07112)
			(type default)
		)
		(layer "In15.Cu")
	)
	(gr_line
		(start 121.908824 -414.976818)
		(end 121.606818 -414.674812)
		(stroke
			(width 0.07112)
			(type default)
		)
		(layer "In15.Cu")
	)
	(gr_line
		(start 122.015504 -418.954966)
		(end 122.015504 -418.762688)
		(stroke
			(width 0.07112)
			(type default)
		)
		(layer "In15.Cu")
	)
	(gr_line
		(start 122.015504 -418.762688)
		(end 121.713498 -418.460682)
		(stroke
			(width 0.07112)
			(type default)
		)
		(layer "In15.Cu")
	)
	(gr_line
		(start 122.404378 -415.472372)
		(end 122.2121 -415.472372)
		(stroke
			(width 0.07112)
			(type default)
		)
		(layer "In15.Cu")
	)
	(gr_line
		(start 122.506994 -416.167824)
		(end 122.010932 -415.671762)
		(stroke
			(width 0.07112)
			(type default)
		)
		(layer "In15.Cu")
	)
	(gr_line
		(start 122.511058 -419.258242)
		(end 122.31878 -419.258242)
		(stroke
			(width 0.07112)
			(type default)
		)
		(layer "In15.Cu")
	)
	(gr_line
		(start 122.613674 -419.953694)
		(end 122.117612 -419.457632)
		(stroke
			(width 0.07112)
			(type default)
		)
		(layer "In15.Cu")
	)
	(gr_line
		(start 122.706384 -415.966656)
		(end 122.706384 -415.774378)
		(stroke
			(width 0.07112)
			(type default)
		)
		(layer "In15.Cu")
	)
	(gr_line
		(start 122.706384 -415.774378)
		(end 122.404378 -415.472372)
		(stroke
			(width 0.07112)
			(type default)
		)
		(layer "In15.Cu")
	)
	(gr_line
		(start 122.813064 -419.752526)
		(end 122.813064 -419.560248)
		(stroke
			(width 0.07112)
			(type default)
		)
		(layer "In15.Cu")
	)
	(gr_line
		(start 122.813064 -419.560248)
		(end 122.511058 -419.258242)
		(stroke
			(width 0.07112)
			(type default)
		)
		(layer "In15.Cu")
	)
	(gr_line
		(start 122.81535 -35.762438)
		(end 122.52452 -36.053268)
		(stroke
			(width 0.07112)
			(type default)
		)
		(layer "In15.Cu")
	)
	(gr_line
		(start 123.09729 -35.762438)
		(end 123.38812 -36.053268)
		(stroke
			(width 0.07112)
			(type default)
		)
		(layer "In15.Cu")
	)
	(gr_line
		(start 123.308364 -420.055802)
		(end 123.11634 -420.055802)
		(stroke
			(width 0.07112)
			(type default)
		)
		(layer "In15.Cu")
	)
	(gr_line
		(start 123.41098 -420.751)
		(end 122.915172 -420.255192)
		(stroke
			(width 0.07112)
			(type default)
		)
		(layer "In15.Cu")
	)
	(gr_line
		(start 123.61037 -420.549832)
		(end 123.61037 -420.357808)
		(stroke
			(width 0.07112)
			(type default)
		)
		(layer "In15.Cu")
	)
	(gr_line
		(start 123.61037 -420.357808)
		(end 123.308364 -420.055802)
		(stroke
			(width 0.07112)
			(type default)
		)
		(layer "In15.Cu")
	)
	(gr_line
		(start 123.698 -34.862008)
		(end 123.672346 -34.872676)
		(stroke
			(width 0.07112)
			(type default)
		)
		(layer "In15.Cu")
	)
	(gr_line
		(start 123.725432 -34.856674)
		(end 123.725432 -34.85642)
		(stroke
			(width 0.07112)
			(type default)
		)
		(layer "In15.Cu")
	)
	(gr_line
		(start 123.725432 -34.85642)
		(end 123.698 -34.862008)
		(stroke
			(width 0.07112)
			(type default)
		)
		(layer "In15.Cu")
	)
	(gr_line
		(start 124.374656 -409.69438)
		(end 124.374656 -408.99334)
		(stroke
			(width 0.07112)
			(type default)
		)
		(layer "In15.Cu")
	)
	(gr_line
		(start 124.374656 -408.56662)
		(end 124.374656 -407.86558)
		(stroke
			(width 0.07112)
			(type default)
		)
		(layer "In15.Cu")
	)
	(gr_line
		(start 124.657866 -409.69311)
		(end 124.793756 -409.55722)
		(stroke
			(width 0.07112)
			(type default)
		)
		(layer "In15.Cu")
	)
	(gr_line
		(start 124.657866 -408.56535)
		(end 124.793756 -408.42946)
		(stroke
			(width 0.07112)
			(type default)
		)
		(layer "In15.Cu")
	)
	(gr_line
		(start 124.793756 -409.55722)
		(end 124.793756 -409.1305)
		(stroke
			(width 0.07112)
			(type default)
		)
		(layer "In15.Cu")
	)
	(gr_line
		(start 124.793756 -409.1305)
		(end 124.657866 -408.99461)
		(stroke
			(width 0.07112)
			(type default)
		)
		(layer "In15.Cu")
	)
	(gr_line
		(start 124.793756 -408.42946)
		(end 124.793756 -408.00274)
		(stroke
			(width 0.07112)
			(type default)
		)
		(layer "In15.Cu")
	)
	(gr_line
		(start 124.793756 -408.00274)
		(end 124.657866 -407.86685)
		(stroke
			(width 0.07112)
			(type default)
		)
		(layer "In15.Cu")
	)
	(gr_line
		(start 124.826014 -402.576284)
		(end 125.474222 -402.308314)
		(stroke
			(width 0.07112)
			(type default)
		)
		(layer "In15.Cu")
	)
	(gr_line
		(start 124.935234 -402.83765)
		(end 125.113034 -402.91131)
		(stroke
			(width 0.07112)
			(type default)
		)
		(layer "In15.Cu")
	)
	(gr_line
		(start 125.113034 -402.91131)
		(end 125.507496 -402.748242)
		(stroke
			(width 0.07112)
			(type default)
		)
		(layer "In15.Cu")
	)
	(gr_line
		(start 125.507496 -402.748242)
		(end 125.581156 -402.570442)
		(stroke
			(width 0.07112)
			(type default)
		)
		(layer "In15.Cu")
	)
	(gr_line
		(start 125.603762 -437.3372)
		(end 125.59919 -437.3372)
		(stroke
			(width 0.07112)
			(type default)
		)
		(layer "In15.Cu")
	)
	(gr_line
		(start 125.749812 -438.089802)
		(end 125.749812 -437.769762)
		(stroke
			(width 0.07112)
			(type default)
		)
		(layer "In15.Cu")
	)
	(gr_line
		(start 125.749812 -437.769762)
		(end 125.60046 -437.62041)
		(stroke
			(width 0.07112)
			(type default)
		)
		(layer "In15.Cu")
	)
	(gr_line
		(start 125.749812 -437.19115)
		(end 125.603762 -437.3372)
		(stroke
			(width 0.07112)
			(type default)
		)
		(layer "In15.Cu")
	)
	(gr_line
		(start 125.749812 -436.889906)
		(end 125.749812 -437.19115)
		(stroke
			(width 0.07112)
			(type default)
		)
		(layer "In15.Cu")
	)
	(gr_line
		(start 126.810516 -400.100546)
		(end 127.449834 -399.811748)
		(stroke
			(width 0.07112)
			(type default)
		)
		(layer "In15.Cu")
	)
	(gr_line
		(start 126.928118 -400.358356)
		(end 127.108204 -400.426174)
		(stroke
			(width 0.07112)
			(type default)
		)
		(layer "In15.Cu")
	)
	(gr_line
		(start 127.108204 -400.426174)
		(end 127.497332 -400.250406)
		(stroke
			(width 0.07112)
			(type default)
		)
		(layer "In15.Cu")
	)
	(gr_line
		(start 127.195326 -415.481262)
		(end 127.003048 -415.481262)
		(stroke
			(width 0.07112)
			(type default)
		)
		(layer "In15.Cu")
	)
	(gr_line
		(start 127.272796 -402.64588)
		(end 127.92329 -402.384006)
		(stroke
			(width 0.07112)
			(type default)
		)
		(layer "In15.Cu")
	)
	(gr_line
		(start 127.297942 -416.176714)
		(end 126.80188 -415.680652)
		(stroke
			(width 0.07112)
			(type default)
		)
		(layer "In15.Cu")
	)
	(gr_line
		(start 127.379476 -402.908262)
		(end 127.556514 -402.9837)
		(stroke
			(width 0.07112)
			(type default)
		)
		(layer "In15.Cu")
	)
	(gr_line
		(start 127.437896 -409.579318)
		(end 127.437896 -408.878278)
		(stroke
			(width 0.07112)
			(type default)
		)
		(layer "In15.Cu")
	)
	(gr_line
		(start 127.437896 -408.451558)
		(end 127.437896 -407.750518)
		(stroke
			(width 0.07112)
			(type default)
		)
		(layer "In15.Cu")
	)
	(gr_line
		(start 127.497332 -415.975546)
		(end 127.497332 -415.783268)
		(stroke
			(width 0.07112)
			(type default)
		)
		(layer "In15.Cu")
	)
	(gr_line
		(start 127.497332 -415.783268)
		(end 127.195326 -415.481262)
		(stroke
			(width 0.07112)
			(type default)
		)
		(layer "In15.Cu")
	)
	(gr_line
		(start 127.497332 -400.250406)
		(end 127.565404 -400.07032)
		(stroke
			(width 0.07112)
			(type default)
		)
		(layer "In15.Cu")
	)
	(gr_line
		(start 127.556514 -402.9837)
		(end 127.952754 -402.824442)
		(stroke
			(width 0.07112)
			(type default)
		)
		(layer "In15.Cu")
	)
	(gr_line
		(start 127.603758 -438.337198)
		(end 127.599186 -438.337198)
		(stroke
			(width 0.07112)
			(type default)
		)
		(layer "In15.Cu")
	)
	(gr_line
		(start 127.721106 -409.578048)
		(end 127.856996 -409.442158)
		(stroke
			(width 0.07112)
			(type default)
		)
		(layer "In15.Cu")
	)
	(gr_line
		(start 127.721106 -408.450288)
		(end 127.856996 -408.314398)
		(stroke
			(width 0.07112)
			(type default)
		)
		(layer "In15.Cu")
	)
	(gr_line
		(start 127.749808 -439.0898)
		(end 127.749808 -438.76976)
		(stroke
			(width 0.07112)
			(type default)
		)
		(layer "In15.Cu")
	)
	(gr_line
		(start 127.749808 -438.76976)
		(end 127.600456 -438.620408)
		(stroke
			(width 0.07112)
			(type default)
		)
		(layer "In15.Cu")
	)
	(gr_line
		(start 127.749808 -438.191148)
		(end 127.603758 -438.337198)
		(stroke
			(width 0.07112)
			(type default)
		)
		(layer "In15.Cu")
	)
	(gr_line
		(start 127.749808 -437.889904)
		(end 127.749808 -438.191148)
		(stroke
			(width 0.07112)
			(type default)
		)
		(layer "In15.Cu")
	)
	(gr_line
		(start 127.856996 -409.442158)
		(end 127.856996 -409.015438)
		(stroke
			(width 0.07112)
			(type default)
		)
		(layer "In15.Cu")
	)
	(gr_line
		(start 127.856996 -409.015438)
		(end 127.721106 -408.879548)
		(stroke
			(width 0.07112)
			(type default)
		)
		(layer "In15.Cu")
	)
	(gr_line
		(start 127.856996 -408.314398)
		(end 127.856996 -407.887678)
		(stroke
			(width 0.07112)
			(type default)
		)
		(layer "In15.Cu")
	)
	(gr_line
		(start 127.856996 -407.887678)
		(end 127.721106 -407.751788)
		(stroke
			(width 0.07112)
			(type default)
		)
		(layer "In15.Cu")
	)
	(gr_line
		(start 127.952754 -402.824442)
		(end 128.027938 -402.647404)
		(stroke
			(width 0.07112)
			(type default)
		)
		(layer "In15.Cu")
	)
	(gr_line
		(start 127.992886 -416.278822)
		(end 127.800608 -416.278822)
		(stroke
			(width 0.07112)
			(type default)
		)
		(layer "In15.Cu")
	)
	(gr_line
		(start 128.095502 -416.974274)
		(end 127.59944 -416.478212)
		(stroke
			(width 0.07112)
			(type default)
		)
		(layer "In15.Cu")
	)
	(gr_line
		(start 128.294892 -416.773106)
		(end 128.294892 -416.580828)
		(stroke
			(width 0.07112)
			(type default)
		)
		(layer "In15.Cu")
	)
	(gr_line
		(start 128.294892 -416.580828)
		(end 127.992886 -416.278822)
		(stroke
			(width 0.07112)
			(type default)
		)
		(layer "In15.Cu")
	)
	(gr_line
		(start 128.694688 -415.117026)
		(end 128.50241 -415.117026)
		(stroke
			(width 0.07112)
			(type default)
		)
		(layer "In15.Cu")
	)
	(gr_line
		(start 128.797304 -415.812478)
		(end 128.301242 -415.316416)
		(stroke
			(width 0.07112)
			(type default)
		)
		(layer "In15.Cu")
	)
	(gr_line
		(start 128.996694 -415.61131)
		(end 128.996694 -415.419032)
		(stroke
			(width 0.07112)
			(type default)
		)
		(layer "In15.Cu")
	)
	(gr_line
		(start 128.996694 -415.419032)
		(end 128.694688 -415.117026)
		(stroke
			(width 0.07112)
			(type default)
		)
		(layer "In15.Cu")
	)
	(gr_line
		(start 129.0701 -25.97912)
		(end 129.0701 -26.65476)
		(stroke
			(width 0.07112)
			(type default)
		)
		(layer "In15.Cu")
	)
	(gr_line
		(start 129.0701 -24.89708)
		(end 129.0701 -25.57272)
		(stroke
			(width 0.07112)
			(type default)
		)
		(layer "In15.Cu")
	)
	(gr_line
		(start 129.35331 -25.98039)
		(end 129.48666 -26.11374)
		(stroke
			(width 0.07112)
			(type default)
		)
		(layer "In15.Cu")
	)
	(gr_line
		(start 129.35331 -24.89835)
		(end 129.48666 -25.0317)
		(stroke
			(width 0.07112)
			(type default)
		)
		(layer "In15.Cu")
	)
	(gr_line
		(start 129.48666 -26.52014)
		(end 129.35331 -26.65349)
		(stroke
			(width 0.07112)
			(type default)
		)
		(layer "In15.Cu")
	)
	(gr_line
		(start 129.48666 -26.11374)
		(end 129.48666 -26.52014)
		(stroke
			(width 0.07112)
			(type default)
		)
		(layer "In15.Cu")
	)
	(gr_line
		(start 129.48666 -25.4381)
		(end 129.35331 -25.57145)
		(stroke
			(width 0.07112)
			(type default)
		)
		(layer "In15.Cu")
	)
	(gr_line
		(start 129.48666 -25.0317)
		(end 129.48666 -25.4381)
		(stroke
			(width 0.07112)
			(type default)
		)
		(layer "In15.Cu")
	)
	(gr_line
		(start 129.491994 -415.914586)
		(end 129.29997 -415.914586)
		(stroke
			(width 0.07112)
			(type default)
		)
		(layer "In15.Cu")
	)
	(gr_line
		(start 129.59461 -416.609784)
		(end 129.098802 -416.113976)
		(stroke
			(width 0.07112)
			(type default)
		)
		(layer "In15.Cu")
	)
	(gr_line
		(start 129.603246 -437.623204)
		(end 129.59969 -437.623204)
		(stroke
			(width 0.07112)
			(type default)
		)
		(layer "In15.Cu")
	)
	(gr_line
		(start 129.749804 -438.089802)
		(end 129.749804 -437.769762)
		(stroke
			(width 0.07112)
			(type default)
		)
		(layer "In15.Cu")
	)
	(gr_line
		(start 129.749804 -437.769762)
		(end 129.603246 -437.623204)
		(stroke
			(width 0.07112)
			(type default)
		)
		(layer "In15.Cu")
	)
	(gr_line
		(start 129.749804 -437.19115)
		(end 129.60096 -437.339994)
		(stroke
			(width 0.07112)
			(type default)
		)
		(layer "In15.Cu")
	)
	(gr_line
		(start 129.749804 -436.889906)
		(end 129.749804 -437.19115)
		(stroke
			(width 0.07112)
			(type default)
		)
		(layer "In15.Cu")
	)
	(gr_line
		(start 129.794 -416.408616)
		(end 129.794 -416.216592)
		(stroke
			(width 0.07112)
			(type default)
		)
		(layer "In15.Cu")
	)
	(gr_line
		(start 129.794 -416.216592)
		(end 129.491994 -415.914586)
		(stroke
			(width 0.07112)
			(type default)
		)
		(layer "In15.Cu")
	)
	(gr_line
		(start 130.501136 -409.497784)
		(end 130.501136 -408.796744)
		(stroke
			(width 0.07112)
			(type default)
		)
		(layer "In15.Cu")
	)
	(gr_line
		(start 130.501136 -408.32659)
		(end 130.501136 -407.62555)
		(stroke
			(width 0.07112)
			(type default)
		)
		(layer "In15.Cu")
	)
	(gr_line
		(start 130.784346 -409.496514)
		(end 130.920236 -409.360624)
		(stroke
			(width 0.07112)
			(type default)
		)
		(layer "In15.Cu")
	)
	(gr_line
		(start 130.784346 -408.32532)
		(end 130.920236 -408.18943)
		(stroke
			(width 0.07112)
			(type default)
		)
		(layer "In15.Cu")
	)
	(gr_line
		(start 130.789172 -419.249606)
		(end 130.789172 -418.548566)
		(stroke
			(width 0.07112)
			(type default)
		)
		(layer "In15.Cu")
	)
	(gr_line
		(start 130.920236 -409.360624)
		(end 130.920236 -408.933904)
		(stroke
			(width 0.07112)
			(type default)
		)
		(layer "In15.Cu")
	)
	(gr_line
		(start 130.920236 -408.933904)
		(end 130.784346 -408.798014)
		(stroke
			(width 0.07112)
			(type default)
		)
		(layer "In15.Cu")
	)
	(gr_line
		(start 130.920236 -408.18943)
		(end 130.920236 -407.76271)
		(stroke
			(width 0.07112)
			(type default)
		)
		(layer "In15.Cu")
	)
	(gr_line
		(start 130.920236 -407.76271)
		(end 130.784346 -407.62682)
		(stroke
			(width 0.07112)
			(type default)
		)
		(layer "In15.Cu")
	)
	(gr_line
		(start 130.958082 -402.236432)
		(end 131.61264 -401.983956)
		(stroke
			(width 0.07112)
			(type default)
		)
		(layer "In15.Cu")
	)
	(gr_line
		(start 131.060952 -402.500084)
		(end 131.236974 -402.578062)
		(stroke
			(width 0.07112)
			(type default)
		)
		(layer "In15.Cu")
	)
	(gr_line
		(start 131.072382 -419.248336)
		(end 131.208272 -419.112446)
		(stroke
			(width 0.07112)
			(type default)
		)
		(layer "In15.Cu")
	)
	(gr_line
		(start 131.208272 -419.112446)
		(end 131.208272 -418.685726)
		(stroke
			(width 0.07112)
			(type default)
		)
		(layer "In15.Cu")
	)
	(gr_line
		(start 131.208272 -418.685726)
		(end 131.072382 -418.549836)
		(stroke
			(width 0.07112)
			(type default)
		)
		(layer "In15.Cu")
	)
	(gr_line
		(start 131.236974 -402.578062)
		(end 131.635246 -402.424646)
		(stroke
			(width 0.07112)
			(type default)
		)
		(layer "In15.Cu")
	)
	(gr_line
		(start 131.423664 -415.36493)
		(end 131.231386 -415.36493)
		(stroke
			(width 0.07112)
			(type default)
		)
		(layer "In15.Cu")
	)
	(gr_line
		(start 131.52628 -416.060382)
		(end 131.030218 -415.56432)
		(stroke
			(width 0.07112)
			(type default)
		)
		(layer "In15.Cu")
	)
	(gr_line
		(start 131.603242 -438.623202)
		(end 131.599686 -438.623202)
		(stroke
			(width 0.07112)
			(type default)
		)
		(layer "In15.Cu")
	)
	(gr_line
		(start 131.635246 -402.424646)
		(end 131.713224 -402.248624)
		(stroke
			(width 0.07112)
			(type default)
		)
		(layer "In15.Cu")
	)
	(gr_line
		(start 131.72567 -415.859214)
		(end 131.72567 -415.666936)
		(stroke
			(width 0.07112)
			(type default)
		)
		(layer "In15.Cu")
	)
	(gr_line
		(start 131.72567 -415.666936)
		(end 131.423664 -415.36493)
		(stroke
			(width 0.07112)
			(type default)
		)
		(layer "In15.Cu")
	)
	(gr_line
		(start 131.7498 -439.0898)
		(end 131.7498 -438.76976)
		(stroke
			(width 0.07112)
			(type default)
		)
		(layer "In15.Cu")
	)
	(gr_line
		(start 131.7498 -438.76976)
		(end 131.603242 -438.623202)
		(stroke
			(width 0.07112)
			(type default)
		)
		(layer "In15.Cu")
	)
	(gr_line
		(start 131.7498 -438.191148)
		(end 131.600956 -438.339992)
		(stroke
			(width 0.07112)
			(type default)
		)
		(layer "In15.Cu")
	)
	(gr_line
		(start 131.7498 -437.889904)
		(end 131.7498 -438.191148)
		(stroke
			(width 0.07112)
			(type default)
		)
		(layer "In15.Cu")
	)
	(gr_line
		(start 132.014722 -18.144744)
		(end 132.305552 -18.435574)
		(stroke
			(width 0.07112)
			(type default)
		)
		(layer "In15.Cu")
	)
	(gr_line
		(start 132.2197 -22.452838)
		(end 132.08635 -22.319488)
		(stroke
			(width 0.07112)
			(type default)
		)
		(layer "In15.Cu")
	)
	(gr_line
		(start 132.221224 -416.16249)
		(end 132.028946 -416.16249)
		(stroke
			(width 0.07112)
			(type default)
		)
		(layer "In15.Cu")
	)
	(gr_line
		(start 132.233162 -401.744688)
		(end 132.887466 -401.492466)
		(stroke
			(width 0.07112)
			(type default)
		)
		(layer "In15.Cu")
	)
	(gr_line
		(start 132.31114 -10.534142)
		(end 132.02031 -10.243312)
		(stroke
			(width 0.07112)
			(type default)
		)
		(layer "In15.Cu")
	)
	(gr_line
		(start 132.32384 -416.857942)
		(end 131.827778 -416.36188)
		(stroke
			(width 0.07112)
			(type default)
		)
		(layer "In15.Cu")
	)
	(gr_line
		(start 132.335778 -402.008594)
		(end 132.5118 -402.086572)
		(stroke
			(width 0.07112)
			(type default)
		)
		(layer "In15.Cu")
	)
	(gr_line
		(start 132.5118 -402.086572)
		(end 132.910326 -401.933156)
		(stroke
			(width 0.07112)
			(type default)
		)
		(layer "In15.Cu")
	)
	(gr_line
		(start 132.52323 -416.656774)
		(end 132.52323 -416.464496)
		(stroke
			(width 0.07112)
			(type default)
		)
		(layer "In15.Cu")
	)
	(gr_line
		(start 132.52323 -416.464496)
		(end 132.221224 -416.16249)
		(stroke
			(width 0.07112)
			(type default)
		)
		(layer "In15.Cu")
	)
	(gr_line
		(start 132.59308 -10.534142)
		(end 132.88391 -10.243312)
		(stroke
			(width 0.07112)
			(type default)
		)
		(layer "In15.Cu")
	)
	(gr_line
		(start 132.6261 -22.452838)
		(end 132.2197 -22.452838)
		(stroke
			(width 0.07112)
			(type default)
		)
		(layer "In15.Cu")
	)
	(gr_line
		(start 132.75945 -22.319488)
		(end 132.6261 -22.452838)
		(stroke
			(width 0.07112)
			(type default)
		)
		(layer "In15.Cu")
	)
	(gr_line
		(start 132.76072 -22.036278)
		(end 132.08508 -22.036278)
		(stroke
			(width 0.07112)
			(type default)
		)
		(layer "In15.Cu")
	)
	(gr_line
		(start 132.8039 -14.619986)
		(end 132.877814 -14.44244)
		(stroke
			(width 0.07112)
			(type default)
		)
		(layer "In15.Cu")
	)
	(gr_line
		(start 132.878322 -18.144744)
		(end 132.587492 -18.435574)
		(stroke
			(width 0.07112)
			(type default)
		)
		(layer "In15.Cu")
	)
	(gr_line
		(start 132.910326 -401.933156)
		(end 132.98805 -401.757134)
		(stroke
			(width 0.07112)
			(type default)
		)
		(layer "In15.Cu")
	)
	(gr_line
		(start 132.966968 -15.014448)
		(end 132.8039 -14.619986)
		(stroke
			(width 0.07112)
			(type default)
		)
		(layer "In15.Cu")
	)
	(gr_line
		(start 133.145022 -15.088362)
		(end 132.966968 -15.014448)
		(stroke
			(width 0.07112)
			(type default)
		)
		(layer "In15.Cu")
	)
	(gr_line
		(start 133.30174 -22.452838)
		(end 133.16839 -22.319488)
		(stroke
			(width 0.07112)
			(type default)
		)
		(layer "In15.Cu")
	)
	(gr_line
		(start 133.30936 -15.483332)
		(end 133.30936 -15.483078)
		(stroke
			(width 0.07112)
			(type default)
		)
		(layer "In15.Cu")
	)
	(gr_line
		(start 133.33095 -15.540228)
		(end 133.33095 -15.537942)
		(stroke
			(width 0.07112)
			(type default)
		)
		(layer "In15.Cu")
	)
	(gr_line
		(start 133.331966 -15.540736)
		(end 133.33095 -15.540228)
		(stroke
			(width 0.07112)
			(type default)
		)
		(layer "In15.Cu")
	)
	(gr_line
		(start 133.40715 -14.98092)
		(end 133.138926 -14.33322)
		(stroke
			(width 0.07112)
			(type default)
		)
		(layer "In15.Cu")
	)
	(gr_line
		(start 133.499098 -401.256754)
		(end 134.153656 -401.004278)
		(stroke
			(width 0.07112)
			(type default)
		)
		(layer "In15.Cu")
	)
	(gr_line
		(start 133.564376 -409.316174)
		(end 133.564376 -408.615134)
		(stroke
			(width 0.07112)
			(type default)
		)
		(layer "In15.Cu")
	)
	(gr_line
		(start 133.564376 -408.188414)
		(end 133.564376 -407.487374)
		(stroke
			(width 0.07112)
			(type default)
		)
		(layer "In15.Cu")
	)
	(gr_line
		(start 133.594094 -15.433294)
		(end 133.591808 -15.42796)
		(stroke
			(width 0.07112)
			(type default)
		)
		(layer "In15.Cu")
	)
	(gr_line
		(start 133.601968 -401.52066)
		(end 133.777736 -401.598384)
		(stroke
			(width 0.07112)
			(type default)
		)
		(layer "In15.Cu")
	)
	(gr_line
		(start 133.603238 -437.623204)
		(end 133.599682 -437.623204)
		(stroke
			(width 0.07112)
			(type default)
		)
		(layer "In15.Cu")
	)
	(gr_line
		(start 133.70814 -22.452838)
		(end 133.30174 -22.452838)
		(stroke
			(width 0.07112)
			(type default)
		)
		(layer "In15.Cu")
	)
	(gr_line
		(start 133.749796 -438.089802)
		(end 133.749796 -437.769762)
		(stroke
			(width 0.07112)
			(type default)
		)
		(layer "In15.Cu")
	)
	(gr_line
		(start 133.749796 -437.769762)
		(end 133.603238 -437.623204)
		(stroke
			(width 0.07112)
			(type default)
		)
		(layer "In15.Cu")
	)
	(gr_line
		(start 133.749796 -437.19115)
		(end 133.600952 -437.339994)
		(stroke
			(width 0.07112)
			(type default)
		)
		(layer "In15.Cu")
	)
	(gr_line
		(start 133.749796 -436.889906)
		(end 133.749796 -437.19115)
		(stroke
			(width 0.07112)
			(type default)
		)
		(layer "In15.Cu")
	)
	(gr_line
		(start 133.777736 -401.598384)
		(end 134.176262 -401.444968)
		(stroke
			(width 0.07112)
			(type default)
		)
		(layer "In15.Cu")
	)
	(gr_line
		(start 133.84149 -22.319488)
		(end 133.70814 -22.452838)
		(stroke
			(width 0.07112)
			(type default)
		)
		(layer "In15.Cu")
	)
	(gr_line
		(start 133.84276 -22.036278)
		(end 133.16712 -22.036278)
		(stroke
			(width 0.07112)
			(type default)
		)
		(layer "In15.Cu")
	)
	(gr_line
		(start 133.847586 -409.314904)
		(end 133.983476 -409.179014)
		(stroke
			(width 0.07112)
			(type default)
		)
		(layer "In15.Cu")
	)
	(gr_line
		(start 133.847586 -408.187144)
		(end 133.983476 -408.051254)
		(stroke
			(width 0.07112)
			(type default)
		)
		(layer "In15.Cu")
	)
	(gr_line
		(start 133.976364 -402.363432)
		(end 134.621016 -402.087334)
		(stroke
			(width 0.07112)
			(type default)
		)
		(layer "In15.Cu")
	)
	(gr_line
		(start 133.983476 -409.179014)
		(end 133.983476 -408.752294)
		(stroke
			(width 0.07112)
			(type default)
		)
		(layer "In15.Cu")
	)
	(gr_line
		(start 133.983476 -408.752294)
		(end 133.847586 -408.616404)
		(stroke
			(width 0.07112)
			(type default)
		)
		(layer "In15.Cu")
	)
	(gr_line
		(start 133.983476 -408.051254)
		(end 133.983476 -407.624534)
		(stroke
			(width 0.07112)
			(type default)
		)
		(layer "In15.Cu")
	)
	(gr_line
		(start 133.983476 -407.624534)
		(end 133.847586 -407.488644)
		(stroke
			(width 0.07112)
			(type default)
		)
		(layer "In15.Cu")
	)
	(gr_line
		(start 134.088632 -402.623528)
		(end 134.267448 -402.694902)
		(stroke
			(width 0.07112)
			(type default)
		)
		(layer "In15.Cu")
	)
	(gr_line
		(start 134.176262 -401.444968)
		(end 134.25424 -401.268946)
		(stroke
			(width 0.07112)
			(type default)
		)
		(layer "In15.Cu")
	)
	(gr_line
		(start 134.259066 -415.766758)
		(end 134.066788 -415.766758)
		(stroke
			(width 0.07112)
			(type default)
		)
		(layer "In15.Cu")
	)
	(gr_line
		(start 134.267448 -402.694902)
		(end 134.659878 -402.527008)
		(stroke
			(width 0.07112)
			(type default)
		)
		(layer "In15.Cu")
	)
	(gr_line
		(start 134.361682 -416.46221)
		(end 133.86562 -415.966148)
		(stroke
			(width 0.07112)
			(type default)
		)
		(layer "In15.Cu")
	)
	(gr_line
		(start 134.376668 -398.625822)
		(end 135.024876 -398.357852)
		(stroke
			(width 0.07112)
			(type default)
		)
		(layer "In15.Cu")
	)
	(gr_line
		(start 134.38378 -22.452838)
		(end 134.25043 -22.319488)
		(stroke
			(width 0.07112)
			(type default)
		)
		(layer "In15.Cu")
	)
	(gr_line
		(start 134.485888 -398.887188)
		(end 134.663688 -398.961102)
		(stroke
			(width 0.07112)
			(type default)
		)
		(layer "In15.Cu")
	)
	(gr_line
		(start 134.561072 -416.261042)
		(end 134.561072 -416.068764)
		(stroke
			(width 0.07112)
			(type default)
		)
		(layer "In15.Cu")
	)
	(gr_line
		(start 134.561072 -416.068764)
		(end 134.259066 -415.766758)
		(stroke
			(width 0.07112)
			(type default)
		)
		(layer "In15.Cu")
	)
	(gr_line
		(start 134.659878 -402.527008)
		(end 134.731506 -402.347938)
		(stroke
			(width 0.07112)
			(type default)
		)
		(layer "In15.Cu")
	)
	(gr_line
		(start 134.663688 -398.961102)
		(end 135.058404 -398.79778)
		(stroke
			(width 0.07112)
			(type default)
		)
		(layer "In15.Cu")
	)
	(gr_line
		(start 134.79018 -22.452838)
		(end 134.38378 -22.452838)
		(stroke
			(width 0.07112)
			(type default)
		)
		(layer "In15.Cu")
	)
	(gr_line
		(start 134.92353 -22.319488)
		(end 134.79018 -22.452838)
		(stroke
			(width 0.07112)
			(type default)
		)
		(layer "In15.Cu")
	)
	(gr_line
		(start 134.9248 -22.036278)
		(end 134.24916 -22.036278)
		(stroke
			(width 0.07112)
			(type default)
		)
		(layer "In15.Cu")
	)
	(gr_line
		(start 135.013192 -401.919186)
		(end 135.657844 -401.643088)
		(stroke
			(width 0.07112)
			(type default)
		)
		(layer "In15.Cu")
	)
	(gr_line
		(start 135.058404 -398.79778)
		(end 135.132064 -398.61998)
		(stroke
			(width 0.07112)
			(type default)
		)
		(layer "In15.Cu")
	)
	(gr_line
		(start 135.12546 -402.179282)
		(end 135.304276 -402.250656)
		(stroke
			(width 0.07112)
			(type default)
		)
		(layer "In15.Cu")
	)
	(gr_line
		(start 135.215376 -400.595084)
		(end 135.869934 -400.342608)
		(stroke
			(width 0.07112)
			(type default)
		)
		(layer "In15.Cu")
	)
	(gr_line
		(start 135.304276 -402.250656)
		(end 135.696706 -402.082762)
		(stroke
			(width 0.07112)
			(type default)
		)
		(layer "In15.Cu")
	)
	(gr_line
		(start 135.318246 -400.85899)
		(end 135.494014 -400.936714)
		(stroke
			(width 0.07112)
			(type default)
		)
		(layer "In15.Cu")
	)
	(gr_line
		(start 135.46582 -22.452838)
		(end 135.33247 -22.319488)
		(stroke
			(width 0.07112)
			(type default)
		)
		(layer "In15.Cu")
	)
	(gr_line
		(start 135.494014 -400.936714)
		(end 135.89254 -400.783298)
		(stroke
			(width 0.07112)
			(type default)
		)
		(layer "In15.Cu")
	)
	(gr_line
		(start 135.52678 -399.322798)
		(end 136.177274 -399.060924)
		(stroke
			(width 0.07112)
			(type default)
		)
		(layer "In15.Cu")
	)
	(gr_line
		(start 135.551164 -398.13992)
		(end 136.199372 -397.87195)
		(stroke
			(width 0.07112)
			(type default)
		)
		(layer "In15.Cu")
	)
	(gr_line
		(start 135.579104 -37.07384)
		(end 135.579104 -36.37534)
		(stroke
			(width 0.07112)
			(type default)
		)
		(layer "In15.Cu")
	)
	(gr_line
		(start 135.579104 -35.95116)
		(end 135.579104 -35.25266)
		(stroke
			(width 0.07112)
			(type default)
		)
		(layer "In15.Cu")
	)
	(gr_line
		(start 135.579104 -34.82848)
		(end 135.579104 -34.15284)
		(stroke
			(width 0.07112)
			(type default)
		)
		(layer "In15.Cu")
	)
	(gr_line
		(start 135.603234 -438.623202)
		(end 135.599678 -438.623202)
		(stroke
			(width 0.07112)
			(type default)
		)
		(layer "In15.Cu")
	)
	(gr_line
		(start 135.633714 -399.58518)
		(end 135.810498 -399.660618)
		(stroke
			(width 0.07112)
			(type default)
		)
		(layer "In15.Cu")
	)
	(gr_line
		(start 135.660384 -398.401286)
		(end 135.838184 -398.4752)
		(stroke
			(width 0.07112)
			(type default)
		)
		(layer "In15.Cu")
	)
	(gr_line
		(start 135.696706 -402.082762)
		(end 135.768334 -401.903692)
		(stroke
			(width 0.07112)
			(type default)
		)
		(layer "In15.Cu")
	)
	(gr_line
		(start 135.70712 -358.977692)
		(end 136.40816 -358.977692)
		(stroke
			(width 0.07112)
			(type default)
		)
		(layer "In15.Cu")
	)
	(gr_line
		(start 135.70839 -358.694482)
		(end 135.84428 -358.558592)
		(stroke
			(width 0.07112)
			(type default)
		)
		(layer "In15.Cu")
	)
	(gr_line
		(start 135.749792 -439.0898)
		(end 135.749792 -438.76976)
		(stroke
			(width 0.07112)
			(type default)
		)
		(layer "In15.Cu")
	)
	(gr_line
		(start 135.749792 -438.76976)
		(end 135.603234 -438.623202)
		(stroke
			(width 0.07112)
			(type default)
		)
		(layer "In15.Cu")
	)
	(gr_line
		(start 135.749792 -438.191148)
		(end 135.600948 -438.339992)
		(stroke
			(width 0.07112)
			(type default)
		)
		(layer "In15.Cu")
	)
	(gr_line
		(start 135.749792 -437.889904)
		(end 135.749792 -438.191148)
		(stroke
			(width 0.07112)
			(type default)
		)
		(layer "In15.Cu")
	)
	(gr_line
		(start 135.805418 -38.037262)
		(end 135.805418 -38.037008)
		(stroke
			(width 0.07112)
			(type default)
		)
		(layer "In15.Cu")
	)
	(gr_line
		(start 135.810498 -399.660618)
		(end 136.206738 -399.501106)
		(stroke
			(width 0.07112)
			(type default)
		)
		(layer "In15.Cu")
	)
	(gr_line
		(start 135.838184 -398.4752)
		(end 136.2329 -398.311878)
		(stroke
			(width 0.07112)
			(type default)
		)
		(layer "In15.Cu")
	)
	(gr_line
		(start 135.84428 -358.558592)
		(end 136.271 -358.558592)
		(stroke
			(width 0.07112)
			(type default)
		)
		(layer "In15.Cu")
	)
	(gr_line
		(start 135.862314 -37.07257)
		(end 135.998204 -36.93668)
		(stroke
			(width 0.07112)
			(type default)
		)
		(layer "In15.Cu")
	)
	(gr_line
		(start 135.862314 -35.94989)
		(end 135.998204 -35.814)
		(stroke
			(width 0.07112)
			(type default)
		)
		(layer "In15.Cu")
	)
	(gr_line
		(start 135.862314 -34.82721)
		(end 135.995664 -34.69386)
		(stroke
			(width 0.07112)
			(type default)
		)
		(layer "In15.Cu")
	)
	(gr_line
		(start 135.87222 -22.452838)
		(end 135.46582 -22.452838)
		(stroke
			(width 0.07112)
			(type default)
		)
		(layer "In15.Cu")
	)
	(gr_line
		(start 135.89254 -400.783298)
		(end 135.970518 -400.607276)
		(stroke
			(width 0.07112)
			(type default)
		)
		(layer "In15.Cu")
	)
	(gr_line
		(start 135.995664 -34.69386)
		(end 135.995664 -34.28746)
		(stroke
			(width 0.07112)
			(type default)
		)
		(layer "In15.Cu")
	)
	(gr_line
		(start 135.995664 -34.28746)
		(end 135.862314 -34.15411)
		(stroke
			(width 0.07112)
			(type default)
		)
		(layer "In15.Cu")
	)
	(gr_line
		(start 135.998204 -36.93668)
		(end 135.998204 -36.5125)
		(stroke
			(width 0.07112)
			(type default)
		)
		(layer "In15.Cu")
	)
	(gr_line
		(start 135.998204 -36.5125)
		(end 135.862314 -36.37661)
		(stroke
			(width 0.07112)
			(type default)
		)
		(layer "In15.Cu")
	)
	(gr_line
		(start 135.998204 -35.814)
		(end 135.998204 -35.38982)
		(stroke
			(width 0.07112)
			(type default)
		)
		(layer "In15.Cu")
	)
	(gr_line
		(start 135.998204 -35.38982)
		(end 135.862314 -35.25393)
		(stroke
			(width 0.07112)
			(type default)
		)
		(layer "In15.Cu")
	)
	(gr_line
		(start 136.00557 -22.319488)
		(end 135.87222 -22.452838)
		(stroke
			(width 0.07112)
			(type default)
		)
		(layer "In15.Cu")
	)
	(gr_line
		(start 136.00684 -22.036278)
		(end 135.3312 -22.036278)
		(stroke
			(width 0.07112)
			(type default)
		)
		(layer "In15.Cu")
	)
	(gr_line
		(start 136.05002 -401.47494)
		(end 136.694672 -401.198842)
		(stroke
			(width 0.07112)
			(type default)
		)
		(layer "In15.Cu")
	)
	(gr_line
		(start 136.162288 -401.735036)
		(end 136.341104 -401.80641)
		(stroke
			(width 0.07112)
			(type default)
		)
		(layer "In15.Cu")
	)
	(gr_line
		(start 136.206738 -399.501106)
		(end 136.281922 -399.324068)
		(stroke
			(width 0.07112)
			(type default)
		)
		(layer "In15.Cu")
	)
	(gr_line
		(start 136.2329 -398.311878)
		(end 136.306814 -398.134078)
		(stroke
			(width 0.07112)
			(type default)
		)
		(layer "In15.Cu")
	)
	(gr_line
		(start 136.271 -358.558592)
		(end 136.40689 -358.694482)
		(stroke
			(width 0.07112)
			(type default)
		)
		(layer "In15.Cu")
	)
	(gr_line
		(start 136.297162 -414.036002)
		(end 136.104884 -414.036002)
		(stroke
			(width 0.07112)
			(type default)
		)
		(layer "In15.Cu")
	)
	(gr_line
		(start 136.341104 -401.80641)
		(end 136.733534 -401.638516)
		(stroke
			(width 0.07112)
			(type default)
		)
		(layer "In15.Cu")
	)
	(gr_line
		(start 136.399778 -414.731454)
		(end 135.903716 -414.235392)
		(stroke
			(width 0.07112)
			(type default)
		)
		(layer "In15.Cu")
	)
	(gr_line
		(start 136.570212 -44.431458)
		(end 136.889998 -43.816778)
		(stroke
			(width 0.07112)
			(type default)
		)
		(layer "In15.Cu")
	)
	(gr_line
		(start 136.599168 -414.530286)
		(end 136.599168 -414.338008)
		(stroke
			(width 0.07112)
			(type default)
		)
		(layer "In15.Cu")
	)
	(gr_line
		(start 136.599168 -414.338008)
		(end 136.297162 -414.036002)
		(stroke
			(width 0.07112)
			(type default)
		)
		(layer "In15.Cu")
	)
	(gr_line
		(start 136.625584 -397.69542)
		(end 137.273792 -397.42745)
		(stroke
			(width 0.07112)
			(type default)
		)
		(layer "In15.Cu")
	)
	(gr_line
		(start 136.627616 -409.444698)
		(end 136.627616 -408.743658)
		(stroke
			(width 0.07112)
			(type default)
		)
		(layer "In15.Cu")
	)
	(gr_line
		(start 136.627616 -408.316938)
		(end 136.627616 -407.615898)
		(stroke
			(width 0.07112)
			(type default)
		)
		(layer "In15.Cu")
	)
	(gr_line
		(start 136.70534 -23.016972)
		(end 136.70534 -22.605492)
		(stroke
			(width 0.07112)
			(type default)
		)
		(layer "In15.Cu")
	)
	(gr_line
		(start 136.733534 -401.638516)
		(end 136.805162 -401.459446)
		(stroke
			(width 0.07112)
			(type default)
		)
		(layer "In15.Cu")
	)
	(gr_line
		(start 136.734804 -397.956786)
		(end 136.912604 -398.030446)
		(stroke
			(width 0.07112)
			(type default)
		)
		(layer "In15.Cu")
	)
	(gr_line
		(start 136.78916 -416.683952)
		(end 136.78916 -415.982912)
		(stroke
			(width 0.07112)
			(type default)
		)
		(layer "In15.Cu")
	)
	(gr_line
		(start 136.820148 -44.561506)
		(end 137.140188 -43.946826)
		(stroke
			(width 0.07112)
			(type default)
		)
		(layer "In15.Cu")
	)
	(gr_line
		(start 136.889998 -43.816778)
		(end 137.202418 -43.21683)
		(stroke
			(width 0.07112)
			(type default)
		)
		(layer "In15.Cu")
	)
	(gr_line
		(start 136.910826 -409.443428)
		(end 137.046716 -409.307538)
		(stroke
			(width 0.07112)
			(type default)
		)
		(layer "In15.Cu")
	)
	(gr_line
		(start 136.910826 -408.315668)
		(end 137.046716 -408.179778)
		(stroke
			(width 0.07112)
			(type default)
		)
		(layer "In15.Cu")
	)
	(gr_line
		(start 136.912604 -398.030446)
		(end 137.307066 -397.867378)
		(stroke
			(width 0.07112)
			(type default)
		)
		(layer "In15.Cu")
	)
	(gr_line
		(start 137.046716 -409.307538)
		(end 137.046716 -408.880818)
		(stroke
			(width 0.07112)
			(type default)
		)
		(layer "In15.Cu")
	)
	(gr_line
		(start 137.046716 -408.880818)
		(end 136.910826 -408.744928)
		(stroke
			(width 0.07112)
			(type default)
		)
		(layer "In15.Cu")
	)
	(gr_line
		(start 137.046716 -408.179778)
		(end 137.046716 -407.753058)
		(stroke
			(width 0.07112)
			(type default)
		)
		(layer "In15.Cu")
	)
	(gr_line
		(start 137.046716 -407.753058)
		(end 136.910826 -407.617168)
		(stroke
			(width 0.07112)
			(type default)
		)
		(layer "In15.Cu")
	)
	(gr_line
		(start 137.07237 -416.682682)
		(end 137.20826 -416.546792)
		(stroke
			(width 0.07112)
			(type default)
		)
		(layer "In15.Cu")
	)
	(gr_line
		(start 137.086848 -401.030694)
		(end 137.731246 -400.754596)
		(stroke
			(width 0.07112)
			(type default)
		)
		(layer "In15.Cu")
	)
	(gr_line
		(start 137.089642 -398.69364)
		(end 137.740644 -398.431512)
		(stroke
			(width 0.07112)
			(type default)
		)
		(layer "In15.Cu")
	)
	(gr_line
		(start 137.141966 -43.946318)
		(end 137.322052 -43.889422)
		(stroke
			(width 0.07112)
			(type default)
		)
		(layer "In15.Cu")
	)
	(gr_line
		(start 137.196576 -398.955768)
		(end 137.373614 -399.031206)
		(stroke
			(width 0.07112)
			(type default)
		)
		(layer "In15.Cu")
	)
	(gr_line
		(start 137.199116 -401.29079)
		(end 137.377932 -401.362164)
		(stroke
			(width 0.07112)
			(type default)
		)
		(layer "In15.Cu")
	)
	(gr_line
		(start 137.20826 -416.546792)
		(end 137.20826 -416.120072)
		(stroke
			(width 0.07112)
			(type default)
		)
		(layer "In15.Cu")
	)
	(gr_line
		(start 137.20826 -416.120072)
		(end 137.07237 -415.984182)
		(stroke
			(width 0.07112)
			(type default)
		)
		(layer "In15.Cu")
	)
	(gr_line
		(start 137.307066 -397.867378)
		(end 137.380726 -397.689578)
		(stroke
			(width 0.07112)
			(type default)
		)
		(layer "In15.Cu")
	)
	(gr_line
		(start 137.31621 -22.406102)
		(end 136.90473 -22.406102)
		(stroke
			(width 0.07112)
			(type default)
		)
		(layer "In15.Cu")
	)
	(gr_line
		(start 137.322052 -43.889422)
		(end 137.509758 -43.528742)
		(stroke
			(width 0.07112)
			(type default)
		)
		(layer "In15.Cu")
	)
	(gr_line
		(start 137.373614 -399.031206)
		(end 137.769854 -398.871948)
		(stroke
			(width 0.07112)
			(type default)
		)
		(layer "In15.Cu")
	)
	(gr_line
		(start 137.377932 -401.362164)
		(end 137.770362 -401.19427)
		(stroke
			(width 0.07112)
			(type default)
		)
		(layer "In15.Cu")
	)
	(gr_line
		(start 137.38987 -42.856658)
		(end 137.702036 -42.257218)
		(stroke
			(width 0.07112)
			(type default)
		)
		(layer "In15.Cu")
	)
	(gr_line
		(start 137.509758 -43.528742)
		(end 137.453116 -43.348656)
		(stroke
			(width 0.07112)
			(type default)
		)
		(layer "In15.Cu")
	)
	(gr_line
		(start 137.55116 -358.977692)
		(end 138.2522 -358.977692)
		(stroke
			(width 0.07112)
			(type default)
		)
		(layer "In15.Cu")
	)
	(gr_line
		(start 137.55243 -358.694482)
		(end 137.68832 -358.558592)
		(stroke
			(width 0.07112)
			(type default)
		)
		(layer "In15.Cu")
	)
	(gr_line
		(start 137.60323 -437.623204)
		(end 137.599674 -437.623204)
		(stroke
			(width 0.07112)
			(type default)
		)
		(layer "In15.Cu")
	)
	(gr_line
		(start 137.622788 -23.985728)
		(end 137.623042 -23.985728)
		(stroke
			(width 0.07112)
			(type default)
		)
		(layer "In15.Cu")
	)
	(gr_line
		(start 137.62863 -23.791926)
		(end 137.623042 -23.984204)
		(stroke
			(width 0.07112)
			(type default)
		)
		(layer "In15.Cu")
	)
	(gr_line
		(start 137.641584 -42.986198)
		(end 137.821924 -42.929556)
		(stroke
			(width 0.07112)
			(type default)
		)
		(layer "In15.Cu")
	)
	(gr_line
		(start 137.68832 -358.558592)
		(end 138.11504 -358.558592)
		(stroke
			(width 0.07112)
			(type default)
		)
		(layer "In15.Cu")
	)
	(gr_line
		(start 137.723372 -402.077174)
		(end 138.378946 -401.827238)
		(stroke
			(width 0.07112)
			(type default)
		)
		(layer "In15.Cu")
	)
	(gr_line
		(start 137.749788 -438.089802)
		(end 137.749788 -437.769762)
		(stroke
			(width 0.07112)
			(type default)
		)
		(layer "In15.Cu")
	)
	(gr_line
		(start 137.749788 -437.769762)
		(end 137.60323 -437.623204)
		(stroke
			(width 0.07112)
			(type default)
		)
		(layer "In15.Cu")
	)
	(gr_line
		(start 137.749788 -437.19115)
		(end 137.600944 -437.339994)
		(stroke
			(width 0.07112)
			(type default)
		)
		(layer "In15.Cu")
	)
	(gr_line
		(start 137.749788 -436.889906)
		(end 137.749788 -437.19115)
		(stroke
			(width 0.07112)
			(type default)
		)
		(layer "In15.Cu")
	)
	(gr_line
		(start 137.769854 -398.871948)
		(end 137.845038 -398.694656)
		(stroke
			(width 0.07112)
			(type default)
		)
		(layer "In15.Cu")
	)
	(gr_line
		(start 137.770362 -401.19427)
		(end 137.84199 -401.0152)
		(stroke
			(width 0.07112)
			(type default)
		)
		(layer "In15.Cu")
	)
	(gr_line
		(start 137.821924 -42.929556)
		(end 138.00963 -42.568876)
		(stroke
			(width 0.07112)
			(type default)
		)
		(layer "In15.Cu")
	)
	(gr_line
		(start 137.825226 -402.341334)
		(end 138.00074 -402.420074)
		(stroke
			(width 0.07112)
			(type default)
		)
		(layer "In15.Cu")
	)
	(gr_line
		(start 137.84326 -31.477712)
		(end 137.84326 -31.477458)
		(stroke
			(width 0.07112)
			(type default)
		)
		(layer "In15.Cu")
	)
	(gr_line
		(start 137.84326 -31.477458)
		(end 137.843514 -31.477458)
		(stroke
			(width 0.07112)
			(type default)
		)
		(layer "In15.Cu")
	)
	(gr_line
		(start 137.843514 -31.477458)
		(end 137.860278 -31.47187)
		(stroke
			(width 0.07112)
			(type default)
		)
		(layer "In15.Cu")
	)
	(gr_line
		(start 137.860278 -31.47187)
		(end 137.875264 -31.468822)
		(stroke
			(width 0.07112)
			(type default)
		)
		(layer "In15.Cu")
	)
	(gr_line
		(start 137.875264 -31.468822)
		(end 137.876788 -31.468568)
		(stroke
			(width 0.07112)
			(type default)
		)
		(layer "In15.Cu")
	)
	(gr_line
		(start 137.876788 -31.468568)
		(end 137.87755 -31.468314)
		(stroke
			(width 0.07112)
			(type default)
		)
		(layer "In15.Cu")
	)
	(gr_line
		(start 137.889488 -41.896792)
		(end 138.201654 -41.297098)
		(stroke
			(width 0.07112)
			(type default)
		)
		(layer "In15.Cu")
	)
	(gr_line
		(start 137.937748 -23.500842)
		(end 137.62863 -23.791926)
		(stroke
			(width 0.07112)
			(type default)
		)
		(layer "In15.Cu")
	)
	(gr_line
		(start 138.00074 -402.420074)
		(end 138.399774 -402.268182)
		(stroke
			(width 0.07112)
			(type default)
		)
		(layer "In15.Cu")
	)
	(gr_line
		(start 138.00963 -42.568876)
		(end 137.952734 -42.38879)
		(stroke
			(width 0.07112)
			(type default)
		)
		(layer "In15.Cu")
	)
	(gr_line
		(start 138.11504 -358.558592)
		(end 138.25093 -358.694482)
		(stroke
			(width 0.07112)
			(type default)
		)
		(layer "In15.Cu")
	)
	(gr_line
		(start 138.129772 -23.506684)
		(end 137.937748 -23.500842)
		(stroke
			(width 0.07112)
			(type default)
		)
		(layer "In15.Cu")
	)
	(gr_line
		(start 138.141456 -42.026332)
		(end 138.321542 -41.96969)
		(stroke
			(width 0.07112)
			(type default)
		)
		(layer "In15.Cu")
	)
	(gr_line
		(start 138.321542 -41.96969)
		(end 138.509248 -41.60901)
		(stroke
			(width 0.07112)
			(type default)
		)
		(layer "In15.Cu")
	)
	(gr_line
		(start 138.325098 -23.711916)
		(end 137.816336 -24.191214)
		(stroke
			(width 0.07112)
			(type default)
		)
		(layer "In15.Cu")
	)
	(gr_line
		(start 138.399774 -402.268182)
		(end 138.478514 -402.092414)
		(stroke
			(width 0.07112)
			(type default)
		)
		(layer "In15.Cu")
	)
	(gr_line
		(start 138.445748 -23.021798)
		(end 138.44016 -23.21433)
		(stroke
			(width 0.07112)
			(type default)
		)
		(layer "In15.Cu")
	)
	(gr_line
		(start 138.509248 -41.60901)
		(end 138.452352 -41.428924)
		(stroke
			(width 0.07112)
			(type default)
		)
		(layer "In15.Cu")
	)
	(gr_line
		(start 138.633708 -31.317946)
		(end 139.296902 -31.18612)
		(stroke
			(width 0.07112)
			(type default)
		)
		(layer "In15.Cu")
	)
	(gr_line
		(start 138.689842 -31.595568)
		(end 138.847068 -31.70047)
		(stroke
			(width 0.07112)
			(type default)
		)
		(layer "In15.Cu")
	)
	(gr_line
		(start 138.754866 -22.730714)
		(end 138.445748 -23.021798)
		(stroke
			(width 0.07112)
			(type default)
		)
		(layer "In15.Cu")
	)
	(gr_line
		(start 138.777472 -401.6756)
		(end 139.433046 -401.425918)
		(stroke
			(width 0.07112)
			(type default)
		)
		(layer "In15.Cu")
	)
	(gr_line
		(start 138.789156 -418.137086)
		(end 138.789156 -417.436046)
		(stroke
			(width 0.07112)
			(type default)
		)
		(layer "In15.Cu")
	)
	(gr_line
		(start 138.789156 -416.683952)
		(end 138.789156 -415.982912)
		(stroke
			(width 0.07112)
			(type default)
		)
		(layer "In15.Cu")
	)
	(gr_line
		(start 138.789156 -415.556192)
		(end 138.789156 -414.855152)
		(stroke
			(width 0.07112)
			(type default)
		)
		(layer "In15.Cu")
	)
	(gr_line
		(start 138.830558 -397.9926)
		(end 139.481052 -397.730726)
		(stroke
			(width 0.07112)
			(type default)
		)
		(layer "In15.Cu")
	)
	(gr_line
		(start 138.847068 -31.70047)
		(end 139.246102 -31.621222)
		(stroke
			(width 0.07112)
			(type default)
		)
		(layer "In15.Cu")
	)
	(gr_line
		(start 138.879326 -401.93976)
		(end 139.05484 -402.0185)
		(stroke
			(width 0.07112)
			(type default)
		)
		(layer "In15.Cu")
	)
	(gr_line
		(start 138.937238 -398.254982)
		(end 139.114276 -398.33042)
		(stroke
			(width 0.07112)
			(type default)
		)
		(layer "In15.Cu")
	)
	(gr_line
		(start 138.947144 -22.736556)
		(end 138.754866 -22.730714)
		(stroke
			(width 0.07112)
			(type default)
		)
		(layer "In15.Cu")
	)
	(gr_line
		(start 139.05484 -402.0185)
		(end 139.453874 -401.866608)
		(stroke
			(width 0.07112)
			(type default)
		)
		(layer "In15.Cu")
	)
	(gr_line
		(start 139.072366 -418.135816)
		(end 139.208256 -417.999926)
		(stroke
			(width 0.07112)
			(type default)
		)
		(layer "In15.Cu")
	)
	(gr_line
		(start 139.072366 -416.682682)
		(end 139.208256 -416.546792)
		(stroke
			(width 0.07112)
			(type default)
		)
		(layer "In15.Cu")
	)
	(gr_line
		(start 139.072366 -415.554922)
		(end 139.208256 -415.419032)
		(stroke
			(width 0.07112)
			(type default)
		)
		(layer "In15.Cu")
	)
	(gr_line
		(start 139.114276 -398.33042)
		(end 139.510516 -398.170908)
		(stroke
			(width 0.07112)
			(type default)
		)
		(layer "In15.Cu")
	)
	(gr_line
		(start 139.142216 -22.942042)
		(end 138.633708 -23.421086)
		(stroke
			(width 0.07112)
			(type default)
		)
		(layer "In15.Cu")
	)
	(gr_line
		(start 139.208256 -417.999926)
		(end 139.208256 -417.573206)
		(stroke
			(width 0.07112)
			(type default)
		)
		(layer "In15.Cu")
	)
	(gr_line
		(start 139.208256 -417.573206)
		(end 139.072366 -417.437316)
		(stroke
			(width 0.07112)
			(type default)
		)
		(layer "In15.Cu")
	)
	(gr_line
		(start 139.208256 -416.546792)
		(end 139.208256 -416.120072)
		(stroke
			(width 0.07112)
			(type default)
		)
		(layer "In15.Cu")
	)
	(gr_line
		(start 139.208256 -416.120072)
		(end 139.072366 -415.984182)
		(stroke
			(width 0.07112)
			(type default)
		)
		(layer "In15.Cu")
	)
	(gr_line
		(start 139.208256 -415.419032)
		(end 139.208256 -414.992312)
		(stroke
			(width 0.07112)
			(type default)
		)
		(layer "In15.Cu")
	)
	(gr_line
		(start 139.208256 -414.992312)
		(end 139.072366 -414.856422)
		(stroke
			(width 0.07112)
			(type default)
		)
		(layer "In15.Cu")
	)
	(gr_line
		(start 139.246102 -31.621222)
		(end 139.35075 -31.463996)
		(stroke
			(width 0.07112)
			(type default)
		)
		(layer "In15.Cu")
	)
	(gr_line
		(start 139.257278 -22.445726)
		(end 139.257532 -22.44598)
		(stroke
			(width 0.07112)
			(type default)
		)
		(layer "In15.Cu")
	)
	(gr_line
		(start 139.26312 -22.251924)
		(end 139.257532 -22.444202)
		(stroke
			(width 0.07112)
			(type default)
		)
		(layer "In15.Cu")
	)
	(gr_line
		(start 139.32662 -358.977692)
		(end 140.02766 -358.977692)
		(stroke
			(width 0.07112)
			(type default)
		)
		(layer "In15.Cu")
	)
	(gr_line
		(start 139.32789 -358.694482)
		(end 139.46378 -358.558592)
		(stroke
			(width 0.07112)
			(type default)
		)
		(layer "In15.Cu")
	)
	(gr_line
		(start 139.351766 -31.462472)
		(end 139.351766 -31.462726)
		(stroke
			(width 0.07112)
			(type default)
		)
		(layer "In15.Cu")
	)
	(gr_line
		(start 139.453874 -401.866608)
		(end 139.532614 -401.69084)
		(stroke
			(width 0.07112)
			(type default)
		)
		(layer "In15.Cu")
	)
	(gr_line
		(start 139.46251 -400.053302)
		(end 140.128244 -399.83283)
		(stroke
			(width 0.07112)
			(type default)
		)
		(layer "In15.Cu")
	)
	(gr_line
		(start 139.46378 -358.558592)
		(end 139.8905 -358.558592)
		(stroke
			(width 0.07112)
			(type default)
		)
		(layer "In15.Cu")
	)
	(gr_line
		(start 139.510516 -398.170908)
		(end 139.5857 -397.99387)
		(stroke
			(width 0.07112)
			(type default)
		)
		(layer "In15.Cu")
	)
	(gr_line
		(start 139.55268 -400.32178)
		(end 139.724638 -400.40814)
		(stroke
			(width 0.07112)
			(type default)
		)
		(layer "In15.Cu")
	)
	(gr_line
		(start 139.572238 -21.96084)
		(end 139.26312 -22.251924)
		(stroke
			(width 0.07112)
			(type default)
		)
		(layer "In15.Cu")
	)
	(gr_line
		(start 139.60348 -438.337452)
		(end 139.599416 -438.337452)
		(stroke
			(width 0.07112)
			(type default)
		)
		(layer "In15.Cu")
	)
	(gr_line
		(start 139.690856 -409.53944)
		(end 139.690856 -408.8384)
		(stroke
			(width 0.07112)
			(type default)
		)
		(layer "In15.Cu")
	)
	(gr_line
		(start 139.690856 -408.41168)
		(end 139.690856 -407.71064)
		(stroke
			(width 0.07112)
			(type default)
		)
		(layer "In15.Cu")
	)
	(gr_line
		(start 139.69492 -402.7551)
		(end 140.339318 -402.479002)
		(stroke
			(width 0.07112)
			(type default)
		)
		(layer "In15.Cu")
	)
	(gr_line
		(start 139.724638 -400.40814)
		(end 140.130022 -400.274028)
		(stroke
			(width 0.07112)
			(type default)
		)
		(layer "In15.Cu")
	)
	(gr_line
		(start 139.749784 -439.0898)
		(end 139.749784 -438.76976)
		(stroke
			(width 0.07112)
			(type default)
		)
		(layer "In15.Cu")
	)
	(gr_line
		(start 139.749784 -438.76976)
		(end 139.600686 -438.620662)
		(stroke
			(width 0.07112)
			(type default)
		)
		(layer "In15.Cu")
	)
	(gr_line
		(start 139.749784 -438.191148)
		(end 139.60348 -438.337452)
		(stroke
			(width 0.07112)
			(type default)
		)
		(layer "In15.Cu")
	)
	(gr_line
		(start 139.749784 -437.889904)
		(end 139.749784 -438.191148)
		(stroke
			(width 0.07112)
			(type default)
		)
		(layer "In15.Cu")
	)
	(gr_line
		(start 139.764262 -21.966682)
		(end 139.572238 -21.96084)
		(stroke
			(width 0.07112)
			(type default)
		)
		(layer "In15.Cu")
	)
	(gr_line
		(start 139.773914 -31.091124)
		(end 139.800838 -31.08579)
		(stroke
			(width 0.07112)
			(type default)
		)
		(layer "In15.Cu")
	)
	(gr_line
		(start 139.800838 -31.08579)
		(end 139.829032 -31.08579)
		(stroke
			(width 0.07112)
			(type default)
		)
		(layer "In15.Cu")
	)
	(gr_line
		(start 139.806934 -403.015196)
		(end 139.986004 -403.08657)
		(stroke
			(width 0.07112)
			(type default)
		)
		(layer "In15.Cu")
	)
	(gr_line
		(start 139.828778 -31.367984)
		(end 139.829032 -31.36773)
		(stroke
			(width 0.07112)
			(type default)
		)
		(layer "In15.Cu")
	)
	(gr_line
		(start 139.831572 -401.274026)
		(end 140.487146 -401.024344)
		(stroke
			(width 0.07112)
			(type default)
		)
		(layer "In15.Cu")
	)
	(gr_line
		(start 139.8905 -358.558592)
		(end 140.02639 -358.694482)
		(stroke
			(width 0.07112)
			(type default)
		)
		(layer "In15.Cu")
	)
	(gr_line
		(start 139.933426 -401.538186)
		(end 140.10894 -401.616926)
		(stroke
			(width 0.07112)
			(type default)
		)
		(layer "In15.Cu")
	)
	(gr_line
		(start 139.959334 -22.171914)
		(end 139.450826 -22.651212)
		(stroke
			(width 0.07112)
			(type default)
		)
		(layer "In15.Cu")
	)
	(gr_line
		(start 139.974066 -409.53817)
		(end 140.109956 -409.40228)
		(stroke
			(width 0.07112)
			(type default)
		)
		(layer "In15.Cu")
	)
	(gr_line
		(start 139.974066 -408.41041)
		(end 140.109956 -408.27452)
		(stroke
			(width 0.07112)
			(type default)
		)
		(layer "In15.Cu")
	)
	(gr_line
		(start 139.986004 -403.08657)
		(end 140.378434 -402.918676)
		(stroke
			(width 0.07112)
			(type default)
		)
		(layer "In15.Cu")
	)
	(gr_line
		(start 140.080238 -21.48205)
		(end 140.07465 -21.674328)
		(stroke
			(width 0.07112)
			(type default)
		)
		(layer "In15.Cu")
	)
	(gr_line
		(start 140.10894 -401.616926)
		(end 140.507974 -401.465034)
		(stroke
			(width 0.07112)
			(type default)
		)
		(layer "In15.Cu")
	)
	(gr_line
		(start 140.109956 -409.40228)
		(end 140.109956 -408.97556)
		(stroke
			(width 0.07112)
			(type default)
		)
		(layer "In15.Cu")
	)
	(gr_line
		(start 140.109956 -408.97556)
		(end 139.974066 -408.83967)
		(stroke
			(width 0.07112)
			(type default)
		)
		(layer "In15.Cu")
	)
	(gr_line
		(start 140.109956 -408.27452)
		(end 140.109956 -407.8478)
		(stroke
			(width 0.07112)
			(type default)
		)
		(layer "In15.Cu")
	)
	(gr_line
		(start 140.109956 -407.8478)
		(end 139.974066 -407.71191)
		(stroke
			(width 0.07112)
			(type default)
		)
		(layer "In15.Cu")
	)
	(gr_line
		(start 140.130022 -400.274028)
		(end 140.216128 -400.10207)
		(stroke
			(width 0.07112)
			(type default)
		)
		(layer "In15.Cu")
	)
	(gr_line
		(start 140.36929 -31.36773)
		(end 140.66012 -31.65856)
		(stroke
			(width 0.07112)
			(type default)
		)
		(layer "In15.Cu")
	)
	(gr_line
		(start 140.36929 -31.08579)
		(end 140.66012 -30.79496)
		(stroke
			(width 0.07112)
			(type default)
		)
		(layer "In15.Cu")
	)
	(gr_line
		(start 140.378434 -402.918676)
		(end 140.449554 -402.73986)
		(stroke
			(width 0.07112)
			(type default)
		)
		(layer "In15.Cu")
	)
	(gr_line
		(start 140.389356 -21.190966)
		(end 140.080238 -21.48205)
		(stroke
			(width 0.07112)
			(type default)
		)
		(layer "In15.Cu")
	)
	(gr_line
		(start 140.507974 -401.465034)
		(end 140.586714 -401.289266)
		(stroke
			(width 0.07112)
			(type default)
		)
		(layer "In15.Cu")
	)
	(gr_line
		(start 140.581634 -21.196554)
		(end 140.389356 -21.190966)
		(stroke
			(width 0.07112)
			(type default)
		)
		(layer "In15.Cu")
	)
	(gr_line
		(start 140.731494 -402.310854)
		(end 141.376146 -402.034502)
		(stroke
			(width 0.07112)
			(type default)
		)
		(layer "In15.Cu")
	)
	(gr_line
		(start 140.776706 -21.40204)
		(end 140.268198 -21.881084)
		(stroke
			(width 0.07112)
			(type default)
		)
		(layer "In15.Cu")
	)
	(gr_line
		(start 140.844016 -402.570696)
		(end 141.022578 -402.64207)
		(stroke
			(width 0.07112)
			(type default)
		)
		(layer "In15.Cu")
	)
	(gr_line
		(start 140.885672 -400.872452)
		(end 141.541246 -400.62277)
		(stroke
			(width 0.07112)
			(type default)
		)
		(layer "In15.Cu")
	)
	(gr_line
		(start 140.987526 -401.136612)
		(end 141.16304 -401.215352)
		(stroke
			(width 0.07112)
			(type default)
		)
		(layer "In15.Cu")
	)
	(gr_line
		(start 141.014704 -18.144744)
		(end 141.305534 -18.435574)
		(stroke
			(width 0.07112)
			(type default)
		)
		(layer "In15.Cu")
	)
	(gr_line
		(start 141.022578 -402.64207)
		(end 141.415008 -402.474176)
		(stroke
			(width 0.07112)
			(type default)
		)
		(layer "In15.Cu")
	)
	(gr_line
		(start 141.068044 -397.153892)
		(end 141.745208 -396.971774)
		(stroke
			(width 0.07112)
			(type default)
		)
		(layer "In15.Cu")
	)
	(gr_line
		(start 141.142466 -397.427196)
		(end 141.309344 -397.523208)
		(stroke
			(width 0.07112)
			(type default)
		)
		(layer "In15.Cu")
	)
	(gr_line
		(start 141.16304 -401.215352)
		(end 141.562074 -401.06346)
		(stroke
			(width 0.07112)
			(type default)
		)
		(layer "In15.Cu")
	)
	(gr_line
		(start 141.222476 -424.292522)
		(end 141.222476 -423.591482)
		(stroke
			(width 0.07112)
			(type default)
		)
		(layer "In15.Cu")
	)
	(gr_line
		(start 141.222476 -423.164762)
		(end 141.222476 -422.463722)
		(stroke
			(width 0.07112)
			(type default)
		)
		(layer "In15.Cu")
	)
	(gr_line
		(start 141.222476 -422.037002)
		(end 141.222476 -421.335962)
		(stroke
			(width 0.07112)
			(type default)
		)
		(layer "In15.Cu")
	)
	(gr_line
		(start 141.222476 -420.681404)
		(end 141.222476 -419.980364)
		(stroke
			(width 0.07112)
			(type default)
		)
		(layer "In15.Cu")
	)
	(gr_line
		(start 141.309344 -397.523208)
		(end 141.721586 -397.412464)
		(stroke
			(width 0.07112)
			(type default)
		)
		(layer "In15.Cu")
	)
	(gr_line
		(start 141.415008 -402.474176)
		(end 141.486636 -402.29536)
		(stroke
			(width 0.07112)
			(type default)
		)
		(layer "In15.Cu")
	)
	(gr_line
		(start 141.505686 -424.291252)
		(end 141.641576 -424.155362)
		(stroke
			(width 0.07112)
			(type default)
		)
		(layer "In15.Cu")
	)
	(gr_line
		(start 141.505686 -423.163492)
		(end 141.641576 -423.027602)
		(stroke
			(width 0.07112)
			(type default)
		)
		(layer "In15.Cu")
	)
	(gr_line
		(start 141.505686 -422.035732)
		(end 141.641576 -421.899842)
		(stroke
			(width 0.07112)
			(type default)
		)
		(layer "In15.Cu")
	)
	(gr_line
		(start 141.505686 -420.680134)
		(end 141.641576 -420.544244)
		(stroke
			(width 0.07112)
			(type default)
		)
		(layer "In15.Cu")
	)
	(gr_line
		(start 141.562074 -401.06346)
		(end 141.640814 -400.887692)
		(stroke
			(width 0.07112)
			(type default)
		)
		(layer "In15.Cu")
	)
	(gr_line
		(start 141.641576 -424.155362)
		(end 141.641576 -423.728642)
		(stroke
			(width 0.07112)
			(type default)
		)
		(layer "In15.Cu")
	)
	(gr_line
		(start 141.641576 -423.728642)
		(end 141.505686 -423.592752)
		(stroke
			(width 0.07112)
			(type default)
		)
		(layer "In15.Cu")
	)
	(gr_line
		(start 141.641576 -423.027602)
		(end 141.641576 -422.600882)
		(stroke
			(width 0.07112)
			(type default)
		)
		(layer "In15.Cu")
	)
	(gr_line
		(start 141.641576 -422.600882)
		(end 141.505686 -422.464992)
		(stroke
			(width 0.07112)
			(type default)
		)
		(layer "In15.Cu")
	)
	(gr_line
		(start 141.641576 -421.899842)
		(end 141.641576 -421.473122)
		(stroke
			(width 0.07112)
			(type default)
		)
		(layer "In15.Cu")
	)
	(gr_line
		(start 141.641576 -421.473122)
		(end 141.505686 -421.337232)
		(stroke
			(width 0.07112)
			(type default)
		)
		(layer "In15.Cu")
	)
	(gr_line
		(start 141.641576 -420.544244)
		(end 141.641576 -420.117524)
		(stroke
			(width 0.07112)
			(type default)
		)
		(layer "In15.Cu")
	)
	(gr_line
		(start 141.641576 -420.117524)
		(end 141.505686 -419.981634)
		(stroke
			(width 0.07112)
			(type default)
		)
		(layer "In15.Cu")
	)
	(gr_line
		(start 141.721586 -397.412464)
		(end 141.817598 -397.245586)
		(stroke
			(width 0.07112)
			(type default)
		)
		(layer "In15.Cu")
	)
	(gr_line
		(start 141.768322 -401.866608)
		(end 142.41272 -401.590256)
		(stroke
			(width 0.07112)
			(type default)
		)
		(layer "In15.Cu")
	)
	(gr_line
		(start 141.84122 -33.4137)
		(end 141.84122 -32.73806)
		(stroke
			(width 0.07112)
			(type default)
		)
		(layer "In15.Cu")
	)
	(gr_line
		(start 141.878304 -18.144744)
		(end 141.587474 -18.435574)
		(stroke
			(width 0.07112)
			(type default)
		)
		(layer "In15.Cu")
	)
	(gr_line
		(start 141.88059 -402.12645)
		(end 142.059406 -402.197824)
		(stroke
			(width 0.07112)
			(type default)
		)
		(layer "In15.Cu")
	)
	(gr_line
		(start 141.939772 -400.470878)
		(end 142.595346 -400.220942)
		(stroke
			(width 0.07112)
			(type default)
		)
		(layer "In15.Cu")
	)
	(gr_line
		(start 142.041626 -400.735038)
		(end 142.21714 -400.813778)
		(stroke
			(width 0.07112)
			(type default)
		)
		(layer "In15.Cu")
	)
	(gr_line
		(start 142.059406 -402.197824)
		(end 142.451836 -402.02993)
		(stroke
			(width 0.07112)
			(type default)
		)
		(layer "In15.Cu")
	)
	(gr_line
		(start 142.12443 -33.41243)
		(end 142.25778 -33.27908)
		(stroke
			(width 0.07112)
			(type default)
		)
		(layer "In15.Cu")
	)
	(gr_line
		(start 142.21714 -400.813778)
		(end 142.616174 -400.661886)
		(stroke
			(width 0.07112)
			(type default)
		)
		(layer "In15.Cu")
	)
	(gr_line
		(start 142.25778 -33.27908)
		(end 142.25778 -32.87268)
		(stroke
			(width 0.07112)
			(type default)
		)
		(layer "In15.Cu")
	)
	(gr_line
		(start 142.25778 -32.87268)
		(end 142.12443 -32.73933)
		(stroke
			(width 0.07112)
			(type default)
		)
		(layer "In15.Cu")
	)
	(gr_line
		(start 142.451836 -402.02993)
		(end 142.523464 -401.851114)
		(stroke
			(width 0.07112)
			(type default)
		)
		(layer "In15.Cu")
	)
	(gr_line
		(start 142.603982 -437.3372)
		(end 142.59941 -437.3372)
		(stroke
			(width 0.07112)
			(type default)
		)
		(layer "In15.Cu")
	)
	(gr_line
		(start 142.616174 -400.661886)
		(end 142.694914 -400.486118)
		(stroke
			(width 0.07112)
			(type default)
		)
		(layer "In15.Cu")
	)
	(gr_line
		(start 142.711932 -347.819218)
		(end 142.711932 -347.819472)
		(stroke
			(width 0.07112)
			(type default)
		)
		(layer "In15.Cu")
	)
	(gr_line
		(start 142.750032 -438.089802)
		(end 142.750032 -437.769762)
		(stroke
			(width 0.07112)
			(type default)
		)
		(layer "In15.Cu")
	)
	(gr_line
		(start 142.750032 -437.769762)
		(end 142.60068 -437.62041)
		(stroke
			(width 0.07112)
			(type default)
		)
		(layer "In15.Cu")
	)
	(gr_line
		(start 142.750032 -437.19115)
		(end 142.603982 -437.3372)
		(stroke
			(width 0.07112)
			(type default)
		)
		(layer "In15.Cu")
	)
	(gr_line
		(start 142.750032 -436.889906)
		(end 142.750032 -437.19115)
		(stroke
			(width 0.07112)
			(type default)
		)
		(layer "In15.Cu")
	)
	(gr_line
		(start 142.754096 -409.569158)
		(end 142.754096 -408.868118)
		(stroke
			(width 0.07112)
			(type default)
		)
		(layer "In15.Cu")
	)
	(gr_line
		(start 142.754096 -408.441398)
		(end 142.754096 -407.740358)
		(stroke
			(width 0.07112)
			(type default)
		)
		(layer "In15.Cu")
	)
	(gr_line
		(start 142.791942 -402.61667)
		(end 143.434816 -402.336254)
		(stroke
			(width 0.07112)
			(type default)
		)
		(layer "In15.Cu")
	)
	(gr_line
		(start 142.855442 -401.400518)
		(end 143.500348 -401.124166)
		(stroke
			(width 0.07112)
			(type default)
		)
		(layer "In15.Cu")
	)
	(gr_line
		(start 142.906242 -402.87575)
		(end 143.085312 -402.946108)
		(stroke
			(width 0.07112)
			(type default)
		)
		(layer "In15.Cu")
	)
	(gr_line
		(start 142.968218 -401.66036)
		(end 143.14678 -401.731988)
		(stroke
			(width 0.07112)
			(type default)
		)
		(layer "In15.Cu")
	)
	(gr_line
		(start 143.037306 -409.567888)
		(end 143.173196 -409.431998)
		(stroke
			(width 0.07112)
			(type default)
		)
		(layer "In15.Cu")
	)
	(gr_line
		(start 143.037306 -408.440128)
		(end 143.173196 -408.304238)
		(stroke
			(width 0.07112)
			(type default)
		)
		(layer "In15.Cu")
	)
	(gr_line
		(start 143.085312 -402.946108)
		(end 143.476726 -402.775674)
		(stroke
			(width 0.07112)
			(type default)
		)
		(layer "In15.Cu")
	)
	(gr_line
		(start 143.110458 -400.024854)
		(end 143.766032 -399.774918)
		(stroke
			(width 0.07112)
			(type default)
		)
		(layer "In15.Cu")
	)
	(gr_line
		(start 143.14678 -401.731988)
		(end 143.53921 -401.56384)
		(stroke
			(width 0.07112)
			(type default)
		)
		(layer "In15.Cu")
	)
	(gr_line
		(start 143.173196 -409.431998)
		(end 143.173196 -409.005278)
		(stroke
			(width 0.07112)
			(type default)
		)
		(layer "In15.Cu")
	)
	(gr_line
		(start 143.173196 -409.005278)
		(end 143.037306 -408.869388)
		(stroke
			(width 0.07112)
			(type default)
		)
		(layer "In15.Cu")
	)
	(gr_line
		(start 143.173196 -408.304238)
		(end 143.173196 -407.877518)
		(stroke
			(width 0.07112)
			(type default)
		)
		(layer "In15.Cu")
	)
	(gr_line
		(start 143.173196 -407.877518)
		(end 143.037306 -407.741628)
		(stroke
			(width 0.07112)
			(type default)
		)
		(layer "In15.Cu")
	)
	(gr_line
		(start 143.212058 -400.289014)
		(end 143.387826 -400.367754)
		(stroke
			(width 0.07112)
			(type default)
		)
		(layer "In15.Cu")
	)
	(gr_line
		(start 143.387826 -400.367754)
		(end 143.78686 -400.215862)
		(stroke
			(width 0.07112)
			(type default)
		)
		(layer "In15.Cu")
	)
	(gr_line
		(start 143.434816 -402.336254)
		(end 143.43507 -402.336254)
		(stroke
			(width 0.07112)
			(type default)
		)
		(layer "In15.Cu")
	)
	(gr_line
		(start 143.476726 -402.775674)
		(end 143.547084 -402.59635)
		(stroke
			(width 0.07112)
			(type default)
		)
		(layer "In15.Cu")
	)
	(gr_line
		(start 143.53921 -401.56384)
		(end 143.610838 -401.385024)
		(stroke
			(width 0.07112)
			(type default)
		)
		(layer "In15.Cu")
	)
	(gr_line
		(start 143.71066 -359.950258)
		(end 144.4117 -359.950258)
		(stroke
			(width 0.07112)
			(type default)
		)
		(layer "In15.Cu")
	)
	(gr_line
		(start 143.71193 -359.667048)
		(end 143.84782 -359.531158)
		(stroke
			(width 0.07112)
			(type default)
		)
		(layer "In15.Cu")
	)
	(gr_line
		(start 143.78686 -400.215862)
		(end 143.8656 -400.040094)
		(stroke
			(width 0.07112)
			(type default)
		)
		(layer "In15.Cu")
	)
	(gr_line
		(start 143.789146 -418.91966)
		(end 143.789146 -418.21862)
		(stroke
			(width 0.07112)
			(type default)
		)
		(layer "In15.Cu")
	)
	(gr_line
		(start 143.789146 -417.7919)
		(end 143.789146 -417.09086)
		(stroke
			(width 0.07112)
			(type default)
		)
		(layer "In15.Cu")
	)
	(gr_line
		(start 143.825722 -402.16582)
		(end 144.468596 -401.885404)
		(stroke
			(width 0.07112)
			(type default)
		)
		(layer "In15.Cu")
	)
	(gr_line
		(start 143.84782 -359.531158)
		(end 144.27454 -359.531158)
		(stroke
			(width 0.07112)
			(type default)
		)
		(layer "In15.Cu")
	)
	(gr_line
		(start 143.892524 -400.956272)
		(end 144.536922 -400.67992)
		(stroke
			(width 0.07112)
			(type default)
		)
		(layer "In15.Cu")
	)
	(gr_line
		(start 143.940022 -402.4249)
		(end 144.119092 -402.495258)
		(stroke
			(width 0.07112)
			(type default)
		)
		(layer "In15.Cu")
	)
	(gr_line
		(start 144.004792 -401.216114)
		(end 144.183608 -401.287488)
		(stroke
			(width 0.07112)
			(type default)
		)
		(layer "In15.Cu")
	)
	(gr_line
		(start 144.072356 -418.91839)
		(end 144.208246 -418.7825)
		(stroke
			(width 0.07112)
			(type default)
		)
		(layer "In15.Cu")
	)
	(gr_line
		(start 144.072356 -417.79063)
		(end 144.208246 -417.65474)
		(stroke
			(width 0.07112)
			(type default)
		)
		(layer "In15.Cu")
	)
	(gr_line
		(start 144.119092 -402.495258)
		(end 144.510506 -402.324824)
		(stroke
			(width 0.07112)
			(type default)
		)
		(layer "In15.Cu")
	)
	(gr_line
		(start 144.183608 -401.287488)
		(end 144.576038 -401.119594)
		(stroke
			(width 0.07112)
			(type default)
		)
		(layer "In15.Cu")
	)
	(gr_line
		(start 144.208246 -418.7825)
		(end 144.208246 -418.35578)
		(stroke
			(width 0.07112)
			(type default)
		)
		(layer "In15.Cu")
	)
	(gr_line
		(start 144.208246 -418.35578)
		(end 144.072356 -418.21989)
		(stroke
			(width 0.07112)
			(type default)
		)
		(layer "In15.Cu")
	)
	(gr_line
		(start 144.208246 -417.65474)
		(end 144.208246 -417.22802)
		(stroke
			(width 0.07112)
			(type default)
		)
		(layer "In15.Cu")
	)
	(gr_line
		(start 144.208246 -417.22802)
		(end 144.072356 -417.09213)
		(stroke
			(width 0.07112)
			(type default)
		)
		(layer "In15.Cu")
	)
	(gr_line
		(start 144.27454 -359.531158)
		(end 144.41043 -359.667048)
		(stroke
			(width 0.07112)
			(type default)
		)
		(layer "In15.Cu")
	)
	(gr_line
		(start 144.510506 -402.324824)
		(end 144.580864 -402.1455)
		(stroke
			(width 0.07112)
			(type default)
		)
		(layer "In15.Cu")
	)
	(gr_line
		(start 144.576038 -401.119594)
		(end 144.647666 -400.940524)
		(stroke
			(width 0.07112)
			(type default)
		)
		(layer "In15.Cu")
	)
	(gr_line
		(start 144.60347 -438.623202)
		(end 144.599914 -438.623202)
		(stroke
			(width 0.07112)
			(type default)
		)
		(layer "In15.Cu")
	)
	(gr_line
		(start 144.70761 -31.38551)
		(end 144.99844 -31.67634)
		(stroke
			(width 0.07112)
			(type default)
		)
		(layer "In15.Cu")
	)
	(gr_line
		(start 144.70761 -31.10357)
		(end 144.99844 -30.81274)
		(stroke
			(width 0.07112)
			(type default)
		)
		(layer "In15.Cu")
	)
	(gr_line
		(start 144.750028 -439.0898)
		(end 144.750028 -438.76976)
		(stroke
			(width 0.07112)
			(type default)
		)
		(layer "In15.Cu")
	)
	(gr_line
		(start 144.750028 -438.76976)
		(end 144.60347 -438.623202)
		(stroke
			(width 0.07112)
			(type default)
		)
		(layer "In15.Cu")
	)
	(gr_line
		(start 144.750028 -438.191148)
		(end 144.601184 -438.339992)
		(stroke
			(width 0.07112)
			(type default)
		)
		(layer "In15.Cu")
	)
	(gr_line
		(start 144.750028 -437.889904)
		(end 144.750028 -438.191148)
		(stroke
			(width 0.07112)
			(type default)
		)
		(layer "In15.Cu")
	)
	(gr_line
		(start 144.83842 -359.950258)
		(end 145.53946 -359.950258)
		(stroke
			(width 0.07112)
			(type default)
		)
		(layer "In15.Cu")
	)
	(gr_line
		(start 144.83969 -359.667048)
		(end 144.97558 -359.531158)
		(stroke
			(width 0.07112)
			(type default)
		)
		(layer "In15.Cu")
	)
	(gr_line
		(start 144.859502 -401.71497)
		(end 145.502376 -401.434554)
		(stroke
			(width 0.07112)
			(type default)
		)
		(layer "In15.Cu")
	)
	(gr_line
		(start 144.973802 -401.97405)
		(end 145.152872 -402.044408)
		(stroke
			(width 0.07112)
			(type default)
		)
		(layer "In15.Cu")
	)
	(gr_line
		(start 144.97558 -359.531158)
		(end 145.4023 -359.531158)
		(stroke
			(width 0.07112)
			(type default)
		)
		(layer "In15.Cu")
	)
	(gr_line
		(start 145.152872 -402.044408)
		(end 145.544286 -401.873974)
		(stroke
			(width 0.07112)
			(type default)
		)
		(layer "In15.Cu")
	)
	(gr_line
		(start 145.4023 -359.531158)
		(end 145.53819 -359.667048)
		(stroke
			(width 0.07112)
			(type default)
		)
		(layer "In15.Cu")
	)
	(gr_line
		(start 145.544286 -401.873974)
		(end 145.61439 -401.69465)
		(stroke
			(width 0.07112)
			(type default)
		)
		(layer "In15.Cu")
	)
	(gr_line
		(start 145.789142 -420.50843)
		(end 145.789142 -419.80739)
		(stroke
			(width 0.07112)
			(type default)
		)
		(layer "In15.Cu")
	)
	(gr_line
		(start 145.789142 -419.38067)
		(end 145.789142 -418.67963)
		(stroke
			(width 0.07112)
			(type default)
		)
		(layer "In15.Cu")
	)
	(gr_line
		(start 145.817336 -409.360878)
		(end 145.817336 -408.659838)
		(stroke
			(width 0.07112)
			(type default)
		)
		(layer "In15.Cu")
	)
	(gr_line
		(start 145.817336 -408.233118)
		(end 145.817336 -407.532078)
		(stroke
			(width 0.07112)
			(type default)
		)
		(layer "In15.Cu")
	)
	(gr_line
		(start 146.072352 -420.50716)
		(end 146.208242 -420.37127)
		(stroke
			(width 0.07112)
			(type default)
		)
		(layer "In15.Cu")
	)
	(gr_line
		(start 146.072352 -419.3794)
		(end 146.208242 -419.24351)
		(stroke
			(width 0.07112)
			(type default)
		)
		(layer "In15.Cu")
	)
	(gr_line
		(start 146.100546 -409.359608)
		(end 146.236436 -409.223718)
		(stroke
			(width 0.07112)
			(type default)
		)
		(layer "In15.Cu")
	)
	(gr_line
		(start 146.100546 -408.231848)
		(end 146.236436 -408.095958)
		(stroke
			(width 0.07112)
			(type default)
		)
		(layer "In15.Cu")
	)
	(gr_line
		(start 146.17954 -359.950258)
		(end 146.88058 -359.950258)
		(stroke
			(width 0.07112)
			(type default)
		)
		(layer "In15.Cu")
	)
	(gr_line
		(start 146.18081 -359.667048)
		(end 146.3167 -359.531158)
		(stroke
			(width 0.07112)
			(type default)
		)
		(layer "In15.Cu")
	)
	(gr_line
		(start 146.208242 -420.37127)
		(end 146.208242 -419.94455)
		(stroke
			(width 0.07112)
			(type default)
		)
		(layer "In15.Cu")
	)
	(gr_line
		(start 146.208242 -419.94455)
		(end 146.072352 -419.80866)
		(stroke
			(width 0.07112)
			(type default)
		)
		(layer "In15.Cu")
	)
	(gr_line
		(start 146.208242 -419.24351)
		(end 146.208242 -418.81679)
		(stroke
			(width 0.07112)
			(type default)
		)
		(layer "In15.Cu")
	)
	(gr_line
		(start 146.208242 -418.81679)
		(end 146.072352 -418.6809)
		(stroke
			(width 0.07112)
			(type default)
		)
		(layer "In15.Cu")
	)
	(gr_line
		(start 146.236436 -409.223718)
		(end 146.236436 -408.796998)
		(stroke
			(width 0.07112)
			(type default)
		)
		(layer "In15.Cu")
	)
	(gr_line
		(start 146.236436 -408.796998)
		(end 146.100546 -408.661108)
		(stroke
			(width 0.07112)
			(type default)
		)
		(layer "In15.Cu")
	)
	(gr_line
		(start 146.236436 -408.095958)
		(end 146.236436 -407.669238)
		(stroke
			(width 0.07112)
			(type default)
		)
		(layer "In15.Cu")
	)
	(gr_line
		(start 146.236436 -407.669238)
		(end 146.100546 -407.533348)
		(stroke
			(width 0.07112)
			(type default)
		)
		(layer "In15.Cu")
	)
	(gr_line
		(start 146.3167 -359.531158)
		(end 146.74342 -359.531158)
		(stroke
			(width 0.07112)
			(type default)
		)
		(layer "In15.Cu")
	)
	(gr_line
		(start 146.511264 -402.310092)
		(end 147.158964 -402.041614)
		(stroke
			(width 0.07112)
			(type default)
		)
		(layer "In15.Cu")
	)
	(gr_line
		(start 146.603466 -437.623204)
		(end 146.59991 -437.623204)
		(stroke
			(width 0.07112)
			(type default)
		)
		(layer "In15.Cu")
	)
	(gr_line
		(start 146.620738 -402.571204)
		(end 146.798284 -402.645118)
		(stroke
			(width 0.07112)
			(type default)
		)
		(layer "In15.Cu")
	)
	(gr_line
		(start 146.74342 -359.531158)
		(end 146.87931 -359.667048)
		(stroke
			(width 0.07112)
			(type default)
		)
		(layer "In15.Cu")
	)
	(gr_line
		(start 146.750024 -438.089802)
		(end 146.750024 -437.769762)
		(stroke
			(width 0.07112)
			(type default)
		)
		(layer "In15.Cu")
	)
	(gr_line
		(start 146.750024 -437.769762)
		(end 146.603466 -437.623204)
		(stroke
			(width 0.07112)
			(type default)
		)
		(layer "In15.Cu")
	)
	(gr_line
		(start 146.750024 -437.19115)
		(end 146.60118 -437.339994)
		(stroke
			(width 0.07112)
			(type default)
		)
		(layer "In15.Cu")
	)
	(gr_line
		(start 146.750024 -436.889906)
		(end 146.750024 -437.19115)
		(stroke
			(width 0.07112)
			(type default)
		)
		(layer "In15.Cu")
	)
	(gr_line
		(start 146.798284 -402.645118)
		(end 147.192746 -402.481542)
		(stroke
			(width 0.07112)
			(type default)
		)
		(layer "In15.Cu")
	)
	(gr_line
		(start 146.982688 -400.85137)
		(end 147.65655 -400.656044)
		(stroke
			(width 0.07112)
			(type default)
		)
		(layer "In15.Cu")
	)
	(gr_line
		(start 147.062698 -401.12315)
		(end 147.231354 -401.216114)
		(stroke
			(width 0.07112)
			(type default)
		)
		(layer "In15.Cu")
	)
	(gr_line
		(start 147.153376 -393.002008)
		(end 147.444206 -393.292838)
		(stroke
			(width 0.07112)
			(type default)
		)
		(layer "In15.Cu")
	)
	(gr_line
		(start 147.153376 -392.720068)
		(end 147.444206 -392.429238)
		(stroke
			(width 0.07112)
			(type default)
		)
		(layer "In15.Cu")
	)
	(gr_line
		(start 147.192746 -402.481542)
		(end 147.266152 -402.303742)
		(stroke
			(width 0.07112)
			(type default)
		)
		(layer "In15.Cu")
	)
	(gr_line
		(start 147.231354 -401.216114)
		(end 147.641564 -401.097242)
		(stroke
			(width 0.07112)
			(type default)
		)
		(layer "In15.Cu")
	)
	(gr_line
		(start 147.621244 -401.850098)
		(end 148.268944 -401.58162)
		(stroke
			(width 0.07112)
			(type default)
		)
		(layer "In15.Cu")
	)
	(gr_line
		(start 147.641564 -401.097242)
		(end 147.734274 -400.928332)
		(stroke
			(width 0.07112)
			(type default)
		)
		(layer "In15.Cu")
	)
	(gr_line
		(start 147.730718 -402.11121)
		(end 147.908264 -402.185124)
		(stroke
			(width 0.07112)
			(type default)
		)
		(layer "In15.Cu")
	)
	(gr_line
		(start 147.789138 -419.205664)
		(end 147.789138 -418.504624)
		(stroke
			(width 0.07112)
			(type default)
		)
		(layer "In15.Cu")
	)
	(gr_line
		(start 147.908264 -402.185124)
		(end 148.302726 -402.021548)
		(stroke
			(width 0.07112)
			(type default)
		)
		(layer "In15.Cu")
	)
	(gr_line
		(start 148.072348 -419.204394)
		(end 148.208238 -419.068504)
		(stroke
			(width 0.07112)
			(type default)
		)
		(layer "In15.Cu")
	)
	(gr_line
		(start 148.208238 -419.068504)
		(end 148.208238 -418.641784)
		(stroke
			(width 0.07112)
			(type default)
		)
		(layer "In15.Cu")
	)
	(gr_line
		(start 148.208238 -418.641784)
		(end 148.072348 -418.505894)
		(stroke
			(width 0.07112)
			(type default)
		)
		(layer "In15.Cu")
	)
	(gr_line
		(start 148.302726 -402.021548)
		(end 148.376132 -401.843748)
		(stroke
			(width 0.07112)
			(type default)
		)
		(layer "In15.Cu")
	)
	(gr_line
		(start 148.433282 -416.612832)
		(end 148.929344 -416.11677)
		(stroke
			(width 0.07112)
			(type default)
		)
		(layer "In15.Cu")
	)
	(gr_line
		(start 148.505672 -393.017756)
		(end 148.517102 -393.017756)
		(stroke
			(width 0.07112)
			(type default)
		)
		(layer "In15.Cu")
	)
	(gr_line
		(start 148.506942 -392.734546)
		(end 148.644102 -392.597386)
		(stroke
			(width 0.07112)
			(type default)
		)
		(layer "In15.Cu")
	)
	(gr_line
		(start 148.517102 -393.017756)
		(end 148.644102 -393.144756)
		(stroke
			(width 0.07112)
			(type default)
		)
		(layer "In15.Cu")
	)
	(gr_line
		(start 148.603462 -438.623202)
		(end 148.599906 -438.623202)
		(stroke
			(width 0.07112)
			(type default)
		)
		(layer "In15.Cu")
	)
	(gr_line
		(start 148.63445 -416.812222)
		(end 148.826728 -416.812222)
		(stroke
			(width 0.07112)
			(type default)
		)
		(layer "In15.Cu")
	)
	(gr_line
		(start 148.644102 -393.144756)
		(end 148.644102 -393.292838)
		(stroke
			(width 0.07112)
			(type default)
		)
		(layer "In15.Cu")
	)
	(gr_line
		(start 148.644102 -392.597386)
		(end 148.644102 -392.429238)
		(stroke
			(width 0.07112)
			(type default)
		)
		(layer "In15.Cu")
	)
	(gr_line
		(start 148.75002 -439.0898)
		(end 148.75002 -438.76976)
		(stroke
			(width 0.07112)
			(type default)
		)
		(layer "In15.Cu")
	)
	(gr_line
		(start 148.75002 -438.76976)
		(end 148.603462 -438.623202)
		(stroke
			(width 0.07112)
			(type default)
		)
		(layer "In15.Cu")
	)
	(gr_line
		(start 148.75002 -438.191148)
		(end 148.601176 -438.339992)
		(stroke
			(width 0.07112)
			(type default)
		)
		(layer "In15.Cu")
	)
	(gr_line
		(start 148.75002 -437.889904)
		(end 148.75002 -438.191148)
		(stroke
			(width 0.07112)
			(type default)
		)
		(layer "In15.Cu")
	)
	(gr_line
		(start 148.826728 -416.812222)
		(end 149.128734 -416.510216)
		(stroke
			(width 0.07112)
			(type default)
		)
		(layer "In15.Cu")
	)
	(gr_line
		(start 148.880576 -409.415234)
		(end 148.880576 -408.714194)
		(stroke
			(width 0.07112)
			(type default)
		)
		(layer "In15.Cu")
	)
	(gr_line
		(start 148.880576 -408.287474)
		(end 148.880576 -407.586434)
		(stroke
			(width 0.07112)
			(type default)
		)
		(layer "In15.Cu")
	)
	(gr_line
		(start 149.11197 -402.410676)
		(end 149.75967 -402.142198)
		(stroke
			(width 0.07112)
			(type default)
		)
		(layer "In15.Cu")
	)
	(gr_line
		(start 149.128734 -416.510216)
		(end 149.128734 -416.317938)
		(stroke
			(width 0.07112)
			(type default)
		)
		(layer "In15.Cu")
	)
	(gr_line
		(start 149.163786 -409.413964)
		(end 149.299676 -409.278074)
		(stroke
			(width 0.07112)
			(type default)
		)
		(layer "In15.Cu")
	)
	(gr_line
		(start 149.163786 -408.286204)
		(end 149.299676 -408.150314)
		(stroke
			(width 0.07112)
			(type default)
		)
		(layer "In15.Cu")
	)
	(gr_line
		(start 149.221444 -402.671788)
		(end 149.39899 -402.745702)
		(stroke
			(width 0.07112)
			(type default)
		)
		(layer "In15.Cu")
	)
	(gr_line
		(start 149.230842 -415.815272)
		(end 149.726904 -415.31921)
		(stroke
			(width 0.07112)
			(type default)
		)
		(layer "In15.Cu")
	)
	(gr_line
		(start 149.299676 -409.278074)
		(end 149.299676 -408.851354)
		(stroke
			(width 0.07112)
			(type default)
		)
		(layer "In15.Cu")
	)
	(gr_line
		(start 149.299676 -408.851354)
		(end 149.163786 -408.715464)
		(stroke
			(width 0.07112)
			(type default)
		)
		(layer "In15.Cu")
	)
	(gr_line
		(start 149.299676 -408.150314)
		(end 149.299676 -407.723594)
		(stroke
			(width 0.07112)
			(type default)
		)
		(layer "In15.Cu")
	)
	(gr_line
		(start 149.299676 -407.723594)
		(end 149.163786 -407.587704)
		(stroke
			(width 0.07112)
			(type default)
		)
		(layer "In15.Cu")
	)
	(gr_line
		(start 149.39899 -402.745702)
		(end 149.793452 -402.58238)
		(stroke
			(width 0.07112)
			(type default)
		)
		(layer "In15.Cu")
	)
	(gr_line
		(start 149.43201 -416.014662)
		(end 149.624288 -416.014662)
		(stroke
			(width 0.07112)
			(type default)
		)
		(layer "In15.Cu")
	)
	(gr_line
		(start 149.624288 -416.014662)
		(end 149.926294 -415.712656)
		(stroke
			(width 0.07112)
			(type default)
		)
		(layer "In15.Cu")
	)
	(gr_line
		(start 149.705822 -393.017756)
		(end 149.717252 -393.017756)
		(stroke
			(width 0.07112)
			(type default)
		)
		(layer "In15.Cu")
	)
	(gr_line
		(start 149.707092 -392.734546)
		(end 149.844252 -392.597386)
		(stroke
			(width 0.07112)
			(type default)
		)
		(layer "In15.Cu")
	)
	(gr_line
		(start 149.717252 -393.017756)
		(end 149.844252 -393.144756)
		(stroke
			(width 0.07112)
			(type default)
		)
		(layer "In15.Cu")
	)
	(gr_line
		(start 149.793452 -402.58238)
		(end 149.866858 -402.404326)
		(stroke
			(width 0.07112)
			(type default)
		)
		(layer "In15.Cu")
	)
	(gr_line
		(start 149.844252 -393.144756)
		(end 149.844252 -393.292838)
		(stroke
			(width 0.07112)
			(type default)
		)
		(layer "In15.Cu")
	)
	(gr_line
		(start 149.844252 -392.597386)
		(end 149.844252 -392.429238)
		(stroke
			(width 0.07112)
			(type default)
		)
		(layer "In15.Cu")
	)
	(gr_line
		(start 149.926294 -415.712656)
		(end 149.926294 -415.520378)
		(stroke
			(width 0.07112)
			(type default)
		)
		(layer "In15.Cu")
	)
	(gr_line
		(start 150.183596 -401.966684)
		(end 150.831296 -401.698206)
		(stroke
			(width 0.07112)
			(type default)
		)
		(layer "In15.Cu")
	)
	(gr_line
		(start 150.29307 -402.227796)
		(end 150.470616 -402.301456)
		(stroke
			(width 0.07112)
			(type default)
		)
		(layer "In15.Cu")
	)
	(gr_line
		(start 150.439628 -417.029646)
		(end 150.93569 -416.533584)
		(stroke
			(width 0.07112)
			(type default)
		)
		(layer "In15.Cu")
	)
	(gr_line
		(start 150.470616 -402.301456)
		(end 150.865078 -402.138134)
		(stroke
			(width 0.07112)
			(type default)
		)
		(layer "In15.Cu")
	)
	(gr_line
		(start 150.603458 -437.623204)
		(end 150.599902 -437.623204)
		(stroke
			(width 0.07112)
			(type default)
		)
		(layer "In15.Cu")
	)
	(gr_line
		(start 150.640796 -417.229036)
		(end 150.833074 -417.229036)
		(stroke
			(width 0.07112)
			(type default)
		)
		(layer "In15.Cu")
	)
	(gr_line
		(start 150.750016 -438.089802)
		(end 150.750016 -437.769762)
		(stroke
			(width 0.07112)
			(type default)
		)
		(layer "In15.Cu")
	)
	(gr_line
		(start 150.750016 -437.769762)
		(end 150.603458 -437.623204)
		(stroke
			(width 0.07112)
			(type default)
		)
		(layer "In15.Cu")
	)
	(gr_line
		(start 150.750016 -437.19115)
		(end 150.601172 -437.339994)
		(stroke
			(width 0.07112)
			(type default)
		)
		(layer "In15.Cu")
	)
	(gr_line
		(start 150.750016 -436.889906)
		(end 150.750016 -437.19115)
		(stroke
			(width 0.07112)
			(type default)
		)
		(layer "In15.Cu")
	)
	(gr_line
		(start 150.833074 -417.229036)
		(end 151.13508 -416.92703)
		(stroke
			(width 0.07112)
			(type default)
		)
		(layer "In15.Cu")
	)
	(gr_line
		(start 150.865078 -402.138134)
		(end 150.938484 -401.960334)
		(stroke
			(width 0.07112)
			(type default)
		)
		(layer "In15.Cu")
	)
	(gr_line
		(start 150.905718 -393.017756)
		(end 150.917148 -393.017756)
		(stroke
			(width 0.07112)
			(type default)
		)
		(layer "In15.Cu")
	)
	(gr_line
		(start 150.906988 -392.734546)
		(end 151.044148 -392.597386)
		(stroke
			(width 0.07112)
			(type default)
		)
		(layer "In15.Cu")
	)
	(gr_line
		(start 150.917148 -393.017756)
		(end 151.044148 -393.144756)
		(stroke
			(width 0.07112)
			(type default)
		)
		(layer "In15.Cu")
	)
	(gr_line
		(start 151.044148 -393.144756)
		(end 151.044148 -393.292838)
		(stroke
			(width 0.07112)
			(type default)
		)
		(layer "In15.Cu")
	)
	(gr_line
		(start 151.044148 -392.597386)
		(end 151.044148 -392.429238)
		(stroke
			(width 0.07112)
			(type default)
		)
		(layer "In15.Cu")
	)
	(gr_line
		(start 151.13508 -416.92703)
		(end 151.13508 -416.734752)
		(stroke
			(width 0.07112)
			(type default)
		)
		(layer "In15.Cu")
	)
	(gr_line
		(start 151.237188 -416.232086)
		(end 151.73325 -415.736024)
		(stroke
			(width 0.07112)
			(type default)
		)
		(layer "In15.Cu")
	)
	(gr_line
		(start 151.438356 -416.431476)
		(end 151.630634 -416.431476)
		(stroke
			(width 0.07112)
			(type default)
		)
		(layer "In15.Cu")
	)
	(gr_line
		(start 151.630634 -416.431476)
		(end 151.93264 -416.12947)
		(stroke
			(width 0.07112)
			(type default)
		)
		(layer "In15.Cu")
	)
	(gr_line
		(start 151.93264 -416.12947)
		(end 151.93264 -415.937192)
		(stroke
			(width 0.07112)
			(type default)
		)
		(layer "In15.Cu")
	)
	(gr_line
		(start 151.943816 -409.387294)
		(end 151.943816 -408.686254)
		(stroke
			(width 0.07112)
			(type default)
		)
		(layer "In15.Cu")
	)
	(gr_line
		(start 151.943816 -408.259534)
		(end 151.943816 -407.558494)
		(stroke
			(width 0.07112)
			(type default)
		)
		(layer "In15.Cu")
	)
	(gr_line
		(start 152.034748 -415.434526)
		(end 152.53081 -414.938464)
		(stroke
			(width 0.07112)
			(type default)
		)
		(layer "In15.Cu")
	)
	(gr_line
		(start 152.105868 -393.017756)
		(end 152.117298 -393.017756)
		(stroke
			(width 0.07112)
			(type default)
		)
		(layer "In15.Cu")
	)
	(gr_line
		(start 152.107138 -392.734546)
		(end 152.244298 -392.597386)
		(stroke
			(width 0.07112)
			(type default)
		)
		(layer "In15.Cu")
	)
	(gr_line
		(start 152.117298 -393.017756)
		(end 152.244298 -393.144756)
		(stroke
			(width 0.07112)
			(type default)
		)
		(layer "In15.Cu")
	)
	(gr_arc
		(start 152.144222 -401.077176)
		(mid 152.145111 -401.076542)
		(end 152.146 -401.075906)
		(stroke
			(width 0.07112)
			(type default)
		)
		(layer "In15.Cu")
	)
	(gr_line
		(start 152.209754 -402.274532)
		(end 152.788874 -401.8788)
		(stroke
			(width 0.07112)
			(type default)
		)
		(layer "In15.Cu")
	)
	(gr_line
		(start 152.227026 -409.386024)
		(end 152.362916 -409.250134)
		(stroke
			(width 0.07112)
			(type default)
		)
		(layer "In15.Cu")
	)
	(gr_line
		(start 152.227026 -408.258264)
		(end 152.362916 -408.122374)
		(stroke
			(width 0.07112)
			(type default)
		)
		(layer "In15.Cu")
	)
	(gr_line
		(start 152.235916 -415.633916)
		(end 152.428194 -415.633916)
		(stroke
			(width 0.07112)
			(type default)
		)
		(layer "In15.Cu")
	)
	(gr_line
		(start 152.244298 -393.144756)
		(end 152.244298 -393.292838)
		(stroke
			(width 0.07112)
			(type default)
		)
		(layer "In15.Cu")
	)
	(gr_line
		(start 152.244298 -392.597386)
		(end 152.244298 -392.429238)
		(stroke
			(width 0.07112)
			(type default)
		)
		(layer "In15.Cu")
	)
	(gr_line
		(start 152.362916 -409.250134)
		(end 152.362916 -408.823414)
		(stroke
			(width 0.07112)
			(type default)
		)
		(layer "In15.Cu")
	)
	(gr_line
		(start 152.362916 -408.823414)
		(end 152.227026 -408.687524)
		(stroke
			(width 0.07112)
			(type default)
		)
		(layer "In15.Cu")
	)
	(gr_line
		(start 152.362916 -408.122374)
		(end 152.362916 -407.695654)
		(stroke
			(width 0.07112)
			(type default)
		)
		(layer "In15.Cu")
	)
	(gr_line
		(start 152.362916 -407.695654)
		(end 152.227026 -407.559764)
		(stroke
			(width 0.07112)
			(type default)
		)
		(layer "In15.Cu")
	)
	(gr_line
		(start 152.370536 -402.507704)
		(end 152.559766 -402.543264)
		(stroke
			(width 0.07112)
			(type default)
		)
		(layer "In15.Cu")
	)
	(gr_line
		(start 152.428194 -415.633916)
		(end 152.7302 -415.33191)
		(stroke
			(width 0.07112)
			(type default)
		)
		(layer "In15.Cu")
	)
	(gr_line
		(start 152.559766 -402.543264)
		(end 152.912318 -402.302218)
		(stroke
			(width 0.07112)
			(type default)
		)
		(layer "In15.Cu")
	)
	(gr_line
		(start 152.588214 -158.225998)
		(end 152.58796 -158.225744)
		(stroke
			(width 0.07112)
			(type default)
		)
		(layer "In15.Cu")
	)
	(gr_line
		(start 152.603454 -438.623202)
		(end 152.599898 -438.623202)
		(stroke
			(width 0.07112)
			(type default)
		)
		(layer "In15.Cu")
	)
	(gr_line
		(start 152.7302 -415.33191)
		(end 152.7302 -415.139632)
		(stroke
			(width 0.07112)
			(type default)
		)
		(layer "In15.Cu")
	)
	(gr_line
		(start 152.750012 -439.0898)
		(end 152.750012 -438.76976)
		(stroke
			(width 0.07112)
			(type default)
		)
		(layer "In15.Cu")
	)
	(gr_line
		(start 152.750012 -438.76976)
		(end 152.603454 -438.623202)
		(stroke
			(width 0.07112)
			(type default)
		)
		(layer "In15.Cu")
	)
	(gr_line
		(start 152.750012 -438.191148)
		(end 152.601168 -438.339992)
		(stroke
			(width 0.07112)
			(type default)
		)
		(layer "In15.Cu")
	)
	(gr_line
		(start 152.750012 -437.889904)
		(end 152.750012 -438.191148)
		(stroke
			(width 0.07112)
			(type default)
		)
		(layer "In15.Cu")
	)
	(gr_line
		(start 152.82418 -417.808918)
		(end 153.320242 -417.312856)
		(stroke
			(width 0.07112)
			(type default)
		)
		(layer "In15.Cu")
	)
	(gr_line
		(start 152.912318 -402.302218)
		(end 152.947878 -402.113242)
		(stroke
			(width 0.07112)
			(type default)
		)
		(layer "In15.Cu")
	)
	(gr_line
		(start 153.025348 -418.008308)
		(end 153.217626 -418.008308)
		(stroke
			(width 0.07112)
			(type default)
		)
		(layer "In15.Cu")
	)
	(gr_line
		(start 153.140918 -401.638008)
		(end 153.720292 -401.242276)
		(stroke
			(width 0.07112)
			(type default)
		)
		(layer "In15.Cu")
	)
	(gr_line
		(start 153.217626 -418.008308)
		(end 153.519632 -417.706302)
		(stroke
			(width 0.07112)
			(type default)
		)
		(layer "In15.Cu")
	)
	(gr_line
		(start 153.3017 -401.87118)
		(end 153.49093 -401.90674)
		(stroke
			(width 0.07112)
			(type default)
		)
		(layer "In15.Cu")
	)
	(gr_line
		(start 153.305764 -393.017756)
		(end 153.317194 -393.017756)
		(stroke
			(width 0.07112)
			(type default)
		)
		(layer "In15.Cu")
	)
	(gr_line
		(start 153.307034 -392.734546)
		(end 153.444194 -392.597386)
		(stroke
			(width 0.07112)
			(type default)
		)
		(layer "In15.Cu")
	)
	(gr_line
		(start 153.317194 -393.017756)
		(end 153.444194 -393.144756)
		(stroke
			(width 0.07112)
			(type default)
		)
		(layer "In15.Cu")
	)
	(gr_line
		(start 153.444194 -393.144756)
		(end 153.444194 -393.292838)
		(stroke
			(width 0.07112)
			(type default)
		)
		(layer "In15.Cu")
	)
	(gr_line
		(start 153.444194 -392.597386)
		(end 153.444194 -392.429238)
		(stroke
			(width 0.07112)
			(type default)
		)
		(layer "In15.Cu")
	)
	(gr_line
		(start 153.49093 -401.90674)
		(end 153.843482 -401.665694)
		(stroke
			(width 0.07112)
			(type default)
		)
		(layer "In15.Cu")
	)
	(gr_line
		(start 153.519632 -417.706302)
		(end 153.519632 -417.514024)
		(stroke
			(width 0.07112)
			(type default)
		)
		(layer "In15.Cu")
	)
	(gr_line
		(start 153.614374 -399.913094)
		(end 154.110436 -399.417286)
		(stroke
			(width 0.07112)
			(type default)
		)
		(layer "In15.Cu")
	)
	(gr_line
		(start 153.62174 -417.011358)
		(end 154.117802 -416.515296)
		(stroke
			(width 0.07112)
			(type default)
		)
		(layer "In15.Cu")
	)
	(gr_line
		(start 153.76398 -363.103922)
		(end 154.46502 -363.103922)
		(stroke
			(width 0.07112)
			(type default)
		)
		(layer "In15.Cu")
	)
	(gr_line
		(start 153.76525 -362.820712)
		(end 153.90114 -362.684822)
		(stroke
			(width 0.07112)
			(type default)
		)
		(layer "In15.Cu")
	)
	(gr_line
		(start 153.815288 -400.112738)
		(end 154.007566 -400.112738)
		(stroke
			(width 0.07112)
			(type default)
		)
		(layer "In15.Cu")
	)
	(gr_line
		(start 153.822908 -417.210748)
		(end 154.015186 -417.210748)
		(stroke
			(width 0.07112)
			(type default)
		)
		(layer "In15.Cu")
	)
	(gr_line
		(start 153.843482 -401.665694)
		(end 153.879042 -401.476718)
		(stroke
			(width 0.07112)
			(type default)
		)
		(layer "In15.Cu")
	)
	(gr_line
		(start 153.90114 -362.684822)
		(end 154.32786 -362.684822)
		(stroke
			(width 0.07112)
			(type default)
		)
		(layer "In15.Cu")
	)
	(gr_line
		(start 154.007566 -400.112738)
		(end 154.309826 -399.810732)
		(stroke
			(width 0.07112)
			(type default)
		)
		(layer "In15.Cu")
	)
	(gr_line
		(start 154.015186 -417.210748)
		(end 154.317192 -416.908742)
		(stroke
			(width 0.07112)
			(type default)
		)
		(layer "In15.Cu")
	)
	(gr_line
		(start 154.048714 -402.951696)
		(end 154.519884 -402.432012)
		(stroke
			(width 0.07112)
			(type default)
		)
		(layer "In15.Cu")
	)
	(gr_line
		(start 154.259534 -403.14118)
		(end 154.451558 -403.131528)
		(stroke
			(width 0.07112)
			(type default)
		)
		(layer "In15.Cu")
	)
	(gr_line
		(start 154.309826 -399.810732)
		(end 154.309826 -399.618454)
		(stroke
			(width 0.07112)
			(type default)
		)
		(layer "In15.Cu")
	)
	(gr_line
		(start 154.317192 -416.908742)
		(end 154.317192 -416.716464)
		(stroke
			(width 0.07112)
			(type default)
		)
		(layer "In15.Cu")
	)
	(gr_line
		(start 154.32786 -362.684822)
		(end 154.46375 -362.820712)
		(stroke
			(width 0.07112)
			(type default)
		)
		(layer "In15.Cu")
	)
	(gr_line
		(start 154.411934 -400.679666)
		(end 154.907742 -400.183858)
		(stroke
			(width 0.07112)
			(type default)
		)
		(layer "In15.Cu")
	)
	(gr_line
		(start 154.411934 -399.115788)
		(end 154.907996 -398.61998)
		(stroke
			(width 0.07112)
			(type default)
		)
		(layer "In15.Cu")
	)
	(gr_line
		(start 154.429968 -420.050976)
		(end 154.92603 -419.554914)
		(stroke
			(width 0.07112)
			(type default)
		)
		(layer "In15.Cu")
	)
	(gr_line
		(start 154.451558 -403.131528)
		(end 154.738324 -402.815044)
		(stroke
			(width 0.07112)
			(type default)
		)
		(layer "In15.Cu")
	)
	(gr_line
		(start 154.505914 -393.017756)
		(end 154.517344 -393.017756)
		(stroke
			(width 0.07112)
			(type default)
		)
		(layer "In15.Cu")
	)
	(gr_line
		(start 154.507184 -392.734546)
		(end 154.644344 -392.597386)
		(stroke
			(width 0.07112)
			(type default)
		)
		(layer "In15.Cu")
	)
	(gr_line
		(start 154.517344 -393.017756)
		(end 154.644344 -393.144756)
		(stroke
			(width 0.07112)
			(type default)
		)
		(layer "In15.Cu")
	)
	(gr_line
		(start 154.60345 -437.623204)
		(end 154.599894 -437.623204)
		(stroke
			(width 0.07112)
			(type default)
		)
		(layer "In15.Cu")
	)
	(gr_line
		(start 154.612848 -400.87931)
		(end 154.805126 -400.87931)
		(stroke
			(width 0.07112)
			(type default)
		)
		(layer "In15.Cu")
	)
	(gr_line
		(start 154.612848 -399.315432)
		(end 154.80538 -399.315432)
		(stroke
			(width 0.07112)
			(type default)
		)
		(layer "In15.Cu")
	)
	(gr_line
		(start 154.631136 -420.250366)
		(end 154.823414 -420.250366)
		(stroke
			(width 0.07112)
			(type default)
		)
		(layer "In15.Cu")
	)
	(gr_line
		(start 154.644344 -393.144756)
		(end 154.644344 -393.292838)
		(stroke
			(width 0.07112)
			(type default)
		)
		(layer "In15.Cu")
	)
	(gr_line
		(start 154.644344 -392.597386)
		(end 154.644344 -392.429238)
		(stroke
			(width 0.07112)
			(type default)
		)
		(layer "In15.Cu")
	)
	(gr_line
		(start 154.738324 -402.815044)
		(end 154.728672 -402.623274)
		(stroke
			(width 0.07112)
			(type default)
		)
		(layer "In15.Cu")
	)
	(gr_line
		(start 154.750008 -438.089802)
		(end 154.750008 -437.769762)
		(stroke
			(width 0.07112)
			(type default)
		)
		(layer "In15.Cu")
	)
	(gr_line
		(start 154.750008 -437.769762)
		(end 154.60345 -437.623204)
		(stroke
			(width 0.07112)
			(type default)
		)
		(layer "In15.Cu")
	)
	(gr_line
		(start 154.750008 -437.19115)
		(end 154.601164 -437.339994)
		(stroke
			(width 0.07112)
			(type default)
		)
		(layer "In15.Cu")
	)
	(gr_line
		(start 154.750008 -436.889906)
		(end 154.750008 -437.19115)
		(stroke
			(width 0.07112)
			(type default)
		)
		(layer "In15.Cu")
	)
	(gr_line
		(start 154.805126 -400.87931)
		(end 155.107132 -400.577304)
		(stroke
			(width 0.07112)
			(type default)
		)
		(layer "In15.Cu")
	)
	(gr_line
		(start 154.80538 -399.315432)
		(end 155.107386 -399.013426)
		(stroke
			(width 0.07112)
			(type default)
		)
		(layer "In15.Cu")
	)
	(gr_line
		(start 154.806142 -402.116036)
		(end 155.277312 -401.596352)
		(stroke
			(width 0.07112)
			(type default)
		)
		(layer "In15.Cu")
	)
	(gr_line
		(start 154.823414 -420.250366)
		(end 155.12542 -419.94836)
		(stroke
			(width 0.07112)
			(type default)
		)
		(layer "In15.Cu")
	)
	(gr_line
		(start 155.007056 -409.640024)
		(end 155.007056 -408.938984)
		(stroke
			(width 0.07112)
			(type default)
		)
		(layer "In15.Cu")
	)
	(gr_line
		(start 155.007056 -408.512264)
		(end 155.007056 -407.811224)
		(stroke
			(width 0.07112)
			(type default)
		)
		(layer "In15.Cu")
	)
	(gr_line
		(start 155.016708 -402.30552)
		(end 155.208732 -402.295868)
		(stroke
			(width 0.07112)
			(type default)
		)
		(layer "In15.Cu")
	)
	(gr_line
		(start 155.05938 -363.103922)
		(end 155.76042 -363.103922)
		(stroke
			(width 0.07112)
			(type default)
		)
		(layer "In15.Cu")
	)
	(gr_line
		(start 155.06065 -362.820712)
		(end 155.19654 -362.684822)
		(stroke
			(width 0.07112)
			(type default)
		)
		(layer "In15.Cu")
	)
	(gr_line
		(start 155.107132 -400.577304)
		(end 155.107132 -400.385026)
		(stroke
			(width 0.07112)
			(type default)
		)
		(layer "In15.Cu")
	)
	(gr_line
		(start 155.107386 -399.013426)
		(end 155.107386 -398.820894)
		(stroke
			(width 0.07112)
			(type default)
		)
		(layer "In15.Cu")
	)
	(gr_line
		(start 155.12542 -419.94836)
		(end 155.12542 -419.756082)
		(stroke
			(width 0.07112)
			(type default)
		)
		(layer "In15.Cu")
	)
	(gr_line
		(start 155.19654 -362.684822)
		(end 155.62326 -362.684822)
		(stroke
			(width 0.07112)
			(type default)
		)
		(layer "In15.Cu")
	)
	(gr_line
		(start 155.208732 -402.295868)
		(end 155.495752 -401.979384)
		(stroke
			(width 0.07112)
			(type default)
		)
		(layer "In15.Cu")
	)
	(gr_line
		(start 155.209494 -399.882106)
		(end 155.705302 -399.386298)
		(stroke
			(width 0.07112)
			(type default)
		)
		(layer "In15.Cu")
	)
	(gr_line
		(start 155.227528 -419.253416)
		(end 155.72359 -418.757354)
		(stroke
			(width 0.07112)
			(type default)
		)
		(layer "In15.Cu")
	)
	(gr_line
		(start 155.290266 -409.638754)
		(end 155.426156 -409.502864)
		(stroke
			(width 0.07112)
			(type default)
		)
		(layer "In15.Cu")
	)
	(gr_line
		(start 155.290266 -408.510994)
		(end 155.426156 -408.375104)
		(stroke
			(width 0.07112)
			(type default)
		)
		(layer "In15.Cu")
	)
	(gr_line
		(start 155.410408 -400.08175)
		(end 155.602686 -400.08175)
		(stroke
			(width 0.07112)
			(type default)
		)
		(layer "In15.Cu")
	)
	(gr_line
		(start 155.426156 -409.502864)
		(end 155.426156 -409.076144)
		(stroke
			(width 0.07112)
			(type default)
		)
		(layer "In15.Cu")
	)
	(gr_line
		(start 155.426156 -409.076144)
		(end 155.290266 -408.940254)
		(stroke
			(width 0.07112)
			(type default)
		)
		(layer "In15.Cu")
	)
	(gr_line
		(start 155.426156 -408.375104)
		(end 155.426156 -407.948384)
		(stroke
			(width 0.07112)
			(type default)
		)
		(layer "In15.Cu")
	)
	(gr_line
		(start 155.426156 -407.948384)
		(end 155.290266 -407.812494)
		(stroke
			(width 0.07112)
			(type default)
		)
		(layer "In15.Cu")
	)
	(gr_line
		(start 155.428696 -419.452806)
		(end 155.620974 -419.452806)
		(stroke
			(width 0.07112)
			(type default)
		)
		(layer "In15.Cu")
	)
	(gr_line
		(start 155.495752 -401.979384)
		(end 155.4861 -401.787614)
		(stroke
			(width 0.07112)
			(type default)
		)
		(layer "In15.Cu")
	)
	(gr_line
		(start 155.56357 -401.280376)
		(end 156.03474 -400.760692)
		(stroke
			(width 0.07112)
			(type default)
		)
		(layer "In15.Cu")
	)
	(gr_line
		(start 155.578302 -397.892778)
		(end 156.02331 -397.350488)
		(stroke
			(width 0.07112)
			(type default)
		)
		(layer "In15.Cu")
	)
	(gr_line
		(start 155.602686 -400.08175)
		(end 155.904692 -399.779744)
		(stroke
			(width 0.07112)
			(type default)
		)
		(layer "In15.Cu")
	)
	(gr_line
		(start 155.620974 -419.452806)
		(end 155.92298 -419.1508)
		(stroke
			(width 0.07112)
			(type default)
		)
		(layer "In15.Cu")
	)
	(gr_line
		(start 155.62326 -362.684822)
		(end 155.75915 -362.820712)
		(stroke
			(width 0.07112)
			(type default)
		)
		(layer "In15.Cu")
	)
	(gr_line
		(start 155.705302 -396.015972)
		(end 156.109162 -395.44244)
		(stroke
			(width 0.07112)
			(type default)
		)
		(layer "In15.Cu")
	)
	(gr_line
		(start 155.70581 -393.017756)
		(end 155.71724 -393.017756)
		(stroke
			(width 0.07112)
			(type default)
		)
		(layer "In15.Cu")
	)
	(gr_line
		(start 155.70708 -392.734546)
		(end 155.84424 -392.597386)
		(stroke
			(width 0.07112)
			(type default)
		)
		(layer "In15.Cu")
	)
	(gr_line
		(start 155.71724 -393.017756)
		(end 155.84424 -393.144756)
		(stroke
			(width 0.07112)
			(type default)
		)
		(layer "In15.Cu")
	)
	(gr_line
		(start 155.774136 -401.46986)
		(end 155.96616 -401.460208)
		(stroke
			(width 0.07112)
			(type default)
		)
		(layer "In15.Cu")
	)
	(gr_line
		(start 155.797758 -398.07134)
		(end 155.989274 -398.052544)
		(stroke
			(width 0.07112)
			(type default)
		)
		(layer "In15.Cu")
	)
	(gr_line
		(start 155.84424 -393.144756)
		(end 155.84424 -393.292838)
		(stroke
			(width 0.07112)
			(type default)
		)
		(layer "In15.Cu")
	)
	(gr_line
		(start 155.84424 -392.597386)
		(end 155.84424 -392.429238)
		(stroke
			(width 0.07112)
			(type default)
		)
		(layer "In15.Cu")
	)
	(gr_line
		(start 155.904692 -399.779744)
		(end 155.904692 -399.587466)
		(stroke
			(width 0.07112)
			(type default)
		)
		(layer "In15.Cu")
	)
	(gr_line
		(start 155.92298 -419.1508)
		(end 155.92298 -418.958522)
		(stroke
			(width 0.07112)
			(type default)
		)
		(layer "In15.Cu")
	)
	(gr_line
		(start 155.937712 -396.178024)
		(end 156.127196 -396.145004)
		(stroke
			(width 0.07112)
			(type default)
		)
		(layer "In15.Cu")
	)
	(gr_line
		(start 155.96616 -401.460208)
		(end 156.25318 -401.143724)
		(stroke
			(width 0.07112)
			(type default)
		)
		(layer "In15.Cu")
	)
	(gr_line
		(start 155.989274 -398.052544)
		(end 156.260292 -397.722598)
		(stroke
			(width 0.07112)
			(type default)
		)
		(layer "In15.Cu")
	)
	(gr_line
		(start 156.127196 -396.145004)
		(end 156.373068 -395.796008)
		(stroke
			(width 0.07112)
			(type default)
		)
		(layer "In15.Cu")
	)
	(gr_line
		(start 156.25318 -401.143724)
		(end 156.243528 -400.951954)
		(stroke
			(width 0.07112)
			(type default)
		)
		(layer "In15.Cu")
	)
	(gr_line
		(start 156.260292 -397.722598)
		(end 156.24175 -397.530828)
		(stroke
			(width 0.07112)
			(type default)
		)
		(layer "In15.Cu")
	)
	(gr_line
		(start 156.320998 -400.444716)
		(end 156.791914 -399.925032)
		(stroke
			(width 0.07112)
			(type default)
		)
		(layer "In15.Cu")
	)
	(gr_line
		(start 156.34208 -363.103922)
		(end 157.04312 -363.103922)
		(stroke
			(width 0.07112)
			(type default)
		)
		(layer "In15.Cu")
	)
	(gr_line
		(start 156.34335 -362.820712)
		(end 156.47924 -362.684822)
		(stroke
			(width 0.07112)
			(type default)
		)
		(layer "In15.Cu")
	)
	(gr_line
		(start 156.373068 -395.796008)
		(end 156.340048 -395.606524)
		(stroke
			(width 0.07112)
			(type default)
		)
		(layer "In15.Cu")
	)
	(gr_line
		(start 156.47924 -362.684822)
		(end 156.90596 -362.684822)
		(stroke
			(width 0.07112)
			(type default)
		)
		(layer "In15.Cu")
	)
	(gr_line
		(start 156.531564 -400.6342)
		(end 156.723588 -400.624548)
		(stroke
			(width 0.07112)
			(type default)
		)
		(layer "In15.Cu")
	)
	(gr_line
		(start 156.603446 -438.623202)
		(end 156.59989 -438.623202)
		(stroke
			(width 0.07112)
			(type default)
		)
		(layer "In15.Cu")
	)
	(gr_line
		(start 156.723588 -400.624548)
		(end 157.010608 -400.308064)
		(stroke
			(width 0.07112)
			(type default)
		)
		(layer "In15.Cu")
	)
	(gr_line
		(start 156.750004 -439.0898)
		(end 156.750004 -438.76976)
		(stroke
			(width 0.07112)
			(type default)
		)
		(layer "In15.Cu")
	)
	(gr_line
		(start 156.750004 -438.76976)
		(end 156.603446 -438.623202)
		(stroke
			(width 0.07112)
			(type default)
		)
		(layer "In15.Cu")
	)
	(gr_line
		(start 156.750004 -438.191148)
		(end 156.60116 -438.339992)
		(stroke
			(width 0.07112)
			(type default)
		)
		(layer "In15.Cu")
	)
	(gr_line
		(start 156.750004 -437.889904)
		(end 156.750004 -438.191148)
		(stroke
			(width 0.07112)
			(type default)
		)
		(layer "In15.Cu")
	)
	(gr_line
		(start 156.800296 -398.193006)
		(end 157.20441 -397.61922)
		(stroke
			(width 0.07112)
			(type default)
		)
		(layer "In15.Cu")
	)
	(gr_line
		(start 156.90596 -393.017756)
		(end 156.91739 -393.017756)
		(stroke
			(width 0.07112)
			(type default)
		)
		(layer "In15.Cu")
	)
	(gr_line
		(start 156.90596 -362.684822)
		(end 157.04185 -362.820712)
		(stroke
			(width 0.07112)
			(type default)
		)
		(layer "In15.Cu")
	)
	(gr_line
		(start 156.90723 -392.734546)
		(end 157.04439 -392.597386)
		(stroke
			(width 0.07112)
			(type default)
		)
		(layer "In15.Cu")
	)
	(gr_line
		(start 156.912056 -402.796502)
		(end 157.272736 -402.194776)
		(stroke
			(width 0.07112)
			(type default)
		)
		(layer "In15.Cu")
	)
	(gr_line
		(start 156.91739 -393.017756)
		(end 157.04439 -393.144756)
		(stroke
			(width 0.07112)
			(type default)
		)
		(layer "In15.Cu")
	)
	(gr_line
		(start 157.010608 -400.308064)
		(end 157.000956 -400.116294)
		(stroke
			(width 0.07112)
			(type default)
		)
		(layer "In15.Cu")
	)
	(gr_line
		(start 157.032452 -398.355058)
		(end 157.22219 -398.322038)
		(stroke
			(width 0.07112)
			(type default)
		)
		(layer "In15.Cu")
	)
	(gr_line
		(start 157.04439 -393.144756)
		(end 157.04439 -393.292838)
		(stroke
			(width 0.07112)
			(type default)
		)
		(layer "In15.Cu")
	)
	(gr_line
		(start 157.04439 -392.597386)
		(end 157.04439 -392.429238)
		(stroke
			(width 0.07112)
			(type default)
		)
		(layer "In15.Cu")
	)
	(gr_line
		(start 157.155642 -402.941028)
		(end 157.342332 -402.894292)
		(stroke
			(width 0.07112)
			(type default)
		)
		(layer "In15.Cu")
	)
	(gr_line
		(start 157.22219 -398.322038)
		(end 157.468062 -397.972788)
		(stroke
			(width 0.07112)
			(type default)
		)
		(layer "In15.Cu")
	)
	(gr_line
		(start 157.342332 -402.894292)
		(end 157.561788 -402.528024)
		(stroke
			(width 0.07112)
			(type default)
		)
		(layer "In15.Cu")
	)
	(gr_line
		(start 157.468062 -397.972788)
		(end 157.435296 -397.78305)
		(stroke
			(width 0.07112)
			(type default)
		)
		(layer "In15.Cu")
	)
	(gr_line
		(start 157.561788 -402.528024)
		(end 157.515052 -402.341588)
		(stroke
			(width 0.07112)
			(type default)
		)
		(layer "In15.Cu")
	)
	(gr_line
		(start 157.65145 -401.563078)
		(end 158.01213 -400.961352)
		(stroke
			(width 0.07112)
			(type default)
		)
		(layer "In15.Cu")
	)
	(gr_line
		(start 157.888178 -418.992558)
		(end 158.38424 -418.496496)
		(stroke
			(width 0.07112)
			(type default)
		)
		(layer "In15.Cu")
	)
	(gr_line
		(start 157.894782 -401.707604)
		(end 158.081726 -401.660868)
		(stroke
			(width 0.07112)
			(type default)
		)
		(layer "In15.Cu")
	)
	(gr_line
		(start 158.070296 -409.548584)
		(end 158.070296 -408.847544)
		(stroke
			(width 0.07112)
			(type default)
		)
		(layer "In15.Cu")
	)
	(gr_line
		(start 158.070296 -408.420824)
		(end 158.070296 -407.719784)
		(stroke
			(width 0.07112)
			(type default)
		)
		(layer "In15.Cu")
	)
	(gr_line
		(start 158.081726 -401.660868)
		(end 158.300928 -401.2946)
		(stroke
			(width 0.07112)
			(type default)
		)
		(layer "In15.Cu")
	)
	(gr_line
		(start 158.089346 -419.191948)
		(end 158.281624 -419.191948)
		(stroke
			(width 0.07112)
			(type default)
		)
		(layer "In15.Cu")
	)
	(gr_line
		(start 158.105856 -393.017756)
		(end 158.117286 -393.017756)
		(stroke
			(width 0.07112)
			(type default)
		)
		(layer "In15.Cu")
	)
	(gr_line
		(start 158.107126 -392.734546)
		(end 158.244286 -392.597386)
		(stroke
			(width 0.07112)
			(type default)
		)
		(layer "In15.Cu")
	)
	(gr_line
		(start 158.117286 -393.017756)
		(end 158.244286 -393.144756)
		(stroke
			(width 0.07112)
			(type default)
		)
		(layer "In15.Cu")
	)
	(gr_line
		(start 158.231332 -400.595592)
		(end 158.592012 -399.993866)
		(stroke
			(width 0.07112)
			(type default)
		)
		(layer "In15.Cu")
	)
	(gr_line
		(start 158.244286 -393.144756)
		(end 158.244286 -393.292838)
		(stroke
			(width 0.07112)
			(type default)
		)
		(layer "In15.Cu")
	)
	(gr_line
		(start 158.244286 -392.597386)
		(end 158.244286 -392.429238)
		(stroke
			(width 0.07112)
			(type default)
		)
		(layer "In15.Cu")
	)
	(gr_line
		(start 158.281624 -419.191948)
		(end 158.58363 -418.889942)
		(stroke
			(width 0.07112)
			(type default)
		)
		(layer "In15.Cu")
	)
	(gr_line
		(start 158.300928 -401.2946)
		(end 158.254446 -401.10791)
		(stroke
			(width 0.07112)
			(type default)
		)
		(layer "In15.Cu")
	)
	(gr_line
		(start 158.353506 -409.547314)
		(end 158.489396 -409.411424)
		(stroke
			(width 0.07112)
			(type default)
		)
		(layer "In15.Cu")
	)
	(gr_line
		(start 158.353506 -408.419554)
		(end 158.489396 -408.283664)
		(stroke
			(width 0.07112)
			(type default)
		)
		(layer "In15.Cu")
	)
	(gr_line
		(start 158.474664 -400.740118)
		(end 158.661608 -400.693382)
		(stroke
			(width 0.07112)
			(type default)
		)
		(layer "In15.Cu")
	)
	(gr_line
		(start 158.489396 -409.411424)
		(end 158.489396 -408.984704)
		(stroke
			(width 0.07112)
			(type default)
		)
		(layer "In15.Cu")
	)
	(gr_line
		(start 158.489396 -408.984704)
		(end 158.353506 -408.848814)
		(stroke
			(width 0.07112)
			(type default)
		)
		(layer "In15.Cu")
	)
	(gr_line
		(start 158.489396 -408.283664)
		(end 158.489396 -407.856944)
		(stroke
			(width 0.07112)
			(type default)
		)
		(layer "In15.Cu")
	)
	(gr_line
		(start 158.489396 -407.856944)
		(end 158.353506 -407.721054)
		(stroke
			(width 0.07112)
			(type default)
		)
		(layer "In15.Cu")
	)
	(gr_line
		(start 158.58363 -418.889942)
		(end 158.58363 -418.697664)
		(stroke
			(width 0.07112)
			(type default)
		)
		(layer "In15.Cu")
	)
	(gr_line
		(start 158.661608 -400.693382)
		(end 158.881064 -400.327114)
		(stroke
			(width 0.07112)
			(type default)
		)
		(layer "In15.Cu")
	)
	(gr_line
		(start 158.685738 -418.194998)
		(end 159.1818 -417.698936)
		(stroke
			(width 0.07112)
			(type default)
		)
		(layer "In15.Cu")
	)
	(gr_line
		(start 158.881064 -400.327114)
		(end 158.834328 -400.140424)
		(stroke
			(width 0.07112)
			(type default)
		)
		(layer "In15.Cu")
	)
	(gr_line
		(start 158.886906 -418.394388)
		(end 159.079184 -418.394388)
		(stroke
			(width 0.07112)
			(type default)
		)
		(layer "In15.Cu")
	)
	(gr_line
		(start 159.079184 -418.394388)
		(end 159.38119 -418.092382)
		(stroke
			(width 0.07112)
			(type default)
		)
		(layer "In15.Cu")
	)
	(gr_line
		(start 159.306006 -393.017756)
		(end 159.317436 -393.017756)
		(stroke
			(width 0.07112)
			(type default)
		)
		(layer "In15.Cu")
	)
	(gr_line
		(start 159.307276 -392.734546)
		(end 159.444436 -392.597386)
		(stroke
			(width 0.07112)
			(type default)
		)
		(layer "In15.Cu")
	)
	(gr_line
		(start 159.317436 -393.017756)
		(end 159.444436 -393.144756)
		(stroke
			(width 0.07112)
			(type default)
		)
		(layer "In15.Cu")
	)
	(gr_line
		(start 159.38119 -418.092382)
		(end 159.38119 -417.900104)
		(stroke
			(width 0.07112)
			(type default)
		)
		(layer "In15.Cu")
	)
	(gr_line
		(start 159.444436 -393.144756)
		(end 159.444436 -393.292838)
		(stroke
			(width 0.07112)
			(type default)
		)
		(layer "In15.Cu")
	)
	(gr_line
		(start 159.444436 -392.597386)
		(end 159.444436 -392.429238)
		(stroke
			(width 0.07112)
			(type default)
		)
		(layer "In15.Cu")
	)
	(gr_line
		(start 159.67456 -417.206176)
		(end 160.170622 -416.710114)
		(stroke
			(width 0.07112)
			(type default)
		)
		(layer "In15.Cu")
	)
	(gr_line
		(start 159.68726 -398.111472)
		(end 160.017714 -397.493236)
		(stroke
			(width 0.07112)
			(type default)
		)
		(layer "In15.Cu")
	)
	(gr_line
		(start 159.756348 -402.97862)
		(end 159.893254 -402.290534)
		(stroke
			(width 0.07112)
			(type default)
		)
		(layer "In15.Cu")
	)
	(gr_line
		(start 159.84728 -364.114334)
		(end 160.54832 -364.114334)
		(stroke
			(width 0.07112)
			(type default)
		)
		(layer "In15.Cu")
	)
	(gr_line
		(start 159.84855 -363.831124)
		(end 159.98444 -363.695234)
		(stroke
			(width 0.07112)
			(type default)
		)
		(layer "In15.Cu")
	)
	(gr_line
		(start 159.875728 -417.405566)
		(end 160.068006 -417.405566)
		(stroke
			(width 0.07112)
			(type default)
		)
		(layer "In15.Cu")
	)
	(gr_line
		(start 159.937196 -398.244568)
		(end 160.121854 -398.188434)
		(stroke
			(width 0.07112)
			(type default)
		)
		(layer "In15.Cu")
	)
	(gr_line
		(start 159.98444 -363.695234)
		(end 160.41116 -363.695234)
		(stroke
			(width 0.07112)
			(type default)
		)
		(layer "In15.Cu")
	)
	(gr_line
		(start 160.017968 -397.493236)
		(end 160.017714 -397.493236)
		(stroke
			(width 0.07112)
			(type default)
		)
		(layer "In15.Cu")
	)
	(gr_line
		(start 160.034478 -403.032468)
		(end 160.194498 -402.925788)
		(stroke
			(width 0.07112)
			(type default)
		)
		(layer "In15.Cu")
	)
	(gr_line
		(start 160.068006 -417.405566)
		(end 160.370012 -417.10356)
		(stroke
			(width 0.07112)
			(type default)
		)
		(layer "In15.Cu")
	)
	(gr_line
		(start 160.121854 -398.188434)
		(end 160.323022 -397.811752)
		(stroke
			(width 0.07112)
			(type default)
		)
		(layer "In15.Cu")
	)
	(gr_line
		(start 160.194498 -402.925788)
		(end 160.277556 -402.506942)
		(stroke
			(width 0.07112)
			(type default)
		)
		(layer "In15.Cu")
	)
	(gr_line
		(start 160.277556 -402.506942)
		(end 160.170876 -402.346922)
		(stroke
			(width 0.07112)
			(type default)
		)
		(layer "In15.Cu")
	)
	(gr_line
		(start 160.323022 -397.811752)
		(end 160.267142 -397.627602)
		(stroke
			(width 0.07112)
			(type default)
		)
		(layer "In15.Cu")
	)
	(gr_line
		(start 160.34512 -400.402298)
		(end 160.58134 -399.742152)
		(stroke
			(width 0.07112)
			(type default)
		)
		(layer "In15.Cu")
	)
	(gr_line
		(start 160.370012 -417.10356)
		(end 160.370012 -416.911282)
		(stroke
			(width 0.07112)
			(type default)
		)
		(layer "In15.Cu")
	)
	(gr_line
		(start 160.41116 -363.695234)
		(end 160.54705 -363.831124)
		(stroke
			(width 0.07112)
			(type default)
		)
		(layer "In15.Cu")
	)
	(gr_line
		(start 160.47212 -416.408616)
		(end 160.968182 -415.912554)
		(stroke
			(width 0.07112)
			(type default)
		)
		(layer "In15.Cu")
	)
	(gr_line
		(start 160.505902 -393.017756)
		(end 160.517332 -393.017756)
		(stroke
			(width 0.07112)
			(type default)
		)
		(layer "In15.Cu")
	)
	(gr_line
		(start 160.507172 -392.734546)
		(end 160.644332 -392.597386)
		(stroke
			(width 0.07112)
			(type default)
		)
		(layer "In15.Cu")
	)
	(gr_line
		(start 160.517332 -393.017756)
		(end 160.644332 -393.144756)
		(stroke
			(width 0.07112)
			(type default)
		)
		(layer "In15.Cu")
	)
	(gr_line
		(start 160.612074 -400.49704)
		(end 160.786318 -400.41449)
		(stroke
			(width 0.07112)
			(type default)
		)
		(layer "In15.Cu")
	)
	(gr_line
		(start 160.644332 -393.144756)
		(end 160.644332 -393.292838)
		(stroke
			(width 0.07112)
			(type default)
		)
		(layer "In15.Cu")
	)
	(gr_line
		(start 160.644332 -392.597386)
		(end 160.644332 -392.429238)
		(stroke
			(width 0.07112)
			(type default)
		)
		(layer "In15.Cu")
	)
	(gr_line
		(start 160.673288 -416.608006)
		(end 160.865566 -416.608006)
		(stroke
			(width 0.07112)
			(type default)
		)
		(layer "In15.Cu")
	)
	(gr_line
		(start 160.725104 -399.340578)
		(end 160.961324 -398.680178)
		(stroke
			(width 0.07112)
			(type default)
		)
		(layer "In15.Cu")
	)
	(gr_line
		(start 160.786318 -400.41449)
		(end 160.930082 -400.012408)
		(stroke
			(width 0.07112)
			(type default)
		)
		(layer "In15.Cu")
	)
	(gr_line
		(start 160.865566 -416.608006)
		(end 161.167572 -416.306)
		(stroke
			(width 0.07112)
			(type default)
		)
		(layer "In15.Cu")
	)
	(gr_line
		(start 160.930082 -400.012408)
		(end 160.847786 -399.838418)
		(stroke
			(width 0.07112)
			(type default)
		)
		(layer "In15.Cu")
	)
	(gr_line
		(start 160.992058 -399.435066)
		(end 161.166302 -399.352516)
		(stroke
			(width 0.07112)
			(type default)
		)
		(layer "In15.Cu")
	)
	(gr_line
		(start 161.097468 -362.05414)
		(end 161.097468 -361.62742)
		(stroke
			(width 0.07112)
			(type default)
		)
		(layer "In15.Cu")
	)
	(gr_line
		(start 161.097468 -361.62742)
		(end 161.233358 -361.49153)
		(stroke
			(width 0.07112)
			(type default)
		)
		(layer "In15.Cu")
	)
	(gr_line
		(start 161.097468 -360.89336)
		(end 161.097468 -360.46664)
		(stroke
			(width 0.07112)
			(type default)
		)
		(layer "In15.Cu")
	)
	(gr_line
		(start 161.097468 -360.46664)
		(end 161.233358 -360.33075)
		(stroke
			(width 0.07112)
			(type default)
		)
		(layer "In15.Cu")
	)
	(gr_line
		(start 161.105088 -398.278604)
		(end 161.341308 -397.618204)
		(stroke
			(width 0.07112)
			(type default)
		)
		(layer "In15.Cu")
	)
	(gr_line
		(start 161.133536 -409.45308)
		(end 161.133536 -408.75204)
		(stroke
			(width 0.07112)
			(type default)
		)
		(layer "In15.Cu")
	)
	(gr_line
		(start 161.133536 -408.32532)
		(end 161.133536 -407.62428)
		(stroke
			(width 0.07112)
			(type default)
		)
		(layer "In15.Cu")
	)
	(gr_line
		(start 161.166302 -399.352516)
		(end 161.310066 -398.950434)
		(stroke
			(width 0.07112)
			(type default)
		)
		(layer "In15.Cu")
	)
	(gr_line
		(start 161.167572 -416.306)
		(end 161.167572 -416.113722)
		(stroke
			(width 0.07112)
			(type default)
		)
		(layer "In15.Cu")
	)
	(gr_line
		(start 161.233358 -362.19003)
		(end 161.097468 -362.05414)
		(stroke
			(width 0.07112)
			(type default)
		)
		(layer "In15.Cu")
	)
	(gr_line
		(start 161.233358 -361.02925)
		(end 161.097468 -360.89336)
		(stroke
			(width 0.07112)
			(type default)
		)
		(layer "In15.Cu")
	)
	(gr_line
		(start 161.26968 -415.611056)
		(end 161.765742 -415.114994)
		(stroke
			(width 0.07112)
			(type default)
		)
		(layer "In15.Cu")
	)
	(gr_line
		(start 161.310066 -398.950434)
		(end 161.22777 -398.776698)
		(stroke
			(width 0.07112)
			(type default)
		)
		(layer "In15.Cu")
	)
	(gr_line
		(start 161.372042 -398.373092)
		(end 161.546286 -398.290542)
		(stroke
			(width 0.07112)
			(type default)
		)
		(layer "In15.Cu")
	)
	(gr_line
		(start 161.416746 -409.45181)
		(end 161.552636 -409.31592)
		(stroke
			(width 0.07112)
			(type default)
		)
		(layer "In15.Cu")
	)
	(gr_line
		(start 161.416746 -408.32405)
		(end 161.552636 -408.18816)
		(stroke
			(width 0.07112)
			(type default)
		)
		(layer "In15.Cu")
	)
	(gr_line
		(start 161.470848 -415.810446)
		(end 161.663126 -415.810446)
		(stroke
			(width 0.07112)
			(type default)
		)
		(layer "In15.Cu")
	)
	(gr_line
		(start 161.485072 -397.21663)
		(end 161.71926 -396.561818)
		(stroke
			(width 0.07112)
			(type default)
		)
		(layer "In15.Cu")
	)
	(gr_line
		(start 161.516568 -362.1913)
		(end 161.516568 -361.49026)
		(stroke
			(width 0.07112)
			(type default)
		)
		(layer "In15.Cu")
	)
	(gr_line
		(start 161.516568 -361.03052)
		(end 161.516568 -360.32948)
		(stroke
			(width 0.07112)
			(type default)
		)
		(layer "In15.Cu")
	)
	(gr_line
		(start 161.546286 -398.290542)
		(end 161.69005 -397.88846)
		(stroke
			(width 0.07112)
			(type default)
		)
		(layer "In15.Cu")
	)
	(gr_line
		(start 161.552636 -409.31592)
		(end 161.552636 -408.8892)
		(stroke
			(width 0.07112)
			(type default)
		)
		(layer "In15.Cu")
	)
	(gr_line
		(start 161.552636 -408.8892)
		(end 161.416746 -408.75331)
		(stroke
			(width 0.07112)
			(type default)
		)
		(layer "In15.Cu")
	)
	(gr_line
		(start 161.552636 -408.18816)
		(end 161.552636 -407.76144)
		(stroke
			(width 0.07112)
			(type default)
		)
		(layer "In15.Cu")
	)
	(gr_line
		(start 161.552636 -407.76144)
		(end 161.416746 -407.62555)
		(stroke
			(width 0.07112)
			(type default)
		)
		(layer "In15.Cu")
	)
	(gr_line
		(start 161.663126 -415.810446)
		(end 161.965132 -415.50844)
		(stroke
			(width 0.07112)
			(type default)
		)
		(layer "In15.Cu")
	)
	(gr_line
		(start 161.69005 -397.88846)
		(end 161.607754 -397.714724)
		(stroke
			(width 0.07112)
			(type default)
		)
		(layer "In15.Cu")
	)
	(gr_line
		(start 161.705798 -393.017756)
		(end 161.717228 -393.017756)
		(stroke
			(width 0.07112)
			(type default)
		)
		(layer "In15.Cu")
	)
	(gr_line
		(start 161.707068 -392.734546)
		(end 161.844228 -392.597386)
		(stroke
			(width 0.07112)
			(type default)
		)
		(layer "In15.Cu")
	)
	(gr_line
		(start 161.717228 -393.017756)
		(end 161.844228 -393.144756)
		(stroke
			(width 0.07112)
			(type default)
		)
		(layer "In15.Cu")
	)
	(gr_line
		(start 161.719768 -396.560294)
		(end 161.721292 -396.556484)
		(stroke
			(width 0.07112)
			(type default)
		)
		(layer "In15.Cu")
	)
	(gr_line
		(start 161.721292 -396.556484)
		(end 161.722054 -396.554706)
		(stroke
			(width 0.07112)
			(type default)
		)
		(layer "In15.Cu")
	)
	(gr_line
		(start 161.752026 -397.310864)
		(end 161.92627 -397.228568)
		(stroke
			(width 0.07112)
			(type default)
		)
		(layer "In15.Cu")
	)
	(gr_line
		(start 161.844228 -393.144756)
		(end 161.844228 -393.292838)
		(stroke
			(width 0.07112)
			(type default)
		)
		(layer "In15.Cu")
	)
	(gr_line
		(start 161.844228 -392.597386)
		(end 161.844228 -392.429238)
		(stroke
			(width 0.07112)
			(type default)
		)
		(layer "In15.Cu")
	)
	(gr_line
		(start 161.92627 -397.228568)
		(end 162.070034 -396.82674)
		(stroke
			(width 0.07112)
			(type default)
		)
		(layer "In15.Cu")
	)
	(gr_line
		(start 161.965132 -415.50844)
		(end 161.965132 -415.316162)
		(stroke
			(width 0.07112)
			(type default)
		)
		(layer "In15.Cu")
	)
	(gr_line
		(start 162.070034 -396.82674)
		(end 161.987738 -396.652496)
		(stroke
			(width 0.07112)
			(type default)
		)
		(layer "In15.Cu")
	)
	(gr_line
		(start 162.58794 -363.4105)
		(end 162.58794 -362.98378)
		(stroke
			(width 0.07112)
			(type default)
		)
		(layer "In15.Cu")
	)
	(gr_line
		(start 162.58794 -362.98378)
		(end 162.72383 -362.84789)
		(stroke
			(width 0.07112)
			(type default)
		)
		(layer "In15.Cu")
	)
	(gr_line
		(start 162.58794 -362.28274)
		(end 162.58794 -361.85602)
		(stroke
			(width 0.07112)
			(type default)
		)
		(layer "In15.Cu")
	)
	(gr_line
		(start 162.58794 -361.85602)
		(end 162.72383 -361.72013)
		(stroke
			(width 0.07112)
			(type default)
		)
		(layer "In15.Cu")
	)
	(gr_line
		(start 162.58794 -361.15498)
		(end 162.58794 -360.72826)
		(stroke
			(width 0.07112)
			(type default)
		)
		(layer "In15.Cu")
	)
	(gr_line
		(start 162.58794 -360.72826)
		(end 162.72383 -360.59237)
		(stroke
			(width 0.07112)
			(type default)
		)
		(layer "In15.Cu")
	)
	(gr_line
		(start 162.684968 -404.718012)
		(end 162.697414 -404.589234)
		(stroke
			(width 0.07112)
			(type default)
		)
		(layer "In15.Cu")
	)
	(gr_line
		(start 162.697414 -404.589234)
		(end 162.766248 -403.890988)
		(stroke
			(width 0.07112)
			(type default)
		)
		(layer "In15.Cu")
	)
	(gr_line
		(start 162.72383 -363.54639)
		(end 162.58794 -363.4105)
		(stroke
			(width 0.07112)
			(type default)
		)
		(layer "In15.Cu")
	)
	(gr_line
		(start 162.72383 -362.41863)
		(end 162.58794 -362.28274)
		(stroke
			(width 0.07112)
			(type default)
		)
		(layer "In15.Cu")
	)
	(gr_line
		(start 162.72383 -361.29087)
		(end 162.58794 -361.15498)
		(stroke
			(width 0.07112)
			(type default)
		)
		(layer "In15.Cu")
	)
	(gr_line
		(start 162.808158 -403.466808)
		(end 162.876738 -402.768562)
		(stroke
			(width 0.07112)
			(type default)
		)
		(layer "In15.Cu")
	)
	(gr_line
		(start 162.905694 -393.017756)
		(end 162.917124 -393.017756)
		(stroke
			(width 0.07112)
			(type default)
		)
		(layer "In15.Cu")
	)
	(gr_line
		(start 162.906964 -392.734546)
		(end 163.044124 -392.597386)
		(stroke
			(width 0.07112)
			(type default)
		)
		(layer "In15.Cu")
	)
	(gr_line
		(start 162.917124 -393.017756)
		(end 163.044124 -393.144756)
		(stroke
			(width 0.07112)
			(type default)
		)
		(layer "In15.Cu")
	)
	(gr_line
		(start 162.918648 -402.344382)
		(end 162.987228 -401.646136)
		(stroke
			(width 0.07112)
			(type default)
		)
		(layer "In15.Cu")
	)
	(gr_line
		(start 162.979608 -404.615396)
		(end 163.128198 -404.493476)
		(stroke
			(width 0.07112)
			(type default)
		)
		(layer "In15.Cu")
	)
	(gr_line
		(start 163.00704 -363.54766)
		(end 163.00704 -362.84662)
		(stroke
			(width 0.07112)
			(type default)
		)
		(layer "In15.Cu")
	)
	(gr_line
		(start 163.00704 -362.4199)
		(end 163.00704 -361.71886)
		(stroke
			(width 0.07112)
			(type default)
		)
		(layer "In15.Cu")
	)
	(gr_line
		(start 163.00704 -361.29214)
		(end 163.00704 -360.5911)
		(stroke
			(width 0.07112)
			(type default)
		)
		(layer "In15.Cu")
	)
	(gr_line
		(start 163.029138 -401.221956)
		(end 163.097718 -400.52371)
		(stroke
			(width 0.07112)
			(type default)
		)
		(layer "In15.Cu")
	)
	(gr_line
		(start 163.044124 -393.144756)
		(end 163.044124 -393.292838)
		(stroke
			(width 0.07112)
			(type default)
		)
		(layer "In15.Cu")
	)
	(gr_line
		(start 163.044124 -392.597386)
		(end 163.044124 -392.429238)
		(stroke
			(width 0.07112)
			(type default)
		)
		(layer "In15.Cu")
	)
	(gr_line
		(start 163.090098 -403.493224)
		(end 163.238942 -403.37105)
		(stroke
			(width 0.07112)
			(type default)
		)
		(layer "In15.Cu")
	)
	(gr_line
		(start 163.128198 -404.493476)
		(end 163.170108 -404.068534)
		(stroke
			(width 0.07112)
			(type default)
		)
		(layer "In15.Cu")
	)
	(gr_line
		(start 163.139628 -400.09953)
		(end 163.208208 -399.401284)
		(stroke
			(width 0.07112)
			(type default)
		)
		(layer "In15.Cu")
	)
	(gr_line
		(start 163.170108 -404.068534)
		(end 163.047934 -403.91969)
		(stroke
			(width 0.07112)
			(type default)
		)
		(layer "In15.Cu")
	)
	(gr_line
		(start 163.200588 -402.370798)
		(end 163.349432 -402.248624)
		(stroke
			(width 0.07112)
			(type default)
		)
		(layer "In15.Cu")
	)
	(gr_line
		(start 163.238942 -403.37105)
		(end 163.280852 -402.946108)
		(stroke
			(width 0.07112)
			(type default)
		)
		(layer "In15.Cu")
	)
	(gr_line
		(start 163.280852 -402.946108)
		(end 163.158424 -402.797264)
		(stroke
			(width 0.07112)
			(type default)
		)
		(layer "In15.Cu")
	)
	(gr_line
		(start 163.311078 -401.248372)
		(end 163.459922 -401.126198)
		(stroke
			(width 0.07112)
			(type default)
		)
		(layer "In15.Cu")
	)
	(gr_line
		(start 163.349432 -402.248624)
		(end 163.391342 -401.823682)
		(stroke
			(width 0.07112)
			(type default)
		)
		(layer "In15.Cu")
	)
	(gr_line
		(start 163.391342 -401.823682)
		(end 163.269168 -401.674838)
		(stroke
			(width 0.07112)
			(type default)
		)
		(layer "In15.Cu")
	)
	(gr_line
		(start 163.421568 -400.125946)
		(end 163.570412 -400.003772)
		(stroke
			(width 0.07112)
			(type default)
		)
		(layer "In15.Cu")
	)
	(gr_line
		(start 163.459922 -401.126198)
		(end 163.501832 -400.701256)
		(stroke
			(width 0.07112)
			(type default)
		)
		(layer "In15.Cu")
	)
	(gr_line
		(start 163.501832 -400.701256)
		(end 163.379658 -400.552412)
		(stroke
			(width 0.07112)
			(type default)
		)
		(layer "In15.Cu")
	)
	(gr_line
		(start 163.570412 -400.003772)
		(end 163.612322 -399.57883)
		(stroke
			(width 0.07112)
			(type default)
		)
		(layer "In15.Cu")
	)
	(gr_line
		(start 163.612322 -399.57883)
		(end 163.490148 -399.429986)
		(stroke
			(width 0.07112)
			(type default)
		)
		(layer "In15.Cu")
	)
	(gr_line
		(start 163.86175 -411.329886)
		(end 163.908994 -411.222952)
		(stroke
			(width 0.07112)
			(type default)
		)
		(layer "In15.Cu")
	)
	(gr_line
		(start 163.908994 -411.222952)
		(end 163.909248 -411.222952)
		(stroke
			(width 0.07112)
			(type default)
		)
		(layer "In15.Cu")
	)
	(gr_line
		(start 163.909248 -411.222952)
		(end 164.145976 -410.688536)
		(stroke
			(width 0.07112)
			(type default)
		)
		(layer "In15.Cu")
	)
	(gr_line
		(start 164.105844 -393.017756)
		(end 164.117274 -393.017756)
		(stroke
			(width 0.07112)
			(type default)
		)
		(layer "In15.Cu")
	)
	(gr_line
		(start 164.107114 -392.734546)
		(end 164.244274 -392.597386)
		(stroke
			(width 0.07112)
			(type default)
		)
		(layer "In15.Cu")
	)
	(gr_line
		(start 164.117274 -393.017756)
		(end 164.244274 -393.144756)
		(stroke
			(width 0.07112)
			(type default)
		)
		(layer "In15.Cu")
	)
	(gr_line
		(start 164.121084 -411.443678)
		(end 164.300916 -411.374336)
		(stroke
			(width 0.07112)
			(type default)
		)
		(layer "In15.Cu")
	)
	(gr_line
		(start 164.244274 -393.144756)
		(end 164.244274 -393.292838)
		(stroke
			(width 0.07112)
			(type default)
		)
		(layer "In15.Cu")
	)
	(gr_line
		(start 164.244274 -392.597386)
		(end 164.244274 -392.429238)
		(stroke
			(width 0.07112)
			(type default)
		)
		(layer "In15.Cu")
	)
	(gr_line
		(start 164.300916 -411.374336)
		(end 164.473636 -410.983938)
		(stroke
			(width 0.07112)
			(type default)
		)
		(layer "In15.Cu")
	)
	(gr_line
		(start 164.473636 -410.983938)
		(end 164.404548 -410.804614)
		(stroke
			(width 0.07112)
			(type default)
		)
		(layer "In15.Cu")
	)
	(gr_line
		(start 164.703252 -397.778478)
		(end 164.703252 -397.077438)
		(stroke
			(width 0.07112)
			(type default)
		)
		(layer "In15.Cu")
	)
	(gr_line
		(start 164.703252 -396.650718)
		(end 164.703252 -395.949678)
		(stroke
			(width 0.07112)
			(type default)
		)
		(layer "In15.Cu")
	)
	(gr_line
		(start 164.703252 -395.522958)
		(end 164.703252 -394.821918)
		(stroke
			(width 0.07112)
			(type default)
		)
		(layer "In15.Cu")
	)
	(gr_line
		(start 164.80282 -366.027716)
		(end 165.50386 -366.027716)
		(stroke
			(width 0.07112)
			(type default)
		)
		(layer "In15.Cu")
	)
	(gr_line
		(start 164.80409 -365.744506)
		(end 164.93998 -365.608616)
		(stroke
			(width 0.07112)
			(type default)
		)
		(layer "In15.Cu")
	)
	(gr_line
		(start 164.93998 -365.608616)
		(end 165.3667 -365.608616)
		(stroke
			(width 0.07112)
			(type default)
		)
		(layer "In15.Cu")
	)
	(gr_line
		(start 164.986462 -397.777208)
		(end 165.122352 -397.641318)
		(stroke
			(width 0.07112)
			(type default)
		)
		(layer "In15.Cu")
	)
	(gr_line
		(start 164.986462 -396.649448)
		(end 165.122352 -396.513558)
		(stroke
			(width 0.07112)
			(type default)
		)
		(layer "In15.Cu")
	)
	(gr_line
		(start 164.986462 -395.521688)
		(end 165.122352 -395.385798)
		(stroke
			(width 0.07112)
			(type default)
		)
		(layer "In15.Cu")
	)
	(gr_line
		(start 165.122352 -397.641318)
		(end 165.122352 -397.214598)
		(stroke
			(width 0.07112)
			(type default)
		)
		(layer "In15.Cu")
	)
	(gr_line
		(start 165.122352 -397.214598)
		(end 164.986462 -397.078708)
		(stroke
			(width 0.07112)
			(type default)
		)
		(layer "In15.Cu")
	)
	(gr_line
		(start 165.122352 -396.513558)
		(end 165.122352 -396.086838)
		(stroke
			(width 0.07112)
			(type default)
		)
		(layer "In15.Cu")
	)
	(gr_line
		(start 165.122352 -396.086838)
		(end 164.986462 -395.950948)
		(stroke
			(width 0.07112)
			(type default)
		)
		(layer "In15.Cu")
	)
	(gr_line
		(start 165.122352 -395.385798)
		(end 165.122352 -394.959078)
		(stroke
			(width 0.07112)
			(type default)
		)
		(layer "In15.Cu")
	)
	(gr_line
		(start 165.122352 -394.959078)
		(end 164.986462 -394.823188)
		(stroke
			(width 0.07112)
			(type default)
		)
		(layer "In15.Cu")
	)
	(gr_line
		(start 165.30574 -393.017756)
		(end 165.31717 -393.017756)
		(stroke
			(width 0.07112)
			(type default)
		)
		(layer "In15.Cu")
	)
	(gr_line
		(start 165.30701 -392.734546)
		(end 165.44417 -392.597386)
		(stroke
			(width 0.07112)
			(type default)
		)
		(layer "In15.Cu")
	)
	(gr_line
		(start 165.31717 -393.017756)
		(end 165.44417 -393.144756)
		(stroke
			(width 0.07112)
			(type default)
		)
		(layer "In15.Cu")
	)
	(gr_line
		(start 165.3667 -365.608616)
		(end 165.50259 -365.744506)
		(stroke
			(width 0.07112)
			(type default)
		)
		(layer "In15.Cu")
	)
	(gr_line
		(start 165.44417 -393.144756)
		(end 165.44417 -393.292838)
		(stroke
			(width 0.07112)
			(type default)
		)
		(layer "In15.Cu")
	)
	(gr_line
		(start 165.44417 -392.597386)
		(end 165.44417 -392.429238)
		(stroke
			(width 0.07112)
			(type default)
		)
		(layer "In15.Cu")
	)
	(gr_line
		(start 165.93058 -366.027716)
		(end 166.63162 -366.027716)
		(stroke
			(width 0.07112)
			(type default)
		)
		(layer "In15.Cu")
	)
	(gr_line
		(start 165.93185 -365.744506)
		(end 166.06774 -365.608616)
		(stroke
			(width 0.07112)
			(type default)
		)
		(layer "In15.Cu")
	)
	(gr_line
		(start 166.06774 -365.608616)
		(end 166.49446 -365.608616)
		(stroke
			(width 0.07112)
			(type default)
		)
		(layer "In15.Cu")
	)
	(gr_line
		(start 166.49446 -365.608616)
		(end 166.63035 -365.744506)
		(stroke
			(width 0.07112)
			(type default)
		)
		(layer "In15.Cu")
	)
	(gr_line
		(start 172.202856 -366.854994)
		(end 172.205142 -366.84966)
		(stroke
			(width 0.07112)
			(type default)
		)
		(layer "In15.Cu")
	)
	(gr_arc
		(start 172.22978 -361.659932)
		(mid 172.22978 -361.660186)
		(end 172.22978 -361.66044)
		(stroke
			(width 0.07112)
			(type default)
		)
		(layer "In15.Cu")
	)
	(gr_line
		(start 172.46346 -366.962944)
		(end 172.465492 -366.957864)
		(stroke
			(width 0.07112)
			(type default)
		)
		(layer "In15.Cu")
	)
	(gr_line
		(start 214.24011 2.401824)
		(end 213.94928 2.110994)
		(stroke
			(width 0.07112)
			(type default)
		)
		(layer "In15.Cu")
	)
	(gr_line
		(start 214.24011 2.683764)
		(end 213.94928 2.974594)
		(stroke
			(width 0.07112)
			(type default)
		)
		(layer "In15.Cu")
	)
	(gr_line
		(start 250.852432 -210.030822)
		(end 250.852432 -209.329782)
		(stroke
			(width 0.07112)
			(type default)
		)
		(layer "In15.Cu")
	)
	(gr_line
		(start 250.852432 -208.903062)
		(end 250.852432 -208.202022)
		(stroke
			(width 0.07112)
			(type default)
		)
		(layer "In15.Cu")
	)
	(gr_line
		(start 250.852432 -207.775302)
		(end 250.852432 -207.074262)
		(stroke
			(width 0.07112)
			(type default)
		)
		(layer "In15.Cu")
	)
	(gr_line
		(start 250.852432 -206.647542)
		(end 250.852432 -205.946502)
		(stroke
			(width 0.07112)
			(type default)
		)
		(layer "In15.Cu")
	)
	(gr_line
		(start 250.852432 -205.519782)
		(end 250.852432 -204.818742)
		(stroke
			(width 0.07112)
			(type default)
		)
		(layer "In15.Cu")
	)
	(gr_line
		(start 250.852432 -204.392022)
		(end 250.852432 -203.690982)
		(stroke
			(width 0.07112)
			(type default)
		)
		(layer "In15.Cu")
	)
	(gr_line
		(start 250.852432 -203.264262)
		(end 250.852432 -202.563222)
		(stroke
			(width 0.07112)
			(type default)
		)
		(layer "In15.Cu")
	)
	(gr_line
		(start 250.852432 -202.136502)
		(end 250.852432 -201.435462)
		(stroke
			(width 0.07112)
			(type default)
		)
		(layer "In15.Cu")
	)
	(gr_line
		(start 251.135642 -210.029552)
		(end 251.271532 -209.893662)
		(stroke
			(width 0.07112)
			(type default)
		)
		(layer "In15.Cu")
	)
	(gr_line
		(start 251.135642 -208.901792)
		(end 251.271532 -208.765902)
		(stroke
			(width 0.07112)
			(type default)
		)
		(layer "In15.Cu")
	)
	(gr_line
		(start 251.135642 -207.774032)
		(end 251.271532 -207.638142)
		(stroke
			(width 0.07112)
			(type default)
		)
		(layer "In15.Cu")
	)
	(gr_line
		(start 251.135642 -206.646272)
		(end 251.271532 -206.510382)
		(stroke
			(width 0.07112)
			(type default)
		)
		(layer "In15.Cu")
	)
	(gr_line
		(start 251.135642 -205.518512)
		(end 251.271532 -205.382622)
		(stroke
			(width 0.07112)
			(type default)
		)
		(layer "In15.Cu")
	)
	(gr_line
		(start 251.135642 -204.390752)
		(end 251.271532 -204.254862)
		(stroke
			(width 0.07112)
			(type default)
		)
		(layer "In15.Cu")
	)
	(gr_line
		(start 251.135642 -203.262992)
		(end 251.271532 -203.127102)
		(stroke
			(width 0.07112)
			(type default)
		)
		(layer "In15.Cu")
	)
	(gr_line
		(start 251.135642 -202.135232)
		(end 251.271532 -201.999342)
		(stroke
			(width 0.07112)
			(type default)
		)
		(layer "In15.Cu")
	)
	(gr_line
		(start 251.271532 -209.893662)
		(end 251.271532 -209.466942)
		(stroke
			(width 0.07112)
			(type default)
		)
		(layer "In15.Cu")
	)
	(gr_line
		(start 251.271532 -209.466942)
		(end 251.135642 -209.331052)
		(stroke
			(width 0.07112)
			(type default)
		)
		(layer "In15.Cu")
	)
	(gr_line
		(start 251.271532 -208.765902)
		(end 251.271532 -208.339182)
		(stroke
			(width 0.07112)
			(type default)
		)
		(layer "In15.Cu")
	)
	(gr_line
		(start 251.271532 -208.339182)
		(end 251.135642 -208.203292)
		(stroke
			(width 0.07112)
			(type default)
		)
		(layer "In15.Cu")
	)
	(gr_line
		(start 251.271532 -207.638142)
		(end 251.271532 -207.211422)
		(stroke
			(width 0.07112)
			(type default)
		)
		(layer "In15.Cu")
	)
	(gr_line
		(start 251.271532 -207.211422)
		(end 251.135642 -207.075532)
		(stroke
			(width 0.07112)
			(type default)
		)
		(layer "In15.Cu")
	)
	(gr_line
		(start 251.271532 -206.510382)
		(end 251.271532 -206.083662)
		(stroke
			(width 0.07112)
			(type default)
		)
		(layer "In15.Cu")
	)
	(gr_line
		(start 251.271532 -206.083662)
		(end 251.135642 -205.947772)
		(stroke
			(width 0.07112)
			(type default)
		)
		(layer "In15.Cu")
	)
	(gr_line
		(start 251.271532 -205.382622)
		(end 251.271532 -204.955902)
		(stroke
			(width 0.07112)
			(type default)
		)
		(layer "In15.Cu")
	)
	(gr_line
		(start 251.271532 -204.955902)
		(end 251.135642 -204.820012)
		(stroke
			(width 0.07112)
			(type default)
		)
		(layer "In15.Cu")
	)
	(gr_line
		(start 251.271532 -204.254862)
		(end 251.271532 -203.828142)
		(stroke
			(width 0.07112)
			(type default)
		)
		(layer "In15.Cu")
	)
	(gr_line
		(start 251.271532 -203.828142)
		(end 251.135642 -203.692252)
		(stroke
			(width 0.07112)
			(type default)
		)
		(layer "In15.Cu")
	)
	(gr_line
		(start 251.271532 -203.127102)
		(end 251.271532 -202.700382)
		(stroke
			(width 0.07112)
			(type default)
		)
		(layer "In15.Cu")
	)
	(gr_line
		(start 251.271532 -202.700382)
		(end 251.135642 -202.564492)
		(stroke
			(width 0.07112)
			(type default)
		)
		(layer "In15.Cu")
	)
	(gr_line
		(start 251.271532 -201.999342)
		(end 251.271532 -201.572622)
		(stroke
			(width 0.07112)
			(type default)
		)
		(layer "In15.Cu")
	)
	(gr_line
		(start 251.271532 -201.572622)
		(end 251.135642 -201.436732)
		(stroke
			(width 0.07112)
			(type default)
		)
		(layer "In15.Cu")
	)
	(gr_line
		(start 252.11278 -210.438746)
		(end 252.11278 -209.737706)
		(stroke
			(width 0.07112)
			(type default)
		)
		(layer "In15.Cu")
	)
	(gr_line
		(start 252.11278 -209.310986)
		(end 252.11278 -208.609946)
		(stroke
			(width 0.07112)
			(type default)
		)
		(layer "In15.Cu")
	)
	(gr_line
		(start 252.11278 -208.183226)
		(end 252.11278 -207.482186)
		(stroke
			(width 0.07112)
			(type default)
		)
		(layer "In15.Cu")
	)
	(gr_line
		(start 252.11278 -207.055466)
		(end 252.11278 -206.354426)
		(stroke
			(width 0.07112)
			(type default)
		)
		(layer "In15.Cu")
	)
	(gr_line
		(start 252.11278 -205.927706)
		(end 252.11278 -205.226666)
		(stroke
			(width 0.07112)
			(type default)
		)
		(layer "In15.Cu")
	)
	(gr_line
		(start 252.11278 -204.799946)
		(end 252.11278 -204.098906)
		(stroke
			(width 0.07112)
			(type default)
		)
		(layer "In15.Cu")
	)
	(gr_line
		(start 252.11278 -203.672186)
		(end 252.11278 -202.971146)
		(stroke
			(width 0.07112)
			(type default)
		)
		(layer "In15.Cu")
	)
	(gr_line
		(start 252.11278 -202.544426)
		(end 252.11278 -201.843386)
		(stroke
			(width 0.07112)
			(type default)
		)
		(layer "In15.Cu")
	)
	(gr_line
		(start 252.39599 -210.437476)
		(end 252.53188 -210.301586)
		(stroke
			(width 0.07112)
			(type default)
		)
		(layer "In15.Cu")
	)
	(gr_line
		(start 252.39599 -209.309716)
		(end 252.53188 -209.173826)
		(stroke
			(width 0.07112)
			(type default)
		)
		(layer "In15.Cu")
	)
	(gr_line
		(start 252.39599 -208.181956)
		(end 252.53188 -208.046066)
		(stroke
			(width 0.07112)
			(type default)
		)
		(layer "In15.Cu")
	)
	(gr_line
		(start 252.39599 -207.054196)
		(end 252.53188 -206.918306)
		(stroke
			(width 0.07112)
			(type default)
		)
		(layer "In15.Cu")
	)
	(gr_line
		(start 252.39599 -205.926436)
		(end 252.53188 -205.790546)
		(stroke
			(width 0.07112)
			(type default)
		)
		(layer "In15.Cu")
	)
	(gr_line
		(start 252.39599 -204.798676)
		(end 252.53188 -204.662786)
		(stroke
			(width 0.07112)
			(type default)
		)
		(layer "In15.Cu")
	)
	(gr_line
		(start 252.39599 -203.670916)
		(end 252.53188 -203.535026)
		(stroke
			(width 0.07112)
			(type default)
		)
		(layer "In15.Cu")
	)
	(gr_line
		(start 252.39599 -202.543156)
		(end 252.53188 -202.407266)
		(stroke
			(width 0.07112)
			(type default)
		)
		(layer "In15.Cu")
	)
	(gr_line
		(start 252.53188 -210.301586)
		(end 252.53188 -209.874866)
		(stroke
			(width 0.07112)
			(type default)
		)
		(layer "In15.Cu")
	)
	(gr_line
		(start 252.53188 -209.874866)
		(end 252.39599 -209.738976)
		(stroke
			(width 0.07112)
			(type default)
		)
		(layer "In15.Cu")
	)
	(gr_line
		(start 252.53188 -209.173826)
		(end 252.53188 -208.747106)
		(stroke
			(width 0.07112)
			(type default)
		)
		(layer "In15.Cu")
	)
	(gr_line
		(start 252.53188 -208.747106)
		(end 252.39599 -208.611216)
		(stroke
			(width 0.07112)
			(type default)
		)
		(layer "In15.Cu")
	)
	(gr_line
		(start 252.53188 -208.046066)
		(end 252.53188 -207.619346)
		(stroke
			(width 0.07112)
			(type default)
		)
		(layer "In15.Cu")
	)
	(gr_line
		(start 252.53188 -207.619346)
		(end 252.39599 -207.483456)
		(stroke
			(width 0.07112)
			(type default)
		)
		(layer "In15.Cu")
	)
	(gr_line
		(start 252.53188 -206.918306)
		(end 252.53188 -206.491586)
		(stroke
			(width 0.07112)
			(type default)
		)
		(layer "In15.Cu")
	)
	(gr_line
		(start 252.53188 -206.491586)
		(end 252.39599 -206.355696)
		(stroke
			(width 0.07112)
			(type default)
		)
		(layer "In15.Cu")
	)
	(gr_line
		(start 252.53188 -205.790546)
		(end 252.53188 -205.363826)
		(stroke
			(width 0.07112)
			(type default)
		)
		(layer "In15.Cu")
	)
	(gr_line
		(start 252.53188 -205.363826)
		(end 252.39599 -205.227936)
		(stroke
			(width 0.07112)
			(type default)
		)
		(layer "In15.Cu")
	)
	(gr_line
		(start 252.53188 -204.662786)
		(end 252.53188 -204.236066)
		(stroke
			(width 0.07112)
			(type default)
		)
		(layer "In15.Cu")
	)
	(gr_line
		(start 252.53188 -204.236066)
		(end 252.39599 -204.100176)
		(stroke
			(width 0.07112)
			(type default)
		)
		(layer "In15.Cu")
	)
	(gr_line
		(start 252.53188 -203.535026)
		(end 252.53188 -203.108306)
		(stroke
			(width 0.07112)
			(type default)
		)
		(layer "In15.Cu")
	)
	(gr_line
		(start 252.53188 -203.108306)
		(end 252.39599 -202.972416)
		(stroke
			(width 0.07112)
			(type default)
		)
		(layer "In15.Cu")
	)
	(gr_line
		(start 252.53188 -202.407266)
		(end 252.53188 -201.980546)
		(stroke
			(width 0.07112)
			(type default)
		)
		(layer "In15.Cu")
	)
	(gr_line
		(start 252.53188 -201.980546)
		(end 252.39599 -201.844656)
		(stroke
			(width 0.07112)
			(type default)
		)
		(layer "In15.Cu")
	)
	(gr_line
		(start 253.373128 -211.017612)
		(end 253.373128 -210.316572)
		(stroke
			(width 0.07112)
			(type default)
		)
		(layer "In15.Cu")
	)
	(gr_line
		(start 253.373128 -209.889852)
		(end 253.373128 -209.188812)
		(stroke
			(width 0.07112)
			(type default)
		)
		(layer "In15.Cu")
	)
	(gr_line
		(start 253.373128 -208.762092)
		(end 253.373128 -208.061052)
		(stroke
			(width 0.07112)
			(type default)
		)
		(layer "In15.Cu")
	)
	(gr_line
		(start 253.373128 -207.634332)
		(end 253.373128 -206.933292)
		(stroke
			(width 0.07112)
			(type default)
		)
		(layer "In15.Cu")
	)
	(gr_line
		(start 253.373128 -206.506572)
		(end 253.373128 -205.805532)
		(stroke
			(width 0.07112)
			(type default)
		)
		(layer "In15.Cu")
	)
	(gr_line
		(start 253.373128 -205.378812)
		(end 253.373128 -204.677772)
		(stroke
			(width 0.07112)
			(type default)
		)
		(layer "In15.Cu")
	)
	(gr_line
		(start 253.373128 -204.251052)
		(end 253.373128 -203.550012)
		(stroke
			(width 0.07112)
			(type default)
		)
		(layer "In15.Cu")
	)
	(gr_line
		(start 253.373128 -203.123292)
		(end 253.373128 -202.422252)
		(stroke
			(width 0.07112)
			(type default)
		)
		(layer "In15.Cu")
	)
	(gr_line
		(start 253.656338 -211.016342)
		(end 253.792228 -210.880452)
		(stroke
			(width 0.07112)
			(type default)
		)
		(layer "In15.Cu")
	)
	(gr_line
		(start 253.656338 -209.888582)
		(end 253.792228 -209.752692)
		(stroke
			(width 0.07112)
			(type default)
		)
		(layer "In15.Cu")
	)
	(gr_line
		(start 253.656338 -208.760822)
		(end 253.792228 -208.624932)
		(stroke
			(width 0.07112)
			(type default)
		)
		(layer "In15.Cu")
	)
	(gr_line
		(start 253.656338 -207.633062)
		(end 253.792228 -207.497172)
		(stroke
			(width 0.07112)
			(type default)
		)
		(layer "In15.Cu")
	)
	(gr_line
		(start 253.656338 -206.505302)
		(end 253.792228 -206.369412)
		(stroke
			(width 0.07112)
			(type default)
		)
		(layer "In15.Cu")
	)
	(gr_line
		(start 253.656338 -205.377542)
		(end 253.792228 -205.241652)
		(stroke
			(width 0.07112)
			(type default)
		)
		(layer "In15.Cu")
	)
	(gr_line
		(start 253.656338 -204.249782)
		(end 253.792228 -204.113892)
		(stroke
			(width 0.07112)
			(type default)
		)
		(layer "In15.Cu")
	)
	(gr_line
		(start 253.656338 -203.122022)
		(end 253.792228 -202.986132)
		(stroke
			(width 0.07112)
			(type default)
		)
		(layer "In15.Cu")
	)
	(gr_line
		(start 253.792228 -210.880452)
		(end 253.792228 -210.453732)
		(stroke
			(width 0.07112)
			(type default)
		)
		(layer "In15.Cu")
	)
	(gr_line
		(start 253.792228 -210.453732)
		(end 253.656338 -210.317842)
		(stroke
			(width 0.07112)
			(type default)
		)
		(layer "In15.Cu")
	)
	(gr_line
		(start 253.792228 -209.752692)
		(end 253.792228 -209.325972)
		(stroke
			(width 0.07112)
			(type default)
		)
		(layer "In15.Cu")
	)
	(gr_line
		(start 253.792228 -209.325972)
		(end 253.656338 -209.190082)
		(stroke
			(width 0.07112)
			(type default)
		)
		(layer "In15.Cu")
	)
	(gr_line
		(start 253.792228 -208.624932)
		(end 253.792228 -208.198212)
		(stroke
			(width 0.07112)
			(type default)
		)
		(layer "In15.Cu")
	)
	(gr_line
		(start 253.792228 -208.198212)
		(end 253.656338 -208.062322)
		(stroke
			(width 0.07112)
			(type default)
		)
		(layer "In15.Cu")
	)
	(gr_line
		(start 253.792228 -207.497172)
		(end 253.792228 -207.070452)
		(stroke
			(width 0.07112)
			(type default)
		)
		(layer "In15.Cu")
	)
	(gr_line
		(start 253.792228 -207.070452)
		(end 253.656338 -206.934562)
		(stroke
			(width 0.07112)
			(type default)
		)
		(layer "In15.Cu")
	)
	(gr_line
		(start 253.792228 -206.369412)
		(end 253.792228 -205.942692)
		(stroke
			(width 0.07112)
			(type default)
		)
		(layer "In15.Cu")
	)
	(gr_line
		(start 253.792228 -205.942692)
		(end 253.656338 -205.806802)
		(stroke
			(width 0.07112)
			(type default)
		)
		(layer "In15.Cu")
	)
	(gr_line
		(start 253.792228 -205.241652)
		(end 253.792228 -204.814932)
		(stroke
			(width 0.07112)
			(type default)
		)
		(layer "In15.Cu")
	)
	(gr_line
		(start 253.792228 -204.814932)
		(end 253.656338 -204.679042)
		(stroke
			(width 0.07112)
			(type default)
		)
		(layer "In15.Cu")
	)
	(gr_line
		(start 253.792228 -204.113892)
		(end 253.792228 -203.687172)
		(stroke
			(width 0.07112)
			(type default)
		)
		(layer "In15.Cu")
	)
	(gr_line
		(start 253.792228 -203.687172)
		(end 253.656338 -203.551282)
		(stroke
			(width 0.07112)
			(type default)
		)
		(layer "In15.Cu")
	)
	(gr_line
		(start 253.792228 -202.986132)
		(end 253.792228 -202.559412)
		(stroke
			(width 0.07112)
			(type default)
		)
		(layer "In15.Cu")
	)
	(gr_line
		(start 253.792228 -202.559412)
		(end 253.656338 -202.423522)
		(stroke
			(width 0.07112)
			(type default)
		)
		(layer "In15.Cu")
	)
	(gr_line
		(start 254.635 -211.884514)
		(end 254.635 -211.183474)
		(stroke
			(width 0.07112)
			(type default)
		)
		(layer "In15.Cu")
	)
	(gr_line
		(start 254.635 -210.756754)
		(end 254.635 -210.055714)
		(stroke
			(width 0.07112)
			(type default)
		)
		(layer "In15.Cu")
	)
	(gr_line
		(start 254.635 -209.628994)
		(end 254.635 -208.927954)
		(stroke
			(width 0.07112)
			(type default)
		)
		(layer "In15.Cu")
	)
	(gr_line
		(start 254.635 -208.501234)
		(end 254.635 -207.800194)
		(stroke
			(width 0.07112)
			(type default)
		)
		(layer "In15.Cu")
	)
	(gr_line
		(start 254.635 -207.373474)
		(end 254.635 -206.672434)
		(stroke
			(width 0.07112)
			(type default)
		)
		(layer "In15.Cu")
	)
	(gr_line
		(start 254.635 -206.245714)
		(end 254.635 -205.544674)
		(stroke
			(width 0.07112)
			(type default)
		)
		(layer "In15.Cu")
	)
	(gr_line
		(start 254.635 -205.117954)
		(end 254.635 -204.416914)
		(stroke
			(width 0.07112)
			(type default)
		)
		(layer "In15.Cu")
	)
	(gr_line
		(start 254.635 -203.990194)
		(end 254.635 -203.289154)
		(stroke
			(width 0.07112)
			(type default)
		)
		(layer "In15.Cu")
	)
	(gr_line
		(start 254.91821 -211.883244)
		(end 255.0541 -211.747354)
		(stroke
			(width 0.07112)
			(type default)
		)
		(layer "In15.Cu")
	)
	(gr_line
		(start 254.91821 -210.755484)
		(end 255.0541 -210.619594)
		(stroke
			(width 0.07112)
			(type default)
		)
		(layer "In15.Cu")
	)
	(gr_line
		(start 254.91821 -209.627724)
		(end 255.0541 -209.491834)
		(stroke
			(width 0.07112)
			(type default)
		)
		(layer "In15.Cu")
	)
	(gr_line
		(start 254.91821 -208.499964)
		(end 255.0541 -208.364074)
		(stroke
			(width 0.07112)
			(type default)
		)
		(layer "In15.Cu")
	)
	(gr_line
		(start 254.91821 -207.372204)
		(end 255.0541 -207.236314)
		(stroke
			(width 0.07112)
			(type default)
		)
		(layer "In15.Cu")
	)
	(gr_line
		(start 254.91821 -206.244444)
		(end 255.0541 -206.108554)
		(stroke
			(width 0.07112)
			(type default)
		)
		(layer "In15.Cu")
	)
	(gr_line
		(start 254.91821 -205.116684)
		(end 255.0541 -204.980794)
		(stroke
			(width 0.07112)
			(type default)
		)
		(layer "In15.Cu")
	)
	(gr_line
		(start 254.91821 -203.988924)
		(end 255.0541 -203.853034)
		(stroke
			(width 0.07112)
			(type default)
		)
		(layer "In15.Cu")
	)
	(gr_line
		(start 255.0541 -211.747354)
		(end 255.0541 -211.320634)
		(stroke
			(width 0.07112)
			(type default)
		)
		(layer "In15.Cu")
	)
	(gr_line
		(start 255.0541 -211.320634)
		(end 254.91821 -211.184744)
		(stroke
			(width 0.07112)
			(type default)
		)
		(layer "In15.Cu")
	)
	(gr_line
		(start 255.0541 -210.619594)
		(end 255.0541 -210.192874)
		(stroke
			(width 0.07112)
			(type default)
		)
		(layer "In15.Cu")
	)
	(gr_line
		(start 255.0541 -210.192874)
		(end 254.91821 -210.056984)
		(stroke
			(width 0.07112)
			(type default)
		)
		(layer "In15.Cu")
	)
	(gr_line
		(start 255.0541 -209.491834)
		(end 255.0541 -209.065114)
		(stroke
			(width 0.07112)
			(type default)
		)
		(layer "In15.Cu")
	)
	(gr_line
		(start 255.0541 -209.065114)
		(end 254.91821 -208.929224)
		(stroke
			(width 0.07112)
			(type default)
		)
		(layer "In15.Cu")
	)
	(gr_line
		(start 255.0541 -208.364074)
		(end 255.0541 -207.937354)
		(stroke
			(width 0.07112)
			(type default)
		)
		(layer "In15.Cu")
	)
	(gr_line
		(start 255.0541 -207.937354)
		(end 254.91821 -207.801464)
		(stroke
			(width 0.07112)
			(type default)
		)
		(layer "In15.Cu")
	)
	(gr_line
		(start 255.0541 -207.236314)
		(end 255.0541 -206.809594)
		(stroke
			(width 0.07112)
			(type default)
		)
		(layer "In15.Cu")
	)
	(gr_line
		(start 255.0541 -206.809594)
		(end 254.91821 -206.673704)
		(stroke
			(width 0.07112)
			(type default)
		)
		(layer "In15.Cu")
	)
	(gr_line
		(start 255.0541 -206.108554)
		(end 255.0541 -205.681834)
		(stroke
			(width 0.07112)
			(type default)
		)
		(layer "In15.Cu")
	)
	(gr_line
		(start 255.0541 -205.681834)
		(end 254.91821 -205.545944)
		(stroke
			(width 0.07112)
			(type default)
		)
		(layer "In15.Cu")
	)
	(gr_line
		(start 255.0541 -204.980794)
		(end 255.0541 -204.554074)
		(stroke
			(width 0.07112)
			(type default)
		)
		(layer "In15.Cu")
	)
	(gr_line
		(start 255.0541 -204.554074)
		(end 254.91821 -204.418184)
		(stroke
			(width 0.07112)
			(type default)
		)
		(layer "In15.Cu")
	)
	(gr_line
		(start 255.0541 -203.853034)
		(end 255.0541 -203.426314)
		(stroke
			(width 0.07112)
			(type default)
		)
		(layer "In15.Cu")
	)
	(gr_line
		(start 255.0541 -203.426314)
		(end 254.91821 -203.290424)
		(stroke
			(width 0.07112)
			(type default)
		)
		(layer "In15.Cu")
	)
	(gr_line
		(start 255.636268 -202.371706)
		(end 255.927098 -202.662536)
		(stroke
			(width 0.07112)
			(type default)
		)
		(layer "In15.Cu")
	)
	(gr_line
		(start 255.636268 -202.089766)
		(end 255.927098 -201.798936)
		(stroke
			(width 0.07112)
			(type default)
		)
		(layer "In15.Cu")
	)
	(gr_line
		(start 255.636268 -199.577198)
		(end 255.927098 -199.868028)
		(stroke
			(width 0.07112)
			(type default)
		)
		(layer "In15.Cu")
	)
	(gr_line
		(start 255.636268 -199.295258)
		(end 255.927098 -199.004428)
		(stroke
			(width 0.07112)
			(type default)
		)
		(layer "In15.Cu")
	)
	(gr_line
		(start 255.636268 -196.78269)
		(end 255.927098 -197.07352)
		(stroke
			(width 0.07112)
			(type default)
		)
		(layer "In15.Cu")
	)
	(gr_line
		(start 255.636268 -196.50075)
		(end 255.927098 -196.20992)
		(stroke
			(width 0.07112)
			(type default)
		)
		(layer "In15.Cu")
	)
	(gr_line
		(start 255.636268 -194.005454)
		(end 255.927098 -194.296284)
		(stroke
			(width 0.07112)
			(type default)
		)
		(layer "In15.Cu")
	)
	(gr_line
		(start 255.636268 -193.723514)
		(end 255.927098 -193.432684)
		(stroke
			(width 0.07112)
			(type default)
		)
		(layer "In15.Cu")
	)
	(gr_line
		(start 299.060616 2.110994)
		(end 298.769786 2.401824)
		(stroke
			(width 0.07112)
			(type default)
		)
		(layer "In15.Cu")
	)
	(gr_line
		(start 299.060616 2.974594)
		(end 298.769786 2.683764)
		(stroke
			(width 0.07112)
			(type default)
		)
		(layer "In15.Cu")
	)
	(gr_line
		(start 303.07534 -409.64104)
		(end 303.07534 -408.94)
		(stroke
			(width 0.07112)
			(type default)
		)
		(layer "In15.Cu")
	)
	(gr_line
		(start 303.07534 -408.51328)
		(end 303.07534 -407.81224)
		(stroke
			(width 0.07112)
			(type default)
		)
		(layer "In15.Cu")
	)
	(gr_line
		(start 303.07534 -407.38552)
		(end 303.07534 -406.68448)
		(stroke
			(width 0.07112)
			(type default)
		)
		(layer "In15.Cu")
	)
	(gr_line
		(start 303.07534 -406.25776)
		(end 303.07534 -405.55672)
		(stroke
			(width 0.07112)
			(type default)
		)
		(layer "In15.Cu")
	)
	(gr_line
		(start 303.07534 -405.13)
		(end 303.07534 -404.42896)
		(stroke
			(width 0.07112)
			(type default)
		)
		(layer "In15.Cu")
	)
	(gr_line
		(start 303.07534 -404.00224)
		(end 303.07534 -403.3012)
		(stroke
			(width 0.07112)
			(type default)
		)
		(layer "In15.Cu")
	)
	(gr_line
		(start 303.35855 -409.63977)
		(end 303.49444 -409.50388)
		(stroke
			(width 0.07112)
			(type default)
		)
		(layer "In15.Cu")
	)
	(gr_line
		(start 303.35855 -408.51201)
		(end 303.49444 -408.37612)
		(stroke
			(width 0.07112)
			(type default)
		)
		(layer "In15.Cu")
	)
	(gr_line
		(start 303.35855 -407.38425)
		(end 303.49444 -407.24836)
		(stroke
			(width 0.07112)
			(type default)
		)
		(layer "In15.Cu")
	)
	(gr_line
		(start 303.35855 -406.25649)
		(end 303.49444 -406.1206)
		(stroke
			(width 0.07112)
			(type default)
		)
		(layer "In15.Cu")
	)
	(gr_line
		(start 303.35855 -405.12873)
		(end 303.49444 -404.99284)
		(stroke
			(width 0.07112)
			(type default)
		)
		(layer "In15.Cu")
	)
	(gr_line
		(start 303.35855 -404.00097)
		(end 303.49444 -403.86508)
		(stroke
			(width 0.07112)
			(type default)
		)
		(layer "In15.Cu")
	)
	(gr_line
		(start 303.49444 -409.50388)
		(end 303.49444 -409.07716)
		(stroke
			(width 0.07112)
			(type default)
		)
		(layer "In15.Cu")
	)
	(gr_line
		(start 303.49444 -409.07716)
		(end 303.35855 -408.94127)
		(stroke
			(width 0.07112)
			(type default)
		)
		(layer "In15.Cu")
	)
	(gr_line
		(start 303.49444 -408.37612)
		(end 303.49444 -407.9494)
		(stroke
			(width 0.07112)
			(type default)
		)
		(layer "In15.Cu")
	)
	(gr_line
		(start 303.49444 -407.9494)
		(end 303.35855 -407.81351)
		(stroke
			(width 0.07112)
			(type default)
		)
		(layer "In15.Cu")
	)
	(gr_line
		(start 303.49444 -407.24836)
		(end 303.49444 -406.82164)
		(stroke
			(width 0.07112)
			(type default)
		)
		(layer "In15.Cu")
	)
	(gr_line
		(start 303.49444 -406.82164)
		(end 303.35855 -406.68575)
		(stroke
			(width 0.07112)
			(type default)
		)
		(layer "In15.Cu")
	)
	(gr_line
		(start 303.49444 -406.1206)
		(end 303.49444 -405.69388)
		(stroke
			(width 0.07112)
			(type default)
		)
		(layer "In15.Cu")
	)
	(gr_line
		(start 303.49444 -405.69388)
		(end 303.35855 -405.55799)
		(stroke
			(width 0.07112)
			(type default)
		)
		(layer "In15.Cu")
	)
	(gr_line
		(start 303.49444 -404.99284)
		(end 303.49444 -404.56612)
		(stroke
			(width 0.07112)
			(type default)
		)
		(layer "In15.Cu")
	)
	(gr_line
		(start 303.49444 -404.56612)
		(end 303.35855 -404.43023)
		(stroke
			(width 0.07112)
			(type default)
		)
		(layer "In15.Cu")
	)
	(gr_line
		(start 303.49444 -403.86508)
		(end 303.49444 -403.43836)
		(stroke
			(width 0.07112)
			(type default)
		)
		(layer "In15.Cu")
	)
	(gr_line
		(start 303.49444 -403.43836)
		(end 303.35855 -403.30247)
		(stroke
			(width 0.07112)
			(type default)
		)
		(layer "In15.Cu")
	)
	(gr_line
		(start 303.676812 -401.089622)
		(end 303.689258 -401.089622)
		(stroke
			(width 0.07112)
			(type default)
		)
		(layer "In15.Cu")
	)
	(gr_line
		(start 303.678082 -401.372832)
		(end 303.816258 -401.511008)
		(stroke
			(width 0.07112)
			(type default)
		)
		(layer "In15.Cu")
	)
	(gr_line
		(start 303.689258 -401.089622)
		(end 303.816258 -400.962622)
		(stroke
			(width 0.07112)
			(type default)
		)
		(layer "In15.Cu")
	)
	(gr_line
		(start 303.816258 -401.511008)
		(end 303.816258 -401.674838)
		(stroke
			(width 0.07112)
			(type default)
		)
		(layer "In15.Cu")
	)
	(gr_line
		(start 303.816258 -400.962622)
		(end 303.816258 -400.811238)
		(stroke
			(width 0.07112)
			(type default)
		)
		(layer "In15.Cu")
	)
	(gr_line
		(start 304.084736 -417.636452)
		(end 304.084736 -416.935412)
		(stroke
			(width 0.07112)
			(type default)
		)
		(layer "In15.Cu")
	)
	(gr_line
		(start 304.084736 -416.508692)
		(end 304.084736 -415.807652)
		(stroke
			(width 0.07112)
			(type default)
		)
		(layer "In15.Cu")
	)
	(gr_line
		(start 304.275236 -407.92019)
		(end 304.275236 -407.21915)
		(stroke
			(width 0.07112)
			(type default)
		)
		(layer "In15.Cu")
	)
	(gr_line
		(start 304.275236 -406.79243)
		(end 304.275236 -406.09139)
		(stroke
			(width 0.07112)
			(type default)
		)
		(layer "In15.Cu")
	)
	(gr_line
		(start 304.275236 -405.66467)
		(end 304.275236 -404.96363)
		(stroke
			(width 0.07112)
			(type default)
		)
		(layer "In15.Cu")
	)
	(gr_line
		(start 304.275236 -404.53691)
		(end 304.275236 -403.83587)
		(stroke
			(width 0.07112)
			(type default)
		)
		(layer "In15.Cu")
	)
	(gr_line
		(start 304.275236 -403.40915)
		(end 304.275236 -402.70811)
		(stroke
			(width 0.07112)
			(type default)
		)
		(layer "In15.Cu")
	)
	(gr_line
		(start 304.367946 -417.635182)
		(end 304.503836 -417.499292)
		(stroke
			(width 0.07112)
			(type default)
		)
		(layer "In15.Cu")
	)
	(gr_line
		(start 304.367946 -416.507422)
		(end 304.503836 -416.371532)
		(stroke
			(width 0.07112)
			(type default)
		)
		(layer "In15.Cu")
	)
	(gr_line
		(start 304.459894 -409.221686)
		(end 304.45964 -409.221686)
		(stroke
			(width 0.07112)
			(type default)
		)
		(layer "In15.Cu")
	)
	(gr_line
		(start 304.503836 -417.499292)
		(end 304.503836 -417.072572)
		(stroke
			(width 0.07112)
			(type default)
		)
		(layer "In15.Cu")
	)
	(gr_line
		(start 304.503836 -417.072572)
		(end 304.367946 -416.936682)
		(stroke
			(width 0.07112)
			(type default)
		)
		(layer "In15.Cu")
	)
	(gr_line
		(start 304.503836 -416.371532)
		(end 304.503836 -415.944812)
		(stroke
			(width 0.07112)
			(type default)
		)
		(layer "In15.Cu")
	)
	(gr_line
		(start 304.503836 -415.944812)
		(end 304.367946 -415.808922)
		(stroke
			(width 0.07112)
			(type default)
		)
		(layer "In15.Cu")
	)
	(gr_line
		(start 304.558446 -407.91892)
		(end 304.694336 -407.78303)
		(stroke
			(width 0.07112)
			(type default)
		)
		(layer "In15.Cu")
	)
	(gr_line
		(start 304.558446 -406.79116)
		(end 304.694336 -406.65527)
		(stroke
			(width 0.07112)
			(type default)
		)
		(layer "In15.Cu")
	)
	(gr_line
		(start 304.558446 -405.6634)
		(end 304.694336 -405.52751)
		(stroke
			(width 0.07112)
			(type default)
		)
		(layer "In15.Cu")
	)
	(gr_line
		(start 304.558446 -404.53564)
		(end 304.694336 -404.39975)
		(stroke
			(width 0.07112)
			(type default)
		)
		(layer "In15.Cu")
	)
	(gr_line
		(start 304.558446 -403.40788)
		(end 304.694336 -403.27199)
		(stroke
			(width 0.07112)
			(type default)
		)
		(layer "In15.Cu")
	)
	(gr_line
		(start 304.694336 -407.78303)
		(end 304.694336 -407.35631)
		(stroke
			(width 0.07112)
			(type default)
		)
		(layer "In15.Cu")
	)
	(gr_line
		(start 304.694336 -407.35631)
		(end 304.558446 -407.22042)
		(stroke
			(width 0.07112)
			(type default)
		)
		(layer "In15.Cu")
	)
	(gr_line
		(start 304.694336 -406.65527)
		(end 304.694336 -406.22855)
		(stroke
			(width 0.07112)
			(type default)
		)
		(layer "In15.Cu")
	)
	(gr_line
		(start 304.694336 -406.22855)
		(end 304.558446 -406.09266)
		(stroke
			(width 0.07112)
			(type default)
		)
		(layer "In15.Cu")
	)
	(gr_line
		(start 304.694336 -405.52751)
		(end 304.694336 -405.10079)
		(stroke
			(width 0.07112)
			(type default)
		)
		(layer "In15.Cu")
	)
	(gr_line
		(start 304.694336 -405.10079)
		(end 304.558446 -404.9649)
		(stroke
			(width 0.07112)
			(type default)
		)
		(layer "In15.Cu")
	)
	(gr_line
		(start 304.694336 -404.39975)
		(end 304.694336 -403.97303)
		(stroke
			(width 0.07112)
			(type default)
		)
		(layer "In15.Cu")
	)
	(gr_line
		(start 304.694336 -403.97303)
		(end 304.558446 -403.83714)
		(stroke
			(width 0.07112)
			(type default)
		)
		(layer "In15.Cu")
	)
	(gr_line
		(start 304.694336 -403.27199)
		(end 304.694336 -402.84527)
		(stroke
			(width 0.07112)
			(type default)
		)
		(layer "In15.Cu")
	)
	(gr_line
		(start 304.694336 -402.84527)
		(end 304.558446 -402.70938)
		(stroke
			(width 0.07112)
			(type default)
		)
		(layer "In15.Cu")
	)
	(gr_line
		(start 304.728372 -409.869894)
		(end 304.459894 -409.221686)
		(stroke
			(width 0.07112)
			(type default)
		)
		(layer "In15.Cu")
	)
	(gr_line
		(start 304.876708 -401.089622)
		(end 304.889154 -401.089622)
		(stroke
			(width 0.07112)
			(type default)
		)
		(layer "In15.Cu")
	)
	(gr_line
		(start 304.877978 -401.372832)
		(end 305.016154 -401.511008)
		(stroke
			(width 0.07112)
			(type default)
		)
		(layer "In15.Cu")
	)
	(gr_line
		(start 304.889154 -401.089622)
		(end 305.016154 -400.962622)
		(stroke
			(width 0.07112)
			(type default)
		)
		(layer "In15.Cu")
	)
	(gr_line
		(start 304.89144 -410.263848)
		(end 304.847752 -410.15793)
		(stroke
			(width 0.07112)
			(type default)
		)
		(layer "In15.Cu")
	)
	(gr_line
		(start 304.899822 -409.188158)
		(end 304.722276 -409.114752)
		(stroke
			(width 0.07112)
			(type default)
		)
		(layer "In15.Cu")
	)
	(gr_line
		(start 304.989484 -409.76042)
		(end 305.063144 -409.58262)
		(stroke
			(width 0.07112)
			(type default)
		)
		(layer "In15.Cu")
	)
	(gr_line
		(start 305.016154 -401.511008)
		(end 305.016154 -401.674838)
		(stroke
			(width 0.07112)
			(type default)
		)
		(layer "In15.Cu")
	)
	(gr_line
		(start 305.016154 -400.962622)
		(end 305.016154 -400.811238)
		(stroke
			(width 0.07112)
			(type default)
		)
		(layer "In15.Cu")
	)
	(gr_line
		(start 305.063144 -409.58262)
		(end 304.899822 -409.188158)
		(stroke
			(width 0.07112)
			(type default)
		)
		(layer "In15.Cu")
	)
	(gr_line
		(start 305.159918 -410.912056)
		(end 304.89144 -410.263848)
		(stroke
			(width 0.07112)
			(type default)
		)
		(layer "In15.Cu")
	)
	(gr_line
		(start 305.331622 -410.23032)
		(end 305.153822 -410.156914)
		(stroke
			(width 0.07112)
			(type default)
		)
		(layer "In15.Cu")
	)
	(gr_line
		(start 305.421284 -410.802582)
		(end 305.494944 -410.624782)
		(stroke
			(width 0.07112)
			(type default)
		)
		(layer "In15.Cu")
	)
	(gr_line
		(start 305.475386 -407.01087)
		(end 305.475386 -406.30983)
		(stroke
			(width 0.07112)
			(type default)
		)
		(layer "In15.Cu")
	)
	(gr_line
		(start 305.475386 -405.88311)
		(end 305.475386 -405.18207)
		(stroke
			(width 0.07112)
			(type default)
		)
		(layer "In15.Cu")
	)
	(gr_line
		(start 305.475386 -404.75535)
		(end 305.475386 -404.05431)
		(stroke
			(width 0.07112)
			(type default)
		)
		(layer "In15.Cu")
	)
	(gr_line
		(start 305.475386 -403.62759)
		(end 305.475386 -402.92655)
		(stroke
			(width 0.07112)
			(type default)
		)
		(layer "In15.Cu")
	)
	(gr_line
		(start 305.494944 -410.624782)
		(end 305.331622 -410.23032)
		(stroke
			(width 0.07112)
			(type default)
		)
		(layer "In15.Cu")
	)
	(gr_line
		(start 305.758596 -407.0096)
		(end 305.894486 -406.87371)
		(stroke
			(width 0.07112)
			(type default)
		)
		(layer "In15.Cu")
	)
	(gr_line
		(start 305.758596 -405.88184)
		(end 305.894486 -405.74595)
		(stroke
			(width 0.07112)
			(type default)
		)
		(layer "In15.Cu")
	)
	(gr_line
		(start 305.758596 -404.75408)
		(end 305.894486 -404.61819)
		(stroke
			(width 0.07112)
			(type default)
		)
		(layer "In15.Cu")
	)
	(gr_line
		(start 305.758596 -403.62632)
		(end 305.894486 -403.49043)
		(stroke
			(width 0.07112)
			(type default)
		)
		(layer "In15.Cu")
	)
	(gr_line
		(start 305.894486 -406.87371)
		(end 305.894486 -406.44699)
		(stroke
			(width 0.07112)
			(type default)
		)
		(layer "In15.Cu")
	)
	(gr_line
		(start 305.894486 -406.44699)
		(end 305.758596 -406.3111)
		(stroke
			(width 0.07112)
			(type default)
		)
		(layer "In15.Cu")
	)
	(gr_line
		(start 305.894486 -405.74595)
		(end 305.894486 -405.31923)
		(stroke
			(width 0.07112)
			(type default)
		)
		(layer "In15.Cu")
	)
	(gr_line
		(start 305.894486 -405.31923)
		(end 305.758596 -405.18334)
		(stroke
			(width 0.07112)
			(type default)
		)
		(layer "In15.Cu")
	)
	(gr_line
		(start 305.894486 -404.61819)
		(end 305.894486 -404.19147)
		(stroke
			(width 0.07112)
			(type default)
		)
		(layer "In15.Cu")
	)
	(gr_line
		(start 305.894486 -404.19147)
		(end 305.758596 -404.05558)
		(stroke
			(width 0.07112)
			(type default)
		)
		(layer "In15.Cu")
	)
	(gr_line
		(start 305.894486 -403.49043)
		(end 305.894486 -403.06371)
		(stroke
			(width 0.07112)
			(type default)
		)
		(layer "In15.Cu")
	)
	(gr_line
		(start 305.894486 -403.06371)
		(end 305.758596 -402.92782)
		(stroke
			(width 0.07112)
			(type default)
		)
		(layer "In15.Cu")
	)
	(gr_line
		(start 306.076858 -401.089622)
		(end 306.089304 -401.089622)
		(stroke
			(width 0.07112)
			(type default)
		)
		(layer "In15.Cu")
	)
	(gr_line
		(start 306.078128 -401.372832)
		(end 306.216304 -401.511008)
		(stroke
			(width 0.07112)
			(type default)
		)
		(layer "In15.Cu")
	)
	(gr_line
		(start 306.089304 -401.089622)
		(end 306.216304 -400.962622)
		(stroke
			(width 0.07112)
			(type default)
		)
		(layer "In15.Cu")
	)
	(gr_line
		(start 306.216304 -401.511008)
		(end 306.216304 -401.674838)
		(stroke
			(width 0.07112)
			(type default)
		)
		(layer "In15.Cu")
	)
	(gr_line
		(start 306.216304 -400.962622)
		(end 306.216304 -400.811238)
		(stroke
			(width 0.07112)
			(type default)
		)
		(layer "In15.Cu")
	)
	(gr_line
		(start 306.244752 -408.347164)
		(end 306.053236 -408.328368)
		(stroke
			(width 0.07112)
			(type default)
		)
		(layer "In15.Cu")
	)
	(gr_line
		(start 306.278534 -409.048966)
		(end 305.833526 -408.50693)
		(stroke
			(width 0.07112)
			(type default)
		)
		(layer "In15.Cu")
	)
	(gr_line
		(start 306.49672 -408.868372)
		(end 306.515516 -408.67711)
		(stroke
			(width 0.07112)
			(type default)
		)
		(layer "In15.Cu")
	)
	(gr_line
		(start 306.515516 -408.67711)
		(end 306.244752 -408.347164)
		(stroke
			(width 0.07112)
			(type default)
		)
		(layer "In15.Cu")
	)
	(gr_line
		(start 306.675282 -405.711406)
		(end 306.675282 -405.010366)
		(stroke
			(width 0.07112)
			(type default)
		)
		(layer "In15.Cu")
	)
	(gr_line
		(start 306.675282 -404.583646)
		(end 306.675282 -403.882606)
		(stroke
			(width 0.07112)
			(type default)
		)
		(layer "In15.Cu")
	)
	(gr_line
		(start 306.675282 -403.455886)
		(end 306.675282 -402.754846)
		(stroke
			(width 0.07112)
			(type default)
		)
		(layer "In15.Cu")
	)
	(gr_line
		(start 306.81041 -422.023794)
		(end 306.635912 -422.096184)
		(stroke
			(width 0.07112)
			(type default)
		)
		(layer "In15.Cu")
	)
	(gr_line
		(start 306.958492 -405.710136)
		(end 307.094382 -405.574246)
		(stroke
			(width 0.07112)
			(type default)
		)
		(layer "In15.Cu")
	)
	(gr_line
		(start 306.958492 -404.582376)
		(end 307.094382 -404.446486)
		(stroke
			(width 0.07112)
			(type default)
		)
		(layer "In15.Cu")
	)
	(gr_line
		(start 306.958492 -403.454616)
		(end 307.094382 -403.318726)
		(stroke
			(width 0.07112)
			(type default)
		)
		(layer "In15.Cu")
	)
	(gr_line
		(start 306.960016 -409.218892)
		(end 306.768754 -409.200096)
		(stroke
			(width 0.07112)
			(type default)
		)
		(layer "In15.Cu")
	)
	(gr_line
		(start 306.994052 -409.921202)
		(end 306.993798 -409.921202)
		(stroke
			(width 0.07112)
			(type default)
		)
		(layer "In15.Cu")
	)
	(gr_line
		(start 306.994052 -409.920948)
		(end 306.549044 -409.378658)
		(stroke
			(width 0.07112)
			(type default)
		)
		(layer "In15.Cu")
	)
	(gr_line
		(start 306.994052 -409.920948)
		(end 306.994052 -409.921202)
		(stroke
			(width 0.07112)
			(type default)
		)
		(layer "In15.Cu")
	)
	(gr_line
		(start 307.094382 -405.574246)
		(end 307.094382 -405.147526)
		(stroke
			(width 0.07112)
			(type default)
		)
		(layer "In15.Cu")
	)
	(gr_line
		(start 307.094382 -405.147526)
		(end 306.958492 -405.011636)
		(stroke
			(width 0.07112)
			(type default)
		)
		(layer "In15.Cu")
	)
	(gr_line
		(start 307.094382 -404.446486)
		(end 307.094382 -404.019766)
		(stroke
			(width 0.07112)
			(type default)
		)
		(layer "In15.Cu")
	)
	(gr_line
		(start 307.094382 -404.019766)
		(end 306.958492 -403.883876)
		(stroke
			(width 0.07112)
			(type default)
		)
		(layer "In15.Cu")
	)
	(gr_line
		(start 307.094382 -403.318726)
		(end 307.094382 -402.892006)
		(stroke
			(width 0.07112)
			(type default)
		)
		(layer "In15.Cu")
	)
	(gr_line
		(start 307.094382 -402.892006)
		(end 306.958492 -402.756116)
		(stroke
			(width 0.07112)
			(type default)
		)
		(layer "In15.Cu")
	)
	(gr_line
		(start 307.147976 -417.796218)
		(end 307.147976 -417.095178)
		(stroke
			(width 0.07112)
			(type default)
		)
		(layer "In15.Cu")
	)
	(gr_line
		(start 307.147976 -416.579304)
		(end 307.147976 -415.878264)
		(stroke
			(width 0.07112)
			(type default)
		)
		(layer "In15.Cu")
	)
	(gr_line
		(start 307.16982 -422.623996)
		(end 306.526438 -422.357296)
		(stroke
			(width 0.07112)
			(type default)
		)
		(layer "In15.Cu")
	)
	(gr_line
		(start 307.204872 -422.18737)
		(end 306.81041 -422.023794)
		(stroke
			(width 0.07112)
			(type default)
		)
		(layer "In15.Cu")
	)
	(gr_line
		(start 307.212238 -409.740354)
		(end 307.231034 -409.549092)
		(stroke
			(width 0.07112)
			(type default)
		)
		(layer "In15.Cu")
	)
	(gr_line
		(start 307.231034 -409.549092)
		(end 306.960016 -409.218892)
		(stroke
			(width 0.07112)
			(type default)
		)
		(layer "In15.Cu")
	)
	(gr_line
		(start 307.276754 -401.089622)
		(end 307.2892 -401.089622)
		(stroke
			(width 0.07112)
			(type default)
		)
		(layer "In15.Cu")
	)
	(gr_line
		(start 307.277262 -422.362122)
		(end 307.204872 -422.18737)
		(stroke
			(width 0.07112)
			(type default)
		)
		(layer "In15.Cu")
	)
	(gr_line
		(start 307.278024 -401.372832)
		(end 307.4162 -401.511008)
		(stroke
			(width 0.07112)
			(type default)
		)
		(layer "In15.Cu")
	)
	(gr_line
		(start 307.2892 -401.089622)
		(end 307.4162 -400.962622)
		(stroke
			(width 0.07112)
			(type default)
		)
		(layer "In15.Cu")
	)
	(gr_line
		(start 307.4162 -401.511008)
		(end 307.4162 -401.674838)
		(stroke
			(width 0.07112)
			(type default)
		)
		(layer "In15.Cu")
	)
	(gr_line
		(start 307.4162 -400.962622)
		(end 307.4162 -400.811238)
		(stroke
			(width 0.07112)
			(type default)
		)
		(layer "In15.Cu")
	)
	(gr_line
		(start 307.431186 -417.794948)
		(end 307.567076 -417.659058)
		(stroke
			(width 0.07112)
			(type default)
		)
		(layer "In15.Cu")
	)
	(gr_line
		(start 307.431186 -416.578034)
		(end 307.567076 -416.442144)
		(stroke
			(width 0.07112)
			(type default)
		)
		(layer "In15.Cu")
	)
	(gr_line
		(start 307.452776 -407.415238)
		(end 307.260498 -407.415238)
		(stroke
			(width 0.07112)
			(type default)
		)
		(layer "In15.Cu")
	)
	(gr_line
		(start 307.555392 -408.11069)
		(end 307.05933 -407.614628)
		(stroke
			(width 0.07112)
			(type default)
		)
		(layer "In15.Cu")
	)
	(gr_line
		(start 307.567076 -417.659058)
		(end 307.567076 -417.232338)
		(stroke
			(width 0.07112)
			(type default)
		)
		(layer "In15.Cu")
	)
	(gr_line
		(start 307.567076 -417.232338)
		(end 307.431186 -417.096448)
		(stroke
			(width 0.07112)
			(type default)
		)
		(layer "In15.Cu")
	)
	(gr_line
		(start 307.567076 -416.442144)
		(end 307.567076 -416.015424)
		(stroke
			(width 0.07112)
			(type default)
		)
		(layer "In15.Cu")
	)
	(gr_line
		(start 307.567076 -416.015424)
		(end 307.431186 -415.879534)
		(stroke
			(width 0.07112)
			(type default)
		)
		(layer "In15.Cu")
	)
	(gr_line
		(start 307.754782 -407.909522)
		(end 307.754782 -407.717244)
		(stroke
			(width 0.07112)
			(type default)
		)
		(layer "In15.Cu")
	)
	(gr_line
		(start 307.754782 -407.717244)
		(end 307.452776 -407.415238)
		(stroke
			(width 0.07112)
			(type default)
		)
		(layer "In15.Cu")
	)
	(gr_line
		(start 307.875432 -405.680164)
		(end 307.875432 -404.979124)
		(stroke
			(width 0.07112)
			(type default)
		)
		(layer "In15.Cu")
	)
	(gr_line
		(start 307.875432 -404.552404)
		(end 307.875432 -403.851364)
		(stroke
			(width 0.07112)
			(type default)
		)
		(layer "In15.Cu")
	)
	(gr_line
		(start 307.875432 -403.424644)
		(end 307.875432 -402.723604)
		(stroke
			(width 0.07112)
			(type default)
		)
		(layer "In15.Cu")
	)
	(gr_line
		(start 308.158642 -405.678894)
		(end 308.294532 -405.543004)
		(stroke
			(width 0.07112)
			(type default)
		)
		(layer "In15.Cu")
	)
	(gr_line
		(start 308.158642 -404.551134)
		(end 308.294532 -404.415244)
		(stroke
			(width 0.07112)
			(type default)
		)
		(layer "In15.Cu")
	)
	(gr_line
		(start 308.158642 -403.423374)
		(end 308.294532 -403.287484)
		(stroke
			(width 0.07112)
			(type default)
		)
		(layer "In15.Cu")
	)
	(gr_line
		(start 308.250336 -408.212798)
		(end 308.058058 -408.212798)
		(stroke
			(width 0.07112)
			(type default)
		)
		(layer "In15.Cu")
	)
	(gr_line
		(start 308.294532 -405.543004)
		(end 308.294532 -405.116284)
		(stroke
			(width 0.07112)
			(type default)
		)
		(layer "In15.Cu")
	)
	(gr_line
		(start 308.294532 -405.116284)
		(end 308.158642 -404.980394)
		(stroke
			(width 0.07112)
			(type default)
		)
		(layer "In15.Cu")
	)
	(gr_line
		(start 308.294532 -404.415244)
		(end 308.294532 -403.988524)
		(stroke
			(width 0.07112)
			(type default)
		)
		(layer "In15.Cu")
	)
	(gr_line
		(start 308.294532 -403.988524)
		(end 308.158642 -403.852634)
		(stroke
			(width 0.07112)
			(type default)
		)
		(layer "In15.Cu")
	)
	(gr_line
		(start 308.294532 -403.287484)
		(end 308.294532 -402.860764)
		(stroke
			(width 0.07112)
			(type default)
		)
		(layer "In15.Cu")
	)
	(gr_line
		(start 308.294532 -402.860764)
		(end 308.158642 -402.724874)
		(stroke
			(width 0.07112)
			(type default)
		)
		(layer "In15.Cu")
	)
	(gr_line
		(start 308.352952 -408.90825)
		(end 307.85689 -408.412188)
		(stroke
			(width 0.07112)
			(type default)
		)
		(layer "In15.Cu")
	)
	(gr_line
		(start 308.476904 -401.089622)
		(end 308.48935 -401.089622)
		(stroke
			(width 0.07112)
			(type default)
		)
		(layer "In15.Cu")
	)
	(gr_line
		(start 308.478174 -401.372832)
		(end 308.61635 -401.511008)
		(stroke
			(width 0.07112)
			(type default)
		)
		(layer "In15.Cu")
	)
	(gr_line
		(start 308.48935 -401.089622)
		(end 308.61635 -400.962622)
		(stroke
			(width 0.07112)
			(type default)
		)
		(layer "In15.Cu")
	)
	(gr_line
		(start 308.552342 -408.707082)
		(end 308.552342 -408.514804)
		(stroke
			(width 0.07112)
			(type default)
		)
		(layer "In15.Cu")
	)
	(gr_line
		(start 308.552342 -408.514804)
		(end 308.250336 -408.212798)
		(stroke
			(width 0.07112)
			(type default)
		)
		(layer "In15.Cu")
	)
	(gr_line
		(start 308.61635 -401.511008)
		(end 308.61635 -401.674838)
		(stroke
			(width 0.07112)
			(type default)
		)
		(layer "In15.Cu")
	)
	(gr_line
		(start 308.61635 -400.962622)
		(end 308.61635 -400.811238)
		(stroke
			(width 0.07112)
			(type default)
		)
		(layer "In15.Cu")
	)
	(gr_line
		(start 308.652926 -407.0858)
		(end 308.460648 -407.0858)
		(stroke
			(width 0.07112)
			(type default)
		)
		(layer "In15.Cu")
	)
	(gr_line
		(start 308.679342 -412.159196)
		(end 308.679596 -412.159196)
		(stroke
			(width 0.07112)
			(type default)
		)
		(layer "In15.Cu")
	)
	(gr_line
		(start 308.755542 -407.781252)
		(end 308.25948 -407.28519)
		(stroke
			(width 0.07112)
			(type default)
		)
		(layer "In15.Cu")
	)
	(gr_line
		(start 308.954932 -407.580084)
		(end 308.954932 -407.387806)
		(stroke
			(width 0.07112)
			(type default)
		)
		(layer "In15.Cu")
	)
	(gr_line
		(start 308.954932 -407.387806)
		(end 308.652926 -407.0858)
		(stroke
			(width 0.07112)
			(type default)
		)
		(layer "In15.Cu")
	)
	(gr_line
		(start 309.047896 -409.010358)
		(end 308.855618 -409.010358)
		(stroke
			(width 0.07112)
			(type default)
		)
		(layer "In15.Cu")
	)
	(gr_line
		(start 309.075328 -405.071072)
		(end 309.075328 -404.370032)
		(stroke
			(width 0.07112)
			(type default)
		)
		(layer "In15.Cu")
	)
	(gr_line
		(start 309.075328 -403.869398)
		(end 309.075328 -403.168358)
		(stroke
			(width 0.07112)
			(type default)
		)
		(layer "In15.Cu")
	)
	(gr_line
		(start 309.150512 -409.70581)
		(end 308.65445 -409.209748)
		(stroke
			(width 0.07112)
			(type default)
		)
		(layer "In15.Cu")
	)
	(gr_line
		(start 309.349902 -409.504642)
		(end 309.349902 -409.312364)
		(stroke
			(width 0.07112)
			(type default)
		)
		(layer "In15.Cu")
	)
	(gr_line
		(start 309.349902 -409.312364)
		(end 309.047896 -409.010358)
		(stroke
			(width 0.07112)
			(type default)
		)
		(layer "In15.Cu")
	)
	(gr_line
		(start 309.358538 -405.069802)
		(end 309.494428 -404.933912)
		(stroke
			(width 0.07112)
			(type default)
		)
		(layer "In15.Cu")
	)
	(gr_line
		(start 309.358538 -403.868128)
		(end 309.494428 -403.732238)
		(stroke
			(width 0.07112)
			(type default)
		)
		(layer "In15.Cu")
	)
	(gr_line
		(start 309.450486 -407.88336)
		(end 309.258208 -407.88336)
		(stroke
			(width 0.07112)
			(type default)
		)
		(layer "In15.Cu")
	)
	(gr_line
		(start 309.494428 -404.933912)
		(end 309.494428 -404.507192)
		(stroke
			(width 0.07112)
			(type default)
		)
		(layer "In15.Cu")
	)
	(gr_line
		(start 309.494428 -404.507192)
		(end 309.358538 -404.371302)
		(stroke
			(width 0.07112)
			(type default)
		)
		(layer "In15.Cu")
	)
	(gr_line
		(start 309.494428 -403.732238)
		(end 309.494428 -403.305518)
		(stroke
			(width 0.07112)
			(type default)
		)
		(layer "In15.Cu")
	)
	(gr_line
		(start 309.494428 -403.305518)
		(end 309.358538 -403.169628)
		(stroke
			(width 0.07112)
			(type default)
		)
		(layer "In15.Cu")
	)
	(gr_line
		(start 309.553102 -408.578812)
		(end 309.05704 -408.08275)
		(stroke
			(width 0.07112)
			(type default)
		)
		(layer "In15.Cu")
	)
	(gr_line
		(start 309.6768 -401.089622)
		(end 309.689246 -401.089622)
		(stroke
			(width 0.07112)
			(type default)
		)
		(layer "In15.Cu")
	)
	(gr_line
		(start 309.67807 -401.372832)
		(end 309.816246 -401.511008)
		(stroke
			(width 0.07112)
			(type default)
		)
		(layer "In15.Cu")
	)
	(gr_line
		(start 309.689246 -401.089622)
		(end 309.816246 -400.962622)
		(stroke
			(width 0.07112)
			(type default)
		)
		(layer "In15.Cu")
	)
	(gr_line
		(start 309.752492 -408.377644)
		(end 309.752492 -408.185366)
		(stroke
			(width 0.07112)
			(type default)
		)
		(layer "In15.Cu")
	)
	(gr_line
		(start 309.752492 -408.185366)
		(end 309.450486 -407.88336)
		(stroke
			(width 0.07112)
			(type default)
		)
		(layer "In15.Cu")
	)
	(gr_line
		(start 309.816246 -401.511008)
		(end 309.816246 -401.674838)
		(stroke
			(width 0.07112)
			(type default)
		)
		(layer "In15.Cu")
	)
	(gr_line
		(start 309.816246 -400.962622)
		(end 309.816246 -400.811238)
		(stroke
			(width 0.07112)
			(type default)
		)
		(layer "In15.Cu")
	)
	(gr_line
		(start 309.845456 -409.807918)
		(end 309.653178 -409.807918)
		(stroke
			(width 0.07112)
			(type default)
		)
		(layer "In15.Cu")
	)
	(gr_line
		(start 309.852822 -406.655778)
		(end 309.660544 -406.655778)
		(stroke
			(width 0.07112)
			(type default)
		)
		(layer "In15.Cu")
	)
	(gr_line
		(start 309.948072 -410.50337)
		(end 309.45201 -410.007308)
		(stroke
			(width 0.07112)
			(type default)
		)
		(layer "In15.Cu")
	)
	(gr_line
		(start 309.955438 -407.35123)
		(end 309.459376 -406.855168)
		(stroke
			(width 0.07112)
			(type default)
		)
		(layer "In15.Cu")
	)
	(gr_line
		(start 310.147462 -410.302202)
		(end 310.147462 -410.109924)
		(stroke
			(width 0.07112)
			(type default)
		)
		(layer "In15.Cu")
	)
	(gr_line
		(start 310.147462 -410.109924)
		(end 309.845456 -409.807918)
		(stroke
			(width 0.07112)
			(type default)
		)
		(layer "In15.Cu")
	)
	(gr_line
		(start 310.154828 -407.150062)
		(end 310.154828 -406.957784)
		(stroke
			(width 0.07112)
			(type default)
		)
		(layer "In15.Cu")
	)
	(gr_line
		(start 310.154828 -406.957784)
		(end 309.852822 -406.655778)
		(stroke
			(width 0.07112)
			(type default)
		)
		(layer "In15.Cu")
	)
	(gr_line
		(start 310.211216 -417.967922)
		(end 310.211216 -417.266882)
		(stroke
			(width 0.07112)
			(type default)
		)
		(layer "In15.Cu")
	)
	(gr_line
		(start 310.211216 -416.840162)
		(end 310.211216 -416.139122)
		(stroke
			(width 0.07112)
			(type default)
		)
		(layer "In15.Cu")
	)
	(gr_line
		(start 310.248046 -408.68092)
		(end 310.055768 -408.68092)
		(stroke
			(width 0.07112)
			(type default)
		)
		(layer "In15.Cu")
	)
	(gr_line
		(start 310.275478 -404.708614)
		(end 310.275478 -404.007574)
		(stroke
			(width 0.07112)
			(type default)
		)
		(layer "In15.Cu")
	)
	(gr_line
		(start 310.275478 -403.580854)
		(end 310.275478 -402.879814)
		(stroke
			(width 0.07112)
			(type default)
		)
		(layer "In15.Cu")
	)
	(gr_line
		(start 310.350662 -409.376372)
		(end 309.8546 -408.88031)
		(stroke
			(width 0.07112)
			(type default)
		)
		(layer "In15.Cu")
	)
	(gr_line
		(start 310.494426 -417.966652)
		(end 310.630316 -417.830762)
		(stroke
			(width 0.07112)
			(type default)
		)
		(layer "In15.Cu")
	)
	(gr_line
		(start 310.494426 -416.838892)
		(end 310.630316 -416.703002)
		(stroke
			(width 0.07112)
			(type default)
		)
		(layer "In15.Cu")
	)
	(gr_line
		(start 310.550052 -409.175204)
		(end 310.550052 -408.982926)
		(stroke
			(width 0.07112)
			(type default)
		)
		(layer "In15.Cu")
	)
	(gr_line
		(start 310.550052 -408.982926)
		(end 310.248046 -408.68092)
		(stroke
			(width 0.07112)
			(type default)
		)
		(layer "In15.Cu")
	)
	(gr_line
		(start 310.558688 -404.707344)
		(end 310.694578 -404.571454)
		(stroke
			(width 0.07112)
			(type default)
		)
		(layer "In15.Cu")
	)
	(gr_line
		(start 310.558688 -403.579584)
		(end 310.694578 -403.443694)
		(stroke
			(width 0.07112)
			(type default)
		)
		(layer "In15.Cu")
	)
	(gr_line
		(start 310.630316 -417.830762)
		(end 310.630316 -417.404042)
		(stroke
			(width 0.07112)
			(type default)
		)
		(layer "In15.Cu")
	)
	(gr_line
		(start 310.630316 -417.404042)
		(end 310.494426 -417.268152)
		(stroke
			(width 0.07112)
			(type default)
		)
		(layer "In15.Cu")
	)
	(gr_line
		(start 310.630316 -416.703002)
		(end 310.630316 -416.276282)
		(stroke
			(width 0.07112)
			(type default)
		)
		(layer "In15.Cu")
	)
	(gr_line
		(start 310.630316 -416.276282)
		(end 310.494426 -416.140392)
		(stroke
			(width 0.07112)
			(type default)
		)
		(layer "In15.Cu")
	)
	(gr_line
		(start 310.650382 -407.453338)
		(end 310.458104 -407.453338)
		(stroke
			(width 0.07112)
			(type default)
		)
		(layer "In15.Cu")
	)
	(gr_line
		(start 310.694578 -404.571454)
		(end 310.694578 -404.144734)
		(stroke
			(width 0.07112)
			(type default)
		)
		(layer "In15.Cu")
	)
	(gr_line
		(start 310.694578 -404.144734)
		(end 310.558688 -404.008844)
		(stroke
			(width 0.07112)
			(type default)
		)
		(layer "In15.Cu")
	)
	(gr_line
		(start 310.694578 -403.443694)
		(end 310.694578 -403.016974)
		(stroke
			(width 0.07112)
			(type default)
		)
		(layer "In15.Cu")
	)
	(gr_line
		(start 310.694578 -403.016974)
		(end 310.558688 -402.881084)
		(stroke
			(width 0.07112)
			(type default)
		)
		(layer "In15.Cu")
	)
	(gr_line
		(start 310.752998 -408.14879)
		(end 310.256936 -407.652728)
		(stroke
			(width 0.07112)
			(type default)
		)
		(layer "In15.Cu")
	)
	(gr_line
		(start 310.87695 -401.089622)
		(end 310.889396 -401.089622)
		(stroke
			(width 0.07112)
			(type default)
		)
		(layer "In15.Cu")
	)
	(gr_line
		(start 310.87822 -401.372832)
		(end 311.016396 -401.511008)
		(stroke
			(width 0.07112)
			(type default)
		)
		(layer "In15.Cu")
	)
	(gr_line
		(start 310.889396 -401.089622)
		(end 311.016396 -400.962622)
		(stroke
			(width 0.07112)
			(type default)
		)
		(layer "In15.Cu")
	)
	(gr_line
		(start 310.952388 -407.947622)
		(end 310.952388 -407.755344)
		(stroke
			(width 0.07112)
			(type default)
		)
		(layer "In15.Cu")
	)
	(gr_line
		(start 310.952388 -407.755344)
		(end 310.650382 -407.453338)
		(stroke
			(width 0.07112)
			(type default)
		)
		(layer "In15.Cu")
	)
	(gr_line
		(start 311.016396 -401.511008)
		(end 311.016396 -401.674838)
		(stroke
			(width 0.07112)
			(type default)
		)
		(layer "In15.Cu")
	)
	(gr_line
		(start 311.016396 -400.962622)
		(end 311.016396 -400.811238)
		(stroke
			(width 0.07112)
			(type default)
		)
		(layer "In15.Cu")
	)
	(gr_line
		(start 311.052972 -406.161748)
		(end 310.860694 -406.161748)
		(stroke
			(width 0.07112)
			(type default)
		)
		(layer "In15.Cu")
	)
	(gr_line
		(start 311.068212 -409.501086)
		(end 310.875934 -409.501086)
		(stroke
			(width 0.07112)
			(type default)
		)
		(layer "In15.Cu")
	)
	(gr_line
		(start 311.155588 -406.8572)
		(end 310.659526 -406.361138)
		(stroke
			(width 0.07112)
			(type default)
		)
		(layer "In15.Cu")
	)
	(gr_line
		(start 311.170828 -410.196538)
		(end 310.674766 -409.700476)
		(stroke
			(width 0.07112)
			(type default)
		)
		(layer "In15.Cu")
	)
	(gr_line
		(start 311.354978 -406.656286)
		(end 311.354978 -406.463754)
		(stroke
			(width 0.07112)
			(type default)
		)
		(layer "In15.Cu")
	)
	(gr_line
		(start 311.354978 -406.463754)
		(end 311.052972 -406.161748)
		(stroke
			(width 0.07112)
			(type default)
		)
		(layer "In15.Cu")
	)
	(gr_line
		(start 311.370218 -409.99537)
		(end 311.370218 -409.803092)
		(stroke
			(width 0.07112)
			(type default)
		)
		(layer "In15.Cu")
	)
	(gr_line
		(start 311.370218 -409.803092)
		(end 311.068212 -409.501086)
		(stroke
			(width 0.07112)
			(type default)
		)
		(layer "In15.Cu")
	)
	(gr_line
		(start 311.447942 -408.250898)
		(end 311.255664 -408.250898)
		(stroke
			(width 0.07112)
			(type default)
		)
		(layer "In15.Cu")
	)
	(gr_line
		(start 311.475374 -404.661624)
		(end 311.475374 -403.960584)
		(stroke
			(width 0.07112)
			(type default)
		)
		(layer "In15.Cu")
	)
	(gr_line
		(start 311.475374 -403.533864)
		(end 311.475374 -402.832824)
		(stroke
			(width 0.07112)
			(type default)
		)
		(layer "In15.Cu")
	)
	(gr_line
		(start 311.550558 -408.94635)
		(end 311.054496 -408.450288)
		(stroke
			(width 0.07112)
			(type default)
		)
		(layer "In15.Cu")
	)
	(gr_line
		(start 311.749948 -408.745182)
		(end 311.749948 -408.552904)
		(stroke
			(width 0.07112)
			(type default)
		)
		(layer "In15.Cu")
	)
	(gr_line
		(start 311.749948 -408.552904)
		(end 311.447942 -408.250898)
		(stroke
			(width 0.07112)
			(type default)
		)
		(layer "In15.Cu")
	)
	(gr_line
		(start 311.758584 -404.660354)
		(end 311.894474 -404.524464)
		(stroke
			(width 0.07112)
			(type default)
		)
		(layer "In15.Cu")
	)
	(gr_line
		(start 311.758584 -403.532594)
		(end 311.894474 -403.396704)
		(stroke
			(width 0.07112)
			(type default)
		)
		(layer "In15.Cu")
	)
	(gr_line
		(start 311.850532 -406.959308)
		(end 311.658 -406.959308)
		(stroke
			(width 0.07112)
			(type default)
		)
		(layer "In15.Cu")
	)
	(gr_line
		(start 311.894474 -404.524464)
		(end 311.894474 -404.097744)
		(stroke
			(width 0.07112)
			(type default)
		)
		(layer "In15.Cu")
	)
	(gr_line
		(start 311.894474 -404.097744)
		(end 311.758584 -403.961854)
		(stroke
			(width 0.07112)
			(type default)
		)
		(layer "In15.Cu")
	)
	(gr_line
		(start 311.894474 -403.396704)
		(end 311.894474 -402.969984)
		(stroke
			(width 0.07112)
			(type default)
		)
		(layer "In15.Cu")
	)
	(gr_line
		(start 311.894474 -402.969984)
		(end 311.758584 -402.834094)
		(stroke
			(width 0.07112)
			(type default)
		)
		(layer "In15.Cu")
	)
	(gr_line
		(start 311.953148 -407.655014)
		(end 311.457086 -407.158698)
		(stroke
			(width 0.07112)
			(type default)
		)
		(layer "In15.Cu")
	)
	(gr_line
		(start 311.953148 -407.655014)
		(end 311.953148 -407.65476)
		(stroke
			(width 0.07112)
			(type default)
		)
		(layer "In15.Cu")
	)
	(gr_line
		(start 312.076846 -401.089622)
		(end 312.089292 -401.089622)
		(stroke
			(width 0.07112)
			(type default)
		)
		(layer "In15.Cu")
	)
	(gr_line
		(start 312.078116 -401.372832)
		(end 312.216292 -401.511008)
		(stroke
			(width 0.07112)
			(type default)
		)
		(layer "In15.Cu")
	)
	(gr_line
		(start 312.089292 -401.089622)
		(end 312.216292 -400.962622)
		(stroke
			(width 0.07112)
			(type default)
		)
		(layer "In15.Cu")
	)
	(gr_line
		(start 312.152538 -407.453846)
		(end 312.152538 -407.261314)
		(stroke
			(width 0.07112)
			(type default)
		)
		(layer "In15.Cu")
	)
	(gr_line
		(start 312.152538 -407.261314)
		(end 311.850532 -406.959308)
		(stroke
			(width 0.07112)
			(type default)
		)
		(layer "In15.Cu")
	)
	(gr_line
		(start 312.216292 -401.511008)
		(end 312.216292 -401.674838)
		(stroke
			(width 0.07112)
			(type default)
		)
		(layer "In15.Cu")
	)
	(gr_line
		(start 312.216292 -400.962622)
		(end 312.216292 -400.811238)
		(stroke
			(width 0.07112)
			(type default)
		)
		(layer "In15.Cu")
	)
	(gr_line
		(start 312.252868 -405.77008)
		(end 312.06059 -405.77008)
		(stroke
			(width 0.07112)
			(type default)
		)
		(layer "In15.Cu")
	)
	(gr_line
		(start 312.26379 -409.066746)
		(end 312.071512 -409.066746)
		(stroke
			(width 0.07112)
			(type default)
		)
		(layer "In15.Cu")
	)
	(gr_line
		(start 312.355484 -406.465532)
		(end 311.859422 -405.96947)
		(stroke
			(width 0.07112)
			(type default)
		)
		(layer "In15.Cu")
	)
	(gr_line
		(start 312.366406 -409.762198)
		(end 311.870344 -409.266136)
		(stroke
			(width 0.07112)
			(type default)
		)
		(layer "In15.Cu")
	)
	(gr_line
		(start 312.554874 -406.264364)
		(end 312.554874 -406.072086)
		(stroke
			(width 0.07112)
			(type default)
		)
		(layer "In15.Cu")
	)
	(gr_line
		(start 312.554874 -406.072086)
		(end 312.252868 -405.77008)
		(stroke
			(width 0.07112)
			(type default)
		)
		(layer "In15.Cu")
	)
	(gr_line
		(start 312.565796 -409.56103)
		(end 312.565796 -409.368752)
		(stroke
			(width 0.07112)
			(type default)
		)
		(layer "In15.Cu")
	)
	(gr_line
		(start 312.565796 -409.368752)
		(end 312.26379 -409.066746)
		(stroke
			(width 0.07112)
			(type default)
		)
		(layer "In15.Cu")
	)
	(gr_line
		(start 312.648092 -407.756868)
		(end 312.455814 -407.756868)
		(stroke
			(width 0.07112)
			(type default)
		)
		(layer "In15.Cu")
	)
	(gr_line
		(start 312.675524 -404.681944)
		(end 312.675524 -403.980904)
		(stroke
			(width 0.07112)
			(type default)
		)
		(layer "In15.Cu")
	)
	(gr_line
		(start 312.675524 -403.554184)
		(end 312.675524 -402.853144)
		(stroke
			(width 0.07112)
			(type default)
		)
		(layer "In15.Cu")
	)
	(gr_line
		(start 312.750708 -408.45232)
		(end 312.254646 -407.956258)
		(stroke
			(width 0.07112)
			(type default)
		)
		(layer "In15.Cu")
	)
	(gr_line
		(start 312.950098 -408.251152)
		(end 312.950098 -408.058874)
		(stroke
			(width 0.07112)
			(type default)
		)
		(layer "In15.Cu")
	)
	(gr_line
		(start 312.950098 -408.058874)
		(end 312.648092 -407.756868)
		(stroke
			(width 0.07112)
			(type default)
		)
		(layer "In15.Cu")
	)
	(gr_line
		(start 312.958734 -404.680674)
		(end 313.094624 -404.544784)
		(stroke
			(width 0.07112)
			(type default)
		)
		(layer "In15.Cu")
	)
	(gr_line
		(start 312.958734 -403.552914)
		(end 313.094624 -403.417024)
		(stroke
			(width 0.07112)
			(type default)
		)
		(layer "In15.Cu")
	)
	(gr_line
		(start 313.050428 -406.56764)
		(end 312.85815 -406.56764)
		(stroke
			(width 0.07112)
			(type default)
		)
		(layer "In15.Cu")
	)
	(gr_line
		(start 313.094624 -404.544784)
		(end 313.094624 -404.118064)
		(stroke
			(width 0.07112)
			(type default)
		)
		(layer "In15.Cu")
	)
	(gr_line
		(start 313.094624 -404.118064)
		(end 312.958734 -403.982174)
		(stroke
			(width 0.07112)
			(type default)
		)
		(layer "In15.Cu")
	)
	(gr_line
		(start 313.094624 -403.417024)
		(end 313.094624 -402.990304)
		(stroke
			(width 0.07112)
			(type default)
		)
		(layer "In15.Cu")
	)
	(gr_line
		(start 313.094624 -402.990304)
		(end 312.958734 -402.854414)
		(stroke
			(width 0.07112)
			(type default)
		)
		(layer "In15.Cu")
	)
	(gr_line
		(start 313.153044 -407.263092)
		(end 312.657236 -406.767284)
		(stroke
			(width 0.07112)
			(type default)
		)
		(layer "In15.Cu")
	)
	(gr_line
		(start 313.274456 -417.909502)
		(end 313.274456 -417.208462)
		(stroke
			(width 0.07112)
			(type default)
		)
		(layer "In15.Cu")
	)
	(gr_line
		(start 313.274456 -416.781742)
		(end 313.274456 -416.080702)
		(stroke
			(width 0.07112)
			(type default)
		)
		(layer "In15.Cu")
	)
	(gr_line
		(start 313.276996 -401.089622)
		(end 313.289442 -401.089622)
		(stroke
			(width 0.07112)
			(type default)
		)
		(layer "In15.Cu")
	)
	(gr_line
		(start 313.278266 -401.372832)
		(end 313.416442 -401.511008)
		(stroke
			(width 0.07112)
			(type default)
		)
		(layer "In15.Cu")
	)
	(gr_line
		(start 313.289442 -401.089622)
		(end 313.416442 -400.962622)
		(stroke
			(width 0.07112)
			(type default)
		)
		(layer "In15.Cu")
	)
	(gr_line
		(start 313.352434 -407.061924)
		(end 313.352434 -406.869646)
		(stroke
			(width 0.07112)
			(type default)
		)
		(layer "In15.Cu")
	)
	(gr_line
		(start 313.352434 -406.869646)
		(end 313.050428 -406.56764)
		(stroke
			(width 0.07112)
			(type default)
		)
		(layer "In15.Cu")
	)
	(gr_line
		(start 313.391042 -393.69238)
		(end 313.744356 -393.787376)
		(stroke
			(width 0.07112)
			(type default)
		)
		(layer "In15.Cu")
	)
	(gr_line
		(start 313.416442 -401.511008)
		(end 313.416442 -401.674838)
		(stroke
			(width 0.07112)
			(type default)
		)
		(layer "In15.Cu")
	)
	(gr_line
		(start 313.416442 -400.962622)
		(end 313.416442 -400.811238)
		(stroke
			(width 0.07112)
			(type default)
		)
		(layer "In15.Cu")
	)
	(gr_line
		(start 313.557666 -417.908232)
		(end 313.693556 -417.772342)
		(stroke
			(width 0.07112)
			(type default)
		)
		(layer "In15.Cu")
	)
	(gr_line
		(start 313.557666 -416.780472)
		(end 313.693556 -416.644582)
		(stroke
			(width 0.07112)
			(type default)
		)
		(layer "In15.Cu")
	)
	(gr_line
		(start 313.645296 -422.299384)
		(end 313.475624 -422.390062)
		(stroke
			(width 0.07112)
			(type default)
		)
		(layer "In15.Cu")
	)
	(gr_line
		(start 313.693556 -417.772342)
		(end 313.693556 -417.345622)
		(stroke
			(width 0.07112)
			(type default)
		)
		(layer "In15.Cu")
	)
	(gr_line
		(start 313.693556 -417.345622)
		(end 313.557666 -417.209732)
		(stroke
			(width 0.07112)
			(type default)
		)
		(layer "In15.Cu")
	)
	(gr_line
		(start 313.693556 -416.644582)
		(end 313.693556 -416.217862)
		(stroke
			(width 0.07112)
			(type default)
		)
		(layer "In15.Cu")
	)
	(gr_line
		(start 313.693556 -416.217862)
		(end 313.557666 -416.081972)
		(stroke
			(width 0.07112)
			(type default)
		)
		(layer "In15.Cu")
	)
	(gr_line
		(start 313.744356 -393.787376)
		(end 313.744864 -393.786868)
		(stroke
			(width 0.07112)
			(type default)
		)
		(layer "In15.Cu")
	)
	(gr_line
		(start 313.791092 -394.385292)
		(end 313.885834 -394.031724)
		(stroke
			(width 0.07112)
			(type default)
		)
		(layer "In15.Cu")
	)
	(gr_line
		(start 313.858402 -386.210048)
		(end 313.858402 -386.20954)
		(stroke
			(width 0.07112)
			(type default)
		)
		(layer "In15.Cu")
	)
	(gr_line
		(start 313.87542 -404.183596)
		(end 313.87542 -403.482556)
		(stroke
			(width 0.07112)
			(type default)
		)
		(layer "In15.Cu")
	)
	(gr_line
		(start 313.927998 -407.445464)
		(end 313.735974 -407.445464)
		(stroke
			(width 0.07112)
			(type default)
		)
		(layer "In15.Cu")
	)
	(gr_line
		(start 314.0075 -393.961112)
		(end 314.060332 -393.930632)
		(stroke
			(width 0.07112)
			(type default)
		)
		(layer "In15.Cu")
	)
	(gr_line
		(start 314.030614 -408.140662)
		(end 313.534806 -407.644854)
		(stroke
			(width 0.07112)
			(type default)
		)
		(layer "In15.Cu")
	)
	(gr_line
		(start 314.05195 -406.009348)
		(end 313.859926 -406.009348)
		(stroke
			(width 0.07112)
			(type default)
		)
		(layer "In15.Cu")
	)
	(gr_line
		(start 314.053982 -422.423082)
		(end 313.645296 -422.299384)
		(stroke
			(width 0.07112)
			(type default)
		)
		(layer "In15.Cu")
	)
	(gr_line
		(start 314.060332 -393.930632)
		(end 314.14847 -393.842494)
		(stroke
			(width 0.07112)
			(type default)
		)
		(layer "In15.Cu")
	)
	(gr_line
		(start 314.064142 -422.864026)
		(end 313.392566 -422.66108)
		(stroke
			(width 0.07112)
			(type default)
		)
		(layer "In15.Cu")
	)
	(gr_line
		(start 314.070746 -422.866058)
		(end 314.064142 -422.864026)
		(stroke
			(width 0.07112)
			(type default)
		)
		(layer "In15.Cu")
	)
	(gr_line
		(start 314.144914 -422.592754)
		(end 314.053982 -422.423082)
		(stroke
			(width 0.07112)
			(type default)
		)
		(layer "In15.Cu")
	)
	(gr_line
		(start 314.14847 -393.842494)
		(end 314.14847 -393.716764)
		(stroke
			(width 0.07112)
			(type default)
		)
		(layer "In15.Cu")
	)
	(gr_line
		(start 314.15228 -422.59631)
		(end 314.145676 -422.594278)
		(stroke
			(width 0.07112)
			(type default)
		)
		(layer "In15.Cu")
	)
	(gr_line
		(start 314.154566 -406.704546)
		(end 313.658758 -406.208738)
		(stroke
			(width 0.07112)
			(type default)
		)
		(layer "In15.Cu")
	)
	(gr_line
		(start 314.15863 -404.182326)
		(end 314.29452 -404.046436)
		(stroke
			(width 0.07112)
			(type default)
		)
		(layer "In15.Cu")
	)
	(gr_line
		(start 314.230004 -407.939494)
		(end 314.230004 -407.74747)
		(stroke
			(width 0.07112)
			(type default)
		)
		(layer "In15.Cu")
	)
	(gr_line
		(start 314.230004 -407.74747)
		(end 313.927998 -407.445464)
		(stroke
			(width 0.07112)
			(type default)
		)
		(layer "In15.Cu")
	)
	(gr_line
		(start 314.29452 -404.046436)
		(end 314.29452 -403.619716)
		(stroke
			(width 0.07112)
			(type default)
		)
		(layer "In15.Cu")
	)
	(gr_line
		(start 314.29452 -403.619716)
		(end 314.15863 -403.483826)
		(stroke
			(width 0.07112)
			(type default)
		)
		(layer "In15.Cu")
	)
	(gr_line
		(start 314.353956 -406.503378)
		(end 314.353956 -406.311354)
		(stroke
			(width 0.07112)
			(type default)
		)
		(layer "In15.Cu")
	)
	(gr_line
		(start 314.353956 -406.311354)
		(end 314.05195 -406.009348)
		(stroke
			(width 0.07112)
			(type default)
		)
		(layer "In15.Cu")
	)
	(gr_line
		(start 314.467494 -401.393406)
		(end 314.489338 -401.393406)
		(stroke
			(width 0.07112)
			(type default)
		)
		(layer "In15.Cu")
	)
	(gr_line
		(start 314.468764 -401.110196)
		(end 314.616338 -400.962622)
		(stroke
			(width 0.07112)
			(type default)
		)
		(layer "In15.Cu")
	)
	(gr_line
		(start 314.489338 -401.393406)
		(end 314.616338 -401.520406)
		(stroke
			(width 0.07112)
			(type default)
		)
		(layer "In15.Cu")
	)
	(gr_line
		(start 314.503562 -437.3372)
		(end 314.49899 -437.3372)
		(stroke
			(width 0.07112)
			(type default)
		)
		(layer "In15.Cu")
	)
	(gr_line
		(start 314.590938 -393.69238)
		(end 314.944252 -393.787376)
		(stroke
			(width 0.07112)
			(type default)
		)
		(layer "In15.Cu")
	)
	(gr_line
		(start 314.616338 -401.520406)
		(end 314.616338 -401.674838)
		(stroke
			(width 0.07112)
			(type default)
		)
		(layer "In15.Cu")
	)
	(gr_line
		(start 314.616338 -400.962622)
		(end 314.616338 -400.811238)
		(stroke
			(width 0.07112)
			(type default)
		)
		(layer "In15.Cu")
	)
	(gr_line
		(start 314.649612 -438.089802)
		(end 314.649612 -437.769762)
		(stroke
			(width 0.07112)
			(type default)
		)
		(layer "In15.Cu")
	)
	(gr_line
		(start 314.649612 -437.769762)
		(end 314.50026 -437.62041)
		(stroke
			(width 0.07112)
			(type default)
		)
		(layer "In15.Cu")
	)
	(gr_line
		(start 314.649612 -437.19115)
		(end 314.503562 -437.3372)
		(stroke
			(width 0.07112)
			(type default)
		)
		(layer "In15.Cu")
	)
	(gr_line
		(start 314.649612 -436.889906)
		(end 314.649612 -437.19115)
		(stroke
			(width 0.07112)
			(type default)
		)
		(layer "In15.Cu")
	)
	(gr_line
		(start 314.652914 -404.964646)
		(end 314.460636 -404.964646)
		(stroke
			(width 0.07112)
			(type default)
		)
		(layer "In15.Cu")
	)
	(gr_line
		(start 314.75553 -405.660098)
		(end 314.259468 -405.164036)
		(stroke
			(width 0.07112)
			(type default)
		)
		(layer "In15.Cu")
	)
	(gr_line
		(start 314.944252 -393.787376)
		(end 314.94476 -393.786868)
		(stroke
			(width 0.07112)
			(type default)
		)
		(layer "In15.Cu")
	)
	(gr_line
		(start 314.95492 -405.459184)
		(end 314.95492 -405.266652)
		(stroke
			(width 0.07112)
			(type default)
		)
		(layer "In15.Cu")
	)
	(gr_line
		(start 314.95492 -405.266652)
		(end 314.652914 -404.964646)
		(stroke
			(width 0.07112)
			(type default)
		)
		(layer "In15.Cu")
	)
	(gr_line
		(start 314.990988 -394.385292)
		(end 315.08573 -394.031724)
		(stroke
			(width 0.07112)
			(type default)
		)
		(layer "In15.Cu")
	)
	(gr_line
		(start 315.048138 -407.005282)
		(end 314.85586 -407.005282)
		(stroke
			(width 0.07112)
			(type default)
		)
		(layer "In15.Cu")
	)
	(gr_line
		(start 315.058298 -387.993128)
		(end 315.058298 -387.99262)
		(stroke
			(width 0.07112)
			(type default)
		)
		(layer "In15.Cu")
	)
	(gr_line
		(start 315.06795 -407.61793)
		(end 314.654692 -407.204672)
		(stroke
			(width 0.07112)
			(type default)
		)
		(layer "In15.Cu")
	)
	(gr_line
		(start 315.068204 -407.61793)
		(end 315.06795 -407.61793)
		(stroke
			(width 0.07112)
			(type default)
		)
		(layer "In15.Cu")
	)
	(gr_line
		(start 315.07557 -403.721062)
		(end 315.07557 -403.020022)
		(stroke
			(width 0.07112)
			(type default)
		)
		(layer "In15.Cu")
	)
	(gr_line
		(start 315.150754 -407.70048)
		(end 315.068204 -407.61793)
		(stroke
			(width 0.07112)
			(type default)
		)
		(layer "In15.Cu")
	)
	(gr_line
		(start 315.207396 -393.961112)
		(end 315.260228 -393.930632)
		(stroke
			(width 0.07112)
			(type default)
		)
		(layer "In15.Cu")
	)
	(gr_line
		(start 315.260228 -393.930632)
		(end 315.348366 -393.842494)
		(stroke
			(width 0.07112)
			(type default)
		)
		(layer "In15.Cu")
	)
	(gr_line
		(start 315.348366 -393.842494)
		(end 315.348366 -393.716764)
		(stroke
			(width 0.07112)
			(type default)
		)
		(layer "In15.Cu")
	)
	(gr_line
		(start 315.350144 -407.499312)
		(end 315.350144 -407.307288)
		(stroke
			(width 0.07112)
			(type default)
		)
		(layer "In15.Cu")
	)
	(gr_line
		(start 315.350144 -407.307288)
		(end 315.048138 -407.005282)
		(stroke
			(width 0.07112)
			(type default)
		)
		(layer "In15.Cu")
	)
	(gr_line
		(start 315.35878 -403.719792)
		(end 315.49467 -403.583902)
		(stroke
			(width 0.07112)
			(type default)
		)
		(layer "In15.Cu")
	)
	(gr_line
		(start 315.439298 -405.762206)
		(end 315.257942 -405.762206)
		(stroke
			(width 0.07112)
			(type default)
		)
		(layer "In15.Cu")
	)
	(gr_line
		(start 315.470286 -406.375108)
		(end 315.057028 -405.961596)
		(stroke
			(width 0.07112)
			(type default)
		)
		(layer "In15.Cu")
	)
	(gr_line
		(start 315.47054 -406.375108)
		(end 315.470286 -406.375108)
		(stroke
			(width 0.07112)
			(type default)
		)
		(layer "In15.Cu")
	)
	(gr_line
		(start 315.49467 -403.583902)
		(end 315.49467 -403.157182)
		(stroke
			(width 0.07112)
			(type default)
		)
		(layer "In15.Cu")
	)
	(gr_line
		(start 315.49467 -403.157182)
		(end 315.35878 -403.021292)
		(stroke
			(width 0.07112)
			(type default)
		)
		(layer "In15.Cu")
	)
	(gr_line
		(start 315.55309 -406.457658)
		(end 315.47054 -406.375108)
		(stroke
			(width 0.07112)
			(type default)
		)
		(layer "In15.Cu")
	)
	(gr_line
		(start 315.677042 -401.089622)
		(end 315.689488 -401.089622)
		(stroke
			(width 0.07112)
			(type default)
		)
		(layer "In15.Cu")
	)
	(gr_line
		(start 315.678312 -401.372832)
		(end 315.816488 -401.511008)
		(stroke
			(width 0.07112)
			(type default)
		)
		(layer "In15.Cu")
	)
	(gr_line
		(start 315.689488 -401.089622)
		(end 315.816488 -400.962622)
		(stroke
			(width 0.07112)
			(type default)
		)
		(layer "In15.Cu")
	)
	(gr_line
		(start 315.75248 -406.25649)
		(end 315.75248 -406.075388)
		(stroke
			(width 0.07112)
			(type default)
		)
		(layer "In15.Cu")
	)
	(gr_line
		(start 315.75248 -406.075388)
		(end 315.439298 -405.762206)
		(stroke
			(width 0.07112)
			(type default)
		)
		(layer "In15.Cu")
	)
	(gr_line
		(start 315.791088 -393.69238)
		(end 316.144402 -393.787376)
		(stroke
			(width 0.07112)
			(type default)
		)
		(layer "In15.Cu")
	)
	(gr_line
		(start 315.816488 -401.511008)
		(end 315.816488 -401.674838)
		(stroke
			(width 0.07112)
			(type default)
		)
		(layer "In15.Cu")
	)
	(gr_line
		(start 315.816488 -400.962622)
		(end 315.816488 -400.811238)
		(stroke
			(width 0.07112)
			(type default)
		)
		(layer "In15.Cu")
	)
	(gr_line
		(start 316.144402 -393.787376)
		(end 316.14491 -393.786868)
		(stroke
			(width 0.07112)
			(type default)
		)
		(layer "In15.Cu")
	)
	(gr_line
		(start 316.191138 -394.385292)
		(end 316.28588 -394.031724)
		(stroke
			(width 0.07112)
			(type default)
		)
		(layer "In15.Cu")
	)
	(gr_line
		(start 316.275466 -403.582124)
		(end 316.275466 -402.881084)
		(stroke
			(width 0.07112)
			(type default)
		)
		(layer "In15.Cu")
	)
	(gr_line
		(start 316.337696 -417.296854)
		(end 316.337696 -416.595814)
		(stroke
			(width 0.07112)
			(type default)
		)
		(layer "In15.Cu")
	)
	(gr_line
		(start 316.407546 -393.961112)
		(end 316.460378 -393.930632)
		(stroke
			(width 0.07112)
			(type default)
		)
		(layer "In15.Cu")
	)
	(gr_line
		(start 316.460378 -393.930632)
		(end 316.548516 -393.842494)
		(stroke
			(width 0.07112)
			(type default)
		)
		(layer "In15.Cu")
	)
	(gr_line
		(start 316.503558 -438.337198)
		(end 316.498986 -438.337198)
		(stroke
			(width 0.07112)
			(type default)
		)
		(layer "In15.Cu")
	)
	(gr_line
		(start 316.548516 -393.842494)
		(end 316.548516 -393.716764)
		(stroke
			(width 0.07112)
			(type default)
		)
		(layer "In15.Cu")
	)
	(gr_line
		(start 316.558676 -403.580854)
		(end 316.694566 -403.444964)
		(stroke
			(width 0.07112)
			(type default)
		)
		(layer "In15.Cu")
	)
	(gr_line
		(start 316.620906 -417.295584)
		(end 316.756796 -417.159694)
		(stroke
			(width 0.07112)
			(type default)
		)
		(layer "In15.Cu")
	)
	(gr_line
		(start 316.649608 -439.0898)
		(end 316.649608 -438.76976)
		(stroke
			(width 0.07112)
			(type default)
		)
		(layer "In15.Cu")
	)
	(gr_line
		(start 316.649608 -438.76976)
		(end 316.500256 -438.620408)
		(stroke
			(width 0.07112)
			(type default)
		)
		(layer "In15.Cu")
	)
	(gr_line
		(start 316.649608 -438.191148)
		(end 316.503558 -438.337198)
		(stroke
			(width 0.07112)
			(type default)
		)
		(layer "In15.Cu")
	)
	(gr_line
		(start 316.649608 -437.889904)
		(end 316.649608 -438.191148)
		(stroke
			(width 0.07112)
			(type default)
		)
		(layer "In15.Cu")
	)
	(gr_line
		(start 316.694566 -403.444964)
		(end 316.694566 -403.018244)
		(stroke
			(width 0.07112)
			(type default)
		)
		(layer "In15.Cu")
	)
	(gr_line
		(start 316.694566 -403.018244)
		(end 316.558676 -402.882354)
		(stroke
			(width 0.07112)
			(type default)
		)
		(layer "In15.Cu")
	)
	(gr_line
		(start 316.73419 -2.678176)
		(end 316.44336 -2.969006)
		(stroke
			(width 0.07112)
			(type default)
		)
		(layer "In15.Cu")
	)
	(gr_line
		(start 316.73419 -2.396236)
		(end 316.44336 -2.105406)
		(stroke
			(width 0.07112)
			(type default)
		)
		(layer "In15.Cu")
	)
	(gr_line
		(start 316.756796 -417.159694)
		(end 316.756796 -416.732974)
		(stroke
			(width 0.07112)
			(type default)
		)
		(layer "In15.Cu")
	)
	(gr_line
		(start 316.756796 -416.732974)
		(end 316.620906 -416.597084)
		(stroke
			(width 0.07112)
			(type default)
		)
		(layer "In15.Cu")
	)
	(gr_line
		(start 316.876938 -401.089622)
		(end 316.889384 -401.089622)
		(stroke
			(width 0.07112)
			(type default)
		)
		(layer "In15.Cu")
	)
	(gr_line
		(start 316.878208 -401.372832)
		(end 317.016384 -401.511008)
		(stroke
			(width 0.07112)
			(type default)
		)
		(layer "In15.Cu")
	)
	(gr_line
		(start 316.889384 -401.089622)
		(end 317.016384 -400.962622)
		(stroke
			(width 0.07112)
			(type default)
		)
		(layer "In15.Cu")
	)
	(gr_line
		(start 316.990984 -393.69238)
		(end 317.344298 -393.787376)
		(stroke
			(width 0.07112)
			(type default)
		)
		(layer "In15.Cu")
	)
	(gr_line
		(start 317.016384 -401.511008)
		(end 317.016384 -401.674838)
		(stroke
			(width 0.07112)
			(type default)
		)
		(layer "In15.Cu")
	)
	(gr_line
		(start 317.016384 -400.962622)
		(end 317.016384 -400.811238)
		(stroke
			(width 0.07112)
			(type default)
		)
		(layer "In15.Cu")
	)
	(gr_line
		(start 317.344298 -393.787376)
		(end 317.344806 -393.786868)
		(stroke
			(width 0.07112)
			(type default)
		)
		(layer "In15.Cu")
	)
	(gr_line
		(start 317.391034 -394.385292)
		(end 317.485776 -394.031724)
		(stroke
			(width 0.07112)
			(type default)
		)
		(layer "In15.Cu")
	)
	(gr_arc
		(start 317.475362 -403.448266)
		(mid 317.475362 -403.448012)
		(end 317.475362 -403.447758)
		(stroke
			(width 0.07112)
			(type default)
		)
		(layer "In15.Cu")
	)
	(gr_line
		(start 317.475362 -403.33041)
		(end 317.475362 -402.682202)
		(stroke
			(width 0.07112)
			(type default)
		)
		(layer "In15.Cu")
	)
	(gr_line
		(start 317.59525 -404.912322)
		(end 317.403226 -404.921974)
		(stroke
			(width 0.07112)
			(type default)
		)
		(layer "In15.Cu")
	)
	(gr_line
		(start 317.607442 -393.961112)
		(end 317.660274 -393.930632)
		(stroke
			(width 0.07112)
			(type default)
		)
		(layer "In15.Cu")
	)
	(gr_line
		(start 317.660274 -393.930632)
		(end 317.748412 -393.842494)
		(stroke
			(width 0.07112)
			(type default)
		)
		(layer "In15.Cu")
	)
	(gr_line
		(start 317.73241 -405.601678)
		(end 317.212218 -405.131016)
		(stroke
			(width 0.07112)
			(type default)
		)
		(layer "In15.Cu")
	)
	(gr_line
		(start 317.748412 -393.842494)
		(end 317.748412 -393.716764)
		(stroke
			(width 0.07112)
			(type default)
		)
		(layer "In15.Cu")
	)
	(gr_line
		(start 317.758572 -403.32914)
		(end 317.868046 -403.219666)
		(stroke
			(width 0.07112)
			(type default)
		)
		(layer "In15.Cu")
	)
	(gr_line
		(start 317.868046 -403.219666)
		(end 317.868046 -402.792946)
		(stroke
			(width 0.07112)
			(type default)
		)
		(layer "In15.Cu")
	)
	(gr_line
		(start 317.868046 -402.792946)
		(end 317.758572 -402.683472)
		(stroke
			(width 0.07112)
			(type default)
		)
		(layer "In15.Cu")
	)
	(gr_line
		(start 317.911988 -405.199088)
		(end 317.59525 -404.912322)
		(stroke
			(width 0.07112)
			(type default)
		)
		(layer "In15.Cu")
	)
	(gr_line
		(start 317.92164 -405.390858)
		(end 317.911988 -405.199088)
		(stroke
			(width 0.07112)
			(type default)
		)
		(layer "In15.Cu")
	)
	(gr_line
		(start 318.076834 -401.089622)
		(end 318.08928 -401.089622)
		(stroke
			(width 0.07112)
			(type default)
		)
		(layer "In15.Cu")
	)
	(gr_line
		(start 318.078104 -401.372832)
		(end 318.21628 -401.511008)
		(stroke
			(width 0.07112)
			(type default)
		)
		(layer "In15.Cu")
	)
	(gr_line
		(start 318.08928 -401.089622)
		(end 318.21628 -400.962622)
		(stroke
			(width 0.07112)
			(type default)
		)
		(layer "In15.Cu")
	)
	(gr_line
		(start 318.191134 -393.69238)
		(end 318.544194 -393.787376)
		(stroke
			(width 0.07112)
			(type default)
		)
		(layer "In15.Cu")
	)
	(gr_line
		(start 318.21628 -401.511008)
		(end 318.21628 -401.674838)
		(stroke
			(width 0.07112)
			(type default)
		)
		(layer "In15.Cu")
	)
	(gr_line
		(start 318.21628 -400.962622)
		(end 318.21628 -400.811238)
		(stroke
			(width 0.07112)
			(type default)
		)
		(layer "In15.Cu")
	)
	(gr_line
		(start 318.503046 -437.623204)
		(end 318.49949 -437.623204)
		(stroke
			(width 0.07112)
			(type default)
		)
		(layer "In15.Cu")
	)
	(gr_line
		(start 318.544194 -393.787376)
		(end 318.544702 -393.786868)
		(stroke
			(width 0.07112)
			(type default)
		)
		(layer "In15.Cu")
	)
	(gr_line
		(start 318.59093 -394.385292)
		(end 318.685672 -394.031724)
		(stroke
			(width 0.07112)
			(type default)
		)
		(layer "In15.Cu")
	)
	(gr_line
		(start 318.649604 -438.089802)
		(end 318.649604 -437.769762)
		(stroke
			(width 0.07112)
			(type default)
		)
		(layer "In15.Cu")
	)
	(gr_line
		(start 318.649604 -437.769762)
		(end 318.503046 -437.623204)
		(stroke
			(width 0.07112)
			(type default)
		)
		(layer "In15.Cu")
	)
	(gr_line
		(start 318.649604 -437.19115)
		(end 318.50076 -437.339994)
		(stroke
			(width 0.07112)
			(type default)
		)
		(layer "In15.Cu")
	)
	(gr_line
		(start 318.649604 -436.889906)
		(end 318.649604 -437.19115)
		(stroke
			(width 0.07112)
			(type default)
		)
		(layer "In15.Cu")
	)
	(gr_line
		(start 318.807338 -393.961112)
		(end 318.86017 -393.930632)
		(stroke
			(width 0.07112)
			(type default)
		)
		(layer "In15.Cu")
	)
	(gr_line
		(start 318.86017 -393.930632)
		(end 318.948308 -393.842494)
		(stroke
			(width 0.07112)
			(type default)
		)
		(layer "In15.Cu")
	)
	(gr_line
		(start 318.948308 -393.842494)
		(end 318.948308 -393.716764)
		(stroke
			(width 0.07112)
			(type default)
		)
		(layer "In15.Cu")
	)
	(gr_line
		(start 319.289176 -401.371562)
		(end 319.416176 -401.498562)
		(stroke
			(width 0.07112)
			(type default)
		)
		(layer "In15.Cu")
	)
	(gr_line
		(start 319.289176 -401.089622)
		(end 319.416176 -400.962622)
		(stroke
			(width 0.07112)
			(type default)
		)
		(layer "In15.Cu")
	)
	(gr_line
		(start 319.39103 -393.69238)
		(end 319.744344 -393.787376)
		(stroke
			(width 0.07112)
			(type default)
		)
		(layer "In15.Cu")
	)
	(gr_line
		(start 319.400936 -418.175186)
		(end 319.400936 -417.474146)
		(stroke
			(width 0.07112)
			(type default)
		)
		(layer "In15.Cu")
	)
	(gr_line
		(start 319.400936 -417.047426)
		(end 319.400936 -416.346386)
		(stroke
			(width 0.07112)
			(type default)
		)
		(layer "In15.Cu")
	)
	(gr_line
		(start 319.416176 -401.498562)
		(end 319.416176 -401.674838)
		(stroke
			(width 0.07112)
			(type default)
		)
		(layer "In15.Cu")
	)
	(gr_line
		(start 319.416176 -400.962622)
		(end 319.416176 -400.811238)
		(stroke
			(width 0.07112)
			(type default)
		)
		(layer "In15.Cu")
	)
	(gr_line
		(start 319.436242 -422.602914)
		(end 319.250568 -422.639998)
		(stroke
			(width 0.07112)
			(type default)
		)
		(layer "In15.Cu")
	)
	(gr_line
		(start 319.671954 -423.26179)
		(end 319.092834 -422.875456)
		(stroke
			(width 0.07112)
			(type default)
		)
		(layer "In15.Cu")
	)
	(gr_line
		(start 319.684146 -418.173916)
		(end 319.820036 -418.038026)
		(stroke
			(width 0.07112)
			(type default)
		)
		(layer "In15.Cu")
	)
	(gr_line
		(start 319.684146 -417.046156)
		(end 319.820036 -416.910266)
		(stroke
			(width 0.07112)
			(type default)
		)
		(layer "In15.Cu")
	)
	(gr_line
		(start 319.744344 -393.787376)
		(end 319.744852 -393.786868)
		(stroke
			(width 0.07112)
			(type default)
		)
		(layer "In15.Cu")
	)
	(gr_line
		(start 319.79108 -394.385292)
		(end 319.885822 -394.031724)
		(stroke
			(width 0.07112)
			(type default)
		)
		(layer "In15.Cu")
	)
	(gr_line
		(start 319.791588 -422.839896)
		(end 319.436242 -422.602914)
		(stroke
			(width 0.07112)
			(type default)
		)
		(layer "In15.Cu")
	)
	(gr_line
		(start 319.820036 -418.038026)
		(end 319.820036 -417.611306)
		(stroke
			(width 0.07112)
			(type default)
		)
		(layer "In15.Cu")
	)
	(gr_line
		(start 319.820036 -417.611306)
		(end 319.684146 -417.475416)
		(stroke
			(width 0.07112)
			(type default)
		)
		(layer "In15.Cu")
	)
	(gr_line
		(start 319.820036 -416.910266)
		(end 319.820036 -416.483546)
		(stroke
			(width 0.07112)
			(type default)
		)
		(layer "In15.Cu")
	)
	(gr_line
		(start 319.820036 -416.483546)
		(end 319.684146 -416.347656)
		(stroke
			(width 0.07112)
			(type default)
		)
		(layer "In15.Cu")
	)
	(gr_arc
		(start 319.824354 -392.345418)
		(mid 319.846042 -392.308255)
		(end 319.85712 -392.266678)
		(stroke
			(width 0.07112)
			(type default)
		)
		(layer "In15.Cu")
	)
	(gr_line
		(start 319.82918 -423.026078)
		(end 319.791588 -422.839896)
		(stroke
			(width 0.07112)
			(type default)
		)
		(layer "In15.Cu")
	)
	(gr_line
		(start 320.007488 -393.961112)
		(end 320.06032 -393.930632)
		(stroke
			(width 0.07112)
			(type default)
		)
		(layer "In15.Cu")
	)
	(gr_line
		(start 320.033904 -392.536426)
		(end 320.14033 -392.43)
		(stroke
			(width 0.07112)
			(type default)
		)
		(layer "In15.Cu")
	)
	(gr_line
		(start 320.06032 -393.930632)
		(end 320.148458 -393.842494)
		(stroke
			(width 0.07112)
			(type default)
		)
		(layer "In15.Cu")
	)
	(gr_line
		(start 320.14033 -392.43)
		(end 320.14033 -392.279886)
		(stroke
			(width 0.07112)
			(type default)
		)
		(layer "In15.Cu")
	)
	(gr_line
		(start 320.148458 -393.842494)
		(end 320.148458 -393.716764)
		(stroke
			(width 0.07112)
			(type default)
		)
		(layer "In15.Cu")
	)
	(gr_line
		(start 320.47688 -401.089622)
		(end 320.489326 -401.089622)
		(stroke
			(width 0.07112)
			(type default)
		)
		(layer "In15.Cu")
	)
	(gr_line
		(start 320.47815 -401.372832)
		(end 320.616326 -401.511008)
		(stroke
			(width 0.07112)
			(type default)
		)
		(layer "In15.Cu")
	)
	(gr_line
		(start 320.489326 -401.089622)
		(end 320.616326 -400.962622)
		(stroke
			(width 0.07112)
			(type default)
		)
		(layer "In15.Cu")
	)
	(gr_line
		(start 320.503042 -438.623202)
		(end 320.499486 -438.623202)
		(stroke
			(width 0.07112)
			(type default)
		)
		(layer "In15.Cu")
	)
	(gr_line
		(start 320.59118 -393.69238)
		(end 320.94424 -393.787376)
		(stroke
			(width 0.07112)
			(type default)
		)
		(layer "In15.Cu")
	)
	(gr_line
		(start 320.616326 -401.511008)
		(end 320.616326 -401.674838)
		(stroke
			(width 0.07112)
			(type default)
		)
		(layer "In15.Cu")
	)
	(gr_line
		(start 320.616326 -400.962622)
		(end 320.616326 -400.811238)
		(stroke
			(width 0.07112)
			(type default)
		)
		(layer "In15.Cu")
	)
	(gr_line
		(start 320.6496 -439.0898)
		(end 320.6496 -438.76976)
		(stroke
			(width 0.07112)
			(type default)
		)
		(layer "In15.Cu")
	)
	(gr_line
		(start 320.6496 -438.76976)
		(end 320.503042 -438.623202)
		(stroke
			(width 0.07112)
			(type default)
		)
		(layer "In15.Cu")
	)
	(gr_line
		(start 320.6496 -438.191148)
		(end 320.500756 -438.339992)
		(stroke
			(width 0.07112)
			(type default)
		)
		(layer "In15.Cu")
	)
	(gr_line
		(start 320.6496 -437.889904)
		(end 320.6496 -438.191148)
		(stroke
			(width 0.07112)
			(type default)
		)
		(layer "In15.Cu")
	)
	(gr_line
		(start 320.94424 -393.787376)
		(end 320.944748 -393.786868)
		(stroke
			(width 0.07112)
			(type default)
		)
		(layer "In15.Cu")
	)
	(gr_line
		(start 320.990976 -394.385292)
		(end 321.085718 -394.031724)
		(stroke
			(width 0.07112)
			(type default)
		)
		(layer "In15.Cu")
	)
	(gr_line
		(start 321.207384 -393.961112)
		(end 321.260216 -393.930632)
		(stroke
			(width 0.07112)
			(type default)
		)
		(layer "In15.Cu")
	)
	(gr_line
		(start 321.260216 -393.930632)
		(end 321.348354 -393.842494)
		(stroke
			(width 0.07112)
			(type default)
		)
		(layer "In15.Cu")
	)
	(gr_line
		(start 321.348354 -393.842494)
		(end 321.348354 -393.716764)
		(stroke
			(width 0.07112)
			(type default)
		)
		(layer "In15.Cu")
	)
	(gr_line
		(start 321.661028 -424.923458)
		(end 321.661028 -424.923966)
		(stroke
			(width 0.07112)
			(type default)
		)
		(layer "In15.Cu")
	)
	(gr_line
		(start 321.676776 -401.089622)
		(end 321.689222 -401.089622)
		(stroke
			(width 0.07112)
			(type default)
		)
		(layer "In15.Cu")
	)
	(gr_line
		(start 321.678046 -401.372832)
		(end 321.816222 -401.511008)
		(stroke
			(width 0.07112)
			(type default)
		)
		(layer "In15.Cu")
	)
	(gr_line
		(start 321.689222 -401.089622)
		(end 321.816222 -400.962622)
		(stroke
			(width 0.07112)
			(type default)
		)
		(layer "In15.Cu")
	)
	(gr_line
		(start 321.747896 -411.21965)
		(end 321.747642 -411.21965)
		(stroke
			(width 0.07112)
			(type default)
		)
		(layer "In15.Cu")
	)
	(gr_line
		(start 321.791076 -393.69238)
		(end 322.14439 -393.787376)
		(stroke
			(width 0.07112)
			(type default)
		)
		(layer "In15.Cu")
	)
	(gr_line
		(start 321.816222 -401.511008)
		(end 321.816222 -401.674838)
		(stroke
			(width 0.07112)
			(type default)
		)
		(layer "In15.Cu")
	)
	(gr_line
		(start 321.816222 -400.962622)
		(end 321.816222 -400.811238)
		(stroke
			(width 0.07112)
			(type default)
		)
		(layer "In15.Cu")
	)
	(gr_line
		(start 321.93484 -424.856148)
		(end 321.93484 -424.85564)
		(stroke
			(width 0.07112)
			(type default)
		)
		(layer "In15.Cu")
	)
	(gr_line
		(start 322.034662 -410.884624)
		(end 321.857116 -410.958538)
		(stroke
			(width 0.07112)
			(type default)
		)
		(layer "In15.Cu")
	)
	(gr_line
		(start 322.14439 -393.787376)
		(end 322.144898 -393.786868)
		(stroke
			(width 0.07112)
			(type default)
		)
		(layer "In15.Cu")
	)
	(gr_line
		(start 322.191126 -394.385292)
		(end 322.285868 -394.031724)
		(stroke
			(width 0.07112)
			(type default)
		)
		(layer "In15.Cu")
	)
	(gr_line
		(start 322.301108 -423.26306)
		(end 321.886326 -422.704006)
		(stroke
			(width 0.07112)
			(type default)
		)
		(layer "In15.Cu")
	)
	(gr_line
		(start 322.301108 -422.563798)
		(end 322.114164 -422.536112)
		(stroke
			(width 0.07112)
			(type default)
		)
		(layer "In15.Cu")
	)
	(gr_line
		(start 322.395596 -411.487874)
		(end 321.747642 -411.21965)
		(stroke
			(width 0.07112)
			(type default)
		)
		(layer "In15.Cu")
	)
	(gr_line
		(start 322.407534 -393.961112)
		(end 322.460366 -393.930632)
		(stroke
			(width 0.07112)
			(type default)
		)
		(layer "In15.Cu")
	)
	(gr_line
		(start 322.429378 -411.047946)
		(end 322.034662 -410.884624)
		(stroke
			(width 0.07112)
			(type default)
		)
		(layer "In15.Cu")
	)
	(gr_line
		(start 322.460366 -393.930632)
		(end 322.548504 -393.842494)
		(stroke
			(width 0.07112)
			(type default)
		)
		(layer "In15.Cu")
	)
	(gr_line
		(start 322.464176 -417.7538)
		(end 322.464176 -417.05276)
		(stroke
			(width 0.07112)
			(type default)
		)
		(layer "In15.Cu")
	)
	(gr_line
		(start 322.464176 -416.62604)
		(end 322.464176 -415.925)
		(stroke
			(width 0.07112)
			(type default)
		)
		(layer "In15.Cu")
	)
	(gr_line
		(start 322.502784 -411.225746)
		(end 322.429378 -411.047946)
		(stroke
			(width 0.07112)
			(type default)
		)
		(layer "In15.Cu")
	)
	(gr_line
		(start 322.503038 -437.623204)
		(end 322.499482 -437.623204)
		(stroke
			(width 0.07112)
			(type default)
		)
		(layer "In15.Cu")
	)
	(gr_line
		(start 322.503546 -411.22727)
		(end 322.503546 -411.227016)
		(stroke
			(width 0.07112)
			(type default)
		)
		(layer "In15.Cu")
	)
	(gr_line
		(start 322.509642 -312.52922)
		(end 322.509896 -312.52922)
		(stroke
			(width 0.07112)
			(type default)
		)
		(layer "In15.Cu")
	)
	(gr_line
		(start 322.52793 -423.093642)
		(end 322.555616 -422.906698)
		(stroke
			(width 0.07112)
			(type default)
		)
		(layer "In15.Cu")
	)
	(gr_line
		(start 322.548504 -393.842494)
		(end 322.548504 -393.716764)
		(stroke
			(width 0.07112)
			(type default)
		)
		(layer "In15.Cu")
	)
	(gr_line
		(start 322.555616 -422.906698)
		(end 322.301108 -422.563798)
		(stroke
			(width 0.07112)
			(type default)
		)
		(layer "In15.Cu")
	)
	(gr_line
		(start 322.649596 -438.089802)
		(end 322.649596 -437.769762)
		(stroke
			(width 0.07112)
			(type default)
		)
		(layer "In15.Cu")
	)
	(gr_line
		(start 322.649596 -437.769762)
		(end 322.503038 -437.623204)
		(stroke
			(width 0.07112)
			(type default)
		)
		(layer "In15.Cu")
	)
	(gr_line
		(start 322.649596 -437.19115)
		(end 322.500752 -437.339994)
		(stroke
			(width 0.07112)
			(type default)
		)
		(layer "In15.Cu")
	)
	(gr_line
		(start 322.649596 -436.889906)
		(end 322.649596 -437.19115)
		(stroke
			(width 0.07112)
			(type default)
		)
		(layer "In15.Cu")
	)
	(gr_line
		(start 322.747386 -417.75253)
		(end 322.883276 -417.61664)
		(stroke
			(width 0.07112)
			(type default)
		)
		(layer "In15.Cu")
	)
	(gr_line
		(start 322.747386 -416.62477)
		(end 322.883276 -416.48888)
		(stroke
			(width 0.07112)
			(type default)
		)
		(layer "In15.Cu")
	)
	(gr_line
		(start 322.883276 -417.61664)
		(end 322.883276 -417.18992)
		(stroke
			(width 0.07112)
			(type default)
		)
		(layer "In15.Cu")
	)
	(gr_line
		(start 322.883276 -417.18992)
		(end 322.747386 -417.05403)
		(stroke
			(width 0.07112)
			(type default)
		)
		(layer "In15.Cu")
	)
	(gr_line
		(start 322.883276 -416.48888)
		(end 322.883276 -416.06216)
		(stroke
			(width 0.07112)
			(type default)
		)
		(layer "In15.Cu")
	)
	(gr_line
		(start 322.883276 -416.06216)
		(end 322.747386 -415.92627)
		(stroke
			(width 0.07112)
			(type default)
		)
		(layer "In15.Cu")
	)
	(gr_line
		(start 324.503034 -438.623202)
		(end 324.499478 -438.623202)
		(stroke
			(width 0.07112)
			(type default)
		)
		(layer "In15.Cu")
	)
	(gr_line
		(start 324.649592 -439.0898)
		(end 324.649592 -438.76976)
		(stroke
			(width 0.07112)
			(type default)
		)
		(layer "In15.Cu")
	)
	(gr_line
		(start 324.649592 -438.76976)
		(end 324.503034 -438.623202)
		(stroke
			(width 0.07112)
			(type default)
		)
		(layer "In15.Cu")
	)
	(gr_line
		(start 324.649592 -438.191148)
		(end 324.500748 -438.339992)
		(stroke
			(width 0.07112)
			(type default)
		)
		(layer "In15.Cu")
	)
	(gr_line
		(start 324.649592 -437.889904)
		(end 324.649592 -438.191148)
		(stroke
			(width 0.07112)
			(type default)
		)
		(layer "In15.Cu")
	)
	(gr_line
		(start 324.907656 -423.40276)
		(end 324.609968 -422.773348)
		(stroke
			(width 0.07112)
			(type default)
		)
		(layer "In15.Cu")
	)
	(gr_line
		(start 325.044308 -422.716706)
		(end 324.866508 -422.653206)
		(stroke
			(width 0.07112)
			(type default)
		)
		(layer "In15.Cu")
	)
	(gr_line
		(start 325.16318 -423.280586)
		(end 325.226934 -423.102786)
		(stroke
			(width 0.07112)
			(type default)
		)
		(layer "In15.Cu")
	)
	(gr_line
		(start 325.226934 -423.102786)
		(end 325.044308 -422.716706)
		(stroke
			(width 0.07112)
			(type default)
		)
		(layer "In15.Cu")
	)
	(gr_line
		(start 325.387716 -424.417744)
		(end 325.090028 -423.788332)
		(stroke
			(width 0.07112)
			(type default)
		)
		(layer "In15.Cu")
	)
	(gr_line
		(start 325.415656 -410.089604)
		(end 325.289418 -410.157168)
		(stroke
			(width 0.07112)
			(type default)
		)
		(layer "In15.Cu")
	)
	(gr_line
		(start 325.524622 -423.731944)
		(end 325.346568 -423.66819)
		(stroke
			(width 0.07112)
			(type default)
		)
		(layer "In15.Cu")
	)
	(gr_line
		(start 325.527416 -417.858702)
		(end 325.527416 -417.157662)
		(stroke
			(width 0.07112)
			(type default)
		)
		(layer "In15.Cu")
	)
	(gr_line
		(start 325.527416 -416.730942)
		(end 325.527416 -416.029902)
		(stroke
			(width 0.07112)
			(type default)
		)
		(layer "In15.Cu")
	)
	(gr_line
		(start 325.580248 -381.202438)
		(end 325.580248 -381.010414)
		(stroke
			(width 0.07112)
			(type default)
		)
		(layer "In15.Cu")
	)
	(gr_line
		(start 325.580248 -381.010414)
		(end 325.882254 -380.708408)
		(stroke
			(width 0.07112)
			(type default)
		)
		(layer "In15.Cu")
	)
	(gr_line
		(start 325.64324 -424.29557)
		(end 325.706994 -424.11777)
		(stroke
			(width 0.07112)
			(type default)
		)
		(layer "In15.Cu")
	)
	(gr_line
		(start 325.706994 -424.11777)
		(end 325.524622 -423.731944)
		(stroke
			(width 0.07112)
			(type default)
		)
		(layer "In15.Cu")
	)
	(gr_line
		(start 325.756524 -409.073096)
		(end 325.586598 -409.163774)
		(stroke
			(width 0.07112)
			(type default)
		)
		(layer "In15.Cu")
	)
	(gr_line
		(start 325.779638 -381.403606)
		(end 326.275446 -380.907798)
		(stroke
			(width 0.07112)
			(type default)
		)
		(layer "In15.Cu")
	)
	(gr_line
		(start 325.809864 -410.611066)
		(end 325.206868 -410.427932)
		(stroke
			(width 0.07112)
			(type default)
		)
		(layer "In15.Cu")
	)
	(gr_line
		(start 325.810626 -417.857432)
		(end 325.946516 -417.721542)
		(stroke
			(width 0.07112)
			(type default)
		)
		(layer "In15.Cu")
	)
	(gr_line
		(start 325.810626 -416.729672)
		(end 325.946516 -416.593782)
		(stroke
			(width 0.07112)
			(type default)
		)
		(layer "In15.Cu")
	)
	(gr_line
		(start 325.824088 -410.213556)
		(end 325.415656 -410.089604)
		(stroke
			(width 0.07112)
			(type default)
		)
		(layer "In15.Cu")
	)
	(gr_line
		(start 325.882254 -380.708408)
		(end 326.074278 -380.708408)
		(stroke
			(width 0.07112)
			(type default)
		)
		(layer "In15.Cu")
	)
	(gr_line
		(start 325.891652 -410.339794)
		(end 325.824088 -410.213556)
		(stroke
			(width 0.07112)
			(type default)
		)
		(layer "In15.Cu")
	)
	(gr_line
		(start 325.946516 -417.721542)
		(end 325.946516 -417.294822)
		(stroke
			(width 0.07112)
			(type default)
		)
		(layer "In15.Cu")
	)
	(gr_line
		(start 325.946516 -417.294822)
		(end 325.810626 -417.158932)
		(stroke
			(width 0.07112)
			(type default)
		)
		(layer "In15.Cu")
	)
	(gr_line
		(start 325.946516 -416.593782)
		(end 325.946516 -416.167062)
		(stroke
			(width 0.07112)
			(type default)
		)
		(layer "In15.Cu")
	)
	(gr_line
		(start 325.946516 -416.167062)
		(end 325.810626 -416.031172)
		(stroke
			(width 0.07112)
			(type default)
		)
		(layer "In15.Cu")
	)
	(gr_line
		(start 326.16521 -409.197048)
		(end 325.756524 -409.073096)
		(stroke
			(width 0.07112)
			(type default)
		)
		(layer "In15.Cu")
	)
	(gr_line
		(start 326.174862 -409.638246)
		(end 325.50354 -409.434538)
		(stroke
			(width 0.07112)
			(type default)
		)
		(layer "In15.Cu")
	)
	(gr_line
		(start 326.255888 -409.366974)
		(end 326.16521 -409.197048)
		(stroke
			(width 0.07112)
			(type default)
		)
		(layer "In15.Cu")
	)
	(gr_line
		(start 326.377554 -380.405132)
		(end 326.377554 -380.212854)
		(stroke
			(width 0.07112)
			(type default)
		)
		(layer "In15.Cu")
	)
	(gr_line
		(start 326.377554 -380.212854)
		(end 326.67956 -379.910848)
		(stroke
			(width 0.07112)
			(type default)
		)
		(layer "In15.Cu")
	)
	(gr_line
		(start 326.42683 -410.396182)
		(end 326.300084 -410.464)
		(stroke
			(width 0.07112)
			(type default)
		)
		(layer "In15.Cu")
	)
	(gr_line
		(start 326.50303 -437.623204)
		(end 326.499474 -437.623204)
		(stroke
			(width 0.07112)
			(type default)
		)
		(layer "In15.Cu")
	)
	(gr_line
		(start 326.576944 -380.6063)
		(end 327.073006 -380.110238)
		(stroke
			(width 0.07112)
			(type default)
		)
		(layer "In15.Cu")
	)
	(gr_line
		(start 326.649588 -438.089802)
		(end 326.649588 -437.769762)
		(stroke
			(width 0.07112)
			(type default)
		)
		(layer "In15.Cu")
	)
	(gr_line
		(start 326.649588 -437.769762)
		(end 326.50303 -437.623204)
		(stroke
			(width 0.07112)
			(type default)
		)
		(layer "In15.Cu")
	)
	(gr_line
		(start 326.649588 -437.19115)
		(end 326.500744 -437.339994)
		(stroke
			(width 0.07112)
			(type default)
		)
		(layer "In15.Cu")
	)
	(gr_line
		(start 326.649588 -436.889906)
		(end 326.649588 -437.19115)
		(stroke
			(width 0.07112)
			(type default)
		)
		(layer "In15.Cu")
	)
	(gr_line
		(start 326.67956 -379.910848)
		(end 326.871838 -379.910848)
		(stroke
			(width 0.07112)
			(type default)
		)
		(layer "In15.Cu")
	)
	(gr_line
		(start 326.821038 -410.917644)
		(end 326.218042 -410.734764)
		(stroke
			(width 0.07112)
			(type default)
		)
		(layer "In15.Cu")
	)
	(gr_line
		(start 326.835516 -410.520134)
		(end 326.42683 -410.396182)
		(stroke
			(width 0.07112)
			(type default)
		)
		(layer "In15.Cu")
	)
	(gr_line
		(start 326.902826 -410.646626)
		(end 326.835516 -410.520134)
		(stroke
			(width 0.07112)
			(type default)
		)
		(layer "In15.Cu")
	)
	(gr_line
		(start 327.175114 -379.607572)
		(end 327.175114 -379.415294)
		(stroke
			(width 0.07112)
			(type default)
		)
		(layer "In15.Cu")
	)
	(gr_line
		(start 327.175114 -379.415294)
		(end 327.47712 -379.113288)
		(stroke
			(width 0.07112)
			(type default)
		)
		(layer "In15.Cu")
	)
	(gr_line
		(start 327.328276 -423.36466)
		(end 327.192386 -422.681908)
		(stroke
			(width 0.07112)
			(type default)
		)
		(layer "In15.Cu")
	)
	(gr_line
		(start 327.374504 -379.80874)
		(end 327.870566 -379.312678)
		(stroke
			(width 0.07112)
			(type default)
		)
		(layer "In15.Cu")
	)
	(gr_line
		(start 327.438004 -410.703014)
		(end 327.311258 -410.770832)
		(stroke
			(width 0.07112)
			(type default)
		)
		(layer "In15.Cu")
	)
	(gr_line
		(start 327.454768 -407.392632)
		(end 327.292462 -407.497026)
		(stroke
			(width 0.07112)
			(type default)
		)
		(layer "In15.Cu")
	)
	(gr_line
		(start 327.47712 -379.113288)
		(end 327.669398 -379.113288)
		(stroke
			(width 0.07112)
			(type default)
		)
		(layer "In15.Cu")
	)
	(gr_line
		(start 327.570592 -372.667022)
		(end 327.570592 -372.474998)
		(stroke
			(width 0.07112)
			(type default)
		)
		(layer "In15.Cu")
	)
	(gr_line
		(start 327.570592 -372.474998)
		(end 327.872598 -372.172992)
		(stroke
			(width 0.07112)
			(type default)
		)
		(layer "In15.Cu")
	)
	(gr_line
		(start 327.605644 -423.308272)
		(end 327.710546 -423.151046)
		(stroke
			(width 0.07112)
			(type default)
		)
		(layer "In15.Cu")
	)
	(gr_line
		(start 327.627488 -422.732454)
		(end 327.470516 -422.627806)
		(stroke
			(width 0.07112)
			(type default)
		)
		(layer "In15.Cu")
	)
	(gr_line
		(start 327.710546 -423.151046)
		(end 327.627488 -422.732454)
		(stroke
			(width 0.07112)
			(type default)
		)
		(layer "In15.Cu")
	)
	(gr_line
		(start 327.769982 -372.86819)
		(end 328.26579 -372.372382)
		(stroke
			(width 0.07112)
			(type default)
		)
		(layer "In15.Cu")
	)
	(gr_line
		(start 327.83272 -411.22473)
		(end 327.229216 -411.041596)
		(stroke
			(width 0.07112)
			(type default)
		)
		(layer "In15.Cu")
	)
	(gr_line
		(start 327.84669 -410.826966)
		(end 327.438004 -410.703014)
		(stroke
			(width 0.07112)
			(type default)
		)
		(layer "In15.Cu")
	)
	(gr_line
		(start 327.871836 -407.48331)
		(end 327.454768 -407.392632)
		(stroke
			(width 0.07112)
			(type default)
		)
		(layer "In15.Cu")
	)
	(gr_line
		(start 327.872598 -372.172992)
		(end 328.064622 -372.172992)
		(stroke
			(width 0.07112)
			(type default)
		)
		(layer "In15.Cu")
	)
	(gr_line
		(start 327.914 -410.953204)
		(end 327.84669 -410.826966)
		(stroke
			(width 0.07112)
			(type default)
		)
		(layer "In15.Cu")
	)
	(gr_line
		(start 327.915016 -409.727908)
		(end 327.744836 -409.81884)
		(stroke
			(width 0.07112)
			(type default)
		)
		(layer "In15.Cu")
	)
	(gr_line
		(start 327.917048 -407.922476)
		(end 327.231502 -407.773632)
		(stroke
			(width 0.07112)
			(type default)
		)
		(layer "In15.Cu")
	)
	(gr_line
		(start 327.97623 -407.645362)
		(end 327.871836 -407.48331)
		(stroke
			(width 0.07112)
			(type default)
		)
		(layer "In15.Cu")
	)
	(gr_line
		(start 328.323448 -409.85186)
		(end 327.915016 -409.727908)
		(stroke
			(width 0.07112)
			(type default)
		)
		(layer "In15.Cu")
	)
	(gr_line
		(start 328.3331 -410.293312)
		(end 327.661778 -410.089604)
		(stroke
			(width 0.07112)
			(type default)
		)
		(layer "In15.Cu")
	)
	(gr_line
		(start 328.367898 -371.869716)
		(end 328.367898 -371.677438)
		(stroke
			(width 0.07112)
			(type default)
		)
		(layer "In15.Cu")
	)
	(gr_line
		(start 328.367898 -371.677438)
		(end 328.669904 -371.375432)
		(stroke
			(width 0.07112)
			(type default)
		)
		(layer "In15.Cu")
	)
	(gr_line
		(start 328.41438 -410.021786)
		(end 328.323448 -409.85186)
		(stroke
			(width 0.07112)
			(type default)
		)
		(layer "In15.Cu")
	)
	(gr_line
		(start 328.458576 -403.64283)
		(end 328.309478 -403.765258)
		(stroke
			(width 0.07112)
			(type default)
		)
		(layer "In15.Cu")
	)
	(gr_line
		(start 328.50328 -438.337452)
		(end 328.499216 -438.337452)
		(stroke
			(width 0.07112)
			(type default)
		)
		(layer "In15.Cu")
	)
	(gr_line
		(start 328.567288 -372.070884)
		(end 329.06335 -371.574822)
		(stroke
			(width 0.07112)
			(type default)
		)
		(layer "In15.Cu")
	)
	(gr_line
		(start 328.576686 -407.636472)
		(end 328.414634 -407.740612)
		(stroke
			(width 0.07112)
			(type default)
		)
		(layer "In15.Cu")
	)
	(gr_line
		(start 328.590656 -417.983416)
		(end 328.590656 -417.282376)
		(stroke
			(width 0.07112)
			(type default)
		)
		(layer "In15.Cu")
	)
	(gr_line
		(start 328.590656 -416.855656)
		(end 328.590656 -416.154616)
		(stroke
			(width 0.07112)
			(type default)
		)
		(layer "In15.Cu")
	)
	(gr_line
		(start 328.649584 -439.0898)
		(end 328.649584 -438.76976)
		(stroke
			(width 0.07112)
			(type default)
		)
		(layer "In15.Cu")
	)
	(gr_line
		(start 328.649584 -438.76976)
		(end 328.500486 -438.620662)
		(stroke
			(width 0.07112)
			(type default)
		)
		(layer "In15.Cu")
	)
	(gr_line
		(start 328.649584 -438.191148)
		(end 328.50328 -438.337452)
		(stroke
			(width 0.07112)
			(type default)
		)
		(layer "In15.Cu")
	)
	(gr_line
		(start 328.649584 -437.889904)
		(end 328.649584 -438.191148)
		(stroke
			(width 0.07112)
			(type default)
		)
		(layer "In15.Cu")
	)
	(gr_line
		(start 328.669904 -371.375432)
		(end 328.862182 -371.375432)
		(stroke
			(width 0.07112)
			(type default)
		)
		(layer "In15.Cu")
	)
	(gr_line
		(start 328.850752 -373.086122)
		(end 328.850752 -372.894098)
		(stroke
			(width 0.07112)
			(type default)
		)
		(layer "In15.Cu")
	)
	(gr_line
		(start 328.850752 -372.894098)
		(end 329.152758 -372.592092)
		(stroke
			(width 0.07112)
			(type default)
		)
		(layer "In15.Cu")
	)
	(gr_line
		(start 328.873866 -417.982146)
		(end 329.009756 -417.846256)
		(stroke
			(width 0.07112)
			(type default)
		)
		(layer "In15.Cu")
	)
	(gr_line
		(start 328.873866 -416.854386)
		(end 329.009756 -416.718496)
		(stroke
			(width 0.07112)
			(type default)
		)
		(layer "In15.Cu")
	)
	(gr_line
		(start 328.883518 -403.68474)
		(end 328.458576 -403.64283)
		(stroke
			(width 0.07112)
			(type default)
		)
		(layer "In15.Cu")
	)
	(gr_line
		(start 328.979022 -404.115778)
		(end 328.28103 -404.047198)
		(stroke
			(width 0.07112)
			(type default)
		)
		(layer "In15.Cu")
	)
	(gr_line
		(start 328.994008 -407.72715)
		(end 328.576686 -407.636472)
		(stroke
			(width 0.07112)
			(type default)
		)
		(layer "In15.Cu")
	)
	(gr_line
		(start 328.994262 -410.055314)
		(end 328.824082 -410.146246)
		(stroke
			(width 0.07112)
			(type default)
		)
		(layer "In15.Cu")
	)
	(gr_line
		(start 329.005438 -405.430736)
		(end 329.005438 -405.43099)
		(stroke
			(width 0.07112)
			(type default)
		)
		(layer "In15.Cu")
	)
	(gr_line
		(start 329.005946 -403.833838)
		(end 328.883518 -403.68474)
		(stroke
			(width 0.07112)
			(type default)
		)
		(layer "In15.Cu")
	)
	(gr_line
		(start 329.009756 -417.846256)
		(end 329.009756 -417.419536)
		(stroke
			(width 0.07112)
			(type default)
		)
		(layer "In15.Cu")
	)
	(gr_line
		(start 329.009756 -417.419536)
		(end 328.873866 -417.283646)
		(stroke
			(width 0.07112)
			(type default)
		)
		(layer "In15.Cu")
	)
	(gr_line
		(start 329.009756 -416.718496)
		(end 329.009756 -416.291776)
		(stroke
			(width 0.07112)
			(type default)
		)
		(layer "In15.Cu")
	)
	(gr_line
		(start 329.009756 -416.291776)
		(end 328.873866 -416.155886)
		(stroke
			(width 0.07112)
			(type default)
		)
		(layer "In15.Cu")
	)
	(gr_line
		(start 329.03922 -408.166062)
		(end 328.353674 -408.017218)
		(stroke
			(width 0.07112)
			(type default)
		)
		(layer "In15.Cu")
	)
	(gr_line
		(start 329.050142 -373.28729)
		(end 329.54595 -372.791482)
		(stroke
			(width 0.07112)
			(type default)
		)
		(layer "In15.Cu")
	)
	(gr_line
		(start 329.097894 -407.888948)
		(end 328.994008 -407.72715)
		(stroke
			(width 0.07112)
			(type default)
		)
		(layer "In15.Cu")
	)
	(gr_line
		(start 329.152758 -372.592092)
		(end 329.344782 -372.592092)
		(stroke
			(width 0.07112)
			(type default)
		)
		(layer "In15.Cu")
	)
	(gr_line
		(start 329.165458 -371.072156)
		(end 329.165458 -370.879878)
		(stroke
			(width 0.07112)
			(type default)
		)
		(layer "In15.Cu")
	)
	(gr_line
		(start 329.165458 -370.879878)
		(end 329.467464 -370.577872)
		(stroke
			(width 0.07112)
			(type default)
		)
		(layer "In15.Cu")
	)
	(gr_line
		(start 329.210416 -405.030432)
		(end 329.04811 -405.151082)
		(stroke
			(width 0.07112)
			(type default)
		)
		(layer "In15.Cu")
	)
	(gr_line
		(start 329.211686 -406.535128)
		(end 329.056746 -406.649936)
		(stroke
			(width 0.07112)
			(type default)
		)
		(layer "In15.Cu")
	)
	(gr_line
		(start 329.331574 -379.081538)
		(end 329.331574 -378.88926)
		(stroke
			(width 0.07112)
			(type default)
		)
		(layer "In15.Cu")
	)
	(gr_line
		(start 329.331574 -378.88926)
		(end 329.63358 -378.587254)
		(stroke
			(width 0.07112)
			(type default)
		)
		(layer "In15.Cu")
	)
	(gr_line
		(start 329.364848 -371.273324)
		(end 329.86091 -370.777262)
		(stroke
			(width 0.07112)
			(type default)
		)
		(layer "In15.Cu")
	)
	(gr_line
		(start 329.402694 -410.179266)
		(end 328.994262 -410.055314)
		(stroke
			(width 0.07112)
			(type default)
		)
		(layer "In15.Cu")
	)
	(gr_line
		(start 329.412346 -410.620464)
		(end 328.741278 -410.41701)
		(stroke
			(width 0.07112)
			(type default)
		)
		(layer "In15.Cu")
	)
	(gr_line
		(start 329.467464 -370.577872)
		(end 329.659742 -370.577872)
		(stroke
			(width 0.07112)
			(type default)
		)
		(layer "In15.Cu")
	)
	(gr_line
		(start 329.493372 -410.349192)
		(end 329.402694 -410.179266)
		(stroke
			(width 0.07112)
			(type default)
		)
		(layer "In15.Cu")
	)
	(gr_line
		(start 329.530964 -379.282706)
		(end 330.027026 -378.786644)
		(stroke
			(width 0.07112)
			(type default)
		)
		(layer "In15.Cu")
	)
	(gr_line
		(start 329.530964 -379.282452)
		(end 329.530964 -379.282706)
		(stroke
			(width 0.07112)
			(type default)
		)
		(layer "In15.Cu")
	)
	(gr_line
		(start 329.581002 -403.75332)
		(end 329.431904 -403.875748)
		(stroke
			(width 0.07112)
			(type default)
		)
		(layer "In15.Cu")
	)
	(gr_line
		(start 329.619102 -405.091138)
		(end 329.210416 -405.030432)
		(stroke
			(width 0.07112)
			(type default)
		)
		(layer "In15.Cu")
	)
	(gr_line
		(start 329.63358 -378.587254)
		(end 329.825858 -378.587254)
		(stroke
			(width 0.07112)
			(type default)
		)
		(layer "In15.Cu")
	)
	(gr_line
		(start 329.634088 -406.597612)
		(end 329.211686 -406.535128)
		(stroke
			(width 0.07112)
			(type default)
		)
		(layer "In15.Cu")
	)
	(gr_line
		(start 329.648058 -372.288816)
		(end 329.648058 -372.096538)
		(stroke
			(width 0.07112)
			(type default)
		)
		(layer "In15.Cu")
	)
	(gr_line
		(start 329.648058 -372.096538)
		(end 329.950064 -371.794532)
		(stroke
			(width 0.07112)
			(type default)
		)
		(layer "In15.Cu")
	)
	(gr_line
		(start 329.699112 -405.534114)
		(end 329.005438 -405.43099)
		(stroke
			(width 0.07112)
			(type default)
		)
		(layer "In15.Cu")
	)
	(gr_line
		(start 329.708256 -407.032968)
		(end 329.014328 -406.929844)
		(stroke
			(width 0.07112)
			(type default)
		)
		(layer "In15.Cu")
	)
	(gr_line
		(start 329.739498 -405.253698)
		(end 329.619102 -405.091138)
		(stroke
			(width 0.07112)
			(type default)
		)
		(layer "In15.Cu")
	)
	(gr_line
		(start 329.748896 -406.752552)
		(end 329.634088 -406.597612)
		(stroke
			(width 0.07112)
			(type default)
		)
		(layer "In15.Cu")
	)
	(gr_line
		(start 329.847448 -372.489984)
		(end 330.34351 -371.993922)
		(stroke
			(width 0.07112)
			(type default)
		)
		(layer "In15.Cu")
	)
	(gr_line
		(start 329.950064 -371.794532)
		(end 330.142342 -371.794532)
		(stroke
			(width 0.07112)
			(type default)
		)
		(layer "In15.Cu")
	)
	(gr_line
		(start 330.005944 -403.79523)
		(end 329.581002 -403.75332)
		(stroke
			(width 0.07112)
			(type default)
		)
		(layer "In15.Cu")
	)
	(gr_line
		(start 330.073508 -410.38272)
		(end 329.903328 -410.473652)
		(stroke
			(width 0.07112)
			(type default)
		)
		(layer "In15.Cu")
	)
	(gr_line
		(start 330.101448 -404.226522)
		(end 329.403456 -404.157688)
		(stroke
			(width 0.07112)
			(type default)
		)
		(layer "In15.Cu")
	)
	(gr_line
		(start 330.122276 -421.998902)
		(end 330.122276 -421.320214)
		(stroke
			(width 0.07112)
			(type default)
		)
		(layer "In15.Cu")
	)
	(gr_line
		(start 330.128372 -403.944582)
		(end 330.005944 -403.79523)
		(stroke
			(width 0.07112)
			(type default)
		)
		(layer "In15.Cu")
	)
	(gr_line
		(start 330.129134 -378.283978)
		(end 330.129134 -378.0917)
		(stroke
			(width 0.07112)
			(type default)
		)
		(layer "In15.Cu")
	)
	(gr_line
		(start 330.129134 -378.0917)
		(end 330.43114 -377.789694)
		(stroke
			(width 0.07112)
			(type default)
		)
		(layer "In15.Cu")
	)
	(gr_line
		(start 330.318364 -405.201882)
		(end 330.163424 -405.31669)
		(stroke
			(width 0.07112)
			(type default)
		)
		(layer "In15.Cu")
	)
	(gr_line
		(start 330.327254 -406.700482)
		(end 330.172314 -406.815544)
		(stroke
			(width 0.07112)
			(type default)
		)
		(layer "In15.Cu")
	)
	(gr_line
		(start 330.328524 -378.485146)
		(end 330.824586 -377.989084)
		(stroke
			(width 0.07112)
			(type default)
		)
		(layer "In15.Cu")
	)
	(gr_line
		(start 330.335382 -311.72531)
		(end 330.335128 -311.72531)
		(stroke
			(width 0.07112)
			(type default)
		)
		(layer "In15.Cu")
	)
	(gr_line
		(start 330.34732 -423.515536)
		(end 330.210668 -422.82745)
		(stroke
			(width 0.07112)
			(type default)
		)
		(layer "In15.Cu")
	)
	(gr_line
		(start 330.370688 -408.026108)
		(end 330.208636 -408.130248)
		(stroke
			(width 0.07112)
			(type default)
		)
		(layer "In15.Cu")
	)
	(gr_line
		(start 330.379324 -410.913834)
		(end 329.820524 -410.744416)
		(stroke
			(width 0.07112)
			(type default)
		)
		(layer "In15.Cu")
	)
	(gr_line
		(start 330.379324 -410.913834)
		(end 330.379578 -410.914088)
		(stroke
			(width 0.07112)
			(type default)
		)
		(layer "In15.Cu")
	)
	(gr_line
		(start 330.405486 -421.997632)
		(end 330.5302 -421.872918)
		(stroke
			(width 0.07112)
			(type default)
		)
		(layer "In15.Cu")
	)
	(gr_line
		(start 330.43114 -377.789694)
		(end 330.623418 -377.789694)
		(stroke
			(width 0.07112)
			(type default)
		)
		(layer "In15.Cu")
	)
	(gr_line
		(start 330.445618 -371.491256)
		(end 330.445618 -371.298978)
		(stroke
			(width 0.07112)
			(type default)
		)
		(layer "In15.Cu")
	)
	(gr_line
		(start 330.445618 -371.298978)
		(end 330.747624 -370.996972)
		(stroke
			(width 0.07112)
			(type default)
		)
		(layer "In15.Cu")
	)
	(gr_line
		(start 330.48194 -410.506672)
		(end 330.073508 -410.38272)
		(stroke
			(width 0.07112)
			(type default)
		)
		(layer "In15.Cu")
	)
	(gr_line
		(start 330.491592 -410.948124)
		(end 330.379578 -410.914088)
		(stroke
			(width 0.07112)
			(type default)
		)
		(layer "In15.Cu")
	)
	(gr_line
		(start 330.5302 -421.872918)
		(end 330.5302 -421.446198)
		(stroke
			(width 0.07112)
			(type default)
		)
		(layer "In15.Cu")
	)
	(gr_line
		(start 330.5302 -421.446198)
		(end 330.405486 -421.321484)
		(stroke
			(width 0.07112)
			(type default)
		)
		(layer "In15.Cu")
	)
	(gr_line
		(start 330.567538 -424.621706)
		(end 330.430632 -423.93362)
		(stroke
			(width 0.07112)
			(type default)
		)
		(layer "In15.Cu")
	)
	(gr_line
		(start 330.572872 -410.676598)
		(end 330.48194 -410.506672)
		(stroke
			(width 0.07112)
			(type default)
		)
		(layer "In15.Cu")
	)
	(gr_line
		(start 330.624942 -423.459402)
		(end 330.73213 -423.299128)
		(stroke
			(width 0.07112)
			(type default)
		)
		(layer "In15.Cu")
	)
	(gr_line
		(start 330.63434 -424.956732)
		(end 330.634086 -424.956732)
		(stroke
			(width 0.07112)
			(type default)
		)
		(layer "In15.Cu")
	)
	(gr_line
		(start 330.645008 -371.692424)
		(end 331.14107 -371.196362)
		(stroke
			(width 0.07112)
			(type default)
		)
		(layer "In15.Cu")
	)
	(gr_line
		(start 330.648818 -422.880282)
		(end 330.488544 -422.773348)
		(stroke
			(width 0.07112)
			(type default)
		)
		(layer "In15.Cu")
	)
	(gr_line
		(start 330.681838 -409.624022)
		(end 330.682092 -409.623514)
		(stroke
			(width 0.07112)
			(type default)
		)
		(layer "In15.Cu")
	)
	(gr_line
		(start 330.682092 -409.623514)
		(end 330.681838 -409.623006)
		(stroke
			(width 0.07112)
			(type default)
		)
		(layer "In15.Cu")
	)
	(gr_line
		(start 330.73213 -423.299128)
		(end 330.648818 -422.880282)
		(stroke
			(width 0.07112)
			(type default)
		)
		(layer "In15.Cu")
	)
	(gr_line
		(start 330.740766 -405.26462)
		(end 330.318364 -405.201882)
		(stroke
			(width 0.07112)
			(type default)
		)
		(layer "In15.Cu")
	)
	(gr_line
		(start 330.747624 -370.996972)
		(end 330.939902 -370.996972)
		(stroke
			(width 0.07112)
			(type default)
		)
		(layer "In15.Cu")
	)
	(gr_line
		(start 330.749656 -406.76322)
		(end 330.327254 -406.700482)
		(stroke
			(width 0.07112)
			(type default)
		)
		(layer "In15.Cu")
	)
	(gr_line
		(start 330.78801 -408.116786)
		(end 330.370688 -408.026108)
		(stroke
			(width 0.07112)
			(type default)
		)
		(layer "In15.Cu")
	)
	(gr_line
		(start 330.808838 -403.874478)
		(end 330.65974 -403.996906)
		(stroke
			(width 0.07112)
			(type default)
		)
		(layer "In15.Cu")
	)
	(gr_line
		(start 330.81468 -405.699722)
		(end 330.121006 -405.596598)
		(stroke
			(width 0.07112)
			(type default)
		)
		(layer "In15.Cu")
	)
	(gr_line
		(start 330.823824 -407.198322)
		(end 330.13015 -407.095452)
		(stroke
			(width 0.07112)
			(type default)
		)
		(layer "In15.Cu")
	)
	(gr_line
		(start 330.832968 -408.555698)
		(end 330.147422 -408.406854)
		(stroke
			(width 0.07112)
			(type default)
		)
		(layer "In15.Cu")
	)
	(gr_line
		(start 330.84516 -424.565572)
		(end 330.952348 -424.405298)
		(stroke
			(width 0.07112)
			(type default)
		)
		(layer "In15.Cu")
	)
	(gr_line
		(start 330.855066 -405.419306)
		(end 330.740766 -405.26462)
		(stroke
			(width 0.07112)
			(type default)
		)
		(layer "In15.Cu")
	)
	(gr_line
		(start 330.864464 -406.91816)
		(end 330.749656 -406.76322)
		(stroke
			(width 0.07112)
			(type default)
		)
		(layer "In15.Cu")
	)
	(gr_line
		(start 330.869036 -423.986706)
		(end 330.708508 -423.879518)
		(stroke
			(width 0.07112)
			(type default)
		)
		(layer "In15.Cu")
	)
	(gr_line
		(start 330.891896 -408.278584)
		(end 330.78801 -408.116786)
		(stroke
			(width 0.07112)
			(type default)
		)
		(layer "In15.Cu")
	)
	(gr_line
		(start 330.903326 -409.246832)
		(end 330.743814 -409.347924)
		(stroke
			(width 0.07112)
			(type default)
		)
		(layer "In15.Cu")
	)
	(gr_line
		(start 330.926694 -377.486418)
		(end 330.926694 -377.29414)
		(stroke
			(width 0.07112)
			(type default)
		)
		(layer "In15.Cu")
	)
	(gr_line
		(start 330.926694 -377.29414)
		(end 331.2287 -376.992134)
		(stroke
			(width 0.07112)
			(type default)
		)
		(layer "In15.Cu")
	)
	(gr_line
		(start 330.952348 -424.405298)
		(end 330.869036 -423.986706)
		(stroke
			(width 0.07112)
			(type default)
		)
		(layer "In15.Cu")
	)
	(gr_line
		(start 331.126084 -377.687586)
		(end 331.622146 -377.191524)
		(stroke
			(width 0.07112)
			(type default)
		)
		(layer "In15.Cu")
	)
	(gr_line
		(start 331.2287 -376.992134)
		(end 331.420978 -376.992134)
		(stroke
			(width 0.07112)
			(type default)
		)
		(layer "In15.Cu")
	)
	(gr_line
		(start 331.23378 -403.916388)
		(end 330.808838 -403.874478)
		(stroke
			(width 0.07112)
			(type default)
		)
		(layer "In15.Cu")
	)
	(gr_line
		(start 331.326998 -409.341828)
		(end 330.903326 -409.246832)
		(stroke
			(width 0.07112)
			(type default)
		)
		(layer "In15.Cu")
	)
	(gr_line
		(start 331.329538 -404.347426)
		(end 330.631292 -404.278592)
		(stroke
			(width 0.07112)
			(type default)
		)
		(layer "In15.Cu")
	)
	(gr_line
		(start 331.355954 -404.065486)
		(end 331.23378 -403.916388)
		(stroke
			(width 0.07112)
			(type default)
		)
		(layer "In15.Cu")
	)
	(gr_line
		(start 331.357224 -404.066756)
		(end 331.35697 -404.066502)
		(stroke
			(width 0.07112)
			(type default)
		)
		(layer "In15.Cu")
	)
	(gr_line
		(start 331.366114 -409.777692)
		(end 330.681838 -409.624022)
		(stroke
			(width 0.07112)
			(type default)
		)
		(layer "In15.Cu")
	)
	(gr_line
		(start 331.427836 -409.50134)
		(end 331.326998 -409.341828)
		(stroke
			(width 0.07112)
			(type default)
		)
		(layer "In15.Cu")
	)
	(gr_line
		(start 331.433932 -405.36749)
		(end 331.278992 -405.482298)
		(stroke
			(width 0.07112)
			(type default)
		)
		(layer "In15.Cu")
	)
	(gr_line
		(start 331.442822 -406.86609)
		(end 331.288136 -406.980898)
		(stroke
			(width 0.07112)
			(type default)
		)
		(layer "In15.Cu")
	)
	(gr_line
		(start 331.503782 -437.3372)
		(end 331.49921 -437.3372)
		(stroke
			(width 0.07112)
			(type default)
		)
		(layer "In15.Cu")
	)
	(gr_line
		(start 331.649832 -438.089802)
		(end 331.649832 -437.769762)
		(stroke
			(width 0.07112)
			(type default)
		)
		(layer "In15.Cu")
	)
	(gr_line
		(start 331.649832 -437.769762)
		(end 331.50048 -437.62041)
		(stroke
			(width 0.07112)
			(type default)
		)
		(layer "In15.Cu")
	)
	(gr_line
		(start 331.649832 -437.19115)
		(end 331.503782 -437.3372)
		(stroke
			(width 0.07112)
			(type default)
		)
		(layer "In15.Cu")
	)
	(gr_line
		(start 331.649832 -436.889906)
		(end 331.649832 -437.19115)
		(stroke
			(width 0.07112)
			(type default)
		)
		(layer "In15.Cu")
	)
	(gr_line
		(start 331.653896 -417.60902)
		(end 331.653896 -416.90798)
		(stroke
			(width 0.07112)
			(type default)
		)
		(layer "In15.Cu")
	)
	(gr_line
		(start 331.653896 -416.48126)
		(end 331.653896 -415.78022)
		(stroke
			(width 0.07112)
			(type default)
		)
		(layer "In15.Cu")
	)
	(gr_line
		(start 331.856334 -405.430228)
		(end 331.433932 -405.36749)
		(stroke
			(width 0.07112)
			(type default)
		)
		(layer "In15.Cu")
	)
	(gr_line
		(start 331.865224 -406.928828)
		(end 331.442822 -406.86609)
		(stroke
			(width 0.07112)
			(type default)
		)
		(layer "In15.Cu")
	)
	(gr_line
		(start 331.930248 -405.86533)
		(end 331.236574 -405.762206)
		(stroke
			(width 0.07112)
			(type default)
		)
		(layer "In15.Cu")
	)
	(gr_line
		(start 331.937106 -417.60775)
		(end 332.072996 -417.47186)
		(stroke
			(width 0.07112)
			(type default)
		)
		(layer "In15.Cu")
	)
	(gr_line
		(start 331.937106 -416.47999)
		(end 332.072996 -416.3441)
		(stroke
			(width 0.07112)
			(type default)
		)
		(layer "In15.Cu")
	)
	(gr_line
		(start 331.939392 -407.36393)
		(end 331.245718 -407.26106)
		(stroke
			(width 0.07112)
			(type default)
		)
		(layer "In15.Cu")
	)
	(gr_line
		(start 331.970634 -405.584914)
		(end 331.856334 -405.430228)
		(stroke
			(width 0.07112)
			(type default)
		)
		(layer "In15.Cu")
	)
	(gr_line
		(start 331.980032 -407.083514)
		(end 331.865224 -406.928828)
		(stroke
			(width 0.07112)
			(type default)
		)
		(layer "In15.Cu")
	)
	(gr_line
		(start 332.008226 -409.491434)
		(end 331.844904 -409.595066)
		(stroke
			(width 0.07112)
			(type default)
		)
		(layer "In15.Cu")
	)
	(gr_line
		(start 332.072996 -417.47186)
		(end 332.072996 -417.04514)
		(stroke
			(width 0.07112)
			(type default)
		)
		(layer "In15.Cu")
	)
	(gr_line
		(start 332.072996 -417.04514)
		(end 331.937106 -416.90925)
		(stroke
			(width 0.07112)
			(type default)
		)
		(layer "In15.Cu")
	)
	(gr_line
		(start 332.072996 -416.3441)
		(end 332.072996 -415.91738)
		(stroke
			(width 0.07112)
			(type default)
		)
		(layer "In15.Cu")
	)
	(gr_line
		(start 332.072996 -415.91738)
		(end 331.937106 -415.78149)
		(stroke
			(width 0.07112)
			(type default)
		)
		(layer "In15.Cu")
	)
	(gr_line
		(start 332.37932 -367.547652)
		(end 333.08036 -367.547652)
		(stroke
			(width 0.07112)
			(type default)
		)
		(layer "In15.Cu")
	)
	(gr_line
		(start 332.38059 -367.264442)
		(end 332.51648 -367.128552)
		(stroke
			(width 0.07112)
			(type default)
		)
		(layer "In15.Cu")
	)
	(gr_line
		(start 332.424786 -409.584906)
		(end 332.008226 -409.491434)
		(stroke
			(width 0.07112)
			(type default)
		)
		(layer "In15.Cu")
	)
	(gr_line
		(start 332.467204 -410.025088)
		(end 331.78242 -409.871164)
		(stroke
			(width 0.07112)
			(type default)
		)
		(layer "In15.Cu")
	)
	(gr_line
		(start 332.51648 -367.128552)
		(end 332.9432 -367.128552)
		(stroke
			(width 0.07112)
			(type default)
		)
		(layer "In15.Cu")
	)
	(gr_line
		(start 332.528418 -409.748482)
		(end 332.424786 -409.584906)
		(stroke
			(width 0.07112)
			(type default)
		)
		(layer "In15.Cu")
	)
	(gr_line
		(start 332.764638 -424.206924)
		(end 332.787244 -424.092116)
		(stroke
			(width 0.07112)
			(type default)
		)
		(layer "In15.Cu")
	)
	(gr_line
		(start 332.787244 -424.092116)
		(end 332.787498 -424.091862)
		(stroke
			(width 0.07112)
			(type default)
		)
		(layer "In15.Cu")
	)
	(gr_line
		(start 332.787498 -424.091862)
		(end 332.897734 -423.53738)
		(stroke
			(width 0.07112)
			(type default)
		)
		(layer "In15.Cu")
	)
	(gr_line
		(start 332.80096 -372.803166)
		(end 333.502 -372.803166)
		(stroke
			(width 0.07112)
			(type default)
		)
		(layer "In15.Cu")
	)
	(gr_line
		(start 332.80223 -372.519956)
		(end 332.93812 -372.384066)
		(stroke
			(width 0.07112)
			(type default)
		)
		(layer "In15.Cu")
	)
	(gr_line
		(start 332.93812 -372.384066)
		(end 333.36484 -372.384066)
		(stroke
			(width 0.07112)
			(type default)
		)
		(layer "In15.Cu")
	)
	(gr_line
		(start 332.9432 -367.128552)
		(end 333.07909 -367.264442)
		(stroke
			(width 0.07112)
			(type default)
		)
		(layer "In15.Cu")
	)
	(gr_line
		(start 332.978252 -422.998646)
		(end 333.08036 -422.309798)
		(stroke
			(width 0.07112)
			(type default)
		)
		(layer "In15.Cu")
	)
	(gr_line
		(start 333.042514 -424.261026)
		(end 333.19974 -424.15587)
		(stroke
			(width 0.07112)
			(type default)
		)
		(layer "In15.Cu")
	)
	(gr_line
		(start 333.177388 -423.578782)
		(end 333.178912 -423.568368)
		(stroke
			(width 0.07112)
			(type default)
		)
		(layer "In15.Cu")
	)
	(gr_line
		(start 333.19974 -424.15587)
		(end 333.283052 -423.737278)
		(stroke
			(width 0.07112)
			(type default)
		)
		(layer "In15.Cu")
	)
	(gr_line
		(start 333.258414 -423.039032)
		(end 333.410306 -422.92651)
		(stroke
			(width 0.07112)
			(type default)
		)
		(layer "In15.Cu")
	)
	(gr_line
		(start 333.283052 -423.737278)
		(end 333.177388 -423.578782)
		(stroke
			(width 0.07112)
			(type default)
		)
		(layer "In15.Cu")
	)
	(gr_line
		(start 333.36484 -372.384066)
		(end 333.50073 -372.519956)
		(stroke
			(width 0.07112)
			(type default)
		)
		(layer "In15.Cu")
	)
	(gr_line
		(start 333.410306 -422.92651)
		(end 333.473044 -422.504108)
		(stroke
			(width 0.07112)
			(type default)
		)
		(layer "In15.Cu")
	)
	(gr_line
		(start 333.473044 -422.504108)
		(end 333.360522 -422.35247)
		(stroke
			(width 0.07112)
			(type default)
		)
		(layer "In15.Cu")
	)
	(gr_line
		(start 333.50327 -438.623202)
		(end 333.499714 -438.623202)
		(stroke
			(width 0.07112)
			(type default)
		)
		(layer "In15.Cu")
	)
	(gr_line
		(start 333.57312 -367.547652)
		(end 334.27416 -367.547652)
		(stroke
			(width 0.07112)
			(type default)
		)
		(layer "In15.Cu")
	)
	(gr_line
		(start 333.57439 -367.264442)
		(end 333.71028 -367.128552)
		(stroke
			(width 0.07112)
			(type default)
		)
		(layer "In15.Cu")
	)
	(gr_line
		(start 333.649828 -439.0898)
		(end 333.649828 -438.76976)
		(stroke
			(width 0.07112)
			(type default)
		)
		(layer "In15.Cu")
	)
	(gr_line
		(start 333.649828 -438.76976)
		(end 333.50327 -438.623202)
		(stroke
			(width 0.07112)
			(type default)
		)
		(layer "In15.Cu")
	)
	(gr_line
		(start 333.649828 -438.191148)
		(end 333.500984 -438.339992)
		(stroke
			(width 0.07112)
			(type default)
		)
		(layer "In15.Cu")
	)
	(gr_line
		(start 333.649828 -437.889904)
		(end 333.649828 -438.191148)
		(stroke
			(width 0.07112)
			(type default)
		)
		(layer "In15.Cu")
	)
	(gr_line
		(start 333.71028 -367.128552)
		(end 334.137 -367.128552)
		(stroke
			(width 0.07112)
			(type default)
		)
		(layer "In15.Cu")
	)
	(gr_line
		(start 333.9338 -372.803166)
		(end 334.63484 -372.803166)
		(stroke
			(width 0.07112)
			(type default)
		)
		(layer "In15.Cu")
	)
	(gr_line
		(start 333.93507 -372.519956)
		(end 334.07096 -372.384066)
		(stroke
			(width 0.07112)
			(type default)
		)
		(layer "In15.Cu")
	)
	(gr_line
		(start 334.07096 -372.384066)
		(end 334.49768 -372.384066)
		(stroke
			(width 0.07112)
			(type default)
		)
		(layer "In15.Cu")
	)
	(gr_line
		(start 334.137 -367.128552)
		(end 334.27289 -367.264442)
		(stroke
			(width 0.07112)
			(type default)
		)
		(layer "In15.Cu")
	)
	(gr_line
		(start 334.176878 -304.681128)
		(end 333.886048 -304.390298)
		(stroke
			(width 0.07112)
			(type default)
		)
		(layer "In15.Cu")
	)
	(gr_line
		(start 334.176878 -303.817528)
		(end 333.886048 -304.108358)
		(stroke
			(width 0.07112)
			(type default)
		)
		(layer "In15.Cu")
	)
	(gr_line
		(start 334.49768 -372.384066)
		(end 334.63357 -372.519956)
		(stroke
			(width 0.07112)
			(type default)
		)
		(layer "In15.Cu")
	)
	(gr_line
		(start 334.675734 -408.901138)
		(end 334.515714 -409.008072)
		(stroke
			(width 0.07112)
			(type default)
		)
		(layer "In15.Cu")
	)
	(gr_line
		(start 334.717136 -417.783264)
		(end 334.717136 -417.082224)
		(stroke
			(width 0.07112)
			(type default)
		)
		(layer "In15.Cu")
	)
	(gr_line
		(start 334.717136 -416.655504)
		(end 334.717136 -415.954464)
		(stroke
			(width 0.07112)
			(type default)
		)
		(layer "In15.Cu")
	)
	(gr_line
		(start 334.76438 -367.547652)
		(end 335.46542 -367.547652)
		(stroke
			(width 0.07112)
			(type default)
		)
		(layer "In15.Cu")
	)
	(gr_line
		(start 334.76565 -367.264442)
		(end 334.90154 -367.128552)
		(stroke
			(width 0.07112)
			(type default)
		)
		(layer "In15.Cu")
	)
	(gr_line
		(start 334.90154 -367.128552)
		(end 335.32826 -367.128552)
		(stroke
			(width 0.07112)
			(type default)
		)
		(layer "In15.Cu")
	)
	(gr_line
		(start 335.000346 -417.781994)
		(end 335.136236 -417.646104)
		(stroke
			(width 0.07112)
			(type default)
		)
		(layer "In15.Cu")
	)
	(gr_line
		(start 335.000346 -416.654234)
		(end 335.136236 -416.518344)
		(stroke
			(width 0.07112)
			(type default)
		)
		(layer "In15.Cu")
	)
	(gr_line
		(start 335.043018 -423.864278)
		(end 335.432654 -423.281094)
		(stroke
			(width 0.07112)
			(type default)
		)
		(layer "In15.Cu")
	)
	(gr_line
		(start 335.09458 -408.98445)
		(end 334.675734 -408.901138)
		(stroke
			(width 0.07112)
			(type default)
		)
		(layer "In15.Cu")
	)
	(gr_line
		(start 335.136236 -417.646104)
		(end 335.136236 -417.219384)
		(stroke
			(width 0.07112)
			(type default)
		)
		(layer "In15.Cu")
	)
	(gr_line
		(start 335.136236 -417.219384)
		(end 335.000346 -417.083494)
		(stroke
			(width 0.07112)
			(type default)
		)
		(layer "In15.Cu")
	)
	(gr_line
		(start 335.136236 -416.518344)
		(end 335.136236 -416.091624)
		(stroke
			(width 0.07112)
			(type default)
		)
		(layer "In15.Cu")
	)
	(gr_line
		(start 335.136236 -416.091624)
		(end 335.000346 -415.955734)
		(stroke
			(width 0.07112)
			(type default)
		)
		(layer "In15.Cu")
	)
	(gr_line
		(start 335.147158 -409.4226)
		(end 334.459326 -409.285694)
		(stroke
			(width 0.07112)
			(type default)
		)
		(layer "In15.Cu")
	)
	(gr_line
		(start 335.20126 -409.14447)
		(end 335.09458 -408.98445)
		(stroke
			(width 0.07112)
			(type default)
		)
		(layer "In15.Cu")
	)
	(gr_line
		(start 335.278984 -424.020742)
		(end 335.467706 -423.98315)
		(stroke
			(width 0.07112)
			(type default)
		)
		(layer "In15.Cu")
	)
	(gr_line
		(start 335.32826 -367.128552)
		(end 335.46415 -367.264442)
		(stroke
			(width 0.07112)
			(type default)
		)
		(layer "In15.Cu")
	)
	(gr_line
		(start 335.45272 -372.803166)
		(end 336.15376 -372.803166)
		(stroke
			(width 0.07112)
			(type default)
		)
		(layer "In15.Cu")
	)
	(gr_line
		(start 335.45399 -372.519956)
		(end 335.58988 -372.384066)
		(stroke
			(width 0.07112)
			(type default)
		)
		(layer "In15.Cu")
	)
	(gr_line
		(start 335.467706 -423.98315)
		(end 335.704942 -423.628058)
		(stroke
			(width 0.07112)
			(type default)
		)
		(layer "In15.Cu")
	)
	(gr_line
		(start 335.503266 -437.623204)
		(end 335.49971 -437.623204)
		(stroke
			(width 0.07112)
			(type default)
		)
		(layer "In15.Cu")
	)
	(gr_line
		(start 335.58988 -372.384066)
		(end 336.0166 -372.384066)
		(stroke
			(width 0.07112)
			(type default)
		)
		(layer "In15.Cu")
	)
	(gr_line
		(start 335.649824 -438.089802)
		(end 335.649824 -437.769762)
		(stroke
			(width 0.07112)
			(type default)
		)
		(layer "In15.Cu")
	)
	(gr_line
		(start 335.649824 -437.769762)
		(end 335.503266 -437.623204)
		(stroke
			(width 0.07112)
			(type default)
		)
		(layer "In15.Cu")
	)
	(gr_line
		(start 335.649824 -437.19115)
		(end 335.50098 -437.339994)
		(stroke
			(width 0.07112)
			(type default)
		)
		(layer "In15.Cu")
	)
	(gr_line
		(start 335.649824 -436.889906)
		(end 335.649824 -437.19115)
		(stroke
			(width 0.07112)
			(type default)
		)
		(layer "In15.Cu")
	)
	(gr_line
		(start 335.669636 -422.92651)
		(end 336.059272 -422.343326)
		(stroke
			(width 0.07112)
			(type default)
		)
		(layer "In15.Cu")
	)
	(gr_line
		(start 335.704942 -423.628058)
		(end 335.66735 -423.43959)
		(stroke
			(width 0.07112)
			(type default)
		)
		(layer "In15.Cu")
	)
	(gr_line
		(start 335.905856 -423.082974)
		(end 336.094324 -423.045382)
		(stroke
			(width 0.07112)
			(type default)
		)
		(layer "In15.Cu")
	)
	(gr_line
		(start 336.0166 -372.384066)
		(end 336.15249 -372.519956)
		(stroke
			(width 0.07112)
			(type default)
		)
		(layer "In15.Cu")
	)
	(gr_line
		(start 336.06232 -408.266138)
		(end 336.06232 -408.266392)
		(stroke
			(width 0.07112)
			(type default)
		)
		(layer "In15.Cu")
	)
	(gr_line
		(start 336.094324 -423.045382)
		(end 336.33156 -422.69029)
		(stroke
			(width 0.07112)
			(type default)
		)
		(layer "In15.Cu")
	)
	(gr_line
		(start 336.33156 -422.69029)
		(end 336.293968 -422.501822)
		(stroke
			(width 0.07112)
			(type default)
		)
		(layer "In15.Cu")
	)
	(gr_line
		(start 336.361532 -407.942034)
		(end 336.181192 -408.009344)
		(stroke
			(width 0.07112)
			(type default)
		)
		(layer "In15.Cu")
	)
	(gr_line
		(start 336.651346 -409.600908)
		(end 336.462878 -409.6385)
		(stroke
			(width 0.07112)
			(type default)
		)
		(layer "In15.Cu")
	)
	(gr_line
		(start 336.700114 -408.558492)
		(end 336.06232 -408.266392)
		(stroke
			(width 0.07112)
			(type default)
		)
		(layer "In15.Cu")
	)
	(gr_line
		(start 336.749898 -408.119834)
		(end 336.361532 -407.942034)
		(stroke
			(width 0.07112)
			(type default)
		)
		(layer "In15.Cu")
	)
	(gr_line
		(start 336.816954 -408.300428)
		(end 336.749898 -408.119834)
		(stroke
			(width 0.07112)
			(type default)
		)
		(layer "In15.Cu")
	)
	(gr_line
		(start 336.887566 -410.262832)
		(end 336.304382 -409.873196)
		(stroke
			(width 0.07112)
			(type default)
		)
		(layer "In15.Cu")
	)
	(gr_line
		(start 337.006438 -409.838144)
		(end 336.651346 -409.600908)
		(stroke
			(width 0.07112)
			(type default)
		)
		(layer "In15.Cu")
	)
	(gr_line
		(start 337.04403 -410.026612)
		(end 337.006438 -409.838144)
		(stroke
			(width 0.07112)
			(type default)
		)
		(layer "In15.Cu")
	)
	(gr_line
		(start 337.503262 -438.623202)
		(end 337.499706 -438.623202)
		(stroke
			(width 0.07112)
			(type default)
		)
		(layer "In15.Cu")
	)
	(gr_line
		(start 337.589114 -410.227526)
		(end 337.400646 -410.265118)
		(stroke
			(width 0.07112)
			(type default)
		)
		(layer "In15.Cu")
	)
	(gr_line
		(start 337.596734 -408.507692)
		(end 337.416394 -408.575002)
		(stroke
			(width 0.07112)
			(type default)
		)
		(layer "In15.Cu")
	)
	(gr_line
		(start 337.64982 -439.0898)
		(end 337.64982 -438.76976)
		(stroke
			(width 0.07112)
			(type default)
		)
		(layer "In15.Cu")
	)
	(gr_line
		(start 337.64982 -438.76976)
		(end 337.503262 -438.623202)
		(stroke
			(width 0.07112)
			(type default)
		)
		(layer "In15.Cu")
	)
	(gr_line
		(start 337.64982 -438.191148)
		(end 337.500976 -438.339992)
		(stroke
			(width 0.07112)
			(type default)
		)
		(layer "In15.Cu")
	)
	(gr_line
		(start 337.64982 -437.889904)
		(end 337.64982 -438.191148)
		(stroke
			(width 0.07112)
			(type default)
		)
		(layer "In15.Cu")
	)
	(gr_line
		(start 337.670648 -423.147998)
		(end 338.16671 -422.651936)
		(stroke
			(width 0.07112)
			(type default)
		)
		(layer "In15.Cu")
	)
	(gr_line
		(start 337.780376 -417.764976)
		(end 337.780376 -417.063936)
		(stroke
			(width 0.07112)
			(type default)
		)
		(layer "In15.Cu")
	)
	(gr_line
		(start 337.780376 -416.637216)
		(end 337.780376 -415.936176)
		(stroke
			(width 0.07112)
			(type default)
		)
		(layer "In15.Cu")
	)
	(gr_line
		(start 337.825334 -410.88945)
		(end 337.24215 -410.499814)
		(stroke
			(width 0.07112)
			(type default)
		)
		(layer "In15.Cu")
	)
	(gr_line
		(start 337.871816 -423.347388)
		(end 338.064094 -423.347388)
		(stroke
			(width 0.07112)
			(type default)
		)
		(layer "In15.Cu")
	)
	(gr_line
		(start 337.935062 -409.12415)
		(end 337.297522 -408.83205)
		(stroke
			(width 0.07112)
			(type default)
		)
		(layer "In15.Cu")
	)
	(gr_line
		(start 337.944206 -410.464762)
		(end 337.589114 -410.227526)
		(stroke
			(width 0.07112)
			(type default)
		)
		(layer "In15.Cu")
	)
	(gr_line
		(start 337.981798 -410.65323)
		(end 337.944206 -410.464762)
		(stroke
			(width 0.07112)
			(type default)
		)
		(layer "In15.Cu")
	)
	(gr_line
		(start 337.984846 -408.685492)
		(end 337.596734 -408.507692)
		(stroke
			(width 0.07112)
			(type default)
		)
		(layer "In15.Cu")
	)
	(gr_line
		(start 338.051902 -408.866086)
		(end 337.984846 -408.685492)
		(stroke
			(width 0.07112)
			(type default)
		)
		(layer "In15.Cu")
	)
	(gr_line
		(start 338.063586 -417.763706)
		(end 338.199476 -417.627816)
		(stroke
			(width 0.07112)
			(type default)
		)
		(layer "In15.Cu")
	)
	(gr_line
		(start 338.063586 -416.635946)
		(end 338.199476 -416.500056)
		(stroke
			(width 0.07112)
			(type default)
		)
		(layer "In15.Cu")
	)
	(gr_line
		(start 338.064094 -423.347388)
		(end 338.3661 -423.045382)
		(stroke
			(width 0.07112)
			(type default)
		)
		(layer "In15.Cu")
	)
	(gr_line
		(start 338.199476 -417.627816)
		(end 338.199476 -417.201096)
		(stroke
			(width 0.07112)
			(type default)
		)
		(layer "In15.Cu")
	)
	(gr_line
		(start 338.199476 -417.201096)
		(end 338.063586 -417.065206)
		(stroke
			(width 0.07112)
			(type default)
		)
		(layer "In15.Cu")
	)
	(gr_line
		(start 338.199476 -416.500056)
		(end 338.199476 -416.073336)
		(stroke
			(width 0.07112)
			(type default)
		)
		(layer "In15.Cu")
	)
	(gr_line
		(start 338.199476 -416.073336)
		(end 338.063586 -415.937446)
		(stroke
			(width 0.07112)
			(type default)
		)
		(layer "In15.Cu")
	)
	(gr_line
		(start 338.3661 -423.045382)
		(end 338.3661 -422.853104)
		(stroke
			(width 0.07112)
			(type default)
		)
		(layer "In15.Cu")
	)
	(gr_line
		(start 338.468208 -422.350438)
		(end 338.96427 -421.854376)
		(stroke
			(width 0.07112)
			(type default)
		)
		(layer "In15.Cu")
	)
	(gr_line
		(start 338.669376 -422.549828)
		(end 338.861654 -422.549828)
		(stroke
			(width 0.07112)
			(type default)
		)
		(layer "In15.Cu")
	)
	(gr_line
		(start 338.770468 -424.520614)
		(end 338.770468 -424.520868)
		(stroke
			(width 0.07112)
			(type default)
		)
		(layer "In15.Cu")
	)
	(gr_line
		(start 338.861654 -422.549828)
		(end 339.16366 -422.247822)
		(stroke
			(width 0.07112)
			(type default)
		)
		(layer "In15.Cu")
	)
	(gr_line
		(start 339.16366 -422.247822)
		(end 339.16366 -422.055544)
		(stroke
			(width 0.07112)
			(type default)
		)
		(layer "In15.Cu")
	)
	(gr_line
		(start 339.503258 -437.623204)
		(end 339.499702 -437.623204)
		(stroke
			(width 0.07112)
			(type default)
		)
		(layer "In15.Cu")
	)
	(gr_line
		(start 339.649816 -438.089802)
		(end 339.649816 -437.769762)
		(stroke
			(width 0.07112)
			(type default)
		)
		(layer "In15.Cu")
	)
	(gr_line
		(start 339.649816 -437.769762)
		(end 339.503258 -437.623204)
		(stroke
			(width 0.07112)
			(type default)
		)
		(layer "In15.Cu")
	)
	(gr_line
		(start 339.649816 -437.19115)
		(end 339.500972 -437.339994)
		(stroke
			(width 0.07112)
			(type default)
		)
		(layer "In15.Cu")
	)
	(gr_line
		(start 339.649816 -436.889906)
		(end 339.649816 -437.19115)
		(stroke
			(width 0.07112)
			(type default)
		)
		(layer "In15.Cu")
	)
	(gr_line
		(start 339.718142 -409.734258)
		(end 339.52942 -409.77185)
		(stroke
			(width 0.07112)
			(type default)
		)
		(layer "In15.Cu")
	)
	(gr_line
		(start 339.954362 -410.396436)
		(end 339.371178 -410.006546)
		(stroke
			(width 0.07112)
			(type default)
		)
		(layer "In15.Cu")
	)
	(gr_line
		(start 340.073234 -409.971748)
		(end 339.718142 -409.734258)
		(stroke
			(width 0.07112)
			(type default)
		)
		(layer "In15.Cu")
	)
	(gr_line
		(start 340.110826 -410.16047)
		(end 340.073234 -409.971748)
		(stroke
			(width 0.07112)
			(type default)
		)
		(layer "In15.Cu")
	)
	(gr_line
		(start 340.65591 -410.36113)
		(end 340.467188 -410.398722)
		(stroke
			(width 0.07112)
			(type default)
		)
		(layer "In15.Cu")
	)
	(gr_line
		(start 340.843616 -417.858702)
		(end 340.843616 -417.157662)
		(stroke
			(width 0.07112)
			(type default)
		)
		(layer "In15.Cu")
	)
	(gr_line
		(start 340.843616 -416.730942)
		(end 340.843616 -416.029902)
		(stroke
			(width 0.07112)
			(type default)
		)
		(layer "In15.Cu")
	)
	(gr_line
		(start 340.877144 -306.432966)
		(end 340.586314 -306.142136)
		(stroke
			(width 0.07112)
			(type default)
		)
		(layer "In15.Cu")
	)
	(gr_line
		(start 340.877144 -305.569366)
		(end 340.586314 -305.860196)
		(stroke
			(width 0.07112)
			(type default)
		)
		(layer "In15.Cu")
	)
	(gr_line
		(start 340.89213 -411.023308)
		(end 340.308946 -410.633418)
		(stroke
			(width 0.07112)
			(type default)
		)
		(layer "In15.Cu")
	)
	(gr_line
		(start 341.011002 -410.59862)
		(end 340.65591 -410.36113)
		(stroke
			(width 0.07112)
			(type default)
		)
		(layer "In15.Cu")
	)
	(gr_line
		(start 341.018368 -408.707336)
		(end 341.018368 -408.70759)
		(stroke
			(width 0.07112)
			(type default)
		)
		(layer "In15.Cu")
	)
	(gr_line
		(start 341.048594 -410.787088)
		(end 341.011002 -410.59862)
		(stroke
			(width 0.07112)
			(type default)
		)
		(layer "In15.Cu")
	)
	(gr_line
		(start 341.126826 -417.857432)
		(end 341.262716 -417.721542)
		(stroke
			(width 0.07112)
			(type default)
		)
		(layer "In15.Cu")
	)
	(gr_line
		(start 341.126826 -416.729672)
		(end 341.262716 -416.593782)
		(stroke
			(width 0.07112)
			(type default)
		)
		(layer "In15.Cu")
	)
	(gr_line
		(start 341.262716 -417.721542)
		(end 341.262716 -417.294822)
		(stroke
			(width 0.07112)
			(type default)
		)
		(layer "In15.Cu")
	)
	(gr_line
		(start 341.262716 -417.294822)
		(end 341.126826 -417.158932)
		(stroke
			(width 0.07112)
			(type default)
		)
		(layer "In15.Cu")
	)
	(gr_line
		(start 341.262716 -416.593782)
		(end 341.262716 -416.167062)
		(stroke
			(width 0.07112)
			(type default)
		)
		(layer "In15.Cu")
	)
	(gr_line
		(start 341.262716 -416.167062)
		(end 341.126826 -416.031172)
		(stroke
			(width 0.07112)
			(type default)
		)
		(layer "In15.Cu")
	)
	(gr_line
		(start 341.347806 -408.41422)
		(end 341.161878 -408.463496)
		(stroke
			(width 0.07112)
			(type default)
		)
		(layer "In15.Cu")
	)
	(gr_line
		(start 341.503254 -438.623202)
		(end 341.499698 -438.623202)
		(stroke
			(width 0.07112)
			(type default)
		)
		(layer "In15.Cu")
	)
	(gr_line
		(start 341.593678 -410.988002)
		(end 341.40521 -411.025594)
		(stroke
			(width 0.07112)
			(type default)
		)
		(layer "In15.Cu")
	)
	(gr_line
		(start 341.623904 -409.06065)
		(end 341.018368 -408.70759)
		(stroke
			(width 0.07112)
			(type default)
		)
		(layer "In15.Cu")
	)
	(gr_line
		(start 341.649812 -439.0898)
		(end 341.649812 -438.76976)
		(stroke
			(width 0.07112)
			(type default)
		)
		(layer "In15.Cu")
	)
	(gr_line
		(start 341.649812 -438.76976)
		(end 341.503254 -438.623202)
		(stroke
			(width 0.07112)
			(type default)
		)
		(layer "In15.Cu")
	)
	(gr_line
		(start 341.649812 -438.191148)
		(end 341.500968 -438.339992)
		(stroke
			(width 0.07112)
			(type default)
		)
		(layer "In15.Cu")
	)
	(gr_line
		(start 341.649812 -437.889904)
		(end 341.649812 -438.191148)
		(stroke
			(width 0.07112)
			(type default)
		)
		(layer "In15.Cu")
	)
	(gr_line
		(start 341.716614 -408.629104)
		(end 341.347806 -408.41422)
		(stroke
			(width 0.07112)
			(type default)
		)
		(layer "In15.Cu")
	)
	(gr_line
		(start 341.75954 -386.757418)
		(end 342.46058 -386.757418)
		(stroke
			(width 0.07112)
			(type default)
		)
		(layer "In15.Cu")
	)
	(gr_line
		(start 341.76081 -386.474208)
		(end 341.8967 -386.338318)
		(stroke
			(width 0.07112)
			(type default)
		)
		(layer "In15.Cu")
	)
	(gr_line
		(start 341.76589 -408.81554)
		(end 341.716614 -408.629104)
		(stroke
			(width 0.07112)
			(type default)
		)
		(layer "In15.Cu")
	)
	(gr_line
		(start 341.829898 -411.65018)
		(end 341.246714 -411.26029)
		(stroke
			(width 0.07112)
			(type default)
		)
		(layer "In15.Cu")
	)
	(gr_line
		(start 341.8967 -386.338318)
		(end 342.32342 -386.338318)
		(stroke
			(width 0.07112)
			(type default)
		)
		(layer "In15.Cu")
	)
	(gr_line
		(start 341.900002 -309.303166)
		(end 341.609172 -309.012336)
		(stroke
			(width 0.07112)
			(type default)
		)
		(layer "In15.Cu")
	)
	(gr_line
		(start 341.900002 -308.439566)
		(end 341.609172 -308.730396)
		(stroke
			(width 0.07112)
			(type default)
		)
		(layer "In15.Cu")
	)
	(gr_line
		(start 341.94877 -411.225492)
		(end 341.593678 -410.988002)
		(stroke
			(width 0.07112)
			(type default)
		)
		(layer "In15.Cu")
	)
	(gr_line
		(start 341.986362 -411.41396)
		(end 341.94877 -411.225492)
		(stroke
			(width 0.07112)
			(type default)
		)
		(layer "In15.Cu")
	)
	(gr_line
		(start 342.32215 -408.982418)
		(end 342.136222 -409.03144)
		(stroke
			(width 0.07112)
			(type default)
		)
		(layer "In15.Cu")
	)
	(gr_line
		(start 342.32342 -386.338318)
		(end 342.45931 -386.474208)
		(stroke
			(width 0.07112)
			(type default)
		)
		(layer "In15.Cu")
	)
	(gr_line
		(start 342.598502 -409.628594)
		(end 341.992458 -409.275534)
		(stroke
			(width 0.07112)
			(type default)
		)
		(layer "In15.Cu")
	)
	(gr_line
		(start 342.691212 -409.197302)
		(end 342.32215 -408.982418)
		(stroke
			(width 0.07112)
			(type default)
		)
		(layer "In15.Cu")
	)
	(gr_line
		(start 342.73998 -409.383484)
		(end 342.691212 -409.197302)
		(stroke
			(width 0.07112)
			(type default)
		)
		(layer "In15.Cu")
	)
	(gr_line
		(start 342.8873 -386.757418)
		(end 343.58834 -386.757418)
		(stroke
			(width 0.07112)
			(type default)
		)
		(layer "In15.Cu")
	)
	(gr_line
		(start 342.88857 -386.474208)
		(end 343.02446 -386.338318)
		(stroke
			(width 0.07112)
			(type default)
		)
		(layer "In15.Cu")
	)
	(gr_line
		(start 343.02446 -386.338318)
		(end 343.45118 -386.338318)
		(stroke
			(width 0.07112)
			(type default)
		)
		(layer "In15.Cu")
	)
	(gr_line
		(start 343.45118 -386.338318)
		(end 343.58707 -386.474208)
		(stroke
			(width 0.07112)
			(type default)
		)
		(layer "In15.Cu")
	)
	(gr_line
		(start 343.50325 -437.623204)
		(end 343.499694 -437.623204)
		(stroke
			(width 0.07112)
			(type default)
		)
		(layer "In15.Cu")
	)
	(gr_line
		(start 343.649808 -438.089802)
		(end 343.649808 -437.769762)
		(stroke
			(width 0.07112)
			(type default)
		)
		(layer "In15.Cu")
	)
	(gr_line
		(start 343.649808 -437.769762)
		(end 343.50325 -437.623204)
		(stroke
			(width 0.07112)
			(type default)
		)
		(layer "In15.Cu")
	)
	(gr_line
		(start 343.649808 -437.19115)
		(end 343.500964 -437.339994)
		(stroke
			(width 0.07112)
			(type default)
		)
		(layer "In15.Cu")
	)
	(gr_line
		(start 343.649808 -436.889906)
		(end 343.649808 -437.19115)
		(stroke
			(width 0.07112)
			(type default)
		)
		(layer "In15.Cu")
	)
	(gr_line
		(start 344.01506 -386.757418)
		(end 344.7161 -386.757418)
		(stroke
			(width 0.07112)
			(type default)
		)
		(layer "In15.Cu")
	)
	(gr_line
		(start 344.01633 -386.474208)
		(end 344.15222 -386.338318)
		(stroke
			(width 0.07112)
			(type default)
		)
		(layer "In15.Cu")
	)
	(gr_line
		(start 344.15222 -386.338318)
		(end 344.57894 -386.338318)
		(stroke
			(width 0.07112)
			(type default)
		)
		(layer "In15.Cu")
	)
	(gr_line
		(start 344.57894 -386.338318)
		(end 344.71483 -386.474208)
		(stroke
			(width 0.07112)
			(type default)
		)
		(layer "In15.Cu")
	)
	(gr_line
		(start 345.503246 -438.623202)
		(end 345.49969 -438.623202)
		(stroke
			(width 0.07112)
			(type default)
		)
		(layer "In15.Cu")
	)
	(gr_line
		(start 345.649804 -439.0898)
		(end 345.649804 -438.76976)
		(stroke
			(width 0.07112)
			(type default)
		)
		(layer "In15.Cu")
	)
	(gr_line
		(start 345.649804 -438.76976)
		(end 345.503246 -438.623202)
		(stroke
			(width 0.07112)
			(type default)
		)
		(layer "In15.Cu")
	)
	(gr_line
		(start 345.649804 -438.191148)
		(end 345.50096 -438.339992)
		(stroke
			(width 0.07112)
			(type default)
		)
		(layer "In15.Cu")
	)
	(gr_line
		(start 345.649804 -437.889904)
		(end 345.649804 -438.191148)
		(stroke
			(width 0.07112)
			(type default)
		)
		(layer "In15.Cu")
	)
	(gr_line
		(start 346.009722 -422.644824)
		(end 346.607638 -422.445688)
		(stroke
			(width 0.07112)
			(type default)
		)
		(layer "In15.Cu")
	)
	(gr_line
		(start 346.099892 -422.913302)
		(end 346.2274 -422.977056)
		(stroke
			(width 0.07112)
			(type default)
		)
		(layer "In15.Cu")
	)
	(gr_line
		(start 346.2274 -422.977056)
		(end 346.63253 -422.842182)
		(stroke
			(width 0.07112)
			(type default)
		)
		(layer "In15.Cu")
	)
	(gr_line
		(start 346.63253 -422.842182)
		(end 346.696284 -422.714674)
		(stroke
			(width 0.07112)
			(type default)
		)
		(layer "In15.Cu")
	)
	(gr_line
		(start 346.668598 -423.524426)
		(end 347.339666 -423.320972)
		(stroke
			(width 0.07112)
			(type default)
		)
		(layer "In15.Cu")
	)
	(gr_line
		(start 346.751656 -423.79519)
		(end 346.921582 -423.886122)
		(stroke
			(width 0.07112)
			(type default)
		)
		(layer "In15.Cu")
	)
	(gr_line
		(start 346.83192 -373.747284)
		(end 347.53296 -373.747284)
		(stroke
			(width 0.07112)
			(type default)
		)
		(layer "In15.Cu")
	)
	(gr_line
		(start 346.83319 -373.464074)
		(end 346.96908 -373.328184)
		(stroke
			(width 0.07112)
			(type default)
		)
		(layer "In15.Cu")
	)
	(gr_line
		(start 346.921582 -423.886122)
		(end 347.330014 -423.76217)
		(stroke
			(width 0.07112)
			(type default)
		)
		(layer "In15.Cu")
	)
	(gr_line
		(start 346.96908 -373.328184)
		(end 347.3958 -373.328184)
		(stroke
			(width 0.07112)
			(type default)
		)
		(layer "In15.Cu")
	)
	(gr_line
		(start 346.970096 -417.764976)
		(end 346.970096 -417.063936)
		(stroke
			(width 0.07112)
			(type default)
		)
		(layer "In15.Cu")
	)
	(gr_line
		(start 346.970096 -416.637216)
		(end 346.970096 -415.936176)
		(stroke
			(width 0.07112)
			(type default)
		)
		(layer "In15.Cu")
	)
	(gr_line
		(start 347.01226 -422.310814)
		(end 347.610176 -422.111424)
		(stroke
			(width 0.07112)
			(type default)
		)
		(layer "In15.Cu")
	)
	(gr_line
		(start 347.102684 -422.579038)
		(end 347.229938 -422.642792)
		(stroke
			(width 0.07112)
			(type default)
		)
		(layer "In15.Cu")
	)
	(gr_line
		(start 347.229938 -422.642792)
		(end 347.635068 -422.507918)
		(stroke
			(width 0.07112)
			(type default)
		)
		(layer "In15.Cu")
	)
	(gr_line
		(start 347.253306 -417.763706)
		(end 347.389196 -417.627816)
		(stroke
			(width 0.07112)
			(type default)
		)
		(layer "In15.Cu")
	)
	(gr_line
		(start 347.253306 -416.635946)
		(end 347.389196 -416.500056)
		(stroke
			(width 0.07112)
			(type default)
		)
		(layer "In15.Cu")
	)
	(gr_line
		(start 347.330014 -423.76217)
		(end 347.420692 -423.592244)
		(stroke
			(width 0.07112)
			(type default)
		)
		(layer "In15.Cu")
	)
	(gr_line
		(start 347.389196 -417.627816)
		(end 347.389196 -417.201096)
		(stroke
			(width 0.07112)
			(type default)
		)
		(layer "In15.Cu")
	)
	(gr_line
		(start 347.389196 -417.201096)
		(end 347.253306 -417.065206)
		(stroke
			(width 0.07112)
			(type default)
		)
		(layer "In15.Cu")
	)
	(gr_line
		(start 347.389196 -416.500056)
		(end 347.389196 -416.073336)
		(stroke
			(width 0.07112)
			(type default)
		)
		(layer "In15.Cu")
	)
	(gr_line
		(start 347.389196 -416.073336)
		(end 347.253306 -415.937446)
		(stroke
			(width 0.07112)
			(type default)
		)
		(layer "In15.Cu")
	)
	(gr_line
		(start 347.3958 -373.328184)
		(end 347.53169 -373.464074)
		(stroke
			(width 0.07112)
			(type default)
		)
		(layer "In15.Cu")
	)
	(gr_line
		(start 347.635068 -422.507918)
		(end 347.698822 -422.38041)
		(stroke
			(width 0.07112)
			(type default)
		)
		(layer "In15.Cu")
	)
	(gr_line
		(start 347.747844 -423.197274)
		(end 348.418912 -422.993566)
		(stroke
			(width 0.07112)
			(type default)
		)
		(layer "In15.Cu")
	)
	(gr_line
		(start 347.830902 -423.468038)
		(end 348.000828 -423.558716)
		(stroke
			(width 0.07112)
			(type default)
		)
		(layer "In15.Cu")
	)
	(gr_line
		(start 348.000828 -423.558716)
		(end 348.40926 -423.434764)
		(stroke
			(width 0.07112)
			(type default)
		)
		(layer "In15.Cu")
	)
	(gr_line
		(start 348.09938 -373.747284)
		(end 348.80042 -373.747284)
		(stroke
			(width 0.07112)
			(type default)
		)
		(layer "In15.Cu")
	)
	(gr_line
		(start 348.10065 -373.464074)
		(end 348.23654 -373.328184)
		(stroke
			(width 0.07112)
			(type default)
		)
		(layer "In15.Cu")
	)
	(gr_line
		(start 348.15399 -311.513728)
		(end 347.86316 -311.222898)
		(stroke
			(width 0.07112)
			(type default)
		)
		(layer "In15.Cu")
	)
	(gr_line
		(start 348.15399 -310.650128)
		(end 347.86316 -310.940958)
		(stroke
			(width 0.07112)
			(type default)
		)
		(layer "In15.Cu")
	)
	(gr_line
		(start 348.23654 -373.328184)
		(end 348.66326 -373.328184)
		(stroke
			(width 0.07112)
			(type default)
		)
		(layer "In15.Cu")
	)
	(gr_line
		(start 348.40926 -423.434764)
		(end 348.499938 -423.265092)
		(stroke
			(width 0.07112)
			(type default)
		)
		(layer "In15.Cu")
	)
	(gr_line
		(start 348.66326 -373.328184)
		(end 348.79915 -373.464074)
		(stroke
			(width 0.07112)
			(type default)
		)
		(layer "In15.Cu")
	)
	(gr_line
		(start 348.82709 -422.869868)
		(end 349.498158 -422.666414)
		(stroke
			(width 0.07112)
			(type default)
		)
		(layer "In15.Cu")
	)
	(gr_line
		(start 348.910148 -423.140632)
		(end 349.080074 -423.23131)
		(stroke
			(width 0.07112)
			(type default)
		)
		(layer "In15.Cu")
	)
	(gr_line
		(start 349.080074 -423.23131)
		(end 349.488506 -423.107612)
		(stroke
			(width 0.07112)
			(type default)
		)
		(layer "In15.Cu")
	)
	(gr_line
		(start 349.488506 -423.107612)
		(end 349.579184 -422.937686)
		(stroke
			(width 0.07112)
			(type default)
		)
		(layer "In15.Cu")
	)
	(gr_line
		(start 350.033336 -417.671504)
		(end 350.033336 -416.970464)
		(stroke
			(width 0.07112)
			(type default)
		)
		(layer "In15.Cu")
	)
	(gr_line
		(start 350.033336 -416.543744)
		(end 350.033336 -415.842704)
		(stroke
			(width 0.07112)
			(type default)
		)
		(layer "In15.Cu")
	)
	(gr_line
		(start 350.09582 -373.747284)
		(end 350.79686 -373.747284)
		(stroke
			(width 0.07112)
			(type default)
		)
		(layer "In15.Cu")
	)
	(gr_line
		(start 350.09709 -373.464074)
		(end 350.23298 -373.328184)
		(stroke
			(width 0.07112)
			(type default)
		)
		(layer "In15.Cu")
	)
	(gr_line
		(start 350.23298 -373.328184)
		(end 350.6597 -373.328184)
		(stroke
			(width 0.07112)
			(type default)
		)
		(layer "In15.Cu")
	)
	(gr_line
		(start 350.316546 -417.670234)
		(end 350.452436 -417.534344)
		(stroke
			(width 0.07112)
			(type default)
		)
		(layer "In15.Cu")
	)
	(gr_line
		(start 350.316546 -416.542474)
		(end 350.452436 -416.406584)
		(stroke
			(width 0.07112)
			(type default)
		)
		(layer "In15.Cu")
	)
	(gr_line
		(start 350.452436 -417.534344)
		(end 350.452436 -417.107624)
		(stroke
			(width 0.07112)
			(type default)
		)
		(layer "In15.Cu")
	)
	(gr_line
		(start 350.452436 -417.107624)
		(end 350.316546 -416.971734)
		(stroke
			(width 0.07112)
			(type default)
		)
		(layer "In15.Cu")
	)
	(gr_line
		(start 350.452436 -416.406584)
		(end 350.452436 -415.979864)
		(stroke
			(width 0.07112)
			(type default)
		)
		(layer "In15.Cu")
	)
	(gr_line
		(start 350.452436 -415.979864)
		(end 350.316546 -415.843974)
		(stroke
			(width 0.07112)
			(type default)
		)
		(layer "In15.Cu")
	)
	(gr_line
		(start 350.6597 -373.328184)
		(end 350.79559 -373.464074)
		(stroke
			(width 0.07112)
			(type default)
		)
		(layer "In15.Cu")
	)
	(gr_line
		(start 351.859088 -270.036036)
		(end 351.561146 -270.036036)
		(stroke
			(width 0.05715)
			(type default)
		)
		(layer "In15.Cu")
	)
	(gr_line
		(start 351.941892 -270.11884)
		(end 351.859088 -270.036036)
		(stroke
			(width 0.05715)
			(type default)
		)
		(layer "In15.Cu")
	)
	(gr_arc
		(start 351.941892 -270.11884)
		(mid 351.943678 -270.13029)
		(end 351.945702 -270.1417)
		(stroke
			(width 0.05715)
			(type default)
		)
		(layer "In15.Cu")
	)
	(gr_line
		(start 351.966784 -296.374566)
		(end 351.966784 -296.346118)
		(stroke
			(width 0.05715)
			(type default)
		)
		(layer "In15.Cu")
	)
	(gr_line
		(start 351.966784 -296.346118)
		(end 352.012504 -296.300398)
		(stroke
			(width 0.05715)
			(type default)
		)
		(layer "In15.Cu")
	)
	(gr_line
		(start 352.133916 -270.105378)
		(end 352.203258 -270.036036)
		(stroke
			(width 0.05715)
			(type default)
		)
		(layer "In15.Cu")
	)
	(gr_line
		(start 352.203258 -270.036036)
		(end 352.5012 -270.036036)
		(stroke
			(width 0.05715)
			(type default)
		)
		(layer "In15.Cu")
	)
	(gr_line
		(start 352.248724 -296.374566)
		(end 352.248724 -296.346118)
		(stroke
			(width 0.05715)
			(type default)
		)
		(layer "In15.Cu")
	)
	(gr_line
		(start 352.248724 -296.346118)
		(end 352.203004 -296.300398)
		(stroke
			(width 0.05715)
			(type default)
		)
		(layer "In15.Cu")
	)
	(gr_line
		(start 352.62312 -272.912078)
		(end 352.621342 -272.910808)
		(stroke
			(width 0.05715)
			(type default)
		)
		(layer "In15.Cu")
	)
	(gr_line
		(start 352.638614 -272.923)
		(end 352.637598 -272.922238)
		(stroke
			(width 0.05715)
			(type default)
		)
		(layer "In15.Cu")
	)
	(gr_line
		(start 352.660204 -272.937224)
		(end 352.653346 -272.93316)
		(stroke
			(width 0.05715)
			(type default)
		)
		(layer "In15.Cu")
	)
	(gr_line
		(start 352.67519 -288.186114)
		(end 352.677222 -288.184844)
		(stroke
			(width 0.05715)
			(type default)
		)
		(layer "In15.Cu")
	)
	(gr_line
		(start 352.675698 -289.14598)
		(end 352.67519 -289.145726)
		(stroke
			(width 0.05715)
			(type default)
		)
		(layer "In15.Cu")
	)
	(gr_arc
		(start 352.676714 -294.006778)
		(mid 352.679124 -294.008181)
		(end 352.68154 -294.009572)
		(stroke
			(width 0.05715)
			(type default)
		)
		(layer "In15.Cu")
	)
	(gr_arc
		(start 352.676714 -292.386766)
		(mid 352.679124 -292.388169)
		(end 352.68154 -292.38956)
		(stroke
			(width 0.05715)
			(type default)
		)
		(layer "In15.Cu")
	)
	(gr_arc
		(start 352.676714 -290.766754)
		(mid 352.67849 -290.767773)
		(end 352.68027 -290.768786)
		(stroke
			(width 0.05715)
			(type default)
		)
		(layer "In15.Cu")
	)
	(gr_line
		(start 352.679254 -287.527746)
		(end 352.671888 -287.52292)
		(stroke
			(width 0.05715)
			(type default)
		)
		(layer "In15.Cu")
	)
	(gr_line
		(start 352.68789 -293.038784)
		(end 352.688144 -293.03853)
		(stroke
			(width 0.05715)
			(type default)
		)
		(layer "In15.Cu")
	)
	(gr_line
		(start 352.68789 -291.418772)
		(end 352.688144 -291.418518)
		(stroke
			(width 0.05715)
			(type default)
		)
		(layer "In15.Cu")
	)
	(gr_line
		(start 352.68789 -289.79876)
		(end 352.688144 -289.798506)
		(stroke
			(width 0.05715)
			(type default)
		)
		(layer "In15.Cu")
	)
	(gr_line
		(start 352.688144 -294.013382)
		(end 352.68789 -294.013382)
		(stroke
			(width 0.05715)
			(type default)
		)
		(layer "In15.Cu")
	)
	(gr_line
		(start 352.688144 -292.39337)
		(end 352.68789 -292.39337)
		(stroke
			(width 0.05715)
			(type default)
		)
		(layer "In15.Cu")
	)
	(gr_line
		(start 352.688144 -290.773358)
		(end 352.68789 -290.773358)
		(stroke
			(width 0.05715)
			(type default)
		)
		(layer "In15.Cu")
	)
	(gr_line
		(start 352.688144 -284.938724)
		(end 352.688652 -284.93847)
		(stroke
			(width 0.05715)
			(type default)
		)
		(layer "In15.Cu")
	)
	(gr_line
		(start 352.688144 -281.05354)
		(end 352.688144 -281.053286)
		(stroke
			(width 0.05715)
			(type default)
		)
		(layer "In15.Cu")
	)
	(gr_line
		(start 352.688144 -273.59864)
		(end 352.688652 -273.598386)
		(stroke
			(width 0.05715)
			(type default)
		)
		(layer "In15.Cu")
	)
	(gr_line
		(start 352.688398 -275.218652)
		(end 352.689668 -275.21789)
		(stroke
			(width 0.05715)
			(type default)
		)
		(layer "In15.Cu")
	)
	(gr_line
		(start 352.688652 -281.053794)
		(end 352.688144 -281.05354)
		(stroke
			(width 0.05715)
			(type default)
		)
		(layer "In15.Cu")
	)
	(gr_line
		(start 352.688906 -285.914084)
		(end 352.688144 -285.913576)
		(stroke
			(width 0.05715)
			(type default)
		)
		(layer "In15.Cu")
	)
	(gr_line
		(start 352.688906 -284.294072)
		(end 352.688144 -284.293564)
		(stroke
			(width 0.05715)
			(type default)
		)
		(layer "In15.Cu")
	)
	(gr_line
		(start 352.688906 -282.67406)
		(end 352.688144 -282.673552)
		(stroke
			(width 0.05715)
			(type default)
		)
		(layer "In15.Cu")
	)
	(gr_line
		(start 352.688906 -279.434036)
		(end 352.688144 -279.433528)
		(stroke
			(width 0.05715)
			(type default)
		)
		(layer "In15.Cu")
	)
	(gr_line
		(start 352.688906 -277.814024)
		(end 352.688144 -277.813516)
		(stroke
			(width 0.05715)
			(type default)
		)
		(layer "In15.Cu")
	)
	(gr_line
		(start 352.688906 -276.194012)
		(end 352.688144 -276.193504)
		(stroke
			(width 0.05715)
			(type default)
		)
		(layer "In15.Cu")
	)
	(gr_line
		(start 352.688906 -274.574)
		(end 352.688144 -274.573492)
		(stroke
			(width 0.05715)
			(type default)
		)
		(layer "In15.Cu")
	)
	(gr_line
		(start 352.688906 -272.953988)
		(end 352.688144 -272.95348)
		(stroke
			(width 0.05715)
			(type default)
		)
		(layer "In15.Cu")
	)
	(gr_line
		(start 352.689668 -294.65778)
		(end 352.69043 -294.657272)
		(stroke
			(width 0.05715)
			(type default)
		)
		(layer "In15.Cu")
	)
	(gr_line
		(start 352.689668 -275.21789)
		(end 352.69043 -275.217382)
		(stroke
			(width 0.05715)
			(type default)
		)
		(layer "In15.Cu")
	)
	(gr_line
		(start 352.69043 -294.657272)
		(end 352.691446 -294.656764)
		(stroke
			(width 0.05715)
			(type default)
		)
		(layer "In15.Cu")
	)
	(gr_line
		(start 352.69043 -276.837394)
		(end 352.691446 -276.836886)
		(stroke
			(width 0.05715)
			(type default)
		)
		(layer "In15.Cu")
	)
	(gr_line
		(start 352.691446 -294.656764)
		(end 352.692208 -294.656256)
		(stroke
			(width 0.05715)
			(type default)
		)
		(layer "In15.Cu")
	)
	(gr_line
		(start 352.691446 -276.836886)
		(end 352.692208 -276.836378)
		(stroke
			(width 0.05715)
			(type default)
		)
		(layer "In15.Cu")
	)
	(gr_line
		(start 352.692208 -294.656256)
		(end 352.693732 -294.655494)
		(stroke
			(width 0.05715)
			(type default)
		)
		(layer "In15.Cu")
	)
	(gr_line
		(start 352.692208 -276.836378)
		(end 352.693224 -276.83587)
		(stroke
			(width 0.05715)
			(type default)
		)
		(layer "In15.Cu")
	)
	(gr_line
		(start 352.692208 -275.216366)
		(end 352.694748 -275.215096)
		(stroke
			(width 0.05715)
			(type default)
		)
		(layer "In15.Cu")
	)
	(gr_line
		(start 352.693224 -276.83587)
		(end 352.693986 -276.835362)
		(stroke
			(width 0.05715)
			(type default)
		)
		(layer "In15.Cu")
	)
	(gr_line
		(start 352.694748 -275.215096)
		(end 352.69551 -275.214588)
		(stroke
			(width 0.05715)
			(type default)
		)
		(layer "In15.Cu")
	)
	(gr_line
		(start 352.69551 -275.214588)
		(end 352.696526 -275.21408)
		(stroke
			(width 0.05715)
			(type default)
		)
		(layer "In15.Cu")
	)
	(gr_line
		(start 352.697034 -294.018462)
		(end 352.695764 -294.0177)
		(stroke
			(width 0.05715)
			(type default)
		)
		(layer "In15.Cu")
	)
	(gr_line
		(start 352.780092 -294.825674)
		(end 352.783394 -294.823896)
		(stroke
			(width 0.05715)
			(type default)
		)
		(layer "In15.Cu")
	)
	(gr_line
		(start 352.783394 -294.823896)
		(end 352.784156 -294.823388)
		(stroke
			(width 0.05715)
			(type default)
		)
		(layer "In15.Cu")
	)
	(gr_line
		(start 352.783394 -284.12821)
		(end 352.7806 -284.126686)
		(stroke
			(width 0.05715)
			(type default)
		)
		(layer "In15.Cu")
	)
	(gr_line
		(start 352.783394 -282.508198)
		(end 352.7806 -282.506674)
		(stroke
			(width 0.05715)
			(type default)
		)
		(layer "In15.Cu")
	)
	(gr_line
		(start 352.783394 -280.888186)
		(end 352.782632 -280.887678)
		(stroke
			(width 0.05715)
			(type default)
		)
		(layer "In15.Cu")
	)
	(gr_line
		(start 352.783394 -279.268174)
		(end 352.7806 -279.26665)
		(stroke
			(width 0.05715)
			(type default)
		)
		(layer "In15.Cu")
	)
	(gr_line
		(start 352.783394 -277.648162)
		(end 352.7806 -277.646638)
		(stroke
			(width 0.05715)
			(type default)
		)
		(layer "In15.Cu")
	)
	(gr_line
		(start 352.783394 -276.02815)
		(end 352.7806 -276.026626)
		(stroke
			(width 0.05715)
			(type default)
		)
		(layer "In15.Cu")
	)
	(gr_line
		(start 352.783394 -272.788126)
		(end 352.7806 -272.786602)
		(stroke
			(width 0.05715)
			(type default)
		)
		(layer "In15.Cu")
	)
	(gr_line
		(start 352.784156 -294.823388)
		(end 352.785172 -294.82288)
		(stroke
			(width 0.05715)
			(type default)
		)
		(layer "In15.Cu")
	)
	(gr_line
		(start 352.784156 -284.128718)
		(end 352.783394 -284.12821)
		(stroke
			(width 0.05715)
			(type default)
		)
		(layer "In15.Cu")
	)
	(gr_line
		(start 352.784156 -282.508706)
		(end 352.783394 -282.508198)
		(stroke
			(width 0.05715)
			(type default)
		)
		(layer "In15.Cu")
	)
	(gr_line
		(start 352.784156 -279.268682)
		(end 352.783394 -279.268174)
		(stroke
			(width 0.05715)
			(type default)
		)
		(layer "In15.Cu")
	)
	(gr_line
		(start 352.784156 -277.64867)
		(end 352.783394 -277.648162)
		(stroke
			(width 0.05715)
			(type default)
		)
		(layer "In15.Cu")
	)
	(gr_line
		(start 352.784156 -276.028658)
		(end 352.783394 -276.02815)
		(stroke
			(width 0.05715)
			(type default)
		)
		(layer "In15.Cu")
	)
	(gr_line
		(start 352.784156 -272.788634)
		(end 352.783394 -272.788126)
		(stroke
			(width 0.05715)
			(type default)
		)
		(layer "In15.Cu")
	)
	(gr_line
		(start 352.784156 -271.168622)
		(end 352.783648 -271.168368)
		(stroke
			(width 0.05715)
			(type default)
		)
		(layer "In15.Cu")
	)
	(gr_line
		(start 352.784664 -272.14322)
		(end 352.792792 -272.138648)
		(stroke
			(width 0.05715)
			(type default)
		)
		(layer "In15.Cu")
	)
	(gr_line
		(start 352.785172 -294.82288)
		(end 352.79076 -294.819832)
		(stroke
			(width 0.05715)
			(type default)
		)
		(layer "In15.Cu")
	)
	(gr_line
		(start 352.785172 -284.129226)
		(end 352.784156 -284.128718)
		(stroke
			(width 0.05715)
			(type default)
		)
		(layer "In15.Cu")
	)
	(gr_line
		(start 352.785172 -283.48305)
		(end 352.792792 -283.478732)
		(stroke
			(width 0.05715)
			(type default)
		)
		(layer "In15.Cu")
	)
	(gr_line
		(start 352.785172 -282.509214)
		(end 352.784156 -282.508706)
		(stroke
			(width 0.05715)
			(type default)
		)
		(layer "In15.Cu")
	)
	(gr_line
		(start 352.785172 -281.863038)
		(end 352.792792 -281.85872)
		(stroke
			(width 0.05715)
			(type default)
		)
		(layer "In15.Cu")
	)
	(gr_line
		(start 352.785172 -279.26919)
		(end 352.784156 -279.268682)
		(stroke
			(width 0.05715)
			(type default)
		)
		(layer "In15.Cu")
	)
	(gr_line
		(start 352.785172 -278.623014)
		(end 352.792792 -278.618696)
		(stroke
			(width 0.05715)
			(type default)
		)
		(layer "In15.Cu")
	)
	(gr_line
		(start 352.785172 -277.649178)
		(end 352.784156 -277.64867)
		(stroke
			(width 0.05715)
			(type default)
		)
		(layer "In15.Cu")
	)
	(gr_line
		(start 352.785172 -277.003002)
		(end 352.789744 -277.000208)
		(stroke
			(width 0.05715)
			(type default)
		)
		(layer "In15.Cu")
	)
	(gr_line
		(start 352.785172 -276.029166)
		(end 352.784156 -276.028658)
		(stroke
			(width 0.05715)
			(type default)
		)
		(layer "In15.Cu")
	)
	(gr_line
		(start 352.785172 -275.38299)
		(end 352.78695 -275.381974)
		(stroke
			(width 0.05715)
			(type default)
		)
		(layer "In15.Cu")
	)
	(gr_line
		(start 352.785172 -272.789142)
		(end 352.784156 -272.788634)
		(stroke
			(width 0.05715)
			(type default)
		)
		(layer "In15.Cu")
	)
	(gr_line
		(start 352.78695 -275.381974)
		(end 352.787966 -275.381466)
		(stroke
			(width 0.05715)
			(type default)
		)
		(layer "In15.Cu")
	)
	(gr_line
		(start 352.787204 -284.130242)
		(end 352.785172 -284.129226)
		(stroke
			(width 0.05715)
			(type default)
		)
		(layer "In15.Cu")
	)
	(gr_line
		(start 352.787204 -282.51023)
		(end 352.785172 -282.509214)
		(stroke
			(width 0.05715)
			(type default)
		)
		(layer "In15.Cu")
	)
	(gr_line
		(start 352.787204 -279.270206)
		(end 352.785172 -279.26919)
		(stroke
			(width 0.05715)
			(type default)
		)
		(layer "In15.Cu")
	)
	(gr_line
		(start 352.787204 -277.650194)
		(end 352.785172 -277.649178)
		(stroke
			(width 0.05715)
			(type default)
		)
		(layer "In15.Cu")
	)
	(gr_line
		(start 352.787204 -276.030182)
		(end 352.785172 -276.029166)
		(stroke
			(width 0.05715)
			(type default)
		)
		(layer "In15.Cu")
	)
	(gr_line
		(start 352.787204 -272.790158)
		(end 352.785172 -272.789142)
		(stroke
			(width 0.05715)
			(type default)
		)
		(layer "In15.Cu")
	)
	(gr_line
		(start 352.787966 -293.850568)
		(end 352.783648 -293.848282)
		(stroke
			(width 0.05715)
			(type default)
		)
		(layer "In15.Cu")
	)
	(gr_line
		(start 352.787966 -275.381466)
		(end 352.79076 -275.379942)
		(stroke
			(width 0.05715)
			(type default)
		)
		(layer "In15.Cu")
	)
	(gr_line
		(start 352.788728 -292.231064)
		(end 352.783648 -292.22827)
		(stroke
			(width 0.05715)
			(type default)
		)
		(layer "In15.Cu")
	)
	(gr_line
		(start 352.789236 -285.751524)
		(end 352.788474 -285.751016)
		(stroke
			(width 0.05715)
			(type default)
		)
		(layer "In15.Cu")
	)
	(gr_line
		(start 352.789236 -274.41144)
		(end 352.788474 -274.410932)
		(stroke
			(width 0.05715)
			(type default)
		)
		(layer "In15.Cu")
	)
	(gr_line
		(start 352.78949 -292.231572)
		(end 352.788728 -292.231064)
		(stroke
			(width 0.05715)
			(type default)
		)
		(layer "In15.Cu")
	)
	(gr_line
		(start 352.790506 -292.23208)
		(end 352.78949 -292.231572)
		(stroke
			(width 0.05715)
			(type default)
		)
		(layer "In15.Cu")
	)
	(gr_line
		(start 352.79076 -294.819832)
		(end 352.791776 -294.819324)
		(stroke
			(width 0.05715)
			(type default)
		)
		(layer "In15.Cu")
	)
	(gr_line
		(start 352.79076 -275.379942)
		(end 352.791776 -275.379434)
		(stroke
			(width 0.05715)
			(type default)
		)
		(layer "In15.Cu")
	)
	(gr_line
		(start 352.791522 -292.232588)
		(end 352.790506 -292.23208)
		(stroke
			(width 0.05715)
			(type default)
		)
		(layer "In15.Cu")
	)
	(gr_line
		(start 352.79203 -290.613084)
		(end 352.783648 -290.608258)
		(stroke
			(width 0.05715)
			(type default)
		)
		(layer "In15.Cu")
	)
	(gr_line
		(start 352.792792 -293.853616)
		(end 352.790506 -293.852092)
		(stroke
			(width 0.05715)
			(type default)
		)
		(layer "In15.Cu")
	)
	(gr_line
		(start 352.804984 -293.191184)
		(end 352.805238 -293.191184)
		(stroke
			(width 0.05715)
			(type default)
		)
		(layer "In15.Cu")
	)
	(gr_line
		(start 352.804984 -291.571172)
		(end 352.805238 -291.571172)
		(stroke
			(width 0.05715)
			(type default)
		)
		(layer "In15.Cu")
	)
	(gr_line
		(start 352.804984 -289.95116)
		(end 352.805238 -289.95116)
		(stroke
			(width 0.05715)
			(type default)
		)
		(layer "In15.Cu")
	)
	(gr_line
		(start 352.81362 -293.186358)
		(end 352.815144 -293.185342)
		(stroke
			(width 0.05715)
			(type default)
		)
		(layer "In15.Cu")
	)
	(gr_line
		(start 352.81362 -291.566346)
		(end 352.815144 -291.56533)
		(stroke
			(width 0.05715)
			(type default)
		)
		(layer "In15.Cu")
	)
	(gr_line
		(start 352.81362 -289.946334)
		(end 352.815144 -289.945318)
		(stroke
			(width 0.05715)
			(type default)
		)
		(layer "In15.Cu")
	)
	(gr_line
		(start 352.815652 -285.767018)
		(end 352.81489 -285.76651)
		(stroke
			(width 0.05715)
			(type default)
		)
		(layer "In15.Cu")
	)
	(gr_line
		(start 352.815652 -284.147006)
		(end 352.81489 -284.146498)
		(stroke
			(width 0.05715)
			(type default)
		)
		(layer "In15.Cu")
	)
	(gr_line
		(start 352.815652 -282.526994)
		(end 352.81489 -282.526486)
		(stroke
			(width 0.05715)
			(type default)
		)
		(layer "In15.Cu")
	)
	(gr_line
		(start 352.815652 -279.28697)
		(end 352.81489 -279.286462)
		(stroke
			(width 0.05715)
			(type default)
		)
		(layer "In15.Cu")
	)
	(gr_line
		(start 352.815652 -277.666958)
		(end 352.81489 -277.66645)
		(stroke
			(width 0.05715)
			(type default)
		)
		(layer "In15.Cu")
	)
	(gr_line
		(start 352.815652 -276.046946)
		(end 352.81489 -276.046438)
		(stroke
			(width 0.05715)
			(type default)
		)
		(layer "In15.Cu")
	)
	(gr_line
		(start 352.815652 -274.426934)
		(end 352.81489 -274.426426)
		(stroke
			(width 0.05715)
			(type default)
		)
		(layer "In15.Cu")
	)
	(gr_line
		(start 352.815652 -272.806922)
		(end 352.81489 -272.806414)
		(stroke
			(width 0.05715)
			(type default)
		)
		(layer "In15.Cu")
	)
	(gr_line
		(start 352.816414 -285.767526)
		(end 352.815652 -285.767018)
		(stroke
			(width 0.05715)
			(type default)
		)
		(layer "In15.Cu")
	)
	(gr_line
		(start 352.816414 -284.147514)
		(end 352.815652 -284.147006)
		(stroke
			(width 0.05715)
			(type default)
		)
		(layer "In15.Cu")
	)
	(gr_line
		(start 352.816414 -282.527502)
		(end 352.815652 -282.526994)
		(stroke
			(width 0.05715)
			(type default)
		)
		(layer "In15.Cu")
	)
	(gr_line
		(start 352.816414 -279.287478)
		(end 352.815652 -279.28697)
		(stroke
			(width 0.05715)
			(type default)
		)
		(layer "In15.Cu")
	)
	(gr_line
		(start 352.816414 -277.667466)
		(end 352.815652 -277.666958)
		(stroke
			(width 0.05715)
			(type default)
		)
		(layer "In15.Cu")
	)
	(gr_line
		(start 352.816414 -276.047454)
		(end 352.815652 -276.046946)
		(stroke
			(width 0.05715)
			(type default)
		)
		(layer "In15.Cu")
	)
	(gr_line
		(start 352.816414 -274.427442)
		(end 352.815652 -274.426934)
		(stroke
			(width 0.05715)
			(type default)
		)
		(layer "In15.Cu")
	)
	(gr_line
		(start 352.816414 -272.80743)
		(end 352.815652 -272.806922)
		(stroke
			(width 0.05715)
			(type default)
		)
		(layer "In15.Cu")
	)
	(gr_line
		(start 352.818954 -287.389062)
		(end 352.815144 -287.386776)
		(stroke
			(width 0.05715)
			(type default)
		)
		(layer "In15.Cu")
	)
	(gr_line
		(start 352.82251 -293.870888)
		(end 352.815398 -293.866824)
		(stroke
			(width 0.05715)
			(type default)
		)
		(layer "In15.Cu")
	)
	(gr_arc
		(start 352.82251 -293.870888)
		(mid 352.822891 -293.871142)
		(end 352.823272 -293.871396)
		(stroke
			(width 0.05715)
			(type default)
		)
		(layer "In15.Cu")
	)
	(gr_line
		(start 352.82251 -292.250876)
		(end 352.814382 -292.24605)
		(stroke
			(width 0.05715)
			(type default)
		)
		(layer "In15.Cu")
	)
	(gr_arc
		(start 352.82251 -292.250876)
		(mid 352.822891 -292.25113)
		(end 352.823272 -292.251384)
		(stroke
			(width 0.05715)
			(type default)
		)
		(layer "In15.Cu")
	)
	(gr_line
		(start 352.82251 -290.630864)
		(end 352.815652 -290.6268)
		(stroke
			(width 0.05715)
			(type default)
		)
		(layer "In15.Cu")
	)
	(gr_arc
		(start 352.82251 -290.630864)
		(mid 352.822891 -290.631118)
		(end 352.823272 -290.631372)
		(stroke
			(width 0.05715)
			(type default)
		)
		(layer "In15.Cu")
	)
	(gr_line
		(start 352.82251 -289.010852)
		(end 352.815398 -289.006788)
		(stroke
			(width 0.05715)
			(type default)
		)
		(layer "In15.Cu")
	)
	(gr_arc
		(start 352.82251 -289.010852)
		(mid 352.822891 -289.011106)
		(end 352.823272 -289.01136)
		(stroke
			(width 0.05715)
			(type default)
		)
		(layer "In15.Cu")
	)
	(gr_line
		(start 352.82251 -287.391094)
		(end 352.818954 -287.389062)
		(stroke
			(width 0.05715)
			(type default)
		)
		(layer "In15.Cu")
	)
	(gr_line
		(start 352.82251 -287.39084)
		(end 352.82251 -287.391094)
		(stroke
			(width 0.05715)
			(type default)
		)
		(layer "In15.Cu")
	)
	(gr_line
		(start 352.823272 -285.77159)
		(end 352.816414 -285.767526)
		(stroke
			(width 0.05715)
			(type default)
		)
		(layer "In15.Cu")
	)
	(gr_line
		(start 352.823272 -284.151578)
		(end 352.816414 -284.147514)
		(stroke
			(width 0.05715)
			(type default)
		)
		(layer "In15.Cu")
	)
	(gr_line
		(start 352.823272 -282.531566)
		(end 352.816414 -282.527502)
		(stroke
			(width 0.05715)
			(type default)
		)
		(layer "In15.Cu")
	)
	(gr_line
		(start 352.823272 -279.291542)
		(end 352.816414 -279.287478)
		(stroke
			(width 0.05715)
			(type default)
		)
		(layer "In15.Cu")
	)
	(gr_line
		(start 352.823272 -277.67153)
		(end 352.816414 -277.667466)
		(stroke
			(width 0.05715)
			(type default)
		)
		(layer "In15.Cu")
	)
	(gr_line
		(start 352.823272 -276.051518)
		(end 352.816414 -276.047454)
		(stroke
			(width 0.05715)
			(type default)
		)
		(layer "In15.Cu")
	)
	(gr_line
		(start 352.823272 -274.431506)
		(end 352.816414 -274.427442)
		(stroke
			(width 0.05715)
			(type default)
		)
		(layer "In15.Cu")
	)
	(gr_line
		(start 352.823272 -272.811494)
		(end 352.816414 -272.80743)
		(stroke
			(width 0.05715)
			(type default)
		)
		(layer "In15.Cu")
	)
	(gr_arc
		(start 352.831146 -293.876984)
		(mid 352.827221 -293.874173)
		(end 352.823272 -293.871396)
		(stroke
			(width 0.05715)
			(type default)
		)
		(layer "In15.Cu")
	)
	(gr_arc
		(start 352.831146 -292.256972)
		(mid 352.827221 -292.254161)
		(end 352.823272 -292.251384)
		(stroke
			(width 0.05715)
			(type default)
		)
		(layer "In15.Cu")
	)
	(gr_arc
		(start 352.831146 -290.63696)
		(mid 352.827221 -290.634149)
		(end 352.823272 -290.631372)
		(stroke
			(width 0.05715)
			(type default)
		)
		(layer "In15.Cu")
	)
	(gr_arc
		(start 352.831146 -289.016948)
		(mid 352.827221 -289.014137)
		(end 352.823272 -289.01136)
		(stroke
			(width 0.05715)
			(type default)
		)
		(layer "In15.Cu")
	)
	(gr_arc
		(start 352.831146 -285.777178)
		(mid 352.827221 -285.774367)
		(end 352.823272 -285.77159)
		(stroke
			(width 0.05715)
			(type default)
		)
		(layer "In15.Cu")
	)
	(gr_arc
		(start 352.831146 -284.157166)
		(mid 352.827221 -284.154355)
		(end 352.823272 -284.151578)
		(stroke
			(width 0.05715)
			(type default)
		)
		(layer "In15.Cu")
	)
	(gr_arc
		(start 352.831146 -282.537154)
		(mid 352.827221 -282.534343)
		(end 352.823272 -282.531566)
		(stroke
			(width 0.05715)
			(type default)
		)
		(layer "In15.Cu")
	)
	(gr_arc
		(start 352.831146 -279.29713)
		(mid 352.827221 -279.294319)
		(end 352.823272 -279.291542)
		(stroke
			(width 0.05715)
			(type default)
		)
		(layer "In15.Cu")
	)
	(gr_arc
		(start 352.831146 -277.677118)
		(mid 352.827221 -277.674307)
		(end 352.823272 -277.67153)
		(stroke
			(width 0.05715)
			(type default)
		)
		(layer "In15.Cu")
	)
	(gr_arc
		(start 352.831146 -276.057106)
		(mid 352.827221 -276.054295)
		(end 352.823272 -276.051518)
		(stroke
			(width 0.05715)
			(type default)
		)
		(layer "In15.Cu")
	)
	(gr_arc
		(start 352.831146 -274.437094)
		(mid 352.827221 -274.434283)
		(end 352.823272 -274.431506)
		(stroke
			(width 0.05715)
			(type default)
		)
		(layer "In15.Cu")
	)
	(gr_arc
		(start 352.831146 -272.817082)
		(mid 352.827221 -272.814271)
		(end 352.823272 -272.811494)
		(stroke
			(width 0.05715)
			(type default)
		)
		(layer "In15.Cu")
	)
	(gr_arc
		(start 352.8314 -287.396936)
		(mid 352.82697 -287.393866)
		(end 352.82251 -287.39084)
		(stroke
			(width 0.05715)
			(type default)
		)
		(layer "In15.Cu")
	)
	(gr_arc
		(start 352.911918 -304.341022)
		(mid 352.911918 -304.340768)
		(end 352.911918 -304.340514)
		(stroke
			(width 0.07112)
			(type default)
		)
		(layer "In15.Cu")
	)
	(gr_line
		(start 352.911918 -296.374566)
		(end 352.911918 -296.346118)
		(stroke
			(width 0.05715)
			(type default)
		)
		(layer "In15.Cu")
	)
	(gr_line
		(start 352.911918 -296.346118)
		(end 352.957638 -296.300398)
		(stroke
			(width 0.05715)
			(type default)
		)
		(layer "In15.Cu")
	)
	(gr_line
		(start 353.193858 -296.374566)
		(end 353.193858 -296.346118)
		(stroke
			(width 0.05715)
			(type default)
		)
		(layer "In15.Cu")
	)
	(gr_line
		(start 353.193858 -296.346118)
		(end 353.148138 -296.300398)
		(stroke
			(width 0.05715)
			(type default)
		)
		(layer "In15.Cu")
	)
	(gr_line
		(start 353.53625 -295.239694)
		(end 353.536504 -295.23944)
		(stroke
			(width 0.05715)
			(type default)
		)
		(layer "In15.Cu")
	)
	(gr_arc
		(start 353.589082 -286.581342)
		(mid 353.584365 -286.584619)
		(end 353.579684 -286.587946)
		(stroke
			(width 0.05715)
			(type default)
		)
		(layer "In15.Cu")
	)
	(gr_line
		(start 353.589082 -286.581342)
		(end 353.591114 -286.579818)
		(stroke
			(width 0.05715)
			(type default)
		)
		(layer "In15.Cu")
	)
	(gr_line
		(start 353.591114 -286.579818)
		(end 353.59594 -286.577024)
		(stroke
			(width 0.05715)
			(type default)
		)
		(layer "In15.Cu")
	)
	(gr_line
		(start 353.723448 -286.723836)
		(end 353.723956 -286.723582)
		(stroke
			(width 0.05715)
			(type default)
		)
		(layer "In15.Cu")
	)
	(gr_line
		(start 353.857052 -296.374566)
		(end 353.857052 -296.346118)
		(stroke
			(width 0.05715)
			(type default)
		)
		(layer "In15.Cu")
	)
	(gr_line
		(start 353.857052 -296.346118)
		(end 353.902772 -296.300398)
		(stroke
			(width 0.05715)
			(type default)
		)
		(layer "In15.Cu")
	)
	(gr_line
		(start 354.138992 -296.374566)
		(end 354.138992 -296.346118)
		(stroke
			(width 0.05715)
			(type default)
		)
		(layer "In15.Cu")
	)
	(gr_line
		(start 354.138992 -296.346118)
		(end 354.093272 -296.300398)
		(stroke
			(width 0.05715)
			(type default)
		)
		(layer "In15.Cu")
	)
	(gr_line
		(start 354.16236 -272.971768)
		(end 354.162614 -272.972022)
		(stroke
			(width 0.05715)
			(type default)
		)
		(layer "In15.Cu")
	)
	(gr_line
		(start 354.285804 -295.192958)
		(end 354.285804 -295.191942)
		(stroke
			(width 0.05715)
			(type default)
		)
		(layer "In15.Cu")
	)
	(gr_arc
		(start 354.529136 -286.581342)
		(mid 354.52442 -286.584619)
		(end 354.519738 -286.587946)
		(stroke
			(width 0.05715)
			(type default)
		)
		(layer "In15.Cu")
	)
	(gr_line
		(start 354.529136 -286.581342)
		(end 354.531168 -286.579818)
		(stroke
			(width 0.05715)
			(type default)
		)
		(layer "In15.Cu")
	)
	(gr_line
		(start 354.531168 -286.579818)
		(end 354.535994 -286.577024)
		(stroke
			(width 0.05715)
			(type default)
		)
		(layer "In15.Cu")
	)
	(gr_line
		(start 354.663502 -286.723836)
		(end 354.66401 -286.723582)
		(stroke
			(width 0.05715)
			(type default)
		)
		(layer "In15.Cu")
	)
	(gr_line
		(start 354.678996 -273.27606)
		(end 354.381054 -273.27606)
		(stroke
			(width 0.05715)
			(type default)
		)
		(layer "In15.Cu")
	)
	(gr_line
		(start 354.678996 -271.656048)
		(end 354.381054 -271.656048)
		(stroke
			(width 0.05715)
			(type default)
		)
		(layer "In15.Cu")
	)
	(gr_line
		(start 354.678996 -270.036036)
		(end 354.381054 -270.036036)
		(stroke
			(width 0.05715)
			(type default)
		)
		(layer "In15.Cu")
	)
	(gr_line
		(start 354.748338 -273.345402)
		(end 354.678996 -273.27606)
		(stroke
			(width 0.05715)
			(type default)
		)
		(layer "In15.Cu")
	)
	(gr_line
		(start 354.748338 -271.72539)
		(end 354.678996 -271.656048)
		(stroke
			(width 0.05715)
			(type default)
		)
		(layer "In15.Cu")
	)
	(gr_line
		(start 354.7618 -270.11884)
		(end 354.678996 -270.036036)
		(stroke
			(width 0.05715)
			(type default)
		)
		(layer "In15.Cu")
	)
	(gr_arc
		(start 354.7618 -270.11884)
		(mid 354.763591 -270.130162)
		(end 354.76561 -270.141446)
		(stroke
			(width 0.05715)
			(type default)
		)
		(layer "In15.Cu")
	)
	(gr_arc
		(start 354.936552 -273.381724)
		(mid 354.938574 -273.370313)
		(end 354.940362 -273.358864)
		(stroke
			(width 0.05715)
			(type default)
		)
		(layer "In15.Cu")
	)
	(gr_arc
		(start 354.936552 -271.761712)
		(mid 354.938573 -271.750301)
		(end 354.940362 -271.738852)
		(stroke
			(width 0.05715)
			(type default)
		)
		(layer "In15.Cu")
	)
	(gr_line
		(start 354.940362 -273.358864)
		(end 355.023166 -273.27606)
		(stroke
			(width 0.05715)
			(type default)
		)
		(layer "In15.Cu")
	)
	(gr_line
		(start 354.940362 -271.738852)
		(end 355.023166 -271.656048)
		(stroke
			(width 0.05715)
			(type default)
		)
		(layer "In15.Cu")
	)
	(gr_line
		(start 354.953824 -270.105378)
		(end 355.023166 -270.036036)
		(stroke
			(width 0.05715)
			(type default)
		)
		(layer "In15.Cu")
	)
	(gr_line
		(start 354.954332 -296.61231)
		(end 354.954332 -296.583862)
		(stroke
			(width 0.05715)
			(type default)
		)
		(layer "In15.Cu")
	)
	(gr_line
		(start 354.954332 -296.583862)
		(end 355.000052 -296.538142)
		(stroke
			(width 0.05715)
			(type default)
		)
		(layer "In15.Cu")
	)
	(gr_arc
		(start 354.990908 -270.495014)
		(mid 354.99496 -270.497826)
		(end 354.999036 -270.500602)
		(stroke
			(width 0.05715)
			(type default)
		)
		(layer "In15.Cu")
	)
	(gr_line
		(start 355.00183 -270.502634)
		(end 354.999036 -270.500602)
		(stroke
			(width 0.05715)
			(type default)
		)
		(layer "In15.Cu")
	)
	(gr_line
		(start 355.007164 -270.505682)
		(end 355.00183 -270.502634)
		(stroke
			(width 0.05715)
			(type default)
		)
		(layer "In15.Cu")
	)
	(gr_line
		(start 355.023166 -273.27606)
		(end 355.321108 -273.27606)
		(stroke
			(width 0.05715)
			(type default)
		)
		(layer "In15.Cu")
	)
	(gr_line
		(start 355.023166 -271.656048)
		(end 355.321108 -271.656048)
		(stroke
			(width 0.05715)
			(type default)
		)
		(layer "In15.Cu")
	)
	(gr_line
		(start 355.023166 -270.036036)
		(end 355.321108 -270.036036)
		(stroke
			(width 0.05715)
			(type default)
		)
		(layer "In15.Cu")
	)
	(gr_line
		(start 355.039422 -270.524224)
		(end 355.038914 -270.52397)
		(stroke
			(width 0.05715)
			(type default)
		)
		(layer "In15.Cu")
	)
	(gr_line
		(start 355.156262 -270.371316)
		(end 355.1555 -270.370808)
		(stroke
			(width 0.05715)
			(type default)
		)
		(layer "In15.Cu")
	)
	(gr_line
		(start 355.225604 -270.867632)
		(end 355.225604 -270.86433)
		(stroke
			(width 0.05715)
			(type default)
		)
		(layer "In15.Cu")
	)
	(gr_line
		(start 355.236272 -296.61231)
		(end 355.236272 -296.583862)
		(stroke
			(width 0.05715)
			(type default)
		)
		(layer "In15.Cu")
	)
	(gr_line
		(start 355.236272 -296.583862)
		(end 355.190552 -296.538142)
		(stroke
			(width 0.05715)
			(type default)
		)
		(layer "In15.Cu")
	)
	(gr_line
		(start 355.41204 -270.808704)
		(end 355.412294 -270.80972)
		(stroke
			(width 0.05715)
			(type default)
		)
		(layer "In15.Cu")
	)
	(gr_line
		(start 355.41204 -270.807942)
		(end 355.41204 -270.808704)
		(stroke
			(width 0.05715)
			(type default)
		)
		(layer "In15.Cu")
	)
	(gr_arc
		(start 355.45649 -293.981632)
		(mid 355.464066 -293.987029)
		(end 355.47173 -293.9923)
		(stroke
			(width 0.05715)
			(type default)
		)
		(layer "In15.Cu")
	)
	(gr_arc
		(start 355.461062 -271.30502)
		(mid 355.466374 -271.308735)
		(end 355.47173 -271.312386)
		(stroke
			(width 0.05715)
			(type default)
		)
		(layer "In15.Cu")
	)
	(gr_arc
		(start 355.47173 -273.619722)
		(mid 355.464066 -273.624994)
		(end 355.45649 -273.63039)
		(stroke
			(width 0.05715)
			(type default)
		)
		(layer "In15.Cu")
	)
	(gr_line
		(start 355.47173 -273.619722)
		(end 355.473254 -273.618706)
		(stroke
			(width 0.05715)
			(type default)
		)
		(layer "In15.Cu")
	)
	(gr_line
		(start 355.473254 -293.993316)
		(end 355.47173 -293.9923)
		(stroke
			(width 0.05715)
			(type default)
		)
		(layer "In15.Cu")
	)
	(gr_line
		(start 355.473254 -273.618706)
		(end 355.477318 -273.61642)
		(stroke
			(width 0.05715)
			(type default)
		)
		(layer "In15.Cu")
	)
	(gr_line
		(start 355.477318 -293.995602)
		(end 355.473254 -293.993316)
		(stroke
			(width 0.05715)
			(type default)
		)
		(layer "In15.Cu")
	)
	(gr_line
		(start 355.477318 -271.315688)
		(end 355.47173 -271.312386)
		(stroke
			(width 0.05715)
			(type default)
		)
		(layer "In15.Cu")
	)
	(gr_line
		(start 355.493066 -294.667178)
		(end 355.496622 -294.665146)
		(stroke
			(width 0.05715)
			(type default)
		)
		(layer "In15.Cu")
	)
	(gr_line
		(start 355.495098 -288.186114)
		(end 355.49713 -288.184844)
		(stroke
			(width 0.05715)
			(type default)
		)
		(layer "In15.Cu")
	)
	(gr_line
		(start 355.495606 -289.14598)
		(end 355.495098 -289.145726)
		(stroke
			(width 0.05715)
			(type default)
		)
		(layer "In15.Cu")
	)
	(gr_arc
		(start 355.496622 -292.386766)
		(mid 355.499032 -292.388169)
		(end 355.501448 -292.38956)
		(stroke
			(width 0.05715)
			(type default)
		)
		(layer "In15.Cu")
	)
	(gr_arc
		(start 355.496622 -290.766754)
		(mid 355.499032 -290.768157)
		(end 355.501448 -290.769548)
		(stroke
			(width 0.05715)
			(type default)
		)
		(layer "In15.Cu")
	)
	(gr_line
		(start 355.499162 -287.527746)
		(end 355.491796 -287.52292)
		(stroke
			(width 0.05715)
			(type default)
		)
		(layer "In15.Cu")
	)
	(gr_line
		(start 355.507798 -291.418772)
		(end 355.508052 -291.418518)
		(stroke
			(width 0.05715)
			(type default)
		)
		(layer "In15.Cu")
	)
	(gr_line
		(start 355.507798 -289.79876)
		(end 355.508052 -289.798506)
		(stroke
			(width 0.05715)
			(type default)
		)
		(layer "In15.Cu")
	)
	(gr_line
		(start 355.508052 -292.39337)
		(end 355.507798 -292.39337)
		(stroke
			(width 0.05715)
			(type default)
		)
		(layer "In15.Cu")
	)
	(gr_line
		(start 355.508052 -290.773358)
		(end 355.507798 -290.773358)
		(stroke
			(width 0.05715)
			(type default)
		)
		(layer "In15.Cu")
	)
	(gr_line
		(start 355.508052 -284.938724)
		(end 355.50856 -284.93847)
		(stroke
			(width 0.05715)
			(type default)
		)
		(layer "In15.Cu")
	)
	(gr_line
		(start 355.508052 -281.05354)
		(end 355.508052 -281.053286)
		(stroke
			(width 0.05715)
			(type default)
		)
		(layer "In15.Cu")
	)
	(gr_line
		(start 355.508306 -275.218652)
		(end 355.509576 -275.21789)
		(stroke
			(width 0.05715)
			(type default)
		)
		(layer "In15.Cu")
	)
	(gr_line
		(start 355.508306 -273.598386)
		(end 355.508814 -273.598132)
		(stroke
			(width 0.05715)
			(type default)
		)
		(layer "In15.Cu")
	)
	(gr_line
		(start 355.508306 -271.978374)
		(end 355.508814 -271.97812)
		(stroke
			(width 0.05715)
			(type default)
		)
		(layer "In15.Cu")
	)
	(gr_line
		(start 355.50856 -281.053794)
		(end 355.508052 -281.05354)
		(stroke
			(width 0.05715)
			(type default)
		)
		(layer "In15.Cu")
	)
	(gr_line
		(start 355.508814 -294.01389)
		(end 355.508052 -294.013382)
		(stroke
			(width 0.05715)
			(type default)
		)
		(layer "In15.Cu")
	)
	(gr_line
		(start 355.508814 -285.914084)
		(end 355.508052 -285.913576)
		(stroke
			(width 0.05715)
			(type default)
		)
		(layer "In15.Cu")
	)
	(gr_line
		(start 355.508814 -284.294072)
		(end 355.508052 -284.293564)
		(stroke
			(width 0.05715)
			(type default)
		)
		(layer "In15.Cu")
	)
	(gr_line
		(start 355.508814 -282.67406)
		(end 355.508052 -282.673552)
		(stroke
			(width 0.05715)
			(type default)
		)
		(layer "In15.Cu")
	)
	(gr_line
		(start 355.508814 -279.434036)
		(end 355.508052 -279.433528)
		(stroke
			(width 0.05715)
			(type default)
		)
		(layer "In15.Cu")
	)
	(gr_line
		(start 355.508814 -277.814024)
		(end 355.508052 -277.813516)
		(stroke
			(width 0.05715)
			(type default)
		)
		(layer "In15.Cu")
	)
	(gr_line
		(start 355.508814 -276.194012)
		(end 355.508052 -276.193504)
		(stroke
			(width 0.05715)
			(type default)
		)
		(layer "In15.Cu")
	)
	(gr_line
		(start 355.508814 -274.574)
		(end 355.508052 -274.573492)
		(stroke
			(width 0.05715)
			(type default)
		)
		(layer "In15.Cu")
	)
	(gr_line
		(start 355.508814 -273.598132)
		(end 355.510084 -273.59737)
		(stroke
			(width 0.05715)
			(type default)
		)
		(layer "In15.Cu")
	)
	(gr_line
		(start 355.508814 -271.97812)
		(end 355.510084 -271.977358)
		(stroke
			(width 0.05715)
			(type default)
		)
		(layer "In15.Cu")
	)
	(gr_line
		(start 355.509576 -275.21789)
		(end 355.510338 -275.217382)
		(stroke
			(width 0.05715)
			(type default)
		)
		(layer "In15.Cu")
	)
	(gr_line
		(start 355.510084 -285.914846)
		(end 355.508814 -285.914084)
		(stroke
			(width 0.05715)
			(type default)
		)
		(layer "In15.Cu")
	)
	(gr_line
		(start 355.510084 -284.294834)
		(end 355.508814 -284.294072)
		(stroke
			(width 0.05715)
			(type default)
		)
		(layer "In15.Cu")
	)
	(gr_line
		(start 355.510084 -282.674822)
		(end 355.508814 -282.67406)
		(stroke
			(width 0.05715)
			(type default)
		)
		(layer "In15.Cu")
	)
	(gr_line
		(start 355.510084 -279.434798)
		(end 355.508814 -279.434036)
		(stroke
			(width 0.05715)
			(type default)
		)
		(layer "In15.Cu")
	)
	(gr_line
		(start 355.510084 -277.814786)
		(end 355.508814 -277.814024)
		(stroke
			(width 0.05715)
			(type default)
		)
		(layer "In15.Cu")
	)
	(gr_line
		(start 355.510084 -276.194774)
		(end 355.508814 -276.194012)
		(stroke
			(width 0.05715)
			(type default)
		)
		(layer "In15.Cu")
	)
	(gr_line
		(start 355.510084 -274.574762)
		(end 355.508814 -274.574)
		(stroke
			(width 0.05715)
			(type default)
		)
		(layer "In15.Cu")
	)
	(gr_line
		(start 355.510338 -276.837394)
		(end 355.511354 -276.836886)
		(stroke
			(width 0.05715)
			(type default)
		)
		(layer "In15.Cu")
	)
	(gr_line
		(start 355.511354 -276.836886)
		(end 355.512116 -276.836378)
		(stroke
			(width 0.05715)
			(type default)
		)
		(layer "In15.Cu")
	)
	(gr_line
		(start 355.512116 -276.836378)
		(end 355.513132 -276.83587)
		(stroke
			(width 0.05715)
			(type default)
		)
		(layer "In15.Cu")
	)
	(gr_line
		(start 355.512116 -275.216366)
		(end 355.514656 -275.215096)
		(stroke
			(width 0.05715)
			(type default)
		)
		(layer "In15.Cu")
	)
	(gr_line
		(start 355.513132 -276.83587)
		(end 355.513894 -276.835362)
		(stroke
			(width 0.05715)
			(type default)
		)
		(layer "In15.Cu")
	)
	(gr_line
		(start 355.514656 -275.215096)
		(end 355.515418 -275.214588)
		(stroke
			(width 0.05715)
			(type default)
		)
		(layer "In15.Cu")
	)
	(gr_line
		(start 355.515418 -275.214588)
		(end 355.516434 -275.21408)
		(stroke
			(width 0.05715)
			(type default)
		)
		(layer "In15.Cu")
	)
	(gr_line
		(start 355.516688 -292.39845)
		(end 355.514148 -292.396926)
		(stroke
			(width 0.05715)
			(type default)
		)
		(layer "In15.Cu")
	)
	(gr_line
		(start 355.516942 -290.778438)
		(end 355.515672 -290.777676)
		(stroke
			(width 0.05715)
			(type default)
		)
		(layer "In15.Cu")
	)
	(gr_line
		(start 355.517196 -292.398704)
		(end 355.516688 -292.39845)
		(stroke
			(width 0.05715)
			(type default)
		)
		(layer "In15.Cu")
	)
	(gr_line
		(start 355.603302 -284.12821)
		(end 355.600508 -284.126686)
		(stroke
			(width 0.05715)
			(type default)
		)
		(layer "In15.Cu")
	)
	(gr_line
		(start 355.603302 -282.508198)
		(end 355.600508 -282.506674)
		(stroke
			(width 0.05715)
			(type default)
		)
		(layer "In15.Cu")
	)
	(gr_line
		(start 355.603302 -280.888186)
		(end 355.60254 -280.887678)
		(stroke
			(width 0.05715)
			(type default)
		)
		(layer "In15.Cu")
	)
	(gr_line
		(start 355.603302 -279.268174)
		(end 355.600508 -279.26665)
		(stroke
			(width 0.05715)
			(type default)
		)
		(layer "In15.Cu")
	)
	(gr_line
		(start 355.603302 -277.648162)
		(end 355.600508 -277.646638)
		(stroke
			(width 0.05715)
			(type default)
		)
		(layer "In15.Cu")
	)
	(gr_line
		(start 355.603302 -276.02815)
		(end 355.600508 -276.026626)
		(stroke
			(width 0.05715)
			(type default)
		)
		(layer "In15.Cu")
	)
	(gr_line
		(start 355.603302 -273.763994)
		(end 355.604064 -273.763486)
		(stroke
			(width 0.05715)
			(type default)
		)
		(layer "In15.Cu")
	)
	(gr_line
		(start 355.604064 -293.848536)
		(end 355.603302 -293.848028)
		(stroke
			(width 0.05715)
			(type default)
		)
		(layer "In15.Cu")
	)
	(gr_line
		(start 355.604064 -284.128718)
		(end 355.603302 -284.12821)
		(stroke
			(width 0.05715)
			(type default)
		)
		(layer "In15.Cu")
	)
	(gr_line
		(start 355.604064 -282.508706)
		(end 355.603302 -282.508198)
		(stroke
			(width 0.05715)
			(type default)
		)
		(layer "In15.Cu")
	)
	(gr_line
		(start 355.604064 -279.268682)
		(end 355.603302 -279.268174)
		(stroke
			(width 0.05715)
			(type default)
		)
		(layer "In15.Cu")
	)
	(gr_line
		(start 355.604064 -277.64867)
		(end 355.603302 -277.648162)
		(stroke
			(width 0.05715)
			(type default)
		)
		(layer "In15.Cu")
	)
	(gr_line
		(start 355.604064 -276.028658)
		(end 355.603302 -276.02815)
		(stroke
			(width 0.05715)
			(type default)
		)
		(layer "In15.Cu")
	)
	(gr_line
		(start 355.604064 -273.763486)
		(end 355.60508 -273.762978)
		(stroke
			(width 0.05715)
			(type default)
		)
		(layer "In15.Cu")
	)
	(gr_line
		(start 355.604064 -272.143474)
		(end 355.60508 -272.142966)
		(stroke
			(width 0.05715)
			(type default)
		)
		(layer "In15.Cu")
	)
	(gr_line
		(start 355.60508 -293.849044)
		(end 355.604064 -293.848536)
		(stroke
			(width 0.05715)
			(type default)
		)
		(layer "In15.Cu")
	)
	(gr_line
		(start 355.60508 -285.749238)
		(end 355.604064 -285.74873)
		(stroke
			(width 0.05715)
			(type default)
		)
		(layer "In15.Cu")
	)
	(gr_line
		(start 355.60508 -284.129226)
		(end 355.604064 -284.128718)
		(stroke
			(width 0.05715)
			(type default)
		)
		(layer "In15.Cu")
	)
	(gr_line
		(start 355.60508 -283.48305)
		(end 355.6127 -283.478732)
		(stroke
			(width 0.05715)
			(type default)
		)
		(layer "In15.Cu")
	)
	(gr_line
		(start 355.60508 -282.509214)
		(end 355.604064 -282.508706)
		(stroke
			(width 0.05715)
			(type default)
		)
		(layer "In15.Cu")
	)
	(gr_line
		(start 355.60508 -281.863038)
		(end 355.6127 -281.85872)
		(stroke
			(width 0.05715)
			(type default)
		)
		(layer "In15.Cu")
	)
	(gr_line
		(start 355.60508 -279.26919)
		(end 355.604064 -279.268682)
		(stroke
			(width 0.05715)
			(type default)
		)
		(layer "In15.Cu")
	)
	(gr_line
		(start 355.60508 -278.623014)
		(end 355.6127 -278.618696)
		(stroke
			(width 0.05715)
			(type default)
		)
		(layer "In15.Cu")
	)
	(gr_line
		(start 355.60508 -277.649178)
		(end 355.604064 -277.64867)
		(stroke
			(width 0.05715)
			(type default)
		)
		(layer "In15.Cu")
	)
	(gr_line
		(start 355.60508 -277.003002)
		(end 355.609652 -277.000208)
		(stroke
			(width 0.05715)
			(type default)
		)
		(layer "In15.Cu")
	)
	(gr_line
		(start 355.60508 -276.029166)
		(end 355.604064 -276.028658)
		(stroke
			(width 0.05715)
			(type default)
		)
		(layer "In15.Cu")
	)
	(gr_line
		(start 355.60508 -275.38299)
		(end 355.606858 -275.381974)
		(stroke
			(width 0.05715)
			(type default)
		)
		(layer "In15.Cu")
	)
	(gr_line
		(start 355.60508 -274.409154)
		(end 355.604064 -274.408646)
		(stroke
			(width 0.05715)
			(type default)
		)
		(layer "In15.Cu")
	)
	(gr_line
		(start 355.606858 -275.381974)
		(end 355.607874 -275.381466)
		(stroke
			(width 0.05715)
			(type default)
		)
		(layer "In15.Cu")
	)
	(gr_line
		(start 355.607112 -293.85006)
		(end 355.60508 -293.849044)
		(stroke
			(width 0.05715)
			(type default)
		)
		(layer "In15.Cu")
	)
	(gr_line
		(start 355.607874 -290.610544)
		(end 355.603556 -290.608258)
		(stroke
			(width 0.05715)
			(type default)
		)
		(layer "In15.Cu")
	)
	(gr_line
		(start 355.607874 -275.381466)
		(end 355.610668 -275.379942)
		(stroke
			(width 0.05715)
			(type default)
		)
		(layer "In15.Cu")
	)
	(gr_line
		(start 355.608636 -292.231064)
		(end 355.604572 -292.228778)
		(stroke
			(width 0.05715)
			(type default)
		)
		(layer "In15.Cu")
	)
	(gr_line
		(start 355.609398 -292.231572)
		(end 355.608636 -292.231064)
		(stroke
			(width 0.05715)
			(type default)
		)
		(layer "In15.Cu")
	)
	(gr_line
		(start 355.609652 -293.851584)
		(end 355.608382 -293.850822)
		(stroke
			(width 0.05715)
			(type default)
		)
		(layer "In15.Cu")
	)
	(gr_line
		(start 355.610668 -275.379942)
		(end 355.611684 -275.379434)
		(stroke
			(width 0.05715)
			(type default)
		)
		(layer "In15.Cu")
	)
	(gr_line
		(start 355.612192 -292.23335)
		(end 355.609398 -292.231572)
		(stroke
			(width 0.05715)
			(type default)
		)
		(layer "In15.Cu")
	)
	(gr_line
		(start 355.6127 -290.613592)
		(end 355.610414 -290.612068)
		(stroke
			(width 0.05715)
			(type default)
		)
		(layer "In15.Cu")
	)
	(gr_line
		(start 355.624892 -291.571172)
		(end 355.625146 -291.571172)
		(stroke
			(width 0.05715)
			(type default)
		)
		(layer "In15.Cu")
	)
	(gr_line
		(start 355.624892 -289.95116)
		(end 355.625146 -289.95116)
		(stroke
			(width 0.05715)
			(type default)
		)
		(layer "In15.Cu")
	)
	(gr_line
		(start 355.633528 -291.566346)
		(end 355.635052 -291.56533)
		(stroke
			(width 0.05715)
			(type default)
		)
		(layer "In15.Cu")
	)
	(gr_line
		(start 355.633528 -289.946334)
		(end 355.635052 -289.945318)
		(stroke
			(width 0.05715)
			(type default)
		)
		(layer "In15.Cu")
	)
	(gr_line
		(start 355.635052 -293.185596)
		(end 355.640386 -293.182548)
		(stroke
			(width 0.05715)
			(type default)
		)
		(layer "In15.Cu")
	)
	(gr_line
		(start 355.63556 -293.866824)
		(end 355.63429 -293.866062)
		(stroke
			(width 0.05715)
			(type default)
		)
		(layer "In15.Cu")
	)
	(gr_line
		(start 355.63556 -272.806922)
		(end 355.634798 -272.806414)
		(stroke
			(width 0.05715)
			(type default)
		)
		(layer "In15.Cu")
	)
	(gr_line
		(start 355.63556 -271.18691)
		(end 355.634798 -271.186402)
		(stroke
			(width 0.05715)
			(type default)
		)
		(layer "In15.Cu")
	)
	(gr_line
		(start 355.636068 -292.247066)
		(end 355.63429 -292.24605)
		(stroke
			(width 0.05715)
			(type default)
		)
		(layer "In15.Cu")
	)
	(gr_line
		(start 355.636322 -293.867332)
		(end 355.63556 -293.866824)
		(stroke
			(width 0.05715)
			(type default)
		)
		(layer "In15.Cu")
	)
	(gr_line
		(start 355.636322 -272.80743)
		(end 355.63556 -272.806922)
		(stroke
			(width 0.05715)
			(type default)
		)
		(layer "In15.Cu")
	)
	(gr_line
		(start 355.636322 -271.187418)
		(end 355.63556 -271.18691)
		(stroke
			(width 0.05715)
			(type default)
		)
		(layer "In15.Cu")
	)
	(gr_line
		(start 355.638862 -287.389062)
		(end 355.635052 -287.386776)
		(stroke
			(width 0.05715)
			(type default)
		)
		(layer "In15.Cu")
	)
	(gr_line
		(start 355.640386 -293.182548)
		(end 355.64318 -293.180516)
		(stroke
			(width 0.05715)
			(type default)
		)
		(layer "In15.Cu")
	)
	(gr_line
		(start 355.642418 -292.250876)
		(end 355.636068 -292.247066)
		(stroke
			(width 0.05715)
			(type default)
		)
		(layer "In15.Cu")
	)
	(gr_arc
		(start 355.642418 -292.250876)
		(mid 355.642799 -292.25113)
		(end 355.64318 -292.251384)
		(stroke
			(width 0.05715)
			(type default)
		)
		(layer "In15.Cu")
	)
	(gr_line
		(start 355.642418 -290.630864)
		(end 355.635306 -290.6268)
		(stroke
			(width 0.05715)
			(type default)
		)
		(layer "In15.Cu")
	)
	(gr_arc
		(start 355.642418 -290.630864)
		(mid 355.642799 -290.631118)
		(end 355.64318 -290.631372)
		(stroke
			(width 0.05715)
			(type default)
		)
		(layer "In15.Cu")
	)
	(gr_line
		(start 355.642418 -289.010852)
		(end 355.635306 -289.006788)
		(stroke
			(width 0.05715)
			(type default)
		)
		(layer "In15.Cu")
	)
	(gr_arc
		(start 355.642418 -289.010852)
		(mid 355.642799 -289.011106)
		(end 355.64318 -289.01136)
		(stroke
			(width 0.05715)
			(type default)
		)
		(layer "In15.Cu")
	)
	(gr_line
		(start 355.642418 -287.391094)
		(end 355.638862 -287.389062)
		(stroke
			(width 0.05715)
			(type default)
		)
		(layer "In15.Cu")
	)
	(gr_line
		(start 355.642418 -287.39084)
		(end 355.642418 -287.391094)
		(stroke
			(width 0.05715)
			(type default)
		)
		(layer "In15.Cu")
	)
	(gr_line
		(start 355.64318 -293.871396)
		(end 355.636322 -293.867332)
		(stroke
			(width 0.05715)
			(type default)
		)
		(layer "In15.Cu")
	)
	(gr_arc
		(start 355.64318 -293.180516)
		(mid 355.647129 -293.177739)
		(end 355.651054 -293.174928)
		(stroke
			(width 0.05715)
			(type default)
		)
		(layer "In15.Cu")
	)
	(gr_line
		(start 355.64318 -272.811494)
		(end 355.636322 -272.80743)
		(stroke
			(width 0.05715)
			(type default)
		)
		(layer "In15.Cu")
	)
	(gr_line
		(start 355.64318 -271.191482)
		(end 355.636322 -271.187418)
		(stroke
			(width 0.05715)
			(type default)
		)
		(layer "In15.Cu")
	)
	(gr_arc
		(start 355.644704 -292.2524)
		(mid 355.643942 -292.251891)
		(end 355.64318 -292.251384)
		(stroke
			(width 0.05715)
			(type default)
		)
		(layer "In15.Cu")
	)
	(gr_arc
		(start 355.651054 -293.876984)
		(mid 355.647129 -293.874173)
		(end 355.64318 -293.871396)
		(stroke
			(width 0.05715)
			(type default)
		)
		(layer "In15.Cu")
	)
	(gr_arc
		(start 355.651054 -292.256972)
		(mid 355.648266 -292.255058)
		(end 355.645466 -292.253162)
		(stroke
			(width 0.05715)
			(type default)
		)
		(layer "In15.Cu")
	)
	(gr_arc
		(start 355.651054 -290.63696)
		(mid 355.647129 -290.634149)
		(end 355.64318 -290.631372)
		(stroke
			(width 0.05715)
			(type default)
		)
		(layer "In15.Cu")
	)
	(gr_arc
		(start 355.651054 -289.016948)
		(mid 355.647129 -289.014137)
		(end 355.64318 -289.01136)
		(stroke
			(width 0.05715)
			(type default)
		)
		(layer "In15.Cu")
	)
	(gr_arc
		(start 355.651054 -272.817082)
		(mid 355.647129 -272.814271)
		(end 355.64318 -272.811494)
		(stroke
			(width 0.05715)
			(type default)
		)
		(layer "In15.Cu")
	)
	(gr_arc
		(start 355.651054 -271.19707)
		(mid 355.647129 -271.194259)
		(end 355.64318 -271.191482)
		(stroke
			(width 0.05715)
			(type default)
		)
		(layer "In15.Cu")
	)
	(gr_arc
		(start 355.651308 -287.396936)
		(mid 355.646878 -287.393866)
		(end 355.642418 -287.39084)
		(stroke
			(width 0.05715)
			(type default)
		)
		(layer "In15.Cu")
	)
	(gr_line
		(start 356.119938 -296.070528)
		(end 356.119938 -296.04208)
		(stroke
			(width 0.05715)
			(type default)
		)
		(layer "In15.Cu")
	)
	(gr_line
		(start 356.119938 -296.04208)
		(end 356.165658 -295.99636)
		(stroke
			(width 0.05715)
			(type default)
		)
		(layer "In15.Cu")
	)
	(gr_line
		(start 356.356158 -295.423336)
		(end 356.356412 -295.423082)
		(stroke
			(width 0.05715)
			(type default)
		)
		(layer "In15.Cu")
	)
	(gr_line
		(start 356.401878 -296.070528)
		(end 356.401878 -296.04208)
		(stroke
			(width 0.05715)
			(type default)
		)
		(layer "In15.Cu")
	)
	(gr_line
		(start 356.401878 -296.04208)
		(end 356.356158 -295.99636)
		(stroke
			(width 0.05715)
			(type default)
		)
		(layer "In15.Cu")
	)
	(gr_arc
		(start 356.40899 -293.06139)
		(mid 356.405041 -293.064167)
		(end 356.401116 -293.066978)
		(stroke
			(width 0.05715)
			(type default)
		)
		(layer "In15.Cu")
	)
	(gr_line
		(start 356.40899 -293.06139)
		(end 356.42677 -293.050976)
		(stroke
			(width 0.05715)
			(type default)
		)
		(layer "In15.Cu")
	)
	(gr_arc
		(start 356.40899 -291.441378)
		(mid 356.406063 -291.443401)
		(end 356.403148 -291.445442)
		(stroke
			(width 0.05715)
			(type default)
		)
		(layer "In15.Cu")
	)
	(gr_line
		(start 356.40899 -291.441378)
		(end 356.417626 -291.436298)
		(stroke
			(width 0.05715)
			(type default)
		)
		(layer "In15.Cu")
	)
	(gr_arc
		(start 356.40899 -286.581342)
		(mid 356.403634 -286.585121)
		(end 356.398322 -286.588962)
		(stroke
			(width 0.05715)
			(type default)
		)
		(layer "In15.Cu")
	)
	(gr_line
		(start 356.40899 -286.581342)
		(end 356.409498 -286.581088)
		(stroke
			(width 0.05715)
			(type default)
		)
		(layer "In15.Cu")
	)
	(gr_line
		(start 356.409498 -286.581088)
		(end 356.414324 -286.578294)
		(stroke
			(width 0.05715)
			(type default)
		)
		(layer "In15.Cu")
	)
	(gr_line
		(start 356.417626 -291.436298)
		(end 356.418642 -291.43579)
		(stroke
			(width 0.05715)
			(type default)
		)
		(layer "In15.Cu")
	)
	(gr_line
		(start 356.42677 -293.050976)
		(end 356.427786 -293.050468)
		(stroke
			(width 0.05715)
			(type default)
		)
		(layer "In15.Cu")
	)
	(gr_line
		(start 356.441248 -280.082752)
		(end 356.44455 -280.08072)
		(stroke
			(width 0.05715)
			(type default)
		)
		(layer "In15.Cu")
	)
	(gr_line
		(start 356.441248 -278.46274)
		(end 356.44455 -278.460708)
		(stroke
			(width 0.05715)
			(type default)
		)
		(layer "In15.Cu")
	)
	(gr_line
		(start 356.441248 -276.842728)
		(end 356.44455 -276.840696)
		(stroke
			(width 0.05715)
			(type default)
		)
		(layer "In15.Cu")
	)
	(gr_line
		(start 356.441248 -275.222716)
		(end 356.44455 -275.220684)
		(stroke
			(width 0.05715)
			(type default)
		)
		(layer "In15.Cu")
	)
	(gr_line
		(start 356.441248 -273.602704)
		(end 356.44455 -273.600672)
		(stroke
			(width 0.05715)
			(type default)
		)
		(layer "In15.Cu")
	)
	(gr_line
		(start 356.442518 -294.661844)
		(end 356.443788 -294.661082)
		(stroke
			(width 0.05715)
			(type default)
		)
		(layer "In15.Cu")
	)
	(gr_line
		(start 356.44455 -280.08072)
		(end 356.445566 -280.080212)
		(stroke
			(width 0.05715)
			(type default)
		)
		(layer "In15.Cu")
	)
	(gr_line
		(start 356.44455 -278.460708)
		(end 356.445566 -278.4602)
		(stroke
			(width 0.05715)
			(type default)
		)
		(layer "In15.Cu")
	)
	(gr_line
		(start 356.44455 -276.840696)
		(end 356.445566 -276.840188)
		(stroke
			(width 0.05715)
			(type default)
		)
		(layer "In15.Cu")
	)
	(gr_line
		(start 356.44455 -275.220684)
		(end 356.445566 -275.220176)
		(stroke
			(width 0.05715)
			(type default)
		)
		(layer "In15.Cu")
	)
	(gr_line
		(start 356.44455 -273.600672)
		(end 356.445566 -273.600164)
		(stroke
			(width 0.05715)
			(type default)
		)
		(layer "In15.Cu")
	)
	(gr_line
		(start 356.445566 -294.660066)
		(end 356.44709 -294.65905)
		(stroke
			(width 0.05715)
			(type default)
		)
		(layer "In15.Cu")
	)
	(gr_line
		(start 356.445566 -280.080212)
		(end 356.44709 -280.079196)
		(stroke
			(width 0.05715)
			(type default)
		)
		(layer "In15.Cu")
	)
	(gr_line
		(start 356.445566 -278.4602)
		(end 356.44709 -278.459184)
		(stroke
			(width 0.05715)
			(type default)
		)
		(layer "In15.Cu")
	)
	(gr_line
		(start 356.445566 -276.840188)
		(end 356.44709 -276.839172)
		(stroke
			(width 0.05715)
			(type default)
		)
		(layer "In15.Cu")
	)
	(gr_line
		(start 356.445566 -275.220176)
		(end 356.44709 -275.21916)
		(stroke
			(width 0.05715)
			(type default)
		)
		(layer "In15.Cu")
	)
	(gr_line
		(start 356.445566 -273.600164)
		(end 356.44709 -273.599148)
		(stroke
			(width 0.05715)
			(type default)
		)
		(layer "In15.Cu")
	)
	(gr_line
		(start 356.44709 -294.65905)
		(end 356.448106 -294.658542)
		(stroke
			(width 0.05715)
			(type default)
		)
		(layer "In15.Cu")
	)
	(gr_line
		(start 356.44709 -283.31922)
		(end 356.448106 -283.318712)
		(stroke
			(width 0.05715)
			(type default)
		)
		(layer "In15.Cu")
	)
	(gr_line
		(start 356.44709 -280.079196)
		(end 356.448106 -280.078688)
		(stroke
			(width 0.05715)
			(type default)
		)
		(layer "In15.Cu")
	)
	(gr_line
		(start 356.44709 -278.459184)
		(end 356.448106 -278.458676)
		(stroke
			(width 0.05715)
			(type default)
		)
		(layer "In15.Cu")
	)
	(gr_line
		(start 356.44709 -276.839172)
		(end 356.448106 -276.838664)
		(stroke
			(width 0.05715)
			(type default)
		)
		(layer "In15.Cu")
	)
	(gr_line
		(start 356.44709 -275.21916)
		(end 356.448106 -275.218652)
		(stroke
			(width 0.05715)
			(type default)
		)
		(layer "In15.Cu")
	)
	(gr_line
		(start 356.44709 -273.599148)
		(end 356.448106 -273.59864)
		(stroke
			(width 0.05715)
			(type default)
		)
		(layer "In15.Cu")
	)
	(gr_line
		(start 356.448106 -294.658542)
		(end 356.448614 -294.658288)
		(stroke
			(width 0.05715)
			(type default)
		)
		(layer "In15.Cu")
	)
	(gr_line
		(start 356.448106 -294.013382)
		(end 356.44709 -294.012874)
		(stroke
			(width 0.05715)
			(type default)
		)
		(layer "In15.Cu")
	)
	(gr_line
		(start 356.448106 -292.39337)
		(end 356.44709 -292.392862)
		(stroke
			(width 0.05715)
			(type default)
		)
		(layer "In15.Cu")
	)
	(gr_line
		(start 356.448106 -290.773358)
		(end 356.44709 -290.77285)
		(stroke
			(width 0.05715)
			(type default)
		)
		(layer "In15.Cu")
	)
	(gr_line
		(start 356.448106 -289.153346)
		(end 356.44709 -289.152838)
		(stroke
			(width 0.05715)
			(type default)
		)
		(layer "In15.Cu")
	)
	(gr_line
		(start 356.448106 -283.318712)
		(end 356.448614 -283.318458)
		(stroke
			(width 0.05715)
			(type default)
		)
		(layer "In15.Cu")
	)
	(gr_line
		(start 356.448106 -281.05354)
		(end 356.44709 -281.053032)
		(stroke
			(width 0.05715)
			(type default)
		)
		(layer "In15.Cu")
	)
	(gr_line
		(start 356.448106 -280.078688)
		(end 356.448868 -280.07818)
		(stroke
			(width 0.05715)
			(type default)
		)
		(layer "In15.Cu")
	)
	(gr_line
		(start 356.448106 -278.458676)
		(end 356.448868 -278.458168)
		(stroke
			(width 0.05715)
			(type default)
		)
		(layer "In15.Cu")
	)
	(gr_line
		(start 356.448106 -276.838664)
		(end 356.448868 -276.838156)
		(stroke
			(width 0.05715)
			(type default)
		)
		(layer "In15.Cu")
	)
	(gr_line
		(start 356.448106 -275.218652)
		(end 356.448868 -275.218144)
		(stroke
			(width 0.05715)
			(type default)
		)
		(layer "In15.Cu")
	)
	(gr_line
		(start 356.448106 -273.59864)
		(end 356.448868 -273.598132)
		(stroke
			(width 0.05715)
			(type default)
		)
		(layer "In15.Cu")
	)
	(gr_line
		(start 356.448868 -281.054048)
		(end 356.448106 -281.05354)
		(stroke
			(width 0.05715)
			(type default)
		)
		(layer "In15.Cu")
	)
	(gr_line
		(start 356.450138 -284.294834)
		(end 356.448868 -284.294072)
		(stroke
			(width 0.05715)
			(type default)
		)
		(layer "In15.Cu")
	)
	(gr_line
		(start 356.450138 -282.674822)
		(end 356.448868 -282.67406)
		(stroke
			(width 0.05715)
			(type default)
		)
		(layer "In15.Cu")
	)
	(gr_line
		(start 356.450138 -279.434798)
		(end 356.448868 -279.434036)
		(stroke
			(width 0.05715)
			(type default)
		)
		(layer "In15.Cu")
	)
	(gr_line
		(start 356.450138 -277.814786)
		(end 356.448868 -277.814024)
		(stroke
			(width 0.05715)
			(type default)
		)
		(layer "In15.Cu")
	)
	(gr_line
		(start 356.452678 -281.056334)
		(end 356.448868 -281.054048)
		(stroke
			(width 0.05715)
			(type default)
		)
		(layer "In15.Cu")
	)
	(gr_line
		(start 356.479856 -276.820376)
		(end 356.479602 -276.820376)
		(stroke
			(width 0.05715)
			(type default)
		)
		(layer "In15.Cu")
	)
	(gr_line
		(start 356.479856 -275.200364)
		(end 356.479602 -275.200364)
		(stroke
			(width 0.05715)
			(type default)
		)
		(layer "In15.Cu")
	)
	(gr_line
		(start 356.512368 -291.601652)
		(end 356.512368 -291.601906)
		(stroke
			(width 0.05715)
			(type default)
		)
		(layer "In15.Cu")
	)
	(gr_line
		(start 356.512368 -289.98164)
		(end 356.512622 -289.981894)
		(stroke
			(width 0.05715)
			(type default)
		)
		(layer "In15.Cu")
	)
	(gr_line
		(start 356.514908 -293.221664)
		(end 356.52329 -293.221664)
		(stroke
			(width 0.05715)
			(type default)
		)
		(layer "In15.Cu")
	)
	(gr_line
		(start 356.52329 -293.221664)
		(end 356.52329 -293.216584)
		(stroke
			(width 0.05715)
			(type default)
		)
		(layer "In15.Cu")
	)
	(gr_line
		(start 356.53853 -294.82669)
		(end 356.540562 -294.82542)
		(stroke
			(width 0.05715)
			(type default)
		)
		(layer "In15.Cu")
	)
	(gr_line
		(start 356.540562 -294.82542)
		(end 356.542086 -294.824658)
		(stroke
			(width 0.05715)
			(type default)
		)
		(layer "In15.Cu")
	)
	(gr_line
		(start 356.54107 -280.245312)
		(end 356.543356 -280.244042)
		(stroke
			(width 0.05715)
			(type default)
		)
		(layer "In15.Cu")
	)
	(gr_line
		(start 356.54107 -278.6253)
		(end 356.543356 -278.62403)
		(stroke
			(width 0.05715)
			(type default)
		)
		(layer "In15.Cu")
	)
	(gr_line
		(start 356.54107 -277.005288)
		(end 356.543356 -277.004018)
		(stroke
			(width 0.05715)
			(type default)
		)
		(layer "In15.Cu")
	)
	(gr_line
		(start 356.54107 -275.385276)
		(end 356.543356 -275.384006)
		(stroke
			(width 0.05715)
			(type default)
		)
		(layer "In15.Cu")
	)
	(gr_line
		(start 356.54107 -273.765264)
		(end 356.543356 -273.763994)
		(stroke
			(width 0.05715)
			(type default)
		)
		(layer "In15.Cu")
	)
	(gr_line
		(start 356.542086 -294.824658)
		(end 356.543356 -294.823896)
		(stroke
			(width 0.05715)
			(type default)
		)
		(layer "In15.Cu")
	)
	(gr_line
		(start 356.542086 -283.484828)
		(end 356.543356 -283.484066)
		(stroke
			(width 0.05715)
			(type default)
		)
		(layer "In15.Cu")
	)
	(gr_line
		(start 356.543356 -293.848028)
		(end 356.542086 -293.847266)
		(stroke
			(width 0.05715)
			(type default)
		)
		(layer "In15.Cu")
	)
	(gr_line
		(start 356.543356 -292.228016)
		(end 356.542086 -292.227254)
		(stroke
			(width 0.05715)
			(type default)
		)
		(layer "In15.Cu")
	)
	(gr_line
		(start 356.543356 -290.608004)
		(end 356.542086 -290.607242)
		(stroke
			(width 0.05715)
			(type default)
		)
		(layer "In15.Cu")
	)
	(gr_line
		(start 356.543356 -288.987992)
		(end 356.542086 -288.98723)
		(stroke
			(width 0.05715)
			(type default)
		)
		(layer "In15.Cu")
	)
	(gr_line
		(start 356.543356 -280.888186)
		(end 356.542086 -280.887424)
		(stroke
			(width 0.05715)
			(type default)
		)
		(layer "In15.Cu")
	)
	(gr_line
		(start 356.543356 -280.244042)
		(end 356.544118 -280.243534)
		(stroke
			(width 0.05715)
			(type default)
		)
		(layer "In15.Cu")
	)
	(gr_line
		(start 356.543356 -278.62403)
		(end 356.544118 -278.623522)
		(stroke
			(width 0.05715)
			(type default)
		)
		(layer "In15.Cu")
	)
	(gr_line
		(start 356.543356 -277.004018)
		(end 356.544118 -277.00351)
		(stroke
			(width 0.05715)
			(type default)
		)
		(layer "In15.Cu")
	)
	(gr_line
		(start 356.543356 -275.384006)
		(end 356.544118 -275.383498)
		(stroke
			(width 0.05715)
			(type default)
		)
		(layer "In15.Cu")
	)
	(gr_line
		(start 356.543356 -273.763994)
		(end 356.544118 -273.763486)
		(stroke
			(width 0.05715)
			(type default)
		)
		(layer "In15.Cu")
	)
	(gr_line
		(start 356.543864 -293.848282)
		(end 356.543356 -293.848028)
		(stroke
			(width 0.05715)
			(type default)
		)
		(layer "In15.Cu")
	)
	(gr_line
		(start 356.543864 -292.22827)
		(end 356.543356 -292.228016)
		(stroke
			(width 0.05715)
			(type default)
		)
		(layer "In15.Cu")
	)
	(gr_line
		(start 356.543864 -290.608258)
		(end 356.543356 -290.608004)
		(stroke
			(width 0.05715)
			(type default)
		)
		(layer "In15.Cu")
	)
	(gr_line
		(start 356.543864 -288.988246)
		(end 356.543356 -288.987992)
		(stroke
			(width 0.05715)
			(type default)
		)
		(layer "In15.Cu")
	)
	(gr_line
		(start 356.544118 -285.74873)
		(end 356.54361 -285.748476)
		(stroke
			(width 0.05715)
			(type default)
		)
		(layer "In15.Cu")
	)
	(gr_line
		(start 356.544118 -284.128718)
		(end 356.54361 -284.128464)
		(stroke
			(width 0.05715)
			(type default)
		)
		(layer "In15.Cu")
	)
	(gr_line
		(start 356.544118 -282.508706)
		(end 356.54361 -282.508452)
		(stroke
			(width 0.05715)
			(type default)
		)
		(layer "In15.Cu")
	)
	(gr_line
		(start 356.544118 -280.243534)
		(end 356.545134 -280.243026)
		(stroke
			(width 0.05715)
			(type default)
		)
		(layer "In15.Cu")
	)
	(gr_line
		(start 356.544118 -279.268682)
		(end 356.54361 -279.268428)
		(stroke
			(width 0.05715)
			(type default)
		)
		(layer "In15.Cu")
	)
	(gr_line
		(start 356.544118 -278.623522)
		(end 356.545134 -278.623014)
		(stroke
			(width 0.05715)
			(type default)
		)
		(layer "In15.Cu")
	)
	(gr_line
		(start 356.544118 -277.64867)
		(end 356.54361 -277.648416)
		(stroke
			(width 0.05715)
			(type default)
		)
		(layer "In15.Cu")
	)
	(gr_line
		(start 356.544118 -277.00351)
		(end 356.545134 -277.003002)
		(stroke
			(width 0.05715)
			(type default)
		)
		(layer "In15.Cu")
	)
	(gr_line
		(start 356.544118 -275.383498)
		(end 356.545134 -275.38299)
		(stroke
			(width 0.05715)
			(type default)
		)
		(layer "In15.Cu")
	)
	(gr_line
		(start 356.544118 -273.763486)
		(end 356.545134 -273.762978)
		(stroke
			(width 0.05715)
			(type default)
		)
		(layer "In15.Cu")
	)
	(gr_line
		(start 356.545134 -284.129226)
		(end 356.544118 -284.128718)
		(stroke
			(width 0.05715)
			(type default)
		)
		(layer "In15.Cu")
	)
	(gr_line
		(start 356.545134 -282.509214)
		(end 356.544118 -282.508706)
		(stroke
			(width 0.05715)
			(type default)
		)
		(layer "In15.Cu")
	)
	(gr_line
		(start 356.545134 -280.889202)
		(end 356.544118 -280.888694)
		(stroke
			(width 0.05715)
			(type default)
		)
		(layer "In15.Cu")
	)
	(gr_line
		(start 356.545134 -279.26919)
		(end 356.544118 -279.268682)
		(stroke
			(width 0.05715)
			(type default)
		)
		(layer "In15.Cu")
	)
	(gr_line
		(start 356.545134 -277.649178)
		(end 356.544118 -277.64867)
		(stroke
			(width 0.05715)
			(type default)
		)
		(layer "In15.Cu")
	)
	(gr_line
		(start 356.545896 -280.88971)
		(end 356.545134 -280.889202)
		(stroke
			(width 0.05715)
			(type default)
		)
		(layer "In15.Cu")
	)
	(gr_line
		(start 356.550214 -280.891996)
		(end 356.545896 -280.88971)
		(stroke
			(width 0.05715)
			(type default)
		)
		(layer "In15.Cu")
	)
	(gr_line
		(start 356.563168 -276.039072)
		(end 356.562406 -276.038564)
		(stroke
			(width 0.05715)
			(type default)
		)
		(layer "In15.Cu")
	)
	(gr_line
		(start 356.563168 -274.41906)
		(end 356.562406 -274.418552)
		(stroke
			(width 0.05715)
			(type default)
		)
		(layer "In15.Cu")
	)
	(gr_line
		(start 356.567232 -276.041358)
		(end 356.563168 -276.039072)
		(stroke
			(width 0.05715)
			(type default)
		)
		(layer "In15.Cu")
	)
	(gr_line
		(start 356.567232 -274.421346)
		(end 356.563168 -274.41906)
		(stroke
			(width 0.05715)
			(type default)
		)
		(layer "In15.Cu")
	)
	(gr_line
		(start 356.574598 -276.98573)
		(end 356.583234 -276.98065)
		(stroke
			(width 0.05715)
			(type default)
		)
		(layer "In15.Cu")
	)
	(gr_line
		(start 356.574598 -275.365718)
		(end 356.583234 -275.360638)
		(stroke
			(width 0.05715)
			(type default)
		)
		(layer "In15.Cu")
	)
	(gr_line
		(start 356.575106 -285.08579)
		(end 356.58044 -285.082742)
		(stroke
			(width 0.05715)
			(type default)
		)
		(layer "In15.Cu")
	)
	(gr_line
		(start 356.575106 -281.845766)
		(end 356.58044 -281.842718)
		(stroke
			(width 0.05715)
			(type default)
		)
		(layer "In15.Cu")
	)
	(gr_line
		(start 356.575614 -293.866824)
		(end 356.574852 -293.866316)
		(stroke
			(width 0.05715)
			(type default)
		)
		(layer "In15.Cu")
	)
	(gr_line
		(start 356.575614 -293.185088)
		(end 356.582726 -293.181024)
		(stroke
			(width 0.05715)
			(type default)
		)
		(layer "In15.Cu")
	)
	(gr_line
		(start 356.575614 -292.246812)
		(end 356.574852 -292.246304)
		(stroke
			(width 0.05715)
			(type default)
		)
		(layer "In15.Cu")
	)
	(gr_line
		(start 356.575614 -291.565076)
		(end 356.582726 -291.561012)
		(stroke
			(width 0.05715)
			(type default)
		)
		(layer "In15.Cu")
	)
	(gr_line
		(start 356.575614 -290.6268)
		(end 356.574852 -290.626292)
		(stroke
			(width 0.05715)
			(type default)
		)
		(layer "In15.Cu")
	)
	(gr_line
		(start 356.575614 -289.945318)
		(end 356.58298 -289.941)
		(stroke
			(width 0.05715)
			(type default)
		)
		(layer "In15.Cu")
	)
	(gr_line
		(start 356.575614 -289.006788)
		(end 356.574852 -289.00628)
		(stroke
			(width 0.05715)
			(type default)
		)
		(layer "In15.Cu")
	)
	(gr_line
		(start 356.575614 -285.767018)
		(end 356.574852 -285.76651)
		(stroke
			(width 0.05715)
			(type default)
		)
		(layer "In15.Cu")
	)
	(gr_line
		(start 356.576376 -293.867332)
		(end 356.575614 -293.866824)
		(stroke
			(width 0.05715)
			(type default)
		)
		(layer "In15.Cu")
	)
	(gr_line
		(start 356.576376 -292.24732)
		(end 356.575614 -292.246812)
		(stroke
			(width 0.05715)
			(type default)
		)
		(layer "In15.Cu")
	)
	(gr_line
		(start 356.576376 -290.627308)
		(end 356.575614 -290.6268)
		(stroke
			(width 0.05715)
			(type default)
		)
		(layer "In15.Cu")
	)
	(gr_line
		(start 356.576376 -289.007296)
		(end 356.575614 -289.006788)
		(stroke
			(width 0.05715)
			(type default)
		)
		(layer "In15.Cu")
	)
	(gr_line
		(start 356.576376 -285.767526)
		(end 356.575614 -285.767018)
		(stroke
			(width 0.05715)
			(type default)
		)
		(layer "In15.Cu")
	)
	(gr_line
		(start 356.576376 -276.046438)
		(end 356.569264 -276.042374)
		(stroke
			(width 0.05715)
			(type default)
		)
		(layer "In15.Cu")
	)
	(gr_line
		(start 356.576376 -274.426426)
		(end 356.569264 -274.422362)
		(stroke
			(width 0.05715)
			(type default)
		)
		(layer "In15.Cu")
	)
	(gr_line
		(start 356.58044 -285.082742)
		(end 356.583234 -285.08071)
		(stroke
			(width 0.05715)
			(type default)
		)
		(layer "In15.Cu")
	)
	(gr_line
		(start 356.58044 -281.842718)
		(end 356.583234 -281.840686)
		(stroke
			(width 0.05715)
			(type default)
		)
		(layer "In15.Cu")
	)
	(gr_line
		(start 356.582726 -293.181024)
		(end 356.583234 -293.18077)
		(stroke
			(width 0.05715)
			(type default)
		)
		(layer "In15.Cu")
	)
	(gr_line
		(start 356.582726 -291.561012)
		(end 356.583234 -291.560758)
		(stroke
			(width 0.05715)
			(type default)
		)
		(layer "In15.Cu")
	)
	(gr_line
		(start 356.58298 -289.941)
		(end 356.583488 -289.940746)
		(stroke
			(width 0.05715)
			(type default)
		)
		(layer "In15.Cu")
	)
	(gr_line
		(start 356.583234 -293.871396)
		(end 356.576376 -293.867332)
		(stroke
			(width 0.05715)
			(type default)
		)
		(layer "In15.Cu")
	)
	(gr_line
		(start 356.583234 -293.18077)
		(end 356.583234 -293.180516)
		(stroke
			(width 0.05715)
			(type default)
		)
		(layer "In15.Cu")
	)
	(gr_arc
		(start 356.583234 -293.180516)
		(mid 356.587183 -293.177739)
		(end 356.591108 -293.174928)
		(stroke
			(width 0.05715)
			(type default)
		)
		(layer "In15.Cu")
	)
	(gr_line
		(start 356.583234 -292.251384)
		(end 356.576376 -292.24732)
		(stroke
			(width 0.05715)
			(type default)
		)
		(layer "In15.Cu")
	)
	(gr_line
		(start 356.583234 -291.560758)
		(end 356.583234 -291.560504)
		(stroke
			(width 0.05715)
			(type default)
		)
		(layer "In15.Cu")
	)
	(gr_arc
		(start 356.583234 -291.560504)
		(mid 356.587183 -291.557727)
		(end 356.591108 -291.554916)
		(stroke
			(width 0.05715)
			(type default)
		)
		(layer "In15.Cu")
	)
	(gr_line
		(start 356.583234 -290.631372)
		(end 356.576376 -290.627308)
		(stroke
			(width 0.05715)
			(type default)
		)
		(layer "In15.Cu")
	)
	(gr_arc
		(start 356.583234 -289.940492)
		(mid 356.587183 -289.937715)
		(end 356.591108 -289.934904)
		(stroke
			(width 0.05715)
			(type default)
		)
		(layer "In15.Cu")
	)
	(gr_line
		(start 356.583234 -289.01136)
		(end 356.576376 -289.007296)
		(stroke
			(width 0.05715)
			(type default)
		)
		(layer "In15.Cu")
	)
	(gr_line
		(start 356.583234 -285.77159)
		(end 356.576376 -285.767526)
		(stroke
			(width 0.05715)
			(type default)
		)
		(layer "In15.Cu")
	)
	(gr_arc
		(start 356.583234 -285.08071)
		(mid 356.587183 -285.077933)
		(end 356.591108 -285.075122)
		(stroke
			(width 0.05715)
			(type default)
		)
		(layer "In15.Cu")
	)
	(gr_arc
		(start 356.583234 -281.840686)
		(mid 356.587183 -281.837909)
		(end 356.591108 -281.835098)
		(stroke
			(width 0.05715)
			(type default)
		)
		(layer "In15.Cu")
	)
	(gr_arc
		(start 356.583234 -276.98065)
		(mid 356.58731 -276.977746)
		(end 356.591362 -276.974808)
		(stroke
			(width 0.05715)
			(type default)
		)
		(layer "In15.Cu")
	)
	(gr_line
		(start 356.583234 -276.050756)
		(end 356.583234 -276.050248)
		(stroke
			(width 0.05715)
			(type default)
		)
		(layer "In15.Cu")
	)
	(gr_line
		(start 356.583234 -276.050248)
		(end 356.5779 -276.0472)
		(stroke
			(width 0.05715)
			(type default)
		)
		(layer "In15.Cu")
	)
	(gr_arc
		(start 356.583234 -275.360638)
		(mid 356.58731 -275.357734)
		(end 356.591362 -275.354796)
		(stroke
			(width 0.05715)
			(type default)
		)
		(layer "In15.Cu")
	)
	(gr_line
		(start 356.583234 -274.430744)
		(end 356.583234 -274.430236)
		(stroke
			(width 0.05715)
			(type default)
		)
		(layer "In15.Cu")
	)
	(gr_line
		(start 356.583234 -274.430236)
		(end 356.5779 -274.427188)
		(stroke
			(width 0.05715)
			(type default)
		)
		(layer "In15.Cu")
	)
	(gr_line
		(start 356.583488 -289.940746)
		(end 356.583234 -289.940492)
		(stroke
			(width 0.05715)
			(type default)
		)
		(layer "In15.Cu")
	)
	(gr_arc
		(start 356.591108 -293.876984)
		(mid 356.587183 -293.874173)
		(end 356.583234 -293.871396)
		(stroke
			(width 0.05715)
			(type default)
		)
		(layer "In15.Cu")
	)
	(gr_arc
		(start 356.591108 -292.256972)
		(mid 356.587183 -292.254161)
		(end 356.583234 -292.251384)
		(stroke
			(width 0.05715)
			(type default)
		)
		(layer "In15.Cu")
	)
	(gr_arc
		(start 356.591108 -290.63696)
		(mid 356.587183 -290.634149)
		(end 356.583234 -290.631372)
		(stroke
			(width 0.05715)
			(type default)
		)
		(layer "In15.Cu")
	)
	(gr_arc
		(start 356.591108 -289.016948)
		(mid 356.587183 -289.014137)
		(end 356.583234 -289.01136)
		(stroke
			(width 0.05715)
			(type default)
		)
		(layer "In15.Cu")
	)
	(gr_arc
		(start 356.591108 -285.777178)
		(mid 356.587183 -285.774367)
		(end 356.583234 -285.77159)
		(stroke
			(width 0.05715)
			(type default)
		)
		(layer "In15.Cu")
	)
	(gr_line
		(start 357.029004 -274.086066)
		(end 356.731062 -274.086066)
		(stroke
			(width 0.05715)
			(type default)
		)
		(layer "In15.Cu")
	)
	(gr_line
		(start 357.029004 -272.466054)
		(end 356.731062 -272.466054)
		(stroke
			(width 0.05715)
			(type default)
		)
		(layer "In15.Cu")
	)
	(gr_line
		(start 357.029004 -270.846042)
		(end 356.731062 -270.846042)
		(stroke
			(width 0.05715)
			(type default)
		)
		(layer "In15.Cu")
	)
	(gr_line
		(start 357.029004 -269.22603)
		(end 356.731062 -269.22603)
		(stroke
			(width 0.05715)
			(type default)
		)
		(layer "In15.Cu")
	)
	(gr_line
		(start 357.059992 -295.911016)
		(end 357.059992 -295.882568)
		(stroke
			(width 0.05715)
			(type default)
		)
		(layer "In15.Cu")
	)
	(gr_line
		(start 357.059992 -295.882568)
		(end 357.104442 -295.838118)
		(stroke
			(width 0.05715)
			(type default)
		)
		(layer "In15.Cu")
	)
	(gr_line
		(start 357.098346 -272.535396)
		(end 357.029004 -272.466054)
		(stroke
			(width 0.05715)
			(type default)
		)
		(layer "In15.Cu")
	)
	(gr_line
		(start 357.111808 -274.16887)
		(end 357.029004 -274.086066)
		(stroke
			(width 0.05715)
			(type default)
		)
		(layer "In15.Cu")
	)
	(gr_arc
		(start 357.111808 -274.16887)
		(mid 357.1136 -274.180192)
		(end 357.115618 -274.191476)
		(stroke
			(width 0.05715)
			(type default)
		)
		(layer "In15.Cu")
	)
	(gr_line
		(start 357.111808 -270.928846)
		(end 357.029004 -270.846042)
		(stroke
			(width 0.05715)
			(type default)
		)
		(layer "In15.Cu")
	)
	(gr_arc
		(start 357.111808 -270.928846)
		(mid 357.1136 -270.940168)
		(end 357.115618 -270.951452)
		(stroke
			(width 0.05715)
			(type default)
		)
		(layer "In15.Cu")
	)
	(gr_line
		(start 357.111808 -269.308834)
		(end 357.029004 -269.22603)
		(stroke
			(width 0.05715)
			(type default)
		)
		(layer "In15.Cu")
	)
	(gr_arc
		(start 357.111808 -269.308834)
		(mid 357.113599 -269.320156)
		(end 357.115618 -269.33144)
		(stroke
			(width 0.05715)
			(type default)
		)
		(layer "In15.Cu")
	)
	(gr_arc
		(start 357.28656 -272.571718)
		(mid 357.288581 -272.560307)
		(end 357.29037 -272.548858)
		(stroke
			(width 0.05715)
			(type default)
		)
		(layer "In15.Cu")
	)
	(gr_line
		(start 357.29037 -272.548858)
		(end 357.373174 -272.466054)
		(stroke
			(width 0.05715)
			(type default)
		)
		(layer "In15.Cu")
	)
	(gr_line
		(start 357.296212 -295.850818)
		(end 357.296212 -295.836848)
		(stroke
			(width 0.05715)
			(type default)
		)
		(layer "In15.Cu")
	)
	(gr_line
		(start 357.296466 -287.046162)
		(end 357.296212 -287.045908)
		(stroke
			(width 0.05715)
			(type default)
		)
		(layer "In15.Cu")
	)
	(gr_line
		(start 357.303832 -274.155408)
		(end 357.373174 -274.086066)
		(stroke
			(width 0.05715)
			(type default)
		)
		(layer "In15.Cu")
	)
	(gr_line
		(start 357.303832 -270.915384)
		(end 357.373174 -270.846042)
		(stroke
			(width 0.05715)
			(type default)
		)
		(layer "In15.Cu")
	)
	(gr_line
		(start 357.303832 -269.295372)
		(end 357.373174 -269.22603)
		(stroke
			(width 0.05715)
			(type default)
		)
		(layer "In15.Cu")
	)
	(gr_arc
		(start 357.33609 -291.450776)
		(mid 357.336471 -291.450522)
		(end 357.336852 -291.450268)
		(stroke
			(width 0.05715)
			(type default)
		)
		(layer "In15.Cu")
	)
	(gr_arc
		(start 357.337614 -292.362128)
		(mid 357.337233 -292.361874)
		(end 357.336852 -292.36162)
		(stroke
			(width 0.05715)
			(type default)
		)
		(layer "In15.Cu")
	)
	(gr_arc
		(start 357.337614 -292.362128)
		(mid 357.338502 -292.362764)
		(end 357.339392 -292.363398)
		(stroke
			(width 0.05715)
			(type default)
		)
		(layer "In15.Cu")
	)
	(gr_arc
		(start 357.338376 -291.448998)
		(mid 357.337613 -291.449632)
		(end 357.336852 -291.450268)
		(stroke
			(width 0.05715)
			(type default)
		)
		(layer "In15.Cu")
	)
	(gr_arc
		(start 357.3399 -291.447982)
		(mid 357.339138 -291.448489)
		(end 357.338376 -291.448998)
		(stroke
			(width 0.05715)
			(type default)
		)
		(layer "In15.Cu")
	)
	(gr_arc
		(start 357.340408 -292.36416)
		(mid 357.3399 -292.363779)
		(end 357.339392 -292.363398)
		(stroke
			(width 0.05715)
			(type default)
		)
		(layer "In15.Cu")
	)
	(gr_arc
		(start 357.340408 -292.36416)
		(mid 357.344712 -292.367354)
		(end 357.349044 -292.37051)
		(stroke
			(width 0.05715)
			(type default)
		)
		(layer "In15.Cu")
	)
	(gr_arc
		(start 357.340916 -274.545044)
		(mid 357.344968 -274.547856)
		(end 357.349044 -274.550632)
		(stroke
			(width 0.05715)
			(type default)
		)
		(layer "In15.Cu")
	)
	(gr_arc
		(start 357.340916 -269.685008)
		(mid 357.344968 -269.68782)
		(end 357.349044 -269.690596)
		(stroke
			(width 0.05715)
			(type default)
		)
		(layer "In15.Cu")
	)
	(gr_arc
		(start 357.34117 -279.40508)
		(mid 357.345095 -279.407891)
		(end 357.349044 -279.410668)
		(stroke
			(width 0.05715)
			(type default)
		)
		(layer "In15.Cu")
	)
	(gr_line
		(start 357.341932 -295.911016)
		(end 357.341932 -295.896538)
		(stroke
			(width 0.05715)
			(type default)
		)
		(layer "In15.Cu")
	)
	(gr_line
		(start 357.341932 -295.896538)
		(end 357.296212 -295.850818)
		(stroke
			(width 0.05715)
			(type default)
		)
		(layer "In15.Cu")
	)
	(gr_arc
		(start 357.349044 -291.441378)
		(mid 357.344455 -291.444657)
		(end 357.3399 -291.447982)
		(stroke
			(width 0.05715)
			(type default)
		)
		(layer "In15.Cu")
	)
	(gr_line
		(start 357.349044 -291.441378)
		(end 357.35641 -291.43706)
		(stroke
			(width 0.05715)
			(type default)
		)
		(layer "In15.Cu")
	)
	(gr_arc
		(start 357.349806 -279.411176)
		(mid 357.349425 -279.410922)
		(end 357.349044 -279.410668)
		(stroke
			(width 0.05715)
			(type default)
		)
		(layer "In15.Cu")
	)
	(gr_arc
		(start 357.349806 -274.55114)
		(mid 357.349425 -274.550886)
		(end 357.349044 -274.550632)
		(stroke
			(width 0.05715)
			(type default)
		)
		(layer "In15.Cu")
	)
	(gr_arc
		(start 357.349806 -269.691104)
		(mid 357.349425 -269.69085)
		(end 357.349044 -269.690596)
		(stroke
			(width 0.05715)
			(type default)
		)
		(layer "In15.Cu")
	)
	(gr_line
		(start 357.353108 -286.579056)
		(end 357.355648 -286.577532)
		(stroke
			(width 0.05715)
			(type default)
		)
		(layer "In15.Cu")
	)
	(gr_line
		(start 357.35641 -269.694914)
		(end 357.349806 -269.691104)
		(stroke
			(width 0.05715)
			(type default)
		)
		(layer "In15.Cu")
	)
	(gr_line
		(start 357.356918 -279.41524)
		(end 357.349806 -279.411176)
		(stroke
			(width 0.05715)
			(type default)
		)
		(layer "In15.Cu")
	)
	(gr_line
		(start 357.356918 -274.555204)
		(end 357.349806 -274.55114)
		(stroke
			(width 0.05715)
			(type default)
		)
		(layer "In15.Cu")
	)
	(gr_line
		(start 357.357172 -292.375336)
		(end 357.349044 -292.37051)
		(stroke
			(width 0.05715)
			(type default)
		)
		(layer "In15.Cu")
	)
	(gr_line
		(start 357.357172 -269.695422)
		(end 357.35641 -269.694914)
		(stroke
			(width 0.05715)
			(type default)
		)
		(layer "In15.Cu")
	)
	(gr_line
		(start 357.35768 -269.695676)
		(end 357.357172 -269.695422)
		(stroke
			(width 0.05715)
			(type default)
		)
		(layer "In15.Cu")
	)
	(gr_line
		(start 357.36784 -289.141662)
		(end 357.364284 -289.139376)
		(stroke
			(width 0.05715)
			(type default)
		)
		(layer "In15.Cu")
	)
	(gr_line
		(start 357.373174 -274.086066)
		(end 357.671116 -274.086066)
		(stroke
			(width 0.05715)
			(type default)
		)
		(layer "In15.Cu")
	)
	(gr_line
		(start 357.373174 -272.466054)
		(end 357.671116 -272.466054)
		(stroke
			(width 0.05715)
			(type default)
		)
		(layer "In15.Cu")
	)
	(gr_line
		(start 357.373174 -270.846042)
		(end 357.671116 -270.846042)
		(stroke
			(width 0.05715)
			(type default)
		)
		(layer "In15.Cu")
	)
	(gr_line
		(start 357.373174 -269.22603)
		(end 357.671116 -269.22603)
		(stroke
			(width 0.05715)
			(type default)
		)
		(layer "In15.Cu")
	)
	(gr_line
		(start 357.373682 -281.045158)
		(end 357.373174 -281.044904)
		(stroke
			(width 0.05715)
			(type default)
		)
		(layer "In15.Cu")
	)
	(gr_line
		(start 357.374698 -281.045666)
		(end 357.373682 -281.045158)
		(stroke
			(width 0.05715)
			(type default)
		)
		(layer "In15.Cu")
	)
	(gr_line
		(start 357.377238 -281.04719)
		(end 357.37673 -281.046936)
		(stroke
			(width 0.05715)
			(type default)
		)
		(layer "In15.Cu")
	)
	(gr_line
		(start 357.378508 -292.388036)
		(end 357.377492 -292.387528)
		(stroke
			(width 0.05715)
			(type default)
		)
		(layer "In15.Cu")
	)
	(gr_line
		(start 357.379016 -292.38829)
		(end 357.378508 -292.388036)
		(stroke
			(width 0.05715)
			(type default)
		)
		(layer "In15.Cu")
	)
	(gr_line
		(start 357.380032 -269.70863)
		(end 357.376984 -269.706852)
		(stroke
			(width 0.05715)
			(type default)
		)
		(layer "In15.Cu")
	)
	(gr_line
		(start 357.380794 -269.709138)
		(end 357.380032 -269.70863)
		(stroke
			(width 0.05715)
			(type default)
		)
		(layer "In15.Cu")
	)
	(gr_line
		(start 357.383588 -289.8013)
		(end 357.38562 -289.80003)
		(stroke
			(width 0.05715)
			(type default)
		)
		(layer "In15.Cu")
	)
	(gr_line
		(start 357.38562 -289.80003)
		(end 357.387144 -289.799014)
		(stroke
			(width 0.05715)
			(type default)
		)
		(layer "In15.Cu")
	)
	(gr_line
		(start 357.387144 -290.77285)
		(end 357.38181 -290.769802)
		(stroke
			(width 0.05715)
			(type default)
		)
		(layer "In15.Cu")
	)
	(gr_line
		(start 357.387144 -289.799014)
		(end 357.38816 -289.798506)
		(stroke
			(width 0.05715)
			(type default)
		)
		(layer "In15.Cu")
	)
	(gr_line
		(start 357.38816 -290.773358)
		(end 357.387144 -290.77285)
		(stroke
			(width 0.05715)
			(type default)
		)
		(layer "In15.Cu")
	)
	(gr_line
		(start 357.388922 -290.773866)
		(end 357.38816 -290.773358)
		(stroke
			(width 0.05715)
			(type default)
		)
		(layer "In15.Cu")
	)
	(gr_line
		(start 357.389938 -293.037514)
		(end 357.391462 -293.036498)
		(stroke
			(width 0.05715)
			(type default)
		)
		(layer "In15.Cu")
	)
	(gr_line
		(start 357.390192 -290.774628)
		(end 357.388922 -290.773866)
		(stroke
			(width 0.05715)
			(type default)
		)
		(layer "In15.Cu")
	)
	(gr_line
		(start 357.391462 -293.036498)
		(end 357.394764 -293.03472)
		(stroke
			(width 0.05715)
			(type default)
		)
		(layer "In15.Cu")
	)
	(gr_line
		(start 357.396542 -291.413692)
		(end 357.398066 -291.41293)
		(stroke
			(width 0.05715)
			(type default)
		)
		(layer "In15.Cu")
	)
	(gr_line
		(start 357.408988 -275.20646)
		(end 357.409496 -275.206206)
		(stroke
			(width 0.05715)
			(type default)
		)
		(layer "In15.Cu")
	)
	(gr_line
		(start 357.409496 -275.206206)
		(end 357.40975 -275.206206)
		(stroke
			(width 0.05715)
			(type default)
		)
		(layer "In15.Cu")
	)
	(gr_line
		(start 357.447342 -289.19424)
		(end 357.437436 -289.187636)
		(stroke
			(width 0.05715)
			(type default)
		)
		(layer "In15.Cu")
	)
	(gr_line
		(start 357.469694 -292.220142)
		(end 357.468932 -292.219634)
		(stroke
			(width 0.05715)
			(type default)
		)
		(layer "In15.Cu")
	)
	(gr_line
		(start 357.469948 -288.980626)
		(end 357.465884 -288.978086)
		(stroke
			(width 0.05715)
			(type default)
		)
		(layer "In15.Cu")
	)
	(gr_line
		(start 357.470964 -292.220904)
		(end 357.469694 -292.220142)
		(stroke
			(width 0.05715)
			(type default)
		)
		(layer "In15.Cu")
	)
	(gr_line
		(start 357.471472 -280.881328)
		(end 357.469694 -280.880312)
		(stroke
			(width 0.05715)
			(type default)
		)
		(layer "In15.Cu")
	)
	(gr_line
		(start 357.471472 -269.541244)
		(end 357.470964 -269.54099)
		(stroke
			(width 0.05715)
			(type default)
		)
		(layer "In15.Cu")
	)
	(gr_line
		(start 357.47198 -292.221412)
		(end 357.470964 -292.220904)
		(stroke
			(width 0.05715)
			(type default)
		)
		(layer "In15.Cu")
	)
	(gr_line
		(start 357.472742 -292.22192)
		(end 357.47198 -292.221412)
		(stroke
			(width 0.05715)
			(type default)
		)
		(layer "In15.Cu")
	)
	(gr_line
		(start 357.472996 -269.542006)
		(end 357.471472 -269.541244)
		(stroke
			(width 0.05715)
			(type default)
		)
		(layer "In15.Cu")
	)
	(gr_line
		(start 357.477822 -269.544546)
		(end 357.477314 -269.544292)
		(stroke
			(width 0.05715)
			(type default)
		)
		(layer "In15.Cu")
	)
	(gr_line
		(start 357.479092 -288.986214)
		(end 357.473758 -288.982658)
		(stroke
			(width 0.05715)
			(type default)
		)
		(layer "In15.Cu")
	)
	(gr_line
		(start 357.481886 -291.585142)
		(end 357.484172 -291.583872)
		(stroke
			(width 0.05715)
			(type default)
		)
		(layer "In15.Cu")
	)
	(gr_line
		(start 357.481886 -289.96513)
		(end 357.484172 -289.96386)
		(stroke
			(width 0.05715)
			(type default)
		)
		(layer "In15.Cu")
	)
	(gr_line
		(start 357.482394 -292.227254)
		(end 357.481378 -292.226746)
		(stroke
			(width 0.05715)
			(type default)
		)
		(layer "In15.Cu")
	)
	(gr_line
		(start 357.482394 -269.547086)
		(end 357.477822 -269.544546)
		(stroke
			(width 0.05715)
			(type default)
		)
		(layer "In15.Cu")
	)
	(gr_line
		(start 357.484172 -280.888694)
		(end 357.481378 -280.886916)
		(stroke
			(width 0.05715)
			(type default)
		)
		(layer "In15.Cu")
	)
	(gr_line
		(start 357.484172 -269.548356)
		(end 357.483156 -269.547594)
		(stroke
			(width 0.05715)
			(type default)
		)
		(layer "In15.Cu")
	)
	(gr_line
		(start 357.48595 -292.229032)
		(end 357.48468 -292.22827)
		(stroke
			(width 0.05715)
			(type default)
		)
		(layer "In15.Cu")
	)
	(gr_line
		(start 357.487728 -292.230302)
		(end 357.486966 -292.229794)
		(stroke
			(width 0.05715)
			(type default)
		)
		(layer "In15.Cu")
	)
	(gr_line
		(start 357.48976 -293.200074)
		(end 357.493062 -293.198296)
		(stroke
			(width 0.05715)
			(type default)
		)
		(layer "In15.Cu")
	)
	(gr_line
		(start 357.491284 -269.55242)
		(end 357.489506 -269.551404)
		(stroke
			(width 0.05715)
			(type default)
		)
		(layer "In15.Cu")
	)
	(gr_line
		(start 357.492046 -269.552928)
		(end 357.491284 -269.55242)
		(stroke
			(width 0.05715)
			(type default)
		)
		(layer "In15.Cu")
	)
	(gr_line
		(start 357.493062 -293.198296)
		(end 357.493824 -293.197788)
		(stroke
			(width 0.05715)
			(type default)
		)
		(layer "In15.Cu")
	)
	(gr_line
		(start 357.494078 -292.23462)
		(end 357.487728 -292.230302)
		(stroke
			(width 0.05715)
			(type default)
		)
		(layer "In15.Cu")
	)
	(gr_arc
		(start 357.495348 -269.55496)
		(mid 357.495856 -269.555214)
		(end 357.496364 -269.555468)
		(stroke
			(width 0.05715)
			(type default)
		)
		(layer "In15.Cu")
	)
	(gr_line
		(start 357.49865 -292.237922)
		(end 357.495602 -292.235636)
		(stroke
			(width 0.05715)
			(type default)
		)
		(layer "In15.Cu")
	)
	(gr_line
		(start 357.50373 -288.331656)
		(end 357.506778 -288.329878)
		(stroke
			(width 0.05715)
			(type default)
		)
		(layer "In15.Cu")
	)
	(gr_line
		(start 357.504746 -280.231596)
		(end 357.505508 -280.231088)
		(stroke
			(width 0.05715)
			(type default)
		)
		(layer "In15.Cu")
	)
	(gr_line
		(start 357.504746 -275.37156)
		(end 357.505508 -275.371052)
		(stroke
			(width 0.05715)
			(type default)
		)
		(layer "In15.Cu")
	)
	(gr_line
		(start 357.514906 -293.185596)
		(end 357.523034 -293.18077)
		(stroke
			(width 0.05715)
			(type default)
		)
		(layer "In15.Cu")
	)
	(gr_line
		(start 357.514906 -289.945572)
		(end 357.518716 -289.943286)
		(stroke
			(width 0.05715)
			(type default)
		)
		(layer "In15.Cu")
	)
	(gr_line
		(start 357.51897 -282.528772)
		(end 357.51516 -282.526486)
		(stroke
			(width 0.05715)
			(type default)
		)
		(layer "In15.Cu")
	)
	(gr_line
		(start 357.519986 -289.942524)
		(end 357.523034 -289.940746)
		(stroke
			(width 0.05715)
			(type default)
		)
		(layer "In15.Cu")
	)
	(gr_line
		(start 357.520494 -282.529788)
		(end 357.51897 -282.528772)
		(stroke
			(width 0.05715)
			(type default)
		)
		(layer "In15.Cu")
	)
	(gr_line
		(start 357.52278 -293.181024)
		(end 357.531162 -293.175182)
		(stroke
			(width 0.05715)
			(type default)
		)
		(layer "In15.Cu")
	)
	(gr_line
		(start 357.52278 -289.941)
		(end 357.52786 -289.937444)
		(stroke
			(width 0.05715)
			(type default)
		)
		(layer "In15.Cu")
	)
	(gr_line
		(start 357.523034 -293.18077)
		(end 357.52278 -293.181024)
		(stroke
			(width 0.05715)
			(type default)
		)
		(layer "In15.Cu")
	)
	(gr_line
		(start 357.523034 -289.940746)
		(end 357.52278 -289.941)
		(stroke
			(width 0.05715)
			(type default)
		)
		(layer "In15.Cu")
	)
	(gr_line
		(start 357.528622 -289.936936)
		(end 357.532178 -289.934396)
		(stroke
			(width 0.05715)
			(type default)
		)
		(layer "In15.Cu")
	)
	(gr_line
		(start 357.532178 -289.934396)
		(end 357.537004 -289.93084)
		(stroke
			(width 0.05715)
			(type default)
		)
		(layer "In15.Cu")
	)
	(gr_arc
		(start 357.534718 -282.539694)
		(mid 357.527644 -282.534686)
		(end 357.520494 -282.529788)
		(stroke
			(width 0.05715)
			(type default)
		)
		(layer "In15.Cu")
	)
	(gr_line
		(start 357.537004 -289.93084)
		(end 357.537766 -289.930332)
		(stroke
			(width 0.05715)
			(type default)
		)
		(layer "In15.Cu")
	)
	(gr_line
		(start 357.537766 -289.930332)
		(end 357.539036 -289.929316)
		(stroke
			(width 0.05715)
			(type default)
		)
		(layer "In15.Cu")
	)
	(gr_line
		(start 357.553768 -289.03422)
		(end 357.55072 -289.032696)
		(stroke
			(width 0.05715)
			(type default)
		)
		(layer "In15.Cu")
	)
	(gr_arc
		(start 357.559356 -289.038538)
		(mid 357.556569 -289.03637)
		(end 357.553768 -289.03422)
		(stroke
			(width 0.05715)
			(type default)
		)
		(layer "In15.Cu")
	)
	(gr_line
		(start 357.575612 -287.856168)
		(end 357.575866 -287.856422)
		(stroke
			(width 0.05715)
			(type default)
		)
		(layer "In15.Cu")
	)
	(gr_line
		(start 357.575866 -271.647666)
		(end 357.575866 -271.646396)
		(stroke
			(width 0.05715)
			(type default)
		)
		(layer "In15.Cu")
	)
	(gr_arc
		(start 357.577136 -289.052762)
		(mid 357.569195 -289.046211)
		(end 357.561134 -289.039808)
		(stroke
			(width 0.05715)
			(type default)
		)
		(layer "In15.Cu")
	)
	(gr_line
		(start 357.57866 -289.054032)
		(end 357.579422 -289.05454)
		(stroke
			(width 0.05715)
			(type default)
		)
		(layer "In15.Cu")
	)
	(gr_line
		(start 357.579676 -271.692116)
		(end 357.579422 -271.690846)
		(stroke
			(width 0.05715)
			(type default)
		)
		(layer "In15.Cu")
	)
	(gr_line
		(start 357.766366 -286.229552)
		(end 357.766366 -286.236156)
		(stroke
			(width 0.05715)
			(type default)
		)
		(layer "In15.Cu")
	)
	(gr_line
		(start 357.85806 -270.523462)
		(end 357.85806 -270.523208)
		(stroke
			(width 0.05715)
			(type default)
		)
		(layer "In15.Cu")
	)
	(gr_line
		(start 357.858822 -270.52397)
		(end 357.85806 -270.523462)
		(stroke
			(width 0.05715)
			(type default)
		)
		(layer "In15.Cu")
	)
	(gr_line
		(start 357.954072 -270.358616)
		(end 357.95331 -270.358108)
		(stroke
			(width 0.05715)
			(type default)
		)
		(layer "In15.Cu")
	)
	(gr_line
		(start 357.955088 -270.359124)
		(end 357.954072 -270.358616)
		(stroke
			(width 0.05715)
			(type default)
		)
		(layer "In15.Cu")
	)
	(gr_line
		(start 357.95712 -270.36014)
		(end 357.955088 -270.359124)
		(stroke
			(width 0.05715)
			(type default)
		)
		(layer "In15.Cu")
	)
	(gr_line
		(start 357.959152 -270.36141)
		(end 357.95839 -270.360902)
		(stroke
			(width 0.05715)
			(type default)
		)
		(layer "In15.Cu")
	)
	(gr_line
		(start 357.985568 -270.376904)
		(end 357.984806 -270.376396)
		(stroke
			(width 0.05715)
			(type default)
		)
		(layer "In15.Cu")
	)
	(gr_line
		(start 357.98633 -270.377412)
		(end 357.985568 -270.376904)
		(stroke
			(width 0.05715)
			(type default)
		)
		(layer "In15.Cu")
	)
	(gr_line
		(start 357.993188 -270.381476)
		(end 357.98633 -270.377412)
		(stroke
			(width 0.05715)
			(type default)
		)
		(layer "In15.Cu")
	)
	(gr_line
		(start 358.000046 -295.841928)
		(end 358.000046 -295.81348)
		(stroke
			(width 0.05715)
			(type default)
		)
		(layer "In15.Cu")
	)
	(gr_line
		(start 358.000046 -295.81348)
		(end 358.045766 -295.76776)
		(stroke
			(width 0.05715)
			(type default)
		)
		(layer "In15.Cu")
	)
	(gr_arc
		(start 358.001062 -270.387064)
		(mid 357.997137 -270.384253)
		(end 357.993188 -270.381476)
		(stroke
			(width 0.05715)
			(type default)
		)
		(layer "In15.Cu")
	)
	(gr_line
		(start 358.281986 -295.841928)
		(end 358.281986 -295.81348)
		(stroke
			(width 0.05715)
			(type default)
		)
		(layer "In15.Cu")
	)
	(gr_line
		(start 358.281986 -295.81348)
		(end 358.236266 -295.76776)
		(stroke
			(width 0.05715)
			(type default)
		)
		(layer "In15.Cu")
	)
	(gr_arc
		(start 358.282748 -290.745926)
		(mid 358.285156 -290.747711)
		(end 358.287574 -290.749482)
		(stroke
			(width 0.05715)
			(type default)
		)
		(layer "In15.Cu")
	)
	(gr_arc
		(start 358.282748 -276.166072)
		(mid 358.285915 -276.168369)
		(end 358.289098 -276.170644)
		(stroke
			(width 0.05715)
			(type default)
		)
		(layer "In15.Cu")
	)
	(gr_arc
		(start 358.282748 -274.54606)
		(mid 358.285915 -274.548357)
		(end 358.289098 -274.550632)
		(stroke
			(width 0.05715)
			(type default)
		)
		(layer "In15.Cu")
	)
	(gr_arc
		(start 358.287574 -283.342588)
		(mid 358.285156 -283.34436)
		(end 358.282748 -283.346144)
		(stroke
			(width 0.05715)
			(type default)
		)
		(layer "In15.Cu")
	)
	(gr_arc
		(start 358.288336 -283.34208)
		(mid 358.288717 -283.341826)
		(end 358.289098 -283.341572)
		(stroke
			(width 0.05715)
			(type default)
		)
		(layer "In15.Cu")
	)
	(gr_arc
		(start 358.289098 -294.681402)
		(mid 358.285788 -294.683677)
		(end 358.282494 -294.685974)
		(stroke
			(width 0.05715)
			(type default)
		)
		(layer "In15.Cu")
	)
	(gr_line
		(start 358.289098 -283.341572)
		(end 358.289606 -283.341318)
		(stroke
			(width 0.05715)
			(type default)
		)
		(layer "In15.Cu")
	)
	(gr_arc
		(start 358.289098 -276.170644)
		(mid 358.28986 -276.171153)
		(end 358.290622 -276.17166)
		(stroke
			(width 0.05715)
			(type default)
		)
		(layer "In15.Cu")
	)
	(gr_arc
		(start 358.289098 -274.550632)
		(mid 358.28986 -274.551141)
		(end 358.290622 -274.551648)
		(stroke
			(width 0.05715)
			(type default)
		)
		(layer "In15.Cu")
	)
	(gr_line
		(start 358.289606 -283.341318)
		(end 358.298496 -283.335984)
		(stroke
			(width 0.05715)
			(type default)
		)
		(layer "In15.Cu")
	)
	(gr_arc
		(start 358.290622 -294.680386)
		(mid 358.28986 -294.680893)
		(end 358.289098 -294.681402)
		(stroke
			(width 0.05715)
			(type default)
		)
		(layer "In15.Cu")
	)
	(gr_line
		(start 358.290622 -294.680386)
		(end 358.29748 -294.676322)
		(stroke
			(width 0.05715)
			(type default)
		)
		(layer "In15.Cu")
	)
	(gr_line
		(start 358.296718 -274.555204)
		(end 358.290622 -274.551648)
		(stroke
			(width 0.05715)
			(type default)
		)
		(layer "In15.Cu")
	)
	(gr_line
		(start 358.299512 -276.17674)
		(end 358.290622 -276.17166)
		(stroke
			(width 0.05715)
			(type default)
		)
		(layer "In15.Cu")
	)
	(gr_arc
		(start 358.315514 -294.006016)
		(mid 358.317544 -294.007163)
		(end 358.319578 -294.008302)
		(stroke
			(width 0.05715)
			(type default)
		)
		(layer "In15.Cu")
	)
	(gr_line
		(start 358.324912 -288.180526)
		(end 358.328214 -288.178494)
		(stroke
			(width 0.05715)
			(type default)
		)
		(layer "In15.Cu")
	)
	(gr_line
		(start 358.32796 -293.038784)
		(end 358.328214 -293.03853)
		(stroke
			(width 0.05715)
			(type default)
		)
		(layer "In15.Cu")
	)
	(gr_line
		(start 358.328214 -294.013382)
		(end 358.32796 -294.013382)
		(stroke
			(width 0.05715)
			(type default)
		)
		(layer "In15.Cu")
	)
	(gr_line
		(start 358.328468 -279.433782)
		(end 358.32796 -279.433528)
		(stroke
			(width 0.05715)
			(type default)
		)
		(layer "In15.Cu")
	)
	(gr_line
		(start 358.328468 -276.193758)
		(end 358.327706 -276.19325)
		(stroke
			(width 0.05715)
			(type default)
		)
		(layer "In15.Cu")
	)
	(gr_line
		(start 358.328976 -285.91383)
		(end 358.32796 -285.913322)
		(stroke
			(width 0.05715)
			(type default)
		)
		(layer "In15.Cu")
	)
	(gr_line
		(start 358.329738 -278.463502)
		(end 358.329992 -278.463502)
		(stroke
			(width 0.05715)
			(type default)
		)
		(layer "In15.Cu")
	)
	(gr_arc
		(start 358.368346 -286.534098)
		(mid 358.369236 -286.533337)
		(end 358.370124 -286.532574)
		(stroke
			(width 0.05715)
			(type default)
		)
		(layer "In15.Cu")
	)
	(gr_line
		(start 358.393238 -294.841168)
		(end 358.393492 -294.841168)
		(stroke
			(width 0.05715)
			(type default)
		)
		(layer "In15.Cu")
	)
	(gr_line
		(start 358.393492 -272.7706)
		(end 358.393492 -272.770854)
		(stroke
			(width 0.05715)
			(type default)
		)
		(layer "In15.Cu")
	)
	(gr_line
		(start 358.403144 -279.25649)
		(end 358.401112 -279.255474)
		(stroke
			(width 0.05715)
			(type default)
		)
		(layer "In15.Cu")
	)
	(gr_line
		(start 358.403144 -276.016466)
		(end 358.401112 -276.015196)
		(stroke
			(width 0.05715)
			(type default)
		)
		(layer "In15.Cu")
	)
	(gr_line
		(start 358.417368 -280.247344)
		(end 358.417876 -280.24709)
		(stroke
			(width 0.05715)
			(type default)
		)
		(layer "In15.Cu")
	)
	(gr_line
		(start 358.417368 -277.00732)
		(end 358.417876 -277.007066)
		(stroke
			(width 0.05715)
			(type default)
		)
		(layer "In15.Cu")
	)
	(gr_line
		(start 358.417876 -280.24709)
		(end 358.42194 -280.244804)
		(stroke
			(width 0.05715)
			(type default)
		)
		(layer "In15.Cu")
	)
	(gr_line
		(start 358.417876 -277.007066)
		(end 358.42194 -277.00478)
		(stroke
			(width 0.05715)
			(type default)
		)
		(layer "In15.Cu")
	)
	(gr_line
		(start 358.423972 -280.243534)
		(end 358.42448 -280.243026)
		(stroke
			(width 0.05715)
			(type default)
		)
		(layer "In15.Cu")
	)
	(gr_line
		(start 358.423972 -277.00351)
		(end 358.42448 -277.003002)
		(stroke
			(width 0.05715)
			(type default)
		)
		(layer "In15.Cu")
	)
	(gr_line
		(start 358.424226 -285.748984)
		(end 358.424226 -285.74873)
		(stroke
			(width 0.05715)
			(type default)
		)
		(layer "In15.Cu")
	)
	(gr_line
		(start 358.424226 -285.74873)
		(end 358.423972 -285.74873)
		(stroke
			(width 0.05715)
			(type default)
		)
		(layer "In15.Cu")
	)
	(gr_line
		(start 358.445308 -293.19093)
		(end 358.445562 -293.19093)
		(stroke
			(width 0.05715)
			(type default)
		)
		(layer "In15.Cu")
	)
	(gr_line
		(start 358.455722 -293.184834)
		(end 358.456484 -293.184326)
		(stroke
			(width 0.05715)
			(type default)
		)
		(layer "In15.Cu")
	)
	(gr_line
		(start 358.456484 -293.184326)
		(end 358.463088 -293.180516)
		(stroke
			(width 0.05715)
			(type default)
		)
		(layer "In15.Cu")
	)
	(gr_line
		(start 358.461564 -293.87038)
		(end 358.45623 -293.867332)
		(stroke
			(width 0.05715)
			(type default)
		)
		(layer "In15.Cu")
	)
	(gr_arc
		(start 358.463088 -293.871396)
		(mid 358.462326 -293.870887)
		(end 358.461564 -293.87038)
		(stroke
			(width 0.05715)
			(type default)
		)
		(layer "In15.Cu")
	)
	(gr_arc
		(start 358.463088 -293.180516)
		(mid 358.464232 -293.179756)
		(end 358.465374 -293.178992)
		(stroke
			(width 0.05715)
			(type default)
		)
		(layer "In15.Cu")
	)
	(gr_arc
		(start 358.466136 -293.178484)
		(mid 358.468937 -293.176461)
		(end 358.471724 -293.17442)
		(stroke
			(width 0.05715)
			(type default)
		)
		(layer "In15.Cu")
	)
	(gr_line
		(start 358.468676 -293.875206)
		(end 358.463088 -293.871396)
		(stroke
			(width 0.05715)
			(type default)
		)
		(layer "In15.Cu")
	)
	(gr_arc
		(start 358.480868 -285.067756)
		(mid 358.482521 -285.066489)
		(end 358.48417 -285.065216)
		(stroke
			(width 0.05715)
			(type default)
		)
		(layer "In15.Cu")
	)
	(gr_arc
		(start 358.48417 -285.065216)
		(mid 358.485696 -285.063949)
		(end 358.487218 -285.062676)
		(stroke
			(width 0.05715)
			(type default)
		)
		(layer "In15.Cu")
	)
	(gr_line
		(start 358.51338 -273.232372)
		(end 358.51338 -273.233134)
		(stroke
			(width 0.05715)
			(type default)
		)
		(layer "In15.Cu")
	)
	(gr_line
		(start 358.515412 -292.72992)
		(end 358.515412 -292.728904)
		(stroke
			(width 0.05715)
			(type default)
		)
		(layer "In15.Cu")
	)
	(gr_line
		(start 358.515412 -274.910042)
		(end 358.515412 -274.909026)
		(stroke
			(width 0.05715)
			(type default)
		)
		(layer "In15.Cu")
	)
	(gr_line
		(start 358.51592 -273.27606)
		(end 358.515666 -273.27606)
		(stroke
			(width 0.05715)
			(type default)
		)
		(layer "In15.Cu")
	)
	(gr_arc
		(start 358.704896 -287.870392)
		(mid 358.705556 -287.864426)
		(end 358.706166 -287.858454)
		(stroke
			(width 0.05715)
			(type default)
		)
		(layer "In15.Cu")
	)
	(gr_arc
		(start 358.705912 -292.737032)
		(mid 358.706051 -292.733476)
		(end 358.706166 -292.72992)
		(stroke
			(width 0.05715)
			(type default)
		)
		(layer "In15.Cu")
	)
	(gr_arc
		(start 358.705912 -274.917154)
		(mid 358.706051 -274.913598)
		(end 358.706166 -274.910042)
		(stroke
			(width 0.05715)
			(type default)
		)
		(layer "In15.Cu")
	)
	(gr_line
		(start 358.706166 -287.845246)
		(end 358.706166 -287.858454)
		(stroke
			(width 0.05715)
			(type default)
		)
		(layer "In15.Cu")
	)
	(gr_line
		(start 358.70642 -292.71595)
		(end 358.706166 -292.71595)
		(stroke
			(width 0.05715)
			(type default)
		)
		(layer "In15.Cu")
	)
	(gr_line
		(start 358.70642 -274.896072)
		(end 358.706166 -274.896072)
		(stroke
			(width 0.05715)
			(type default)
		)
		(layer "In15.Cu")
	)
	(gr_line
		(start 358.880918 -271.938496)
		(end 358.880918 -271.874234)
		(stroke
			(width 0.05715)
			(type default)
		)
		(layer "In15.Cu")
	)
	(gr_line
		(start 358.900984 -271.958562)
		(end 358.880918 -271.938496)
		(stroke
			(width 0.05715)
			(type default)
		)
		(layer "In15.Cu")
	)
	(gr_line
		(start 359.016046 -271.739106)
		(end 359.015792 -271.738852)
		(stroke
			(width 0.05715)
			(type default)
		)
		(layer "In15.Cu")
	)
	(gr_line
		(start 359.080308 -271.739106)
		(end 359.016046 -271.739106)
		(stroke
			(width 0.05715)
			(type default)
		)
		(layer "In15.Cu")
	)
	(gr_line
		(start 359.100374 -271.759172)
		(end 359.080308 -271.739106)
		(stroke
			(width 0.05715)
			(type default)
		)
		(layer "In15.Cu")
	)
	(gr_line
		(start 359.132886 -274.811236)
		(end 359.132886 -274.806918)
		(stroke
			(width 0.07112)
			(type default)
		)
		(layer "In15.Cu")
	)
	(gr_arc
		(start 364.300008 -315.847476)
		(mid 364.298631 -315.845052)
		(end 364.297214 -315.84265)
		(stroke
			(width 0.07112)
			(type default)
		)
		(layer "In15.Cu")
	)
	(gr_line
		(start 364.53953 -315.698124)
		(end 364.538514 -315.696346)
		(stroke
			(width 0.07112)
			(type default)
		)
		(layer "In15.Cu")
	)
	(gr_arc
		(start 364.5408 -315.70041)
		(mid 364.540166 -315.699266)
		(end 364.53953 -315.698124)
		(stroke
			(width 0.07112)
			(type default)
		)
		(layer "In15.Cu")
	)
	(gr_line
		(start 364.810802 -2.969006)
		(end 364.519972 -2.678176)
		(stroke
			(width 0.07112)
			(type default)
		)
		(layer "In15.Cu")
	)
	(gr_line
		(start 364.810802 -2.105406)
		(end 364.519972 -2.396236)
		(stroke
			(width 0.07112)
			(type default)
		)
		(layer "In15.Cu")
	)
	(gr_line
		(start 367.563908 -221.420436)
		(end 367.563908 -221.391988)
		(stroke
			(width 0.05715)
			(type default)
		)
		(layer "In15.Cu")
	)
	(gr_line
		(start 367.609628 -221.466156)
		(end 367.563908 -221.420436)
		(stroke
			(width 0.05715)
			(type default)
		)
		(layer "In15.Cu")
	)
	(gr_line
		(start 367.800128 -221.466156)
		(end 367.845848 -221.420436)
		(stroke
			(width 0.05715)
			(type default)
		)
		(layer "In15.Cu")
	)
	(gr_line
		(start 367.845848 -221.420436)
		(end 367.845848 -221.391988)
		(stroke
			(width 0.05715)
			(type default)
		)
		(layer "In15.Cu")
	)
	(gr_arc
		(start 367.87074 -222.023432)
		(mid 367.871753 -222.024704)
		(end 367.872772 -222.025972)
		(stroke
			(width 0.05715)
			(type default)
		)
		(layer "In15.Cu")
	)
	(gr_arc
		(start 367.872772 -222.025972)
		(mid 367.873785 -222.027371)
		(end 367.874804 -222.028766)
		(stroke
			(width 0.05715)
			(type default)
		)
		(layer "In15.Cu")
	)
	(gr_line
		(start 367.885726 -222.288354)
		(end 367.88598 -222.2881)
		(stroke
			(width 0.05715)
			(type default)
		)
		(layer "In15.Cu")
	)
	(gr_line
		(start 367.888266 -222.289624)
		(end 367.885726 -222.288354)
		(stroke
			(width 0.05715)
			(type default)
		)
		(layer "In15.Cu")
	)
	(gr_line
		(start 367.891822 -222.292164)
		(end 367.888266 -222.289624)
		(stroke
			(width 0.05715)
			(type default)
		)
		(layer "In15.Cu")
	)
	(gr_line
		(start 367.987072 -222.126302)
		(end 367.984278 -222.124778)
		(stroke
			(width 0.05715)
			(type default)
		)
		(layer "In15.Cu")
	)
	(gr_line
		(start 367.987834 -222.12681)
		(end 367.987072 -222.126302)
		(stroke
			(width 0.05715)
			(type default)
		)
		(layer "In15.Cu")
	)
	(gr_line
		(start 367.98885 -222.127318)
		(end 367.987834 -222.12681)
		(stroke
			(width 0.05715)
			(type default)
		)
		(layer "In15.Cu")
	)
	(gr_line
		(start 367.995454 -222.131382)
		(end 367.98885 -222.127318)
		(stroke
			(width 0.05715)
			(type default)
		)
		(layer "In15.Cu")
	)
	(gr_arc
		(start 368.372898 -223.107758)
		(mid 368.37404 -223.108394)
		(end 368.375184 -223.109028)
		(stroke
			(width 0.05715)
			(type default)
		)
		(layer "In15.Cu")
	)
	(gr_arc
		(start 368.62893 -385.007358)
		(mid 368.628676 -385.007358)
		(end 368.628422 -385.007358)
		(stroke
			(width 0.07112)
			(type default)
		)
		(layer "In15.Cu")
	)
	(gr_arc
		(start 369.914932 -223.775524)
		(mid 369.915313 -223.775778)
		(end 369.915694 -223.776032)
		(stroke
			(width 0.05715)
			(type default)
		)
		(layer "In15.Cu")
	)
	(gr_line
		(start 370.054886 -225.044254)
		(end 370.352828 -225.044254)
		(stroke
			(width 0.05715)
			(type default)
		)
		(layer "In15.Cu")
	)
	(gr_line
		(start 370.352828 -225.044254)
		(end 370.422678 -225.07321)
		(stroke
			(width 0.05715)
			(type default)
		)
		(layer "In15.Cu")
	)
	(gr_line
		(start 370.383816 -221.39783)
		(end 370.383816 -221.369382)
		(stroke
			(width 0.05715)
			(type default)
		)
		(layer "In15.Cu")
	)
	(gr_arc
		(start 370.422678 -225.07321)
		(mid 370.404491 -224.919733)
		(end 370.325396 -224.786952)
		(stroke
			(width 0.05715)
			(type default)
		)
		(layer "In15.Cu")
	)
	(gr_line
		(start 370.429536 -221.44355)
		(end 370.383816 -221.39783)
		(stroke
			(width 0.05715)
			(type default)
		)
		(layer "In15.Cu")
	)
	(gr_arc
		(start 370.61394 -224.96145)
		(mid 370.563091 -224.797068)
		(end 370.465096 -224.655634)
		(stroke
			(width 0.05715)
			(type default)
		)
		(layer "In15.Cu")
	)
	(gr_line
		(start 370.620036 -221.44355)
		(end 370.665756 -221.39783)
		(stroke
			(width 0.05715)
			(type default)
		)
		(layer "In15.Cu")
	)
	(gr_line
		(start 370.665756 -221.39783)
		(end 370.665756 -221.369382)
		(stroke
			(width 0.05715)
			(type default)
		)
		(layer "In15.Cu")
	)
	(gr_line
		(start 370.696744 -225.044254)
		(end 370.61394 -224.96145)
		(stroke
			(width 0.05715)
			(type default)
		)
		(layer "In15.Cu")
	)
	(gr_line
		(start 370.70919 -222.290132)
		(end 370.708428 -222.289624)
		(stroke
			(width 0.05715)
			(type default)
		)
		(layer "In15.Cu")
	)
	(gr_line
		(start 370.712238 -222.29191)
		(end 370.70919 -222.290132)
		(stroke
			(width 0.05715)
			(type default)
		)
		(layer "In15.Cu")
	)
	(gr_line
		(start 370.805456 -222.12554)
		(end 370.80444 -222.125032)
		(stroke
			(width 0.05715)
			(type default)
		)
		(layer "In15.Cu")
	)
	(gr_line
		(start 370.994686 -225.044254)
		(end 370.696744 -225.044254)
		(stroke
			(width 0.05715)
			(type default)
		)
		(layer "In15.Cu")
	)
	(gr_line
		(start 370.994686 -223.424242)
		(end 371.292628 -223.424242)
		(stroke
			(width 0.05715)
			(type default)
		)
		(layer "In15.Cu")
	)
	(gr_line
		(start 371.292628 -223.424242)
		(end 371.36197 -223.3549)
		(stroke
			(width 0.05715)
			(type default)
		)
		(layer "In15.Cu")
	)
	(gr_arc
		(start 371.553994 -223.341438)
		(mid 371.552202 -223.330116)
		(end 371.550184 -223.318832)
		(stroke
			(width 0.05715)
			(type default)
		)
		(layer "In15.Cu")
	)
	(gr_line
		(start 371.636798 -223.424242)
		(end 371.553994 -223.341438)
		(stroke
			(width 0.05715)
			(type default)
		)
		(layer "In15.Cu")
	)
	(gr_line
		(start 371.93474 -223.424242)
		(end 371.636798 -223.424242)
		(stroke
			(width 0.05715)
			(type default)
		)
		(layer "In15.Cu")
	)
	(gr_line
		(start 373.51589 -419.607238)
		(end 373.515636 -419.607238)
		(stroke
			(width 0.07112)
			(type default)
		)
		(layer "In15.Cu")
	)
	(gr_line
		(start 374.248172 -417.590224)
		(end 374.248172 -416.889184)
		(stroke
			(width 0.07112)
			(type default)
		)
		(layer "In15.Cu")
	)
	(gr_line
		(start 374.248172 -416.462464)
		(end 374.248172 -415.761424)
		(stroke
			(width 0.07112)
			(type default)
		)
		(layer "In15.Cu")
	)
	(gr_line
		(start 374.531382 -417.588954)
		(end 374.667272 -417.453064)
		(stroke
			(width 0.07112)
			(type default)
		)
		(layer "In15.Cu")
	)
	(gr_line
		(start 374.531382 -416.461194)
		(end 374.667272 -416.325304)
		(stroke
			(width 0.07112)
			(type default)
		)
		(layer "In15.Cu")
	)
	(gr_line
		(start 374.667272 -417.453064)
		(end 374.667272 -417.026344)
		(stroke
			(width 0.07112)
			(type default)
		)
		(layer "In15.Cu")
	)
	(gr_line
		(start 374.667272 -417.026344)
		(end 374.531382 -416.890454)
		(stroke
			(width 0.07112)
			(type default)
		)
		(layer "In15.Cu")
	)
	(gr_line
		(start 374.667272 -416.325304)
		(end 374.667272 -415.898584)
		(stroke
			(width 0.07112)
			(type default)
		)
		(layer "In15.Cu")
	)
	(gr_line
		(start 374.667272 -415.898584)
		(end 374.531382 -415.762694)
		(stroke
			(width 0.07112)
			(type default)
		)
		(layer "In15.Cu")
	)
	(gr_line
		(start 374.826022 -423.95521)
		(end 374.633744 -423.95521)
		(stroke
			(width 0.07112)
			(type default)
		)
		(layer "In15.Cu")
	)
	(gr_line
		(start 374.928638 -424.650662)
		(end 374.432576 -424.1546)
		(stroke
			(width 0.07112)
			(type default)
		)
		(layer "In15.Cu")
	)
	(gr_line
		(start 375.128028 -424.449494)
		(end 375.128028 -424.257216)
		(stroke
			(width 0.07112)
			(type default)
		)
		(layer "In15.Cu")
	)
	(gr_line
		(start 375.128028 -424.257216)
		(end 374.826022 -423.95521)
		(stroke
			(width 0.07112)
			(type default)
		)
		(layer "In15.Cu")
	)
	(gr_line
		(start 375.623328 -424.75277)
		(end 375.431304 -424.75277)
		(stroke
			(width 0.07112)
			(type default)
		)
		(layer "In15.Cu")
	)
	(gr_line
		(start 375.725944 -425.447968)
		(end 375.230136 -424.95216)
		(stroke
			(width 0.07112)
			(type default)
		)
		(layer "In15.Cu")
	)
	(gr_line
		(start 375.925334 -425.2468)
		(end 375.925334 -425.054776)
		(stroke
			(width 0.07112)
			(type default)
		)
		(layer "In15.Cu")
	)
	(gr_line
		(start 375.925334 -425.054776)
		(end 375.623328 -424.75277)
		(stroke
			(width 0.07112)
			(type default)
		)
		(layer "In15.Cu")
	)
	(gr_line
		(start 376.420888 -425.550076)
		(end 376.22861 -425.550076)
		(stroke
			(width 0.07112)
			(type default)
		)
		(layer "In15.Cu")
	)
	(gr_line
		(start 376.523504 -426.245528)
		(end 376.027442 -425.749466)
		(stroke
			(width 0.07112)
			(type default)
		)
		(layer "In15.Cu")
	)
	(gr_line
		(start 376.722894 -426.04436)
		(end 376.722894 -425.852082)
		(stroke
			(width 0.07112)
			(type default)
		)
		(layer "In15.Cu")
	)
	(gr_line
		(start 376.722894 -425.852082)
		(end 376.420888 -425.550076)
		(stroke
			(width 0.07112)
			(type default)
		)
		(layer "In15.Cu")
	)
	(gr_line
		(start 377.246642 -422.273476)
		(end 377.073668 -422.357296)
		(stroke
			(width 0.07112)
			(type default)
		)
		(layer "In15.Cu")
	)
	(gr_line
		(start 377.311412 -417.684458)
		(end 377.311412 -416.983418)
		(stroke
			(width 0.07112)
			(type default)
		)
		(layer "In15.Cu")
	)
	(gr_line
		(start 377.311412 -416.487102)
		(end 377.311412 -415.786062)
		(stroke
			(width 0.07112)
			(type default)
		)
		(layer "In15.Cu")
	)
	(gr_line
		(start 377.594622 -417.683188)
		(end 377.730512 -417.547298)
		(stroke
			(width 0.07112)
			(type default)
		)
		(layer "In15.Cu")
	)
	(gr_line
		(start 377.594622 -416.485832)
		(end 377.730512 -416.349942)
		(stroke
			(width 0.07112)
			(type default)
		)
		(layer "In15.Cu")
	)
	(gr_line
		(start 377.64212 -422.854882)
		(end 376.979434 -422.624504)
		(stroke
			(width 0.07112)
			(type default)
		)
		(layer "In15.Cu")
	)
	(gr_line
		(start 377.649994 -422.413684)
		(end 377.246642 -422.273476)
		(stroke
			(width 0.07112)
			(type default)
		)
		(layer "In15.Cu")
	)
	(gr_line
		(start 377.713494 -426.842682)
		(end 377.521216 -426.842682)
		(stroke
			(width 0.07112)
			(type default)
		)
		(layer "In15.Cu")
	)
	(gr_line
		(start 377.730512 -417.547298)
		(end 377.730512 -417.120578)
		(stroke
			(width 0.07112)
			(type default)
		)
		(layer "In15.Cu")
	)
	(gr_line
		(start 377.730512 -417.120578)
		(end 377.594622 -416.984688)
		(stroke
			(width 0.07112)
			(type default)
		)
		(layer "In15.Cu")
	)
	(gr_line
		(start 377.730512 -416.349942)
		(end 377.730512 -415.923222)
		(stroke
			(width 0.07112)
			(type default)
		)
		(layer "In15.Cu")
	)
	(gr_line
		(start 377.730512 -415.923222)
		(end 377.594622 -415.787332)
		(stroke
			(width 0.07112)
			(type default)
		)
		(layer "In15.Cu")
	)
	(gr_line
		(start 377.733814 -422.587166)
		(end 377.649994 -422.413684)
		(stroke
			(width 0.07112)
			(type default)
		)
		(layer "In15.Cu")
	)
	(gr_line
		(start 377.81611 -427.538134)
		(end 377.320048 -427.042072)
		(stroke
			(width 0.07112)
			(type default)
		)
		(layer "In15.Cu")
	)
	(gr_line
		(start 378.0155 -427.336966)
		(end 378.0155 -427.144688)
		(stroke
			(width 0.07112)
			(type default)
		)
		(layer "In15.Cu")
	)
	(gr_line
		(start 378.0155 -427.144688)
		(end 377.713494 -426.842682)
		(stroke
			(width 0.07112)
			(type default)
		)
		(layer "In15.Cu")
	)
	(gr_line
		(start 378.320046 -422.646856)
		(end 378.146818 -422.730676)
		(stroke
			(width 0.07112)
			(type default)
		)
		(layer "In15.Cu")
	)
	(gr_line
		(start 378.511054 -427.640242)
		(end 378.318776 -427.640242)
		(stroke
			(width 0.07112)
			(type default)
		)
		(layer "In15.Cu")
	)
	(gr_line
		(start 378.61367 -428.335694)
		(end 378.117608 -427.839632)
		(stroke
			(width 0.07112)
			(type default)
		)
		(layer "In15.Cu")
	)
	(gr_line
		(start 378.715016 -423.228262)
		(end 378.052584 -422.997884)
		(stroke
			(width 0.07112)
			(type default)
		)
		(layer "In15.Cu")
	)
	(gr_line
		(start 378.723144 -422.787064)
		(end 378.320046 -422.646856)
		(stroke
			(width 0.07112)
			(type default)
		)
		(layer "In15.Cu")
	)
	(gr_line
		(start 378.807218 -422.960546)
		(end 378.723144 -422.787064)
		(stroke
			(width 0.07112)
			(type default)
		)
		(layer "In15.Cu")
	)
	(gr_line
		(start 378.81306 -428.134526)
		(end 378.81306 -427.942248)
		(stroke
			(width 0.07112)
			(type default)
		)
		(layer "In15.Cu")
	)
	(gr_line
		(start 378.81306 -427.942248)
		(end 378.511054 -427.640242)
		(stroke
			(width 0.07112)
			(type default)
		)
		(layer "In15.Cu")
	)
	(gr_line
		(start 378.85624 -410.270198)
		(end 379.495304 -409.981146)
		(stroke
			(width 0.07112)
			(type default)
		)
		(layer "In15.Cu")
	)
	(gr_line
		(start 378.973842 -410.527754)
		(end 379.153674 -410.595826)
		(stroke
			(width 0.07112)
			(type default)
		)
		(layer "In15.Cu")
	)
	(gr_line
		(start 379.153674 -410.595826)
		(end 379.542802 -410.420058)
		(stroke
			(width 0.07112)
			(type default)
		)
		(layer "In15.Cu")
	)
	(gr_line
		(start 379.30836 -428.437802)
		(end 379.116336 -428.437802)
		(stroke
			(width 0.07112)
			(type default)
		)
		(layer "In15.Cu")
	)
	(gr_line
		(start 379.410976 -429.133)
		(end 378.915168 -428.637192)
		(stroke
			(width 0.07112)
			(type default)
		)
		(layer "In15.Cu")
	)
	(gr_line
		(start 379.542802 -410.420058)
		(end 379.610874 -410.239972)
		(stroke
			(width 0.07112)
			(type default)
		)
		(layer "In15.Cu")
	)
	(gr_line
		(start 379.610366 -428.931832)
		(end 379.610366 -428.739808)
		(stroke
			(width 0.07112)
			(type default)
		)
		(layer "In15.Cu")
	)
	(gr_line
		(start 379.610366 -428.739808)
		(end 379.30836 -428.437802)
		(stroke
			(width 0.07112)
			(type default)
		)
		(layer "In15.Cu")
	)
	(gr_line
		(start 380.374652 -418.07638)
		(end 380.374652 -417.37534)
		(stroke
			(width 0.07112)
			(type default)
		)
		(layer "In15.Cu")
	)
	(gr_line
		(start 380.374652 -416.94862)
		(end 380.374652 -416.24758)
		(stroke
			(width 0.07112)
			(type default)
		)
		(layer "In15.Cu")
	)
	(gr_line
		(start 380.522226 -423.323258)
		(end 380.355094 -423.418508)
		(stroke
			(width 0.07112)
			(type default)
		)
		(layer "In15.Cu")
	)
	(gr_line
		(start 380.657862 -418.07511)
		(end 380.793752 -417.93922)
		(stroke
			(width 0.07112)
			(type default)
		)
		(layer "In15.Cu")
	)
	(gr_line
		(start 380.657862 -416.94735)
		(end 380.793752 -416.81146)
		(stroke
			(width 0.07112)
			(type default)
		)
		(layer "In15.Cu")
	)
	(gr_line
		(start 380.793752 -417.93922)
		(end 380.793752 -417.5125)
		(stroke
			(width 0.07112)
			(type default)
		)
		(layer "In15.Cu")
	)
	(gr_line
		(start 380.793752 -417.5125)
		(end 380.657862 -417.37661)
		(stroke
			(width 0.07112)
			(type default)
		)
		(layer "In15.Cu")
	)
	(gr_line
		(start 380.793752 -416.81146)
		(end 380.793752 -416.38474)
		(stroke
			(width 0.07112)
			(type default)
		)
		(layer "In15.Cu")
	)
	(gr_line
		(start 380.793752 -416.38474)
		(end 380.657862 -416.24885)
		(stroke
			(width 0.07112)
			(type default)
		)
		(layer "In15.Cu")
	)
	(gr_line
		(start 380.82601 -410.958284)
		(end 381.474218 -410.690314)
		(stroke
			(width 0.07112)
			(type default)
		)
		(layer "In15.Cu")
	)
	(gr_line
		(start 380.93396 -423.436288)
		(end 380.522226 -423.323258)
		(stroke
			(width 0.07112)
			(type default)
		)
		(layer "In15.Cu")
	)
	(gr_line
		(start 380.93523 -411.21965)
		(end 381.11303 -411.29331)
		(stroke
			(width 0.07112)
			(type default)
		)
		(layer "In15.Cu")
	)
	(gr_line
		(start 380.95555 -423.876978)
		(end 380.279148 -423.691558)
		(stroke
			(width 0.07112)
			(type default)
		)
		(layer "In15.Cu")
	)
	(gr_line
		(start 381.02921 -423.60342)
		(end 380.93396 -423.436288)
		(stroke
			(width 0.07112)
			(type default)
		)
		(layer "In15.Cu")
	)
	(gr_line
		(start 381.11303 -411.29331)
		(end 381.507492 -411.130242)
		(stroke
			(width 0.07112)
			(type default)
		)
		(layer "In15.Cu")
	)
	(gr_line
		(start 381.507492 -411.130242)
		(end 381.581152 -410.952442)
		(stroke
			(width 0.07112)
			(type default)
		)
		(layer "In15.Cu")
	)
	(gr_line
		(start 381.603758 -437.3372)
		(end 381.599186 -437.3372)
		(stroke
			(width 0.07112)
			(type default)
		)
		(layer "In15.Cu")
	)
	(gr_line
		(start 381.749808 -438.089802)
		(end 381.749808 -437.769762)
		(stroke
			(width 0.07112)
			(type default)
		)
		(layer "In15.Cu")
	)
	(gr_line
		(start 381.749808 -437.769762)
		(end 381.600456 -437.62041)
		(stroke
			(width 0.07112)
			(type default)
		)
		(layer "In15.Cu")
	)
	(gr_line
		(start 381.749808 -437.19115)
		(end 381.603758 -437.3372)
		(stroke
			(width 0.07112)
			(type default)
		)
		(layer "In15.Cu")
	)
	(gr_line
		(start 381.749808 -436.889906)
		(end 381.749808 -437.19115)
		(stroke
			(width 0.07112)
			(type default)
		)
		(layer "In15.Cu")
	)
	(gr_line
		(start 381.803402 -422.635172)
		(end 381.625348 -422.708832)
		(stroke
			(width 0.07112)
			(type default)
		)
		(layer "In15.Cu")
	)
	(gr_line
		(start 382.164336 -423.238676)
		(end 381.516128 -422.970198)
		(stroke
			(width 0.07112)
			(type default)
		)
		(layer "In15.Cu")
	)
	(gr_line
		(start 382.197864 -422.798494)
		(end 381.803402 -422.635172)
		(stroke
			(width 0.07112)
			(type default)
		)
		(layer "In15.Cu")
	)
	(gr_line
		(start 382.27127 -422.976548)
		(end 382.197864 -422.798494)
		(stroke
			(width 0.07112)
			(type default)
		)
		(layer "In15.Cu")
	)
	(gr_line
		(start 382.845564 -423.066972)
		(end 382.66751 -423.140632)
		(stroke
			(width 0.07112)
			(type default)
		)
		(layer "In15.Cu")
	)
	(gr_line
		(start 383.206244 -423.670222)
		(end 382.55829 -423.401744)
		(stroke
			(width 0.07112)
			(type default)
		)
		(layer "In15.Cu")
	)
	(gr_line
		(start 383.240026 -423.230294)
		(end 382.845564 -423.066972)
		(stroke
			(width 0.07112)
			(type default)
		)
		(layer "In15.Cu")
	)
	(gr_line
		(start 383.272792 -411.02788)
		(end 383.923286 -410.766006)
		(stroke
			(width 0.07112)
			(type default)
		)
		(layer "In15.Cu")
	)
	(gr_line
		(start 383.313686 -423.408094)
		(end 383.240026 -423.230294)
		(stroke
			(width 0.07112)
			(type default)
		)
		(layer "In15.Cu")
	)
	(gr_line
		(start 383.379472 -411.290262)
		(end 383.55651 -411.3657)
		(stroke
			(width 0.07112)
			(type default)
		)
		(layer "In15.Cu")
	)
	(gr_line
		(start 383.437892 -417.961318)
		(end 383.437892 -417.260278)
		(stroke
			(width 0.07112)
			(type default)
		)
		(layer "In15.Cu")
	)
	(gr_line
		(start 383.437892 -416.833558)
		(end 383.437892 -416.132518)
		(stroke
			(width 0.07112)
			(type default)
		)
		(layer "In15.Cu")
	)
	(gr_line
		(start 383.55651 -411.3657)
		(end 383.95275 -411.206442)
		(stroke
			(width 0.07112)
			(type default)
		)
		(layer "In15.Cu")
	)
	(gr_line
		(start 383.603754 -438.337198)
		(end 383.599182 -438.337198)
		(stroke
			(width 0.07112)
			(type default)
		)
		(layer "In15.Cu")
	)
	(gr_line
		(start 383.648966 -422.220644)
		(end 383.471166 -422.294304)
		(stroke
			(width 0.07112)
			(type default)
		)
		(layer "In15.Cu")
	)
	(gr_line
		(start 383.721102 -417.960048)
		(end 383.856992 -417.824158)
		(stroke
			(width 0.07112)
			(type default)
		)
		(layer "In15.Cu")
	)
	(gr_line
		(start 383.721102 -416.832288)
		(end 383.856992 -416.696398)
		(stroke
			(width 0.07112)
			(type default)
		)
		(layer "In15.Cu")
	)
	(gr_line
		(start 383.749804 -439.0898)
		(end 383.749804 -438.76976)
		(stroke
			(width 0.07112)
			(type default)
		)
		(layer "In15.Cu")
	)
	(gr_line
		(start 383.749804 -438.76976)
		(end 383.600452 -438.620408)
		(stroke
			(width 0.07112)
			(type default)
		)
		(layer "In15.Cu")
	)
	(gr_line
		(start 383.749804 -438.191148)
		(end 383.603754 -438.337198)
		(stroke
			(width 0.07112)
			(type default)
		)
		(layer "In15.Cu")
	)
	(gr_line
		(start 383.749804 -437.889904)
		(end 383.749804 -438.191148)
		(stroke
			(width 0.07112)
			(type default)
		)
		(layer "In15.Cu")
	)
	(gr_line
		(start 383.856992 -417.824158)
		(end 383.856992 -417.397438)
		(stroke
			(width 0.07112)
			(type default)
		)
		(layer "In15.Cu")
	)
	(gr_line
		(start 383.856992 -417.397438)
		(end 383.721102 -417.261548)
		(stroke
			(width 0.07112)
			(type default)
		)
		(layer "In15.Cu")
	)
	(gr_line
		(start 383.856992 -416.696398)
		(end 383.856992 -416.269678)
		(stroke
			(width 0.07112)
			(type default)
		)
		(layer "In15.Cu")
	)
	(gr_line
		(start 383.856992 -416.269678)
		(end 383.721102 -416.133788)
		(stroke
			(width 0.07112)
			(type default)
		)
		(layer "In15.Cu")
	)
	(gr_line
		(start 383.95275 -411.206442)
		(end 384.027934 -411.029404)
		(stroke
			(width 0.07112)
			(type default)
		)
		(layer "In15.Cu")
	)
	(gr_line
		(start 384.0099 -422.823894)
		(end 383.361946 -422.55567)
		(stroke
			(width 0.07112)
			(type default)
		)
		(layer "In15.Cu")
	)
	(gr_line
		(start 384.043428 -422.383966)
		(end 383.648966 -422.220644)
		(stroke
			(width 0.07112)
			(type default)
		)
		(layer "In15.Cu")
	)
	(gr_line
		(start 384.116834 -422.561766)
		(end 384.043428 -422.383966)
		(stroke
			(width 0.07112)
			(type default)
		)
		(layer "In15.Cu")
	)
	(gr_line
		(start 384.227832 -422.914318)
		(end 384.0099 -422.823894)
		(stroke
			(width 0.07112)
			(type default)
		)
		(layer "In15.Cu")
	)
	(gr_line
		(start 384.335782 -422.653714)
		(end 384.117596 -422.563544)
		(stroke
			(width 0.07112)
			(type default)
		)
		(layer "In15.Cu")
	)
	(gr_line
		(start 385.203954 -423.024046)
		(end 385.015232 -423.061638)
		(stroke
			(width 0.07112)
			(type default)
		)
		(layer "In15.Cu")
	)
	(gr_line
		(start 385.440174 -423.68597)
		(end 384.85699 -423.296334)
		(stroke
			(width 0.07112)
			(type default)
		)
		(layer "In15.Cu")
	)
	(gr_line
		(start 385.559046 -423.261282)
		(end 385.203954 -423.024046)
		(stroke
			(width 0.07112)
			(type default)
		)
		(layer "In15.Cu")
	)
	(gr_line
		(start 385.596638 -423.450004)
		(end 385.559046 -423.261282)
		(stroke
			(width 0.07112)
			(type default)
		)
		(layer "In15.Cu")
	)
	(gr_line
		(start 385.603242 -437.623204)
		(end 385.599686 -437.623204)
		(stroke
			(width 0.07112)
			(type default)
		)
		(layer "In15.Cu")
	)
	(gr_line
		(start 385.7498 -438.089802)
		(end 385.7498 -437.769762)
		(stroke
			(width 0.07112)
			(type default)
		)
		(layer "In15.Cu")
	)
	(gr_line
		(start 385.7498 -437.769762)
		(end 385.603242 -437.623204)
		(stroke
			(width 0.07112)
			(type default)
		)
		(layer "In15.Cu")
	)
	(gr_line
		(start 385.7498 -437.19115)
		(end 385.600956 -437.339994)
		(stroke
			(width 0.07112)
			(type default)
		)
		(layer "In15.Cu")
	)
	(gr_line
		(start 385.7498 -436.889906)
		(end 385.7498 -437.19115)
		(stroke
			(width 0.07112)
			(type default)
		)
		(layer "In15.Cu")
	)
	(gr_line
		(start 386.501132 -417.879784)
		(end 386.501132 -417.178744)
		(stroke
			(width 0.07112)
			(type default)
		)
		(layer "In15.Cu")
	)
	(gr_line
		(start 386.501132 -416.70859)
		(end 386.501132 -416.00755)
		(stroke
			(width 0.07112)
			(type default)
		)
		(layer "In15.Cu")
	)
	(gr_line
		(start 386.784342 -417.878514)
		(end 386.920232 -417.742624)
		(stroke
			(width 0.07112)
			(type default)
		)
		(layer "In15.Cu")
	)
	(gr_line
		(start 386.784342 -416.70732)
		(end 386.920232 -416.57143)
		(stroke
			(width 0.07112)
			(type default)
		)
		(layer "In15.Cu")
	)
	(gr_line
		(start 386.920232 -417.742624)
		(end 386.920232 -417.315904)
		(stroke
			(width 0.07112)
			(type default)
		)
		(layer "In15.Cu")
	)
	(gr_line
		(start 386.920232 -417.315904)
		(end 386.784342 -417.180014)
		(stroke
			(width 0.07112)
			(type default)
		)
		(layer "In15.Cu")
	)
	(gr_line
		(start 386.920232 -416.57143)
		(end 386.920232 -416.14471)
		(stroke
			(width 0.07112)
			(type default)
		)
		(layer "In15.Cu")
	)
	(gr_line
		(start 386.920232 -416.14471)
		(end 386.784342 -416.00882)
		(stroke
			(width 0.07112)
			(type default)
		)
		(layer "In15.Cu")
	)
	(gr_line
		(start 386.958078 -410.618432)
		(end 387.612636 -410.365956)
		(stroke
			(width 0.07112)
			(type default)
		)
		(layer "In15.Cu")
	)
	(gr_line
		(start 387.060948 -410.882084)
		(end 387.23697 -410.960062)
		(stroke
			(width 0.07112)
			(type default)
		)
		(layer "In15.Cu")
	)
	(gr_line
		(start 387.23697 -410.960062)
		(end 387.635242 -410.806646)
		(stroke
			(width 0.07112)
			(type default)
		)
		(layer "In15.Cu")
	)
	(gr_line
		(start 387.355588 -422.921938)
		(end 387.166866 -422.95953)
		(stroke
			(width 0.07112)
			(type default)
		)
		(layer "In15.Cu")
	)
	(gr_line
		(start 387.5913 -423.584116)
		(end 387.008624 -423.194226)
		(stroke
			(width 0.07112)
			(type default)
		)
		(layer "In15.Cu")
	)
	(gr_line
		(start 387.603238 -438.623202)
		(end 387.599682 -438.623202)
		(stroke
			(width 0.07112)
			(type default)
		)
		(layer "In15.Cu")
	)
	(gr_line
		(start 387.635242 -410.806646)
		(end 387.71322 -410.630624)
		(stroke
			(width 0.07112)
			(type default)
		)
		(layer "In15.Cu")
	)
	(gr_line
		(start 387.710426 -423.159428)
		(end 387.355588 -422.921938)
		(stroke
			(width 0.07112)
			(type default)
		)
		(layer "In15.Cu")
	)
	(gr_line
		(start 387.748018 -423.34815)
		(end 387.710426 -423.159428)
		(stroke
			(width 0.07112)
			(type default)
		)
		(layer "In15.Cu")
	)
	(gr_line
		(start 387.749796 -439.0898)
		(end 387.749796 -438.76976)
		(stroke
			(width 0.07112)
			(type default)
		)
		(layer "In15.Cu")
	)
	(gr_line
		(start 387.749796 -438.76976)
		(end 387.603238 -438.623202)
		(stroke
			(width 0.07112)
			(type default)
		)
		(layer "In15.Cu")
	)
	(gr_line
		(start 387.749796 -438.191148)
		(end 387.600952 -438.339992)
		(stroke
			(width 0.07112)
			(type default)
		)
		(layer "In15.Cu")
	)
	(gr_line
		(start 387.749796 -437.889904)
		(end 387.749796 -438.191148)
		(stroke
			(width 0.07112)
			(type default)
		)
		(layer "In15.Cu")
	)
	(gr_line
		(start 388.233158 -410.126688)
		(end 388.887462 -409.874466)
		(stroke
			(width 0.07112)
			(type default)
		)
		(layer "In15.Cu")
	)
	(gr_line
		(start 388.335774 -410.390594)
		(end 388.511796 -410.468572)
		(stroke
			(width 0.07112)
			(type default)
		)
		(layer "In15.Cu")
	)
	(gr_line
		(start 388.511796 -410.468572)
		(end 388.910322 -410.315156)
		(stroke
			(width 0.07112)
			(type default)
		)
		(layer "In15.Cu")
	)
	(gr_line
		(start 388.910322 -410.315156)
		(end 388.988046 -410.139134)
		(stroke
			(width 0.07112)
			(type default)
		)
		(layer "In15.Cu")
	)
	(gr_line
		(start 389.499094 -409.638754)
		(end 390.153652 -409.386278)
		(stroke
			(width 0.07112)
			(type default)
		)
		(layer "In15.Cu")
	)
	(gr_line
		(start 389.564372 -417.698174)
		(end 389.564372 -416.997134)
		(stroke
			(width 0.07112)
			(type default)
		)
		(layer "In15.Cu")
	)
	(gr_line
		(start 389.564372 -416.570414)
		(end 389.564372 -415.869374)
		(stroke
			(width 0.07112)
			(type default)
		)
		(layer "In15.Cu")
	)
	(gr_line
		(start 389.601964 -409.90266)
		(end 389.777732 -409.980384)
		(stroke
			(width 0.07112)
			(type default)
		)
		(layer "In15.Cu")
	)
	(gr_line
		(start 389.603234 -437.623204)
		(end 389.599678 -437.623204)
		(stroke
			(width 0.07112)
			(type default)
		)
		(layer "In15.Cu")
	)
	(gr_line
		(start 389.749792 -438.089802)
		(end 389.749792 -437.769762)
		(stroke
			(width 0.07112)
			(type default)
		)
		(layer "In15.Cu")
	)
	(gr_line
		(start 389.749792 -437.769762)
		(end 389.603234 -437.623204)
		(stroke
			(width 0.07112)
			(type default)
		)
		(layer "In15.Cu")
	)
	(gr_line
		(start 389.749792 -437.19115)
		(end 389.600948 -437.339994)
		(stroke
			(width 0.07112)
			(type default)
		)
		(layer "In15.Cu")
	)
	(gr_line
		(start 389.749792 -436.889906)
		(end 389.749792 -437.19115)
		(stroke
			(width 0.07112)
			(type default)
		)
		(layer "In15.Cu")
	)
	(gr_line
		(start 389.777732 -409.980384)
		(end 390.176258 -409.826968)
		(stroke
			(width 0.07112)
			(type default)
		)
		(layer "In15.Cu")
	)
	(gr_line
		(start 389.847582 -417.696904)
		(end 389.983472 -417.561014)
		(stroke
			(width 0.07112)
			(type default)
		)
		(layer "In15.Cu")
	)
	(gr_line
		(start 389.847582 -416.569144)
		(end 389.983472 -416.433254)
		(stroke
			(width 0.07112)
			(type default)
		)
		(layer "In15.Cu")
	)
	(gr_line
		(start 389.97636 -410.745432)
		(end 390.621012 -410.469334)
		(stroke
			(width 0.07112)
			(type default)
		)
		(layer "In15.Cu")
	)
	(gr_line
		(start 389.983472 -417.561014)
		(end 389.983472 -417.134294)
		(stroke
			(width 0.07112)
			(type default)
		)
		(layer "In15.Cu")
	)
	(gr_line
		(start 389.983472 -417.134294)
		(end 389.847582 -416.998404)
		(stroke
			(width 0.07112)
			(type default)
		)
		(layer "In15.Cu")
	)
	(gr_line
		(start 389.983472 -416.433254)
		(end 389.983472 -416.006534)
		(stroke
			(width 0.07112)
			(type default)
		)
		(layer "In15.Cu")
	)
	(gr_line
		(start 389.983472 -416.006534)
		(end 389.847582 -415.870644)
		(stroke
			(width 0.07112)
			(type default)
		)
		(layer "In15.Cu")
	)
	(gr_line
		(start 390.088628 -411.005528)
		(end 390.267444 -411.076902)
		(stroke
			(width 0.07112)
			(type default)
		)
		(layer "In15.Cu")
	)
	(gr_line
		(start 390.176258 -409.826968)
		(end 390.254236 -409.650946)
		(stroke
			(width 0.07112)
			(type default)
		)
		(layer "In15.Cu")
	)
	(gr_line
		(start 390.201912 -423.546524)
		(end 390.010396 -423.527728)
		(stroke
			(width 0.07112)
			(type default)
		)
		(layer "In15.Cu")
	)
	(gr_line
		(start 390.235694 -424.24858)
		(end 389.790686 -423.706544)
		(stroke
			(width 0.07112)
			(type default)
		)
		(layer "In15.Cu")
	)
	(gr_line
		(start 390.267444 -411.076902)
		(end 390.659874 -410.909008)
		(stroke
			(width 0.07112)
			(type default)
		)
		(layer "In15.Cu")
	)
	(gr_line
		(start 390.454134 -424.06824)
		(end 390.47293 -423.87647)
		(stroke
			(width 0.07112)
			(type default)
		)
		(layer "In15.Cu")
	)
	(gr_line
		(start 390.47293 -423.87647)
		(end 390.201912 -423.546524)
		(stroke
			(width 0.07112)
			(type default)
		)
		(layer "In15.Cu")
	)
	(gr_line
		(start 390.659874 -410.909008)
		(end 390.731502 -410.729938)
		(stroke
			(width 0.07112)
			(type default)
		)
		(layer "In15.Cu")
	)
	(gr_line
		(start 391.013188 -410.301186)
		(end 391.65784 -410.025088)
		(stroke
			(width 0.07112)
			(type default)
		)
		(layer "In15.Cu")
	)
	(gr_line
		(start 391.125456 -410.561282)
		(end 391.304272 -410.632656)
		(stroke
			(width 0.07112)
			(type default)
		)
		(layer "In15.Cu")
	)
	(gr_line
		(start 391.215372 -408.977084)
		(end 391.86993 -408.724608)
		(stroke
			(width 0.07112)
			(type default)
		)
		(layer "In15.Cu")
	)
	(gr_line
		(start 391.304272 -410.632656)
		(end 391.696702 -410.464762)
		(stroke
			(width 0.07112)
			(type default)
		)
		(layer "In15.Cu")
	)
	(gr_line
		(start 391.318242 -409.24099)
		(end 391.49401 -409.318714)
		(stroke
			(width 0.07112)
			(type default)
		)
		(layer "In15.Cu")
	)
	(gr_line
		(start 391.49401 -409.318714)
		(end 391.892536 -409.165298)
		(stroke
			(width 0.07112)
			(type default)
		)
		(layer "In15.Cu")
	)
	(gr_line
		(start 391.526776 -407.704798)
		(end 392.17727 -407.442924)
		(stroke
			(width 0.07112)
			(type default)
		)
		(layer "In15.Cu")
	)
	(gr_line
		(start 391.55116 -406.52192)
		(end 392.199368 -406.25395)
		(stroke
			(width 0.07112)
			(type default)
		)
		(layer "In15.Cu")
	)
	(gr_line
		(start 391.60323 -438.623202)
		(end 391.599674 -438.623202)
		(stroke
			(width 0.07112)
			(type default)
		)
		(layer "In15.Cu")
	)
	(gr_line
		(start 391.63371 -407.96718)
		(end 391.810494 -408.042618)
		(stroke
			(width 0.07112)
			(type default)
		)
		(layer "In15.Cu")
	)
	(gr_line
		(start 391.66038 -406.783286)
		(end 391.83818 -406.8572)
		(stroke
			(width 0.07112)
			(type default)
		)
		(layer "In15.Cu")
	)
	(gr_line
		(start 391.696702 -410.464762)
		(end 391.76833 -410.285692)
		(stroke
			(width 0.07112)
			(type default)
		)
		(layer "In15.Cu")
	)
	(gr_line
		(start 391.749788 -439.0898)
		(end 391.749788 -438.76976)
		(stroke
			(width 0.07112)
			(type default)
		)
		(layer "In15.Cu")
	)
	(gr_line
		(start 391.749788 -438.76976)
		(end 391.60323 -438.623202)
		(stroke
			(width 0.07112)
			(type default)
		)
		(layer "In15.Cu")
	)
	(gr_line
		(start 391.749788 -438.191148)
		(end 391.600944 -438.339992)
		(stroke
			(width 0.07112)
			(type default)
		)
		(layer "In15.Cu")
	)
	(gr_line
		(start 391.749788 -437.889904)
		(end 391.749788 -438.191148)
		(stroke
			(width 0.07112)
			(type default)
		)
		(layer "In15.Cu")
	)
	(gr_line
		(start 391.810494 -408.042618)
		(end 392.206734 -407.883106)
		(stroke
			(width 0.07112)
			(type default)
		)
		(layer "In15.Cu")
	)
	(gr_line
		(start 391.83818 -406.8572)
		(end 392.232896 -406.693878)
		(stroke
			(width 0.07112)
			(type default)
		)
		(layer "In15.Cu")
	)
	(gr_line
		(start 391.892536 -409.165298)
		(end 391.970514 -408.989276)
		(stroke
			(width 0.07112)
			(type default)
		)
		(layer "In15.Cu")
	)
	(gr_line
		(start 391.903458 -423.238422)
		(end 391.573004 -422.619678)
		(stroke
			(width 0.07112)
			(type default)
		)
		(layer "In15.Cu")
	)
	(gr_line
		(start 392.007344 -422.543224)
		(end 391.823194 -422.487344)
		(stroke
			(width 0.07112)
			(type default)
		)
		(layer "In15.Cu")
	)
	(gr_line
		(start 392.050016 -409.85694)
		(end 392.694668 -409.580842)
		(stroke
			(width 0.07112)
			(type default)
		)
		(layer "In15.Cu")
	)
	(gr_line
		(start 392.152632 -423.104056)
		(end 392.208512 -422.919906)
		(stroke
			(width 0.07112)
			(type default)
		)
		(layer "In15.Cu")
	)
	(gr_line
		(start 392.162284 -410.117036)
		(end 392.3411 -410.18841)
		(stroke
			(width 0.07112)
			(type default)
		)
		(layer "In15.Cu")
	)
	(gr_line
		(start 392.206734 -407.883106)
		(end 392.281918 -407.706068)
		(stroke
			(width 0.07112)
			(type default)
		)
		(layer "In15.Cu")
	)
	(gr_line
		(start 392.208512 -422.919906)
		(end 392.007344 -422.543224)
		(stroke
			(width 0.07112)
			(type default)
		)
		(layer "In15.Cu")
	)
	(gr_line
		(start 392.232896 -406.693878)
		(end 392.30681 -406.516078)
		(stroke
			(width 0.07112)
			(type default)
		)
		(layer "In15.Cu")
	)
	(gr_line
		(start 392.3411 -410.18841)
		(end 392.73353 -410.020516)
		(stroke
			(width 0.07112)
			(type default)
		)
		(layer "In15.Cu")
	)
	(gr_line
		(start 392.57732 -408.452066)
		(end 393.231878 -408.19959)
		(stroke
			(width 0.07112)
			(type default)
		)
		(layer "In15.Cu")
	)
	(gr_line
		(start 392.580114 -424.622214)
		(end 392.280394 -423.987976)
		(stroke
			(width 0.07112)
			(type default)
		)
		(layer "In15.Cu")
	)
	(gr_line
		(start 392.62558 -406.07742)
		(end 393.273788 -405.80945)
		(stroke
			(width 0.07112)
			(type default)
		)
		(layer "In15.Cu")
	)
	(gr_line
		(start 392.627612 -417.826698)
		(end 392.627612 -417.125658)
		(stroke
			(width 0.07112)
			(type default)
		)
		(layer "In15.Cu")
	)
	(gr_line
		(start 392.627612 -416.698938)
		(end 392.627612 -415.997898)
		(stroke
			(width 0.07112)
			(type default)
		)
		(layer "In15.Cu")
	)
	(gr_line
		(start 392.68019 -408.715718)
		(end 392.822176 -408.77871)
		(stroke
			(width 0.07112)
			(type default)
		)
		(layer "In15.Cu")
	)
	(gr_line
		(start 392.71829 -423.932858)
		(end 392.536934 -423.867834)
		(stroke
			(width 0.07112)
			(type default)
		)
		(layer "In15.Cu")
	)
	(gr_line
		(start 392.73353 -410.020516)
		(end 392.805158 -409.841446)
		(stroke
			(width 0.07112)
			(type default)
		)
		(layer "In15.Cu")
	)
	(gr_line
		(start 392.7348 -406.338786)
		(end 392.9126 -406.412446)
		(stroke
			(width 0.07112)
			(type default)
		)
		(layer "In15.Cu")
	)
	(gr_line
		(start 392.822176 -408.77871)
		(end 393.269724 -408.606244)
		(stroke
			(width 0.07112)
			(type default)
		)
		(layer "In15.Cu")
	)
	(gr_line
		(start 392.835638 -424.50004)
		(end 392.900662 -424.318938)
		(stroke
			(width 0.07112)
			(type default)
		)
		(layer "In15.Cu")
	)
	(gr_line
		(start 392.900662 -424.318938)
		(end 392.71829 -423.932858)
		(stroke
			(width 0.07112)
			(type default)
		)
		(layer "In15.Cu")
	)
	(gr_line
		(start 392.910822 -417.825428)
		(end 393.046712 -417.689538)
		(stroke
			(width 0.07112)
			(type default)
		)
		(layer "In15.Cu")
	)
	(gr_line
		(start 392.910822 -416.697668)
		(end 393.046712 -416.561778)
		(stroke
			(width 0.07112)
			(type default)
		)
		(layer "In15.Cu")
	)
	(gr_line
		(start 392.9126 -406.412446)
		(end 393.307062 -406.249378)
		(stroke
			(width 0.07112)
			(type default)
		)
		(layer "In15.Cu")
	)
	(gr_line
		(start 393.046712 -417.689538)
		(end 393.046712 -417.262818)
		(stroke
			(width 0.07112)
			(type default)
		)
		(layer "In15.Cu")
	)
	(gr_line
		(start 393.046712 -417.262818)
		(end 392.910822 -417.126928)
		(stroke
			(width 0.07112)
			(type default)
		)
		(layer "In15.Cu")
	)
	(gr_line
		(start 393.046712 -416.561778)
		(end 393.046712 -416.135058)
		(stroke
			(width 0.07112)
			(type default)
		)
		(layer "In15.Cu")
	)
	(gr_line
		(start 393.046712 -416.135058)
		(end 392.910822 -415.999168)
		(stroke
			(width 0.07112)
			(type default)
		)
		(layer "In15.Cu")
	)
	(gr_line
		(start 393.086844 -409.412694)
		(end 393.731242 -409.136596)
		(stroke
			(width 0.07112)
			(type default)
		)
		(layer "In15.Cu")
	)
	(gr_line
		(start 393.089638 -407.07564)
		(end 393.74064 -406.813512)
		(stroke
			(width 0.07112)
			(type default)
		)
		(layer "In15.Cu")
	)
	(gr_line
		(start 393.196572 -407.337768)
		(end 393.37361 -407.413206)
		(stroke
			(width 0.07112)
			(type default)
		)
		(layer "In15.Cu")
	)
	(gr_line
		(start 393.199112 -409.67279)
		(end 393.377928 -409.744164)
		(stroke
			(width 0.07112)
			(type default)
		)
		(layer "In15.Cu")
	)
	(gr_line
		(start 393.269724 -408.606244)
		(end 393.332462 -408.464258)
		(stroke
			(width 0.07112)
			(type default)
		)
		(layer "In15.Cu")
	)
	(gr_line
		(start 393.307062 -406.249378)
		(end 393.380722 -406.071578)
		(stroke
			(width 0.07112)
			(type default)
		)
		(layer "In15.Cu")
	)
	(gr_line
		(start 393.37361 -407.413206)
		(end 393.76985 -407.253948)
		(stroke
			(width 0.07112)
			(type default)
		)
		(layer "In15.Cu")
	)
	(gr_line
		(start 393.377928 -409.744164)
		(end 393.770358 -409.57627)
		(stroke
			(width 0.07112)
			(type default)
		)
		(layer "In15.Cu")
	)
	(gr_line
		(start 393.603226 -437.623204)
		(end 393.59967 -437.623204)
		(stroke
			(width 0.07112)
			(type default)
		)
		(layer "In15.Cu")
	)
	(gr_line
		(start 393.723368 -410.459174)
		(end 394.378942 -410.209238)
		(stroke
			(width 0.07112)
			(type default)
		)
		(layer "In15.Cu")
	)
	(gr_line
		(start 393.749784 -438.089802)
		(end 393.749784 -437.769762)
		(stroke
			(width 0.07112)
			(type default)
		)
		(layer "In15.Cu")
	)
	(gr_line
		(start 393.749784 -437.769762)
		(end 393.603226 -437.623204)
		(stroke
			(width 0.07112)
			(type default)
		)
		(layer "In15.Cu")
	)
	(gr_line
		(start 393.749784 -437.19115)
		(end 393.60094 -437.339994)
		(stroke
			(width 0.07112)
			(type default)
		)
		(layer "In15.Cu")
	)
	(gr_line
		(start 393.749784 -436.889906)
		(end 393.749784 -437.19115)
		(stroke
			(width 0.07112)
			(type default)
		)
		(layer "In15.Cu")
	)
	(gr_line
		(start 393.76985 -407.253948)
		(end 393.845034 -407.076656)
		(stroke
			(width 0.07112)
			(type default)
		)
		(layer "In15.Cu")
	)
	(gr_line
		(start 393.770358 -409.57627)
		(end 393.841986 -409.3972)
		(stroke
			(width 0.07112)
			(type default)
		)
		(layer "In15.Cu")
	)
	(gr_line
		(start 393.825222 -410.723334)
		(end 394.000736 -410.802074)
		(stroke
			(width 0.07112)
			(type default)
		)
		(layer "In15.Cu")
	)
	(gr_line
		(start 394.000736 -410.802074)
		(end 394.39977 -410.650182)
		(stroke
			(width 0.07112)
			(type default)
		)
		(layer "In15.Cu")
	)
	(gr_line
		(start 394.159232 -420.771574)
		(end 394.159486 -420.77132)
		(stroke
			(width 0.07112)
			(type default)
		)
		(layer "In15.Cu")
	)
	(gr_line
		(start 394.159232 -420.426642)
		(end 394.159486 -420.426642)
		(stroke
			(width 0.07112)
			(type default)
		)
		(layer "In15.Cu")
	)
	(gr_line
		(start 394.159486 -420.426896)
		(end 394.159232 -420.426642)
		(stroke
			(width 0.07112)
			(type default)
		)
		(layer "In15.Cu")
	)
	(gr_line
		(start 394.35532 -422.329356)
		(end 394.232892 -421.63873)
		(stroke
			(width 0.07112)
			(type default)
		)
		(layer "In15.Cu")
	)
	(gr_line
		(start 394.39977 -410.650182)
		(end 394.47851 -410.474414)
		(stroke
			(width 0.07112)
			(type default)
		)
		(layer "In15.Cu")
	)
	(gr_line
		(start 394.441172 -420.888414)
		(end 394.441426 -420.88816)
		(stroke
			(width 0.07112)
			(type default)
		)
		(layer "In15.Cu")
	)
	(gr_line
		(start 394.441426 -420.317168)
		(end 394.44168 -420.317422)
		(stroke
			(width 0.07112)
			(type default)
		)
		(layer "In15.Cu")
	)
	(gr_line
		(start 394.633958 -422.278556)
		(end 394.744194 -422.121076)
		(stroke
			(width 0.07112)
			(type default)
		)
		(layer "In15.Cu")
	)
	(gr_line
		(start 394.655802 -424.023282)
		(end 394.533374 -423.33291)
		(stroke
			(width 0.07112)
			(type default)
		)
		(layer "In15.Cu")
	)
	(gr_line
		(start 394.669518 -421.700706)
		(end 394.511784 -421.59047)
		(stroke
			(width 0.07112)
			(type default)
		)
		(layer "In15.Cu")
	)
	(gr_line
		(start 394.744194 -422.121076)
		(end 394.669518 -421.700706)
		(stroke
			(width 0.07112)
			(type default)
		)
		(layer "In15.Cu")
	)
	(gr_line
		(start 394.777468 -410.0576)
		(end 395.433042 -409.807918)
		(stroke
			(width 0.07112)
			(type default)
		)
		(layer "In15.Cu")
	)
	(gr_line
		(start 394.830554 -406.3746)
		(end 395.481048 -406.112726)
		(stroke
			(width 0.07112)
			(type default)
		)
		(layer "In15.Cu")
	)
	(gr_line
		(start 394.879322 -410.32176)
		(end 395.054836 -410.4005)
		(stroke
			(width 0.07112)
			(type default)
		)
		(layer "In15.Cu")
	)
	(gr_line
		(start 394.93444 -423.972736)
		(end 395.044676 -423.815002)
		(stroke
			(width 0.07112)
			(type default)
		)
		(layer "In15.Cu")
	)
	(gr_line
		(start 394.937234 -406.636982)
		(end 395.114272 -406.71242)
		(stroke
			(width 0.07112)
			(type default)
		)
		(layer "In15.Cu")
	)
	(gr_line
		(start 394.970254 -423.394632)
		(end 394.81252 -423.28465)
		(stroke
			(width 0.07112)
			(type default)
		)
		(layer "In15.Cu")
	)
	(gr_line
		(start 395.044676 -423.815002)
		(end 394.970254 -423.394632)
		(stroke
			(width 0.07112)
			(type default)
		)
		(layer "In15.Cu")
	)
	(gr_line
		(start 395.054836 -410.4005)
		(end 395.45387 -410.248608)
		(stroke
			(width 0.07112)
			(type default)
		)
		(layer "In15.Cu")
	)
	(gr_line
		(start 395.114272 -406.71242)
		(end 395.510512 -406.552908)
		(stroke
			(width 0.07112)
			(type default)
		)
		(layer "In15.Cu")
	)
	(gr_line
		(start 395.45387 -410.248608)
		(end 395.53261 -410.07284)
		(stroke
			(width 0.07112)
			(type default)
		)
		(layer "In15.Cu")
	)
	(gr_line
		(start 395.462506 -408.435302)
		(end 396.12824 -408.21483)
		(stroke
			(width 0.07112)
			(type default)
		)
		(layer "In15.Cu")
	)
	(gr_line
		(start 395.510512 -406.552908)
		(end 395.585696 -406.37587)
		(stroke
			(width 0.07112)
			(type default)
		)
		(layer "In15.Cu")
	)
	(gr_line
		(start 395.552676 -408.70378)
		(end 395.724634 -408.79014)
		(stroke
			(width 0.07112)
			(type default)
		)
		(layer "In15.Cu")
	)
	(gr_line
		(start 395.603476 -438.337452)
		(end 395.599412 -438.337452)
		(stroke
			(width 0.07112)
			(type default)
		)
		(layer "In15.Cu")
	)
	(gr_line
		(start 395.690852 -417.92144)
		(end 395.690852 -417.2204)
		(stroke
			(width 0.07112)
			(type default)
		)
		(layer "In15.Cu")
	)
	(gr_line
		(start 395.690852 -416.79368)
		(end 395.690852 -416.09264)
		(stroke
			(width 0.07112)
			(type default)
		)
		(layer "In15.Cu")
	)
	(gr_line
		(start 395.694916 -411.1371)
		(end 396.339314 -410.861002)
		(stroke
			(width 0.07112)
			(type default)
		)
		(layer "In15.Cu")
	)
	(gr_line
		(start 395.724634 -408.79014)
		(end 396.130018 -408.656028)
		(stroke
			(width 0.07112)
			(type default)
		)
		(layer "In15.Cu")
	)
	(gr_line
		(start 395.74978 -439.0898)
		(end 395.74978 -438.76976)
		(stroke
			(width 0.07112)
			(type default)
		)
		(layer "In15.Cu")
	)
	(gr_line
		(start 395.74978 -438.76976)
		(end 395.600682 -438.620662)
		(stroke
			(width 0.07112)
			(type default)
		)
		(layer "In15.Cu")
	)
	(gr_line
		(start 395.74978 -438.191148)
		(end 395.603476 -438.337452)
		(stroke
			(width 0.07112)
			(type default)
		)
		(layer "In15.Cu")
	)
	(gr_line
		(start 395.74978 -437.889904)
		(end 395.74978 -438.191148)
		(stroke
			(width 0.07112)
			(type default)
		)
		(layer "In15.Cu")
	)
	(gr_line
		(start 395.80693 -411.397196)
		(end 395.986 -411.46857)
		(stroke
			(width 0.07112)
			(type default)
		)
		(layer "In15.Cu")
	)
	(gr_line
		(start 395.831568 -409.656026)
		(end 396.487142 -409.406344)
		(stroke
			(width 0.07112)
			(type default)
		)
		(layer "In15.Cu")
	)
	(gr_line
		(start 395.933422 -409.920186)
		(end 396.108936 -409.998926)
		(stroke
			(width 0.07112)
			(type default)
		)
		(layer "In15.Cu")
	)
	(gr_line
		(start 395.974062 -417.92017)
		(end 396.109952 -417.78428)
		(stroke
			(width 0.07112)
			(type default)
		)
		(layer "In15.Cu")
	)
	(gr_line
		(start 395.974062 -416.79241)
		(end 396.109952 -416.65652)
		(stroke
			(width 0.07112)
			(type default)
		)
		(layer "In15.Cu")
	)
	(gr_line
		(start 395.986 -411.46857)
		(end 396.37843 -411.300676)
		(stroke
			(width 0.07112)
			(type default)
		)
		(layer "In15.Cu")
	)
	(gr_line
		(start 396.108936 -409.998926)
		(end 396.50797 -409.847034)
		(stroke
			(width 0.07112)
			(type default)
		)
		(layer "In15.Cu")
	)
	(gr_line
		(start 396.109952 -417.78428)
		(end 396.109952 -417.35756)
		(stroke
			(width 0.07112)
			(type default)
		)
		(layer "In15.Cu")
	)
	(gr_line
		(start 396.109952 -417.35756)
		(end 395.974062 -417.22167)
		(stroke
			(width 0.07112)
			(type default)
		)
		(layer "In15.Cu")
	)
	(gr_line
		(start 396.109952 -416.65652)
		(end 396.109952 -416.2298)
		(stroke
			(width 0.07112)
			(type default)
		)
		(layer "In15.Cu")
	)
	(gr_line
		(start 396.109952 -416.2298)
		(end 395.974062 -416.09391)
		(stroke
			(width 0.07112)
			(type default)
		)
		(layer "In15.Cu")
	)
	(gr_line
		(start 396.130018 -408.656028)
		(end 396.216124 -408.48407)
		(stroke
			(width 0.07112)
			(type default)
		)
		(layer "In15.Cu")
	)
	(gr_line
		(start 396.37843 -411.300676)
		(end 396.44955 -411.12186)
		(stroke
			(width 0.07112)
			(type default)
		)
		(layer "In15.Cu")
	)
	(gr_line
		(start 396.50797 -409.847034)
		(end 396.58671 -409.671266)
		(stroke
			(width 0.07112)
			(type default)
		)
		(layer "In15.Cu")
	)
	(gr_line
		(start 396.533116 -408.080718)
		(end 397.19885 -407.860246)
		(stroke
			(width 0.07112)
			(type default)
		)
		(layer "In15.Cu")
	)
	(gr_line
		(start 396.623286 -408.349196)
		(end 396.795244 -408.435556)
		(stroke
			(width 0.07112)
			(type default)
		)
		(layer "In15.Cu")
	)
	(gr_line
		(start 396.73149 -410.692854)
		(end 397.376142 -410.416502)
		(stroke
			(width 0.07112)
			(type default)
		)
		(layer "In15.Cu")
	)
	(gr_line
		(start 396.795244 -408.435556)
		(end 397.200628 -408.301444)
		(stroke
			(width 0.07112)
			(type default)
		)
		(layer "In15.Cu")
	)
	(gr_line
		(start 396.844012 -410.952696)
		(end 397.022574 -411.02407)
		(stroke
			(width 0.07112)
			(type default)
		)
		(layer "In15.Cu")
	)
	(gr_line
		(start 396.885668 -409.254452)
		(end 397.541242 -409.00477)
		(stroke
			(width 0.07112)
			(type default)
		)
		(layer "In15.Cu")
	)
	(gr_line
		(start 396.987522 -409.518612)
		(end 397.163036 -409.597352)
		(stroke
			(width 0.07112)
			(type default)
		)
		(layer "In15.Cu")
	)
	(gr_line
		(start 397.022574 -411.02407)
		(end 397.415004 -410.856176)
		(stroke
			(width 0.07112)
			(type default)
		)
		(layer "In15.Cu")
	)
	(gr_line
		(start 397.163036 -409.597352)
		(end 397.56207 -409.44546)
		(stroke
			(width 0.07112)
			(type default)
		)
		(layer "In15.Cu")
	)
	(gr_line
		(start 397.200628 -408.301444)
		(end 397.286734 -408.129486)
		(stroke
			(width 0.07112)
			(type default)
		)
		(layer "In15.Cu")
	)
	(gr_line
		(start 397.222472 -424.292522)
		(end 397.222472 -423.591482)
		(stroke
			(width 0.07112)
			(type default)
		)
		(layer "In15.Cu")
	)
	(gr_line
		(start 397.222472 -423.164762)
		(end 397.222472 -422.463722)
		(stroke
			(width 0.07112)
			(type default)
		)
		(layer "In15.Cu")
	)
	(gr_line
		(start 397.222472 -422.037002)
		(end 397.222472 -421.335962)
		(stroke
			(width 0.07112)
			(type default)
		)
		(layer "In15.Cu")
	)
	(gr_line
		(start 397.415004 -410.856176)
		(end 397.486632 -410.67736)
		(stroke
			(width 0.07112)
			(type default)
		)
		(layer "In15.Cu")
	)
	(gr_line
		(start 397.505682 -424.291252)
		(end 397.641572 -424.155362)
		(stroke
			(width 0.07112)
			(type default)
		)
		(layer "In15.Cu")
	)
	(gr_line
		(start 397.505682 -423.163492)
		(end 397.641572 -423.027602)
		(stroke
			(width 0.07112)
			(type default)
		)
		(layer "In15.Cu")
	)
	(gr_line
		(start 397.505682 -422.035732)
		(end 397.641572 -421.899842)
		(stroke
			(width 0.07112)
			(type default)
		)
		(layer "In15.Cu")
	)
	(gr_line
		(start 397.56207 -409.44546)
		(end 397.64081 -409.269692)
		(stroke
			(width 0.07112)
			(type default)
		)
		(layer "In15.Cu")
	)
	(gr_line
		(start 397.641572 -424.155362)
		(end 397.641572 -423.728642)
		(stroke
			(width 0.07112)
			(type default)
		)
		(layer "In15.Cu")
	)
	(gr_line
		(start 397.641572 -423.728642)
		(end 397.505682 -423.592752)
		(stroke
			(width 0.07112)
			(type default)
		)
		(layer "In15.Cu")
	)
	(gr_line
		(start 397.641572 -423.027602)
		(end 397.641572 -422.600882)
		(stroke
			(width 0.07112)
			(type default)
		)
		(layer "In15.Cu")
	)
	(gr_line
		(start 397.641572 -422.600882)
		(end 397.505682 -422.464992)
		(stroke
			(width 0.07112)
			(type default)
		)
		(layer "In15.Cu")
	)
	(gr_line
		(start 397.641572 -421.899842)
		(end 397.641572 -421.473122)
		(stroke
			(width 0.07112)
			(type default)
		)
		(layer "In15.Cu")
	)
	(gr_line
		(start 397.641572 -421.473122)
		(end 397.505682 -421.337232)
		(stroke
			(width 0.07112)
			(type default)
		)
		(layer "In15.Cu")
	)
	(gr_line
		(start 397.768318 -410.248608)
		(end 398.412716 -409.972256)
		(stroke
			(width 0.07112)
			(type default)
		)
		(layer "In15.Cu")
	)
	(gr_line
		(start 397.776446 -405.345392)
		(end 398.453864 -405.163274)
		(stroke
			(width 0.07112)
			(type default)
		)
		(layer "In15.Cu")
	)
	(gr_line
		(start 397.850868 -405.618696)
		(end 398.017746 -405.714708)
		(stroke
			(width 0.07112)
			(type default)
		)
		(layer "In15.Cu")
	)
	(gr_line
		(start 397.880586 -410.50845)
		(end 398.059402 -410.579824)
		(stroke
			(width 0.07112)
			(type default)
		)
		(layer "In15.Cu")
	)
	(gr_line
		(start 397.939768 -408.852878)
		(end 398.595342 -408.602942)
		(stroke
			(width 0.07112)
			(type default)
		)
		(layer "In15.Cu")
	)
	(gr_line
		(start 398.017746 -405.714708)
		(end 398.429988 -405.603964)
		(stroke
			(width 0.07112)
			(type default)
		)
		(layer "In15.Cu")
	)
	(gr_line
		(start 398.041622 -409.117038)
		(end 398.217136 -409.195778)
		(stroke
			(width 0.07112)
			(type default)
		)
		(layer "In15.Cu")
	)
	(gr_line
		(start 398.059402 -410.579824)
		(end 398.451832 -410.41193)
		(stroke
			(width 0.07112)
			(type default)
		)
		(layer "In15.Cu")
	)
	(gr_line
		(start 398.217136 -409.195778)
		(end 398.61617 -409.043886)
		(stroke
			(width 0.07112)
			(type default)
		)
		(layer "In15.Cu")
	)
	(gr_line
		(start 398.429988 -405.603964)
		(end 398.526254 -405.437086)
		(stroke
			(width 0.07112)
			(type default)
		)
		(layer "In15.Cu")
	)
	(gr_line
		(start 398.451832 -410.41193)
		(end 398.52346 -410.233114)
		(stroke
			(width 0.07112)
			(type default)
		)
		(layer "In15.Cu")
	)
	(gr_line
		(start 398.603978 -437.3372)
		(end 398.599406 -437.3372)
		(stroke
			(width 0.07112)
			(type default)
		)
		(layer "In15.Cu")
	)
	(gr_line
		(start 398.61617 -409.043886)
		(end 398.69491 -408.868118)
		(stroke
			(width 0.07112)
			(type default)
		)
		(layer "In15.Cu")
	)
	(gr_line
		(start 398.750028 -438.089802)
		(end 398.750028 -437.769762)
		(stroke
			(width 0.07112)
			(type default)
		)
		(layer "In15.Cu")
	)
	(gr_line
		(start 398.750028 -437.769762)
		(end 398.600676 -437.62041)
		(stroke
			(width 0.07112)
			(type default)
		)
		(layer "In15.Cu")
	)
	(gr_line
		(start 398.750028 -437.19115)
		(end 398.603978 -437.3372)
		(stroke
			(width 0.07112)
			(type default)
		)
		(layer "In15.Cu")
	)
	(gr_line
		(start 398.750028 -436.889906)
		(end 398.750028 -437.19115)
		(stroke
			(width 0.07112)
			(type default)
		)
		(layer "In15.Cu")
	)
	(gr_line
		(start 398.754092 -417.951158)
		(end 398.754092 -417.250118)
		(stroke
			(width 0.07112)
			(type default)
		)
		(layer "In15.Cu")
	)
	(gr_line
		(start 398.754092 -416.823398)
		(end 398.754092 -416.122358)
		(stroke
			(width 0.07112)
			(type default)
		)
		(layer "In15.Cu")
	)
	(gr_line
		(start 398.791938 -410.99867)
		(end 399.434812 -410.718254)
		(stroke
			(width 0.07112)
			(type default)
		)
		(layer "In15.Cu")
	)
	(gr_line
		(start 398.855438 -409.782518)
		(end 399.500344 -409.506166)
		(stroke
			(width 0.07112)
			(type default)
		)
		(layer "In15.Cu")
	)
	(gr_line
		(start 398.906238 -411.25775)
		(end 399.085308 -411.328108)
		(stroke
			(width 0.07112)
			(type default)
		)
		(layer "In15.Cu")
	)
	(gr_line
		(start 398.968214 -410.04236)
		(end 399.146776 -410.113988)
		(stroke
			(width 0.07112)
			(type default)
		)
		(layer "In15.Cu")
	)
	(gr_line
		(start 398.993868 -408.451304)
		(end 399.649442 -408.201368)
		(stroke
			(width 0.07112)
			(type default)
		)
		(layer "In15.Cu")
	)
	(gr_line
		(start 399.037302 -417.949888)
		(end 399.173192 -417.813998)
		(stroke
			(width 0.07112)
			(type default)
		)
		(layer "In15.Cu")
	)
	(gr_line
		(start 399.037302 -416.822128)
		(end 399.173192 -416.686238)
		(stroke
			(width 0.07112)
			(type default)
		)
		(layer "In15.Cu")
	)
	(gr_line
		(start 399.085308 -411.328108)
		(end 399.476722 -411.157674)
		(stroke
			(width 0.07112)
			(type default)
		)
		(layer "In15.Cu")
	)
	(gr_line
		(start 399.095468 -408.715464)
		(end 399.271236 -408.794204)
		(stroke
			(width 0.07112)
			(type default)
		)
		(layer "In15.Cu")
	)
	(gr_line
		(start 399.146776 -410.113988)
		(end 399.539206 -409.94584)
		(stroke
			(width 0.07112)
			(type default)
		)
		(layer "In15.Cu")
	)
	(gr_line
		(start 399.173192 -417.813998)
		(end 399.173192 -417.387278)
		(stroke
			(width 0.07112)
			(type default)
		)
		(layer "In15.Cu")
	)
	(gr_line
		(start 399.173192 -417.387278)
		(end 399.037302 -417.251388)
		(stroke
			(width 0.07112)
			(type default)
		)
		(layer "In15.Cu")
	)
	(gr_line
		(start 399.173192 -416.686238)
		(end 399.173192 -416.259518)
		(stroke
			(width 0.07112)
			(type default)
		)
		(layer "In15.Cu")
	)
	(gr_line
		(start 399.173192 -416.259518)
		(end 399.037302 -416.123628)
		(stroke
			(width 0.07112)
			(type default)
		)
		(layer "In15.Cu")
	)
	(gr_line
		(start 399.271236 -408.794204)
		(end 399.67027 -408.642312)
		(stroke
			(width 0.07112)
			(type default)
		)
		(layer "In15.Cu")
	)
	(gr_line
		(start 399.434812 -410.718254)
		(end 399.435066 -410.718254)
		(stroke
			(width 0.07112)
			(type default)
		)
		(layer "In15.Cu")
	)
	(gr_line
		(start 399.476722 -411.157674)
		(end 399.54708 -410.97835)
		(stroke
			(width 0.07112)
			(type default)
		)
		(layer "In15.Cu")
	)
	(gr_line
		(start 399.539206 -409.94584)
		(end 399.610834 -409.767024)
		(stroke
			(width 0.07112)
			(type default)
		)
		(layer "In15.Cu")
	)
	(gr_line
		(start 399.67027 -408.642312)
		(end 399.74901 -408.466544)
		(stroke
			(width 0.07112)
			(type default)
		)
		(layer "In15.Cu")
	)
	(gr_line
		(start 399.825718 -410.54782)
		(end 400.468592 -410.267404)
		(stroke
			(width 0.07112)
			(type default)
		)
		(layer "In15.Cu")
	)
	(gr_line
		(start 399.89252 -409.338272)
		(end 400.536918 -409.06192)
		(stroke
			(width 0.07112)
			(type default)
		)
		(layer "In15.Cu")
	)
	(gr_line
		(start 399.893282 -423.991024)
		(end 399.893536 -423.991024)
		(stroke
			(width 0.07112)
			(type default)
		)
		(layer "In15.Cu")
	)
	(gr_line
		(start 399.893536 -423.99077)
		(end 400.030442 -423.302684)
		(stroke
			(width 0.07112)
			(type default)
		)
		(layer "In15.Cu")
	)
	(gr_line
		(start 399.940018 -410.8069)
		(end 400.119088 -410.877258)
		(stroke
			(width 0.07112)
			(type default)
		)
		(layer "In15.Cu")
	)
	(gr_line
		(start 400.004788 -409.598114)
		(end 400.183604 -409.669488)
		(stroke
			(width 0.07112)
			(type default)
		)
		(layer "In15.Cu")
	)
	(gr_line
		(start 400.119088 -410.877258)
		(end 400.510502 -410.706824)
		(stroke
			(width 0.07112)
			(type default)
		)
		(layer "In15.Cu")
	)
	(gr_line
		(start 400.171666 -424.044618)
		(end 400.331686 -423.937938)
		(stroke
			(width 0.07112)
			(type default)
		)
		(layer "In15.Cu")
	)
	(gr_line
		(start 400.183604 -409.669488)
		(end 400.576034 -409.501594)
		(stroke
			(width 0.07112)
			(type default)
		)
		(layer "In15.Cu")
	)
	(gr_line
		(start 400.331686 -423.937938)
		(end 400.414998 -423.519092)
		(stroke
			(width 0.07112)
			(type default)
		)
		(layer "In15.Cu")
	)
	(gr_line
		(start 400.414998 -423.519092)
		(end 400.308064 -423.359072)
		(stroke
			(width 0.07112)
			(type default)
		)
		(layer "In15.Cu")
	)
	(gr_line
		(start 400.510502 -410.706824)
		(end 400.58086 -410.5275)
		(stroke
			(width 0.07112)
			(type default)
		)
		(layer "In15.Cu")
	)
	(gr_line
		(start 400.576034 -409.501594)
		(end 400.647662 -409.322524)
		(stroke
			(width 0.07112)
			(type default)
		)
		(layer "In15.Cu")
	)
	(gr_line
		(start 400.603466 -438.623202)
		(end 400.59991 -438.623202)
		(stroke
			(width 0.07112)
			(type default)
		)
		(layer "In15.Cu")
	)
	(gr_line
		(start 400.750024 -439.0898)
		(end 400.750024 -438.76976)
		(stroke
			(width 0.07112)
			(type default)
		)
		(layer "In15.Cu")
	)
	(gr_line
		(start 400.750024 -438.76976)
		(end 400.603466 -438.623202)
		(stroke
			(width 0.07112)
			(type default)
		)
		(layer "In15.Cu")
	)
	(gr_line
		(start 400.750024 -438.191148)
		(end 400.60118 -438.339992)
		(stroke
			(width 0.07112)
			(type default)
		)
		(layer "In15.Cu")
	)
	(gr_line
		(start 400.750024 -437.889904)
		(end 400.750024 -438.191148)
		(stroke
			(width 0.07112)
			(type default)
		)
		(layer "In15.Cu")
	)
	(gr_line
		(start 400.859498 -410.09697)
		(end 401.502372 -409.816554)
		(stroke
			(width 0.07112)
			(type default)
		)
		(layer "In15.Cu")
	)
	(gr_line
		(start 400.973798 -410.35605)
		(end 401.152868 -410.426408)
		(stroke
			(width 0.07112)
			(type default)
		)
		(layer "In15.Cu")
	)
	(gr_line
		(start 401.152868 -410.426408)
		(end 401.544282 -410.255974)
		(stroke
			(width 0.07112)
			(type default)
		)
		(layer "In15.Cu")
	)
	(gr_line
		(start 401.391882 -411.195774)
		(end 402.037042 -410.920692)
		(stroke
			(width 0.07112)
			(type default)
		)
		(layer "In15.Cu")
	)
	(gr_line
		(start 401.503642 -411.45587)
		(end 401.682458 -411.527752)
		(stroke
			(width 0.07112)
			(type default)
		)
		(layer "In15.Cu")
	)
	(gr_line
		(start 401.544282 -410.255974)
		(end 401.614386 -410.07665)
		(stroke
			(width 0.07112)
			(type default)
		)
		(layer "In15.Cu")
	)
	(gr_line
		(start 401.682458 -411.527752)
		(end 402.075142 -411.360366)
		(stroke
			(width 0.07112)
			(type default)
		)
		(layer "In15.Cu")
	)
	(gr_line
		(start 401.817332 -417.742878)
		(end 401.817332 -417.041838)
		(stroke
			(width 0.07112)
			(type default)
		)
		(layer "In15.Cu")
	)
	(gr_line
		(start 401.817332 -416.615118)
		(end 401.817332 -415.914078)
		(stroke
			(width 0.07112)
			(type default)
		)
		(layer "In15.Cu")
	)
	(gr_line
		(start 402.075142 -411.360366)
		(end 402.147024 -411.181804)
		(stroke
			(width 0.07112)
			(type default)
		)
		(layer "In15.Cu")
	)
	(gr_line
		(start 402.100542 -417.741608)
		(end 402.236432 -417.605718)
		(stroke
			(width 0.07112)
			(type default)
		)
		(layer "In15.Cu")
	)
	(gr_line
		(start 402.100542 -416.613848)
		(end 402.236432 -416.477958)
		(stroke
			(width 0.07112)
			(type default)
		)
		(layer "In15.Cu")
	)
	(gr_line
		(start 402.15693 -423.984928)
		(end 402.471636 -423.357548)
		(stroke
			(width 0.07112)
			(type default)
		)
		(layer "In15.Cu")
	)
	(gr_line
		(start 402.236432 -417.605718)
		(end 402.236432 -417.178998)
		(stroke
			(width 0.07112)
			(type default)
		)
		(layer "In15.Cu")
	)
	(gr_line
		(start 402.236432 -417.178998)
		(end 402.100542 -417.043108)
		(stroke
			(width 0.07112)
			(type default)
		)
		(layer "In15.Cu")
	)
	(gr_line
		(start 402.236432 -416.477958)
		(end 402.236432 -416.051238)
		(stroke
			(width 0.07112)
			(type default)
		)
		(layer "In15.Cu")
	)
	(gr_line
		(start 402.236432 -416.051238)
		(end 402.100542 -415.915348)
		(stroke
			(width 0.07112)
			(type default)
		)
		(layer "In15.Cu")
	)
	(gr_line
		(start 402.410676 -424.110658)
		(end 402.593556 -424.050206)
		(stroke
			(width 0.07112)
			(type default)
		)
		(layer "In15.Cu")
	)
	(gr_line
		(start 402.471636 -423.357548)
		(end 402.472906 -423.355262)
		(stroke
			(width 0.07112)
			(type default)
		)
		(layer "In15.Cu")
	)
	(gr_line
		(start 402.593556 -424.050206)
		(end 402.784818 -423.668444)
		(stroke
			(width 0.07112)
			(type default)
		)
		(layer "In15.Cu")
	)
	(gr_line
		(start 402.603462 -437.623204)
		(end 402.599906 -437.623204)
		(stroke
			(width 0.07112)
			(type default)
		)
		(layer "In15.Cu")
	)
	(gr_line
		(start 402.710142 -410.63418)
		(end 403.355302 -410.359098)
		(stroke
			(width 0.07112)
			(type default)
		)
		(layer "In15.Cu")
	)
	(gr_line
		(start 402.723858 -423.48404)
		(end 402.725128 -423.481246)
		(stroke
			(width 0.07112)
			(type default)
		)
		(layer "In15.Cu")
	)
	(gr_line
		(start 402.731732 -423.469308)
		(end 402.732748 -423.46753)
		(stroke
			(width 0.07112)
			(type default)
		)
		(layer "In15.Cu")
	)
	(gr_line
		(start 402.75002 -438.089802)
		(end 402.75002 -437.769762)
		(stroke
			(width 0.07112)
			(type default)
		)
		(layer "In15.Cu")
	)
	(gr_line
		(start 402.75002 -437.769762)
		(end 402.603462 -437.623204)
		(stroke
			(width 0.07112)
			(type default)
		)
		(layer "In15.Cu")
	)
	(gr_line
		(start 402.75002 -437.19115)
		(end 402.601176 -437.339994)
		(stroke
			(width 0.07112)
			(type default)
		)
		(layer "In15.Cu")
	)
	(gr_line
		(start 402.75002 -436.889906)
		(end 402.75002 -437.19115)
		(stroke
			(width 0.07112)
			(type default)
		)
		(layer "In15.Cu")
	)
	(gr_line
		(start 402.784818 -423.668444)
		(end 402.724112 -423.485818)
		(stroke
			(width 0.07112)
			(type default)
		)
		(layer "In15.Cu")
	)
	(gr_line
		(start 402.809456 -422.790366)
		(end 403.169882 -422.18864)
		(stroke
			(width 0.07112)
			(type default)
		)
		(layer "In15.Cu")
	)
	(gr_line
		(start 402.821902 -410.894276)
		(end 403.000464 -410.966158)
		(stroke
			(width 0.07112)
			(type default)
		)
		(layer "In15.Cu")
	)
	(gr_line
		(start 402.982684 -409.23337)
		(end 403.656292 -409.03779)
		(stroke
			(width 0.07112)
			(type default)
		)
		(layer "In15.Cu")
	)
	(gr_line
		(start 403.000464 -410.966158)
		(end 403.393402 -410.798772)
		(stroke
			(width 0.07112)
			(type default)
		)
		(layer "In15.Cu")
	)
	(gr_line
		(start 403.053042 -422.934638)
		(end 403.239732 -422.887902)
		(stroke
			(width 0.07112)
			(type default)
		)
		(layer "In15.Cu")
	)
	(gr_line
		(start 403.062694 -409.50515)
		(end 403.23135 -409.598114)
		(stroke
			(width 0.07112)
			(type default)
		)
		(layer "In15.Cu")
	)
	(gr_line
		(start 403.153372 -401.384008)
		(end 403.444202 -401.674838)
		(stroke
			(width 0.07112)
			(type default)
		)
		(layer "In15.Cu")
	)
	(gr_line
		(start 403.153372 -401.102068)
		(end 403.444202 -400.811238)
		(stroke
			(width 0.07112)
			(type default)
		)
		(layer "In15.Cu")
	)
	(gr_line
		(start 403.23135 -409.598114)
		(end 403.64156 -409.479242)
		(stroke
			(width 0.07112)
			(type default)
		)
		(layer "In15.Cu")
	)
	(gr_line
		(start 403.239732 -422.887902)
		(end 403.458934 -422.521634)
		(stroke
			(width 0.07112)
			(type default)
		)
		(layer "In15.Cu")
	)
	(gr_line
		(start 403.393402 -410.798772)
		(end 403.465284 -410.62021)
		(stroke
			(width 0.07112)
			(type default)
		)
		(layer "In15.Cu")
	)
	(gr_line
		(start 403.458934 -422.521634)
		(end 403.412198 -422.334944)
		(stroke
			(width 0.07112)
			(type default)
		)
		(layer "In15.Cu")
	)
	(gr_line
		(start 403.64156 -409.479242)
		(end 403.73427 -409.310078)
		(stroke
			(width 0.07112)
			(type default)
		)
		(layer "In15.Cu")
	)
	(gr_line
		(start 403.656292 -409.03779)
		(end 403.656292 -409.038044)
		(stroke
			(width 0.07112)
			(type default)
		)
		(layer "In15.Cu")
	)
	(gr_line
		(start 403.747732 -410.191966)
		(end 404.392892 -409.917138)
		(stroke
			(width 0.07112)
			(type default)
		)
		(layer "In15.Cu")
	)
	(gr_line
		(start 403.859746 -410.452062)
		(end 404.038054 -410.523944)
		(stroke
			(width 0.07112)
			(type default)
		)
		(layer "In15.Cu")
	)
	(gr_line
		(start 404.038054 -410.523944)
		(end 404.430992 -410.356558)
		(stroke
			(width 0.07112)
			(type default)
		)
		(layer "In15.Cu")
	)
	(gr_line
		(start 404.430992 -410.356558)
		(end 404.50262 -410.177996)
		(stroke
			(width 0.07112)
			(type default)
		)
		(layer "In15.Cu")
	)
	(gr_line
		(start 404.442676 -423.637964)
		(end 404.93315 -423.136314)
		(stroke
			(width 0.07112)
			(type default)
		)
		(layer "In15.Cu")
	)
	(gr_line
		(start 404.505668 -401.399756)
		(end 404.517098 -401.399756)
		(stroke
			(width 0.07112)
			(type default)
		)
		(layer "In15.Cu")
	)
	(gr_line
		(start 404.506938 -401.116546)
		(end 404.644098 -400.979386)
		(stroke
			(width 0.07112)
			(type default)
		)
		(layer "In15.Cu")
	)
	(gr_line
		(start 404.517098 -401.399756)
		(end 404.644098 -401.526756)
		(stroke
			(width 0.07112)
			(type default)
		)
		(layer "In15.Cu")
	)
	(gr_line
		(start 404.603458 -438.623202)
		(end 404.599902 -438.623202)
		(stroke
			(width 0.07112)
			(type default)
		)
		(layer "In15.Cu")
	)
	(gr_line
		(start 404.644098 -401.526756)
		(end 404.644098 -401.674838)
		(stroke
			(width 0.07112)
			(type default)
		)
		(layer "In15.Cu")
	)
	(gr_line
		(start 404.644098 -400.979386)
		(end 404.644098 -400.811238)
		(stroke
			(width 0.07112)
			(type default)
		)
		(layer "In15.Cu")
	)
	(gr_line
		(start 404.645876 -423.835068)
		(end 404.838408 -423.833036)
		(stroke
			(width 0.07112)
			(type default)
		)
		(layer "In15.Cu")
	)
	(gr_line
		(start 404.750016 -439.0898)
		(end 404.750016 -438.76976)
		(stroke
			(width 0.07112)
			(type default)
		)
		(layer "In15.Cu")
	)
	(gr_line
		(start 404.750016 -438.76976)
		(end 404.603458 -438.623202)
		(stroke
			(width 0.07112)
			(type default)
		)
		(layer "In15.Cu")
	)
	(gr_line
		(start 404.750016 -438.191148)
		(end 404.601172 -438.339992)
		(stroke
			(width 0.07112)
			(type default)
		)
		(layer "In15.Cu")
	)
	(gr_line
		(start 404.750016 -437.889904)
		(end 404.750016 -438.191148)
		(stroke
			(width 0.07112)
			(type default)
		)
		(layer "In15.Cu")
	)
	(gr_line
		(start 404.838408 -423.833036)
		(end 405.136858 -423.527474)
		(stroke
			(width 0.07112)
			(type default)
		)
		(layer "In15.Cu")
	)
	(gr_line
		(start 404.880572 -417.797234)
		(end 404.880572 -417.096194)
		(stroke
			(width 0.07112)
			(type default)
		)
		(layer "In15.Cu")
	)
	(gr_line
		(start 404.880572 -416.669474)
		(end 404.880572 -415.968434)
		(stroke
			(width 0.07112)
			(type default)
		)
		(layer "In15.Cu")
	)
	(gr_line
		(start 404.929086 -404.480268)
		(end 404.928832 -404.480268)
		(stroke
			(width 0.07112)
			(type default)
		)
		(layer "In15.Cu")
	)
	(gr_line
		(start 405.111966 -410.792676)
		(end 405.759666 -410.524198)
		(stroke
			(width 0.07112)
			(type default)
		)
		(layer "In15.Cu")
	)
	(gr_line
		(start 405.136858 -423.527474)
		(end 405.134826 -423.335196)
		(stroke
			(width 0.07112)
			(type default)
		)
		(layer "In15.Cu")
	)
	(gr_line
		(start 405.163782 -417.795964)
		(end 405.299672 -417.660074)
		(stroke
			(width 0.07112)
			(type default)
		)
		(layer "In15.Cu")
	)
	(gr_line
		(start 405.163782 -416.668204)
		(end 405.299672 -416.532314)
		(stroke
			(width 0.07112)
			(type default)
		)
		(layer "In15.Cu")
	)
	(gr_line
		(start 405.22144 -411.053788)
		(end 405.398986 -411.127702)
		(stroke
			(width 0.07112)
			(type default)
		)
		(layer "In15.Cu")
	)
	(gr_line
		(start 405.231346 -422.831514)
		(end 405.721566 -422.330118)
		(stroke
			(width 0.07112)
			(type default)
		)
		(layer "In15.Cu")
	)
	(gr_line
		(start 405.299672 -417.660074)
		(end 405.299672 -417.233354)
		(stroke
			(width 0.07112)
			(type default)
		)
		(layer "In15.Cu")
	)
	(gr_line
		(start 405.299672 -417.233354)
		(end 405.163782 -417.097464)
		(stroke
			(width 0.07112)
			(type default)
		)
		(layer "In15.Cu")
	)
	(gr_line
		(start 405.299672 -416.532314)
		(end 405.299672 -416.105594)
		(stroke
			(width 0.07112)
			(type default)
		)
		(layer "In15.Cu")
	)
	(gr_line
		(start 405.299672 -416.105594)
		(end 405.163782 -415.969704)
		(stroke
			(width 0.07112)
			(type default)
		)
		(layer "In15.Cu")
	)
	(gr_line
		(start 405.398986 -411.127702)
		(end 405.793448 -410.96438)
		(stroke
			(width 0.07112)
			(type default)
		)
		(layer "In15.Cu")
	)
	(gr_line
		(start 405.434546 -423.028618)
		(end 405.627078 -423.026586)
		(stroke
			(width 0.07112)
			(type default)
		)
		(layer "In15.Cu")
	)
	(gr_line
		(start 405.49449 -408.478482)
		(end 406.15489 -408.242008)
		(stroke
			(width 0.07112)
			(type default)
		)
		(layer "In15.Cu")
	)
	(gr_line
		(start 405.59101 -408.744674)
		(end 405.69261 -408.79268)
		(stroke
			(width 0.07112)
			(type default)
		)
		(layer "In15.Cu")
	)
	(gr_line
		(start 405.627078 -423.026586)
		(end 405.925528 -422.721024)
		(stroke
			(width 0.07112)
			(type default)
		)
		(layer "In15.Cu")
	)
	(gr_line
		(start 405.69261 -408.79268)
		(end 406.201118 -408.610816)
		(stroke
			(width 0.07112)
			(type default)
		)
		(layer "In15.Cu")
	)
	(gr_line
		(start 405.705818 -401.399756)
		(end 405.717248 -401.399756)
		(stroke
			(width 0.07112)
			(type default)
		)
		(layer "In15.Cu")
	)
	(gr_line
		(start 405.707088 -401.116546)
		(end 405.844248 -400.979386)
		(stroke
			(width 0.07112)
			(type default)
		)
		(layer "In15.Cu")
	)
	(gr_line
		(start 405.717248 -401.399756)
		(end 405.844248 -401.526756)
		(stroke
			(width 0.07112)
			(type default)
		)
		(layer "In15.Cu")
	)
	(gr_line
		(start 405.793448 -410.96438)
		(end 405.866854 -410.786326)
		(stroke
			(width 0.07112)
			(type default)
		)
		(layer "In15.Cu")
	)
	(gr_line
		(start 405.844248 -401.526756)
		(end 405.844248 -401.674838)
		(stroke
			(width 0.07112)
			(type default)
		)
		(layer "In15.Cu")
	)
	(gr_line
		(start 405.844248 -400.979386)
		(end 405.844248 -400.811238)
		(stroke
			(width 0.07112)
			(type default)
		)
		(layer "In15.Cu")
	)
	(gr_line
		(start 405.925528 -422.721024)
		(end 405.923242 -422.528746)
		(stroke
			(width 0.07112)
			(type default)
		)
		(layer "In15.Cu")
	)
	(gr_line
		(start 406.183592 -410.348684)
		(end 406.831292 -410.080206)
		(stroke
			(width 0.07112)
			(type default)
		)
		(layer "In15.Cu")
	)
	(gr_line
		(start 406.201118 -408.610816)
		(end 406.249124 -408.509216)
		(stroke
			(width 0.07112)
			(type default)
		)
		(layer "In15.Cu")
	)
	(gr_line
		(start 406.293066 -410.609796)
		(end 406.470612 -410.683456)
		(stroke
			(width 0.07112)
			(type default)
		)
		(layer "In15.Cu")
	)
	(gr_line
		(start 406.46096 -423.706036)
		(end 407.04516 -423.317162)
		(stroke
			(width 0.07112)
			(type default)
		)
		(layer "In15.Cu")
	)
	(gr_line
		(start 406.470612 -410.683456)
		(end 406.865074 -410.520134)
		(stroke
			(width 0.07112)
			(type default)
		)
		(layer "In15.Cu")
	)
	(gr_line
		(start 406.603454 -437.623204)
		(end 406.599898 -437.623204)
		(stroke
			(width 0.07112)
			(type default)
		)
		(layer "In15.Cu")
	)
	(gr_line
		(start 406.618948 -423.940986)
		(end 406.80767 -423.978832)
		(stroke
			(width 0.07112)
			(type default)
		)
		(layer "In15.Cu")
	)
	(gr_line
		(start 406.750012 -438.089802)
		(end 406.750012 -437.769762)
		(stroke
			(width 0.07112)
			(type default)
		)
		(layer "In15.Cu")
	)
	(gr_line
		(start 406.750012 -437.769762)
		(end 406.603454 -437.623204)
		(stroke
			(width 0.07112)
			(type default)
		)
		(layer "In15.Cu")
	)
	(gr_line
		(start 406.750012 -437.19115)
		(end 406.601168 -437.339994)
		(stroke
			(width 0.07112)
			(type default)
		)
		(layer "In15.Cu")
	)
	(gr_line
		(start 406.750012 -436.889906)
		(end 406.750012 -437.19115)
		(stroke
			(width 0.07112)
			(type default)
		)
		(layer "In15.Cu")
	)
	(gr_line
		(start 406.80767 -423.978832)
		(end 407.16327 -423.742358)
		(stroke
			(width 0.07112)
			(type default)
		)
		(layer "In15.Cu")
	)
	(gr_line
		(start 406.865074 -410.520134)
		(end 406.93848 -410.342334)
		(stroke
			(width 0.07112)
			(type default)
		)
		(layer "In15.Cu")
	)
	(gr_line
		(start 406.905714 -401.399756)
		(end 406.917144 -401.399756)
		(stroke
			(width 0.07112)
			(type default)
		)
		(layer "In15.Cu")
	)
	(gr_line
		(start 406.906984 -401.116546)
		(end 407.044144 -400.979386)
		(stroke
			(width 0.07112)
			(type default)
		)
		(layer "In15.Cu")
	)
	(gr_line
		(start 406.917144 -401.399756)
		(end 407.044144 -401.526756)
		(stroke
			(width 0.07112)
			(type default)
		)
		(layer "In15.Cu")
	)
	(gr_line
		(start 407.044144 -401.526756)
		(end 407.044144 -401.674838)
		(stroke
			(width 0.07112)
			(type default)
		)
		(layer "In15.Cu")
	)
	(gr_line
		(start 407.044144 -400.979386)
		(end 407.044144 -400.811238)
		(stroke
			(width 0.07112)
			(type default)
		)
		(layer "In15.Cu")
	)
	(gr_line
		(start 407.16327 -423.742358)
		(end 407.201116 -423.553636)
		(stroke
			(width 0.07112)
			(type default)
		)
		(layer "In15.Cu")
	)
	(gr_line
		(start 407.836624 -422.79062)
		(end 408.42057 -422.402)
		(stroke
			(width 0.07112)
			(type default)
		)
		(layer "In15.Cu")
	)
	(gr_line
		(start 407.943812 -417.769294)
		(end 407.943812 -417.068254)
		(stroke
			(width 0.07112)
			(type default)
		)
		(layer "In15.Cu")
	)
	(gr_line
		(start 407.943812 -416.641534)
		(end 407.943812 -415.940494)
		(stroke
			(width 0.07112)
			(type default)
		)
		(layer "In15.Cu")
	)
	(gr_line
		(start 407.994104 -423.025824)
		(end 408.18308 -423.06367)
		(stroke
			(width 0.07112)
			(type default)
		)
		(layer "In15.Cu")
	)
	(gr_line
		(start 408.105864 -401.399756)
		(end 408.117294 -401.399756)
		(stroke
			(width 0.07112)
			(type default)
		)
		(layer "In15.Cu")
	)
	(gr_line
		(start 408.107134 -401.116546)
		(end 408.244294 -400.979386)
		(stroke
			(width 0.07112)
			(type default)
		)
		(layer "In15.Cu")
	)
	(gr_line
		(start 408.117294 -401.399756)
		(end 408.244294 -401.526756)
		(stroke
			(width 0.07112)
			(type default)
		)
		(layer "In15.Cu")
	)
	(gr_line
		(start 408.18308 -423.06367)
		(end 408.538426 -422.827196)
		(stroke
			(width 0.07112)
			(type default)
		)
		(layer "In15.Cu")
	)
	(gr_line
		(start 408.20975 -410.656532)
		(end 408.78887 -410.2608)
		(stroke
			(width 0.07112)
			(type default)
		)
		(layer "In15.Cu")
	)
	(gr_line
		(start 408.227022 -417.768024)
		(end 408.362912 -417.632134)
		(stroke
			(width 0.07112)
			(type default)
		)
		(layer "In15.Cu")
	)
	(gr_line
		(start 408.227022 -416.640264)
		(end 408.362912 -416.504374)
		(stroke
			(width 0.07112)
			(type default)
		)
		(layer "In15.Cu")
	)
	(gr_line
		(start 408.244294 -401.526756)
		(end 408.244294 -401.674838)
		(stroke
			(width 0.07112)
			(type default)
		)
		(layer "In15.Cu")
	)
	(gr_line
		(start 408.244294 -400.979386)
		(end 408.244294 -400.811238)
		(stroke
			(width 0.07112)
			(type default)
		)
		(layer "In15.Cu")
	)
	(gr_line
		(start 408.362912 -417.632134)
		(end 408.362912 -417.205414)
		(stroke
			(width 0.07112)
			(type default)
		)
		(layer "In15.Cu")
	)
	(gr_line
		(start 408.362912 -417.205414)
		(end 408.227022 -417.069524)
		(stroke
			(width 0.07112)
			(type default)
		)
		(layer "In15.Cu")
	)
	(gr_line
		(start 408.362912 -416.504374)
		(end 408.362912 -416.077654)
		(stroke
			(width 0.07112)
			(type default)
		)
		(layer "In15.Cu")
	)
	(gr_line
		(start 408.362912 -416.077654)
		(end 408.227022 -415.941764)
		(stroke
			(width 0.07112)
			(type default)
		)
		(layer "In15.Cu")
	)
	(gr_line
		(start 408.370532 -410.889704)
		(end 408.559762 -410.925264)
		(stroke
			(width 0.07112)
			(type default)
		)
		(layer "In15.Cu")
	)
	(gr_line
		(start 408.538426 -422.827196)
		(end 408.576526 -422.63822)
		(stroke
			(width 0.07112)
			(type default)
		)
		(layer "In15.Cu")
	)
	(gr_line
		(start 408.559762 -410.925264)
		(end 408.912314 -410.684218)
		(stroke
			(width 0.07112)
			(type default)
		)
		(layer "In15.Cu")
	)
	(gr_line
		(start 408.60345 -438.623202)
		(end 408.599894 -438.623202)
		(stroke
			(width 0.07112)
			(type default)
		)
		(layer "In15.Cu")
	)
	(gr_line
		(start 408.673554 -423.585894)
		(end 409.292298 -423.255186)
		(stroke
			(width 0.07112)
			(type default)
		)
		(layer "In15.Cu")
	)
	(gr_line
		(start 408.750008 -439.0898)
		(end 408.750008 -438.76976)
		(stroke
			(width 0.07112)
			(type default)
		)
		(layer "In15.Cu")
	)
	(gr_line
		(start 408.750008 -438.76976)
		(end 408.60345 -438.623202)
		(stroke
			(width 0.07112)
			(type default)
		)
		(layer "In15.Cu")
	)
	(gr_line
		(start 408.750008 -438.191148)
		(end 408.601164 -438.339992)
		(stroke
			(width 0.07112)
			(type default)
		)
		(layer "In15.Cu")
	)
	(gr_line
		(start 408.750008 -437.889904)
		(end 408.750008 -438.191148)
		(stroke
			(width 0.07112)
			(type default)
		)
		(layer "In15.Cu")
	)
	(gr_line
		(start 408.808174 -423.835068)
		(end 408.992324 -423.890948)
		(stroke
			(width 0.07112)
			(type default)
		)
		(layer "In15.Cu")
	)
	(gr_line
		(start 408.912314 -410.684218)
		(end 408.947874 -410.495242)
		(stroke
			(width 0.07112)
			(type default)
		)
		(layer "In15.Cu")
	)
	(gr_line
		(start 408.992324 -423.890948)
		(end 409.368752 -423.68978)
		(stroke
			(width 0.07112)
			(type default)
		)
		(layer "In15.Cu")
	)
	(gr_line
		(start 409.140914 -410.020008)
		(end 409.720288 -409.624276)
		(stroke
			(width 0.07112)
			(type default)
		)
		(layer "In15.Cu")
	)
	(gr_line
		(start 409.301696 -410.25318)
		(end 409.490926 -410.28874)
		(stroke
			(width 0.07112)
			(type default)
		)
		(layer "In15.Cu")
	)
	(gr_line
		(start 409.30576 -401.399756)
		(end 409.31719 -401.399756)
		(stroke
			(width 0.07112)
			(type default)
		)
		(layer "In15.Cu")
	)
	(gr_line
		(start 409.30703 -401.116546)
		(end 409.44419 -400.979386)
		(stroke
			(width 0.07112)
			(type default)
		)
		(layer "In15.Cu")
	)
	(gr_line
		(start 409.31719 -401.399756)
		(end 409.44419 -401.526756)
		(stroke
			(width 0.07112)
			(type default)
		)
		(layer "In15.Cu")
	)
	(gr_line
		(start 409.368752 -423.68978)
		(end 409.424632 -423.505376)
		(stroke
			(width 0.07112)
			(type default)
		)
		(layer "In15.Cu")
	)
	(gr_line
		(start 409.44419 -401.526756)
		(end 409.44419 -401.674838)
		(stroke
			(width 0.07112)
			(type default)
		)
		(layer "In15.Cu")
	)
	(gr_line
		(start 409.44419 -400.979386)
		(end 409.44419 -400.811238)
		(stroke
			(width 0.07112)
			(type default)
		)
		(layer "In15.Cu")
	)
	(gr_line
		(start 409.490926 -410.28874)
		(end 409.843478 -410.047694)
		(stroke
			(width 0.07112)
			(type default)
		)
		(layer "In15.Cu")
	)
	(gr_line
		(start 409.61437 -408.295094)
		(end 410.110432 -407.799286)
		(stroke
			(width 0.07112)
			(type default)
		)
		(layer "In15.Cu")
	)
	(gr_line
		(start 409.815284 -408.494738)
		(end 410.007562 -408.494738)
		(stroke
			(width 0.07112)
			(type default)
		)
		(layer "In15.Cu")
	)
	(gr_line
		(start 409.843478 -410.047694)
		(end 409.879038 -409.858718)
		(stroke
			(width 0.07112)
			(type default)
		)
		(layer "In15.Cu")
	)
	(gr_line
		(start 410.007562 -408.494738)
		(end 410.309822 -408.192732)
		(stroke
			(width 0.07112)
			(type default)
		)
		(layer "In15.Cu")
	)
	(gr_line
		(start 410.04871 -411.333696)
		(end 410.51988 -410.814012)
		(stroke
			(width 0.07112)
			(type default)
		)
		(layer "In15.Cu")
	)
	(gr_line
		(start 410.25953 -411.52318)
		(end 410.451554 -411.513528)
		(stroke
			(width 0.07112)
			(type default)
		)
		(layer "In15.Cu")
	)
	(gr_line
		(start 410.309822 -408.192732)
		(end 410.309822 -408.000454)
		(stroke
			(width 0.07112)
			(type default)
		)
		(layer "In15.Cu")
	)
	(gr_line
		(start 410.41193 -409.061666)
		(end 410.907738 -408.565858)
		(stroke
			(width 0.07112)
			(type default)
		)
		(layer "In15.Cu")
	)
	(gr_line
		(start 410.41193 -407.497788)
		(end 410.907992 -407.00198)
		(stroke
			(width 0.07112)
			(type default)
		)
		(layer "In15.Cu")
	)
	(gr_line
		(start 410.451554 -411.513528)
		(end 410.73832 -411.197044)
		(stroke
			(width 0.07112)
			(type default)
		)
		(layer "In15.Cu")
	)
	(gr_line
		(start 410.50591 -401.399756)
		(end 410.51734 -401.399756)
		(stroke
			(width 0.07112)
			(type default)
		)
		(layer "In15.Cu")
	)
	(gr_line
		(start 410.50718 -401.116546)
		(end 410.64434 -400.979386)
		(stroke
			(width 0.07112)
			(type default)
		)
		(layer "In15.Cu")
	)
	(gr_line
		(start 410.51734 -401.399756)
		(end 410.64434 -401.526756)
		(stroke
			(width 0.07112)
			(type default)
		)
		(layer "In15.Cu")
	)
	(gr_line
		(start 410.603446 -437.623204)
		(end 410.59989 -437.623204)
		(stroke
			(width 0.07112)
			(type default)
		)
		(layer "In15.Cu")
	)
	(gr_line
		(start 410.612844 -409.26131)
		(end 410.805122 -409.26131)
		(stroke
			(width 0.07112)
			(type default)
		)
		(layer "In15.Cu")
	)
	(gr_line
		(start 410.612844 -407.697432)
		(end 410.805376 -407.697432)
		(stroke
			(width 0.07112)
			(type default)
		)
		(layer "In15.Cu")
	)
	(gr_line
		(start 410.64434 -401.526756)
		(end 410.64434 -401.674838)
		(stroke
			(width 0.07112)
			(type default)
		)
		(layer "In15.Cu")
	)
	(gr_line
		(start 410.64434 -400.979386)
		(end 410.64434 -400.811238)
		(stroke
			(width 0.07112)
			(type default)
		)
		(layer "In15.Cu")
	)
	(gr_line
		(start 410.73832 -411.197044)
		(end 410.728668 -411.005274)
		(stroke
			(width 0.07112)
			(type default)
		)
		(layer "In15.Cu")
	)
	(gr_line
		(start 410.750004 -438.089802)
		(end 410.750004 -437.769762)
		(stroke
			(width 0.07112)
			(type default)
		)
		(layer "In15.Cu")
	)
	(gr_line
		(start 410.750004 -437.769762)
		(end 410.603446 -437.623204)
		(stroke
			(width 0.07112)
			(type default)
		)
		(layer "In15.Cu")
	)
	(gr_line
		(start 410.750004 -437.19115)
		(end 410.60116 -437.339994)
		(stroke
			(width 0.07112)
			(type default)
		)
		(layer "In15.Cu")
	)
	(gr_line
		(start 410.750004 -436.889906)
		(end 410.750004 -437.19115)
		(stroke
			(width 0.07112)
			(type default)
		)
		(layer "In15.Cu")
	)
	(gr_line
		(start 410.805122 -409.26131)
		(end 411.107128 -408.959304)
		(stroke
			(width 0.07112)
			(type default)
		)
		(layer "In15.Cu")
	)
	(gr_line
		(start 410.805376 -407.697432)
		(end 411.107382 -407.395426)
		(stroke
			(width 0.07112)
			(type default)
		)
		(layer "In15.Cu")
	)
	(gr_line
		(start 410.806138 -410.498036)
		(end 411.277308 -409.978352)
		(stroke
			(width 0.07112)
			(type default)
		)
		(layer "In15.Cu")
	)
	(gr_line
		(start 411.007052 -418.022024)
		(end 411.007052 -417.320984)
		(stroke
			(width 0.07112)
			(type default)
		)
		(layer "In15.Cu")
	)
	(gr_line
		(start 411.007052 -416.894264)
		(end 411.007052 -416.193224)
		(stroke
			(width 0.07112)
			(type default)
		)
		(layer "In15.Cu")
	)
	(gr_line
		(start 411.016704 -410.68752)
		(end 411.208728 -410.677868)
		(stroke
			(width 0.07112)
			(type default)
		)
		(layer "In15.Cu")
	)
	(gr_line
		(start 411.107128 -408.959304)
		(end 411.107128 -408.767026)
		(stroke
			(width 0.07112)
			(type default)
		)
		(layer "In15.Cu")
	)
	(gr_line
		(start 411.107382 -407.395426)
		(end 411.107382 -407.202894)
		(stroke
			(width 0.07112)
			(type default)
		)
		(layer "In15.Cu")
	)
	(gr_line
		(start 411.208728 -410.677868)
		(end 411.495748 -410.361384)
		(stroke
			(width 0.07112)
			(type default)
		)
		(layer "In15.Cu")
	)
	(gr_line
		(start 411.20949 -408.264106)
		(end 411.705298 -407.768298)
		(stroke
			(width 0.07112)
			(type default)
		)
		(layer "In15.Cu")
	)
	(gr_line
		(start 411.290262 -418.020754)
		(end 411.426152 -417.884864)
		(stroke
			(width 0.07112)
			(type default)
		)
		(layer "In15.Cu")
	)
	(gr_line
		(start 411.290262 -416.892994)
		(end 411.426152 -416.757104)
		(stroke
			(width 0.07112)
			(type default)
		)
		(layer "In15.Cu")
	)
	(gr_line
		(start 411.410404 -408.46375)
		(end 411.602682 -408.46375)
		(stroke
			(width 0.07112)
			(type default)
		)
		(layer "In15.Cu")
	)
	(gr_line
		(start 411.426152 -417.884864)
		(end 411.426152 -417.458144)
		(stroke
			(width 0.07112)
			(type default)
		)
		(layer "In15.Cu")
	)
	(gr_line
		(start 411.426152 -417.458144)
		(end 411.290262 -417.322254)
		(stroke
			(width 0.07112)
			(type default)
		)
		(layer "In15.Cu")
	)
	(gr_line
		(start 411.426152 -416.757104)
		(end 411.426152 -416.330384)
		(stroke
			(width 0.07112)
			(type default)
		)
		(layer "In15.Cu")
	)
	(gr_line
		(start 411.426152 -416.330384)
		(end 411.290262 -416.194494)
		(stroke
			(width 0.07112)
			(type default)
		)
		(layer "In15.Cu")
	)
	(gr_line
		(start 411.495748 -410.361384)
		(end 411.486096 -410.169614)
		(stroke
			(width 0.07112)
			(type default)
		)
		(layer "In15.Cu")
	)
	(gr_line
		(start 411.563566 -409.662376)
		(end 412.034736 -409.142692)
		(stroke
			(width 0.07112)
			(type default)
		)
		(layer "In15.Cu")
	)
	(gr_line
		(start 411.578298 -406.274778)
		(end 412.023306 -405.732488)
		(stroke
			(width 0.07112)
			(type default)
		)
		(layer "In15.Cu")
	)
	(gr_line
		(start 411.602682 -408.46375)
		(end 411.904688 -408.161744)
		(stroke
			(width 0.07112)
			(type default)
		)
		(layer "In15.Cu")
	)
	(gr_line
		(start 411.705298 -404.397972)
		(end 411.772608 -404.302468)
		(stroke
			(width 0.07112)
			(type default)
		)
		(layer "In15.Cu")
	)
	(gr_line
		(start 411.705806 -401.399756)
		(end 411.717236 -401.399756)
		(stroke
			(width 0.07112)
			(type default)
		)
		(layer "In15.Cu")
	)
	(gr_line
		(start 411.707076 -401.116546)
		(end 411.844236 -400.979386)
		(stroke
			(width 0.07112)
			(type default)
		)
		(layer "In15.Cu")
	)
	(gr_line
		(start 411.717236 -401.399756)
		(end 411.844236 -401.526756)
		(stroke
			(width 0.07112)
			(type default)
		)
		(layer "In15.Cu")
	)
	(gr_line
		(start 411.772354 -404.302468)
		(end 412.109158 -403.82444)
		(stroke
			(width 0.07112)
			(type default)
		)
		(layer "In15.Cu")
	)
	(gr_line
		(start 411.772608 -404.302468)
		(end 411.772354 -404.302468)
		(stroke
			(width 0.07112)
			(type default)
		)
		(layer "In15.Cu")
	)
	(gr_line
		(start 411.774132 -409.85186)
		(end 411.966156 -409.842208)
		(stroke
			(width 0.07112)
			(type default)
		)
		(layer "In15.Cu")
	)
	(gr_line
		(start 411.797754 -406.45334)
		(end 411.98927 -406.434544)
		(stroke
			(width 0.07112)
			(type default)
		)
		(layer "In15.Cu")
	)
	(gr_line
		(start 411.844236 -401.526756)
		(end 411.844236 -401.674838)
		(stroke
			(width 0.07112)
			(type default)
		)
		(layer "In15.Cu")
	)
	(gr_line
		(start 411.844236 -400.979386)
		(end 411.844236 -400.811238)
		(stroke
			(width 0.07112)
			(type default)
		)
		(layer "In15.Cu")
	)
	(gr_line
		(start 411.904688 -408.161744)
		(end 411.904688 -407.969466)
		(stroke
			(width 0.07112)
			(type default)
		)
		(layer "In15.Cu")
	)
	(gr_line
		(start 411.937708 -404.560024)
		(end 412.127192 -404.527004)
		(stroke
			(width 0.07112)
			(type default)
		)
		(layer "In15.Cu")
	)
	(gr_line
		(start 411.966156 -409.842208)
		(end 412.253176 -409.525724)
		(stroke
			(width 0.07112)
			(type default)
		)
		(layer "In15.Cu")
	)
	(gr_line
		(start 411.98927 -406.434544)
		(end 412.260288 -406.104598)
		(stroke
			(width 0.07112)
			(type default)
		)
		(layer "In15.Cu")
	)
	(gr_line
		(start 412.127192 -404.527004)
		(end 412.373064 -404.178008)
		(stroke
			(width 0.07112)
			(type default)
		)
		(layer "In15.Cu")
	)
	(gr_line
		(start 412.253176 -409.525724)
		(end 412.243524 -409.333954)
		(stroke
			(width 0.07112)
			(type default)
		)
		(layer "In15.Cu")
	)
	(gr_line
		(start 412.260288 -406.104598)
		(end 412.241746 -405.912828)
		(stroke
			(width 0.07112)
			(type default)
		)
		(layer "In15.Cu")
	)
	(gr_line
		(start 412.320994 -408.826716)
		(end 412.79191 -408.307032)
		(stroke
			(width 0.07112)
			(type default)
		)
		(layer "In15.Cu")
	)
	(gr_line
		(start 412.373064 -404.178008)
		(end 412.340044 -403.98827)
		(stroke
			(width 0.07112)
			(type default)
		)
		(layer "In15.Cu")
	)
	(gr_line
		(start 412.53156 -409.0162)
		(end 412.723584 -409.006548)
		(stroke
			(width 0.07112)
			(type default)
		)
		(layer "In15.Cu")
	)
	(gr_line
		(start 412.603442 -438.623202)
		(end 412.599886 -438.623202)
		(stroke
			(width 0.07112)
			(type default)
		)
		(layer "In15.Cu")
	)
	(gr_line
		(start 412.723584 -409.006548)
		(end 413.010604 -408.690064)
		(stroke
			(width 0.07112)
			(type default)
		)
		(layer "In15.Cu")
	)
	(gr_line
		(start 412.75 -439.0898)
		(end 412.75 -438.76976)
		(stroke
			(width 0.07112)
			(type default)
		)
		(layer "In15.Cu")
	)
	(gr_line
		(start 412.75 -438.76976)
		(end 412.603442 -438.623202)
		(stroke
			(width 0.07112)
			(type default)
		)
		(layer "In15.Cu")
	)
	(gr_line
		(start 412.75 -438.191148)
		(end 412.601156 -438.339992)
		(stroke
			(width 0.07112)
			(type default)
		)
		(layer "In15.Cu")
	)
	(gr_line
		(start 412.75 -437.889904)
		(end 412.75 -438.191148)
		(stroke
			(width 0.07112)
			(type default)
		)
		(layer "In15.Cu")
	)
	(gr_line
		(start 412.800292 -406.575006)
		(end 413.204406 -406.00122)
		(stroke
			(width 0.07112)
			(type default)
		)
		(layer "In15.Cu")
	)
	(gr_line
		(start 412.905956 -401.399756)
		(end 412.917386 -401.399756)
		(stroke
			(width 0.07112)
			(type default)
		)
		(layer "In15.Cu")
	)
	(gr_line
		(start 412.907226 -401.116546)
		(end 413.044386 -400.979386)
		(stroke
			(width 0.07112)
			(type default)
		)
		(layer "In15.Cu")
	)
	(gr_line
		(start 412.912052 -411.178502)
		(end 413.272732 -410.576776)
		(stroke
			(width 0.07112)
			(type default)
		)
		(layer "In15.Cu")
	)
	(gr_line
		(start 412.917386 -401.399756)
		(end 413.044386 -401.526756)
		(stroke
			(width 0.07112)
			(type default)
		)
		(layer "In15.Cu")
	)
	(gr_line
		(start 412.981394 -423.705782)
		(end 413.661606 -423.535094)
		(stroke
			(width 0.07112)
			(type default)
		)
		(layer "In15.Cu")
	)
	(gr_line
		(start 413.010604 -408.690064)
		(end 413.000952 -408.498294)
		(stroke
			(width 0.07112)
			(type default)
		)
		(layer "In15.Cu")
	)
	(gr_line
		(start 413.032448 -406.737058)
		(end 413.222186 -406.704038)
		(stroke
			(width 0.07112)
			(type default)
		)
		(layer "In15.Cu")
	)
	(gr_line
		(start 413.044386 -401.526756)
		(end 413.044386 -401.674838)
		(stroke
			(width 0.07112)
			(type default)
		)
		(layer "In15.Cu")
	)
	(gr_line
		(start 413.044386 -400.979386)
		(end 413.044386 -400.811238)
		(stroke
			(width 0.07112)
			(type default)
		)
		(layer "In15.Cu")
	)
	(gr_line
		(start 413.051244 -423.980102)
		(end 413.216344 -424.078908)
		(stroke
			(width 0.07112)
			(type default)
		)
		(layer "In15.Cu")
	)
	(gr_line
		(start 413.155638 -411.323028)
		(end 413.342328 -411.276292)
		(stroke
			(width 0.07112)
			(type default)
		)
		(layer "In15.Cu")
	)
	(gr_line
		(start 413.216344 -424.078908)
		(end 413.630618 -423.975276)
		(stroke
			(width 0.07112)
			(type default)
		)
		(layer "In15.Cu")
	)
	(gr_line
		(start 413.222186 -406.704038)
		(end 413.468058 -406.354788)
		(stroke
			(width 0.07112)
			(type default)
		)
		(layer "In15.Cu")
	)
	(gr_line
		(start 413.342328 -411.276292)
		(end 413.561784 -410.910024)
		(stroke
			(width 0.07112)
			(type default)
		)
		(layer "In15.Cu")
	)
	(gr_line
		(start 413.468058 -406.354788)
		(end 413.435292 -406.16505)
		(stroke
			(width 0.07112)
			(type default)
		)
		(layer "In15.Cu")
	)
	(gr_line
		(start 413.561784 -410.910024)
		(end 413.515048 -410.723588)
		(stroke
			(width 0.07112)
			(type default)
		)
		(layer "In15.Cu")
	)
	(gr_line
		(start 413.630618 -423.975276)
		(end 413.72917 -423.810176)
		(stroke
			(width 0.07112)
			(type default)
		)
		(layer "In15.Cu")
	)
	(gr_line
		(start 413.651446 -409.945078)
		(end 414.011872 -409.343352)
		(stroke
			(width 0.07112)
			(type default)
		)
		(layer "In15.Cu")
	)
	(gr_line
		(start 413.727138 -422.414954)
		(end 414.402778 -422.227756)
		(stroke
			(width 0.07112)
			(type default)
		)
		(layer "In15.Cu")
	)
	(gr_line
		(start 413.803592 -422.68775)
		(end 413.970978 -422.782492)
		(stroke
			(width 0.07112)
			(type default)
		)
		(layer "In15.Cu")
	)
	(gr_line
		(start 413.894778 -410.089604)
		(end 414.081722 -410.042868)
		(stroke
			(width 0.07112)
			(type default)
		)
		(layer "In15.Cu")
	)
	(gr_line
		(start 413.970978 -422.782492)
		(end 414.382458 -422.6687)
		(stroke
			(width 0.07112)
			(type default)
		)
		(layer "In15.Cu")
	)
	(gr_line
		(start 414.070292 -417.930584)
		(end 414.070292 -417.229544)
		(stroke
			(width 0.07112)
			(type default)
		)
		(layer "In15.Cu")
	)
	(gr_line
		(start 414.070292 -416.802824)
		(end 414.070292 -416.101784)
		(stroke
			(width 0.07112)
			(type default)
		)
		(layer "In15.Cu")
	)
	(gr_line
		(start 414.081722 -410.042868)
		(end 414.300924 -409.6766)
		(stroke
			(width 0.07112)
			(type default)
		)
		(layer "In15.Cu")
	)
	(gr_line
		(start 414.105852 -401.399756)
		(end 414.117282 -401.399756)
		(stroke
			(width 0.07112)
			(type default)
		)
		(layer "In15.Cu")
	)
	(gr_line
		(start 414.107122 -401.116546)
		(end 414.244282 -400.979386)
		(stroke
			(width 0.07112)
			(type default)
		)
		(layer "In15.Cu")
	)
	(gr_line
		(start 414.117282 -401.399756)
		(end 414.244282 -401.526756)
		(stroke
			(width 0.07112)
			(type default)
		)
		(layer "In15.Cu")
	)
	(gr_line
		(start 414.231328 -408.977592)
		(end 414.588198 -408.382216)
		(stroke
			(width 0.07112)
			(type default)
		)
		(layer "In15.Cu")
	)
	(gr_line
		(start 414.244282 -401.526756)
		(end 414.244282 -401.674838)
		(stroke
			(width 0.07112)
			(type default)
		)
		(layer "In15.Cu")
	)
	(gr_line
		(start 414.244282 -400.979386)
		(end 414.244282 -400.811238)
		(stroke
			(width 0.07112)
			(type default)
		)
		(layer "In15.Cu")
	)
	(gr_line
		(start 414.300924 -409.6766)
		(end 414.254442 -409.48991)
		(stroke
			(width 0.07112)
			(type default)
		)
		(layer "In15.Cu")
	)
	(gr_line
		(start 414.334198 -406.35555)
		(end 414.724088 -405.772366)
		(stroke
			(width 0.07112)
			(type default)
		)
		(layer "In15.Cu")
	)
	(gr_line
		(start 414.353502 -417.929314)
		(end 414.489392 -417.793424)
		(stroke
			(width 0.07112)
			(type default)
		)
		(layer "In15.Cu")
	)
	(gr_line
		(start 414.353502 -416.801554)
		(end 414.489392 -416.665664)
		(stroke
			(width 0.07112)
			(type default)
		)
		(layer "In15.Cu")
	)
	(gr_line
		(start 414.382458 -422.6687)
		(end 414.4772 -422.50106)
		(stroke
			(width 0.07112)
			(type default)
		)
		(layer "In15.Cu")
	)
	(gr_line
		(start 414.402778 -422.227756)
		(end 414.406334 -422.22674)
		(stroke
			(width 0.07112)
			(type default)
		)
		(layer "In15.Cu")
	)
	(gr_line
		(start 414.47466 -409.122118)
		(end 414.661604 -409.075382)
		(stroke
			(width 0.07112)
			(type default)
		)
		(layer "In15.Cu")
	)
	(gr_line
		(start 414.477962 -422.499536)
		(end 414.481518 -422.49852)
		(stroke
			(width 0.07112)
			(type default)
		)
		(layer "In15.Cu")
	)
	(gr_line
		(start 414.489392 -417.793424)
		(end 414.489392 -417.366704)
		(stroke
			(width 0.07112)
			(type default)
		)
		(layer "In15.Cu")
	)
	(gr_line
		(start 414.489392 -417.366704)
		(end 414.353502 -417.230814)
		(stroke
			(width 0.07112)
			(type default)
		)
		(layer "In15.Cu")
	)
	(gr_line
		(start 414.489392 -416.665664)
		(end 414.489392 -416.238944)
		(stroke
			(width 0.07112)
			(type default)
		)
		(layer "In15.Cu")
	)
	(gr_line
		(start 414.489392 -416.238944)
		(end 414.353502 -416.103054)
		(stroke
			(width 0.07112)
			(type default)
		)
		(layer "In15.Cu")
	)
	(gr_line
		(start 414.570418 -406.512014)
		(end 414.758886 -406.474422)
		(stroke
			(width 0.07112)
			(type default)
		)
		(layer "In15.Cu")
	)
	(gr_line
		(start 414.591754 -408.37612)
		(end 414.592008 -408.375866)
		(stroke
			(width 0.07112)
			(type default)
		)
		(layer "In15.Cu")
	)
	(gr_line
		(start 414.592008 -408.375866)
		(end 414.591754 -408.375866)
		(stroke
			(width 0.07112)
			(type default)
		)
		(layer "In15.Cu")
	)
	(gr_line
		(start 414.661604 -409.075382)
		(end 414.88106 -408.709114)
		(stroke
			(width 0.07112)
			(type default)
		)
		(layer "In15.Cu")
	)
	(gr_line
		(start 414.758886 -406.474422)
		(end 414.996376 -406.11933)
		(stroke
			(width 0.07112)
			(type default)
		)
		(layer "In15.Cu")
	)
	(gr_line
		(start 414.780222 -423.223182)
		(end 415.44621 -423.003218)
		(stroke
			(width 0.07112)
			(type default)
		)
		(layer "In15.Cu")
	)
	(gr_line
		(start 414.797748 -408.010614)
		(end 415.142426 -407.399744)
		(stroke
			(width 0.07112)
			(type default)
		)
		(layer "In15.Cu")
	)
	(gr_line
		(start 414.833816 -408.5209)
		(end 414.837372 -408.51455)
		(stroke
			(width 0.07112)
			(type default)
		)
		(layer "In15.Cu")
	)
	(gr_line
		(start 414.869884 -423.491914)
		(end 415.041842 -423.578274)
		(stroke
			(width 0.07112)
			(type default)
		)
		(layer "In15.Cu")
	)
	(gr_line
		(start 414.88106 -408.709114)
		(end 414.834324 -408.522424)
		(stroke
			(width 0.07112)
			(type default)
		)
		(layer "In15.Cu")
	)
	(gr_line
		(start 414.996376 -406.11933)
		(end 414.958784 -405.930608)
		(stroke
			(width 0.07112)
			(type default)
		)
		(layer "In15.Cu")
	)
	(gr_line
		(start 415.041842 -423.578274)
		(end 415.447226 -423.444416)
		(stroke
			(width 0.07112)
			(type default)
		)
		(layer "In15.Cu")
	)
	(gr_line
		(start 415.04489 -408.149298)
		(end 415.230818 -408.097736)
		(stroke
			(width 0.07112)
			(type default)
		)
		(layer "In15.Cu")
	)
	(gr_line
		(start 415.230818 -408.097736)
		(end 415.440876 -407.72588)
		(stroke
			(width 0.07112)
			(type default)
		)
		(layer "In15.Cu")
	)
	(gr_line
		(start 415.306002 -401.399756)
		(end 415.317432 -401.399756)
		(stroke
			(width 0.07112)
			(type default)
		)
		(layer "In15.Cu")
	)
	(gr_line
		(start 415.307272 -401.116546)
		(end 415.444432 -400.979386)
		(stroke
			(width 0.07112)
			(type default)
		)
		(layer "In15.Cu")
	)
	(gr_line
		(start 415.317432 -401.399756)
		(end 415.444432 -401.526756)
		(stroke
			(width 0.07112)
			(type default)
		)
		(layer "In15.Cu")
	)
	(gr_line
		(start 415.351976 -407.028396)
		(end 415.695892 -406.418796)
		(stroke
			(width 0.07112)
			(type default)
		)
		(layer "In15.Cu")
	)
	(gr_line
		(start 415.440876 -407.72588)
		(end 415.388806 -407.538936)
		(stroke
			(width 0.07112)
			(type default)
		)
		(layer "In15.Cu")
	)
	(gr_line
		(start 415.444432 -401.526756)
		(end 415.444432 -401.674838)
		(stroke
			(width 0.07112)
			(type default)
		)
		(layer "In15.Cu")
	)
	(gr_line
		(start 415.444432 -400.979386)
		(end 415.444432 -400.811238)
		(stroke
			(width 0.07112)
			(type default)
		)
		(layer "In15.Cu")
	)
	(gr_line
		(start 415.447226 -423.444416)
		(end 415.53384 -423.272458)
		(stroke
			(width 0.07112)
			(type default)
		)
		(layer "In15.Cu")
	)
	(gr_line
		(start 415.59861 -407.167588)
		(end 415.785808 -407.115772)
		(stroke
			(width 0.07112)
			(type default)
		)
		(layer "In15.Cu")
	)
	(gr_line
		(start 415.695892 -406.418796)
		(end 415.69767 -406.418542)
		(stroke
			(width 0.07112)
			(type default)
		)
		(layer "In15.Cu")
	)
	(gr_line
		(start 415.751772 -411.564074)
		(end 415.75228 -411.564074)
		(stroke
			(width 0.07112)
			(type default)
		)
		(layer "In15.Cu")
	)
	(gr_line
		(start 415.75228 -411.56382)
		(end 415.887408 -410.87548)
		(stroke
			(width 0.07112)
			(type default)
		)
		(layer "In15.Cu")
	)
	(gr_line
		(start 415.785808 -407.115772)
		(end 415.995866 -406.743916)
		(stroke
			(width 0.07112)
			(type default)
		)
		(layer "In15.Cu")
	)
	(gr_line
		(start 415.788094 -413.615124)
		(end 415.78784 -413.615124)
		(stroke
			(width 0.07112)
			(type default)
		)
		(layer "In15.Cu")
	)
	(gr_line
		(start 415.85134 -422.86936)
		(end 416.517328 -422.649396)
		(stroke
			(width 0.07112)
			(type default)
		)
		(layer "In15.Cu")
	)
	(gr_line
		(start 415.941002 -423.138092)
		(end 416.11296 -423.224452)
		(stroke
			(width 0.07112)
			(type default)
		)
		(layer "In15.Cu")
	)
	(gr_line
		(start 415.995866 -406.743916)
		(end 415.94405 -406.556972)
		(stroke
			(width 0.07112)
			(type default)
		)
		(layer "In15.Cu")
	)
	(gr_line
		(start 416.018472 -410.207206)
		(end 416.153346 -409.51912)
		(stroke
			(width 0.07112)
			(type default)
		)
		(layer "In15.Cu")
	)
	(gr_line
		(start 416.030664 -411.616906)
		(end 416.190176 -411.509718)
		(stroke
			(width 0.07112)
			(type default)
		)
		(layer "In15.Cu")
	)
	(gr_line
		(start 416.11296 -423.224452)
		(end 416.518344 -423.090848)
		(stroke
			(width 0.07112)
			(type default)
		)
		(layer "In15.Cu")
	)
	(gr_line
		(start 416.190176 -411.509718)
		(end 416.272218 -411.090872)
		(stroke
			(width 0.07112)
			(type default)
		)
		(layer "In15.Cu")
	)
	(gr_line
		(start 416.272218 -411.090872)
		(end 416.16503 -410.93136)
		(stroke
			(width 0.07112)
			(type default)
		)
		(layer "In15.Cu")
	)
	(gr_line
		(start 416.296602 -410.260546)
		(end 416.456368 -410.153612)
		(stroke
			(width 0.07112)
			(type default)
		)
		(layer "In15.Cu")
	)
	(gr_line
		(start 416.3441 -408.787092)
		(end 416.344608 -408.785568)
		(stroke
			(width 0.07112)
			(type default)
		)
		(layer "In15.Cu")
	)
	(gr_line
		(start 416.344608 -408.785568)
		(end 416.581336 -408.123898)
		(stroke
			(width 0.07112)
			(type default)
		)
		(layer "In15.Cu")
	)
	(gr_line
		(start 416.456368 -410.153612)
		(end 416.53841 -409.734512)
		(stroke
			(width 0.07112)
			(type default)
		)
		(layer "In15.Cu")
	)
	(gr_line
		(start 416.505898 -401.399756)
		(end 416.517328 -401.399756)
		(stroke
			(width 0.07112)
			(type default)
		)
		(layer "In15.Cu")
	)
	(gr_line
		(start 416.507168 -401.116546)
		(end 416.644328 -400.979386)
		(stroke
			(width 0.07112)
			(type default)
		)
		(layer "In15.Cu")
	)
	(gr_line
		(start 416.517328 -422.649396)
		(end 416.53587 -422.6433)
		(stroke
			(width 0.07112)
			(type default)
		)
		(layer "In15.Cu")
	)
	(gr_line
		(start 416.517328 -401.399756)
		(end 416.644328 -401.526756)
		(stroke
			(width 0.07112)
			(type default)
		)
		(layer "In15.Cu")
	)
	(gr_line
		(start 416.518344 -423.090848)
		(end 416.604958 -422.918636)
		(stroke
			(width 0.07112)
			(type default)
		)
		(layer "In15.Cu")
	)
	(gr_line
		(start 416.53841 -409.734512)
		(end 416.430968 -409.574746)
		(stroke
			(width 0.07112)
			(type default)
		)
		(layer "In15.Cu")
	)
	(gr_line
		(start 416.609784 -408.882342)
		(end 416.610292 -408.880818)
		(stroke
			(width 0.07112)
			(type default)
		)
		(layer "In15.Cu")
	)
	(gr_line
		(start 416.61207 -408.87904)
		(end 416.786314 -408.79649)
		(stroke
			(width 0.07112)
			(type default)
		)
		(layer "In15.Cu")
	)
	(gr_line
		(start 416.644328 -401.526756)
		(end 416.644328 -401.674838)
		(stroke
			(width 0.07112)
			(type default)
		)
		(layer "In15.Cu")
	)
	(gr_line
		(start 416.644328 -400.979386)
		(end 416.644328 -400.811238)
		(stroke
			(width 0.07112)
			(type default)
		)
		(layer "In15.Cu")
	)
	(gr_line
		(start 416.723068 -407.72842)
		(end 416.7251 -407.72207)
		(stroke
			(width 0.07112)
			(type default)
		)
		(layer "In15.Cu")
	)
	(gr_line
		(start 416.7251 -407.72207)
		(end 416.96132 -407.062178)
		(stroke
			(width 0.07112)
			(type default)
		)
		(layer "In15.Cu")
	)
	(gr_line
		(start 416.786314 -408.79649)
		(end 416.930078 -408.394408)
		(stroke
			(width 0.07112)
			(type default)
		)
		(layer "In15.Cu")
	)
	(gr_line
		(start 416.930078 -408.394408)
		(end 416.847782 -408.220418)
		(stroke
			(width 0.07112)
			(type default)
		)
		(layer "In15.Cu")
	)
	(gr_line
		(start 416.988752 -407.82367)
		(end 416.99053 -407.818082)
		(stroke
			(width 0.07112)
			(type default)
		)
		(layer "In15.Cu")
	)
	(gr_line
		(start 416.992054 -407.817066)
		(end 417.166298 -407.734516)
		(stroke
			(width 0.07112)
			(type default)
		)
		(layer "In15.Cu")
	)
	(gr_line
		(start 417.105084 -406.66035)
		(end 417.341304 -406.000204)
		(stroke
			(width 0.07112)
			(type default)
		)
		(layer "In15.Cu")
	)
	(gr_line
		(start 417.133532 -417.83508)
		(end 417.133532 -417.13404)
		(stroke
			(width 0.07112)
			(type default)
		)
		(layer "In15.Cu")
	)
	(gr_line
		(start 417.133532 -416.70732)
		(end 417.133532 -416.00628)
		(stroke
			(width 0.07112)
			(type default)
		)
		(layer "In15.Cu")
	)
	(gr_line
		(start 417.166298 -407.734516)
		(end 417.310062 -407.332434)
		(stroke
			(width 0.07112)
			(type default)
		)
		(layer "In15.Cu")
	)
	(gr_line
		(start 417.310062 -407.332434)
		(end 417.227512 -407.158444)
		(stroke
			(width 0.07112)
			(type default)
		)
		(layer "In15.Cu")
	)
	(gr_line
		(start 417.372038 -406.755092)
		(end 417.546282 -406.672542)
		(stroke
			(width 0.07112)
			(type default)
		)
		(layer "In15.Cu")
	)
	(gr_line
		(start 417.416742 -417.83381)
		(end 417.552632 -417.69792)
		(stroke
			(width 0.07112)
			(type default)
		)
		(layer "In15.Cu")
	)
	(gr_line
		(start 417.416742 -416.70605)
		(end 417.552632 -416.57016)
		(stroke
			(width 0.07112)
			(type default)
		)
		(layer "In15.Cu")
	)
	(gr_line
		(start 417.485068 -405.59863)
		(end 417.719256 -404.943818)
		(stroke
			(width 0.07112)
			(type default)
		)
		(layer "In15.Cu")
	)
	(gr_line
		(start 417.546282 -406.672542)
		(end 417.690046 -406.27046)
		(stroke
			(width 0.07112)
			(type default)
		)
		(layer "In15.Cu")
	)
	(gr_line
		(start 417.552632 -417.69792)
		(end 417.552632 -417.2712)
		(stroke
			(width 0.07112)
			(type default)
		)
		(layer "In15.Cu")
	)
	(gr_line
		(start 417.552632 -417.2712)
		(end 417.416742 -417.13531)
		(stroke
			(width 0.07112)
			(type default)
		)
		(layer "In15.Cu")
	)
	(gr_line
		(start 417.552632 -416.57016)
		(end 417.552632 -416.14344)
		(stroke
			(width 0.07112)
			(type default)
		)
		(layer "In15.Cu")
	)
	(gr_line
		(start 417.552632 -416.14344)
		(end 417.416742 -416.00755)
		(stroke
			(width 0.07112)
			(type default)
		)
		(layer "In15.Cu")
	)
	(gr_line
		(start 417.690046 -406.27046)
		(end 417.60775 -406.09647)
		(stroke
			(width 0.07112)
			(type default)
		)
		(layer "In15.Cu")
	)
	(gr_line
		(start 417.705794 -401.399756)
		(end 417.717224 -401.399756)
		(stroke
			(width 0.07112)
			(type default)
		)
		(layer "In15.Cu")
	)
	(gr_line
		(start 417.707064 -401.116546)
		(end 417.844224 -400.979386)
		(stroke
			(width 0.07112)
			(type default)
		)
		(layer "In15.Cu")
	)
	(gr_line
		(start 417.717224 -401.399756)
		(end 417.844224 -401.526756)
		(stroke
			(width 0.07112)
			(type default)
		)
		(layer "In15.Cu")
	)
	(gr_line
		(start 417.719764 -404.942294)
		(end 417.721288 -404.938484)
		(stroke
			(width 0.07112)
			(type default)
		)
		(layer "In15.Cu")
	)
	(gr_line
		(start 417.721288 -404.938484)
		(end 417.72205 -404.936706)
		(stroke
			(width 0.07112)
			(type default)
		)
		(layer "In15.Cu")
	)
	(gr_line
		(start 417.752022 -405.693118)
		(end 417.926266 -405.610568)
		(stroke
			(width 0.07112)
			(type default)
		)
		(layer "In15.Cu")
	)
	(gr_line
		(start 417.844224 -401.526756)
		(end 417.844224 -401.674838)
		(stroke
			(width 0.07112)
			(type default)
		)
		(layer "In15.Cu")
	)
	(gr_line
		(start 417.844224 -400.979386)
		(end 417.844224 -400.811238)
		(stroke
			(width 0.07112)
			(type default)
		)
		(layer "In15.Cu")
	)
	(gr_line
		(start 417.926266 -405.610568)
		(end 418.07003 -405.20874)
		(stroke
			(width 0.07112)
			(type default)
		)
		(layer "In15.Cu")
	)
	(gr_line
		(start 418.07003 -405.20874)
		(end 417.987734 -405.034496)
		(stroke
			(width 0.07112)
			(type default)
		)
		(layer "In15.Cu")
	)
	(gr_line
		(start 418.684964 -413.100012)
		(end 418.69741 -412.971234)
		(stroke
			(width 0.07112)
			(type default)
		)
		(layer "In15.Cu")
	)
	(gr_line
		(start 418.69741 -412.971234)
		(end 418.766244 -412.272988)
		(stroke
			(width 0.07112)
			(type default)
		)
		(layer "In15.Cu")
	)
	(gr_line
		(start 418.768276 -421.36441)
		(end 419.179248 -420.796212)
		(stroke
			(width 0.07112)
			(type default)
		)
		(layer "In15.Cu")
	)
	(gr_line
		(start 418.808154 -411.848808)
		(end 418.876734 -411.150562)
		(stroke
			(width 0.07112)
			(type default)
		)
		(layer "In15.Cu")
	)
	(gr_line
		(start 418.90569 -401.399756)
		(end 418.91712 -401.399756)
		(stroke
			(width 0.07112)
			(type default)
		)
		(layer "In15.Cu")
	)
	(gr_line
		(start 418.90696 -401.116546)
		(end 419.04412 -400.979386)
		(stroke
			(width 0.07112)
			(type default)
		)
		(layer "In15.Cu")
	)
	(gr_line
		(start 418.91712 -401.399756)
		(end 419.04412 -401.526756)
		(stroke
			(width 0.07112)
			(type default)
		)
		(layer "In15.Cu")
	)
	(gr_line
		(start 418.918644 -410.726382)
		(end 418.987224 -410.028136)
		(stroke
			(width 0.07112)
			(type default)
		)
		(layer "In15.Cu")
	)
	(gr_line
		(start 418.979604 -412.997396)
		(end 419.128194 -412.875476)
		(stroke
			(width 0.07112)
			(type default)
		)
		(layer "In15.Cu")
	)
	(gr_line
		(start 418.9984 -421.52951)
		(end 419.188392 -421.49903)
		(stroke
			(width 0.07112)
			(type default)
		)
		(layer "In15.Cu")
	)
	(gr_line
		(start 419.029134 -409.603956)
		(end 419.097714 -408.90571)
		(stroke
			(width 0.07112)
			(type default)
		)
		(layer "In15.Cu")
	)
	(gr_line
		(start 419.04412 -401.526756)
		(end 419.04412 -401.674838)
		(stroke
			(width 0.07112)
			(type default)
		)
		(layer "In15.Cu")
	)
	(gr_line
		(start 419.04412 -400.979386)
		(end 419.04412 -400.811238)
		(stroke
			(width 0.07112)
			(type default)
		)
		(layer "In15.Cu")
	)
	(gr_line
		(start 419.090094 -411.875224)
		(end 419.238938 -411.75305)
		(stroke
			(width 0.07112)
			(type default)
		)
		(layer "In15.Cu")
	)
	(gr_line
		(start 419.128194 -412.875476)
		(end 419.170104 -412.450534)
		(stroke
			(width 0.07112)
			(type default)
		)
		(layer "In15.Cu")
	)
	(gr_line
		(start 419.139624 -408.48153)
		(end 419.208204 -407.783284)
		(stroke
			(width 0.07112)
			(type default)
		)
		(layer "In15.Cu")
	)
	(gr_line
		(start 419.170104 -412.450534)
		(end 419.04793 -412.30169)
		(stroke
			(width 0.07112)
			(type default)
		)
		(layer "In15.Cu")
	)
	(gr_line
		(start 419.188392 -421.49903)
		(end 419.438582 -421.153082)
		(stroke
			(width 0.07112)
			(type default)
		)
		(layer "In15.Cu")
	)
	(gr_line
		(start 419.200584 -410.752798)
		(end 419.349428 -410.630624)
		(stroke
			(width 0.07112)
			(type default)
		)
		(layer "In15.Cu")
	)
	(gr_line
		(start 419.238938 -411.75305)
		(end 419.280848 -411.328108)
		(stroke
			(width 0.07112)
			(type default)
		)
		(layer "In15.Cu")
	)
	(gr_line
		(start 419.270688 -407.149808)
		(end 419.339522 -406.451816)
		(stroke
			(width 0.07112)
			(type default)
		)
		(layer "In15.Cu")
	)
	(gr_line
		(start 419.280848 -411.328108)
		(end 419.15842 -411.179264)
		(stroke
			(width 0.07112)
			(type default)
		)
		(layer "In15.Cu")
	)
	(gr_line
		(start 419.311074 -409.630372)
		(end 419.459918 -409.508198)
		(stroke
			(width 0.07112)
			(type default)
		)
		(layer "In15.Cu")
	)
	(gr_line
		(start 419.349428 -410.630624)
		(end 419.391338 -410.205682)
		(stroke
			(width 0.07112)
			(type default)
		)
		(layer "In15.Cu")
	)
	(gr_line
		(start 419.391338 -410.205682)
		(end 419.269164 -410.056838)
		(stroke
			(width 0.07112)
			(type default)
		)
		(layer "In15.Cu")
	)
	(gr_line
		(start 419.421564 -408.507946)
		(end 419.570408 -408.385772)
		(stroke
			(width 0.07112)
			(type default)
		)
		(layer "In15.Cu")
	)
	(gr_line
		(start 419.438582 -421.153082)
		(end 419.408102 -420.96309)
		(stroke
			(width 0.07112)
			(type default)
		)
		(layer "In15.Cu")
	)
	(gr_line
		(start 419.459918 -409.508198)
		(end 419.501828 -409.083256)
		(stroke
			(width 0.07112)
			(type default)
		)
		(layer "In15.Cu")
	)
	(gr_line
		(start 419.501828 -409.083256)
		(end 419.379654 -408.934412)
		(stroke
			(width 0.07112)
			(type default)
		)
		(layer "In15.Cu")
	)
	(gr_line
		(start 419.552628 -407.176478)
		(end 419.701472 -407.054304)
		(stroke
			(width 0.07112)
			(type default)
		)
		(layer "In15.Cu")
	)
	(gr_line
		(start 419.570408 -408.385772)
		(end 419.612318 -407.96083)
		(stroke
			(width 0.07112)
			(type default)
		)
		(layer "In15.Cu")
	)
	(gr_line
		(start 419.612318 -407.96083)
		(end 419.490144 -407.811986)
		(stroke
			(width 0.07112)
			(type default)
		)
		(layer "In15.Cu")
	)
	(gr_line
		(start 419.701472 -407.054304)
		(end 419.743382 -406.629362)
		(stroke
			(width 0.07112)
			(type default)
		)
		(layer "In15.Cu")
	)
	(gr_line
		(start 419.743382 -406.629362)
		(end 419.621208 -406.480772)
		(stroke
			(width 0.07112)
			(type default)
		)
		(layer "In15.Cu")
	)
	(gr_line
		(start 419.861746 -419.711886)
		(end 420.145972 -419.070536)
		(stroke
			(width 0.07112)
			(type default)
		)
		(layer "In15.Cu")
	)
	(gr_line
		(start 420.10584 -401.399756)
		(end 420.11727 -401.399756)
		(stroke
			(width 0.07112)
			(type default)
		)
		(layer "In15.Cu")
	)
	(gr_line
		(start 420.10711 -401.116546)
		(end 420.24427 -400.979386)
		(stroke
			(width 0.07112)
			(type default)
		)
		(layer "In15.Cu")
	)
	(gr_line
		(start 420.11727 -401.399756)
		(end 420.24427 -401.526756)
		(stroke
			(width 0.07112)
			(type default)
		)
		(layer "In15.Cu")
	)
	(gr_line
		(start 420.121334 -419.825424)
		(end 420.300912 -419.756336)
		(stroke
			(width 0.07112)
			(type default)
		)
		(layer "In15.Cu")
	)
	(gr_line
		(start 420.24427 -401.526756)
		(end 420.24427 -401.674838)
		(stroke
			(width 0.07112)
			(type default)
		)
		(layer "In15.Cu")
	)
	(gr_line
		(start 420.24427 -400.979386)
		(end 420.24427 -400.811238)
		(stroke
			(width 0.07112)
			(type default)
		)
		(layer "In15.Cu")
	)
	(gr_line
		(start 420.300912 -419.756336)
		(end 420.473632 -419.365938)
		(stroke
			(width 0.07112)
			(type default)
		)
		(layer "In15.Cu")
	)
	(gr_line
		(start 420.473632 -419.365938)
		(end 420.40429 -419.18636)
		(stroke
			(width 0.07112)
			(type default)
		)
		(layer "In15.Cu")
	)
	(gr_line
		(start 420.703248 -417.192714)
		(end 420.703248 -416.491674)
		(stroke
			(width 0.07112)
			(type default)
		)
		(layer "In15.Cu")
	)
	(gr_line
		(start 420.703248 -416.064954)
		(end 420.703248 -415.363914)
		(stroke
			(width 0.07112)
			(type default)
		)
		(layer "In15.Cu")
	)
	(gr_line
		(start 420.703248 -414.937194)
		(end 420.703248 -414.236154)
		(stroke
			(width 0.07112)
			(type default)
		)
		(layer "In15.Cu")
	)
	(gr_line
		(start 420.703248 -413.809434)
		(end 420.703248 -413.108394)
		(stroke
			(width 0.07112)
			(type default)
		)
		(layer "In15.Cu")
	)
	(gr_line
		(start 420.986458 -417.191444)
		(end 421.122348 -417.055554)
		(stroke
			(width 0.07112)
			(type default)
		)
		(layer "In15.Cu")
	)
	(gr_line
		(start 420.986458 -416.063684)
		(end 421.122348 -415.927794)
		(stroke
			(width 0.07112)
			(type default)
		)
		(layer "In15.Cu")
	)
	(gr_line
		(start 420.986458 -414.935924)
		(end 421.122348 -414.800034)
		(stroke
			(width 0.07112)
			(type default)
		)
		(layer "In15.Cu")
	)
	(gr_line
		(start 420.986458 -413.808164)
		(end 421.122348 -413.672274)
		(stroke
			(width 0.07112)
			(type default)
		)
		(layer "In15.Cu")
	)
	(gr_line
		(start 421.122348 -417.055554)
		(end 421.122348 -416.628834)
		(stroke
			(width 0.07112)
			(type default)
		)
		(layer "In15.Cu")
	)
	(gr_line
		(start 421.122348 -416.628834)
		(end 420.986458 -416.492944)
		(stroke
			(width 0.07112)
			(type default)
		)
		(layer "In15.Cu")
	)
	(gr_line
		(start 421.122348 -415.927794)
		(end 421.122348 -415.501074)
		(stroke
			(width 0.07112)
			(type default)
		)
		(layer "In15.Cu")
	)
	(gr_line
		(start 421.122348 -415.501074)
		(end 420.986458 -415.365184)
		(stroke
			(width 0.07112)
			(type default)
		)
		(layer "In15.Cu")
	)
	(gr_line
		(start 421.122348 -414.800034)
		(end 421.122348 -414.373314)
		(stroke
			(width 0.07112)
			(type default)
		)
		(layer "In15.Cu")
	)
	(gr_line
		(start 421.122348 -414.373314)
		(end 420.986458 -414.237424)
		(stroke
			(width 0.07112)
			(type default)
		)
		(layer "In15.Cu")
	)
	(gr_line
		(start 421.122348 -413.672274)
		(end 421.122348 -413.245554)
		(stroke
			(width 0.07112)
			(type default)
		)
		(layer "In15.Cu")
	)
	(gr_line
		(start 421.122348 -413.245554)
		(end 420.986458 -413.109664)
		(stroke
			(width 0.07112)
			(type default)
		)
		(layer "In15.Cu")
	)
	(gr_line
		(start 421.305736 -401.399756)
		(end 421.317166 -401.399756)
		(stroke
			(width 0.07112)
			(type default)
		)
		(layer "In15.Cu")
	)
	(gr_line
		(start 421.307006 -401.116546)
		(end 421.444166 -400.979386)
		(stroke
			(width 0.07112)
			(type default)
		)
		(layer "In15.Cu")
	)
	(gr_line
		(start 421.317166 -401.399756)
		(end 421.444166 -401.526756)
		(stroke
			(width 0.07112)
			(type default)
		)
		(layer "In15.Cu")
	)
	(gr_line
		(start 421.444166 -401.526756)
		(end 421.444166 -401.674838)
		(stroke
			(width 0.07112)
			(type default)
		)
		(layer "In15.Cu")
	)
	(gr_line
		(start 421.444166 -400.979386)
		(end 421.444166 -400.811238)
		(stroke
			(width 0.07112)
			(type default)
		)
		(layer "In15.Cu")
	)
	(gr_line
		(start 0 -77.671676)
		(end 0 -13.780008)
		(stroke
			(width 1.016)
			(type default)
		)
		(layer "In16.Cu")
	)
	(gr_arc
		(start 0 -77.671676)
		(mid 0.152237 -78.436936)
		(end 0.585724 -79.085694)
		(stroke
			(width 1.016)
			(type default)
		)
		(layer "In16.Cu")
	)
	(gr_poly
		(pts
			(arc
				(start 279.248108 -392.23696)
				(mid 279.284029 -392.222081)
				(end 279.298908 -392.18616)
			)
			(arc
				(start 279.298908 -383.93116)
				(mid 279.284029 -383.895239)
				(end 279.248108 -383.88036)
			)
			(arc
				(start 275.026374 -383.88036)
				(mid 275.006851 -383.884261)
				(end 274.990306 -383.895346)
			)
			(arc
				(start 274.766278 -384.119374)
				(mid 274.755167 -384.135908)
				(end 274.751292 -384.155442)
			)
			(arc
				(start 274.751292 -392.107928)
				(mid 274.755193 -392.127451)
				(end 274.766278 -392.143996)
			)
			(arc
				(start 274.844256 -392.221974)
				(mid 274.86079 -392.233085)
				(end 274.880324 -392.23696)
			)
		)
		(stroke
			(width 0)
			(type solid)
		)
		(fill yes)
		(layer "In16.Cu")
		(net "P12V_MAIN_R_0")
	)
	(gr_poly
		(pts
			(arc
				(start 273.15541 -393.27836)
				(mid 273.174933 -393.274459)
				(end 273.191478 -393.263374)
			)
			(xy 273.191732 -393.26312) (xy 273.669252 -392.7856)
			(arc
				(start 273.669506 -392.785346)
				(mid 273.680617 -392.768812)
				(end 273.684492 -392.749278)
			)
			(arc
				(start 273.684492 -384.155442)
				(mid 273.680591 -384.135919)
				(end 273.669506 -384.119374)
			)
			(xy 273.669252 -384.11912) (xy 273.447764 -383.897632) (xy 273.447256 -383.897124)
			(arc
				(start 273.445478 -383.895346)
				(mid 273.428944 -383.884235)
				(end 273.40941 -383.88036)
			)
			(arc
				(start 239.542574 -383.88036)
				(mid 239.523051 -383.884261)
				(end 239.506506 -383.895346)
			)
			(xy 239.506252 -383.8956) (xy 239.03051 -384.371342) (xy 239.030256 -384.371596)
			(arc
				(start 239.028478 -384.373374)
				(mid 239.017367 -384.389908)
				(end 239.013492 -384.409442)
			)
			(arc
				(start 239.013492 -393.003278)
				(mid 239.017393 -393.022801)
				(end 239.028478 -393.039346)
			)
			(xy 239.028732 -393.0396) (xy 239.252252 -393.26312)
			(arc
				(start 239.252506 -393.263374)
				(mid 239.26904 -393.274485)
				(end 239.288574 -393.27836)
			)
		)
		(stroke
			(width 0)
			(type solid)
		)
		(fill yes)
		(layer "In16.Cu")
		(net "P12V_MAIN_R")
	)
	(gr_poly
		(pts
			(arc
				(start 228.921818 -436.47868)
				(mid 228.941341 -436.474779)
				(end 228.957886 -436.463694)
			)
			(arc
				(start 229.664514 -435.757066)
				(mid 229.675625 -435.740532)
				(end 229.6795 -435.720998)
			)
			(arc
				(start 229.6795 -422.180766)
				(mid 229.703653 -422.05925)
				(end 229.772464 -421.95623)
			)
			(arc
				(start 234.67314 -417.055554)
				(mid 234.776172 -416.986773)
				(end 234.897676 -416.96259)
			)
			(arc
				(start 272.037556 -416.96259)
				(mid 272.057079 -416.958689)
				(end 272.073624 -416.947604)
			)
			(arc
				(start 280.035254 -408.985974)
				(mid 280.046365 -408.96944)
				(end 280.05024 -408.949906)
			)
			(arc
				(start 280.05024 -394.963396)
				(mid 280.046339 -394.943873)
				(end 280.035254 -394.927328)
			)
			(xy 280.035 -394.927074) (xy 279.65146 -394.543534)
			(arc
				(start 279.651206 -394.54328)
				(mid 279.634672 -394.532169)
				(end 279.615138 -394.528294)
			)
			(arc
				(start 278.051514 -394.528294)
				(mid 278.036928 -394.530433)
				(end 278.023574 -394.536676)
			)
			(arc
				(start 278.023574 -394.536676)
				(mid 277.823537 -394.629726)
				(end 277.605236 -394.661644)
			)
			(arc
				(start 277.605236 -394.661644)
				(mid 277.421236 -394.639047)
				(end 277.248112 -394.572744)
			)
			(arc
				(start 277.248112 -394.572744)
				(mid 277.224236 -394.566797)
				(end 277.20036 -394.572744)
			)
			(arc
				(start 277.20036 -394.572744)
				(mid 277.027244 -394.639078)
				(end 276.843236 -394.661644)
			)
			(arc
				(start 276.843236 -394.661644)
				(mid 276.624932 -394.629737)
				(end 276.424898 -394.536676)
			)
			(arc
				(start 276.424898 -394.536676)
				(mid 276.411542 -394.53044)
				(end 276.396958 -394.528294)
			)
			(arc
				(start 269.04569 -394.528294)
				(mid 269.030398 -394.53065)
				(end 269.01648 -394.537438)
			)
			(arc
				(start 269.01648 -394.537438)
				(mid 268.808203 -394.640414)
				(end 268.578584 -394.675868)
			)
			(arc
				(start 268.578584 -394.675868)
				(mid 268.394584 -394.653271)
				(end 268.22146 -394.586968)
			)
			(arc
				(start 268.22146 -394.586968)
				(mid 268.197584 -394.581021)
				(end 268.173708 -394.586968)
			)
			(arc
				(start 268.173708 -394.586968)
				(mid 268.000592 -394.653302)
				(end 267.816584 -394.675868)
			)
			(arc
				(start 267.816584 -394.675868)
				(mid 267.586971 -394.640395)
				(end 267.378688 -394.537438)
			)
			(arc
				(start 267.378688 -394.537438)
				(mid 267.364793 -394.530577)
				(end 267.349478 -394.528294)
			)
			(arc
				(start 261.01929 -394.528294)
				(mid 261.003998 -394.53065)
				(end 260.99008 -394.537438)
			)
			(arc
				(start 260.99008 -394.537438)
				(mid 260.781803 -394.640414)
				(end 260.552184 -394.675868)
			)
			(arc
				(start 260.552184 -394.675868)
				(mid 260.368184 -394.653271)
				(end 260.19506 -394.586968)
			)
			(arc
				(start 260.19506 -394.586968)
				(mid 260.171184 -394.581021)
				(end 260.147308 -394.586968)
			)
			(arc
				(start 260.147308 -394.586968)
				(mid 259.974192 -394.653302)
				(end 259.790184 -394.675868)
			)
			(arc
				(start 259.790184 -394.675868)
				(mid 259.560571 -394.640395)
				(end 259.352288 -394.537438)
			)
			(arc
				(start 259.352288 -394.537438)
				(mid 259.338393 -394.530577)
				(end 259.323078 -394.528294)
			)
			(arc
				(start 252.99289 -394.528294)
				(mid 252.977598 -394.53065)
				(end 252.96368 -394.537438)
			)
			(arc
				(start 252.96368 -394.537438)
				(mid 252.755403 -394.640414)
				(end 252.525784 -394.675868)
			)
			(arc
				(start 252.525784 -394.675868)
				(mid 252.341784 -394.653271)
				(end 252.16866 -394.586968)
			)
			(arc
				(start 252.16866 -394.586968)
				(mid 252.144784 -394.581021)
				(end 252.120908 -394.586968)
			)
			(arc
				(start 252.120908 -394.586968)
				(mid 251.947792 -394.653302)
				(end 251.763784 -394.675868)
			)
			(arc
				(start 251.763784 -394.675868)
				(mid 251.534171 -394.640395)
				(end 251.325888 -394.537438)
			)
			(arc
				(start 251.325888 -394.537438)
				(mid 251.311993 -394.530577)
				(end 251.296678 -394.528294)
			)
			(arc
				(start 244.9576 -394.528294)
				(mid 244.942576 -394.530567)
				(end 244.928898 -394.537184)
			)
			(arc
				(start 244.928898 -394.537184)
				(mid 244.722849 -394.637373)
				(end 244.496336 -394.671804)
			)
			(arc
				(start 244.496336 -394.671804)
				(mid 244.312336 -394.649207)
				(end 244.139212 -394.582904)
			)
			(arc
				(start 244.139212 -394.582904)
				(mid 244.115336 -394.576957)
				(end 244.09146 -394.582904)
			)
			(arc
				(start 244.09146 -394.582904)
				(mid 243.918344 -394.649238)
				(end 243.734336 -394.671804)
			)
			(arc
				(start 243.734336 -394.671804)
				(mid 243.507823 -394.637371)
				(end 243.301774 -394.537184)
			)
			(arc
				(start 243.301774 -394.537184)
				(mid 243.288095 -394.53057)
				(end 243.273072 -394.528294)
			)
			(arc
				(start 239.250982 -394.528294)
				(mid 239.215061 -394.543173)
				(end 239.200182 -394.579094)
			)
			(arc
				(start 239.200182 -405.390096)
				(mid 239.176029 -405.511612)
				(end 239.107218 -405.614632)
			)
			(arc
				(start 238.94034 -405.78151)
				(mid 238.837308 -405.850291)
				(end 238.715804 -405.874474)
			)
			(arc
				(start 234.522264 -405.874474)
				(mid 234.400748 -405.850321)
				(end 234.297728 -405.78151)
			)
			(arc
				(start 233.595926 -405.079708)
				(mid 233.527145 -404.976676)
				(end 233.502962 -404.855172)
			)
			(arc
				(start 233.502962 -404.072344)
				(mid 233.499061 -404.052821)
				(end 233.487976 -404.036276)
			)
			(arc
				(start 233.3498 -403.8981)
				(mid 233.281019 -403.795068)
				(end 233.256836 -403.673564)
			)
			(arc
				(start 233.256836 -400.256502)
				(mid 233.252935 -400.236979)
				(end 233.24185 -400.220434)
			)
			(arc
				(start 233.236008 -400.214592)
				(mid 233.219474 -400.203481)
				(end 233.19994 -400.199606)
			)
			(arc
				(start 229.898956 -400.199606)
				(mid 229.879433 -400.203507)
				(end 229.862888 -400.214592)
			)
			(arc
				(start 229.848664 -400.228816)
				(mid 229.837553 -400.24535)
				(end 229.833678 -400.264884)
			)
			(arc
				(start 229.833678 -403.583648)
				(mid 229.809525 -403.705164)
				(end 229.740714 -403.808184)
			)
			(arc
				(start 229.66426 -403.884638)
				(mid 229.653149 -403.901172)
				(end 229.649274 -403.920706)
			)
			(arc
				(start 229.649274 -406.19299)
				(mid 229.625121 -406.314506)
				(end 229.55631 -406.417526)
			)
			(arc
				(start 227.443284 -408.530552)
				(mid 227.340252 -408.599333)
				(end 227.218748 -408.623516)
			)
			(arc
				(start 225.642424 -408.623516)
				(mid 225.623565 -408.627146)
				(end 225.607372 -408.637486)
			)
			(arc
				(start 225.607372 -408.637486)
				(mid 225.364908 -408.792887)
				(end 225.0821 -408.84729)
			)
			(arc
				(start 225.0821 -408.84729)
				(mid 224.549885 -408.630828)
				(end 224.319846 -408.10434)
			)
			(xy 224.319592 -408.094434) (xy 224.311972 -408.076654)
			(arc
				(start 222.874586 -406.639268)
				(mid 222.805805 -406.536236)
				(end 222.781622 -406.414732)
			)
			(arc
				(start 222.781622 -403.953472)
				(mid 222.777721 -403.933949)
				(end 222.766636 -403.917404)
			)
			(arc
				(start 222.681546 -403.832314)
				(mid 222.612765 -403.729282)
				(end 222.588582 -403.607778)
			)
			(xy 222.588582 -400.229832) (xy 222.580962 -400.21129) (xy 222.57766 -400.207988)
			(arc
				(start 219.197936 -400.207988)
				(mid 219.178413 -400.211889)
				(end 219.161868 -400.222974)
			)
			(xy 219.157296 -400.227546)
			(arc
				(start 219.157296 -403.583394)
				(mid 219.133143 -403.70491)
				(end 219.064332 -403.80793)
			)
			(arc
				(start 219.00007 -403.872192)
				(mid 218.988959 -403.888726)
				(end 218.985084 -403.90826)
			)
			(arc
				(start 218.985084 -406.217374)
				(mid 218.960931 -406.33889)
				(end 218.89212 -406.44191)
			)
			(arc
				(start 216.76614 -408.56789)
				(mid 216.663108 -408.636671)
				(end 216.541604 -408.660854)
			)
			(arc
				(start 214.93226 -408.660854)
				(mid 214.915131 -408.66392)
				(end 214.900002 -408.672538)
			)
			(arc
				(start 214.900002 -408.672538)
				(mid 214.672289 -408.802264)
				(end 214.4141 -408.84729)
			)
			(arc
				(start 214.4141 -408.84729)
				(mid 213.886272 -408.635069)
				(end 213.652354 -408.116532)
			)
			(xy 213.651846 -408.10688) (xy 213.644226 -408.089608)
			(arc
				(start 212.189822 -406.635204)
				(mid 212.121041 -406.532172)
				(end 212.096858 -406.410668)
			)
			(arc
				(start 212.096858 -403.916642)
				(mid 212.092957 -403.897119)
				(end 212.081872 -403.880574)
			)
			(arc
				(start 212.058504 -403.857206)
				(mid 211.989723 -403.754174)
				(end 211.96554 -403.63267)
			)
			(arc
				(start 211.96554 -400.29765)
				(mid 211.961639 -400.278127)
				(end 211.950554 -400.261582)
			)
			(arc
				(start 211.854542 -400.16557)
				(mid 211.838008 -400.154459)
				(end 211.818474 -400.150584)
			)
			(arc
				(start 208.578704 -400.150584)
				(mid 208.559181 -400.154485)
				(end 208.542636 -400.16557)
			)
			(arc
				(start 208.512156 -400.19605)
				(mid 208.501045 -400.212584)
				(end 208.49717 -400.232118)
			)
			(arc
				(start 208.49717 -403.534118)
				(mid 208.473017 -403.655634)
				(end 208.404206 -403.758654)
			)
			(arc
				(start 208.323688 -403.839172)
				(mid 208.312577 -403.855706)
				(end 208.308702 -403.87524)
			)
			(arc
				(start 208.308702 -406.275032)
				(mid 208.284549 -406.396548)
				(end 208.215738 -406.499568)
			)
			(arc
				(start 206.172562 -408.542744)
				(mid 206.06953 -408.611525)
				(end 205.948026 -408.635708)
			)
			(arc
				(start 204.293216 -408.635708)
				(mid 204.274946 -408.639107)
				(end 204.25918 -408.648916)
			)
			(arc
				(start 204.25918 -408.648916)
				(mid 204.021144 -408.79596)
				(end 203.7461 -408.84729)
			)
			(arc
				(start 203.7461 -408.84729)
				(mid 203.306844 -408.708001)
				(end 203.028042 -408.341068)
			)
			(xy 203.023978 -408.330146)
			(arc
				(start 201.5871 -406.893268)
				(mid 201.518319 -406.790236)
				(end 201.494136 -406.668732)
			)
			(arc
				(start 201.494136 -403.941026)
				(mid 201.490235 -403.921503)
				(end 201.47915 -403.904958)
			)
			(arc
				(start 201.373994 -403.799802)
				(mid 201.305213 -403.69677)
				(end 201.28103 -403.575266)
			)
			(arc
				(start 201.28103 -400.264884)
				(mid 201.277129 -400.245361)
				(end 201.266044 -400.228816)
			)
			(arc
				(start 201.221594 -400.184366)
				(mid 201.20506 -400.173255)
				(end 201.185526 -400.16938)
			)
			(arc
				(start 197.9168 -400.16938)
				(mid 197.897277 -400.173281)
				(end 197.880732 -400.184366)
			)
			(arc
				(start 197.844156 -400.220942)
				(mid 197.833045 -400.237476)
				(end 197.82917 -400.25701)
			)
			(arc
				(start 197.82917 -403.58314)
				(mid 197.805017 -403.704656)
				(end 197.736206 -403.807676)
			)
			(arc
				(start 195.6435 -405.900382)
				(mid 195.540468 -405.969163)
				(end 195.418964 -405.993346)
			)
			(arc
				(start 191.073786 -405.993346)
				(mid 190.95227 -405.969193)
				(end 190.84925 -405.900382)
			)
			(arc
				(start 188.07938 -403.130512)
				(mid 188.010599 -403.02748)
				(end 187.986416 -402.905976)
			)
			(arc
				(start 187.986416 -400.258534)
				(mid 187.971537 -400.222613)
				(end 187.935616 -400.207734)
			)
			(arc
				(start 184.616598 -400.207734)
				(mid 184.597075 -400.211635)
				(end 184.58053 -400.22272)
			)
			(xy 184.575958 -400.227292) (xy 184.575958 -405.83104) (xy 184.598818 -405.85898)
			(arc
				(start 184.617106 -405.862536)
				(mid 184.925224 -406.236932)
				(end 184.617106 -406.611328)
			)
			(xy 184.598818 -406.614884) (xy 184.575958 -406.642824)
			(arc
				(start 184.575958 -410.555694)
				(mid 184.579859 -410.575217)
				(end 184.590944 -410.591762)
			)
			(arc
				(start 184.926986 -410.927804)
				(mid 184.94352 -410.938915)
				(end 184.963054 -410.94279)
			)
			(arc
				(start 187.965334 -410.94279)
				(mid 188.08685 -410.966943)
				(end 188.18987 -411.035754)
			)
			(arc
				(start 188.836808 -411.682692)
				(mid 188.853342 -411.693803)
				(end 188.872876 -411.697678)
			)
			(arc
				(start 195.270882 -411.697678)
				(mid 195.392398 -411.721831)
				(end 195.495418 -411.790642)
			)
			(arc
				(start 196.65696 -412.952184)
				(mid 196.725741 -413.055216)
				(end 196.749924 -413.17672)
			)
			(arc
				(start 196.749924 -421.558466)
				(mid 196.753825 -421.577989)
				(end 196.76491 -421.594534)
			)
			(arc
				(start 205.961996 -430.79162)
				(mid 206.030777 -430.894652)
				(end 206.05496 -431.016156)
			)
			(arc
				(start 206.05496 -435.078378)
				(mid 206.058861 -435.097901)
				(end 206.069946 -435.114446)
			)
			(arc
				(start 207.419194 -436.463694)
				(mid 207.435728 -436.474805)
				(end 207.455262 -436.47868)
			)
		)
		(stroke
			(width 0)
			(type solid)
		)
		(fill yes)
		(layer "In16.Cu")
		(net "P12V_PSU")
	)
	(gr_poly
		(pts
			(xy 531.7998 -462.519268) (xy 531.855569 -462.518759) (xy 531.966796 -462.510424) (xy 532.077089 -462.4938)
			(xy 532.185831 -462.46898) (xy 532.292414 -462.436103) (xy 532.396243 -462.395354) (xy 532.496736 -462.346959)
			(xy 532.593331 -462.291189) (xy 532.685488 -462.228357) (xy 532.772692 -462.158813) (xy 532.854456 -462.082947)
			(xy 532.930321 -462.001183) (xy 532.999864 -461.913979) (xy 533.062695 -461.821821) (xy 533.118464 -461.725225)
			(xy 533.166858 -461.624732) (xy 533.207607 -461.520903) (xy 533.240483 -461.41432) (xy 533.265302 -461.305577)
			(xy 533.281925 -461.195284) (xy 533.29026 -461.084057) (xy 533.29078 -461.028288) (xy 533.29078 -455.0283)
			(xy 533.290259 -454.972531) (xy 533.281923 -454.861305) (xy 533.265299 -454.751013) (xy 533.24048 -454.642271)
			(xy 533.207603 -454.535688) (xy 533.166854 -454.43186) (xy 533.118459 -454.331368) (xy 533.06269 -454.234773)
			(xy 532.999859 -454.142616) (xy 532.930316 -454.055412) (xy 532.854451 -453.973649) (xy 532.772688 -453.897784)
			(xy 532.685484 -453.828241) (xy 532.593327 -453.76541) (xy 532.496732 -453.709641) (xy 532.39624 -453.661246)
			(xy 532.292412 -453.620497) (xy 532.185829 -453.58762) (xy 532.077087 -453.562801) (xy 531.966795 -453.546177)
			(xy 531.855569 -453.537841) (xy 531.7998 -453.53732) (xy 516.019796 -453.53732) (xy 515.949414 -453.536826)
			(xy 515.808871 -453.528933) (xy 515.668991 -453.513172) (xy 515.530216 -453.489593) (xy 515.392981 -453.45827)
			(xy 515.257718 -453.419302) (xy 515.124852 -453.37281) (xy 514.994803 -453.318942) (xy 514.867978 -453.257866)
			(xy 514.744778 -453.189776) (xy 514.625589 -453.114884) (xy 514.510787 -453.033428) (xy 514.400733 -452.945663)
			(xy 514.295773 -452.851865) (xy 514.196238 -452.75233) (xy 514.10244 -452.64737) (xy 514.014674 -452.537316)
			(xy 513.933218 -452.422514) (xy 513.858326 -452.303325) (xy 513.790236 -452.180125) (xy 513.72916 -452.053301)
			(xy 513.675292 -451.923251) (xy 513.6288 -451.790386) (xy 513.589831 -451.655123) (xy 513.558507 -451.517888)
			(xy 513.534928 -451.379113) (xy 513.519167 -451.239233) (xy 513.511274 -451.09869) (xy 513.510784 -451.028308)
			(xy 513.510784 -312.408316) (xy 513.511268 -312.337933) (xy 513.51916 -312.197389) (xy 513.53492 -312.057508)
			(xy 513.558498 -311.918731) (xy 513.589821 -311.781495) (xy 513.628789 -311.646231) (xy 513.67528 -311.513364)
			(xy 513.729148 -311.383313) (xy 513.790224 -311.256488) (xy 513.858314 -311.133286) (xy 513.933205 -311.014096)
			(xy 514.014662 -310.899292) (xy 514.102427 -310.789237) (xy 514.196225 -310.684276) (xy 514.295761 -310.584739)
			(xy 514.400722 -310.49094) (xy 514.510776 -310.403174) (xy 514.625579 -310.321716) (xy 514.744769 -310.246824)
			(xy 514.86797 -310.178733) (xy 514.994795 -310.117656) (xy 515.124845 -310.063787) (xy 515.257712 -310.017295)
			(xy 515.392976 -309.978326) (xy 515.530212 -309.947002) (xy 515.668989 -309.923423) (xy 515.808869 -309.907662)
			(xy 515.949413 -309.899769) (xy 516.019796 -309.899304) (xy 531.7998 -309.899304) (xy 531.855569 -309.898783)
			(xy 531.966796 -309.890447) (xy 532.077089 -309.873823) (xy 532.185831 -309.849004) (xy 532.292415 -309.816128)
			(xy 532.396243 -309.775378) (xy 532.496737 -309.726984) (xy 532.593332 -309.671215) (xy 532.68549 -309.608384)
			(xy 532.772695 -309.538841) (xy 532.854459 -309.462976) (xy 532.930326 -309.381213) (xy 532.99987 -309.294009)
			(xy 533.062703 -309.201852) (xy 533.118473 -309.105258) (xy 533.166869 -309.004765) (xy 533.20762 -308.900937)
			(xy 533.240498 -308.794355) (xy 533.265319 -308.685613) (xy 533.281945 -308.57532) (xy 533.290282 -308.464093)
			(xy 533.29078 -308.408324) (xy 533.29078 10.40003) (xy 533.290257 10.455798) (xy 533.28192 10.567023)
			(xy 533.265294 10.677313) (xy 533.240473 10.786053) (xy 533.207596 10.892634) (xy 533.166845 10.99646)
			(xy 533.11845 11.09695) (xy 533.06268 11.193543) (xy 532.999848 11.285698) (xy 532.930305 11.3729)
			(xy 532.85444 11.454661) (xy 532.772677 11.530525) (xy 532.685474 11.600066) (xy 532.593318 11.662896)
			(xy 532.496724 11.718664) (xy 532.396232 11.767057) (xy 532.292406 11.807806) (xy 532.185824 11.840681)
			(xy 532.077084 11.8655) (xy 531.966793 11.882123) (xy 531.855568 11.890459) (xy 531.7998 11.89101)
			(xy 475.799912 11.89101) (xy 475.744142 11.890489) (xy 475.632915 11.882155) (xy 475.522621 11.865531)
			(xy 475.413878 11.840713) (xy 475.307293 11.807837) (xy 475.203464 11.767088) (xy 475.10297 11.718694)
			(xy 475.006373 11.662926) (xy 474.914214 11.600094) (xy 474.827008 11.530552) (xy 474.745243 11.454687)
			(xy 474.669376 11.372924) (xy 474.599831 11.28572) (xy 474.536997 11.193563) (xy 474.481225 11.096967)
			(xy 474.432829 10.996475) (xy 474.392077 10.892646) (xy 474.359198 10.786063) (xy 474.334376 10.67732)
			(xy 474.31775 10.567027) (xy 474.309413 10.4558) (xy 474.308932 10.40003) (xy 474.308932 7.335466)
			(xy 526.704041 7.335466) (xy 526.704041 7.464606) (xy 526.711991 7.593501) (xy 526.727861 7.721661)
			(xy 526.75159 7.848602) (xy 526.783089 7.973841) (xy 526.822238 8.096904) (xy 526.868889 8.217323)
			(xy 526.922864 8.334642) (xy 526.983959 8.448416) (xy 527.051942 8.558213) (xy 527.126556 8.663616)
			(xy 527.207517 8.764226) (xy 527.294517 8.859661) (xy 527.387228 8.94956) (xy 527.485298 9.033581)
			(xy 527.588353 9.111405) (xy 527.696004 9.182737) (xy 527.807843 9.247307) (xy 527.923444 9.304869)
			(xy 528.042369 9.355206) (xy 528.164168 9.398126) (xy 528.288378 9.433467) (xy 528.414527 9.461094)
			(xy 528.542139 9.480903) (xy 528.670728 9.492819) (xy 528.799806 9.496796) (xy 528.928884 9.492819)
			(xy 529.057473 9.480903) (xy 529.185085 9.461094) (xy 529.311234 9.433467) (xy 529.435444 9.398126)
			(xy 529.557243 9.355206) (xy 529.676168 9.304869) (xy 529.791769 9.247307) (xy 529.903608 9.182737)
			(xy 530.011259 9.111405) (xy 530.114314 9.033581) (xy 530.212384 8.94956) (xy 530.305095 8.859661)
			(xy 530.392095 8.764226) (xy 530.473056 8.663616) (xy 530.54767 8.558213) (xy 530.615653 8.448416)
			(xy 530.676748 8.334642) (xy 530.730723 8.217323) (xy 530.777374 8.096904) (xy 530.816523 7.973841)
			(xy 530.848022 7.848602) (xy 530.871751 7.721661) (xy 530.887621 7.593501) (xy 530.895571 7.464606)
			(xy 530.896068 7.400036) (xy 530.895571 7.335466) (xy 530.887621 7.206571) (xy 530.871751 7.078411)
			(xy 530.848022 6.95147) (xy 530.816523 6.826231) (xy 530.777374 6.703168) (xy 530.730723 6.582749)
			(xy 530.676748 6.46543) (xy 530.615653 6.351656) (xy 530.54767 6.241859) (xy 530.473056 6.136456)
			(xy 530.392095 6.035846) (xy 530.305095 5.940411) (xy 530.212384 5.850512) (xy 530.114314 5.766491)
			(xy 530.011259 5.688667) (xy 529.903608 5.617335) (xy 529.791769 5.552765) (xy 529.676168 5.495203)
			(xy 529.557243 5.444866) (xy 529.435444 5.401946) (xy 529.311234 5.366605) (xy 529.185085 5.338978)
			(xy 529.057473 5.319169) (xy 528.928884 5.307253) (xy 528.799806 5.303277) (xy 528.670728 5.307253)
			(xy 528.542139 5.319169) (xy 528.414527 5.338978) (xy 528.288378 5.366605) (xy 528.164168 5.401946)
			(xy 528.042369 5.444866) (xy 527.923444 5.495203) (xy 527.807843 5.552765) (xy 527.696004 5.617335)
			(xy 527.588353 5.688667) (xy 527.485298 5.766491) (xy 527.387228 5.850512) (xy 527.294517 5.940411)
			(xy 527.207517 6.035846) (xy 527.126556 6.136456) (xy 527.051942 6.241859) (xy 526.983959 6.351656)
			(xy 526.922864 6.46543) (xy 526.868889 6.582749) (xy 526.822238 6.703168) (xy 526.783089 6.826231)
			(xy 526.75159 6.95147) (xy 526.727861 7.078411) (xy 526.711991 7.206571) (xy 526.704041 7.335466)
			(xy 474.308932 7.335466) (xy 474.308932 -12.515904) (xy 476.704141 -12.515904) (xy 476.704141 -12.386764)
			(xy 476.712091 -12.257869) (xy 476.727961 -12.129709) (xy 476.75169 -12.002768) (xy 476.783189 -11.877529)
			(xy 476.822338 -11.754466) (xy 476.868989 -11.634047) (xy 476.922964 -11.516728) (xy 476.984059 -11.402954)
			(xy 477.052042 -11.293157) (xy 477.126656 -11.187754) (xy 477.207617 -11.087144) (xy 477.294617 -10.991709)
			(xy 477.387328 -10.90181) (xy 477.485398 -10.817789) (xy 477.588453 -10.739965) (xy 477.696104 -10.668633)
			(xy 477.807943 -10.604063) (xy 477.923544 -10.546501) (xy 478.042469 -10.496164) (xy 478.164268 -10.453244)
			(xy 478.288478 -10.417903) (xy 478.414627 -10.390276) (xy 478.542239 -10.370467) (xy 478.670828 -10.358551)
			(xy 478.799906 -10.354575) (xy 478.928984 -10.358551) (xy 479.057573 -10.370467) (xy 479.185185 -10.390276)
			(xy 479.311334 -10.417903) (xy 479.435544 -10.453244) (xy 479.557343 -10.496164) (xy 479.676268 -10.546501)
			(xy 479.791869 -10.604063) (xy 479.903708 -10.668633) (xy 480.011359 -10.739965) (xy 480.114414 -10.817789)
			(xy 480.212484 -10.90181) (xy 480.305195 -10.991709) (xy 480.392195 -11.087144) (xy 480.473156 -11.187754)
			(xy 480.54777 -11.293157) (xy 480.615753 -11.402954) (xy 480.676848 -11.516728) (xy 480.730823 -11.634047)
			(xy 480.777474 -11.754466) (xy 480.816623 -11.877529) (xy 480.848122 -12.002768) (xy 480.871851 -12.129709)
			(xy 480.887721 -12.257869) (xy 480.895671 -12.386764) (xy 480.896168 -12.451334) (xy 480.895671 -12.515904)
			(xy 480.887721 -12.644799) (xy 480.871851 -12.772959) (xy 480.848122 -12.8999) (xy 480.816623 -13.025139)
			(xy 480.777474 -13.148202) (xy 480.730823 -13.268621) (xy 480.676848 -13.38594) (xy 480.615753 -13.499714)
			(xy 480.54777 -13.609511) (xy 480.473156 -13.714914) (xy 480.392195 -13.815524) (xy 480.305195 -13.910959)
			(xy 480.212484 -14.000858) (xy 480.114414 -14.084879) (xy 480.011359 -14.162703) (xy 479.903708 -14.234035)
			(xy 479.791869 -14.298605) (xy 479.676268 -14.356167) (xy 479.557343 -14.406504) (xy 479.435544 -14.449424)
			(xy 479.311334 -14.484765) (xy 479.185185 -14.512392) (xy 479.057573 -14.532201) (xy 478.928984 -14.544117)
			(xy 478.799906 -14.548094) (xy 478.670828 -14.544117) (xy 478.542239 -14.532201) (xy 478.414627 -14.512392)
			(xy 478.288478 -14.484765) (xy 478.164268 -14.449424) (xy 478.042469 -14.406504) (xy 477.923544 -14.356167)
			(xy 477.807943 -14.298605) (xy 477.696104 -14.234035) (xy 477.588453 -14.162703) (xy 477.485398 -14.084879)
			(xy 477.387328 -14.000858) (xy 477.294617 -13.910959) (xy 477.207617 -13.815524) (xy 477.126656 -13.714914)
			(xy 477.052042 -13.609511) (xy 476.984059 -13.499714) (xy 476.922964 -13.38594) (xy 476.868989 -13.268621)
			(xy 476.822338 -13.148202) (xy 476.783189 -13.025139) (xy 476.75169 -12.8999) (xy 476.727961 -12.772959)
			(xy 476.712091 -12.644799) (xy 476.704141 -12.515904) (xy 474.308932 -12.515904) (xy 474.308932 -77.67193)
			(xy 474.308458 -77.765117) (xy 474.300759 -77.951331) (xy 474.28537 -78.137067) (xy 474.262318 -78.32201)
			(xy 474.231642 -78.505841) (xy 474.193396 -78.688247) (xy 474.147643 -78.868917) (xy 474.094463 -79.047542)
			(xy 474.033945 -79.223817) (xy 473.966195 -79.397439) (xy 473.891327 -79.568113) (xy 473.809469 -79.735548)
			(xy 473.720761 -79.899456) (xy 473.625355 -80.059558) (xy 473.523414 -80.21558) (xy 473.415112 -80.367256)
			(xy 473.300633 -80.514327) (xy 473.180175 -80.65654) (xy 473.053942 -80.793654) (xy 472.988386 -80.859884)
			(xy 471.245946 -82.602324) (xy 471.208633 -82.640304) (xy 471.138899 -82.72077) (xy 471.07508 -82.806006)
			(xy 471.017504 -82.895576) (xy 470.966464 -82.989025) (xy 470.922218 -83.085876) (xy 470.884993 -83.185636)
			(xy 470.854978 -83.287798) (xy 470.832326 -83.391839) (xy 470.817153 -83.497232) (xy 470.809535 -83.603438)
			(xy 470.809066 -83.656678) (xy 470.809066 -328.137828) (xy 473.204275 -328.137828) (xy 473.204275 -328.008688)
			(xy 473.212225 -327.879793) (xy 473.228095 -327.751633) (xy 473.251824 -327.624692) (xy 473.283323 -327.499453)
			(xy 473.322472 -327.37639) (xy 473.369123 -327.255971) (xy 473.423098 -327.138652) (xy 473.484193 -327.024878)
			(xy 473.552176 -326.915081) (xy 473.62679 -326.809678) (xy 473.707751 -326.709068) (xy 473.794751 -326.613633)
			(xy 473.887462 -326.523734) (xy 473.985532 -326.439713) (xy 474.088587 -326.361889) (xy 474.196238 -326.290557)
			(xy 474.308077 -326.225987) (xy 474.423678 -326.168425) (xy 474.542603 -326.118088) (xy 474.664402 -326.075168)
			(xy 474.788612 -326.039827) (xy 474.914761 -326.0122) (xy 475.042373 -325.992391) (xy 475.170962 -325.980475)
			(xy 475.30004 -325.976499) (xy 475.429118 -325.980475) (xy 475.557707 -325.992391) (xy 475.685319 -326.0122)
			(xy 475.811468 -326.039827) (xy 475.935678 -326.075168) (xy 476.057477 -326.118088) (xy 476.176402 -326.168425)
			(xy 476.292003 -326.225987) (xy 476.403842 -326.290557) (xy 476.511493 -326.361889) (xy 476.614548 -326.439713)
			(xy 476.712618 -326.523734) (xy 476.805329 -326.613633) (xy 476.892329 -326.709068) (xy 476.97329 -326.809678)
			(xy 477.047904 -326.915081) (xy 477.115887 -327.024878) (xy 477.176982 -327.138652) (xy 477.230957 -327.255971)
			(xy 477.277608 -327.37639) (xy 477.316757 -327.499453) (xy 477.348256 -327.624692) (xy 477.371985 -327.751633)
			(xy 477.387855 -327.879793) (xy 477.395805 -328.008688) (xy 477.396302 -328.073258) (xy 477.395805 -328.137828)
			(xy 477.387855 -328.266723) (xy 477.371985 -328.394883) (xy 477.348256 -328.521824) (xy 477.316757 -328.647063)
			(xy 477.277608 -328.770126) (xy 477.230957 -328.890545) (xy 477.176982 -329.007864) (xy 477.115887 -329.121638)
			(xy 477.047904 -329.231435) (xy 476.97329 -329.336838) (xy 476.892329 -329.437448) (xy 476.805329 -329.532883)
			(xy 476.712618 -329.622782) (xy 476.614548 -329.706803) (xy 476.511493 -329.784627) (xy 476.403842 -329.855959)
			(xy 476.292003 -329.920529) (xy 476.176402 -329.978091) (xy 476.057477 -330.028428) (xy 475.935678 -330.071348)
			(xy 475.811468 -330.106689) (xy 475.685319 -330.134316) (xy 475.557707 -330.154125) (xy 475.429118 -330.166041)
			(xy 475.30004 -330.170018) (xy 475.170962 -330.166041) (xy 475.042373 -330.154125) (xy 474.914761 -330.134316)
			(xy 474.788612 -330.106689) (xy 474.664402 -330.071348) (xy 474.542603 -330.028428) (xy 474.423678 -329.978091)
			(xy 474.308077 -329.920529) (xy 474.196238 -329.855959) (xy 474.088587 -329.784627) (xy 473.985532 -329.706803)
			(xy 473.887462 -329.622782) (xy 473.794751 -329.532883) (xy 473.707751 -329.437448) (xy 473.62679 -329.336838)
			(xy 473.552176 -329.231435) (xy 473.484193 -329.121638) (xy 473.423098 -329.007864) (xy 473.369123 -328.890545)
			(xy 473.322472 -328.770126) (xy 473.283323 -328.647063) (xy 473.251824 -328.521824) (xy 473.228095 -328.394883)
			(xy 473.212225 -328.266723) (xy 473.204275 -328.137828) (xy 470.809066 -328.137828) (xy 470.809066 -404.871936)
			(xy 470.808592 -404.965123) (xy 470.800892 -405.151337) (xy 470.785503 -405.337074) (xy 470.762451 -405.522016)
			(xy 470.731776 -405.705847) (xy 470.693529 -405.888254) (xy 470.647776 -406.068924) (xy 470.594596 -406.247549)
			(xy 470.534079 -406.423823) (xy 470.466329 -406.597446) (xy 470.391461 -406.76812) (xy 470.309603 -406.935555)
			(xy 470.220896 -407.099463) (xy 470.12549 -407.259566) (xy 470.02355 -407.415588) (xy 469.915248 -407.567265)
			(xy 469.80077 -407.714335) (xy 469.680312 -407.856549) (xy 469.554079 -407.993664) (xy 469.48852 -408.05989)
			(xy 468.245698 -409.302712) (xy 468.208406 -409.340689) (xy 468.138712 -409.421147) (xy 468.074932 -409.506369)
			(xy 468.017391 -409.595922) (xy 467.966382 -409.68935) (xy 467.922165 -409.786178) (xy 467.884964 -409.885911)
			(xy 467.85497 -409.988044) (xy 467.832334 -410.092055) (xy 467.817172 -410.197416) (xy 467.809562 -410.303589)
			(xy 467.809072 -410.356812) (xy 467.809072 -439.989976) (xy 467.809593 -440.045746) (xy 467.817926 -440.156975)
			(xy 467.834548 -440.26727) (xy 467.859367 -440.376014) (xy 467.892242 -440.4826) (xy 467.93299 -440.586431)
			(xy 467.981383 -440.686926) (xy 468.037152 -440.783525) (xy 468.099983 -440.875685) (xy 468.169525 -440.962893)
			(xy 468.24539 -441.044659) (xy 468.327153 -441.120528) (xy 468.414357 -441.190075) (xy 468.506514 -441.25291)
			(xy 468.60311 -441.308683) (xy 468.703603 -441.357081) (xy 468.807432 -441.397835) (xy 468.914016 -441.430715)
			(xy 469.022759 -441.455538) (xy 469.133053 -441.472166) (xy 469.244282 -441.480505) (xy 469.300052 -441.480956)
			(xy 471.79992 -441.480956) (xy 471.870302 -441.48145) (xy 472.010845 -441.489344) (xy 472.150724 -441.505105)
			(xy 472.2895 -441.528685) (xy 472.426735 -441.560009) (xy 472.561998 -441.598978) (xy 472.694863 -441.64547)
			(xy 472.824912 -441.699339) (xy 472.951736 -441.760414) (xy 473.074936 -441.828505) (xy 473.194125 -441.903396)
			(xy 473.308927 -441.984852) (xy 473.418981 -442.072617) (xy 473.523941 -442.166415) (xy 473.623477 -442.26595)
			(xy 473.717275 -442.37091) (xy 473.80504 -442.480964) (xy 473.886497 -442.595765) (xy 473.961389 -442.714953)
			(xy 474.02948 -442.838153) (xy 474.090556 -442.964977) (xy 474.144426 -443.095026) (xy 474.190918 -443.227891)
			(xy 474.229888 -443.363154) (xy 474.261212 -443.500389) (xy 474.284793 -443.639164) (xy 474.300555 -443.779043)
			(xy 474.308449 -443.919586) (xy 474.308932 -443.989968) (xy 474.308932 -458.092864) (xy 526.704041 -458.092864)
			(xy 526.704041 -457.963724) (xy 526.711991 -457.834829) (xy 526.727861 -457.706669) (xy 526.75159 -457.579728)
			(xy 526.783089 -457.454489) (xy 526.822238 -457.331426) (xy 526.868889 -457.211007) (xy 526.922864 -457.093688)
			(xy 526.983959 -456.979914) (xy 527.051942 -456.870117) (xy 527.126556 -456.764714) (xy 527.207517 -456.664104)
			(xy 527.294517 -456.568669) (xy 527.387228 -456.47877) (xy 527.485298 -456.394749) (xy 527.588353 -456.316925)
			(xy 527.696004 -456.245593) (xy 527.807843 -456.181023) (xy 527.923444 -456.123461) (xy 528.042369 -456.073124)
			(xy 528.164168 -456.030204) (xy 528.288378 -455.994863) (xy 528.414527 -455.967236) (xy 528.542139 -455.947427)
			(xy 528.670728 -455.935511) (xy 528.799806 -455.931535) (xy 528.928884 -455.935511) (xy 529.057473 -455.947427)
			(xy 529.185085 -455.967236) (xy 529.311234 -455.994863) (xy 529.435444 -456.030204) (xy 529.557243 -456.073124)
			(xy 529.676168 -456.123461) (xy 529.791769 -456.181023) (xy 529.903608 -456.245593) (xy 530.011259 -456.316925)
			(xy 530.114314 -456.394749) (xy 530.212384 -456.47877) (xy 530.305095 -456.568669) (xy 530.392095 -456.664104)
			(xy 530.473056 -456.764714) (xy 530.54767 -456.870117) (xy 530.615653 -456.979914) (xy 530.676748 -457.093688)
			(xy 530.730723 -457.211007) (xy 530.777374 -457.331426) (xy 530.816523 -457.454489) (xy 530.848022 -457.579728)
			(xy 530.871751 -457.706669) (xy 530.887621 -457.834829) (xy 530.895571 -457.963724) (xy 530.896068 -458.028294)
			(xy 530.895571 -458.092864) (xy 530.887621 -458.221759) (xy 530.871751 -458.349919) (xy 530.848022 -458.47686)
			(xy 530.816523 -458.602099) (xy 530.777374 -458.725162) (xy 530.730723 -458.845581) (xy 530.676748 -458.9629)
			(xy 530.615653 -459.076674) (xy 530.54767 -459.186471) (xy 530.473056 -459.291874) (xy 530.392095 -459.392484)
			(xy 530.305095 -459.487919) (xy 530.212384 -459.577818) (xy 530.114314 -459.661839) (xy 530.011259 -459.739663)
			(xy 529.903608 -459.810995) (xy 529.791769 -459.875565) (xy 529.676168 -459.933127) (xy 529.557243 -459.983464)
			(xy 529.435444 -460.026384) (xy 529.311234 -460.061725) (xy 529.185085 -460.089352) (xy 529.057473 -460.109161)
			(xy 528.928884 -460.121077) (xy 528.799806 -460.125054) (xy 528.670728 -460.121077) (xy 528.542139 -460.109161)
			(xy 528.414527 -460.089352) (xy 528.288378 -460.061725) (xy 528.164168 -460.026384) (xy 528.042369 -459.983464)
			(xy 527.923444 -459.933127) (xy 527.807843 -459.875565) (xy 527.696004 -459.810995) (xy 527.588353 -459.739663)
			(xy 527.485298 -459.661839) (xy 527.387228 -459.577818) (xy 527.294517 -459.487919) (xy 527.207517 -459.392484)
			(xy 527.126556 -459.291874) (xy 527.051942 -459.186471) (xy 526.983959 -459.076674) (xy 526.922864 -458.9629)
			(xy 526.868889 -458.845581) (xy 526.822238 -458.725162) (xy 526.783089 -458.602099) (xy 526.75159 -458.47686)
			(xy 526.727861 -458.349919) (xy 526.711991 -458.221759) (xy 526.704041 -458.092864) (xy 474.308932 -458.092864)
			(xy 474.308932 -461.028288) (xy 474.30944 -461.084058) (xy 474.317775 -461.195285) (xy 474.334398 -461.305579)
			(xy 474.359217 -461.414322) (xy 474.392093 -461.520906) (xy 474.432843 -461.624735) (xy 474.481238 -461.725228)
			(xy 474.537007 -461.821824) (xy 474.599839 -461.913982) (xy 474.669383 -462.001187) (xy 474.745248 -462.082952)
			(xy 474.827013 -462.158817) (xy 474.914218 -462.228361) (xy 475.006376 -462.291193) (xy 475.102972 -462.346962)
			(xy 475.203465 -462.395357) (xy 475.307294 -462.436107) (xy 475.413878 -462.468983) (xy 475.522621 -462.493802)
			(xy 475.632915 -462.510425) (xy 475.744142 -462.51876) (xy 475.799912 -462.519268)
		)
		(stroke
			(width 0)
			(type solid)
		)
		(fill yes)
		(layer "In16.Cu")
		(net "T1_GND")
	)
	(gr_poly
		(pts
			(xy 255.800098 -33.611058) (xy 255.832245 -33.610555) (xy 255.89599 -33.602163) (xy 255.958093 -33.585522)
			(xy 256.017493 -33.560917) (xy 256.073173 -33.528769) (xy 256.124181 -33.489628) (xy 256.169643 -33.444164)
			(xy 256.208781 -33.393155) (xy 256.240927 -33.337473) (xy 256.265529 -33.278072) (xy 256.282167 -33.215968)
			(xy 256.290557 -33.152223) (xy 256.29108 -33.120076) (xy 256.29108 -11.780012) (xy 256.291564 -11.709629)
			(xy 256.299456 -11.569085) (xy 256.315217 -11.429205) (xy 256.338795 -11.290428) (xy 256.370118 -11.153191)
			(xy 256.409086 -11.017927) (xy 256.455577 -10.885061) (xy 256.509445 -10.75501) (xy 256.570521 -10.628184)
			(xy 256.638611 -10.504983) (xy 256.713502 -10.385793) (xy 256.794959 -10.27099) (xy 256.882724 -10.160934)
			(xy 256.976523 -10.055973) (xy 257.076059 -9.956436) (xy 257.181019 -9.862637) (xy 257.291074 -9.774871)
			(xy 257.405876 -9.693414) (xy 257.525065 -9.618521) (xy 257.648266 -9.55043) (xy 257.775092 -9.489354)
			(xy 257.905142 -9.435484) (xy 258.038008 -9.388992) (xy 258.173272 -9.350023) (xy 258.310508 -9.318699)
			(xy 258.449285 -9.295119) (xy 258.589165 -9.279358) (xy 258.729709 -9.271465) (xy 258.800092 -9.271)
			(xy 383.601976 -9.271) (xy 383.657746 -9.270492) (xy 383.768975 -9.262159) (xy 383.87927 -9.245536)
			(xy 383.988015 -9.220718) (xy 384.094601 -9.187842) (xy 384.198432 -9.147093) (xy 384.298927 -9.098699)
			(xy 384.395525 -9.04293) (xy 384.487685 -8.980099) (xy 384.574892 -8.910555) (xy 384.656659 -8.83469)
			(xy 384.732527 -8.752926) (xy 384.802073 -8.665721) (xy 384.864907 -8.573562) (xy 384.920679 -8.476966)
			(xy 384.969076 -8.376472) (xy 385.009828 -8.272642) (xy 385.042706 -8.166058) (xy 385.067528 -8.057314)
			(xy 385.084154 -7.947019) (xy 385.092491 -7.83579) (xy 385.092956 -7.78002) (xy 385.092956 0.40005)
			(xy 385.093451 0.470432) (xy 385.101346 0.610973) (xy 385.117109 0.750851) (xy 385.14069 0.889625)
			(xy 385.172015 1.026859) (xy 385.210985 1.16212) (xy 385.257478 1.294984) (xy 385.311348 1.425032)
			(xy 385.372424 1.551855) (xy 385.440515 1.675053) (xy 385.515407 1.79424) (xy 385.596863 1.909041)
			(xy 385.684628 2.019094) (xy 385.778426 2.124052) (xy 385.877961 2.223587) (xy 385.98292 2.317383)
			(xy 386.092974 2.405148) (xy 386.207775 2.486603) (xy 386.326962 2.561494) (xy 386.450161 2.629584)
			(xy 386.576985 2.69066) (xy 386.707033 2.744528) (xy 386.839897 2.79102) (xy 386.975158 2.829989)
			(xy 387.112392 2.861313) (xy 387.251166 2.884893) (xy 387.391045 2.900655) (xy 387.531586 2.908549)
			(xy 387.601968 2.909062) (xy 456.202034 2.909062) (xy 456.272416 2.908567) (xy 456.412959 2.900673)
			(xy 456.552838 2.884911) (xy 456.691613 2.861331) (xy 456.828848 2.830006) (xy 456.96411 2.791037)
			(xy 457.096975 2.744544) (xy 457.227024 2.690676) (xy 457.353848 2.6296) (xy 457.477048 2.561509)
			(xy 457.596236 2.486618) (xy 457.711038 2.405161) (xy 457.821092 2.317396) (xy 457.926052 2.223599)
			(xy 458.025588 2.124064) (xy 458.119386 2.019104) (xy 458.207152 1.909051) (xy 458.288609 1.79425)
			(xy 458.363501 1.675062) (xy 458.431592 1.551862) (xy 458.492669 1.425039) (xy 458.546539 1.29499)
			(xy 458.593032 1.162126) (xy 458.632002 1.026863) (xy 458.663327 0.889629) (xy 458.686909 0.750854)
			(xy 458.702672 0.610975) (xy 458.710567 0.470432) (xy 458.711046 0.40005) (xy 458.711046 -4.844596)
			(xy 464.704165 -4.844596) (xy 464.704165 -4.715456) (xy 464.712115 -4.586561) (xy 464.727985 -4.458401)
			(xy 464.751714 -4.33146) (xy 464.783213 -4.206221) (xy 464.822362 -4.083158) (xy 464.869013 -3.962739)
			(xy 464.922988 -3.84542) (xy 464.984083 -3.731646) (xy 465.052066 -3.621849) (xy 465.12668 -3.516446)
			(xy 465.207641 -3.415836) (xy 465.294641 -3.320401) (xy 465.387352 -3.230502) (xy 465.485422 -3.146481)
			(xy 465.588477 -3.068657) (xy 465.696128 -2.997325) (xy 465.807967 -2.932755) (xy 465.923568 -2.875193)
			(xy 466.042493 -2.824856) (xy 466.164292 -2.781936) (xy 466.288502 -2.746595) (xy 466.414651 -2.718968)
			(xy 466.542263 -2.699159) (xy 466.670852 -2.687243) (xy 466.79993 -2.683267) (xy 466.929008 -2.687243)
			(xy 467.057597 -2.699159) (xy 467.185209 -2.718968) (xy 467.311358 -2.746595) (xy 467.435568 -2.781936)
			(xy 467.557367 -2.824856) (xy 467.676292 -2.875193) (xy 467.791893 -2.932755) (xy 467.903732 -2.997325)
			(xy 468.011383 -3.068657) (xy 468.114438 -3.146481) (xy 468.212508 -3.230502) (xy 468.305219 -3.320401)
			(xy 468.392219 -3.415836) (xy 468.47318 -3.516446) (xy 468.547794 -3.621849) (xy 468.615777 -3.731646)
			(xy 468.676872 -3.84542) (xy 468.730847 -3.962739) (xy 468.777498 -4.083158) (xy 468.816647 -4.206221)
			(xy 468.848146 -4.33146) (xy 468.871875 -4.458401) (xy 468.887745 -4.586561) (xy 468.895695 -4.715456)
			(xy 468.896192 -4.780026) (xy 468.895695 -4.844596) (xy 468.887745 -4.973491) (xy 468.871875 -5.101651)
			(xy 468.848146 -5.228592) (xy 468.816647 -5.353831) (xy 468.777498 -5.476894) (xy 468.730847 -5.597313)
			(xy 468.676872 -5.714632) (xy 468.615777 -5.828406) (xy 468.547794 -5.938203) (xy 468.47318 -6.043606)
			(xy 468.392219 -6.144216) (xy 468.305219 -6.239651) (xy 468.212508 -6.32955) (xy 468.114438 -6.413571)
			(xy 468.011383 -6.491395) (xy 467.903732 -6.562727) (xy 467.791893 -6.627297) (xy 467.676292 -6.684859)
			(xy 467.557367 -6.735196) (xy 467.435568 -6.778116) (xy 467.311358 -6.813457) (xy 467.185209 -6.841084)
			(xy 467.057597 -6.860893) (xy 466.929008 -6.872809) (xy 466.79993 -6.876786) (xy 466.670852 -6.872809)
			(xy 466.542263 -6.860893) (xy 466.414651 -6.841084) (xy 466.288502 -6.813457) (xy 466.164292 -6.778116)
			(xy 466.042493 -6.735196) (xy 465.923568 -6.684859) (xy 465.807967 -6.627297) (xy 465.696128 -6.562727)
			(xy 465.588477 -6.491395) (xy 465.485422 -6.413571) (xy 465.387352 -6.32955) (xy 465.294641 -6.239651)
			(xy 465.207641 -6.144216) (xy 465.12668 -6.043606) (xy 465.052066 -5.938203) (xy 464.984083 -5.828406)
			(xy 464.922988 -5.714632) (xy 464.869013 -5.597313) (xy 464.822362 -5.476894) (xy 464.783213 -5.353831)
			(xy 464.751714 -5.228592) (xy 464.727985 -5.101651) (xy 464.712115 -4.973491) (xy 464.704165 -4.844596)
			(xy 458.711046 -4.844596) (xy 458.711046 -7.78002) (xy 458.711555 -7.835789) (xy 458.719892 -7.947014)
			(xy 458.736517 -8.057305) (xy 458.761338 -8.166046) (xy 458.794216 -8.272628) (xy 458.834967 -8.376454)
			(xy 458.883362 -8.476945) (xy 458.939132 -8.573538) (xy 459.001965 -8.665694) (xy 459.071509 -8.752896)
			(xy 459.147375 -8.834658) (xy 459.229138 -8.910521) (xy 459.316343 -8.980062) (xy 459.4085 -9.042892)
			(xy 459.505096 -9.098659) (xy 459.605588 -9.147052) (xy 459.709416 -9.187799) (xy 459.815999 -9.220674)
			(xy 459.92474 -9.245491) (xy 460.035032 -9.262113) (xy 460.146257 -9.270446) (xy 460.202026 -9.271)
			(xy 469.799924 -9.271) (xy 469.855693 -9.270478) (xy 469.966918 -9.262141) (xy 470.07721 -9.245516)
			(xy 470.18595 -9.220695) (xy 470.292532 -9.187817) (xy 470.396359 -9.147067) (xy 470.49685 -9.098672)
			(xy 470.593444 -9.042903) (xy 470.685601 -8.980071) (xy 470.772804 -8.910528) (xy 470.854566 -8.834664)
			(xy 470.930431 -8.752901) (xy 470.999974 -8.665697) (xy 471.062805 -8.573541) (xy 471.118574 -8.476947)
			(xy 471.166969 -8.376455) (xy 471.207719 -8.272628) (xy 471.240596 -8.166046) (xy 471.265416 -8.057306)
			(xy 471.282041 -7.947014) (xy 471.290378 -7.835789) (xy 471.290904 -7.78002) (xy 471.290904 10.40003)
			(xy 471.290381 10.455799) (xy 471.282044 10.567024) (xy 471.265419 10.677315) (xy 471.240598 10.786055)
			(xy 471.20772 10.892637) (xy 471.16697 10.996464) (xy 471.118574 11.096955) (xy 471.062805 11.193548)
			(xy 470.999973 11.285705) (xy 470.930431 11.372908) (xy 470.854566 11.45467) (xy 470.772803 11.530534)
			(xy 470.6856 11.600077) (xy 470.593443 11.662908) (xy 470.49685 11.718677) (xy 470.396358 11.767072)
			(xy 470.292531 11.807822) (xy 470.18595 11.840699) (xy 470.077209 11.86552) (xy 469.966918 11.882145)
			(xy 469.855693 11.890482) (xy 469.799924 11.89101) (xy 1.999996 11.89101) (xy 1.944227 11.890488)
			(xy 1.833001 11.882153) (xy 1.722709 11.865529) (xy 1.613968 11.840709) (xy 1.507385 11.807832) (xy 1.403558 11.767083)
			(xy 1.303066 11.718688) (xy 1.206471 11.662919) (xy 1.114314 11.600087) (xy 1.027111 11.530545) (xy 0.945348 11.454679)
			(xy 0.869483 11.372916) (xy 0.79994 11.285712) (xy 0.737109 11.193555) (xy 0.68134 11.096961) (xy 0.632946 10.996469)
			(xy 0.592196 10.892641) (xy 0.55932 10.786058) (xy 0.534501 10.677317) (xy 0.517877 10.567025) (xy 0.509541 10.455799)
			(xy 0.509016 10.40003) (xy 0.509016 9.916973) (xy 385.651997 9.916973) (xy 385.651997 10.002723)
			(xy 385.659909 10.088106) (xy 385.675665 10.172396) (xy 385.699132 10.254872) (xy 385.730108 10.334831)
			(xy 385.76833 10.411591) (xy 385.813471 10.484497) (xy 385.865147 10.552926) (xy 385.922916 10.616296)
			(xy 385.986286 10.674065) (xy 386.054715 10.725741) (xy 386.127621 10.770882) (xy 386.204381 10.809104)
			(xy 386.28434 10.84008) (xy 386.366816 10.863547) (xy 386.451106 10.879303) (xy 386.536489 10.887215)
			(xy 386.622239 10.887215) (xy 386.707622 10.879303) (xy 386.791912 10.863547) (xy 386.874388 10.84008)
			(xy 386.954347 10.809104) (xy 387.031107 10.770882) (xy 387.104013 10.725741) (xy 387.172442 10.674065)
			(xy 387.235812 10.616296) (xy 387.293581 10.552926) (xy 387.345257 10.484497) (xy 387.390398 10.411591)
			(xy 387.42862 10.334831) (xy 387.459596 10.254872) (xy 387.483063 10.172396) (xy 387.498819 10.088106)
			(xy 387.506731 10.002723) (xy 387.507226 9.959848) (xy 387.506731 9.916973) (xy 392.001997 9.916973)
			(xy 392.001997 10.002723) (xy 392.009909 10.088106) (xy 392.025665 10.172396) (xy 392.049132 10.254872)
			(xy 392.080108 10.334831) (xy 392.11833 10.411591) (xy 392.163471 10.484497) (xy 392.215147 10.552926)
			(xy 392.272916 10.616296) (xy 392.336286 10.674065) (xy 392.404715 10.725741) (xy 392.477621 10.770882)
			(xy 392.554381 10.809104) (xy 392.63434 10.84008) (xy 392.716816 10.863547) (xy 392.801106 10.879303)
			(xy 392.886489 10.887215) (xy 392.972239 10.887215) (xy 393.057622 10.879303) (xy 393.141912 10.863547)
			(xy 393.224388 10.84008) (xy 393.304347 10.809104) (xy 393.381107 10.770882) (xy 393.454013 10.725741)
			(xy 393.522442 10.674065) (xy 393.585812 10.616296) (xy 393.643581 10.552926) (xy 393.695257 10.484497)
			(xy 393.740398 10.411591) (xy 393.77862 10.334831) (xy 393.809596 10.254872) (xy 393.833063 10.172396)
			(xy 393.848819 10.088106) (xy 393.856731 10.002723) (xy 393.857226 9.959848) (xy 393.856731 9.916973)
			(xy 436.390783 9.916973) (xy 436.390783 10.002723) (xy 436.398695 10.088106) (xy 436.414451 10.172396)
			(xy 436.437918 10.254872) (xy 436.468894 10.334831) (xy 436.507116 10.411591) (xy 436.552257 10.484497)
			(xy 436.603933 10.552926) (xy 436.661702 10.616296) (xy 436.725072 10.674065) (xy 436.793501 10.725741)
			(xy 436.866407 10.770882) (xy 436.943167 10.809104) (xy 437.023126 10.84008) (xy 437.105602 10.863547)
			(xy 437.189892 10.879303) (xy 437.275275 10.887215) (xy 437.361025 10.887215) (xy 437.446408 10.879303)
			(xy 437.530698 10.863547) (xy 437.613174 10.84008) (xy 437.693133 10.809104) (xy 437.769893 10.770882)
			(xy 437.842799 10.725741) (xy 437.911228 10.674065) (xy 437.974598 10.616296) (xy 438.032367 10.552926)
			(xy 438.084043 10.484497) (xy 438.129184 10.411591) (xy 438.167406 10.334831) (xy 438.198382 10.254872)
			(xy 438.221849 10.172396) (xy 438.237605 10.088106) (xy 438.245517 10.002723) (xy 438.246012 9.959848)
			(xy 438.245517 9.916973) (xy 442.740783 9.916973) (xy 442.740783 10.002723) (xy 442.748695 10.088106)
			(xy 442.764451 10.172396) (xy 442.787918 10.254872) (xy 442.818894 10.334831) (xy 442.857116 10.411591)
			(xy 442.902257 10.484497) (xy 442.953933 10.552926) (xy 443.011702 10.616296) (xy 443.075072 10.674065)
			(xy 443.143501 10.725741) (xy 443.216407 10.770882) (xy 443.293167 10.809104) (xy 443.373126 10.84008)
			(xy 443.455602 10.863547) (xy 443.539892 10.879303) (xy 443.625275 10.887215) (xy 443.711025 10.887215)
			(xy 443.796408 10.879303) (xy 443.880698 10.863547) (xy 443.963174 10.84008) (xy 444.043133 10.809104)
			(xy 444.119893 10.770882) (xy 444.192799 10.725741) (xy 444.261228 10.674065) (xy 444.324598 10.616296)
			(xy 444.382367 10.552926) (xy 444.434043 10.484497) (xy 444.479184 10.411591) (xy 444.517406 10.334831)
			(xy 444.548382 10.254872) (xy 444.571849 10.172396) (xy 444.587605 10.088106) (xy 444.595517 10.002723)
			(xy 444.596012 9.959848) (xy 444.595517 9.916973) (xy 444.587605 9.83159) (xy 444.571849 9.7473)
			(xy 444.548382 9.664824) (xy 444.517406 9.584865) (xy 444.479184 9.508105) (xy 444.434043 9.435199)
			(xy 444.382367 9.36677) (xy 444.324598 9.3034) (xy 444.261228 9.245631) (xy 444.192799 9.193955)
			(xy 444.119893 9.148814) (xy 444.043133 9.110592) (xy 443.963174 9.079616) (xy 443.880698 9.056149)
			(xy 443.796408 9.040393) (xy 443.711025 9.032481) (xy 443.625275 9.032481) (xy 443.539892 9.040393)
			(xy 443.455602 9.056149) (xy 443.373126 9.079616) (xy 443.293167 9.110592) (xy 443.216407 9.148814)
			(xy 443.143501 9.193955) (xy 443.075072 9.245631) (xy 443.011702 9.3034) (xy 442.953933 9.36677)
			(xy 442.902257 9.435199) (xy 442.857116 9.508105) (xy 442.818894 9.584865) (xy 442.787918 9.664824)
			(xy 442.764451 9.7473) (xy 442.748695 9.83159) (xy 442.740783 9.916973) (xy 438.245517 9.916973)
			(xy 438.237605 9.83159) (xy 438.221849 9.7473) (xy 438.198382 9.664824) (xy 438.167406 9.584865)
			(xy 438.129184 9.508105) (xy 438.084043 9.435199) (xy 438.032367 9.36677) (xy 437.974598 9.3034)
			(xy 437.911228 9.245631) (xy 437.842799 9.193955) (xy 437.769893 9.148814) (xy 437.693133 9.110592)
			(xy 437.613174 9.079616) (xy 437.530698 9.056149) (xy 437.446408 9.040393) (xy 437.361025 9.032481)
			(xy 437.275275 9.032481) (xy 437.189892 9.040393) (xy 437.105602 9.056149) (xy 437.023126 9.079616)
			(xy 436.943167 9.110592) (xy 436.866407 9.148814) (xy 436.793501 9.193955) (xy 436.725072 9.245631)
			(xy 436.661702 9.3034) (xy 436.603933 9.36677) (xy 436.552257 9.435199) (xy 436.507116 9.508105)
			(xy 436.468894 9.584865) (xy 436.437918 9.664824) (xy 436.414451 9.7473) (xy 436.398695 9.83159)
			(xy 436.390783 9.916973) (xy 393.856731 9.916973) (xy 393.848819 9.83159) (xy 393.833063 9.7473)
			(xy 393.809596 9.664824) (xy 393.77862 9.584865) (xy 393.740398 9.508105) (xy 393.695257 9.435199)
			(xy 393.643581 9.36677) (xy 393.585812 9.3034) (xy 393.522442 9.245631) (xy 393.454013 9.193955)
			(xy 393.381107 9.148814) (xy 393.304347 9.110592) (xy 393.224388 9.079616) (xy 393.141912 9.056149)
			(xy 393.057622 9.040393) (xy 392.972239 9.032481) (xy 392.886489 9.032481) (xy 392.801106 9.040393)
			(xy 392.716816 9.056149) (xy 392.63434 9.079616) (xy 392.554381 9.110592) (xy 392.477621 9.148814)
			(xy 392.404715 9.193955) (xy 392.336286 9.245631) (xy 392.272916 9.3034) (xy 392.215147 9.36677)
			(xy 392.163471 9.435199) (xy 392.11833 9.508105) (xy 392.080108 9.584865) (xy 392.049132 9.664824)
			(xy 392.025665 9.7473) (xy 392.009909 9.83159) (xy 392.001997 9.916973) (xy 387.506731 9.916973)
			(xy 387.498819 9.83159) (xy 387.483063 9.7473) (xy 387.459596 9.664824) (xy 387.42862 9.584865) (xy 387.390398 9.508105)
			(xy 387.345257 9.435199) (xy 387.293581 9.36677) (xy 387.235812 9.3034) (xy 387.172442 9.245631)
			(xy 387.104013 9.193955) (xy 387.031107 9.148814) (xy 386.954347 9.110592) (xy 386.874388 9.079616)
			(xy 386.791912 9.056149) (xy 386.707622 9.040393) (xy 386.622239 9.032481) (xy 386.536489 9.032481)
			(xy 386.451106 9.040393) (xy 386.366816 9.056149) (xy 386.28434 9.079616) (xy 386.204381 9.110592)
			(xy 386.127621 9.148814) (xy 386.054715 9.193955) (xy 385.986286 9.245631) (xy 385.922916 9.3034)
			(xy 385.865147 9.36677) (xy 385.813471 9.435199) (xy 385.76833 9.508105) (xy 385.730108 9.584865)
			(xy 385.699132 9.664824) (xy 385.675665 9.7473) (xy 385.659909 9.83159) (xy 385.651997 9.916973)
			(xy 0.509016 9.916973) (xy 0.509016 7.335466) (xy 2.904225 7.335466) (xy 2.904225 7.464606) (xy 2.912175 7.593501)
			(xy 2.928045 7.721661) (xy 2.951774 7.848602) (xy 2.983273 7.973841) (xy 3.022422 8.096904) (xy 3.069073 8.217323)
			(xy 3.123048 8.334642) (xy 3.184143 8.448416) (xy 3.252126 8.558213) (xy 3.32674 8.663616) (xy 3.407701 8.764226)
			(xy 3.494701 8.859661) (xy 3.587412 8.94956) (xy 3.685482 9.033581) (xy 3.788537 9.111405) (xy 3.896188 9.182737)
			(xy 4.008027 9.247307) (xy 4.123628 9.304869) (xy 4.242553 9.355206) (xy 4.364352 9.398126) (xy 4.488562 9.433467)
			(xy 4.614711 9.461094) (xy 4.742323 9.480903) (xy 4.870912 9.492819) (xy 4.99999 9.496796) (xy 5.129068 9.492819)
			(xy 5.257657 9.480903) (xy 5.385269 9.461094) (xy 5.511418 9.433467) (xy 5.635628 9.398126) (xy 5.757427 9.355206)
			(xy 5.876352 9.304869) (xy 5.991953 9.247307) (xy 6.103792 9.182737) (xy 6.211443 9.111405) (xy 6.314498 9.033581)
			(xy 6.412568 8.94956) (xy 6.505279 8.859661) (xy 6.51416 8.849919) (xy 208.661241 8.849919) (xy 208.661241 8.935669)
			(xy 208.669153 9.021052) (xy 208.684909 9.105342) (xy 208.708376 9.187818) (xy 208.739352 9.267777)
			(xy 208.777574 9.344537) (xy 208.822715 9.417443) (xy 208.874391 9.485872) (xy 208.93216 9.549242)
			(xy 208.99553 9.607011) (xy 209.063959 9.658687) (xy 209.136865 9.703828) (xy 209.213625 9.74205)
			(xy 209.293584 9.773026) (xy 209.37606 9.796493) (xy 209.46035 9.812249) (xy 209.545733 9.820161)
			(xy 209.631483 9.820161) (xy 209.716866 9.812249) (xy 209.801156 9.796493) (xy 209.883632 9.773026)
			(xy 209.963591 9.74205) (xy 210.040351 9.703828) (xy 210.113257 9.658687) (xy 210.181686 9.607011)
			(xy 210.245056 9.549242) (xy 210.302825 9.485872) (xy 210.354501 9.417443) (xy 210.399642 9.344537)
			(xy 210.437864 9.267777) (xy 210.46884 9.187818) (xy 210.492307 9.105342) (xy 210.508063 9.021052)
			(xy 210.515975 8.935669) (xy 210.51647 8.892794) (xy 210.515975 8.849919) (xy 215.011241 8.849919)
			(xy 215.011241 8.935669) (xy 215.019153 9.021052) (xy 215.034909 9.105342) (xy 215.058376 9.187818)
			(xy 215.089352 9.267777) (xy 215.127574 9.344537) (xy 215.172715 9.417443) (xy 215.224391 9.485872)
			(xy 215.28216 9.549242) (xy 215.34553 9.607011) (xy 215.413959 9.658687) (xy 215.486865 9.703828)
			(xy 215.563625 9.74205) (xy 215.643584 9.773026) (xy 215.72606 9.796493) (xy 215.81035 9.812249)
			(xy 215.895733 9.820161) (xy 215.981483 9.820161) (xy 216.066866 9.812249) (xy 216.151156 9.796493)
			(xy 216.233632 9.773026) (xy 216.313591 9.74205) (xy 216.390351 9.703828) (xy 216.463257 9.658687)
			(xy 216.531686 9.607011) (xy 216.595056 9.549242) (xy 216.652825 9.485872) (xy 216.704501 9.417443)
			(xy 216.749642 9.344537) (xy 216.787864 9.267777) (xy 216.81884 9.187818) (xy 216.842307 9.105342)
			(xy 216.858063 9.021052) (xy 216.865975 8.935669) (xy 216.86647 8.892794) (xy 216.865975 8.849919)
			(xy 296.143921 8.849919) (xy 296.143921 8.935669) (xy 296.151833 9.021052) (xy 296.167589 9.105342)
			(xy 296.191056 9.187818) (xy 296.222032 9.267777) (xy 296.260254 9.344537) (xy 296.305395 9.417443)
			(xy 296.357071 9.485872) (xy 296.41484 9.549242) (xy 296.47821 9.607011) (xy 296.546639 9.658687)
			(xy 296.619545 9.703828) (xy 296.696305 9.74205) (xy 296.776264 9.773026) (xy 296.85874 9.796493)
			(xy 296.94303 9.812249) (xy 297.028413 9.820161) (xy 297.114163 9.820161) (xy 297.199546 9.812249)
			(xy 297.283836 9.796493) (xy 297.366312 9.773026) (xy 297.446271 9.74205) (xy 297.523031 9.703828)
			(xy 297.595937 9.658687) (xy 297.664366 9.607011) (xy 297.727736 9.549242) (xy 297.785505 9.485872)
			(xy 297.837181 9.417443) (xy 297.882322 9.344537) (xy 297.920544 9.267777) (xy 297.95152 9.187818)
			(xy 297.974987 9.105342) (xy 297.990743 9.021052) (xy 297.998655 8.935669) (xy 297.99915 8.892794)
			(xy 297.998655 8.849919) (xy 302.493921 8.849919) (xy 302.493921 8.935669) (xy 302.501833 9.021052)
			(xy 302.517589 9.105342) (xy 302.541056 9.187818) (xy 302.572032 9.267777) (xy 302.610254 9.344537)
			(xy 302.655395 9.417443) (xy 302.707071 9.485872) (xy 302.76484 9.549242) (xy 302.82821 9.607011)
			(xy 302.896639 9.658687) (xy 302.969545 9.703828) (xy 303.046305 9.74205) (xy 303.126264 9.773026)
			(xy 303.20874 9.796493) (xy 303.29303 9.812249) (xy 303.378413 9.820161) (xy 303.464163 9.820161)
			(xy 303.549546 9.812249) (xy 303.633836 9.796493) (xy 303.716312 9.773026) (xy 303.796271 9.74205)
			(xy 303.873031 9.703828) (xy 303.945937 9.658687) (xy 304.014366 9.607011) (xy 304.077736 9.549242)
			(xy 304.135505 9.485872) (xy 304.187181 9.417443) (xy 304.232322 9.344537) (xy 304.270544 9.267777)
			(xy 304.30152 9.187818) (xy 304.324987 9.105342) (xy 304.340743 9.021052) (xy 304.348655 8.935669)
			(xy 304.34915 8.892794) (xy 304.348655 8.849919) (xy 311.155321 8.849919) (xy 311.155321 8.935669)
			(xy 311.163233 9.021052) (xy 311.178989 9.105342) (xy 311.202456 9.187818) (xy 311.233432 9.267777)
			(xy 311.271654 9.344537) (xy 311.316795 9.417443) (xy 311.368471 9.485872) (xy 311.42624 9.549242)
			(xy 311.48961 9.607011) (xy 311.558039 9.658687) (xy 311.630945 9.703828) (xy 311.707705 9.74205)
			(xy 311.787664 9.773026) (xy 311.87014 9.796493) (xy 311.95443 9.812249) (xy 312.039813 9.820161)
			(xy 312.125563 9.820161) (xy 312.210946 9.812249) (xy 312.295236 9.796493) (xy 312.377712 9.773026)
			(xy 312.457671 9.74205) (xy 312.534431 9.703828) (xy 312.607337 9.658687) (xy 312.675766 9.607011)
			(xy 312.739136 9.549242) (xy 312.796905 9.485872) (xy 312.848581 9.417443) (xy 312.893722 9.344537)
			(xy 312.931944 9.267777) (xy 312.96292 9.187818) (xy 312.986387 9.105342) (xy 313.002143 9.021052)
			(xy 313.010055 8.935669) (xy 313.01055 8.892794) (xy 313.010055 8.849919) (xy 317.505321 8.849919)
			(xy 317.505321 8.935669) (xy 317.513233 9.021052) (xy 317.528989 9.105342) (xy 317.552456 9.187818)
			(xy 317.583432 9.267777) (xy 317.621654 9.344537) (xy 317.666795 9.417443) (xy 317.718471 9.485872)
			(xy 317.77624 9.549242) (xy 317.83961 9.607011) (xy 317.908039 9.658687) (xy 317.980945 9.703828)
			(xy 318.057705 9.74205) (xy 318.137664 9.773026) (xy 318.22014 9.796493) (xy 318.30443 9.812249)
			(xy 318.389813 9.820161) (xy 318.475563 9.820161) (xy 318.560946 9.812249) (xy 318.645236 9.796493)
			(xy 318.727712 9.773026) (xy 318.807671 9.74205) (xy 318.884431 9.703828) (xy 318.957337 9.658687)
			(xy 319.025766 9.607011) (xy 319.089136 9.549242) (xy 319.146905 9.485872) (xy 319.198581 9.417443)
			(xy 319.243722 9.344537) (xy 319.281944 9.267777) (xy 319.31292 9.187818) (xy 319.336387 9.105342)
			(xy 319.352143 9.021052) (xy 319.360055 8.935669) (xy 319.36055 8.892794) (xy 319.360055 8.849919)
			(xy 361.894107 8.849919) (xy 361.894107 8.935669) (xy 361.902019 9.021052) (xy 361.917775 9.105342)
			(xy 361.941242 9.187818) (xy 361.972218 9.267777) (xy 362.01044 9.344537) (xy 362.055581 9.417443)
			(xy 362.107257 9.485872) (xy 362.165026 9.549242) (xy 362.228396 9.607011) (xy 362.296825 9.658687)
			(xy 362.369731 9.703828) (xy 362.446491 9.74205) (xy 362.52645 9.773026) (xy 362.608926 9.796493)
			(xy 362.693216 9.812249) (xy 362.778599 9.820161) (xy 362.864349 9.820161) (xy 362.949732 9.812249)
			(xy 363.034022 9.796493) (xy 363.116498 9.773026) (xy 363.196457 9.74205) (xy 363.273217 9.703828)
			(xy 363.346123 9.658687) (xy 363.414552 9.607011) (xy 363.477922 9.549242) (xy 363.535691 9.485872)
			(xy 363.587367 9.417443) (xy 363.632508 9.344537) (xy 363.67073 9.267777) (xy 363.701706 9.187818)
			(xy 363.725173 9.105342) (xy 363.740929 9.021052) (xy 363.748841 8.935669) (xy 363.749336 8.892794)
			(xy 363.748841 8.849919) (xy 368.244107 8.849919) (xy 368.244107 8.935669) (xy 368.252019 9.021052)
			(xy 368.267775 9.105342) (xy 368.291242 9.187818) (xy 368.322218 9.267777) (xy 368.36044 9.344537)
			(xy 368.405581 9.417443) (xy 368.457257 9.485872) (xy 368.515026 9.549242) (xy 368.578396 9.607011)
			(xy 368.646825 9.658687) (xy 368.719731 9.703828) (xy 368.796491 9.74205) (xy 368.87645 9.773026)
			(xy 368.958926 9.796493) (xy 369.043216 9.812249) (xy 369.128599 9.820161) (xy 369.214349 9.820161)
			(xy 369.299732 9.812249) (xy 369.384022 9.796493) (xy 369.466498 9.773026) (xy 369.546457 9.74205)
			(xy 369.623217 9.703828) (xy 369.696123 9.658687) (xy 369.764552 9.607011) (xy 369.827922 9.549242)
			(xy 369.885691 9.485872) (xy 369.937367 9.417443) (xy 369.982508 9.344537) (xy 370.02073 9.267777)
			(xy 370.051706 9.187818) (xy 370.075173 9.105342) (xy 370.090929 9.021052) (xy 370.098841 8.935669)
			(xy 370.099336 8.892794) (xy 370.098841 8.849919) (xy 370.090929 8.764536) (xy 370.075173 8.680246)
			(xy 370.051706 8.59777) (xy 370.02073 8.517811) (xy 369.982508 8.441051) (xy 369.937367 8.368145)
			(xy 369.885691 8.299716) (xy 369.827922 8.236346) (xy 369.764552 8.178577) (xy 369.696123 8.126901)
			(xy 369.623217 8.08176) (xy 369.546457 8.043538) (xy 369.466498 8.012562) (xy 369.384022 7.989095)
			(xy 369.299732 7.973339) (xy 369.214349 7.965427) (xy 369.128599 7.965427) (xy 369.043216 7.973339)
			(xy 368.958926 7.989095) (xy 368.87645 8.012562) (xy 368.796491 8.043538) (xy 368.719731 8.08176)
			(xy 368.646825 8.126901) (xy 368.578396 8.178577) (xy 368.515026 8.236346) (xy 368.457257 8.299716)
			(xy 368.405581 8.368145) (xy 368.36044 8.441051) (xy 368.322218 8.517811) (xy 368.291242 8.59777)
			(xy 368.267775 8.680246) (xy 368.252019 8.764536) (xy 368.244107 8.849919) (xy 363.748841 8.849919)
			(xy 363.740929 8.764536) (xy 363.725173 8.680246) (xy 363.701706 8.59777) (xy 363.67073 8.517811)
			(xy 363.632508 8.441051) (xy 363.587367 8.368145) (xy 363.535691 8.299716) (xy 363.477922 8.236346)
			(xy 363.414552 8.178577) (xy 363.346123 8.126901) (xy 363.273217 8.08176) (xy 363.196457 8.043538)
			(xy 363.116498 8.012562) (xy 363.034022 7.989095) (xy 362.949732 7.973339) (xy 362.864349 7.965427)
			(xy 362.778599 7.965427) (xy 362.693216 7.973339) (xy 362.608926 7.989095) (xy 362.52645 8.012562)
			(xy 362.446491 8.043538) (xy 362.369731 8.08176) (xy 362.296825 8.126901) (xy 362.228396 8.178577)
			(xy 362.165026 8.236346) (xy 362.107257 8.299716) (xy 362.055581 8.368145) (xy 362.01044 8.441051)
			(xy 361.972218 8.517811) (xy 361.941242 8.59777) (xy 361.917775 8.680246) (xy 361.902019 8.764536)
			(xy 361.894107 8.849919) (xy 319.360055 8.849919) (xy 319.352143 8.764536) (xy 319.336387 8.680246)
			(xy 319.31292 8.59777) (xy 319.281944 8.517811) (xy 319.243722 8.441051) (xy 319.198581 8.368145)
			(xy 319.146905 8.299716) (xy 319.089136 8.236346) (xy 319.025766 8.178577) (xy 318.957337 8.126901)
			(xy 318.884431 8.08176) (xy 318.807671 8.043538) (xy 318.727712 8.012562) (xy 318.645236 7.989095)
			(xy 318.560946 7.973339) (xy 318.475563 7.965427) (xy 318.389813 7.965427) (xy 318.30443 7.973339)
			(xy 318.22014 7.989095) (xy 318.137664 8.012562) (xy 318.057705 8.043538) (xy 317.980945 8.08176)
			(xy 317.908039 8.126901) (xy 317.83961 8.178577) (xy 317.77624 8.236346) (xy 317.718471 8.299716)
			(xy 317.666795 8.368145) (xy 317.621654 8.441051) (xy 317.583432 8.517811) (xy 317.552456 8.59777)
			(xy 317.528989 8.680246) (xy 317.513233 8.764536) (xy 317.505321 8.849919) (xy 313.010055 8.849919)
			(xy 313.002143 8.764536) (xy 312.986387 8.680246) (xy 312.96292 8.59777) (xy 312.931944 8.517811)
			(xy 312.893722 8.441051) (xy 312.848581 8.368145) (xy 312.796905 8.299716) (xy 312.739136 8.236346)
			(xy 312.675766 8.178577) (xy 312.607337 8.126901) (xy 312.534431 8.08176) (xy 312.457671 8.043538)
			(xy 312.377712 8.012562) (xy 312.295236 7.989095) (xy 312.210946 7.973339) (xy 312.125563 7.965427)
			(xy 312.039813 7.965427) (xy 311.95443 7.973339) (xy 311.87014 7.989095) (xy 311.787664 8.012562)
			(xy 311.707705 8.043538) (xy 311.630945 8.08176) (xy 311.558039 8.126901) (xy 311.48961 8.178577)
			(xy 311.42624 8.236346) (xy 311.368471 8.299716) (xy 311.316795 8.368145) (xy 311.271654 8.441051)
			(xy 311.233432 8.517811) (xy 311.202456 8.59777) (xy 311.178989 8.680246) (xy 311.163233 8.764536)
			(xy 311.155321 8.849919) (xy 304.348655 8.849919) (xy 304.340743 8.764536) (xy 304.324987 8.680246)
			(xy 304.30152 8.59777) (xy 304.270544 8.517811) (xy 304.232322 8.441051) (xy 304.187181 8.368145)
			(xy 304.135505 8.299716) (xy 304.077736 8.236346) (xy 304.014366 8.178577) (xy 303.945937 8.126901)
			(xy 303.873031 8.08176) (xy 303.796271 8.043538) (xy 303.716312 8.012562) (xy 303.633836 7.989095)
			(xy 303.549546 7.973339) (xy 303.464163 7.965427) (xy 303.378413 7.965427) (xy 303.29303 7.973339)
			(xy 303.20874 7.989095) (xy 303.126264 8.012562) (xy 303.046305 8.043538) (xy 302.969545 8.08176)
			(xy 302.896639 8.126901) (xy 302.82821 8.178577) (xy 302.76484 8.236346) (xy 302.707071 8.299716)
			(xy 302.655395 8.368145) (xy 302.610254 8.441051) (xy 302.572032 8.517811) (xy 302.541056 8.59777)
			(xy 302.517589 8.680246) (xy 302.501833 8.764536) (xy 302.493921 8.849919) (xy 297.998655 8.849919)
			(xy 297.990743 8.764536) (xy 297.974987 8.680246) (xy 297.95152 8.59777) (xy 297.920544 8.517811)
			(xy 297.882322 8.441051) (xy 297.837181 8.368145) (xy 297.785505 8.299716) (xy 297.727736 8.236346)
			(xy 297.664366 8.178577) (xy 297.595937 8.126901) (xy 297.523031 8.08176) (xy 297.446271 8.043538)
			(xy 297.366312 8.012562) (xy 297.283836 7.989095) (xy 297.199546 7.973339) (xy 297.114163 7.965427)
			(xy 297.028413 7.965427) (xy 296.94303 7.973339) (xy 296.85874 7.989095) (xy 296.776264 8.012562)
			(xy 296.696305 8.043538) (xy 296.619545 8.08176) (xy 296.546639 8.126901) (xy 296.47821 8.178577)
			(xy 296.41484 8.236346) (xy 296.357071 8.299716) (xy 296.305395 8.368145) (xy 296.260254 8.441051)
			(xy 296.222032 8.517811) (xy 296.191056 8.59777) (xy 296.167589 8.680246) (xy 296.151833 8.764536)
			(xy 296.143921 8.849919) (xy 216.865975 8.849919) (xy 216.858063 8.764536) (xy 216.842307 8.680246)
			(xy 216.81884 8.59777) (xy 216.787864 8.517811) (xy 216.749642 8.441051) (xy 216.704501 8.368145)
			(xy 216.652825 8.299716) (xy 216.595056 8.236346) (xy 216.531686 8.178577) (xy 216.463257 8.126901)
			(xy 216.390351 8.08176) (xy 216.313591 8.043538) (xy 216.233632 8.012562) (xy 216.151156 7.989095)
			(xy 216.066866 7.973339) (xy 215.981483 7.965427) (xy 215.895733 7.965427) (xy 215.81035 7.973339)
			(xy 215.72606 7.989095) (xy 215.643584 8.012562) (xy 215.563625 8.043538) (xy 215.486865 8.08176)
			(xy 215.413959 8.126901) (xy 215.34553 8.178577) (xy 215.28216 8.236346) (xy 215.224391 8.299716)
			(xy 215.172715 8.368145) (xy 215.127574 8.441051) (xy 215.089352 8.517811) (xy 215.058376 8.59777)
			(xy 215.034909 8.680246) (xy 215.019153 8.764536) (xy 215.011241 8.849919) (xy 210.515975 8.849919)
			(xy 210.508063 8.764536) (xy 210.492307 8.680246) (xy 210.46884 8.59777) (xy 210.437864 8.517811)
			(xy 210.399642 8.441051) (xy 210.354501 8.368145) (xy 210.302825 8.299716) (xy 210.245056 8.236346)
			(xy 210.181686 8.178577) (xy 210.113257 8.126901) (xy 210.040351 8.08176) (xy 209.963591 8.043538)
			(xy 209.883632 8.012562) (xy 209.801156 7.989095) (xy 209.716866 7.973339) (xy 209.631483 7.965427)
			(xy 209.545733 7.965427) (xy 209.46035 7.973339) (xy 209.37606 7.989095) (xy 209.293584 8.012562)
			(xy 209.213625 8.043538) (xy 209.136865 8.08176) (xy 209.063959 8.126901) (xy 208.99553 8.178577)
			(xy 208.93216 8.236346) (xy 208.874391 8.299716) (xy 208.822715 8.368145) (xy 208.777574 8.441051)
			(xy 208.739352 8.517811) (xy 208.708376 8.59777) (xy 208.684909 8.680246) (xy 208.669153 8.764536)
			(xy 208.661241 8.849919) (xy 6.51416 8.849919) (xy 6.592279 8.764226) (xy 6.67324 8.663616) (xy 6.747854 8.558213)
			(xy 6.815837 8.448416) (xy 6.876932 8.334642) (xy 6.930907 8.217323) (xy 6.977558 8.096904) (xy 7.016707 7.973841)
			(xy 7.048206 7.848602) (xy 7.071935 7.721661) (xy 7.087805 7.593501) (xy 7.095755 7.464606) (xy 7.096252 7.400036)
			(xy 7.095755 7.335466) (xy 7.092973 7.290359) (xy 93.985575 7.290359) (xy 93.985575 7.376109) (xy 93.993487 7.461492)
			(xy 94.009243 7.545782) (xy 94.03271 7.628258) (xy 94.063686 7.708217) (xy 94.101908 7.784977) (xy 94.147049 7.857883)
			(xy 94.198725 7.926312) (xy 94.256494 7.989682) (xy 94.319864 8.047451) (xy 94.388293 8.099127) (xy 94.461199 8.144268)
			(xy 94.537959 8.18249) (xy 94.617918 8.213466) (xy 94.700394 8.236933) (xy 94.784684 8.252689) (xy 94.870067 8.260601)
			(xy 94.955817 8.260601) (xy 95.0412 8.252689) (xy 95.12549 8.236933) (xy 95.207966 8.213466) (xy 95.287925 8.18249)
			(xy 95.364685 8.144268) (xy 95.437591 8.099127) (xy 95.50602 8.047451) (xy 95.56939 7.989682) (xy 95.627159 7.926312)
			(xy 95.678835 7.857883) (xy 95.723976 7.784977) (xy 95.762198 7.708217) (xy 95.793174 7.628258) (xy 95.816641 7.545782)
			(xy 95.832397 7.461492) (xy 95.840309 7.376109) (xy 95.840804 7.333234) (xy 95.840309 7.290359) (xy 100.335575 7.290359)
			(xy 100.335575 7.376109) (xy 100.343487 7.461492) (xy 100.359243 7.545782) (xy 100.38271 7.628258)
			(xy 100.413686 7.708217) (xy 100.451908 7.784977) (xy 100.497049 7.857883) (xy 100.548725 7.926312)
			(xy 100.606494 7.989682) (xy 100.669864 8.047451) (xy 100.738293 8.099127) (xy 100.811199 8.144268)
			(xy 100.887959 8.18249) (xy 100.967918 8.213466) (xy 101.050394 8.236933) (xy 101.134684 8.252689)
			(xy 101.220067 8.260601) (xy 101.305817 8.260601) (xy 101.3912 8.252689) (xy 101.47549 8.236933)
			(xy 101.557966 8.213466) (xy 101.637925 8.18249) (xy 101.714685 8.144268) (xy 101.787591 8.099127)
			(xy 101.85602 8.047451) (xy 101.91939 7.989682) (xy 101.977159 7.926312) (xy 102.028835 7.857883)
			(xy 102.073976 7.784977) (xy 102.112198 7.708217) (xy 102.143174 7.628258) (xy 102.166641 7.545782)
			(xy 102.182397 7.461492) (xy 102.190309 7.376109) (xy 102.190804 7.333234) (xy 102.190309 7.290359)
			(xy 181.468255 7.290359) (xy 181.468255 7.376109) (xy 181.476167 7.461492) (xy 181.491923 7.545782)
			(xy 181.51539 7.628258) (xy 181.546366 7.708217) (xy 181.584588 7.784977) (xy 181.629729 7.857883)
			(xy 181.681405 7.926312) (xy 181.739174 7.989682) (xy 181.802544 8.047451) (xy 181.870973 8.099127)
			(xy 181.943879 8.144268) (xy 182.020639 8.18249) (xy 182.100598 8.213466) (xy 182.183074 8.236933)
			(xy 182.267364 8.252689) (xy 182.352747 8.260601) (xy 182.438497 8.260601) (xy 182.52388 8.252689)
			(xy 182.60817 8.236933) (xy 182.690646 8.213466) (xy 182.770605 8.18249) (xy 182.847365 8.144268)
			(xy 182.920271 8.099127) (xy 182.9887 8.047451) (xy 183.05207 7.989682) (xy 183.109839 7.926312)
			(xy 183.161515 7.857883) (xy 183.206656 7.784977) (xy 183.244878 7.708217) (xy 183.275854 7.628258)
			(xy 183.299321 7.545782) (xy 183.315077 7.461492) (xy 183.322989 7.376109) (xy 183.323484 7.333234)
			(xy 183.322989 7.290359) (xy 187.818255 7.290359) (xy 187.818255 7.376109) (xy 187.826167 7.461492)
			(xy 187.841923 7.545782) (xy 187.86539 7.628258) (xy 187.896366 7.708217) (xy 187.934588 7.784977)
			(xy 187.979729 7.857883) (xy 188.031405 7.926312) (xy 188.089174 7.989682) (xy 188.152544 8.047451)
			(xy 188.220973 8.099127) (xy 188.293879 8.144268) (xy 188.370639 8.18249) (xy 188.450598 8.213466)
			(xy 188.533074 8.236933) (xy 188.617364 8.252689) (xy 188.702747 8.260601) (xy 188.788497 8.260601)
			(xy 188.87388 8.252689) (xy 188.95817 8.236933) (xy 189.040646 8.213466) (xy 189.120605 8.18249)
			(xy 189.197365 8.144268) (xy 189.270271 8.099127) (xy 189.3387 8.047451) (xy 189.40207 7.989682)
			(xy 189.459839 7.926312) (xy 189.511515 7.857883) (xy 189.556656 7.784977) (xy 189.594878 7.708217)
			(xy 189.625854 7.628258) (xy 189.649321 7.545782) (xy 189.665077 7.461492) (xy 189.672989 7.376109)
			(xy 189.673484 7.333234) (xy 189.672989 7.290359) (xy 189.665077 7.204976) (xy 189.649321 7.120686)
			(xy 189.625854 7.03821) (xy 189.594878 6.958251) (xy 189.556656 6.881491) (xy 189.511515 6.808585)
			(xy 189.459839 6.740156) (xy 189.40207 6.676786) (xy 189.3387 6.619017) (xy 189.270271 6.567341)
			(xy 189.197365 6.5222) (xy 189.120605 6.483978) (xy 189.040646 6.453002) (xy 188.95817 6.429535)
			(xy 188.87388 6.413779) (xy 188.788497 6.405867) (xy 188.702747 6.405867) (xy 188.617364 6.413779)
			(xy 188.533074 6.429535) (xy 188.450598 6.453002) (xy 188.370639 6.483978) (xy 188.293879 6.5222)
			(xy 188.220973 6.567341) (xy 188.152544 6.619017) (xy 188.089174 6.676786) (xy 188.031405 6.740156)
			(xy 187.979729 6.808585) (xy 187.934588 6.881491) (xy 187.896366 6.958251) (xy 187.86539 7.03821)
			(xy 187.841923 7.120686) (xy 187.826167 7.204976) (xy 187.818255 7.290359) (xy 183.322989 7.290359)
			(xy 183.315077 7.204976) (xy 183.299321 7.120686) (xy 183.275854 7.03821) (xy 183.244878 6.958251)
			(xy 183.206656 6.881491) (xy 183.161515 6.808585) (xy 183.109839 6.740156) (xy 183.05207 6.676786)
			(xy 182.9887 6.619017) (xy 182.920271 6.567341) (xy 182.847365 6.5222) (xy 182.770605 6.483978) (xy 182.690646 6.453002)
			(xy 182.60817 6.429535) (xy 182.52388 6.413779) (xy 182.438497 6.405867) (xy 182.352747 6.405867)
			(xy 182.267364 6.413779) (xy 182.183074 6.429535) (xy 182.100598 6.453002) (xy 182.020639 6.483978)
			(xy 181.943879 6.5222) (xy 181.870973 6.567341) (xy 181.802544 6.619017) (xy 181.739174 6.676786)
			(xy 181.681405 6.740156) (xy 181.629729 6.808585) (xy 181.584588 6.881491) (xy 181.546366 6.958251)
			(xy 181.51539 7.03821) (xy 181.491923 7.120686) (xy 181.476167 7.204976) (xy 181.468255 7.290359)
			(xy 102.190309 7.290359) (xy 102.182397 7.204976) (xy 102.166641 7.120686) (xy 102.143174 7.03821)
			(xy 102.112198 6.958251) (xy 102.073976 6.881491) (xy 102.028835 6.808585) (xy 101.977159 6.740156)
			(xy 101.91939 6.676786) (xy 101.85602 6.619017) (xy 101.787591 6.567341) (xy 101.714685 6.5222) (xy 101.637925 6.483978)
			(xy 101.557966 6.453002) (xy 101.47549 6.429535) (xy 101.3912 6.413779) (xy 101.305817 6.405867)
			(xy 101.220067 6.405867) (xy 101.134684 6.413779) (xy 101.050394 6.429535) (xy 100.967918 6.453002)
			(xy 100.887959 6.483978) (xy 100.811199 6.5222) (xy 100.738293 6.567341) (xy 100.669864 6.619017)
			(xy 100.606494 6.676786) (xy 100.548725 6.740156) (xy 100.497049 6.808585) (xy 100.451908 6.881491)
			(xy 100.413686 6.958251) (xy 100.38271 7.03821) (xy 100.359243 7.120686) (xy 100.343487 7.204976)
			(xy 100.335575 7.290359) (xy 95.840309 7.290359) (xy 95.832397 7.204976) (xy 95.816641 7.120686)
			(xy 95.793174 7.03821) (xy 95.762198 6.958251) (xy 95.723976 6.881491) (xy 95.678835 6.808585) (xy 95.627159 6.740156)
			(xy 95.56939 6.676786) (xy 95.50602 6.619017) (xy 95.437591 6.567341) (xy 95.364685 6.5222) (xy 95.287925 6.483978)
			(xy 95.207966 6.453002) (xy 95.12549 6.429535) (xy 95.0412 6.413779) (xy 94.955817 6.405867) (xy 94.870067 6.405867)
			(xy 94.784684 6.413779) (xy 94.700394 6.429535) (xy 94.617918 6.453002) (xy 94.537959 6.483978) (xy 94.461199 6.5222)
			(xy 94.388293 6.567341) (xy 94.319864 6.619017) (xy 94.256494 6.676786) (xy 94.198725 6.740156) (xy 94.147049 6.808585)
			(xy 94.101908 6.881491) (xy 94.063686 6.958251) (xy 94.03271 7.03821) (xy 94.009243 7.120686) (xy 93.993487 7.204976)
			(xy 93.985575 7.290359) (xy 7.092973 7.290359) (xy 7.087805 7.206571) (xy 7.071935 7.078411) (xy 7.048206 6.95147)
			(xy 7.016707 6.826231) (xy 6.977558 6.703168) (xy 6.930907 6.582749) (xy 6.876932 6.46543) (xy 6.815837 6.351656)
			(xy 6.747854 6.241859) (xy 6.67324 6.136456) (xy 6.592279 6.035846) (xy 6.505279 5.940411) (xy 6.412568 5.850512)
			(xy 6.314498 5.766491) (xy 6.211443 5.688667) (xy 6.103792 5.617335) (xy 5.991953 5.552765) (xy 5.876352 5.495203)
			(xy 5.757427 5.444866) (xy 5.635628 5.401946) (xy 5.511418 5.366605) (xy 5.385269 5.338978) (xy 5.257657 5.319169)
			(xy 5.129068 5.307253) (xy 4.99999 5.303277) (xy 4.870912 5.307253) (xy 4.742323 5.319169) (xy 4.614711 5.338978)
			(xy 4.488562 5.366605) (xy 4.364352 5.401946) (xy 4.242553 5.444866) (xy 4.123628 5.495203) (xy 4.008027 5.552765)
			(xy 3.896188 5.617335) (xy 3.788537 5.688667) (xy 3.685482 5.766491) (xy 3.587412 5.850512) (xy 3.494701 5.940411)
			(xy 3.407701 6.035846) (xy 3.32674 6.136456) (xy 3.252126 6.241859) (xy 3.184143 6.351656) (xy 3.123048 6.46543)
			(xy 3.069073 6.582749) (xy 3.022422 6.703168) (xy 2.983273 6.826231) (xy 2.951774 6.95147) (xy 2.928045 7.078411)
			(xy 2.912175 7.206571) (xy 2.904225 7.335466) (xy 0.509016 7.335466) (xy 0.509016 4.750359) (xy 93.985575 4.750359)
			(xy 93.985575 4.836109) (xy 93.993487 4.921492) (xy 94.009243 5.005782) (xy 94.03271 5.088258) (xy 94.063686 5.168217)
			(xy 94.101908 5.244977) (xy 94.147049 5.317883) (xy 94.198725 5.386312) (xy 94.256494 5.449682) (xy 94.319864 5.507451)
			(xy 94.388293 5.559127) (xy 94.461199 5.604268) (xy 94.537959 5.64249) (xy 94.617918 5.673466) (xy 94.700394 5.696933)
			(xy 94.784684 5.712689) (xy 94.870067 5.720601) (xy 94.955817 5.720601) (xy 95.0412 5.712689) (xy 95.12549 5.696933)
			(xy 95.207966 5.673466) (xy 95.287925 5.64249) (xy 95.308598 5.632196) (xy 98.842576 5.632196) (xy 98.842576 6.495796)
			(xy 98.84308 6.525332) (xy 98.851124 6.583854) (xy 98.867061 6.640736) (xy 98.890596 6.694918) (xy 98.921289 6.745391)
			(xy 98.958569 6.791214) (xy 99.001741 6.831534) (xy 99.050001 6.8656) (xy 99.102451 6.892777) (xy 99.158112 6.912559)
			(xy 99.215949 6.924578) (xy 99.274884 6.928609) (xy 99.333819 6.924578) (xy 99.391656 6.912559) (xy 99.447317 6.892777)
			(xy 99.499767 6.8656) (xy 99.548027 6.831534) (xy 99.591199 6.791214) (xy 99.628479 6.745391) (xy 99.659172 6.694918)
			(xy 99.682707 6.640736) (xy 99.698644 6.583854) (xy 99.706688 6.525332) (xy 99.707192 6.495796) (xy 99.707192 5.632196)
			(xy 99.706688 5.60266) (xy 99.698644 5.544138) (xy 99.682707 5.487256) (xy 99.659172 5.433074) (xy 99.628479 5.382601)
			(xy 99.591199 5.336778) (xy 99.548027 5.296458) (xy 99.499767 5.262392) (xy 99.447317 5.235215) (xy 99.391656 5.215433)
			(xy 99.333819 5.203414) (xy 99.274884 5.199383) (xy 99.215949 5.203414) (xy 99.158112 5.215433) (xy 99.102451 5.235215)
			(xy 99.050001 5.262392) (xy 99.001741 5.296458) (xy 98.958569 5.336778) (xy 98.921289 5.382601) (xy 98.890596 5.433074)
			(xy 98.867061 5.487256) (xy 98.851124 5.544138) (xy 98.84308 5.60266) (xy 98.842576 5.632196) (xy 95.308598 5.632196)
			(xy 95.364685 5.604268) (xy 95.437591 5.559127) (xy 95.50602 5.507451) (xy 95.56939 5.449682) (xy 95.627159 5.386312)
			(xy 95.678835 5.317883) (xy 95.723976 5.244977) (xy 95.762198 5.168217) (xy 95.793174 5.088258) (xy 95.816641 5.005782)
			(xy 95.832397 4.921492) (xy 95.840309 4.836109) (xy 95.840804 4.793234) (xy 95.840309 4.750359) (xy 100.335575 4.750359)
			(xy 100.335575 4.836109) (xy 100.343487 4.921492) (xy 100.359243 5.005782) (xy 100.38271 5.088258)
			(xy 100.413686 5.168217) (xy 100.451908 5.244977) (xy 100.497049 5.317883) (xy 100.548725 5.386312)
			(xy 100.606494 5.449682) (xy 100.669864 5.507451) (xy 100.738293 5.559127) (xy 100.811199 5.604268)
			(xy 100.887959 5.64249) (xy 100.967918 5.673466) (xy 101.050394 5.696933) (xy 101.134684 5.712689)
			(xy 101.220067 5.720601) (xy 101.305817 5.720601) (xy 101.3912 5.712689) (xy 101.47549 5.696933)
			(xy 101.557966 5.673466) (xy 101.637925 5.64249) (xy 101.714685 5.604268) (xy 101.787591 5.559127)
			(xy 101.85602 5.507451) (xy 101.91939 5.449682) (xy 101.977159 5.386312) (xy 102.028835 5.317883)
			(xy 102.073976 5.244977) (xy 102.112198 5.168217) (xy 102.143174 5.088258) (xy 102.166641 5.005782)
			(xy 102.182397 4.921492) (xy 102.190309 4.836109) (xy 102.190804 4.793234) (xy 102.190309 4.750359)
			(xy 181.468255 4.750359) (xy 181.468255 4.836109) (xy 181.476167 4.921492) (xy 181.491923 5.005782)
			(xy 181.51539 5.088258) (xy 181.546366 5.168217) (xy 181.584588 5.244977) (xy 181.629729 5.317883)
			(xy 181.681405 5.386312) (xy 181.739174 5.449682) (xy 181.802544 5.507451) (xy 181.870973 5.559127)
			(xy 181.943879 5.604268) (xy 182.020639 5.64249) (xy 182.100598 5.673466) (xy 182.183074 5.696933)
			(xy 182.267364 5.712689) (xy 182.352747 5.720601) (xy 182.438497 5.720601) (xy 182.52388 5.712689)
			(xy 182.60817 5.696933) (xy 182.690646 5.673466) (xy 182.770605 5.64249) (xy 182.791278 5.632196)
			(xy 183.953912 5.632196) (xy 183.953912 6.495796) (xy 183.954416 6.525332) (xy 183.96246 6.583854)
			(xy 183.978397 6.640736) (xy 184.001932 6.694918) (xy 184.032625 6.745391) (xy 184.069905 6.791214)
			(xy 184.113077 6.831534) (xy 184.161337 6.8656) (xy 184.213787 6.892777) (xy 184.269448 6.912559)
			(xy 184.327285 6.924578) (xy 184.38622 6.928609) (xy 184.445155 6.924578) (xy 184.502992 6.912559)
			(xy 184.558653 6.892777) (xy 184.611103 6.8656) (xy 184.659363 6.831534) (xy 184.702535 6.791214)
			(xy 184.739815 6.745391) (xy 184.770508 6.694918) (xy 184.794043 6.640736) (xy 184.80998 6.583854)
			(xy 184.818024 6.525332) (xy 184.818528 6.495796) (xy 184.818528 6.309919) (xy 208.661241 6.309919)
			(xy 208.661241 6.395669) (xy 208.669153 6.481052) (xy 208.684909 6.565342) (xy 208.708376 6.647818)
			(xy 208.739352 6.727777) (xy 208.777574 6.804537) (xy 208.822715 6.877443) (xy 208.874391 6.945872)
			(xy 208.93216 7.009242) (xy 208.99553 7.067011) (xy 209.063959 7.118687) (xy 209.136865 7.163828)
			(xy 209.213625 7.20205) (xy 209.293584 7.233026) (xy 209.37606 7.256493) (xy 209.46035 7.272249)
			(xy 209.545733 7.280161) (xy 209.631483 7.280161) (xy 209.716866 7.272249) (xy 209.801156 7.256493)
			(xy 209.883632 7.233026) (xy 209.963591 7.20205) (xy 210.040351 7.163828) (xy 210.113257 7.118687)
			(xy 210.1692 7.07644) (xy 212.819996 7.07644) (xy 212.819996 7.076694) (xy 212.819996 8.173974) (xy 212.820529 8.186058)
			(xy 212.827973 8.20905) (xy 212.842144 8.228627) (xy 212.861661 8.24288) (xy 212.884622 8.25042)
			(xy 212.896704 8.250936) (xy 213.508844 8.250936) (xy 213.520918 8.250474) (xy 213.543882 8.243003)
			(xy 213.563416 8.228805) (xy 213.57761 8.209268) (xy 213.585076 8.186302) (xy 213.585552 8.174228)
			(xy 213.585552 8.173974) (xy 213.585552 7.076694) (xy 213.585097 7.064603) (xy 213.577638 7.041601)
			(xy 213.563449 7.022021) (xy 213.543912 7.007771) (xy 213.520933 7.00024) (xy 213.508844 6.999732)
			(xy 212.896704 6.999732) (xy 212.884617 7.000116) (xy 212.861628 7.007588) (xy 212.842074 7.0218)
			(xy 212.827871 7.04136) (xy 212.820411 7.064353) (xy 212.819996 7.07644) (xy 210.1692 7.07644) (xy 210.181686 7.067011)
			(xy 210.245056 7.009242) (xy 210.302825 6.945872) (xy 210.354501 6.877443) (xy 210.399642 6.804537)
			(xy 210.437864 6.727777) (xy 210.46884 6.647818) (xy 210.492307 6.565342) (xy 210.508063 6.481052)
			(xy 210.515975 6.395669) (xy 210.51647 6.352794) (xy 210.515975 6.309919) (xy 215.011241 6.309919)
			(xy 215.011241 6.395669) (xy 215.019153 6.481052) (xy 215.034909 6.565342) (xy 215.058376 6.647818)
			(xy 215.089352 6.727777) (xy 215.127574 6.804537) (xy 215.172715 6.877443) (xy 215.224391 6.945872)
			(xy 215.28216 7.009242) (xy 215.34553 7.067011) (xy 215.413959 7.118687) (xy 215.486865 7.163828)
			(xy 215.563625 7.20205) (xy 215.643584 7.233026) (xy 215.72606 7.256493) (xy 215.81035 7.272249)
			(xy 215.895733 7.280161) (xy 215.981483 7.280161) (xy 216.066866 7.272249) (xy 216.151156 7.256493)
			(xy 216.233632 7.233026) (xy 216.313591 7.20205) (xy 216.390351 7.163828) (xy 216.463257 7.118687)
			(xy 216.531686 7.067011) (xy 216.595056 7.009242) (xy 216.652825 6.945872) (xy 216.704501 6.877443)
			(xy 216.749642 6.804537) (xy 216.787864 6.727777) (xy 216.81884 6.647818) (xy 216.842307 6.565342)
			(xy 216.858063 6.481052) (xy 216.865975 6.395669) (xy 216.86647 6.352794) (xy 216.865975 6.309919)
			(xy 296.143921 6.309919) (xy 296.143921 6.395669) (xy 296.151833 6.481052) (xy 296.167589 6.565342)
			(xy 296.191056 6.647818) (xy 296.222032 6.727777) (xy 296.260254 6.804537) (xy 296.305395 6.877443)
			(xy 296.357071 6.945872) (xy 296.41484 7.009242) (xy 296.47821 7.067011) (xy 296.546639 7.118687)
			(xy 296.619545 7.163828) (xy 296.696305 7.20205) (xy 296.776264 7.233026) (xy 296.85874 7.256493)
			(xy 296.94303 7.272249) (xy 297.028413 7.280161) (xy 297.114163 7.280161) (xy 297.199546 7.272249)
			(xy 297.283836 7.256493) (xy 297.366312 7.233026) (xy 297.446271 7.20205) (xy 297.523031 7.163828)
			(xy 297.595937 7.118687) (xy 297.658607 7.07136) (xy 299.424344 7.07136) (xy 299.424344 7.071614)
			(xy 299.424344 8.168894) (xy 299.424813 8.180984) (xy 299.432268 8.203985) (xy 299.446454 8.223565)
			(xy 299.465988 8.237816) (xy 299.488964 8.245347) (xy 299.501052 8.245856) (xy 300.113192 8.245856)
			(xy 300.125261 8.24533) (xy 300.14822 8.237875) (xy 300.167753 8.223693) (xy 300.18195 8.20417) (xy 300.189421 8.181217)
			(xy 300.1899 8.169148) (xy 300.1899 8.168894) (xy 300.1899 7.071614) (xy 300.189381 7.059529) (xy 300.181933 7.036536)
			(xy 300.167759 7.016959) (xy 300.148238 7.002707) (xy 300.125275 6.995167) (xy 300.113192 6.994652)
			(xy 299.501052 6.994652) (xy 299.488979 6.995123) (xy 299.466017 7.002593) (xy 299.446484 7.01679)
			(xy 299.43229 7.036324) (xy 299.424821 7.059287) (xy 299.424344 7.07136) (xy 297.658607 7.07136)
			(xy 297.664366 7.067011) (xy 297.727736 7.009242) (xy 297.785505 6.945872) (xy 297.837181 6.877443)
			(xy 297.882322 6.804537) (xy 297.920544 6.727777) (xy 297.95152 6.647818) (xy 297.974987 6.565342)
			(xy 297.990743 6.481052) (xy 297.998655 6.395669) (xy 297.99915 6.352794) (xy 297.998655 6.309919)
			(xy 302.493921 6.309919) (xy 302.493921 6.395669) (xy 302.501833 6.481052) (xy 302.517589 6.565342)
			(xy 302.541056 6.647818) (xy 302.572032 6.727777) (xy 302.610254 6.804537) (xy 302.655395 6.877443)
			(xy 302.707071 6.945872) (xy 302.76484 7.009242) (xy 302.82821 7.067011) (xy 302.896639 7.118687)
			(xy 302.969545 7.163828) (xy 303.046305 7.20205) (xy 303.126264 7.233026) (xy 303.20874 7.256493)
			(xy 303.29303 7.272249) (xy 303.378413 7.280161) (xy 303.464163 7.280161) (xy 303.549546 7.272249)
			(xy 303.633836 7.256493) (xy 303.716312 7.233026) (xy 303.796271 7.20205) (xy 303.873031 7.163828)
			(xy 303.945937 7.118687) (xy 304.014366 7.067011) (xy 304.077736 7.009242) (xy 304.135505 6.945872)
			(xy 304.187181 6.877443) (xy 304.232322 6.804537) (xy 304.270544 6.727777) (xy 304.30152 6.647818)
			(xy 304.324987 6.565342) (xy 304.340743 6.481052) (xy 304.348655 6.395669) (xy 304.34915 6.352794)
			(xy 304.348655 6.309919) (xy 311.155321 6.309919) (xy 311.155321 6.395669) (xy 311.163233 6.481052)
			(xy 311.178989 6.565342) (xy 311.202456 6.647818) (xy 311.233432 6.727777) (xy 311.271654 6.804537)
			(xy 311.316795 6.877443) (xy 311.368471 6.945872) (xy 311.42624 7.009242) (xy 311.48961 7.067011)
			(xy 311.558039 7.118687) (xy 311.630945 7.163828) (xy 311.707705 7.20205) (xy 311.787664 7.233026)
			(xy 311.87014 7.256493) (xy 311.95443 7.272249) (xy 312.039813 7.280161) (xy 312.125563 7.280161)
			(xy 312.210946 7.272249) (xy 312.295236 7.256493) (xy 312.377712 7.233026) (xy 312.457671 7.20205)
			(xy 312.534431 7.163828) (xy 312.607337 7.118687) (xy 312.662944 7.076694) (xy 315.314076 7.076694)
			(xy 315.314076 8.173974) (xy 315.31453 8.186066) (xy 315.321984 8.209072) (xy 315.336173 8.228655)
			(xy 315.355711 8.242905) (xy 315.378694 8.250431) (xy 315.390784 8.250936) (xy 316.002924 8.250936)
			(xy 316.006988 8.250682) (xy 316.013005 8.25059) (xy 316.024813 8.25291) (xy 316.030356 8.255254)
			(xy 316.057026 8.267192) (xy 316.063688 8.270455) (xy 316.07492 8.280132) (xy 316.079124 8.286242)
			(xy 316.096177 8.312284) (xy 316.136632 8.359594) (xy 316.183453 8.400613) (xy 316.235673 8.434495)
			(xy 316.292211 8.460537) (xy 316.3519 8.478202) (xy 316.413506 8.487124) (xy 316.44463 8.487664)
			(xy 316.472941 8.487228) (xy 316.529079 8.479836) (xy 316.583773 8.465183) (xy 316.636088 8.44352)
			(xy 316.685129 8.415216) (xy 316.730058 8.380756) (xy 316.770106 8.340728) (xy 316.80459 8.295817)
			(xy 316.83292 8.246791) (xy 316.854611 8.194487) (xy 316.869292 8.139801) (xy 316.876713 8.083667)
			(xy 316.877192 8.055356) (xy 316.877192 7.191756) (xy 316.876806 7.163438) (xy 316.869405 7.107287)
			(xy 316.854736 7.052583) (xy 316.83305 7.000263) (xy 316.804718 6.951222) (xy 316.770226 6.9063)
			(xy 316.730163 6.866267) (xy 316.685217 6.831807) (xy 316.636155 6.803511) (xy 316.583819 6.781863)
			(xy 316.529105 6.767234) (xy 316.472949 6.759874) (xy 316.44463 6.759448) (xy 316.413256 6.760032)
			(xy 316.351166 6.769088) (xy 316.291034 6.787015) (xy 316.234121 6.813438) (xy 316.18162 6.847801)
			(xy 316.134631 6.889386) (xy 316.094139 6.93732) (xy 316.077092 6.963664) (xy 316.073038 6.969812)
			(xy 316.062062 6.979621) (xy 316.055502 6.982968) (xy 316.01664 7.001002) (xy 316.002924 6.999732)
			(xy 315.390784 6.999732) (xy 315.378671 7.000103) (xy 315.355638 7.007611) (xy 315.336062 7.021883)
			(xy 315.321869 7.041516) (xy 315.314455 7.064579) (xy 315.314076 7.076694) (xy 312.662944 7.076694)
			(xy 312.675766 7.067011) (xy 312.739136 7.009242) (xy 312.796905 6.945872) (xy 312.848581 6.877443)
			(xy 312.893722 6.804537) (xy 312.931944 6.727777) (xy 312.96292 6.647818) (xy 312.986387 6.565342)
			(xy 313.002143 6.481052) (xy 313.010055 6.395669) (xy 313.01055 6.352794) (xy 313.010055 6.309919)
			(xy 317.505321 6.309919) (xy 317.505321 6.395669) (xy 317.513233 6.481052) (xy 317.528989 6.565342)
			(xy 317.552456 6.647818) (xy 317.583432 6.727777) (xy 317.621654 6.804537) (xy 317.666795 6.877443)
			(xy 317.718471 6.945872) (xy 317.77624 7.009242) (xy 317.83961 7.067011) (xy 317.908039 7.118687)
			(xy 317.980945 7.163828) (xy 318.057705 7.20205) (xy 318.137664 7.233026) (xy 318.22014 7.256493)
			(xy 318.30443 7.272249) (xy 318.389813 7.280161) (xy 318.475563 7.280161) (xy 318.560946 7.272249)
			(xy 318.645236 7.256493) (xy 318.727712 7.233026) (xy 318.807671 7.20205) (xy 318.884431 7.163828)
			(xy 318.957337 7.118687) (xy 319.025766 7.067011) (xy 319.089136 7.009242) (xy 319.146905 6.945872)
			(xy 319.198581 6.877443) (xy 319.243722 6.804537) (xy 319.281944 6.727777) (xy 319.31292 6.647818)
			(xy 319.336387 6.565342) (xy 319.352143 6.481052) (xy 319.360055 6.395669) (xy 319.36055 6.352794)
			(xy 319.360055 6.309919) (xy 361.894107 6.309919) (xy 361.894107 6.395669) (xy 361.902019 6.481052)
			(xy 361.917775 6.565342) (xy 361.941242 6.647818) (xy 361.972218 6.727777) (xy 362.01044 6.804537)
			(xy 362.055581 6.877443) (xy 362.107257 6.945872) (xy 362.165026 7.009242) (xy 362.228396 7.067011)
			(xy 362.296825 7.118687) (xy 362.369731 7.163828) (xy 362.446491 7.20205) (xy 362.52645 7.233026)
			(xy 362.608926 7.256493) (xy 362.693216 7.272249) (xy 362.778599 7.280161) (xy 362.864349 7.280161)
			(xy 362.949732 7.272249) (xy 363.034022 7.256493) (xy 363.116498 7.233026) (xy 363.196457 7.20205)
			(xy 363.21713 7.191756) (xy 364.379764 7.191756) (xy 364.379764 8.055356) (xy 364.380276 8.08366)
			(xy 364.387659 8.139784) (xy 364.402305 8.194464) (xy 364.423963 8.246764) (xy 364.452262 8.29579)
			(xy 364.486719 8.340703) (xy 364.526743 8.380733) (xy 364.57165 8.415197) (xy 364.620671 8.443505)
			(xy 364.672968 8.465172) (xy 364.727646 8.479827) (xy 364.783768 8.487219) (xy 364.812072 8.487664)
			(xy 364.843538 8.487114) (xy 364.905805 8.477993) (xy 364.966091 8.459939) (xy 365.023123 8.433335)
			(xy 365.075694 8.398742) (xy 365.122694 8.356892) (xy 365.163128 8.308669) (xy 365.180118 8.282178)
			(xy 365.184143 8.276124) (xy 365.194988 8.266451) (xy 365.201454 8.263128) (xy 365.239554 8.24484)
			(xy 365.251238 8.245856) (xy 365.863378 8.245856) (xy 365.8755 8.245421) (xy 365.898559 8.237934)
			(xy 365.918175 8.223687) (xy 365.932427 8.204074) (xy 365.939919 8.181016) (xy 365.94034 8.168894)
			(xy 365.94034 7.376973) (xy 385.651997 7.376973) (xy 385.651997 7.462723) (xy 385.659909 7.548106)
			(xy 385.675665 7.632396) (xy 385.699132 7.714872) (xy 385.730108 7.794831) (xy 385.76833 7.871591)
			(xy 385.813471 7.944497) (xy 385.865147 8.012926) (xy 385.922916 8.076296) (xy 385.986286 8.134065)
			(xy 386.054715 8.185741) (xy 386.127621 8.230882) (xy 386.204381 8.269104) (xy 386.28434 8.30008)
			(xy 386.366816 8.323547) (xy 386.451106 8.339303) (xy 386.536489 8.347215) (xy 386.622239 8.347215)
			(xy 386.707622 8.339303) (xy 386.791912 8.323547) (xy 386.874388 8.30008) (xy 386.954347 8.269104)
			(xy 387.031107 8.230882) (xy 387.104013 8.185741) (xy 387.15962 8.143748) (xy 389.810752 8.143748)
			(xy 389.810752 9.241028) (xy 389.811239 9.2531) (xy 389.818705 9.276061) (xy 389.832897 9.295595)
			(xy 389.852428 9.30979) (xy 389.875388 9.317259) (xy 389.88746 9.317736) (xy 390.503664 9.317736)
			(xy 390.509681 9.317657) (xy 390.521488 9.319968) (xy 390.527032 9.322308) (xy 390.553702 9.334246)
			(xy 390.560368 9.3375) (xy 390.571596 9.347184) (xy 390.5758 9.353296) (xy 390.592846 9.379353) (xy 390.633287 9.426699)
			(xy 390.680099 9.467757) (xy 390.732316 9.501676) (xy 390.788857 9.527757) (xy 390.848554 9.545458)
			(xy 390.910173 9.554416) (xy 390.941306 9.554972) (xy 390.969627 9.554504) (xy 391.025784 9.547111)
			(xy 391.080496 9.53245) (xy 391.132826 9.510774) (xy 391.18188 9.482453) (xy 391.226817 9.447972)
			(xy 391.266869 9.40792) (xy 391.301351 9.362983) (xy 391.329672 9.31393) (xy 391.351349 9.2616) (xy 391.36601 9.206888)
			(xy 391.373404 9.150731) (xy 391.373868 9.12241) (xy 391.373868 8.25881) (xy 391.373409 8.230488)
			(xy 391.366017 8.174328) (xy 391.351358 8.119614) (xy 391.329682 8.067281) (xy 391.301361 8.018225)
			(xy 391.266879 7.973286) (xy 391.226826 7.933231) (xy 391.181888 7.898748) (xy 391.132833 7.870425)
			(xy 391.080501 7.848747) (xy 391.025788 7.834086) (xy 390.969628 7.826692) (xy 390.941306 7.826248)
			(xy 390.909919 7.826808) (xy 390.847805 7.835881) (xy 390.787654 7.853837) (xy 390.730731 7.880299)
			(xy 390.678231 7.914712) (xy 390.631256 7.956352) (xy 390.590794 8.004345) (xy 390.573768 8.030718)
			(xy 390.569732 8.036879) (xy 390.558743 8.04668) (xy 390.552178 8.050022) (xy 390.513316 8.068056)
			(xy 390.4996 8.06704) (xy 389.88746 8.06704) (xy 389.87537 8.067379) (xy 389.852378 8.074864) (xy 389.832825 8.089087)
			(xy 389.818623 8.108657) (xy 389.811165 8.131658) (xy 389.810752 8.143748) (xy 387.15962 8.143748)
			(xy 387.172442 8.134065) (xy 387.235812 8.076296) (xy 387.293581 8.012926) (xy 387.345257 7.944497)
			(xy 387.390398 7.871591) (xy 387.42862 7.794831) (xy 387.459596 7.714872) (xy 387.483063 7.632396)
			(xy 387.498819 7.548106) (xy 387.506731 7.462723) (xy 387.507226 7.419848) (xy 387.506731 7.376973)
			(xy 392.001997 7.376973) (xy 392.001997 7.462723) (xy 392.009909 7.548106) (xy 392.025665 7.632396)
			(xy 392.049132 7.714872) (xy 392.080108 7.794831) (xy 392.11833 7.871591) (xy 392.163471 7.944497)
			(xy 392.215147 8.012926) (xy 392.272916 8.076296) (xy 392.336286 8.134065) (xy 392.404715 8.185741)
			(xy 392.477621 8.230882) (xy 392.554381 8.269104) (xy 392.63434 8.30008) (xy 392.716816 8.323547)
			(xy 392.801106 8.339303) (xy 392.886489 8.347215) (xy 392.972239 8.347215) (xy 393.057622 8.339303)
			(xy 393.141912 8.323547) (xy 393.224388 8.30008) (xy 393.304347 8.269104) (xy 393.381107 8.230882)
			(xy 393.454013 8.185741) (xy 393.522442 8.134065) (xy 393.585812 8.076296) (xy 393.643581 8.012926)
			(xy 393.695257 7.944497) (xy 393.740398 7.871591) (xy 393.77862 7.794831) (xy 393.809596 7.714872)
			(xy 393.833063 7.632396) (xy 393.848819 7.548106) (xy 393.856731 7.462723) (xy 393.857226 7.419848)
			(xy 393.856731 7.376973) (xy 436.390783 7.376973) (xy 436.390783 7.462723) (xy 436.398695 7.548106)
			(xy 436.414451 7.632396) (xy 436.437918 7.714872) (xy 436.468894 7.794831) (xy 436.507116 7.871591)
			(xy 436.552257 7.944497) (xy 436.603933 8.012926) (xy 436.661702 8.076296) (xy 436.725072 8.134065)
			(xy 436.793501 8.185741) (xy 436.866407 8.230882) (xy 436.943167 8.269104) (xy 437.023126 8.30008)
			(xy 437.105602 8.323547) (xy 437.189892 8.339303) (xy 437.275275 8.347215) (xy 437.361025 8.347215)
			(xy 437.446408 8.339303) (xy 437.530698 8.323547) (xy 437.613174 8.30008) (xy 437.693133 8.269104)
			(xy 437.713806 8.25881) (xy 438.87644 8.25881) (xy 438.87644 9.12241) (xy 438.876891 9.150721) (xy 438.88428 9.206859)
			(xy 438.898931 9.261553) (xy 438.920592 9.313867) (xy 438.948895 9.362908) (xy 438.983354 9.407838)
			(xy 439.02338 9.447887) (xy 439.06829 9.482371) (xy 439.117315 9.5107) (xy 439.169618 9.532391) (xy 439.224304 9.547073)
			(xy 439.280437 9.554493) (xy 439.308748 9.554972) (xy 439.340223 9.554436) (xy 439.402501 9.545263)
			(xy 439.462792 9.52716) (xy 439.519824 9.500511) (xy 439.57239 9.465878) (xy 439.619383 9.423991)
			(xy 439.659809 9.375737) (xy 439.676794 9.349232) (xy 439.680836 9.343191) (xy 439.691669 9.33351)
			(xy 439.69813 9.330182) (xy 439.73623 9.311894) (xy 439.747914 9.312656) (xy 440.360054 9.312656)
			(xy 440.372142 9.312153) (xy 440.395141 9.304709) (xy 440.414722 9.290532) (xy 440.428974 9.271005)
			(xy 440.436507 9.248034) (xy 440.437016 9.235948) (xy 440.437016 8.138668) (xy 440.436611 8.126559)
			(xy 440.429105 8.103533) (xy 440.41484 8.083962) (xy 440.395217 8.069768) (xy 440.372164 8.062345)
			(xy 440.360054 8.06196) (xy 439.747914 8.06196) (xy 439.733944 8.062976) (xy 439.695336 8.04545)
			(xy 439.688745 8.042158) (xy 439.677642 8.032486) (xy 439.673492 8.0264) (xy 439.656394 8.000515)
			(xy 439.615929 7.953493) (xy 439.569162 7.912734) (xy 439.517051 7.879074) (xy 439.460667 7.853204)
			(xy 439.401165 7.835654) (xy 439.339766 7.826785) (xy 439.308748 7.826248) (xy 439.280434 7.826781)
			(xy 439.224291 7.834168) (xy 439.169594 7.848824) (xy 439.117278 7.870496) (xy 439.06824 7.898814)
			(xy 439.023319 7.933293) (xy 438.983286 7.973341) (xy 438.948824 8.018275) (xy 438.920524 8.067323)
			(xy 438.898872 8.119647) (xy 438.884237 8.17435) (xy 438.87687 8.230496) (xy 438.87644 8.25881) (xy 437.713806 8.25881)
			(xy 437.769893 8.230882) (xy 437.842799 8.185741) (xy 437.911228 8.134065) (xy 437.974598 8.076296)
			(xy 438.032367 8.012926) (xy 438.084043 7.944497) (xy 438.129184 7.871591) (xy 438.167406 7.794831)
			(xy 438.198382 7.714872) (xy 438.221849 7.632396) (xy 438.237605 7.548106) (xy 438.245517 7.462723)
			(xy 438.246012 7.419848) (xy 438.245517 7.376973) (xy 442.740783 7.376973) (xy 442.740783 7.462723)
			(xy 442.748695 7.548106) (xy 442.764451 7.632396) (xy 442.787918 7.714872) (xy 442.818894 7.794831)
			(xy 442.857116 7.871591) (xy 442.902257 7.944497) (xy 442.953933 8.012926) (xy 443.011702 8.076296)
			(xy 443.075072 8.134065) (xy 443.143501 8.185741) (xy 443.216407 8.230882) (xy 443.293167 8.269104)
			(xy 443.373126 8.30008) (xy 443.455602 8.323547) (xy 443.539892 8.339303) (xy 443.625275 8.347215)
			(xy 443.711025 8.347215) (xy 443.796408 8.339303) (xy 443.880698 8.323547) (xy 443.963174 8.30008)
			(xy 444.043133 8.269104) (xy 444.119893 8.230882) (xy 444.192799 8.185741) (xy 444.261228 8.134065)
			(xy 444.324598 8.076296) (xy 444.382367 8.012926) (xy 444.434043 7.944497) (xy 444.479184 7.871591)
			(xy 444.517406 7.794831) (xy 444.548382 7.714872) (xy 444.571849 7.632396) (xy 444.587605 7.548106)
			(xy 444.595517 7.462723) (xy 444.596012 7.419848) (xy 444.595517 7.376973) (xy 444.587605 7.29159)
			(xy 444.571849 7.2073) (xy 444.548382 7.124824) (xy 444.517406 7.044865) (xy 444.479184 6.968105)
			(xy 444.434043 6.895199) (xy 444.382367 6.82677) (xy 444.324598 6.7634) (xy 444.261228 6.705631)
			(xy 444.192799 6.653955) (xy 444.119893 6.608814) (xy 444.043133 6.570592) (xy 443.963174 6.539616)
			(xy 443.880698 6.516149) (xy 443.796408 6.500393) (xy 443.711025 6.492481) (xy 443.625275 6.492481)
			(xy 443.539892 6.500393) (xy 443.455602 6.516149) (xy 443.373126 6.539616) (xy 443.293167 6.570592)
			(xy 443.216407 6.608814) (xy 443.143501 6.653955) (xy 443.075072 6.705631) (xy 443.011702 6.7634)
			(xy 442.953933 6.82677) (xy 442.902257 6.895199) (xy 442.857116 6.968105) (xy 442.818894 7.044865)
			(xy 442.787918 7.124824) (xy 442.764451 7.2073) (xy 442.748695 7.29159) (xy 442.740783 7.376973)
			(xy 438.245517 7.376973) (xy 438.237605 7.29159) (xy 438.221849 7.2073) (xy 438.198382 7.124824)
			(xy 438.167406 7.044865) (xy 438.129184 6.968105) (xy 438.084043 6.895199) (xy 438.032367 6.82677)
			(xy 437.974598 6.7634) (xy 437.911228 6.705631) (xy 437.842799 6.653955) (xy 437.769893 6.608814)
			(xy 437.693133 6.570592) (xy 437.613174 6.539616) (xy 437.530698 6.516149) (xy 437.446408 6.500393)
			(xy 437.361025 6.492481) (xy 437.275275 6.492481) (xy 437.189892 6.500393) (xy 437.105602 6.516149)
			(xy 437.023126 6.539616) (xy 436.943167 6.570592) (xy 436.866407 6.608814) (xy 436.793501 6.653955)
			(xy 436.725072 6.705631) (xy 436.661702 6.7634) (xy 436.603933 6.82677) (xy 436.552257 6.895199)
			(xy 436.507116 6.968105) (xy 436.468894 7.044865) (xy 436.437918 7.124824) (xy 436.414451 7.2073)
			(xy 436.398695 7.29159) (xy 436.390783 7.376973) (xy 393.856731 7.376973) (xy 393.848819 7.29159)
			(xy 393.833063 7.2073) (xy 393.809596 7.124824) (xy 393.77862 7.044865) (xy 393.740398 6.968105)
			(xy 393.695257 6.895199) (xy 393.643581 6.82677) (xy 393.585812 6.7634) (xy 393.522442 6.705631)
			(xy 393.454013 6.653955) (xy 393.381107 6.608814) (xy 393.304347 6.570592) (xy 393.224388 6.539616)
			(xy 393.141912 6.516149) (xy 393.057622 6.500393) (xy 392.972239 6.492481) (xy 392.886489 6.492481)
			(xy 392.801106 6.500393) (xy 392.716816 6.516149) (xy 392.63434 6.539616) (xy 392.554381 6.570592)
			(xy 392.477621 6.608814) (xy 392.404715 6.653955) (xy 392.336286 6.705631) (xy 392.272916 6.7634)
			(xy 392.215147 6.82677) (xy 392.163471 6.895199) (xy 392.11833 6.968105) (xy 392.080108 7.044865)
			(xy 392.049132 7.124824) (xy 392.025665 7.2073) (xy 392.009909 7.29159) (xy 392.001997 7.376973)
			(xy 387.506731 7.376973) (xy 387.498819 7.29159) (xy 387.483063 7.2073) (xy 387.459596 7.124824)
			(xy 387.42862 7.044865) (xy 387.390398 6.968105) (xy 387.345257 6.895199) (xy 387.293581 6.82677)
			(xy 387.235812 6.7634) (xy 387.172442 6.705631) (xy 387.104013 6.653955) (xy 387.031107 6.608814)
			(xy 386.954347 6.570592) (xy 386.874388 6.539616) (xy 386.791912 6.516149) (xy 386.707622 6.500393)
			(xy 386.622239 6.492481) (xy 386.536489 6.492481) (xy 386.451106 6.500393) (xy 386.366816 6.516149)
			(xy 386.28434 6.539616) (xy 386.204381 6.570592) (xy 386.127621 6.608814) (xy 386.054715 6.653955)
			(xy 385.986286 6.705631) (xy 385.922916 6.7634) (xy 385.865147 6.82677) (xy 385.813471 6.895199)
			(xy 385.76833 6.968105) (xy 385.730108 7.044865) (xy 385.699132 7.124824) (xy 385.675665 7.2073)
			(xy 385.659909 7.29159) (xy 385.651997 7.376973) (xy 365.94034 7.376973) (xy 365.94034 7.071614)
			(xy 365.939928 7.05949) (xy 365.932437 7.036428) (xy 365.918184 7.016811) (xy 365.898565 7.00256)
			(xy 365.875502 6.995071) (xy 365.863378 6.994652) (xy 365.251238 6.994652) (xy 365.237268 6.995922)
			(xy 365.19866 6.978396) (xy 365.19205 6.975139) (xy 365.180958 6.965443) (xy 365.176816 6.959346)
			(xy 365.159713 6.933473) (xy 365.119244 6.886474) (xy 365.072473 6.845742) (xy 365.020359 6.812116)
			(xy 364.963973 6.786284) (xy 364.904474 6.768779) (xy 364.843083 6.759959) (xy 364.812072 6.759448)
			(xy 364.783769 6.759928) (xy 364.727646 6.76732) (xy 364.672969 6.781973) (xy 364.620671 6.803637)
			(xy 364.571648 6.831941) (xy 364.526739 6.8664) (xy 364.486711 6.906427) (xy 364.452249 6.951335)
			(xy 364.423944 7.000357) (xy 364.402278 7.052654) (xy 364.387623 7.107331) (xy 364.380229 7.163453)
			(xy 364.379764 7.191756) (xy 363.21713 7.191756) (xy 363.273217 7.163828) (xy 363.346123 7.118687)
			(xy 363.414552 7.067011) (xy 363.477922 7.009242) (xy 363.535691 6.945872) (xy 363.587367 6.877443)
			(xy 363.632508 6.804537) (xy 363.67073 6.727777) (xy 363.701706 6.647818) (xy 363.725173 6.565342)
			(xy 363.740929 6.481052) (xy 363.748841 6.395669) (xy 363.749336 6.352794) (xy 363.748841 6.309919)
			(xy 368.244107 6.309919) (xy 368.244107 6.395669) (xy 368.252019 6.481052) (xy 368.267775 6.565342)
			(xy 368.291242 6.647818) (xy 368.322218 6.727777) (xy 368.36044 6.804537) (xy 368.405581 6.877443)
			(xy 368.457257 6.945872) (xy 368.515026 7.009242) (xy 368.578396 7.067011) (xy 368.646825 7.118687)
			(xy 368.719731 7.163828) (xy 368.796491 7.20205) (xy 368.87645 7.233026) (xy 368.958926 7.256493)
			(xy 369.043216 7.272249) (xy 369.128599 7.280161) (xy 369.214349 7.280161) (xy 369.299732 7.272249)
			(xy 369.384022 7.256493) (xy 369.466498 7.233026) (xy 369.546457 7.20205) (xy 369.623217 7.163828)
			(xy 369.696123 7.118687) (xy 369.764552 7.067011) (xy 369.827922 7.009242) (xy 369.885691 6.945872)
			(xy 369.937367 6.877443) (xy 369.982508 6.804537) (xy 370.02073 6.727777) (xy 370.051706 6.647818)
			(xy 370.075173 6.565342) (xy 370.090929 6.481052) (xy 370.098841 6.395669) (xy 370.099336 6.352794)
			(xy 370.098841 6.309919) (xy 370.090929 6.224536) (xy 370.075173 6.140246) (xy 370.051706 6.05777)
			(xy 370.02073 5.977811) (xy 369.982508 5.901051) (xy 369.937367 5.828145) (xy 369.885691 5.759716)
			(xy 369.827922 5.696346) (xy 369.764552 5.638577) (xy 369.696123 5.586901) (xy 369.623217 5.54176)
			(xy 369.546457 5.503538) (xy 369.466498 5.472562) (xy 369.384022 5.449095) (xy 369.299732 5.433339)
			(xy 369.214349 5.425427) (xy 369.128599 5.425427) (xy 369.043216 5.433339) (xy 368.958926 5.449095)
			(xy 368.87645 5.472562) (xy 368.796491 5.503538) (xy 368.719731 5.54176) (xy 368.646825 5.586901)
			(xy 368.578396 5.638577) (xy 368.515026 5.696346) (xy 368.457257 5.759716) (xy 368.405581 5.828145)
			(xy 368.36044 5.901051) (xy 368.322218 5.977811) (xy 368.291242 6.05777) (xy 368.267775 6.140246)
			(xy 368.252019 6.224536) (xy 368.244107 6.309919) (xy 363.748841 6.309919) (xy 363.740929 6.224536)
			(xy 363.725173 6.140246) (xy 363.701706 6.05777) (xy 363.67073 5.977811) (xy 363.632508 5.901051)
			(xy 363.587367 5.828145) (xy 363.535691 5.759716) (xy 363.477922 5.696346) (xy 363.414552 5.638577)
			(xy 363.346123 5.586901) (xy 363.273217 5.54176) (xy 363.196457 5.503538) (xy 363.116498 5.472562)
			(xy 363.034022 5.449095) (xy 362.949732 5.433339) (xy 362.864349 5.425427) (xy 362.778599 5.425427)
			(xy 362.693216 5.433339) (xy 362.608926 5.449095) (xy 362.52645 5.472562) (xy 362.446491 5.503538)
			(xy 362.369731 5.54176) (xy 362.296825 5.586901) (xy 362.228396 5.638577) (xy 362.165026 5.696346)
			(xy 362.107257 5.759716) (xy 362.055581 5.828145) (xy 362.01044 5.901051) (xy 361.972218 5.977811)
			(xy 361.941242 6.05777) (xy 361.917775 6.140246) (xy 361.902019 6.224536) (xy 361.894107 6.309919)
			(xy 319.360055 6.309919) (xy 319.352143 6.224536) (xy 319.336387 6.140246) (xy 319.31292 6.05777)
			(xy 319.281944 5.977811) (xy 319.243722 5.901051) (xy 319.198581 5.828145) (xy 319.146905 5.759716)
			(xy 319.089136 5.696346) (xy 319.025766 5.638577) (xy 318.957337 5.586901) (xy 318.884431 5.54176)
			(xy 318.807671 5.503538) (xy 318.727712 5.472562) (xy 318.645236 5.449095) (xy 318.560946 5.433339)
			(xy 318.475563 5.425427) (xy 318.389813 5.425427) (xy 318.30443 5.433339) (xy 318.22014 5.449095)
			(xy 318.137664 5.472562) (xy 318.057705 5.503538) (xy 317.980945 5.54176) (xy 317.908039 5.586901)
			(xy 317.83961 5.638577) (xy 317.77624 5.696346) (xy 317.718471 5.759716) (xy 317.666795 5.828145)
			(xy 317.621654 5.901051) (xy 317.583432 5.977811) (xy 317.552456 6.05777) (xy 317.528989 6.140246)
			(xy 317.513233 6.224536) (xy 317.505321 6.309919) (xy 313.010055 6.309919) (xy 313.002143 6.224536)
			(xy 312.986387 6.140246) (xy 312.96292 6.05777) (xy 312.931944 5.977811) (xy 312.893722 5.901051)
			(xy 312.848581 5.828145) (xy 312.796905 5.759716) (xy 312.739136 5.696346) (xy 312.675766 5.638577)
			(xy 312.607337 5.586901) (xy 312.534431 5.54176) (xy 312.457671 5.503538) (xy 312.377712 5.472562)
			(xy 312.295236 5.449095) (xy 312.210946 5.433339) (xy 312.125563 5.425427) (xy 312.039813 5.425427)
			(xy 311.95443 5.433339) (xy 311.87014 5.449095) (xy 311.787664 5.472562) (xy 311.707705 5.503538)
			(xy 311.630945 5.54176) (xy 311.558039 5.586901) (xy 311.48961 5.638577) (xy 311.42624 5.696346)
			(xy 311.368471 5.759716) (xy 311.316795 5.828145) (xy 311.271654 5.901051) (xy 311.233432 5.977811)
			(xy 311.202456 6.05777) (xy 311.178989 6.140246) (xy 311.163233 6.224536) (xy 311.155321 6.309919)
			(xy 304.348655 6.309919) (xy 304.340743 6.224536) (xy 304.324987 6.140246) (xy 304.30152 6.05777)
			(xy 304.270544 5.977811) (xy 304.232322 5.901051) (xy 304.187181 5.828145) (xy 304.135505 5.759716)
			(xy 304.077736 5.696346) (xy 304.014366 5.638577) (xy 303.945937 5.586901) (xy 303.873031 5.54176)
			(xy 303.796271 5.503538) (xy 303.716312 5.472562) (xy 303.633836 5.449095) (xy 303.549546 5.433339)
			(xy 303.464163 5.425427) (xy 303.378413 5.425427) (xy 303.29303 5.433339) (xy 303.20874 5.449095)
			(xy 303.126264 5.472562) (xy 303.046305 5.503538) (xy 302.969545 5.54176) (xy 302.896639 5.586901)
			(xy 302.82821 5.638577) (xy 302.76484 5.696346) (xy 302.707071 5.759716) (xy 302.655395 5.828145)
			(xy 302.610254 5.901051) (xy 302.572032 5.977811) (xy 302.541056 6.05777) (xy 302.517589 6.140246)
			(xy 302.501833 6.224536) (xy 302.493921 6.309919) (xy 297.998655 6.309919) (xy 297.990743 6.224536)
			(xy 297.974987 6.140246) (xy 297.95152 6.05777) (xy 297.920544 5.977811) (xy 297.882322 5.901051)
			(xy 297.837181 5.828145) (xy 297.785505 5.759716) (xy 297.727736 5.696346) (xy 297.664366 5.638577)
			(xy 297.595937 5.586901) (xy 297.523031 5.54176) (xy 297.446271 5.503538) (xy 297.366312 5.472562)
			(xy 297.283836 5.449095) (xy 297.199546 5.433339) (xy 297.114163 5.425427) (xy 297.028413 5.425427)
			(xy 296.94303 5.433339) (xy 296.85874 5.449095) (xy 296.776264 5.472562) (xy 296.696305 5.503538)
			(xy 296.619545 5.54176) (xy 296.546639 5.586901) (xy 296.47821 5.638577) (xy 296.41484 5.696346)
			(xy 296.357071 5.759716) (xy 296.305395 5.828145) (xy 296.260254 5.901051) (xy 296.222032 5.977811)
			(xy 296.191056 6.05777) (xy 296.167589 6.140246) (xy 296.151833 6.224536) (xy 296.143921 6.309919)
			(xy 216.865975 6.309919) (xy 216.858063 6.224536) (xy 216.842307 6.140246) (xy 216.81884 6.05777)
			(xy 216.787864 5.977811) (xy 216.749642 5.901051) (xy 216.704501 5.828145) (xy 216.652825 5.759716)
			(xy 216.595056 5.696346) (xy 216.531686 5.638577) (xy 216.463257 5.586901) (xy 216.390351 5.54176)
			(xy 216.313591 5.503538) (xy 216.233632 5.472562) (xy 216.151156 5.449095) (xy 216.066866 5.433339)
			(xy 215.981483 5.425427) (xy 215.895733 5.425427) (xy 215.81035 5.433339) (xy 215.72606 5.449095)
			(xy 215.643584 5.472562) (xy 215.563625 5.503538) (xy 215.486865 5.54176) (xy 215.413959 5.586901)
			(xy 215.34553 5.638577) (xy 215.28216 5.696346) (xy 215.224391 5.759716) (xy 215.172715 5.828145)
			(xy 215.127574 5.901051) (xy 215.089352 5.977811) (xy 215.058376 6.05777) (xy 215.034909 6.140246)
			(xy 215.019153 6.224536) (xy 215.011241 6.309919) (xy 210.515975 6.309919) (xy 210.508063 6.224536)
			(xy 210.492307 6.140246) (xy 210.46884 6.05777) (xy 210.437864 5.977811) (xy 210.399642 5.901051)
			(xy 210.354501 5.828145) (xy 210.302825 5.759716) (xy 210.245056 5.696346) (xy 210.181686 5.638577)
			(xy 210.113257 5.586901) (xy 210.040351 5.54176) (xy 209.963591 5.503538) (xy 209.883632 5.472562)
			(xy 209.801156 5.449095) (xy 209.716866 5.433339) (xy 209.631483 5.425427) (xy 209.545733 5.425427)
			(xy 209.46035 5.433339) (xy 209.37606 5.449095) (xy 209.293584 5.472562) (xy 209.213625 5.503538)
			(xy 209.136865 5.54176) (xy 209.063959 5.586901) (xy 208.99553 5.638577) (xy 208.93216 5.696346)
			(xy 208.874391 5.759716) (xy 208.822715 5.828145) (xy 208.777574 5.901051) (xy 208.739352 5.977811)
			(xy 208.708376 6.05777) (xy 208.684909 6.140246) (xy 208.669153 6.224536) (xy 208.661241 6.309919)
			(xy 184.818528 6.309919) (xy 184.818528 5.632196) (xy 184.818024 5.60266) (xy 184.80998 5.544138)
			(xy 184.794043 5.487256) (xy 184.770508 5.433074) (xy 184.739815 5.382601) (xy 184.702535 5.336778)
			(xy 184.659363 5.296458) (xy 184.611103 5.262392) (xy 184.558653 5.235215) (xy 184.502992 5.215433)
			(xy 184.445155 5.203414) (xy 184.38622 5.199383) (xy 184.327285 5.203414) (xy 184.269448 5.215433)
			(xy 184.213787 5.235215) (xy 184.161337 5.262392) (xy 184.113077 5.296458) (xy 184.069905 5.336778)
			(xy 184.032625 5.382601) (xy 184.001932 5.433074) (xy 183.978397 5.487256) (xy 183.96246 5.544138)
			(xy 183.954416 5.60266) (xy 183.953912 5.632196) (xy 182.791278 5.632196) (xy 182.847365 5.604268)
			(xy 182.920271 5.559127) (xy 182.9887 5.507451) (xy 183.05207 5.449682) (xy 183.109839 5.386312)
			(xy 183.161515 5.317883) (xy 183.206656 5.244977) (xy 183.244878 5.168217) (xy 183.275854 5.088258)
			(xy 183.299321 5.005782) (xy 183.315077 4.921492) (xy 183.322989 4.836109) (xy 183.323484 4.793234)
			(xy 183.322989 4.750359) (xy 187.818255 4.750359) (xy 187.818255 4.836109) (xy 187.826167 4.921492)
			(xy 187.841923 5.005782) (xy 187.86539 5.088258) (xy 187.896366 5.168217) (xy 187.934588 5.244977)
			(xy 187.979729 5.317883) (xy 188.031405 5.386312) (xy 188.089174 5.449682) (xy 188.152544 5.507451)
			(xy 188.220973 5.559127) (xy 188.293879 5.604268) (xy 188.370639 5.64249) (xy 188.450598 5.673466)
			(xy 188.533074 5.696933) (xy 188.617364 5.712689) (xy 188.702747 5.720601) (xy 188.788497 5.720601)
			(xy 188.87388 5.712689) (xy 188.95817 5.696933) (xy 189.040646 5.673466) (xy 189.120605 5.64249)
			(xy 189.197365 5.604268) (xy 189.270271 5.559127) (xy 189.3387 5.507451) (xy 189.40207 5.449682)
			(xy 189.459839 5.386312) (xy 189.511515 5.317883) (xy 189.556656 5.244977) (xy 189.594878 5.168217)
			(xy 189.625854 5.088258) (xy 189.649321 5.005782) (xy 189.665077 4.921492) (xy 189.672989 4.836109)
			(xy 189.673484 4.793234) (xy 189.672989 4.750359) (xy 189.665077 4.664976) (xy 189.649321 4.580686)
			(xy 189.625854 4.49821) (xy 189.594878 4.418251) (xy 189.556656 4.341491) (xy 189.511515 4.268585)
			(xy 189.459839 4.200156) (xy 189.40207 4.136786) (xy 189.3387 4.079017) (xy 189.270271 4.027341)
			(xy 189.197365 3.9822) (xy 189.120605 3.943978) (xy 189.040646 3.913002) (xy 188.95817 3.889535)
			(xy 188.87388 3.873779) (xy 188.788497 3.865867) (xy 188.702747 3.865867) (xy 188.617364 3.873779)
			(xy 188.533074 3.889535) (xy 188.450598 3.913002) (xy 188.370639 3.943978) (xy 188.293879 3.9822)
			(xy 188.220973 4.027341) (xy 188.152544 4.079017) (xy 188.089174 4.136786) (xy 188.031405 4.200156)
			(xy 187.979729 4.268585) (xy 187.934588 4.341491) (xy 187.896366 4.418251) (xy 187.86539 4.49821)
			(xy 187.841923 4.580686) (xy 187.826167 4.664976) (xy 187.818255 4.750359) (xy 183.322989 4.750359)
			(xy 183.315077 4.664976) (xy 183.299321 4.580686) (xy 183.275854 4.49821) (xy 183.244878 4.418251)
			(xy 183.206656 4.341491) (xy 183.161515 4.268585) (xy 183.109839 4.200156) (xy 183.05207 4.136786)
			(xy 182.9887 4.079017) (xy 182.920271 4.027341) (xy 182.847365 3.9822) (xy 182.770605 3.943978) (xy 182.690646 3.913002)
			(xy 182.60817 3.889535) (xy 182.52388 3.873779) (xy 182.438497 3.865867) (xy 182.352747 3.865867)
			(xy 182.267364 3.873779) (xy 182.183074 3.889535) (xy 182.100598 3.913002) (xy 182.020639 3.943978)
			(xy 181.943879 3.9822) (xy 181.870973 4.027341) (xy 181.802544 4.079017) (xy 181.739174 4.136786)
			(xy 181.681405 4.200156) (xy 181.629729 4.268585) (xy 181.584588 4.341491) (xy 181.546366 4.418251)
			(xy 181.51539 4.49821) (xy 181.491923 4.580686) (xy 181.476167 4.664976) (xy 181.468255 4.750359)
			(xy 102.190309 4.750359) (xy 102.182397 4.664976) (xy 102.166641 4.580686) (xy 102.143174 4.49821)
			(xy 102.112198 4.418251) (xy 102.073976 4.341491) (xy 102.028835 4.268585) (xy 101.977159 4.200156)
			(xy 101.91939 4.136786) (xy 101.85602 4.079017) (xy 101.787591 4.027341) (xy 101.714685 3.9822) (xy 101.637925 3.943978)
			(xy 101.557966 3.913002) (xy 101.47549 3.889535) (xy 101.3912 3.873779) (xy 101.305817 3.865867)
			(xy 101.220067 3.865867) (xy 101.134684 3.873779) (xy 101.050394 3.889535) (xy 100.967918 3.913002)
			(xy 100.887959 3.943978) (xy 100.811199 3.9822) (xy 100.738293 4.027341) (xy 100.669864 4.079017)
			(xy 100.606494 4.136786) (xy 100.548725 4.200156) (xy 100.497049 4.268585) (xy 100.451908 4.341491)
			(xy 100.413686 4.418251) (xy 100.38271 4.49821) (xy 100.359243 4.580686) (xy 100.343487 4.664976)
			(xy 100.335575 4.750359) (xy 95.840309 4.750359) (xy 95.832397 4.664976) (xy 95.816641 4.580686)
			(xy 95.793174 4.49821) (xy 95.762198 4.418251) (xy 95.723976 4.341491) (xy 95.678835 4.268585) (xy 95.627159 4.200156)
			(xy 95.56939 4.136786) (xy 95.50602 4.079017) (xy 95.437591 4.027341) (xy 95.364685 3.9822) (xy 95.287925 3.943978)
			(xy 95.207966 3.913002) (xy 95.12549 3.889535) (xy 95.0412 3.873779) (xy 94.955817 3.865867) (xy 94.870067 3.865867)
			(xy 94.784684 3.873779) (xy 94.700394 3.889535) (xy 94.617918 3.913002) (xy 94.537959 3.943978) (xy 94.461199 3.9822)
			(xy 94.388293 4.027341) (xy 94.319864 4.079017) (xy 94.256494 4.136786) (xy 94.198725 4.200156) (xy 94.147049 4.268585)
			(xy 94.101908 4.341491) (xy 94.063686 4.418251) (xy 94.03271 4.49821) (xy 94.009243 4.580686) (xy 93.993487 4.664976)
			(xy 93.985575 4.750359) (xy 0.509016 4.750359) (xy 0.509016 -7.78002) (xy 0.509537 -7.835789) (xy 0.517873 -7.947015)
			(xy 0.534497 -8.057308) (xy 0.559316 -8.166049) (xy 0.592193 -8.272632) (xy 0.632942 -8.37646) (xy 0.681336 -8.476953)
			(xy 0.737105 -8.573548) (xy 0.799937 -8.665705) (xy 0.86948 -8.752909) (xy 0.945345 -8.834672) (xy 1.027108 -8.910538)
			(xy 1.114312 -8.980081) (xy 1.206469 -9.042912) (xy 1.303064 -9.098682) (xy 1.403556 -9.147076) (xy 1.507384 -9.187826)
			(xy 1.613967 -9.220703) (xy 1.722708 -9.245523) (xy 1.833001 -9.262147) (xy 1.944227 -9.270482) (xy 1.999996 -9.271)
			(xy 9.10209 -9.271) (xy 9.15786 -9.270479) (xy 9.269087 -9.262144) (xy 9.37938 -9.245521) (xy 9.488123 -9.220702)
			(xy 9.594707 -9.187826) (xy 9.698536 -9.147077) (xy 9.79903 -9.098683) (xy 9.895626 -9.042915) (xy 9.987784 -8.980083)
			(xy 10.07499 -8.910541) (xy 10.156754 -8.834676) (xy 10.232621 -8.752912) (xy 10.302165 -8.665708)
			(xy 10.364999 -8.573551) (xy 10.420769 -8.476956) (xy 10.469165 -8.376463) (xy 10.509916 -8.272635)
			(xy 10.542794 -8.166052) (xy 10.567616 -8.05731) (xy 10.584241 -7.947017) (xy 10.592578 -7.83579)
			(xy 10.59307 -7.78002) (xy 10.59307 0.40005) (xy 10.593555 0.470432) (xy 10.601447 0.610976) (xy 10.617208 0.750856)
			(xy 10.640787 0.889632) (xy 10.67211 1.026868) (xy 10.711079 1.162131) (xy 10.757571 1.294997) (xy 10.811439 1.425046)
			(xy 10.872515 1.551871) (xy 10.940606 1.675072) (xy 11.015497 1.794261) (xy 11.096954 1.909063) (xy 11.184719 2.019118)
			(xy 11.278518 2.124078) (xy 11.378053 2.223614) (xy 11.483014 2.317412) (xy 11.593068 2.405178) (xy 11.707871 2.486634)
			(xy 11.82706 2.561525) (xy 11.950261 2.629616) (xy 12.077085 2.690692) (xy 12.207135 2.74456) (xy 12.340001 2.791052)
			(xy 12.475264 2.83002) (xy 12.6125 2.861343) (xy 12.751276 2.884922) (xy 12.891156 2.900683) (xy 13.0317 2.908575)
			(xy 13.102082 2.909062) (xy 81.701894 2.909062) (xy 81.772277 2.908568) (xy 81.912821 2.900676) (xy 82.052702 2.884916)
			(xy 82.191479 2.861337) (xy 82.328715 2.830015) (xy 82.46398 2.791046) (xy 82.596846 2.744555) (xy 82.726897 2.690688)
			(xy 82.853723 2.629613) (xy 82.976925 2.561522) (xy 83.096116 2.486632) (xy 83.210919 2.405176) (xy 83.320975 2.317411)
			(xy 83.425937 2.223613) (xy 83.439191 2.210359) (xy 93.985575 2.210359) (xy 93.985575 2.296109) (xy 93.993487 2.381492)
			(xy 94.009243 2.465782) (xy 94.03271 2.548258) (xy 94.063686 2.628217) (xy 94.101908 2.704977) (xy 94.147049 2.777883)
			(xy 94.198725 2.846312) (xy 94.256494 2.909682) (xy 94.319864 2.967451) (xy 94.388293 3.019127) (xy 94.461199 3.064268)
			(xy 94.537959 3.10249) (xy 94.617918 3.133466) (xy 94.700394 3.156933) (xy 94.784684 3.172689) (xy 94.870067 3.180601)
			(xy 94.955817 3.180601) (xy 95.0412 3.172689) (xy 95.12549 3.156933) (xy 95.207966 3.133466) (xy 95.287925 3.10249)
			(xy 95.364685 3.064268) (xy 95.437591 3.019127) (xy 95.493198 2.977134) (xy 98.144076 2.977134) (xy 98.144076 4.074414)
			(xy 98.144449 4.086541) (xy 98.15195 4.109607) (xy 98.166212 4.129225) (xy 98.18584 4.143474) (xy 98.20891 4.150959)
			(xy 98.221038 4.151376) (xy 98.833178 4.151376) (xy 98.837242 4.151122) (xy 98.843259 4.151051) (xy 98.855065 4.153357)
			(xy 98.86061 4.155694) (xy 98.88728 4.167632) (xy 98.893941 4.170896) (xy 98.905172 4.180573) (xy 98.909378 4.186682)
			(xy 98.926448 4.212712) (xy 98.966901 4.26002) (xy 99.01372 4.301039) (xy 99.065937 4.334921) (xy 99.122473 4.360965)
			(xy 99.182158 4.378634) (xy 99.243761 4.387561) (xy 99.274884 4.388104) (xy 99.30319 4.38765) (xy 99.359317 4.380263)
			(xy 99.414 4.365612) (xy 99.466303 4.343949) (xy 99.51533 4.315645) (xy 99.560244 4.281183) (xy 99.600275 4.241153)
			(xy 99.634738 4.19624) (xy 99.663044 4.147214) (xy 99.684709 4.094911) (xy 99.699361 4.040229) (xy 99.70675 3.984102)
			(xy 99.707192 3.955796) (xy 99.707192 3.092196) (xy 99.706769 3.063889) (xy 99.699379 3.00776) (xy 99.684725 2.953076)
			(xy 99.66306 2.900772) (xy 99.634752 2.851744) (xy 99.600287 2.806831) (xy 99.560254 2.7668) (xy 99.515339 2.732337)
			(xy 99.46631 2.704032) (xy 99.414005 2.682368) (xy 99.35932 2.667717) (xy 99.303191 2.66033) (xy 99.274884 2.659888)
			(xy 99.243508 2.660417) (xy 99.181414 2.669481) (xy 99.12128 2.687417) (xy 99.064366 2.713847) (xy 99.011866 2.74822)
			(xy 98.964879 2.789813) (xy 98.92439 2.837756) (xy 98.907346 2.864104) (xy 98.903286 2.870247) (xy 98.892314 2.880058)
			(xy 98.885756 2.883408) (xy 98.846894 2.901442) (xy 98.833178 2.900172) (xy 98.221038 2.900172) (xy 98.208914 2.900593)
			(xy 98.18585 2.908079) (xy 98.166232 2.922329) (xy 98.151981 2.941947) (xy 98.144493 2.96501) (xy 98.144076 2.977134)
			(xy 95.493198 2.977134) (xy 95.50602 2.967451) (xy 95.56939 2.909682) (xy 95.627159 2.846312) (xy 95.678835 2.777883)
			(xy 95.723976 2.704977) (xy 95.762198 2.628217) (xy 95.793174 2.548258) (xy 95.816641 2.465782) (xy 95.832397 2.381492)
			(xy 95.840309 2.296109) (xy 95.840804 2.253234) (xy 95.840309 2.210359) (xy 100.335575 2.210359)
			(xy 100.335575 2.296109) (xy 100.343487 2.381492) (xy 100.359243 2.465782) (xy 100.38271 2.548258)
			(xy 100.413686 2.628217) (xy 100.451908 2.704977) (xy 100.497049 2.777883) (xy 100.548725 2.846312)
			(xy 100.606494 2.909682) (xy 100.669864 2.967451) (xy 100.738293 3.019127) (xy 100.811199 3.064268)
			(xy 100.887959 3.10249) (xy 100.967918 3.133466) (xy 101.050394 3.156933) (xy 101.134684 3.172689)
			(xy 101.220067 3.180601) (xy 101.305817 3.180601) (xy 101.3912 3.172689) (xy 101.47549 3.156933)
			(xy 101.557966 3.133466) (xy 101.637925 3.10249) (xy 101.714685 3.064268) (xy 101.787591 3.019127)
			(xy 101.85602 2.967451) (xy 101.91939 2.909682) (xy 101.977159 2.846312) (xy 102.028835 2.777883)
			(xy 102.073976 2.704977) (xy 102.112198 2.628217) (xy 102.143174 2.548258) (xy 102.166641 2.465782)
			(xy 102.182397 2.381492) (xy 102.190309 2.296109) (xy 102.190804 2.253234) (xy 102.190309 2.210359)
			(xy 181.468255 2.210359) (xy 181.468255 2.296109) (xy 181.476167 2.381492) (xy 181.491923 2.465782)
			(xy 181.51539 2.548258) (xy 181.546366 2.628217) (xy 181.584588 2.704977) (xy 181.629729 2.777883)
			(xy 181.681405 2.846312) (xy 181.739174 2.909682) (xy 181.802544 2.967451) (xy 181.870973 3.019127)
			(xy 181.943879 3.064268) (xy 182.020639 3.10249) (xy 182.100598 3.133466) (xy 182.183074 3.156933)
			(xy 182.267364 3.172689) (xy 182.352747 3.180601) (xy 182.438497 3.180601) (xy 182.52388 3.172689)
			(xy 182.60817 3.156933) (xy 182.690646 3.133466) (xy 182.770605 3.10249) (xy 182.791278 3.092196)
			(xy 183.953912 3.092196) (xy 183.953912 3.955796) (xy 183.954338 3.984103) (xy 183.961728 4.040232)
			(xy 183.97638 4.094916) (xy 183.998046 4.14722) (xy 184.026353 4.196248) (xy 184.060817 4.241162)
			(xy 184.10085 4.281193) (xy 184.145765 4.315656) (xy 184.194794 4.343962) (xy 184.247099 4.365625)
			(xy 184.301784 4.380275) (xy 184.357913 4.387663) (xy 184.38622 4.388104) (xy 184.417684 4.387495)
			(xy 184.479947 4.378382) (xy 184.540231 4.360337) (xy 184.597262 4.333742) (xy 184.649834 4.299159)
			(xy 184.696835 4.257318) (xy 184.737273 4.209104) (xy 184.754266 4.182618) (xy 184.758313 4.176581)
			(xy 184.769143 4.166898) (xy 184.775602 4.163568) (xy 184.813702 4.14528) (xy 184.825386 4.146296)
			(xy 185.437526 4.146296) (xy 185.449639 4.145811) (xy 185.472677 4.138321) (xy 185.492275 4.124081)
			(xy 185.506517 4.104484) (xy 185.51401 4.081446) (xy 185.514488 4.069334) (xy 185.514488 3.769919)
			(xy 208.661241 3.769919) (xy 208.661241 3.855669) (xy 208.669153 3.941052) (xy 208.684909 4.025342)
			(xy 208.708376 4.107818) (xy 208.739352 4.187777) (xy 208.777574 4.264537) (xy 208.822715 4.337443)
			(xy 208.874391 4.405872) (xy 208.93216 4.469242) (xy 208.99553 4.527011) (xy 209.063959 4.578687)
			(xy 209.136865 4.623828) (xy 209.213625 4.66205) (xy 209.293584 4.693026) (xy 209.37606 4.716493)
			(xy 209.46035 4.732249) (xy 209.545733 4.740161) (xy 209.631483 4.740161) (xy 209.716866 4.732249)
			(xy 209.801156 4.716493) (xy 209.883632 4.693026) (xy 209.963591 4.66205) (xy 209.984264 4.651756)
			(xy 213.517988 4.651756) (xy 213.517988 5.515356) (xy 213.518492 5.54491) (xy 213.526541 5.603466)
			(xy 213.542487 5.660381) (xy 213.566036 5.714595) (xy 213.596747 5.765098) (xy 213.634049 5.810948)
			(xy 213.677246 5.851291) (xy 213.725535 5.885377) (xy 213.778015 5.91257) (xy 213.83371 5.932364)
			(xy 213.891581 5.94439) (xy 213.95055 5.948424) (xy 214.009519 5.94439) (xy 214.06739 5.932364) (xy 214.123085 5.91257)
			(xy 214.175565 5.885377) (xy 214.223854 5.851291) (xy 214.267051 5.810948) (xy 214.304353 5.765098)
			(xy 214.335064 5.714595) (xy 214.358613 5.660381) (xy 214.374559 5.603466) (xy 214.382608 5.54491)
			(xy 214.383112 5.515356) (xy 214.383112 4.651756) (xy 214.382608 4.622202) (xy 214.374559 4.563646)
			(xy 214.358613 4.506731) (xy 214.335064 4.452517) (xy 214.304353 4.402014) (xy 214.267051 4.356164)
			(xy 214.223854 4.315821) (xy 214.175565 4.281735) (xy 214.123085 4.254542) (xy 214.06739 4.234748)
			(xy 214.009519 4.222722) (xy 213.95055 4.218689) (xy 213.891581 4.222722) (xy 213.83371 4.234748)
			(xy 213.778015 4.254542) (xy 213.725535 4.281735) (xy 213.677246 4.315821) (xy 213.634049 4.356164)
			(xy 213.596747 4.402014) (xy 213.566036 4.452517) (xy 213.542487 4.506731) (xy 213.526541 4.563646)
			(xy 213.518492 4.622202) (xy 213.517988 4.651756) (xy 209.984264 4.651756) (xy 210.040351 4.623828)
			(xy 210.113257 4.578687) (xy 210.181686 4.527011) (xy 210.245056 4.469242) (xy 210.302825 4.405872)
			(xy 210.354501 4.337443) (xy 210.399642 4.264537) (xy 210.437864 4.187777) (xy 210.46884 4.107818)
			(xy 210.492307 4.025342) (xy 210.508063 3.941052) (xy 210.515975 3.855669) (xy 210.51647 3.812794)
			(xy 210.515975 3.769919) (xy 215.011241 3.769919) (xy 215.011241 3.855669) (xy 215.019153 3.941052)
			(xy 215.034909 4.025342) (xy 215.058376 4.107818) (xy 215.089352 4.187777) (xy 215.127574 4.264537)
			(xy 215.172715 4.337443) (xy 215.224391 4.405872) (xy 215.28216 4.469242) (xy 215.34553 4.527011)
			(xy 215.413959 4.578687) (xy 215.486865 4.623828) (xy 215.563625 4.66205) (xy 215.643584 4.693026)
			(xy 215.72606 4.716493) (xy 215.81035 4.732249) (xy 215.895733 4.740161) (xy 215.981483 4.740161)
			(xy 216.066866 4.732249) (xy 216.151156 4.716493) (xy 216.233632 4.693026) (xy 216.313591 4.66205)
			(xy 216.390351 4.623828) (xy 216.463257 4.578687) (xy 216.531686 4.527011) (xy 216.595056 4.469242)
			(xy 216.652825 4.405872) (xy 216.704501 4.337443) (xy 216.749642 4.264537) (xy 216.787864 4.187777)
			(xy 216.81884 4.107818) (xy 216.842307 4.025342) (xy 216.858063 3.941052) (xy 216.865975 3.855669)
			(xy 216.86647 3.812794) (xy 216.865975 3.769919) (xy 296.143921 3.769919) (xy 296.143921 3.855669)
			(xy 296.151833 3.941052) (xy 296.167589 4.025342) (xy 296.191056 4.107818) (xy 296.222032 4.187777)
			(xy 296.260254 4.264537) (xy 296.305395 4.337443) (xy 296.357071 4.405872) (xy 296.41484 4.469242)
			(xy 296.47821 4.527011) (xy 296.546639 4.578687) (xy 296.619545 4.623828) (xy 296.696305 4.66205)
			(xy 296.776264 4.693026) (xy 296.85874 4.716493) (xy 296.94303 4.732249) (xy 297.028413 4.740161)
			(xy 297.114163 4.740161) (xy 297.199546 4.732249) (xy 297.283836 4.716493) (xy 297.366312 4.693026)
			(xy 297.446271 4.66205) (xy 297.466944 4.651756) (xy 298.629324 4.651756) (xy 298.629324 5.515356)
			(xy 298.629828 5.54491) (xy 298.637877 5.603466) (xy 298.653823 5.660381) (xy 298.677372 5.714595)
			(xy 298.708083 5.765098) (xy 298.745385 5.810948) (xy 298.788582 5.851291) (xy 298.836871 5.885377)
			(xy 298.889351 5.91257) (xy 298.945046 5.932364) (xy 299.002917 5.94439) (xy 299.061886 5.948424)
			(xy 299.120855 5.94439) (xy 299.178726 5.932364) (xy 299.234421 5.91257) (xy 299.286901 5.885377)
			(xy 299.33519 5.851291) (xy 299.378387 5.810948) (xy 299.415689 5.765098) (xy 299.4464 5.714595)
			(xy 299.469949 5.660381) (xy 299.485895 5.603466) (xy 299.493944 5.54491) (xy 299.494448 5.515356)
			(xy 299.494448 4.651756) (xy 299.493944 4.622202) (xy 299.485895 4.563646) (xy 299.469949 4.506731)
			(xy 299.4464 4.452517) (xy 299.415689 4.402014) (xy 299.378387 4.356164) (xy 299.33519 4.315821)
			(xy 299.286901 4.281735) (xy 299.234421 4.254542) (xy 299.178726 4.234748) (xy 299.120855 4.222722)
			(xy 299.061886 4.218689) (xy 299.002917 4.222722) (xy 298.945046 4.234748) (xy 298.889351 4.254542)
			(xy 298.836871 4.281735) (xy 298.788582 4.315821) (xy 298.745385 4.356164) (xy 298.708083 4.402014)
			(xy 298.677372 4.452517) (xy 298.653823 4.506731) (xy 298.637877 4.563646) (xy 298.629828 4.622202)
			(xy 298.629324 4.651756) (xy 297.466944 4.651756) (xy 297.523031 4.623828) (xy 297.595937 4.578687)
			(xy 297.664366 4.527011) (xy 297.727736 4.469242) (xy 297.785505 4.405872) (xy 297.837181 4.337443)
			(xy 297.882322 4.264537) (xy 297.920544 4.187777) (xy 297.95152 4.107818) (xy 297.974987 4.025342)
			(xy 297.990743 3.941052) (xy 297.998655 3.855669) (xy 297.99915 3.812794) (xy 297.998655 3.769919)
			(xy 302.493921 3.769919) (xy 302.493921 3.855669) (xy 302.501833 3.941052) (xy 302.517589 4.025342)
			(xy 302.541056 4.107818) (xy 302.572032 4.187777) (xy 302.610254 4.264537) (xy 302.655395 4.337443)
			(xy 302.707071 4.405872) (xy 302.76484 4.469242) (xy 302.82821 4.527011) (xy 302.896639 4.578687)
			(xy 302.969545 4.623828) (xy 303.046305 4.66205) (xy 303.126264 4.693026) (xy 303.20874 4.716493)
			(xy 303.29303 4.732249) (xy 303.378413 4.740161) (xy 303.464163 4.740161) (xy 303.549546 4.732249)
			(xy 303.633836 4.716493) (xy 303.716312 4.693026) (xy 303.796271 4.66205) (xy 303.873031 4.623828)
			(xy 303.945937 4.578687) (xy 304.014366 4.527011) (xy 304.077736 4.469242) (xy 304.135505 4.405872)
			(xy 304.187181 4.337443) (xy 304.232322 4.264537) (xy 304.270544 4.187777) (xy 304.30152 4.107818)
			(xy 304.324987 4.025342) (xy 304.340743 3.941052) (xy 304.348655 3.855669) (xy 304.34915 3.812794)
			(xy 304.348655 3.769919) (xy 311.155321 3.769919) (xy 311.155321 3.855669) (xy 311.163233 3.941052)
			(xy 311.178989 4.025342) (xy 311.202456 4.107818) (xy 311.233432 4.187777) (xy 311.271654 4.264537)
			(xy 311.316795 4.337443) (xy 311.368471 4.405872) (xy 311.42624 4.469242) (xy 311.48961 4.527011)
			(xy 311.558039 4.578687) (xy 311.630945 4.623828) (xy 311.707705 4.66205) (xy 311.787664 4.693026)
			(xy 311.87014 4.716493) (xy 311.95443 4.732249) (xy 312.039813 4.740161) (xy 312.125563 4.740161)
			(xy 312.210946 4.732249) (xy 312.295236 4.716493) (xy 312.377712 4.693026) (xy 312.457671 4.66205)
			(xy 312.478344 4.651756) (xy 316.012068 4.651756) (xy 316.012068 5.515356) (xy 316.012572 5.54491)
			(xy 316.020621 5.603466) (xy 316.036567 5.660381) (xy 316.060116 5.714595) (xy 316.090827 5.765098)
			(xy 316.128129 5.810948) (xy 316.171326 5.851291) (xy 316.219615 5.885377) (xy 316.272095 5.91257)
			(xy 316.32779 5.932364) (xy 316.385661 5.94439) (xy 316.44463 5.948424) (xy 316.503599 5.94439) (xy 316.56147 5.932364)
			(xy 316.617165 5.91257) (xy 316.669645 5.885377) (xy 316.717934 5.851291) (xy 316.761131 5.810948)
			(xy 316.798433 5.765098) (xy 316.829144 5.714595) (xy 316.852693 5.660381) (xy 316.868639 5.603466)
			(xy 316.876688 5.54491) (xy 316.877192 5.515356) (xy 316.877192 4.651756) (xy 316.876688 4.622202)
			(xy 316.868639 4.563646) (xy 316.852693 4.506731) (xy 316.829144 4.452517) (xy 316.798433 4.402014)
			(xy 316.761131 4.356164) (xy 316.717934 4.315821) (xy 316.669645 4.281735) (xy 316.617165 4.254542)
			(xy 316.56147 4.234748) (xy 316.503599 4.222722) (xy 316.44463 4.218689) (xy 316.385661 4.222722)
			(xy 316.32779 4.234748) (xy 316.272095 4.254542) (xy 316.219615 4.281735) (xy 316.171326 4.315821)
			(xy 316.128129 4.356164) (xy 316.090827 4.402014) (xy 316.060116 4.452517) (xy 316.036567 4.506731)
			(xy 316.020621 4.563646) (xy 316.012572 4.622202) (xy 316.012068 4.651756) (xy 312.478344 4.651756)
			(xy 312.534431 4.623828) (xy 312.607337 4.578687) (xy 312.675766 4.527011) (xy 312.739136 4.469242)
			(xy 312.796905 4.405872) (xy 312.848581 4.337443) (xy 312.893722 4.264537) (xy 312.931944 4.187777)
			(xy 312.96292 4.107818) (xy 312.986387 4.025342) (xy 313.002143 3.941052) (xy 313.010055 3.855669)
			(xy 313.01055 3.812794) (xy 313.010055 3.769919) (xy 317.505321 3.769919) (xy 317.505321 3.855669)
			(xy 317.513233 3.941052) (xy 317.528989 4.025342) (xy 317.552456 4.107818) (xy 317.583432 4.187777)
			(xy 317.621654 4.264537) (xy 317.666795 4.337443) (xy 317.718471 4.405872) (xy 317.77624 4.469242)
			(xy 317.83961 4.527011) (xy 317.908039 4.578687) (xy 317.980945 4.623828) (xy 318.057705 4.66205)
			(xy 318.137664 4.693026) (xy 318.22014 4.716493) (xy 318.30443 4.732249) (xy 318.389813 4.740161)
			(xy 318.475563 4.740161) (xy 318.560946 4.732249) (xy 318.645236 4.716493) (xy 318.727712 4.693026)
			(xy 318.807671 4.66205) (xy 318.884431 4.623828) (xy 318.957337 4.578687) (xy 319.025766 4.527011)
			(xy 319.089136 4.469242) (xy 319.146905 4.405872) (xy 319.198581 4.337443) (xy 319.243722 4.264537)
			(xy 319.281944 4.187777) (xy 319.31292 4.107818) (xy 319.336387 4.025342) (xy 319.352143 3.941052)
			(xy 319.360055 3.855669) (xy 319.36055 3.812794) (xy 319.360055 3.769919) (xy 361.894107 3.769919)
			(xy 361.894107 3.855669) (xy 361.902019 3.941052) (xy 361.917775 4.025342) (xy 361.941242 4.107818)
			(xy 361.972218 4.187777) (xy 362.01044 4.264537) (xy 362.055581 4.337443) (xy 362.107257 4.405872)
			(xy 362.165026 4.469242) (xy 362.228396 4.527011) (xy 362.296825 4.578687) (xy 362.369731 4.623828)
			(xy 362.446491 4.66205) (xy 362.52645 4.693026) (xy 362.608926 4.716493) (xy 362.693216 4.732249)
			(xy 362.778599 4.740161) (xy 362.864349 4.740161) (xy 362.949732 4.732249) (xy 363.034022 4.716493)
			(xy 363.116498 4.693026) (xy 363.196457 4.66205) (xy 363.21713 4.651756) (xy 364.379764 4.651756)
			(xy 364.379764 5.515356) (xy 364.380268 5.544892) (xy 364.388312 5.603414) (xy 364.404249 5.660296)
			(xy 364.427784 5.714478) (xy 364.458477 5.764951) (xy 364.495757 5.810774) (xy 364.538929 5.851094)
			(xy 364.587189 5.88516) (xy 364.639639 5.912337) (xy 364.6953 5.932119) (xy 364.753137 5.944138)
			(xy 364.812072 5.948169) (xy 364.871007 5.944138) (xy 364.928844 5.932119) (xy 364.984505 5.912337)
			(xy 365.036955 5.88516) (xy 365.085215 5.851094) (xy 365.128387 5.810774) (xy 365.165667 5.764951)
			(xy 365.19636 5.714478) (xy 365.219895 5.660296) (xy 365.235832 5.603414) (xy 365.243876 5.544892)
			(xy 365.24438 5.515356) (xy 365.24438 4.836973) (xy 385.651997 4.836973) (xy 385.651997 4.922723)
			(xy 385.659909 5.008106) (xy 385.675665 5.092396) (xy 385.699132 5.174872) (xy 385.730108 5.254831)
			(xy 385.76833 5.331591) (xy 385.813471 5.404497) (xy 385.865147 5.472926) (xy 385.922916 5.536296)
			(xy 385.986286 5.594065) (xy 386.054715 5.645741) (xy 386.127621 5.690882) (xy 386.204381 5.729104)
			(xy 386.28434 5.76008) (xy 386.366816 5.783547) (xy 386.451106 5.799303) (xy 386.536489 5.807215)
			(xy 386.622239 5.807215) (xy 386.707622 5.799303) (xy 386.791912 5.783547) (xy 386.874388 5.76008)
			(xy 386.954347 5.729104) (xy 386.97502 5.71881) (xy 390.508744 5.71881) (xy 390.508744 6.58241) (xy 390.509248 6.611964)
			(xy 390.517297 6.67052) (xy 390.533243 6.727435) (xy 390.556792 6.781649) (xy 390.587503 6.832152)
			(xy 390.624805 6.878002) (xy 390.668002 6.918345) (xy 390.716291 6.952431) (xy 390.768771 6.979624)
			(xy 390.824466 6.999418) (xy 390.882337 7.011444) (xy 390.941306 7.015478) (xy 391.000275 7.011444)
			(xy 391.058146 6.999418) (xy 391.113841 6.979624) (xy 391.166321 6.952431) (xy 391.21461 6.918345)
			(xy 391.257807 6.878002) (xy 391.295109 6.832152) (xy 391.32582 6.781649) (xy 391.349369 6.727435)
			(xy 391.365315 6.67052) (xy 391.373364 6.611964) (xy 391.373868 6.58241) (xy 391.373868 5.71881)
			(xy 391.373364 5.689256) (xy 391.365315 5.6307) (xy 391.349369 5.573785) (xy 391.32582 5.519571)
			(xy 391.295109 5.469068) (xy 391.257807 5.423218) (xy 391.21461 5.382875) (xy 391.166321 5.348789)
			(xy 391.113841 5.321596) (xy 391.058146 5.301802) (xy 391.000275 5.289776) (xy 390.941306 5.285743)
			(xy 390.882337 5.289776) (xy 390.824466 5.301802) (xy 390.768771 5.321596) (xy 390.716291 5.348789)
			(xy 390.668002 5.382875) (xy 390.624805 5.423218) (xy 390.587503 5.469068) (xy 390.556792 5.519571)
			(xy 390.533243 5.573785) (xy 390.517297 5.6307) (xy 390.509248 5.689256) (xy 390.508744 5.71881)
			(xy 386.97502 5.71881) (xy 387.031107 5.690882) (xy 387.104013 5.645741) (xy 387.172442 5.594065)
			(xy 387.235812 5.536296) (xy 387.293581 5.472926) (xy 387.345257 5.404497) (xy 387.390398 5.331591)
			(xy 387.42862 5.254831) (xy 387.459596 5.174872) (xy 387.483063 5.092396) (xy 387.498819 5.008106)
			(xy 387.506731 4.922723) (xy 387.507226 4.879848) (xy 387.506731 4.836973) (xy 392.001997 4.836973)
			(xy 392.001997 4.922723) (xy 392.009909 5.008106) (xy 392.025665 5.092396) (xy 392.049132 5.174872)
			(xy 392.080108 5.254831) (xy 392.11833 5.331591) (xy 392.163471 5.404497) (xy 392.215147 5.472926)
			(xy 392.272916 5.536296) (xy 392.336286 5.594065) (xy 392.404715 5.645741) (xy 392.477621 5.690882)
			(xy 392.554381 5.729104) (xy 392.63434 5.76008) (xy 392.716816 5.783547) (xy 392.801106 5.799303)
			(xy 392.886489 5.807215) (xy 392.972239 5.807215) (xy 393.057622 5.799303) (xy 393.141912 5.783547)
			(xy 393.224388 5.76008) (xy 393.304347 5.729104) (xy 393.381107 5.690882) (xy 393.454013 5.645741)
			(xy 393.522442 5.594065) (xy 393.585812 5.536296) (xy 393.643581 5.472926) (xy 393.695257 5.404497)
			(xy 393.740398 5.331591) (xy 393.77862 5.254831) (xy 393.809596 5.174872) (xy 393.833063 5.092396)
			(xy 393.848819 5.008106) (xy 393.856731 4.922723) (xy 393.857226 4.879848) (xy 393.856731 4.836973)
			(xy 436.390783 4.836973) (xy 436.390783 4.922723) (xy 436.398695 5.008106) (xy 436.414451 5.092396)
			(xy 436.437918 5.174872) (xy 436.468894 5.254831) (xy 436.507116 5.331591) (xy 436.552257 5.404497)
			(xy 436.603933 5.472926) (xy 436.661702 5.536296) (xy 436.725072 5.594065) (xy 436.793501 5.645741)
			(xy 436.866407 5.690882) (xy 436.943167 5.729104) (xy 437.023126 5.76008) (xy 437.105602 5.783547)
			(xy 437.189892 5.799303) (xy 437.275275 5.807215) (xy 437.361025 5.807215) (xy 437.446408 5.799303)
			(xy 437.530698 5.783547) (xy 437.613174 5.76008) (xy 437.693133 5.729104) (xy 437.713806 5.71881)
			(xy 438.87644 5.71881) (xy 438.87644 6.58241) (xy 438.876944 6.611946) (xy 438.884988 6.670468) (xy 438.900925 6.72735)
			(xy 438.92446 6.781532) (xy 438.955153 6.832005) (xy 438.992433 6.877828) (xy 439.035605 6.918148)
			(xy 439.083865 6.952214) (xy 439.136315 6.979391) (xy 439.191976 6.999173) (xy 439.249813 7.011192)
			(xy 439.308748 7.015223) (xy 439.367683 7.011192) (xy 439.42552 6.999173) (xy 439.481181 6.979391)
			(xy 439.533631 6.952214) (xy 439.581891 6.918148) (xy 439.625063 6.877828) (xy 439.662343 6.832005)
			(xy 439.693036 6.781532) (xy 439.716571 6.72735) (xy 439.732508 6.670468) (xy 439.740552 6.611946)
			(xy 439.741056 6.58241) (xy 439.741056 5.71881) (xy 439.740552 5.689274) (xy 439.732508 5.630752)
			(xy 439.716571 5.57387) (xy 439.693036 5.519688) (xy 439.662343 5.469215) (xy 439.625063 5.423392)
			(xy 439.581891 5.383072) (xy 439.533631 5.349006) (xy 439.481181 5.321829) (xy 439.42552 5.302047)
			(xy 439.367683 5.290028) (xy 439.308748 5.285997) (xy 439.249813 5.290028) (xy 439.191976 5.302047)
			(xy 439.136315 5.321829) (xy 439.083865 5.349006) (xy 439.035605 5.383072) (xy 438.992433 5.423392)
			(xy 438.955153 5.469215) (xy 438.92446 5.519688) (xy 438.900925 5.57387) (xy 438.884988 5.630752)
			(xy 438.876944 5.689274) (xy 438.87644 5.71881) (xy 437.713806 5.71881) (xy 437.769893 5.690882)
			(xy 437.842799 5.645741) (xy 437.911228 5.594065) (xy 437.974598 5.536296) (xy 438.032367 5.472926)
			(xy 438.084043 5.404497) (xy 438.129184 5.331591) (xy 438.167406 5.254831) (xy 438.198382 5.174872)
			(xy 438.221849 5.092396) (xy 438.237605 5.008106) (xy 438.245517 4.922723) (xy 438.246012 4.879848)
			(xy 438.245517 4.836973) (xy 442.740783 4.836973) (xy 442.740783 4.922723) (xy 442.748695 5.008106)
			(xy 442.764451 5.092396) (xy 442.787918 5.174872) (xy 442.818894 5.254831) (xy 442.857116 5.331591)
			(xy 442.902257 5.404497) (xy 442.953933 5.472926) (xy 443.011702 5.536296) (xy 443.075072 5.594065)
			(xy 443.143501 5.645741) (xy 443.216407 5.690882) (xy 443.293167 5.729104) (xy 443.373126 5.76008)
			(xy 443.455602 5.783547) (xy 443.539892 5.799303) (xy 443.625275 5.807215) (xy 443.711025 5.807215)
			(xy 443.796408 5.799303) (xy 443.880698 5.783547) (xy 443.963174 5.76008) (xy 444.043133 5.729104)
			(xy 444.119893 5.690882) (xy 444.192799 5.645741) (xy 444.261228 5.594065) (xy 444.324598 5.536296)
			(xy 444.382367 5.472926) (xy 444.434043 5.404497) (xy 444.479184 5.331591) (xy 444.517406 5.254831)
			(xy 444.548382 5.174872) (xy 444.571849 5.092396) (xy 444.587605 5.008106) (xy 444.595517 4.922723)
			(xy 444.596012 4.879848) (xy 444.595517 4.836973) (xy 444.587605 4.75159) (xy 444.571849 4.6673)
			(xy 444.548382 4.584824) (xy 444.517406 4.504865) (xy 444.479184 4.428105) (xy 444.434043 4.355199)
			(xy 444.382367 4.28677) (xy 444.324598 4.2234) (xy 444.261228 4.165631) (xy 444.192799 4.113955)
			(xy 444.119893 4.068814) (xy 444.043133 4.030592) (xy 443.963174 3.999616) (xy 443.880698 3.976149)
			(xy 443.796408 3.960393) (xy 443.711025 3.952481) (xy 443.625275 3.952481) (xy 443.539892 3.960393)
			(xy 443.455602 3.976149) (xy 443.373126 3.999616) (xy 443.293167 4.030592) (xy 443.216407 4.068814)
			(xy 443.143501 4.113955) (xy 443.075072 4.165631) (xy 443.011702 4.2234) (xy 442.953933 4.28677)
			(xy 442.902257 4.355199) (xy 442.857116 4.428105) (xy 442.818894 4.504865) (xy 442.787918 4.584824)
			(xy 442.764451 4.6673) (xy 442.748695 4.75159) (xy 442.740783 4.836973) (xy 438.245517 4.836973)
			(xy 438.237605 4.75159) (xy 438.221849 4.6673) (xy 438.198382 4.584824) (xy 438.167406 4.504865)
			(xy 438.129184 4.428105) (xy 438.084043 4.355199) (xy 438.032367 4.28677) (xy 437.974598 4.2234)
			(xy 437.911228 4.165631) (xy 437.842799 4.113955) (xy 437.769893 4.068814) (xy 437.693133 4.030592)
			(xy 437.613174 3.999616) (xy 437.530698 3.976149) (xy 437.446408 3.960393) (xy 437.361025 3.952481)
			(xy 437.275275 3.952481) (xy 437.189892 3.960393) (xy 437.105602 3.976149) (xy 437.023126 3.999616)
			(xy 436.943167 4.030592) (xy 436.866407 4.068814) (xy 436.793501 4.113955) (xy 436.725072 4.165631)
			(xy 436.661702 4.2234) (xy 436.603933 4.28677) (xy 436.552257 4.355199) (xy 436.507116 4.428105)
			(xy 436.468894 4.504865) (xy 436.437918 4.584824) (xy 436.414451 4.6673) (xy 436.398695 4.75159)
			(xy 436.390783 4.836973) (xy 393.856731 4.836973) (xy 393.848819 4.75159) (xy 393.833063 4.6673)
			(xy 393.809596 4.584824) (xy 393.77862 4.504865) (xy 393.740398 4.428105) (xy 393.695257 4.355199)
			(xy 393.643581 4.28677) (xy 393.585812 4.2234) (xy 393.522442 4.165631) (xy 393.454013 4.113955)
			(xy 393.381107 4.068814) (xy 393.304347 4.030592) (xy 393.224388 3.999616) (xy 393.141912 3.976149)
			(xy 393.057622 3.960393) (xy 392.972239 3.952481) (xy 392.886489 3.952481) (xy 392.801106 3.960393)
			(xy 392.716816 3.976149) (xy 392.63434 3.999616) (xy 392.554381 4.030592) (xy 392.477621 4.068814)
			(xy 392.404715 4.113955) (xy 392.336286 4.165631) (xy 392.272916 4.2234) (xy 392.215147 4.28677)
			(xy 392.163471 4.355199) (xy 392.11833 4.428105) (xy 392.080108 4.504865) (xy 392.049132 4.584824)
			(xy 392.025665 4.6673) (xy 392.009909 4.75159) (xy 392.001997 4.836973) (xy 387.506731 4.836973)
			(xy 387.498819 4.75159) (xy 387.483063 4.6673) (xy 387.459596 4.584824) (xy 387.42862 4.504865) (xy 387.390398 4.428105)
			(xy 387.345257 4.355199) (xy 387.293581 4.28677) (xy 387.235812 4.2234) (xy 387.172442 4.165631)
			(xy 387.104013 4.113955) (xy 387.031107 4.068814) (xy 386.954347 4.030592) (xy 386.874388 3.999616)
			(xy 386.791912 3.976149) (xy 386.707622 3.960393) (xy 386.622239 3.952481) (xy 386.536489 3.952481)
			(xy 386.451106 3.960393) (xy 386.366816 3.976149) (xy 386.28434 3.999616) (xy 386.204381 4.030592)
			(xy 386.127621 4.068814) (xy 386.054715 4.113955) (xy 385.986286 4.165631) (xy 385.922916 4.2234)
			(xy 385.865147 4.28677) (xy 385.813471 4.355199) (xy 385.76833 4.428105) (xy 385.730108 4.504865)
			(xy 385.699132 4.584824) (xy 385.675665 4.6673) (xy 385.659909 4.75159) (xy 385.651997 4.836973)
			(xy 365.24438 4.836973) (xy 365.24438 4.651756) (xy 365.243876 4.62222) (xy 365.235832 4.563698)
			(xy 365.219895 4.506816) (xy 365.19636 4.452634) (xy 365.165667 4.402161) (xy 365.128387 4.356338)
			(xy 365.085215 4.316018) (xy 365.036955 4.281952) (xy 364.984505 4.254775) (xy 364.928844 4.234993)
			(xy 364.871007 4.222974) (xy 364.812072 4.218943) (xy 364.753137 4.222974) (xy 364.6953 4.234993)
			(xy 364.639639 4.254775) (xy 364.587189 4.281952) (xy 364.538929 4.316018) (xy 364.495757 4.356338)
			(xy 364.458477 4.402161) (xy 364.427784 4.452634) (xy 364.404249 4.506816) (xy 364.388312 4.563698)
			(xy 364.380268 4.62222) (xy 364.379764 4.651756) (xy 363.21713 4.651756) (xy 363.273217 4.623828)
			(xy 363.346123 4.578687) (xy 363.414552 4.527011) (xy 363.477922 4.469242) (xy 363.535691 4.405872)
			(xy 363.587367 4.337443) (xy 363.632508 4.264537) (xy 363.67073 4.187777) (xy 363.701706 4.107818)
			(xy 363.725173 4.025342) (xy 363.740929 3.941052) (xy 363.748841 3.855669) (xy 363.749336 3.812794)
			(xy 363.748841 3.769919) (xy 368.244107 3.769919) (xy 368.244107 3.855669) (xy 368.252019 3.941052)
			(xy 368.267775 4.025342) (xy 368.291242 4.107818) (xy 368.322218 4.187777) (xy 368.36044 4.264537)
			(xy 368.405581 4.337443) (xy 368.457257 4.405872) (xy 368.515026 4.469242) (xy 368.578396 4.527011)
			(xy 368.646825 4.578687) (xy 368.719731 4.623828) (xy 368.796491 4.66205) (xy 368.87645 4.693026)
			(xy 368.958926 4.716493) (xy 369.043216 4.732249) (xy 369.128599 4.740161) (xy 369.214349 4.740161)
			(xy 369.299732 4.732249) (xy 369.384022 4.716493) (xy 369.466498 4.693026) (xy 369.546457 4.66205)
			(xy 369.623217 4.623828) (xy 369.696123 4.578687) (xy 369.764552 4.527011) (xy 369.827922 4.469242)
			(xy 369.885691 4.405872) (xy 369.937367 4.337443) (xy 369.982508 4.264537) (xy 370.02073 4.187777)
			(xy 370.051706 4.107818) (xy 370.075173 4.025342) (xy 370.090929 3.941052) (xy 370.098841 3.855669)
			(xy 370.099336 3.812794) (xy 370.098841 3.769919) (xy 370.090929 3.684536) (xy 370.075173 3.600246)
			(xy 370.051706 3.51777) (xy 370.02073 3.437811) (xy 369.982508 3.361051) (xy 369.937367 3.288145)
			(xy 369.885691 3.219716) (xy 369.827922 3.156346) (xy 369.764552 3.098577) (xy 369.696123 3.046901)
			(xy 369.623217 3.00176) (xy 369.546457 2.963538) (xy 369.466498 2.932562) (xy 369.384022 2.909095)
			(xy 369.299732 2.893339) (xy 369.214349 2.885427) (xy 369.128599 2.885427) (xy 369.043216 2.893339)
			(xy 368.958926 2.909095) (xy 368.87645 2.932562) (xy 368.796491 2.963538) (xy 368.719731 3.00176)
			(xy 368.646825 3.046901) (xy 368.578396 3.098577) (xy 368.515026 3.156346) (xy 368.457257 3.219716)
			(xy 368.405581 3.288145) (xy 368.36044 3.361051) (xy 368.322218 3.437811) (xy 368.291242 3.51777)
			(xy 368.267775 3.600246) (xy 368.252019 3.684536) (xy 368.244107 3.769919) (xy 363.748841 3.769919)
			(xy 363.740929 3.684536) (xy 363.725173 3.600246) (xy 363.701706 3.51777) (xy 363.67073 3.437811)
			(xy 363.632508 3.361051) (xy 363.587367 3.288145) (xy 363.535691 3.219716) (xy 363.477922 3.156346)
			(xy 363.414552 3.098577) (xy 363.346123 3.046901) (xy 363.273217 3.00176) (xy 363.196457 2.963538)
			(xy 363.116498 2.932562) (xy 363.034022 2.909095) (xy 362.949732 2.893339) (xy 362.864349 2.885427)
			(xy 362.778599 2.885427) (xy 362.693216 2.893339) (xy 362.608926 2.909095) (xy 362.52645 2.932562)
			(xy 362.446491 2.963538) (xy 362.369731 3.00176) (xy 362.296825 3.046901) (xy 362.228396 3.098577)
			(xy 362.165026 3.156346) (xy 362.107257 3.219716) (xy 362.055581 3.288145) (xy 362.01044 3.361051)
			(xy 361.972218 3.437811) (xy 361.941242 3.51777) (xy 361.917775 3.600246) (xy 361.902019 3.684536)
			(xy 361.894107 3.769919) (xy 319.360055 3.769919) (xy 319.352143 3.684536) (xy 319.336387 3.600246)
			(xy 319.31292 3.51777) (xy 319.281944 3.437811) (xy 319.243722 3.361051) (xy 319.198581 3.288145)
			(xy 319.146905 3.219716) (xy 319.089136 3.156346) (xy 319.025766 3.098577) (xy 318.957337 3.046901)
			(xy 318.884431 3.00176) (xy 318.807671 2.963538) (xy 318.727712 2.932562) (xy 318.645236 2.909095)
			(xy 318.560946 2.893339) (xy 318.475563 2.885427) (xy 318.389813 2.885427) (xy 318.30443 2.893339)
			(xy 318.22014 2.909095) (xy 318.137664 2.932562) (xy 318.057705 2.963538) (xy 317.980945 3.00176)
			(xy 317.908039 3.046901) (xy 317.83961 3.098577) (xy 317.77624 3.156346) (xy 317.718471 3.219716)
			(xy 317.666795 3.288145) (xy 317.621654 3.361051) (xy 317.583432 3.437811) (xy 317.552456 3.51777)
			(xy 317.528989 3.600246) (xy 317.513233 3.684536) (xy 317.505321 3.769919) (xy 313.010055 3.769919)
			(xy 313.002143 3.684536) (xy 312.986387 3.600246) (xy 312.96292 3.51777) (xy 312.931944 3.437811)
			(xy 312.893722 3.361051) (xy 312.848581 3.288145) (xy 312.796905 3.219716) (xy 312.739136 3.156346)
			(xy 312.675766 3.098577) (xy 312.607337 3.046901) (xy 312.534431 3.00176) (xy 312.457671 2.963538)
			(xy 312.377712 2.932562) (xy 312.295236 2.909095) (xy 312.210946 2.893339) (xy 312.125563 2.885427)
			(xy 312.039813 2.885427) (xy 311.95443 2.893339) (xy 311.87014 2.909095) (xy 311.787664 2.932562)
			(xy 311.707705 2.963538) (xy 311.630945 3.00176) (xy 311.558039 3.046901) (xy 311.48961 3.098577)
			(xy 311.42624 3.156346) (xy 311.368471 3.219716) (xy 311.316795 3.288145) (xy 311.271654 3.361051)
			(xy 311.233432 3.437811) (xy 311.202456 3.51777) (xy 311.178989 3.600246) (xy 311.163233 3.684536)
			(xy 311.155321 3.769919) (xy 304.348655 3.769919) (xy 304.340743 3.684536) (xy 304.324987 3.600246)
			(xy 304.30152 3.51777) (xy 304.270544 3.437811) (xy 304.232322 3.361051) (xy 304.187181 3.288145)
			(xy 304.135505 3.219716) (xy 304.077736 3.156346) (xy 304.014366 3.098577) (xy 303.945937 3.046901)
			(xy 303.873031 3.00176) (xy 303.796271 2.963538) (xy 303.716312 2.932562) (xy 303.633836 2.909095)
			(xy 303.549546 2.893339) (xy 303.464163 2.885427) (xy 303.378413 2.885427) (xy 303.29303 2.893339)
			(xy 303.20874 2.909095) (xy 303.126264 2.932562) (xy 303.046305 2.963538) (xy 302.969545 3.00176)
			(xy 302.896639 3.046901) (xy 302.82821 3.098577) (xy 302.76484 3.156346) (xy 302.707071 3.219716)
			(xy 302.655395 3.288145) (xy 302.610254 3.361051) (xy 302.572032 3.437811) (xy 302.541056 3.51777)
			(xy 302.517589 3.600246) (xy 302.501833 3.684536) (xy 302.493921 3.769919) (xy 297.998655 3.769919)
			(xy 297.990743 3.684536) (xy 297.974987 3.600246) (xy 297.95152 3.51777) (xy 297.920544 3.437811)
			(xy 297.882322 3.361051) (xy 297.837181 3.288145) (xy 297.785505 3.219716) (xy 297.727736 3.156346)
			(xy 297.664366 3.098577) (xy 297.595937 3.046901) (xy 297.523031 3.00176) (xy 297.446271 2.963538)
			(xy 297.366312 2.932562) (xy 297.283836 2.909095) (xy 297.199546 2.893339) (xy 297.114163 2.885427)
			(xy 297.028413 2.885427) (xy 296.94303 2.893339) (xy 296.85874 2.909095) (xy 296.776264 2.932562)
			(xy 296.696305 2.963538) (xy 296.619545 3.00176) (xy 296.546639 3.046901) (xy 296.47821 3.098577)
			(xy 296.41484 3.156346) (xy 296.357071 3.219716) (xy 296.305395 3.288145) (xy 296.260254 3.361051)
			(xy 296.222032 3.437811) (xy 296.191056 3.51777) (xy 296.167589 3.600246) (xy 296.151833 3.684536)
			(xy 296.143921 3.769919) (xy 216.865975 3.769919) (xy 216.858063 3.684536) (xy 216.842307 3.600246)
			(xy 216.81884 3.51777) (xy 216.787864 3.437811) (xy 216.749642 3.361051) (xy 216.704501 3.288145)
			(xy 216.652825 3.219716) (xy 216.595056 3.156346) (xy 216.531686 3.098577) (xy 216.463257 3.046901)
			(xy 216.390351 3.00176) (xy 216.313591 2.963538) (xy 216.233632 2.932562) (xy 216.151156 2.909095)
			(xy 216.066866 2.893339) (xy 215.981483 2.885427) (xy 215.895733 2.885427) (xy 215.81035 2.893339)
			(xy 215.72606 2.909095) (xy 215.643584 2.932562) (xy 215.563625 2.963538) (xy 215.486865 3.00176)
			(xy 215.413959 3.046901) (xy 215.34553 3.098577) (xy 215.28216 3.156346) (xy 215.224391 3.219716)
			(xy 215.172715 3.288145) (xy 215.127574 3.361051) (xy 215.089352 3.437811) (xy 215.058376 3.51777)
			(xy 215.034909 3.600246) (xy 215.019153 3.684536) (xy 215.011241 3.769919) (xy 210.515975 3.769919)
			(xy 210.508063 3.684536) (xy 210.492307 3.600246) (xy 210.46884 3.51777) (xy 210.437864 3.437811)
			(xy 210.399642 3.361051) (xy 210.354501 3.288145) (xy 210.302825 3.219716) (xy 210.245056 3.156346)
			(xy 210.181686 3.098577) (xy 210.113257 3.046901) (xy 210.040351 3.00176) (xy 209.963591 2.963538)
			(xy 209.883632 2.932562) (xy 209.801156 2.909095) (xy 209.716866 2.893339) (xy 209.631483 2.885427)
			(xy 209.545733 2.885427) (xy 209.46035 2.893339) (xy 209.37606 2.909095) (xy 209.293584 2.932562)
			(xy 209.213625 2.963538) (xy 209.136865 3.00176) (xy 209.063959 3.046901) (xy 208.99553 3.098577)
			(xy 208.93216 3.156346) (xy 208.874391 3.219716) (xy 208.822715 3.288145) (xy 208.777574 3.361051)
			(xy 208.739352 3.437811) (xy 208.708376 3.51777) (xy 208.684909 3.600246) (xy 208.669153 3.684536)
			(xy 208.661241 3.769919) (xy 185.514488 3.769919) (xy 185.514488 2.972054) (xy 185.514028 2.95994)
			(xy 185.506531 2.936899) (xy 185.492285 2.917301) (xy 185.472683 2.90306) (xy 185.44964 2.895569)
			(xy 185.437526 2.895092) (xy 184.825386 2.895092) (xy 184.811416 2.896362) (xy 184.772808 2.878836)
			(xy 184.766211 2.875555) (xy 184.755111 2.865876) (xy 184.750964 2.859786) (xy 184.733849 2.833922)
			(xy 184.69338 2.786925) (xy 184.64661 2.746195) (xy 184.594498 2.712569) (xy 184.538115 2.686736)
			(xy 184.478618 2.669227) (xy 184.41723 2.660402) (xy 184.38622 2.659888) (xy 184.357915 2.660353)
			(xy 184.301788 2.66774) (xy 184.247106 2.68239) (xy 184.194804 2.704052) (xy 184.145776 2.732355)
			(xy 184.100863 2.766816) (xy 184.060832 2.806845) (xy 184.026369 2.851756) (xy 183.998062 2.900782)
			(xy 183.976398 2.953083) (xy 183.961745 3.007764) (xy 183.954355 3.063891) (xy 183.953912 3.092196)
			(xy 182.791278 3.092196) (xy 182.847365 3.064268) (xy 182.920271 3.019127) (xy 182.9887 2.967451)
			(xy 183.05207 2.909682) (xy 183.109839 2.846312) (xy 183.161515 2.777883) (xy 183.206656 2.704977)
			(xy 183.244878 2.628217) (xy 183.275854 2.548258) (xy 183.299321 2.465782) (xy 183.315077 2.381492)
			(xy 183.322989 2.296109) (xy 183.323484 2.253234) (xy 183.322989 2.210359) (xy 187.818255 2.210359)
			(xy 187.818255 2.296109) (xy 187.826167 2.381492) (xy 187.841923 2.465782) (xy 187.86539 2.548258)
			(xy 187.896366 2.628217) (xy 187.934588 2.704977) (xy 187.979729 2.777883) (xy 188.031405 2.846312)
			(xy 188.089174 2.909682) (xy 188.152544 2.967451) (xy 188.220973 3.019127) (xy 188.293879 3.064268)
			(xy 188.370639 3.10249) (xy 188.450598 3.133466) (xy 188.533074 3.156933) (xy 188.617364 3.172689)
			(xy 188.702747 3.180601) (xy 188.788497 3.180601) (xy 188.87388 3.172689) (xy 188.95817 3.156933)
			(xy 189.040646 3.133466) (xy 189.120605 3.10249) (xy 189.197365 3.064268) (xy 189.270271 3.019127)
			(xy 189.3387 2.967451) (xy 189.40207 2.909682) (xy 189.459839 2.846312) (xy 189.511515 2.777883)
			(xy 189.556656 2.704977) (xy 189.594878 2.628217) (xy 189.625854 2.548258) (xy 189.649321 2.465782)
			(xy 189.665077 2.381492) (xy 189.672989 2.296109) (xy 189.673484 2.253234) (xy 189.672989 2.210359)
			(xy 189.665077 2.124976) (xy 189.649321 2.040686) (xy 189.625854 1.95821) (xy 189.594878 1.878251)
			(xy 189.556656 1.801491) (xy 189.511515 1.728585) (xy 189.459839 1.660156) (xy 189.40207 1.596786)
			(xy 189.3387 1.539017) (xy 189.270271 1.487341) (xy 189.197365 1.4422) (xy 189.120605 1.403978) (xy 189.040646 1.373002)
			(xy 188.95817 1.349535) (xy 188.87388 1.333779) (xy 188.788497 1.325867) (xy 188.702747 1.325867)
			(xy 188.617364 1.333779) (xy 188.533074 1.349535) (xy 188.450598 1.373002) (xy 188.370639 1.403978)
			(xy 188.293879 1.4422) (xy 188.220973 1.487341) (xy 188.152544 1.539017) (xy 188.089174 1.596786)
			(xy 188.031405 1.660156) (xy 187.979729 1.728585) (xy 187.934588 1.801491) (xy 187.896366 1.878251)
			(xy 187.86539 1.95821) (xy 187.841923 2.040686) (xy 187.826167 2.124976) (xy 187.818255 2.210359)
			(xy 183.322989 2.210359) (xy 183.315077 2.124976) (xy 183.299321 2.040686) (xy 183.275854 1.95821)
			(xy 183.244878 1.878251) (xy 183.206656 1.801491) (xy 183.161515 1.728585) (xy 183.109839 1.660156)
			(xy 183.05207 1.596786) (xy 182.9887 1.539017) (xy 182.920271 1.487341) (xy 182.847365 1.4422) (xy 182.770605 1.403978)
			(xy 182.690646 1.373002) (xy 182.60817 1.349535) (xy 182.52388 1.333779) (xy 182.438497 1.325867)
			(xy 182.352747 1.325867) (xy 182.267364 1.333779) (xy 182.183074 1.349535) (xy 182.100598 1.373002)
			(xy 182.020639 1.403978) (xy 181.943879 1.4422) (xy 181.870973 1.487341) (xy 181.802544 1.539017)
			(xy 181.739174 1.596786) (xy 181.681405 1.660156) (xy 181.629729 1.728585) (xy 181.584588 1.801491)
			(xy 181.546366 1.878251) (xy 181.51539 1.95821) (xy 181.491923 2.040686) (xy 181.476167 2.124976)
			(xy 181.468255 2.210359) (xy 102.190309 2.210359) (xy 102.182397 2.124976) (xy 102.166641 2.040686)
			(xy 102.143174 1.95821) (xy 102.112198 1.878251) (xy 102.073976 1.801491) (xy 102.028835 1.728585)
			(xy 101.977159 1.660156) (xy 101.91939 1.596786) (xy 101.85602 1.539017) (xy 101.787591 1.487341)
			(xy 101.714685 1.4422) (xy 101.637925 1.403978) (xy 101.557966 1.373002) (xy 101.47549 1.349535)
			(xy 101.3912 1.333779) (xy 101.305817 1.325867) (xy 101.220067 1.325867) (xy 101.134684 1.333779)
			(xy 101.050394 1.349535) (xy 100.967918 1.373002) (xy 100.887959 1.403978) (xy 100.811199 1.4422)
			(xy 100.738293 1.487341) (xy 100.669864 1.539017) (xy 100.606494 1.596786) (xy 100.548725 1.660156)
			(xy 100.497049 1.728585) (xy 100.451908 1.801491) (xy 100.413686 1.878251) (xy 100.38271 1.95821)
			(xy 100.359243 2.040686) (xy 100.343487 2.124976) (xy 100.335575 2.210359) (xy 95.840309 2.210359)
			(xy 95.832397 2.124976) (xy 95.816641 2.040686) (xy 95.793174 1.95821) (xy 95.762198 1.878251) (xy 95.723976 1.801491)
			(xy 95.678835 1.728585) (xy 95.627159 1.660156) (xy 95.56939 1.596786) (xy 95.50602 1.539017) (xy 95.437591 1.487341)
			(xy 95.364685 1.4422) (xy 95.287925 1.403978) (xy 95.207966 1.373002) (xy 95.12549 1.349535) (xy 95.0412 1.333779)
			(xy 94.955817 1.325867) (xy 94.870067 1.325867) (xy 94.784684 1.333779) (xy 94.700394 1.349535) (xy 94.617918 1.373002)
			(xy 94.537959 1.403978) (xy 94.461199 1.4422) (xy 94.388293 1.487341) (xy 94.319864 1.539017) (xy 94.256494 1.596786)
			(xy 94.198725 1.660156) (xy 94.147049 1.728585) (xy 94.101908 1.801491) (xy 94.063686 1.878251) (xy 94.03271 1.95821)
			(xy 94.009243 2.040686) (xy 93.993487 2.124976) (xy 93.985575 2.210359) (xy 83.439191 2.210359) (xy 83.525475 2.124078)
			(xy 83.619275 2.019118) (xy 83.707042 1.909064) (xy 83.788501 1.794262) (xy 83.863394 1.675073) (xy 83.931487 1.551873)
			(xy 83.992565 1.425048) (xy 84.046435 1.294999) (xy 84.069209 1.229919) (xy 208.661241 1.229919)
			(xy 208.661241 1.315669) (xy 208.669153 1.401052) (xy 208.684909 1.485342) (xy 208.708376 1.567818)
			(xy 208.739352 1.647777) (xy 208.777574 1.724537) (xy 208.822715 1.797443) (xy 208.874391 1.865872)
			(xy 208.93216 1.929242) (xy 208.99553 1.987011) (xy 209.063959 2.038687) (xy 209.136865 2.083828)
			(xy 209.213625 2.12205) (xy 209.293584 2.153026) (xy 209.37606 2.176493) (xy 209.46035 2.192249)
			(xy 209.545733 2.200161) (xy 209.631483 2.200161) (xy 209.716866 2.192249) (xy 209.801156 2.176493)
			(xy 209.883632 2.153026) (xy 209.963591 2.12205) (xy 210.040351 2.083828) (xy 210.113257 2.038687)
			(xy 210.168864 1.996694) (xy 212.819996 1.996694) (xy 212.819996 3.093974) (xy 212.820529 3.106058)
			(xy 212.827973 3.12905) (xy 212.842144 3.148627) (xy 212.861661 3.16288) (xy 212.884622 3.17042)
			(xy 212.896704 3.170936) (xy 213.508844 3.170936) (xy 213.512908 3.170682) (xy 213.518925 3.170617)
			(xy 213.530731 3.172918) (xy 213.536276 3.175254) (xy 213.562946 3.187192) (xy 213.56961 3.190449)
			(xy 213.580841 3.20013) (xy 213.585044 3.206242) (xy 213.60215 3.232247) (xy 213.642596 3.279558)
			(xy 213.689408 3.32058) (xy 213.741619 3.354465) (xy 213.798149 3.380513) (xy 213.85783 3.398186)
			(xy 213.919429 3.407119) (xy 213.95055 3.407664) (xy 213.978862 3.407246) (xy 214.035 3.399852) (xy 214.089695 3.385197)
			(xy 214.142009 3.363532) (xy 214.19105 3.335226) (xy 214.235979 3.300763) (xy 214.276027 3.260734)
			(xy 214.310511 3.215822) (xy 214.33884 3.166794) (xy 214.360531 3.11449) (xy 214.375212 3.059803)
			(xy 214.382633 3.003668) (xy 214.383112 2.975356) (xy 214.383112 2.111756) (xy 214.382706 2.083439)
			(xy 214.375306 2.027289) (xy 214.360638 1.972587) (xy 214.338953 1.920268) (xy 214.310623 1.871228)
			(xy 214.276132 1.826307) (xy 214.236072 1.786274) (xy 214.191127 1.751814) (xy 214.142068 1.723517)
			(xy 214.089734 1.701868) (xy 214.035022 1.687237) (xy 213.978868 1.679875) (xy 213.95055 1.679448)
			(xy 213.919177 1.680047) (xy 213.857087 1.689101) (xy 213.796955 1.707025) (xy 213.740042 1.733445)
			(xy 213.687541 1.767806) (xy 213.640552 1.809389) (xy 213.600059 1.85732) (xy 213.583012 1.883664)
			(xy 213.578952 1.889808) (xy 213.56798 1.899619) (xy 213.561422 1.902968) (xy 213.52256 1.921002)
			(xy 213.508844 1.919732) (xy 212.896704 1.919732) (xy 212.884592 1.92012) (xy 212.861559 1.927622)
			(xy 212.841983 1.94189) (xy 212.82779 1.96152) (xy 212.820375 1.984581) (xy 212.819996 1.996694)
			(xy 210.168864 1.996694) (xy 210.181686 1.987011) (xy 210.245056 1.929242) (xy 210.302825 1.865872)
			(xy 210.354501 1.797443) (xy 210.399642 1.724537) (xy 210.437864 1.647777) (xy 210.46884 1.567818)
			(xy 210.492307 1.485342) (xy 210.508063 1.401052) (xy 210.515975 1.315669) (xy 210.51647 1.272794)
			(xy 210.515975 1.229919) (xy 215.011241 1.229919) (xy 215.011241 1.315669) (xy 215.019153 1.401052)
			(xy 215.034909 1.485342) (xy 215.058376 1.567818) (xy 215.089352 1.647777) (xy 215.127574 1.724537)
			(xy 215.172715 1.797443) (xy 215.224391 1.865872) (xy 215.28216 1.929242) (xy 215.34553 1.987011)
			(xy 215.413959 2.038687) (xy 215.486865 2.083828) (xy 215.563625 2.12205) (xy 215.643584 2.153026)
			(xy 215.72606 2.176493) (xy 215.81035 2.192249) (xy 215.895733 2.200161) (xy 215.981483 2.200161)
			(xy 216.066866 2.192249) (xy 216.151156 2.176493) (xy 216.233632 2.153026) (xy 216.313591 2.12205)
			(xy 216.390351 2.083828) (xy 216.463257 2.038687) (xy 216.531686 1.987011) (xy 216.595056 1.929242)
			(xy 216.652825 1.865872) (xy 216.704501 1.797443) (xy 216.749642 1.724537) (xy 216.787864 1.647777)
			(xy 216.81884 1.567818) (xy 216.842307 1.485342) (xy 216.858063 1.401052) (xy 216.865975 1.315669)
			(xy 216.86647 1.272794) (xy 216.865975 1.229919) (xy 296.143921 1.229919) (xy 296.143921 1.315669)
			(xy 296.151833 1.401052) (xy 296.167589 1.485342) (xy 296.191056 1.567818) (xy 296.222032 1.647777)
			(xy 296.260254 1.724537) (xy 296.305395 1.797443) (xy 296.357071 1.865872) (xy 296.41484 1.929242)
			(xy 296.47821 1.987011) (xy 296.546639 2.038687) (xy 296.619545 2.083828) (xy 296.696305 2.12205)
			(xy 296.776264 2.153026) (xy 296.85874 2.176493) (xy 296.94303 2.192249) (xy 297.028413 2.200161)
			(xy 297.114163 2.200161) (xy 297.199546 2.192249) (xy 297.283836 2.176493) (xy 297.366312 2.153026)
			(xy 297.446271 2.12205) (xy 297.466944 2.111756) (xy 298.629324 2.111756) (xy 298.629324 2.975356)
			(xy 298.629777 3.003673) (xy 298.637167 3.059822) (xy 298.651826 3.114526) (xy 298.673504 3.166846)
			(xy 298.701828 3.215888) (xy 298.736314 3.260811) (xy 298.776371 3.300846) (xy 298.821313 3.335307)
			(xy 298.870371 3.363604) (xy 298.922704 3.385252) (xy 298.977415 3.39988) (xy 299.033569 3.407239)
			(xy 299.061886 3.407664) (xy 299.093352 3.407125) (xy 299.15562 3.398002) (xy 299.215907 3.379946)
			(xy 299.272938 3.35334) (xy 299.325509 3.318745) (xy 299.372508 3.276894) (xy 299.412942 3.228669)
			(xy 299.429932 3.202178) (xy 299.433953 3.196121) (xy 299.444801 3.18645) (xy 299.451268 3.183128)
			(xy 299.489368 3.16484) (xy 299.501052 3.165856) (xy 300.113192 3.165856) (xy 300.125295 3.165378)
			(xy 300.148312 3.157887) (xy 300.167881 3.14364) (xy 300.182078 3.124035) (xy 300.189509 3.100998)
			(xy 300.1899 3.088894) (xy 300.1899 1.991614) (xy 300.189381 1.979529) (xy 300.181933 1.956536) (xy 300.167759 1.936959)
			(xy 300.148238 1.922707) (xy 300.125275 1.915167) (xy 300.113192 1.914652) (xy 299.501052 1.914652)
			(xy 299.487082 1.915922) (xy 299.448474 1.898396) (xy 299.441866 1.895135) (xy 299.430772 1.885442)
			(xy 299.42663 1.879346) (xy 299.409517 1.85348) (xy 299.369051 1.80648) (xy 299.322281 1.765748)
			(xy 299.270168 1.732121) (xy 299.213784 1.706288) (xy 299.154286 1.688781) (xy 299.092896 1.67996)
			(xy 299.061886 1.679448) (xy 299.033575 1.679887) (xy 298.977436 1.687277) (xy 298.922742 1.701929)
			(xy 298.870426 1.723591) (xy 298.821385 1.751894) (xy 298.776455 1.786354) (xy 298.736406 1.826382)
			(xy 298.701922 1.871293) (xy 298.673593 1.92032) (xy 298.651903 1.972623) (xy 298.637222 2.02731)
			(xy 298.629802 2.083445) (xy 298.629324 2.111756) (xy 297.466944 2.111756) (xy 297.523031 2.083828)
			(xy 297.595937 2.038687) (xy 297.664366 1.987011) (xy 297.727736 1.929242) (xy 297.785505 1.865872)
			(xy 297.837181 1.797443) (xy 297.882322 1.724537) (xy 297.920544 1.647777) (xy 297.95152 1.567818)
			(xy 297.974987 1.485342) (xy 297.990743 1.401052) (xy 297.998655 1.315669) (xy 297.99915 1.272794)
			(xy 297.998655 1.229919) (xy 302.493921 1.229919) (xy 302.493921 1.315669) (xy 302.501833 1.401052)
			(xy 302.517589 1.485342) (xy 302.541056 1.567818) (xy 302.572032 1.647777) (xy 302.610254 1.724537)
			(xy 302.655395 1.797443) (xy 302.707071 1.865872) (xy 302.76484 1.929242) (xy 302.82821 1.987011)
			(xy 302.896639 2.038687) (xy 302.969545 2.083828) (xy 303.046305 2.12205) (xy 303.126264 2.153026)
			(xy 303.20874 2.176493) (xy 303.29303 2.192249) (xy 303.378413 2.200161) (xy 303.464163 2.200161)
			(xy 303.549546 2.192249) (xy 303.633836 2.176493) (xy 303.716312 2.153026) (xy 303.796271 2.12205)
			(xy 303.873031 2.083828) (xy 303.945937 2.038687) (xy 304.014366 1.987011) (xy 304.077736 1.929242)
			(xy 304.135505 1.865872) (xy 304.187181 1.797443) (xy 304.232322 1.724537) (xy 304.270544 1.647777)
			(xy 304.30152 1.567818) (xy 304.324987 1.485342) (xy 304.340743 1.401052) (xy 304.348655 1.315669)
			(xy 304.34915 1.272794) (xy 304.348655 1.229919) (xy 311.155321 1.229919) (xy 311.155321 1.315669)
			(xy 311.163233 1.401052) (xy 311.178989 1.485342) (xy 311.202456 1.567818) (xy 311.233432 1.647777)
			(xy 311.271654 1.724537) (xy 311.316795 1.797443) (xy 311.368471 1.865872) (xy 311.42624 1.929242)
			(xy 311.48961 1.987011) (xy 311.558039 2.038687) (xy 311.630945 2.083828) (xy 311.707705 2.12205)
			(xy 311.787664 2.153026) (xy 311.87014 2.176493) (xy 311.95443 2.192249) (xy 312.039813 2.200161)
			(xy 312.125563 2.200161) (xy 312.210946 2.192249) (xy 312.295236 2.176493) (xy 312.377712 2.153026)
			(xy 312.457671 2.12205) (xy 312.534431 2.083828) (xy 312.607337 2.038687) (xy 312.66328 1.99644)
			(xy 315.314076 1.99644) (xy 315.314076 1.996694) (xy 315.314076 3.093974) (xy 315.31453 3.106066)
			(xy 315.321984 3.129072) (xy 315.336173 3.148655) (xy 315.355711 3.162905) (xy 315.378694 3.170431)
			(xy 315.390784 3.170936) (xy 316.002924 3.170936) (xy 316.014997 3.170456) (xy 316.03796 3.162991)
			(xy 316.057494 3.148797) (xy 316.071689 3.129264) (xy 316.079156 3.106301) (xy 316.079632 3.094228)
			(xy 316.079632 3.093974) (xy 316.079632 1.996694) (xy 316.079197 1.984601) (xy 316.071735 1.961596)
			(xy 316.057541 1.942014) (xy 316.037999 1.927764) (xy 316.015015 1.920238) (xy 316.002924 1.919732)
			(xy 315.390784 1.919732) (xy 315.378696 1.9201) (xy 315.355706 1.927576) (xy 315.336153 1.941793)
			(xy 315.321951 1.961357) (xy 315.314491 1.984352) (xy 315.314076 1.99644) (xy 312.66328 1.99644)
			(xy 312.675766 1.987011) (xy 312.739136 1.929242) (xy 312.796905 1.865872) (xy 312.848581 1.797443)
			(xy 312.893722 1.724537) (xy 312.931944 1.647777) (xy 312.96292 1.567818) (xy 312.986387 1.485342)
			(xy 313.002143 1.401052) (xy 313.010055 1.315669) (xy 313.01055 1.272794) (xy 313.010055 1.229919)
			(xy 317.505321 1.229919) (xy 317.505321 1.315669) (xy 317.513233 1.401052) (xy 317.528989 1.485342)
			(xy 317.552456 1.567818) (xy 317.583432 1.647777) (xy 317.621654 1.724537) (xy 317.666795 1.797443)
			(xy 317.718471 1.865872) (xy 317.77624 1.929242) (xy 317.83961 1.987011) (xy 317.908039 2.038687)
			(xy 317.980945 2.083828) (xy 318.057705 2.12205) (xy 318.137664 2.153026) (xy 318.22014 2.176493)
			(xy 318.30443 2.192249) (xy 318.389813 2.200161) (xy 318.475563 2.200161) (xy 318.560946 2.192249)
			(xy 318.645236 2.176493) (xy 318.727712 2.153026) (xy 318.807671 2.12205) (xy 318.884431 2.083828)
			(xy 318.957337 2.038687) (xy 319.025766 1.987011) (xy 319.089136 1.929242) (xy 319.146905 1.865872)
			(xy 319.198581 1.797443) (xy 319.243722 1.724537) (xy 319.281944 1.647777) (xy 319.31292 1.567818)
			(xy 319.336387 1.485342) (xy 319.352143 1.401052) (xy 319.360055 1.315669) (xy 319.36055 1.272794)
			(xy 319.360055 1.229919) (xy 361.894107 1.229919) (xy 361.894107 1.315669) (xy 361.902019 1.401052)
			(xy 361.917775 1.485342) (xy 361.941242 1.567818) (xy 361.972218 1.647777) (xy 362.01044 1.724537)
			(xy 362.055581 1.797443) (xy 362.107257 1.865872) (xy 362.165026 1.929242) (xy 362.228396 1.987011)
			(xy 362.296825 2.038687) (xy 362.369731 2.083828) (xy 362.446491 2.12205) (xy 362.52645 2.153026)
			(xy 362.608926 2.176493) (xy 362.693216 2.192249) (xy 362.778599 2.200161) (xy 362.864349 2.200161)
			(xy 362.949732 2.192249) (xy 363.034022 2.176493) (xy 363.116498 2.153026) (xy 363.196457 2.12205)
			(xy 363.273217 2.083828) (xy 363.346123 2.038687) (xy 363.408457 1.991614) (xy 365.174276 1.991614)
			(xy 365.174276 3.088894) (xy 365.174666 3.10102) (xy 365.182161 3.124085) (xy 365.196419 3.143704)
			(xy 365.216043 3.157954) (xy 365.239112 3.165439) (xy 365.251238 3.165856) (xy 365.863378 3.165856)
			(xy 365.8755 3.165421) (xy 365.898559 3.157934) (xy 365.918175 3.143687) (xy 365.932427 3.124074)
			(xy 365.939919 3.101016) (xy 365.94034 3.088894) (xy 365.94034 1.991614) (xy 365.939928 1.97949)
			(xy 365.932437 1.956428) (xy 365.918184 1.936811) (xy 365.898565 1.92256) (xy 365.875502 1.915071)
			(xy 365.863378 1.914652) (xy 365.251238 1.914652) (xy 365.239116 1.915092) (xy 365.216056 1.922576)
			(xy 365.196439 1.936822) (xy 365.182187 1.956434) (xy 365.174696 1.979492) (xy 365.174276 1.991614)
			(xy 363.408457 1.991614) (xy 363.414552 1.987011) (xy 363.477922 1.929242) (xy 363.535691 1.865872)
			(xy 363.587367 1.797443) (xy 363.632508 1.724537) (xy 363.67073 1.647777) (xy 363.701706 1.567818)
			(xy 363.725173 1.485342) (xy 363.740929 1.401052) (xy 363.748841 1.315669) (xy 363.749336 1.272794)
			(xy 363.748841 1.229919) (xy 368.244107 1.229919) (xy 368.244107 1.315669) (xy 368.252019 1.401052)
			(xy 368.267775 1.485342) (xy 368.291242 1.567818) (xy 368.322218 1.647777) (xy 368.36044 1.724537)
			(xy 368.405581 1.797443) (xy 368.457257 1.865872) (xy 368.515026 1.929242) (xy 368.578396 1.987011)
			(xy 368.646825 2.038687) (xy 368.719731 2.083828) (xy 368.796491 2.12205) (xy 368.87645 2.153026)
			(xy 368.958926 2.176493) (xy 369.043216 2.192249) (xy 369.128599 2.200161) (xy 369.214349 2.200161)
			(xy 369.299732 2.192249) (xy 369.384022 2.176493) (xy 369.466498 2.153026) (xy 369.546457 2.12205)
			(xy 369.623217 2.083828) (xy 369.696123 2.038687) (xy 369.764552 1.987011) (xy 369.827922 1.929242)
			(xy 369.885691 1.865872) (xy 369.937367 1.797443) (xy 369.982508 1.724537) (xy 370.02073 1.647777)
			(xy 370.051706 1.567818) (xy 370.075173 1.485342) (xy 370.090929 1.401052) (xy 370.098841 1.315669)
			(xy 370.099336 1.272794) (xy 370.098841 1.229919) (xy 370.090929 1.144536) (xy 370.075173 1.060246)
			(xy 370.051706 0.97777) (xy 370.02073 0.897811) (xy 369.982508 0.821051) (xy 369.937367 0.748145)
			(xy 369.885691 0.679716) (xy 369.827922 0.616346) (xy 369.764552 0.558577) (xy 369.696123 0.506901)
			(xy 369.623217 0.46176) (xy 369.546457 0.423538) (xy 369.466498 0.392562) (xy 369.384022 0.369095)
			(xy 369.299732 0.353339) (xy 369.214349 0.345427) (xy 369.128599 0.345427) (xy 369.043216 0.353339)
			(xy 368.958926 0.369095) (xy 368.87645 0.392562) (xy 368.796491 0.423538) (xy 368.719731 0.46176)
			(xy 368.646825 0.506901) (xy 368.578396 0.558577) (xy 368.515026 0.616346) (xy 368.457257 0.679716)
			(xy 368.405581 0.748145) (xy 368.36044 0.821051) (xy 368.322218 0.897811) (xy 368.291242 0.97777)
			(xy 368.267775 1.060246) (xy 368.252019 1.144536) (xy 368.244107 1.229919) (xy 363.748841 1.229919)
			(xy 363.740929 1.144536) (xy 363.725173 1.060246) (xy 363.701706 0.97777) (xy 363.67073 0.897811)
			(xy 363.632508 0.821051) (xy 363.587367 0.748145) (xy 363.535691 0.679716) (xy 363.477922 0.616346)
			(xy 363.414552 0.558577) (xy 363.346123 0.506901) (xy 363.273217 0.46176) (xy 363.196457 0.423538)
			(xy 363.116498 0.392562) (xy 363.034022 0.369095) (xy 362.949732 0.353339) (xy 362.864349 0.345427)
			(xy 362.778599 0.345427) (xy 362.693216 0.353339) (xy 362.608926 0.369095) (xy 362.52645 0.392562)
			(xy 362.446491 0.423538) (xy 362.369731 0.46176) (xy 362.296825 0.506901) (xy 362.228396 0.558577)
			(xy 362.165026 0.616346) (xy 362.107257 0.679716) (xy 362.055581 0.748145) (xy 362.01044 0.821051)
			(xy 361.972218 0.897811) (xy 361.941242 0.97777) (xy 361.917775 1.060246) (xy 361.902019 1.144536)
			(xy 361.894107 1.229919) (xy 319.360055 1.229919) (xy 319.352143 1.144536) (xy 319.336387 1.060246)
			(xy 319.31292 0.97777) (xy 319.281944 0.897811) (xy 319.243722 0.821051) (xy 319.198581 0.748145)
			(xy 319.146905 0.679716) (xy 319.089136 0.616346) (xy 319.025766 0.558577) (xy 318.957337 0.506901)
			(xy 318.884431 0.46176) (xy 318.807671 0.423538) (xy 318.727712 0.392562) (xy 318.645236 0.369095)
			(xy 318.560946 0.353339) (xy 318.475563 0.345427) (xy 318.389813 0.345427) (xy 318.30443 0.353339)
			(xy 318.22014 0.369095) (xy 318.137664 0.392562) (xy 318.057705 0.423538) (xy 317.980945 0.46176)
			(xy 317.908039 0.506901) (xy 317.83961 0.558577) (xy 317.77624 0.616346) (xy 317.718471 0.679716)
			(xy 317.666795 0.748145) (xy 317.621654 0.821051) (xy 317.583432 0.897811) (xy 317.552456 0.97777)
			(xy 317.528989 1.060246) (xy 317.513233 1.144536) (xy 317.505321 1.229919) (xy 313.010055 1.229919)
			(xy 313.002143 1.144536) (xy 312.986387 1.060246) (xy 312.96292 0.97777) (xy 312.931944 0.897811)
			(xy 312.893722 0.821051) (xy 312.848581 0.748145) (xy 312.796905 0.679716) (xy 312.739136 0.616346)
			(xy 312.675766 0.558577) (xy 312.607337 0.506901) (xy 312.534431 0.46176) (xy 312.457671 0.423538)
			(xy 312.377712 0.392562) (xy 312.295236 0.369095) (xy 312.210946 0.353339) (xy 312.125563 0.345427)
			(xy 312.039813 0.345427) (xy 311.95443 0.353339) (xy 311.87014 0.369095) (xy 311.787664 0.392562)
			(xy 311.707705 0.423538) (xy 311.630945 0.46176) (xy 311.558039 0.506901) (xy 311.48961 0.558577)
			(xy 311.42624 0.616346) (xy 311.368471 0.679716) (xy 311.316795 0.748145) (xy 311.271654 0.821051)
			(xy 311.233432 0.897811) (xy 311.202456 0.97777) (xy 311.178989 1.060246) (xy 311.163233 1.144536)
			(xy 311.155321 1.229919) (xy 304.348655 1.229919) (xy 304.340743 1.144536) (xy 304.324987 1.060246)
			(xy 304.30152 0.97777) (xy 304.270544 0.897811) (xy 304.232322 0.821051) (xy 304.187181 0.748145)
			(xy 304.135505 0.679716) (xy 304.077736 0.616346) (xy 304.014366 0.558577) (xy 303.945937 0.506901)
			(xy 303.873031 0.46176) (xy 303.796271 0.423538) (xy 303.716312 0.392562) (xy 303.633836 0.369095)
			(xy 303.549546 0.353339) (xy 303.464163 0.345427) (xy 303.378413 0.345427) (xy 303.29303 0.353339)
			(xy 303.20874 0.369095) (xy 303.126264 0.392562) (xy 303.046305 0.423538) (xy 302.969545 0.46176)
			(xy 302.896639 0.506901) (xy 302.82821 0.558577) (xy 302.76484 0.616346) (xy 302.707071 0.679716)
			(xy 302.655395 0.748145) (xy 302.610254 0.821051) (xy 302.572032 0.897811) (xy 302.541056 0.97777)
			(xy 302.517589 1.060246) (xy 302.501833 1.144536) (xy 302.493921 1.229919) (xy 297.998655 1.229919)
			(xy 297.990743 1.144536) (xy 297.974987 1.060246) (xy 297.95152 0.97777) (xy 297.920544 0.897811)
			(xy 297.882322 0.821051) (xy 297.837181 0.748145) (xy 297.785505 0.679716) (xy 297.727736 0.616346)
			(xy 297.664366 0.558577) (xy 297.595937 0.506901) (xy 297.523031 0.46176) (xy 297.446271 0.423538)
			(xy 297.366312 0.392562) (xy 297.283836 0.369095) (xy 297.199546 0.353339) (xy 297.114163 0.345427)
			(xy 297.028413 0.345427) (xy 296.94303 0.353339) (xy 296.85874 0.369095) (xy 296.776264 0.392562)
			(xy 296.696305 0.423538) (xy 296.619545 0.46176) (xy 296.546639 0.506901) (xy 296.47821 0.558577)
			(xy 296.41484 0.616346) (xy 296.357071 0.679716) (xy 296.305395 0.748145) (xy 296.260254 0.821051)
			(xy 296.222032 0.897811) (xy 296.191056 0.97777) (xy 296.167589 1.060246) (xy 296.151833 1.144536)
			(xy 296.143921 1.229919) (xy 216.865975 1.229919) (xy 216.858063 1.144536) (xy 216.842307 1.060246)
			(xy 216.81884 0.97777) (xy 216.787864 0.897811) (xy 216.749642 0.821051) (xy 216.704501 0.748145)
			(xy 216.652825 0.679716) (xy 216.595056 0.616346) (xy 216.531686 0.558577) (xy 216.463257 0.506901)
			(xy 216.390351 0.46176) (xy 216.313591 0.423538) (xy 216.233632 0.392562) (xy 216.151156 0.369095)
			(xy 216.066866 0.353339) (xy 215.981483 0.345427) (xy 215.895733 0.345427) (xy 215.81035 0.353339)
			(xy 215.72606 0.369095) (xy 215.643584 0.392562) (xy 215.563625 0.423538) (xy 215.486865 0.46176)
			(xy 215.413959 0.506901) (xy 215.34553 0.558577) (xy 215.28216 0.616346) (xy 215.224391 0.679716)
			(xy 215.172715 0.748145) (xy 215.127574 0.821051) (xy 215.089352 0.897811) (xy 215.058376 0.97777)
			(xy 215.034909 1.060246) (xy 215.019153 1.144536) (xy 215.011241 1.229919) (xy 210.515975 1.229919)
			(xy 210.508063 1.144536) (xy 210.492307 1.060246) (xy 210.46884 0.97777) (xy 210.437864 0.897811)
			(xy 210.399642 0.821051) (xy 210.354501 0.748145) (xy 210.302825 0.679716) (xy 210.245056 0.616346)
			(xy 210.181686 0.558577) (xy 210.113257 0.506901) (xy 210.040351 0.46176) (xy 209.963591 0.423538)
			(xy 209.883632 0.392562) (xy 209.801156 0.369095) (xy 209.716866 0.353339) (xy 209.631483 0.345427)
			(xy 209.545733 0.345427) (xy 209.46035 0.353339) (xy 209.37606 0.369095) (xy 209.293584 0.392562)
			(xy 209.213625 0.423538) (xy 209.136865 0.46176) (xy 209.063959 0.506901) (xy 208.99553 0.558577)
			(xy 208.93216 0.616346) (xy 208.874391 0.679716) (xy 208.822715 0.748145) (xy 208.777574 0.821051)
			(xy 208.739352 0.897811) (xy 208.708376 0.97777) (xy 208.684909 1.060246) (xy 208.669153 1.144536)
			(xy 208.661241 1.229919) (xy 84.069209 1.229919) (xy 84.092929 1.162133) (xy 84.131901 1.02687) (xy 84.163226 0.889634)
			(xy 84.186808 0.750857) (xy 84.202571 0.610977) (xy 84.210467 0.470433) (xy 84.210906 0.40005) (xy 84.210906 -1.310081)
			(xy 208.661241 -1.310081) (xy 208.661241 -1.224331) (xy 208.669153 -1.138948) (xy 208.684909 -1.054658)
			(xy 208.708376 -0.972182) (xy 208.739352 -0.892223) (xy 208.777574 -0.815463) (xy 208.822715 -0.742557)
			(xy 208.874391 -0.674128) (xy 208.93216 -0.610758) (xy 208.99553 -0.552989) (xy 209.063959 -0.501313)
			(xy 209.136865 -0.456172) (xy 209.213625 -0.41795) (xy 209.293584 -0.386974) (xy 209.37606 -0.363507)
			(xy 209.46035 -0.347751) (xy 209.545733 -0.339839) (xy 209.631483 -0.339839) (xy 209.716866 -0.347751)
			(xy 209.801156 -0.363507) (xy 209.883632 -0.386974) (xy 209.963591 -0.41795) (xy 210.040351 -0.456172)
			(xy 210.113257 -0.501313) (xy 210.181686 -0.552989) (xy 210.245056 -0.610758) (xy 210.302825 -0.674128)
			(xy 210.354501 -0.742557) (xy 210.399642 -0.815463) (xy 210.437864 -0.892223) (xy 210.46884 -0.972182)
			(xy 210.492307 -1.054658) (xy 210.508063 -1.138948) (xy 210.515975 -1.224331) (xy 210.51647 -1.267206)
			(xy 210.515975 -1.310081) (xy 215.011241 -1.310081) (xy 215.011241 -1.224331) (xy 215.019153 -1.138948)
			(xy 215.034909 -1.054658) (xy 215.058376 -0.972182) (xy 215.089352 -0.892223) (xy 215.127574 -0.815463)
			(xy 215.172715 -0.742557) (xy 215.224391 -0.674128) (xy 215.28216 -0.610758) (xy 215.34553 -0.552989)
			(xy 215.413959 -0.501313) (xy 215.486865 -0.456172) (xy 215.563625 -0.41795) (xy 215.643584 -0.386974)
			(xy 215.72606 -0.363507) (xy 215.81035 -0.347751) (xy 215.895733 -0.339839) (xy 215.981483 -0.339839)
			(xy 216.066866 -0.347751) (xy 216.151156 -0.363507) (xy 216.233632 -0.386974) (xy 216.313591 -0.41795)
			(xy 216.390351 -0.456172) (xy 216.463257 -0.501313) (xy 216.531686 -0.552989) (xy 216.595056 -0.610758)
			(xy 216.652825 -0.674128) (xy 216.704501 -0.742557) (xy 216.749642 -0.815463) (xy 216.787864 -0.892223)
			(xy 216.81884 -0.972182) (xy 216.842307 -1.054658) (xy 216.858063 -1.138948) (xy 216.865975 -1.224331)
			(xy 216.86647 -1.267206) (xy 216.865975 -1.310081) (xy 296.143921 -1.310081) (xy 296.143921 -1.224331)
			(xy 296.151833 -1.138948) (xy 296.167589 -1.054658) (xy 296.191056 -0.972182) (xy 296.222032 -0.892223)
			(xy 296.260254 -0.815463) (xy 296.305395 -0.742557) (xy 296.357071 -0.674128) (xy 296.41484 -0.610758)
			(xy 296.47821 -0.552989) (xy 296.546639 -0.501313) (xy 296.619545 -0.456172) (xy 296.696305 -0.41795)
			(xy 296.776264 -0.386974) (xy 296.85874 -0.363507) (xy 296.94303 -0.347751) (xy 297.028413 -0.339839)
			(xy 297.114163 -0.339839) (xy 297.199546 -0.347751) (xy 297.283836 -0.363507) (xy 297.366312 -0.386974)
			(xy 297.446271 -0.41795) (xy 297.523031 -0.456172) (xy 297.595937 -0.501313) (xy 297.664366 -0.552989)
			(xy 297.727736 -0.610758) (xy 297.785505 -0.674128) (xy 297.837181 -0.742557) (xy 297.882322 -0.815463)
			(xy 297.920544 -0.892223) (xy 297.95152 -0.972182) (xy 297.974987 -1.054658) (xy 297.990743 -1.138948)
			(xy 297.998655 -1.224331) (xy 297.99915 -1.267206) (xy 297.998655 -1.310081) (xy 302.493921 -1.310081)
			(xy 302.493921 -1.224331) (xy 302.501833 -1.138948) (xy 302.517589 -1.054658) (xy 302.541056 -0.972182)
			(xy 302.572032 -0.892223) (xy 302.610254 -0.815463) (xy 302.655395 -0.742557) (xy 302.707071 -0.674128)
			(xy 302.76484 -0.610758) (xy 302.82821 -0.552989) (xy 302.896639 -0.501313) (xy 302.969545 -0.456172)
			(xy 303.046305 -0.41795) (xy 303.126264 -0.386974) (xy 303.20874 -0.363507) (xy 303.29303 -0.347751)
			(xy 303.378413 -0.339839) (xy 303.464163 -0.339839) (xy 303.549546 -0.347751) (xy 303.633836 -0.363507)
			(xy 303.716312 -0.386974) (xy 303.796271 -0.41795) (xy 303.873031 -0.456172) (xy 303.945937 -0.501313)
			(xy 304.014366 -0.552989) (xy 304.077736 -0.610758) (xy 304.135505 -0.674128) (xy 304.187181 -0.742557)
			(xy 304.232322 -0.815463) (xy 304.270544 -0.892223) (xy 304.30152 -0.972182) (xy 304.324987 -1.054658)
			(xy 304.340743 -1.138948) (xy 304.348655 -1.224331) (xy 304.34915 -1.267206) (xy 304.348655 -1.310081)
			(xy 311.155321 -1.310081) (xy 311.155321 -1.224331) (xy 311.163233 -1.138948) (xy 311.178989 -1.054658)
			(xy 311.202456 -0.972182) (xy 311.233432 -0.892223) (xy 311.271654 -0.815463) (xy 311.316795 -0.742557)
			(xy 311.368471 -0.674128) (xy 311.42624 -0.610758) (xy 311.48961 -0.552989) (xy 311.558039 -0.501313)
			(xy 311.630945 -0.456172) (xy 311.707705 -0.41795) (xy 311.787664 -0.386974) (xy 311.87014 -0.363507)
			(xy 311.95443 -0.347751) (xy 312.039813 -0.339839) (xy 312.125563 -0.339839) (xy 312.210946 -0.347751)
			(xy 312.295236 -0.363507) (xy 312.377712 -0.386974) (xy 312.457671 -0.41795) (xy 312.478344 -0.428244)
			(xy 316.012068 -0.428244) (xy 316.012068 0.435356) (xy 316.012572 0.46491) (xy 316.020621 0.523466)
			(xy 316.036567 0.580381) (xy 316.060116 0.634595) (xy 316.090827 0.685098) (xy 316.128129 0.730948)
			(xy 316.171326 0.771291) (xy 316.219615 0.805377) (xy 316.272095 0.83257) (xy 316.32779 0.852364)
			(xy 316.385661 0.86439) (xy 316.44463 0.868424) (xy 316.503599 0.86439) (xy 316.56147 0.852364) (xy 316.617165 0.83257)
			(xy 316.669645 0.805377) (xy 316.717934 0.771291) (xy 316.761131 0.730948) (xy 316.798433 0.685098)
			(xy 316.829144 0.634595) (xy 316.852693 0.580381) (xy 316.868639 0.523466) (xy 316.876688 0.46491)
			(xy 316.877192 0.435356) (xy 316.877192 -0.428244) (xy 316.876688 -0.457798) (xy 316.868639 -0.516354)
			(xy 316.852693 -0.573269) (xy 316.829144 -0.627483) (xy 316.798433 -0.677986) (xy 316.761131 -0.723836)
			(xy 316.717934 -0.764179) (xy 316.669645 -0.798265) (xy 316.617165 -0.825458) (xy 316.56147 -0.845252)
			(xy 316.503599 -0.857278) (xy 316.44463 -0.861312) (xy 316.385661 -0.857278) (xy 316.32779 -0.845252)
			(xy 316.272095 -0.825458) (xy 316.219615 -0.798265) (xy 316.171326 -0.764179) (xy 316.128129 -0.723836)
			(xy 316.090827 -0.677986) (xy 316.060116 -0.627483) (xy 316.036567 -0.573269) (xy 316.020621 -0.516354)
			(xy 316.012572 -0.457798) (xy 316.012068 -0.428244) (xy 312.478344 -0.428244) (xy 312.534431 -0.456172)
			(xy 312.607337 -0.501313) (xy 312.675766 -0.552989) (xy 312.739136 -0.610758) (xy 312.796905 -0.674128)
			(xy 312.848581 -0.742557) (xy 312.893722 -0.815463) (xy 312.931944 -0.892223) (xy 312.96292 -0.972182)
			(xy 312.986387 -1.054658) (xy 313.002143 -1.138948) (xy 313.010055 -1.224331) (xy 313.01055 -1.267206)
			(xy 313.010055 -1.310081) (xy 317.505321 -1.310081) (xy 317.505321 -1.224331) (xy 317.513233 -1.138948)
			(xy 317.528989 -1.054658) (xy 317.552456 -0.972182) (xy 317.583432 -0.892223) (xy 317.621654 -0.815463)
			(xy 317.666795 -0.742557) (xy 317.718471 -0.674128) (xy 317.77624 -0.610758) (xy 317.83961 -0.552989)
			(xy 317.908039 -0.501313) (xy 317.980945 -0.456172) (xy 318.057705 -0.41795) (xy 318.137664 -0.386974)
			(xy 318.22014 -0.363507) (xy 318.30443 -0.347751) (xy 318.389813 -0.339839) (xy 318.475563 -0.339839)
			(xy 318.560946 -0.347751) (xy 318.645236 -0.363507) (xy 318.727712 -0.386974) (xy 318.807671 -0.41795)
			(xy 318.884431 -0.456172) (xy 318.957337 -0.501313) (xy 319.025766 -0.552989) (xy 319.089136 -0.610758)
			(xy 319.146905 -0.674128) (xy 319.198581 -0.742557) (xy 319.243722 -0.815463) (xy 319.281944 -0.892223)
			(xy 319.31292 -0.972182) (xy 319.336387 -1.054658) (xy 319.352143 -1.138948) (xy 319.360055 -1.224331)
			(xy 319.36055 -1.267206) (xy 319.360055 -1.310081) (xy 361.894107 -1.310081) (xy 361.894107 -1.224331)
			(xy 361.902019 -1.138948) (xy 361.917775 -1.054658) (xy 361.941242 -0.972182) (xy 361.972218 -0.892223)
			(xy 362.01044 -0.815463) (xy 362.055581 -0.742557) (xy 362.107257 -0.674128) (xy 362.165026 -0.610758)
			(xy 362.228396 -0.552989) (xy 362.296825 -0.501313) (xy 362.369731 -0.456172) (xy 362.446491 -0.41795)
			(xy 362.52645 -0.386974) (xy 362.608926 -0.363507) (xy 362.693216 -0.347751) (xy 362.778599 -0.339839)
			(xy 362.864349 -0.339839) (xy 362.949732 -0.347751) (xy 363.034022 -0.363507) (xy 363.116498 -0.386974)
			(xy 363.196457 -0.41795) (xy 363.21713 -0.428244) (xy 364.379764 -0.428244) (xy 364.379764 0.435356)
			(xy 364.380268 0.464892) (xy 364.388312 0.523414) (xy 364.404249 0.580296) (xy 364.427784 0.634478)
			(xy 364.458477 0.684951) (xy 364.495757 0.730774) (xy 364.538929 0.771094) (xy 364.587189 0.80516)
			(xy 364.639639 0.832337) (xy 364.6953 0.852119) (xy 364.753137 0.864138) (xy 364.812072 0.868169)
			(xy 364.871007 0.864138) (xy 364.928844 0.852119) (xy 364.984505 0.832337) (xy 365.036955 0.80516)
			(xy 365.085215 0.771094) (xy 365.128387 0.730774) (xy 365.165667 0.684951) (xy 365.19636 0.634478)
			(xy 365.219895 0.580296) (xy 365.235832 0.523414) (xy 365.243876 0.464892) (xy 365.24438 0.435356)
			(xy 365.24438 -0.428244) (xy 365.243876 -0.45778) (xy 365.235832 -0.516302) (xy 365.219895 -0.573184)
			(xy 365.19636 -0.627366) (xy 365.165667 -0.677839) (xy 365.128387 -0.723662) (xy 365.085215 -0.763982)
			(xy 365.036955 -0.798048) (xy 364.984505 -0.825225) (xy 364.928844 -0.845007) (xy 364.871007 -0.857026)
			(xy 364.812072 -0.861057) (xy 364.753137 -0.857026) (xy 364.6953 -0.845007) (xy 364.639639 -0.825225)
			(xy 364.587189 -0.798048) (xy 364.538929 -0.763982) (xy 364.495757 -0.723662) (xy 364.458477 -0.677839)
			(xy 364.427784 -0.627366) (xy 364.404249 -0.573184) (xy 364.388312 -0.516302) (xy 364.380268 -0.45778)
			(xy 364.379764 -0.428244) (xy 363.21713 -0.428244) (xy 363.273217 -0.456172) (xy 363.346123 -0.501313)
			(xy 363.414552 -0.552989) (xy 363.477922 -0.610758) (xy 363.535691 -0.674128) (xy 363.587367 -0.742557)
			(xy 363.632508 -0.815463) (xy 363.67073 -0.892223) (xy 363.701706 -0.972182) (xy 363.725173 -1.054658)
			(xy 363.740929 -1.138948) (xy 363.748841 -1.224331) (xy 363.749336 -1.267206) (xy 363.748841 -1.310081)
			(xy 368.244107 -1.310081) (xy 368.244107 -1.224331) (xy 368.252019 -1.138948) (xy 368.267775 -1.054658)
			(xy 368.291242 -0.972182) (xy 368.322218 -0.892223) (xy 368.36044 -0.815463) (xy 368.405581 -0.742557)
			(xy 368.457257 -0.674128) (xy 368.515026 -0.610758) (xy 368.578396 -0.552989) (xy 368.646825 -0.501313)
			(xy 368.719731 -0.456172) (xy 368.796491 -0.41795) (xy 368.87645 -0.386974) (xy 368.958926 -0.363507)
			(xy 369.043216 -0.347751) (xy 369.128599 -0.339839) (xy 369.214349 -0.339839) (xy 369.299732 -0.347751)
			(xy 369.384022 -0.363507) (xy 369.466498 -0.386974) (xy 369.546457 -0.41795) (xy 369.623217 -0.456172)
			(xy 369.696123 -0.501313) (xy 369.764552 -0.552989) (xy 369.827922 -0.610758) (xy 369.885691 -0.674128)
			(xy 369.937367 -0.742557) (xy 369.982508 -0.815463) (xy 370.02073 -0.892223) (xy 370.051706 -0.972182)
			(xy 370.075173 -1.054658) (xy 370.090929 -1.138948) (xy 370.098841 -1.224331) (xy 370.099336 -1.267206)
			(xy 370.098841 -1.310081) (xy 370.090929 -1.395464) (xy 370.075173 -1.479754) (xy 370.051706 -1.56223)
			(xy 370.02073 -1.642189) (xy 369.982508 -1.718949) (xy 369.937367 -1.791855) (xy 369.885691 -1.860284)
			(xy 369.827922 -1.923654) (xy 369.764552 -1.981423) (xy 369.696123 -2.033099) (xy 369.623217 -2.07824)
			(xy 369.546457 -2.116462) (xy 369.466498 -2.147438) (xy 369.384022 -2.170905) (xy 369.299732 -2.186661)
			(xy 369.214349 -2.194573) (xy 369.128599 -2.194573) (xy 369.043216 -2.186661) (xy 368.958926 -2.170905)
			(xy 368.87645 -2.147438) (xy 368.796491 -2.116462) (xy 368.719731 -2.07824) (xy 368.646825 -2.033099)
			(xy 368.578396 -1.981423) (xy 368.515026 -1.923654) (xy 368.457257 -1.860284) (xy 368.405581 -1.791855)
			(xy 368.36044 -1.718949) (xy 368.322218 -1.642189) (xy 368.291242 -1.56223) (xy 368.267775 -1.479754)
			(xy 368.252019 -1.395464) (xy 368.244107 -1.310081) (xy 363.748841 -1.310081) (xy 363.740929 -1.395464)
			(xy 363.725173 -1.479754) (xy 363.701706 -1.56223) (xy 363.67073 -1.642189) (xy 363.632508 -1.718949)
			(xy 363.587367 -1.791855) (xy 363.535691 -1.860284) (xy 363.477922 -1.923654) (xy 363.414552 -1.981423)
			(xy 363.346123 -2.033099) (xy 363.273217 -2.07824) (xy 363.196457 -2.116462) (xy 363.116498 -2.147438)
			(xy 363.034022 -2.170905) (xy 362.949732 -2.186661) (xy 362.864349 -2.194573) (xy 362.778599 -2.194573)
			(xy 362.693216 -2.186661) (xy 362.608926 -2.170905) (xy 362.52645 -2.147438) (xy 362.446491 -2.116462)
			(xy 362.369731 -2.07824) (xy 362.296825 -2.033099) (xy 362.228396 -1.981423) (xy 362.165026 -1.923654)
			(xy 362.107257 -1.860284) (xy 362.055581 -1.791855) (xy 362.01044 -1.718949) (xy 361.972218 -1.642189)
			(xy 361.941242 -1.56223) (xy 361.917775 -1.479754) (xy 361.902019 -1.395464) (xy 361.894107 -1.310081)
			(xy 319.360055 -1.310081) (xy 319.352143 -1.395464) (xy 319.336387 -1.479754) (xy 319.31292 -1.56223)
			(xy 319.281944 -1.642189) (xy 319.243722 -1.718949) (xy 319.198581 -1.791855) (xy 319.146905 -1.860284)
			(xy 319.089136 -1.923654) (xy 319.025766 -1.981423) (xy 318.957337 -2.033099) (xy 318.884431 -2.07824)
			(xy 318.807671 -2.116462) (xy 318.727712 -2.147438) (xy 318.645236 -2.170905) (xy 318.560946 -2.186661)
			(xy 318.475563 -2.194573) (xy 318.389813 -2.194573) (xy 318.30443 -2.186661) (xy 318.22014 -2.170905)
			(xy 318.137664 -2.147438) (xy 318.057705 -2.116462) (xy 317.980945 -2.07824) (xy 317.908039 -2.033099)
			(xy 317.83961 -1.981423) (xy 317.77624 -1.923654) (xy 317.718471 -1.860284) (xy 317.666795 -1.791855)
			(xy 317.621654 -1.718949) (xy 317.583432 -1.642189) (xy 317.552456 -1.56223) (xy 317.528989 -1.479754)
			(xy 317.513233 -1.395464) (xy 317.505321 -1.310081) (xy 313.010055 -1.310081) (xy 313.002143 -1.395464)
			(xy 312.986387 -1.479754) (xy 312.96292 -1.56223) (xy 312.931944 -1.642189) (xy 312.893722 -1.718949)
			(xy 312.848581 -1.791855) (xy 312.796905 -1.860284) (xy 312.739136 -1.923654) (xy 312.675766 -1.981423)
			(xy 312.607337 -2.033099) (xy 312.534431 -2.07824) (xy 312.457671 -2.116462) (xy 312.377712 -2.147438)
			(xy 312.295236 -2.170905) (xy 312.210946 -2.186661) (xy 312.125563 -2.194573) (xy 312.039813 -2.194573)
			(xy 311.95443 -2.186661) (xy 311.87014 -2.170905) (xy 311.787664 -2.147438) (xy 311.707705 -2.116462)
			(xy 311.630945 -2.07824) (xy 311.558039 -2.033099) (xy 311.48961 -1.981423) (xy 311.42624 -1.923654)
			(xy 311.368471 -1.860284) (xy 311.316795 -1.791855) (xy 311.271654 -1.718949) (xy 311.233432 -1.642189)
			(xy 311.202456 -1.56223) (xy 311.178989 -1.479754) (xy 311.163233 -1.395464) (xy 311.155321 -1.310081)
			(xy 304.348655 -1.310081) (xy 304.340743 -1.395464) (xy 304.324987 -1.479754) (xy 304.30152 -1.56223)
			(xy 304.270544 -1.642189) (xy 304.232322 -1.718949) (xy 304.187181 -1.791855) (xy 304.135505 -1.860284)
			(xy 304.077736 -1.923654) (xy 304.014366 -1.981423) (xy 303.945937 -2.033099) (xy 303.873031 -2.07824)
			(xy 303.796271 -2.116462) (xy 303.716312 -2.147438) (xy 303.633836 -2.170905) (xy 303.549546 -2.186661)
			(xy 303.464163 -2.194573) (xy 303.378413 -2.194573) (xy 303.29303 -2.186661) (xy 303.20874 -2.170905)
			(xy 303.126264 -2.147438) (xy 303.046305 -2.116462) (xy 302.969545 -2.07824) (xy 302.896639 -2.033099)
			(xy 302.82821 -1.981423) (xy 302.76484 -1.923654) (xy 302.707071 -1.860284) (xy 302.655395 -1.791855)
			(xy 302.610254 -1.718949) (xy 302.572032 -1.642189) (xy 302.541056 -1.56223) (xy 302.517589 -1.479754)
			(xy 302.501833 -1.395464) (xy 302.493921 -1.310081) (xy 297.998655 -1.310081) (xy 297.990743 -1.395464)
			(xy 297.974987 -1.479754) (xy 297.95152 -1.56223) (xy 297.920544 -1.642189) (xy 297.882322 -1.718949)
			(xy 297.837181 -1.791855) (xy 297.785505 -1.860284) (xy 297.727736 -1.923654) (xy 297.664366 -1.981423)
			(xy 297.595937 -2.033099) (xy 297.523031 -2.07824) (xy 297.446271 -2.116462) (xy 297.366312 -2.147438)
			(xy 297.283836 -2.170905) (xy 297.199546 -2.186661) (xy 297.114163 -2.194573) (xy 297.028413 -2.194573)
			(xy 296.94303 -2.186661) (xy 296.85874 -2.170905) (xy 296.776264 -2.147438) (xy 296.696305 -2.116462)
			(xy 296.619545 -2.07824) (xy 296.546639 -2.033099) (xy 296.47821 -1.981423) (xy 296.41484 -1.923654)
			(xy 296.357071 -1.860284) (xy 296.305395 -1.791855) (xy 296.260254 -1.718949) (xy 296.222032 -1.642189)
			(xy 296.191056 -1.56223) (xy 296.167589 -1.479754) (xy 296.151833 -1.395464) (xy 296.143921 -1.310081)
			(xy 216.865975 -1.310081) (xy 216.858063 -1.395464) (xy 216.842307 -1.479754) (xy 216.81884 -1.56223)
			(xy 216.787864 -1.642189) (xy 216.749642 -1.718949) (xy 216.704501 -1.791855) (xy 216.652825 -1.860284)
			(xy 216.595056 -1.923654) (xy 216.531686 -1.981423) (xy 216.463257 -2.033099) (xy 216.390351 -2.07824)
			(xy 216.313591 -2.116462) (xy 216.233632 -2.147438) (xy 216.151156 -2.170905) (xy 216.066866 -2.186661)
			(xy 215.981483 -2.194573) (xy 215.895733 -2.194573) (xy 215.81035 -2.186661) (xy 215.72606 -2.170905)
			(xy 215.643584 -2.147438) (xy 215.563625 -2.116462) (xy 215.486865 -2.07824) (xy 215.413959 -2.033099)
			(xy 215.34553 -1.981423) (xy 215.28216 -1.923654) (xy 215.224391 -1.860284) (xy 215.172715 -1.791855)
			(xy 215.127574 -1.718949) (xy 215.089352 -1.642189) (xy 215.058376 -1.56223) (xy 215.034909 -1.479754)
			(xy 215.019153 -1.395464) (xy 215.011241 -1.310081) (xy 210.515975 -1.310081) (xy 210.508063 -1.395464)
			(xy 210.492307 -1.479754) (xy 210.46884 -1.56223) (xy 210.437864 -1.642189) (xy 210.399642 -1.718949)
			(xy 210.354501 -1.791855) (xy 210.302825 -1.860284) (xy 210.245056 -1.923654) (xy 210.181686 -1.981423)
			(xy 210.113257 -2.033099) (xy 210.040351 -2.07824) (xy 209.963591 -2.116462) (xy 209.883632 -2.147438)
			(xy 209.801156 -2.170905) (xy 209.716866 -2.186661) (xy 209.631483 -2.194573) (xy 209.545733 -2.194573)
			(xy 209.46035 -2.186661) (xy 209.37606 -2.170905) (xy 209.293584 -2.147438) (xy 209.213625 -2.116462)
			(xy 209.136865 -2.07824) (xy 209.063959 -2.033099) (xy 208.99553 -1.981423) (xy 208.93216 -1.923654)
			(xy 208.874391 -1.860284) (xy 208.822715 -1.791855) (xy 208.777574 -1.718949) (xy 208.739352 -1.642189)
			(xy 208.708376 -1.56223) (xy 208.684909 -1.479754) (xy 208.669153 -1.395464) (xy 208.661241 -1.310081)
			(xy 84.210906 -1.310081) (xy 84.210906 -7.78002) (xy 84.211428 -7.835789) (xy 84.219765 -7.947014)
			(xy 84.23639 -8.057306) (xy 84.26121 -8.166046) (xy 84.294088 -8.272628) (xy 84.334838 -8.376455)
			(xy 84.383233 -8.476947) (xy 84.439002 -8.573541) (xy 84.501834 -8.665697) (xy 84.571376 -8.7529)
			(xy 84.647241 -8.834663) (xy 84.729004 -8.910527) (xy 84.816208 -8.98007) (xy 84.908364 -9.042901)
			(xy 85.004959 -9.09867) (xy 85.10545 -9.147065) (xy 85.209277 -9.187814) (xy 85.315859 -9.220691)
			(xy 85.4246 -9.245511) (xy 85.534892 -9.262136) (xy 85.646117 -9.270472) (xy 85.701886 -9.271) (xy 122.102118 -9.271)
			(xy 122.157887 -9.270478) (xy 122.269113 -9.262141) (xy 122.379404 -9.245517) (xy 122.488145 -9.220696)
			(xy 122.594728 -9.187819) (xy 122.698555 -9.147069) (xy 122.799047 -9.098674) (xy 122.895641 -9.042905)
			(xy 122.987798 -8.980073) (xy 123.075001 -8.910531) (xy 123.156764 -8.834666) (xy 123.232629 -8.752903)
			(xy 123.302172 -8.665699) (xy 123.365004 -8.573543) (xy 123.420773 -8.476948) (xy 123.469168 -8.376457)
			(xy 123.509918 -8.27263) (xy 123.542796 -8.166047) (xy 123.567616 -8.057306) (xy 123.584241 -7.947015)
			(xy 123.592578 -7.835789) (xy 123.593098 -7.78002) (xy 123.593098 -4.879848) (xy 123.593581 -4.809465)
			(xy 123.601472 -4.66892) (xy 123.61723 -4.529038) (xy 123.640807 -4.39026) (xy 123.672128 -4.253022)
			(xy 123.711095 -4.117757) (xy 123.757586 -3.984889) (xy 123.811453 -3.854837) (xy 123.872528 -3.72801)
			(xy 123.940618 -3.604807) (xy 124.015509 -3.485616) (xy 124.096965 -3.370811) (xy 124.184731 -3.260755)
			(xy 124.278529 -3.155793) (xy 124.378065 -3.056255) (xy 124.483026 -2.962455) (xy 124.593081 -2.874688)
			(xy 124.707884 -2.79323) (xy 124.827074 -2.718337) (xy 124.950276 -2.650245) (xy 125.077102 -2.589169)
			(xy 125.207153 -2.535299) (xy 125.340021 -2.488807) (xy 125.475285 -2.449838) (xy 125.612523 -2.418514)
			(xy 125.7513 -2.394935) (xy 125.891182 -2.379175) (xy 126.031727 -2.371282) (xy 126.10211 -2.370836)
			(xy 194.701922 -2.370836) (xy 194.772304 -2.371321) (xy 194.912845 -2.379215) (xy 195.052723 -2.394977)
			(xy 195.191497 -2.418557) (xy 195.328731 -2.449881) (xy 195.463992 -2.488851) (xy 195.596856 -2.535344)
			(xy 195.726904 -2.589213) (xy 195.853726 -2.650289) (xy 195.976925 -2.71838) (xy 196.096111 -2.793273)
			(xy 196.210911 -2.87473) (xy 196.320963 -2.962495) (xy 196.425921 -3.056294) (xy 196.525454 -3.15583)
			(xy 196.61925 -3.26079) (xy 196.707012 -3.370845) (xy 196.788466 -3.485647) (xy 196.863355 -3.604836)
			(xy 196.931443 -3.728036) (xy 196.990215 -3.850081) (xy 208.661241 -3.850081) (xy 208.661241 -3.764331)
			(xy 208.669153 -3.678948) (xy 208.684909 -3.594658) (xy 208.708376 -3.512182) (xy 208.739352 -3.432223)
			(xy 208.777574 -3.355463) (xy 208.822715 -3.282557) (xy 208.874391 -3.214128) (xy 208.93216 -3.150758)
			(xy 208.99553 -3.092989) (xy 209.063959 -3.041313) (xy 209.136865 -2.996172) (xy 209.213625 -2.95795)
			(xy 209.293584 -2.926974) (xy 209.37606 -2.903507) (xy 209.46035 -2.887751) (xy 209.545733 -2.879839)
			(xy 209.631483 -2.879839) (xy 209.716866 -2.887751) (xy 209.801156 -2.903507) (xy 209.883632 -2.926974)
			(xy 209.963591 -2.95795) (xy 210.040351 -2.996172) (xy 210.113257 -3.041313) (xy 210.168864 -3.083306)
			(xy 212.819996 -3.083306) (xy 212.819996 -1.986026) (xy 212.820529 -1.973942) (xy 212.827973 -1.95095)
			(xy 212.842144 -1.931373) (xy 212.861661 -1.91712) (xy 212.884622 -1.90958) (xy 212.896704 -1.909064)
			(xy 213.508844 -1.909064) (xy 213.512908 -1.909318) (xy 213.518925 -1.909383) (xy 213.530731 -1.907082)
			(xy 213.536276 -1.904746) (xy 213.562946 -1.892808) (xy 213.56961 -1.889551) (xy 213.580841 -1.87987)
			(xy 213.585044 -1.873758) (xy 213.60215 -1.847753) (xy 213.642596 -1.800442) (xy 213.689408 -1.75942)
			(xy 213.741619 -1.725535) (xy 213.798149 -1.699487) (xy 213.85783 -1.681814) (xy 213.919429 -1.672881)
			(xy 213.95055 -1.672336) (xy 213.978862 -1.672754) (xy 214.035 -1.680148) (xy 214.089695 -1.694803)
			(xy 214.142009 -1.716468) (xy 214.19105 -1.744774) (xy 214.235979 -1.779237) (xy 214.276027 -1.819266)
			(xy 214.310511 -1.864178) (xy 214.33884 -1.913206) (xy 214.360531 -1.96551) (xy 214.375212 -2.020197)
			(xy 214.382633 -2.076332) (xy 214.383112 -2.104644) (xy 214.383112 -2.968244) (xy 214.382706 -2.996561)
			(xy 214.375306 -3.052711) (xy 214.360638 -3.107413) (xy 214.338953 -3.159732) (xy 214.310623 -3.208772)
			(xy 214.276132 -3.253693) (xy 214.236072 -3.293726) (xy 214.191127 -3.328186) (xy 214.142068 -3.356483)
			(xy 214.089734 -3.378132) (xy 214.035022 -3.392763) (xy 213.978868 -3.400125) (xy 213.95055 -3.400552)
			(xy 213.919177 -3.399953) (xy 213.857087 -3.390899) (xy 213.796955 -3.372975) (xy 213.740042 -3.346555)
			(xy 213.687541 -3.312194) (xy 213.640552 -3.270611) (xy 213.600059 -3.22268) (xy 213.583012 -3.196336)
			(xy 213.578952 -3.190192) (xy 213.56798 -3.180381) (xy 213.561422 -3.177032) (xy 213.52256 -3.158998)
			(xy 213.508844 -3.160268) (xy 212.896704 -3.160268) (xy 212.884592 -3.15988) (xy 212.861559 -3.152378)
			(xy 212.841983 -3.13811) (xy 212.82779 -3.11848) (xy 212.820375 -3.095419) (xy 212.819996 -3.083306)
			(xy 210.168864 -3.083306) (xy 210.181686 -3.092989) (xy 210.245056 -3.150758) (xy 210.302825 -3.214128)
			(xy 210.354501 -3.282557) (xy 210.399642 -3.355463) (xy 210.437864 -3.432223) (xy 210.46884 -3.512182)
			(xy 210.492307 -3.594658) (xy 210.508063 -3.678948) (xy 210.515975 -3.764331) (xy 210.51647 -3.807206)
			(xy 210.515975 -3.850081) (xy 215.011241 -3.850081) (xy 215.011241 -3.764331) (xy 215.019153 -3.678948)
			(xy 215.034909 -3.594658) (xy 215.058376 -3.512182) (xy 215.089352 -3.432223) (xy 215.127574 -3.355463)
			(xy 215.172715 -3.282557) (xy 215.224391 -3.214128) (xy 215.28216 -3.150758) (xy 215.34553 -3.092989)
			(xy 215.413959 -3.041313) (xy 215.486865 -2.996172) (xy 215.563625 -2.95795) (xy 215.643584 -2.926974)
			(xy 215.72606 -2.903507) (xy 215.81035 -2.887751) (xy 215.895733 -2.879839) (xy 215.981483 -2.879839)
			(xy 216.066866 -2.887751) (xy 216.151156 -2.903507) (xy 216.233632 -2.926974) (xy 216.313591 -2.95795)
			(xy 216.390351 -2.996172) (xy 216.463257 -3.041313) (xy 216.531686 -3.092989) (xy 216.595056 -3.150758)
			(xy 216.652825 -3.214128) (xy 216.704501 -3.282557) (xy 216.749642 -3.355463) (xy 216.787864 -3.432223)
			(xy 216.81884 -3.512182) (xy 216.842307 -3.594658) (xy 216.858063 -3.678948) (xy 216.865975 -3.764331)
			(xy 216.86647 -3.807206) (xy 216.865975 -3.850081) (xy 296.143921 -3.850081) (xy 296.143921 -3.764331)
			(xy 296.151833 -3.678948) (xy 296.167589 -3.594658) (xy 296.191056 -3.512182) (xy 296.222032 -3.432223)
			(xy 296.260254 -3.355463) (xy 296.305395 -3.282557) (xy 296.357071 -3.214128) (xy 296.41484 -3.150758)
			(xy 296.47821 -3.092989) (xy 296.546639 -3.041313) (xy 296.619545 -2.996172) (xy 296.696305 -2.95795)
			(xy 296.776264 -2.926974) (xy 296.85874 -2.903507) (xy 296.94303 -2.887751) (xy 297.028413 -2.879839)
			(xy 297.114163 -2.879839) (xy 297.199546 -2.887751) (xy 297.283836 -2.903507) (xy 297.366312 -2.926974)
			(xy 297.446271 -2.95795) (xy 297.466944 -2.968244) (xy 298.629324 -2.968244) (xy 298.629324 -2.104644)
			(xy 298.629777 -2.076327) (xy 298.637167 -2.020178) (xy 298.651826 -1.965474) (xy 298.673504 -1.913154)
			(xy 298.701828 -1.864112) (xy 298.736314 -1.819189) (xy 298.776371 -1.779154) (xy 298.821313 -1.744693)
			(xy 298.870371 -1.716396) (xy 298.922704 -1.694748) (xy 298.977415 -1.68012) (xy 299.033569 -1.672761)
			(xy 299.061886 -1.672336) (xy 299.093352 -1.672875) (xy 299.15562 -1.681998) (xy 299.215907 -1.700054)
			(xy 299.272938 -1.72666) (xy 299.325509 -1.761255) (xy 299.372508 -1.803106) (xy 299.412942 -1.851331)
			(xy 299.429932 -1.877822) (xy 299.433953 -1.883879) (xy 299.444801 -1.89355) (xy 299.451268 -1.896872)
			(xy 299.489368 -1.91516) (xy 299.501052 -1.914144) (xy 300.113192 -1.914144) (xy 300.125295 -1.914622)
			(xy 300.148312 -1.922113) (xy 300.167881 -1.93636) (xy 300.182078 -1.955965) (xy 300.189509 -1.979002)
			(xy 300.1899 -1.991106) (xy 300.1899 -3.088386) (xy 300.189381 -3.100471) (xy 300.181933 -3.123464)
			(xy 300.167759 -3.143041) (xy 300.148238 -3.157293) (xy 300.125275 -3.164833) (xy 300.113192 -3.165348)
			(xy 299.501052 -3.165348) (xy 299.487082 -3.164078) (xy 299.448474 -3.181604) (xy 299.441866 -3.184865)
			(xy 299.430772 -3.194558) (xy 299.42663 -3.200654) (xy 299.409517 -3.22652) (xy 299.369051 -3.27352)
			(xy 299.322281 -3.314252) (xy 299.270168 -3.347879) (xy 299.213784 -3.373712) (xy 299.154286 -3.391219)
			(xy 299.092896 -3.40004) (xy 299.061886 -3.400552) (xy 299.033575 -3.400113) (xy 298.977436 -3.392723)
			(xy 298.922742 -3.378071) (xy 298.870426 -3.356409) (xy 298.821385 -3.328106) (xy 298.776455 -3.293646)
			(xy 298.736406 -3.253618) (xy 298.701922 -3.208707) (xy 298.673593 -3.15968) (xy 298.651903 -3.107377)
			(xy 298.637222 -3.05269) (xy 298.629802 -2.996555) (xy 298.629324 -2.968244) (xy 297.466944 -2.968244)
			(xy 297.523031 -2.996172) (xy 297.595937 -3.041313) (xy 297.664366 -3.092989) (xy 297.727736 -3.150758)
			(xy 297.785505 -3.214128) (xy 297.837181 -3.282557) (xy 297.882322 -3.355463) (xy 297.920544 -3.432223)
			(xy 297.95152 -3.512182) (xy 297.974987 -3.594658) (xy 297.990743 -3.678948) (xy 297.998655 -3.764331)
			(xy 297.99915 -3.807206) (xy 297.998655 -3.850081) (xy 302.493921 -3.850081) (xy 302.493921 -3.764331)
			(xy 302.501833 -3.678948) (xy 302.517589 -3.594658) (xy 302.541056 -3.512182) (xy 302.572032 -3.432223)
			(xy 302.610254 -3.355463) (xy 302.655395 -3.282557) (xy 302.707071 -3.214128) (xy 302.76484 -3.150758)
			(xy 302.82821 -3.092989) (xy 302.896639 -3.041313) (xy 302.969545 -2.996172) (xy 303.046305 -2.95795)
			(xy 303.126264 -2.926974) (xy 303.20874 -2.903507) (xy 303.29303 -2.887751) (xy 303.378413 -2.879839)
			(xy 303.464163 -2.879839) (xy 303.549546 -2.887751) (xy 303.633836 -2.903507) (xy 303.716312 -2.926974)
			(xy 303.796271 -2.95795) (xy 303.873031 -2.996172) (xy 303.945937 -3.041313) (xy 304.014366 -3.092989)
			(xy 304.077736 -3.150758) (xy 304.135505 -3.214128) (xy 304.187181 -3.282557) (xy 304.232322 -3.355463)
			(xy 304.270544 -3.432223) (xy 304.30152 -3.512182) (xy 304.324987 -3.594658) (xy 304.340743 -3.678948)
			(xy 304.348655 -3.764331) (xy 304.34915 -3.807206) (xy 304.348655 -3.850081) (xy 311.155321 -3.850081)
			(xy 311.155321 -3.764331) (xy 311.163233 -3.678948) (xy 311.178989 -3.594658) (xy 311.202456 -3.512182)
			(xy 311.233432 -3.432223) (xy 311.271654 -3.355463) (xy 311.316795 -3.282557) (xy 311.368471 -3.214128)
			(xy 311.42624 -3.150758) (xy 311.48961 -3.092989) (xy 311.558039 -3.041313) (xy 311.630945 -2.996172)
			(xy 311.707705 -2.95795) (xy 311.787664 -2.926974) (xy 311.87014 -2.903507) (xy 311.95443 -2.887751)
			(xy 312.039813 -2.879839) (xy 312.125563 -2.879839) (xy 312.210946 -2.887751) (xy 312.295236 -2.903507)
			(xy 312.377712 -2.926974) (xy 312.457671 -2.95795) (xy 312.534431 -2.996172) (xy 312.607337 -3.041313)
			(xy 312.662944 -3.083306) (xy 315.314076 -3.083306) (xy 315.314076 -1.986026) (xy 315.31453 -1.973934)
			(xy 315.321984 -1.950928) (xy 315.336173 -1.931345) (xy 315.355711 -1.917095) (xy 315.378694 -1.909569)
			(xy 315.390784 -1.909064) (xy 316.002924 -1.909064) (xy 316.006988 -1.909318) (xy 316.013005 -1.90941)
			(xy 316.024813 -1.90709) (xy 316.030356 -1.904746) (xy 316.057026 -1.892808) (xy 316.063688 -1.889545)
			(xy 316.07492 -1.879868) (xy 316.079124 -1.873758) (xy 316.096177 -1.847716) (xy 316.136632 -1.800406)
			(xy 316.183453 -1.759387) (xy 316.235673 -1.725505) (xy 316.292211 -1.699463) (xy 316.3519 -1.681798)
			(xy 316.413506 -1.672876) (xy 316.44463 -1.672336) (xy 316.472941 -1.672772) (xy 316.529079 -1.680164)
			(xy 316.583773 -1.694817) (xy 316.636088 -1.71648) (xy 316.685129 -1.744784) (xy 316.730058 -1.779244)
			(xy 316.770106 -1.819272) (xy 316.80459 -1.864183) (xy 316.83292 -1.913209) (xy 316.854611 -1.965513)
			(xy 316.869292 -2.020199) (xy 316.876713 -2.076333) (xy 316.877192 -2.104644) (xy 316.877192 -2.968244)
			(xy 316.876806 -2.996562) (xy 316.869405 -3.052713) (xy 316.854736 -3.107417) (xy 316.83305 -3.159737)
			(xy 316.804718 -3.208778) (xy 316.770226 -3.2537) (xy 316.730163 -3.293733) (xy 316.685217 -3.328193)
			(xy 316.636155 -3.356489) (xy 316.583819 -3.378137) (xy 316.529105 -3.392766) (xy 316.472949 -3.400126)
			(xy 316.44463 -3.400552) (xy 316.413256 -3.399968) (xy 316.351166 -3.390912) (xy 316.291034 -3.372985)
			(xy 316.234121 -3.346562) (xy 316.18162 -3.312199) (xy 316.134631 -3.270614) (xy 316.094139 -3.22268)
			(xy 316.077092 -3.196336) (xy 316.073038 -3.190188) (xy 316.062062 -3.180379) (xy 316.055502 -3.177032)
			(xy 316.01664 -3.158998) (xy 316.002924 -3.160268) (xy 315.390784 -3.160268) (xy 315.378671 -3.159897)
			(xy 315.355638 -3.152389) (xy 315.336062 -3.138117) (xy 315.321869 -3.118484) (xy 315.314455 -3.095421)
			(xy 315.314076 -3.083306) (xy 312.662944 -3.083306) (xy 312.675766 -3.092989) (xy 312.739136 -3.150758)
			(xy 312.796905 -3.214128) (xy 312.848581 -3.282557) (xy 312.893722 -3.355463) (xy 312.931944 -3.432223)
			(xy 312.96292 -3.512182) (xy 312.986387 -3.594658) (xy 313.002143 -3.678948) (xy 313.010055 -3.764331)
			(xy 313.01055 -3.807206) (xy 313.010055 -3.850081) (xy 317.505321 -3.850081) (xy 317.505321 -3.764331)
			(xy 317.513233 -3.678948) (xy 317.528989 -3.594658) (xy 317.552456 -3.512182) (xy 317.583432 -3.432223)
			(xy 317.621654 -3.355463) (xy 317.666795 -3.282557) (xy 317.718471 -3.214128) (xy 317.77624 -3.150758)
			(xy 317.83961 -3.092989) (xy 317.908039 -3.041313) (xy 317.980945 -2.996172) (xy 318.057705 -2.95795)
			(xy 318.137664 -2.926974) (xy 318.22014 -2.903507) (xy 318.30443 -2.887751) (xy 318.389813 -2.879839)
			(xy 318.475563 -2.879839) (xy 318.560946 -2.887751) (xy 318.645236 -2.903507) (xy 318.727712 -2.926974)
			(xy 318.807671 -2.95795) (xy 318.884431 -2.996172) (xy 318.957337 -3.041313) (xy 319.025766 -3.092989)
			(xy 319.089136 -3.150758) (xy 319.146905 -3.214128) (xy 319.198581 -3.282557) (xy 319.243722 -3.355463)
			(xy 319.281944 -3.432223) (xy 319.31292 -3.512182) (xy 319.336387 -3.594658) (xy 319.352143 -3.678948)
			(xy 319.360055 -3.764331) (xy 319.36055 -3.807206) (xy 319.360055 -3.850081) (xy 361.894107 -3.850081)
			(xy 361.894107 -3.764331) (xy 361.902019 -3.678948) (xy 361.917775 -3.594658) (xy 361.941242 -3.512182)
			(xy 361.972218 -3.432223) (xy 362.01044 -3.355463) (xy 362.055581 -3.282557) (xy 362.107257 -3.214128)
			(xy 362.165026 -3.150758) (xy 362.228396 -3.092989) (xy 362.296825 -3.041313) (xy 362.369731 -2.996172)
			(xy 362.446491 -2.95795) (xy 362.52645 -2.926974) (xy 362.608926 -2.903507) (xy 362.693216 -2.887751)
			(xy 362.778599 -2.879839) (xy 362.864349 -2.879839) (xy 362.949732 -2.887751) (xy 363.034022 -2.903507)
			(xy 363.116498 -2.926974) (xy 363.196457 -2.95795) (xy 363.21713 -2.968244) (xy 364.379764 -2.968244)
			(xy 364.379764 -2.104644) (xy 364.380276 -2.07634) (xy 364.387659 -2.020216) (xy 364.402305 -1.965536)
			(xy 364.423963 -1.913236) (xy 364.452262 -1.86421) (xy 364.486719 -1.819297) (xy 364.526743 -1.779267)
			(xy 364.57165 -1.744803) (xy 364.620671 -1.716495) (xy 364.672968 -1.694828) (xy 364.727646 -1.680173)
			(xy 364.783768 -1.672781) (xy 364.812072 -1.672336) (xy 364.843538 -1.672886) (xy 364.905805 -1.682007)
			(xy 364.966091 -1.700061) (xy 365.023123 -1.726665) (xy 365.075694 -1.761258) (xy 365.122694 -1.803108)
			(xy 365.163128 -1.851331) (xy 365.180118 -1.877822) (xy 365.184143 -1.883876) (xy 365.194988 -1.893549)
			(xy 365.201454 -1.896872) (xy 365.239554 -1.91516) (xy 365.251238 -1.914144) (xy 365.863378 -1.914144)
			(xy 365.8755 -1.914579) (xy 365.898559 -1.922066) (xy 365.918175 -1.936313) (xy 365.932427 -1.955926)
			(xy 365.939919 -1.978984) (xy 365.94034 -1.991106) (xy 365.94034 -3.088386) (xy 365.939928 -3.10051)
			(xy 365.932437 -3.123572) (xy 365.918184 -3.143189) (xy 365.898565 -3.15744) (xy 365.875502 -3.164929)
			(xy 365.863378 -3.165348) (xy 365.251238 -3.165348) (xy 365.237268 -3.164078) (xy 365.19866 -3.181604)
			(xy 365.19205 -3.184861) (xy 365.180958 -3.194557) (xy 365.176816 -3.200654) (xy 365.159713 -3.226527)
			(xy 365.119244 -3.273526) (xy 365.072473 -3.314258) (xy 365.020359 -3.347884) (xy 364.963973 -3.373716)
			(xy 364.904474 -3.391221) (xy 364.843083 -3.400041) (xy 364.812072 -3.400552) (xy 364.783769 -3.400072)
			(xy 364.727646 -3.39268) (xy 364.672969 -3.378027) (xy 364.620671 -3.356363) (xy 364.571648 -3.328059)
			(xy 364.526739 -3.2936) (xy 364.486711 -3.253573) (xy 364.452249 -3.208665) (xy 364.423944 -3.159643)
			(xy 364.402278 -3.107346) (xy 364.387623 -3.052669) (xy 364.380229 -2.996547) (xy 364.379764 -2.968244)
			(xy 363.21713 -2.968244) (xy 363.273217 -2.996172) (xy 363.346123 -3.041313) (xy 363.414552 -3.092989)
			(xy 363.477922 -3.150758) (xy 363.535691 -3.214128) (xy 363.587367 -3.282557) (xy 363.632508 -3.355463)
			(xy 363.67073 -3.432223) (xy 363.701706 -3.512182) (xy 363.725173 -3.594658) (xy 363.740929 -3.678948)
			(xy 363.748841 -3.764331) (xy 363.749336 -3.807206) (xy 363.748841 -3.850081) (xy 368.244107 -3.850081)
			(xy 368.244107 -3.764331) (xy 368.252019 -3.678948) (xy 368.267775 -3.594658) (xy 368.291242 -3.512182)
			(xy 368.322218 -3.432223) (xy 368.36044 -3.355463) (xy 368.405581 -3.282557) (xy 368.457257 -3.214128)
			(xy 368.515026 -3.150758) (xy 368.578396 -3.092989) (xy 368.646825 -3.041313) (xy 368.719731 -2.996172)
			(xy 368.796491 -2.95795) (xy 368.87645 -2.926974) (xy 368.958926 -2.903507) (xy 369.043216 -2.887751)
			(xy 369.128599 -2.879839) (xy 369.214349 -2.879839) (xy 369.299732 -2.887751) (xy 369.384022 -2.903507)
			(xy 369.466498 -2.926974) (xy 369.546457 -2.95795) (xy 369.623217 -2.996172) (xy 369.696123 -3.041313)
			(xy 369.764552 -3.092989) (xy 369.827922 -3.150758) (xy 369.885691 -3.214128) (xy 369.937367 -3.282557)
			(xy 369.982508 -3.355463) (xy 370.02073 -3.432223) (xy 370.051706 -3.512182) (xy 370.075173 -3.594658)
			(xy 370.090929 -3.678948) (xy 370.098841 -3.764331) (xy 370.099336 -3.807206) (xy 370.098841 -3.850081)
			(xy 370.090929 -3.935464) (xy 370.075173 -4.019754) (xy 370.051706 -4.10223) (xy 370.02073 -4.182189)
			(xy 369.982508 -4.258949) (xy 369.937367 -4.331855) (xy 369.885691 -4.400284) (xy 369.827922 -4.463654)
			(xy 369.764552 -4.521423) (xy 369.696123 -4.573099) (xy 369.623217 -4.61824) (xy 369.546457 -4.656462)
			(xy 369.466498 -4.687438) (xy 369.384022 -4.710905) (xy 369.299732 -4.726661) (xy 369.214349 -4.734573)
			(xy 369.128599 -4.734573) (xy 369.043216 -4.726661) (xy 368.958926 -4.710905) (xy 368.87645 -4.687438)
			(xy 368.796491 -4.656462) (xy 368.719731 -4.61824) (xy 368.646825 -4.573099) (xy 368.578396 -4.521423)
			(xy 368.515026 -4.463654) (xy 368.457257 -4.400284) (xy 368.405581 -4.331855) (xy 368.36044 -4.258949)
			(xy 368.322218 -4.182189) (xy 368.291242 -4.10223) (xy 368.267775 -4.019754) (xy 368.252019 -3.935464)
			(xy 368.244107 -3.850081) (xy 363.748841 -3.850081) (xy 363.740929 -3.935464) (xy 363.725173 -4.019754)
			(xy 363.701706 -4.10223) (xy 363.67073 -4.182189) (xy 363.632508 -4.258949) (xy 363.587367 -4.331855)
			(xy 363.535691 -4.400284) (xy 363.477922 -4.463654) (xy 363.414552 -4.521423) (xy 363.346123 -4.573099)
			(xy 363.273217 -4.61824) (xy 363.196457 -4.656462) (xy 363.116498 -4.687438) (xy 363.034022 -4.710905)
			(xy 362.949732 -4.726661) (xy 362.864349 -4.734573) (xy 362.778599 -4.734573) (xy 362.693216 -4.726661)
			(xy 362.608926 -4.710905) (xy 362.52645 -4.687438) (xy 362.446491 -4.656462) (xy 362.369731 -4.61824)
			(xy 362.296825 -4.573099) (xy 362.228396 -4.521423) (xy 362.165026 -4.463654) (xy 362.107257 -4.400284)
			(xy 362.055581 -4.331855) (xy 362.01044 -4.258949) (xy 361.972218 -4.182189) (xy 361.941242 -4.10223)
			(xy 361.917775 -4.019754) (xy 361.902019 -3.935464) (xy 361.894107 -3.850081) (xy 319.360055 -3.850081)
			(xy 319.352143 -3.935464) (xy 319.336387 -4.019754) (xy 319.31292 -4.10223) (xy 319.281944 -4.182189)
			(xy 319.243722 -4.258949) (xy 319.198581 -4.331855) (xy 319.146905 -4.400284) (xy 319.089136 -4.463654)
			(xy 319.025766 -4.521423) (xy 318.957337 -4.573099) (xy 318.884431 -4.61824) (xy 318.807671 -4.656462)
			(xy 318.727712 -4.687438) (xy 318.645236 -4.710905) (xy 318.560946 -4.726661) (xy 318.475563 -4.734573)
			(xy 318.389813 -4.734573) (xy 318.30443 -4.726661) (xy 318.22014 -4.710905) (xy 318.137664 -4.687438)
			(xy 318.057705 -4.656462) (xy 317.980945 -4.61824) (xy 317.908039 -4.573099) (xy 317.83961 -4.521423)
			(xy 317.77624 -4.463654) (xy 317.718471 -4.400284) (xy 317.666795 -4.331855) (xy 317.621654 -4.258949)
			(xy 317.583432 -4.182189) (xy 317.552456 -4.10223) (xy 317.528989 -4.019754) (xy 317.513233 -3.935464)
			(xy 317.505321 -3.850081) (xy 313.010055 -3.850081) (xy 313.002143 -3.935464) (xy 312.986387 -4.019754)
			(xy 312.96292 -4.10223) (xy 312.931944 -4.182189) (xy 312.893722 -4.258949) (xy 312.848581 -4.331855)
			(xy 312.796905 -4.400284) (xy 312.739136 -4.463654) (xy 312.675766 -4.521423) (xy 312.607337 -4.573099)
			(xy 312.534431 -4.61824) (xy 312.457671 -4.656462) (xy 312.377712 -4.687438) (xy 312.295236 -4.710905)
			(xy 312.210946 -4.726661) (xy 312.125563 -4.734573) (xy 312.039813 -4.734573) (xy 311.95443 -4.726661)
			(xy 311.87014 -4.710905) (xy 311.787664 -4.687438) (xy 311.707705 -4.656462) (xy 311.630945 -4.61824)
			(xy 311.558039 -4.573099) (xy 311.48961 -4.521423) (xy 311.42624 -4.463654) (xy 311.368471 -4.400284)
			(xy 311.316795 -4.331855) (xy 311.271654 -4.258949) (xy 311.233432 -4.182189) (xy 311.202456 -4.10223)
			(xy 311.178989 -4.019754) (xy 311.163233 -3.935464) (xy 311.155321 -3.850081) (xy 304.348655 -3.850081)
			(xy 304.340743 -3.935464) (xy 304.324987 -4.019754) (xy 304.30152 -4.10223) (xy 304.270544 -4.182189)
			(xy 304.232322 -4.258949) (xy 304.187181 -4.331855) (xy 304.135505 -4.400284) (xy 304.077736 -4.463654)
			(xy 304.014366 -4.521423) (xy 303.945937 -4.573099) (xy 303.873031 -4.61824) (xy 303.796271 -4.656462)
			(xy 303.716312 -4.687438) (xy 303.633836 -4.710905) (xy 303.549546 -4.726661) (xy 303.464163 -4.734573)
			(xy 303.378413 -4.734573) (xy 303.29303 -4.726661) (xy 303.20874 -4.710905) (xy 303.126264 -4.687438)
			(xy 303.046305 -4.656462) (xy 302.969545 -4.61824) (xy 302.896639 -4.573099) (xy 302.82821 -4.521423)
			(xy 302.76484 -4.463654) (xy 302.707071 -4.400284) (xy 302.655395 -4.331855) (xy 302.610254 -4.258949)
			(xy 302.572032 -4.182189) (xy 302.541056 -4.10223) (xy 302.517589 -4.019754) (xy 302.501833 -3.935464)
			(xy 302.493921 -3.850081) (xy 297.998655 -3.850081) (xy 297.990743 -3.935464) (xy 297.974987 -4.019754)
			(xy 297.95152 -4.10223) (xy 297.920544 -4.182189) (xy 297.882322 -4.258949) (xy 297.837181 -4.331855)
			(xy 297.785505 -4.400284) (xy 297.727736 -4.463654) (xy 297.664366 -4.521423) (xy 297.595937 -4.573099)
			(xy 297.523031 -4.61824) (xy 297.446271 -4.656462) (xy 297.366312 -4.687438) (xy 297.283836 -4.710905)
			(xy 297.199546 -4.726661) (xy 297.114163 -4.734573) (xy 297.028413 -4.734573) (xy 296.94303 -4.726661)
			(xy 296.85874 -4.710905) (xy 296.776264 -4.687438) (xy 296.696305 -4.656462) (xy 296.619545 -4.61824)
			(xy 296.546639 -4.573099) (xy 296.47821 -4.521423) (xy 296.41484 -4.463654) (xy 296.357071 -4.400284)
			(xy 296.305395 -4.331855) (xy 296.260254 -4.258949) (xy 296.222032 -4.182189) (xy 296.191056 -4.10223)
			(xy 296.167589 -4.019754) (xy 296.151833 -3.935464) (xy 296.143921 -3.850081) (xy 216.865975 -3.850081)
			(xy 216.858063 -3.935464) (xy 216.842307 -4.019754) (xy 216.81884 -4.10223) (xy 216.787864 -4.182189)
			(xy 216.749642 -4.258949) (xy 216.704501 -4.331855) (xy 216.652825 -4.400284) (xy 216.595056 -4.463654)
			(xy 216.531686 -4.521423) (xy 216.463257 -4.573099) (xy 216.390351 -4.61824) (xy 216.313591 -4.656462)
			(xy 216.233632 -4.687438) (xy 216.151156 -4.710905) (xy 216.066866 -4.726661) (xy 215.981483 -4.734573)
			(xy 215.895733 -4.734573) (xy 215.81035 -4.726661) (xy 215.72606 -4.710905) (xy 215.643584 -4.687438)
			(xy 215.563625 -4.656462) (xy 215.486865 -4.61824) (xy 215.413959 -4.573099) (xy 215.34553 -4.521423)
			(xy 215.28216 -4.463654) (xy 215.224391 -4.400284) (xy 215.172715 -4.331855) (xy 215.127574 -4.258949)
			(xy 215.089352 -4.182189) (xy 215.058376 -4.10223) (xy 215.034909 -4.019754) (xy 215.019153 -3.935464)
			(xy 215.011241 -3.850081) (xy 210.515975 -3.850081) (xy 210.508063 -3.935464) (xy 210.492307 -4.019754)
			(xy 210.46884 -4.10223) (xy 210.437864 -4.182189) (xy 210.399642 -4.258949) (xy 210.354501 -4.331855)
			(xy 210.302825 -4.400284) (xy 210.245056 -4.463654) (xy 210.181686 -4.521423) (xy 210.113257 -4.573099)
			(xy 210.040351 -4.61824) (xy 209.963591 -4.656462) (xy 209.883632 -4.687438) (xy 209.801156 -4.710905)
			(xy 209.716866 -4.726661) (xy 209.631483 -4.734573) (xy 209.545733 -4.734573) (xy 209.46035 -4.726661)
			(xy 209.37606 -4.710905) (xy 209.293584 -4.687438) (xy 209.213625 -4.656462) (xy 209.136865 -4.61824)
			(xy 209.063959 -4.573099) (xy 208.99553 -4.521423) (xy 208.93216 -4.463654) (xy 208.874391 -4.400284)
			(xy 208.822715 -4.331855) (xy 208.777574 -4.258949) (xy 208.739352 -4.182189) (xy 208.708376 -4.10223)
			(xy 208.684909 -4.019754) (xy 208.669153 -3.935464) (xy 208.661241 -3.850081) (xy 196.990215 -3.850081)
			(xy 196.992516 -3.85486) (xy 197.046381 -3.984909) (xy 197.09287 -4.117774) (xy 197.131836 -4.253037)
			(xy 197.163157 -4.390271) (xy 197.186733 -4.529046) (xy 197.202491 -4.668924) (xy 197.210381 -4.809466)
			(xy 197.210934 -4.879848) (xy 197.210934 -6.390081) (xy 208.661241 -6.390081) (xy 208.661241 -6.304331)
			(xy 208.669153 -6.218948) (xy 208.684909 -6.134658) (xy 208.708376 -6.052182) (xy 208.739352 -5.972223)
			(xy 208.777574 -5.895463) (xy 208.822715 -5.822557) (xy 208.874391 -5.754128) (xy 208.93216 -5.690758)
			(xy 208.99553 -5.632989) (xy 209.063959 -5.581313) (xy 209.136865 -5.536172) (xy 209.213625 -5.49795)
			(xy 209.293584 -5.466974) (xy 209.37606 -5.443507) (xy 209.46035 -5.427751) (xy 209.545733 -5.419839)
			(xy 209.631483 -5.419839) (xy 209.716866 -5.427751) (xy 209.801156 -5.443507) (xy 209.883632 -5.466974)
			(xy 209.963591 -5.49795) (xy 209.984264 -5.508244) (xy 213.517988 -5.508244) (xy 213.517988 -4.644644)
			(xy 213.518492 -4.61509) (xy 213.526541 -4.556534) (xy 213.542487 -4.499619) (xy 213.566036 -4.445405)
			(xy 213.596747 -4.394902) (xy 213.634049 -4.349052) (xy 213.677246 -4.308709) (xy 213.725535 -4.274623)
			(xy 213.778015 -4.24743) (xy 213.83371 -4.227636) (xy 213.891581 -4.21561) (xy 213.95055 -4.211577)
			(xy 214.009519 -4.21561) (xy 214.06739 -4.227636) (xy 214.123085 -4.24743) (xy 214.175565 -4.274623)
			(xy 214.223854 -4.308709) (xy 214.267051 -4.349052) (xy 214.304353 -4.394902) (xy 214.335064 -4.445405)
			(xy 214.358613 -4.499619) (xy 214.374559 -4.556534) (xy 214.382608 -4.61509) (xy 214.383112 -4.644644)
			(xy 214.383112 -5.508244) (xy 214.382608 -5.537798) (xy 214.374559 -5.596354) (xy 214.358613 -5.653269)
			(xy 214.335064 -5.707483) (xy 214.304353 -5.757986) (xy 214.267051 -5.803836) (xy 214.223854 -5.844179)
			(xy 214.175565 -5.878265) (xy 214.123085 -5.905458) (xy 214.06739 -5.925252) (xy 214.009519 -5.937278)
			(xy 213.95055 -5.941312) (xy 213.891581 -5.937278) (xy 213.83371 -5.925252) (xy 213.778015 -5.905458)
			(xy 213.725535 -5.878265) (xy 213.677246 -5.844179) (xy 213.634049 -5.803836) (xy 213.596747 -5.757986)
			(xy 213.566036 -5.707483) (xy 213.542487 -5.653269) (xy 213.526541 -5.596354) (xy 213.518492 -5.537798)
			(xy 213.517988 -5.508244) (xy 209.984264 -5.508244) (xy 210.040351 -5.536172) (xy 210.113257 -5.581313)
			(xy 210.181686 -5.632989) (xy 210.245056 -5.690758) (xy 210.302825 -5.754128) (xy 210.354501 -5.822557)
			(xy 210.399642 -5.895463) (xy 210.437864 -5.972223) (xy 210.46884 -6.052182) (xy 210.492307 -6.134658)
			(xy 210.508063 -6.218948) (xy 210.515975 -6.304331) (xy 210.51647 -6.347206) (xy 210.515975 -6.390081)
			(xy 215.011241 -6.390081) (xy 215.011241 -6.304331) (xy 215.019153 -6.218948) (xy 215.034909 -6.134658)
			(xy 215.058376 -6.052182) (xy 215.089352 -5.972223) (xy 215.127574 -5.895463) (xy 215.172715 -5.822557)
			(xy 215.224391 -5.754128) (xy 215.28216 -5.690758) (xy 215.34553 -5.632989) (xy 215.413959 -5.581313)
			(xy 215.486865 -5.536172) (xy 215.563625 -5.49795) (xy 215.643584 -5.466974) (xy 215.72606 -5.443507)
			(xy 215.81035 -5.427751) (xy 215.895733 -5.419839) (xy 215.981483 -5.419839) (xy 216.066866 -5.427751)
			(xy 216.151156 -5.443507) (xy 216.233632 -5.466974) (xy 216.313591 -5.49795) (xy 216.390351 -5.536172)
			(xy 216.463257 -5.581313) (xy 216.531686 -5.632989) (xy 216.595056 -5.690758) (xy 216.652825 -5.754128)
			(xy 216.704501 -5.822557) (xy 216.749642 -5.895463) (xy 216.787864 -5.972223) (xy 216.81884 -6.052182)
			(xy 216.842307 -6.134658) (xy 216.858063 -6.218948) (xy 216.865975 -6.304331) (xy 216.86647 -6.347206)
			(xy 216.865975 -6.390081) (xy 296.143921 -6.390081) (xy 296.143921 -6.304331) (xy 296.151833 -6.218948)
			(xy 296.167589 -6.134658) (xy 296.191056 -6.052182) (xy 296.222032 -5.972223) (xy 296.260254 -5.895463)
			(xy 296.305395 -5.822557) (xy 296.357071 -5.754128) (xy 296.41484 -5.690758) (xy 296.47821 -5.632989)
			(xy 296.546639 -5.581313) (xy 296.619545 -5.536172) (xy 296.696305 -5.49795) (xy 296.776264 -5.466974)
			(xy 296.85874 -5.443507) (xy 296.94303 -5.427751) (xy 297.028413 -5.419839) (xy 297.114163 -5.419839)
			(xy 297.199546 -5.427751) (xy 297.283836 -5.443507) (xy 297.366312 -5.466974) (xy 297.446271 -5.49795)
			(xy 297.466944 -5.508244) (xy 298.629324 -5.508244) (xy 298.629324 -4.644644) (xy 298.629828 -4.61509)
			(xy 298.637877 -4.556534) (xy 298.653823 -4.499619) (xy 298.677372 -4.445405) (xy 298.708083 -4.394902)
			(xy 298.745385 -4.349052) (xy 298.788582 -4.308709) (xy 298.836871 -4.274623) (xy 298.889351 -4.24743)
			(xy 298.945046 -4.227636) (xy 299.002917 -4.21561) (xy 299.061886 -4.211577) (xy 299.120855 -4.21561)
			(xy 299.178726 -4.227636) (xy 299.234421 -4.24743) (xy 299.286901 -4.274623) (xy 299.33519 -4.308709)
			(xy 299.378387 -4.349052) (xy 299.415689 -4.394902) (xy 299.4464 -4.445405) (xy 299.469949 -4.499619)
			(xy 299.485895 -4.556534) (xy 299.493944 -4.61509) (xy 299.494448 -4.644644) (xy 299.494448 -5.508244)
			(xy 299.493944 -5.537798) (xy 299.485895 -5.596354) (xy 299.469949 -5.653269) (xy 299.4464 -5.707483)
			(xy 299.415689 -5.757986) (xy 299.378387 -5.803836) (xy 299.33519 -5.844179) (xy 299.286901 -5.878265)
			(xy 299.234421 -5.905458) (xy 299.178726 -5.925252) (xy 299.120855 -5.937278) (xy 299.061886 -5.941312)
			(xy 299.002917 -5.937278) (xy 298.945046 -5.925252) (xy 298.889351 -5.905458) (xy 298.836871 -5.878265)
			(xy 298.788582 -5.844179) (xy 298.745385 -5.803836) (xy 298.708083 -5.757986) (xy 298.677372 -5.707483)
			(xy 298.653823 -5.653269) (xy 298.637877 -5.596354) (xy 298.629828 -5.537798) (xy 298.629324 -5.508244)
			(xy 297.466944 -5.508244) (xy 297.523031 -5.536172) (xy 297.595937 -5.581313) (xy 297.664366 -5.632989)
			(xy 297.727736 -5.690758) (xy 297.785505 -5.754128) (xy 297.837181 -5.822557) (xy 297.882322 -5.895463)
			(xy 297.920544 -5.972223) (xy 297.95152 -6.052182) (xy 297.974987 -6.134658) (xy 297.990743 -6.218948)
			(xy 297.998655 -6.304331) (xy 297.99915 -6.347206) (xy 297.998655 -6.390081) (xy 302.493921 -6.390081)
			(xy 302.493921 -6.304331) (xy 302.501833 -6.218948) (xy 302.517589 -6.134658) (xy 302.541056 -6.052182)
			(xy 302.572032 -5.972223) (xy 302.610254 -5.895463) (xy 302.655395 -5.822557) (xy 302.707071 -5.754128)
			(xy 302.76484 -5.690758) (xy 302.82821 -5.632989) (xy 302.896639 -5.581313) (xy 302.969545 -5.536172)
			(xy 303.046305 -5.49795) (xy 303.126264 -5.466974) (xy 303.20874 -5.443507) (xy 303.29303 -5.427751)
			(xy 303.378413 -5.419839) (xy 303.464163 -5.419839) (xy 303.549546 -5.427751) (xy 303.633836 -5.443507)
			(xy 303.716312 -5.466974) (xy 303.796271 -5.49795) (xy 303.873031 -5.536172) (xy 303.945937 -5.581313)
			(xy 304.014366 -5.632989) (xy 304.077736 -5.690758) (xy 304.135505 -5.754128) (xy 304.187181 -5.822557)
			(xy 304.232322 -5.895463) (xy 304.270544 -5.972223) (xy 304.30152 -6.052182) (xy 304.324987 -6.134658)
			(xy 304.340743 -6.218948) (xy 304.348655 -6.304331) (xy 304.34915 -6.347206) (xy 304.348655 -6.390081)
			(xy 311.155321 -6.390081) (xy 311.155321 -6.304331) (xy 311.163233 -6.218948) (xy 311.178989 -6.134658)
			(xy 311.202456 -6.052182) (xy 311.233432 -5.972223) (xy 311.271654 -5.895463) (xy 311.316795 -5.822557)
			(xy 311.368471 -5.754128) (xy 311.42624 -5.690758) (xy 311.48961 -5.632989) (xy 311.558039 -5.581313)
			(xy 311.630945 -5.536172) (xy 311.707705 -5.49795) (xy 311.787664 -5.466974) (xy 311.87014 -5.443507)
			(xy 311.95443 -5.427751) (xy 312.039813 -5.419839) (xy 312.125563 -5.419839) (xy 312.210946 -5.427751)
			(xy 312.295236 -5.443507) (xy 312.377712 -5.466974) (xy 312.457671 -5.49795) (xy 312.534431 -5.536172)
			(xy 312.607337 -5.581313) (xy 312.675766 -5.632989) (xy 312.739136 -5.690758) (xy 312.796905 -5.754128)
			(xy 312.848581 -5.822557) (xy 312.893722 -5.895463) (xy 312.931944 -5.972223) (xy 312.96292 -6.052182)
			(xy 312.986387 -6.134658) (xy 313.002143 -6.218948) (xy 313.010055 -6.304331) (xy 313.01055 -6.347206)
			(xy 313.010055 -6.390081) (xy 317.505321 -6.390081) (xy 317.505321 -6.304331) (xy 317.513233 -6.218948)
			(xy 317.528989 -6.134658) (xy 317.552456 -6.052182) (xy 317.583432 -5.972223) (xy 317.621654 -5.895463)
			(xy 317.666795 -5.822557) (xy 317.718471 -5.754128) (xy 317.77624 -5.690758) (xy 317.83961 -5.632989)
			(xy 317.908039 -5.581313) (xy 317.980945 -5.536172) (xy 318.057705 -5.49795) (xy 318.137664 -5.466974)
			(xy 318.22014 -5.443507) (xy 318.30443 -5.427751) (xy 318.389813 -5.419839) (xy 318.475563 -5.419839)
			(xy 318.560946 -5.427751) (xy 318.645236 -5.443507) (xy 318.727712 -5.466974) (xy 318.807671 -5.49795)
			(xy 318.884431 -5.536172) (xy 318.957337 -5.581313) (xy 319.025766 -5.632989) (xy 319.089136 -5.690758)
			(xy 319.146905 -5.754128) (xy 319.198581 -5.822557) (xy 319.243722 -5.895463) (xy 319.281944 -5.972223)
			(xy 319.31292 -6.052182) (xy 319.336387 -6.134658) (xy 319.352143 -6.218948) (xy 319.360055 -6.304331)
			(xy 319.36055 -6.347206) (xy 319.360055 -6.390081) (xy 361.894107 -6.390081) (xy 361.894107 -6.304331)
			(xy 361.902019 -6.218948) (xy 361.917775 -6.134658) (xy 361.941242 -6.052182) (xy 361.972218 -5.972223)
			(xy 362.01044 -5.895463) (xy 362.055581 -5.822557) (xy 362.107257 -5.754128) (xy 362.165026 -5.690758)
			(xy 362.228396 -5.632989) (xy 362.296825 -5.581313) (xy 362.369731 -5.536172) (xy 362.446491 -5.49795)
			(xy 362.52645 -5.466974) (xy 362.608926 -5.443507) (xy 362.693216 -5.427751) (xy 362.778599 -5.419839)
			(xy 362.864349 -5.419839) (xy 362.949732 -5.427751) (xy 363.034022 -5.443507) (xy 363.116498 -5.466974)
			(xy 363.196457 -5.49795) (xy 363.273217 -5.536172) (xy 363.346123 -5.581313) (xy 363.414552 -5.632989)
			(xy 363.477922 -5.690758) (xy 363.535691 -5.754128) (xy 363.587367 -5.822557) (xy 363.632508 -5.895463)
			(xy 363.67073 -5.972223) (xy 363.701706 -6.052182) (xy 363.725173 -6.134658) (xy 363.740929 -6.218948)
			(xy 363.748841 -6.304331) (xy 363.749336 -6.347206) (xy 363.748841 -6.390081) (xy 368.244107 -6.390081)
			(xy 368.244107 -6.304331) (xy 368.252019 -6.218948) (xy 368.267775 -6.134658) (xy 368.291242 -6.052182)
			(xy 368.322218 -5.972223) (xy 368.36044 -5.895463) (xy 368.405581 -5.822557) (xy 368.457257 -5.754128)
			(xy 368.515026 -5.690758) (xy 368.578396 -5.632989) (xy 368.646825 -5.581313) (xy 368.719731 -5.536172)
			(xy 368.796491 -5.49795) (xy 368.87645 -5.466974) (xy 368.958926 -5.443507) (xy 369.043216 -5.427751)
			(xy 369.128599 -5.419839) (xy 369.214349 -5.419839) (xy 369.299732 -5.427751) (xy 369.384022 -5.443507)
			(xy 369.466498 -5.466974) (xy 369.546457 -5.49795) (xy 369.623217 -5.536172) (xy 369.696123 -5.581313)
			(xy 369.764552 -5.632989) (xy 369.827922 -5.690758) (xy 369.885691 -5.754128) (xy 369.937367 -5.822557)
			(xy 369.982508 -5.895463) (xy 370.02073 -5.972223) (xy 370.051706 -6.052182) (xy 370.075173 -6.134658)
			(xy 370.090929 -6.218948) (xy 370.098841 -6.304331) (xy 370.099336 -6.347206) (xy 370.098841 -6.390081)
			(xy 370.090929 -6.475464) (xy 370.075173 -6.559754) (xy 370.051706 -6.64223) (xy 370.02073 -6.722189)
			(xy 369.982508 -6.798949) (xy 369.937367 -6.871855) (xy 369.885691 -6.940284) (xy 369.827922 -7.003654)
			(xy 369.764552 -7.061423) (xy 369.696123 -7.113099) (xy 369.623217 -7.15824) (xy 369.546457 -7.196462)
			(xy 369.466498 -7.227438) (xy 369.384022 -7.250905) (xy 369.299732 -7.266661) (xy 369.214349 -7.274573)
			(xy 369.128599 -7.274573) (xy 369.043216 -7.266661) (xy 368.958926 -7.250905) (xy 368.87645 -7.227438)
			(xy 368.796491 -7.196462) (xy 368.719731 -7.15824) (xy 368.646825 -7.113099) (xy 368.578396 -7.061423)
			(xy 368.515026 -7.003654) (xy 368.457257 -6.940284) (xy 368.405581 -6.871855) (xy 368.36044 -6.798949)
			(xy 368.322218 -6.722189) (xy 368.291242 -6.64223) (xy 368.267775 -6.559754) (xy 368.252019 -6.475464)
			(xy 368.244107 -6.390081) (xy 363.748841 -6.390081) (xy 363.740929 -6.475464) (xy 363.725173 -6.559754)
			(xy 363.701706 -6.64223) (xy 363.67073 -6.722189) (xy 363.632508 -6.798949) (xy 363.587367 -6.871855)
			(xy 363.535691 -6.940284) (xy 363.477922 -7.003654) (xy 363.414552 -7.061423) (xy 363.346123 -7.113099)
			(xy 363.273217 -7.15824) (xy 363.196457 -7.196462) (xy 363.116498 -7.227438) (xy 363.034022 -7.250905)
			(xy 362.949732 -7.266661) (xy 362.864349 -7.274573) (xy 362.778599 -7.274573) (xy 362.693216 -7.266661)
			(xy 362.608926 -7.250905) (xy 362.52645 -7.227438) (xy 362.446491 -7.196462) (xy 362.369731 -7.15824)
			(xy 362.296825 -7.113099) (xy 362.228396 -7.061423) (xy 362.165026 -7.003654) (xy 362.107257 -6.940284)
			(xy 362.055581 -6.871855) (xy 362.01044 -6.798949) (xy 361.972218 -6.722189) (xy 361.941242 -6.64223)
			(xy 361.917775 -6.559754) (xy 361.902019 -6.475464) (xy 361.894107 -6.390081) (xy 319.360055 -6.390081)
			(xy 319.352143 -6.475464) (xy 319.336387 -6.559754) (xy 319.31292 -6.64223) (xy 319.281944 -6.722189)
			(xy 319.243722 -6.798949) (xy 319.198581 -6.871855) (xy 319.146905 -6.940284) (xy 319.089136 -7.003654)
			(xy 319.025766 -7.061423) (xy 318.957337 -7.113099) (xy 318.884431 -7.15824) (xy 318.807671 -7.196462)
			(xy 318.727712 -7.227438) (xy 318.645236 -7.250905) (xy 318.560946 -7.266661) (xy 318.475563 -7.274573)
			(xy 318.389813 -7.274573) (xy 318.30443 -7.266661) (xy 318.22014 -7.250905) (xy 318.137664 -7.227438)
			(xy 318.057705 -7.196462) (xy 317.980945 -7.15824) (xy 317.908039 -7.113099) (xy 317.83961 -7.061423)
			(xy 317.77624 -7.003654) (xy 317.718471 -6.940284) (xy 317.666795 -6.871855) (xy 317.621654 -6.798949)
			(xy 317.583432 -6.722189) (xy 317.552456 -6.64223) (xy 317.528989 -6.559754) (xy 317.513233 -6.475464)
			(xy 317.505321 -6.390081) (xy 313.010055 -6.390081) (xy 313.002143 -6.475464) (xy 312.986387 -6.559754)
			(xy 312.96292 -6.64223) (xy 312.931944 -6.722189) (xy 312.893722 -6.798949) (xy 312.848581 -6.871855)
			(xy 312.796905 -6.940284) (xy 312.739136 -7.003654) (xy 312.675766 -7.061423) (xy 312.607337 -7.113099)
			(xy 312.534431 -7.15824) (xy 312.457671 -7.196462) (xy 312.377712 -7.227438) (xy 312.295236 -7.250905)
			(xy 312.210946 -7.266661) (xy 312.125563 -7.274573) (xy 312.039813 -7.274573) (xy 311.95443 -7.266661)
			(xy 311.87014 -7.250905) (xy 311.787664 -7.227438) (xy 311.707705 -7.196462) (xy 311.630945 -7.15824)
			(xy 311.558039 -7.113099) (xy 311.48961 -7.061423) (xy 311.42624 -7.003654) (xy 311.368471 -6.940284)
			(xy 311.316795 -6.871855) (xy 311.271654 -6.798949) (xy 311.233432 -6.722189) (xy 311.202456 -6.64223)
			(xy 311.178989 -6.559754) (xy 311.163233 -6.475464) (xy 311.155321 -6.390081) (xy 304.348655 -6.390081)
			(xy 304.340743 -6.475464) (xy 304.324987 -6.559754) (xy 304.30152 -6.64223) (xy 304.270544 -6.722189)
			(xy 304.232322 -6.798949) (xy 304.187181 -6.871855) (xy 304.135505 -6.940284) (xy 304.077736 -7.003654)
			(xy 304.014366 -7.061423) (xy 303.945937 -7.113099) (xy 303.873031 -7.15824) (xy 303.796271 -7.196462)
			(xy 303.716312 -7.227438) (xy 303.633836 -7.250905) (xy 303.549546 -7.266661) (xy 303.464163 -7.274573)
			(xy 303.378413 -7.274573) (xy 303.29303 -7.266661) (xy 303.20874 -7.250905) (xy 303.126264 -7.227438)
			(xy 303.046305 -7.196462) (xy 302.969545 -7.15824) (xy 302.896639 -7.113099) (xy 302.82821 -7.061423)
			(xy 302.76484 -7.003654) (xy 302.707071 -6.940284) (xy 302.655395 -6.871855) (xy 302.610254 -6.798949)
			(xy 302.572032 -6.722189) (xy 302.541056 -6.64223) (xy 302.517589 -6.559754) (xy 302.501833 -6.475464)
			(xy 302.493921 -6.390081) (xy 297.998655 -6.390081) (xy 297.990743 -6.475464) (xy 297.974987 -6.559754)
			(xy 297.95152 -6.64223) (xy 297.920544 -6.722189) (xy 297.882322 -6.798949) (xy 297.837181 -6.871855)
			(xy 297.785505 -6.940284) (xy 297.727736 -7.003654) (xy 297.664366 -7.061423) (xy 297.595937 -7.113099)
			(xy 297.523031 -7.15824) (xy 297.446271 -7.196462) (xy 297.366312 -7.227438) (xy 297.283836 -7.250905)
			(xy 297.199546 -7.266661) (xy 297.114163 -7.274573) (xy 297.028413 -7.274573) (xy 296.94303 -7.266661)
			(xy 296.85874 -7.250905) (xy 296.776264 -7.227438) (xy 296.696305 -7.196462) (xy 296.619545 -7.15824)
			(xy 296.546639 -7.113099) (xy 296.47821 -7.061423) (xy 296.41484 -7.003654) (xy 296.357071 -6.940284)
			(xy 296.305395 -6.871855) (xy 296.260254 -6.798949) (xy 296.222032 -6.722189) (xy 296.191056 -6.64223)
			(xy 296.167589 -6.559754) (xy 296.151833 -6.475464) (xy 296.143921 -6.390081) (xy 216.865975 -6.390081)
			(xy 216.858063 -6.475464) (xy 216.842307 -6.559754) (xy 216.81884 -6.64223) (xy 216.787864 -6.722189)
			(xy 216.749642 -6.798949) (xy 216.704501 -6.871855) (xy 216.652825 -6.940284) (xy 216.595056 -7.003654)
			(xy 216.531686 -7.061423) (xy 216.463257 -7.113099) (xy 216.390351 -7.15824) (xy 216.313591 -7.196462)
			(xy 216.233632 -7.227438) (xy 216.151156 -7.250905) (xy 216.066866 -7.266661) (xy 215.981483 -7.274573)
			(xy 215.895733 -7.274573) (xy 215.81035 -7.266661) (xy 215.72606 -7.250905) (xy 215.643584 -7.227438)
			(xy 215.563625 -7.196462) (xy 215.486865 -7.15824) (xy 215.413959 -7.113099) (xy 215.34553 -7.061423)
			(xy 215.28216 -7.003654) (xy 215.224391 -6.940284) (xy 215.172715 -6.871855) (xy 215.127574 -6.798949)
			(xy 215.089352 -6.722189) (xy 215.058376 -6.64223) (xy 215.034909 -6.559754) (xy 215.019153 -6.475464)
			(xy 215.011241 -6.390081) (xy 210.515975 -6.390081) (xy 210.508063 -6.475464) (xy 210.492307 -6.559754)
			(xy 210.46884 -6.64223) (xy 210.437864 -6.722189) (xy 210.399642 -6.798949) (xy 210.354501 -6.871855)
			(xy 210.302825 -6.940284) (xy 210.245056 -7.003654) (xy 210.181686 -7.061423) (xy 210.113257 -7.113099)
			(xy 210.040351 -7.15824) (xy 209.963591 -7.196462) (xy 209.883632 -7.227438) (xy 209.801156 -7.250905)
			(xy 209.716866 -7.266661) (xy 209.631483 -7.274573) (xy 209.545733 -7.274573) (xy 209.46035 -7.266661)
			(xy 209.37606 -7.250905) (xy 209.293584 -7.227438) (xy 209.213625 -7.196462) (xy 209.136865 -7.15824)
			(xy 209.063959 -7.113099) (xy 208.99553 -7.061423) (xy 208.93216 -7.003654) (xy 208.874391 -6.940284)
			(xy 208.822715 -6.871855) (xy 208.777574 -6.798949) (xy 208.739352 -6.722189) (xy 208.708376 -6.64223)
			(xy 208.684909 -6.559754) (xy 208.669153 -6.475464) (xy 208.661241 -6.390081) (xy 197.210934 -6.390081)
			(xy 197.210934 -7.78002) (xy 197.211456 -7.835788) (xy 197.219793 -7.947013) (xy 197.236418 -8.057304)
			(xy 197.261239 -8.166044) (xy 197.294116 -8.272625) (xy 197.334866 -8.376451) (xy 197.383261 -8.476941)
			(xy 197.439031 -8.573534) (xy 197.501863 -8.66569) (xy 197.571406 -8.752892) (xy 197.647271 -8.834653)
			(xy 197.729034 -8.910516) (xy 197.816238 -8.980057) (xy 197.908394 -9.042887) (xy 198.004989 -9.098654)
			(xy 198.10548 -9.147047) (xy 198.209307 -9.187795) (xy 198.315889 -9.22067) (xy 198.42463 -9.245488)
			(xy 198.534921 -9.262111) (xy 198.646146 -9.270445) (xy 198.701914 -9.271) (xy 223.300036 -9.271)
			(xy 223.370417 -9.271495) (xy 223.510959 -9.279389) (xy 223.650836 -9.295152) (xy 223.78961 -9.318732)
			(xy 223.926844 -9.350057) (xy 224.062105 -9.389027) (xy 224.194968 -9.435519) (xy 224.325015 -9.489388)
			(xy 224.451838 -9.550465) (xy 224.575036 -9.618556) (xy 224.694222 -9.693447) (xy 224.809022 -9.774904)
			(xy 224.919074 -9.862669) (xy 225.024032 -9.956467) (xy 225.123566 -10.056003) (xy 225.217361 -10.160962)
			(xy 225.305125 -10.271016) (xy 225.386579 -10.385818) (xy 225.461469 -10.505006) (xy 225.529557 -10.628205)
			(xy 225.590631 -10.755029) (xy 225.644498 -10.885077) (xy 225.690988 -11.017941) (xy 225.729955 -11.153203)
			(xy 225.761277 -11.290437) (xy 225.784855 -11.429211) (xy 225.800615 -11.569089) (xy 225.808507 -11.709631)
			(xy 225.809048 -11.780012) (xy 225.809048 -33.120076) (xy 225.809549 -33.152224) (xy 225.817939 -33.21597)
			(xy 225.834578 -33.278076) (xy 225.859182 -33.337478) (xy 225.891329 -33.39316) (xy 225.93047 -33.44417)
			(xy 225.975934 -33.489634) (xy 226.026945 -33.528774) (xy 226.082627 -33.560921) (xy 226.14203 -33.585524)
			(xy 226.204136 -33.602162) (xy 226.267882 -33.610551) (xy 226.30003 -33.611058)
		)
		(stroke
			(width 0)
			(type solid)
		)
		(fill yes)
		(layer "In16.Cu")
		(net "DELTA_L_GND_1")
	)
	(gr_poly
		(pts
			(xy 194.445128 -441.480956) (xy 194.455142 -441.480531) (xy 194.473642 -441.472854) (xy 194.487795 -441.458682)
			(xy 194.495445 -441.440171) (xy 194.495928 -441.430156) (xy 194.495928 -441.17006) (xy 194.49641 -441.126022)
			(xy 194.50409 -441.03828) (xy 194.519387 -440.951542) (xy 194.542185 -440.866466) (xy 194.572311 -440.783702)
			(xy 194.609536 -440.703878) (xy 194.653576 -440.627602) (xy 194.704095 -440.555454) (xy 194.760711 -440.487984)
			(xy 194.822991 -440.425704) (xy 194.890462 -440.369089) (xy 194.96261 -440.31857) (xy 195.038887 -440.274531)
			(xy 195.118711 -440.237308) (xy 195.201476 -440.207182) (xy 195.286551 -440.184385) (xy 195.37329 -440.169088)
			(xy 195.461032 -440.16141) (xy 195.50507 -440.160918) (xy 276.314916 -440.160918) (xy 276.358955 -440.161399)
			(xy 276.446699 -440.169077) (xy 276.533439 -440.184372) (xy 276.618516 -440.207169) (xy 276.701283 -440.237294)
			(xy 276.781109 -440.274518) (xy 276.857388 -440.318557) (xy 276.929538 -440.369076) (xy 276.99701 -440.425692)
			(xy 277.059292 -440.487972) (xy 277.115909 -440.555443) (xy 277.16643 -440.627592) (xy 277.210471 -440.703869)
			(xy 277.247697 -440.783695) (xy 277.277823 -440.866461) (xy 277.300622 -440.951538) (xy 277.31592 -441.038278)
			(xy 277.3236 -441.126021) (xy 277.324058 -441.17006) (xy 277.324058 -441.430156) (xy 277.324469 -441.440186)
			(xy 277.33213 -441.458725) (xy 277.346302 -441.472922) (xy 277.364828 -441.480614) (xy 277.374858 -441.480956)
			(xy 463.300064 -441.480956) (xy 463.355834 -441.480449) (xy 463.467062 -441.472116) (xy 463.577357 -441.455494)
			(xy 463.686101 -441.430676) (xy 463.792686 -441.397801) (xy 463.896517 -441.357052) (xy 463.997011 -441.308658)
			(xy 464.093608 -441.252889) (xy 464.185768 -441.190057) (xy 464.272974 -441.120513) (xy 464.354739 -441.044647)
			(xy 464.430606 -440.962883) (xy 464.50015 -440.875677) (xy 464.562982 -440.783519) (xy 464.618752 -440.686922)
			(xy 464.667147 -440.586428) (xy 464.707897 -440.482598) (xy 464.740773 -440.376013) (xy 464.765592 -440.267269)
			(xy 464.782215 -440.156974) (xy 464.790548 -440.045746) (xy 464.791044 -439.989976) (xy 464.791044 -409.528264)
			(xy 464.791546 -409.457891) (xy 464.799454 -409.317366) (xy 464.815227 -409.177505) (xy 464.838815 -409.038749)
			(xy 464.870143 -408.901532) (xy 464.909113 -408.766288) (xy 464.955604 -408.633441) (xy 465.009467 -408.503408)
			(xy 465.070535 -408.376599) (xy 465.138615 -408.253413) (xy 465.213493 -408.134236) (xy 465.294933 -408.019444)
			(xy 465.38268 -407.909398) (xy 465.476458 -407.804443) (xy 465.525866 -407.754328) (xy 467.354412 -405.925782)
			(xy 467.391703 -405.887819) (xy 467.461396 -405.807388) (xy 467.525176 -405.722192) (xy 467.582717 -405.632663)
			(xy 467.633725 -405.539259) (xy 467.677942 -405.442454) (xy 467.715142 -405.342742) (xy 467.745135 -405.240631)
			(xy 467.767768 -405.136641) (xy 467.782928 -405.031301) (xy 467.790535 -404.925148) (xy 467.791038 -404.871936)
			(xy 467.791038 -82.82813) (xy 467.791541 -82.757757) (xy 467.799451 -82.617233) (xy 467.815226 -82.477373)
			(xy 467.838815 -82.338618) (xy 467.870145 -82.201402) (xy 467.909116 -82.066159) (xy 467.955608 -81.933313)
			(xy 468.009473 -81.803282) (xy 468.070541 -81.676474) (xy 468.138622 -81.553289) (xy 468.213501 -81.434114)
			(xy 468.294942 -81.319323) (xy 468.382689 -81.209278) (xy 468.476467 -81.104324) (xy 468.52586 -81.054194)
			(xy 470.854278 -78.725776) (xy 470.891569 -78.687813) (xy 470.961264 -78.607383) (xy 471.025045 -78.522187)
			(xy 471.082586 -78.432659) (xy 471.133596 -78.339255) (xy 471.177813 -78.24245) (xy 471.215013 -78.142738)
			(xy 471.245007 -78.040626) (xy 471.267641 -77.936636) (xy 471.2828 -77.831296) (xy 471.290407 -77.725143)
			(xy 471.290904 -77.67193) (xy 471.290904 -13.780008) (xy 471.290383 -13.724238) (xy 471.282048 -13.613011)
			(xy 471.265425 -13.502718) (xy 471.240606 -13.393975) (xy 471.20773 -13.287391) (xy 471.166981 -13.183562)
			(xy 471.118587 -13.083068) (xy 471.062818 -12.986472) (xy 470.999987 -12.894314) (xy 470.930444 -12.807108)
			(xy 470.854579 -12.725344) (xy 470.772816 -12.649477) (xy 470.685612 -12.579932) (xy 470.593455 -12.517099)
			(xy 470.49686 -12.461328) (xy 470.396367 -12.412932) (xy 470.292539 -12.372181) (xy 470.185956 -12.339303)
			(xy 470.077214 -12.314481) (xy 469.966921 -12.297855) (xy 469.855694 -12.289518) (xy 469.799924 -12.289028)
			(xy 458.20203 -12.289028) (xy 458.131647 -12.288544) (xy 457.991102 -12.280653) (xy 457.85122 -12.264894)
			(xy 457.712443 -12.241316) (xy 457.575205 -12.209994) (xy 457.43994 -12.171027) (xy 457.307072 -12.124536)
			(xy 457.177021 -12.070668) (xy 457.050194 -12.009593) (xy 456.926991 -11.941503) (xy 456.8078 -11.866612)
			(xy 456.692996 -11.785156) (xy 456.582939 -11.69739) (xy 456.477977 -11.603592) (xy 456.378439 -11.504056)
			(xy 456.284639 -11.399096) (xy 456.196872 -11.289041) (xy 456.115413 -11.174238) (xy 456.04052 -11.055048)
			(xy 455.972428 -10.931847) (xy 455.911351 -10.805021) (xy 455.857481 -10.674971) (xy 455.810987 -10.542104)
			(xy 455.772017 -10.406839) (xy 455.740693 -10.269603) (xy 455.717113 -10.130825) (xy 455.701351 -9.990944)
			(xy 455.693457 -9.850399) (xy 455.693018 -9.780016) (xy 455.693018 -0.559816) (xy 455.692533 -0.549805)
			(xy 455.684877 -0.531304) (xy 455.670724 -0.517142) (xy 455.652229 -0.509474) (xy 455.642218 -0.509016)
			(xy 388.161784 -0.509016) (xy 388.15178 -0.509507) (xy 388.133296 -0.51717) (xy 388.119152 -0.531323)
			(xy 388.111501 -0.549811) (xy 388.110984 -0.559816) (xy 388.110984 -5.169916) (xy 388.849623 -5.169916)
			(xy 388.85363 -5.081961) (xy 388.865619 -4.994736) (xy 388.88549 -4.908962) (xy 388.913078 -4.82535)
			(xy 388.948156 -4.744593) (xy 388.990432 -4.667361) (xy 389.039555 -4.594293) (xy 389.09512 -4.525995)
			(xy 389.156665 -4.463033) (xy 389.223681 -4.405928) (xy 389.295611 -4.355154) (xy 389.371861 -4.311131)
			(xy 389.451799 -4.274224) (xy 389.534761 -4.244739) (xy 389.62006 -4.222921) (xy 389.70699 -4.20895)
			(xy 389.794831 -4.202941) (xy 389.882854 -4.204945) (xy 389.97033 -4.214946) (xy 390.056534 -4.232859)
			(xy 390.140752 -4.258537) (xy 390.222286 -4.291767) (xy 390.300461 -4.332274) (xy 390.374628 -4.379722)
			(xy 390.444173 -4.433717) (xy 390.50852 -4.493813) (xy 390.567136 -4.559512) (xy 390.619534 -4.630268)
			(xy 390.665281 -4.705496) (xy 390.703998 -4.784572) (xy 390.735364 -4.866842) (xy 390.759118 -4.951623)
			(xy 390.766309 -4.990667) (xy 394.939038 -4.990667) (xy 394.939038 -4.936133) (xy 394.946799 -4.882155)
			(xy 394.962162 -4.82983) (xy 394.984815 -4.780224) (xy 395.014296 -4.734346) (xy 395.050007 -4.693131)
			(xy 395.091219 -4.657417) (xy 395.137094 -4.627931) (xy 395.186698 -4.605274) (xy 395.239021 -4.589906)
			(xy 395.292999 -4.582141) (xy 395.320266 -4.581652) (xy 396.183866 -4.581652) (xy 396.21114 -4.582085)
			(xy 396.265132 -4.589844) (xy 396.317471 -4.605208) (xy 396.36709 -4.627864) (xy 396.41298 -4.657352)
			(xy 396.454205 -4.693071) (xy 396.489928 -4.734293) (xy 396.51942 -4.78018) (xy 396.542081 -4.829797)
			(xy 396.557449 -4.882135) (xy 396.565212 -4.936126) (xy 396.565212 -4.99067) (xy 398.538915 -4.99067)
			(xy 398.538915 -4.93613) (xy 398.546678 -4.882144) (xy 398.562044 -4.829813) (xy 398.584701 -4.780201)
			(xy 398.614188 -4.734318) (xy 398.649905 -4.6931) (xy 398.691125 -4.657383) (xy 398.737008 -4.627897)
			(xy 398.78662 -4.605241) (xy 398.838952 -4.589876) (xy 398.892938 -4.582115) (xy 398.920208 -4.581652)
			(xy 399.783808 -4.581652) (xy 399.811078 -4.582111) (xy 399.865063 -4.589874) (xy 399.917393 -4.60524)
			(xy 399.967004 -4.627898) (xy 400.012886 -4.657385) (xy 400.054104 -4.693102) (xy 400.08982 -4.734321)
			(xy 400.119306 -4.780203) (xy 400.141962 -4.829814) (xy 400.157328 -4.882145) (xy 400.16509 -4.93613)
			(xy 400.16509 -4.990666) (xy 402.138938 -4.990666) (xy 402.138938 -4.936134) (xy 402.146698 -4.882157)
			(xy 402.162061 -4.829833) (xy 402.184712 -4.780228) (xy 402.214192 -4.734351) (xy 402.249901 -4.693136)
			(xy 402.291111 -4.657422) (xy 402.336984 -4.627936) (xy 402.386586 -4.605278) (xy 402.438908 -4.589909)
			(xy 402.492884 -4.582142) (xy 402.52015 -4.581652) (xy 403.38375 -4.581652) (xy 403.411024 -4.582084)
			(xy 403.465019 -4.589841) (xy 403.517359 -4.605203) (xy 403.56698 -4.627859) (xy 403.612872 -4.657346)
			(xy 403.6541 -4.693065) (xy 403.689824 -4.734288) (xy 403.719317 -4.780176) (xy 403.741979 -4.829794)
			(xy 403.757349 -4.882132) (xy 403.765112 -4.936126) (xy 403.765112 -4.990672) (xy 405.739016 -4.990672)
			(xy 405.739016 -4.936128) (xy 405.746779 -4.882139) (xy 405.762147 -4.829805) (xy 405.784807 -4.78019)
			(xy 405.814298 -4.734306) (xy 405.850019 -4.693086) (xy 405.891243 -4.65737) (xy 405.937131 -4.627885)
			(xy 405.986748 -4.605231) (xy 406.039084 -4.589869) (xy 406.093074 -4.582112) (xy 406.120346 -4.581652)
			(xy 406.983946 -4.581652) (xy 407.011214 -4.582114) (xy 407.065195 -4.589881) (xy 407.117521 -4.605251)
			(xy 407.167127 -4.62791) (xy 407.213004 -4.657399) (xy 407.254217 -4.693115) (xy 407.289929 -4.734333)
			(xy 407.319412 -4.780213) (xy 407.342065 -4.829822) (xy 407.357429 -4.88215) (xy 407.36519 -4.936132)
			(xy 407.36519 -4.990668) (xy 407.36519 -4.99067) (xy 414.849015 -4.99067) (xy 414.849015 -4.93613)
			(xy 414.856778 -4.882144) (xy 414.872144 -4.829812) (xy 414.894801 -4.7802) (xy 414.924289 -4.734318)
			(xy 414.960006 -4.693099) (xy 415.001226 -4.657383) (xy 415.047109 -4.627896) (xy 415.096722 -4.60524)
			(xy 415.149054 -4.589875) (xy 415.20304 -4.582115) (xy 415.23031 -4.581652) (xy 416.09391 -4.581652)
			(xy 416.12118 -4.582111) (xy 416.175164 -4.589874) (xy 416.227495 -4.605241) (xy 416.277105 -4.627899)
			(xy 416.322987 -4.657386) (xy 416.364205 -4.693102) (xy 416.39992 -4.734321) (xy 416.429406 -4.780203)
			(xy 416.452062 -4.829815) (xy 416.467428 -4.882145) (xy 416.47519 -4.93613) (xy 416.47519 -4.990666)
			(xy 418.449038 -4.990666) (xy 418.449038 -4.936134) (xy 418.456798 -4.882156) (xy 418.472161 -4.829833)
			(xy 418.494813 -4.780227) (xy 418.524293 -4.734351) (xy 418.560002 -4.693136) (xy 418.601212 -4.657422)
			(xy 418.647085 -4.627936) (xy 418.696688 -4.605278) (xy 418.749009 -4.589909) (xy 418.802986 -4.582142)
			(xy 418.830252 -4.581652) (xy 419.693852 -4.581652) (xy 419.721126 -4.582084) (xy 419.77512 -4.589841)
			(xy 419.827461 -4.605204) (xy 419.877082 -4.627859) (xy 419.922973 -4.657347) (xy 419.9642 -4.693066)
			(xy 419.999924 -4.734288) (xy 420.029418 -4.780176) (xy 420.052079 -4.829794) (xy 420.067449 -4.882133)
			(xy 420.075212 -4.936126) (xy 420.075212 -4.990672) (xy 426.059016 -4.990672) (xy 426.059016 -4.936128)
			(xy 426.066779 -4.882139) (xy 426.082147 -4.829805) (xy 426.104807 -4.78019) (xy 426.134298 -4.734306)
			(xy 426.170019 -4.693086) (xy 426.211243 -4.65737) (xy 426.257131 -4.627885) (xy 426.306748 -4.605231)
			(xy 426.359084 -4.589869) (xy 426.413074 -4.582112) (xy 426.440346 -4.581652) (xy 427.303946 -4.581652)
			(xy 427.331214 -4.582114) (xy 427.385195 -4.589881) (xy 427.437521 -4.605251) (xy 427.487127 -4.62791)
			(xy 427.533004 -4.657399) (xy 427.574217 -4.693115) (xy 427.609929 -4.734333) (xy 427.639412 -4.780213)
			(xy 427.662065 -4.829822) (xy 427.677429 -4.88215) (xy 427.68519 -4.936132) (xy 427.68519 -4.990668)
			(xy 429.659038 -4.990668) (xy 429.659038 -4.936132) (xy 429.666799 -4.882152) (xy 429.682164 -4.829825)
			(xy 429.704818 -4.780217) (xy 429.734302 -4.734339) (xy 429.770014 -4.693123) (xy 429.811229 -4.657409)
			(xy 429.857107 -4.627924) (xy 429.906714 -4.605268) (xy 429.95904 -4.589902) (xy 430.01302 -4.582139)
			(xy 430.040288 -4.581652) (xy 430.903888 -4.581652) (xy 430.931161 -4.582087) (xy 430.985151 -4.589848)
			(xy 431.037487 -4.605214) (xy 431.087103 -4.627871) (xy 431.13299 -4.65736) (xy 431.174213 -4.693078)
			(xy 431.209933 -4.7343) (xy 431.239423 -4.780186) (xy 431.262082 -4.829802) (xy 431.27745 -4.882138)
			(xy 431.285212 -4.936127) (xy 431.285212 -4.990673) (xy 431.27745 -5.044662) (xy 431.262082 -5.096998)
			(xy 431.239423 -5.146614) (xy 431.209933 -5.1925) (xy 431.174213 -5.233722) (xy 431.13299 -5.26944)
			(xy 431.087103 -5.298929) (xy 431.037487 -5.321586) (xy 430.985151 -5.336952) (xy 430.931161 -5.344713)
			(xy 430.903888 -5.345176) (xy 430.040288 -5.345176) (xy 430.01302 -5.344661) (xy 429.95904 -5.336898)
			(xy 429.906714 -5.321532) (xy 429.857107 -5.298876) (xy 429.811229 -5.269391) (xy 429.770014 -5.233677)
			(xy 429.734302 -5.192461) (xy 429.704818 -5.146583) (xy 429.682164 -5.096975) (xy 429.666799 -5.044648)
			(xy 429.659038 -4.990668) (xy 427.68519 -4.990668) (xy 427.677429 -5.04465) (xy 427.662065 -5.096978)
			(xy 427.639412 -5.146587) (xy 427.609929 -5.192467) (xy 427.574217 -5.233685) (xy 427.533004 -5.269401)
			(xy 427.487127 -5.29889) (xy 427.437521 -5.321549) (xy 427.385195 -5.336919) (xy 427.331214 -5.344686)
			(xy 427.303946 -5.345176) (xy 426.440346 -5.345176) (xy 426.413074 -5.344688) (xy 426.359084 -5.336931)
			(xy 426.306748 -5.321569) (xy 426.257131 -5.298915) (xy 426.211243 -5.26943) (xy 426.170019 -5.233714)
			(xy 426.134298 -5.192494) (xy 426.104807 -5.14661) (xy 426.082147 -5.096995) (xy 426.066779 -5.044661)
			(xy 426.059016 -4.990672) (xy 420.075212 -4.990672) (xy 420.075212 -4.990674) (xy 420.067449 -5.044667)
			(xy 420.052079 -5.097006) (xy 420.029418 -5.146624) (xy 419.999924 -5.192512) (xy 419.9642 -5.233734)
			(xy 419.922973 -5.269453) (xy 419.877082 -5.298941) (xy 419.827461 -5.321596) (xy 419.77512 -5.336959)
			(xy 419.721126 -5.344716) (xy 419.693852 -5.345176) (xy 418.830252 -5.345176) (xy 418.802986 -5.344658)
			(xy 418.749009 -5.336891) (xy 418.696688 -5.321522) (xy 418.647085 -5.298864) (xy 418.601212 -5.269378)
			(xy 418.560002 -5.233664) (xy 418.524293 -5.192449) (xy 418.494813 -5.146573) (xy 418.472161 -5.096967)
			(xy 418.456798 -5.044644) (xy 418.449038 -4.990666) (xy 416.47519 -4.990666) (xy 416.47519 -4.99067)
			(xy 416.467428 -5.044655) (xy 416.452062 -5.096985) (xy 416.429406 -5.146597) (xy 416.39992 -5.192479)
			(xy 416.364205 -5.233698) (xy 416.322987 -5.269414) (xy 416.277105 -5.298901) (xy 416.227495 -5.321559)
			(xy 416.175164 -5.336926) (xy 416.12118 -5.344689) (xy 416.09391 -5.345176) (xy 415.23031 -5.345176)
			(xy 415.20304 -5.344685) (xy 415.149054 -5.336925) (xy 415.096722 -5.32156) (xy 415.047109 -5.298904)
			(xy 415.001226 -5.269417) (xy 414.960006 -5.233701) (xy 414.924289 -5.192482) (xy 414.894801 -5.1466)
			(xy 414.872144 -5.096988) (xy 414.856778 -5.044656) (xy 414.849015 -4.99067) (xy 407.36519 -4.99067)
			(xy 407.357429 -5.04465) (xy 407.342065 -5.096978) (xy 407.319412 -5.146587) (xy 407.289929 -5.192467)
			(xy 407.254217 -5.233685) (xy 407.213004 -5.269401) (xy 407.167127 -5.29889) (xy 407.117521 -5.321549)
			(xy 407.065195 -5.336919) (xy 407.011214 -5.344686) (xy 406.983946 -5.345176) (xy 406.120346 -5.345176)
			(xy 406.093074 -5.344688) (xy 406.039084 -5.336931) (xy 405.986748 -5.321569) (xy 405.937131 -5.298915)
			(xy 405.891243 -5.26943) (xy 405.850019 -5.233714) (xy 405.814298 -5.192494) (xy 405.784807 -5.14661)
			(xy 405.762147 -5.096995) (xy 405.746779 -5.044661) (xy 405.739016 -4.990672) (xy 403.765112 -4.990672)
			(xy 403.765112 -4.990674) (xy 403.757349 -5.044668) (xy 403.741979 -5.097006) (xy 403.719317 -5.146624)
			(xy 403.689824 -5.192512) (xy 403.6541 -5.233735) (xy 403.612872 -5.269454) (xy 403.56698 -5.298941)
			(xy 403.517359 -5.321597) (xy 403.465019 -5.336959) (xy 403.411024 -5.344716) (xy 403.38375 -5.345176)
			(xy 402.52015 -5.345176) (xy 402.492884 -5.344658) (xy 402.438908 -5.336891) (xy 402.386586 -5.321522)
			(xy 402.336984 -5.298864) (xy 402.291111 -5.269378) (xy 402.249901 -5.233664) (xy 402.214192 -5.192449)
			(xy 402.184712 -5.146572) (xy 402.162061 -5.096967) (xy 402.146698 -5.044643) (xy 402.138938 -4.990666)
			(xy 400.16509 -4.990666) (xy 400.16509 -4.99067) (xy 400.157328 -5.044655) (xy 400.141962 -5.096986)
			(xy 400.119306 -5.146597) (xy 400.08982 -5.192479) (xy 400.054104 -5.233698) (xy 400.012886 -5.269415)
			(xy 399.967004 -5.298902) (xy 399.917393 -5.32156) (xy 399.865063 -5.336926) (xy 399.811078 -5.344689)
			(xy 399.783808 -5.345176) (xy 398.920208 -5.345176) (xy 398.892938 -5.344685) (xy 398.838952 -5.336924)
			(xy 398.78662 -5.321559) (xy 398.737008 -5.298903) (xy 398.691125 -5.269417) (xy 398.649905 -5.2337)
			(xy 398.614188 -5.192482) (xy 398.584701 -5.146599) (xy 398.562044 -5.096987) (xy 398.546678 -5.044656)
			(xy 398.538915 -4.99067) (xy 396.565212 -4.99067) (xy 396.565212 -4.990674) (xy 396.557449 -5.044665)
			(xy 396.542081 -5.097003) (xy 396.51942 -5.14662) (xy 396.489928 -5.192507) (xy 396.454205 -5.233729)
			(xy 396.41298 -5.269448) (xy 396.36709 -5.298936) (xy 396.317471 -5.321592) (xy 396.265132 -5.336956)
			(xy 396.21114 -5.344715) (xy 396.183866 -5.345176) (xy 395.320266 -5.345176) (xy 395.292999 -5.344659)
			(xy 395.239021 -5.336894) (xy 395.186698 -5.321526) (xy 395.137094 -5.298869) (xy 395.091219 -5.269383)
			(xy 395.050007 -5.233669) (xy 395.014296 -5.192454) (xy 394.984815 -5.146576) (xy 394.962162 -5.09697)
			(xy 394.946799 -5.044645) (xy 394.939038 -4.990667) (xy 390.766309 -4.990667) (xy 390.775065 -5.038212)
			(xy 390.783071 -5.125893) (xy 390.783572 -5.169916) (xy 390.783071 -5.213939) (xy 390.775065 -5.30162)
			(xy 390.759118 -5.388209) (xy 390.735364 -5.47299) (xy 390.703998 -5.55526) (xy 390.665281 -5.634336)
			(xy 390.619534 -5.709564) (xy 390.567136 -5.78032) (xy 390.50852 -5.846019) (xy 390.444173 -5.906115)
			(xy 390.374628 -5.96011) (xy 390.300461 -6.007558) (xy 390.222286 -6.048065) (xy 390.140752 -6.081295)
			(xy 390.056534 -6.106973) (xy 389.97033 -6.124886) (xy 389.882854 -6.134887) (xy 389.794831 -6.136891)
			(xy 389.70699 -6.130882) (xy 389.62006 -6.116911) (xy 389.534761 -6.095093) (xy 389.451799 -6.065608)
			(xy 389.371861 -6.028701) (xy 389.295611 -5.984678) (xy 389.223681 -5.933904) (xy 389.156665 -5.876799)
			(xy 389.09512 -5.813837) (xy 389.039555 -5.745539) (xy 388.990432 -5.672471) (xy 388.948156 -5.595239)
			(xy 388.913078 -5.514482) (xy 388.88549 -5.43087) (xy 388.865619 -5.345096) (xy 388.85363 -5.257871)
			(xy 388.849623 -5.169916) (xy 388.110984 -5.169916) (xy 388.110984 -6.169914) (xy 453.015103 -6.169914)
			(xy 453.019108 -6.082006) (xy 453.031091 -5.994826) (xy 453.050951 -5.909097) (xy 453.078526 -5.825529)
			(xy 453.113585 -5.744815) (xy 453.155838 -5.667623) (xy 453.204936 -5.594594) (xy 453.260472 -5.526332)
			(xy 453.321984 -5.463402) (xy 453.388965 -5.406328) (xy 453.460858 -5.35558) (xy 453.537067 -5.31158)
			(xy 453.616962 -5.274693) (xy 453.699881 -5.245224) (xy 453.785136 -5.223417) (xy 453.87202 -5.209453)
			(xy 453.959814 -5.203447) (xy 454.047791 -5.205451) (xy 454.135221 -5.215446) (xy 454.22138 -5.23335)
			(xy 454.305554 -5.259014) (xy 454.387045 -5.292227) (xy 454.465179 -5.332713) (xy 454.539307 -5.380135)
			(xy 454.608815 -5.434102) (xy 454.673129 -5.494167) (xy 454.731713 -5.559831) (xy 454.784084 -5.63055)
			(xy 454.829807 -5.705738) (xy 454.868504 -5.784773) (xy 454.899853 -5.866999) (xy 454.923595 -5.951735)
			(xy 454.939533 -6.038279) (xy 454.947535 -6.125914) (xy 454.948036 -6.169914) (xy 454.947535 -6.213914)
			(xy 454.939533 -6.301549) (xy 454.923595 -6.388093) (xy 454.899853 -6.472829) (xy 454.868504 -6.555055)
			(xy 454.829807 -6.63409) (xy 454.784084 -6.709278) (xy 454.731713 -6.779997) (xy 454.673129 -6.845661)
			(xy 454.608815 -6.905726) (xy 454.539307 -6.959693) (xy 454.465179 -7.007115) (xy 454.387045 -7.047601)
			(xy 454.305554 -7.080814) (xy 454.22138 -7.106478) (xy 454.135221 -7.124382) (xy 454.047791 -7.134377)
			(xy 453.959814 -7.136381) (xy 453.87202 -7.130375) (xy 453.785136 -7.116411) (xy 453.699881 -7.094604)
			(xy 453.616962 -7.065135) (xy 453.537067 -7.028248) (xy 453.460858 -6.984248) (xy 453.388965 -6.9335)
			(xy 453.321984 -6.876426) (xy 453.260472 -6.813496) (xy 453.204936 -6.745234) (xy 453.155838 -6.672205)
			(xy 453.113585 -6.595013) (xy 453.078526 -6.514299) (xy 453.050951 -6.430731) (xy 453.031091 -6.345002)
			(xy 453.019108 -6.257822) (xy 453.015103 -6.169914) (xy 388.110984 -6.169914) (xy 388.110984 -6.752472)
			(xy 393.134283 -6.752472) (xy 393.134283 -6.697928) (xy 393.142045 -6.643939) (xy 393.157412 -6.591604)
			(xy 393.18007 -6.541988) (xy 393.209559 -6.496103) (xy 393.245278 -6.454881) (xy 393.286499 -6.419161)
			(xy 393.332385 -6.389672) (xy 393.382 -6.367013) (xy 393.434335 -6.351646) (xy 393.488324 -6.343883)
			(xy 393.515596 -6.343396) (xy 394.379196 -6.343396) (xy 394.406464 -6.343943) (xy 394.460446 -6.351704)
			(xy 394.512773 -6.367068) (xy 394.562381 -6.389723) (xy 394.60826 -6.419207) (xy 394.649476 -6.454921)
			(xy 394.68519 -6.496136) (xy 394.714675 -6.542015) (xy 394.73733 -6.591623) (xy 394.752695 -6.643951)
			(xy 394.760457 -6.697932) (xy 394.760457 -6.752468) (xy 394.760456 -6.752476) (xy 396.73416 -6.752476)
			(xy 396.73416 -6.697924) (xy 396.741924 -6.643928) (xy 396.757294 -6.591587) (xy 396.779956 -6.541966)
			(xy 396.809451 -6.496075) (xy 396.845176 -6.454849) (xy 396.886405 -6.419128) (xy 396.932299 -6.389638)
			(xy 396.981922 -6.36698) (xy 397.034265 -6.351616) (xy 397.088262 -6.343857) (xy 397.115538 -6.343396)
			(xy 397.979138 -6.343396) (xy 398.006403 -6.343969) (xy 398.060376 -6.351734) (xy 398.112695 -6.367101)
			(xy 398.162295 -6.389757) (xy 398.208166 -6.419241) (xy 398.249375 -6.454952) (xy 398.285082 -6.496164)
			(xy 398.314561 -6.542038) (xy 398.337212 -6.59164) (xy 398.352574 -6.643961) (xy 398.360334 -6.697935)
			(xy 398.360334 -6.752465) (xy 398.360333 -6.752471) (xy 400.334182 -6.752471) (xy 400.334182 -6.697929)
			(xy 400.341944 -6.643941) (xy 400.35731 -6.591607) (xy 400.379968 -6.541993) (xy 400.409455 -6.496108)
			(xy 400.445172 -6.454886) (xy 400.486392 -6.419167) (xy 400.532275 -6.389677) (xy 400.581888 -6.367017)
			(xy 400.634221 -6.351649) (xy 400.688209 -6.343884) (xy 400.71548 -6.343396) (xy 401.57908 -6.343396)
			(xy 401.606349 -6.343942) (xy 401.660332 -6.351701) (xy 401.712661 -6.367064) (xy 401.762272 -6.389718)
			(xy 401.808153 -6.419202) (xy 401.849371 -6.454915) (xy 401.885086 -6.496131) (xy 401.914573 -6.542011)
			(xy 401.937229 -6.59162) (xy 401.952595 -6.643948) (xy 401.960357 -6.697931) (xy 401.960357 -6.752469)
			(xy 401.960357 -6.752471) (xy 403.934382 -6.752471) (xy 403.934382 -6.697929) (xy 403.942144 -6.643941)
			(xy 403.95751 -6.591608) (xy 403.980167 -6.541994) (xy 404.009654 -6.496109) (xy 404.045371 -6.454888)
			(xy 404.08659 -6.419168) (xy 404.132473 -6.389679) (xy 404.182085 -6.367019) (xy 404.234418 -6.351649)
			(xy 404.288405 -6.343884) (xy 404.315676 -6.343396) (xy 405.179276 -6.343396) (xy 405.206545 -6.343942)
			(xy 405.260529 -6.3517) (xy 405.312858 -6.367063) (xy 405.362469 -6.389716) (xy 405.408351 -6.4192)
			(xy 405.449569 -6.454914) (xy 405.485285 -6.49613) (xy 405.514772 -6.54201) (xy 405.537429 -6.591619)
			(xy 405.552795 -6.643948) (xy 405.560557 -6.697931) (xy 405.560557 -6.752469) (xy 405.560556 -6.752476)
			(xy 413.04426 -6.752476) (xy 413.04426 -6.697924) (xy 413.052024 -6.643928) (xy 413.067394 -6.591586)
			(xy 413.090057 -6.541965) (xy 413.119551 -6.496074) (xy 413.155277 -6.454849) (xy 413.196506 -6.419127)
			(xy 413.2424 -6.389638) (xy 413.292024 -6.36698) (xy 413.344367 -6.351615) (xy 413.398364 -6.343857)
			(xy 413.42564 -6.343396) (xy 414.28924 -6.343396) (xy 414.316504 -6.343969) (xy 414.370478 -6.351734)
			(xy 414.422797 -6.367102) (xy 414.472397 -6.389758) (xy 414.518267 -6.419241) (xy 414.559476 -6.454953)
			(xy 414.595183 -6.496165) (xy 414.624662 -6.542039) (xy 414.647312 -6.591641) (xy 414.662674 -6.643961)
			(xy 414.670434 -6.697935) (xy 414.670434 -6.752465) (xy 414.670433 -6.752472) (xy 416.644282 -6.752472)
			(xy 416.644282 -6.697928) (xy 416.652045 -6.64394) (xy 416.667411 -6.591607) (xy 416.690068 -6.541992)
			(xy 416.719555 -6.496107) (xy 416.755273 -6.454885) (xy 416.796493 -6.419166) (xy 416.842376 -6.389677)
			(xy 416.89199 -6.367017) (xy 416.944323 -6.351648) (xy 416.99831 -6.343884) (xy 417.025582 -6.343396)
			(xy 417.889182 -6.343396) (xy 417.916451 -6.343942) (xy 417.970434 -6.351701) (xy 418.022763 -6.367064)
			(xy 418.072373 -6.389718) (xy 418.118254 -6.419202) (xy 418.159471 -6.454916) (xy 418.195187 -6.496132)
			(xy 418.224673 -6.542011) (xy 418.247329 -6.59162) (xy 418.262695 -6.643949) (xy 418.270457 -6.697931)
			(xy 418.270457 -6.752469) (xy 418.270457 -6.752471) (xy 424.254382 -6.752471) (xy 424.254382 -6.697929)
			(xy 424.262144 -6.643941) (xy 424.27751 -6.591608) (xy 424.300167 -6.541994) (xy 424.329654 -6.496109)
			(xy 424.365371 -6.454888) (xy 424.40659 -6.419168) (xy 424.452473 -6.389679) (xy 424.502085 -6.367019)
			(xy 424.554418 -6.351649) (xy 424.608405 -6.343884) (xy 424.635676 -6.343396) (xy 425.499276 -6.343396)
			(xy 425.526545 -6.343942) (xy 425.580529 -6.3517) (xy 425.632858 -6.367063) (xy 425.682469 -6.389716)
			(xy 425.728351 -6.4192) (xy 425.769569 -6.454914) (xy 425.805285 -6.49613) (xy 425.834772 -6.54201)
			(xy 425.857429 -6.591619) (xy 425.872795 -6.643948) (xy 425.880557 -6.697931) (xy 425.880557 -6.752469)
			(xy 425.880556 -6.752475) (xy 427.85426 -6.752475) (xy 427.85426 -6.697925) (xy 427.862023 -6.643931)
			(xy 427.877392 -6.591591) (xy 427.900053 -6.541971) (xy 427.929546 -6.496082) (xy 427.965269 -6.454856)
			(xy 428.006496 -6.419135) (xy 428.052387 -6.389645) (xy 428.102008 -6.366986) (xy 428.154348 -6.351619)
			(xy 428.208343 -6.343858) (xy 428.235618 -6.343396) (xy 429.099218 -6.343396) (xy 429.126484 -6.343968)
			(xy 429.180459 -6.35173) (xy 429.232781 -6.367096) (xy 429.282383 -6.38975) (xy 429.328257 -6.419234)
			(xy 429.369468 -6.454945) (xy 429.405177 -6.496157) (xy 429.434658 -6.542032) (xy 429.457311 -6.591636)
			(xy 429.472673 -6.643958) (xy 429.480434 -6.697934) (xy 429.480434 -6.752466) (xy 429.479412 -6.759571)
			(xy 431.465194 -6.759571) (xy 431.465194 -6.705029) (xy 431.472956 -6.651043) (xy 431.488322 -6.598711)
			(xy 431.510979 -6.549098) (xy 431.540465 -6.503214) (xy 431.576181 -6.461994) (xy 431.6174 -6.426276)
			(xy 431.663282 -6.396787) (xy 431.712894 -6.374128) (xy 431.765225 -6.35876) (xy 431.819211 -6.350996)
			(xy 431.846482 -6.350508) (xy 432.710082 -6.350508) (xy 432.737352 -6.35103) (xy 432.791336 -6.35879)
			(xy 432.843667 -6.374153) (xy 432.893279 -6.396808) (xy 432.939161 -6.426293) (xy 432.98038 -6.462007)
			(xy 433.016096 -6.503225) (xy 433.045583 -6.549106) (xy 433.068241 -6.598716) (xy 433.083607 -6.651046)
			(xy 433.091369 -6.70503) (xy 433.091369 -6.75247) (xy 445.449182 -6.75247) (xy 445.449182 -6.69793)
			(xy 445.456944 -6.643944) (xy 445.472308 -6.591613) (xy 445.494963 -6.542001) (xy 445.524448 -6.496117)
			(xy 445.560162 -6.454896) (xy 445.601379 -6.419177) (xy 445.647258 -6.389686) (xy 445.696868 -6.367025)
			(xy 445.749198 -6.351654) (xy 445.803182 -6.343886) (xy 445.830452 -6.343396) (xy 446.694052 -6.343396)
			(xy 446.721322 -6.34394) (xy 446.775308 -6.351696) (xy 446.827641 -6.367056) (xy 446.877255 -6.389709)
			(xy 446.923139 -6.419192) (xy 446.964361 -6.454905) (xy 447.00008 -6.496122) (xy 447.029568 -6.542003)
			(xy 447.052227 -6.591614) (xy 447.067594 -6.643945) (xy 447.075356 -6.69793) (xy 447.075356 -6.75247)
			(xy 447.067594 -6.806455) (xy 447.052227 -6.858786) (xy 447.029568 -6.908397) (xy 447.000079 -6.954278)
			(xy 446.964361 -6.995495) (xy 446.923139 -7.031208) (xy 446.877255 -7.060691) (xy 446.827641 -7.083344)
			(xy 446.775308 -7.098704) (xy 446.721322 -7.10646) (xy 446.694052 -7.10692) (xy 445.830452 -7.10692)
			(xy 445.803182 -7.106514) (xy 445.749198 -7.098746) (xy 445.696868 -7.083375) (xy 445.647258 -7.060714)
			(xy 445.601378 -7.031223) (xy 445.560162 -6.995504) (xy 445.524448 -6.954283) (xy 445.494963 -6.908399)
			(xy 445.472308 -6.858787) (xy 445.456944 -6.806455) (xy 445.449182 -6.75247) (xy 433.091369 -6.75247)
			(xy 433.091369 -6.75957) (xy 433.083607 -6.813554) (xy 433.068241 -6.865884) (xy 433.045583 -6.915494)
			(xy 433.016096 -6.961375) (xy 432.98038 -7.002593) (xy 432.939161 -7.038307) (xy 432.893279 -7.067792)
			(xy 432.843667 -7.090447) (xy 432.791336 -7.10581) (xy 432.737352 -7.11357) (xy 432.710082 -7.114032)
			(xy 431.846482 -7.114032) (xy 431.819211 -7.113604) (xy 431.765225 -7.10584) (xy 431.712894 -7.090472)
			(xy 431.663282 -7.067813) (xy 431.6174 -7.038324) (xy 431.576181 -7.002606) (xy 431.540465 -6.961386)
			(xy 431.510979 -6.915502) (xy 431.488322 -6.865889) (xy 431.472956 -6.813557) (xy 431.465194 -6.759571)
			(xy 429.479412 -6.759571) (xy 429.472673 -6.806442) (xy 429.457311 -6.858764) (xy 429.434658 -6.908368)
			(xy 429.405177 -6.954243) (xy 429.369468 -6.995455) (xy 429.328257 -7.031166) (xy 429.282383 -7.06065)
			(xy 429.232781 -7.083304) (xy 429.180459 -7.09867) (xy 429.126484 -7.106432) (xy 429.099218 -7.10692)
			(xy 428.235618 -7.10692) (xy 428.208343 -7.106542) (xy 428.154348 -7.098781) (xy 428.102008 -7.083414)
			(xy 428.052387 -7.060755) (xy 428.006496 -7.031265) (xy 427.965269 -6.995544) (xy 427.929546 -6.954318)
			(xy 427.900053 -6.908429) (xy 427.877392 -6.858809) (xy 427.862023 -6.806469) (xy 427.85426 -6.752475)
			(xy 425.880556 -6.752475) (xy 425.872795 -6.806452) (xy 425.857429 -6.858781) (xy 425.834772 -6.90839)
			(xy 425.805285 -6.95427) (xy 425.769569 -6.995486) (xy 425.728351 -7.0312) (xy 425.682469 -7.060684)
			(xy 425.632858 -7.083337) (xy 425.580529 -7.0987) (xy 425.526545 -7.106458) (xy 425.499276 -7.10692)
			(xy 424.635676 -7.10692) (xy 424.608405 -7.106516) (xy 424.554418 -7.098751) (xy 424.502085 -7.083381)
			(xy 424.452473 -7.060721) (xy 424.40659 -7.031232) (xy 424.365371 -6.995512) (xy 424.329654 -6.954291)
			(xy 424.300167 -6.908406) (xy 424.27751 -6.858792) (xy 424.262144 -6.806459) (xy 424.254382 -6.752471)
			(xy 418.270457 -6.752471) (xy 418.262695 -6.806451) (xy 418.247329 -6.85878) (xy 418.224673 -6.908389)
			(xy 418.195187 -6.954268) (xy 418.159471 -6.995484) (xy 418.118254 -7.031198) (xy 418.072373 -7.060682)
			(xy 418.022763 -7.083336) (xy 417.970434 -7.098699) (xy 417.916451 -7.106458) (xy 417.889182 -7.10692)
			(xy 417.025582 -7.10692) (xy 416.99831 -7.106516) (xy 416.944323 -7.098752) (xy 416.89199 -7.083383)
			(xy 416.842376 -7.060723) (xy 416.796493 -7.031234) (xy 416.755273 -6.995515) (xy 416.719555 -6.954293)
			(xy 416.690068 -6.908408) (xy 416.667411 -6.858793) (xy 416.652045 -6.806459) (xy 416.644282 -6.752472)
			(xy 414.670433 -6.752472) (xy 414.662674 -6.806439) (xy 414.647312 -6.858759) (xy 414.624662 -6.908361)
			(xy 414.595183 -6.954235) (xy 414.559476 -6.995447) (xy 414.518267 -7.031159) (xy 414.472397 -7.060642)
			(xy 414.422797 -7.083298) (xy 414.370478 -7.098666) (xy 414.316505 -7.106431) (xy 414.28924 -7.10692)
			(xy 413.42564 -7.10692) (xy 413.398364 -7.106543) (xy 413.344367 -7.098785) (xy 413.292024 -7.08342)
			(xy 413.2424 -7.060762) (xy 413.196506 -7.031273) (xy 413.155277 -6.995551) (xy 413.119551 -6.954326)
			(xy 413.090057 -6.908435) (xy 413.067394 -6.858814) (xy 413.052024 -6.806472) (xy 413.04426 -6.752476)
			(xy 405.560556 -6.752476) (xy 405.552795 -6.806452) (xy 405.537429 -6.858781) (xy 405.514772 -6.90839)
			(xy 405.485285 -6.95427) (xy 405.449569 -6.995486) (xy 405.408351 -7.0312) (xy 405.362469 -7.060684)
			(xy 405.312858 -7.083337) (xy 405.260529 -7.0987) (xy 405.206545 -7.106458) (xy 405.179276 -7.10692)
			(xy 404.315676 -7.10692) (xy 404.288405 -7.106516) (xy 404.234418 -7.098751) (xy 404.182085 -7.083381)
			(xy 404.132473 -7.060721) (xy 404.08659 -7.031232) (xy 404.045371 -6.995512) (xy 404.009654 -6.954291)
			(xy 403.980167 -6.908406) (xy 403.95751 -6.858792) (xy 403.942144 -6.806459) (xy 403.934382 -6.752471)
			(xy 401.960357 -6.752471) (xy 401.952595 -6.806452) (xy 401.937229 -6.85878) (xy 401.914573 -6.908389)
			(xy 401.885086 -6.954269) (xy 401.849371 -6.995485) (xy 401.808153 -7.031198) (xy 401.762272 -7.060682)
			(xy 401.712661 -7.083336) (xy 401.660332 -7.098699) (xy 401.606349 -7.106458) (xy 401.57908 -7.10692)
			(xy 400.71548 -7.10692) (xy 400.688209 -7.106516) (xy 400.634221 -7.098751) (xy 400.581888 -7.083383)
			(xy 400.532275 -7.060723) (xy 400.486392 -7.031233) (xy 400.445172 -6.995514) (xy 400.409455 -6.954292)
			(xy 400.379968 -6.908407) (xy 400.35731 -6.858793) (xy 400.341944 -6.806459) (xy 400.334182 -6.752471)
			(xy 398.360333 -6.752471) (xy 398.352574 -6.806439) (xy 398.337212 -6.85876) (xy 398.314561 -6.908362)
			(xy 398.285082 -6.954236) (xy 398.249375 -6.995448) (xy 398.208166 -7.031159) (xy 398.162295 -7.060643)
			(xy 398.112695 -7.083299) (xy 398.060376 -7.098666) (xy 398.006403 -7.106431) (xy 397.979138 -7.10692)
			(xy 397.115538 -7.10692) (xy 397.088262 -7.106543) (xy 397.034265 -7.098784) (xy 396.981922 -7.08342)
			(xy 396.932299 -7.060762) (xy 396.886405 -7.031272) (xy 396.845176 -6.995551) (xy 396.809451 -6.954325)
			(xy 396.779956 -6.908434) (xy 396.757294 -6.858813) (xy 396.741924 -6.806472) (xy 396.73416 -6.752476)
			(xy 394.760456 -6.752476) (xy 394.752695 -6.806449) (xy 394.73733 -6.858777) (xy 394.714675 -6.908385)
			(xy 394.68519 -6.954264) (xy 394.649476 -6.995479) (xy 394.60826 -7.031193) (xy 394.562381 -7.060677)
			(xy 394.512773 -7.083332) (xy 394.460446 -7.098696) (xy 394.406464 -7.106457) (xy 394.379196 -7.10692)
			(xy 393.515596 -7.10692) (xy 393.488324 -7.106517) (xy 393.434335 -7.098754) (xy 393.382 -7.083387)
			(xy 393.332385 -7.060728) (xy 393.286499 -7.031239) (xy 393.245278 -6.995519) (xy 393.209559 -6.954297)
			(xy 393.18007 -6.908412) (xy 393.157412 -6.858796) (xy 393.142045 -6.806461) (xy 393.134283 -6.752472)
			(xy 388.110984 -6.752472) (xy 388.110984 -9.780016) (xy 388.110499 -9.850398) (xy 388.102605 -9.99094)
			(xy 388.086844 -10.130819) (xy 388.063264 -10.269594) (xy 388.03194 -10.406828) (xy 387.992971 -10.54209)
			(xy 387.946478 -10.674954) (xy 387.892609 -10.805003) (xy 387.831533 -10.931826) (xy 387.763442 -11.055026)
			(xy 387.68855 -11.174213) (xy 387.607093 -11.289014) (xy 387.519328 -11.399067) (xy 387.425529 -11.504025)
			(xy 387.325993 -11.60356) (xy 387.221033 -11.697356) (xy 387.110979 -11.78512) (xy 386.996176 -11.866575)
			(xy 386.876988 -11.941465) (xy 386.753787 -12.009554) (xy 386.626963 -12.070627) (xy 386.496913 -12.124494)
			(xy 386.364048 -12.170984) (xy 386.228785 -12.209951) (xy 386.091551 -12.241273) (xy 385.952775 -12.26485)
			(xy 385.812896 -12.280609) (xy 385.672354 -12.2885) (xy 385.601972 -12.289028) (xy 260.800088 -12.289028)
			(xy 260.744319 -12.28955) (xy 260.633094 -12.297886) (xy 260.522803 -12.314511) (xy 260.414062 -12.339331)
			(xy 260.30748 -12.372208) (xy 260.234662 -12.400788) (xy 436.813452 -12.400788) (xy 436.813941 -12.359678)
			(xy 436.821529 -12.27781) (xy 436.83664 -12.196991) (xy 436.859145 -12.117912) (xy 436.888851 -12.041247)
			(xy 436.925505 -11.96765) (xy 436.968795 -11.89775) (xy 437.01835 -11.832142) (xy 437.073748 -11.771388)
			(xy 437.134516 -11.716006) (xy 437.200136 -11.666467) (xy 437.270047 -11.623195) (xy 437.343653 -11.58656)
			(xy 437.420326 -11.556873) (xy 437.499411 -11.534389) (xy 437.580234 -11.519298) (xy 437.662104 -11.511731)
			(xy 437.703214 -11.51128) (xy 437.747029 -11.511772) (xy 437.83424 -11.520318) (xy 437.920187 -11.537406)
			(xy 438.004035 -11.562868) (xy 438.084971 -11.596458) (xy 438.123838 -11.61669) (xy 438.135191 -11.622017)
			(xy 438.160237 -11.622017) (xy 438.17159 -11.61669) (xy 438.210465 -11.596477) (xy 438.291405 -11.562905)
			(xy 438.375252 -11.537448) (xy 438.461195 -11.520353) (xy 438.548401 -11.511784) (xy 438.592214 -11.51128)
			(xy 438.636029 -11.511772) (xy 438.72324 -11.520318) (xy 438.809187 -11.537406) (xy 438.893035 -11.562868)
			(xy 438.973971 -11.596458) (xy 439.012838 -11.61669) (xy 439.024191 -11.622017) (xy 439.049237 -11.622017)
			(xy 439.06059 -11.61669) (xy 439.099465 -11.596477) (xy 439.180405 -11.562905) (xy 439.264252 -11.537448)
			(xy 439.350195 -11.520353) (xy 439.437401 -11.511784) (xy 439.481214 -11.51128) (xy 439.521951 -11.511719)
			(xy 439.603086 -11.519152) (xy 439.683202 -11.533973) (xy 439.761626 -11.556057) (xy 439.837703 -11.585219)
			(xy 439.910794 -11.621216) (xy 439.94578 -11.64209) (xy 439.954798 -11.647053) (xy 439.975154 -11.650004)
			(xy 439.995036 -11.644737) (xy 440.003438 -11.638788) (xy 440.091322 -11.570462) (xy 440.10072 -11.54049)
			(xy 440.095894 -11.52525) (xy 440.083229 -11.482506) (xy 440.065483 -11.395136) (xy 440.056563 -11.306429)
			(xy 440.056016 -11.261852) (xy 440.056016 -11.26109) (xy 440.056438 -11.22287) (xy 440.062998 -11.146712)
			(xy 440.076079 -11.071399) (xy 440.095582 -10.997489) (xy 440.108086 -10.96137) (xy 440.110695 -10.953059)
			(xy 440.110679 -10.935651) (xy 440.108086 -10.927334) (xy 440.095582 -10.891215) (xy 440.076095 -10.817302)
			(xy 440.063015 -10.74199) (xy 440.056437 -10.665834) (xy 440.056016 -10.627614) (xy 440.056016 -10.626852)
			(xy 440.05652 -10.584504) (xy 440.064571 -10.50019) (xy 440.0806 -10.417024) (xy 440.104461 -10.335757)
			(xy 440.13594 -10.257127) (xy 440.174751 -10.181846) (xy 440.220541 -10.110594) (xy 440.272897 -10.044018)
			(xy 440.331345 -9.98272) (xy 440.395355 -9.927255) (xy 440.464347 -9.878126) (xy 440.537697 -9.835777)
			(xy 440.61474 -9.800593) (xy 440.694779 -9.772891) (xy 440.777088 -9.752923) (xy 440.860923 -9.74087)
			(xy 440.945524 -9.73684) (xy 441.030125 -9.74087) (xy 441.11396 -9.752923) (xy 441.196269 -9.772891)
			(xy 441.276308 -9.800593) (xy 441.353351 -9.835777) (xy 441.426701 -9.878126) (xy 441.495693 -9.927255)
			(xy 441.559703 -9.98272) (xy 441.618151 -10.044018) (xy 441.670507 -10.110594) (xy 441.716297 -10.181846)
			(xy 441.755108 -10.257127) (xy 441.786587 -10.335757) (xy 441.810448 -10.417024) (xy 441.826477 -10.50019)
			(xy 441.834528 -10.584504) (xy 441.835032 -10.626852) (xy 441.835032 -10.627614) (xy 441.834614 -10.665834)
			(xy 441.828053 -10.741992) (xy 441.814972 -10.817305) (xy 441.795467 -10.891215) (xy 441.782962 -10.927334)
			(xy 441.780399 -10.935656) (xy 441.780383 -10.953054) (xy 441.782962 -10.96137) (xy 441.795465 -10.997489)
			(xy 441.814952 -11.071403) (xy 441.828033 -11.146715) (xy 441.834611 -11.22287) (xy 441.835032 -11.26109)
			(xy 441.835032 -11.261852) (xy 441.834502 -11.302954) (xy 441.826922 -11.384807) (xy 441.811821 -11.465611)
			(xy 441.789329 -11.544677) (xy 441.759637 -11.621331) (xy 441.722999 -11.694918) (xy 441.679728 -11.764811)
			(xy 441.630192 -11.830413) (xy 441.574815 -11.891164) (xy 441.514068 -11.946546) (xy 441.44847 -11.996087)
			(xy 441.378581 -12.039364) (xy 441.304997 -12.076008) (xy 441.228346 -12.105706) (xy 441.149281 -12.128204)
			(xy 441.068478 -12.143312) (xy 440.986626 -12.150899) (xy 440.945524 -12.15136) (xy 440.945016 -12.15136)
			(xy 440.904322 -12.150875) (xy 440.823276 -12.143416) (xy 440.74325 -12.128584) (xy 440.664913 -12.106505)
			(xy 440.58892 -12.077363) (xy 440.515907 -12.041401) (xy 440.480958 -12.02055) (xy 440.471926 -12.015614)
			(xy 440.451579 -12.012649) (xy 440.431701 -12.017907) (xy 440.4233 -12.023852) (xy 440.335416 -12.092178)
			(xy 440.326018 -12.12215) (xy 440.330844 -12.13739) (xy 440.343568 -12.180123) (xy 440.361398 -12.267491)
			(xy 440.370394 -12.356204) (xy 440.370976 -12.400788) (xy 440.370415 -12.444238) (xy 440.361895 -12.530719)
			(xy 440.344992 -12.615959) (xy 440.319868 -12.699148) (xy 440.286761 -12.779495) (xy 440.266836 -12.81811)
			(xy 440.262961 -12.82623) (xy 440.260628 -12.84406) (xy 440.262264 -12.852908) (xy 440.272023 -12.900055)
			(xy 440.282457 -12.995773) (xy 440.283092 -13.043916) (xy 440.282667 -13.085188) (xy 440.275027 -13.167377)
			(xy 440.259804 -13.248505) (xy 440.23713 -13.327874) (xy 440.2072 -13.4048) (xy 440.170271 -13.478622)
			(xy 440.126661 -13.548705) (xy 440.076745 -13.614446) (xy 440.020952 -13.675279) (xy 439.959763 -13.730681)
			(xy 439.893704 -13.780175) (xy 439.823344 -13.823336) (xy 439.786522 -13.841984) (xy 439.778885 -13.846179)
			(xy 439.766763 -13.858679) (xy 439.759479 -13.874495) (xy 439.758328 -13.883132) (xy 439.755251 -13.911241)
			(xy 439.741951 -13.966197) (xy 439.720685 -14.018587) (xy 439.69192 -14.067266) (xy 439.656285 -14.111165)
			(xy 439.643167 -14.123162) (xy 440.58586 -14.123162) (xy 440.586283 -14.084873) (xy 440.592885 -14.008579)
			(xy 440.60603 -13.933136) (xy 440.625619 -13.859105) (xy 440.638184 -13.822934) (xy 440.640853 -13.814502)
			(xy 440.64084 -13.796827) (xy 440.638184 -13.78839) (xy 440.625655 -13.752208) (xy 440.606078 -13.678176)
			(xy 440.592927 -13.602738) (xy 440.586298 -13.52645) (xy 440.58586 -13.488162) (xy 440.586364 -13.445801)
			(xy 440.594417 -13.361464) (xy 440.610451 -13.278274) (xy 440.634319 -13.196984) (xy 440.665807 -13.118332)
			(xy 440.704629 -13.043029) (xy 440.750432 -12.971757) (xy 440.802803 -12.905161) (xy 440.861268 -12.843846)
			(xy 440.925296 -12.788365) (xy 440.994308 -12.739222) (xy 441.067678 -12.696862) (xy 441.144743 -12.661667)
			(xy 441.224805 -12.633958) (xy 441.307138 -12.613984) (xy 441.390997 -12.601927) (xy 441.475622 -12.597896)
			(xy 441.560247 -12.601927) (xy 441.644106 -12.613984) (xy 441.726439 -12.633958) (xy 441.806501 -12.661667)
			(xy 441.883566 -12.696862) (xy 441.956936 -12.739222) (xy 442.025948 -12.788365) (xy 442.089976 -12.843846)
			(xy 442.135955 -12.892066) (xy 445.44847 -12.892066) (xy 445.44847 -12.837534) (xy 445.456231 -12.783558)
			(xy 445.471594 -12.731236) (xy 445.494246 -12.681632) (xy 445.523728 -12.635757) (xy 445.559438 -12.594545)
			(xy 445.600649 -12.558834) (xy 445.646523 -12.529351) (xy 445.696126 -12.506697) (xy 445.748448 -12.491333)
			(xy 445.802424 -12.483571) (xy 445.82969 -12.483084) (xy 446.69329 -12.483084) (xy 446.720565 -12.483455)
			(xy 446.774559 -12.491217) (xy 446.826899 -12.506584) (xy 446.87652 -12.529244) (xy 446.92241 -12.558735)
			(xy 446.963636 -12.594456) (xy 446.999359 -12.635682) (xy 447.028851 -12.681571) (xy 447.051512 -12.731191)
			(xy 447.066881 -12.783531) (xy 447.074644 -12.837525) (xy 447.074644 -12.892075) (xy 447.066881 -12.946069)
			(xy 447.051512 -12.998409) (xy 447.028851 -13.048029) (xy 446.999359 -13.093918) (xy 446.963636 -13.135144)
			(xy 446.92241 -13.170865) (xy 446.87652 -13.200356) (xy 446.826899 -13.223016) (xy 446.774559 -13.238383)
			(xy 446.720565 -13.246145) (xy 446.69329 -13.246608) (xy 445.82969 -13.246608) (xy 445.802424 -13.246029)
			(xy 445.748448 -13.238267) (xy 445.696126 -13.222903) (xy 445.646523 -13.200249) (xy 445.600649 -13.170766)
			(xy 445.559438 -13.135055) (xy 445.523728 -13.093843) (xy 445.494246 -13.047968) (xy 445.471594 -12.998364)
			(xy 445.456231 -12.946042) (xy 445.44847 -12.892066) (xy 442.135955 -12.892066) (xy 442.148441 -12.905161)
			(xy 442.200812 -12.971757) (xy 442.246615 -13.043029) (xy 442.285437 -13.118332) (xy 442.316925 -13.196984)
			(xy 442.340793 -13.278274) (xy 442.356827 -13.361464) (xy 442.36488 -13.445801) (xy 442.365384 -13.488162)
			(xy 442.364966 -13.526452) (xy 442.358362 -13.602745) (xy 442.345216 -13.678188) (xy 442.325626 -13.752219)
			(xy 442.31306 -13.78839) (xy 442.310428 -13.796831) (xy 442.310415 -13.814498) (xy 442.31306 -13.822934)
			(xy 442.325598 -13.859113) (xy 442.345172 -13.933146) (xy 442.358321 -14.008585) (xy 442.364947 -14.084874)
			(xy 442.365384 -14.123162) (xy 442.36488 -14.165523) (xy 442.356827 -14.24986) (xy 442.340793 -14.33305)
			(xy 442.316925 -14.41434) (xy 442.285437 -14.492992) (xy 442.268155 -14.526514) (xy 449.780152 -14.526514)
			(xy 449.780656 -14.484153) (xy 449.788709 -14.399816) (xy 449.804743 -14.316626) (xy 449.828611 -14.235336)
			(xy 449.860099 -14.156684) (xy 449.898921 -14.081381) (xy 449.944724 -14.010109) (xy 449.997095 -13.943513)
			(xy 450.05556 -13.882198) (xy 450.119588 -13.826717) (xy 450.1886 -13.777574) (xy 450.26197 -13.735214)
			(xy 450.339035 -13.700019) (xy 450.419097 -13.67231) (xy 450.50143 -13.652336) (xy 450.585289 -13.640279)
			(xy 450.669914 -13.636248) (xy 450.754539 -13.640279) (xy 450.838398 -13.652336) (xy 450.920731 -13.67231)
			(xy 451.000793 -13.700019) (xy 451.077858 -13.735214) (xy 451.151228 -13.777574) (xy 451.22024 -13.826717)
			(xy 451.284268 -13.882198) (xy 451.342733 -13.943513) (xy 451.395104 -14.010109) (xy 451.440907 -14.081381)
			(xy 451.479729 -14.156684) (xy 451.511217 -14.235336) (xy 451.535085 -14.316626) (xy 451.551119 -14.399816)
			(xy 451.559172 -14.484153) (xy 451.559676 -14.526514) (xy 451.559114 -14.571839) (xy 451.549887 -14.662018)
			(xy 451.531531 -14.750791) (xy 451.504235 -14.837234) (xy 451.486778 -14.879066) (xy 451.483143 -14.888844)
			(xy 451.483128 -14.909681) (xy 451.486778 -14.919452) (xy 451.504363 -14.961485) (xy 451.531877 -15.048351)
			(xy 451.550364 -15.137575) (xy 451.559632 -15.228222) (xy 451.560184 -15.273782) (xy 451.559623 -15.318552)
			(xy 451.550621 -15.407639) (xy 451.532717 -15.495371) (xy 451.506092 -15.580861) (xy 451.489064 -15.62227)
			(xy 451.485509 -15.631864) (xy 451.485503 -15.652304) (xy 451.489064 -15.661894) (xy 451.50607 -15.703278)
			(xy 451.532693 -15.788702) (xy 451.550602 -15.876368) (xy 451.559616 -15.96539) (xy 451.560184 -16.010128)
			(xy 451.560184 -16.010382) (xy 451.55968 -16.05273) (xy 451.551629 -16.137044) (xy 451.5356 -16.22021)
			(xy 451.511739 -16.301477) (xy 451.48026 -16.380107) (xy 451.441449 -16.455388) (xy 451.395659 -16.52664)
			(xy 451.343303 -16.593216) (xy 451.284855 -16.654514) (xy 451.220845 -16.709979) (xy 451.151853 -16.759108)
			(xy 451.078503 -16.801457) (xy 451.00146 -16.836641) (xy 450.921421 -16.864343) (xy 450.839112 -16.884311)
			(xy 450.755277 -16.896364) (xy 450.670676 -16.900395) (xy 450.586075 -16.896364) (xy 450.50224 -16.884311)
			(xy 450.419931 -16.864343) (xy 450.339892 -16.836641) (xy 450.262849 -16.801457) (xy 450.189499 -16.759108)
			(xy 450.120507 -16.709979) (xy 450.056497 -16.654514) (xy 449.998049 -16.593216) (xy 449.945693 -16.52664)
			(xy 449.899903 -16.455388) (xy 449.861092 -16.380107) (xy 449.829613 -16.301477) (xy 449.805752 -16.22021)
			(xy 449.789723 -16.137044) (xy 449.781672 -16.05273) (xy 449.781168 -16.010382) (xy 449.781168 -16.010128)
			(xy 449.781731 -15.96539) (xy 449.790749 -15.876368) (xy 449.808655 -15.788701) (xy 449.83527 -15.703273)
			(xy 449.852288 -15.661894) (xy 449.855865 -15.652307) (xy 449.855859 -15.63186) (xy 449.852288 -15.62227)
			(xy 449.835263 -15.580859) (xy 449.808628 -15.495372) (xy 449.790721 -15.40764) (xy 449.781723 -15.318552)
			(xy 449.781168 -15.273782) (xy 449.781749 -15.228458) (xy 449.79099 -15.138283) (xy 449.809345 -15.049513)
			(xy 449.836623 -14.963067) (xy 449.854066 -14.92123) (xy 449.857691 -14.911438) (xy 449.857571 -14.890584)
			(xy 449.853812 -14.880844) (xy 449.836183 -14.838823) (xy 449.808624 -14.751958) (xy 449.790079 -14.662732)
			(xy 449.780742 -14.57208) (xy 449.780152 -14.526514) (xy 442.268155 -14.526514) (xy 442.246615 -14.568295)
			(xy 442.200812 -14.639567) (xy 442.148441 -14.706163) (xy 442.089976 -14.767478) (xy 442.025948 -14.822959)
			(xy 441.956936 -14.872102) (xy 441.883566 -14.914462) (xy 441.806501 -14.949657) (xy 441.726439 -14.977366)
			(xy 441.644106 -14.99734) (xy 441.560247 -15.009397) (xy 441.475622 -15.013429) (xy 441.390997 -15.009397)
			(xy 441.307138 -14.99734) (xy 441.224805 -14.977366) (xy 441.144743 -14.949657) (xy 441.067678 -14.914462)
			(xy 440.994308 -14.872102) (xy 440.925296 -14.822959) (xy 440.861268 -14.767478) (xy 440.802803 -14.706163)
			(xy 440.750432 -14.639567) (xy 440.704629 -14.568295) (xy 440.665807 -14.492992) (xy 440.634319 -14.41434)
			(xy 440.610451 -14.33305) (xy 440.594417 -14.24986) (xy 440.586364 -14.165523) (xy 440.58586 -14.123162)
			(xy 439.643167 -14.123162) (xy 439.614561 -14.149324) (xy 439.567661 -14.180907) (xy 439.516614 -14.205222)
			(xy 439.462537 -14.221736) (xy 439.406615 -14.230088) (xy 439.378344 -14.230604) (xy 439.350975 -14.230111)
			(xy 439.296797 -14.2223) (xy 439.244294 -14.206817) (xy 439.194547 -14.183981) (xy 439.148579 -14.154262)
			(xy 439.127646 -14.136624) (xy 439.127392 -14.13637) (xy 439.120314 -14.130771) (xy 439.103391 -14.124533)
			(xy 439.094372 -14.124178) (xy 439.027316 -14.124178) (xy 439.018301 -14.124547) (xy 439.001384 -14.130787)
			(xy 438.994296 -14.13637) (xy 438.994296 -14.136624) (xy 438.994042 -14.136624) (xy 438.973108 -14.154261)
			(xy 438.927135 -14.183972) (xy 438.877388 -14.206808) (xy 438.824888 -14.2223) (xy 438.770713 -14.230129)
			(xy 438.743344 -14.230604) (xy 438.713998 -14.230028) (xy 438.656001 -14.221024) (xy 438.600065 -14.203253)
			(xy 438.547506 -14.177132) (xy 438.499563 -14.143277) (xy 438.457364 -14.102486) (xy 438.421903 -14.055718)
			(xy 438.394015 -14.004075) (xy 438.38368 -13.976604) (xy 438.380221 -13.968026) (xy 438.368225 -13.953963)
			(xy 438.360312 -13.949172) (xy 438.333388 -13.93444) (xy 438.324705 -13.93016) (xy 438.305508 -13.927807)
			(xy 438.29605 -13.929868) (xy 438.259095 -13.939128) (xy 438.184005 -13.952036) (xy 438.108086 -13.958466)
			(xy 438.06999 -13.958824) (xy 438.028658 -13.958363) (xy 437.94635 -13.95071) (xy 437.865107 -13.935453)
			(xy 437.78563 -13.912724) (xy 437.708605 -13.882718) (xy 437.634696 -13.845694) (xy 437.564542 -13.801972)
			(xy 437.498747 -13.751929) (xy 437.43788 -13.695998) (xy 437.382465 -13.634659) (xy 437.332981 -13.568444)
			(xy 437.289854 -13.497922) (xy 437.253456 -13.423703) (xy 437.224103 -13.346427) (xy 437.202046 -13.266761)
			(xy 437.187477 -13.185391) (xy 437.18353 -13.144246) (xy 437.182106 -13.133691) (xy 437.171856 -13.11505)
			(xy 437.163718 -13.108178) (xy 437.131484 -13.082996) (xy 437.071245 -13.027653) (xy 437.016344 -12.967011)
			(xy 436.967245 -12.901582) (xy 436.924364 -12.831919) (xy 436.888063 -12.758612) (xy 436.858649 -12.682281)
			(xy 436.83637 -12.603571) (xy 436.821416 -12.523147) (xy 436.813913 -12.441689) (xy 436.813452 -12.400788)
			(xy 260.234662 -12.400788) (xy 260.203654 -12.412958) (xy 260.103162 -12.461353) (xy 260.006569 -12.517122)
			(xy 259.914413 -12.579954) (xy 259.82721 -12.649497) (xy 259.745448 -12.725362) (xy 259.669584 -12.807125)
			(xy 259.601843 -12.89207) (xy 431.453248 -12.89207) (xy 431.453248 -12.83753) (xy 431.46101 -12.783546)
			(xy 431.476376 -12.731216) (xy 431.499035 -12.681606) (xy 431.528523 -12.635726) (xy 431.564241 -12.594509)
			(xy 431.605461 -12.558796) (xy 431.651345 -12.529313) (xy 431.700957 -12.506661) (xy 431.753289 -12.4913)
			(xy 431.807274 -12.483544) (xy 431.834544 -12.483084) (xy 432.698144 -12.483084) (xy 432.725415 -12.483482)
			(xy 432.7794 -12.491249) (xy 432.83173 -12.50662) (xy 432.881341 -12.529282) (xy 432.927222 -12.558772)
			(xy 432.968439 -12.594492) (xy 433.004154 -12.635713) (xy 433.033639 -12.681598) (xy 433.056295 -12.731211)
			(xy 433.07166 -12.783543) (xy 433.079422 -12.837529) (xy 433.079422 -12.892071) (xy 433.07166 -12.946057)
			(xy 433.056295 -12.998389) (xy 433.033639 -13.048002) (xy 433.004154 -13.093887) (xy 432.968439 -13.135108)
			(xy 432.927222 -13.170828) (xy 432.881341 -13.200318) (xy 432.83173 -13.22298) (xy 432.7794 -13.238351)
			(xy 432.725415 -13.246118) (xy 432.698144 -13.246608) (xy 431.834544 -13.246608) (xy 431.807274 -13.246056)
			(xy 431.753289 -13.2383) (xy 431.700957 -13.222939) (xy 431.651345 -13.200287) (xy 431.605461 -13.170804)
			(xy 431.564241 -13.135091) (xy 431.528523 -13.093874) (xy 431.499035 -13.047994) (xy 431.476376 -12.998384)
			(xy 431.46101 -12.946054) (xy 431.453248 -12.89207) (xy 259.601843 -12.89207) (xy 259.600042 -12.894329)
			(xy 259.537211 -12.986486) (xy 259.481443 -13.08308) (xy 259.43305 -13.183572) (xy 259.392301 -13.287399)
			(xy 259.359426 -13.393981) (xy 259.334607 -13.502722) (xy 259.317984 -13.613014) (xy 259.309649 -13.724239)
			(xy 259.309108 -13.780008) (xy 259.309108 -17.126458) (xy 310.265572 -17.126458) (xy 310.265992 -17.082972)
			(xy 310.273576 -16.996331) (xy 310.288682 -16.910681) (xy 310.311195 -16.826674) (xy 310.340944 -16.744948)
			(xy 310.377702 -16.666126) (xy 310.421191 -16.590808) (xy 310.471078 -16.519566) (xy 310.526985 -16.452943)
			(xy 310.588485 -16.391447) (xy 310.65511 -16.335544) (xy 310.726355 -16.285661) (xy 310.801676 -16.242177)
			(xy 310.8805 -16.205422) (xy 310.962227 -16.175678) (xy 311.046236 -16.15317) (xy 311.131887 -16.138068)
			(xy 311.218528 -16.13049) (xy 311.262014 -16.130016) (xy 311.287414 -16.130016) (xy 311.33271 -16.130609)
			(xy 311.422936 -16.13873) (xy 311.512071 -16.154907) (xy 311.599397 -16.179009) (xy 311.684211 -16.210841)
			(xy 311.76583 -16.250148) (xy 311.843598 -16.296613) (xy 311.916887 -16.349861) (xy 311.985108 -16.409465)
			(xy 312.047712 -16.474944) (xy 312.104194 -16.545772) (xy 312.1541 -16.621377) (xy 312.197028 -16.701151)
			(xy 312.232632 -16.784452) (xy 312.260626 -16.870609) (xy 312.280784 -16.958929) (xy 312.292944 -17.0487)
			(xy 312.297009 -17.1392) (xy 312.292944 -17.2297) (xy 312.280784 -17.319471) (xy 312.260626 -17.407791)
			(xy 312.232632 -17.493948) (xy 312.197028 -17.577249) (xy 312.163448 -17.639652) (xy 389.652738 -17.639652)
			(xy 389.652738 -17.585148) (xy 389.660494 -17.531197) (xy 389.675849 -17.4789) (xy 389.69849 -17.42932)
			(xy 389.727956 -17.383466) (xy 389.763647 -17.342273) (xy 389.804838 -17.306578) (xy 389.850688 -17.277107)
			(xy 389.900266 -17.254462) (xy 389.952562 -17.239102) (xy 390.006512 -17.23134) (xy 390.033764 -17.230852)
			(xy 390.897364 -17.230852) (xy 390.924616 -17.231393) (xy 390.978565 -17.239145) (xy 391.030862 -17.254496)
			(xy 391.080441 -17.277134) (xy 391.126294 -17.306598) (xy 391.167486 -17.342288) (xy 391.20318 -17.383477)
			(xy 391.232649 -17.429327) (xy 391.255291 -17.478905) (xy 391.270648 -17.5312) (xy 391.278405 -17.585148)
			(xy 391.278405 -17.639652) (xy 395.240738 -17.639652) (xy 395.240738 -17.585148) (xy 395.248494 -17.531197)
			(xy 395.263849 -17.4789) (xy 395.28649 -17.42932) (xy 395.315956 -17.383466) (xy 395.351647 -17.342273)
			(xy 395.392838 -17.306578) (xy 395.438688 -17.277107) (xy 395.488266 -17.254462) (xy 395.540562 -17.239102)
			(xy 395.594512 -17.23134) (xy 395.621764 -17.230852) (xy 396.485364 -17.230852) (xy 396.512616 -17.231393)
			(xy 396.566565 -17.239145) (xy 396.618862 -17.254496) (xy 396.668441 -17.277134) (xy 396.714294 -17.306598)
			(xy 396.755486 -17.342288) (xy 396.79118 -17.383477) (xy 396.820649 -17.429327) (xy 396.843291 -17.478905)
			(xy 396.858648 -17.5312) (xy 396.866405 -17.585148) (xy 396.866405 -17.639652) (xy 400.828738 -17.639652)
			(xy 400.828738 -17.585148) (xy 400.836494 -17.531197) (xy 400.851849 -17.4789) (xy 400.87449 -17.42932)
			(xy 400.903956 -17.383466) (xy 400.939647 -17.342273) (xy 400.980838 -17.306578) (xy 401.026688 -17.277107)
			(xy 401.076266 -17.254462) (xy 401.128562 -17.239102) (xy 401.182512 -17.23134) (xy 401.209764 -17.230852)
			(xy 402.073364 -17.230852) (xy 402.100616 -17.231393) (xy 402.154565 -17.239145) (xy 402.206862 -17.254496)
			(xy 402.256441 -17.277134) (xy 402.302294 -17.306598) (xy 402.343486 -17.342288) (xy 402.37918 -17.383477)
			(xy 402.408649 -17.429327) (xy 402.431291 -17.478905) (xy 402.446648 -17.5312) (xy 402.454405 -17.585148)
			(xy 402.454405 -17.639652) (xy 402.454301 -17.640372) (xy 406.415424 -17.640372) (xy 406.415424 -17.585828)
			(xy 406.423187 -17.53184) (xy 406.438554 -17.479507) (xy 406.461214 -17.429893) (xy 406.490704 -17.38401)
			(xy 406.526425 -17.342791) (xy 406.567649 -17.307076) (xy 406.613536 -17.277591) (xy 406.663152 -17.254938)
			(xy 406.715487 -17.239576) (xy 406.769476 -17.23182) (xy 406.796748 -17.23136) (xy 407.660348 -17.23136)
			(xy 407.687617 -17.231806) (xy 407.741598 -17.239573) (xy 407.793925 -17.254944) (xy 407.843532 -17.277604)
			(xy 407.88941 -17.307093) (xy 407.930624 -17.34281) (xy 407.966336 -17.384029) (xy 407.995819 -17.42991)
			(xy 408.018473 -17.47952) (xy 408.033837 -17.531849) (xy 408.041598 -17.585831) (xy 408.041598 -17.640369)
			(xy 408.041598 -17.640372) (xy 412.003424 -17.640372) (xy 412.003424 -17.585828) (xy 412.011187 -17.53184)
			(xy 412.026554 -17.479507) (xy 412.049214 -17.429893) (xy 412.078704 -17.38401) (xy 412.114425 -17.342791)
			(xy 412.155649 -17.307076) (xy 412.201536 -17.277591) (xy 412.251152 -17.254938) (xy 412.303487 -17.239576)
			(xy 412.357476 -17.23182) (xy 412.384748 -17.23136) (xy 413.248348 -17.23136) (xy 413.275617 -17.231806)
			(xy 413.329598 -17.239573) (xy 413.381925 -17.254944) (xy 413.431532 -17.277604) (xy 413.47741 -17.307093)
			(xy 413.518624 -17.34281) (xy 413.554336 -17.384029) (xy 413.583819 -17.42991) (xy 413.606473 -17.47952)
			(xy 413.621837 -17.531849) (xy 413.629598 -17.585831) (xy 413.629598 -17.639653) (xy 417.898538 -17.639653)
			(xy 417.898538 -17.585147) (xy 417.906295 -17.531195) (xy 417.92165 -17.478897) (xy 417.944292 -17.429315)
			(xy 417.97376 -17.383461) (xy 418.009453 -17.342267) (xy 418.050645 -17.306572) (xy 418.096498 -17.277102)
			(xy 418.146078 -17.254457) (xy 418.198376 -17.239099) (xy 418.252327 -17.231339) (xy 418.27958 -17.230852)
			(xy 419.14318 -17.230852) (xy 419.170431 -17.231394) (xy 419.224378 -17.239148) (xy 419.276673 -17.2545)
			(xy 419.326251 -17.277139) (xy 419.372101 -17.306604) (xy 419.413292 -17.342294) (xy 419.448984 -17.383483)
			(xy 419.478451 -17.429332) (xy 419.501093 -17.478908) (xy 419.516448 -17.531202) (xy 419.524205 -17.585149)
			(xy 419.524205 -17.639651) (xy 419.524205 -17.639653) (xy 423.486538 -17.639653) (xy 423.486538 -17.585147)
			(xy 423.494295 -17.531195) (xy 423.50965 -17.478897) (xy 423.532292 -17.429315) (xy 423.56176 -17.383461)
			(xy 423.597453 -17.342267) (xy 423.638645 -17.306572) (xy 423.684498 -17.277102) (xy 423.734078 -17.254457)
			(xy 423.786376 -17.239099) (xy 423.840327 -17.231339) (xy 423.86758 -17.230852) (xy 424.73118 -17.230852)
			(xy 424.758431 -17.231394) (xy 424.812378 -17.239148) (xy 424.864673 -17.2545) (xy 424.914251 -17.277139)
			(xy 424.960101 -17.306604) (xy 425.001292 -17.342294) (xy 425.036984 -17.383483) (xy 425.066451 -17.429332)
			(xy 425.089093 -17.478908) (xy 425.104448 -17.531202) (xy 425.112205 -17.585149) (xy 425.112205 -17.639651)
			(xy 425.112102 -17.640368) (xy 429.107346 -17.640368) (xy 429.107346 -17.585832) (xy 429.115108 -17.531852)
			(xy 429.130472 -17.479525) (xy 429.153127 -17.429918) (xy 429.182611 -17.38404) (xy 429.218324 -17.342824)
			(xy 429.25954 -17.307111) (xy 429.305418 -17.277627) (xy 429.355025 -17.254972) (xy 429.407352 -17.239608)
			(xy 429.461332 -17.231846) (xy 429.4886 -17.23136) (xy 430.3522 -17.23136) (xy 430.379471 -17.231802)
			(xy 430.433458 -17.239565) (xy 430.48579 -17.254931) (xy 430.535403 -17.277588) (xy 430.581287 -17.307076)
			(xy 430.622507 -17.342793) (xy 430.658224 -17.384013) (xy 430.687712 -17.429897) (xy 430.710369 -17.47951)
			(xy 430.725735 -17.531842) (xy 430.733498 -17.585829) (xy 430.733498 -17.640371) (xy 430.725735 -17.694358)
			(xy 430.710369 -17.74669) (xy 430.687712 -17.796303) (xy 430.658224 -17.842187) (xy 430.622507 -17.883407)
			(xy 430.581287 -17.919124) (xy 430.535403 -17.948612) (xy 430.48579 -17.971269) (xy 430.433458 -17.986635)
			(xy 430.379471 -17.994398) (xy 430.3522 -17.994884) (xy 429.4886 -17.994884) (xy 429.461332 -17.994354)
			(xy 429.407352 -17.986592) (xy 429.355025 -17.971228) (xy 429.305418 -17.948573) (xy 429.25954 -17.919089)
			(xy 429.218324 -17.883376) (xy 429.182611 -17.84216) (xy 429.153127 -17.796282) (xy 429.130472 -17.746675)
			(xy 429.115108 -17.694348) (xy 429.107346 -17.640368) (xy 425.112102 -17.640368) (xy 425.104448 -17.693598)
			(xy 425.089093 -17.745892) (xy 425.066451 -17.795468) (xy 425.036984 -17.841317) (xy 425.001292 -17.882506)
			(xy 424.960101 -17.918196) (xy 424.914251 -17.947661) (xy 424.864673 -17.9703) (xy 424.812378 -17.985652)
			(xy 424.758431 -17.993406) (xy 424.73118 -17.993868) (xy 423.86758 -17.993868) (xy 423.840327 -17.993461)
			(xy 423.786376 -17.985701) (xy 423.734078 -17.970343) (xy 423.684498 -17.947698) (xy 423.638645 -17.918228)
			(xy 423.597453 -17.882533) (xy 423.56176 -17.841339) (xy 423.532292 -17.795485) (xy 423.50965 -17.745903)
			(xy 423.494295 -17.693605) (xy 423.486538 -17.639653) (xy 419.524205 -17.639653) (xy 419.516448 -17.693598)
			(xy 419.501093 -17.745892) (xy 419.478451 -17.795468) (xy 419.448984 -17.841317) (xy 419.413292 -17.882506)
			(xy 419.372101 -17.918196) (xy 419.326251 -17.947661) (xy 419.276673 -17.9703) (xy 419.224378 -17.985652)
			(xy 419.170431 -17.993406) (xy 419.14318 -17.993868) (xy 418.27958 -17.993868) (xy 418.252327 -17.993461)
			(xy 418.198376 -17.985701) (xy 418.146078 -17.970343) (xy 418.096498 -17.947698) (xy 418.050645 -17.918228)
			(xy 418.009453 -17.882533) (xy 417.97376 -17.841339) (xy 417.944292 -17.795485) (xy 417.92165 -17.745903)
			(xy 417.906295 -17.693605) (xy 417.898538 -17.639653) (xy 413.629598 -17.639653) (xy 413.629598 -17.640369)
			(xy 413.621837 -17.694351) (xy 413.606473 -17.74668) (xy 413.583819 -17.79629) (xy 413.554336 -17.842171)
			(xy 413.518624 -17.88339) (xy 413.47741 -17.919107) (xy 413.431532 -17.948596) (xy 413.381925 -17.971256)
			(xy 413.329598 -17.986627) (xy 413.275617 -17.994394) (xy 413.248348 -17.994884) (xy 412.384748 -17.994884)
			(xy 412.357476 -17.99438) (xy 412.303487 -17.986624) (xy 412.251152 -17.971262) (xy 412.201536 -17.948609)
			(xy 412.155649 -17.919124) (xy 412.114425 -17.883409) (xy 412.078704 -17.84219) (xy 412.049214 -17.796307)
			(xy 412.026554 -17.746693) (xy 412.011187 -17.69436) (xy 412.003424 -17.640372) (xy 408.041598 -17.640372)
			(xy 408.033837 -17.694351) (xy 408.018473 -17.74668) (xy 407.995819 -17.79629) (xy 407.966336 -17.842171)
			(xy 407.930624 -17.88339) (xy 407.88941 -17.919107) (xy 407.843532 -17.948596) (xy 407.793925 -17.971256)
			(xy 407.741598 -17.986627) (xy 407.687617 -17.994394) (xy 407.660348 -17.994884) (xy 406.796748 -17.994884)
			(xy 406.769476 -17.99438) (xy 406.715487 -17.986624) (xy 406.663152 -17.971262) (xy 406.613536 -17.948609)
			(xy 406.567649 -17.919124) (xy 406.526425 -17.883409) (xy 406.490704 -17.84219) (xy 406.461214 -17.796307)
			(xy 406.438554 -17.746693) (xy 406.423187 -17.69436) (xy 406.415424 -17.640372) (xy 402.454301 -17.640372)
			(xy 402.446648 -17.6936) (xy 402.431291 -17.745895) (xy 402.408649 -17.795473) (xy 402.37918 -17.841323)
			(xy 402.343486 -17.882512) (xy 402.302294 -17.918202) (xy 402.256441 -17.947666) (xy 402.206862 -17.970304)
			(xy 402.154565 -17.985655) (xy 402.100616 -17.993407) (xy 402.073364 -17.993868) (xy 401.209764 -17.993868)
			(xy 401.182512 -17.99346) (xy 401.128562 -17.985698) (xy 401.076266 -17.970338) (xy 401.026688 -17.947693)
			(xy 400.980838 -17.918222) (xy 400.939647 -17.882527) (xy 400.903956 -17.841334) (xy 400.87449 -17.79548)
			(xy 400.851849 -17.7459) (xy 400.836494 -17.693603) (xy 400.828738 -17.639652) (xy 396.866405 -17.639652)
			(xy 396.858648 -17.6936) (xy 396.843291 -17.745895) (xy 396.820649 -17.795473) (xy 396.79118 -17.841323)
			(xy 396.755486 -17.882512) (xy 396.714294 -17.918202) (xy 396.668441 -17.947666) (xy 396.618862 -17.970304)
			(xy 396.566565 -17.985655) (xy 396.512616 -17.993407) (xy 396.485364 -17.993868) (xy 395.621764 -17.993868)
			(xy 395.594512 -17.99346) (xy 395.540562 -17.985698) (xy 395.488266 -17.970338) (xy 395.438688 -17.947693)
			(xy 395.392838 -17.918222) (xy 395.351647 -17.882527) (xy 395.315956 -17.841334) (xy 395.28649 -17.79548)
			(xy 395.263849 -17.7459) (xy 395.248494 -17.693603) (xy 395.240738 -17.639652) (xy 391.278405 -17.639652)
			(xy 391.270648 -17.6936) (xy 391.255291 -17.745895) (xy 391.232649 -17.795473) (xy 391.20318 -17.841323)
			(xy 391.167486 -17.882512) (xy 391.126294 -17.918202) (xy 391.080441 -17.947666) (xy 391.030862 -17.970304)
			(xy 390.978565 -17.985655) (xy 390.924616 -17.993407) (xy 390.897364 -17.993868) (xy 390.033764 -17.993868)
			(xy 390.006512 -17.99346) (xy 389.952562 -17.985698) (xy 389.900266 -17.970338) (xy 389.850688 -17.947693)
			(xy 389.804838 -17.918222) (xy 389.763647 -17.882527) (xy 389.727956 -17.841334) (xy 389.69849 -17.79548)
			(xy 389.675849 -17.7459) (xy 389.660494 -17.693603) (xy 389.652738 -17.639652) (xy 312.163448 -17.639652)
			(xy 312.1541 -17.657023) (xy 312.104194 -17.732628) (xy 312.047712 -17.803456) (xy 311.985108 -17.868935)
			(xy 311.916887 -17.928539) (xy 311.843598 -17.981787) (xy 311.76583 -18.028252) (xy 311.684211 -18.067559)
			(xy 311.599397 -18.099391) (xy 311.512071 -18.123493) (xy 311.422936 -18.13967) (xy 311.33271 -18.147791)
			(xy 311.287414 -18.1483) (xy 311.28716 -18.1483) (xy 311.242573 -18.147831) (xy 311.153739 -18.140039)
			(xy 311.065923 -18.124536) (xy 310.979792 -18.101438) (xy 310.896001 -18.070922) (xy 310.815188 -18.033221)
			(xy 310.737969 -17.988621) (xy 310.664929 -17.937461) (xy 310.596626 -17.88013) (xy 310.533579 -17.817066)
			(xy 310.476268 -17.748747) (xy 310.425128 -17.675693) (xy 310.380549 -17.598461) (xy 310.34287 -17.517638)
			(xy 310.312377 -17.433839) (xy 310.289303 -17.347701) (xy 310.273824 -17.259881) (xy 310.266056 -17.171045)
			(xy 310.265572 -17.126458) (xy 259.309108 -17.126458) (xy 259.309108 -19.164372) (xy 392.445424 -19.164372)
			(xy 392.445424 -19.109828) (xy 392.453187 -19.05584) (xy 392.468554 -19.003507) (xy 392.491214 -18.953893)
			(xy 392.520704 -18.90801) (xy 392.556425 -18.866791) (xy 392.597649 -18.831076) (xy 392.643536 -18.801591)
			(xy 392.693152 -18.778938) (xy 392.745487 -18.763576) (xy 392.799476 -18.75582) (xy 392.826748 -18.75536)
			(xy 393.690348 -18.75536) (xy 393.717617 -18.755806) (xy 393.771598 -18.763573) (xy 393.823925 -18.778944)
			(xy 393.873532 -18.801604) (xy 393.91941 -18.831093) (xy 393.960624 -18.86681) (xy 393.996336 -18.908029)
			(xy 394.025819 -18.95391) (xy 394.048473 -19.00352) (xy 394.063837 -19.055849) (xy 394.071598 -19.109831)
			(xy 394.071598 -19.163652) (xy 398.034738 -19.163652) (xy 398.034738 -19.109148) (xy 398.042494 -19.055197)
			(xy 398.057849 -19.0029) (xy 398.08049 -18.95332) (xy 398.109956 -18.907466) (xy 398.145647 -18.866273)
			(xy 398.186838 -18.830578) (xy 398.232688 -18.801107) (xy 398.282266 -18.778462) (xy 398.334562 -18.763102)
			(xy 398.388512 -18.75534) (xy 398.415764 -18.754852) (xy 399.279364 -18.754852) (xy 399.306616 -18.755393)
			(xy 399.360565 -18.763145) (xy 399.412862 -18.778496) (xy 399.462441 -18.801134) (xy 399.508294 -18.830598)
			(xy 399.549486 -18.866288) (xy 399.58518 -18.907477) (xy 399.614649 -18.953327) (xy 399.637291 -19.002905)
			(xy 399.652648 -19.0552) (xy 399.660405 -19.109148) (xy 399.660405 -19.163652) (xy 403.622738 -19.163652)
			(xy 403.622738 -19.109148) (xy 403.630494 -19.055197) (xy 403.645849 -19.0029) (xy 403.66849 -18.95332)
			(xy 403.697956 -18.907466) (xy 403.733647 -18.866273) (xy 403.774838 -18.830578) (xy 403.820688 -18.801107)
			(xy 403.870266 -18.778462) (xy 403.922562 -18.763102) (xy 403.976512 -18.75534) (xy 404.003764 -18.754852)
			(xy 404.867364 -18.754852) (xy 404.894616 -18.755393) (xy 404.948565 -18.763145) (xy 405.000862 -18.778496)
			(xy 405.050441 -18.801134) (xy 405.096294 -18.830598) (xy 405.137486 -18.866288) (xy 405.17318 -18.907477)
			(xy 405.202649 -18.953327) (xy 405.225291 -19.002905) (xy 405.240648 -19.0552) (xy 405.248405 -19.109148)
			(xy 405.248405 -19.163652) (xy 409.210738 -19.163652) (xy 409.210738 -19.109148) (xy 409.218494 -19.055197)
			(xy 409.233849 -19.0029) (xy 409.25649 -18.95332) (xy 409.285956 -18.907466) (xy 409.321647 -18.866273)
			(xy 409.362838 -18.830578) (xy 409.408688 -18.801107) (xy 409.458266 -18.778462) (xy 409.510562 -18.763102)
			(xy 409.564512 -18.75534) (xy 409.591764 -18.754852) (xy 410.455364 -18.754852) (xy 410.482616 -18.755393)
			(xy 410.536565 -18.763145) (xy 410.588862 -18.778496) (xy 410.638441 -18.801134) (xy 410.684294 -18.830598)
			(xy 410.725486 -18.866288) (xy 410.76118 -18.907477) (xy 410.790649 -18.953327) (xy 410.813291 -19.002905)
			(xy 410.828648 -19.0552) (xy 410.836405 -19.109148) (xy 410.836405 -19.163652) (xy 410.836405 -19.163653)
			(xy 415.104538 -19.163653) (xy 415.104538 -19.109147) (xy 415.112295 -19.055195) (xy 415.12765 -19.002897)
			(xy 415.150292 -18.953315) (xy 415.17976 -18.907461) (xy 415.215453 -18.866267) (xy 415.256645 -18.830572)
			(xy 415.302498 -18.801102) (xy 415.352078 -18.778457) (xy 415.404376 -18.763099) (xy 415.458327 -18.755339)
			(xy 415.48558 -18.754852) (xy 416.34918 -18.754852) (xy 416.376431 -18.755394) (xy 416.430378 -18.763148)
			(xy 416.482673 -18.7785) (xy 416.532251 -18.801139) (xy 416.578101 -18.830604) (xy 416.619292 -18.866294)
			(xy 416.654984 -18.907483) (xy 416.684451 -18.953332) (xy 416.707093 -19.002908) (xy 416.722448 -19.055202)
			(xy 416.730205 -19.109149) (xy 416.730205 -19.163651) (xy 416.730102 -19.164366) (xy 420.691346 -19.164366)
			(xy 420.691346 -19.109834) (xy 420.699107 -19.055857) (xy 420.714469 -19.003533) (xy 420.737121 -18.953928)
			(xy 420.766602 -18.908051) (xy 420.802312 -18.866837) (xy 420.843523 -18.831124) (xy 420.889396 -18.801639)
			(xy 420.938999 -18.778982) (xy 420.991321 -18.763614) (xy 421.045298 -18.755849) (xy 421.072564 -18.75536)
			(xy 421.936164 -18.75536) (xy 421.963438 -18.755777) (xy 422.017432 -18.763536) (xy 422.069772 -18.7789)
			(xy 422.119393 -18.801556) (xy 422.165284 -18.831045) (xy 422.20651 -18.866764) (xy 422.242234 -18.907988)
			(xy 422.271726 -18.953876) (xy 422.294388 -19.003494) (xy 422.309757 -19.055833) (xy 422.31752 -19.109826)
			(xy 422.31752 -19.163656) (xy 426.314515 -19.163656) (xy 426.314515 -19.109144) (xy 426.322273 -19.055185)
			(xy 426.337632 -19.002881) (xy 426.360278 -18.953294) (xy 426.38975 -18.907436) (xy 426.42545 -18.866238)
			(xy 426.466648 -18.830541) (xy 426.512508 -18.80107) (xy 426.562096 -18.778426) (xy 426.614401 -18.76307)
			(xy 426.66836 -18.755314) (xy 426.695616 -18.754852) (xy 427.559216 -18.754852) (xy 427.586464 -18.755419)
			(xy 427.640404 -18.763177) (xy 427.692691 -18.778532) (xy 427.742261 -18.801171) (xy 427.788105 -18.830635)
			(xy 427.829289 -18.866323) (xy 427.864975 -18.907508) (xy 427.894436 -18.953353) (xy 427.917074 -19.002924)
			(xy 427.932427 -19.055212) (xy 427.940182 -19.109152) (xy 427.940182 -19.163648) (xy 427.940181 -19.163656)
			(xy 431.902515 -19.163656) (xy 431.902515 -19.109144) (xy 431.910273 -19.055185) (xy 431.925632 -19.002881)
			(xy 431.948278 -18.953294) (xy 431.97775 -18.907436) (xy 432.01345 -18.866238) (xy 432.054648 -18.830541)
			(xy 432.100508 -18.80107) (xy 432.150096 -18.778426) (xy 432.202401 -18.76307) (xy 432.25636 -18.755314)
			(xy 432.283616 -18.754852) (xy 433.147216 -18.754852) (xy 433.174464 -18.755419) (xy 433.228404 -18.763177)
			(xy 433.280691 -18.778532) (xy 433.330261 -18.801171) (xy 433.376105 -18.830635) (xy 433.417289 -18.866323)
			(xy 433.452975 -18.907508) (xy 433.482436 -18.953353) (xy 433.505074 -19.002924) (xy 433.520427 -19.055212)
			(xy 433.528182 -19.109152) (xy 433.528182 -19.163648) (xy 433.520427 -19.217588) (xy 433.505074 -19.269876)
			(xy 433.482436 -19.319447) (xy 433.452975 -19.365292) (xy 433.417289 -19.406477) (xy 433.376105 -19.442165)
			(xy 433.330261 -19.471629) (xy 433.280691 -19.494268) (xy 433.228404 -19.509623) (xy 433.174464 -19.517381)
			(xy 433.147216 -19.517868) (xy 432.283616 -19.517868) (xy 432.25636 -19.517486) (xy 432.202401 -19.50973)
			(xy 432.150096 -19.494374) (xy 432.100508 -19.47173) (xy 432.054648 -19.442259) (xy 432.01345 -19.406562)
			(xy 431.97775 -19.365364) (xy 431.948278 -19.319506) (xy 431.925632 -19.269919) (xy 431.910273 -19.217615)
			(xy 431.902515 -19.163656) (xy 427.940181 -19.163656) (xy 427.932427 -19.217588) (xy 427.917074 -19.269876)
			(xy 427.894436 -19.319447) (xy 427.864975 -19.365292) (xy 427.829289 -19.406477) (xy 427.788105 -19.442165)
			(xy 427.742261 -19.471629) (xy 427.692691 -19.494268) (xy 427.640404 -19.509623) (xy 427.586464 -19.517381)
			(xy 427.559216 -19.517868) (xy 426.695616 -19.517868) (xy 426.66836 -19.517486) (xy 426.614401 -19.50973)
			(xy 426.562096 -19.494374) (xy 426.512508 -19.47173) (xy 426.466648 -19.442259) (xy 426.42545 -19.406562)
			(xy 426.38975 -19.365364) (xy 426.360278 -19.319506) (xy 426.337632 -19.269919) (xy 426.322273 -19.217615)
			(xy 426.314515 -19.163656) (xy 422.31752 -19.163656) (xy 422.31752 -19.164374) (xy 422.309757 -19.218367)
			(xy 422.294388 -19.270706) (xy 422.271726 -19.320324) (xy 422.242234 -19.366212) (xy 422.20651 -19.407436)
			(xy 422.165284 -19.443155) (xy 422.119393 -19.472644) (xy 422.069772 -19.4953) (xy 422.017432 -19.510664)
			(xy 421.963438 -19.518423) (xy 421.936164 -19.518884) (xy 421.072564 -19.518884) (xy 421.045298 -19.518351)
			(xy 420.991321 -19.510586) (xy 420.938999 -19.495218) (xy 420.889396 -19.472561) (xy 420.843523 -19.443076)
			(xy 420.802312 -19.407363) (xy 420.766602 -19.366149) (xy 420.737121 -19.320272) (xy 420.714469 -19.270667)
			(xy 420.699107 -19.218343) (xy 420.691346 -19.164366) (xy 416.730102 -19.164366) (xy 416.722448 -19.217598)
			(xy 416.707093 -19.269892) (xy 416.684451 -19.319468) (xy 416.654984 -19.365317) (xy 416.619292 -19.406506)
			(xy 416.578101 -19.442196) (xy 416.532251 -19.471661) (xy 416.482673 -19.4943) (xy 416.430378 -19.509652)
			(xy 416.376431 -19.517406) (xy 416.34918 -19.517868) (xy 415.48558 -19.517868) (xy 415.458327 -19.517461)
			(xy 415.404376 -19.509701) (xy 415.352078 -19.494343) (xy 415.302498 -19.471698) (xy 415.256645 -19.442228)
			(xy 415.215453 -19.406533) (xy 415.17976 -19.365339) (xy 415.150292 -19.319485) (xy 415.12765 -19.269903)
			(xy 415.112295 -19.217605) (xy 415.104538 -19.163653) (xy 410.836405 -19.163653) (xy 410.828648 -19.2176)
			(xy 410.813291 -19.269895) (xy 410.790649 -19.319473) (xy 410.76118 -19.365323) (xy 410.725486 -19.406512)
			(xy 410.684294 -19.442202) (xy 410.638441 -19.471666) (xy 410.588862 -19.494304) (xy 410.536565 -19.509655)
			(xy 410.482616 -19.517407) (xy 410.455364 -19.517868) (xy 409.591764 -19.517868) (xy 409.564512 -19.51746)
			(xy 409.510562 -19.509698) (xy 409.458266 -19.494338) (xy 409.408688 -19.471693) (xy 409.362838 -19.442222)
			(xy 409.321647 -19.406527) (xy 409.285956 -19.365334) (xy 409.25649 -19.31948) (xy 409.233849 -19.2699)
			(xy 409.218494 -19.217603) (xy 409.210738 -19.163652) (xy 405.248405 -19.163652) (xy 405.240648 -19.2176)
			(xy 405.225291 -19.269895) (xy 405.202649 -19.319473) (xy 405.17318 -19.365323) (xy 405.137486 -19.406512)
			(xy 405.096294 -19.442202) (xy 405.050441 -19.471666) (xy 405.000862 -19.494304) (xy 404.948565 -19.509655)
			(xy 404.894616 -19.517407) (xy 404.867364 -19.517868) (xy 404.003764 -19.517868) (xy 403.976512 -19.51746)
			(xy 403.922562 -19.509698) (xy 403.870266 -19.494338) (xy 403.820688 -19.471693) (xy 403.774838 -19.442222)
			(xy 403.733647 -19.406527) (xy 403.697956 -19.365334) (xy 403.66849 -19.31948) (xy 403.645849 -19.2699)
			(xy 403.630494 -19.217603) (xy 403.622738 -19.163652) (xy 399.660405 -19.163652) (xy 399.652648 -19.2176)
			(xy 399.637291 -19.269895) (xy 399.614649 -19.319473) (xy 399.58518 -19.365323) (xy 399.549486 -19.406512)
			(xy 399.508294 -19.442202) (xy 399.462441 -19.471666) (xy 399.412862 -19.494304) (xy 399.360565 -19.509655)
			(xy 399.306616 -19.517407) (xy 399.279364 -19.517868) (xy 398.415764 -19.517868) (xy 398.388512 -19.51746)
			(xy 398.334562 -19.509698) (xy 398.282266 -19.494338) (xy 398.232688 -19.471693) (xy 398.186838 -19.442222)
			(xy 398.145647 -19.406527) (xy 398.109956 -19.365334) (xy 398.08049 -19.31948) (xy 398.057849 -19.2699)
			(xy 398.042494 -19.217603) (xy 398.034738 -19.163652) (xy 394.071598 -19.163652) (xy 394.071598 -19.164369)
			(xy 394.063837 -19.218351) (xy 394.048473 -19.27068) (xy 394.025819 -19.32029) (xy 393.996336 -19.366171)
			(xy 393.960624 -19.40739) (xy 393.91941 -19.443107) (xy 393.873532 -19.472596) (xy 393.823925 -19.495256)
			(xy 393.771598 -19.510627) (xy 393.717617 -19.518394) (xy 393.690348 -19.518884) (xy 392.826748 -19.518884)
			(xy 392.799476 -19.51838) (xy 392.745487 -19.510624) (xy 392.693152 -19.495262) (xy 392.643536 -19.472609)
			(xy 392.597649 -19.443124) (xy 392.556425 -19.407409) (xy 392.520704 -19.36619) (xy 392.491214 -19.320307)
			(xy 392.468554 -19.270693) (xy 392.453187 -19.21836) (xy 392.445424 -19.164372) (xy 259.309108 -19.164372)
			(xy 259.309108 -20.4061) (xy 368.50594 -20.4061) (xy 368.510005 -20.315592) (xy 368.522167 -20.225813)
			(xy 368.542328 -20.137486) (xy 368.570325 -20.051322) (xy 368.605934 -19.968014) (xy 368.648867 -19.888233)
			(xy 368.698779 -19.812623) (xy 368.755267 -19.741791) (xy 368.817878 -19.676308) (xy 368.886107 -19.616701)
			(xy 368.959405 -19.56345) (xy 369.037181 -19.516984) (xy 369.118809 -19.477677) (xy 369.203632 -19.445846)
			(xy 369.290966 -19.421746) (xy 369.38011 -19.405573) (xy 369.470345 -19.397455) (xy 369.515644 -19.396964)
			(xy 369.560233 -19.397442) (xy 369.649072 -19.405219) (xy 369.736895 -19.420711) (xy 369.823033 -19.443798)
			(xy 369.906831 -19.474305) (xy 369.987651 -19.512001) (xy 370.064878 -19.556597) (xy 370.137923 -19.607756)
			(xy 370.206232 -19.665086) (xy 370.269283 -19.728153) (xy 370.326597 -19.796475) (xy 370.377737 -19.869533)
			(xy 370.422315 -19.946771) (xy 370.459991 -20.0276) (xy 370.490478 -20.111405) (xy 370.513544 -20.197549)
			(xy 370.529013 -20.285376) (xy 370.536768 -20.374217) (xy 370.537232 -20.418806) (xy 370.536774 -20.462284)
			(xy 370.529196 -20.54891) (xy 370.514098 -20.634545) (xy 370.491595 -20.71854) (xy 370.485037 -20.73656)
			(xy 440.464956 -20.73656) (xy 440.465378 -20.698271) (xy 440.471981 -20.621977) (xy 440.485126 -20.546534)
			(xy 440.504715 -20.472503) (xy 440.51728 -20.436332) (xy 440.51995 -20.4279) (xy 440.519937 -20.410225)
			(xy 440.51728 -20.401788) (xy 440.50475 -20.365606) (xy 440.485173 -20.291575) (xy 440.472022 -20.216136)
			(xy 440.465394 -20.139848) (xy 440.464956 -20.10156) (xy 440.46549 -20.057765) (xy 440.474106 -19.9706)
			(xy 440.49125 -19.884704) (xy 440.516756 -19.80091) (xy 440.550377 -19.72003) (xy 440.57062 -19.68119)
			(xy 440.576064 -19.669733) (xy 440.576046 -19.644397) (xy 440.57062 -19.63293) (xy 440.550398 -19.594081)
			(xy 440.51679 -19.513198) (xy 440.491286 -19.429406) (xy 440.474133 -19.343514) (xy 440.465497 -19.256354)
			(xy 440.464956 -19.21256) (xy 440.465378 -19.174271) (xy 440.471981 -19.097977) (xy 440.485126 -19.022534)
			(xy 440.504715 -18.948503) (xy 440.51728 -18.912332) (xy 440.51995 -18.9039) (xy 440.519937 -18.886225)
			(xy 440.51728 -18.877788) (xy 440.50475 -18.841606) (xy 440.485173 -18.767575) (xy 440.472022 -18.692136)
			(xy 440.465394 -18.615848) (xy 440.464956 -18.57756) (xy 440.465414 -18.53645) (xy 440.473005 -18.45458)
			(xy 440.488119 -18.373761) (xy 440.510626 -18.294681) (xy 440.540334 -18.218015) (xy 440.576991 -18.144418)
			(xy 440.620282 -18.074518) (xy 440.66984 -18.008911) (xy 440.72524 -17.948157) (xy 440.78601 -17.892775)
			(xy 440.851631 -17.843237) (xy 440.921544 -17.799965) (xy 440.995152 -17.76333) (xy 441.071826 -17.733644)
			(xy 441.150912 -17.71116) (xy 441.231736 -17.69607) (xy 441.313608 -17.688502) (xy 441.354718 -17.688052)
			(xy 441.395668 -17.688478) (xy 441.477223 -17.695989) (xy 441.557742 -17.710965) (xy 441.636544 -17.733279)
			(xy 441.712961 -17.762742) (xy 441.786347 -17.799105) (xy 441.856079 -17.842059) (xy 441.921567 -17.891241)
			(xy 441.982258 -17.946234) (xy 442.010292 -17.976088) (xy 442.017449 -17.983101) (xy 442.035585 -17.991562)
			(xy 442.055576 -17.99248) (xy 442.065156 -17.98955) (xy 442.102033 -17.976445) (xy 442.177582 -17.955997)
			(xy 442.254637 -17.94227) (xy 442.3326 -17.935373) (xy 442.371734 -17.93494) (xy 442.412849 -17.93538)
			(xy 442.494727 -17.942971) (xy 442.575557 -17.958083) (xy 442.654646 -17.980589) (xy 442.731323 -18.010296)
			(xy 442.804931 -18.046951) (xy 442.874843 -18.090241) (xy 442.940462 -18.139797) (xy 443.001229 -18.195196)
			(xy 443.056626 -18.255966) (xy 443.106179 -18.321587) (xy 443.149467 -18.391501) (xy 443.186119 -18.46511)
			(xy 443.213248 -18.535142) (xy 451.165468 -18.535142) (xy 451.165468 -18.534888) (xy 451.166052 -18.49015)
			(xy 451.175063 -18.401129) (xy 451.192964 -18.313462) (xy 451.219572 -18.228034) (xy 451.236588 -18.186654)
			(xy 451.240131 -18.177057) (xy 451.240147 -18.15662) (xy 451.236588 -18.14703) (xy 451.219555 -18.105656)
			(xy 451.192939 -18.020228) (xy 451.175038 -17.932559) (xy 451.166032 -17.843535) (xy 451.165468 -17.798796)
			(xy 451.165468 -17.798542) (xy 451.165972 -17.756194) (xy 451.174023 -17.67188) (xy 451.190052 -17.588714)
			(xy 451.213913 -17.507447) (xy 451.245392 -17.428817) (xy 451.284203 -17.353536) (xy 451.329993 -17.282284)
			(xy 451.382349 -17.215708) (xy 451.440797 -17.15441) (xy 451.504807 -17.098945) (xy 451.573799 -17.049816)
			(xy 451.647149 -17.007467) (xy 451.724192 -16.972283) (xy 451.804231 -16.944581) (xy 451.88654 -16.924613)
			(xy 451.970375 -16.91256) (xy 452.054976 -16.90853) (xy 452.139577 -16.91256) (xy 452.223412 -16.924613)
			(xy 452.305721 -16.944581) (xy 452.38576 -16.972283) (xy 452.462803 -17.007467) (xy 452.536153 -17.049816)
			(xy 452.605145 -17.098945) (xy 452.669155 -17.15441) (xy 452.727603 -17.215708) (xy 452.779959 -17.282284)
			(xy 452.825749 -17.353536) (xy 452.86456 -17.428817) (xy 452.896039 -17.507447) (xy 452.9199 -17.588714)
			(xy 452.935929 -17.67188) (xy 452.94398 -17.756194) (xy 452.944484 -17.798542) (xy 452.944484 -17.798796)
			(xy 452.943898 -17.843534) (xy 452.934888 -17.932555) (xy 452.916988 -18.020222) (xy 452.890379 -18.10565)
			(xy 452.873364 -18.14703) (xy 452.869775 -18.156614) (xy 452.869791 -18.177063) (xy 452.873364 -18.186654)
			(xy 452.890389 -18.228031) (xy 452.917007 -18.313458) (xy 452.934911 -18.401126) (xy 452.943919 -18.490149)
			(xy 452.944484 -18.534888) (xy 452.944484 -18.535142) (xy 452.94398 -18.57749) (xy 452.935929 -18.661804)
			(xy 452.9199 -18.74497) (xy 452.896039 -18.826237) (xy 452.86456 -18.904867) (xy 452.825749 -18.980148)
			(xy 452.779959 -19.0514) (xy 452.727603 -19.117976) (xy 452.669155 -19.179274) (xy 452.605145 -19.234739)
			(xy 452.536153 -19.283868) (xy 452.462803 -19.326217) (xy 452.38576 -19.361401) (xy 452.305721 -19.389103)
			(xy 452.223412 -19.409071) (xy 452.139577 -19.421124) (xy 452.054976 -19.425155) (xy 451.970375 -19.421124)
			(xy 451.88654 -19.409071) (xy 451.804231 -19.389103) (xy 451.724192 -19.361401) (xy 451.647149 -19.326217)
			(xy 451.573799 -19.283868) (xy 451.504807 -19.234739) (xy 451.440797 -19.179274) (xy 451.382349 -19.117976)
			(xy 451.329993 -19.0514) (xy 451.284203 -18.980148) (xy 451.245392 -18.904867) (xy 451.213913 -18.826237)
			(xy 451.190052 -18.74497) (xy 451.174023 -18.661804) (xy 451.165972 -18.57749) (xy 451.165468 -18.535142)
			(xy 443.213248 -18.535142) (xy 443.215823 -18.541788) (xy 443.238325 -18.620878) (xy 443.253434 -18.701708)
			(xy 443.261021 -18.783587) (xy 443.261496 -18.824702) (xy 443.261095 -18.862992) (xy 443.254486 -18.939286)
			(xy 443.241336 -19.014729) (xy 443.221741 -19.088759) (xy 443.209172 -19.12493) (xy 443.206519 -19.133366)
			(xy 443.20652 -19.151037) (xy 443.209172 -19.159474) (xy 443.221718 -19.195651) (xy 443.24129 -19.269684)
			(xy 443.254437 -19.345124) (xy 443.261061 -19.421414) (xy 443.261496 -19.459702) (xy 443.260982 -19.503497)
			(xy 443.252361 -19.590663) (xy 443.235212 -19.676559) (xy 443.209701 -19.760353) (xy 443.176076 -19.841233)
			(xy 443.155832 -19.880072) (xy 443.15041 -19.891537) (xy 443.150411 -19.916866) (xy 443.155832 -19.928332)
			(xy 443.176073 -19.967172) (xy 443.209679 -20.048057) (xy 443.235179 -20.131851) (xy 443.252328 -20.217745)
			(xy 443.260958 -20.304908) (xy 443.261496 -20.348702) (xy 443.261095 -20.386992) (xy 443.254486 -20.463286)
			(xy 443.241336 -20.538729) (xy 443.221741 -20.612759) (xy 443.209172 -20.64893) (xy 443.206519 -20.657366)
			(xy 443.20652 -20.675037) (xy 443.209172 -20.683474) (xy 443.221718 -20.719651) (xy 443.24129 -20.793684)
			(xy 443.254437 -20.869124) (xy 443.261061 -20.945414) (xy 443.261496 -20.983702) (xy 443.260989 -21.024815)
			(xy 443.253402 -21.106691) (xy 443.238293 -21.187518) (xy 443.215791 -21.266605) (xy 443.186088 -21.343279)
			(xy 443.149437 -21.416886) (xy 443.106152 -21.486797) (xy 443.0566 -21.552416) (xy 443.001205 -21.613183)
			(xy 442.94044 -21.66858) (xy 442.874823 -21.718133) (xy 442.804914 -21.761422) (xy 442.731309 -21.798075)
			(xy 442.654636 -21.827781) (xy 442.575549 -21.850286) (xy 442.494723 -21.865398) (xy 442.412847 -21.872988)
			(xy 442.371734 -21.873464) (xy 442.330778 -21.872996) (xy 442.249213 -21.865468) (xy 442.168686 -21.850472)
			(xy 442.089879 -21.828136) (xy 442.013459 -21.798648) (xy 441.940074 -21.762259) (xy 441.870346 -21.719277)
			(xy 441.804865 -21.670066) (xy 441.744186 -21.615042) (xy 441.71616 -21.585174) (xy 441.709037 -21.578124)
			(xy 441.690882 -21.569676) (xy 441.670879 -21.568774) (xy 441.661296 -21.571712) (xy 441.624502 -21.584749)
			(xy 441.549137 -21.605106) (xy 441.472276 -21.618771) (xy 441.394513 -21.625637) (xy 441.35548 -21.626068)
			(xy 441.354718 -21.626068) (xy 441.313612 -21.62557) (xy 441.23175 -21.617988) (xy 441.150936 -21.602885)
			(xy 441.07186 -21.580392) (xy 440.995197 -21.5507) (xy 440.9216 -21.514062) (xy 440.851696 -21.470791)
			(xy 440.786082 -21.421255) (xy 440.725318 -21.365878) (xy 440.669922 -21.305132) (xy 440.620366 -21.239533)
			(xy 440.577073 -21.169643) (xy 440.540412 -21.096058) (xy 440.510696 -21.019403) (xy 440.488178 -20.940335)
			(xy 440.473051 -20.859526) (xy 440.465443 -20.777666) (xy 440.464956 -20.73656) (xy 370.485037 -20.73656)
			(xy 370.461858 -20.800254) (xy 370.425114 -20.879065) (xy 370.381641 -20.954375) (xy 370.331772 -21.02561)
			(xy 370.275884 -21.092228) (xy 370.214404 -21.153723) (xy 370.147799 -21.209627) (xy 370.076576 -21.259513)
			(xy 370.001276 -21.303004) (xy 369.922473 -21.339767) (xy 369.840767 -21.369523) (xy 369.756778 -21.392046)
			(xy 369.671146 -21.407165) (xy 369.584522 -21.414763) (xy 369.541044 -21.415248) (xy 369.515644 -21.415248)
			(xy 369.470345 -21.414745) (xy 369.38011 -21.406627) (xy 369.290966 -21.390454) (xy 369.203632 -21.366354)
			(xy 369.118809 -21.334523) (xy 369.037181 -21.295216) (xy 368.959405 -21.24875) (xy 368.886107 -21.195499)
			(xy 368.817878 -21.135892) (xy 368.755267 -21.070409) (xy 368.698779 -20.999577) (xy 368.648867 -20.923967)
			(xy 368.605934 -20.844186) (xy 368.570325 -20.760878) (xy 368.542328 -20.674714) (xy 368.522167 -20.586387)
			(xy 368.510005 -20.496608) (xy 368.50594 -20.4061) (xy 259.309108 -20.4061) (xy 259.309108 -25.982422)
			(xy 440.239912 -25.982422) (xy 440.240419 -25.939461) (xy 440.248702 -25.85394) (xy 440.265193 -25.769616)
			(xy 440.289738 -25.687275) (xy 440.322109 -25.607684) (xy 440.362003 -25.531586) (xy 440.40905 -25.459689)
			(xy 440.46281 -25.392664) (xy 440.522782 -25.331135) (xy 440.588408 -25.275676) (xy 440.659076 -25.226803)
			(xy 440.69635 -25.205436) (xy 440.704332 -25.200469) (xy 440.716316 -25.186006) (xy 440.719718 -25.177242)
			(xy 440.733823 -25.137039) (xy 440.768699 -25.059297) (xy 440.810847 -24.985247) (xy 440.859883 -24.915565)
			(xy 440.915357 -24.850891) (xy 440.97676 -24.791817) (xy 441.043529 -24.738885) (xy 441.115054 -24.692579)
			(xy 441.190679 -24.653323) (xy 441.26971 -24.621478) (xy 441.351424 -24.597336) (xy 441.435072 -24.581116)
			(xy 441.519887 -24.572969) (xy 441.56249 -24.572468) (xy 441.562998 -24.572468) (xy 441.606762 -24.572982)
			(xy 441.693869 -24.581557) (xy 441.77971 -24.598653) (xy 441.863455 -24.624106) (xy 441.944293 -24.657667)
			(xy 441.983114 -24.677878) (xy 441.994467 -24.683205) (xy 442.019513 -24.683205) (xy 442.030866 -24.677878)
			(xy 442.069745 -24.657673) (xy 442.150684 -24.6241) (xy 442.23453 -24.598641) (xy 442.320472 -24.581544)
			(xy 442.407677 -24.572973) (xy 442.45149 -24.572468) (xy 442.495305 -24.572971) (xy 442.582516 -24.581515)
			(xy 442.668462 -24.5986) (xy 442.752311 -24.62406) (xy 442.833246 -24.657648) (xy 442.872114 -24.677878)
			(xy 442.883467 -24.683205) (xy 442.908513 -24.683205) (xy 442.919866 -24.677878) (xy 442.959061 -24.657499)
			(xy 443.040701 -24.623735) (xy 443.125286 -24.598229) (xy 443.211982 -24.581233) (xy 443.255908 -24.576532)
			(xy 443.266358 -24.575008) (xy 443.284755 -24.564681) (xy 443.297434 -24.547819) (xy 443.300358 -24.53767)
			(xy 443.310609 -24.496358) (xy 443.337964 -24.415751) (xy 443.372893 -24.338124) (xy 443.415077 -24.264189)
			(xy 443.464129 -24.19462) (xy 443.519603 -24.130055) (xy 443.580989 -24.071084) (xy 443.647727 -24.018245)
			(xy 443.719207 -23.972023) (xy 443.794775 -23.932839) (xy 443.87374 -23.901052) (xy 443.955381 -23.876952)
			(xy 444.038949 -23.86076) (xy 444.123683 -23.852625) (xy 444.166244 -23.852124) (xy 444.207348 -23.852525)
			(xy 444.289205 -23.860114) (xy 444.370013 -23.875224) (xy 444.449082 -23.897725) (xy 444.525738 -23.927425)
			(xy 444.599326 -23.964072) (xy 444.669219 -24.007352) (xy 444.734821 -24.056897) (xy 444.795571 -24.112283)
			(xy 444.850952 -24.173038) (xy 444.900491 -24.238644) (xy 444.943765 -24.30854) (xy 444.980405 -24.382132)
			(xy 445.0101 -24.45879) (xy 445.032594 -24.537861) (xy 445.047697 -24.61867) (xy 445.055279 -24.700528)
			(xy 445.055752 -24.741632) (xy 445.055238 -24.782654) (xy 445.04768 -24.864348) (xy 445.032631 -24.944999)
			(xy 445.01022 -25.023921) (xy 444.980635 -25.100445) (xy 444.94413 -25.173919) (xy 444.901014 -25.243719)
			(xy 444.851653 -25.309252) (xy 444.796467 -25.369961) (xy 444.735925 -25.425331) (xy 444.670542 -25.47489)
			(xy 444.600873 -25.518217) (xy 444.52751 -25.554945) (xy 444.451076 -25.584761) (xy 444.372222 -25.607412)
			(xy 444.291617 -25.622705) (xy 444.250826 -25.627076) (xy 444.240379 -25.628618) (xy 444.221981 -25.638935)
			(xy 444.2093 -25.655791) (xy 444.206376 -25.665938) (xy 444.196473 -25.705794) (xy 444.170375 -25.783666)
			(xy 444.137208 -25.8588) (xy 444.097254 -25.930555) (xy 444.050854 -25.998321) (xy 443.998403 -26.061519)
			(xy 443.940348 -26.119612) (xy 443.877184 -26.172104) (xy 443.809448 -26.218548) (xy 443.773814 -26.238962)
			(xy 443.765845 -26.243946) (xy 443.753852 -26.258396) (xy 443.750446 -26.267156) (xy 443.736369 -26.307378)
			(xy 443.701515 -26.385148) (xy 443.659384 -26.459228) (xy 443.61036 -26.528939) (xy 443.554893 -26.593641)
			(xy 443.493492 -26.652741) (xy 443.42672 -26.705698) (xy 443.355189 -26.752025) (xy 443.279554 -26.791298)
			(xy 443.200511 -26.823158) (xy 443.118782 -26.847311) (xy 443.035118 -26.863536) (xy 442.950285 -26.871685)
			(xy 442.907674 -26.872184) (xy 442.863879 -26.871639) (xy 442.776715 -26.863025) (xy 442.690819 -26.845883)
			(xy 442.607025 -26.82038) (xy 442.526144 -26.786761) (xy 442.487304 -26.76652) (xy 442.475838 -26.761102)
			(xy 442.45051 -26.761102) (xy 442.439044 -26.76652) (xy 442.400209 -26.786769) (xy 442.319322 -26.820374)
			(xy 442.235526 -26.845873) (xy 442.149632 -26.863019) (xy 442.062468 -26.871647) (xy 442.018674 -26.872184)
			(xy 441.974879 -26.871639) (xy 441.887715 -26.863025) (xy 441.801819 -26.845883) (xy 441.718025 -26.82038)
			(xy 441.637144 -26.786761) (xy 441.598304 -26.76652) (xy 441.586838 -26.761102) (xy 441.56151 -26.761102)
			(xy 441.550044 -26.76652) (xy 441.511209 -26.786769) (xy 441.430322 -26.820374) (xy 441.346526 -26.845873)
			(xy 441.260632 -26.863019) (xy 441.173468 -26.871647) (xy 441.129674 -26.872184) (xy 441.08856 -26.871712)
			(xy 441.006683 -26.864123) (xy 440.925855 -26.849012) (xy 440.846767 -26.826507) (xy 440.770092 -26.796802)
			(xy 440.696485 -26.760149) (xy 440.626574 -26.71686) (xy 440.560955 -26.667306) (xy 440.500188 -26.61191)
			(xy 440.444791 -26.551142) (xy 440.395237 -26.485523) (xy 440.351949 -26.415612) (xy 440.315297 -26.342004)
			(xy 440.285592 -26.265329) (xy 440.263088 -26.186241) (xy 440.247977 -26.105413) (xy 440.240388 -26.023536)
			(xy 440.239912 -25.982422) (xy 259.309108 -25.982422) (xy 259.309108 -32.117846) (xy 455.218281 -32.117846)
			(xy 455.218281 -31.988706) (xy 455.226231 -31.859811) (xy 455.242101 -31.731651) (xy 455.26583 -31.60471)
			(xy 455.297329 -31.479471) (xy 455.336478 -31.356408) (xy 455.383129 -31.235989) (xy 455.437104 -31.11867)
			(xy 455.498199 -31.004896) (xy 455.566182 -30.895099) (xy 455.640796 -30.789696) (xy 455.721757 -30.689086)
			(xy 455.808757 -30.593651) (xy 455.901468 -30.503752) (xy 455.999538 -30.419731) (xy 456.102593 -30.341907)
			(xy 456.210244 -30.270575) (xy 456.322083 -30.206005) (xy 456.437684 -30.148443) (xy 456.556609 -30.098106)
			(xy 456.678408 -30.055186) (xy 456.802618 -30.019845) (xy 456.928767 -29.992218) (xy 457.056379 -29.972409)
			(xy 457.184968 -29.960493) (xy 457.314046 -29.956517) (xy 457.443124 -29.960493) (xy 457.571713 -29.972409)
			(xy 457.699325 -29.992218) (xy 457.825474 -30.019845) (xy 457.949684 -30.055186) (xy 458.071483 -30.098106)
			(xy 458.190408 -30.148443) (xy 458.306009 -30.206005) (xy 458.417848 -30.270575) (xy 458.525499 -30.341907)
			(xy 458.628554 -30.419731) (xy 458.726624 -30.503752) (xy 458.819335 -30.593651) (xy 458.906335 -30.689086)
			(xy 458.987296 -30.789696) (xy 459.06191 -30.895099) (xy 459.129893 -31.004896) (xy 459.190988 -31.11867)
			(xy 459.244963 -31.235989) (xy 459.291614 -31.356408) (xy 459.330763 -31.479471) (xy 459.362262 -31.60471)
			(xy 459.385991 -31.731651) (xy 459.401861 -31.859811) (xy 459.409811 -31.988706) (xy 459.410308 -32.053276)
			(xy 459.409811 -32.117846) (xy 459.401861 -32.246741) (xy 459.385991 -32.374901) (xy 459.362262 -32.501842)
			(xy 459.330763 -32.627081) (xy 459.291614 -32.750144) (xy 459.244963 -32.870563) (xy 459.190988 -32.987882)
			(xy 459.129893 -33.101656) (xy 459.06191 -33.211453) (xy 458.987296 -33.316856) (xy 458.906335 -33.417466)
			(xy 458.819335 -33.512901) (xy 458.726624 -33.6028) (xy 458.628554 -33.686821) (xy 458.525499 -33.764645)
			(xy 458.417848 -33.835977) (xy 458.307206 -33.899856) (xy 461.798924 -33.899856) (xy 461.798924 -32.299656)
			(xy 461.799422 -32.222373) (xy 461.807378 -32.068013) (xy 461.823271 -31.914267) (xy 461.847057 -31.761543)
			(xy 461.878674 -31.610247) (xy 461.918037 -31.460778) (xy 461.965042 -31.313534) (xy 462.019566 -31.168904)
			(xy 462.081462 -31.027274) (xy 462.150567 -30.889017) (xy 462.226698 -30.754502) (xy 462.309652 -30.624083)
			(xy 462.399211 -30.498108) (xy 462.495135 -30.376911) (xy 462.597172 -30.260812) (xy 462.705049 -30.15012)
			(xy 462.818482 -30.045128) (xy 462.93717 -29.946115) (xy 463.060797 -29.853342) (xy 463.189036 -29.767057)
			(xy 463.321547 -29.687488) (xy 463.457979 -29.614846) (xy 463.597969 -29.549324) (xy 463.741146 -29.491095)
			(xy 463.887131 -29.440314) (xy 464.035537 -29.397115) (xy 464.185969 -29.361613) (xy 464.33803 -29.333903)
			(xy 464.491316 -29.314057) (xy 464.64542 -29.302128) (xy 464.799934 -29.298149) (xy 464.954448 -29.302128)
			(xy 465.108552 -29.314057) (xy 465.261838 -29.333903) (xy 465.413899 -29.361613) (xy 465.564331 -29.397115)
			(xy 465.712737 -29.440314) (xy 465.858722 -29.491095) (xy 466.001899 -29.549324) (xy 466.141889 -29.614846)
			(xy 466.278321 -29.687488) (xy 466.410832 -29.767057) (xy 466.539071 -29.853342) (xy 466.662698 -29.946115)
			(xy 466.781386 -30.045128) (xy 466.894819 -30.15012) (xy 467.002696 -30.260812) (xy 467.104733 -30.376911)
			(xy 467.200657 -30.498108) (xy 467.290216 -30.624083) (xy 467.37317 -30.754502) (xy 467.449301 -30.889017)
			(xy 467.518406 -31.027274) (xy 467.580302 -31.168904) (xy 467.634826 -31.313534) (xy 467.681831 -31.460778)
			(xy 467.721194 -31.610247) (xy 467.752811 -31.761543) (xy 467.776597 -31.914267) (xy 467.79249 -32.068013)
			(xy 467.800446 -32.222373) (xy 467.800944 -32.299656) (xy 467.800944 -33.899856) (xy 467.800446 -33.977139)
			(xy 467.79249 -34.131499) (xy 467.776597 -34.285245) (xy 467.752811 -34.437969) (xy 467.721194 -34.589265)
			(xy 467.681831 -34.738734) (xy 467.634826 -34.885978) (xy 467.580302 -35.030608) (xy 467.518406 -35.172238)
			(xy 467.449301 -35.310495) (xy 467.37317 -35.44501) (xy 467.290216 -35.575429) (xy 467.200657 -35.701404)
			(xy 467.104733 -35.822601) (xy 467.002696 -35.9387) (xy 466.894819 -36.049392) (xy 466.781386 -36.154384)
			(xy 466.662698 -36.253397) (xy 466.539071 -36.34617) (xy 466.410832 -36.432455) (xy 466.278321 -36.512024)
			(xy 466.141889 -36.584666) (xy 466.001899 -36.650188) (xy 465.858722 -36.708417) (xy 465.712737 -36.759198)
			(xy 465.564331 -36.802397) (xy 465.413899 -36.837899) (xy 465.261838 -36.865609) (xy 465.108552 -36.885455)
			(xy 464.954448 -36.897384) (xy 464.799934 -36.901364) (xy 464.64542 -36.897384) (xy 464.491316 -36.885455)
			(xy 464.33803 -36.865609) (xy 464.185969 -36.837899) (xy 464.035537 -36.802397) (xy 463.887131 -36.759198)
			(xy 463.741146 -36.708417) (xy 463.597969 -36.650188) (xy 463.457979 -36.584666) (xy 463.321547 -36.512024)
			(xy 463.189036 -36.432455) (xy 463.060797 -36.34617) (xy 462.93717 -36.253397) (xy 462.818482 -36.154384)
			(xy 462.705049 -36.049392) (xy 462.597172 -35.9387) (xy 462.495135 -35.822601) (xy 462.399211 -35.701404)
			(xy 462.309652 -35.575429) (xy 462.226698 -35.44501) (xy 462.150567 -35.310495) (xy 462.081462 -35.172238)
			(xy 462.019566 -35.030608) (xy 461.965042 -34.885978) (xy 461.918037 -34.738734) (xy 461.878674 -34.589265)
			(xy 461.847057 -34.437969) (xy 461.823271 -34.285245) (xy 461.807378 -34.131499) (xy 461.799422 -33.977139)
			(xy 461.798924 -33.899856) (xy 458.307206 -33.899856) (xy 458.306009 -33.900547) (xy 458.190408 -33.958109)
			(xy 458.071483 -34.008446) (xy 457.949684 -34.051366) (xy 457.825474 -34.086707) (xy 457.699325 -34.114334)
			(xy 457.571713 -34.134143) (xy 457.443124 -34.146059) (xy 457.314046 -34.150036) (xy 457.184968 -34.146059)
			(xy 457.056379 -34.134143) (xy 456.928767 -34.114334) (xy 456.802618 -34.086707) (xy 456.678408 -34.051366)
			(xy 456.556609 -34.008446) (xy 456.437684 -33.958109) (xy 456.322083 -33.900547) (xy 456.210244 -33.835977)
			(xy 456.102593 -33.764645) (xy 455.999538 -33.686821) (xy 455.901468 -33.6028) (xy 455.808757 -33.512901)
			(xy 455.721757 -33.417466) (xy 455.640796 -33.316856) (xy 455.566182 -33.211453) (xy 455.498199 -33.101656)
			(xy 455.437104 -32.987882) (xy 455.383129 -32.870563) (xy 455.336478 -32.750144) (xy 455.297329 -32.627081)
			(xy 455.26583 -32.501842) (xy 455.242101 -32.374901) (xy 455.226231 -32.246741) (xy 455.218281 -32.117846)
			(xy 259.309108 -32.117846) (xy 259.309108 -34.120074) (xy 259.308624 -34.190457) (xy 259.300733 -34.331001)
			(xy 259.284973 -34.470882) (xy 259.261395 -34.609659) (xy 259.230073 -34.746896) (xy 259.191105 -34.882161)
			(xy 259.144614 -35.015028) (xy 259.090747 -35.145079) (xy 259.029671 -35.271905) (xy 258.961581 -35.395107)
			(xy 258.88669 -35.514297) (xy 258.805233 -35.629101) (xy 258.717468 -35.739156) (xy 258.62367 -35.844118)
			(xy 258.524134 -35.943655) (xy 258.419173 -36.037454) (xy 258.309118 -36.12522) (xy 258.194315 -36.206678)
			(xy 258.075126 -36.28157) (xy 257.951924 -36.349661) (xy 257.825099 -36.410738) (xy 257.695048 -36.464606)
			(xy 257.562182 -36.511099) (xy 257.426917 -36.550068) (xy 257.289681 -36.581391) (xy 257.150904 -36.60497)
			(xy 257.011023 -36.620731) (xy 256.870479 -36.628623) (xy 256.800096 -36.629086) (xy 225.300032 -36.629086)
			(xy 225.229649 -36.628602) (xy 225.089105 -36.620711) (xy 224.949224 -36.604952) (xy 224.810447 -36.581374)
			(xy 224.673211 -36.550052) (xy 224.537946 -36.511084) (xy 224.40508 -36.464594) (xy 224.275029 -36.410726)
			(xy 224.148203 -36.349651) (xy 224.025001 -36.28156) (xy 223.905811 -36.206669) (xy 223.791008 -36.125213)
			(xy 223.680953 -36.037447) (xy 223.575992 -35.943648) (xy 223.476456 -35.844112) (xy 223.382657 -35.739152)
			(xy 223.294891 -35.629097) (xy 223.213434 -35.514294) (xy 223.138543 -35.395104) (xy 223.070452 -35.271902)
			(xy 223.009377 -35.145077) (xy 222.955509 -35.015026) (xy 222.909017 -34.882159) (xy 222.870049 -34.746895)
			(xy 222.838727 -34.609659) (xy 222.815149 -34.470882) (xy 222.799389 -34.331001) (xy 222.791498 -34.190457)
			(xy 222.79102 -34.120074) (xy 222.79102 -13.780008) (xy 222.790499 -13.724238) (xy 222.782164 -13.613011)
			(xy 222.765541 -13.502717) (xy 222.740722 -13.393974) (xy 222.707846 -13.287389) (xy 222.667097 -13.183559)
			(xy 222.618703 -13.083065) (xy 222.562935 -12.986469) (xy 222.500103 -12.894309) (xy 222.430561 -12.807103)
			(xy 222.354696 -12.725338) (xy 222.272933 -12.64947) (xy 222.185729 -12.579925) (xy 222.093572 -12.517091)
			(xy 221.996977 -12.461319) (xy 221.896485 -12.412922) (xy 221.792656 -12.37217) (xy 221.686073 -12.339291)
			(xy 221.57733 -12.314468) (xy 221.467037 -12.297841) (xy 221.35581 -12.289503) (xy 221.30004 -12.289028)
			(xy 196.701918 -12.289028) (xy 196.631535 -12.288544) (xy 196.49099 -12.280652) (xy 196.35111 -12.264892)
			(xy 196.212332 -12.241314) (xy 196.075095 -12.209992) (xy 195.939831 -12.171024) (xy 195.806964 -12.124532)
			(xy 195.676913 -12.070665) (xy 195.550086 -12.009589) (xy 195.426884 -11.941499) (xy 195.307694 -11.866608)
			(xy 195.19289 -11.785152) (xy 195.082834 -11.697386) (xy 194.977873 -11.603588) (xy 194.878335 -11.504052)
			(xy 194.784536 -11.399092) (xy 194.696769 -11.289037) (xy 194.615311 -11.174234) (xy 194.540418 -11.055045)
			(xy 194.472326 -10.931844) (xy 194.411249 -10.805018) (xy 194.35738 -10.674968) (xy 194.310887 -10.542102)
			(xy 194.271917 -10.406837) (xy 194.240593 -10.269601) (xy 194.217013 -10.130824) (xy 194.201251 -9.990943)
			(xy 194.193357 -9.850399) (xy 194.192906 -9.780016) (xy 194.192906 -5.839714) (xy 194.192489 -5.82969)
			(xy 194.184822 -5.811168) (xy 194.170649 -5.79699) (xy 194.152129 -5.789315) (xy 194.142106 -5.788914)
			(xy 126.661926 -5.788914) (xy 126.651902 -5.789329) (xy 126.633379 -5.796995) (xy 126.619202 -5.811169)
			(xy 126.611531 -5.82969) (xy 126.611126 -5.839714) (xy 126.611126 -9.780016) (xy 126.610632 -9.850398)
			(xy 126.602738 -9.990941) (xy 126.586977 -10.13082) (xy 126.563397 -10.269595) (xy 126.532074 -10.40683)
			(xy 126.51969 -10.449814) (xy 127.349765 -10.449814) (xy 127.353772 -10.361859) (xy 127.365761 -10.274634)
			(xy 127.385632 -10.18886) (xy 127.41322 -10.105248) (xy 127.448298 -10.024491) (xy 127.490574 -9.947259)
			(xy 127.539697 -9.874191) (xy 127.595262 -9.805893) (xy 127.656807 -9.742931) (xy 127.723823 -9.685826)
			(xy 127.795753 -9.635052) (xy 127.872003 -9.591029) (xy 127.951941 -9.554122) (xy 128.034903 -9.524637)
			(xy 128.120202 -9.502819) (xy 128.207132 -9.488848) (xy 128.294973 -9.482839) (xy 128.382996 -9.484843)
			(xy 128.470472 -9.494844) (xy 128.556676 -9.512757) (xy 128.640894 -9.538435) (xy 128.722428 -9.571665)
			(xy 128.800603 -9.612172) (xy 128.87477 -9.65962) (xy 128.944315 -9.713615) (xy 129.008662 -9.773711)
			(xy 129.067278 -9.83941) (xy 129.119676 -9.910166) (xy 129.165423 -9.985394) (xy 129.20414 -10.06447)
			(xy 129.235506 -10.14674) (xy 129.25926 -10.231521) (xy 129.266448 -10.270552) (xy 131.639267 -10.270552)
			(xy 131.639267 -10.216048) (xy 131.647024 -10.162097) (xy 131.66238 -10.1098) (xy 131.685023 -10.060221)
			(xy 131.714491 -10.014369) (xy 131.750185 -9.973177) (xy 131.791377 -9.937485) (xy 131.83723 -9.908018)
			(xy 131.88681 -9.885377) (xy 131.939107 -9.870022) (xy 131.993058 -9.862267) (xy 132.02031 -9.861804)
			(xy 132.88391 -9.861804) (xy 132.911162 -9.862266) (xy 132.96511 -9.870024) (xy 133.017405 -9.885381)
			(xy 133.066983 -9.908023) (xy 133.112833 -9.937491) (xy 133.154024 -9.973183) (xy 133.189715 -10.014375)
			(xy 133.219181 -10.060226) (xy 133.241823 -10.109804) (xy 133.257178 -10.1621) (xy 133.264934 -10.216048)
			(xy 133.264934 -10.270552) (xy 133.257178 -10.3245) (xy 133.241823 -10.376796) (xy 133.219181 -10.426374)
			(xy 133.189715 -10.472225) (xy 133.154024 -10.513417) (xy 133.112833 -10.549109) (xy 133.066983 -10.578577)
			(xy 133.017405 -10.601219) (xy 132.96511 -10.616576) (xy 132.911162 -10.624334) (xy 132.88391 -10.62482)
			(xy 132.02031 -10.62482) (xy 131.993058 -10.624333) (xy 131.939107 -10.616578) (xy 131.88681 -10.601223)
			(xy 131.83723 -10.578582) (xy 131.791377 -10.549115) (xy 131.750185 -10.513423) (xy 131.714491 -10.472231)
			(xy 131.685023 -10.426379) (xy 131.66238 -10.3768) (xy 131.647024 -10.324503) (xy 131.639267 -10.270552)
			(xy 129.266448 -10.270552) (xy 129.275207 -10.31811) (xy 129.283213 -10.405791) (xy 129.283714 -10.449814)
			(xy 129.283213 -10.493837) (xy 129.275207 -10.581518) (xy 129.25926 -10.668107) (xy 129.235506 -10.752888)
			(xy 129.212528 -10.813156) (xy 169.954611 -10.813156) (xy 169.954611 -10.758644) (xy 169.962369 -10.704687)
			(xy 169.977727 -10.652382) (xy 170.000372 -10.602796) (xy 170.029844 -10.556938) (xy 170.065542 -10.51574)
			(xy 170.106739 -10.480043) (xy 170.152598 -10.450571) (xy 170.202184 -10.427926) (xy 170.254488 -10.412568)
			(xy 170.308446 -10.404811) (xy 170.335702 -10.404348) (xy 171.199302 -10.404348) (xy 171.22655 -10.404922)
			(xy 171.280491 -10.412678) (xy 171.33278 -10.428032) (xy 171.382351 -10.45067) (xy 171.428196 -10.480133)
			(xy 171.469381 -10.515821) (xy 171.505068 -10.557006) (xy 171.534531 -10.602851) (xy 171.557169 -10.652422)
			(xy 171.572522 -10.704711) (xy 171.580278 -10.758652) (xy 171.580278 -10.813148) (xy 171.572522 -10.867089)
			(xy 171.557169 -10.919378) (xy 171.534531 -10.968949) (xy 171.505068 -11.014794) (xy 171.469381 -11.055979)
			(xy 171.428196 -11.091667) (xy 171.382351 -11.12113) (xy 171.33278 -11.143768) (xy 171.280491 -11.159122)
			(xy 171.22655 -11.166878) (xy 171.199302 -11.167364) (xy 170.335702 -11.167364) (xy 170.308446 -11.166989)
			(xy 170.254488 -11.159232) (xy 170.202184 -11.143874) (xy 170.152598 -11.121229) (xy 170.106739 -11.091757)
			(xy 170.065542 -11.05606) (xy 170.029844 -11.014862) (xy 170.000372 -10.969004) (xy 169.977727 -10.919418)
			(xy 169.962369 -10.867113) (xy 169.954611 -10.813156) (xy 129.212528 -10.813156) (xy 129.20414 -10.835158)
			(xy 129.165423 -10.914234) (xy 129.119676 -10.989462) (xy 129.067278 -11.060218) (xy 129.008662 -11.125917)
			(xy 128.944315 -11.186013) (xy 128.87477 -11.240008) (xy 128.800603 -11.287456) (xy 128.722428 -11.327963)
			(xy 128.640894 -11.361193) (xy 128.556676 -11.386871) (xy 128.470472 -11.404784) (xy 128.382996 -11.414785)
			(xy 128.294973 -11.416789) (xy 128.207132 -11.41078) (xy 128.120202 -11.396809) (xy 128.034903 -11.374991)
			(xy 127.951941 -11.345506) (xy 127.872003 -11.308599) (xy 127.795753 -11.264576) (xy 127.723823 -11.213802)
			(xy 127.656807 -11.156697) (xy 127.595262 -11.093735) (xy 127.539697 -11.025437) (xy 127.490574 -10.952369)
			(xy 127.448298 -10.875137) (xy 127.41322 -10.79438) (xy 127.385632 -10.710768) (xy 127.365761 -10.624994)
			(xy 127.353772 -10.537769) (xy 127.349765 -10.449814) (xy 126.51969 -10.449814) (xy 126.493105 -10.542092)
			(xy 126.446613 -10.674957) (xy 126.392744 -10.805006) (xy 126.331668 -10.93183) (xy 126.263578 -11.05503)
			(xy 126.188687 -11.174218) (xy 126.10723 -11.28902) (xy 126.019465 -11.399074) (xy 125.925667 -11.504033)
			(xy 125.826132 -11.603569) (xy 125.721172 -11.697366) (xy 125.611118 -11.785131) (xy 125.496317 -11.866588)
			(xy 125.495706 -11.866972) (xy 129.833804 -11.866972) (xy 129.833804 -11.812428) (xy 129.841567 -11.758438)
			(xy 129.856934 -11.706103) (xy 129.879594 -11.656488) (xy 129.909085 -11.610603) (xy 129.944805 -11.569383)
			(xy 129.986029 -11.533665) (xy 130.031916 -11.504179) (xy 130.081533 -11.481523) (xy 130.13387 -11.46616)
			(xy 130.18786 -11.458401) (xy 130.215132 -11.45794) (xy 131.078732 -11.45794) (xy 131.106 -11.458425)
			(xy 131.15998 -11.46619) (xy 131.212306 -11.481558) (xy 131.261913 -11.504216) (xy 131.30779 -11.533703)
			(xy 131.349004 -11.569419) (xy 131.384716 -11.610636) (xy 131.414199 -11.656515) (xy 131.436853 -11.706124)
			(xy 131.452217 -11.758451) (xy 131.459978 -11.812432) (xy 131.459978 -11.866968) (xy 131.452217 -11.920949)
			(xy 131.436853 -11.973276) (xy 131.432747 -11.982267) (xy 135.233942 -11.982267) (xy 135.233942 -11.927733)
			(xy 135.241703 -11.873755) (xy 135.257066 -11.82143) (xy 135.279719 -11.771824) (xy 135.309201 -11.725946)
			(xy 135.344912 -11.684731) (xy 135.386124 -11.649018) (xy 135.431999 -11.619533) (xy 135.481603 -11.596876)
			(xy 135.533927 -11.581509) (xy 135.587905 -11.573744) (xy 135.615172 -11.573256) (xy 136.478772 -11.573256)
			(xy 136.506046 -11.573682) (xy 136.560038 -11.581441) (xy 136.612377 -11.596805) (xy 136.661996 -11.619462)
			(xy 136.707885 -11.648951) (xy 136.74911 -11.68467) (xy 136.784832 -11.725893) (xy 136.814324 -11.77178)
			(xy 136.836985 -11.821397) (xy 136.852353 -11.873735) (xy 136.860116 -11.927726) (xy 136.860116 -11.982274)
			(xy 136.852353 -12.036265) (xy 136.836985 -12.088603) (xy 136.814324 -12.13822) (xy 136.784832 -12.184107)
			(xy 136.74911 -12.22533) (xy 136.707885 -12.261049) (xy 136.661996 -12.290538) (xy 136.612377 -12.313195)
			(xy 136.560038 -12.328559) (xy 136.506046 -12.336318) (xy 136.478772 -12.33678) (xy 135.615172 -12.33678)
			(xy 135.587905 -12.336256) (xy 135.533927 -12.328491) (xy 135.481603 -12.313124) (xy 135.431999 -12.290467)
			(xy 135.386124 -12.260982) (xy 135.344912 -12.225269) (xy 135.309201 -12.184054) (xy 135.279719 -12.138176)
			(xy 135.257066 -12.08857) (xy 135.241703 -12.036245) (xy 135.233942 -11.982267) (xy 131.432747 -11.982267)
			(xy 131.414199 -12.022885) (xy 131.384716 -12.068764) (xy 131.349004 -12.109981) (xy 131.30779 -12.145697)
			(xy 131.261913 -12.175184) (xy 131.212306 -12.197842) (xy 131.15998 -12.21321) (xy 131.106 -12.220975)
			(xy 131.078732 -12.221464) (xy 130.215132 -12.221464) (xy 130.18786 -12.220999) (xy 130.13387 -12.21324)
			(xy 130.081533 -12.197877) (xy 130.031916 -12.175221) (xy 129.986029 -12.145735) (xy 129.944805 -12.110017)
			(xy 129.909085 -12.068797) (xy 129.879594 -12.022912) (xy 129.856934 -11.973297) (xy 129.841567 -11.920962)
			(xy 129.833804 -11.866972) (xy 125.495706 -11.866972) (xy 125.377128 -11.941479) (xy 125.253928 -12.009569)
			(xy 125.127104 -12.070645) (xy 124.997055 -12.124513) (xy 124.86419 -12.171005) (xy 124.728928 -12.209974)
			(xy 124.591693 -12.241298) (xy 124.452918 -12.264877) (xy 124.313039 -12.280639) (xy 124.172496 -12.288532)
			(xy 124.102114 -12.289028) (xy 83.70189 -12.289028) (xy 83.631508 -12.288534) (xy 83.490965 -12.280641)
			(xy 83.351086 -12.26488) (xy 83.21231 -12.2413) (xy 83.075075 -12.209977) (xy 82.939812 -12.171008)
			(xy 82.806947 -12.124516) (xy 82.676898 -12.070648) (xy 82.550073 -12.009572) (xy 82.426873 -11.941482)
			(xy 82.307684 -11.866591) (xy 82.192882 -11.785134) (xy 82.082828 -11.697369) (xy 81.977868 -11.603571)
			(xy 81.878333 -11.504036) (xy 81.784535 -11.399076) (xy 81.696769 -11.289022) (xy 81.615313 -11.174221)
			(xy 81.540421 -11.055032) (xy 81.47233 -10.931832) (xy 81.411254 -10.805008) (xy 81.357386 -10.674959)
			(xy 81.310894 -10.542094) (xy 81.271924 -10.406831) (xy 81.240601 -10.269596) (xy 81.217021 -10.13082)
			(xy 81.20126 -9.990941) (xy 81.193366 -9.850398) (xy 81.192878 -9.780016) (xy 81.192878 -0.559816)
			(xy 81.192461 -0.549794) (xy 81.184793 -0.531276) (xy 81.170619 -0.517104) (xy 81.1521 -0.509438)
			(xy 81.142078 -0.509016) (xy 13.661898 -0.509016) (xy 13.651878 -0.509436) (xy 13.633365 -0.517107)
			(xy 13.619197 -0.53128) (xy 13.611532 -0.549796) (xy 13.611098 -0.559816) (xy 13.611098 -5.169916)
			(xy 14.349737 -5.169916) (xy 14.353744 -5.081961) (xy 14.365733 -4.994736) (xy 14.385604 -4.908962)
			(xy 14.413192 -4.82535) (xy 14.44827 -4.744593) (xy 14.490546 -4.667361) (xy 14.539669 -4.594293)
			(xy 14.595234 -4.525995) (xy 14.656779 -4.463033) (xy 14.723795 -4.405928) (xy 14.795725 -4.355154)
			(xy 14.871975 -4.311131) (xy 14.951913 -4.274224) (xy 15.034875 -4.244739) (xy 15.120174 -4.222921)
			(xy 15.207104 -4.20895) (xy 15.294945 -4.202941) (xy 15.382968 -4.204945) (xy 15.470444 -4.214946)
			(xy 15.556648 -4.232859) (xy 15.640866 -4.258537) (xy 15.7224 -4.291767) (xy 15.800575 -4.332274)
			(xy 15.874742 -4.379722) (xy 15.944287 -4.433717) (xy 16.008634 -4.493813) (xy 16.06725 -4.559512)
			(xy 16.119648 -4.630268) (xy 16.165395 -4.705496) (xy 16.204112 -4.784572) (xy 16.235478 -4.866842)
			(xy 16.259232 -4.951623) (xy 16.266423 -4.990667) (xy 20.439138 -4.990667) (xy 20.439138 -4.936133)
			(xy 20.446899 -4.882153) (xy 20.462263 -4.829827) (xy 20.484917 -4.78022) (xy 20.5144 -4.734341)
			(xy 20.550112 -4.693126) (xy 20.591325 -4.657412) (xy 20.637202 -4.627926) (xy 20.686808 -4.60527)
			(xy 20.739133 -4.589903) (xy 20.793113 -4.58214) (xy 20.82038 -4.581652) (xy 21.68398 -4.581652)
			(xy 21.711253 -4.582086) (xy 21.765244 -4.589846) (xy 21.817581 -4.605211) (xy 21.867198 -4.627869)
			(xy 21.913086 -4.657357) (xy 21.95431 -4.693076) (xy 21.990031 -4.734298) (xy 22.019522 -4.780184)
			(xy 22.042182 -4.8298) (xy 22.057549 -4.882136) (xy 22.065312 -4.936127) (xy 22.065312 -4.990671)
			(xy 24.039016 -4.990671) (xy 24.039016 -4.936129) (xy 24.046778 -4.882142) (xy 24.062145 -4.82981)
			(xy 24.084803 -4.780197) (xy 24.114292 -4.734314) (xy 24.15001 -4.693095) (xy 24.191231 -4.657379)
			(xy 24.237116 -4.627893) (xy 24.28673 -4.605237) (xy 24.339064 -4.589873) (xy 24.393051 -4.582114)
			(xy 24.420322 -4.581652) (xy 25.283922 -4.581652) (xy 25.311191 -4.582112) (xy 25.365175 -4.589876)
			(xy 25.417503 -4.605244) (xy 25.467113 -4.627903) (xy 25.512992 -4.65739) (xy 25.554209 -4.693107)
			(xy 25.589923 -4.734325) (xy 25.619408 -4.780207) (xy 25.642063 -4.829817) (xy 25.657428 -4.882147)
			(xy 25.66519 -4.936131) (xy 25.66519 -4.990667) (xy 27.639038 -4.990667) (xy 27.639038 -4.936133)
			(xy 27.646799 -4.882155) (xy 27.662162 -4.82983) (xy 27.684814 -4.780224) (xy 27.714296 -4.734347)
			(xy 27.750006 -4.693131) (xy 27.791218 -4.657417) (xy 27.837092 -4.627932) (xy 27.886696 -4.605274)
			(xy 27.93902 -4.589906) (xy 27.992997 -4.582141) (xy 28.020264 -4.581652) (xy 28.883864 -4.581652)
			(xy 28.911138 -4.582085) (xy 28.96513 -4.589843) (xy 29.017469 -4.605207) (xy 29.067089 -4.627863)
			(xy 29.112979 -4.657351) (xy 29.154205 -4.69307) (xy 29.189927 -4.734292) (xy 29.219419 -4.78018)
			(xy 29.24208 -4.829797) (xy 29.257449 -4.882134) (xy 29.265212 -4.936126) (xy 29.265212 -4.990667)
			(xy 31.239238 -4.990667) (xy 31.239238 -4.936133) (xy 31.246999 -4.882155) (xy 31.262361 -4.829831)
			(xy 31.285014 -4.780225) (xy 31.314495 -4.734348) (xy 31.350205 -4.693133) (xy 31.391416 -4.657419)
			(xy 31.43729 -4.627933) (xy 31.486893 -4.605275) (xy 31.539216 -4.589907) (xy 31.593193 -4.582141)
			(xy 31.62046 -4.581652) (xy 32.48406 -4.581652) (xy 32.511334 -4.582085) (xy 32.565327 -4.589843)
			(xy 32.617666 -4.605206) (xy 32.667286 -4.627862) (xy 32.713177 -4.65735) (xy 32.754403 -4.693068)
			(xy 32.790126 -4.734291) (xy 32.819619 -4.780178) (xy 32.84228 -4.829796) (xy 32.857649 -4.882134)
			(xy 32.865412 -4.936126) (xy 32.865412 -4.990671) (xy 40.349116 -4.990671) (xy 40.349116 -4.936129)
			(xy 40.356878 -4.882142) (xy 40.372245 -4.829809) (xy 40.394903 -4.780196) (xy 40.424392 -4.734313)
			(xy 40.460111 -4.693094) (xy 40.501332 -4.657378) (xy 40.547217 -4.627892) (xy 40.596832 -4.605237)
			(xy 40.649165 -4.589873) (xy 40.703153 -4.582114) (xy 40.730424 -4.581652) (xy 41.594024 -4.581652)
			(xy 41.621293 -4.582112) (xy 41.675276 -4.589877) (xy 41.727605 -4.605245) (xy 41.777214 -4.627903)
			(xy 41.823093 -4.657391) (xy 41.86431 -4.693107) (xy 41.900024 -4.734326) (xy 41.929508 -4.780207)
			(xy 41.952164 -4.829818) (xy 41.967528 -4.882147) (xy 41.97529 -4.936131) (xy 41.97529 -4.990667)
			(xy 43.949138 -4.990667) (xy 43.949138 -4.936133) (xy 43.956899 -4.882155) (xy 43.972262 -4.82983)
			(xy 43.994915 -4.780224) (xy 44.024396 -4.734346) (xy 44.060107 -4.693131) (xy 44.101319 -4.657417)
			(xy 44.147194 -4.627931) (xy 44.196798 -4.605274) (xy 44.249121 -4.589906) (xy 44.303099 -4.582141)
			(xy 44.330366 -4.581652) (xy 45.193966 -4.581652) (xy 45.22124 -4.582085) (xy 45.275232 -4.589844)
			(xy 45.327571 -4.605208) (xy 45.37719 -4.627864) (xy 45.42308 -4.657352) (xy 45.464305 -4.693071)
			(xy 45.500028 -4.734293) (xy 45.52952 -4.78018) (xy 45.552181 -4.829797) (xy 45.567549 -4.882135)
			(xy 45.575312 -4.936126) (xy 45.575312 -4.990667) (xy 51.559238 -4.990667) (xy 51.559238 -4.936133)
			(xy 51.566999 -4.882155) (xy 51.582361 -4.829831) (xy 51.605014 -4.780225) (xy 51.634495 -4.734348)
			(xy 51.670205 -4.693133) (xy 51.711416 -4.657419) (xy 51.75729 -4.627933) (xy 51.806893 -4.605275)
			(xy 51.859216 -4.589907) (xy 51.913193 -4.582141) (xy 51.94046 -4.581652) (xy 52.80406 -4.581652)
			(xy 52.831334 -4.582085) (xy 52.885327 -4.589843) (xy 52.937666 -4.605206) (xy 52.987286 -4.627862)
			(xy 53.033177 -4.65735) (xy 53.074403 -4.693068) (xy 53.110126 -4.734291) (xy 53.139619 -4.780178)
			(xy 53.16228 -4.829796) (xy 53.177649 -4.882134) (xy 53.185412 -4.936126) (xy 53.185412 -4.99067)
			(xy 55.159115 -4.99067) (xy 55.159115 -4.93613) (xy 55.166877 -4.882145) (xy 55.182243 -4.829814)
			(xy 55.2049 -4.780202) (xy 55.234387 -4.73432) (xy 55.270103 -4.693102) (xy 55.311322 -4.657386)
			(xy 55.357204 -4.627899) (xy 55.406816 -4.605242) (xy 55.459147 -4.589877) (xy 55.513132 -4.582115)
			(xy 55.540402 -4.581652) (xy 56.404002 -4.581652) (xy 56.431272 -4.582111) (xy 56.485258 -4.589873)
			(xy 56.537589 -4.605239) (xy 56.587201 -4.627896) (xy 56.633083 -4.657383) (xy 56.674302 -4.6931)
			(xy 56.710018 -4.734319) (xy 56.739505 -4.780201) (xy 56.762162 -4.829813) (xy 56.777528 -4.882144)
			(xy 56.78529 -4.93613) (xy 56.78529 -4.99067) (xy 56.777528 -5.044656) (xy 56.762162 -5.096987) (xy 56.739505 -5.146599)
			(xy 56.710018 -5.192481) (xy 56.674302 -5.2337) (xy 56.633083 -5.269417) (xy 56.587201 -5.298904)
			(xy 56.537589 -5.321561) (xy 56.485258 -5.336927) (xy 56.431272 -5.344689) (xy 56.404002 -5.345176)
			(xy 55.540402 -5.345176) (xy 55.513132 -5.344685) (xy 55.459147 -5.336923) (xy 55.406816 -5.321558)
			(xy 55.357204 -5.298901) (xy 55.311322 -5.269414) (xy 55.270103 -5.233698) (xy 55.234387 -5.19248)
			(xy 55.2049 -5.146598) (xy 55.182243 -5.096986) (xy 55.166877 -5.044655) (xy 55.159115 -4.99067)
			(xy 53.185412 -4.99067) (xy 53.185412 -4.990674) (xy 53.177649 -5.044666) (xy 53.16228 -5.097004)
			(xy 53.139619 -5.146622) (xy 53.110126 -5.192509) (xy 53.074403 -5.233732) (xy 53.033177 -5.26945)
			(xy 52.987286 -5.298938) (xy 52.937666 -5.321594) (xy 52.885327 -5.336957) (xy 52.831334 -5.344715)
			(xy 52.80406 -5.345176) (xy 51.94046 -5.345176) (xy 51.913194 -5.344659) (xy 51.859216 -5.336893)
			(xy 51.806893 -5.321525) (xy 51.75729 -5.298867) (xy 51.711416 -5.269381) (xy 51.670205 -5.233667)
			(xy 51.634495 -5.192452) (xy 51.605014 -5.146575) (xy 51.582361 -5.096969) (xy 51.566999 -5.044645)
			(xy 51.559238 -4.990667) (xy 45.575312 -4.990667) (xy 45.575312 -4.990674) (xy 45.567549 -5.044665)
			(xy 45.552181 -5.097003) (xy 45.52952 -5.14662) (xy 45.500028 -5.192507) (xy 45.464305 -5.233729)
			(xy 45.42308 -5.269448) (xy 45.37719 -5.298936) (xy 45.327571 -5.321592) (xy 45.275232 -5.336956)
			(xy 45.22124 -5.344715) (xy 45.193966 -5.345176) (xy 44.330366 -5.345176) (xy 44.303099 -5.344659)
			(xy 44.249121 -5.336894) (xy 44.196798 -5.321526) (xy 44.147194 -5.298869) (xy 44.101319 -5.269383)
			(xy 44.060107 -5.233669) (xy 44.024396 -5.192454) (xy 43.994915 -5.146576) (xy 43.972262 -5.09697)
			(xy 43.956899 -5.044645) (xy 43.949138 -4.990667) (xy 41.97529 -4.990667) (xy 41.97529 -4.990669)
			(xy 41.967528 -5.044653) (xy 41.952164 -5.096982) (xy 41.929508 -5.146593) (xy 41.900024 -5.192474)
			(xy 41.86431 -5.233693) (xy 41.823093 -5.269409) (xy 41.777214 -5.298897) (xy 41.727605 -5.321555)
			(xy 41.675276 -5.336923) (xy 41.621293 -5.344688) (xy 41.594024 -5.345176) (xy 40.730424 -5.345176)
			(xy 40.703153 -5.344686) (xy 40.649165 -5.336927) (xy 40.596832 -5.321563) (xy 40.547217 -5.298908)
			(xy 40.501332 -5.269422) (xy 40.460111 -5.233706) (xy 40.424392 -5.192487) (xy 40.394903 -5.146604)
			(xy 40.372245 -5.096991) (xy 40.356878 -5.044658) (xy 40.349116 -4.990671) (xy 32.865412 -4.990671)
			(xy 32.865412 -4.990674) (xy 32.857649 -5.044666) (xy 32.84228 -5.097004) (xy 32.819619 -5.146622)
			(xy 32.790126 -5.192509) (xy 32.754403 -5.233732) (xy 32.713177 -5.26945) (xy 32.667286 -5.298938)
			(xy 32.617666 -5.321594) (xy 32.565327 -5.336957) (xy 32.511334 -5.344715) (xy 32.48406 -5.345176)
			(xy 31.62046 -5.345176) (xy 31.593194 -5.344659) (xy 31.539216 -5.336893) (xy 31.486893 -5.321525)
			(xy 31.43729 -5.298867) (xy 31.391416 -5.269381) (xy 31.350205 -5.233667) (xy 31.314495 -5.192452)
			(xy 31.285014 -5.146575) (xy 31.262361 -5.096969) (xy 31.246999 -5.044645) (xy 31.239238 -4.990667)
			(xy 29.265212 -4.990667) (xy 29.265212 -4.990674) (xy 29.257449 -5.044666) (xy 29.24208 -5.097003)
			(xy 29.219419 -5.14662) (xy 29.189927 -5.192508) (xy 29.154205 -5.23373) (xy 29.112979 -5.269449)
			(xy 29.067089 -5.298937) (xy 29.017469 -5.321593) (xy 28.96513 -5.336957) (xy 28.911138 -5.344715)
			(xy 28.883864 -5.345176) (xy 28.020264 -5.345176) (xy 27.992997 -5.344659) (xy 27.93902 -5.336894)
			(xy 27.886696 -5.321526) (xy 27.837092 -5.298868) (xy 27.791218 -5.269383) (xy 27.750006 -5.233669)
			(xy 27.714296 -5.192453) (xy 27.684814 -5.146576) (xy 27.662162 -5.09697) (xy 27.646799 -5.044645)
			(xy 27.639038 -4.990667) (xy 25.66519 -4.990667) (xy 25.66519 -4.990669) (xy 25.657428 -5.044653)
			(xy 25.642063 -5.096983) (xy 25.619408 -5.146593) (xy 25.589923 -5.192475) (xy 25.554209 -5.233693)
			(xy 25.512992 -5.26941) (xy 25.467113 -5.298897) (xy 25.417503 -5.321556) (xy 25.365175 -5.336924)
			(xy 25.311191 -5.344688) (xy 25.283922 -5.345176) (xy 24.420322 -5.345176) (xy 24.393051 -5.344686)
			(xy 24.339064 -5.336927) (xy 24.28673 -5.321563) (xy 24.237116 -5.298907) (xy 24.191231 -5.269421)
			(xy 24.15001 -5.233705) (xy 24.114292 -5.192486) (xy 24.084803 -5.146603) (xy 24.062145 -5.09699)
			(xy 24.046778 -5.044658) (xy 24.039016 -4.990671) (xy 22.065312 -4.990671) (xy 22.065312 -4.990673)
			(xy 22.057549 -5.044664) (xy 22.042182 -5.097) (xy 22.019522 -5.146616) (xy 21.990031 -5.192502)
			(xy 21.95431 -5.233724) (xy 21.913086 -5.269443) (xy 21.867198 -5.298931) (xy 21.817581 -5.321589)
			(xy 21.765244 -5.336954) (xy 21.711253 -5.344714) (xy 21.68398 -5.345176) (xy 20.82038 -5.345176)
			(xy 20.793113 -5.34466) (xy 20.739133 -5.336897) (xy 20.686808 -5.32153) (xy 20.637202 -5.298874)
			(xy 20.591325 -5.269388) (xy 20.550112 -5.233674) (xy 20.5144 -5.192459) (xy 20.484917 -5.14658)
			(xy 20.462263 -5.096973) (xy 20.446899 -5.044647) (xy 20.439138 -4.990667) (xy 16.266423 -4.990667)
			(xy 16.275179 -5.038212) (xy 16.283185 -5.125893) (xy 16.283686 -5.169916) (xy 16.283185 -5.213939)
			(xy 16.275179 -5.30162) (xy 16.259232 -5.388209) (xy 16.235478 -5.47299) (xy 16.204112 -5.55526)
			(xy 16.165395 -5.634336) (xy 16.119648 -5.709564) (xy 16.06725 -5.78032) (xy 16.008634 -5.846019)
			(xy 15.944287 -5.906115) (xy 15.874742 -5.96011) (xy 15.800575 -6.007558) (xy 15.7224 -6.048065)
			(xy 15.640866 -6.081295) (xy 15.556648 -6.106973) (xy 15.470444 -6.124886) (xy 15.382968 -6.134887)
			(xy 15.294945 -6.136891) (xy 15.207104 -6.130882) (xy 15.120174 -6.116911) (xy 15.034875 -6.095093)
			(xy 14.951913 -6.065608) (xy 14.871975 -6.028701) (xy 14.795725 -5.984678) (xy 14.723795 -5.933904)
			(xy 14.656779 -5.876799) (xy 14.595234 -5.813837) (xy 14.539669 -5.745539) (xy 14.490546 -5.672471)
			(xy 14.44827 -5.595239) (xy 14.413192 -5.514482) (xy 14.385604 -5.43087) (xy 14.365733 -5.345096)
			(xy 14.353744 -5.257871) (xy 14.349737 -5.169916) (xy 13.611098 -5.169916) (xy 13.611098 -6.169914)
			(xy 78.515217 -6.169914) (xy 78.519222 -6.082006) (xy 78.531205 -5.994826) (xy 78.551065 -5.909097)
			(xy 78.57864 -5.825529) (xy 78.613699 -5.744815) (xy 78.655952 -5.667623) (xy 78.70505 -5.594594)
			(xy 78.760586 -5.526332) (xy 78.822098 -5.463402) (xy 78.889079 -5.406328) (xy 78.960972 -5.35558)
			(xy 79.037181 -5.31158) (xy 79.117076 -5.274693) (xy 79.199995 -5.245224) (xy 79.28525 -5.223417)
			(xy 79.372134 -5.209453) (xy 79.459928 -5.203447) (xy 79.547905 -5.205451) (xy 79.635335 -5.215446)
			(xy 79.721494 -5.23335) (xy 79.805668 -5.259014) (xy 79.887159 -5.292227) (xy 79.965293 -5.332713)
			(xy 80.039421 -5.380135) (xy 80.108929 -5.434102) (xy 80.173243 -5.494167) (xy 80.231827 -5.559831)
			(xy 80.284198 -5.63055) (xy 80.329921 -5.705738) (xy 80.368618 -5.784773) (xy 80.399967 -5.866999)
			(xy 80.423709 -5.951735) (xy 80.439647 -6.038279) (xy 80.447649 -6.125914) (xy 80.44815 -6.169914)
			(xy 80.447649 -6.213914) (xy 80.439647 -6.301549) (xy 80.423709 -6.388093) (xy 80.399967 -6.472829)
			(xy 80.368618 -6.555055) (xy 80.329921 -6.63409) (xy 80.284198 -6.709278) (xy 80.231827 -6.779997)
			(xy 80.173243 -6.845661) (xy 80.108929 -6.905726) (xy 80.039421 -6.959693) (xy 79.965293 -7.007115)
			(xy 79.887159 -7.047601) (xy 79.805668 -7.080814) (xy 79.721494 -7.106478) (xy 79.635335 -7.124382)
			(xy 79.547905 -7.134377) (xy 79.459928 -7.136381) (xy 79.372134 -7.130375) (xy 79.28525 -7.116411)
			(xy 79.199995 -7.094604) (xy 79.117076 -7.065135) (xy 79.037181 -7.028248) (xy 78.960972 -6.984248)
			(xy 78.889079 -6.9335) (xy 78.822098 -6.876426) (xy 78.760586 -6.813496) (xy 78.70505 -6.745234)
			(xy 78.655952 -6.672205) (xy 78.613699 -6.595013) (xy 78.57864 -6.514299) (xy 78.551065 -6.430731)
			(xy 78.531205 -6.345002) (xy 78.519222 -6.257822) (xy 78.515217 -6.169914) (xy 13.611098 -6.169914)
			(xy 13.611098 -6.75243) (xy 18.634432 -6.75243) (xy 18.634432 -6.69789) (xy 18.642194 -6.643907)
			(xy 18.65756 -6.591577) (xy 18.680216 -6.541966) (xy 18.709702 -6.496085) (xy 18.745417 -6.454867)
			(xy 18.786635 -6.419152) (xy 18.832516 -6.389666) (xy 18.882127 -6.36701) (xy 18.934457 -6.351644)
			(xy 18.98844 -6.343882) (xy 19.01571 -6.343396) (xy 19.87931 -6.343396) (xy 19.906579 -6.343886)
			(xy 19.960563 -6.351648) (xy 20.012892 -6.367013) (xy 20.062502 -6.389669) (xy 20.108382 -6.419155)
			(xy 20.1496 -6.45487) (xy 20.185315 -6.496088) (xy 20.214801 -6.541968) (xy 20.237457 -6.591578)
			(xy 20.252822 -6.643907) (xy 20.260584 -6.697891) (xy 20.260584 -6.752429) (xy 20.260584 -6.752431)
			(xy 22.234349 -6.752431) (xy 22.234349 -6.697889) (xy 22.242112 -6.643901) (xy 22.257478 -6.591568)
			(xy 22.280136 -6.541955) (xy 22.309624 -6.496071) (xy 22.345342 -6.45485) (xy 22.386562 -6.419133)
			(xy 22.432447 -6.389645) (xy 22.48206 -6.366987) (xy 22.534393 -6.351621) (xy 22.588381 -6.343859)
			(xy 22.615652 -6.343396) (xy 23.479252 -6.343396) (xy 23.506521 -6.343887) (xy 23.560504 -6.351648)
			(xy 23.612833 -6.367014) (xy 23.662443 -6.38967) (xy 23.708323 -6.419156) (xy 23.749541 -6.454871)
			(xy 23.785255 -6.496088) (xy 23.814741 -6.541969) (xy 23.837397 -6.591579) (xy 23.852762 -6.643908)
			(xy 23.860524 -6.697891) (xy 23.860524 -6.752429) (xy 23.860518 -6.752472) (xy 25.834283 -6.752472)
			(xy 25.834283 -6.697928) (xy 25.842045 -6.643939) (xy 25.857412 -6.591604) (xy 25.88007 -6.541989)
			(xy 25.909558 -6.496103) (xy 25.945277 -6.454881) (xy 25.986498 -6.419162) (xy 26.032384 -6.389673)
			(xy 26.081998 -6.367014) (xy 26.134333 -6.351646) (xy 26.188322 -6.343883) (xy 26.215594 -6.343396)
			(xy 27.079194 -6.343396) (xy 27.106462 -6.343943) (xy 27.160444 -6.351704) (xy 27.212772 -6.367068)
			(xy 27.26238 -6.389722) (xy 27.308259 -6.419207) (xy 27.349476 -6.45492) (xy 27.38519 -6.496136)
			(xy 27.414675 -6.542015) (xy 27.43733 -6.591623) (xy 27.452695 -6.64395) (xy 27.460457 -6.697932)
			(xy 27.460457 -6.752468) (xy 27.460456 -6.752472) (xy 29.434483 -6.752472) (xy 29.434483 -6.697928)
			(xy 29.442245 -6.643939) (xy 29.457611 -6.591605) (xy 29.480269 -6.54199) (xy 29.509757 -6.496105)
			(xy 29.545476 -6.454883) (xy 29.586697 -6.419163) (xy 29.632581 -6.389674) (xy 29.682196 -6.367015)
			(xy 29.73453 -6.351647) (xy 29.788518 -6.343883) (xy 29.81579 -6.343396) (xy 30.67939 -6.343396)
			(xy 30.706658 -6.343943) (xy 30.76064 -6.351703) (xy 30.812969 -6.367067) (xy 30.862578 -6.389721)
			(xy 30.908457 -6.419205) (xy 30.949674 -6.454919) (xy 30.985389 -6.496135) (xy 31.014874 -6.542014)
			(xy 31.03753 -6.591622) (xy 31.052895 -6.64395) (xy 31.060657 -6.697932) (xy 31.060657 -6.752468)
			(xy 31.060657 -6.75247) (xy 38.544482 -6.75247) (xy 38.544482 -6.69793) (xy 38.552244 -6.643944)
			(xy 38.567608 -6.591613) (xy 38.590264 -6.542) (xy 38.619749 -6.496116) (xy 38.655463 -6.454895)
			(xy 38.696679 -6.419176) (xy 38.74256 -6.389686) (xy 38.792169 -6.367025) (xy 38.844499 -6.351654)
			(xy 38.898484 -6.343886) (xy 38.925754 -6.343396) (xy 39.789354 -6.343396) (xy 39.816624 -6.34394)
			(xy 39.87061 -6.351696) (xy 39.922943 -6.367057) (xy 39.972556 -6.389709) (xy 40.01844 -6.419192)
			(xy 40.059662 -6.454906) (xy 40.09538 -6.496123) (xy 40.124869 -6.542004) (xy 40.147527 -6.591614)
			(xy 40.162894 -6.643945) (xy 40.170656 -6.69793) (xy 40.170656 -6.75247) (xy 40.170656 -6.752472)
			(xy 42.144383 -6.752472) (xy 42.144383 -6.697928) (xy 42.152145 -6.643939) (xy 42.167512 -6.591604)
			(xy 42.19017 -6.541988) (xy 42.219659 -6.496103) (xy 42.255378 -6.454881) (xy 42.296599 -6.419161)
			(xy 42.342485 -6.389672) (xy 42.3921 -6.367013) (xy 42.444435 -6.351646) (xy 42.498424 -6.343883)
			(xy 42.525696 -6.343396) (xy 43.389296 -6.343396) (xy 43.416564 -6.343943) (xy 43.470546 -6.351704)
			(xy 43.522873 -6.367068) (xy 43.572481 -6.389723) (xy 43.61836 -6.419207) (xy 43.659576 -6.454921)
			(xy 43.69529 -6.496136) (xy 43.724775 -6.542015) (xy 43.74743 -6.591623) (xy 43.762795 -6.643951)
			(xy 43.770557 -6.697932) (xy 43.770557 -6.752468) (xy 43.770556 -6.752472) (xy 49.754483 -6.752472)
			(xy 49.754483 -6.697928) (xy 49.762245 -6.643939) (xy 49.777611 -6.591605) (xy 49.800269 -6.54199)
			(xy 49.829757 -6.496105) (xy 49.865476 -6.454883) (xy 49.906697 -6.419163) (xy 49.952581 -6.389674)
			(xy 50.002196 -6.367015) (xy 50.05453 -6.351647) (xy 50.108518 -6.343883) (xy 50.13579 -6.343396)
			(xy 50.99939 -6.343396) (xy 51.026658 -6.343943) (xy 51.08064 -6.351703) (xy 51.132969 -6.367067)
			(xy 51.182578 -6.389721) (xy 51.228457 -6.419205) (xy 51.269674 -6.454919) (xy 51.305389 -6.496135)
			(xy 51.334874 -6.542014) (xy 51.35753 -6.591622) (xy 51.372895 -6.64395) (xy 51.380657 -6.697932)
			(xy 51.380657 -6.752468) (xy 51.380656 -6.752475) (xy 53.35436 -6.752475) (xy 53.35436 -6.697925)
			(xy 53.362124 -6.643929) (xy 53.377493 -6.591588) (xy 53.400155 -6.541967) (xy 53.429649 -6.496077)
			(xy 53.465374 -6.454851) (xy 53.506603 -6.41913) (xy 53.552495 -6.38964) (xy 53.602118 -6.366982)
			(xy 53.65446 -6.351617) (xy 53.708457 -6.343857) (xy 53.735732 -6.343396) (xy 54.599332 -6.343396)
			(xy 54.626597 -6.343969) (xy 54.680571 -6.351733) (xy 54.732891 -6.367099) (xy 54.782492 -6.389755)
			(xy 54.828364 -6.419238) (xy 54.869573 -6.45495) (xy 54.905281 -6.496162) (xy 54.93476 -6.542036)
			(xy 54.957412 -6.591639) (xy 54.972774 -6.64396) (xy 54.980534 -6.697935) (xy 54.980534 -6.752465)
			(xy 54.980533 -6.752471) (xy 56.954382 -6.752471) (xy 56.954382 -6.697929) (xy 56.962144 -6.643942)
			(xy 56.97751 -6.591608) (xy 57.000167 -6.541994) (xy 57.029654 -6.49611) (xy 57.06537 -6.454888)
			(xy 57.106589 -6.419169) (xy 57.152472 -6.389679) (xy 57.202084 -6.367019) (xy 57.254416 -6.35165)
			(xy 57.308403 -6.343884) (xy 57.335674 -6.343396) (xy 58.199274 -6.343396) (xy 58.226543 -6.343942)
			(xy 58.280527 -6.3517) (xy 58.332857 -6.367062) (xy 58.382468 -6.389716) (xy 58.42835 -6.4192) (xy 58.469569 -6.454913)
			(xy 58.505285 -6.496129) (xy 58.534772 -6.542009) (xy 58.557429 -6.591619) (xy 58.564228 -6.614772)
			(xy 70.948992 -6.614772) (xy 70.948992 -6.560228) (xy 70.956754 -6.506238) (xy 70.972121 -6.453903)
			(xy 70.994781 -6.404288) (xy 71.02427 -6.358403) (xy 71.05999 -6.317181) (xy 71.101212 -6.281463)
			(xy 71.147099 -6.251975) (xy 71.196715 -6.229317) (xy 71.24905 -6.213952) (xy 71.30304 -6.206191)
			(xy 71.330312 -6.205728) (xy 72.193912 -6.205728) (xy 72.22118 -6.206235) (xy 72.275161 -6.213998)
			(xy 72.327488 -6.229364) (xy 72.377095 -6.25202) (xy 72.422973 -6.281506) (xy 72.464188 -6.31722)
			(xy 72.499901 -6.358436) (xy 72.529385 -6.404315) (xy 72.55204 -6.453924) (xy 72.567404 -6.506251)
			(xy 72.575166 -6.560232) (xy 72.575166 -6.614768) (xy 72.567404 -6.668749) (xy 72.55204 -6.721076)
			(xy 72.529385 -6.770685) (xy 72.499901 -6.816564) (xy 72.464188 -6.85778) (xy 72.422973 -6.893494)
			(xy 72.377095 -6.92298) (xy 72.327488 -6.945636) (xy 72.275161 -6.961002) (xy 72.22118 -6.968765)
			(xy 72.193912 -6.969252) (xy 71.330312 -6.969252) (xy 71.30304 -6.968809) (xy 71.24905 -6.961048)
			(xy 71.196715 -6.945683) (xy 71.147099 -6.923025) (xy 71.101212 -6.893537) (xy 71.05999 -6.857819)
			(xy 71.02427 -6.816597) (xy 70.994781 -6.770712) (xy 70.972121 -6.721097) (xy 70.956754 -6.668762)
			(xy 70.948992 -6.614772) (xy 58.564228 -6.614772) (xy 58.572795 -6.643948) (xy 58.580557 -6.697931)
			(xy 58.580557 -6.752469) (xy 58.572795 -6.806452) (xy 58.557429 -6.858781) (xy 58.534772 -6.908391)
			(xy 58.505285 -6.954271) (xy 58.469569 -6.995487) (xy 58.42835 -7.0312) (xy 58.382468 -7.060684)
			(xy 58.332857 -7.083338) (xy 58.280527 -7.0987) (xy 58.226543 -7.106458) (xy 58.199274 -7.10692)
			(xy 57.335674 -7.10692) (xy 57.308403 -7.106516) (xy 57.254416 -7.09875) (xy 57.202084 -7.083381)
			(xy 57.152472 -7.060721) (xy 57.106589 -7.031231) (xy 57.06537 -6.995512) (xy 57.029654 -6.95429)
			(xy 57.000167 -6.908406) (xy 56.97751 -6.858792) (xy 56.962144 -6.806458) (xy 56.954382 -6.752471)
			(xy 54.980533 -6.752471) (xy 54.972774 -6.80644) (xy 54.957412 -6.858761) (xy 54.93476 -6.908364)
			(xy 54.905281 -6.954238) (xy 54.869573 -6.99545) (xy 54.828364 -7.031162) (xy 54.782492 -7.060645)
			(xy 54.732891 -7.083301) (xy 54.680571 -7.098667) (xy 54.626597 -7.106431) (xy 54.599332 -7.10692)
			(xy 53.735732 -7.10692) (xy 53.708457 -7.106543) (xy 53.65446 -7.098783) (xy 53.602118 -7.083418)
			(xy 53.552495 -7.06076) (xy 53.506603 -7.03127) (xy 53.465374 -6.995549) (xy 53.429649 -6.954323)
			(xy 53.400155 -6.908433) (xy 53.377493 -6.858812) (xy 53.362124 -6.806471) (xy 53.35436 -6.752475)
			(xy 51.380656 -6.752475) (xy 51.372895 -6.80645) (xy 51.35753 -6.858778) (xy 51.334874 -6.908386)
			(xy 51.305389 -6.954265) (xy 51.269674 -6.995481) (xy 51.228457 -7.031195) (xy 51.182578 -7.060679)
			(xy 51.132969 -7.083333) (xy 51.08064 -7.098697) (xy 51.026658 -7.106457) (xy 50.99939 -7.10692)
			(xy 50.13579 -7.10692) (xy 50.108518 -7.106517) (xy 50.05453 -7.098753) (xy 50.002196 -7.083385)
			(xy 49.952581 -7.060726) (xy 49.906697 -7.031237) (xy 49.865476 -6.995517) (xy 49.829757 -6.954295)
			(xy 49.800269 -6.90841) (xy 49.777611 -6.858795) (xy 49.762245 -6.806461) (xy 49.754483 -6.752472)
			(xy 43.770556 -6.752472) (xy 43.762795 -6.806449) (xy 43.74743 -6.858777) (xy 43.724775 -6.908385)
			(xy 43.69529 -6.954264) (xy 43.659576 -6.995479) (xy 43.61836 -7.031193) (xy 43.572481 -7.060677)
			(xy 43.522873 -7.083332) (xy 43.470546 -7.098696) (xy 43.416564 -7.106457) (xy 43.389296 -7.10692)
			(xy 42.525696 -7.10692) (xy 42.498424 -7.106517) (xy 42.444435 -7.098754) (xy 42.3921 -7.083387)
			(xy 42.342485 -7.060728) (xy 42.296599 -7.031239) (xy 42.255378 -6.995519) (xy 42.219659 -6.954297)
			(xy 42.19017 -6.908412) (xy 42.167512 -6.858796) (xy 42.152145 -6.806461) (xy 42.144383 -6.752472)
			(xy 40.170656 -6.752472) (xy 40.162894 -6.806455) (xy 40.147527 -6.858786) (xy 40.124869 -6.908396)
			(xy 40.09538 -6.954277) (xy 40.059661 -6.995494) (xy 40.01844 -7.031208) (xy 39.972556 -7.060691)
			(xy 39.922943 -7.083343) (xy 39.87061 -7.098704) (xy 39.816624 -7.10646) (xy 39.789354 -7.10692)
			(xy 38.925754 -7.10692) (xy 38.898484 -7.106514) (xy 38.844499 -7.098746) (xy 38.792169 -7.083375)
			(xy 38.74256 -7.060714) (xy 38.696679 -7.031224) (xy 38.655463 -6.995505) (xy 38.619749 -6.954284)
			(xy 38.590264 -6.9084) (xy 38.567608 -6.858787) (xy 38.552244 -6.806456) (xy 38.544482 -6.75247)
			(xy 31.060657 -6.75247) (xy 31.052895 -6.80645) (xy 31.03753 -6.858778) (xy 31.014874 -6.908386)
			(xy 30.985389 -6.954265) (xy 30.949674 -6.995481) (xy 30.908457 -7.031195) (xy 30.862578 -7.060679)
			(xy 30.812969 -7.083333) (xy 30.76064 -7.098697) (xy 30.706658 -7.106457) (xy 30.67939 -7.10692)
			(xy 29.81579 -7.10692) (xy 29.788518 -7.106517) (xy 29.73453 -7.098753) (xy 29.682196 -7.083385)
			(xy 29.632581 -7.060726) (xy 29.586697 -7.031237) (xy 29.545476 -6.995517) (xy 29.509757 -6.954295)
			(xy 29.480269 -6.90841) (xy 29.457611 -6.858795) (xy 29.442245 -6.806461) (xy 29.434483 -6.752472)
			(xy 27.460456 -6.752472) (xy 27.452695 -6.80645) (xy 27.43733 -6.858777) (xy 27.414675 -6.908385)
			(xy 27.38519 -6.954264) (xy 27.349476 -6.99548) (xy 27.308259 -7.031193) (xy 27.26238 -7.060678)
			(xy 27.212772 -7.083332) (xy 27.160444 -7.098696) (xy 27.106462 -7.106457) (xy 27.079194 -7.10692)
			(xy 26.215594 -7.10692) (xy 26.188322 -7.106517) (xy 26.134333 -7.098754) (xy 26.081998 -7.083386)
			(xy 26.032384 -7.060727) (xy 25.986498 -7.031238) (xy 25.945277 -6.995519) (xy 25.909558 -6.954297)
			(xy 25.88007 -6.908411) (xy 25.857412 -6.858796) (xy 25.842045 -6.806461) (xy 25.834283 -6.752472)
			(xy 23.860518 -6.752472) (xy 23.852762 -6.806412) (xy 23.837397 -6.858741) (xy 23.814741 -6.908351)
			(xy 23.785255 -6.954232) (xy 23.749541 -6.995449) (xy 23.708323 -7.031164) (xy 23.662443 -7.06065)
			(xy 23.612833 -7.083306) (xy 23.560504 -7.098672) (xy 23.506521 -7.106433) (xy 23.479252 -7.10692)
			(xy 22.615652 -7.10692) (xy 22.588381 -7.106461) (xy 22.534393 -7.098699) (xy 22.48206 -7.083333)
			(xy 22.432447 -7.060675) (xy 22.386562 -7.031187) (xy 22.345342 -6.99547) (xy 22.309624 -6.954249)
			(xy 22.280136 -6.908365) (xy 22.257478 -6.858752) (xy 22.242112 -6.806419) (xy 22.234349 -6.752431)
			(xy 20.260584 -6.752431) (xy 20.252822 -6.806413) (xy 20.237457 -6.858742) (xy 20.214801 -6.908352)
			(xy 20.185315 -6.954232) (xy 20.1496 -6.99545) (xy 20.108382 -7.031165) (xy 20.062502 -7.060651)
			(xy 20.012892 -7.083307) (xy 19.960563 -7.098672) (xy 19.906579 -7.106434) (xy 19.87931 -7.10692)
			(xy 19.01571 -7.10692) (xy 18.98844 -7.106438) (xy 18.934457 -7.098676) (xy 18.882127 -7.08331) (xy 18.832516 -7.060654)
			(xy 18.786635 -7.031168) (xy 18.745417 -6.995453) (xy 18.709702 -6.954235) (xy 18.680216 -6.908354)
			(xy 18.65756 -6.858743) (xy 18.642194 -6.806413) (xy 18.634432 -6.75243) (xy 13.611098 -6.75243)
			(xy 13.611098 -9.780016) (xy 13.610604 -9.850398) (xy 13.602711 -9.990941) (xy 13.58695 -10.13082)
			(xy 13.563371 -10.269596) (xy 13.532048 -10.406831) (xy 13.493079 -10.542094) (xy 13.446587 -10.674959)
			(xy 13.392719 -10.805008) (xy 13.331643 -10.931832) (xy 13.263553 -11.055033) (xy 13.188662 -11.174221)
			(xy 13.107205 -11.289023) (xy 13.01944 -11.399077) (xy 12.925642 -11.504037) (xy 12.826107 -11.603572)
			(xy 12.721147 -11.69737) (xy 12.611093 -11.785135) (xy 12.496291 -11.866592) (xy 12.377103 -11.941483)
			(xy 12.253902 -12.009573) (xy 12.127078 -12.070649) (xy 11.997029 -12.124517) (xy 11.864164 -12.171009)
			(xy 11.728901 -12.209978) (xy 11.591666 -12.241301) (xy 11.45289 -12.26488) (xy 11.313011 -12.280641)
			(xy 11.172468 -12.288534) (xy 11.102086 -12.289028) (xy 1.999996 -12.289028) (xy 1.944227 -12.289537)
			(xy 1.833 -12.297872) (xy 1.722707 -12.314497) (xy 1.613965 -12.339317) (xy 1.507382 -12.372193)
			(xy 1.403554 -12.412943) (xy 1.353372 -12.43711) (xy 62.309756 -12.43711) (xy 62.310222 -12.396003)
			(xy 62.317806 -12.314139) (xy 62.332909 -12.233324) (xy 62.355404 -12.154247) (xy 62.385098 -12.077583)
			(xy 62.421737 -12.003984) (xy 62.46501 -11.93408) (xy 62.514548 -11.868466) (xy 62.569927 -11.807701)
			(xy 62.630676 -11.752305) (xy 62.696277 -11.70275) (xy 62.766169 -11.659457) (xy 62.839757 -11.622797)
			(xy 62.916414 -11.593082) (xy 62.995485 -11.570566) (xy 63.076295 -11.55544) (xy 63.158157 -11.547833)
			(xy 63.199264 -11.547348) (xy 63.243059 -11.547873) (xy 63.330225 -11.556491) (xy 63.416121 -11.573637)
			(xy 63.499915 -11.599145) (xy 63.580795 -11.632768) (xy 63.619634 -11.653012) (xy 63.6311 -11.65843)
			(xy 63.656428 -11.65843) (xy 63.667894 -11.653012) (xy 63.706738 -11.632781) (xy 63.787623 -11.599174)
			(xy 63.871416 -11.573672) (xy 63.957309 -11.556521) (xy 64.04447 -11.547888) (xy 64.088264 -11.547348)
			(xy 64.132059 -11.547873) (xy 64.219225 -11.556491) (xy 64.305121 -11.573637) (xy 64.388915 -11.599145)
			(xy 64.469795 -11.632768) (xy 64.508634 -11.653012) (xy 64.5201 -11.65843) (xy 64.545428 -11.65843)
			(xy 64.556894 -11.653012) (xy 64.595738 -11.632781) (xy 64.676623 -11.599174) (xy 64.760416 -11.573672)
			(xy 64.846309 -11.556521) (xy 64.93347 -11.547888) (xy 64.977264 -11.547348) (xy 65.021059 -11.547873)
			(xy 65.108225 -11.556491) (xy 65.194121 -11.573637) (xy 65.277915 -11.599145) (xy 65.358795 -11.632768)
			(xy 65.397634 -11.653012) (xy 65.4091 -11.65843) (xy 65.434428 -11.65843) (xy 65.445894 -11.653012)
			(xy 65.484738 -11.632781) (xy 65.565623 -11.599174) (xy 65.649416 -11.573672) (xy 65.735309 -11.556521)
			(xy 65.82247 -11.547888) (xy 65.866264 -11.547348) (xy 65.904554 -11.547763) (xy 65.980848 -11.554368)
			(xy 66.05629 -11.567515) (xy 66.130321 -11.587105) (xy 66.166492 -11.599672) (xy 66.174929 -11.602323)
			(xy 66.192599 -11.602323) (xy 66.201036 -11.599672) (xy 66.237216 -11.587135) (xy 66.311248 -11.56756)
			(xy 66.386687 -11.554411) (xy 66.462976 -11.547785) (xy 66.501264 -11.547348) (xy 66.54268 -11.547848)
			(xy 66.625149 -11.555593) (xy 66.706543 -11.570964) (xy 66.786158 -11.593827) (xy 66.863305 -11.623986)
			(xy 66.937318 -11.661178) (xy 66.972688 -11.68273) (xy 66.980074 -11.686987) (xy 66.996689 -11.690769)
			(xy 67.013625 -11.688896) (xy 67.021456 -11.685524) (xy 67.057233 -11.668994) (xy 67.131154 -11.641645)
			(xy 67.207206 -11.620946) (xy 67.284791 -11.607058) (xy 67.363301 -11.600092) (xy 67.40271 -11.599672)
			(xy 67.443826 -11.600089) (xy 67.525707 -11.607677) (xy 67.606539 -11.622789) (xy 67.685632 -11.645294)
			(xy 67.76231 -11.675001) (xy 67.835921 -11.711656) (xy 67.905835 -11.754947) (xy 67.971457 -11.804505)
			(xy 68.032226 -11.859906) (xy 68.087623 -11.920677) (xy 68.137178 -11.986301) (xy 68.180465 -12.056218)
			(xy 68.217117 -12.12983) (xy 68.24682 -12.20651) (xy 68.269321 -12.285604) (xy 68.284429 -12.366436)
			(xy 68.292013 -12.448318) (xy 68.292472 -12.489434) (xy 68.291907 -12.533047) (xy 68.283357 -12.619854)
			(xy 68.266352 -12.705408) (xy 68.241056 -12.788886) (xy 68.207711 -12.869488) (xy 68.195659 -12.892068)
			(xy 70.948547 -12.892068) (xy 70.948547 -12.837532) (xy 70.956309 -12.783551) (xy 70.971673 -12.731225)
			(xy 70.994328 -12.681617) (xy 71.023813 -12.635739) (xy 71.059526 -12.594524) (xy 71.100742 -12.558811)
			(xy 71.146621 -12.529327) (xy 71.196228 -12.506672) (xy 71.248555 -12.491308) (xy 71.302536 -12.483547)
			(xy 71.329804 -12.483084) (xy 72.193404 -12.483084) (xy 72.220676 -12.483479) (xy 72.274666 -12.491242)
			(xy 72.327001 -12.506609) (xy 72.376617 -12.529269) (xy 72.422503 -12.558758) (xy 72.463725 -12.594478)
			(xy 72.499444 -12.6357) (xy 72.528933 -12.681586) (xy 72.551592 -12.731202) (xy 72.566959 -12.783538)
			(xy 72.574721 -12.837528) (xy 72.574721 -12.892072) (xy 72.566959 -12.946062) (xy 72.551592 -12.998398)
			(xy 72.528933 -13.048014) (xy 72.499444 -13.0939) (xy 72.488173 -13.106908) (xy 191.037972 -13.106908)
			(xy 191.03849 -13.065179) (xy 191.046314 -12.98209) (xy 191.061883 -12.900098) (xy 191.085062 -12.819924)
			(xy 191.115646 -12.742273) (xy 191.153367 -12.667827) (xy 191.197893 -12.59724) (xy 191.248833 -12.531132)
			(xy 191.305739 -12.470085) (xy 191.368112 -12.414635) (xy 191.435403 -12.365269) (xy 191.507021 -12.32242)
			(xy 191.582336 -12.286466) (xy 191.660687 -12.257723) (xy 191.700912 -12.24661) (xy 191.713612 -12.243308)
			(xy 191.732408 -12.225274) (xy 191.765936 -12.117578) (xy 191.760348 -12.091924) (xy 191.751712 -12.082018)
			(xy 191.723476 -12.048682) (xy 191.672486 -11.977736) (xy 191.628113 -11.902474) (xy 191.590718 -11.823512)
			(xy 191.560607 -11.741496) (xy 191.538028 -11.657095) (xy 191.523163 -11.571) (xy 191.516135 -11.483915)
			(xy 191.517001 -11.39655) (xy 191.525753 -11.309621) (xy 191.542322 -11.223837) (xy 191.56657 -11.139901)
			(xy 191.5983 -11.058497) (xy 191.637253 -10.980292) (xy 191.683109 -10.905925) (xy 191.735495 -10.836003)
			(xy 191.793982 -10.771099) (xy 191.858092 -10.711742) (xy 191.927301 -10.658417) (xy 192.001043 -10.611562)
			(xy 192.078715 -10.571558) (xy 192.159684 -10.538733) (xy 192.243285 -10.513355) (xy 192.328838 -10.495631)
			(xy 192.415641 -10.485707) (xy 192.502986 -10.483662) (xy 192.590159 -10.489515) (xy 192.676446 -10.503218)
			(xy 192.761144 -10.524657) (xy 192.843559 -10.553659) (xy 192.923018 -10.589985) (xy 192.998871 -10.63334)
			(xy 193.070499 -10.683368) (xy 193.137315 -10.739661) (xy 193.198774 -10.801758) (xy 193.254374 -10.869153)
			(xy 193.303659 -10.941294) (xy 193.346227 -11.017591) (xy 193.381731 -11.097421) (xy 193.409879 -11.180131)
			(xy 193.430442 -11.265046) (xy 193.443252 -11.35147) (xy 193.448204 -11.438699) (xy 193.445257 -11.526018)
			(xy 193.434436 -11.612714) (xy 193.415829 -11.698079) (xy 193.389589 -11.781414) (xy 193.355929 -11.862038)
			(xy 193.315124 -11.939293) (xy 193.267509 -12.012547) (xy 193.213473 -12.081201) (xy 193.153457 -12.144694)
			(xy 193.121026 -12.173966) (xy 193.112347 -12.182457) (xy 193.103466 -12.205016) (xy 193.104008 -12.217146)
			(xy 193.112136 -12.298934) (xy 193.113935 -12.310868) (xy 193.126948 -12.331156) (xy 193.137028 -12.337796)
			(xy 193.137282 -12.33805) (xy 193.173525 -12.359702) (xy 193.242152 -12.408882) (xy 193.305811 -12.464344)
			(xy 193.363928 -12.525589) (xy 193.415979 -12.592065) (xy 193.461498 -12.663174) (xy 193.500073 -12.738277)
			(xy 193.531358 -12.816697) (xy 193.555071 -12.897729) (xy 193.570999 -12.980643) (xy 193.578999 -13.064693)
			(xy 193.579496 -13.106908) (xy 193.579055 -13.148019) (xy 193.571467 -13.22989) (xy 193.556355 -13.310712)
			(xy 193.533849 -13.389794) (xy 193.504141 -13.466462) (xy 193.467484 -13.540061) (xy 193.424192 -13.609963)
			(xy 193.374634 -13.675571) (xy 193.319232 -13.736326) (xy 193.25846 -13.791709) (xy 193.192836 -13.841247)
			(xy 193.122921 -13.884518) (xy 193.049311 -13.921151) (xy 192.972634 -13.950836) (xy 192.893545 -13.973317)
			(xy 192.812719 -13.988404) (xy 192.730845 -13.995968) (xy 192.689734 -13.996416) (xy 192.643339 -13.99582)
			(xy 192.551051 -13.986179) (xy 192.460267 -13.966987) (xy 192.371973 -13.938452) (xy 192.329308 -13.920216)
			(xy 192.319366 -13.91641) (xy 192.298102 -13.91641) (xy 192.28816 -13.920216) (xy 192.245553 -13.938427)
			(xy 192.157387 -13.966948) (xy 192.066733 -13.986143) (xy 191.974574 -13.995806) (xy 191.928242 -13.996416)
			(xy 191.927734 -13.996416) (xy 191.886626 -13.995955) (xy 191.804762 -13.988373) (xy 191.723946 -13.973271)
			(xy 191.644867 -13.950778) (xy 191.568202 -13.921085) (xy 191.494602 -13.884445) (xy 191.424697 -13.841172)
			(xy 191.359082 -13.791634) (xy 191.298317 -13.736254) (xy 191.24292 -13.675504) (xy 191.193365 -13.609903)
			(xy 191.150073 -13.540009) (xy 191.113413 -13.46642) (xy 191.083699 -13.389762) (xy 191.061184 -13.31069)
			(xy 191.04606 -13.229878) (xy 191.038456 -13.148015) (xy 191.037972 -13.106908) (xy 72.488173 -13.106908)
			(xy 72.463725 -13.135122) (xy 72.422503 -13.170842) (xy 72.376617 -13.200331) (xy 72.327001 -13.222991)
			(xy 72.274666 -13.238358) (xy 72.220676 -13.246121) (xy 72.193404 -13.246608) (xy 71.329804 -13.246608)
			(xy 71.302536 -13.246053) (xy 71.248555 -13.238292) (xy 71.196228 -13.222928) (xy 71.146621 -13.200273)
			(xy 71.100742 -13.170789) (xy 71.059526 -13.135076) (xy 71.023813 -13.093861) (xy 70.994328 -13.047983)
			(xy 70.971673 -12.998375) (xy 70.956309 -12.946049) (xy 70.948547 -12.892068) (xy 68.195659 -12.892068)
			(xy 68.166638 -12.946439) (xy 68.118231 -13.019001) (xy 68.062955 -13.086478) (xy 68.00134 -13.14822)
			(xy 67.933978 -13.203636) (xy 67.861516 -13.252193) (xy 67.823334 -13.273278) (xy 67.814055 -13.278811)
			(xy 67.800889 -13.295908) (xy 67.797934 -13.306298) (xy 67.787525 -13.3474) (xy 67.759881 -13.427561)
			(xy 67.724737 -13.504728) (xy 67.682409 -13.578201) (xy 67.633283 -13.647314) (xy 67.577804 -13.711439)
			(xy 67.516475 -13.769995) (xy 67.449854 -13.82245) (xy 67.378544 -13.868328) (xy 67.303192 -13.907213)
			(xy 67.224482 -13.938753) (xy 67.143129 -13.96266) (xy 67.05987 -13.978719) (xy 66.975461 -13.986784)
			(xy 66.933064 -13.987272) (xy 66.894775 -13.986847) (xy 66.818481 -13.980245) (xy 66.743038 -13.967101)
			(xy 66.669007 -13.947513) (xy 66.632836 -13.934948) (xy 66.624399 -13.932297) (xy 66.606729 -13.932297)
			(xy 66.598292 -13.934948) (xy 66.56211 -13.947478) (xy 66.488079 -13.967055) (xy 66.41264 -13.980205)
			(xy 66.336352 -13.986834) (xy 66.298064 -13.987272) (xy 66.254269 -13.986733) (xy 66.167104 -13.978118)
			(xy 66.081208 -13.960975) (xy 65.997414 -13.93547) (xy 65.916534 -13.90185) (xy 65.877694 -13.881608)
			(xy 65.866228 -13.87619) (xy 65.8409 -13.87619) (xy 65.829434 -13.881608) (xy 65.790581 -13.901822)
			(xy 65.709699 -13.935433) (xy 65.625908 -13.96094) (xy 65.540018 -13.978094) (xy 65.452857 -13.986731)
			(xy 65.409064 -13.987272) (xy 65.365269 -13.986733) (xy 65.278104 -13.978118) (xy 65.192208 -13.960975)
			(xy 65.108414 -13.93547) (xy 65.027534 -13.90185) (xy 64.988694 -13.881608) (xy 64.977228 -13.87619)
			(xy 64.9519 -13.87619) (xy 64.940434 -13.881608) (xy 64.901581 -13.901822) (xy 64.820699 -13.935433)
			(xy 64.736908 -13.96094) (xy 64.651018 -13.978094) (xy 64.563857 -13.986731) (xy 64.520064 -13.987272)
			(xy 64.476269 -13.986733) (xy 64.389104 -13.978118) (xy 64.303208 -13.960975) (xy 64.219414 -13.93547)
			(xy 64.138534 -13.90185) (xy 64.099694 -13.881608) (xy 64.088228 -13.87619) (xy 64.0629 -13.87619)
			(xy 64.051434 -13.881608) (xy 64.012581 -13.901822) (xy 63.931699 -13.935433) (xy 63.847908 -13.96094)
			(xy 63.762018 -13.978094) (xy 63.674857 -13.986731) (xy 63.631064 -13.987272) (xy 63.588804 -13.98679)
			(xy 63.504665 -13.978779) (xy 63.421665 -13.962822) (xy 63.340553 -13.939064) (xy 63.26206 -13.907718)
			(xy 63.186895 -13.869068) (xy 63.115735 -13.823463) (xy 63.049222 -13.771312) (xy 62.987956 -13.713088)
			(xy 62.93249 -13.649314) (xy 62.883323 -13.580566) (xy 62.840899 -13.507464) (xy 62.805601 -13.430668)
			(xy 62.777747 -13.35087) (xy 62.757589 -13.268789) (xy 62.750954 -13.22705) (xy 62.748768 -13.216225)
			(xy 62.736658 -13.197787) (xy 62.727586 -13.19149) (xy 62.693115 -13.169417) (xy 62.628004 -13.119803)
			(xy 62.567725 -13.064419) (xy 62.512788 -13.003732) (xy 62.463657 -12.938255) (xy 62.420747 -12.868543)
			(xy 62.384422 -12.795185) (xy 62.354987 -12.7188) (xy 62.332693 -12.640034) (xy 62.317728 -12.559554)
			(xy 62.310218 -12.47804) (xy 62.309756 -12.43711) (xy 1.353372 -12.43711) (xy 1.303061 -12.461339)
			(xy 1.206466 -12.517108) (xy 1.114309 -12.579941) (xy 1.027105 -12.649484) (xy 0.945341 -12.72535)
			(xy 0.869476 -12.807114) (xy 0.801731 -12.892064) (xy 56.95347 -12.892064) (xy 56.95347 -12.837536)
			(xy 56.96123 -12.783562) (xy 56.976591 -12.731243) (xy 56.999242 -12.681641) (xy 57.02872 -12.635768)
			(xy 57.064426 -12.594556) (xy 57.105634 -12.558845) (xy 57.151504 -12.529362) (xy 57.201103 -12.506706)
			(xy 57.253421 -12.491339) (xy 57.307394 -12.483573) (xy 57.334658 -12.483084) (xy 58.198258 -12.483084)
			(xy 58.225534 -12.483453) (xy 58.279532 -12.491211) (xy 58.331876 -12.506575) (xy 58.381501 -12.529233)
			(xy 58.427395 -12.558723) (xy 58.468625 -12.594445) (xy 58.504351 -12.635671) (xy 58.533847 -12.681562)
			(xy 58.55651 -12.731184) (xy 58.57188 -12.783527) (xy 58.579644 -12.837524) (xy 58.579644 -12.892076)
			(xy 58.57188 -12.946073) (xy 58.55651 -12.998416) (xy 58.533847 -13.048037) (xy 58.504351 -13.093929)
			(xy 58.468625 -13.135155) (xy 58.427395 -13.170877) (xy 58.381501 -13.200367) (xy 58.331876 -13.223025)
			(xy 58.279532 -13.238389) (xy 58.225534 -13.246147) (xy 58.198258 -13.246608) (xy 57.334658 -13.246608)
			(xy 57.307394 -13.246027) (xy 57.253421 -13.238261) (xy 57.201103 -13.222894) (xy 57.151504 -13.200238)
			(xy 57.105634 -13.170755) (xy 57.064426 -13.135044) (xy 57.02872 -13.093832) (xy 56.999242 -13.047959)
			(xy 56.976591 -12.998357) (xy 56.96123 -12.946038) (xy 56.95347 -12.892064) (xy 0.801731 -12.892064)
			(xy 0.799933 -12.894318) (xy 0.737102 -12.986476) (xy 0.681333 -13.083072) (xy 0.632939 -13.183565)
			(xy 0.59219 -13.287393) (xy 0.559313 -13.393977) (xy 0.534494 -13.502719) (xy 0.517871 -13.613012)
			(xy 0.509536 -13.724239) (xy 0.509016 -13.780008) (xy 0.509016 -16.5207) (xy 76.28834 -16.5207) (xy 76.29237 -16.436094)
			(xy 76.304425 -16.352254) (xy 76.324394 -16.26994) (xy 76.352098 -16.189896) (xy 76.387284 -16.112849)
			(xy 76.429635 -16.039495) (xy 76.478768 -15.970499) (xy 76.534236 -15.906485) (xy 76.595538 -15.848035)
			(xy 76.662118 -15.795676) (xy 76.733375 -15.749883) (xy 76.808661 -15.711071) (xy 76.887296 -15.679591)
			(xy 76.968567 -15.655728) (xy 77.051738 -15.639698) (xy 77.136057 -15.631648) (xy 77.178408 -15.63116)
			(xy 77.178916 -15.63116) (xy 77.224101 -15.631724) (xy 77.314005 -15.640873) (xy 77.402518 -15.659097)
			(xy 77.488725 -15.686205) (xy 77.530452 -15.70355) (xy 77.539034 -15.706862) (xy 77.557395 -15.707764)
			(xy 77.566266 -15.705328) (xy 77.610936 -15.69133) (xy 77.702468 -15.671687) (xy 77.795557 -15.661772)
			(xy 77.842364 -15.661132) (xy 77.84338 -15.661132) (xy 77.885732 -15.661539) (xy 77.970052 -15.669589)
			(xy 78.053225 -15.685618) (xy 78.134498 -15.70948) (xy 78.213134 -15.74096) (xy 78.288422 -15.779772)
			(xy 78.35968 -15.825565) (xy 78.426262 -15.877924) (xy 78.487566 -15.936376) (xy 78.543035 -16.00039)
			(xy 78.592169 -16.069387) (xy 78.634521 -16.142742) (xy 78.669709 -16.219791) (xy 78.697413 -16.299835)
			(xy 78.717383 -16.382151) (xy 78.722326 -16.416528) (xy 191.571372 -16.416528) (xy 191.571784 -16.378238)
			(xy 191.57839 -16.301944) (xy 191.591537 -16.226502) (xy 191.611129 -16.152471) (xy 191.623696 -16.1163)
			(xy 191.626331 -16.10786) (xy 191.62634 -16.090193) (xy 191.623696 -16.081756) (xy 191.611158 -16.045577)
			(xy 191.591583 -15.971544) (xy 191.578434 -15.896105) (xy 191.571809 -15.819816) (xy 191.571372 -15.781528)
			(xy 191.571879 -15.740418) (xy 191.579464 -15.65855) (xy 191.594572 -15.577731) (xy 191.617074 -15.498651)
			(xy 191.646778 -15.421985) (xy 191.68343 -15.348387) (xy 191.726718 -15.278486) (xy 191.776272 -15.212878)
			(xy 191.831669 -15.152124) (xy 191.892437 -15.096741) (xy 191.958056 -15.047202) (xy 192.027967 -15.00393)
			(xy 192.101573 -14.967295) (xy 192.178246 -14.937609) (xy 192.257331 -14.915125) (xy 192.338154 -14.900036)
			(xy 192.420024 -14.89247) (xy 192.461134 -14.89202) (xy 192.499451 -14.892376) (xy 192.575804 -14.898912)
			(xy 192.651311 -14.912) (xy 192.72541 -14.931543) (xy 192.761616 -14.94409) (xy 192.769932 -14.946676)
			(xy 192.787336 -14.946676) (xy 192.795652 -14.94409) (xy 192.831863 -14.931562) (xy 192.905965 -14.912041)
			(xy 192.981469 -14.898959) (xy 193.057819 -14.892413) (xy 193.096134 -14.89202) (xy 193.134451 -14.892376)
			(xy 193.210804 -14.898912) (xy 193.286311 -14.912) (xy 193.36041 -14.931543) (xy 193.396616 -14.94409)
			(xy 193.404932 -14.946676) (xy 193.422336 -14.946676) (xy 193.430652 -14.94409) (xy 193.466772 -14.93159)
			(xy 193.540685 -14.912102) (xy 193.615997 -14.899021) (xy 193.692153 -14.892442) (xy 193.730372 -14.89202)
			(xy 193.731134 -14.89202) (xy 193.772241 -14.89248) (xy 193.854104 -14.900067) (xy 193.934917 -14.915174)
			(xy 194.013993 -14.937671) (xy 194.090656 -14.967367) (xy 194.164253 -15.004008) (xy 194.234156 -15.047282)
			(xy 194.299769 -15.09682) (xy 194.360532 -15.152199) (xy 194.415928 -15.212948) (xy 194.465484 -15.278547)
			(xy 194.508776 -15.348439) (xy 194.545437 -15.422026) (xy 194.575153 -15.498681) (xy 194.597672 -15.577751)
			(xy 194.6128 -15.658561) (xy 194.620409 -15.740421) (xy 194.620896 -15.781528) (xy 194.620451 -15.819809)
			(xy 194.613795 -15.896082) (xy 194.600605 -15.971499) (xy 194.591178 -16.008604) (xy 194.588893 -16.019174)
			(xy 194.592456 -16.040487) (xy 194.598036 -16.049752) (xy 194.621836 -16.08633) (xy 194.662956 -16.163308)
			(xy 194.696348 -16.24394) (xy 194.721691 -16.327453) (xy 194.738741 -16.413043) (xy 194.747336 -16.499892)
			(xy 194.747896 -16.543528) (xy 194.747474 -16.584639) (xy 194.739884 -16.666511) (xy 194.72477 -16.747333)
			(xy 194.702263 -16.826416) (xy 194.672553 -16.903083) (xy 194.635895 -16.976682) (xy 194.592602 -17.046584)
			(xy 194.543042 -17.112192) (xy 194.487639 -17.172947) (xy 194.426866 -17.22833) (xy 194.361241 -17.277868)
			(xy 194.291325 -17.321138) (xy 194.217714 -17.357772) (xy 194.141037 -17.387456) (xy 194.061947 -17.409938)
			(xy 193.98112 -17.425024) (xy 193.899246 -17.432588) (xy 193.858134 -17.433036) (xy 193.814503 -17.432505)
			(xy 193.727659 -17.42397) (xy 193.642069 -17.40697) (xy 193.558556 -17.381667) (xy 193.477923 -17.348306)
			(xy 193.400945 -17.307207) (xy 193.364358 -17.28343) (xy 193.355108 -17.277824) (xy 193.333785 -17.274289)
			(xy 193.32321 -17.276572) (xy 193.286097 -17.285942) (xy 193.210677 -17.299046) (xy 193.134409 -17.305624)
			(xy 193.096134 -17.306036) (xy 193.057818 -17.305656) (xy 192.981465 -17.299127) (xy 192.905958 -17.286046)
			(xy 192.831859 -17.26651) (xy 192.795652 -17.253966) (xy 192.787336 -17.25138) (xy 192.769932 -17.25138)
			(xy 192.761616 -17.253966) (xy 192.725489 -17.266445) (xy 192.651578 -17.285939) (xy 192.576269 -17.299026)
			(xy 192.500115 -17.305611) (xy 192.461896 -17.306036) (xy 192.461134 -17.306036) (xy 192.420027 -17.305555)
			(xy 192.338163 -17.297973) (xy 192.257348 -17.282872) (xy 192.178271 -17.260379) (xy 192.101606 -17.230687)
			(xy 192.028008 -17.194048) (xy 191.958103 -17.150776) (xy 191.892489 -17.10124) (xy 191.831724 -17.045861)
			(xy 191.776328 -16.985113) (xy 191.726772 -16.919513) (xy 191.683479 -16.849621) (xy 191.646819 -16.776033)
			(xy 191.617104 -16.699377) (xy 191.594588 -16.620307) (xy 191.579463 -16.539496) (xy 191.571857 -16.457635)
			(xy 191.571372 -16.416528) (xy 78.722326 -16.416528) (xy 78.729438 -16.465992) (xy 78.733468 -16.5506)
			(xy 78.729438 -16.635208) (xy 78.717383 -16.719049) (xy 78.697413 -16.801365) (xy 78.669709 -16.881409)
			(xy 78.634521 -16.958458) (xy 78.592169 -17.031813) (xy 78.543035 -17.10081) (xy 78.487566 -17.164824)
			(xy 78.426262 -17.223276) (xy 78.35968 -17.275635) (xy 78.288422 -17.321428) (xy 78.213134 -17.36024)
			(xy 78.134498 -17.39172) (xy 78.053225 -17.415582) (xy 77.970052 -17.431611) (xy 77.885732 -17.439661)
			(xy 77.84338 -17.440148) (xy 77.842872 -17.440148) (xy 77.797687 -17.439588) (xy 77.707782 -17.430437)
			(xy 77.61927 -17.412213) (xy 77.533063 -17.385103) (xy 77.491336 -17.367758) (xy 77.482756 -17.36444)
			(xy 77.464393 -17.363542) (xy 77.455522 -17.36598) (xy 77.410853 -17.379982) (xy 77.319321 -17.399623)
			(xy 77.226231 -17.409537) (xy 77.179424 -17.410176) (xy 77.178408 -17.410176) (xy 77.136057 -17.409752)
			(xy 77.051738 -17.401702) (xy 76.968567 -17.385672) (xy 76.887296 -17.361809) (xy 76.808661 -17.330329)
			(xy 76.733375 -17.291517) (xy 76.662118 -17.245724) (xy 76.595538 -17.193365) (xy 76.534236 -17.134915)
			(xy 76.478768 -17.070901) (xy 76.429635 -17.001905) (xy 76.387284 -16.928551) (xy 76.352098 -16.851504)
			(xy 76.324394 -16.77146) (xy 76.304425 -16.689146) (xy 76.29237 -16.605306) (xy 76.28834 -16.5207)
			(xy 0.509016 -16.5207) (xy 0.509016 -17.639611) (xy 15.152858 -17.639611) (xy 15.152858 -17.585109)
			(xy 15.160614 -17.531161) (xy 15.175969 -17.478867) (xy 15.19861 -17.42929) (xy 15.228076 -17.383439)
			(xy 15.263768 -17.342249) (xy 15.304958 -17.306558) (xy 15.350808 -17.277091) (xy 15.400385 -17.25445)
			(xy 15.452679 -17.239095) (xy 15.506627 -17.231338) (xy 15.533878 -17.230852) (xy 16.397478 -17.230852)
			(xy 16.424731 -17.231315) (xy 16.478682 -17.239072) (xy 16.53098 -17.254428) (xy 16.580561 -17.27707)
			(xy 16.626414 -17.306538) (xy 16.667607 -17.342232) (xy 16.703301 -17.383424) (xy 16.732769 -17.429278)
			(xy 16.755412 -17.478858) (xy 16.770768 -17.531156) (xy 16.778525 -17.585107) (xy 16.778525 -17.639611)
			(xy 20.740858 -17.639611) (xy 20.740858 -17.585109) (xy 20.748614 -17.531161) (xy 20.763969 -17.478867)
			(xy 20.78661 -17.42929) (xy 20.816076 -17.383439) (xy 20.851768 -17.342249) (xy 20.892958 -17.306558)
			(xy 20.938808 -17.277091) (xy 20.988385 -17.25445) (xy 21.040679 -17.239095) (xy 21.094627 -17.231338)
			(xy 21.121878 -17.230852) (xy 21.985478 -17.230852) (xy 22.012729 -17.231394) (xy 22.066677 -17.239147)
			(xy 22.118972 -17.2545) (xy 22.168549 -17.277139) (xy 22.2144 -17.306603) (xy 22.255591 -17.342293)
			(xy 22.291284 -17.383482) (xy 22.320751 -17.429331) (xy 22.343392 -17.478908) (xy 22.358748 -17.531202)
			(xy 22.366505 -17.585149) (xy 22.366505 -17.639651) (xy 22.366505 -17.639653) (xy 26.328838 -17.639653)
			(xy 26.328838 -17.585147) (xy 26.336595 -17.531195) (xy 26.35195 -17.478897) (xy 26.374592 -17.429316)
			(xy 26.404059 -17.383462) (xy 26.439752 -17.342268) (xy 26.480944 -17.306573) (xy 26.526797 -17.277103)
			(xy 26.576376 -17.254458) (xy 26.628674 -17.239099) (xy 26.682625 -17.231339) (xy 26.709878 -17.230852)
			(xy 27.573478 -17.230852) (xy 27.600729 -17.231394) (xy 27.654677 -17.239147) (xy 27.706972 -17.2545)
			(xy 27.756549 -17.277139) (xy 27.8024 -17.306603) (xy 27.843591 -17.342293) (xy 27.879284 -17.383482)
			(xy 27.908751 -17.429331) (xy 27.931392 -17.478908) (xy 27.946748 -17.531202) (xy 27.954505 -17.585149)
			(xy 27.954505 -17.639651) (xy 27.954402 -17.640366) (xy 31.915646 -17.640366) (xy 31.915646 -17.585834)
			(xy 31.923406 -17.531857) (xy 31.938769 -17.479533) (xy 31.961421 -17.429928) (xy 31.990902 -17.384052)
			(xy 32.026611 -17.342838) (xy 32.067822 -17.307125) (xy 32.113695 -17.277639) (xy 32.163298 -17.254982)
			(xy 32.21562 -17.239615) (xy 32.269596 -17.231849) (xy 32.296862 -17.23136) (xy 33.160462 -17.23136)
			(xy 33.187736 -17.231777) (xy 33.24173 -17.239535) (xy 33.294071 -17.254899) (xy 33.343691 -17.277556)
			(xy 33.389583 -17.307044) (xy 33.43081 -17.342764) (xy 33.466533 -17.383987) (xy 33.496026 -17.429875)
			(xy 33.518688 -17.479494) (xy 33.534057 -17.531832) (xy 33.54182 -17.585826) (xy 33.54182 -17.640366)
			(xy 37.503646 -17.640366) (xy 37.503646 -17.585834) (xy 37.511406 -17.531857) (xy 37.526769 -17.479533)
			(xy 37.549421 -17.429928) (xy 37.578902 -17.384052) (xy 37.614611 -17.342838) (xy 37.655822 -17.307125)
			(xy 37.701695 -17.277639) (xy 37.751298 -17.254982) (xy 37.80362 -17.239615) (xy 37.857596 -17.231849)
			(xy 37.884862 -17.23136) (xy 38.748462 -17.23136) (xy 38.775736 -17.231777) (xy 38.82973 -17.239535)
			(xy 38.882071 -17.254899) (xy 38.931691 -17.277556) (xy 38.977583 -17.307044) (xy 39.01881 -17.342764)
			(xy 39.054533 -17.383987) (xy 39.084026 -17.429875) (xy 39.106688 -17.479494) (xy 39.122057 -17.531832)
			(xy 39.12982 -17.585826) (xy 39.12982 -17.639654) (xy 43.398638 -17.639654) (xy 43.398638 -17.585146)
			(xy 43.406395 -17.531193) (xy 43.421751 -17.478894) (xy 43.444395 -17.429312) (xy 43.473863 -17.383457)
			(xy 43.509558 -17.342262) (xy 43.550752 -17.306567) (xy 43.596606 -17.277097) (xy 43.646188 -17.254454)
			(xy 43.698487 -17.239096) (xy 43.75244 -17.231338) (xy 43.779694 -17.230852) (xy 44.643294 -17.230852)
			(xy 44.670544 -17.231395) (xy 44.72449 -17.23915) (xy 44.776783 -17.254504) (xy 44.826359 -17.277144)
			(xy 44.872208 -17.306609) (xy 44.913397 -17.342299) (xy 44.949088 -17.383487) (xy 44.978553 -17.429336)
			(xy 45.001194 -17.478911) (xy 45.016548 -17.531204) (xy 45.024305 -17.58515) (xy 45.024305 -17.63965)
			(xy 45.024304 -17.639654) (xy 48.986638 -17.639654) (xy 48.986638 -17.585146) (xy 48.994395 -17.531193)
			(xy 49.009751 -17.478894) (xy 49.032395 -17.429312) (xy 49.061863 -17.383457) (xy 49.097558 -17.342262)
			(xy 49.138752 -17.306567) (xy 49.184606 -17.277097) (xy 49.234188 -17.254454) (xy 49.286487 -17.239096)
			(xy 49.34044 -17.231338) (xy 49.367694 -17.230852) (xy 50.231294 -17.230852) (xy 50.258544 -17.231395)
			(xy 50.31249 -17.23915) (xy 50.364783 -17.254504) (xy 50.414359 -17.277144) (xy 50.460208 -17.306609)
			(xy 50.501397 -17.342299) (xy 50.537088 -17.383487) (xy 50.566553 -17.429336) (xy 50.589194 -17.478911)
			(xy 50.604548 -17.531204) (xy 50.612305 -17.58515) (xy 50.612305 -17.63965) (xy 50.612201 -17.64037)
			(xy 54.607423 -17.64037) (xy 54.607423 -17.58583) (xy 54.615186 -17.531845) (xy 54.630552 -17.479514)
			(xy 54.653209 -17.429903) (xy 54.682696 -17.384021) (xy 54.718413 -17.342803) (xy 54.759632 -17.307088)
			(xy 54.805515 -17.277602) (xy 54.855127 -17.254947) (xy 54.907459 -17.239583) (xy 54.961444 -17.231822)
			(xy 54.988714 -17.23136) (xy 55.852314 -17.23136) (xy 55.879584 -17.231803) (xy 55.933569 -17.239567)
			(xy 55.9859 -17.254935) (xy 56.035512 -17.277593) (xy 56.081393 -17.307081) (xy 56.122612 -17.342798)
			(xy 56.158328 -17.384018) (xy 56.187814 -17.429901) (xy 56.21047 -17.479513) (xy 56.225836 -17.531844)
			(xy 56.233598 -17.58583) (xy 56.233598 -17.64037) (xy 56.225836 -17.694356) (xy 56.21047 -17.746687)
			(xy 56.187814 -17.796299) (xy 56.158328 -17.842182) (xy 56.122612 -17.883402) (xy 56.081393 -17.919119)
			(xy 56.035512 -17.948607) (xy 55.9859 -17.971265) (xy 55.933569 -17.986633) (xy 55.879584 -17.994397)
			(xy 55.852314 -17.994884) (xy 54.988714 -17.994884) (xy 54.961444 -17.994378) (xy 54.907459 -17.986617)
			(xy 54.855127 -17.971253) (xy 54.805515 -17.948598) (xy 54.759632 -17.919112) (xy 54.718413 -17.883397)
			(xy 54.682696 -17.842179) (xy 54.653209 -17.796297) (xy 54.630552 -17.746686) (xy 54.615186 -17.694355)
			(xy 54.607423 -17.64037) (xy 50.612201 -17.64037) (xy 50.604548 -17.693596) (xy 50.589194 -17.745889)
			(xy 50.566553 -17.795464) (xy 50.537088 -17.841313) (xy 50.501397 -17.882501) (xy 50.460208 -17.918191)
			(xy 50.414359 -17.947656) (xy 50.364783 -17.970296) (xy 50.31249 -17.98565) (xy 50.258544 -17.993405)
			(xy 50.231294 -17.993868) (xy 49.367694 -17.993868) (xy 49.34044 -17.993462) (xy 49.286487 -17.985704)
			(xy 49.234188 -17.970346) (xy 49.184606 -17.947703) (xy 49.138752 -17.918233) (xy 49.097558 -17.882538)
			(xy 49.061863 -17.841343) (xy 49.032395 -17.795488) (xy 49.009751 -17.745906) (xy 48.994395 -17.693607)
			(xy 48.986638 -17.639654) (xy 45.024304 -17.639654) (xy 45.016548 -17.693596) (xy 45.001194 -17.745889)
			(xy 44.978553 -17.795464) (xy 44.949088 -17.841313) (xy 44.913397 -17.882501) (xy 44.872208 -17.918191)
			(xy 44.826359 -17.947656) (xy 44.776783 -17.970296) (xy 44.72449 -17.98565) (xy 44.670544 -17.993405)
			(xy 44.643294 -17.993868) (xy 43.779694 -17.993868) (xy 43.75244 -17.993462) (xy 43.698487 -17.985704)
			(xy 43.646188 -17.970346) (xy 43.596606 -17.947703) (xy 43.550752 -17.918233) (xy 43.509558 -17.882538)
			(xy 43.473863 -17.841343) (xy 43.444395 -17.795488) (xy 43.421751 -17.745906) (xy 43.406395 -17.693607)
			(xy 43.398638 -17.639654) (xy 39.12982 -17.639654) (xy 39.12982 -17.640374) (xy 39.122057 -17.694368)
			(xy 39.106688 -17.746706) (xy 39.084026 -17.796325) (xy 39.054533 -17.842213) (xy 39.01881 -17.883436)
			(xy 38.977583 -17.919156) (xy 38.931691 -17.948644) (xy 38.882071 -17.971301) (xy 38.82973 -17.986665)
			(xy 38.775736 -17.994423) (xy 38.748462 -17.994884) (xy 37.884862 -17.994884) (xy 37.857596 -17.994351)
			(xy 37.80362 -17.986585) (xy 37.751298 -17.971218) (xy 37.701695 -17.948561) (xy 37.655822 -17.919075)
			(xy 37.614611 -17.883362) (xy 37.578902 -17.842148) (xy 37.549421 -17.796272) (xy 37.526769 -17.746667)
			(xy 37.511406 -17.694343) (xy 37.503646 -17.640366) (xy 33.54182 -17.640366) (xy 33.54182 -17.640374)
			(xy 33.534057 -17.694368) (xy 33.518688 -17.746706) (xy 33.496026 -17.796325) (xy 33.466533 -17.842213)
			(xy 33.43081 -17.883436) (xy 33.389583 -17.919156) (xy 33.343691 -17.948644) (xy 33.294071 -17.971301)
			(xy 33.24173 -17.986665) (xy 33.187736 -17.994423) (xy 33.160462 -17.994884) (xy 32.296862 -17.994884)
			(xy 32.269596 -17.994351) (xy 32.21562 -17.986585) (xy 32.163298 -17.971218) (xy 32.113695 -17.948561)
			(xy 32.067822 -17.919075) (xy 32.026611 -17.883362) (xy 31.990902 -17.842148) (xy 31.961421 -17.796272)
			(xy 31.938769 -17.746667) (xy 31.923406 -17.694343) (xy 31.915646 -17.640366) (xy 27.954402 -17.640366)
			(xy 27.946748 -17.693598) (xy 27.931392 -17.745892) (xy 27.908751 -17.795469) (xy 27.879284 -17.841318)
			(xy 27.843591 -17.882507) (xy 27.8024 -17.918197) (xy 27.756549 -17.947661) (xy 27.706972 -17.9703)
			(xy 27.654677 -17.985653) (xy 27.600729 -17.993406) (xy 27.573478 -17.993868) (xy 26.709878 -17.993868)
			(xy 26.682625 -17.993461) (xy 26.628674 -17.985701) (xy 26.576376 -17.970342) (xy 26.526797 -17.947697)
			(xy 26.480944 -17.918227) (xy 26.439752 -17.882532) (xy 26.404059 -17.841338) (xy 26.374592 -17.795484)
			(xy 26.35195 -17.745903) (xy 26.336595 -17.693605) (xy 26.328838 -17.639653) (xy 22.366505 -17.639653)
			(xy 22.358748 -17.693598) (xy 22.343392 -17.745892) (xy 22.320751 -17.795469) (xy 22.291284 -17.841318)
			(xy 22.255591 -17.882507) (xy 22.2144 -17.918197) (xy 22.168549 -17.947661) (xy 22.118972 -17.9703)
			(xy 22.066677 -17.985653) (xy 22.012729 -17.993406) (xy 21.985478 -17.993868) (xy 21.121878 -17.993868)
			(xy 21.094627 -17.993382) (xy 21.040679 -17.985625) (xy 20.988385 -17.97027) (xy 20.938808 -17.947629)
			(xy 20.892958 -17.918162) (xy 20.851768 -17.882471) (xy 20.816076 -17.841281) (xy 20.78661 -17.79543)
			(xy 20.763969 -17.745853) (xy 20.748614 -17.693559) (xy 20.740858 -17.639611) (xy 16.778525 -17.639611)
			(xy 16.778525 -17.639613) (xy 16.770768 -17.693564) (xy 16.755412 -17.745862) (xy 16.732769 -17.795442)
			(xy 16.703301 -17.841296) (xy 16.667607 -17.882488) (xy 16.626414 -17.918182) (xy 16.580561 -17.94765)
			(xy 16.53098 -17.970292) (xy 16.478682 -17.985648) (xy 16.424731 -17.993405) (xy 16.397478 -17.993868)
			(xy 15.533878 -17.993868) (xy 15.506627 -17.993382) (xy 15.452679 -17.985625) (xy 15.400385 -17.97027)
			(xy 15.350808 -17.947629) (xy 15.304958 -17.918162) (xy 15.263768 -17.882471) (xy 15.228076 -17.841281)
			(xy 15.19861 -17.79543) (xy 15.175969 -17.745853) (xy 15.160614 -17.693559) (xy 15.152858 -17.639611)
			(xy 0.509016 -17.639611) (xy 0.509016 -19.164391) (xy 17.945563 -19.164391) (xy 17.945563 -19.109849)
			(xy 17.953326 -19.055862) (xy 17.968692 -19.00353) (xy 17.99135 -18.953917) (xy 18.020837 -18.908033)
			(xy 18.056555 -18.866813) (xy 18.097775 -18.831096) (xy 18.143658 -18.801609) (xy 18.193272 -18.778951)
			(xy 18.245604 -18.763585) (xy 18.299591 -18.755823) (xy 18.326862 -18.75536) (xy 19.190462 -18.75536)
			(xy 19.217731 -18.755843) (xy 19.271715 -18.763605) (xy 19.324045 -18.77897) (xy 19.373655 -18.801627)
			(xy 19.419536 -18.831113) (xy 19.460753 -18.866828) (xy 19.496469 -18.908046) (xy 19.525954 -18.953927)
			(xy 19.548611 -19.003537) (xy 19.563976 -19.055867) (xy 19.571738 -19.109851) (xy 19.571738 -19.163653)
			(xy 23.534838 -19.163653) (xy 23.534838 -19.109147) (xy 23.542595 -19.055195) (xy 23.55795 -19.002897)
			(xy 23.580592 -18.953316) (xy 23.610059 -18.907462) (xy 23.645752 -18.866268) (xy 23.686944 -18.830573)
			(xy 23.732797 -18.801103) (xy 23.782376 -18.778458) (xy 23.834674 -18.763099) (xy 23.888625 -18.755339)
			(xy 23.915878 -18.754852) (xy 24.779478 -18.754852) (xy 24.806729 -18.755394) (xy 24.860677 -18.763147)
			(xy 24.912972 -18.7785) (xy 24.962549 -18.801139) (xy 25.0084 -18.830603) (xy 25.049591 -18.866293)
			(xy 25.085284 -18.907482) (xy 25.114751 -18.953331) (xy 25.137392 -19.002908) (xy 25.152748 -19.055202)
			(xy 25.160505 -19.109149) (xy 25.160505 -19.163651) (xy 25.160505 -19.163653) (xy 29.122838 -19.163653)
			(xy 29.122838 -19.109147) (xy 29.130595 -19.055195) (xy 29.14595 -19.002897) (xy 29.168592 -18.953316)
			(xy 29.198059 -18.907462) (xy 29.233752 -18.866268) (xy 29.274944 -18.830573) (xy 29.320797 -18.801103)
			(xy 29.370376 -18.778458) (xy 29.422674 -18.763099) (xy 29.476625 -18.755339) (xy 29.503878 -18.754852)
			(xy 30.367478 -18.754852) (xy 30.394729 -18.755394) (xy 30.448677 -18.763147) (xy 30.500972 -18.7785)
			(xy 30.550549 -18.801139) (xy 30.5964 -18.830603) (xy 30.637591 -18.866293) (xy 30.673284 -18.907482)
			(xy 30.702751 -18.953331) (xy 30.725392 -19.002908) (xy 30.740748 -19.055202) (xy 30.748505 -19.109149)
			(xy 30.748505 -19.163651) (xy 30.748505 -19.163653) (xy 34.710838 -19.163653) (xy 34.710838 -19.109147)
			(xy 34.718595 -19.055195) (xy 34.73395 -19.002897) (xy 34.756592 -18.953316) (xy 34.786059 -18.907462)
			(xy 34.821752 -18.866268) (xy 34.862944 -18.830573) (xy 34.908797 -18.801103) (xy 34.958376 -18.778458)
			(xy 35.010674 -18.763099) (xy 35.064625 -18.755339) (xy 35.091878 -18.754852) (xy 35.955478 -18.754852)
			(xy 35.982729 -18.755394) (xy 36.036677 -18.763147) (xy 36.088972 -18.7785) (xy 36.138549 -18.801139)
			(xy 36.1844 -18.830603) (xy 36.225591 -18.866293) (xy 36.261284 -18.907482) (xy 36.290751 -18.953331)
			(xy 36.313392 -19.002908) (xy 36.328748 -19.055202) (xy 36.336505 -19.109149) (xy 36.336505 -19.163651)
			(xy 36.336505 -19.163654) (xy 40.604638 -19.163654) (xy 40.604638 -19.109146) (xy 40.612395 -19.055193)
			(xy 40.627751 -19.002894) (xy 40.650395 -18.953312) (xy 40.679863 -18.907457) (xy 40.715558 -18.866262)
			(xy 40.756752 -18.830567) (xy 40.802606 -18.801097) (xy 40.852188 -18.778454) (xy 40.904487 -18.763096)
			(xy 40.95844 -18.755338) (xy 40.985694 -18.754852) (xy 41.849294 -18.754852) (xy 41.876544 -18.755395)
			(xy 41.93049 -18.76315) (xy 41.982783 -18.778504) (xy 42.032359 -18.801144) (xy 42.078208 -18.830609)
			(xy 42.119397 -18.866299) (xy 42.155088 -18.907487) (xy 42.184553 -18.953336) (xy 42.207194 -19.002911)
			(xy 42.222548 -19.055204) (xy 42.230305 -19.10915) (xy 42.230305 -19.16365) (xy 42.230202 -19.164367)
			(xy 46.191446 -19.164367) (xy 46.191446 -19.109833) (xy 46.199207 -19.055855) (xy 46.21457 -19.00353)
			(xy 46.237224 -18.953924) (xy 46.266706 -18.908047) (xy 46.302417 -18.866832) (xy 46.343629 -18.831119)
			(xy 46.389505 -18.801634) (xy 46.439109 -18.778978) (xy 46.491433 -18.763612) (xy 46.545411 -18.755848)
			(xy 46.572678 -18.75536) (xy 47.436278 -18.75536) (xy 47.463552 -18.755778) (xy 47.517544 -18.763538)
			(xy 47.569882 -18.778903) (xy 47.619501 -18.801561) (xy 47.66539 -18.83105) (xy 47.706615 -18.866769)
			(xy 47.742337 -18.907992) (xy 47.771828 -18.95388) (xy 47.794489 -19.003497) (xy 47.809857 -19.055835)
			(xy 47.81762 -19.109826) (xy 47.81762 -19.163657) (xy 51.814615 -19.163657) (xy 51.814615 -19.109143)
			(xy 51.822374 -19.055184) (xy 51.837733 -19.002878) (xy 51.86038 -18.95329) (xy 51.889854 -18.907431)
			(xy 51.925554 -18.866233) (xy 51.966755 -18.830536) (xy 52.012617 -18.801065) (xy 52.062206 -18.778422)
			(xy 52.114513 -18.763067) (xy 52.168473 -18.755313) (xy 52.19573 -18.754852) (xy 53.05933 -18.754852)
			(xy 53.086577 -18.75542) (xy 53.140516 -18.763179) (xy 53.192801 -18.778535) (xy 53.24237 -18.801176)
			(xy 53.288211 -18.83064) (xy 53.329394 -18.866328) (xy 53.365078 -18.907513) (xy 53.394538 -18.953357)
			(xy 53.417175 -19.002927) (xy 53.432527 -19.055214) (xy 53.440282 -19.109153) (xy 53.440282 -19.163647)
			(xy 53.440281 -19.163657) (xy 57.402615 -19.163657) (xy 57.402615 -19.109143) (xy 57.410374 -19.055184)
			(xy 57.425733 -19.002878) (xy 57.44838 -18.95329) (xy 57.477854 -18.907431) (xy 57.513554 -18.866233)
			(xy 57.554755 -18.830536) (xy 57.600617 -18.801065) (xy 57.650206 -18.778422) (xy 57.702513 -18.763067)
			(xy 57.756473 -18.755313) (xy 57.78373 -18.754852) (xy 58.64733 -18.754852) (xy 58.674577 -18.75542)
			(xy 58.728516 -18.763179) (xy 58.780801 -18.778535) (xy 58.83037 -18.801176) (xy 58.876211 -18.83064)
			(xy 58.917394 -18.866328) (xy 58.953078 -18.907513) (xy 58.982538 -18.953357) (xy 59.005175 -19.002927)
			(xy 59.020527 -19.055214) (xy 59.028282 -19.109153) (xy 59.028282 -19.163647) (xy 59.020527 -19.217586)
			(xy 59.005175 -19.269873) (xy 58.982538 -19.319443) (xy 58.953078 -19.365287) (xy 58.917394 -19.406472)
			(xy 58.876211 -19.44216) (xy 58.83037 -19.471624) (xy 58.780801 -19.494265) (xy 58.728516 -19.509621)
			(xy 58.674577 -19.51738) (xy 58.64733 -19.517868) (xy 57.78373 -19.517868) (xy 57.756473 -19.517487)
			(xy 57.702513 -19.509733) (xy 57.650206 -19.494378) (xy 57.600617 -19.471735) (xy 57.554755 -19.442264)
			(xy 57.513554 -19.406567) (xy 57.477854 -19.365369) (xy 57.44838 -19.31951) (xy 57.425733 -19.269922)
			(xy 57.410374 -19.217616) (xy 57.402615 -19.163657) (xy 53.440281 -19.163657) (xy 53.432527 -19.217586)
			(xy 53.417175 -19.269873) (xy 53.394538 -19.319443) (xy 53.365078 -19.365287) (xy 53.329394 -19.406472)
			(xy 53.288211 -19.44216) (xy 53.24237 -19.471624) (xy 53.192801 -19.494265) (xy 53.140516 -19.509621)
			(xy 53.086577 -19.51738) (xy 53.05933 -19.517868) (xy 52.19573 -19.517868) (xy 52.168473 -19.517487)
			(xy 52.114513 -19.509733) (xy 52.062206 -19.494378) (xy 52.012617 -19.471735) (xy 51.966755 -19.442264)
			(xy 51.925554 -19.406567) (xy 51.889854 -19.365369) (xy 51.86038 -19.31951) (xy 51.837733 -19.269922)
			(xy 51.822374 -19.217616) (xy 51.814615 -19.163657) (xy 47.81762 -19.163657) (xy 47.81762 -19.164374)
			(xy 47.809857 -19.218365) (xy 47.794489 -19.270703) (xy 47.771828 -19.32032) (xy 47.742337 -19.366208)
			(xy 47.706615 -19.407431) (xy 47.66539 -19.44315) (xy 47.619501 -19.472639) (xy 47.569882 -19.495297)
			(xy 47.517544 -19.510662) (xy 47.463552 -19.518422) (xy 47.436278 -19.518884) (xy 46.572678 -19.518884)
			(xy 46.545411 -19.518352) (xy 46.491433 -19.510588) (xy 46.439109 -19.495222) (xy 46.389505 -19.472566)
			(xy 46.343629 -19.443081) (xy 46.302417 -19.407368) (xy 46.266706 -19.366153) (xy 46.237224 -19.320276)
			(xy 46.21457 -19.27067) (xy 46.199207 -19.218345) (xy 46.191446 -19.164367) (xy 42.230202 -19.164367)
			(xy 42.222548 -19.217596) (xy 42.207194 -19.269889) (xy 42.184553 -19.319464) (xy 42.155088 -19.365313)
			(xy 42.119397 -19.406501) (xy 42.078208 -19.442191) (xy 42.032359 -19.471656) (xy 41.982783 -19.494296)
			(xy 41.93049 -19.50965) (xy 41.876544 -19.517405) (xy 41.849294 -19.517868) (xy 40.985694 -19.517868)
			(xy 40.95844 -19.517462) (xy 40.904487 -19.509704) (xy 40.852188 -19.494346) (xy 40.802606 -19.471703)
			(xy 40.756752 -19.442233) (xy 40.715558 -19.406538) (xy 40.679863 -19.365343) (xy 40.650395 -19.319488)
			(xy 40.627751 -19.269906) (xy 40.612395 -19.217607) (xy 40.604638 -19.163654) (xy 36.336505 -19.163654)
			(xy 36.328748 -19.217598) (xy 36.313392 -19.269892) (xy 36.290751 -19.319469) (xy 36.261284 -19.365318)
			(xy 36.225591 -19.406507) (xy 36.1844 -19.442197) (xy 36.138549 -19.471661) (xy 36.088972 -19.4943)
			(xy 36.036677 -19.509653) (xy 35.982729 -19.517406) (xy 35.955478 -19.517868) (xy 35.091878 -19.517868)
			(xy 35.064625 -19.517461) (xy 35.010674 -19.509701) (xy 34.958376 -19.494342) (xy 34.908797 -19.471697)
			(xy 34.862944 -19.442227) (xy 34.821752 -19.406532) (xy 34.786059 -19.365338) (xy 34.756592 -19.319484)
			(xy 34.73395 -19.269903) (xy 34.718595 -19.217605) (xy 34.710838 -19.163653) (xy 30.748505 -19.163653)
			(xy 30.740748 -19.217598) (xy 30.725392 -19.269892) (xy 30.702751 -19.319469) (xy 30.673284 -19.365318)
			(xy 30.637591 -19.406507) (xy 30.5964 -19.442197) (xy 30.550549 -19.471661) (xy 30.500972 -19.4943)
			(xy 30.448677 -19.509653) (xy 30.394729 -19.517406) (xy 30.367478 -19.517868) (xy 29.503878 -19.517868)
			(xy 29.476625 -19.517461) (xy 29.422674 -19.509701) (xy 29.370376 -19.494342) (xy 29.320797 -19.471697)
			(xy 29.274944 -19.442227) (xy 29.233752 -19.406532) (xy 29.198059 -19.365338) (xy 29.168592 -19.319484)
			(xy 29.14595 -19.269903) (xy 29.130595 -19.217605) (xy 29.122838 -19.163653) (xy 25.160505 -19.163653)
			(xy 25.152748 -19.217598) (xy 25.137392 -19.269892) (xy 25.114751 -19.319469) (xy 25.085284 -19.365318)
			(xy 25.049591 -19.406507) (xy 25.0084 -19.442197) (xy 24.962549 -19.471661) (xy 24.912972 -19.4943)
			(xy 24.860677 -19.509653) (xy 24.806729 -19.517406) (xy 24.779478 -19.517868) (xy 23.915878 -19.517868)
			(xy 23.888625 -19.517461) (xy 23.834674 -19.509701) (xy 23.782376 -19.494342) (xy 23.732797 -19.471697)
			(xy 23.686944 -19.442227) (xy 23.645752 -19.406532) (xy 23.610059 -19.365338) (xy 23.580592 -19.319484)
			(xy 23.55795 -19.269903) (xy 23.542595 -19.217605) (xy 23.534838 -19.163653) (xy 19.571738 -19.163653)
			(xy 19.571738 -19.164389) (xy 19.563976 -19.218373) (xy 19.548611 -19.270703) (xy 19.525954 -19.320313)
			(xy 19.496469 -19.366194) (xy 19.460753 -19.407412) (xy 19.419536 -19.443127) (xy 19.373655 -19.472613)
			(xy 19.324045 -19.49527) (xy 19.271715 -19.510635) (xy 19.217731 -19.518397) (xy 19.190462 -19.518884)
			(xy 18.326862 -19.518884) (xy 18.299591 -19.518417) (xy 18.245604 -19.510655) (xy 18.193272 -19.495289)
			(xy 18.143658 -19.472631) (xy 18.097775 -19.443144) (xy 18.056555 -19.407427) (xy 18.020837 -19.366207)
			(xy 17.99135 -19.320323) (xy 17.968692 -19.27071) (xy 17.953326 -19.218378) (xy 17.945563 -19.164391)
			(xy 0.509016 -19.164391) (xy 0.509016 -20.327366) (xy 65.88506 -20.327366) (xy 65.885484 -20.289077)
			(xy 65.892086 -20.212783) (xy 65.90523 -20.13734) (xy 65.924819 -20.063309) (xy 65.937384 -20.027138)
			(xy 65.940051 -20.018705) (xy 65.94004 -20.001031) (xy 65.937384 -19.992594) (xy 65.924856 -19.956411)
			(xy 65.905279 -19.88238) (xy 65.892127 -19.806942) (xy 65.885498 -19.730654) (xy 65.88506 -19.692366)
			(xy 65.885582 -19.650174) (xy 65.893576 -19.56617) (xy 65.909488 -19.483301) (xy 65.933176 -19.402311)
			(xy 65.964427 -19.323927) (xy 66.00296 -19.248856) (xy 66.048429 -19.17777) (xy 66.074036 -19.144234)
			(xy 66.079883 -19.13601) (xy 66.085128 -19.116537) (xy 66.082515 -19.096539) (xy 66.077846 -19.087592)
			(xy 66.058798 -19.053767) (xy 66.026006 -18.983399) (xy 65.999468 -18.910441) (xy 65.979384 -18.83545)
			(xy 65.965909 -18.758994) (xy 65.959144 -18.681655) (xy 65.95872 -18.642838) (xy 65.95872 -18.642584)
			(xy 65.959137 -18.60148) (xy 65.966724 -18.519622) (xy 65.981831 -18.438814) (xy 66.00433 -18.359744)
			(xy 66.034029 -18.283087) (xy 66.070674 -18.209498) (xy 66.113953 -18.139604) (xy 66.163496 -18.074001)
			(xy 66.218881 -18.01325) (xy 66.279635 -17.957868) (xy 66.34524 -17.908328) (xy 66.415137 -17.865053)
			(xy 66.488728 -17.828411) (xy 66.565386 -17.798716) (xy 66.644456 -17.776221) (xy 66.725266 -17.761118)
			(xy 66.807124 -17.753535) (xy 66.848228 -17.753076) (xy 66.889911 -17.753577) (xy 66.972911 -17.761363)
			(xy 67.054819 -17.776882) (xy 67.134915 -17.799999) (xy 67.212496 -17.830511) (xy 67.286881 -17.868149)
			(xy 67.357417 -17.912584) (xy 67.423485 -17.963425) (xy 67.484504 -18.020226) (xy 67.53994 -18.082488)
			(xy 67.565016 -18.115788) (xy 67.56527 -18.116042) (xy 67.570757 -18.122776) (xy 67.585223 -18.132372)
			(xy 67.602063 -18.136587) (xy 67.610736 -18.136108) (xy 67.697858 -18.127726) (xy 67.706567 -18.126584)
			(xy 67.722478 -18.119178) (xy 67.734922 -18.1068) (xy 67.739006 -18.099024) (xy 67.739006 -18.098516)
			(xy 67.757258 -18.060702) (xy 67.799884 -17.988356) (xy 67.849141 -17.920351) (xy 67.90459 -17.857291)
			(xy 67.965736 -17.79974) (xy 68.032035 -17.748209) (xy 68.102897 -17.703158) (xy 68.17769 -17.664987)
			(xy 68.255748 -17.634037) (xy 68.336377 -17.610583) (xy 68.418857 -17.594835) (xy 68.502455 -17.586933)
			(xy 68.54444 -17.586452) (xy 68.5868 -17.58693) (xy 68.671136 -17.594986) (xy 68.754325 -17.611023)
			(xy 68.835612 -17.634895) (xy 68.914262 -17.666384) (xy 68.989563 -17.705208) (xy 69.060833 -17.751013)
			(xy 69.127426 -17.803385) (xy 69.18874 -17.86185) (xy 69.244218 -17.925878) (xy 69.293359 -17.99489)
			(xy 69.335718 -18.068261) (xy 69.370911 -18.145325) (xy 69.39862 -18.225386) (xy 69.401856 -18.238724)
			(xy 79.0321 -18.238724) (xy 79.032651 -18.193954) (xy 79.041664 -18.104869) (xy 79.059573 -18.017137)
			(xy 79.086195 -17.931647) (xy 79.10322 -17.890236) (xy 79.106772 -17.880641) (xy 79.106781 -17.860202)
			(xy 79.10322 -17.850612) (xy 79.086184 -17.809205) (xy 79.059551 -17.723717) (xy 79.041646 -17.635983)
			(xy 79.032653 -17.546895) (xy 79.0321 -17.502124) (xy 79.032604 -17.459763) (xy 79.040657 -17.375426)
			(xy 79.056691 -17.292236) (xy 79.080559 -17.210946) (xy 79.112047 -17.132294) (xy 79.150869 -17.056991)
			(xy 79.196672 -16.985719) (xy 79.249043 -16.919123) (xy 79.307508 -16.857808) (xy 79.371536 -16.802327)
			(xy 79.440548 -16.753184) (xy 79.513918 -16.710824) (xy 79.590983 -16.675629) (xy 79.671045 -16.64792)
			(xy 79.753378 -16.627946) (xy 79.837237 -16.615889) (xy 79.921862 -16.611858) (xy 80.006487 -16.615889)
			(xy 80.090346 -16.627946) (xy 80.172679 -16.64792) (xy 80.252741 -16.675629) (xy 80.329806 -16.710824)
			(xy 80.403176 -16.753184) (xy 80.472188 -16.802327) (xy 80.536216 -16.857808) (xy 80.594681 -16.919123)
			(xy 80.647052 -16.985719) (xy 80.692855 -17.056991) (xy 80.731677 -17.132294) (xy 80.763165 -17.210946)
			(xy 80.787033 -17.292236) (xy 80.803067 -17.375426) (xy 80.81112 -17.459763) (xy 80.811624 -17.502124)
			(xy 80.811054 -17.546893) (xy 80.802046 -17.635978) (xy 80.784143 -17.723709) (xy 80.757526 -17.809201)
			(xy 80.740504 -17.850612) (xy 80.736924 -17.860198) (xy 80.736933 -17.880645) (xy 80.740504 -17.890236)
			(xy 80.757551 -17.931638) (xy 80.784182 -18.017129) (xy 80.802084 -18.104863) (xy 80.808854 -18.171951)
			(xy 131.633699 -18.171951) (xy 131.633699 -18.117449) (xy 131.641456 -18.063503) (xy 131.656811 -18.011209)
			(xy 131.679453 -17.961633) (xy 131.708919 -17.915784) (xy 131.744611 -17.874596) (xy 131.785802 -17.838906)
			(xy 131.831653 -17.809442) (xy 131.88123 -17.786804) (xy 131.933524 -17.771451) (xy 131.987471 -17.763698)
			(xy 132.014722 -17.763236) (xy 132.878322 -17.763236) (xy 132.905575 -17.763635) (xy 132.959527 -17.771395)
			(xy 133.011825 -17.786754) (xy 133.061405 -17.809399) (xy 133.107258 -17.838869) (xy 133.148451 -17.874565)
			(xy 133.184144 -17.915759) (xy 133.213611 -17.961614) (xy 133.236254 -18.011196) (xy 133.251609 -18.063495)
			(xy 133.259366 -18.117447) (xy 133.259366 -18.171946) (xy 137.033822 -18.171946) (xy 137.033822 -18.117454)
			(xy 137.041577 -18.063516) (xy 137.056928 -18.01123) (xy 137.079564 -17.961661) (xy 137.109023 -17.915818)
			(xy 137.144706 -17.874633) (xy 137.185887 -17.838946) (xy 137.231728 -17.809482) (xy 137.281294 -17.786841)
			(xy 137.333578 -17.771485) (xy 137.387516 -17.763725) (xy 137.414762 -17.763236) (xy 138.278362 -17.763236)
			(xy 138.30562 -17.763608) (xy 138.359581 -17.771362) (xy 138.41189 -17.786716) (xy 138.46148 -17.809359)
			(xy 138.507344 -17.83883) (xy 138.548546 -17.874528) (xy 138.584247 -17.915726) (xy 138.613722 -17.961586)
			(xy 138.63637 -18.011175) (xy 138.65173 -18.063482) (xy 138.659489 -18.117442) (xy 138.659489 -18.17195)
			(xy 140.633699 -18.17195) (xy 140.633699 -18.11745) (xy 140.641455 -18.063505) (xy 140.65681 -18.011213)
			(xy 140.67945 -17.961638) (xy 140.708915 -17.91579) (xy 140.744605 -17.874602) (xy 140.785793 -17.838913)
			(xy 140.831642 -17.809448) (xy 140.881217 -17.786808) (xy 140.933509 -17.771455) (xy 140.987454 -17.763699)
			(xy 141.014704 -17.763236) (xy 141.878304 -17.763236) (xy 141.905558 -17.763634) (xy 141.959512 -17.771392)
			(xy 142.011812 -17.786749) (xy 142.061394 -17.809393) (xy 142.10725 -17.838863) (xy 142.148444 -17.874559)
			(xy 142.184139 -17.915754) (xy 142.213609 -17.961609) (xy 142.236252 -18.011192) (xy 142.251609 -18.063492)
			(xy 142.259366 -18.117446) (xy 142.259366 -18.171954) (xy 142.251609 -18.225908) (xy 142.236252 -18.278208)
			(xy 142.213609 -18.327791) (xy 142.184139 -18.373646) (xy 142.148444 -18.414841) (xy 142.10725 -18.450537)
			(xy 142.061394 -18.480007) (xy 142.011812 -18.502651) (xy 141.959512 -18.518008) (xy 141.905558 -18.525766)
			(xy 141.878304 -18.526252) (xy 141.014704 -18.526252) (xy 140.987454 -18.525701) (xy 140.933509 -18.517945)
			(xy 140.881217 -18.502592) (xy 140.831642 -18.479952) (xy 140.785793 -18.450487) (xy 140.744605 -18.414798)
			(xy 140.708915 -18.37361) (xy 140.67945 -18.327762) (xy 140.65681 -18.278187) (xy 140.641455 -18.225895)
			(xy 140.633699 -18.17195) (xy 138.659489 -18.17195) (xy 138.659489 -18.171958) (xy 138.65173 -18.225918)
			(xy 138.63637 -18.278225) (xy 138.613722 -18.327814) (xy 138.584247 -18.373674) (xy 138.548546 -18.414872)
			(xy 138.507344 -18.45057) (xy 138.46148 -18.480041) (xy 138.41189 -18.502684) (xy 138.359581 -18.518038)
			(xy 138.30562 -18.525792) (xy 138.278362 -18.526252) (xy 137.414762 -18.526252) (xy 137.387516 -18.525675)
			(xy 137.333578 -18.517915) (xy 137.281294 -18.502559) (xy 137.231728 -18.479918) (xy 137.185887 -18.450454)
			(xy 137.144706 -18.414767) (xy 137.109023 -18.373582) (xy 137.079564 -18.327739) (xy 137.056928 -18.27817)
			(xy 137.041577 -18.225884) (xy 137.033822 -18.171946) (xy 133.259366 -18.171946) (xy 133.259366 -18.171953)
			(xy 133.251609 -18.225905) (xy 133.236254 -18.278204) (xy 133.213611 -18.327786) (xy 133.184144 -18.373641)
			(xy 133.148451 -18.414835) (xy 133.107258 -18.450531) (xy 133.061405 -18.480001) (xy 133.011825 -18.502646)
			(xy 132.959527 -18.518005) (xy 132.905575 -18.525765) (xy 132.878322 -18.526252) (xy 132.014722 -18.526252)
			(xy 131.987471 -18.525702) (xy 131.933524 -18.517949) (xy 131.88123 -18.502596) (xy 131.831653 -18.479958)
			(xy 131.785802 -18.450494) (xy 131.744611 -18.414804) (xy 131.708919 -18.373616) (xy 131.679453 -18.327767)
			(xy 131.656811 -18.278191) (xy 131.641456 -18.225897) (xy 131.633699 -18.171951) (xy 80.808854 -18.171951)
			(xy 80.811074 -18.193953) (xy 80.811624 -18.238724) (xy 80.81112 -18.281085) (xy 80.803067 -18.365422)
			(xy 80.787033 -18.448612) (xy 80.763165 -18.529902) (xy 80.731677 -18.608554) (xy 80.692855 -18.683857)
			(xy 80.647052 -18.755129) (xy 80.594681 -18.821725) (xy 80.536216 -18.88304) (xy 80.472188 -18.938521)
			(xy 80.403176 -18.987664) (xy 80.329806 -19.030024) (xy 80.252741 -19.065219) (xy 80.172679 -19.092928)
			(xy 80.090346 -19.112902) (xy 80.006487 -19.124959) (xy 79.921862 -19.128991) (xy 79.837237 -19.124959)
			(xy 79.753378 -19.112902) (xy 79.671045 -19.092928) (xy 79.590983 -19.065219) (xy 79.513918 -19.030024)
			(xy 79.440548 -18.987664) (xy 79.371536 -18.938521) (xy 79.307508 -18.88304) (xy 79.249043 -18.821725)
			(xy 79.196672 -18.755129) (xy 79.150869 -18.683857) (xy 79.112047 -18.608554) (xy 79.080559 -18.529902)
			(xy 79.056691 -18.448612) (xy 79.040657 -18.365422) (xy 79.032604 -18.281085) (xy 79.0321 -18.238724)
			(xy 69.401856 -18.238724) (xy 69.418593 -18.307718) (xy 69.430649 -18.391576) (xy 69.434681 -18.4762)
			(xy 69.430649 -18.560824) (xy 69.418593 -18.644682) (xy 69.39862 -18.727014) (xy 69.370911 -18.807075)
			(xy 69.335718 -18.884139) (xy 69.293359 -18.95751) (xy 69.244218 -19.026522) (xy 69.18874 -19.09055)
			(xy 69.127426 -19.149015) (xy 69.060833 -19.201387) (xy 68.989563 -19.247192) (xy 68.914262 -19.286016)
			(xy 68.835612 -19.317505) (xy 68.754325 -19.341377) (xy 68.671136 -19.357414) (xy 68.5868 -19.36547)
			(xy 68.54444 -19.365976) (xy 68.502753 -19.365468) (xy 68.419745 -19.357644) (xy 68.337834 -19.342089)
			(xy 68.257737 -19.31894) (xy 68.180157 -19.288398) (xy 68.105774 -19.250734) (xy 68.035242 -19.206275)
			(xy 67.969177 -19.155414) (xy 67.90816 -19.098595) (xy 67.852727 -19.036317) (xy 67.827652 -19.00301)
			(xy 67.827398 -19.002756) (xy 67.821873 -18.996058) (xy 67.807425 -18.986454) (xy 67.790601 -18.982223)
			(xy 67.781932 -18.98269) (xy 67.69481 -18.991072) (xy 67.686098 -18.992195) (xy 67.670187 -18.999611)
			(xy 67.657745 -19.011995) (xy 67.653662 -19.019774) (xy 67.653662 -19.020282) (xy 67.63179 -19.065383)
			(xy 67.579339 -19.150805) (xy 67.549014 -19.190716) (xy 67.543272 -19.198996) (xy 67.538026 -19.218428)
			(xy 67.540615 -19.238388) (xy 67.545204 -19.247358) (xy 67.564269 -19.281203) (xy 67.597117 -19.351604)
			(xy 67.623706 -19.424598) (xy 67.643834 -19.499632) (xy 67.657349 -19.576134) (xy 67.664146 -19.653523)
			(xy 67.664584 -19.692366) (xy 67.664167 -19.730656) (xy 67.657563 -19.806949) (xy 67.644416 -19.882392)
			(xy 67.624826 -19.956423) (xy 67.61226 -19.992594) (xy 67.609626 -20.001035) (xy 67.609615 -20.018702)
			(xy 67.61226 -20.027138) (xy 67.624799 -20.063317) (xy 67.644373 -20.13735) (xy 67.653158 -20.187755)
			(xy 138.765443 -20.187755) (xy 138.765443 -20.133245) (xy 138.773201 -20.079289) (xy 138.788559 -20.026987)
			(xy 138.811205 -19.977403) (xy 138.840677 -19.931547) (xy 138.876376 -19.890352) (xy 138.917574 -19.854657)
			(xy 138.963433 -19.825189) (xy 139.013019 -19.802547) (xy 139.065322 -19.787194) (xy 139.119279 -19.779441)
			(xy 139.146534 -19.77898) (xy 140.137134 -19.77898) (xy 140.164383 -19.779493) (xy 140.218325 -19.787253)
			(xy 140.270614 -19.80261) (xy 140.320185 -19.825253) (xy 140.36603 -19.854719) (xy 140.407215 -19.890409)
			(xy 140.442901 -19.931597) (xy 140.449617 -19.942048) (xy 175.988472 -19.942048) (xy 175.988976 -19.899687)
			(xy 175.997029 -19.81535) (xy 176.013063 -19.73216) (xy 176.036931 -19.65087) (xy 176.068419 -19.572218)
			(xy 176.107241 -19.496915) (xy 176.153044 -19.425643) (xy 176.205415 -19.359047) (xy 176.26388 -19.297732)
			(xy 176.327908 -19.242251) (xy 176.39692 -19.193108) (xy 176.47029 -19.150748) (xy 176.547355 -19.115553)
			(xy 176.627417 -19.087844) (xy 176.70975 -19.06787) (xy 176.793609 -19.055813) (xy 176.878234 -19.051782)
			(xy 176.962859 -19.055813) (xy 177.046718 -19.06787) (xy 177.129051 -19.087844) (xy 177.209113 -19.115553)
			(xy 177.286178 -19.150748) (xy 177.359548 -19.193108) (xy 177.42856 -19.242251) (xy 177.492588 -19.297732)
			(xy 177.551053 -19.359047) (xy 177.603424 -19.425643) (xy 177.649227 -19.496915) (xy 177.688049 -19.572218)
			(xy 177.719537 -19.65087) (xy 177.743405 -19.73216) (xy 177.759439 -19.81535) (xy 177.767492 -19.899687)
			(xy 177.767996 -19.942048) (xy 177.767398 -19.98792) (xy 177.757891 -20.079169) (xy 177.739034 -20.168954)
			(xy 177.725578 -20.212812) (xy 177.722752 -20.223379) (xy 177.72523 -20.245087) (xy 177.730404 -20.254722)
			(xy 177.750836 -20.289402) (xy 177.786035 -20.361795) (xy 177.814552 -20.437071) (xy 177.836153 -20.514616)
			(xy 177.850661 -20.593794) (xy 177.857958 -20.67396) (xy 177.85842 -20.714208) (xy 177.85842 -20.715224)
			(xy 177.857839 -20.760561) (xy 177.84856 -20.850758) (xy 177.830152 -20.939544) (xy 177.817018 -20.98294)
			(xy 177.81462 -20.991841) (xy 177.815621 -21.010233) (xy 177.823067 -21.02708) (xy 177.835994 -21.040201)
			(xy 177.844196 -21.044408) (xy 177.8824 -21.062505) (xy 177.955518 -21.104946) (xy 178.024281 -21.15413)
			(xy 178.088069 -21.209614) (xy 178.146306 -21.270898) (xy 178.198469 -21.337429) (xy 178.244087 -21.408608)
			(xy 178.282748 -21.483792) (xy 178.314103 -21.562305) (xy 178.337871 -21.643437) (xy 178.353837 -21.726458)
			(xy 178.361856 -21.810619) (xy 178.362356 -21.85289) (xy 178.361892 -21.894005) (xy 178.354306 -21.975884)
			(xy 178.339197 -22.056714) (xy 178.316694 -22.135805) (xy 178.28699 -22.212482) (xy 178.250337 -22.286091)
			(xy 178.207049 -22.356005) (xy 178.157495 -22.421626) (xy 178.102097 -22.482394) (xy 178.041329 -22.537792)
			(xy 177.975708 -22.587347) (xy 177.905795 -22.630635) (xy 177.832186 -22.667288) (xy 177.755509 -22.696993)
			(xy 177.676418 -22.719496) (xy 177.595588 -22.734605) (xy 177.513709 -22.742192) (xy 177.472594 -22.742652)
			(xy 177.429071 -22.742084) (xy 177.34244 -22.73358) (xy 177.257055 -22.716655) (xy 177.173731 -22.69147)
			(xy 177.093266 -22.658267) (xy 177.016429 -22.617362) (xy 176.943956 -22.569146) (xy 176.876538 -22.514083)
			(xy 176.814822 -22.452697) (xy 176.759398 -22.385575) (xy 176.710795 -22.313361) (xy 176.669479 -22.236745)
			(xy 176.652174 -22.196806) (xy 176.647921 -22.187866) (xy 176.633936 -22.17388) (xy 176.624996 -22.169628)
			(xy 176.585068 -22.152314) (xy 176.508472 -22.110985) (xy 176.436278 -22.062372) (xy 176.369178 -22.006941)
			(xy 176.307813 -21.945221) (xy 176.252769 -21.877802) (xy 176.204574 -21.80533) (xy 176.163687 -21.728496)
			(xy 176.1305 -21.648037) (xy 176.105331 -21.564721) (xy 176.088419 -21.479345) (xy 176.079928 -21.392725)
			(xy 176.079404 -21.349208) (xy 176.079404 -21.348446) (xy 176.079814 -21.310226) (xy 176.086378 -21.234067)
			(xy 176.099462 -21.158755) (xy 176.118968 -21.084845) (xy 176.131474 -21.048726) (xy 176.134055 -21.040409)
			(xy 176.134058 -21.023006) (xy 176.131474 -21.01469) (xy 176.118957 -20.978475) (xy 176.099434 -20.904375)
			(xy 176.086349 -20.828871) (xy 176.079799 -20.752523) (xy 176.079404 -20.714208) (xy 176.07999 -20.668344)
			(xy 176.089425 -20.577104) (xy 176.108186 -20.487316) (xy 176.121568 -20.443444) (xy 176.124428 -20.432883)
			(xy 176.121929 -20.411168) (xy 176.116742 -20.401534) (xy 176.096312 -20.366847) (xy 176.06107 -20.294464)
			(xy 176.032509 -20.219194) (xy 176.010862 -20.141652) (xy 175.996306 -20.062472) (xy 175.988959 -19.982301)
			(xy 175.988472 -19.942048) (xy 140.449617 -19.942048) (xy 140.472364 -19.977445) (xy 140.495002 -20.027018)
			(xy 140.510354 -20.079308) (xy 140.51811 -20.133251) (xy 140.51811 -20.187749) (xy 140.510354 -20.241692)
			(xy 140.495002 -20.293982) (xy 140.472364 -20.343555) (xy 140.442901 -20.389403) (xy 140.407215 -20.430591)
			(xy 140.36603 -20.466281) (xy 140.320185 -20.495747) (xy 140.270614 -20.51839) (xy 140.218325 -20.533747)
			(xy 140.164383 -20.541507) (xy 140.137134 -20.541996) (xy 139.146534 -20.541996) (xy 139.119279 -20.541559)
			(xy 139.065322 -20.533806) (xy 139.013019 -20.518453) (xy 138.963433 -20.495811) (xy 138.917574 -20.466343)
			(xy 138.876376 -20.430648) (xy 138.840677 -20.389453) (xy 138.811205 -20.343597) (xy 138.788559 -20.294013)
			(xy 138.773201 -20.241711) (xy 138.765443 -20.187755) (xy 67.653158 -20.187755) (xy 67.657521 -20.212789)
			(xy 67.664147 -20.289078) (xy 67.664584 -20.327366) (xy 67.66408 -20.369727) (xy 67.656027 -20.454064)
			(xy 67.639993 -20.537254) (xy 67.616125 -20.618544) (xy 67.584637 -20.697196) (xy 67.545815 -20.772499)
			(xy 67.500012 -20.843771) (xy 67.447641 -20.910367) (xy 67.389176 -20.971682) (xy 67.325148 -21.027163)
			(xy 67.256136 -21.076306) (xy 67.182766 -21.118666) (xy 67.105701 -21.153861) (xy 67.025639 -21.18157)
			(xy 66.943306 -21.201544) (xy 66.859447 -21.213601) (xy 66.774822 -21.217633) (xy 66.690197 -21.213601)
			(xy 66.606338 -21.201544) (xy 66.524005 -21.18157) (xy 66.443943 -21.153861) (xy 66.366878 -21.118666)
			(xy 66.293508 -21.076306) (xy 66.224496 -21.027163) (xy 66.160468 -20.971682) (xy 66.102003 -20.910367)
			(xy 66.049632 -20.843771) (xy 66.003829 -20.772499) (xy 65.965007 -20.697196) (xy 65.933519 -20.618544)
			(xy 65.909651 -20.537254) (xy 65.893617 -20.454064) (xy 65.885564 -20.369727) (xy 65.88506 -20.327366)
			(xy 0.509016 -20.327366) (xy 0.509016 -22.309271) (xy 65.993006 -22.309271) (xy 65.993006 -22.224549)
			(xy 66.001059 -22.140212) (xy 66.017093 -22.057022) (xy 66.040961 -21.975732) (xy 66.072449 -21.89708)
			(xy 66.111271 -21.821777) (xy 66.157074 -21.750505) (xy 66.209445 -21.683909) (xy 66.26791 -21.622594)
			(xy 66.331938 -21.567113) (xy 66.40095 -21.51797) (xy 66.47432 -21.47561) (xy 66.551385 -21.440415)
			(xy 66.631447 -21.412706) (xy 66.71378 -21.392732) (xy 66.797639 -21.380675) (xy 66.882264 -21.376644)
			(xy 66.966889 -21.380675) (xy 67.050748 -21.392732) (xy 67.133081 -21.412706) (xy 67.213143 -21.440415)
			(xy 67.290208 -21.47561) (xy 67.363578 -21.51797) (xy 67.43259 -21.567113) (xy 67.496618 -21.622594)
			(xy 67.555083 -21.683909) (xy 67.607454 -21.750505) (xy 67.653257 -21.821777) (xy 67.692079 -21.89708)
			(xy 67.723567 -21.975732) (xy 67.747435 -22.057022) (xy 67.763469 -22.140212) (xy 67.771522 -22.224549)
			(xy 67.772026 -22.26691) (xy 67.771522 -22.309271) (xy 67.763469 -22.393608) (xy 67.747435 -22.476798)
			(xy 67.723567 -22.558088) (xy 67.722853 -22.559872) (xy 114.452596 -22.559872) (xy 114.452596 -22.505328)
			(xy 114.460358 -22.45134) (xy 114.475725 -22.399006) (xy 114.498383 -22.349391) (xy 114.527872 -22.303506)
			(xy 114.563591 -22.262285) (xy 114.604813 -22.226567) (xy 114.650698 -22.19708) (xy 114.700313 -22.174422)
			(xy 114.752648 -22.159056) (xy 114.806636 -22.151295) (xy 114.833908 -22.150832) (xy 115.697508 -22.150832)
			(xy 115.724777 -22.151331) (xy 115.778758 -22.159093) (xy 115.831086 -22.174459) (xy 115.880695 -22.197116)
			(xy 115.926574 -22.226601) (xy 115.96779 -22.262316) (xy 116.003504 -22.303533) (xy 116.032988 -22.349412)
			(xy 116.055644 -22.399021) (xy 116.071008 -22.451349) (xy 116.07877 -22.505331) (xy 116.07877 -22.559869)
			(xy 116.071008 -22.613851) (xy 116.055644 -22.666179) (xy 116.032988 -22.715788) (xy 116.003504 -22.761667)
			(xy 115.96779 -22.802884) (xy 115.926574 -22.838599) (xy 115.880695 -22.868084) (xy 115.831086 -22.890741)
			(xy 115.778758 -22.906107) (xy 115.724777 -22.913869) (xy 115.697508 -22.914356) (xy 114.833908 -22.914356)
			(xy 114.806636 -22.913905) (xy 114.752648 -22.906144) (xy 114.700313 -22.890778) (xy 114.650698 -22.86812)
			(xy 114.604813 -22.838633) (xy 114.563591 -22.802915) (xy 114.527872 -22.761694) (xy 114.498383 -22.715809)
			(xy 114.475725 -22.666194) (xy 114.460358 -22.61386) (xy 114.452596 -22.559872) (xy 67.722853 -22.559872)
			(xy 67.692079 -22.63674) (xy 67.653257 -22.712043) (xy 67.607454 -22.783315) (xy 67.555083 -22.849911)
			(xy 67.496618 -22.911226) (xy 67.43259 -22.966707) (xy 67.363578 -23.01585) (xy 67.361784 -23.016886)
			(xy 136.323137 -23.016886) (xy 136.327046 -22.962479) (xy 136.338661 -22.909183) (xy 136.357746 -22.858084)
			(xy 136.383911 -22.810221) (xy 136.416623 -22.766572) (xy 136.435592 -22.74697) (xy 137.046208 -22.1361)
			(xy 137.06783 -22.115331) (xy 137.116345 -22.080114) (xy 137.169764 -22.052902) (xy 137.226775 -22.034363)
			(xy 137.285982 -22.024951) (xy 137.315956 -22.02434) (xy 137.31621 -22.02434) (xy 137.34348 -22.024815)
			(xy 137.397464 -22.032578) (xy 137.449794 -22.047945) (xy 137.499404 -22.070602) (xy 137.545285 -22.10009)
			(xy 137.586503 -22.135806) (xy 137.622218 -22.177025) (xy 137.651703 -22.222907) (xy 137.674359 -22.272518)
			(xy 137.689724 -22.324848) (xy 137.697486 -22.378832) (xy 137.697972 -22.406102) (xy 137.697972 -22.406356)
			(xy 137.6974 -22.436336) (xy 137.688023 -22.495559) (xy 137.669494 -22.552585) (xy 137.64227 -22.606009)
			(xy 137.60702 -22.654514) (xy 137.586212 -22.676104) (xy 136.975342 -23.28672) (xy 136.955728 -23.305677)
			(xy 136.912079 -23.338389) (xy 136.864216 -23.364554) (xy 136.813117 -23.383639) (xy 136.759821 -23.395254)
			(xy 136.705414 -23.399163) (xy 136.651005 -23.395286) (xy 136.597702 -23.383703) (xy 136.546591 -23.364649)
			(xy 136.498713 -23.338513) (xy 136.455044 -23.305826) (xy 136.416474 -23.267256) (xy 136.383787 -23.223587)
			(xy 136.357651 -23.175709) (xy 136.338597 -23.124598) (xy 136.327014 -23.071295) (xy 136.323137 -23.016886)
			(xy 67.361784 -23.016886) (xy 67.290208 -23.05821) (xy 67.213143 -23.093405) (xy 67.133081 -23.121114)
			(xy 67.050748 -23.141088) (xy 66.966889 -23.153145) (xy 66.882264 -23.157177) (xy 66.797639 -23.153145)
			(xy 66.71378 -23.141088) (xy 66.631447 -23.121114) (xy 66.551385 -23.093405) (xy 66.47432 -23.05821)
			(xy 66.40095 -23.01585) (xy 66.331938 -22.966707) (xy 66.26791 -22.911226) (xy 66.209445 -22.849911)
			(xy 66.157074 -22.783315) (xy 66.111271 -22.712043) (xy 66.072449 -22.63674) (xy 66.040961 -22.558088)
			(xy 66.017093 -22.476798) (xy 66.001059 -22.393608) (xy 65.993006 -22.309271) (xy 0.509016 -22.309271)
			(xy 0.509016 -23.593552) (xy 189.619128 -23.593552) (xy 189.619128 -23.593298) (xy 189.619711 -23.54856)
			(xy 189.628722 -23.459539) (xy 189.646623 -23.371871) (xy 189.673232 -23.286444) (xy 189.690248 -23.245064)
			(xy 189.69384 -23.235481) (xy 189.693822 -23.215031) (xy 189.690248 -23.20544) (xy 189.673222 -23.164064)
			(xy 189.646604 -23.078637) (xy 189.6287 -22.990968) (xy 189.619692 -22.901945) (xy 189.619128 -22.857206)
			(xy 189.619128 -22.856952) (xy 189.619632 -22.814604) (xy 189.627683 -22.73029) (xy 189.643712 -22.647124)
			(xy 189.667573 -22.565857) (xy 189.699052 -22.487227) (xy 189.737863 -22.411946) (xy 189.783653 -22.340694)
			(xy 189.836009 -22.274118) (xy 189.894457 -22.21282) (xy 189.958467 -22.157355) (xy 190.027459 -22.108226)
			(xy 190.100809 -22.065877) (xy 190.177852 -22.030693) (xy 190.257891 -22.002991) (xy 190.3402 -21.983023)
			(xy 190.424035 -21.97097) (xy 190.508636 -21.96694) (xy 190.593237 -21.97097) (xy 190.677072 -21.983023)
			(xy 190.759381 -22.002991) (xy 190.83942 -22.030693) (xy 190.916463 -22.065877) (xy 190.989813 -22.108226)
			(xy 191.058805 -22.157355) (xy 191.122815 -22.21282) (xy 191.181263 -22.274118) (xy 191.233619 -22.340694)
			(xy 191.279409 -22.411946) (xy 191.31822 -22.487227) (xy 191.349699 -22.565857) (xy 191.37356 -22.647124)
			(xy 191.389589 -22.73029) (xy 191.39764 -22.814604) (xy 191.398144 -22.856952) (xy 191.398144 -22.857206)
			(xy 191.397557 -22.901944) (xy 191.388547 -22.990965) (xy 191.370647 -23.078632) (xy 191.344039 -23.16406)
			(xy 191.327024 -23.20544) (xy 191.323489 -23.215039) (xy 191.323471 -23.235473) (xy 191.327024 -23.245064)
			(xy 191.344055 -23.286438) (xy 191.370671 -23.371866) (xy 191.388573 -23.459535) (xy 191.39758 -23.548559)
			(xy 191.398144 -23.593298) (xy 191.398144 -23.593552) (xy 191.39764 -23.6359) (xy 191.389589 -23.720214)
			(xy 191.37356 -23.80338) (xy 191.349699 -23.884647) (xy 191.31822 -23.963277) (xy 191.279409 -24.038558)
			(xy 191.233619 -24.10981) (xy 191.181263 -24.176386) (xy 191.122815 -24.237684) (xy 191.058805 -24.293149)
			(xy 190.989813 -24.342278) (xy 190.916463 -24.384627) (xy 190.83942 -24.419811) (xy 190.759381 -24.447513)
			(xy 190.677072 -24.467481) (xy 190.593237 -24.479534) (xy 190.508636 -24.483565) (xy 190.424035 -24.479534)
			(xy 190.3402 -24.467481) (xy 190.257891 -24.447513) (xy 190.177852 -24.419811) (xy 190.100809 -24.384627)
			(xy 190.027459 -24.342278) (xy 189.958467 -24.293149) (xy 189.894457 -24.237684) (xy 189.836009 -24.176386)
			(xy 189.783653 -24.10981) (xy 189.737863 -24.038558) (xy 189.699052 -23.963277) (xy 189.667573 -23.884647)
			(xy 189.643712 -23.80338) (xy 189.627683 -23.720214) (xy 189.619632 -23.6359) (xy 189.619128 -23.593552)
			(xy 0.509016 -23.593552) (xy 0.509016 -25.56891) (xy 65.510156 -25.56891) (xy 65.510621 -25.527206)
			(xy 65.518403 -25.444163) (xy 65.533928 -25.362214) (xy 65.557059 -25.282079) (xy 65.587593 -25.204462)
			(xy 65.625262 -25.130046) (xy 65.669734 -25.059485) (xy 65.720619 -24.993398) (xy 65.777469 -24.932368)
			(xy 65.839786 -24.876929) (xy 65.873122 -24.851868) (xy 65.88167 -24.844931) (xy 65.892346 -24.825708)
			(xy 65.893696 -24.814784) (xy 65.897332 -24.773398) (xy 65.911399 -24.69151) (xy 65.933041 -24.611291)
			(xy 65.962067 -24.53344) (xy 65.998226 -24.458634) (xy 66.041203 -24.387525) (xy 66.090622 -24.320733)
			(xy 66.146054 -24.25884) (xy 66.207015 -24.202385) (xy 66.272974 -24.15186) (xy 66.343357 -24.107705)
			(xy 66.41755 -24.070304) (xy 66.494907 -24.039985) (xy 66.574755 -24.01701) (xy 66.656396 -24.00158)
			(xy 66.739121 -23.99383) (xy 66.780664 -23.993348) (xy 66.824459 -23.993873) (xy 66.911625 -24.002491)
			(xy 66.997521 -24.019637) (xy 67.081315 -24.045145) (xy 67.162195 -24.078768) (xy 67.201034 -24.099012)
			(xy 67.2125 -24.10443) (xy 67.237828 -24.10443) (xy 67.249294 -24.099012) (xy 67.288138 -24.078781)
			(xy 67.369023 -24.045174) (xy 67.452816 -24.019672) (xy 67.538709 -24.002521) (xy 67.62587 -23.993888)
			(xy 67.669664 -23.993348) (xy 67.713459 -23.993873) (xy 67.800625 -24.002491) (xy 67.886521 -24.019637)
			(xy 67.970315 -24.045145) (xy 68.051195 -24.078768) (xy 68.090034 -24.099012) (xy 68.1015 -24.10443)
			(xy 68.126828 -24.10443) (xy 68.138294 -24.099012) (xy 68.177138 -24.078781) (xy 68.258023 -24.045174)
			(xy 68.341816 -24.019672) (xy 68.427709 -24.002521) (xy 68.51487 -23.993888) (xy 68.558664 -23.993348)
			(xy 68.607651 -23.994055) (xy 68.705028 -24.00487) (xy 68.752974 -24.014938) (xy 68.762324 -24.016604)
			(xy 68.781086 -24.013776) (xy 68.797533 -24.004314) (xy 68.803774 -23.997158) (xy 68.831851 -23.962886)
			(xy 68.893786 -23.899527) (xy 68.961714 -23.842641) (xy 69.034963 -23.792791) (xy 69.112805 -23.750472)
			(xy 69.19447 -23.716104) (xy 69.279148 -23.690027) (xy 69.365999 -23.672499) (xy 69.454163 -23.663695)
			(xy 69.498464 -23.663148) (xy 69.540827 -23.663615) (xy 69.625169 -23.671665) (xy 69.708365 -23.687697)
			(xy 69.789659 -23.711564) (xy 69.868317 -23.743051) (xy 69.943625 -23.781873) (xy 70.014902 -23.827677)
			(xy 70.081502 -23.880049) (xy 70.142823 -23.938516) (xy 70.198307 -24.002546) (xy 70.247454 -24.071561)
			(xy 70.250564 -24.076947) (xy 112.652614 -24.076947) (xy 112.652614 -24.022453) (xy 112.660369 -23.968515)
			(xy 112.67572 -23.916228) (xy 112.698356 -23.866659) (xy 112.727815 -23.820815) (xy 112.763499 -23.77963)
			(xy 112.80468 -23.743942) (xy 112.85052 -23.714477) (xy 112.900087 -23.691836) (xy 112.952372 -23.676478)
			(xy 113.006309 -23.668717) (xy 113.033556 -23.668228) (xy 113.897156 -23.668228) (xy 113.924413 -23.668616)
			(xy 113.978374 -23.676369) (xy 114.030682 -23.691722) (xy 114.080273 -23.714364) (xy 114.126136 -23.743834)
			(xy 114.167338 -23.779531) (xy 114.20304 -23.820729) (xy 114.232514 -23.866588) (xy 114.255162 -23.916176)
			(xy 114.270522 -23.968483) (xy 114.278281 -24.022443) (xy 114.278281 -24.076957) (xy 114.270522 -24.130917)
			(xy 114.255235 -24.182975) (xy 116.218856 -24.182975) (xy 116.218856 -24.128425) (xy 116.226619 -24.074429)
			(xy 116.241989 -24.022088) (xy 116.264651 -23.972468) (xy 116.294144 -23.926577) (xy 116.329868 -23.885352)
			(xy 116.371096 -23.84963) (xy 116.416989 -23.820139) (xy 116.466611 -23.79748) (xy 116.518953 -23.782114)
			(xy 116.572949 -23.774354) (xy 116.600224 -23.773892) (xy 117.463824 -23.773892) (xy 117.491089 -23.774472)
			(xy 117.545063 -23.782235) (xy 117.597384 -23.797601) (xy 117.646985 -23.820256) (xy 117.692857 -23.849739)
			(xy 117.734067 -23.88545) (xy 117.769776 -23.926662) (xy 117.799256 -23.972536) (xy 117.821907 -24.022139)
			(xy 117.83727 -24.07446) (xy 117.84503 -24.128435) (xy 117.84503 -24.182965) (xy 117.83727 -24.23694)
			(xy 117.821907 -24.289261) (xy 117.799256 -24.338864) (xy 117.769776 -24.384738) (xy 117.734067 -24.42595)
			(xy 117.692857 -24.461661) (xy 117.646985 -24.491144) (xy 117.597384 -24.513799) (xy 117.545063 -24.529165)
			(xy 117.491089 -24.536928) (xy 117.463824 -24.537416) (xy 116.600224 -24.537416) (xy 116.572949 -24.537046)
			(xy 116.518953 -24.529286) (xy 116.466611 -24.51392) (xy 116.416989 -24.491261) (xy 116.371096 -24.46177)
			(xy 116.329868 -24.426049) (xy 116.294144 -24.384823) (xy 116.264651 -24.338932) (xy 116.241989 -24.289312)
			(xy 116.226619 -24.236971) (xy 116.218856 -24.182975) (xy 114.255235 -24.182975) (xy 114.255162 -24.183224)
			(xy 114.232514 -24.232812) (xy 114.20304 -24.278671) (xy 114.167338 -24.319869) (xy 114.126136 -24.355566)
			(xy 114.080273 -24.385036) (xy 114.030682 -24.407678) (xy 113.978374 -24.423031) (xy 113.924414 -24.430784)
			(xy 113.897156 -24.431244) (xy 113.033556 -24.431244) (xy 113.006309 -24.430683) (xy 112.952372 -24.422922)
			(xy 112.900087 -24.407564) (xy 112.85052 -24.384923) (xy 112.80468 -24.355458) (xy 112.763499 -24.31977)
			(xy 112.727815 -24.278585) (xy 112.698356 -24.232741) (xy 112.67572 -24.183172) (xy 112.660369 -24.130885)
			(xy 112.652614 -24.076947) (xy 70.250564 -24.076947) (xy 70.289818 -24.144935) (xy 70.325015 -24.222004)
			(xy 70.352727 -24.302069) (xy 70.372702 -24.384407) (xy 70.38476 -24.46827) (xy 70.388792 -24.5529)
			(xy 70.38476 -24.63753) (xy 70.37544 -24.702351) (xy 130.235962 -24.702351) (xy 130.235962 -24.647849)
			(xy 130.243717 -24.593903) (xy 130.259071 -24.541609) (xy 130.28171 -24.492033) (xy 130.311174 -24.446182)
			(xy 130.346863 -24.404991) (xy 130.38805 -24.369298) (xy 130.433897 -24.33983) (xy 130.483472 -24.317185)
			(xy 130.535764 -24.301826) (xy 130.589709 -24.294065) (xy 130.61696 -24.293576) (xy 131.48056 -24.293576)
			(xy 131.507814 -24.294069) (xy 131.561767 -24.301821) (xy 131.614067 -24.317173) (xy 131.66365 -24.339812)
			(xy 131.709506 -24.369277) (xy 131.750702 -24.40497) (xy 131.786399 -24.446162) (xy 131.815869 -24.492015)
			(xy 131.838513 -24.541595) (xy 131.853871 -24.593894) (xy 131.861629 -24.647846) (xy 131.861629 -24.702354)
			(xy 131.853871 -24.756306) (xy 131.838513 -24.808605) (xy 131.815869 -24.858185) (xy 131.786399 -24.904038)
			(xy 131.750702 -24.94523) (xy 131.709506 -24.980923) (xy 131.66365 -25.010388) (xy 131.614067 -25.033027)
			(xy 131.561767 -25.048379) (xy 131.507814 -25.056131) (xy 131.48056 -25.056592) (xy 130.61696 -25.056592)
			(xy 130.589709 -25.056135) (xy 130.535764 -25.048374) (xy 130.483472 -25.033015) (xy 130.433897 -25.01037)
			(xy 130.38805 -24.980902) (xy 130.346863 -24.945209) (xy 130.311174 -24.904018) (xy 130.28171 -24.858167)
			(xy 130.259071 -24.808591) (xy 130.243717 -24.756297) (xy 130.235962 -24.702351) (xy 70.37544 -24.702351)
			(xy 70.372702 -24.721393) (xy 70.352727 -24.803731) (xy 70.325015 -24.883796) (xy 70.289818 -24.960865)
			(xy 70.247454 -25.034239) (xy 70.198307 -25.103254) (xy 70.142823 -25.167284) (xy 70.081502 -25.225751)
			(xy 70.014902 -25.278123) (xy 69.943625 -25.323927) (xy 69.868317 -25.362749) (xy 69.789659 -25.394236)
			(xy 69.708365 -25.418103) (xy 69.625169 -25.434135) (xy 69.540827 -25.442185) (xy 69.498464 -25.442672)
			(xy 69.449476 -25.441976) (xy 69.3521 -25.431154) (xy 69.304154 -25.421082) (xy 69.294812 -25.41935)
			(xy 69.276039 -25.422204) (xy 69.259591 -25.431693) (xy 69.253354 -25.438862) (xy 69.228687 -25.46901)
			(xy 69.174875 -25.52534) (xy 69.116354 -25.57676) (xy 69.085206 -25.600152) (xy 69.076637 -25.607067)
			(xy 69.065975 -25.626306) (xy 69.065849 -25.62733) (xy 133.339332 -25.62733) (xy 133.339332 -24.76373)
			(xy 133.339818 -24.736479) (xy 133.347574 -24.682531) (xy 133.362929 -24.630236) (xy 133.385571 -24.580659)
			(xy 133.415037 -24.534809) (xy 133.450728 -24.493618) (xy 133.491919 -24.457927) (xy 133.537769 -24.428461)
			(xy 133.587346 -24.405819) (xy 133.639641 -24.390464) (xy 133.693589 -24.382708) (xy 133.748091 -24.382708)
			(xy 133.802039 -24.390464) (xy 133.854334 -24.405819) (xy 133.903911 -24.428461) (xy 133.949761 -24.457927)
			(xy 133.990952 -24.493618) (xy 134.026643 -24.534809) (xy 134.056109 -24.580659) (xy 134.078751 -24.630236)
			(xy 134.094106 -24.682531) (xy 134.101862 -24.736479) (xy 134.102348 -24.76373) (xy 134.102348 -25.62733)
			(xy 134.101862 -25.654581) (xy 134.094106 -25.708529) (xy 134.078751 -25.760824) (xy 134.056109 -25.810401)
			(xy 134.026643 -25.856251) (xy 133.990952 -25.897442) (xy 133.949761 -25.933133) (xy 133.903911 -25.962599)
			(xy 133.854334 -25.985241) (xy 133.802039 -26.000596) (xy 133.748091 -26.008352) (xy 133.693589 -26.008352)
			(xy 133.639641 -26.000596) (xy 133.587346 -25.985241) (xy 133.537769 -25.962599) (xy 133.491919 -25.933133)
			(xy 133.450728 -25.897442) (xy 133.415037 -25.856251) (xy 133.385571 -25.810401) (xy 133.362929 -25.760824)
			(xy 133.347574 -25.708529) (xy 133.339818 -25.654581) (xy 133.339332 -25.62733) (xy 69.065849 -25.62733)
			(xy 69.064632 -25.637236) (xy 69.060986 -25.678621) (xy 69.046917 -25.760507) (xy 69.025275 -25.840725)
			(xy 68.996248 -25.918575) (xy 68.960089 -25.99338) (xy 68.917113 -26.064488) (xy 68.867694 -26.131279)
			(xy 68.812263 -26.193171) (xy 68.751303 -26.249626) (xy 68.685345 -26.300151) (xy 68.614964 -26.344307)
			(xy 68.540772 -26.381708) (xy 68.463416 -26.412028) (xy 68.38357 -26.435004) (xy 68.30193 -26.450436)
			(xy 68.219207 -26.458189) (xy 68.177664 -26.458672) (xy 68.133869 -26.458133) (xy 68.046704 -26.449518)
			(xy 67.960808 -26.432375) (xy 67.877014 -26.40687) (xy 67.796134 -26.37325) (xy 67.757294 -26.353008)
			(xy 67.745828 -26.34759) (xy 67.7205 -26.34759) (xy 67.709034 -26.353008) (xy 67.670181 -26.373222)
			(xy 67.589299 -26.406833) (xy 67.505508 -26.43234) (xy 67.419618 -26.449494) (xy 67.332457 -26.458131)
			(xy 67.288664 -26.458672) (xy 67.244869 -26.458133) (xy 67.157704 -26.449518) (xy 67.071808 -26.432375)
			(xy 66.988014 -26.40687) (xy 66.907134 -26.37325) (xy 66.868294 -26.353008) (xy 66.856828 -26.34759)
			(xy 66.8315 -26.34759) (xy 66.820034 -26.353008) (xy 66.781181 -26.373222) (xy 66.700299 -26.406833)
			(xy 66.616508 -26.43234) (xy 66.530618 -26.449494) (xy 66.443457 -26.458131) (xy 66.399664 -26.458672)
			(xy 66.358552 -26.458282) (xy 66.276678 -26.45069) (xy 66.195855 -26.435576) (xy 66.116771 -26.413067)
			(xy 66.040102 -26.383356) (xy 65.966502 -26.346696) (xy 65.8966 -26.3034) (xy 65.830991 -26.253838)
			(xy 65.770236 -26.198433) (xy 65.714853 -26.137658) (xy 65.665316 -26.072031) (xy 65.622046 -26.002113)
			(xy 65.585413 -25.928499) (xy 65.55573 -25.85182) (xy 65.53325 -25.772728) (xy 65.518165 -25.691899)
			(xy 65.510603 -25.610022) (xy 65.510156 -25.56891) (xy 0.509016 -25.56891) (xy 0.509016 -29.026161)
			(xy 11.140205 -29.026161) (xy 11.147539 -28.866724) (xy 11.162812 -28.70785) (xy 11.185984 -28.549934)
			(xy 11.216999 -28.39337) (xy 11.255779 -28.238547) (xy 11.302228 -28.085849) (xy 11.35623 -27.935656)
			(xy 11.417652 -27.788341) (xy 11.48634 -27.644271) (xy 11.562123 -27.503804) (xy 11.644814 -27.367289)
			(xy 11.734207 -27.235065) (xy 11.830079 -27.107461) (xy 11.932193 -26.984794) (xy 12.040293 -26.86737)
			(xy 12.154112 -26.75548) (xy 12.273367 -26.649402) (xy 12.397761 -26.5494) (xy 12.526985 -26.455723)
			(xy 12.660717 -26.368604) (xy 12.798626 -26.288258) (xy 12.940368 -26.214886) (xy 13.085591 -26.148671)
			(xy 13.233934 -26.089776) (xy 13.385028 -26.038349) (xy 13.538498 -25.994517) (xy 13.693962 -25.958388)
			(xy 13.851033 -25.930054) (xy 14.009321 -25.909584) (xy 14.168433 -25.897029) (xy 14.327973 -25.892421)
			(xy 14.487544 -25.895771) (xy 14.64675 -25.90707) (xy 14.805195 -25.92629) (xy 14.962485 -25.953385)
			(xy 15.118229 -25.988285) (xy 15.272039 -26.030905) (xy 15.423535 -26.081139) (xy 15.572338 -26.138862)
			(xy 15.718078 -26.203929) (xy 15.860395 -26.27618) (xy 15.998933 -26.355436) (xy 16.133349 -26.441497)
			(xy 16.263308 -26.534152) (xy 16.388487 -26.633169) (xy 16.508575 -26.738303) (xy 16.623273 -26.849292)
			(xy 16.678148 -26.907236) (xy 17.470427 -27.75458) (xy 130.687572 -27.75458) (xy 130.687572 -26.76398)
			(xy 130.688058 -26.736729) (xy 130.695814 -26.682781) (xy 130.711169 -26.630486) (xy 130.733811 -26.580909)
			(xy 130.763277 -26.535059) (xy 130.798968 -26.493868) (xy 130.840159 -26.458177) (xy 130.886009 -26.428711)
			(xy 130.935586 -26.406069) (xy 130.987881 -26.390714) (xy 131.041829 -26.382958) (xy 131.096331 -26.382958)
			(xy 131.150279 -26.390714) (xy 131.202574 -26.406069) (xy 131.252151 -26.428711) (xy 131.298001 -26.458177)
			(xy 131.339192 -26.493868) (xy 131.374883 -26.535059) (xy 131.404349 -26.580909) (xy 131.426991 -26.630486)
			(xy 131.442346 -26.682781) (xy 131.450102 -26.736729) (xy 131.450588 -26.76398) (xy 131.450588 -26.76779)
			(xy 141.621764 -26.76779) (xy 141.621764 -25.90419) (xy 141.62225 -25.876921) (xy 141.630012 -25.822937)
			(xy 141.645377 -25.770607) (xy 141.668034 -25.720997) (xy 141.69752 -25.675116) (xy 141.733235 -25.633899)
			(xy 141.774452 -25.598184) (xy 141.820333 -25.568698) (xy 141.869943 -25.546041) (xy 141.922273 -25.530676)
			(xy 141.976257 -25.522914) (xy 142.030795 -25.522914) (xy 142.084779 -25.530676) (xy 142.137109 -25.546041)
			(xy 142.186719 -25.568698) (xy 142.2326 -25.598184) (xy 142.273817 -25.633899) (xy 142.309532 -25.675116)
			(xy 142.339018 -25.720997) (xy 142.361675 -25.770607) (xy 142.37704 -25.822937) (xy 142.384802 -25.876921)
			(xy 142.385288 -25.90419) (xy 142.385288 -26.634948) (xy 175.442372 -26.634948) (xy 175.442817 -26.593237)
			(xy 175.450618 -26.510181) (xy 175.466165 -26.428221) (xy 175.489321 -26.348077) (xy 175.519883 -26.270455)
			(xy 175.557582 -26.196038) (xy 175.602086 -26.125479) (xy 175.653004 -26.059399) (xy 175.709888 -25.99838)
			(xy 175.772239 -25.942957) (xy 175.805592 -25.917906) (xy 175.814178 -25.911009) (xy 175.82483 -25.891756)
			(xy 175.826166 -25.880822) (xy 175.829855 -25.839448) (xy 175.843941 -25.757582) (xy 175.865598 -25.677385)
			(xy 175.894637 -25.599556) (xy 175.930804 -25.524774) (xy 175.973785 -25.453688) (xy 176.023205 -25.386918)
			(xy 176.078634 -25.325046) (xy 176.13959 -25.268611) (xy 176.205541 -25.218103) (xy 176.275913 -25.173964)
			(xy 176.350094 -25.136576) (xy 176.427436 -25.106267) (xy 176.507267 -25.083299) (xy 176.588892 -25.067873)
			(xy 176.671599 -25.060123) (xy 176.713134 -25.05964) (xy 176.713642 -25.05964) (xy 176.757406 -25.060139)
			(xy 176.844513 -25.068717) (xy 176.930355 -25.085818) (xy 177.0141 -25.111273) (xy 177.094937 -25.144838)
			(xy 177.133758 -25.16505) (xy 177.145111 -25.170377) (xy 177.170157 -25.170377) (xy 177.18151 -25.16505)
			(xy 177.22038 -25.144826) (xy 177.301322 -25.111257) (xy 177.38517 -25.085803) (xy 177.471113 -25.068709)
			(xy 177.55832 -25.060143) (xy 177.602134 -25.05964) (xy 177.645949 -25.060116) (xy 177.733161 -25.068665)
			(xy 177.819109 -25.085756) (xy 177.902957 -25.111222) (xy 177.983891 -25.144816) (xy 178.022758 -25.16505)
			(xy 178.034111 -25.170377) (xy 178.059157 -25.170377) (xy 178.07051 -25.16505) (xy 178.10938 -25.144826)
			(xy 178.190322 -25.111257) (xy 178.27417 -25.085803) (xy 178.360113 -25.068709) (xy 178.44732 -25.060143)
			(xy 178.491134 -25.05964) (xy 178.541288 -25.060291) (xy 178.640969 -25.071493) (xy 178.690016 -25.081992)
			(xy 178.700529 -25.083816) (xy 178.72144 -25.079687) (xy 178.7389 -25.067462) (xy 178.74488 -25.058624)
			(xy 178.766746 -25.023211) (xy 178.816155 -24.956227) (xy 178.871604 -24.894151) (xy 178.932608 -24.837525)
			(xy 178.998633 -24.786843) (xy 179.069104 -24.742549) (xy 179.143403 -24.705031) (xy 179.220882 -24.674615)
			(xy 179.300862 -24.651569) (xy 179.382645 -24.636093) (xy 179.465517 -24.628322) (xy 179.507134 -24.62784)
			(xy 179.549484 -24.628249) (xy 179.633799 -24.636303) (xy 179.716968 -24.652336) (xy 179.798236 -24.676201)
			(xy 179.876867 -24.707683) (xy 179.95215 -24.746496) (xy 180.023403 -24.79229) (xy 180.08998 -24.844649)
			(xy 180.151278 -24.9031) (xy 180.206744 -24.967112) (xy 180.255873 -25.036107) (xy 180.298222 -25.10946)
			(xy 180.333407 -25.186506) (xy 180.361109 -25.266547) (xy 180.381077 -25.348859) (xy 180.39313 -25.432696)
			(xy 180.397161 -25.5173) (xy 180.39313 -25.601904) (xy 180.381077 -25.685741) (xy 180.361109 -25.768053)
			(xy 180.333407 -25.848094) (xy 180.298222 -25.92514) (xy 180.255873 -25.998493) (xy 180.206744 -26.067488)
			(xy 180.151278 -26.1315) (xy 180.08998 -26.189951) (xy 180.023403 -26.24231) (xy 179.95215 -26.288104)
			(xy 179.876867 -26.326917) (xy 179.798236 -26.358399) (xy 179.716968 -26.382264) (xy 179.633799 -26.398297)
			(xy 179.549484 -26.406351) (xy 179.507134 -26.406856) (xy 179.505864 -26.406856) (xy 179.456029 -26.406131)
			(xy 179.35699 -26.394927) (xy 179.308252 -26.384504) (xy 179.297742 -26.382653) (xy 179.276827 -26.386794)
			(xy 179.259367 -26.39903) (xy 179.253388 -26.407872) (xy 179.230217 -26.445289) (xy 179.177598 -26.515842)
			(xy 179.118275 -26.58086) (xy 179.052827 -26.639708) (xy 179.017676 -26.66619) (xy 179.009104 -26.673102)
			(xy 178.998441 -26.692343) (xy 178.997102 -26.703274) (xy 178.993441 -26.744651) (xy 178.979354 -26.826519)
			(xy 178.957697 -26.906717) (xy 178.928657 -26.984547) (xy 178.892489 -27.059331) (xy 178.849506 -27.130418)
			(xy 178.835198 -27.149749) (xy 180.032656 -27.149749) (xy 180.032656 -27.065027) (xy 180.040709 -26.98069)
			(xy 180.056743 -26.8975) (xy 180.080611 -26.81621) (xy 180.112099 -26.737558) (xy 180.150921 -26.662255)
			(xy 180.196724 -26.590983) (xy 180.249095 -26.524387) (xy 180.30756 -26.463072) (xy 180.371588 -26.407591)
			(xy 180.4406 -26.358448) (xy 180.51397 -26.316088) (xy 180.591035 -26.280893) (xy 180.671097 -26.253184)
			(xy 180.75343 -26.23321) (xy 180.837289 -26.221153) (xy 180.921914 -26.217122) (xy 181.006539 -26.221153)
			(xy 181.090398 -26.23321) (xy 181.172731 -26.253184) (xy 181.252793 -26.280893) (xy 181.329858 -26.316088)
			(xy 181.403228 -26.358448) (xy 181.47224 -26.407591) (xy 181.536268 -26.463072) (xy 181.594733 -26.524387)
			(xy 181.647104 -26.590983) (xy 181.692907 -26.662255) (xy 181.731729 -26.737558) (xy 181.763217 -26.81621)
			(xy 181.787085 -26.8975) (xy 181.803119 -26.98069) (xy 181.811172 -27.065027) (xy 181.811676 -27.107388)
			(xy 181.811172 -27.149749) (xy 181.803119 -27.234086) (xy 181.787085 -27.317276) (xy 181.763217 -27.398566)
			(xy 181.731729 -27.477218) (xy 181.692907 -27.552521) (xy 181.647104 -27.623793) (xy 181.594733 -27.690389)
			(xy 181.536268 -27.751704) (xy 181.47224 -27.807185) (xy 181.403228 -27.856328) (xy 181.329858 -27.898688)
			(xy 181.252793 -27.933883) (xy 181.172731 -27.961592) (xy 181.090398 -27.981566) (xy 181.006539 -27.993623)
			(xy 180.921914 -27.997655) (xy 180.837289 -27.993623) (xy 180.75343 -27.981566) (xy 180.671097 -27.961592)
			(xy 180.591035 -27.933883) (xy 180.51397 -27.898688) (xy 180.4406 -27.856328) (xy 180.371588 -27.807185)
			(xy 180.30756 -27.751704) (xy 180.249095 -27.690389) (xy 180.196724 -27.623793) (xy 180.150921 -27.552521)
			(xy 180.112099 -27.477218) (xy 180.080611 -27.398566) (xy 180.056743 -27.317276) (xy 180.040709 -27.234086)
			(xy 180.032656 -27.149749) (xy 178.835198 -27.149749) (xy 178.800084 -27.197189) (xy 178.744653 -27.259061)
			(xy 178.683695 -27.315497) (xy 178.617742 -27.366004) (xy 178.547367 -27.410143) (xy 178.473184 -27.447529)
			(xy 178.395839 -27.477837) (xy 178.316006 -27.500803) (xy 178.234379 -27.516227) (xy 178.15167 -27.523974)
			(xy 178.110134 -27.524456) (xy 178.109626 -27.524456) (xy 178.065862 -27.523929) (xy 177.978756 -27.515357)
			(xy 177.892915 -27.498263) (xy 177.809169 -27.472814) (xy 177.728331 -27.439255) (xy 177.68951 -27.419046)
			(xy 177.678157 -27.413719) (xy 177.653111 -27.413719) (xy 177.641758 -27.419046) (xy 177.602894 -27.439282)
			(xy 177.521951 -27.472849) (xy 177.438101 -27.498301) (xy 177.352156 -27.515391) (xy 177.264948 -27.523955)
			(xy 177.221134 -27.524456) (xy 177.177318 -27.523994) (xy 177.090106 -27.515442) (xy 177.004158 -27.498348)
			(xy 176.920311 -27.472879) (xy 176.839376 -27.439281) (xy 176.80051 -27.419046) (xy 176.789157 -27.413719)
			(xy 176.764111 -27.413719) (xy 176.752758 -27.419046) (xy 176.713921 -27.439222) (xy 176.633081 -27.472767)
			(xy 176.549339 -27.498216) (xy 176.463504 -27.515325) (xy 176.376404 -27.523927) (xy 176.332642 -27.524456)
			(xy 176.332134 -27.524456) (xy 176.291028 -27.523955) (xy 176.209165 -27.516374) (xy 176.128351 -27.501273)
			(xy 176.049275 -27.47878) (xy 175.972611 -27.449089) (xy 175.899013 -27.412452) (xy 175.829109 -27.369181)
			(xy 175.763495 -27.319646) (xy 175.702731 -27.264268) (xy 175.647335 -27.203522) (xy 175.597779 -27.137923)
			(xy 175.554486 -27.068033) (xy 175.517825 -26.994447) (xy 175.488109 -26.917792) (xy 175.465592 -26.838723)
			(xy 175.450465 -26.757914) (xy 175.442858 -26.676054) (xy 175.442372 -26.634948) (xy 142.385288 -26.634948)
			(xy 142.385288 -26.76779) (xy 142.384802 -26.795059) (xy 142.37704 -26.849043) (xy 142.361675 -26.901373)
			(xy 142.339018 -26.950983) (xy 142.309532 -26.996864) (xy 142.273817 -27.038081) (xy 142.2326 -27.073796)
			(xy 142.186719 -27.103282) (xy 142.137109 -27.125939) (xy 142.084779 -27.141304) (xy 142.030795 -27.149066)
			(xy 141.976257 -27.149066) (xy 141.922273 -27.141304) (xy 141.869943 -27.125939) (xy 141.820333 -27.103282)
			(xy 141.774452 -27.073796) (xy 141.733235 -27.038081) (xy 141.69752 -26.996864) (xy 141.668034 -26.950983)
			(xy 141.645377 -26.901373) (xy 141.630012 -26.849043) (xy 141.62225 -26.795059) (xy 141.621764 -26.76779)
			(xy 131.450588 -26.76779) (xy 131.450588 -27.75458) (xy 131.450102 -27.781831) (xy 131.442346 -27.835779)
			(xy 131.426991 -27.888074) (xy 131.404349 -27.937651) (xy 131.374883 -27.983501) (xy 131.339192 -28.024692)
			(xy 131.298001 -28.060383) (xy 131.252151 -28.089849) (xy 131.202574 -28.112491) (xy 131.150279 -28.127846)
			(xy 131.096331 -28.135602) (xy 131.041829 -28.135602) (xy 130.987881 -28.127846) (xy 130.935586 -28.112491)
			(xy 130.886009 -28.089849) (xy 130.840159 -28.060383) (xy 130.798968 -28.024692) (xy 130.763277 -27.983501)
			(xy 130.733811 -27.937651) (xy 130.711169 -27.888074) (xy 130.695814 -27.835779) (xy 130.688058 -27.781831)
			(xy 130.687572 -27.75458) (xy 17.470427 -27.75458) (xy 17.770856 -28.07589) (xy 17.824996 -28.134528)
			(xy 17.928078 -28.256394) (xy 18.024957 -28.383247) (xy 18.115392 -28.514772) (xy 18.199158 -28.650641)
			(xy 18.276047 -28.790516) (xy 18.345869 -28.934051) (xy 18.408448 -29.080887) (xy 18.463631 -29.230661)
			(xy 18.511279 -29.382999) (xy 18.546379 -29.51861) (xy 101.326696 -29.51861) (xy 101.326696 -28.65501)
			(xy 101.327182 -28.627759) (xy 101.334938 -28.573811) (xy 101.350293 -28.521516) (xy 101.372935 -28.471939)
			(xy 101.402401 -28.426089) (xy 101.438092 -28.384898) (xy 101.479283 -28.349207) (xy 101.525133 -28.319741)
			(xy 101.57471 -28.297099) (xy 101.627005 -28.281744) (xy 101.680953 -28.273988) (xy 101.735455 -28.273988)
			(xy 101.789403 -28.281744) (xy 101.841698 -28.297099) (xy 101.891275 -28.319741) (xy 101.937125 -28.349207)
			(xy 101.978316 -28.384898) (xy 102.014007 -28.426089) (xy 102.043473 -28.471939) (xy 102.066115 -28.521516)
			(xy 102.08147 -28.573811) (xy 102.089226 -28.627759) (xy 102.089712 -28.65501) (xy 102.089712 -29.24302)
			(xy 135.551672 -29.24302) (xy 135.551672 -28.25242) (xy 135.552158 -28.225169) (xy 135.559914 -28.171221)
			(xy 135.575269 -28.118926) (xy 135.597911 -28.069349) (xy 135.627377 -28.023499) (xy 135.663068 -27.982308)
			(xy 135.704259 -27.946617) (xy 135.750109 -27.917151) (xy 135.799686 -27.894509) (xy 135.851981 -27.879154)
			(xy 135.905929 -27.871398) (xy 135.960431 -27.871398) (xy 136.014379 -27.879154) (xy 136.066674 -27.894509)
			(xy 136.116251 -27.917151) (xy 136.162101 -27.946617) (xy 136.203292 -27.982308) (xy 136.238983 -28.023499)
			(xy 136.268449 -28.069349) (xy 136.291091 -28.118926) (xy 136.306446 -28.171221) (xy 136.314202 -28.225169)
			(xy 136.314688 -28.25242) (xy 136.314688 -28.526871) (xy 139.853386 -28.526871) (xy 139.853386 -28.472329)
			(xy 139.861148 -28.418343) (xy 139.876513 -28.366011) (xy 139.89917 -28.316397) (xy 139.928656 -28.270513)
			(xy 139.964371 -28.229293) (xy 140.005589 -28.193574) (xy 140.051471 -28.164084) (xy 140.101082 -28.141424)
			(xy 140.153414 -28.126054) (xy 140.207399 -28.118289) (xy 140.23467 -28.1178) (xy 141.09827 -28.1178)
			(xy 141.12554 -28.118337) (xy 141.179524 -28.126095) (xy 141.231856 -28.141457) (xy 141.281468 -28.164111)
			(xy 141.32735 -28.193595) (xy 141.36857 -28.229309) (xy 141.404287 -28.270526) (xy 141.433775 -28.316406)
			(xy 141.456432 -28.366016) (xy 141.471798 -28.418346) (xy 141.479561 -28.47233) (xy 141.479561 -28.52687)
			(xy 141.471798 -28.580854) (xy 141.456432 -28.633184) (xy 141.433775 -28.682794) (xy 141.404287 -28.728674)
			(xy 141.36857 -28.769891) (xy 141.32735 -28.805605) (xy 141.281468 -28.835089) (xy 141.231856 -28.857743)
			(xy 141.179524 -28.873105) (xy 141.12554 -28.880863) (xy 141.09827 -28.881324) (xy 140.23467 -28.881324)
			(xy 140.207399 -28.880911) (xy 140.153414 -28.873146) (xy 140.101082 -28.857776) (xy 140.051471 -28.835116)
			(xy 140.005589 -28.805626) (xy 139.964371 -28.769907) (xy 139.928656 -28.728687) (xy 139.89917 -28.682803)
			(xy 139.876513 -28.633189) (xy 139.861148 -28.580857) (xy 139.853386 -28.526871) (xy 136.314688 -28.526871)
			(xy 136.314688 -29.24302) (xy 136.314202 -29.270271) (xy 136.306446 -29.324219) (xy 136.291091 -29.376514)
			(xy 136.268449 -29.426091) (xy 136.238983 -29.471941) (xy 136.203292 -29.513132) (xy 136.162101 -29.548823)
			(xy 136.116251 -29.578289) (xy 136.066674 -29.600931) (xy 136.014379 -29.616286) (xy 135.960431 -29.624042)
			(xy 135.905929 -29.624042) (xy 135.851981 -29.616286) (xy 135.799686 -29.600931) (xy 135.750109 -29.578289)
			(xy 135.704259 -29.548823) (xy 135.663068 -29.513132) (xy 135.627377 -29.471941) (xy 135.597911 -29.426091)
			(xy 135.575269 -29.376514) (xy 135.559914 -29.324219) (xy 135.552158 -29.270271) (xy 135.551672 -29.24302)
			(xy 102.089712 -29.24302) (xy 102.089712 -29.51861) (xy 102.089226 -29.545861) (xy 102.08147 -29.599809)
			(xy 102.066115 -29.652104) (xy 102.043473 -29.701681) (xy 102.014007 -29.747531) (xy 101.978316 -29.788722)
			(xy 101.937125 -29.824413) (xy 101.891275 -29.853879) (xy 101.841698 -29.876521) (xy 101.789403 -29.891876)
			(xy 101.735455 -29.899632) (xy 101.680953 -29.899632) (xy 101.627005 -29.891876) (xy 101.57471 -29.876521)
			(xy 101.525133 -29.853879) (xy 101.479283 -29.824413) (xy 101.438092 -29.788722) (xy 101.402401 -29.747531)
			(xy 101.372935 -29.701681) (xy 101.350293 -29.652104) (xy 101.334938 -29.599809) (xy 101.327182 -29.545861)
			(xy 101.326696 -29.51861) (xy 18.546379 -29.51861) (xy 18.551274 -29.537523) (xy 18.583516 -29.693848)
			(xy 18.607926 -29.851586) (xy 18.624443 -30.010345) (xy 18.63109 -30.1338) (xy 197.595716 -30.1338)
			(xy 197.599747 -30.049172) (xy 197.611805 -29.965311) (xy 197.631779 -29.882976) (xy 197.65949 -29.802912)
			(xy 197.694686 -29.725844) (xy 197.737048 -29.652472) (xy 197.786193 -29.583458) (xy 197.841676 -29.519429)
			(xy 197.902994 -29.460963) (xy 197.969592 -29.408591) (xy 198.040866 -29.362787) (xy 198.116172 -29.323965)
			(xy 198.194827 -29.292477) (xy 198.276119 -29.268609) (xy 198.359312 -29.252576) (xy 198.443652 -29.244524)
			(xy 198.486014 -29.244036) (xy 198.524304 -29.244437) (xy 198.600598 -29.251046) (xy 198.676041 -29.264197)
			(xy 198.750071 -29.283791) (xy 198.786242 -29.29636) (xy 198.794679 -29.299011) (xy 198.812349 -29.299011)
			(xy 198.820786 -29.29636) (xy 198.856961 -29.283808) (xy 198.930995 -29.264238) (xy 199.006435 -29.251093)
			(xy 199.082726 -29.244471) (xy 199.121014 -29.244036) (xy 199.159304 -29.244437) (xy 199.235598 -29.251046)
			(xy 199.311041 -29.264197) (xy 199.385071 -29.283791) (xy 199.421242 -29.29636) (xy 199.429679 -29.299011)
			(xy 199.447349 -29.299011) (xy 199.455786 -29.29636) (xy 199.491961 -29.283808) (xy 199.565995 -29.264238)
			(xy 199.641435 -29.251093) (xy 199.717726 -29.244471) (xy 199.756014 -29.244036) (xy 199.794304 -29.244437)
			(xy 199.870598 -29.251046) (xy 199.946041 -29.264197) (xy 200.020071 -29.283791) (xy 200.056242 -29.29636)
			(xy 200.064679 -29.299011) (xy 200.082349 -29.299011) (xy 200.090786 -29.29636) (xy 200.126961 -29.283808)
			(xy 200.200995 -29.264238) (xy 200.276435 -29.251093) (xy 200.352726 -29.244471) (xy 200.391014 -29.244036)
			(xy 200.431702 -29.244422) (xy 200.512738 -29.251848) (xy 200.592757 -29.266645) (xy 200.67109 -29.288689)
			(xy 200.747082 -29.317797) (xy 200.820096 -29.353725) (xy 200.889524 -29.396173) (xy 200.954784 -29.444785)
			(xy 201.015331 -29.499155) (xy 201.070657 -29.558829) (xy 201.120302 -29.623307) (xy 201.163849 -29.69205)
			(xy 201.200934 -29.764484) (xy 201.216514 -29.802074) (xy 201.22098 -29.811942) (xy 201.236608 -29.826918)
			(xy 201.256995 -29.83419) (xy 201.267822 -29.833824) (xy 201.286077 -29.832403) (xy 201.322664 -29.83088)
			(xy 201.340974 -29.830776) (xy 201.383338 -29.831187) (xy 201.467682 -29.839239) (xy 201.550879 -29.855272)
			(xy 201.632176 -29.87914) (xy 201.710835 -29.910629) (xy 201.786145 -29.949452) (xy 201.857423 -29.995258)
			(xy 201.924025 -30.047632) (xy 201.985346 -30.1061) (xy 202.040832 -30.170132) (xy 202.08998 -30.239149)
			(xy 202.132344 -30.312525) (xy 202.167542 -30.389596) (xy 202.195254 -30.469663) (xy 202.21523 -30.552003)
			(xy 202.227288 -30.635868) (xy 202.23132 -30.7205) (xy 202.227288 -30.805132) (xy 202.21523 -30.888997)
			(xy 202.195254 -30.971337) (xy 202.167542 -31.051404) (xy 202.132344 -31.128475) (xy 202.08998 -31.201851)
			(xy 202.040832 -31.270868) (xy 201.985346 -31.3349) (xy 201.924025 -31.393368) (xy 201.857423 -31.445742)
			(xy 201.786145 -31.491548) (xy 201.710835 -31.530371) (xy 201.632176 -31.56186) (xy 201.550879 -31.585728)
			(xy 201.467682 -31.601761) (xy 201.383338 -31.609813) (xy 201.340974 -31.6103) (xy 201.302684 -31.609905)
			(xy 201.226389 -31.603295) (xy 201.150947 -31.590142) (xy 201.076917 -31.570546) (xy 201.040746 -31.557976)
			(xy 201.032309 -31.555325) (xy 201.014639 -31.555325) (xy 201.006202 -31.557976) (xy 200.970027 -31.570528)
			(xy 200.895993 -31.590099) (xy 200.820553 -31.603244) (xy 200.744262 -31.609866) (xy 200.705974 -31.6103)
			(xy 200.667684 -31.609905) (xy 200.591389 -31.603295) (xy 200.515947 -31.590142) (xy 200.441917 -31.570546)
			(xy 200.405746 -31.557976) (xy 200.397309 -31.555325) (xy 200.379639 -31.555325) (xy 200.371202 -31.557976)
			(xy 200.335027 -31.570528) (xy 200.260993 -31.590099) (xy 200.185553 -31.603244) (xy 200.109262 -31.609866)
			(xy 200.070974 -31.6103) (xy 200.032684 -31.609905) (xy 199.956389 -31.603295) (xy 199.880947 -31.590142)
			(xy 199.806917 -31.570546) (xy 199.770746 -31.557976) (xy 199.762309 -31.555325) (xy 199.744639 -31.555325)
			(xy 199.736202 -31.557976) (xy 199.700027 -31.570528) (xy 199.625993 -31.590099) (xy 199.550553 -31.603244)
			(xy 199.474262 -31.609866) (xy 199.435974 -31.6103) (xy 199.395288 -31.609814) (xy 199.314256 -31.602396)
			(xy 199.23424 -31.587608) (xy 199.15591 -31.565572) (xy 199.07992 -31.536472) (xy 199.006906 -31.500553)
			(xy 198.937478 -31.458114) (xy 198.872217 -31.40951) (xy 198.81167 -31.355148) (xy 198.756341 -31.295482)
			(xy 198.706694 -31.231012) (xy 198.663144 -31.162275) (xy 198.626056 -31.089848) (xy 198.610474 -31.052262)
			(xy 198.605924 -31.042441) (xy 198.590335 -31.027459) (xy 198.569982 -31.020164) (xy 198.559166 -31.020512)
			(xy 198.540911 -31.021927) (xy 198.504324 -31.023454) (xy 198.486014 -31.02356) (xy 198.443652 -31.023076)
			(xy 198.359312 -31.015024) (xy 198.276119 -30.998991) (xy 198.194827 -30.975123) (xy 198.116172 -30.943635)
			(xy 198.040866 -30.904813) (xy 197.969592 -30.859009) (xy 197.902994 -30.806637) (xy 197.841676 -30.748171)
			(xy 197.786193 -30.684142) (xy 197.737048 -30.615128) (xy 197.694686 -30.541756) (xy 197.65949 -30.464688)
			(xy 197.631779 -30.384624) (xy 197.611805 -30.302289) (xy 197.599747 -30.218428) (xy 197.595716 -30.1338)
			(xy 18.63109 -30.1338) (xy 18.633025 -30.16973) (xy 18.633652 -30.329344) (xy 18.626321 -30.488792)
			(xy 18.611051 -30.647675) (xy 18.587881 -30.8056) (xy 18.556867 -30.962174) (xy 18.518086 -31.117007)
			(xy 18.471636 -31.269714) (xy 18.417631 -31.419917) (xy 18.356206 -31.56724) (xy 18.287514 -31.711318)
			(xy 18.211725 -31.851793) (xy 18.129028 -31.988316) (xy 18.039629 -32.120546) (xy 17.943749 -32.248156)
			(xy 17.841627 -32.370828) (xy 17.733517 -32.488256) (xy 17.619688 -32.60015) (xy 17.500423 -32.70623)
			(xy 17.376019 -32.806234) (xy 17.246784 -32.899911) (xy 17.173557 -32.94761) (xy 102.642416 -32.94761)
			(xy 102.642416 -31.95701) (xy 102.642902 -31.929759) (xy 102.650658 -31.875811) (xy 102.666013 -31.823516)
			(xy 102.688655 -31.773939) (xy 102.718121 -31.728089) (xy 102.753812 -31.686898) (xy 102.795003 -31.651207)
			(xy 102.840853 -31.621741) (xy 102.89043 -31.599099) (xy 102.942725 -31.583744) (xy 102.996673 -31.575988)
			(xy 103.051175 -31.575988) (xy 103.105123 -31.583744) (xy 103.157418 -31.599099) (xy 103.206995 -31.621741)
			(xy 103.252845 -31.651207) (xy 103.294036 -31.686898) (xy 103.329727 -31.728089) (xy 103.359193 -31.773939)
			(xy 103.381835 -31.823516) (xy 103.39719 -31.875811) (xy 103.404946 -31.929759) (xy 103.405432 -31.95701)
			(xy 103.405432 -32.405066) (xy 105.659936 -32.405066) (xy 105.659936 -31.541466) (xy 105.660422 -31.514215)
			(xy 105.668178 -31.460267) (xy 105.683533 -31.407972) (xy 105.706175 -31.358395) (xy 105.735641 -31.312545)
			(xy 105.771332 -31.271354) (xy 105.812523 -31.235663) (xy 105.858373 -31.206197) (xy 105.90795 -31.183555)
			(xy 105.960245 -31.1682) (xy 106.014193 -31.160444) (xy 106.068695 -31.160444) (xy 106.122643 -31.1682)
			(xy 106.174938 -31.183555) (xy 106.224515 -31.206197) (xy 106.270365 -31.235663) (xy 106.311556 -31.271354)
			(xy 106.347247 -31.312545) (xy 106.376713 -31.358395) (xy 106.399355 -31.407972) (xy 106.41471 -31.460267)
			(xy 106.422466 -31.514215) (xy 106.422952 -31.541466) (xy 106.422952 -31.65856) (xy 140.278612 -31.65856)
			(xy 140.278612 -30.79496) (xy 140.279098 -30.767709) (xy 140.286854 -30.713761) (xy 140.302209 -30.661466)
			(xy 140.324851 -30.611889) (xy 140.354317 -30.566039) (xy 140.390008 -30.524848) (xy 140.431199 -30.489157)
			(xy 140.477049 -30.459691) (xy 140.526626 -30.437049) (xy 140.578921 -30.421694) (xy 140.632869 -30.413938)
			(xy 140.687371 -30.413938) (xy 140.741319 -30.421694) (xy 140.793614 -30.437049) (xy 140.843191 -30.459691)
			(xy 140.889041 -30.489157) (xy 140.930232 -30.524848) (xy 140.965923 -30.566039) (xy 140.995389 -30.611889)
			(xy 141.018031 -30.661466) (xy 141.033386 -30.713761) (xy 141.041142 -30.767709) (xy 141.041628 -30.79496)
			(xy 141.041628 -31.65856) (xy 141.041311 -31.67634) (xy 144.616932 -31.67634) (xy 144.616932 -30.81274)
			(xy 144.617418 -30.785489) (xy 144.625174 -30.731541) (xy 144.640529 -30.679246) (xy 144.663171 -30.629669)
			(xy 144.692637 -30.583819) (xy 144.728328 -30.542628) (xy 144.769519 -30.506937) (xy 144.815369 -30.477471)
			(xy 144.864946 -30.454829) (xy 144.917241 -30.439474) (xy 144.971189 -30.431718) (xy 145.025691 -30.431718)
			(xy 145.079639 -30.439474) (xy 145.131934 -30.454829) (xy 145.181511 -30.477471) (xy 145.227361 -30.506937)
			(xy 145.268552 -30.542628) (xy 145.304243 -30.583819) (xy 145.333709 -30.629669) (xy 145.356351 -30.679246)
			(xy 145.371706 -30.731541) (xy 145.379462 -30.785489) (xy 145.379948 -30.81274) (xy 145.379948 -31.67634)
			(xy 145.379462 -31.703591) (xy 145.371706 -31.757539) (xy 145.356351 -31.809834) (xy 145.333709 -31.859411)
			(xy 145.304243 -31.905261) (xy 145.268552 -31.946452) (xy 145.227361 -31.982143) (xy 145.181511 -32.011609)
			(xy 145.131934 -32.034251) (xy 145.079639 -32.049606) (xy 145.025691 -32.057362) (xy 144.971189 -32.057362)
			(xy 144.917241 -32.049606) (xy 144.864946 -32.034251) (xy 144.815369 -32.011609) (xy 144.769519 -31.982143)
			(xy 144.728328 -31.946452) (xy 144.692637 -31.905261) (xy 144.663171 -31.859411) (xy 144.640529 -31.809834)
			(xy 144.625174 -31.757539) (xy 144.617418 -31.703591) (xy 144.616932 -31.67634) (xy 141.041311 -31.67634)
			(xy 141.041142 -31.685811) (xy 141.033386 -31.739759) (xy 141.018031 -31.792054) (xy 140.995389 -31.841631)
			(xy 140.965923 -31.887481) (xy 140.930232 -31.928672) (xy 140.889041 -31.964363) (xy 140.843191 -31.993829)
			(xy 140.793614 -32.016471) (xy 140.741319 -32.031826) (xy 140.687371 -32.039582) (xy 140.632869 -32.039582)
			(xy 140.578921 -32.031826) (xy 140.526626 -32.016471) (xy 140.477049 -31.993829) (xy 140.431199 -31.964363)
			(xy 140.390008 -31.928672) (xy 140.354317 -31.887481) (xy 140.324851 -31.841631) (xy 140.302209 -31.792054)
			(xy 140.286854 -31.739759) (xy 140.279098 -31.685811) (xy 140.278612 -31.65856) (xy 106.422952 -31.65856)
			(xy 106.422952 -32.405066) (xy 106.422466 -32.432317) (xy 106.41471 -32.486265) (xy 106.399355 -32.53856)
			(xy 106.376713 -32.588137) (xy 106.347247 -32.633987) (xy 106.311556 -32.675178) (xy 106.270365 -32.710869)
			(xy 106.224515 -32.740335) (xy 106.174938 -32.762977) (xy 106.122643 -32.778332) (xy 106.068695 -32.786088)
			(xy 106.014193 -32.786088) (xy 105.960245 -32.778332) (xy 105.90795 -32.762977) (xy 105.858373 -32.740335)
			(xy 105.812523 -32.710869) (xy 105.771332 -32.675178) (xy 105.735641 -32.633987) (xy 105.706175 -32.588137)
			(xy 105.683533 -32.53856) (xy 105.668178 -32.486265) (xy 105.660422 -32.432317) (xy 105.659936 -32.405066)
			(xy 103.405432 -32.405066) (xy 103.405432 -32.94761) (xy 103.404946 -32.974861) (xy 103.39719 -33.028809)
			(xy 103.390276 -33.052356) (xy 119.734235 -33.052356) (xy 119.734235 -32.997844) (xy 119.741993 -32.943888)
			(xy 119.757352 -32.891585) (xy 119.779997 -32.842) (xy 119.80947 -32.796143) (xy 119.845169 -32.754947)
			(xy 119.886367 -32.719252) (xy 119.932226 -32.689783) (xy 119.981813 -32.667141) (xy 120.034117 -32.651787)
			(xy 120.088074 -32.644033) (xy 120.11533 -32.643572) (xy 120.97893 -32.643572) (xy 121.006178 -32.6441)
			(xy 121.06012 -32.65186) (xy 121.112408 -32.667217) (xy 121.161979 -32.689858) (xy 121.207823 -32.719324)
			(xy 121.249008 -32.755014) (xy 121.284694 -32.796201) (xy 121.314156 -32.842047) (xy 121.336794 -32.89162)
			(xy 121.352147 -32.943909) (xy 121.359902 -32.997852) (xy 121.359902 -33.052348) (xy 121.352147 -33.106291)
			(xy 121.336794 -33.15858) (xy 121.314156 -33.208153) (xy 121.284694 -33.253999) (xy 121.249008 -33.295186)
			(xy 121.207823 -33.330876) (xy 121.161979 -33.360342) (xy 121.112408 -33.382983) (xy 121.06012 -33.39834)
			(xy 121.006178 -33.4061) (xy 120.97893 -33.406588) (xy 120.11533 -33.406588) (xy 120.088074 -33.406167)
			(xy 120.034117 -33.398413) (xy 119.981813 -33.383059) (xy 119.932226 -33.360417) (xy 119.886367 -33.330948)
			(xy 119.845169 -33.295253) (xy 119.80947 -33.254057) (xy 119.779997 -33.2082) (xy 119.757352 -33.158615)
			(xy 119.741993 -33.106312) (xy 119.734235 -33.052356) (xy 103.390276 -33.052356) (xy 103.381835 -33.081104)
			(xy 103.359193 -33.130681) (xy 103.329727 -33.176531) (xy 103.294036 -33.217722) (xy 103.252845 -33.253413)
			(xy 103.206995 -33.282879) (xy 103.157418 -33.305521) (xy 103.105123 -33.320876) (xy 103.051175 -33.328632)
			(xy 102.996673 -33.328632) (xy 102.942725 -33.320876) (xy 102.89043 -33.305521) (xy 102.840853 -33.282879)
			(xy 102.795003 -33.253413) (xy 102.753812 -33.217722) (xy 102.718121 -33.176531) (xy 102.688655 -33.130681)
			(xy 102.666013 -33.081104) (xy 102.650658 -33.028809) (xy 102.642902 -32.974861) (xy 102.642416 -32.94761)
			(xy 17.173557 -32.94761) (xy 17.11304 -32.98703) (xy 16.975119 -33.067374) (xy 16.833366 -33.140743)
			(xy 16.688131 -33.206955) (xy 16.539776 -33.265845) (xy 16.38867 -33.317266) (xy 16.235188 -33.361091)
			(xy 16.079713 -33.397211) (xy 15.922631 -33.425536) (xy 15.764332 -33.445995) (xy 15.605209 -33.458538)
			(xy 15.44566 -33.463134) (xy 15.286079 -33.459771) (xy 15.126865 -33.448457) (xy 14.968413 -33.42922)
			(xy 14.811116 -33.402109) (xy 14.655367 -33.367191) (xy 14.501552 -33.324553) (xy 14.350053 -33.2743)
			(xy 14.201248 -33.216557) (xy 14.055506 -33.151469) (xy 13.91319 -33.079197) (xy 13.774653 -32.999921)
			(xy 13.64024 -32.913837) (xy 13.510286 -32.82116) (xy 13.385112 -32.72212) (xy 13.265032 -32.616964)
			(xy 13.150342 -32.505953) (xy 13.095478 -32.447992) (xy 12.00277 -31.279592) (xy 11.948692 -31.220903)
			(xy 11.845626 -31.099035) (xy 11.748763 -30.972182) (xy 11.658343 -30.840658) (xy 11.574591 -30.704792)
			(xy 11.497716 -30.564919) (xy 11.427907 -30.421388) (xy 11.36534 -30.274557) (xy 11.310169 -30.124789)
			(xy 11.262532 -29.972457) (xy 11.222547 -29.81794) (xy 11.190314 -29.661623) (xy 11.165912 -29.503893)
			(xy 11.149402 -29.345143) (xy 11.140826 -29.185767) (xy 11.140205 -29.026161) (xy 0.509016 -29.026161)
			(xy 0.509016 -33.838388) (xy 122.111008 -33.838388) (xy 122.111008 -32.974788) (xy 122.111494 -32.947519)
			(xy 122.119256 -32.893535) (xy 122.134621 -32.841205) (xy 122.157278 -32.791595) (xy 122.186764 -32.745714)
			(xy 122.222479 -32.704497) (xy 122.263696 -32.668782) (xy 122.309577 -32.639296) (xy 122.359187 -32.616639)
			(xy 122.411517 -32.601274) (xy 122.465501 -32.593512) (xy 122.520039 -32.593512) (xy 122.574023 -32.601274)
			(xy 122.626353 -32.616639) (xy 122.675963 -32.639296) (xy 122.721844 -32.668782) (xy 122.763061 -32.704497)
			(xy 122.798776 -32.745714) (xy 122.828262 -32.791595) (xy 122.850919 -32.841205) (xy 122.866284 -32.893535)
			(xy 122.874046 -32.947519) (xy 122.874532 -32.974788) (xy 122.874532 -33.413556) (xy 124.175423 -33.413556)
			(xy 124.175423 -33.359044) (xy 124.183181 -33.305087) (xy 124.198539 -33.252783) (xy 124.221185 -33.203197)
			(xy 124.250658 -33.157339) (xy 124.286357 -33.116142) (xy 124.327555 -33.080446) (xy 124.373415 -33.050976)
			(xy 124.423002 -33.028332) (xy 124.475306 -33.012977) (xy 124.529264 -33.005222) (xy 124.55652 -33.00476)
			(xy 125.42012 -33.00476) (xy 125.447368 -33.005312) (xy 125.501309 -33.01307) (xy 125.553597 -33.028425)
			(xy 125.603167 -33.051066) (xy 125.649011 -33.08053) (xy 125.690196 -33.116218) (xy 125.725882 -33.157405)
			(xy 125.755344 -33.20325) (xy 125.777982 -33.252822) (xy 125.793335 -33.305111) (xy 125.80109 -33.359052)
			(xy 125.80109 -33.413548) (xy 125.793335 -33.467489) (xy 125.777982 -33.519778) (xy 125.755344 -33.56935)
			(xy 125.725882 -33.615195) (xy 125.690196 -33.656382) (xy 125.649011 -33.69207) (xy 125.603167 -33.721534)
			(xy 125.553597 -33.744175) (xy 125.501309 -33.75953) (xy 125.447368 -33.767288) (xy 125.42012 -33.767776)
			(xy 124.55652 -33.767776) (xy 124.529264 -33.767378) (xy 124.475306 -33.759623) (xy 124.423002 -33.744268)
			(xy 124.373415 -33.721624) (xy 124.327555 -33.692154) (xy 124.286357 -33.656458) (xy 124.250658 -33.615261)
			(xy 124.221185 -33.569403) (xy 124.198539 -33.519817) (xy 124.183181 -33.467513) (xy 124.175423 -33.413556)
			(xy 122.874532 -33.413556) (xy 122.874532 -33.838388) (xy 122.874046 -33.865657) (xy 122.866284 -33.919641)
			(xy 122.850919 -33.971971) (xy 122.828262 -34.021581) (xy 122.798776 -34.067462) (xy 122.763061 -34.108679)
			(xy 122.721844 -34.144394) (xy 122.675963 -34.17388) (xy 122.626353 -34.196537) (xy 122.574023 -34.211902)
			(xy 122.520039 -34.219664) (xy 122.465501 -34.219664) (xy 122.411517 -34.211902) (xy 122.359187 -34.196537)
			(xy 122.309577 -34.17388) (xy 122.263696 -34.144394) (xy 122.222479 -34.108679) (xy 122.186764 -34.067462)
			(xy 122.157278 -34.021581) (xy 122.134621 -33.971971) (xy 122.119256 -33.919641) (xy 122.111494 -33.865657)
			(xy 122.111008 -33.838388) (xy 0.509016 -33.838388) (xy 0.509016 -36.080556) (xy 122.143423 -36.080556)
			(xy 122.143423 -36.026044) (xy 122.151181 -35.972087) (xy 122.166539 -35.919783) (xy 122.189185 -35.870197)
			(xy 122.218658 -35.824339) (xy 122.254357 -35.783142) (xy 122.295555 -35.747446) (xy 122.341415 -35.717976)
			(xy 122.391002 -35.695332) (xy 122.443306 -35.679977) (xy 122.497264 -35.672222) (xy 122.52452 -35.67176)
			(xy 123.38812 -35.67176) (xy 123.415368 -35.672312) (xy 123.469309 -35.68007) (xy 123.521597 -35.695425)
			(xy 123.571167 -35.718066) (xy 123.617011 -35.74753) (xy 123.658196 -35.783218) (xy 123.693882 -35.824405)
			(xy 123.723344 -35.87025) (xy 123.745982 -35.919822) (xy 123.761335 -35.972111) (xy 123.76909 -36.026052)
			(xy 123.76909 -36.080548) (xy 123.761335 -36.134489) (xy 123.745982 -36.186778) (xy 123.723344 -36.23635)
			(xy 123.693882 -36.282195) (xy 123.658196 -36.323382) (xy 123.617011 -36.35907) (xy 123.571167 -36.388534)
			(xy 123.521597 -36.411175) (xy 123.469309 -36.42653) (xy 123.415368 -36.434288) (xy 123.38812 -36.434776)
			(xy 122.52452 -36.434776) (xy 122.497264 -36.434378) (xy 122.443306 -36.426623) (xy 122.391002 -36.411268)
			(xy 122.341415 -36.388624) (xy 122.295555 -36.359154) (xy 122.254357 -36.323458) (xy 122.218658 -36.282261)
			(xy 122.189185 -36.236403) (xy 122.166539 -36.186817) (xy 122.151181 -36.134513) (xy 122.143423 -36.080556)
			(xy 0.509016 -36.080556) (xy 0.509016 -39.23137) (xy 9.080235 -39.23137) (xy 9.080235 -39.10223)
			(xy 9.088185 -38.973335) (xy 9.104055 -38.845175) (xy 9.127784 -38.718234) (xy 9.159283 -38.592995)
			(xy 9.198432 -38.469932) (xy 9.245083 -38.349513) (xy 9.299058 -38.232194) (xy 9.360153 -38.11842)
			(xy 9.428136 -38.008623) (xy 9.50275 -37.90322) (xy 9.583711 -37.80261) (xy 9.670711 -37.707175)
			(xy 9.763422 -37.617276) (xy 9.861492 -37.533255) (xy 9.964547 -37.455431) (xy 10.072198 -37.384099)
			(xy 10.184037 -37.319529) (xy 10.299638 -37.261967) (xy 10.418563 -37.21163) (xy 10.540362 -37.16871)
			(xy 10.664572 -37.133369) (xy 10.790721 -37.105742) (xy 10.918333 -37.085933) (xy 11.046922 -37.074017)
			(xy 11.176 -37.070041) (xy 11.305078 -37.074017) (xy 11.433667 -37.085933) (xy 11.521898 -37.099629)
			(xy 170.60087 -37.099629) (xy 170.60087 -37.000299) (xy 170.608862 -36.901292) (xy 170.624796 -36.803249)
			(xy 170.648567 -36.706806) (xy 170.680022 -36.612588) (xy 170.718955 -36.521208) (xy 170.765116 -36.433256)
			(xy 170.818204 -36.349304) (xy 170.877875 -36.269895) (xy 170.943743 -36.195546) (xy 171.01538 -36.126738)
			(xy 171.092321 -36.063918) (xy 171.174067 -36.007493) (xy 171.260089 -35.957828) (xy 171.349828 -35.915246)
			(xy 171.442702 -35.880024) (xy 171.53811 -35.852388) (xy 171.635432 -35.83252) (xy 171.734037 -35.820547)
			(xy 171.833286 -35.816548) (xy 171.932535 -35.820547) (xy 172.03114 -35.83252) (xy 172.128462 -35.852388)
			(xy 172.22387 -35.880024) (xy 172.316744 -35.915246) (xy 172.406483 -35.957828) (xy 172.492505 -36.007493)
			(xy 172.574251 -36.063918) (xy 172.651192 -36.126738) (xy 172.722829 -36.195546) (xy 172.788697 -36.269895)
			(xy 172.848368 -36.349304) (xy 172.901456 -36.433256) (xy 172.947617 -36.521208) (xy 172.98655 -36.612588)
			(xy 173.018005 -36.706806) (xy 173.041776 -36.803249) (xy 173.05771 -36.901292) (xy 173.065702 -37.000299)
			(xy 173.066202 -37.049964) (xy 173.065702 -37.099629) (xy 173.05771 -37.198636) (xy 173.041776 -37.296679)
			(xy 173.034033 -37.328094) (xy 197.270624 -37.328094) (xy 197.271107 -37.28698) (xy 197.278695 -37.205103)
			(xy 197.293804 -37.124275) (xy 197.316307 -37.045187) (xy 197.346011 -36.968512) (xy 197.382664 -36.894904)
			(xy 197.425951 -36.824993) (xy 197.475504 -36.759373) (xy 197.5309 -36.698606) (xy 197.591667 -36.643209)
			(xy 197.657286 -36.593655) (xy 197.727197 -36.550367) (xy 197.800804 -36.513715) (xy 197.877479 -36.48401)
			(xy 197.956568 -36.461506) (xy 198.037395 -36.446396) (xy 198.119272 -36.438808) (xy 198.160386 -36.438332)
			(xy 198.203952 -36.438853) (xy 198.290667 -36.447372) (xy 198.376134 -36.464329) (xy 198.459533 -36.489562)
			(xy 198.540065 -36.522829) (xy 198.616958 -36.563811) (xy 198.689475 -36.612116) (xy 198.756921 -36.66728)
			(xy 198.81865 -36.728775) (xy 198.87407 -36.796011) (xy 198.922649 -36.868345) (xy 198.963923 -36.945081)
			(xy 198.997496 -37.025486) (xy 199.010778 -37.066982) (xy 199.013703 -37.075249) (xy 199.024271 -37.089233)
			(xy 199.038923 -37.098854) (xy 199.047354 -37.101272) (xy 199.088321 -37.111837) (xy 199.168226 -37.13965)
			(xy 199.24513 -37.174922) (xy 199.318339 -37.217334) (xy 199.387193 -37.266504) (xy 199.451068 -37.321986)
			(xy 199.509389 -37.383281) (xy 199.529427 -37.408809) (xy 207.619596 -37.408809) (xy 207.619596 -37.324087)
			(xy 207.627649 -37.23975) (xy 207.643683 -37.15656) (xy 207.667551 -37.07527) (xy 207.699039 -36.996618)
			(xy 207.737861 -36.921315) (xy 207.783664 -36.850043) (xy 207.836035 -36.783447) (xy 207.8945 -36.722132)
			(xy 207.958528 -36.666651) (xy 208.02754 -36.617508) (xy 208.10091 -36.575148) (xy 208.177975 -36.539953)
			(xy 208.258037 -36.512244) (xy 208.34037 -36.49227) (xy 208.424229 -36.480213) (xy 208.508854 -36.476182)
			(xy 208.593479 -36.480213) (xy 208.677338 -36.49227) (xy 208.759671 -36.512244) (xy 208.839733 -36.539953)
			(xy 208.916798 -36.575148) (xy 208.990168 -36.617508) (xy 209.05918 -36.666651) (xy 209.123208 -36.722132)
			(xy 209.181673 -36.783447) (xy 209.234044 -36.850043) (xy 209.279847 -36.921315) (xy 209.318669 -36.996618)
			(xy 209.350157 -37.07527) (xy 209.374025 -37.15656) (xy 209.390059 -37.23975) (xy 209.398112 -37.324087)
			(xy 209.398616 -37.366448) (xy 209.398112 -37.408809) (xy 209.390059 -37.493146) (xy 209.374025 -37.576336)
			(xy 209.350157 -37.657626) (xy 209.318669 -37.736278) (xy 209.279847 -37.811581) (xy 209.234044 -37.882853)
			(xy 209.181673 -37.949449) (xy 209.123208 -38.010764) (xy 209.05918 -38.066245) (xy 208.990168 -38.115388)
			(xy 208.916798 -38.157748) (xy 208.839733 -38.192943) (xy 208.759671 -38.220652) (xy 208.677338 -38.240626)
			(xy 208.593479 -38.252683) (xy 208.508854 -38.256715) (xy 208.424229 -38.252683) (xy 208.34037 -38.240626)
			(xy 208.258037 -38.220652) (xy 208.177975 -38.192943) (xy 208.10091 -38.157748) (xy 208.02754 -38.115388)
			(xy 207.958528 -38.066245) (xy 207.8945 -38.010764) (xy 207.836035 -37.949449) (xy 207.783664 -37.882853)
			(xy 207.737861 -37.811581) (xy 207.699039 -37.736278) (xy 207.667551 -37.657626) (xy 207.643683 -37.576336)
			(xy 207.627649 -37.493146) (xy 207.619596 -37.408809) (xy 199.529427 -37.408809) (xy 199.561629 -37.449835)
			(xy 199.607316 -37.521047) (xy 199.646037 -37.596273) (xy 199.677444 -37.674835) (xy 199.701252 -37.756024)
			(xy 199.717247 -37.839106) (xy 199.725284 -37.92333) (xy 199.725788 -37.965634) (xy 199.72532 -38.006748)
			(xy 199.71773 -38.088625) (xy 199.702618 -38.169453) (xy 199.680113 -38.248541) (xy 199.650407 -38.325216)
			(xy 199.613754 -38.398823) (xy 199.570465 -38.468734) (xy 199.520911 -38.534353) (xy 199.465514 -38.595119)
			(xy 199.404746 -38.650516) (xy 199.339127 -38.70007) (xy 199.269216 -38.743357) (xy 199.195608 -38.78001)
			(xy 199.118933 -38.809716) (xy 199.039845 -38.83222) (xy 198.959017 -38.847331) (xy 198.87714 -38.85492)
			(xy 198.836026 -38.855396) (xy 198.792461 -38.854844) (xy 198.705747 -38.846327) (xy 198.620282 -38.829372)
			(xy 198.536884 -38.804141) (xy 198.456353 -38.770876) (xy 198.379461 -38.729896) (xy 198.306944 -38.681594)
			(xy 198.239498 -38.626432) (xy 198.177769 -38.56494) (xy 198.122348 -38.497707) (xy 198.073767 -38.425377)
			(xy 198.032492 -38.348643) (xy 197.998917 -38.26824) (xy 197.985634 -38.226746) (xy 197.982688 -38.218487)
			(xy 197.97213 -38.204501) (xy 197.957486 -38.194877) (xy 197.949058 -38.192456) (xy 197.908101 -38.181857)
			(xy 197.828197 -38.154046) (xy 197.751293 -38.118776) (xy 197.678085 -38.076367) (xy 197.609232 -38.0272)
			(xy 197.545356 -37.97172) (xy 197.487035 -37.910428) (xy 197.434795 -37.843877) (xy 197.389107 -37.772668)
			(xy 197.350384 -37.697444) (xy 197.318976 -37.618885) (xy 197.295165 -37.537699) (xy 197.279169 -37.454619)
			(xy 197.271129 -37.370397) (xy 197.270624 -37.328094) (xy 173.034033 -37.328094) (xy 173.018005 -37.393122)
			(xy 172.98655 -37.48734) (xy 172.947617 -37.57872) (xy 172.901456 -37.666672) (xy 172.848368 -37.750624)
			(xy 172.788697 -37.830033) (xy 172.722829 -37.904382) (xy 172.651192 -37.97319) (xy 172.574251 -38.03601)
			(xy 172.492505 -38.092435) (xy 172.406483 -38.1421) (xy 172.316744 -38.184682) (xy 172.22387 -38.219904)
			(xy 172.128462 -38.24754) (xy 172.03114 -38.267408) (xy 171.932535 -38.279381) (xy 171.833286 -38.283381)
			(xy 171.734037 -38.279381) (xy 171.635432 -38.267408) (xy 171.53811 -38.24754) (xy 171.442702 -38.219904)
			(xy 171.349828 -38.184682) (xy 171.260089 -38.1421) (xy 171.174067 -38.092435) (xy 171.092321 -38.03601)
			(xy 171.01538 -37.97319) (xy 170.943743 -37.904382) (xy 170.877875 -37.830033) (xy 170.818204 -37.750624)
			(xy 170.765116 -37.666672) (xy 170.718955 -37.57872) (xy 170.680022 -37.48734) (xy 170.648567 -37.393122)
			(xy 170.624796 -37.296679) (xy 170.608862 -37.198636) (xy 170.60087 -37.099629) (xy 11.521898 -37.099629)
			(xy 11.561279 -37.105742) (xy 11.687428 -37.133369) (xy 11.811638 -37.16871) (xy 11.933437 -37.21163)
			(xy 12.052362 -37.261967) (xy 12.167963 -37.319529) (xy 12.279802 -37.384099) (xy 12.387453 -37.455431)
			(xy 12.490508 -37.533255) (xy 12.588578 -37.617276) (xy 12.681289 -37.707175) (xy 12.768289 -37.80261)
			(xy 12.84925 -37.90322) (xy 12.923864 -38.008623) (xy 12.991847 -38.11842) (xy 13.052942 -38.232194)
			(xy 13.106917 -38.349513) (xy 13.153568 -38.469932) (xy 13.192717 -38.592995) (xy 13.224216 -38.718234)
			(xy 13.247945 -38.845175) (xy 13.263815 -38.973335) (xy 13.271765 -39.10223) (xy 13.272262 -39.1668)
			(xy 13.271765 -39.23137) (xy 13.263815 -39.360265) (xy 13.256012 -39.423283) (xy 254.45872 -39.423283)
			(xy 254.45872 -39.338561) (xy 254.466773 -39.254224) (xy 254.482807 -39.171034) (xy 254.506675 -39.089744)
			(xy 254.538163 -39.011092) (xy 254.576985 -38.935789) (xy 254.622788 -38.864517) (xy 254.675159 -38.797921)
			(xy 254.733624 -38.736606) (xy 254.797652 -38.681125) (xy 254.866664 -38.631982) (xy 254.940034 -38.589622)
			(xy 255.017099 -38.554427) (xy 255.097161 -38.526718) (xy 255.179494 -38.506744) (xy 255.263353 -38.494687)
			(xy 255.347978 -38.490656) (xy 255.432603 -38.494687) (xy 255.516462 -38.506744) (xy 255.598795 -38.526718)
			(xy 255.678857 -38.554427) (xy 255.755922 -38.589622) (xy 255.829292 -38.631982) (xy 255.898304 -38.681125)
			(xy 255.962332 -38.736606) (xy 256.020797 -38.797921) (xy 256.073168 -38.864517) (xy 256.118971 -38.935789)
			(xy 256.157793 -39.011092) (xy 256.189281 -39.089744) (xy 256.213149 -39.171034) (xy 256.229183 -39.254224)
			(xy 256.237236 -39.338561) (xy 256.23774 -39.380922) (xy 256.237236 -39.423283) (xy 256.229183 -39.50762)
			(xy 256.213149 -39.59081) (xy 256.189281 -39.6721) (xy 256.157793 -39.750752) (xy 256.118971 -39.826055)
			(xy 256.073168 -39.897327) (xy 256.020797 -39.963923) (xy 255.962332 -40.025238) (xy 255.898304 -40.080719)
			(xy 255.829292 -40.129862) (xy 255.755922 -40.172222) (xy 255.678857 -40.207417) (xy 255.598795 -40.235126)
			(xy 255.516462 -40.2551) (xy 255.432603 -40.267157) (xy 255.347978 -40.271189) (xy 255.263353 -40.267157)
			(xy 255.179494 -40.2551) (xy 255.097161 -40.235126) (xy 255.017099 -40.207417) (xy 254.940034 -40.172222)
			(xy 254.866664 -40.129862) (xy 254.797652 -40.080719) (xy 254.733624 -40.025238) (xy 254.675159 -39.963923)
			(xy 254.622788 -39.897327) (xy 254.576985 -39.826055) (xy 254.538163 -39.750752) (xy 254.506675 -39.6721)
			(xy 254.482807 -39.59081) (xy 254.466773 -39.50762) (xy 254.45872 -39.423283) (xy 13.256012 -39.423283)
			(xy 13.247945 -39.488425) (xy 13.224216 -39.615366) (xy 13.192717 -39.740605) (xy 13.153568 -39.863668)
			(xy 13.106917 -39.984087) (xy 13.052942 -40.101406) (xy 12.991847 -40.21518) (xy 12.923864 -40.324977)
			(xy 12.84925 -40.43038) (xy 12.768289 -40.53099) (xy 12.681289 -40.626425) (xy 12.588578 -40.716324)
			(xy 12.490508 -40.800345) (xy 12.413317 -40.858637) (xy 24.936192 -40.858637) (xy 24.936192 -40.773915)
			(xy 24.944245 -40.689578) (xy 24.960279 -40.606388) (xy 24.984147 -40.525098) (xy 25.015635 -40.446446)
			(xy 25.054457 -40.371143) (xy 25.10026 -40.299871) (xy 25.152631 -40.233275) (xy 25.211096 -40.17196)
			(xy 25.275124 -40.116479) (xy 25.344136 -40.067336) (xy 25.417506 -40.024976) (xy 25.494571 -39.989781)
			(xy 25.574633 -39.962072) (xy 25.656966 -39.942098) (xy 25.740825 -39.930041) (xy 25.82545 -39.92601)
			(xy 25.910075 -39.930041) (xy 25.993934 -39.942098) (xy 26.076267 -39.962072) (xy 26.156329 -39.989781)
			(xy 26.233394 -40.024976) (xy 26.306764 -40.067336) (xy 26.375776 -40.116479) (xy 26.439804 -40.17196)
			(xy 26.498269 -40.233275) (xy 26.55064 -40.299871) (xy 26.596443 -40.371143) (xy 26.635265 -40.446446)
			(xy 26.666753 -40.525098) (xy 26.690621 -40.606388) (xy 26.706655 -40.689578) (xy 26.711938 -40.744902)
			(xy 235.083357 -40.744902) (xy 235.087362 -40.656994) (xy 235.099345 -40.569814) (xy 235.119205 -40.484085)
			(xy 235.14678 -40.400517) (xy 235.181839 -40.319803) (xy 235.224092 -40.242611) (xy 235.27319 -40.169582)
			(xy 235.328726 -40.10132) (xy 235.390238 -40.03839) (xy 235.457219 -39.981316) (xy 235.529112 -39.930568)
			(xy 235.605321 -39.886568) (xy 235.685216 -39.849681) (xy 235.768135 -39.820212) (xy 235.85339 -39.798405)
			(xy 235.940274 -39.784441) (xy 236.028068 -39.778435) (xy 236.116045 -39.780439) (xy 236.203475 -39.790434)
			(xy 236.289634 -39.808338) (xy 236.373808 -39.834002) (xy 236.455299 -39.867215) (xy 236.533433 -39.907701)
			(xy 236.607561 -39.955123) (xy 236.677069 -40.00909) (xy 236.741383 -40.069155) (xy 236.799967 -40.134819)
			(xy 236.852338 -40.205538) (xy 236.898061 -40.280726) (xy 236.936758 -40.359761) (xy 236.968107 -40.441987)
			(xy 236.991849 -40.526723) (xy 237.007787 -40.613267) (xy 237.015789 -40.700902) (xy 237.01629 -40.744902)
			(xy 237.015789 -40.788902) (xy 237.007787 -40.876537) (xy 236.994276 -40.9499) (xy 246.935452 -40.9499)
			(xy 246.939482 -40.865295) (xy 246.951537 -40.781456) (xy 246.971506 -40.699142) (xy 246.999209 -40.619099)
			(xy 247.034396 -40.542053) (xy 247.076747 -40.468699) (xy 247.125879 -40.399704) (xy 247.181347 -40.335692)
			(xy 247.242648 -40.277242) (xy 247.309228 -40.224883) (xy 247.380484 -40.179091) (xy 247.45577 -40.14028)
			(xy 247.534404 -40.1088) (xy 247.615675 -40.084938) (xy 247.698846 -40.06891) (xy 247.783163 -40.060859)
			(xy 247.825514 -40.060372) (xy 247.868043 -40.060872) (xy 247.952713 -40.068982) (xy 248.036223 -40.085137)
			(xy 248.11781 -40.109189) (xy 248.196728 -40.140918) (xy 248.272258 -40.180035) (xy 248.343709 -40.226182)
			(xy 248.41043 -40.278938) (xy 248.441464 -40.308022) (xy 248.441718 -40.308276) (xy 248.44904 -40.314652)
			(xy 248.467069 -40.321822) (xy 248.47677 -40.322246) (xy 248.557288 -40.321992) (xy 248.575576 -40.314626)
			(xy 248.582688 -40.307514) (xy 248.613778 -40.278057) (xy 248.680689 -40.224588) (xy 248.752429 -40.177798)
			(xy 248.828335 -40.13812) (xy 248.907704 -40.105923) (xy 248.9898 -40.081504) (xy 249.073863 -40.065089)
			(xy 249.159115 -40.056831) (xy 249.20194 -40.056308) (xy 249.202448 -40.056308) (xy 249.244796 -40.056782)
			(xy 249.329107 -40.064837) (xy 249.412272 -40.08087) (xy 249.493536 -40.104735) (xy 249.572163 -40.136216)
			(xy 249.647442 -40.175029) (xy 249.718691 -40.220821) (xy 249.785265 -40.273178) (xy 249.84656 -40.331627)
			(xy 249.902022 -40.395637) (xy 249.951149 -40.464629) (xy 249.993496 -40.537978) (xy 250.028678 -40.615021)
			(xy 250.056379 -40.695058) (xy 250.076346 -40.777367) (xy 250.088399 -40.8612) (xy 250.092429 -40.9458)
			(xy 250.088399 -41.0304) (xy 250.076346 -41.114233) (xy 250.056379 -41.196542) (xy 250.028678 -41.276579)
			(xy 249.993496 -41.353622) (xy 249.951149 -41.426971) (xy 249.902022 -41.495963) (xy 249.84656 -41.559973)
			(xy 249.785265 -41.618422) (xy 249.718691 -41.670779) (xy 249.647442 -41.716571) (xy 249.572163 -41.755384)
			(xy 249.493536 -41.786865) (xy 249.412272 -41.81073) (xy 249.329107 -41.826763) (xy 249.244796 -41.834818)
			(xy 249.202448 -41.835324) (xy 249.159919 -41.834822) (xy 249.07525 -41.826709) (xy 248.991741 -41.810552)
			(xy 248.910155 -41.7865) (xy 248.831237 -41.754771) (xy 248.755707 -41.715655) (xy 248.684255 -41.66951)
			(xy 248.617533 -41.616756) (xy 248.586498 -41.587674) (xy 248.586244 -41.58742) (xy 248.578903 -41.58107)
			(xy 248.560888 -41.573885) (xy 248.551192 -41.57345) (xy 248.470674 -41.573704) (xy 248.452386 -41.58107)
			(xy 248.445274 -41.588182) (xy 248.414201 -41.617657) (xy 248.347287 -41.671125) (xy 248.275544 -41.717913)
			(xy 248.199635 -41.757589) (xy 248.120264 -41.789784) (xy 248.038166 -41.8142) (xy 247.954101 -41.830612)
			(xy 247.868848 -41.838866) (xy 247.826022 -41.839388) (xy 247.825514 -41.839388) (xy 247.783163 -41.838941)
			(xy 247.698846 -41.83089) (xy 247.615675 -41.814862) (xy 247.534404 -41.791) (xy 247.45577 -41.75952)
			(xy 247.380484 -41.720709) (xy 247.309228 -41.674917) (xy 247.242648 -41.622558) (xy 247.181347 -41.564108)
			(xy 247.125879 -41.500096) (xy 247.076747 -41.431101) (xy 247.034396 -41.357747) (xy 246.999209 -41.280701)
			(xy 246.971506 -41.200658) (xy 246.951537 -41.118344) (xy 246.939482 -41.034505) (xy 246.935452 -40.9499)
			(xy 236.994276 -40.9499) (xy 236.991849 -40.963081) (xy 236.968107 -41.047817) (xy 236.936758 -41.130043)
			(xy 236.898061 -41.209078) (xy 236.852338 -41.284266) (xy 236.799967 -41.354985) (xy 236.741383 -41.420649)
			(xy 236.677069 -41.480714) (xy 236.607561 -41.534681) (xy 236.533433 -41.582103) (xy 236.455299 -41.622589)
			(xy 236.373808 -41.655802) (xy 236.289634 -41.681466) (xy 236.203475 -41.69937) (xy 236.116045 -41.709365)
			(xy 236.028068 -41.711369) (xy 235.940274 -41.705363) (xy 235.85339 -41.691399) (xy 235.768135 -41.669592)
			(xy 235.685216 -41.640123) (xy 235.605321 -41.603236) (xy 235.529112 -41.559236) (xy 235.457219 -41.508488)
			(xy 235.390238 -41.451414) (xy 235.328726 -41.388484) (xy 235.27319 -41.320222) (xy 235.224092 -41.247193)
			(xy 235.181839 -41.170001) (xy 235.14678 -41.089287) (xy 235.119205 -41.005719) (xy 235.099345 -40.91999)
			(xy 235.087362 -40.83281) (xy 235.083357 -40.744902) (xy 26.711938 -40.744902) (xy 26.714708 -40.773915)
			(xy 26.715212 -40.816276) (xy 26.714708 -40.858637) (xy 26.706655 -40.942974) (xy 26.690621 -41.026164)
			(xy 26.666753 -41.107454) (xy 26.635265 -41.186106) (xy 26.596443 -41.261409) (xy 26.55064 -41.332681)
			(xy 26.498269 -41.399277) (xy 26.439804 -41.460592) (xy 26.375776 -41.516073) (xy 26.306764 -41.565216)
			(xy 26.233394 -41.607576) (xy 26.156329 -41.642771) (xy 26.076267 -41.67048) (xy 25.993934 -41.690454)
			(xy 25.910075 -41.702511) (xy 25.82545 -41.706543) (xy 25.740825 -41.702511) (xy 25.656966 -41.690454)
			(xy 25.574633 -41.67048) (xy 25.494571 -41.642771) (xy 25.417506 -41.607576) (xy 25.344136 -41.565216)
			(xy 25.275124 -41.516073) (xy 25.211096 -41.460592) (xy 25.152631 -41.399277) (xy 25.10026 -41.332681)
			(xy 25.054457 -41.261409) (xy 25.015635 -41.186106) (xy 24.984147 -41.107454) (xy 24.960279 -41.026164)
			(xy 24.944245 -40.942974) (xy 24.936192 -40.858637) (xy 12.413317 -40.858637) (xy 12.387453 -40.878169)
			(xy 12.279802 -40.949501) (xy 12.167963 -41.014071) (xy 12.052362 -41.071633) (xy 11.933437 -41.12197)
			(xy 11.811638 -41.16489) (xy 11.687428 -41.200231) (xy 11.561279 -41.227858) (xy 11.433667 -41.247667)
			(xy 11.305078 -41.259583) (xy 11.176 -41.26356) (xy 11.046922 -41.259583) (xy 10.918333 -41.247667)
			(xy 10.790721 -41.227858) (xy 10.664572 -41.200231) (xy 10.540362 -41.16489) (xy 10.418563 -41.12197)
			(xy 10.299638 -41.071633) (xy 10.184037 -41.014071) (xy 10.072198 -40.949501) (xy 9.964547 -40.878169)
			(xy 9.861492 -40.800345) (xy 9.763422 -40.716324) (xy 9.670711 -40.626425) (xy 9.583711 -40.53099)
			(xy 9.50275 -40.43038) (xy 9.428136 -40.324977) (xy 9.360153 -40.21518) (xy 9.299058 -40.101406)
			(xy 9.245083 -39.984087) (xy 9.198432 -39.863668) (xy 9.159283 -39.740605) (xy 9.127784 -39.615366)
			(xy 9.104055 -39.488425) (xy 9.088185 -39.360265) (xy 9.080235 -39.23137) (xy 0.509016 -39.23137)
			(xy 0.509016 -43.481752) (xy 178.630072 -43.481752) (xy 178.630072 -42.618152) (xy 178.630558 -42.590883)
			(xy 178.63832 -42.536899) (xy 178.653685 -42.484569) (xy 178.676342 -42.434959) (xy 178.705828 -42.389078)
			(xy 178.741543 -42.347861) (xy 178.78276 -42.312146) (xy 178.828641 -42.28266) (xy 178.878251 -42.260003)
			(xy 178.930581 -42.244638) (xy 178.984565 -42.236876) (xy 179.039103 -42.236876) (xy 179.093087 -42.244638)
			(xy 179.145417 -42.260003) (xy 179.195027 -42.28266) (xy 179.240908 -42.312146) (xy 179.282125 -42.347861)
			(xy 179.31784 -42.389078) (xy 179.347326 -42.434959) (xy 179.369983 -42.484569) (xy 179.385348 -42.536899)
			(xy 179.39311 -42.590883) (xy 179.393596 -42.618152) (xy 179.393596 -43.481752) (xy 179.39311 -43.509021)
			(xy 179.385348 -43.563005) (xy 179.369983 -43.615335) (xy 179.347326 -43.664945) (xy 179.31784 -43.710826)
			(xy 179.282125 -43.752043) (xy 179.240908 -43.787758) (xy 179.195027 -43.817244) (xy 179.145417 -43.839901)
			(xy 179.093087 -43.855266) (xy 179.039103 -43.863028) (xy 178.984565 -43.863028) (xy 178.930581 -43.855266)
			(xy 178.878251 -43.839901) (xy 178.828641 -43.817244) (xy 178.78276 -43.787758) (xy 178.741543 -43.752043)
			(xy 178.705828 -43.710826) (xy 178.676342 -43.664945) (xy 178.653685 -43.615335) (xy 178.63832 -43.563005)
			(xy 178.630558 -43.509021) (xy 178.630072 -43.481752) (xy 0.509016 -43.481752) (xy 0.509016 -47.04994)
			(xy 59.582066 -47.04994) (xy 59.586045 -46.890389) (xy 59.597972 -46.731234) (xy 59.617818 -46.572872)
			(xy 59.645532 -46.415696) (xy 59.681047 -46.260096) (xy 59.724273 -46.10646) (xy 59.775104 -45.95517)
			(xy 59.833413 -45.806602) (xy 59.899054 -45.661125) (xy 59.971866 -45.519101) (xy 60.051666 -45.380882)
			(xy 60.138257 -45.246813) (xy 60.231423 -45.117227) (xy 60.330933 -44.992446) (xy 60.436538 -44.87278)
			(xy 60.547978 -44.758527) (xy 60.664973 -44.649971) (xy 60.787235 -44.547381) (xy 60.914458 -44.451014)
			(xy 61.046326 -44.361107) (xy 61.182512 -44.277886) (xy 61.322677 -44.201556) (xy 61.466472 -44.132307)
			(xy 61.613541 -44.070313) (xy 61.763517 -44.015726) (xy 61.916027 -43.968683) (xy 62.070693 -43.9293)
			(xy 62.227129 -43.897676) (xy 62.384947 -43.873888) (xy 62.543755 -43.857997) (xy 62.703158 -43.850041)
			(xy 62.782958 -43.849544) (xy 64.382904 -43.849544) (xy 64.462705 -43.850033) (xy 64.622107 -43.857989)
			(xy 64.780916 -43.87388) (xy 64.938734 -43.897668) (xy 65.095171 -43.929293) (xy 65.249837 -43.968675)
			(xy 65.402347 -44.015719) (xy 65.552323 -44.070306) (xy 65.699392 -44.132301) (xy 65.843188 -44.201549)
			(xy 65.983353 -44.277879) (xy 66.119539 -44.361101) (xy 66.251408 -44.451008) (xy 66.378631 -44.547376)
			(xy 66.500893 -44.649966) (xy 66.617889 -44.758522) (xy 66.729328 -44.872775) (xy 66.834934 -44.992442)
			(xy 66.934444 -45.117223) (xy 67.02761 -45.246809) (xy 67.114201 -45.380878) (xy 67.194001 -45.519097)
			(xy 67.266813 -45.661122) (xy 67.332455 -45.806599) (xy 67.390764 -45.955168) (xy 67.441595 -46.106458)
			(xy 67.484821 -46.260094) (xy 67.520336 -46.415694) (xy 67.54805 -46.572871) (xy 67.567896 -46.731233)
			(xy 67.579823 -46.890388) (xy 67.583802 -47.04994) (xy 89.78165 -47.04994) (xy 89.78563 -46.895439)
			(xy 89.797557 -46.741349) (xy 89.817402 -46.588076) (xy 89.84511 -46.436028) (xy 89.880608 -46.285609)
			(xy 89.923803 -46.137216) (xy 89.97458 -45.991243) (xy 90.032804 -45.848078) (xy 90.098321 -45.708101)
			(xy 90.170957 -45.571681) (xy 90.250519 -45.439181) (xy 90.336796 -45.310953) (xy 90.42956 -45.187337)
			(xy 90.528565 -45.068659) (xy 90.633548 -44.955236) (xy 90.74423 -44.847368) (xy 90.860319 -44.74534)
			(xy 90.981506 -44.649424) (xy 91.10747 -44.559873) (xy 91.237877 -44.476926) (xy 91.372381 -44.400801)
			(xy 91.510626 -44.331702) (xy 91.652244 -44.269811) (xy 91.796861 -44.215293) (xy 91.944092 -44.168291)
			(xy 92.093548 -44.128931) (xy 92.244832 -44.097317) (xy 92.397543 -44.073533) (xy 92.551275 -44.057642)
			(xy 92.705622 -44.049686) (xy 92.782898 -44.049188) (xy 94.383098 -44.049188) (xy 94.460374 -44.049669)
			(xy 94.614722 -44.057625) (xy 94.768456 -44.073516) (xy 94.921168 -44.0973) (xy 95.072452 -44.128914)
			(xy 95.221909 -44.168274) (xy 95.369142 -44.215276) (xy 95.513759 -44.269795) (xy 95.655379 -44.331686)
			(xy 95.793624 -44.400785) (xy 95.928129 -44.47691) (xy 96.058537 -44.559858) (xy 96.184502 -44.649409)
			(xy 96.30569 -44.745326) (xy 96.421779 -44.847354) (xy 96.532463 -44.955223) (xy 96.555487 -44.980098)
			(xy 181.659784 -44.980098) (xy 181.659784 -44.116498) (xy 181.66027 -44.089229) (xy 181.668032 -44.035245)
			(xy 181.683397 -43.982915) (xy 181.706054 -43.933305) (xy 181.73554 -43.887424) (xy 181.771255 -43.846207)
			(xy 181.812472 -43.810492) (xy 181.858353 -43.781006) (xy 181.907963 -43.758349) (xy 181.960293 -43.742984)
			(xy 182.014277 -43.735222) (xy 182.068815 -43.735222) (xy 182.122799 -43.742984) (xy 182.175129 -43.758349)
			(xy 182.224739 -43.781006) (xy 182.27062 -43.810492) (xy 182.311837 -43.846207) (xy 182.347552 -43.887424)
			(xy 182.377038 -43.933305) (xy 182.399695 -43.982915) (xy 182.412218 -44.025566) (xy 236.740192 -44.025566)
			(xy 236.74068 -43.984453) (xy 236.74827 -43.902577) (xy 236.763381 -43.82175) (xy 236.785886 -43.742663)
			(xy 236.815591 -43.665989) (xy 236.852243 -43.592383) (xy 236.895531 -43.522473) (xy 236.945083 -43.456854)
			(xy 237.000479 -43.396088) (xy 237.061245 -43.340691) (xy 237.126863 -43.291137) (xy 237.196773 -43.247849)
			(xy 237.270378 -43.211196) (xy 237.347052 -43.181489) (xy 237.426139 -43.158984) (xy 237.506965 -43.143872)
			(xy 237.588841 -43.136281) (xy 237.629954 -43.135804) (xy 237.672596 -43.136331) (xy 237.757484 -43.144543)
			(xy 237.841197 -43.160838) (xy 237.922968 -43.185068) (xy 237.962694 -43.200574) (xy 237.971356 -43.203655)
			(xy 237.989722 -43.204046) (xy 237.998508 -43.201336) (xy 238.034032 -43.189272) (xy 238.106663 -43.170452)
			(xy 238.18062 -43.157817) (xy 238.25538 -43.151455) (xy 238.292894 -43.151044) (xy 238.332166 -43.151496)
			(xy 238.410399 -43.158477) (xy 238.487712 -43.172332) (xy 238.563501 -43.192954) (xy 238.600488 -43.206162)
			(xy 238.609037 -43.208926) (xy 238.626991 -43.208926) (xy 238.63554 -43.206162) (xy 238.672533 -43.192975)
			(xy 238.748323 -43.172363) (xy 238.825633 -43.158506) (xy 238.903863 -43.151512) (xy 238.943134 -43.151044)
			(xy 238.981423 -43.151469) (xy 239.057717 -43.158071) (xy 239.133159 -43.171215) (xy 239.207191 -43.190803)
			(xy 239.243362 -43.203368) (xy 239.251799 -43.206019) (xy 239.269469 -43.206019) (xy 239.277906 -43.203368)
			(xy 239.314089 -43.190839) (xy 239.38812 -43.171262) (xy 239.463558 -43.158111) (xy 239.539846 -43.151482)
			(xy 239.578134 -43.151044) (xy 239.616423 -43.151469) (xy 239.692717 -43.158071) (xy 239.768159 -43.171215)
			(xy 239.842191 -43.190803) (xy 239.878362 -43.203368) (xy 239.886799 -43.206019) (xy 239.904469 -43.206019)
			(xy 239.912906 -43.203368) (xy 239.949089 -43.190839) (xy 240.02312 -43.171262) (xy 240.098558 -43.158111)
			(xy 240.174846 -43.151482) (xy 240.213134 -43.151044) (xy 240.25606 -43.151581) (xy 240.341511 -43.159862)
			(xy 240.425768 -43.176335) (xy 240.508046 -43.200846) (xy 240.587581 -43.233168) (xy 240.613613 -43.246802)
			(xy 243.62918 -43.246802) (xy 243.629584 -43.208512) (xy 243.636192 -43.132218) (xy 243.649342 -43.056775)
			(xy 243.668936 -42.982745) (xy 243.681504 -42.946574) (xy 243.684156 -42.938137) (xy 243.684156 -42.920466)
			(xy 243.681504 -42.91203) (xy 243.668959 -42.875853) (xy 243.649386 -42.80182) (xy 243.636239 -42.72638)
			(xy 243.629616 -42.65009) (xy 243.62918 -42.611802) (xy 243.629684 -42.569441) (xy 243.637737 -42.485104)
			(xy 243.653771 -42.401914) (xy 243.677639 -42.320624) (xy 243.709127 -42.241972) (xy 243.747949 -42.166669)
			(xy 243.793752 -42.095397) (xy 243.846123 -42.028801) (xy 243.904588 -41.967486) (xy 243.968616 -41.912005)
			(xy 244.037628 -41.862862) (xy 244.110998 -41.820502) (xy 244.188063 -41.785307) (xy 244.268125 -41.757598)
			(xy 244.350458 -41.737624) (xy 244.434317 -41.725567) (xy 244.518942 -41.721536) (xy 244.603567 -41.725567)
			(xy 244.687426 -41.737624) (xy 244.769759 -41.757598) (xy 244.849821 -41.785307) (xy 244.926886 -41.820502)
			(xy 245.000256 -41.862862) (xy 245.069268 -41.912005) (xy 245.133296 -41.967486) (xy 245.191761 -42.028801)
			(xy 245.244132 -42.095397) (xy 245.289935 -42.166669) (xy 245.328757 -42.241972) (xy 245.360245 -42.320624)
			(xy 245.384113 -42.401914) (xy 245.400147 -42.485104) (xy 245.4082 -42.569441) (xy 245.408704 -42.611802)
			(xy 245.408302 -42.650092) (xy 245.401694 -42.726386) (xy 245.388543 -42.801829) (xy 245.368949 -42.875859)
			(xy 245.35638 -42.91203) (xy 245.353727 -42.920466) (xy 245.353728 -42.938137) (xy 245.35638 -42.946574)
			(xy 245.368926 -42.982751) (xy 245.388499 -43.056784) (xy 245.401645 -43.132224) (xy 245.408269 -43.208514)
			(xy 245.408704 -43.246802) (xy 245.4082 -43.289163) (xy 245.400147 -43.3735) (xy 245.384113 -43.45669)
			(xy 245.360245 -43.53798) (xy 245.328757 -43.616632) (xy 245.289935 -43.691935) (xy 245.244132 -43.763207)
			(xy 245.191761 -43.829803) (xy 245.133296 -43.891118) (xy 245.069268 -43.946599) (xy 245.000256 -43.995742)
			(xy 244.926886 -44.038102) (xy 244.849821 -44.073297) (xy 244.769759 -44.101006) (xy 244.687426 -44.12098)
			(xy 244.603567 -44.133037) (xy 244.518942 -44.137069) (xy 244.434317 -44.133037) (xy 244.350458 -44.12098)
			(xy 244.268125 -44.101006) (xy 244.188063 -44.073297) (xy 244.110998 -44.038102) (xy 244.037628 -43.995742)
			(xy 243.968616 -43.946599) (xy 243.904588 -43.891118) (xy 243.846123 -43.829803) (xy 243.793752 -43.763207)
			(xy 243.747949 -43.691935) (xy 243.709127 -43.616632) (xy 243.677639 -43.53798) (xy 243.653771 -43.45669)
			(xy 243.637737 -43.3735) (xy 243.629684 -43.289163) (xy 243.62918 -43.246802) (xy 240.613613 -43.246802)
			(xy 240.663633 -43.272999) (xy 240.735496 -43.31997) (xy 240.802501 -43.373643) (xy 240.864025 -43.433521)
			(xy 240.919496 -43.499046) (xy 240.968398 -43.569608) (xy 241.010277 -43.644552) (xy 241.044744 -43.723182)
			(xy 241.071477 -43.804765) (xy 241.090229 -43.888544) (xy 241.096038 -43.931078) (xy 241.097792 -43.94092)
			(xy 241.107661 -43.958279) (xy 241.123386 -43.970587) (xy 241.132868 -43.97375) (xy 241.172506 -43.985287)
			(xy 241.249638 -44.014728) (xy 241.32371 -44.051189) (xy 241.394086 -44.094356) (xy 241.460159 -44.143858)
			(xy 241.521362 -44.199269) (xy 241.577167 -44.260112) (xy 241.627095 -44.325864) (xy 241.670716 -44.395959)
			(xy 241.707655 -44.469795) (xy 241.737594 -44.546735) (xy 241.760276 -44.626118) (xy 241.775505 -44.707261)
			(xy 241.78315 -44.789466) (xy 241.783616 -44.830746) (xy 241.783231 -44.871862) (xy 241.775639 -44.953744)
			(xy 241.760525 -45.034576) (xy 241.738017 -45.113668) (xy 241.708307 -45.190346) (xy 241.671649 -45.263956)
			(xy 241.628355 -45.333869) (xy 241.578796 -45.39949) (xy 241.523393 -45.460258) (xy 241.462619 -45.515654)
			(xy 241.396993 -45.565207) (xy 241.327075 -45.608494) (xy 241.253462 -45.645144) (xy 241.176781 -45.674846)
			(xy 241.097686 -45.697346) (xy 241.016853 -45.712452) (xy 240.93497 -45.720035) (xy 240.893854 -45.720508)
			(xy 240.848047 -45.719908) (xy 240.756919 -45.710469) (xy 240.667241 -45.691726) (xy 240.579961 -45.663878)
			(xy 240.537746 -45.646086) (xy 240.528923 -45.642621) (xy 240.509997 -45.641842) (xy 240.500916 -45.644562)
			(xy 240.454475 -45.659757) (xy 240.359116 -45.681105) (xy 240.261993 -45.691873) (xy 240.213134 -45.692568)
			(xy 240.174844 -45.692152) (xy 240.09855 -45.685547) (xy 240.023108 -45.672401) (xy 239.949077 -45.652811)
			(xy 239.912906 -45.640244) (xy 239.904469 -45.637593) (xy 239.886799 -45.637593) (xy 239.878362 -45.640244)
			(xy 239.842183 -45.652782) (xy 239.76815 -45.672357) (xy 239.692711 -45.685505) (xy 239.616422 -45.692131)
			(xy 239.578134 -45.692568) (xy 239.539844 -45.692152) (xy 239.46355 -45.685547) (xy 239.388108 -45.672401)
			(xy 239.314077 -45.652811) (xy 239.277906 -45.640244) (xy 239.269469 -45.637593) (xy 239.251799 -45.637593)
			(xy 239.243362 -45.640244) (xy 239.207183 -45.652782) (xy 239.13315 -45.672357) (xy 239.057711 -45.685505)
			(xy 238.981422 -45.692131) (xy 238.943134 -45.692568) (xy 238.903862 -45.692107) (xy 238.825629 -45.685129)
			(xy 238.748316 -45.671276) (xy 238.672527 -45.650657) (xy 238.63554 -45.63745) (xy 238.626991 -45.634686)
			(xy 238.609037 -45.634686) (xy 238.600488 -45.63745) (xy 238.563502 -45.650659) (xy 238.48771 -45.671265)
			(xy 238.410397 -45.685115) (xy 238.332165 -45.692103) (xy 238.292894 -45.692568) (xy 238.24936 -45.692039)
			(xy 238.16271 -45.683524) (xy 238.077306 -45.666586) (xy 237.993965 -45.641387) (xy 237.913484 -45.608168)
			(xy 237.87481 -45.588174) (xy 237.86657 -45.584248) (xy 237.848476 -45.581916) (xy 237.839504 -45.583602)
			(xy 237.790336 -45.594179) (xy 237.690402 -45.605511) (xy 237.640114 -45.606208) (xy 237.599001 -45.605674)
			(xy 237.517127 -45.598088) (xy 237.436301 -45.582981) (xy 237.357214 -45.560481) (xy 237.280541 -45.53078)
			(xy 237.206935 -45.494131) (xy 237.137024 -45.450847) (xy 237.071406 -45.401297) (xy 237.010639 -45.345904)
			(xy 236.955242 -45.285141) (xy 236.905687 -45.219525) (xy 236.862399 -45.149618) (xy 236.825745 -45.076014)
			(xy 236.796038 -44.999343) (xy 236.773533 -44.920257) (xy 236.75842 -44.839433) (xy 236.750829 -44.757559)
			(xy 236.750352 -44.716446) (xy 236.750814 -44.676228) (xy 236.758123 -44.596123) (xy 236.772622 -44.517004)
			(xy 236.794193 -44.439513) (xy 236.80801 -44.40174) (xy 236.811025 -44.392621) (xy 236.810769 -44.373433)
			(xy 236.807502 -44.364402) (xy 236.791394 -44.324025) (xy 236.766206 -44.240819) (xy 236.749266 -44.15555)
			(xy 236.740738 -44.069034) (xy 236.740192 -44.025566) (xy 182.412218 -44.025566) (xy 182.41506 -44.035245)
			(xy 182.422822 -44.089229) (xy 182.423308 -44.116498) (xy 182.423308 -44.980098) (xy 182.422822 -45.007367)
			(xy 182.41506 -45.061351) (xy 182.399695 -45.113681) (xy 182.377038 -45.163291) (xy 182.347552 -45.209172)
			(xy 182.311837 -45.250389) (xy 182.27062 -45.286104) (xy 182.224739 -45.31559) (xy 182.175129 -45.338247)
			(xy 182.122799 -45.353612) (xy 182.068815 -45.361374) (xy 182.014277 -45.361374) (xy 181.960293 -45.353612)
			(xy 181.907963 -45.338247) (xy 181.858353 -45.31559) (xy 181.812472 -45.286104) (xy 181.771255 -45.250389)
			(xy 181.73554 -45.209172) (xy 181.706054 -45.163291) (xy 181.683397 -45.113681) (xy 181.668032 -45.061351)
			(xy 181.66027 -45.007367) (xy 181.659784 -44.980098) (xy 96.555487 -44.980098) (xy 96.637446 -45.068647)
			(xy 96.736452 -45.187325) (xy 96.829216 -45.310943) (xy 96.915495 -45.439171) (xy 96.995057 -45.571672)
			(xy 97.067693 -45.708092) (xy 97.133211 -45.848071) (xy 97.191435 -45.991237) (xy 97.242212 -46.13721)
			(xy 97.285407 -46.285604) (xy 97.320906 -46.436025) (xy 97.329238 -46.481746) (xy 178.630072 -46.481746)
			(xy 178.630072 -45.618146) (xy 178.630558 -45.590877) (xy 178.63832 -45.536893) (xy 178.653685 -45.484563)
			(xy 178.676342 -45.434953) (xy 178.705828 -45.389072) (xy 178.741543 -45.347855) (xy 178.78276 -45.31214)
			(xy 178.828641 -45.282654) (xy 178.878251 -45.259997) (xy 178.930581 -45.244632) (xy 178.984565 -45.23687)
			(xy 179.039103 -45.23687) (xy 179.093087 -45.244632) (xy 179.145417 -45.259997) (xy 179.195027 -45.282654)
			(xy 179.240908 -45.31214) (xy 179.282125 -45.347855) (xy 179.31784 -45.389072) (xy 179.347326 -45.434953)
			(xy 179.369983 -45.484563) (xy 179.385348 -45.536893) (xy 179.39311 -45.590877) (xy 179.393596 -45.618146)
			(xy 179.393596 -46.481746) (xy 179.39311 -46.509015) (xy 179.385348 -46.562999) (xy 179.369983 -46.615329)
			(xy 179.347326 -46.664939) (xy 179.31784 -46.71082) (xy 179.282125 -46.752037) (xy 179.240908 -46.787752)
			(xy 179.195027 -46.817238) (xy 179.145417 -46.839895) (xy 179.093087 -46.85526) (xy 179.039103 -46.863022)
			(xy 178.984565 -46.863022) (xy 178.930581 -46.85526) (xy 178.878251 -46.839895) (xy 178.828641 -46.817238)
			(xy 178.78276 -46.787752) (xy 178.741543 -46.752037) (xy 178.705828 -46.71082) (xy 178.676342 -46.664939)
			(xy 178.653685 -46.615329) (xy 178.63832 -46.562999) (xy 178.630558 -46.509015) (xy 178.630072 -46.481746)
			(xy 97.329238 -46.481746) (xy 97.348615 -46.588073) (xy 97.368459 -46.741347) (xy 97.380387 -46.895438)
			(xy 97.384366 -47.04994) (xy 97.380387 -47.204442) (xy 97.368459 -47.358533) (xy 97.348615 -47.511807)
			(xy 97.320906 -47.663855) (xy 97.285407 -47.814276) (xy 97.242212 -47.96267) (xy 97.219453 -48.028098)
			(xy 181.659784 -48.028098) (xy 181.659784 -47.164498) (xy 181.66027 -47.137229) (xy 181.668032 -47.083245)
			(xy 181.683397 -47.030915) (xy 181.706054 -46.981305) (xy 181.73554 -46.935424) (xy 181.771255 -46.894207)
			(xy 181.812472 -46.858492) (xy 181.858353 -46.829006) (xy 181.907963 -46.806349) (xy 181.960293 -46.790984)
			(xy 182.014277 -46.783222) (xy 182.068815 -46.783222) (xy 182.122799 -46.790984) (xy 182.175129 -46.806349)
			(xy 182.224739 -46.829006) (xy 182.27062 -46.858492) (xy 182.311837 -46.894207) (xy 182.347552 -46.935424)
			(xy 182.377038 -46.981305) (xy 182.399695 -47.030915) (xy 182.41506 -47.083245) (xy 182.422822 -47.137229)
			(xy 182.423308 -47.164498) (xy 182.423308 -48.028098) (xy 182.422822 -48.055367) (xy 182.41506 -48.109351)
			(xy 182.399695 -48.161681) (xy 182.377038 -48.211291) (xy 182.347552 -48.257172) (xy 182.311837 -48.298389)
			(xy 182.27062 -48.334104) (xy 182.224739 -48.36359) (xy 182.175129 -48.386247) (xy 182.122799 -48.401612)
			(xy 182.068815 -48.409374) (xy 182.014277 -48.409374) (xy 181.960293 -48.401612) (xy 181.907963 -48.386247)
			(xy 181.858353 -48.36359) (xy 181.812472 -48.334104) (xy 181.771255 -48.298389) (xy 181.73554 -48.257172)
			(xy 181.706054 -48.211291) (xy 181.683397 -48.161681) (xy 181.668032 -48.109351) (xy 181.66027 -48.055367)
			(xy 181.659784 -48.028098) (xy 97.219453 -48.028098) (xy 97.191435 -48.108643) (xy 97.133211 -48.251809)
			(xy 97.067693 -48.391788) (xy 96.995057 -48.528208) (xy 96.915495 -48.660709) (xy 96.829216 -48.788937)
			(xy 96.736452 -48.912555) (xy 96.637446 -49.031233) (xy 96.532463 -49.144657) (xy 96.421779 -49.252526)
			(xy 96.30569 -49.354554) (xy 96.184502 -49.450471) (xy 96.140518 -49.48174) (xy 178.630072 -49.48174)
			(xy 178.630072 -48.61814) (xy 178.630558 -48.590871) (xy 178.63832 -48.536887) (xy 178.653685 -48.484557)
			(xy 178.676342 -48.434947) (xy 178.705828 -48.389066) (xy 178.741543 -48.347849) (xy 178.78276 -48.312134)
			(xy 178.828641 -48.282648) (xy 178.878251 -48.259991) (xy 178.930581 -48.244626) (xy 178.984565 -48.236864)
			(xy 179.039103 -48.236864) (xy 179.093087 -48.244626) (xy 179.145417 -48.259991) (xy 179.195027 -48.282648)
			(xy 179.240908 -48.312134) (xy 179.282125 -48.347849) (xy 179.31784 -48.389066) (xy 179.347326 -48.434947)
			(xy 179.369983 -48.484557) (xy 179.385348 -48.536887) (xy 179.39311 -48.590871) (xy 179.393596 -48.61814)
			(xy 179.393596 -49.48174) (xy 179.39311 -49.509009) (xy 179.385348 -49.562993) (xy 179.369983 -49.615323)
			(xy 179.347326 -49.664933) (xy 179.31784 -49.710814) (xy 179.282125 -49.752031) (xy 179.240908 -49.787746)
			(xy 179.195027 -49.817232) (xy 179.145417 -49.839889) (xy 179.093087 -49.855254) (xy 179.039103 -49.863016)
			(xy 178.984565 -49.863016) (xy 178.930581 -49.855254) (xy 178.878251 -49.839889) (xy 178.828641 -49.817232)
			(xy 178.78276 -49.787746) (xy 178.741543 -49.752031) (xy 178.705828 -49.710814) (xy 178.676342 -49.664933)
			(xy 178.653685 -49.615323) (xy 178.63832 -49.562993) (xy 178.630558 -49.509009) (xy 178.630072 -49.48174)
			(xy 96.140518 -49.48174) (xy 96.058537 -49.540022) (xy 95.928129 -49.62297) (xy 95.793624 -49.699095)
			(xy 95.655379 -49.768194) (xy 95.513759 -49.830085) (xy 95.369142 -49.884604) (xy 95.221909 -49.931606)
			(xy 95.072452 -49.970966) (xy 94.921168 -50.00258) (xy 94.768456 -50.026364) (xy 94.614722 -50.042255)
			(xy 94.460374 -50.050211) (xy 94.383098 -50.0507) (xy 92.782898 -50.0507) (xy 92.705622 -50.050194)
			(xy 92.551275 -50.042238) (xy 92.397543 -50.026347) (xy 92.244832 -50.002563) (xy 92.093548 -49.970949)
			(xy 91.944092 -49.931589) (xy 91.796861 -49.884587) (xy 91.652244 -49.830069) (xy 91.510626 -49.768178)
			(xy 91.372381 -49.699079) (xy 91.237877 -49.622954) (xy 91.10747 -49.540007) (xy 90.981506 -49.450456)
			(xy 90.860319 -49.35454) (xy 90.74423 -49.252512) (xy 90.633548 -49.144644) (xy 90.528565 -49.031221)
			(xy 90.42956 -48.912543) (xy 90.336796 -48.788927) (xy 90.250519 -48.660699) (xy 90.170957 -48.528199)
			(xy 90.098321 -48.391779) (xy 90.032804 -48.251802) (xy 89.97458 -48.108637) (xy 89.923803 -47.962664)
			(xy 89.880608 -47.814271) (xy 89.84511 -47.663852) (xy 89.817402 -47.511804) (xy 89.797557 -47.358531)
			(xy 89.78563 -47.204441) (xy 89.78165 -47.04994) (xy 67.583802 -47.04994) (xy 67.579823 -47.209492)
			(xy 67.567896 -47.368647) (xy 67.54805 -47.527009) (xy 67.520336 -47.684186) (xy 67.484821 -47.839786)
			(xy 67.441595 -47.993422) (xy 67.390764 -48.144712) (xy 67.332455 -48.293281) (xy 67.266813 -48.438758)
			(xy 67.194001 -48.580783) (xy 67.114201 -48.719002) (xy 67.02761 -48.853071) (xy 66.934444 -48.982657)
			(xy 66.834934 -49.107438) (xy 66.729328 -49.227105) (xy 66.617889 -49.341358) (xy 66.500893 -49.449914)
			(xy 66.378631 -49.552504) (xy 66.251408 -49.648872) (xy 66.119539 -49.738779) (xy 65.983353 -49.822001)
			(xy 65.843188 -49.898331) (xy 65.699392 -49.967579) (xy 65.552323 -50.029574) (xy 65.402347 -50.084161)
			(xy 65.249837 -50.131205) (xy 65.095171 -50.170587) (xy 64.938734 -50.202212) (xy 64.780916 -50.226)
			(xy 64.622107 -50.241891) (xy 64.462705 -50.249847) (xy 64.382904 -50.250344) (xy 62.782958 -50.250344)
			(xy 62.703158 -50.249839) (xy 62.543755 -50.241883) (xy 62.384947 -50.225992) (xy 62.227129 -50.202204)
			(xy 62.070693 -50.17058) (xy 61.916027 -50.131197) (xy 61.763517 -50.084154) (xy 61.613541 -50.029567)
			(xy 61.466472 -49.967573) (xy 61.322677 -49.898324) (xy 61.182512 -49.821994) (xy 61.046326 -49.738773)
			(xy 60.914458 -49.648866) (xy 60.787235 -49.552499) (xy 60.664973 -49.449909) (xy 60.547978 -49.341353)
			(xy 60.436538 -49.2271) (xy 60.330933 -49.107434) (xy 60.231423 -48.982653) (xy 60.138257 -48.853067)
			(xy 60.051666 -48.718998) (xy 59.971866 -48.580779) (xy 59.899054 -48.438755) (xy 59.833413 -48.293278)
			(xy 59.775104 -48.14471) (xy 59.724273 -47.99342) (xy 59.681047 -47.839784) (xy 59.645532 -47.684184)
			(xy 59.617818 -47.527008) (xy 59.597972 -47.368646) (xy 59.586045 -47.209491) (xy 59.582066 -47.04994)
			(xy 0.509016 -47.04994) (xy 0.509016 -50.949098) (xy 181.659784 -50.949098) (xy 181.659784 -50.085498)
			(xy 181.66027 -50.058229) (xy 181.668032 -50.004245) (xy 181.683397 -49.951915) (xy 181.706054 -49.902305)
			(xy 181.73554 -49.856424) (xy 181.771255 -49.815207) (xy 181.812472 -49.779492) (xy 181.858353 -49.750006)
			(xy 181.907963 -49.727349) (xy 181.960293 -49.711984) (xy 182.014277 -49.704222) (xy 182.068815 -49.704222)
			(xy 182.122799 -49.711984) (xy 182.175129 -49.727349) (xy 182.224739 -49.750006) (xy 182.27062 -49.779492)
			(xy 182.311837 -49.815207) (xy 182.347552 -49.856424) (xy 182.377038 -49.902305) (xy 182.399695 -49.951915)
			(xy 182.41506 -50.004245) (xy 182.422822 -50.058229) (xy 182.423308 -50.085498) (xy 182.423308 -50.949098)
			(xy 182.422822 -50.976367) (xy 182.41506 -51.030351) (xy 182.399695 -51.082681) (xy 182.377038 -51.132291)
			(xy 182.347552 -51.178172) (xy 182.311837 -51.219389) (xy 182.27062 -51.255104) (xy 182.224739 -51.28459)
			(xy 182.175129 -51.307247) (xy 182.122799 -51.322612) (xy 182.068815 -51.330374) (xy 182.014277 -51.330374)
			(xy 181.960293 -51.322612) (xy 181.907963 -51.307247) (xy 181.858353 -51.28459) (xy 181.812472 -51.255104)
			(xy 181.771255 -51.219389) (xy 181.73554 -51.178172) (xy 181.706054 -51.132291) (xy 181.683397 -51.082681)
			(xy 181.668032 -51.030351) (xy 181.66027 -50.976367) (xy 181.659784 -50.949098) (xy 0.509016 -50.949098)
			(xy 0.509016 -52.481734) (xy 178.630072 -52.481734) (xy 178.630072 -51.618134) (xy 178.630558 -51.590865)
			(xy 178.63832 -51.536881) (xy 178.653685 -51.484551) (xy 178.676342 -51.434941) (xy 178.705828 -51.38906)
			(xy 178.741543 -51.347843) (xy 178.78276 -51.312128) (xy 178.828641 -51.282642) (xy 178.878251 -51.259985)
			(xy 178.930581 -51.24462) (xy 178.984565 -51.236858) (xy 179.039103 -51.236858) (xy 179.093087 -51.24462)
			(xy 179.145417 -51.259985) (xy 179.195027 -51.282642) (xy 179.240908 -51.312128) (xy 179.282125 -51.347843)
			(xy 179.31784 -51.38906) (xy 179.347326 -51.434941) (xy 179.369983 -51.484551) (xy 179.385348 -51.536881)
			(xy 179.39311 -51.590865) (xy 179.393596 -51.618134) (xy 179.393596 -51.999896) (xy 201.367397 -51.999896)
			(xy 201.371407 -51.837793) (xy 201.38343 -51.676088) (xy 201.403434 -51.515174) (xy 201.431372 -51.355447)
			(xy 201.467175 -51.197297) (xy 201.510755 -51.041111) (xy 201.562006 -50.887271) (xy 201.620802 -50.736154)
			(xy 201.687 -50.58813) (xy 201.760436 -50.44356) (xy 201.840933 -50.302799) (xy 201.928292 -50.166191)
			(xy 202.0223 -50.034071) (xy 202.122727 -49.906761) (xy 202.229327 -49.784573) (xy 202.341839 -49.667807)
			(xy 202.459987 -49.556748) (xy 202.583484 -49.451667) (xy 202.712026 -49.352823) (xy 202.845299 -49.260456)
			(xy 202.982977 -49.174793) (xy 203.124723 -49.096044) (xy 203.27019 -49.024401) (xy 203.419022 -48.960039)
			(xy 203.570854 -48.903117) (xy 203.725316 -48.853773) (xy 203.882029 -48.812128) (xy 204.04061 -48.778283)
			(xy 204.200671 -48.752323) (xy 204.361819 -48.73431) (xy 204.523661 -48.724289) (xy 204.685801 -48.722283)
			(xy 204.847842 -48.728299) (xy 205.009386 -48.74232) (xy 205.17004 -48.764313) (xy 205.32941 -48.794225)
			(xy 205.487105 -48.831981) (xy 205.64274 -48.877489) (xy 205.795934 -48.930639) (xy 205.946312 -48.9913)
			(xy 206.093507 -49.059323) (xy 206.237157 -49.134542) (xy 206.376912 -49.216773) (xy 206.512428 -49.305815)
			(xy 206.643376 -49.40145) (xy 206.769434 -49.503444) (xy 206.890294 -49.611547) (xy 207.00566 -49.725494)
			(xy 207.115249 -49.845008) (xy 207.218794 -49.969795) (xy 207.316041 -50.09955) (xy 207.406753 -50.233955)
			(xy 207.490706 -50.372682) (xy 207.567696 -50.515391) (xy 207.637535 -50.661732) (xy 207.70005 -50.811349)
			(xy 207.755091 -50.963874) (xy 207.802521 -51.118934) (xy 207.842224 -51.27615) (xy 207.874105 -51.435138)
			(xy 207.898083 -51.595507) (xy 207.914102 -51.756866) (xy 207.922121 -51.91882) (xy 207.922622 -51.999896)
			(xy 207.922121 -52.080972) (xy 207.921092 -52.10175) (xy 244.67947 -52.10175) (xy 244.679975 -52.075243)
			(xy 244.687334 -52.022743) (xy 244.701889 -51.971767) (xy 244.723361 -51.923297) (xy 244.751335 -51.878265)
			(xy 244.785274 -51.837539) (xy 244.824523 -51.801903) (xy 244.868327 -51.772043) (xy 244.915843 -51.748534)
			(xy 244.966156 -51.731829) (xy 244.992144 -51.726592) (xy 245.000543 -51.724726) (xy 245.015476 -51.716197)
			(xy 245.026755 -51.703216) (xy 245.030244 -51.69535) (xy 245.045663 -51.657494) (xy 245.082559 -51.584546)
			(xy 245.125992 -51.515291) (xy 245.175596 -51.450313) (xy 245.230952 -51.39016) (xy 245.291595 -51.335341)
			(xy 245.357011 -51.286316) (xy 245.426649 -51.2435) (xy 245.499922 -51.207254) (xy 245.576211 -51.177884)
			(xy 245.654873 -51.155637) (xy 245.735245 -51.140701) (xy 245.816648 -51.133203) (xy 245.857522 -51.13274)
			(xy 245.899843 -51.133258) (xy 245.984099 -51.14133) (xy 246.067208 -51.157371) (xy 246.148416 -51.181236)
			(xy 246.226989 -51.212708) (xy 246.302217 -51.251503) (xy 246.33809 -51.273964) (xy 246.346484 -51.278827)
			(xy 246.365522 -51.28248) (xy 246.38456 -51.278827) (xy 246.392954 -51.273964) (xy 246.42883 -51.25151)
			(xy 246.504063 -51.212731) (xy 246.582638 -51.181268) (xy 246.663845 -51.157405) (xy 246.74695 -51.141356)
			(xy 246.831202 -51.133268) (xy 246.873522 -51.13274) (xy 246.926862 -51.134518) (xy 246.938638 -51.134618)
			(xy 246.960306 -51.125466) (xy 246.975671 -51.107657) (xy 246.979186 -51.096418) (xy 246.990138 -51.056039)
			(xy 247.018713 -50.977397) (xy 247.054545 -50.901785) (xy 247.097317 -50.829872) (xy 247.146653 -50.762292)
			(xy 247.202115 -50.699642) (xy 247.263214 -50.642477) (xy 247.329411 -50.5913) (xy 247.40012 -50.546564)
			(xy 247.474717 -50.508665) (xy 247.552542 -50.477936) (xy 247.632909 -50.45465) (xy 247.715107 -50.439012)
			(xy 247.79841 -50.431161) (xy 247.840246 -50.430684) (xy 247.883752 -50.431235) (xy 247.970347 -50.439729)
			(xy 248.055699 -50.456641) (xy 248.138991 -50.481809) (xy 248.219426 -50.514992) (xy 248.296235 -50.555874)
			(xy 248.332752 -50.579528) (xy 248.341308 -50.584744) (xy 248.360946 -50.588653) (xy 248.380584 -50.584744)
			(xy 248.38914 -50.579528) (xy 248.425663 -50.555885) (xy 248.50248 -50.515022) (xy 248.582916 -50.481847)
			(xy 248.666204 -50.456676) (xy 248.751551 -50.439749) (xy 248.838142 -50.431227) (xy 248.881646 -50.430684)
			(xy 248.926403 -50.431259) (xy 249.015462 -50.440266) (xy 249.103167 -50.458165) (xy 249.188634 -50.484775)
			(xy 249.270999 -50.519828) (xy 249.349431 -50.562968) (xy 249.386598 -50.58791) (xy 249.394939 -50.593062)
			(xy 249.414052 -50.597328) (xy 249.433374 -50.594144) (xy 249.44197 -50.589434) (xy 249.4758 -50.569354)
			(xy 249.546346 -50.534523) (xy 249.619688 -50.506051) (xy 249.695257 -50.484158) (xy 249.772462 -50.469016)
			(xy 249.850701 -50.460742) (xy 249.890026 -50.45964) (xy 249.889772 -50.4444) (xy 249.889772 -50.443892)
			(xy 249.89024 -50.405527) (xy 249.896983 -50.329093) (xy 249.903234 -50.291238) (xy 249.904413 -50.282319)
			(xy 249.901131 -50.26464) (xy 249.891952 -50.249179) (xy 249.8852 -50.243232) (xy 249.851748 -50.215094)
			(xy 249.789907 -50.153305) (xy 249.734424 -50.08575) (xy 249.685833 -50.01308) (xy 249.644603 -49.935995)
			(xy 249.61113 -49.855239) (xy 249.585738 -49.771589) (xy 249.568671 -49.685852) (xy 249.560094 -49.598855)
			(xy 249.559572 -49.555146) (xy 249.560076 -49.512785) (xy 249.568129 -49.428448) (xy 249.584163 -49.345258)
			(xy 249.608031 -49.263968) (xy 249.639519 -49.185316) (xy 249.678341 -49.110013) (xy 249.724144 -49.038741)
			(xy 249.776515 -48.972145) (xy 249.83498 -48.91083) (xy 249.899008 -48.855349) (xy 249.96802 -48.806206)
			(xy 250.04139 -48.763846) (xy 250.118455 -48.728651) (xy 250.198517 -48.700942) (xy 250.28085 -48.680968)
			(xy 250.364709 -48.668911) (xy 250.449334 -48.66488) (xy 250.533959 -48.668911) (xy 250.617818 -48.680968)
			(xy 250.700151 -48.700942) (xy 250.780213 -48.728651) (xy 250.857278 -48.763846) (xy 250.930648 -48.806206)
			(xy 250.99966 -48.855349) (xy 251.063688 -48.91083) (xy 251.122153 -48.972145) (xy 251.174524 -49.038741)
			(xy 251.220327 -49.110013) (xy 251.259149 -49.185316) (xy 251.290637 -49.263968) (xy 251.314505 -49.345258)
			(xy 251.330539 -49.428448) (xy 251.338592 -49.512785) (xy 251.339096 -49.555146) (xy 251.338636 -49.593574)
			(xy 251.331894 -49.670136) (xy 251.325634 -49.708054) (xy 251.324473 -49.716974) (xy 251.32775 -49.73465)
			(xy 251.336921 -49.750111) (xy 251.343668 -49.75606) (xy 251.362142 -49.771471) (xy 251.397596 -49.803999)
			(xy 251.414534 -49.821084) (xy 251.422676 -49.828571) (xy 251.443355 -49.836348) (xy 251.454412 -49.83607)
			(xy 251.469822 -49.835031) (xy 251.50069 -49.833886) (xy 251.516134 -49.833784) (xy 251.557251 -49.834166)
			(xy 251.639133 -49.841757) (xy 251.719966 -49.85687) (xy 251.79906 -49.879378) (xy 251.875739 -49.909087)
			(xy 251.94935 -49.945745) (xy 252.019265 -49.989039) (xy 252.084886 -50.038598) (xy 252.145655 -50.094001)
			(xy 252.201053 -50.154775) (xy 252.250607 -50.220401) (xy 252.293894 -50.29032) (xy 252.330545 -50.363934)
			(xy 252.360248 -50.440616) (xy 252.382748 -50.519712) (xy 252.397854 -50.600546) (xy 252.405438 -50.682429)
			(xy 252.405896 -50.723546) (xy 252.405358 -50.767341) (xy 252.396743 -50.854506) (xy 252.379599 -50.940401)
			(xy 252.354094 -51.024196) (xy 252.320474 -51.105076) (xy 252.300232 -51.143916) (xy 252.29478 -51.15537)
			(xy 252.2948 -51.18071) (xy 252.300232 -51.192176) (xy 252.320452 -51.231026) (xy 252.354062 -51.311909)
			(xy 252.379567 -51.3957) (xy 252.39672 -51.481592) (xy 252.405355 -51.568752) (xy 252.405896 -51.612546)
			(xy 252.405358 -51.656341) (xy 252.396743 -51.743506) (xy 252.379599 -51.829401) (xy 252.354094 -51.913196)
			(xy 252.320474 -51.994076) (xy 252.317441 -51.999896) (xy 265.367523 -51.999896) (xy 265.371533 -51.837793)
			(xy 265.383556 -51.676088) (xy 265.40356 -51.515174) (xy 265.431498 -51.355447) (xy 265.467301 -51.197297)
			(xy 265.510881 -51.041111) (xy 265.562132 -50.887271) (xy 265.620928 -50.736154) (xy 265.687126 -50.58813)
			(xy 265.760562 -50.44356) (xy 265.841059 -50.302799) (xy 265.928418 -50.166191) (xy 266.022426 -50.034071)
			(xy 266.122853 -49.906761) (xy 266.229453 -49.784573) (xy 266.341965 -49.667807) (xy 266.460113 -49.556748)
			(xy 266.58361 -49.451667) (xy 266.712152 -49.352823) (xy 266.845425 -49.260456) (xy 266.983103 -49.174793)
			(xy 267.124849 -49.096044) (xy 267.270316 -49.024401) (xy 267.419148 -48.960039) (xy 267.57098 -48.903117)
			(xy 267.725442 -48.853773) (xy 267.882155 -48.812128) (xy 268.040736 -48.778283) (xy 268.200797 -48.752323)
			(xy 268.361945 -48.73431) (xy 268.523787 -48.724289) (xy 268.685927 -48.722283) (xy 268.847968 -48.728299)
			(xy 269.009512 -48.74232) (xy 269.170166 -48.764313) (xy 269.329536 -48.794225) (xy 269.487231 -48.831981)
			(xy 269.642866 -48.877489) (xy 269.79606 -48.930639) (xy 269.946438 -48.9913) (xy 270.093633 -49.059323)
			(xy 270.237283 -49.134542) (xy 270.377038 -49.216773) (xy 270.512554 -49.305815) (xy 270.643502 -49.40145)
			(xy 270.76956 -49.503444) (xy 270.89042 -49.611547) (xy 271.005786 -49.725494) (xy 271.115375 -49.845008)
			(xy 271.21892 -49.969795) (xy 271.316167 -50.09955) (xy 271.406879 -50.233955) (xy 271.490832 -50.372682)
			(xy 271.567822 -50.515391) (xy 271.637661 -50.661732) (xy 271.700176 -50.811349) (xy 271.755217 -50.963874)
			(xy 271.802647 -51.118934) (xy 271.84235 -51.27615) (xy 271.874231 -51.435138) (xy 271.898209 -51.595507)
			(xy 271.914228 -51.756866) (xy 271.922247 -51.91882) (xy 271.922748 -51.999896) (xy 271.922247 -52.080972)
			(xy 271.914228 -52.242926) (xy 271.898209 -52.404285) (xy 271.874231 -52.564654) (xy 271.84235 -52.723642)
			(xy 271.802647 -52.880858) (xy 271.755217 -53.035918) (xy 271.700176 -53.188443) (xy 271.637661 -53.33806)
			(xy 271.567822 -53.484401) (xy 271.490832 -53.62711) (xy 271.406879 -53.765837) (xy 271.316167 -53.900242)
			(xy 271.21892 -54.029997) (xy 271.115375 -54.154784) (xy 271.005786 -54.274298) (xy 270.89042 -54.388245)
			(xy 270.76956 -54.496348) (xy 270.643502 -54.598342) (xy 270.512554 -54.693977) (xy 270.377038 -54.783019)
			(xy 270.237283 -54.86525) (xy 270.093633 -54.940469) (xy 269.946438 -55.008492) (xy 269.79606 -55.069153)
			(xy 269.642866 -55.122303) (xy 269.487231 -55.167811) (xy 269.329536 -55.205567) (xy 269.170166 -55.235479)
			(xy 269.009512 -55.257472) (xy 268.847968 -55.271493) (xy 268.685927 -55.277509) (xy 268.523787 -55.275503)
			(xy 268.361945 -55.265482) (xy 268.200797 -55.247469) (xy 268.040736 -55.221509) (xy 267.882155 -55.187664)
			(xy 267.725442 -55.146019) (xy 267.57098 -55.096675) (xy 267.419148 -55.039753) (xy 267.270316 -54.975391)
			(xy 267.124849 -54.903748) (xy 266.983103 -54.824999) (xy 266.845425 -54.739336) (xy 266.712152 -54.646969)
			(xy 266.58361 -54.548125) (xy 266.460113 -54.443044) (xy 266.341965 -54.331985) (xy 266.229453 -54.215219)
			(xy 266.122853 -54.093031) (xy 266.022426 -53.965721) (xy 265.928418 -53.833601) (xy 265.841059 -53.696993)
			(xy 265.760562 -53.556232) (xy 265.687126 -53.411662) (xy 265.620928 -53.263638) (xy 265.562132 -53.112521)
			(xy 265.510881 -52.958681) (xy 265.467301 -52.802495) (xy 265.431498 -52.644345) (xy 265.40356 -52.484618)
			(xy 265.383556 -52.323704) (xy 265.371533 -52.161999) (xy 265.367523 -51.999896) (xy 252.317441 -51.999896)
			(xy 252.300232 -52.032916) (xy 252.29478 -52.04437) (xy 252.2948 -52.06971) (xy 252.300232 -52.081176)
			(xy 252.320452 -52.120026) (xy 252.354062 -52.200909) (xy 252.379567 -52.2847) (xy 252.39672 -52.370592)
			(xy 252.405355 -52.457752) (xy 252.405896 -52.501546) (xy 252.405431 -52.54266) (xy 252.39784 -52.624537)
			(xy 252.382728 -52.705364) (xy 252.360222 -52.784452) (xy 252.330515 -52.861127) (xy 252.293861 -52.934733)
			(xy 252.250573 -53.004644) (xy 252.201018 -53.070263) (xy 252.145621 -53.131029) (xy 252.084853 -53.186426)
			(xy 252.019234 -53.235979) (xy 251.949323 -53.279267) (xy 251.875716 -53.31592) (xy 251.799041 -53.345626)
			(xy 251.719952 -53.36813) (xy 251.639125 -53.383242) (xy 251.557248 -53.390832) (xy 251.516134 -53.391308)
			(xy 251.471924 -53.390745) (xy 251.383942 -53.381965) (xy 251.297264 -53.3645) (xy 251.212747 -53.33852)
			(xy 251.131225 -53.304282) (xy 251.053503 -53.262125) (xy 250.980346 -53.212465) (xy 250.912478 -53.15579)
			(xy 250.881134 -53.124608) (xy 250.873005 -53.117104) (xy 250.852316 -53.109337) (xy 250.841256 -53.109622)
			(xy 250.825846 -53.110663) (xy 250.794978 -53.111806) (xy 250.779534 -53.111908) (xy 250.737779 -53.111492)
			(xy 250.654637 -53.103677) (xy 250.572592 -53.088104) (xy 250.492369 -53.064909) (xy 250.414673 -53.034297)
			(xy 250.340188 -52.996537) (xy 250.269571 -52.951961) (xy 250.203442 -52.900963) (xy 250.142385 -52.843991)
			(xy 250.086937 -52.781547) (xy 250.037585 -52.714181) (xy 249.994765 -52.642486) (xy 249.958854 -52.567092)
			(xy 249.930167 -52.488665) (xy 249.908958 -52.407894) (xy 249.895413 -52.32549) (xy 249.892058 -52.283868)
			(xy 249.891061 -52.274773) (xy 249.88348 -52.258135) (xy 249.870549 -52.245209) (xy 249.853908 -52.237634)
			(xy 249.844814 -52.236624) (xy 249.805225 -52.23352) (xy 249.726783 -52.221122) (xy 249.649759 -52.201775)
			(xy 249.574769 -52.175634) (xy 249.50241 -52.142907) (xy 249.433259 -52.103855) (xy 249.400314 -52.081684)
			(xy 249.392012 -52.076461) (xy 249.372875 -52.072218) (xy 249.353539 -52.075433) (xy 249.344942 -52.08016)
			(xy 249.312459 -52.099495) (xy 249.244799 -52.133223) (xy 249.174522 -52.161088) (xy 249.13844 -52.172362)
			(xy 249.128616 -52.175851) (xy 249.112727 -52.189319) (xy 249.103444 -52.207965) (xy 249.102372 -52.218336)
			(xy 249.099675 -52.260463) (xy 249.087279 -52.34397) (xy 249.067027 -52.425926) (xy 249.039099 -52.505595)
			(xy 249.003748 -52.582258) (xy 248.961291 -52.655227) (xy 248.912112 -52.723845) (xy 248.856651 -52.787493)
			(xy 248.795409 -52.8456) (xy 248.728936 -52.897642) (xy 248.657831 -52.943151) (xy 248.582733 -52.981717)
			(xy 248.504319 -53.012994) (xy 248.423294 -53.036699) (xy 248.340387 -53.052621) (xy 248.256345 -53.060614)
			(xy 248.214134 -53.061108) (xy 248.171669 -53.060607) (xy 248.087125 -53.052507) (xy 248.003739 -53.036385)
			(xy 247.922268 -53.01239) (xy 247.843456 -52.98074) (xy 247.768018 -52.941722) (xy 247.696643 -52.895693)
			(xy 247.629979 -52.84307) (xy 247.568634 -52.784334) (xy 247.540526 -52.752498) (xy 247.534176 -52.745132)
			(xy 247.517412 -52.736496) (xy 247.429274 -52.726336) (xy 247.410986 -52.731416) (xy 247.403112 -52.737258)
			(xy 247.370277 -52.761024) (xy 247.301045 -52.803187) (xy 247.228263 -52.838875) (xy 247.152535 -52.867791)
			(xy 247.07449 -52.889697) (xy 246.994775 -52.904409) (xy 246.914052 -52.911805) (xy 246.873522 -52.912264)
			(xy 246.831202 -52.911724) (xy 246.746946 -52.903656) (xy 246.663838 -52.887619) (xy 246.58263 -52.863758)
			(xy 246.504056 -52.83229) (xy 246.428827 -52.793499) (xy 246.392954 -52.77104) (xy 246.38456 -52.766177)
			(xy 246.365522 -52.762524) (xy 246.346484 -52.766177) (xy 246.33809 -52.77104) (xy 246.302222 -52.793507)
			(xy 246.226987 -52.832285) (xy 246.148411 -52.863747) (xy 246.067203 -52.887609) (xy 245.984096 -52.903654)
			(xy 245.899842 -52.911738) (xy 245.857522 -52.912264) (xy 245.813221 -52.911666) (xy 245.725058 -52.90285)
			(xy 245.638208 -52.885314) (xy 245.553531 -52.85923) (xy 245.471867 -52.824858) (xy 245.394025 -52.782538)
			(xy 245.320775 -52.732689) (xy 245.252843 -52.675806) (xy 245.190903 -52.61245) (xy 245.135568 -52.543252)
			(xy 245.111016 -52.506372) (xy 245.106055 -52.499361) (xy 245.092457 -52.488884) (xy 245.076169 -52.483465)
			(xy 245.067582 -52.483258) (xy 245.060978 -52.483258) (xy 245.033722 -52.482865) (xy 244.979766 -52.475104)
			(xy 244.927464 -52.459743) (xy 244.87788 -52.437094) (xy 244.832025 -52.407619) (xy 244.790831 -52.371918)
			(xy 244.755138 -52.330717) (xy 244.725671 -52.284856) (xy 244.703032 -52.235269) (xy 244.68768 -52.182963)
			(xy 244.679929 -52.129006) (xy 244.67947 -52.10175) (xy 207.921092 -52.10175) (xy 207.914102 -52.242926)
			(xy 207.898083 -52.404285) (xy 207.874105 -52.564654) (xy 207.842224 -52.723642) (xy 207.802521 -52.880858)
			(xy 207.755091 -53.035918) (xy 207.70005 -53.188443) (xy 207.637535 -53.33806) (xy 207.567696 -53.484401)
			(xy 207.490706 -53.62711) (xy 207.406753 -53.765837) (xy 207.316041 -53.900242) (xy 207.218794 -54.029997)
			(xy 207.115249 -54.154784) (xy 207.00566 -54.274298) (xy 206.890294 -54.388245) (xy 206.769434 -54.496348)
			(xy 206.643376 -54.598342) (xy 206.512428 -54.693977) (xy 206.376912 -54.783019) (xy 206.237157 -54.86525)
			(xy 206.093507 -54.940469) (xy 205.946312 -55.008492) (xy 205.795934 -55.069153) (xy 205.64274 -55.122303)
			(xy 205.487105 -55.167811) (xy 205.32941 -55.205567) (xy 205.17004 -55.235479) (xy 205.009386 -55.257472)
			(xy 204.847842 -55.271493) (xy 204.685801 -55.277509) (xy 204.523661 -55.275503) (xy 204.361819 -55.265482)
			(xy 204.200671 -55.247469) (xy 204.04061 -55.221509) (xy 203.882029 -55.187664) (xy 203.725316 -55.146019)
			(xy 203.570854 -55.096675) (xy 203.419022 -55.039753) (xy 203.27019 -54.975391) (xy 203.124723 -54.903748)
			(xy 202.982977 -54.824999) (xy 202.845299 -54.739336) (xy 202.712026 -54.646969) (xy 202.583484 -54.548125)
			(xy 202.459987 -54.443044) (xy 202.341839 -54.331985) (xy 202.229327 -54.215219) (xy 202.122727 -54.093031)
			(xy 202.0223 -53.965721) (xy 201.928292 -53.833601) (xy 201.840933 -53.696993) (xy 201.760436 -53.556232)
			(xy 201.687 -53.411662) (xy 201.620802 -53.263638) (xy 201.562006 -53.112521) (xy 201.510755 -52.958681)
			(xy 201.467175 -52.802495) (xy 201.431372 -52.644345) (xy 201.403434 -52.484618) (xy 201.38343 -52.323704)
			(xy 201.371407 -52.161999) (xy 201.367397 -51.999896) (xy 179.393596 -51.999896) (xy 179.393596 -52.481734)
			(xy 179.39311 -52.509003) (xy 179.385348 -52.562987) (xy 179.369983 -52.615317) (xy 179.347326 -52.664927)
			(xy 179.31784 -52.710808) (xy 179.282125 -52.752025) (xy 179.240908 -52.78774) (xy 179.195027 -52.817226)
			(xy 179.145417 -52.839883) (xy 179.093087 -52.855248) (xy 179.039103 -52.86301) (xy 178.984565 -52.86301)
			(xy 178.930581 -52.855248) (xy 178.878251 -52.839883) (xy 178.828641 -52.817226) (xy 178.78276 -52.78774)
			(xy 178.741543 -52.752025) (xy 178.705828 -52.710808) (xy 178.676342 -52.664927) (xy 178.653685 -52.615317)
			(xy 178.63832 -52.562987) (xy 178.630558 -52.509003) (xy 178.630072 -52.481734) (xy 0.509016 -52.481734)
			(xy 0.509016 -53.954934) (xy 181.659784 -53.954934) (xy 181.659784 -53.091334) (xy 181.66027 -53.064065)
			(xy 181.668032 -53.010081) (xy 181.683397 -52.957751) (xy 181.706054 -52.908141) (xy 181.73554 -52.86226)
			(xy 181.771255 -52.821043) (xy 181.812472 -52.785328) (xy 181.858353 -52.755842) (xy 181.907963 -52.733185)
			(xy 181.960293 -52.71782) (xy 182.014277 -52.710058) (xy 182.068815 -52.710058) (xy 182.122799 -52.71782)
			(xy 182.175129 -52.733185) (xy 182.224739 -52.755842) (xy 182.27062 -52.785328) (xy 182.311837 -52.821043)
			(xy 182.347552 -52.86226) (xy 182.377038 -52.908141) (xy 182.399695 -52.957751) (xy 182.41506 -53.010081)
			(xy 182.422822 -53.064065) (xy 182.423308 -53.091334) (xy 182.423308 -53.954934) (xy 182.422822 -53.982203)
			(xy 182.41506 -54.036187) (xy 182.399695 -54.088517) (xy 182.377038 -54.138127) (xy 182.347552 -54.184008)
			(xy 182.311837 -54.225225) (xy 182.27062 -54.26094) (xy 182.224739 -54.290426) (xy 182.175129 -54.313083)
			(xy 182.122799 -54.328448) (xy 182.068815 -54.33621) (xy 182.014277 -54.33621) (xy 181.960293 -54.328448)
			(xy 181.907963 -54.313083) (xy 181.858353 -54.290426) (xy 181.812472 -54.26094) (xy 181.771255 -54.225225)
			(xy 181.73554 -54.184008) (xy 181.706054 -54.138127) (xy 181.683397 -54.088517) (xy 181.668032 -54.036187)
			(xy 181.66027 -53.982203) (xy 181.659784 -53.954934) (xy 0.509016 -53.954934) (xy 0.509016 -55.481728)
			(xy 178.630072 -55.481728) (xy 178.630072 -54.618128) (xy 178.630558 -54.590859) (xy 178.63832 -54.536875)
			(xy 178.653685 -54.484545) (xy 178.676342 -54.434935) (xy 178.705828 -54.389054) (xy 178.741543 -54.347837)
			(xy 178.78276 -54.312122) (xy 178.828641 -54.282636) (xy 178.878251 -54.259979) (xy 178.930581 -54.244614)
			(xy 178.984565 -54.236852) (xy 179.039103 -54.236852) (xy 179.093087 -54.244614) (xy 179.145417 -54.259979)
			(xy 179.195027 -54.282636) (xy 179.240908 -54.312122) (xy 179.282125 -54.347837) (xy 179.31784 -54.389054)
			(xy 179.347326 -54.434935) (xy 179.369983 -54.484545) (xy 179.385348 -54.536875) (xy 179.39311 -54.590859)
			(xy 179.393596 -54.618128) (xy 179.393596 -55.481728) (xy 179.39311 -55.508997) (xy 179.385348 -55.562981)
			(xy 179.369983 -55.615311) (xy 179.347326 -55.664921) (xy 179.31784 -55.710802) (xy 179.282125 -55.752019)
			(xy 179.240908 -55.787734) (xy 179.195027 -55.81722) (xy 179.145417 -55.839877) (xy 179.093087 -55.855242)
			(xy 179.039103 -55.863004) (xy 178.984565 -55.863004) (xy 178.930581 -55.855242) (xy 178.878251 -55.839877)
			(xy 178.828641 -55.81722) (xy 178.78276 -55.787734) (xy 178.741543 -55.752019) (xy 178.705828 -55.710802)
			(xy 178.676342 -55.664921) (xy 178.653685 -55.615311) (xy 178.63832 -55.562981) (xy 178.630558 -55.508997)
			(xy 178.630072 -55.481728) (xy 0.509016 -55.481728) (xy 0.509016 -57.094435) (xy 170.842169 -57.094435)
			(xy 170.842169 -57.005413) (xy 170.850149 -56.916749) (xy 170.866045 -56.829158) (xy 170.889728 -56.743343)
			(xy 170.921008 -56.659998) (xy 170.959634 -56.579792) (xy 171.005293 -56.503371) (xy 171.057619 -56.43135)
			(xy 171.11619 -56.36431) (xy 171.180535 -56.30279) (xy 171.250135 -56.247286) (xy 171.324431 -56.198244)
			(xy 171.402823 -56.156059) (xy 171.484682 -56.121071) (xy 171.569347 -56.093562) (xy 171.656137 -56.073752)
			(xy 171.744353 -56.061802) (xy 171.833286 -56.057809) (xy 171.922219 -56.061802) (xy 172.010435 -56.073752)
			(xy 172.097225 -56.093562) (xy 172.18189 -56.121071) (xy 172.263749 -56.156059) (xy 172.342141 -56.198244)
			(xy 172.416437 -56.247286) (xy 172.486037 -56.30279) (xy 172.550382 -56.36431) (xy 172.608953 -56.43135)
			(xy 172.661279 -56.503371) (xy 172.706938 -56.579792) (xy 172.745564 -56.659998) (xy 172.776844 -56.743343)
			(xy 172.800527 -56.829158) (xy 172.816423 -56.916749) (xy 172.824403 -57.005413) (xy 172.824902 -57.049924)
			(xy 172.824403 -57.094435) (xy 172.816423 -57.183099) (xy 172.800527 -57.27069) (xy 172.776844 -57.356505)
			(xy 172.745564 -57.43985) (xy 172.706938 -57.520056) (xy 172.661279 -57.596477) (xy 172.608953 -57.668498)
			(xy 172.550382 -57.735538) (xy 172.486037 -57.797058) (xy 172.416437 -57.852562) (xy 172.342141 -57.901604)
			(xy 172.263749 -57.943789) (xy 172.18189 -57.978777) (xy 172.097225 -58.006286) (xy 172.010435 -58.026096)
			(xy 171.922219 -58.038046) (xy 171.833286 -58.04204) (xy 171.744353 -58.038046) (xy 171.656137 -58.026096)
			(xy 171.569347 -58.006286) (xy 171.484682 -57.978777) (xy 171.402823 -57.943789) (xy 171.324431 -57.901604)
			(xy 171.250135 -57.852562) (xy 171.180535 -57.797058) (xy 171.11619 -57.735538) (xy 171.057619 -57.668498)
			(xy 171.005293 -57.596477) (xy 170.959634 -57.520056) (xy 170.921008 -57.43985) (xy 170.889728 -57.356505)
			(xy 170.866045 -57.27069) (xy 170.850149 -57.183099) (xy 170.842169 -57.094435) (xy 0.509016 -57.094435)
			(xy 0.509016 -60.375038) (xy 233.333297 -60.375038) (xy 233.337302 -60.28713) (xy 233.349285 -60.19995)
			(xy 233.369145 -60.114221) (xy 233.39672 -60.030653) (xy 233.431779 -59.949939) (xy 233.474032 -59.872747)
			(xy 233.52313 -59.799718) (xy 233.578666 -59.731456) (xy 233.640178 -59.668526) (xy 233.707159 -59.611452)
			(xy 233.779052 -59.560704) (xy 233.855261 -59.516704) (xy 233.935156 -59.479817) (xy 234.018075 -59.450348)
			(xy 234.10333 -59.428541) (xy 234.190214 -59.414577) (xy 234.278008 -59.408571) (xy 234.365985 -59.410575)
			(xy 234.453415 -59.42057) (xy 234.539574 -59.438474) (xy 234.623748 -59.464138) (xy 234.705239 -59.497351)
			(xy 234.783373 -59.537837) (xy 234.857501 -59.585259) (xy 234.927009 -59.639226) (xy 234.991323 -59.699291)
			(xy 235.049907 -59.764955) (xy 235.102278 -59.835674) (xy 235.148001 -59.910862) (xy 235.186698 -59.989897)
			(xy 235.218047 -60.072123) (xy 235.241789 -60.156859) (xy 235.257727 -60.243403) (xy 235.265729 -60.331038)
			(xy 235.26623 -60.375038) (xy 235.265729 -60.419038) (xy 235.257727 -60.506673) (xy 235.241789 -60.593217)
			(xy 235.218047 -60.677953) (xy 235.186698 -60.760179) (xy 235.148001 -60.839214) (xy 235.102278 -60.914402)
			(xy 235.049907 -60.985121) (xy 234.991323 -61.050785) (xy 234.927009 -61.11085) (xy 234.857501 -61.164817)
			(xy 234.783373 -61.212239) (xy 234.705239 -61.252725) (xy 234.623748 -61.285938) (xy 234.539574 -61.311602)
			(xy 234.453415 -61.329506) (xy 234.365985 -61.339501) (xy 234.278008 -61.341505) (xy 234.190214 -61.335499)
			(xy 234.10333 -61.321535) (xy 234.018075 -61.299728) (xy 233.935156 -61.270259) (xy 233.855261 -61.233372)
			(xy 233.779052 -61.189372) (xy 233.707159 -61.138624) (xy 233.640178 -61.08155) (xy 233.578666 -61.01862)
			(xy 233.52313 -60.950358) (xy 233.474032 -60.877329) (xy 233.431779 -60.800137) (xy 233.39672 -60.719423)
			(xy 233.369145 -60.635855) (xy 233.349285 -60.550126) (xy 233.337302 -60.462946) (xy 233.333297 -60.375038)
			(xy 0.509016 -60.375038) (xy 0.509016 -74.760836) (xy 39.554404 -74.760836) (xy 39.554404 -66.060828)
			(xy 39.554909 -65.955304) (xy 39.562993 -65.74441) (xy 39.579149 -65.533981) (xy 39.603352 -65.324324)
			(xy 39.635569 -65.115749) (xy 39.675751 -64.908561) (xy 39.723839 -64.703064) (xy 39.779763 -64.49956)
			(xy 39.84344 -64.298347) (xy 39.914778 -64.09972) (xy 39.993672 -63.903972) (xy 40.080005 -63.71139)
			(xy 40.173652 -63.522255) (xy 40.274474 -63.336846) (xy 40.382324 -63.155435) (xy 40.497043 -62.978288)
			(xy 40.618463 -62.805666) (xy 40.746406 -62.63782) (xy 40.880684 -62.474998) (xy 41.0211 -62.317439)
			(xy 41.167448 -62.165374) (xy 41.319513 -62.019026) (xy 41.477072 -61.87861) (xy 41.639894 -61.744332)
			(xy 41.80774 -61.616389) (xy 41.980362 -61.494969) (xy 42.157509 -61.38025) (xy 42.33892 -61.2724)
			(xy 42.524329 -61.171578) (xy 42.713464 -61.077931) (xy 42.906046 -60.991598) (xy 43.101794 -60.912704)
			(xy 43.300421 -60.841366) (xy 43.501634 -60.777689) (xy 43.705138 -60.721765) (xy 43.910635 -60.673677)
			(xy 44.117823 -60.633495) (xy 44.326398 -60.601278) (xy 44.536055 -60.577075) (xy 44.746484 -60.560919)
			(xy 44.957378 -60.552835) (xy 45.168426 -60.552835) (xy 45.37932 -60.560919) (xy 45.589749 -60.577075)
			(xy 45.799406 -60.601278) (xy 46.007981 -60.633495) (xy 46.215169 -60.673677) (xy 46.420666 -60.721765)
			(xy 46.62417 -60.777689) (xy 46.825383 -60.841366) (xy 47.02401 -60.912704) (xy 47.219758 -60.991598)
			(xy 47.41234 -61.077931) (xy 47.601475 -61.171578) (xy 47.786884 -61.2724) (xy 47.968295 -61.38025)
			(xy 48.145442 -61.494969) (xy 48.318064 -61.616389) (xy 48.48591 -61.744332) (xy 48.648732 -61.87861)
			(xy 48.806291 -62.019026) (xy 48.958356 -62.165374) (xy 49.104704 -62.317439) (xy 49.24512 -62.474998)
			(xy 49.379398 -62.63782) (xy 49.507341 -62.805666) (xy 49.628761 -62.978288) (xy 49.74348 -63.155435)
			(xy 49.85133 -63.336846) (xy 49.952152 -63.522255) (xy 50.045799 -63.71139) (xy 50.132132 -63.903972)
			(xy 50.211026 -64.09972) (xy 50.282364 -64.298347) (xy 50.346041 -64.49956) (xy 50.401965 -64.703064)
			(xy 50.450053 -64.908561) (xy 50.490235 -65.115749) (xy 50.522452 -65.324324) (xy 50.546655 -65.533981)
			(xy 50.562811 -65.74441) (xy 50.570895 -65.955304) (xy 50.5714 -66.060828) (xy 50.5714 -74.760836)
			(xy 50.571366 -74.767948) (xy 173.354492 -74.767948) (xy 173.354492 -66.06794) (xy 173.354997 -65.962416)
			(xy 173.363081 -65.751522) (xy 173.379237 -65.541093) (xy 173.40344 -65.331436) (xy 173.435657 -65.122861)
			(xy 173.475839 -64.915673) (xy 173.523927 -64.710176) (xy 173.579851 -64.506672) (xy 173.643528 -64.305459)
			(xy 173.714866 -64.106832) (xy 173.79376 -63.911084) (xy 173.880093 -63.718502) (xy 173.97374 -63.529367)
			(xy 174.074562 -63.343958) (xy 174.182412 -63.162547) (xy 174.297131 -62.9854) (xy 174.418551 -62.812778)
			(xy 174.546494 -62.644932) (xy 174.680772 -62.48211) (xy 174.821188 -62.324551) (xy 174.967536 -62.172486)
			(xy 175.119601 -62.026138) (xy 175.27716 -61.885722) (xy 175.439982 -61.751444) (xy 175.607828 -61.623501)
			(xy 175.78045 -61.502081) (xy 175.957597 -61.387362) (xy 176.139008 -61.279512) (xy 176.324417 -61.17869)
			(xy 176.513552 -61.085043) (xy 176.706134 -60.99871) (xy 176.901882 -60.919816) (xy 177.100509 -60.848478)
			(xy 177.301722 -60.784801) (xy 177.505226 -60.728877) (xy 177.710723 -60.680789) (xy 177.917911 -60.640607)
			(xy 178.126486 -60.60839) (xy 178.336143 -60.584187) (xy 178.546572 -60.568031) (xy 178.757466 -60.559947)
			(xy 178.968514 -60.559947) (xy 179.179408 -60.568031) (xy 179.389837 -60.584187) (xy 179.599494 -60.60839)
			(xy 179.808069 -60.640607) (xy 180.015257 -60.680789) (xy 180.220754 -60.728877) (xy 180.424258 -60.784801)
			(xy 180.625471 -60.848478) (xy 180.824098 -60.919816) (xy 181.019846 -60.99871) (xy 181.212428 -61.085043)
			(xy 181.401563 -61.17869) (xy 181.586972 -61.279512) (xy 181.768383 -61.387362) (xy 181.94553 -61.502081)
			(xy 182.118152 -61.623501) (xy 182.285998 -61.751444) (xy 182.44882 -61.885722) (xy 182.606379 -62.026138)
			(xy 182.758444 -62.172486) (xy 182.904792 -62.324551) (xy 183.045208 -62.48211) (xy 183.179486 -62.644932)
			(xy 183.307429 -62.812778) (xy 183.428849 -62.9854) (xy 183.543568 -63.162547) (xy 183.651418 -63.343958)
			(xy 183.75224 -63.529367) (xy 183.845887 -63.718502) (xy 183.93222 -63.911084) (xy 184.011114 -64.106832)
			(xy 184.082452 -64.305459) (xy 184.146129 -64.506672) (xy 184.202053 -64.710176) (xy 184.250141 -64.915673)
			(xy 184.290323 -65.122861) (xy 184.32254 -65.331436) (xy 184.346743 -65.541093) (xy 184.362899 -65.751522)
			(xy 184.370983 -65.962416) (xy 184.371488 -66.06794) (xy 184.371488 -74.760836) (xy 287.494472 -74.760836)
			(xy 287.494472 -66.060828) (xy 287.494977 -65.955304) (xy 287.503061 -65.74441) (xy 287.519217 -65.533981)
			(xy 287.54342 -65.324324) (xy 287.575637 -65.115749) (xy 287.615819 -64.908561) (xy 287.663907 -64.703064)
			(xy 287.719831 -64.49956) (xy 287.783508 -64.298347) (xy 287.854846 -64.09972) (xy 287.93374 -63.903972)
			(xy 288.020073 -63.71139) (xy 288.11372 -63.522255) (xy 288.214542 -63.336846) (xy 288.322392 -63.155435)
			(xy 288.437111 -62.978288) (xy 288.558531 -62.805666) (xy 288.686474 -62.63782) (xy 288.820752 -62.474998)
			(xy 288.961168 -62.317439) (xy 289.107516 -62.165374) (xy 289.259581 -62.019026) (xy 289.41714 -61.87861)
			(xy 289.579962 -61.744332) (xy 289.747808 -61.616389) (xy 289.92043 -61.494969) (xy 290.097577 -61.38025)
			(xy 290.278988 -61.2724) (xy 290.464397 -61.171578) (xy 290.653532 -61.077931) (xy 290.846114 -60.991598)
			(xy 291.041862 -60.912704) (xy 291.240489 -60.841366) (xy 291.441702 -60.777689) (xy 291.645206 -60.721765)
			(xy 291.850703 -60.673677) (xy 292.057891 -60.633495) (xy 292.266466 -60.601278) (xy 292.476123 -60.577075)
			(xy 292.686552 -60.560919) (xy 292.897446 -60.552835) (xy 293.108494 -60.552835) (xy 293.319388 -60.560919)
			(xy 293.529817 -60.577075) (xy 293.739474 -60.601278) (xy 293.948049 -60.633495) (xy 294.155237 -60.673677)
			(xy 294.360734 -60.721765) (xy 294.564238 -60.777689) (xy 294.765451 -60.841366) (xy 294.964078 -60.912704)
			(xy 295.159826 -60.991598) (xy 295.352408 -61.077931) (xy 295.541543 -61.171578) (xy 295.726952 -61.2724)
			(xy 295.908363 -61.38025) (xy 296.08551 -61.494969) (xy 296.258132 -61.616389) (xy 296.425978 -61.744332)
			(xy 296.5888 -61.87861) (xy 296.746359 -62.019026) (xy 296.898424 -62.165374) (xy 297.044772 -62.317439)
			(xy 297.185188 -62.474998) (xy 297.319466 -62.63782) (xy 297.447409 -62.805666) (xy 297.568829 -62.978288)
			(xy 297.683548 -63.155435) (xy 297.791398 -63.336846) (xy 297.89222 -63.522255) (xy 297.985867 -63.71139)
			(xy 298.0722 -63.903972) (xy 298.151094 -64.09972) (xy 298.222432 -64.298347) (xy 298.286109 -64.49956)
			(xy 298.342033 -64.703064) (xy 298.390121 -64.908561) (xy 298.430303 -65.115749) (xy 298.46252 -65.324324)
			(xy 298.486723 -65.533981) (xy 298.502879 -65.74441) (xy 298.510963 -65.955304) (xy 298.511468 -66.060828)
			(xy 298.511468 -74.760836) (xy 298.511434 -74.767948) (xy 421.29456 -74.767948) (xy 421.29456 -66.06794)
			(xy 421.295065 -65.962416) (xy 421.303149 -65.751522) (xy 421.319305 -65.541093) (xy 421.343508 -65.331436)
			(xy 421.375725 -65.122861) (xy 421.415907 -64.915673) (xy 421.463995 -64.710176) (xy 421.519919 -64.506672)
			(xy 421.583596 -64.305459) (xy 421.654934 -64.106832) (xy 421.733828 -63.911084) (xy 421.820161 -63.718502)
			(xy 421.913808 -63.529367) (xy 422.01463 -63.343958) (xy 422.12248 -63.162547) (xy 422.237199 -62.9854)
			(xy 422.358619 -62.812778) (xy 422.486562 -62.644932) (xy 422.62084 -62.48211) (xy 422.761256 -62.324551)
			(xy 422.907604 -62.172486) (xy 423.059669 -62.026138) (xy 423.217228 -61.885722) (xy 423.38005 -61.751444)
			(xy 423.547896 -61.623501) (xy 423.720518 -61.502081) (xy 423.897665 -61.387362) (xy 424.079076 -61.279512)
			(xy 424.264485 -61.17869) (xy 424.45362 -61.085043) (xy 424.646202 -60.99871) (xy 424.84195 -60.919816)
			(xy 425.040577 -60.848478) (xy 425.24179 -60.784801) (xy 425.445294 -60.728877) (xy 425.650791 -60.680789)
			(xy 425.857979 -60.640607) (xy 426.066554 -60.60839) (xy 426.276211 -60.584187) (xy 426.48664 -60.568031)
			(xy 426.697534 -60.559947) (xy 426.908582 -60.559947) (xy 427.119476 -60.568031) (xy 427.329905 -60.584187)
			(xy 427.539562 -60.60839) (xy 427.748137 -60.640607) (xy 427.955325 -60.680789) (xy 428.160822 -60.728877)
			(xy 428.364326 -60.784801) (xy 428.565539 -60.848478) (xy 428.764166 -60.919816) (xy 428.959914 -60.99871)
			(xy 429.152496 -61.085043) (xy 429.341631 -61.17869) (xy 429.52704 -61.279512) (xy 429.708451 -61.387362)
			(xy 429.885598 -61.502081) (xy 430.05822 -61.623501) (xy 430.226066 -61.751444) (xy 430.388888 -61.885722)
			(xy 430.546447 -62.026138) (xy 430.698512 -62.172486) (xy 430.84486 -62.324551) (xy 430.985276 -62.48211)
			(xy 431.119554 -62.644932) (xy 431.247497 -62.812778) (xy 431.368917 -62.9854) (xy 431.483636 -63.162547)
			(xy 431.591486 -63.343958) (xy 431.692308 -63.529367) (xy 431.785955 -63.718502) (xy 431.872288 -63.911084)
			(xy 431.951182 -64.106832) (xy 432.02252 -64.305459) (xy 432.086197 -64.506672) (xy 432.142121 -64.710176)
			(xy 432.190209 -64.915673) (xy 432.230391 -65.122861) (xy 432.262608 -65.331436) (xy 432.286811 -65.541093)
			(xy 432.302967 -65.751522) (xy 432.311051 -65.962416) (xy 432.311556 -66.06794) (xy 432.311556 -74.767948)
			(xy 432.311051 -74.873472) (xy 432.302967 -75.084366) (xy 432.286811 -75.294795) (xy 432.262608 -75.504452)
			(xy 432.230391 -75.713027) (xy 432.190209 -75.920215) (xy 432.142121 -76.125712) (xy 432.086197 -76.329216)
			(xy 432.02252 -76.530429) (xy 431.951182 -76.729056) (xy 431.872288 -76.924804) (xy 431.785955 -77.117386)
			(xy 431.692308 -77.306521) (xy 431.591486 -77.49193) (xy 431.483636 -77.673341) (xy 431.368917 -77.850488)
			(xy 431.247497 -78.02311) (xy 431.119554 -78.190956) (xy 430.985276 -78.353778) (xy 430.84486 -78.511337)
			(xy 430.698512 -78.663402) (xy 430.546447 -78.80975) (xy 430.388888 -78.950166) (xy 430.226066 -79.084444)
			(xy 430.05822 -79.212387) (xy 429.885598 -79.333807) (xy 429.708451 -79.448526) (xy 429.52704 -79.556376)
			(xy 429.341631 -79.657198) (xy 429.152496 -79.750845) (xy 428.959914 -79.837178) (xy 428.764166 -79.916072)
			(xy 428.565539 -79.98741) (xy 428.364326 -80.051087) (xy 428.160822 -80.107011) (xy 427.955325 -80.155099)
			(xy 427.748137 -80.195281) (xy 427.539562 -80.227498) (xy 427.329905 -80.251701) (xy 427.119476 -80.267857)
			(xy 426.908582 -80.275941) (xy 426.697534 -80.275941) (xy 426.48664 -80.267857) (xy 426.276211 -80.251701)
			(xy 426.066554 -80.227498) (xy 425.857979 -80.195281) (xy 425.650791 -80.155099) (xy 425.445294 -80.107011)
			(xy 425.24179 -80.051087) (xy 425.040577 -79.98741) (xy 424.84195 -79.916072) (xy 424.646202 -79.837178)
			(xy 424.45362 -79.750845) (xy 424.264485 -79.657198) (xy 424.079076 -79.556376) (xy 423.897665 -79.448526)
			(xy 423.720518 -79.333807) (xy 423.547896 -79.212387) (xy 423.38005 -79.084444) (xy 423.217228 -78.950166)
			(xy 423.059669 -78.80975) (xy 422.907604 -78.663402) (xy 422.761256 -78.511337) (xy 422.62084 -78.353778)
			(xy 422.486562 -78.190956) (xy 422.358619 -78.02311) (xy 422.237199 -77.850488) (xy 422.12248 -77.673341)
			(xy 422.01463 -77.49193) (xy 421.913808 -77.306521) (xy 421.820161 -77.117386) (xy 421.733828 -76.924804)
			(xy 421.654934 -76.729056) (xy 421.583596 -76.530429) (xy 421.519919 -76.329216) (xy 421.463995 -76.125712)
			(xy 421.415907 -75.920215) (xy 421.375725 -75.713027) (xy 421.343508 -75.504452) (xy 421.319305 -75.294795)
			(xy 421.303149 -75.084366) (xy 421.295065 -74.873472) (xy 421.29456 -74.767948) (xy 298.511434 -74.767948)
			(xy 298.510963 -74.86636) (xy 298.502879 -75.077254) (xy 298.486723 -75.287683) (xy 298.46252 -75.49734)
			(xy 298.430303 -75.705915) (xy 298.390121 -75.913103) (xy 298.342033 -76.1186) (xy 298.286109 -76.322104)
			(xy 298.222432 -76.523317) (xy 298.151094 -76.721944) (xy 298.0722 -76.917692) (xy 297.985867 -77.110274)
			(xy 297.89222 -77.299409) (xy 297.791398 -77.484818) (xy 297.683548 -77.666229) (xy 297.568829 -77.843376)
			(xy 297.447409 -78.015998) (xy 297.319466 -78.183844) (xy 297.185188 -78.346666) (xy 297.044772 -78.504225)
			(xy 296.898424 -78.65629) (xy 296.746359 -78.802638) (xy 296.5888 -78.943054) (xy 296.425978 -79.077332)
			(xy 296.258132 -79.205275) (xy 296.08551 -79.326695) (xy 295.908363 -79.441414) (xy 295.726952 -79.549264)
			(xy 295.541543 -79.650086) (xy 295.352408 -79.743733) (xy 295.159826 -79.830066) (xy 294.964078 -79.90896)
			(xy 294.765451 -79.980298) (xy 294.564238 -80.043975) (xy 294.360734 -80.099899) (xy 294.155237 -80.147987)
			(xy 293.948049 -80.188169) (xy 293.739474 -80.220386) (xy 293.529817 -80.244589) (xy 293.319388 -80.260745)
			(xy 293.108494 -80.268829) (xy 292.897446 -80.268829) (xy 292.686552 -80.260745) (xy 292.476123 -80.244589)
			(xy 292.266466 -80.220386) (xy 292.057891 -80.188169) (xy 291.850703 -80.147987) (xy 291.645206 -80.099899)
			(xy 291.441702 -80.043975) (xy 291.240489 -79.980298) (xy 291.041862 -79.90896) (xy 290.846114 -79.830066)
			(xy 290.653532 -79.743733) (xy 290.464397 -79.650086) (xy 290.278988 -79.549264) (xy 290.097577 -79.441414)
			(xy 289.92043 -79.326695) (xy 289.747808 -79.205275) (xy 289.579962 -79.077332) (xy 289.41714 -78.943054)
			(xy 289.259581 -78.802638) (xy 289.107516 -78.65629) (xy 288.961168 -78.504225) (xy 288.820752 -78.346666)
			(xy 288.686474 -78.183844) (xy 288.558531 -78.015998) (xy 288.437111 -77.843376) (xy 288.322392 -77.666229)
			(xy 288.214542 -77.484818) (xy 288.11372 -77.299409) (xy 288.020073 -77.110274) (xy 287.93374 -76.917692)
			(xy 287.854846 -76.721944) (xy 287.783508 -76.523317) (xy 287.719831 -76.322104) (xy 287.663907 -76.1186)
			(xy 287.615819 -75.913103) (xy 287.575637 -75.705915) (xy 287.54342 -75.49734) (xy 287.519217 -75.287683)
			(xy 287.503061 -75.077254) (xy 287.494977 -74.86636) (xy 287.494472 -74.760836) (xy 184.371488 -74.760836)
			(xy 184.371488 -74.767948) (xy 184.370983 -74.873472) (xy 184.362899 -75.084366) (xy 184.346743 -75.294795)
			(xy 184.32254 -75.504452) (xy 184.290323 -75.713027) (xy 184.250141 -75.920215) (xy 184.202053 -76.125712)
			(xy 184.146129 -76.329216) (xy 184.082452 -76.530429) (xy 184.011114 -76.729056) (xy 183.93222 -76.924804)
			(xy 183.845887 -77.117386) (xy 183.75224 -77.306521) (xy 183.651418 -77.49193) (xy 183.543568 -77.673341)
			(xy 183.428849 -77.850488) (xy 183.307429 -78.02311) (xy 183.179486 -78.190956) (xy 183.045208 -78.353778)
			(xy 182.904792 -78.511337) (xy 182.758444 -78.663402) (xy 182.606379 -78.80975) (xy 182.44882 -78.950166)
			(xy 182.285998 -79.084444) (xy 182.118152 -79.212387) (xy 181.94553 -79.333807) (xy 181.768383 -79.448526)
			(xy 181.586972 -79.556376) (xy 181.401563 -79.657198) (xy 181.212428 -79.750845) (xy 181.019846 -79.837178)
			(xy 180.824098 -79.916072) (xy 180.625471 -79.98741) (xy 180.424258 -80.051087) (xy 180.220754 -80.107011)
			(xy 180.015257 -80.155099) (xy 179.808069 -80.195281) (xy 179.599494 -80.227498) (xy 179.389837 -80.251701)
			(xy 179.179408 -80.267857) (xy 178.968514 -80.275941) (xy 178.757466 -80.275941) (xy 178.546572 -80.267857)
			(xy 178.336143 -80.251701) (xy 178.126486 -80.227498) (xy 177.917911 -80.195281) (xy 177.710723 -80.155099)
			(xy 177.505226 -80.107011) (xy 177.301722 -80.051087) (xy 177.100509 -79.98741) (xy 176.901882 -79.916072)
			(xy 176.706134 -79.837178) (xy 176.513552 -79.750845) (xy 176.324417 -79.657198) (xy 176.139008 -79.556376)
			(xy 175.957597 -79.448526) (xy 175.78045 -79.333807) (xy 175.607828 -79.212387) (xy 175.439982 -79.084444)
			(xy 175.27716 -78.950166) (xy 175.119601 -78.80975) (xy 174.967536 -78.663402) (xy 174.821188 -78.511337)
			(xy 174.680772 -78.353778) (xy 174.546494 -78.190956) (xy 174.418551 -78.02311) (xy 174.297131 -77.850488)
			(xy 174.182412 -77.673341) (xy 174.074562 -77.49193) (xy 173.97374 -77.306521) (xy 173.880093 -77.117386)
			(xy 173.79376 -76.924804) (xy 173.714866 -76.729056) (xy 173.643528 -76.530429) (xy 173.579851 -76.329216)
			(xy 173.523927 -76.125712) (xy 173.475839 -75.920215) (xy 173.435657 -75.713027) (xy 173.40344 -75.504452)
			(xy 173.379237 -75.294795) (xy 173.363081 -75.084366) (xy 173.354997 -74.873472) (xy 173.354492 -74.767948)
			(xy 50.571366 -74.767948) (xy 50.570895 -74.86636) (xy 50.562811 -75.077254) (xy 50.546655 -75.287683)
			(xy 50.522452 -75.49734) (xy 50.490235 -75.705915) (xy 50.450053 -75.913103) (xy 50.401965 -76.1186)
			(xy 50.346041 -76.322104) (xy 50.282364 -76.523317) (xy 50.211026 -76.721944) (xy 50.132132 -76.917692)
			(xy 50.045799 -77.110274) (xy 49.952152 -77.299409) (xy 49.85133 -77.484818) (xy 49.74348 -77.666229)
			(xy 49.628761 -77.843376) (xy 49.507341 -78.015998) (xy 49.379398 -78.183844) (xy 49.24512 -78.346666)
			(xy 49.104704 -78.504225) (xy 48.958356 -78.65629) (xy 48.806291 -78.802638) (xy 48.648732 -78.943054)
			(xy 48.48591 -79.077332) (xy 48.318064 -79.205275) (xy 48.145442 -79.326695) (xy 47.968295 -79.441414)
			(xy 47.786884 -79.549264) (xy 47.601475 -79.650086) (xy 47.41234 -79.743733) (xy 47.219758 -79.830066)
			(xy 47.02401 -79.90896) (xy 46.825383 -79.980298) (xy 46.62417 -80.043975) (xy 46.420666 -80.099899)
			(xy 46.215169 -80.147987) (xy 46.007981 -80.188169) (xy 45.799406 -80.220386) (xy 45.589749 -80.244589)
			(xy 45.37932 -80.260745) (xy 45.168426 -80.268829) (xy 44.957378 -80.268829) (xy 44.746484 -80.260745)
			(xy 44.536055 -80.244589) (xy 44.326398 -80.220386) (xy 44.117823 -80.188169) (xy 43.910635 -80.147987)
			(xy 43.705138 -80.099899) (xy 43.501634 -80.043975) (xy 43.300421 -79.980298) (xy 43.101794 -79.90896)
			(xy 42.906046 -79.830066) (xy 42.713464 -79.743733) (xy 42.524329 -79.650086) (xy 42.33892 -79.549264)
			(xy 42.157509 -79.441414) (xy 41.980362 -79.326695) (xy 41.80774 -79.205275) (xy 41.639894 -79.077332)
			(xy 41.477072 -78.943054) (xy 41.319513 -78.802638) (xy 41.167448 -78.65629) (xy 41.0211 -78.504225)
			(xy 40.880684 -78.346666) (xy 40.746406 -78.183844) (xy 40.618463 -78.015998) (xy 40.497043 -77.843376)
			(xy 40.382324 -77.666229) (xy 40.274474 -77.484818) (xy 40.173652 -77.299409) (xy 40.080005 -77.110274)
			(xy 39.993672 -76.917692) (xy 39.914778 -76.721944) (xy 39.84344 -76.523317) (xy 39.779763 -76.322104)
			(xy 39.723839 -76.1186) (xy 39.675751 -75.913103) (xy 39.635569 -75.705915) (xy 39.603352 -75.49734)
			(xy 39.579149 -75.287683) (xy 39.562993 -75.077254) (xy 39.554909 -74.86636) (xy 39.554404 -74.760836)
			(xy 0.509016 -74.760836) (xy 0.509016 -77.67193) (xy 0.5095 -77.725143) (xy 0.517108 -77.831296)
			(xy 0.532269 -77.936637) (xy 0.554904 -78.040627) (xy 0.584899 -78.142739) (xy 0.622101 -78.242451)
			(xy 0.666319 -78.339256) (xy 0.71733 -78.43266) (xy 0.774873 -78.522188) (xy 0.838654 -78.607384)
			(xy 0.90835 -78.687813) (xy 0.945642 -78.725776) (xy 1.77419 -79.554324) (xy 1.823612 -79.604428)
			(xy 1.917404 -79.709374) (xy 2.005163 -79.819414) (xy 2.086614 -79.934202) (xy 2.161501 -80.053377)
			(xy 2.229587 -80.176563) (xy 2.290658 -80.303374) (xy 2.344523 -80.433409) (xy 2.391012 -80.56626)
			(xy 2.429978 -80.701509) (xy 2.461299 -80.83873) (xy 2.484876 -80.977491) (xy 2.500635 -81.117356)
			(xy 2.508527 -81.257885) (xy 2.509012 -81.32826) (xy 2.509012 -81.691972) (xy 232.140715 -81.691972)
			(xy 232.145114 -81.518126) (xy 232.157548 -81.34467) (xy 232.177991 -81.171975) (xy 232.206398 -81.00041)
			(xy 232.242709 -80.830342) (xy 232.286847 -80.662135) (xy 232.338717 -80.49615) (xy 232.398207 -80.332741)
			(xy 232.465191 -80.172258) (xy 232.539525 -80.015044) (xy 232.62105 -79.861437) (xy 232.709592 -79.711764)
			(xy 232.804961 -79.566346) (xy 232.906953 -79.425495) (xy 233.015351 -79.289511) (xy 233.129921 -79.158685)
			(xy 233.250418 -79.033298) (xy 233.376586 -78.913618) (xy 233.508153 -78.799901) (xy 233.644839 -78.69239)
			(xy 233.715306 -78.641448) (xy 238.084614 -78.641448) (xy 238.155081 -78.69239) (xy 238.291767 -78.799901)
			(xy 238.423334 -78.913618) (xy 238.549502 -79.033298) (xy 238.669999 -79.158685) (xy 238.784569 -79.289511)
			(xy 238.892967 -79.425495) (xy 238.994959 -79.566346) (xy 239.090328 -79.711764) (xy 239.17887 -79.861437)
			(xy 239.260395 -80.015044) (xy 239.334729 -80.172258) (xy 239.401713 -80.332741) (xy 239.461203 -80.49615)
			(xy 239.513073 -80.662135) (xy 239.557211 -80.830342) (xy 239.593522 -81.00041) (xy 239.608937 -81.093507)
			(xy 398.275806 -81.093507) (xy 398.275806 -81.008785) (xy 398.283859 -80.924448) (xy 398.299893 -80.841258)
			(xy 398.323761 -80.759968) (xy 398.355249 -80.681316) (xy 398.394071 -80.606013) (xy 398.439874 -80.534741)
			(xy 398.492245 -80.468145) (xy 398.55071 -80.40683) (xy 398.614738 -80.351349) (xy 398.68375 -80.302206)
			(xy 398.75712 -80.259846) (xy 398.834185 -80.224651) (xy 398.914247 -80.196942) (xy 398.99658 -80.176968)
			(xy 399.080439 -80.164911) (xy 399.165064 -80.16088) (xy 399.249689 -80.164911) (xy 399.333548 -80.176968)
			(xy 399.415881 -80.196942) (xy 399.495943 -80.224651) (xy 399.573008 -80.259846) (xy 399.646378 -80.302206)
			(xy 399.71539 -80.351349) (xy 399.779418 -80.40683) (xy 399.837883 -80.468145) (xy 399.890254 -80.534741)
			(xy 399.936057 -80.606013) (xy 399.974879 -80.681316) (xy 400.006367 -80.759968) (xy 400.030235 -80.841258)
			(xy 400.046269 -80.924448) (xy 400.054322 -81.008785) (xy 400.054826 -81.051146) (xy 400.054322 -81.093507)
			(xy 400.046269 -81.177844) (xy 400.030235 -81.261034) (xy 400.006367 -81.342324) (xy 399.974879 -81.420976)
			(xy 399.936057 -81.496279) (xy 399.890254 -81.567551) (xy 399.837883 -81.634147) (xy 399.779418 -81.695462)
			(xy 399.71539 -81.750943) (xy 399.646378 -81.800086) (xy 399.573008 -81.842446) (xy 399.495943 -81.877641)
			(xy 399.415881 -81.90535) (xy 399.333548 -81.925324) (xy 399.249689 -81.937381) (xy 399.165064 -81.941413)
			(xy 399.080439 -81.937381) (xy 398.99658 -81.925324) (xy 398.914247 -81.90535) (xy 398.834185 -81.877641)
			(xy 398.75712 -81.842446) (xy 398.68375 -81.800086) (xy 398.614738 -81.750943) (xy 398.55071 -81.695462)
			(xy 398.492245 -81.634147) (xy 398.439874 -81.567551) (xy 398.394071 -81.496279) (xy 398.355249 -81.420976)
			(xy 398.323761 -81.342324) (xy 398.299893 -81.261034) (xy 398.283859 -81.177844) (xy 398.275806 -81.093507)
			(xy 239.608937 -81.093507) (xy 239.621929 -81.171975) (xy 239.642372 -81.34467) (xy 239.654806 -81.518126)
			(xy 239.659205 -81.691972) (xy 239.655559 -81.865835) (xy 239.643877 -82.039343) (xy 239.624183 -82.212126)
			(xy 239.596519 -82.383812) (xy 239.560945 -82.554036) (xy 239.517536 -82.722432) (xy 239.466387 -82.888641)
			(xy 239.407605 -83.052306) (xy 239.341317 -83.213078) (xy 239.267665 -83.370612) (xy 239.186806 -83.524571)
			(xy 239.098913 -83.674626) (xy 239.004175 -83.820455) (xy 238.902794 -83.961748) (xy 238.794987 -84.0982)
			(xy 238.680985 -84.229521) (xy 238.561032 -84.355429) (xy 238.435384 -84.475655) (xy 238.30431 -84.589941)
			(xy 238.168092 -84.698043) (xy 238.027019 -84.79973) (xy 237.881395 -84.894784) (xy 237.731531 -84.983001)
			(xy 237.577747 -85.064194) (xy 237.420373 -85.138187) (xy 237.259746 -85.204823) (xy 237.096208 -85.263959)
			(xy 236.930111 -85.315469) (xy 236.761809 -85.359242) (xy 236.591663 -85.395185) (xy 236.420037 -85.423221)
			(xy 236.247297 -85.443289) (xy 236.073815 -85.455348) (xy 235.89996 -85.45937) (xy 235.726105 -85.455348)
			(xy 235.552623 -85.443289) (xy 235.379883 -85.423221) (xy 235.208257 -85.395185) (xy 235.038111 -85.359242)
			(xy 234.869809 -85.315469) (xy 234.703712 -85.263959) (xy 234.540174 -85.204823) (xy 234.379547 -85.138187)
			(xy 234.222173 -85.064194) (xy 234.068389 -84.983001) (xy 233.918525 -84.894784) (xy 233.772901 -84.79973)
			(xy 233.631828 -84.698043) (xy 233.49561 -84.589941) (xy 233.364536 -84.475655) (xy 233.238888 -84.355429)
			(xy 233.118935 -84.229521) (xy 233.004933 -84.0982) (xy 232.897126 -83.961748) (xy 232.795745 -83.820455)
			(xy 232.701007 -83.674626) (xy 232.613114 -83.524571) (xy 232.532255 -83.370612) (xy 232.458603 -83.213078)
			(xy 232.392315 -83.052306) (xy 232.333533 -82.888641) (xy 232.282384 -82.722432) (xy 232.238975 -82.554036)
			(xy 232.203401 -82.383812) (xy 232.175737 -82.212126) (xy 232.156043 -82.039343) (xy 232.144361 -81.865835)
			(xy 232.140715 -81.691972) (xy 2.509012 -81.691972) (xy 2.509012 -84.065147) (xy 218.29831 -84.065147)
			(xy 218.29831 -84.010653) (xy 218.306065 -83.956712) (xy 218.321417 -83.904424) (xy 218.344054 -83.854854)
			(xy 218.373515 -83.809009) (xy 218.4092 -83.767823) (xy 218.450383 -83.732134) (xy 218.496225 -83.70267)
			(xy 218.545794 -83.680029) (xy 218.598081 -83.664672) (xy 218.652021 -83.656912) (xy 218.679268 -83.656424)
			(xy 219.542868 -83.656424) (xy 219.570125 -83.656821) (xy 219.624084 -83.664575) (xy 219.67639 -83.679929)
			(xy 219.725978 -83.702572) (xy 219.771839 -83.732041) (xy 219.813039 -83.767738) (xy 219.848739 -83.808935)
			(xy 219.878213 -83.854794) (xy 219.90086 -83.90438) (xy 219.916219 -83.956685) (xy 219.923977 -84.010643)
			(xy 219.923977 -84.065157) (xy 219.916219 -84.119115) (xy 219.90086 -84.17142) (xy 219.878213 -84.221006)
			(xy 219.848739 -84.266865) (xy 219.813039 -84.308062) (xy 219.771839 -84.343759) (xy 219.725978 -84.373228)
			(xy 219.67639 -84.395871) (xy 219.624084 -84.411225) (xy 219.570125 -84.418979) (xy 219.542868 -84.41944)
			(xy 218.679268 -84.41944) (xy 218.652021 -84.418888) (xy 218.598081 -84.411128) (xy 218.545794 -84.395771)
			(xy 218.496225 -84.37313) (xy 218.450383 -84.343666) (xy 218.4092 -84.307977) (xy 218.373515 -84.266791)
			(xy 218.344054 -84.220946) (xy 218.321417 -84.171376) (xy 218.306065 -84.119088) (xy 218.29831 -84.065147)
			(xy 2.509012 -84.065147) (xy 2.509012 -86.948548) (xy 217.344518 -86.948548) (xy 217.344518 -86.894052)
			(xy 217.352274 -86.84011) (xy 217.367627 -86.787821) (xy 217.390266 -86.738249) (xy 217.419729 -86.692404)
			(xy 217.455416 -86.651218) (xy 217.496602 -86.61553) (xy 217.542447 -86.586067) (xy 217.592019 -86.563428)
			(xy 217.644308 -86.548074) (xy 217.69825 -86.540318) (xy 217.725498 -86.539832) (xy 218.589098 -86.539832)
			(xy 218.616354 -86.540215) (xy 218.670311 -86.547972) (xy 218.722614 -86.56333) (xy 218.7722 -86.585975)
			(xy 218.818058 -86.615446) (xy 218.859255 -86.651143) (xy 218.894953 -86.69234) (xy 218.924424 -86.738198)
			(xy 218.947069 -86.787784) (xy 218.962427 -86.840087) (xy 218.970185 -86.894044) (xy 218.970185 -86.948556)
			(xy 218.962427 -87.002513) (xy 218.947069 -87.054816) (xy 218.924424 -87.104402) (xy 218.894953 -87.15026)
			(xy 218.859255 -87.191457) (xy 218.818058 -87.227154) (xy 218.7722 -87.256625) (xy 218.722614 -87.27927)
			(xy 218.670311 -87.294628) (xy 218.616354 -87.302385) (xy 218.589098 -87.302848) (xy 217.725498 -87.302848)
			(xy 217.69825 -87.302282) (xy 217.644308 -87.294526) (xy 217.592019 -87.279172) (xy 217.542447 -87.256533)
			(xy 217.496602 -87.22707) (xy 217.455416 -87.191382) (xy 217.419729 -87.150196) (xy 217.390266 -87.104351)
			(xy 217.367627 -87.054779) (xy 217.352274 -87.00249) (xy 217.344518 -86.948548) (xy 2.509012 -86.948548)
			(xy 2.509012 -106.447336) (xy 11.713464 -106.447336) (xy 11.713464 -105.456736) (xy 11.71395 -105.429467)
			(xy 11.721712 -105.375483) (xy 11.737077 -105.323153) (xy 11.759734 -105.273543) (xy 11.78922 -105.227662)
			(xy 11.824935 -105.186445) (xy 11.866152 -105.15073) (xy 11.912033 -105.121244) (xy 11.961643 -105.098587)
			(xy 12.013973 -105.083222) (xy 12.067957 -105.07546) (xy 12.122495 -105.07546) (xy 12.176479 -105.083222)
			(xy 12.228809 -105.098587) (xy 12.278419 -105.121244) (xy 12.3243 -105.15073) (xy 12.365517 -105.186445)
			(xy 12.401232 -105.227662) (xy 12.430718 -105.273543) (xy 12.453375 -105.323153) (xy 12.46874 -105.375483)
			(xy 12.476502 -105.429467) (xy 12.476988 -105.456736) (xy 12.476988 -105.664) (xy 15.57274 -105.664)
			(xy 15.57274 -104.6734) (xy 15.573226 -104.646131) (xy 15.580988 -104.592147) (xy 15.596353 -104.539817)
			(xy 15.61901 -104.490207) (xy 15.648496 -104.444326) (xy 15.684211 -104.403109) (xy 15.725428 -104.367394)
			(xy 15.771309 -104.337908) (xy 15.820919 -104.315251) (xy 15.873249 -104.299886) (xy 15.927233 -104.292124)
			(xy 15.981771 -104.292124) (xy 16.035755 -104.299886) (xy 16.088085 -104.315251) (xy 16.137695 -104.337908)
			(xy 16.146631 -104.343651) (xy 326.803 -104.343651) (xy 326.803 -104.258929) (xy 326.811053 -104.174592)
			(xy 326.827087 -104.091402) (xy 326.850955 -104.010112) (xy 326.882443 -103.93146) (xy 326.921265 -103.856157)
			(xy 326.967068 -103.784885) (xy 327.019439 -103.718289) (xy 327.077904 -103.656974) (xy 327.141932 -103.601493)
			(xy 327.210944 -103.55235) (xy 327.284314 -103.50999) (xy 327.361379 -103.474795) (xy 327.441441 -103.447086)
			(xy 327.523774 -103.427112) (xy 327.607633 -103.415055) (xy 327.692258 -103.411024) (xy 327.776883 -103.415055)
			(xy 327.860742 -103.427112) (xy 327.943075 -103.447086) (xy 328.023137 -103.474795) (xy 328.100202 -103.50999)
			(xy 328.173572 -103.55235) (xy 328.242584 -103.601493) (xy 328.306612 -103.656974) (xy 328.365077 -103.718289)
			(xy 328.417448 -103.784885) (xy 328.463251 -103.856157) (xy 328.502073 -103.93146) (xy 328.533561 -104.010112)
			(xy 328.557429 -104.091402) (xy 328.573463 -104.174592) (xy 328.581516 -104.258929) (xy 328.58202 -104.30129)
			(xy 328.581516 -104.343651) (xy 328.573463 -104.427988) (xy 328.557429 -104.511178) (xy 328.533561 -104.592468)
			(xy 328.502073 -104.67112) (xy 328.463251 -104.746423) (xy 328.417448 -104.817695) (xy 328.365077 -104.884291)
			(xy 328.306612 -104.945606) (xy 328.242584 -105.001087) (xy 328.173572 -105.05023) (xy 328.100202 -105.09259)
			(xy 328.023137 -105.127785) (xy 327.943075 -105.155494) (xy 327.860742 -105.175468) (xy 327.776883 -105.187525)
			(xy 327.692258 -105.191557) (xy 327.607633 -105.187525) (xy 327.523774 -105.175468) (xy 327.441441 -105.155494)
			(xy 327.361379 -105.127785) (xy 327.284314 -105.09259) (xy 327.210944 -105.05023) (xy 327.141932 -105.001087)
			(xy 327.077904 -104.945606) (xy 327.019439 -104.884291) (xy 326.967068 -104.817695) (xy 326.921265 -104.746423)
			(xy 326.882443 -104.67112) (xy 326.850955 -104.592468) (xy 326.827087 -104.511178) (xy 326.811053 -104.427988)
			(xy 326.803 -104.343651) (xy 16.146631 -104.343651) (xy 16.183576 -104.367394) (xy 16.224793 -104.403109)
			(xy 16.260508 -104.444326) (xy 16.289994 -104.490207) (xy 16.312651 -104.539817) (xy 16.328016 -104.592147)
			(xy 16.335778 -104.646131) (xy 16.336264 -104.6734) (xy 16.336264 -105.664) (xy 16.335778 -105.691269)
			(xy 16.328016 -105.745253) (xy 16.312651 -105.797583) (xy 16.289994 -105.847193) (xy 16.260508 -105.893074)
			(xy 16.224793 -105.934291) (xy 16.183576 -105.970006) (xy 16.137695 -105.999492) (xy 16.088085 -106.022149)
			(xy 16.035755 -106.037514) (xy 15.981771 -106.045276) (xy 15.927233 -106.045276) (xy 15.873249 -106.037514)
			(xy 15.820919 -106.022149) (xy 15.771309 -105.999492) (xy 15.725428 -105.970006) (xy 15.684211 -105.934291)
			(xy 15.648496 -105.893074) (xy 15.61901 -105.847193) (xy 15.596353 -105.797583) (xy 15.580988 -105.745253)
			(xy 15.573226 -105.691269) (xy 15.57274 -105.664) (xy 12.476988 -105.664) (xy 12.476988 -106.447336)
			(xy 12.476502 -106.474605) (xy 12.46874 -106.528589) (xy 12.453375 -106.580919) (xy 12.430718 -106.630529)
			(xy 12.401232 -106.67641) (xy 12.365517 -106.717627) (xy 12.3243 -106.753342) (xy 12.278419 -106.782828)
			(xy 12.228809 -106.805485) (xy 12.176479 -106.82085) (xy 12.122495 -106.828612) (xy 12.067957 -106.828612)
			(xy 12.013973 -106.82085) (xy 11.961643 -106.805485) (xy 11.912033 -106.782828) (xy 11.866152 -106.753342)
			(xy 11.824935 -106.717627) (xy 11.78922 -106.67641) (xy 11.759734 -106.630529) (xy 11.737077 -106.580919)
			(xy 11.721712 -106.528589) (xy 11.71395 -106.474605) (xy 11.713464 -106.447336) (xy 2.509012 -106.447336)
			(xy 2.509012 -108.943971) (xy 11.292822 -108.943971) (xy 11.292822 -108.889469) (xy 11.300578 -108.835522)
			(xy 11.315933 -108.783228) (xy 11.338574 -108.733651) (xy 11.36804 -108.687801) (xy 11.403731 -108.646611)
			(xy 11.444921 -108.61092) (xy 11.490771 -108.581454) (xy 11.540348 -108.558813) (xy 11.592642 -108.543458)
			(xy 11.646589 -108.535702) (xy 11.67384 -108.535216) (xy 12.53744 -108.535216) (xy 12.564692 -108.535694)
			(xy 12.61864 -108.54345) (xy 12.670935 -108.558806) (xy 12.720513 -108.581447) (xy 12.766364 -108.610914)
			(xy 12.807554 -108.646606) (xy 12.843246 -108.687796) (xy 12.872713 -108.733647) (xy 12.895354 -108.783225)
			(xy 12.91071 -108.83552) (xy 12.918466 -108.889468) (xy 12.918466 -108.943972) (xy 12.91071 -108.99792)
			(xy 12.895354 -109.050215) (xy 12.872713 -109.099793) (xy 12.843246 -109.145644) (xy 12.807554 -109.186834)
			(xy 12.766364 -109.222526) (xy 12.720513 -109.251993) (xy 12.670935 -109.274634) (xy 12.61864 -109.28999)
			(xy 12.564692 -109.297746) (xy 12.53744 -109.298232) (xy 11.67384 -109.298232) (xy 11.646589 -109.297738)
			(xy 11.592642 -109.289982) (xy 11.540348 -109.274627) (xy 11.490771 -109.251986) (xy 11.444921 -109.22252)
			(xy 11.403731 -109.186829) (xy 11.36804 -109.145639) (xy 11.338574 -109.099789) (xy 11.315933 -109.050212)
			(xy 11.300578 -108.997918) (xy 11.292822 -108.943971) (xy 2.509012 -108.943971) (xy 2.509012 -109.451973)
			(xy 15.092889 -109.451973) (xy 15.092889 -109.397467) (xy 15.100646 -109.343517) (xy 15.116002 -109.291219)
			(xy 15.138645 -109.241639) (xy 15.168113 -109.195786) (xy 15.203807 -109.154594) (xy 15.244999 -109.118901)
			(xy 15.290853 -109.089433) (xy 15.340433 -109.066791) (xy 15.39273 -109.051435) (xy 15.446681 -109.043679)
			(xy 15.473934 -109.043216) (xy 16.464534 -109.043216) (xy 16.491785 -109.043694) (xy 16.545733 -109.051451)
			(xy 16.598028 -109.066807) (xy 16.647605 -109.089448) (xy 16.693456 -109.118915) (xy 16.734646 -109.154607)
			(xy 16.770337 -109.195798) (xy 16.799804 -109.241648) (xy 16.822445 -109.291226) (xy 16.8378 -109.343521)
			(xy 16.845556 -109.397469) (xy 16.845556 -109.451971) (xy 16.8378 -109.505919) (xy 16.822445 -109.558214)
			(xy 16.799804 -109.607792) (xy 16.770337 -109.653642) (xy 16.734646 -109.694833) (xy 16.693456 -109.730525)
			(xy 16.647605 -109.759992) (xy 16.598028 -109.782633) (xy 16.545733 -109.797989) (xy 16.491785 -109.805746)
			(xy 16.464534 -109.806232) (xy 15.473934 -109.806232) (xy 15.446681 -109.805761) (xy 15.39273 -109.798005)
			(xy 15.340433 -109.782649) (xy 15.290853 -109.760007) (xy 15.244999 -109.730539) (xy 15.203807 -109.694846)
			(xy 15.168113 -109.653654) (xy 15.138645 -109.607801) (xy 15.116002 -109.558221) (xy 15.100646 -109.505923)
			(xy 15.092889 -109.451973) (xy 2.509012 -109.451973) (xy 2.509012 -111.974884) (xy 11.787124 -111.974884)
			(xy 11.787124 -111.263684) (xy 11.787503 -111.253557) (xy 11.795261 -111.234849) (xy 11.809589 -111.220534)
			(xy 11.828305 -111.212794) (xy 11.838432 -111.212376) (xy 11.914886 -111.212376) (xy 11.925016 -111.212839)
			(xy 11.943744 -111.220569) (xy 11.958102 -111.234863) (xy 11.965915 -111.253556) (xy 11.966448 -111.263684)
			(xy 11.966448 -111.974884) (xy 12.18692 -111.974884) (xy 12.18692 -111.263684) (xy 12.187303 -111.253558)
			(xy 12.19506 -111.23485) (xy 12.209387 -111.220536) (xy 12.228102 -111.212794) (xy 12.238228 -111.212376)
			(xy 12.314682 -111.212376) (xy 12.324812 -111.212842) (xy 12.34354 -111.220571) (xy 12.357898 -111.234864)
			(xy 12.365711 -111.253556) (xy 12.366244 -111.263684) (xy 12.366244 -111.974884) (xy 12.365703 -111.984986)
			(xy 12.357979 -112.003656) (xy 12.343699 -112.01795) (xy 12.325038 -112.025693) (xy 12.314936 -112.026192)
			(xy 12.238482 -112.026192) (xy 12.228358 -112.025689) (xy 12.209642 -112.017962) (xy 12.195288 -112.003681)
			(xy 12.187464 -111.985005) (xy 12.18692 -111.974884) (xy 11.966448 -111.974884) (xy 11.965903 -111.984986)
			(xy 11.95818 -112.003655) (xy 11.943902 -112.017948) (xy 11.925241 -112.025692) (xy 11.91514 -112.026192)
			(xy 11.838686 -112.026192) (xy 11.828562 -112.025686) (xy 11.809847 -112.017959) (xy 11.795492 -112.00368)
			(xy 11.787668 -111.985005) (xy 11.787124 -111.974884) (xy 2.509012 -111.974884) (xy 2.509012 -113.374932)
			(xy 11.787124 -113.374932) (xy 11.787124 -112.663732) (xy 11.787543 -112.653609) (xy 11.795285 -112.634901)
			(xy 11.809601 -112.620585) (xy 11.828309 -112.612843) (xy 11.838432 -112.612424) (xy 11.914886 -112.612424)
			(xy 11.92501 -112.612938) (xy 11.943728 -112.620658) (xy 11.958084 -112.634936) (xy 11.965906 -112.653611)
			(xy 11.966448 -112.663732) (xy 11.966448 -113.374932) (xy 12.18692 -113.374932) (xy 12.18692 -112.663732)
			(xy 12.187342 -112.653609) (xy 12.195084 -112.634902) (xy 12.209399 -112.620586) (xy 12.228105 -112.612843)
			(xy 12.238228 -112.612424) (xy 12.314682 -112.612424) (xy 12.324806 -112.612941) (xy 12.343523 -112.62066)
			(xy 12.35788 -112.634937) (xy 12.365702 -112.653611) (xy 12.366244 -112.663732) (xy 12.366244 -113.374932)
			(xy 12.365742 -113.385037) (xy 12.358002 -113.403708) (xy 12.343711 -113.418) (xy 12.325041 -113.425741)
			(xy 12.314936 -113.42624) (xy 12.238482 -113.42624) (xy 12.228352 -113.425788) (xy 12.209626 -113.41805)
			(xy 12.19527 -113.403753) (xy 12.187455 -113.38506) (xy 12.18692 -113.374932) (xy 11.966448 -113.374932)
			(xy 11.965942 -113.385037) (xy 11.958203 -113.403707) (xy 11.943913 -113.417999) (xy 11.925245 -113.425741)
			(xy 11.91514 -113.42624) (xy 11.838686 -113.42624) (xy 11.828556 -113.425784) (xy 11.809831 -113.418048)
			(xy 11.795474 -113.403752) (xy 11.787659 -113.38506) (xy 11.787124 -113.374932) (xy 2.509012 -113.374932)
			(xy 2.509012 -114.734161) (xy 11.255226 -114.734161) (xy 11.255226 -114.679659) (xy 11.262982 -114.625711)
			(xy 11.278337 -114.573416) (xy 11.300979 -114.523839) (xy 11.330445 -114.477988) (xy 11.366136 -114.436798)
			(xy 11.407326 -114.401106) (xy 11.453177 -114.371639) (xy 11.502754 -114.348998) (xy 11.555049 -114.333643)
			(xy 11.608997 -114.325886) (xy 11.636248 -114.3254) (xy 12.499848 -114.3254) (xy 12.527101 -114.325867)
			(xy 12.581052 -114.333624) (xy 12.633349 -114.34898) (xy 12.68293 -114.371622) (xy 12.728783 -114.40109)
			(xy 12.769975 -114.436783) (xy 12.805669 -114.477976) (xy 12.835137 -114.523829) (xy 12.85778 -114.573409)
			(xy 12.873136 -114.625706) (xy 12.880893 -114.679657) (xy 12.880893 -114.734163) (xy 12.873136 -114.788114)
			(xy 12.85778 -114.840411) (xy 12.835137 -114.889991) (xy 12.805669 -114.935844) (xy 12.769975 -114.977037)
			(xy 12.728783 -115.01273) (xy 12.68293 -115.042198) (xy 12.633349 -115.06484) (xy 12.581052 -115.080196)
			(xy 12.527101 -115.087953) (xy 12.499848 -115.088416) (xy 11.636248 -115.088416) (xy 11.608997 -115.087934)
			(xy 11.555049 -115.080177) (xy 11.502754 -115.064822) (xy 11.453177 -115.042181) (xy 11.407326 -115.012714)
			(xy 11.366136 -114.977022) (xy 11.330445 -114.935832) (xy 11.300979 -114.889981) (xy 11.278337 -114.840404)
			(xy 11.262982 -114.788109) (xy 11.255226 -114.734161) (xy 2.509012 -114.734161) (xy 2.509012 -133.480302)
			(xy 20.179284 -133.480302) (xy 20.179284 -132.489702) (xy 20.17977 -132.462451) (xy 20.187526 -132.408503)
			(xy 20.202881 -132.356208) (xy 20.225523 -132.306631) (xy 20.254989 -132.260781) (xy 20.29068 -132.21959)
			(xy 20.331871 -132.183899) (xy 20.377721 -132.154433) (xy 20.427298 -132.131791) (xy 20.479593 -132.116436)
			(xy 20.533541 -132.10868) (xy 20.588043 -132.10868) (xy 20.641991 -132.116436) (xy 20.694286 -132.131791)
			(xy 20.743863 -132.154433) (xy 20.789713 -132.183899) (xy 20.830904 -132.21959) (xy 20.866595 -132.260781)
			(xy 20.896061 -132.306631) (xy 20.918703 -132.356208) (xy 20.934058 -132.408503) (xy 20.941814 -132.462451)
			(xy 20.9423 -132.489702) (xy 20.9423 -133.480302) (xy 20.941814 -133.507553) (xy 20.934058 -133.561501)
			(xy 20.918703 -133.613796) (xy 20.896061 -133.663373) (xy 20.866595 -133.709223) (xy 20.830904 -133.750414)
			(xy 20.789713 -133.786105) (xy 20.743863 -133.815571) (xy 20.694286 -133.838213) (xy 20.641991 -133.853568)
			(xy 20.588043 -133.861324) (xy 20.533541 -133.861324) (xy 20.479593 -133.853568) (xy 20.427298 -133.838213)
			(xy 20.377721 -133.815571) (xy 20.331871 -133.786105) (xy 20.29068 -133.750414) (xy 20.254989 -133.709223)
			(xy 20.225523 -133.663373) (xy 20.202881 -133.613796) (xy 20.187526 -133.561501) (xy 20.17977 -133.507553)
			(xy 20.179284 -133.480302) (xy 2.509012 -133.480302) (xy 2.509012 -138.001502) (xy 20.019264 -138.001502)
			(xy 20.019264 -137.010902) (xy 20.01975 -136.983651) (xy 20.027506 -136.929703) (xy 20.042861 -136.877408)
			(xy 20.065503 -136.827831) (xy 20.094969 -136.781981) (xy 20.13066 -136.74079) (xy 20.171851 -136.705099)
			(xy 20.217701 -136.675633) (xy 20.267278 -136.652991) (xy 20.319573 -136.637636) (xy 20.373521 -136.62988)
			(xy 20.428023 -136.62988) (xy 20.481971 -136.637636) (xy 20.534266 -136.652991) (xy 20.583843 -136.675633)
			(xy 20.629693 -136.705099) (xy 20.670884 -136.74079) (xy 20.706575 -136.781981) (xy 20.736041 -136.827831)
			(xy 20.758683 -136.877408) (xy 20.774038 -136.929703) (xy 20.781794 -136.983651) (xy 20.78228 -137.010902)
			(xy 20.78228 -138.001502) (xy 20.781794 -138.028753) (xy 20.774038 -138.082701) (xy 20.758683 -138.134996)
			(xy 20.736041 -138.184573) (xy 20.706575 -138.230423) (xy 20.670884 -138.271614) (xy 20.629693 -138.307305)
			(xy 20.583843 -138.336771) (xy 20.534266 -138.359413) (xy 20.481971 -138.374768) (xy 20.428023 -138.382524)
			(xy 20.373521 -138.382524) (xy 20.319573 -138.374768) (xy 20.267278 -138.359413) (xy 20.217701 -138.336771)
			(xy 20.171851 -138.307305) (xy 20.13066 -138.271614) (xy 20.094969 -138.230423) (xy 20.065503 -138.184573)
			(xy 20.042861 -138.134996) (xy 20.027506 -138.082701) (xy 20.01975 -138.028753) (xy 20.019264 -138.001502)
			(xy 2.509012 -138.001502) (xy 2.509012 -145.104166) (xy 163.29995 -145.104166) (xy 163.29995 -145.049634)
			(xy 163.30771 -144.995658) (xy 163.323072 -144.943336) (xy 163.345724 -144.893732) (xy 163.375204 -144.847856)
			(xy 163.410912 -144.806643) (xy 163.452121 -144.77093) (xy 163.497993 -144.741445) (xy 163.547595 -144.718788)
			(xy 163.599915 -144.70342) (xy 163.653891 -144.695653) (xy 163.681156 -144.695164) (xy 164.671756 -144.695164)
			(xy 164.699031 -144.695573) (xy 164.753026 -144.70333) (xy 164.805368 -144.718694) (xy 164.85499 -144.74135)
			(xy 164.900882 -144.770839) (xy 164.94211 -144.806559) (xy 164.977835 -144.847783) (xy 165.007329 -144.893672)
			(xy 165.029991 -144.943291) (xy 165.045361 -144.995631) (xy 165.053124 -145.049625) (xy 165.053124 -145.104175)
			(xy 165.045361 -145.158169) (xy 165.029991 -145.210509) (xy 165.007329 -145.260128) (xy 164.977835 -145.306017)
			(xy 164.94211 -145.347241) (xy 164.900882 -145.382961) (xy 164.85499 -145.41245) (xy 164.805368 -145.435106)
			(xy 164.753026 -145.45047) (xy 164.699031 -145.458227) (xy 164.671756 -145.458688) (xy 163.681156 -145.458688)
			(xy 163.653891 -145.458147) (xy 163.599915 -145.45038) (xy 163.547595 -145.435012) (xy 163.497993 -145.412355)
			(xy 163.452121 -145.38287) (xy 163.410912 -145.347157) (xy 163.375204 -145.305944) (xy 163.345724 -145.260068)
			(xy 163.323072 -145.210464) (xy 163.30771 -145.158142) (xy 163.29995 -145.104166) (xy 2.509012 -145.104166)
			(xy 2.509012 -153.765504) (xy 24.441921 -153.765504) (xy 24.445917 -153.555618) (xy 24.457902 -153.346036)
			(xy 24.477856 -153.137062) (xy 24.505752 -152.929) (xy 24.541549 -152.72215) (xy 24.585194 -152.516813)
			(xy 24.636626 -152.313287) (xy 24.695768 -152.111866) (xy 24.762536 -151.912843) (xy 24.836832 -151.716506)
			(xy 24.91855 -151.52314) (xy 25.007569 -151.333025) (xy 25.103762 -151.146437) (xy 25.206989 -150.963646)
			(xy 25.3171 -150.784918) (xy 25.433935 -150.610511) (xy 25.557325 -150.440679) (xy 25.687092 -150.275667)
			(xy 25.823046 -150.115716) (xy 25.964992 -149.961056) (xy 26.112722 -149.811912) (xy 26.266024 -149.668501)
			(xy 26.424674 -149.53103) (xy 26.588443 -149.399698) (xy 26.757093 -149.274697) (xy 26.930379 -149.156206)
			(xy 27.108051 -149.044399) (xy 27.289851 -148.939437) (xy 27.475515 -148.841472) (xy 27.664773 -148.750647)
			(xy 27.857353 -148.667093) (xy 28.052974 -148.59093) (xy 28.251352 -148.522271) (xy 28.452201 -148.461214)
			(xy 28.655228 -148.407847) (xy 28.860141 -148.362249) (xy 29.06664 -148.324484) (xy 29.274427 -148.294609)
			(xy 29.483202 -148.272666) (xy 29.69266 -148.258687) (xy 29.902499 -148.252692) (xy 30.112413 -148.254691)
			(xy 30.3221 -148.264679) (xy 30.531254 -148.282644) (xy 30.739572 -148.308558) (xy 30.946753 -148.342383)
			(xy 31.152497 -148.384072) (xy 31.356503 -148.433564) (xy 31.558478 -148.490786) (xy 31.758128 -148.555656)
			(xy 31.955163 -148.62808) (xy 32.149299 -148.707953) (xy 32.340252 -148.795159) (xy 32.527748 -148.889571)
			(xy 32.711513 -148.991053) (xy 32.891281 -149.099457) (xy 33.066792 -149.214627) (xy 33.237791 -149.336395)
			(xy 33.404031 -149.464584) (xy 33.56527 -149.59901) (xy 33.721274 -149.739477) (xy 33.871817 -149.885781)
			(xy 34.016681 -150.03771) (xy 34.155656 -150.195044) (xy 34.288541 -150.357555) (xy 34.415142 -150.525008)
			(xy 34.535277 -150.697158) (xy 34.648771 -150.873758) (xy 34.688915 -150.941786) (xy 108.742233 -150.941786)
			(xy 108.746238 -150.836037) (xy 108.758228 -150.730894) (xy 108.778137 -150.626959) (xy 108.805848 -150.524827)
			(xy 108.841205 -150.425083) (xy 108.884003 -150.328299) (xy 108.933999 -150.235029) (xy 108.990906 -150.145808)
			(xy 109.054397 -150.061145) (xy 109.124109 -149.981527) (xy 109.199643 -149.907409) (xy 109.280566 -149.839216)
			(xy 109.366415 -149.777338) (xy 109.456698 -149.722131) (xy 109.550897 -149.673909) (xy 109.648474 -149.632949)
			(xy 109.748869 -149.599487) (xy 109.851507 -149.573713) (xy 109.9558 -149.555775) (xy 110.061151 -149.545776)
			(xy 110.166957 -149.543773) (xy 110.272611 -149.549778) (xy 110.377508 -149.563757) (xy 110.481048 -149.585628)
			(xy 110.582637 -149.615268) (xy 110.681694 -149.652506) (xy 110.777651 -149.697128) (xy 110.869958 -149.74888)
			(xy 110.958087 -149.807465) (xy 111.041533 -149.872547) (xy 111.119817 -149.943753) (xy 111.187365 -150.015249)
			(xy 160.856694 -150.015249) (xy 160.856694 -149.960751) (xy 160.86445 -149.906808) (xy 160.879803 -149.854517)
			(xy 160.902441 -149.804944) (xy 160.931904 -149.759096) (xy 160.967592 -149.717909) (xy 161.008777 -149.682219)
			(xy 161.054623 -149.652753) (xy 161.104195 -149.630111) (xy 161.156484 -149.614755) (xy 161.210427 -149.606996)
			(xy 161.237676 -149.606508) (xy 162.228276 -149.606508) (xy 162.255531 -149.606937) (xy 162.309487 -149.614692)
			(xy 162.36179 -149.630046) (xy 162.411375 -149.652688) (xy 162.457233 -149.682157) (xy 162.498431 -149.717852)
			(xy 162.534128 -149.759047) (xy 162.5636 -149.804904) (xy 162.586245 -149.854488) (xy 162.601603 -149.90679)
			(xy 162.609361 -149.960745) (xy 162.609361 -149.967557) (xy 163.793819 -149.967557) (xy 163.793819 -149.913043)
			(xy 163.801578 -149.859084) (xy 163.816937 -149.806779) (xy 163.839584 -149.757192) (xy 163.869057 -149.711333)
			(xy 163.904758 -149.670135) (xy 163.945958 -149.634438) (xy 163.99182 -149.604968) (xy 164.041409 -149.582325)
			(xy 164.093716 -149.566971) (xy 164.147675 -149.559217) (xy 164.174932 -149.558756) (xy 165.165532 -149.558756)
			(xy 165.192779 -149.559316) (xy 165.246718 -149.567076) (xy 165.299004 -149.582432) (xy 165.348573 -149.605073)
			(xy 165.394415 -149.634537) (xy 165.435597 -149.670226) (xy 165.471282 -149.711411) (xy 165.500742 -149.757255)
			(xy 165.523379 -149.806826) (xy 165.538731 -149.859113) (xy 165.546486 -149.913053) (xy 165.546486 -149.967547)
			(xy 165.538731 -150.021487) (xy 165.523379 -150.073774) (xy 165.500742 -150.123345) (xy 165.471282 -150.169189)
			(xy 165.435597 -150.210374) (xy 165.394415 -150.246063) (xy 165.348573 -150.275527) (xy 165.299004 -150.298168)
			(xy 165.246718 -150.313524) (xy 165.192779 -150.321284) (xy 165.165532 -150.321772) (xy 164.174932 -150.321772)
			(xy 164.147675 -150.321383) (xy 164.093716 -150.313629) (xy 164.041409 -150.298275) (xy 163.99182 -150.275632)
			(xy 163.945958 -150.246162) (xy 163.904758 -150.210465) (xy 163.869057 -150.169267) (xy 163.839584 -150.123408)
			(xy 163.816937 -150.073821) (xy 163.801578 -150.021516) (xy 163.793819 -149.967557) (xy 162.609361 -149.967557)
			(xy 162.609361 -150.015255) (xy 162.601603 -150.06921) (xy 162.586245 -150.121512) (xy 162.5636 -150.171096)
			(xy 162.534128 -150.216953) (xy 162.498431 -150.258148) (xy 162.457233 -150.293843) (xy 162.411375 -150.323312)
			(xy 162.36179 -150.345954) (xy 162.309487 -150.361308) (xy 162.255531 -150.369063) (xy 162.228276 -150.369524)
			(xy 161.237676 -150.369524) (xy 161.210427 -150.369004) (xy 161.156484 -150.361245) (xy 161.104195 -150.345889)
			(xy 161.054623 -150.323247) (xy 161.008777 -150.293781) (xy 160.967592 -150.258091) (xy 160.931904 -150.216904)
			(xy 160.902441 -150.171056) (xy 160.879803 -150.121483) (xy 160.86445 -150.069192) (xy 160.856694 -150.015249)
			(xy 111.187365 -150.015249) (xy 111.192492 -150.020676) (xy 111.259142 -150.102876) (xy 111.319384 -150.18988)
			(xy 111.372873 -150.281191) (xy 111.419304 -150.376286) (xy 111.458409 -150.47462) (xy 111.489966 -150.575631)
			(xy 111.513793 -150.678738) (xy 111.529754 -150.783352) (xy 111.537758 -150.888874) (xy 111.538258 -150.941786)
			(xy 111.537758 -150.994698) (xy 111.529754 -151.10022) (xy 111.513793 -151.204834) (xy 111.489966 -151.307941)
			(xy 111.458409 -151.408952) (xy 111.419304 -151.507286) (xy 111.372873 -151.602381) (xy 111.319384 -151.693692)
			(xy 111.259142 -151.780696) (xy 111.192492 -151.862896) (xy 111.119817 -151.939819) (xy 111.041533 -152.011025)
			(xy 110.958087 -152.076107) (xy 110.869958 -152.134692) (xy 110.777651 -152.186444) (xy 110.681694 -152.231066)
			(xy 110.582637 -152.268304) (xy 110.481048 -152.297944) (xy 110.377508 -152.319815) (xy 110.272611 -152.333794)
			(xy 110.166957 -152.339799) (xy 110.061151 -152.337796) (xy 109.9558 -152.327797) (xy 109.851507 -152.309859)
			(xy 109.748869 -152.284085) (xy 109.648474 -152.250623) (xy 109.550897 -152.209663) (xy 109.456698 -152.161441)
			(xy 109.366415 -152.106234) (xy 109.280566 -152.044356) (xy 109.199643 -151.976163) (xy 109.124109 -151.902045)
			(xy 109.054397 -151.822427) (xy 108.990906 -151.737764) (xy 108.933999 -151.648543) (xy 108.884003 -151.555273)
			(xy 108.841205 -151.458489) (xy 108.805848 -151.358745) (xy 108.778137 -151.256613) (xy 108.758228 -151.152678)
			(xy 108.746238 -151.047535) (xy 108.742233 -150.941786) (xy 34.688915 -150.941786) (xy 34.755459 -151.05455)
			(xy 34.855186 -151.239273) (xy 34.947809 -151.427659) (xy 35.033193 -151.619434) (xy 35.111214 -151.814321)
			(xy 35.181759 -152.012037) (xy 35.244726 -152.212295) (xy 35.300023 -152.414805) (xy 35.34757 -152.619274)
			(xy 35.354948 -152.657556) (xy 115.368832 -152.657556) (xy 115.369254 -152.619267) (xy 115.375857 -152.542973)
			(xy 115.389002 -152.46753) (xy 115.40859 -152.393499) (xy 115.421156 -152.357328) (xy 115.423829 -152.348897)
			(xy 115.423815 -152.331221) (xy 115.421156 -152.322784) (xy 115.408624 -152.286603) (xy 115.389048 -152.212571)
			(xy 115.375898 -152.137132) (xy 115.36927 -152.060844) (xy 115.368832 -152.022556) (xy 115.369211 -151.981443)
			(xy 115.376803 -151.89957) (xy 115.391918 -151.818746) (xy 115.414428 -151.739662) (xy 115.44414 -151.662993)
			(xy 115.480801 -151.589393) (xy 115.524097 -151.51949) (xy 115.573659 -151.453881) (xy 115.629065 -151.393126)
			(xy 115.689841 -151.337743) (xy 115.755469 -151.288206) (xy 115.825388 -151.244936) (xy 115.899002 -151.208303)
			(xy 115.975683 -151.178621) (xy 116.054775 -151.156141) (xy 116.135605 -151.141056) (xy 116.217481 -151.133495)
			(xy 116.258594 -151.133048) (xy 116.29691 -151.133415) (xy 116.373264 -151.139947) (xy 116.448771 -151.153032)
			(xy 116.52287 -151.172572) (xy 116.559076 -151.185118) (xy 116.567392 -151.187704) (xy 116.584796 -151.187704)
			(xy 116.593112 -151.185118) (xy 116.629327 -151.172602) (xy 116.703427 -151.153078) (xy 116.778931 -151.139993)
			(xy 116.855279 -151.133443) (xy 116.893594 -151.133048) (xy 116.933808 -151.133478) (xy 117.01391 -151.140701)
			(xy 117.093031 -151.155132) (xy 117.170525 -151.176654) (xy 117.2083 -151.190452) (xy 117.217087 -151.193359)
			(xy 117.235581 -151.193359) (xy 117.244368 -151.190452) (xy 117.282145 -151.176662) (xy 117.359642 -151.155155)
			(xy 117.438762 -151.140723) (xy 117.518861 -151.133486) (xy 117.559074 -151.133048) (xy 117.59739 -151.133421)
			(xy 117.673744 -151.139951) (xy 117.74925 -151.153034) (xy 117.82335 -151.172573) (xy 117.859556 -151.185118)
			(xy 117.867872 -151.187704) (xy 117.885276 -151.187704) (xy 117.893592 -151.185118) (xy 117.929809 -151.172608)
			(xy 118.003908 -151.153082) (xy 118.079411 -151.139995) (xy 118.155759 -151.133444) (xy 118.194074 -151.133048)
			(xy 118.23239 -151.133421) (xy 118.308744 -151.139951) (xy 118.38425 -151.153034) (xy 118.45835 -151.172573)
			(xy 118.494556 -151.185118) (xy 118.502872 -151.187704) (xy 118.520276 -151.187704) (xy 118.528592 -151.185118)
			(xy 118.564809 -151.172608) (xy 118.638908 -151.153082) (xy 118.714411 -151.139995) (xy 118.790759 -151.133444)
			(xy 118.829074 -151.133048) (xy 118.86739 -151.133421) (xy 118.943744 -151.139951) (xy 119.01925 -151.153034)
			(xy 119.09335 -151.172573) (xy 119.129556 -151.185118) (xy 119.137872 -151.187704) (xy 119.155276 -151.187704)
			(xy 119.163592 -151.185118) (xy 119.199718 -151.172636) (xy 119.273629 -151.153143) (xy 119.348939 -151.140056)
			(xy 119.425093 -151.133472) (xy 119.463312 -151.133048) (xy 119.464074 -151.133048) (xy 119.505181 -151.133537)
			(xy 119.587043 -151.141119) (xy 119.667858 -151.156221) (xy 119.746934 -151.178714) (xy 119.823598 -151.208407)
			(xy 119.897196 -151.245045) (xy 119.9671 -151.288316) (xy 120.032714 -151.337852) (xy 120.093479 -151.39323)
			(xy 120.148875 -151.453978) (xy 120.198431 -151.519577) (xy 120.241724 -151.589468) (xy 120.278384 -151.663055)
			(xy 120.3081 -151.73971) (xy 120.330617 -151.818779) (xy 120.345743 -151.899589) (xy 120.35335 -151.98145)
			(xy 120.353836 -152.022556) (xy 120.353419 -152.060846) (xy 120.346814 -152.137139) (xy 120.333668 -152.212582)
			(xy 120.314078 -152.286613) (xy 120.301512 -152.322784) (xy 120.298884 -152.331226) (xy 120.29887 -152.348891)
			(xy 120.301512 -152.357328) (xy 120.314046 -152.393509) (xy 120.333622 -152.467541) (xy 120.346772 -152.542979)
			(xy 120.353399 -152.619268) (xy 120.353836 -152.657556) (xy 120.353306 -152.698665) (xy 120.345722 -152.780533)
			(xy 120.330616 -152.861351) (xy 120.308115 -152.940431) (xy 120.278413 -153.017096) (xy 120.241762 -153.090693)
			(xy 120.198476 -153.160594) (xy 120.148923 -153.226202) (xy 120.093528 -153.286957) (xy 120.032762 -153.34234)
			(xy 119.967144 -153.391879) (xy 119.897234 -153.435151) (xy 119.823629 -153.471786) (xy 119.746958 -153.501473)
			(xy 119.667874 -153.523957) (xy 119.587052 -153.539047) (xy 119.505183 -153.546614) (xy 119.464074 -153.547064)
			(xy 119.425757 -153.546706) (xy 119.349404 -153.540171) (xy 119.273897 -153.527084) (xy 119.199798 -153.507541)
			(xy 119.163592 -153.494994) (xy 119.155276 -153.492408) (xy 119.137872 -153.492408) (xy 119.129556 -153.494994)
			(xy 119.093344 -153.507519) (xy 119.019243 -153.527041) (xy 118.943738 -153.540123) (xy 118.867389 -153.546671)
			(xy 118.829074 -153.547064) (xy 118.790757 -153.546706) (xy 118.714404 -153.540171) (xy 118.638897 -153.527084)
			(xy 118.564798 -153.507541) (xy 118.528592 -153.494994) (xy 118.520276 -153.492408) (xy 118.502872 -153.492408)
			(xy 118.494556 -153.494994) (xy 118.458344 -153.507519) (xy 118.384243 -153.527041) (xy 118.308738 -153.540123)
			(xy 118.232389 -153.546671) (xy 118.194074 -153.547064) (xy 118.155757 -153.546706) (xy 118.079404 -153.540171)
			(xy 118.003897 -153.527084) (xy 117.929798 -153.507541) (xy 117.893592 -153.494994) (xy 117.885276 -153.492408)
			(xy 117.867872 -153.492408) (xy 117.859556 -153.494994) (xy 117.823344 -153.507519) (xy 117.749243 -153.527041)
			(xy 117.673738 -153.540123) (xy 117.597389 -153.546671) (xy 117.559074 -153.547064) (xy 117.51886 -153.546643)
			(xy 117.438758 -153.539418) (xy 117.359636 -153.524984) (xy 117.282143 -153.50346) (xy 117.244368 -153.48966)
			(xy 117.235581 -153.486753) (xy 117.217087 -153.486753) (xy 117.2083 -153.48966) (xy 117.170526 -153.50346)
			(xy 117.093029 -153.524965) (xy 117.013907 -153.539393) (xy 116.933807 -153.546627) (xy 116.893594 -153.547064)
			(xy 116.855277 -153.5467) (xy 116.778924 -153.540167) (xy 116.703417 -153.527082) (xy 116.629318 -153.50754)
			(xy 116.593112 -153.494994) (xy 116.584796 -153.492408) (xy 116.567392 -153.492408) (xy 116.559076 -153.494994)
			(xy 116.522953 -153.507485) (xy 116.449041 -153.526976) (xy 116.37373 -153.54006) (xy 116.297575 -153.546641)
			(xy 116.259356 -153.547064) (xy 116.258594 -153.547064) (xy 116.217487 -153.546593) (xy 116.135624 -153.539008)
			(xy 116.05481 -153.523904) (xy 115.975734 -153.501409) (xy 115.89907 -153.471714) (xy 115.825473 -153.435075)
			(xy 115.755569 -153.391802) (xy 115.689955 -153.342264) (xy 115.629192 -153.286885) (xy 115.573796 -153.226137)
			(xy 115.52424 -153.160537) (xy 115.480947 -153.090646) (xy 115.444287 -153.017059) (xy 115.414571 -152.940403)
			(xy 115.392053 -152.861333) (xy 115.376926 -152.780524) (xy 115.369318 -152.698663) (xy 115.368832 -152.657556)
			(xy 35.354948 -152.657556) (xy 35.387298 -152.825405) (xy 35.41915 -153.032898) (xy 35.44308 -153.241454)
			(xy 35.459052 -153.45077) (xy 35.467044 -153.660542) (xy 35.467544 -153.765504) (xy 35.467044 -153.870466)
			(xy 35.459052 -154.080238) (xy 35.44308 -154.289554) (xy 35.422918 -154.465274) (xy 127.823468 -154.465274)
			(xy 127.824038 -154.420505) (xy 127.833047 -154.33142) (xy 127.850949 -154.243689) (xy 127.877566 -154.158197)
			(xy 127.894588 -154.116786) (xy 127.89817 -154.1072) (xy 127.89816 -154.086753) (xy 127.894588 -154.077162)
			(xy 127.87754 -154.03576) (xy 127.850909 -153.95027) (xy 127.833008 -153.862535) (xy 127.824018 -153.773445)
			(xy 127.823468 -153.728674) (xy 127.824038 -153.683905) (xy 127.833047 -153.59482) (xy 127.850949 -153.507089)
			(xy 127.877566 -153.421597) (xy 127.894588 -153.380186) (xy 127.89817 -153.3706) (xy 127.89816 -153.350153)
			(xy 127.894588 -153.340562) (xy 127.87754 -153.29916) (xy 127.850909 -153.21367) (xy 127.833008 -153.125935)
			(xy 127.824018 -153.036845) (xy 127.823468 -152.992074) (xy 127.823874 -152.950958) (xy 127.831464 -152.869076)
			(xy 127.846576 -152.788245) (xy 127.869082 -152.709152) (xy 127.898791 -152.632473) (xy 127.935447 -152.558863)
			(xy 127.978739 -152.488949) (xy 128.028297 -152.423328) (xy 128.083699 -152.362559) (xy 128.144471 -152.307161)
			(xy 128.210095 -152.257607) (xy 128.280012 -152.21432) (xy 128.353625 -152.177668) (xy 128.430305 -152.147965)
			(xy 128.509399 -152.125463) (xy 128.590232 -152.110356) (xy 128.672114 -152.102771) (xy 128.71323 -152.102312)
			(xy 128.754841 -152.102773) (xy 128.837698 -152.110553) (xy 128.919467 -152.126031) (xy 128.999435 -152.149074)
			(xy 129.076903 -152.179479) (xy 129.151195 -152.216982) (xy 129.186686 -152.23871) (xy 129.195829 -152.243863)
			(xy 129.216542 -152.24708) (xy 129.236814 -152.241752) (xy 129.24536 -152.235662) (xy 129.278989 -152.209671)
			(xy 129.350383 -152.163546) (xy 129.425854 -152.124445) (xy 129.504712 -152.092724) (xy 129.586237 -152.068675)
			(xy 129.669685 -152.052515) (xy 129.754295 -152.044393) (xy 129.796794 -152.043892) (xy 129.837907 -152.044419)
			(xy 129.919782 -152.052005) (xy 130.000607 -152.067113) (xy 130.079694 -152.089613) (xy 130.156368 -152.119315)
			(xy 130.229974 -152.155965) (xy 130.299884 -152.19925) (xy 130.365503 -152.2488) (xy 130.42627 -152.304193)
			(xy 130.481667 -152.364957) (xy 130.531221 -152.430573) (xy 130.57451 -152.500481) (xy 130.611164 -152.574085)
			(xy 130.64087 -152.650756) (xy 130.663376 -152.729842) (xy 130.678488 -152.810667) (xy 130.686079 -152.892541)
			(xy 130.686556 -152.933654) (xy 130.685993 -152.978424) (xy 130.676983 -153.067509) (xy 130.659077 -153.15524)
			(xy 130.632459 -153.240731) (xy 130.615436 -153.282142) (xy 130.611899 -153.291741) (xy 130.611882 -153.312176)
			(xy 130.615436 -153.321766) (xy 130.63244 -153.363117) (xy 130.659051 -153.448479) (xy 130.676958 -153.536082)
			(xy 130.68598 -153.625039) (xy 130.686556 -153.669746) (xy 130.686556 -153.670762) (xy 130.686302 -153.682192)
			(xy 130.712781 -153.688138) (xy 130.765016 -153.702881) (xy 130.790696 -153.711656) (xy 130.798893 -153.71417)
			(xy 130.816027 -153.71417) (xy 130.824224 -153.711656) (xy 130.85944 -153.699695) (xy 130.931444 -153.681041)
			(xy 131.004765 -153.668532) (xy 131.07888 -153.662259) (xy 131.11607 -153.661872) (xy 131.153259 -153.662271)
			(xy 131.227372 -153.668558) (xy 131.300692 -153.681065) (xy 131.372698 -153.699703) (xy 131.407916 -153.711656)
			(xy 131.416113 -153.71417) (xy 131.433247 -153.71417) (xy 131.441444 -153.711656) (xy 131.476659 -153.699689)
			(xy 131.548662 -153.681037) (xy 131.621984 -153.66853) (xy 131.6961 -153.662258) (xy 131.73329 -153.661872)
			(xy 131.77523 -153.662267) (xy 131.858732 -153.670239) (xy 131.941097 -153.686113) (xy 132.02158 -153.709744)
			(xy 132.099453 -153.740919) (xy 132.165372 -153.774902) (xy 188.441847 -153.774902) (xy 188.445843 -153.565016)
			(xy 188.457828 -153.355434) (xy 188.477782 -153.14646) (xy 188.505678 -152.938398) (xy 188.541475 -152.731548)
			(xy 188.58512 -152.526211) (xy 188.636552 -152.322685) (xy 188.695694 -152.121264) (xy 188.762462 -151.922241)
			(xy 188.836758 -151.725904) (xy 188.918476 -151.532538) (xy 189.007495 -151.342423) (xy 189.103688 -151.155835)
			(xy 189.206915 -150.973044) (xy 189.317026 -150.794316) (xy 189.433861 -150.619909) (xy 189.557251 -150.450077)
			(xy 189.687018 -150.285065) (xy 189.822972 -150.125114) (xy 189.964918 -149.970454) (xy 190.112648 -149.82131)
			(xy 190.26595 -149.677899) (xy 190.4246 -149.540428) (xy 190.588369 -149.409096) (xy 190.757019 -149.284095)
			(xy 190.930305 -149.165604) (xy 191.107977 -149.053797) (xy 191.289777 -148.948835) (xy 191.475441 -148.85087)
			(xy 191.664699 -148.760045) (xy 191.857279 -148.676491) (xy 192.0529 -148.600328) (xy 192.251278 -148.531669)
			(xy 192.452127 -148.470612) (xy 192.655154 -148.417245) (xy 192.860067 -148.371647) (xy 193.066566 -148.333882)
			(xy 193.274353 -148.304007) (xy 193.483128 -148.282064) (xy 193.692586 -148.268085) (xy 193.902425 -148.26209)
			(xy 194.112339 -148.264089) (xy 194.322026 -148.274077) (xy 194.53118 -148.292042) (xy 194.739498 -148.317956)
			(xy 194.946679 -148.351781) (xy 195.152423 -148.39347) (xy 195.356429 -148.442962) (xy 195.558404 -148.500184)
			(xy 195.758054 -148.565054) (xy 195.955089 -148.637478) (xy 196.149225 -148.717351) (xy 196.340178 -148.804557)
			(xy 196.527674 -148.898969) (xy 196.711439 -149.000451) (xy 196.891207 -149.108855) (xy 197.066718 -149.224025)
			(xy 197.237717 -149.345793) (xy 197.403957 -149.473982) (xy 197.565196 -149.608408) (xy 197.7212 -149.748875)
			(xy 197.871743 -149.895179) (xy 198.016607 -150.047108) (xy 198.155582 -150.204442) (xy 198.288467 -150.366953)
			(xy 198.415068 -150.534406) (xy 198.535203 -150.706556) (xy 198.648697 -150.883156) (xy 198.755385 -151.063948)
			(xy 198.855112 -151.248671) (xy 198.947735 -151.437057) (xy 199.033119 -151.628832) (xy 199.11114 -151.823719)
			(xy 199.181685 -152.021435) (xy 199.244652 -152.221693) (xy 199.299949 -152.424203) (xy 199.347496 -152.628672)
			(xy 199.387224 -152.834803) (xy 199.419076 -153.042296) (xy 199.443006 -153.250852) (xy 199.458978 -153.460168)
			(xy 199.46697 -153.66994) (xy 199.467428 -153.766012) (xy 272.382243 -153.766012) (xy 272.386239 -153.556126)
			(xy 272.398224 -153.346544) (xy 272.418178 -153.13757) (xy 272.446074 -152.929508) (xy 272.481871 -152.722658)
			(xy 272.525516 -152.517321) (xy 272.576948 -152.313795) (xy 272.63609 -152.112374) (xy 272.702858 -151.913351)
			(xy 272.777154 -151.717014) (xy 272.858872 -151.523648) (xy 272.947891 -151.333533) (xy 273.044084 -151.146945)
			(xy 273.147311 -150.964154) (xy 273.257422 -150.785426) (xy 273.374257 -150.611019) (xy 273.497647 -150.441187)
			(xy 273.627414 -150.276175) (xy 273.763368 -150.116224) (xy 273.905314 -149.961564) (xy 274.053044 -149.81242)
			(xy 274.206346 -149.669009) (xy 274.364996 -149.531538) (xy 274.528765 -149.400206) (xy 274.697415 -149.275205)
			(xy 274.870701 -149.156714) (xy 275.048373 -149.044907) (xy 275.230173 -148.939945) (xy 275.415837 -148.84198)
			(xy 275.605095 -148.751155) (xy 275.797675 -148.667601) (xy 275.993296 -148.591438) (xy 276.191674 -148.522779)
			(xy 276.392523 -148.461722) (xy 276.59555 -148.408355) (xy 276.800463 -148.362757) (xy 277.006962 -148.324992)
			(xy 277.214749 -148.295117) (xy 277.423524 -148.273174) (xy 277.632982 -148.259195) (xy 277.842821 -148.2532)
			(xy 278.052735 -148.255199) (xy 278.262422 -148.265187) (xy 278.471576 -148.283152) (xy 278.679894 -148.309066)
			(xy 278.887075 -148.342891) (xy 279.092819 -148.38458) (xy 279.296825 -148.434072) (xy 279.4988 -148.491294)
			(xy 279.69845 -148.556164) (xy 279.895485 -148.628588) (xy 280.089621 -148.708461) (xy 280.280574 -148.795667)
			(xy 280.46807 -148.890079) (xy 280.651835 -148.991561) (xy 280.831603 -149.099965) (xy 281.007114 -149.215135)
			(xy 281.178113 -149.336903) (xy 281.344353 -149.465092) (xy 281.505592 -149.599518) (xy 281.661596 -149.739985)
			(xy 281.812139 -149.886289) (xy 281.957003 -150.038218) (xy 282.095978 -150.195552) (xy 282.228863 -150.358063)
			(xy 282.355464 -150.525516) (xy 282.475599 -150.697666) (xy 282.589093 -150.874266) (xy 282.695781 -151.055058)
			(xy 282.795508 -151.239781) (xy 282.888131 -151.428167) (xy 282.973515 -151.619942) (xy 283.051536 -151.814829)
			(xy 283.122081 -152.012545) (xy 283.185048 -152.212803) (xy 283.240345 -152.415313) (xy 283.287892 -152.619782)
			(xy 283.305746 -152.71242) (xy 358.186997 -152.71242) (xy 358.191002 -152.606671) (xy 358.202992 -152.501528)
			(xy 358.222901 -152.397593) (xy 358.250612 -152.295461) (xy 358.285969 -152.195717) (xy 358.328767 -152.098933)
			(xy 358.378763 -152.005663) (xy 358.43567 -151.916442) (xy 358.499161 -151.831779) (xy 358.568873 -151.752161)
			(xy 358.644407 -151.678043) (xy 358.72533 -151.60985) (xy 358.811179 -151.547972) (xy 358.901462 -151.492765)
			(xy 358.995661 -151.444543) (xy 359.093238 -151.403583) (xy 359.193633 -151.370121) (xy 359.296271 -151.344347)
			(xy 359.400564 -151.326409) (xy 359.505915 -151.31641) (xy 359.611721 -151.314407) (xy 359.717375 -151.320412)
			(xy 359.822272 -151.334391) (xy 359.925812 -151.356262) (xy 360.027401 -151.385902) (xy 360.126458 -151.42314)
			(xy 360.222415 -151.467762) (xy 360.314722 -151.519514) (xy 360.402851 -151.578099) (xy 360.486297 -151.643181)
			(xy 360.564581 -151.714387) (xy 360.637256 -151.79131) (xy 360.703906 -151.87351) (xy 360.764148 -151.960514)
			(xy 360.817637 -152.051825) (xy 360.864068 -152.14692) (xy 360.903173 -152.245254) (xy 360.93473 -152.346265)
			(xy 360.958557 -152.449372) (xy 360.974518 -152.553986) (xy 360.982522 -152.659508) (xy 360.983022 -152.71242)
			(xy 360.982522 -152.765332) (xy 360.974518 -152.870854) (xy 360.958557 -152.975468) (xy 360.93473 -153.078575)
			(xy 360.903173 -153.179586) (xy 360.864068 -153.27792) (xy 360.817637 -153.373015) (xy 360.764148 -153.464326)
			(xy 360.703906 -153.55133) (xy 360.637256 -153.63353) (xy 360.564581 -153.710453) (xy 360.486297 -153.781659)
			(xy 360.402851 -153.846741) (xy 360.314722 -153.905326) (xy 360.222415 -153.957078) (xy 360.126458 -154.0017)
			(xy 360.027401 -154.038938) (xy 359.925812 -154.068578) (xy 359.822272 -154.090449) (xy 359.717375 -154.104428)
			(xy 359.611721 -154.110433) (xy 359.505915 -154.10843) (xy 359.400564 -154.098431) (xy 359.296271 -154.080493)
			(xy 359.193633 -154.054719) (xy 359.093238 -154.021257) (xy 358.995661 -153.980297) (xy 358.901462 -153.932075)
			(xy 358.811179 -153.876868) (xy 358.72533 -153.81499) (xy 358.644407 -153.746797) (xy 358.568873 -153.672679)
			(xy 358.499161 -153.593061) (xy 358.43567 -153.508398) (xy 358.378763 -153.419177) (xy 358.328767 -153.325907)
			(xy 358.285969 -153.229123) (xy 358.250612 -153.129379) (xy 358.222901 -153.027247) (xy 358.202992 -152.923312)
			(xy 358.191002 -152.818169) (xy 358.186997 -152.71242) (xy 283.305746 -152.71242) (xy 283.32762 -152.825913)
			(xy 283.359472 -153.033406) (xy 283.383402 -153.241962) (xy 283.399374 -153.451278) (xy 283.407366 -153.66105)
			(xy 283.407866 -153.766012) (xy 283.407366 -153.870974) (xy 283.399374 -154.080746) (xy 283.383402 -154.290062)
			(xy 283.359472 -154.498618) (xy 283.32762 -154.706111) (xy 283.287892 -154.912242) (xy 283.240345 -155.116711)
			(xy 283.185048 -155.319221) (xy 283.122081 -155.519479) (xy 283.051536 -155.717195) (xy 282.973515 -155.912082)
			(xy 282.888131 -156.103857) (xy 282.795508 -156.292243) (xy 282.695781 -156.476966) (xy 282.589093 -156.657758)
			(xy 282.475599 -156.834358) (xy 282.355464 -157.006508) (xy 282.228863 -157.173961) (xy 282.095978 -157.336472)
			(xy 281.957003 -157.493806) (xy 281.812139 -157.645735) (xy 281.661596 -157.792039) (xy 281.505592 -157.932506)
			(xy 281.344353 -158.066932) (xy 281.178113 -158.195121) (xy 281.007114 -158.316889) (xy 280.831603 -158.432059)
			(xy 280.651835 -158.540463) (xy 280.46807 -158.641945) (xy 280.280574 -158.736357) (xy 280.089621 -158.823563)
			(xy 279.895485 -158.903436) (xy 279.69845 -158.97586) (xy 279.4988 -159.04073) (xy 279.382794 -159.073596)
			(xy 343.127076 -159.073596) (xy 343.127653 -159.028827) (xy 343.136659 -158.939742) (xy 343.15456 -158.852011)
			(xy 343.181175 -158.766519) (xy 343.198196 -158.725108) (xy 343.201765 -158.715518) (xy 343.201764 -158.695074)
			(xy 343.198196 -158.685484) (xy 343.181156 -158.644079) (xy 343.154522 -158.55859) (xy 343.136619 -158.470856)
			(xy 343.127627 -158.381767) (xy 343.127076 -158.336996) (xy 343.127653 -158.292227) (xy 343.136659 -158.203142)
			(xy 343.15456 -158.115411) (xy 343.181175 -158.029919) (xy 343.198196 -157.988508) (xy 343.201765 -157.978918)
			(xy 343.201764 -157.958474) (xy 343.198196 -157.948884) (xy 343.181156 -157.907479) (xy 343.154522 -157.82199)
			(xy 343.136619 -157.734256) (xy 343.127627 -157.645167) (xy 343.127076 -157.600396) (xy 343.127549 -157.559286)
			(xy 343.135137 -157.477416) (xy 343.150247 -157.396596) (xy 343.172752 -157.317516) (xy 343.202459 -157.240849)
			(xy 343.239114 -157.167252) (xy 343.282404 -157.097351) (xy 343.33196 -157.031743) (xy 343.387359 -156.970988)
			(xy 343.448129 -156.915605) (xy 343.51375 -156.866067) (xy 343.583663 -156.822796) (xy 343.657271 -156.786161)
			(xy 343.733945 -156.756475) (xy 343.813032 -156.733992) (xy 343.893856 -156.718903) (xy 343.975728 -156.711337)
			(xy 344.016838 -156.710888) (xy 344.058442 -156.711362) (xy 344.14129 -156.719094) (xy 344.223055 -156.734524)
			(xy 344.303022 -156.757517) (xy 344.380495 -156.787874) (xy 344.454797 -156.825328) (xy 344.490294 -156.847032)
			(xy 344.499434 -156.852189) (xy 344.520149 -156.855402) (xy 344.540422 -156.850073) (xy 344.548968 -156.843984)
			(xy 344.582592 -156.818029) (xy 344.653971 -156.771973) (xy 344.729414 -156.73293) (xy 344.808235 -156.701255)
			(xy 344.889716 -156.677237) (xy 344.973116 -156.661094) (xy 345.057674 -156.652974) (xy 345.100148 -156.652468)
			(xy 345.100402 -156.652468) (xy 345.14151 -156.652911) (xy 345.223374 -156.660496) (xy 345.30419 -156.6756)
			(xy 345.383268 -156.698096) (xy 345.459933 -156.727791) (xy 345.533532 -156.764433) (xy 345.603437 -156.807707)
			(xy 345.669051 -156.857246) (xy 345.729816 -156.912627) (xy 345.785212 -156.973378) (xy 345.806812 -157.001972)
			(xy 386.403596 -157.001972) (xy 386.40399 -156.963682) (xy 386.410601 -156.887387) (xy 386.423753 -156.811945)
			(xy 386.44335 -156.737915) (xy 386.45592 -156.701744) (xy 386.458586 -156.693311) (xy 386.458577 -156.675637)
			(xy 386.45592 -156.6672) (xy 386.443367 -156.631026) (xy 386.423796 -156.556991) (xy 386.410652 -156.481551)
			(xy 386.40403 -156.40526) (xy 386.403596 -156.366972) (xy 386.404015 -156.328179) (xy 386.410791 -156.25089)
			(xy 386.424264 -156.174482) (xy 386.44433 -156.099536) (xy 386.45719 -156.062934) (xy 386.459858 -156.054502)
			(xy 386.459846 -156.036827) (xy 386.45719 -156.02839) (xy 386.444324 -155.991789) (xy 386.424239 -155.916847)
			(xy 386.410766 -155.840438) (xy 386.404005 -155.763146) (xy 386.403596 -155.724352) (xy 386.404014 -155.686062)
			(xy 386.410618 -155.609769) (xy 386.423763 -155.534326) (xy 386.443354 -155.460295) (xy 386.45592 -155.424124)
			(xy 386.458596 -155.415693) (xy 386.45858 -155.398017) (xy 386.45592 -155.38958) (xy 386.443389 -155.353398)
			(xy 386.423812 -155.279367) (xy 386.410662 -155.203928) (xy 386.404034 -155.12764) (xy 386.403596 -155.089352)
			(xy 386.40407 -155.049438) (xy 386.411294 -154.969935) (xy 386.425601 -154.891398) (xy 386.446874 -154.814455)
			(xy 386.460492 -154.776932) (xy 386.463345 -154.768269) (xy 386.463329 -154.750041) (xy 386.460492 -154.741372)
			(xy 386.44684 -154.70386) (xy 386.425547 -154.626919) (xy 386.411244 -154.548377) (xy 386.404048 -154.468869)
			(xy 386.403596 -154.428952) (xy 386.404014 -154.390662) (xy 386.410618 -154.314369) (xy 386.423763 -154.238926)
			(xy 386.443354 -154.164895) (xy 386.45592 -154.128724) (xy 386.458596 -154.120293) (xy 386.45858 -154.102617)
			(xy 386.45592 -154.09418) (xy 386.443389 -154.057998) (xy 386.423812 -153.983967) (xy 386.410662 -153.908528)
			(xy 386.404034 -153.83224) (xy 386.403596 -153.793952) (xy 386.404007 -153.75284) (xy 386.411599 -153.670969)
			(xy 386.426714 -153.590147) (xy 386.449223 -153.511065) (xy 386.478934 -153.434397) (xy 386.515593 -153.360799)
			(xy 386.558887 -153.290897) (xy 386.608448 -153.225289) (xy 386.663851 -153.164535) (xy 386.724625 -153.109152)
			(xy 386.79025 -153.059614) (xy 386.860166 -153.016344) (xy 386.933777 -152.97971) (xy 387.010455 -152.950026)
			(xy 387.089545 -152.927544) (xy 387.170372 -152.912457) (xy 387.252246 -152.904893) (xy 387.293358 -152.904444)
			(xy 387.331674 -152.904822) (xy 387.408027 -152.91135) (xy 387.483534 -152.924432) (xy 387.557634 -152.94397)
			(xy 387.59384 -152.956514) (xy 387.602156 -152.9591) (xy 387.61956 -152.9591) (xy 387.627876 -152.956514)
			(xy 387.663994 -152.944008) (xy 387.737908 -152.924522) (xy 387.81322 -152.911442) (xy 387.889376 -152.904865)
			(xy 387.927596 -152.904444) (xy 387.928358 -152.904444) (xy 387.969464 -152.904953) (xy 388.051326 -152.912533)
			(xy 388.13214 -152.927634) (xy 388.211216 -152.950125) (xy 388.28788 -152.979816) (xy 388.361478 -153.016453)
			(xy 388.431382 -153.059723) (xy 388.496996 -153.109258) (xy 388.55776 -153.164634) (xy 388.613157 -153.225381)
			(xy 388.662713 -153.290979) (xy 388.706006 -153.360869) (xy 388.742667 -153.434454) (xy 388.772383 -153.511109)
			(xy 388.7949 -153.590177) (xy 388.810027 -153.670986) (xy 388.817634 -153.752846) (xy 388.817889 -153.774394)
			(xy 436.382169 -153.774394) (xy 436.386165 -153.564508) (xy 436.39815 -153.354926) (xy 436.418104 -153.145952)
			(xy 436.446 -152.93789) (xy 436.481797 -152.73104) (xy 436.525442 -152.525703) (xy 436.576874 -152.322177)
			(xy 436.636016 -152.120756) (xy 436.702784 -151.921733) (xy 436.77708 -151.725396) (xy 436.858798 -151.53203)
			(xy 436.947817 -151.341915) (xy 437.04401 -151.155327) (xy 437.147237 -150.972536) (xy 437.257348 -150.793808)
			(xy 437.374183 -150.619401) (xy 437.497573 -150.449569) (xy 437.62734 -150.284557) (xy 437.763294 -150.124606)
			(xy 437.90524 -149.969946) (xy 438.05297 -149.820802) (xy 438.206272 -149.677391) (xy 438.364922 -149.53992)
			(xy 438.528691 -149.408588) (xy 438.697341 -149.283587) (xy 438.870627 -149.165096) (xy 439.048299 -149.053289)
			(xy 439.230099 -148.948327) (xy 439.415763 -148.850362) (xy 439.605021 -148.759537) (xy 439.797601 -148.675983)
			(xy 439.993222 -148.59982) (xy 440.1916 -148.531161) (xy 440.392449 -148.470104) (xy 440.595476 -148.416737)
			(xy 440.800389 -148.371139) (xy 441.006888 -148.333374) (xy 441.214675 -148.303499) (xy 441.42345 -148.281556)
			(xy 441.632908 -148.267577) (xy 441.842747 -148.261582) (xy 442.052661 -148.263581) (xy 442.262348 -148.273569)
			(xy 442.471502 -148.291534) (xy 442.67982 -148.317448) (xy 442.887001 -148.351273) (xy 443.092745 -148.392962)
			(xy 443.296751 -148.442454) (xy 443.498726 -148.499676) (xy 443.698376 -148.564546) (xy 443.895411 -148.63697)
			(xy 444.089547 -148.716843) (xy 444.2805 -148.804049) (xy 444.467996 -148.898461) (xy 444.651761 -148.999943)
			(xy 444.831529 -149.108347) (xy 445.00704 -149.223517) (xy 445.178039 -149.345285) (xy 445.344279 -149.473474)
			(xy 445.505518 -149.6079) (xy 445.661522 -149.748367) (xy 445.812065 -149.894671) (xy 445.956929 -150.0466)
			(xy 446.095904 -150.203934) (xy 446.228789 -150.366445) (xy 446.35539 -150.533898) (xy 446.475525 -150.706048)
			(xy 446.589019 -150.882648) (xy 446.695707 -151.06344) (xy 446.795434 -151.248163) (xy 446.888057 -151.436549)
			(xy 446.973441 -151.628324) (xy 447.051462 -151.823211) (xy 447.122007 -152.020927) (xy 447.184974 -152.221185)
			(xy 447.240271 -152.423695) (xy 447.287818 -152.628164) (xy 447.327546 -152.834295) (xy 447.359398 -153.041788)
			(xy 447.383328 -153.250344) (xy 447.3993 -153.45966) (xy 447.407292 -153.669432) (xy 447.407792 -153.774394)
			(xy 447.407292 -153.879356) (xy 447.3993 -154.089128) (xy 447.383328 -154.298444) (xy 447.359398 -154.507)
			(xy 447.327546 -154.714493) (xy 447.287818 -154.920624) (xy 447.240271 -155.125093) (xy 447.184974 -155.327603)
			(xy 447.122007 -155.527861) (xy 447.051462 -155.725577) (xy 446.973441 -155.920464) (xy 446.888057 -156.112239)
			(xy 446.795434 -156.300625) (xy 446.695707 -156.485348) (xy 446.589019 -156.66614) (xy 446.475525 -156.84274)
			(xy 446.35539 -157.01489) (xy 446.228789 -157.182343) (xy 446.095904 -157.344854) (xy 445.956929 -157.502188)
			(xy 445.812065 -157.654117) (xy 445.661522 -157.800421) (xy 445.505518 -157.940888) (xy 445.344279 -158.075314)
			(xy 445.178039 -158.203503) (xy 445.00704 -158.325271) (xy 444.831529 -158.440441) (xy 444.651761 -158.548845)
			(xy 444.467996 -158.650327) (xy 444.2805 -158.744739) (xy 444.089547 -158.831945) (xy 443.895411 -158.911818)
			(xy 443.698376 -158.984242) (xy 443.498726 -159.049112) (xy 443.296751 -159.106334) (xy 443.092745 -159.155826)
			(xy 442.887001 -159.197515) (xy 442.67982 -159.23134) (xy 442.471502 -159.257254) (xy 442.262348 -159.275219)
			(xy 442.052661 -159.285207) (xy 441.842747 -159.287206) (xy 441.632908 -159.281211) (xy 441.42345 -159.267232)
			(xy 441.214675 -159.245289) (xy 441.006888 -159.215414) (xy 440.800389 -159.177649) (xy 440.595476 -159.132051)
			(xy 440.392449 -159.078684) (xy 440.1916 -159.017627) (xy 439.993222 -158.948968) (xy 439.797601 -158.872805)
			(xy 439.605021 -158.789251) (xy 439.415763 -158.698426) (xy 439.230099 -158.600461) (xy 439.048299 -158.495499)
			(xy 438.870627 -158.383692) (xy 438.697341 -158.265201) (xy 438.528691 -158.1402) (xy 438.364922 -158.008868)
			(xy 438.206272 -157.871397) (xy 438.05297 -157.727986) (xy 437.90524 -157.578842) (xy 437.763294 -157.424182)
			(xy 437.62734 -157.264231) (xy 437.497573 -157.099219) (xy 437.374183 -156.929387) (xy 437.257348 -156.75498)
			(xy 437.147237 -156.576252) (xy 437.04401 -156.393461) (xy 436.947817 -156.206873) (xy 436.858798 -156.016758)
			(xy 436.77708 -155.823392) (xy 436.702784 -155.627055) (xy 436.636016 -155.428032) (xy 436.576874 -155.226611)
			(xy 436.525442 -155.023085) (xy 436.481797 -154.817748) (xy 436.446 -154.610898) (xy 436.418104 -154.402836)
			(xy 436.39815 -154.193862) (xy 436.386165 -153.98428) (xy 436.382169 -153.774394) (xy 388.817889 -153.774394)
			(xy 388.81812 -153.793952) (xy 388.817702 -153.832242) (xy 388.811098 -153.908535) (xy 388.797953 -153.983978)
			(xy 388.778362 -154.058009) (xy 388.765796 -154.09418) (xy 388.763168 -154.102623) (xy 388.763152 -154.120288)
			(xy 388.765796 -154.128724) (xy 388.778328 -154.164905) (xy 388.797905 -154.238937) (xy 388.811055 -154.314375)
			(xy 388.817683 -154.390664) (xy 388.81812 -154.428952) (xy 388.817646 -154.468866) (xy 388.810422 -154.548369)
			(xy 388.796115 -154.626906) (xy 388.774842 -154.703849) (xy 388.761224 -154.741372) (xy 388.758419 -154.750047)
			(xy 388.758403 -154.768264) (xy 388.761224 -154.776932) (xy 388.774878 -154.814443) (xy 388.79617 -154.891385)
			(xy 388.810472 -154.969927) (xy 388.817668 -155.049435) (xy 388.81812 -155.089352) (xy 388.817702 -155.127642)
			(xy 388.811098 -155.203935) (xy 388.797953 -155.279378) (xy 388.778362 -155.353409) (xy 388.765796 -155.38958)
			(xy 388.763168 -155.398023) (xy 388.763152 -155.415688) (xy 388.765796 -155.424124) (xy 388.778328 -155.460305)
			(xy 388.797905 -155.534337) (xy 388.811055 -155.609775) (xy 388.817683 -155.686064) (xy 388.81812 -155.724352)
			(xy 388.817677 -155.763144) (xy 388.810908 -155.840433) (xy 388.797442 -155.916841) (xy 388.777382 -155.991787)
			(xy 388.764526 -156.02839) (xy 388.761895 -156.036832) (xy 388.761883 -156.054497) (xy 388.764526 -156.062934)
			(xy 388.7774 -156.099532) (xy 388.797482 -156.174476) (xy 388.810953 -156.250885) (xy 388.817712 -156.328178)
			(xy 388.81812 -156.366972) (xy 388.817708 -156.405262) (xy 388.811103 -156.481556) (xy 388.797955 -156.556998)
			(xy 388.778363 -156.631029) (xy 388.765796 -156.6672) (xy 388.763157 -156.67564) (xy 388.763148 -156.693308)
			(xy 388.765796 -156.701744) (xy 388.778334 -156.737923) (xy 388.797909 -156.811956) (xy 388.811058 -156.887395)
			(xy 388.817683 -156.963684) (xy 388.81812 -157.001972) (xy 388.817621 -157.043082) (xy 388.810036 -157.124951)
			(xy 388.794928 -157.20577) (xy 388.772425 -157.284851) (xy 388.742721 -157.361517) (xy 388.706068 -157.435115)
			(xy 388.66278 -157.505016) (xy 388.613226 -157.570624) (xy 388.557828 -157.631379) (xy 388.49706 -157.686762)
			(xy 388.43144 -157.736301) (xy 388.361528 -157.779573) (xy 388.287921 -157.816208) (xy 388.211248 -157.845893)
			(xy 388.132162 -157.868377) (xy 388.051339 -157.883465) (xy 387.969468 -157.891031) (xy 387.928358 -157.89148)
			(xy 387.890041 -157.891126) (xy 387.813688 -157.88459) (xy 387.738181 -157.871501) (xy 387.664082 -157.851957)
			(xy 387.627876 -157.83941) (xy 387.61956 -157.836824) (xy 387.602156 -157.836824) (xy 387.59384 -157.83941)
			(xy 387.557721 -157.851912) (xy 387.483807 -157.871399) (xy 387.408495 -157.88448) (xy 387.33234 -157.891059)
			(xy 387.29412 -157.89148) (xy 387.293358 -157.89148) (xy 387.252251 -157.891028) (xy 387.170388 -157.88344)
			(xy 387.089574 -157.868332) (xy 387.010498 -157.845835) (xy 386.933835 -157.816138) (xy 386.860238 -157.779497)
			(xy 386.790335 -157.736222) (xy 386.724722 -157.686684) (xy 386.663959 -157.631304) (xy 386.608563 -157.570555)
			(xy 386.559008 -157.504955) (xy 386.515715 -157.435063) (xy 386.479055 -157.361475) (xy 386.449338 -157.28482)
			(xy 386.42682 -157.20575) (xy 386.411692 -157.12494) (xy 386.404083 -157.043079) (xy 386.403596 -157.001972)
			(xy 345.806812 -157.001972) (xy 345.834767 -157.03898) (xy 345.878059 -157.108874) (xy 345.914719 -157.182463)
			(xy 345.944433 -157.259121) (xy 345.966949 -157.338193) (xy 345.982074 -157.419006) (xy 345.989679 -157.500868)
			(xy 345.990164 -157.541976) (xy 345.989609 -157.586746) (xy 345.980596 -157.675831) (xy 345.962689 -157.763562)
			(xy 345.936068 -157.849053) (xy 345.919044 -157.890464) (xy 345.915494 -157.900059) (xy 345.915485 -157.920497)
			(xy 345.919044 -157.930088) (xy 345.936056 -157.971436) (xy 345.962665 -158.056799) (xy 345.980569 -158.144403)
			(xy 345.989589 -158.233361) (xy 345.990164 -158.278068) (xy 345.990164 -158.279084) (xy 345.98991 -158.290514)
			(xy 346.016389 -158.296459) (xy 346.068624 -158.311202) (xy 346.094304 -158.319978) (xy 346.102501 -158.322492)
			(xy 346.119635 -158.322492) (xy 346.127832 -158.319978) (xy 346.163048 -158.308033) (xy 346.235059 -158.289446)
			(xy 346.308381 -158.277006) (xy 346.382492 -158.2708) (xy 346.419678 -158.270448) (xy 346.456862 -158.27082)
			(xy 346.53097 -158.277041) (xy 346.60429 -158.289483) (xy 346.676301 -158.308056) (xy 346.711524 -158.319978)
			(xy 346.719721 -158.322492) (xy 346.736855 -158.322492) (xy 346.745052 -158.319978) (xy 346.780146 -158.308069)
			(xy 346.851906 -158.289524) (xy 346.924971 -158.277084) (xy 346.998824 -158.270837) (xy 347.035882 -158.270448)
			(xy 347.036898 -158.270448) (xy 347.078822 -158.270999) (xy 347.162292 -158.278969) (xy 347.244625 -158.294837)
			(xy 347.325078 -158.31846) (xy 347.40292 -158.349624) (xy 347.477448 -158.388045) (xy 347.547987 -158.433377)
			(xy 347.613896 -158.485209) (xy 347.674581 -158.543071) (xy 347.72949 -158.60644) (xy 347.778127 -158.674741)
			(xy 347.820052 -158.747357) (xy 347.854884 -158.823628) (xy 347.882308 -158.902865) (xy 347.902076 -158.984351)
			(xy 347.914009 -159.067346) (xy 347.917999 -159.1511) (xy 347.914009 -159.234854) (xy 347.902076 -159.317849)
			(xy 347.882308 -159.399335) (xy 347.854884 -159.478572) (xy 347.820052 -159.554843) (xy 347.778127 -159.627459)
			(xy 347.72949 -159.69576) (xy 347.674581 -159.759129) (xy 347.613896 -159.816991) (xy 347.547987 -159.868823)
			(xy 347.477448 -159.914155) (xy 347.40292 -159.952576) (xy 347.325078 -159.98374) (xy 347.244625 -160.007363)
			(xy 347.162292 -160.023231) (xy 347.078822 -160.031201) (xy 347.036898 -160.031684) (xy 347.035882 -160.031684)
			(xy 346.998825 -160.031285) (xy 346.924976 -160.025019) (xy 346.851913 -160.012575) (xy 346.780153 -159.994041)
			(xy 346.745052 -159.982154) (xy 346.736855 -159.97964) (xy 346.719721 -159.97964) (xy 346.711524 -159.982154)
			(xy 346.684116 -159.991499) (xy 346.628318 -160.007008) (xy 346.600018 -160.013142) (xy 346.590235 -160.015622)
			(xy 346.573598 -160.027019) (xy 346.562626 -160.04394) (xy 346.560394 -160.053782) (xy 346.550929 -160.102889)
			(xy 346.522417 -160.19875) (xy 346.503498 -160.245044) (xy 346.499892 -160.254619) (xy 346.499745 -160.275056)
			(xy 346.503244 -160.284668) (xy 346.520278 -160.326041) (xy 346.546893 -160.41147) (xy 346.564794 -160.499139)
			(xy 346.5738 -160.588163) (xy 346.574364 -160.632902) (xy 346.574364 -160.633156) (xy 346.57386 -160.675504)
			(xy 346.565809 -160.759818) (xy 346.54978 -160.842984) (xy 346.525919 -160.924251) (xy 346.49444 -161.002881)
			(xy 346.455629 -161.078162) (xy 346.409839 -161.149414) (xy 346.357483 -161.21599) (xy 346.299035 -161.277288)
			(xy 346.235025 -161.332753) (xy 346.166033 -161.381882) (xy 346.092683 -161.424231) (xy 346.01564 -161.459415)
			(xy 345.935601 -161.487117) (xy 345.853292 -161.507085) (xy 345.769457 -161.519138) (xy 345.684856 -161.523169)
			(xy 345.600255 -161.519138) (xy 345.51642 -161.507085) (xy 345.434111 -161.487117) (xy 345.354072 -161.459415)
			(xy 345.277029 -161.424231) (xy 345.203679 -161.381882) (xy 345.134687 -161.332753) (xy 345.070677 -161.277288)
			(xy 345.012229 -161.21599) (xy 344.959873 -161.149414) (xy 344.914083 -161.078162) (xy 344.875272 -161.002881)
			(xy 344.843793 -160.924251) (xy 344.819932 -160.842984) (xy 344.803903 -160.759818) (xy 344.795852 -160.675504)
			(xy 344.795348 -160.633156) (xy 344.795348 -160.632902) (xy 344.795938 -160.588164) (xy 344.804948 -160.499143)
			(xy 344.822847 -160.411476) (xy 344.849453 -160.326048) (xy 344.866468 -160.284668) (xy 344.870056 -160.275084)
			(xy 344.87004 -160.254635) (xy 344.866468 -160.245044) (xy 344.849433 -160.203637) (xy 344.822801 -160.118148)
			(xy 344.804897 -160.030415) (xy 344.795901 -159.941327) (xy 344.795348 -159.896556) (xy 344.795678 -159.859467)
			(xy 344.801776 -159.78554) (xy 344.814009 -159.712377) (xy 344.82278 -159.676338) (xy 344.824538 -159.668008)
			(xy 344.823098 -159.651057) (xy 344.816174 -159.635517) (xy 344.810588 -159.629094) (xy 344.770202 -159.586168)
			(xy 344.758264 -159.588708) (xy 344.749364 -159.591023) (xy 344.733871 -159.600904) (xy 344.728038 -159.608012)
			(xy 344.702891 -159.640664) (xy 344.647483 -159.701681) (xy 344.586669 -159.757312) (xy 344.520971 -159.807081)
			(xy 344.450952 -159.850561) (xy 344.377213 -159.887379) (xy 344.300384 -159.917221) (xy 344.221125 -159.93983)
			(xy 344.140115 -159.955012) (xy 344.058048 -159.962637) (xy 344.016838 -159.963104) (xy 343.975733 -159.962551)
			(xy 343.893874 -159.954971) (xy 343.813062 -159.939871) (xy 343.733989 -159.917381) (xy 343.657327 -159.887692)
			(xy 343.583731 -159.851057) (xy 343.513829 -159.807789) (xy 343.448216 -159.758257) (xy 343.387452 -159.702884)
			(xy 343.332056 -159.642141) (xy 343.2825 -159.576547) (xy 343.239206 -159.506661) (xy 343.202543 -159.433078)
			(xy 343.172826 -159.356428) (xy 343.150306 -159.277363) (xy 343.135175 -159.196557) (xy 343.127564 -159.114701)
			(xy 343.127076 -159.073596) (xy 279.382794 -159.073596) (xy 279.296825 -159.097952) (xy 279.092819 -159.147444)
			(xy 278.887075 -159.189133) (xy 278.679894 -159.222958) (xy 278.471576 -159.248872) (xy 278.262422 -159.266837)
			(xy 278.052735 -159.276825) (xy 277.842821 -159.278824) (xy 277.632982 -159.272829) (xy 277.423524 -159.25885)
			(xy 277.214749 -159.236907) (xy 277.006962 -159.207032) (xy 276.800463 -159.169267) (xy 276.59555 -159.123669)
			(xy 276.392523 -159.070302) (xy 276.191674 -159.009245) (xy 275.993296 -158.940586) (xy 275.797675 -158.864423)
			(xy 275.605095 -158.780869) (xy 275.415837 -158.690044) (xy 275.230173 -158.592079) (xy 275.048373 -158.487117)
			(xy 274.870701 -158.37531) (xy 274.697415 -158.256819) (xy 274.528765 -158.131818) (xy 274.364996 -158.000486)
			(xy 274.206346 -157.863015) (xy 274.053044 -157.719604) (xy 273.905314 -157.57046) (xy 273.763368 -157.4158)
			(xy 273.627414 -157.255849) (xy 273.497647 -157.090837) (xy 273.374257 -156.921005) (xy 273.257422 -156.746598)
			(xy 273.147311 -156.56787) (xy 273.044084 -156.385079) (xy 272.947891 -156.198491) (xy 272.858872 -156.008376)
			(xy 272.777154 -155.81501) (xy 272.702858 -155.618673) (xy 272.63609 -155.41965) (xy 272.576948 -155.218229)
			(xy 272.525516 -155.014703) (xy 272.481871 -154.809366) (xy 272.446074 -154.602516) (xy 272.418178 -154.394454)
			(xy 272.398224 -154.18548) (xy 272.386239 -153.975898) (xy 272.382243 -153.766012) (xy 199.467428 -153.766012)
			(xy 199.46747 -153.774902) (xy 199.46697 -153.879864) (xy 199.458978 -154.089636) (xy 199.443006 -154.298952)
			(xy 199.419076 -154.507508) (xy 199.387224 -154.715001) (xy 199.347496 -154.921132) (xy 199.299949 -155.125601)
			(xy 199.244652 -155.328111) (xy 199.181685 -155.528369) (xy 199.11114 -155.726085) (xy 199.033119 -155.920972)
			(xy 198.947735 -156.112747) (xy 198.855112 -156.301133) (xy 198.755385 -156.485856) (xy 198.648697 -156.666648)
			(xy 198.535203 -156.843248) (xy 198.415068 -157.015398) (xy 198.288467 -157.182851) (xy 198.155582 -157.345362)
			(xy 198.016607 -157.502696) (xy 197.871743 -157.654625) (xy 197.7212 -157.800929) (xy 197.565196 -157.941396)
			(xy 197.403957 -158.075822) (xy 197.237717 -158.204011) (xy 197.066718 -158.325779) (xy 196.891207 -158.440949)
			(xy 196.711439 -158.549353) (xy 196.527674 -158.650835) (xy 196.340178 -158.745247) (xy 196.149225 -158.832453)
			(xy 195.955089 -158.912326) (xy 195.758054 -158.98475) (xy 195.558404 -159.04962) (xy 195.356429 -159.106842)
			(xy 195.152423 -159.156334) (xy 194.946679 -159.198023) (xy 194.739498 -159.231848) (xy 194.53118 -159.257762)
			(xy 194.322026 -159.275727) (xy 194.112339 -159.285715) (xy 193.902425 -159.287714) (xy 193.692586 -159.281719)
			(xy 193.483128 -159.26774) (xy 193.274353 -159.245797) (xy 193.066566 -159.215922) (xy 192.860067 -159.178157)
			(xy 192.655154 -159.132559) (xy 192.452127 -159.079192) (xy 192.251278 -159.018135) (xy 192.0529 -158.949476)
			(xy 191.857279 -158.873313) (xy 191.664699 -158.789759) (xy 191.475441 -158.698934) (xy 191.289777 -158.600969)
			(xy 191.107977 -158.496007) (xy 190.930305 -158.3842) (xy 190.757019 -158.265709) (xy 190.588369 -158.140708)
			(xy 190.4246 -158.009376) (xy 190.26595 -157.871905) (xy 190.112648 -157.728494) (xy 189.964918 -157.57935)
			(xy 189.822972 -157.42469) (xy 189.687018 -157.264739) (xy 189.557251 -157.099727) (xy 189.433861 -156.929895)
			(xy 189.317026 -156.755488) (xy 189.206915 -156.57676) (xy 189.103688 -156.393969) (xy 189.007495 -156.207381)
			(xy 188.918476 -156.017266) (xy 188.836758 -155.8239) (xy 188.762462 -155.627563) (xy 188.695694 -155.42854)
			(xy 188.636552 -155.227119) (xy 188.58512 -155.023593) (xy 188.541475 -154.818256) (xy 188.505678 -154.611406)
			(xy 188.477782 -154.403344) (xy 188.457828 -154.19437) (xy 188.445843 -153.984788) (xy 188.441847 -153.774902)
			(xy 132.165372 -153.774902) (xy 132.17401 -153.779355) (xy 132.244575 -153.824704) (xy 132.31051 -153.876555)
			(xy 132.371218 -153.934439) (xy 132.426149 -153.997832) (xy 132.474805 -154.066159) (xy 132.516746 -154.138802)
			(xy 132.551591 -154.215103) (xy 132.579026 -154.29437) (xy 132.598802 -154.375887) (xy 132.61074 -154.458914)
			(xy 132.614731 -154.5427) (xy 132.61074 -154.626486) (xy 132.598802 -154.709513) (xy 132.579026 -154.79103)
			(xy 132.551591 -154.870297) (xy 132.516746 -154.946598) (xy 132.474805 -155.019241) (xy 132.426149 -155.087568)
			(xy 132.371218 -155.150961) (xy 132.31051 -155.208845) (xy 132.244575 -155.260696) (xy 132.17401 -155.306045)
			(xy 132.099453 -155.344481) (xy 132.02158 -155.375656) (xy 131.941097 -155.399287) (xy 131.858732 -155.415161)
			(xy 131.77523 -155.423133) (xy 131.73329 -155.423616) (xy 131.6961 -155.423229) (xy 131.621987 -155.416939)
			(xy 131.548668 -155.404428) (xy 131.476662 -155.385787) (xy 131.441444 -155.373832) (xy 131.433247 -155.371318)
			(xy 131.416113 -155.371318) (xy 131.407916 -155.373832) (xy 131.374578 -155.385154) (xy 131.306486 -155.403082)
			(xy 131.237181 -155.41552) (xy 131.202176 -155.419298) (xy 131.192163 -155.420682) (xy 131.174401 -155.43031)
			(xy 131.161723 -155.446041) (xy 131.158488 -155.45562) (xy 131.151035 -155.480306) (xy 131.133624 -155.528851)
			(xy 131.12369 -155.552648) (xy 131.120082 -155.562222) (xy 131.119936 -155.58266) (xy 131.123436 -155.592272)
			(xy 131.140471 -155.633645) (xy 131.167086 -155.719073) (xy 131.184987 -155.806743) (xy 131.193992 -155.895767)
			(xy 131.194556 -155.940506) (xy 131.194556 -155.94076) (xy 131.194052 -155.983108) (xy 131.186001 -156.067422)
			(xy 131.169972 -156.150588) (xy 131.146111 -156.231855) (xy 131.114632 -156.310485) (xy 131.075821 -156.385766)
			(xy 131.030031 -156.457018) (xy 130.977675 -156.523594) (xy 130.919227 -156.584892) (xy 130.855217 -156.640357)
			(xy 130.786225 -156.689486) (xy 130.712875 -156.731835) (xy 130.635832 -156.767019) (xy 130.555793 -156.794721)
			(xy 130.473484 -156.814689) (xy 130.389649 -156.826742) (xy 130.305048 -156.830773) (xy 130.220447 -156.826742)
			(xy 130.136612 -156.814689) (xy 130.054303 -156.794721) (xy 129.974264 -156.767019) (xy 129.897221 -156.731835)
			(xy 129.823871 -156.689486) (xy 129.754879 -156.640357) (xy 129.690869 -156.584892) (xy 129.632421 -156.523594)
			(xy 129.580065 -156.457018) (xy 129.534275 -156.385766) (xy 129.495464 -156.310485) (xy 129.463985 -156.231855)
			(xy 129.440124 -156.150588) (xy 129.424095 -156.067422) (xy 129.416044 -155.983108) (xy 129.41554 -155.94076)
			(xy 129.41554 -155.940506) (xy 129.416091 -155.895767) (xy 129.425111 -155.806745) (xy 129.443021 -155.719078)
			(xy 129.46964 -155.633651) (xy 129.48666 -155.592272) (xy 129.490247 -155.582688) (xy 129.490232 -155.562239)
			(xy 129.48666 -155.552648) (xy 129.471663 -155.516314) (xy 129.447353 -155.441557) (xy 129.429731 -155.364948)
			(xy 129.418932 -155.287083) (xy 129.416556 -155.247848) (xy 129.415794 -155.233878) (xy 129.400046 -155.21051)
			(xy 129.29235 -155.160472) (xy 129.264664 -155.16352) (xy 129.253234 -155.172156) (xy 129.220015 -155.196974)
			(xy 129.149739 -155.241) (xy 129.075668 -155.27829) (xy 128.998447 -155.308521) (xy 128.918747 -155.33143)
			(xy 128.83726 -155.346818) (xy 128.754694 -155.354552) (xy 128.71323 -155.355036) (xy 128.672115 -155.354573)
			(xy 128.590235 -155.346988) (xy 128.509404 -155.33188) (xy 128.430313 -155.309379) (xy 128.353635 -155.279675)
			(xy 128.280025 -155.243023) (xy 128.210111 -155.199735) (xy 128.144489 -155.150181) (xy 128.08372 -155.094783)
			(xy 128.028322 -155.034014) (xy 127.978767 -154.968393) (xy 127.935479 -154.898479) (xy 127.898826 -154.824869)
			(xy 127.869122 -154.748191) (xy 127.84662 -154.669099) (xy 127.831512 -154.588269) (xy 127.823927 -154.506389)
			(xy 127.823468 -154.465274) (xy 35.422918 -154.465274) (xy 35.41915 -154.49811) (xy 35.387298 -154.705603)
			(xy 35.34757 -154.911734) (xy 35.300023 -155.116203) (xy 35.244726 -155.318713) (xy 35.181759 -155.518971)
			(xy 35.111214 -155.716687) (xy 35.033193 -155.911574) (xy 34.947809 -156.103349) (xy 34.855186 -156.291735)
			(xy 34.755459 -156.476458) (xy 34.648771 -156.65725) (xy 34.535277 -156.83385) (xy 34.415142 -157.006)
			(xy 34.288541 -157.173453) (xy 34.155656 -157.335964) (xy 34.016681 -157.493298) (xy 33.871817 -157.645227)
			(xy 33.721274 -157.791531) (xy 33.56527 -157.931998) (xy 33.404031 -158.066424) (xy 33.237791 -158.194613)
			(xy 33.066792 -158.316381) (xy 32.891281 -158.431551) (xy 32.711513 -158.539955) (xy 32.527748 -158.641437)
			(xy 32.340252 -158.735849) (xy 32.149299 -158.823055) (xy 31.955163 -158.902928) (xy 31.758128 -158.975352)
			(xy 31.558478 -159.040222) (xy 31.356503 -159.097444) (xy 31.152497 -159.146936) (xy 30.946753 -159.188625)
			(xy 30.739572 -159.22245) (xy 30.531254 -159.248364) (xy 30.3221 -159.266329) (xy 30.112413 -159.276317)
			(xy 29.902499 -159.278316) (xy 29.69266 -159.272321) (xy 29.483202 -159.258342) (xy 29.274427 -159.236399)
			(xy 29.06664 -159.206524) (xy 28.860141 -159.168759) (xy 28.655228 -159.123161) (xy 28.452201 -159.069794)
			(xy 28.251352 -159.008737) (xy 28.052974 -158.940078) (xy 27.857353 -158.863915) (xy 27.664773 -158.780361)
			(xy 27.475515 -158.689536) (xy 27.289851 -158.591571) (xy 27.108051 -158.486609) (xy 26.930379 -158.374802)
			(xy 26.757093 -158.256311) (xy 26.588443 -158.13131) (xy 26.424674 -157.999978) (xy 26.266024 -157.862507)
			(xy 26.112722 -157.719096) (xy 25.964992 -157.569952) (xy 25.823046 -157.415292) (xy 25.687092 -157.255341)
			(xy 25.557325 -157.090329) (xy 25.433935 -156.920497) (xy 25.3171 -156.74609) (xy 25.206989 -156.567362)
			(xy 25.103762 -156.384571) (xy 25.007569 -156.197983) (xy 24.91855 -156.007868) (xy 24.836832 -155.814502)
			(xy 24.762536 -155.618165) (xy 24.695768 -155.419142) (xy 24.636626 -155.217721) (xy 24.585194 -155.014195)
			(xy 24.541549 -154.808858) (xy 24.505752 -154.602008) (xy 24.477856 -154.393946) (xy 24.457902 -154.184972)
			(xy 24.445917 -153.97539) (xy 24.441921 -153.765504) (xy 2.509012 -153.765504) (xy 2.509012 -164.097716)
			(xy 86.129368 -164.097716) (xy 86.129877 -164.05494) (xy 86.138089 -163.969783) (xy 86.154448 -163.88581)
			(xy 86.178803 -163.803797) (xy 86.194392 -163.76396) (xy 86.19746 -163.755511) (xy 86.19811 -163.737557)
			(xy 86.195662 -163.728908) (xy 86.181097 -163.683434) (xy 86.160666 -163.590154) (xy 86.150355 -163.495221)
			(xy 86.149688 -163.447476) (xy 86.150084 -163.409186) (xy 86.156694 -163.332892) (xy 86.169846 -163.257449)
			(xy 86.189443 -163.183419) (xy 86.202012 -163.147248) (xy 86.204676 -163.138815) (xy 86.204669 -163.121141)
			(xy 86.202012 -163.112704) (xy 86.18946 -163.076529) (xy 86.169889 -163.002495) (xy 86.156744 -162.927055)
			(xy 86.150122 -162.850764) (xy 86.149688 -162.812476) (xy 86.15013 -162.771365) (xy 86.157719 -162.689494)
			(xy 86.172832 -162.608673) (xy 86.195339 -162.529592) (xy 86.225048 -162.452925) (xy 86.261705 -162.379327)
			(xy 86.304997 -162.309425) (xy 86.354555 -162.243817) (xy 86.409957 -162.183063) (xy 86.470728 -162.12768)
			(xy 86.536351 -162.078142) (xy 86.606266 -162.034871) (xy 86.679876 -161.998237) (xy 86.756552 -161.968552)
			(xy 86.83564 -161.94607) (xy 86.916466 -161.930982) (xy 86.998339 -161.923417) (xy 87.03945 -161.922968)
			(xy 87.077766 -161.923352) (xy 87.154119 -161.92988) (xy 87.229626 -161.94296) (xy 87.303725 -161.962495)
			(xy 87.339932 -161.975038) (xy 87.348248 -161.977624) (xy 87.365652 -161.977624) (xy 87.373968 -161.975038)
			(xy 87.410177 -161.962503) (xy 87.484279 -161.942985) (xy 87.559785 -161.929905) (xy 87.636135 -161.92336)
			(xy 87.67445 -161.922968) (xy 87.712766 -161.923352) (xy 87.789119 -161.92988) (xy 87.864626 -161.94296)
			(xy 87.938725 -161.962495) (xy 87.974932 -161.975038) (xy 87.983248 -161.977624) (xy 88.000652 -161.977624)
			(xy 88.008968 -161.975038) (xy 88.045177 -161.962503) (xy 88.119279 -161.942985) (xy 88.194785 -161.929905)
			(xy 88.271135 -161.92336) (xy 88.30945 -161.922968) (xy 88.347766 -161.923352) (xy 88.424119 -161.92988)
			(xy 88.499626 -161.94296) (xy 88.573725 -161.962495) (xy 88.609932 -161.975038) (xy 88.618248 -161.977624)
			(xy 88.635652 -161.977624) (xy 88.643968 -161.975038) (xy 88.680177 -161.962503) (xy 88.754279 -161.942985)
			(xy 88.829785 -161.929905) (xy 88.906135 -161.92336) (xy 88.94445 -161.922968) (xy 88.982766 -161.923352)
			(xy 89.059119 -161.92988) (xy 89.134626 -161.94296) (xy 89.208725 -161.962495) (xy 89.244932 -161.975038)
			(xy 89.253248 -161.977624) (xy 89.270652 -161.977624) (xy 89.278968 -161.975038) (xy 89.315177 -161.962503)
			(xy 89.389279 -161.942985) (xy 89.464785 -161.929905) (xy 89.541135 -161.92336) (xy 89.57945 -161.922968)
			(xy 89.62106 -161.923438) (xy 89.703917 -161.931201) (xy 89.785687 -161.946663) (xy 89.865658 -161.96969)
			(xy 89.90457 -161.984436) (xy 89.913248 -161.987466) (xy 89.931617 -161.98771) (xy 89.940384 -161.984944)
			(xy 89.976385 -161.972506) (xy 90.050053 -161.953122) (xy 90.125108 -161.940106) (xy 90.201001 -161.933552)
			(xy 90.239088 -161.933128) (xy 90.23985 -161.933128) (xy 90.280956 -161.93366) (xy 90.362817 -161.94124)
			(xy 90.443629 -161.956339) (xy 90.522705 -161.97883) (xy 90.599368 -162.008519) (xy 90.672965 -162.045155)
			(xy 90.742868 -162.088423) (xy 90.808482 -162.137957) (xy 90.869246 -162.193332) (xy 90.924643 -162.254076)
			(xy 90.974199 -162.319673) (xy 91.017492 -162.389561) (xy 91.054154 -162.463145) (xy 91.08387 -162.539798)
			(xy 91.106389 -162.618865) (xy 91.121517 -162.699672) (xy 91.129125 -162.781531) (xy 91.129612 -162.822636)
			(xy 91.12919 -162.860925) (xy 91.122588 -162.937219) (xy 91.109443 -163.012662) (xy 91.089854 -163.086693)
			(xy 91.077288 -163.122864) (xy 91.076082 -163.126674) (xy 119.365268 -163.126674) (xy 119.365838 -163.081905)
			(xy 119.374847 -162.99282) (xy 119.392749 -162.905089) (xy 119.419366 -162.819597) (xy 119.436388 -162.778186)
			(xy 119.43997 -162.7686) (xy 119.43996 -162.748153) (xy 119.436388 -162.738562) (xy 119.41934 -162.69716)
			(xy 119.392709 -162.61167) (xy 119.374808 -162.523935) (xy 119.365818 -162.434845) (xy 119.365268 -162.390074)
			(xy 119.365838 -162.345305) (xy 119.374847 -162.25622) (xy 119.392749 -162.168489) (xy 119.419366 -162.082997)
			(xy 119.436388 -162.041586) (xy 119.43997 -162.032) (xy 119.43996 -162.011553) (xy 119.436388 -162.001962)
			(xy 119.41934 -161.96056) (xy 119.392709 -161.87507) (xy 119.374808 -161.787335) (xy 119.365818 -161.698245)
			(xy 119.365268 -161.653474) (xy 119.365674 -161.612358) (xy 119.373264 -161.530476) (xy 119.388376 -161.449645)
			(xy 119.410882 -161.370552) (xy 119.440591 -161.293873) (xy 119.477247 -161.220263) (xy 119.520539 -161.150349)
			(xy 119.570097 -161.084728) (xy 119.625499 -161.023959) (xy 119.686271 -160.968561) (xy 119.751895 -160.919007)
			(xy 119.821812 -160.87572) (xy 119.895425 -160.839068) (xy 119.972105 -160.809365) (xy 120.051199 -160.786863)
			(xy 120.132032 -160.771756) (xy 120.213914 -160.764171) (xy 120.25503 -160.763712) (xy 120.296641 -160.764173)
			(xy 120.379498 -160.771953) (xy 120.461267 -160.787431) (xy 120.541235 -160.810474) (xy 120.618703 -160.840879)
			(xy 120.692995 -160.878382) (xy 120.728486 -160.90011) (xy 120.737629 -160.905263) (xy 120.758342 -160.90848)
			(xy 120.778614 -160.903152) (xy 120.78716 -160.897062) (xy 120.820789 -160.871071) (xy 120.892183 -160.824946)
			(xy 120.967654 -160.785845) (xy 121.046512 -160.754124) (xy 121.128037 -160.730075) (xy 121.211485 -160.713915)
			(xy 121.296095 -160.705793) (xy 121.338594 -160.705292) (xy 121.379707 -160.705819) (xy 121.461582 -160.713405)
			(xy 121.542407 -160.728513) (xy 121.621494 -160.751013) (xy 121.698168 -160.780715) (xy 121.771774 -160.817365)
			(xy 121.841684 -160.86065) (xy 121.907303 -160.9102) (xy 121.96807 -160.965593) (xy 122.023467 -161.026357)
			(xy 122.073021 -161.091973) (xy 122.11631 -161.161881) (xy 122.152964 -161.235485) (xy 122.18267 -161.312156)
			(xy 122.205176 -161.391242) (xy 122.220288 -161.472067) (xy 122.227879 -161.553941) (xy 122.228356 -161.595054)
			(xy 122.227793 -161.639824) (xy 122.218783 -161.728909) (xy 122.200877 -161.81664) (xy 122.174259 -161.902131)
			(xy 122.157236 -161.943542) (xy 122.153699 -161.953141) (xy 122.153682 -161.973576) (xy 122.157236 -161.983166)
			(xy 122.17424 -162.024517) (xy 122.200851 -162.109879) (xy 122.218758 -162.197482) (xy 122.22778 -162.286439)
			(xy 122.228356 -162.331146) (xy 122.228356 -162.332162) (xy 122.228102 -162.343592) (xy 122.254581 -162.349538)
			(xy 122.306816 -162.364281) (xy 122.332496 -162.373056) (xy 122.340693 -162.37557) (xy 122.357827 -162.37557)
			(xy 122.366024 -162.373056) (xy 122.40124 -162.361095) (xy 122.473244 -162.342441) (xy 122.546565 -162.329932)
			(xy 122.62068 -162.323659) (xy 122.65787 -162.323272) (xy 122.695059 -162.323671) (xy 122.769172 -162.329958)
			(xy 122.842492 -162.342465) (xy 122.914498 -162.361103) (xy 122.949716 -162.373056) (xy 122.957913 -162.37557)
			(xy 122.975047 -162.37557) (xy 122.983244 -162.373056) (xy 123.018459 -162.361089) (xy 123.090462 -162.342437)
			(xy 123.163784 -162.32993) (xy 123.2379 -162.323658) (xy 123.27509 -162.323272) (xy 123.31703 -162.323667)
			(xy 123.400532 -162.331639) (xy 123.482897 -162.347513) (xy 123.56338 -162.371144) (xy 123.641253 -162.402319)
			(xy 123.71581 -162.440755) (xy 123.786375 -162.486104) (xy 123.85231 -162.537955) (xy 123.913018 -162.595839)
			(xy 123.913877 -162.59683) (xy 376.471695 -162.59683) (xy 376.4757 -162.491081) (xy 376.48769 -162.385938)
			(xy 376.507599 -162.282003) (xy 376.53531 -162.179871) (xy 376.570667 -162.080127) (xy 376.613465 -161.983343)
			(xy 376.663461 -161.890073) (xy 376.720368 -161.800852) (xy 376.783859 -161.716189) (xy 376.853571 -161.636571)
			(xy 376.929105 -161.562453) (xy 377.010028 -161.49426) (xy 377.095877 -161.432382) (xy 377.18616 -161.377175)
			(xy 377.280359 -161.328953) (xy 377.377936 -161.287993) (xy 377.478331 -161.254531) (xy 377.580969 -161.228757)
			(xy 377.685262 -161.210819) (xy 377.790613 -161.20082) (xy 377.896419 -161.198817) (xy 378.002073 -161.204822)
			(xy 378.10697 -161.218801) (xy 378.21051 -161.240672) (xy 378.312099 -161.270312) (xy 378.411156 -161.30755)
			(xy 378.507113 -161.352172) (xy 378.59942 -161.403924) (xy 378.687549 -161.462509) (xy 378.770995 -161.527591)
			(xy 378.849279 -161.598797) (xy 378.921954 -161.67572) (xy 378.988604 -161.75792) (xy 379.048846 -161.844924)
			(xy 379.102335 -161.936235) (xy 379.148766 -162.03133) (xy 379.187871 -162.129664) (xy 379.219428 -162.230675)
			(xy 379.243255 -162.333782) (xy 379.259216 -162.438396) (xy 379.26722 -162.543918) (xy 379.26772 -162.59683)
			(xy 379.26722 -162.649742) (xy 379.266995 -162.65271) (xy 385.808735 -162.65271) (xy 385.81274 -162.546961)
			(xy 385.82473 -162.441818) (xy 385.844639 -162.337883) (xy 385.87235 -162.235751) (xy 385.907707 -162.136007)
			(xy 385.950505 -162.039223) (xy 386.000501 -161.945953) (xy 386.057408 -161.856732) (xy 386.120899 -161.772069)
			(xy 386.190611 -161.692451) (xy 386.266145 -161.618333) (xy 386.347068 -161.55014) (xy 386.432917 -161.488262)
			(xy 386.5232 -161.433055) (xy 386.617399 -161.384833) (xy 386.714976 -161.343873) (xy 386.815371 -161.310411)
			(xy 386.918009 -161.284637) (xy 387.022302 -161.266699) (xy 387.127653 -161.2567) (xy 387.233459 -161.254697)
			(xy 387.339113 -161.260702) (xy 387.44401 -161.274681) (xy 387.54755 -161.296552) (xy 387.649139 -161.326192)
			(xy 387.748196 -161.36343) (xy 387.844153 -161.408052) (xy 387.93646 -161.459804) (xy 388.024589 -161.518389)
			(xy 388.108035 -161.583471) (xy 388.186319 -161.654677) (xy 388.231017 -161.701988) (xy 409.929076 -161.701988)
			(xy 409.92965 -161.657219) (xy 409.938657 -161.568134) (xy 409.956559 -161.480403) (xy 409.983175 -161.394911)
			(xy 410.000196 -161.3535) (xy 410.00377 -161.343912) (xy 410.003765 -161.323466) (xy 410.000196 -161.313876)
			(xy 409.983153 -161.272472) (xy 409.956521 -161.186983) (xy 409.938618 -161.099248) (xy 409.929627 -161.010159)
			(xy 409.929076 -160.965388) (xy 409.92965 -160.920619) (xy 409.938657 -160.831534) (xy 409.956559 -160.743803)
			(xy 409.983175 -160.658311) (xy 410.000196 -160.6169) (xy 410.00377 -160.607312) (xy 410.003765 -160.586866)
			(xy 410.000196 -160.577276) (xy 409.983153 -160.535872) (xy 409.956521 -160.450383) (xy 409.938618 -160.362648)
			(xy 409.929627 -160.273559) (xy 409.929076 -160.228788) (xy 409.929541 -160.187678) (xy 409.93713 -160.105808)
			(xy 409.952241 -160.024988) (xy 409.974747 -159.945907) (xy 410.004454 -159.869241) (xy 410.041109 -159.795643)
			(xy 410.0844 -159.725742) (xy 410.133957 -159.660134) (xy 410.189357 -159.59938) (xy 410.250127 -159.543997)
			(xy 410.315748 -159.494459) (xy 410.385662 -159.451187) (xy 410.45927 -159.414553) (xy 410.535944 -159.384867)
			(xy 410.615031 -159.362384) (xy 410.695856 -159.347295) (xy 410.777728 -159.339729) (xy 410.818838 -159.33928)
			(xy 410.860442 -159.339755) (xy 410.94329 -159.347487) (xy 411.025054 -159.362917) (xy 411.105022 -159.38591)
			(xy 411.182495 -159.416266) (xy 411.256796 -159.45372) (xy 411.292294 -159.475424) (xy 411.301434 -159.480582)
			(xy 411.322149 -159.483796) (xy 411.342422 -159.478466) (xy 411.350968 -159.472376) (xy 411.384591 -159.44642)
			(xy 411.45597 -159.400364) (xy 411.531414 -159.361321) (xy 411.610235 -159.329647) (xy 411.691716 -159.305629)
			(xy 411.775116 -159.289486) (xy 411.859674 -159.281366) (xy 411.902148 -159.28086) (xy 411.902402 -159.28086)
			(xy 411.943509 -159.281311) (xy 412.025374 -159.288895) (xy 412.106189 -159.304) (xy 412.185267 -159.326496)
			(xy 412.261931 -159.356191) (xy 412.33553 -159.392831) (xy 412.405434 -159.436106) (xy 412.471048 -159.485644)
			(xy 412.531813 -159.541025) (xy 412.587209 -159.601775) (xy 412.636764 -159.667376) (xy 412.680057 -159.737269)
			(xy 412.716716 -159.810858) (xy 412.746431 -159.887515) (xy 412.768947 -159.966587) (xy 412.784073 -160.047398)
			(xy 412.791679 -160.129261) (xy 412.792164 -160.170368) (xy 412.791606 -160.215138) (xy 412.782594 -160.304223)
			(xy 412.764688 -160.391954) (xy 412.738068 -160.477445) (xy 412.721044 -160.518856) (xy 412.717498 -160.528452)
			(xy 412.717487 -160.548889) (xy 412.721044 -160.55848) (xy 412.738053 -160.599829) (xy 412.764663 -160.685192)
			(xy 412.782568 -160.772795) (xy 412.791589 -160.861753) (xy 412.792164 -160.90646) (xy 412.792164 -160.907476)
			(xy 412.79191 -160.918906) (xy 412.818389 -160.924851) (xy 412.870624 -160.939594) (xy 412.896304 -160.94837)
			(xy 412.904501 -160.950884) (xy 412.921635 -160.950884) (xy 412.929832 -160.94837) (xy 412.96505 -160.936429)
			(xy 413.037059 -160.91784) (xy 413.110382 -160.905398) (xy 413.184492 -160.899192) (xy 413.221678 -160.89884)
			(xy 413.258862 -160.899213) (xy 413.33297 -160.905434) (xy 413.40629 -160.917875) (xy 413.478301 -160.936448)
			(xy 413.513524 -160.94837) (xy 413.521721 -160.950884) (xy 413.538855 -160.950884) (xy 413.547052 -160.94837)
			(xy 413.582146 -160.93646) (xy 413.653906 -160.917916) (xy 413.726971 -160.905476) (xy 413.800824 -160.899229)
			(xy 413.837882 -160.89884) (xy 413.838898 -160.89884) (xy 413.880822 -160.899407) (xy 413.964291 -160.907377)
			(xy 414.046623 -160.923245) (xy 414.127075 -160.946868) (xy 414.204917 -160.978031) (xy 414.279444 -161.016452)
			(xy 414.349982 -161.061784) (xy 414.415891 -161.113615) (xy 414.476575 -161.171477) (xy 414.531484 -161.234845)
			(xy 414.580121 -161.303146) (xy 414.622045 -161.37576) (xy 414.656876 -161.452031) (xy 414.684301 -161.531268)
			(xy 414.704068 -161.612752) (xy 414.716001 -161.695747) (xy 414.719991 -161.7795) (xy 414.716001 -161.863253)
			(xy 414.704068 -161.946248) (xy 414.684301 -162.027732) (xy 414.656876 -162.106969) (xy 414.622045 -162.18324)
			(xy 414.580121 -162.255854) (xy 414.531484 -162.324155) (xy 414.476575 -162.387523) (xy 414.415891 -162.445385)
			(xy 414.349982 -162.497216) (xy 414.279444 -162.542548) (xy 414.204917 -162.580969) (xy 414.127075 -162.612132)
			(xy 414.046623 -162.635755) (xy 413.964291 -162.651623) (xy 413.880822 -162.659593) (xy 413.838898 -162.660076)
			(xy 413.837882 -162.660076) (xy 413.800825 -162.659672) (xy 413.726976 -162.653407) (xy 413.653913 -162.640964)
			(xy 413.582153 -162.622432) (xy 413.547052 -162.610546) (xy 413.538855 -162.608032) (xy 413.521721 -162.608032)
			(xy 413.513524 -162.610546) (xy 413.484638 -162.620383) (xy 413.425785 -162.636529) (xy 413.395922 -162.642804)
			(xy 413.386334 -162.645159) (xy 413.369889 -162.656054) (xy 413.358796 -162.672367) (xy 413.356298 -162.68192)
			(xy 413.34617 -162.726275) (xy 413.318046 -162.812805) (xy 413.300164 -162.85464) (xy 413.296347 -162.864579)
			(xy 413.296353 -162.885846) (xy 413.300164 -162.895788) (xy 413.318394 -162.938388) (xy 413.346909 -163.026556)
			(xy 413.366099 -163.117213) (xy 413.375757 -163.209373) (xy 413.376364 -163.255706) (xy 413.376364 -163.256214)
			(xy 413.37586 -163.298562) (xy 413.367809 -163.382876) (xy 413.35178 -163.466042) (xy 413.327919 -163.547309)
			(xy 413.29644 -163.625939) (xy 413.257629 -163.70122) (xy 413.230169 -163.74395) (xy 431.840894 -163.74395)
			(xy 431.840894 -163.68945) (xy 431.84865 -163.635505) (xy 431.864004 -163.583213) (xy 431.886644 -163.533639)
			(xy 431.916109 -163.48779) (xy 431.951798 -163.446602) (xy 431.992986 -163.410912) (xy 432.038833 -163.381447)
			(xy 432.088408 -163.358807) (xy 432.140699 -163.343452) (xy 432.194644 -163.335695) (xy 432.221894 -163.335208)
			(xy 433.212494 -163.335208) (xy 433.239748 -163.335638) (xy 433.293702 -163.343395) (xy 433.346003 -163.358751)
			(xy 433.395586 -163.381394) (xy 433.441442 -163.410863) (xy 433.482637 -163.446559) (xy 433.518333 -163.487753)
			(xy 433.547803 -163.533609) (xy 433.570447 -163.583191) (xy 433.585804 -163.635492) (xy 433.593561 -163.689446)
			(xy 433.593561 -163.743954) (xy 433.585804 -163.797908) (xy 433.570447 -163.850209) (xy 433.547803 -163.899791)
			(xy 433.518333 -163.945647) (xy 433.482637 -163.986841) (xy 433.441442 -164.022537) (xy 433.395586 -164.052006)
			(xy 433.346003 -164.074649) (xy 433.293702 -164.090005) (xy 433.239748 -164.097762) (xy 433.212494 -164.098224)
			(xy 432.221894 -164.098224) (xy 432.194644 -164.097705) (xy 432.140699 -164.089948) (xy 432.088408 -164.074593)
			(xy 432.038833 -164.051953) (xy 431.992986 -164.022488) (xy 431.951798 -163.986798) (xy 431.916109 -163.94561)
			(xy 431.886644 -163.899761) (xy 431.864004 -163.850187) (xy 431.84865 -163.797895) (xy 431.840894 -163.74395)
			(xy 413.230169 -163.74395) (xy 413.211839 -163.772472) (xy 413.159483 -163.839048) (xy 413.101035 -163.900346)
			(xy 413.037025 -163.955811) (xy 412.968033 -164.00494) (xy 412.894683 -164.047289) (xy 412.81764 -164.082473)
			(xy 412.737601 -164.110175) (xy 412.655292 -164.130143) (xy 412.571457 -164.142196) (xy 412.486856 -164.146227)
			(xy 412.402255 -164.142196) (xy 412.31842 -164.130143) (xy 412.236111 -164.110175) (xy 412.156072 -164.082473)
			(xy 412.079029 -164.047289) (xy 412.005679 -164.00494) (xy 411.936687 -163.955811) (xy 411.872677 -163.900346)
			(xy 411.814229 -163.839048) (xy 411.761873 -163.772472) (xy 411.716083 -163.70122) (xy 411.677272 -163.625939)
			(xy 411.645793 -163.547309) (xy 411.621932 -163.466042) (xy 411.605903 -163.382876) (xy 411.597852 -163.298562)
			(xy 411.597348 -163.256214) (xy 411.597348 -163.255706) (xy 411.597963 -163.209374) (xy 411.607632 -163.117217)
			(xy 411.626825 -163.026563) (xy 411.655334 -162.938394) (xy 411.673548 -162.895788) (xy 411.677348 -162.885844)
			(xy 411.677353 -162.864582) (xy 411.673548 -162.85464) (xy 411.655311 -162.811974) (xy 411.626764 -162.723684)
			(xy 411.607569 -162.632899) (xy 411.597934 -162.54061) (xy 411.597348 -162.494214) (xy 411.597953 -162.446404)
			(xy 411.608131 -162.351329) (xy 411.617668 -162.304476) (xy 411.61964 -162.292071) (xy 411.612727 -162.267957)
			(xy 411.60446 -162.258502) (xy 411.56382 -162.216338) (xy 411.560264 -162.2171) (xy 411.551416 -162.219411)
			(xy 411.536053 -162.229303) (xy 411.530292 -162.236404) (xy 411.505137 -162.269067) (xy 411.449717 -162.33011)
			(xy 411.388886 -162.385763) (xy 411.323166 -162.435548) (xy 411.253121 -162.479037) (xy 411.179352 -162.515858)
			(xy 411.102492 -162.545694) (xy 411.023201 -162.56829) (xy 410.942159 -162.583451) (xy 410.860062 -162.591047)
			(xy 410.818838 -162.591496) (xy 410.777733 -162.590951) (xy 410.695873 -162.583371) (xy 410.615061 -162.568271)
			(xy 410.535987 -162.54578) (xy 410.459325 -162.516091) (xy 410.385729 -162.479456) (xy 410.315826 -162.436187)
			(xy 410.250213 -162.386655) (xy 410.18945 -162.331281) (xy 410.134053 -162.270538) (xy 410.084497 -162.204943)
			(xy 410.041203 -162.135056) (xy 410.004541 -162.061473) (xy 409.974824 -161.984822) (xy 409.952304 -161.905756)
			(xy 409.937174 -161.82495) (xy 409.929564 -161.743093) (xy 409.929076 -161.701988) (xy 388.231017 -161.701988)
			(xy 388.258994 -161.7316) (xy 388.325644 -161.8138) (xy 388.385886 -161.900804) (xy 388.439375 -161.992115)
			(xy 388.485806 -162.08721) (xy 388.524911 -162.185544) (xy 388.556468 -162.286555) (xy 388.580295 -162.389662)
			(xy 388.596256 -162.494276) (xy 388.60426 -162.599798) (xy 388.60476 -162.65271) (xy 388.60426 -162.705622)
			(xy 388.596256 -162.811144) (xy 388.580295 -162.915758) (xy 388.556468 -163.018865) (xy 388.524911 -163.119876)
			(xy 388.485806 -163.21821) (xy 388.439375 -163.313305) (xy 388.385886 -163.404616) (xy 388.325644 -163.49162)
			(xy 388.258994 -163.57382) (xy 388.186319 -163.650743) (xy 388.108035 -163.721949) (xy 388.024589 -163.787031)
			(xy 387.93646 -163.845616) (xy 387.844153 -163.897368) (xy 387.748196 -163.94199) (xy 387.649139 -163.979228)
			(xy 387.54755 -164.008868) (xy 387.44401 -164.030739) (xy 387.339113 -164.044718) (xy 387.233459 -164.050723)
			(xy 387.127653 -164.04872) (xy 387.022302 -164.038721) (xy 386.918009 -164.020783) (xy 386.815371 -163.995009)
			(xy 386.714976 -163.961547) (xy 386.617399 -163.920587) (xy 386.5232 -163.872365) (xy 386.432917 -163.817158)
			(xy 386.347068 -163.75528) (xy 386.266145 -163.687087) (xy 386.190611 -163.612969) (xy 386.120899 -163.533351)
			(xy 386.057408 -163.448688) (xy 386.000501 -163.359467) (xy 385.950505 -163.266197) (xy 385.907707 -163.169413)
			(xy 385.87235 -163.069669) (xy 385.844639 -162.967537) (xy 385.82473 -162.863602) (xy 385.81274 -162.758459)
			(xy 385.808735 -162.65271) (xy 379.266995 -162.65271) (xy 379.259216 -162.755264) (xy 379.243255 -162.859878)
			(xy 379.219428 -162.962985) (xy 379.187871 -163.063996) (xy 379.148766 -163.16233) (xy 379.102335 -163.257425)
			(xy 379.048846 -163.348736) (xy 378.988604 -163.43574) (xy 378.921954 -163.51794) (xy 378.849279 -163.594863)
			(xy 378.770995 -163.666069) (xy 378.687549 -163.731151) (xy 378.59942 -163.789736) (xy 378.507113 -163.841488)
			(xy 378.411156 -163.88611) (xy 378.312099 -163.923348) (xy 378.21051 -163.952988) (xy 378.10697 -163.974859)
			(xy 378.002073 -163.988838) (xy 377.896419 -163.994843) (xy 377.790613 -163.99284) (xy 377.685262 -163.982841)
			(xy 377.580969 -163.964903) (xy 377.478331 -163.939129) (xy 377.377936 -163.905667) (xy 377.280359 -163.864707)
			(xy 377.18616 -163.816485) (xy 377.095877 -163.761278) (xy 377.010028 -163.6994) (xy 376.929105 -163.631207)
			(xy 376.853571 -163.557089) (xy 376.783859 -163.477471) (xy 376.720368 -163.392808) (xy 376.663461 -163.303587)
			(xy 376.613465 -163.210317) (xy 376.570667 -163.113533) (xy 376.53531 -163.013789) (xy 376.507599 -162.911657)
			(xy 376.48769 -162.807722) (xy 376.4757 -162.702579) (xy 376.471695 -162.59683) (xy 123.913877 -162.59683)
			(xy 123.967949 -162.659232) (xy 124.016605 -162.727559) (xy 124.058546 -162.800202) (xy 124.093391 -162.876503)
			(xy 124.120826 -162.95577) (xy 124.140602 -163.037287) (xy 124.15254 -163.120314) (xy 124.156531 -163.2041)
			(xy 124.15254 -163.287886) (xy 124.140602 -163.370913) (xy 124.120826 -163.45243) (xy 124.093391 -163.531697)
			(xy 124.058546 -163.607998) (xy 124.016605 -163.680641) (xy 123.967949 -163.748968) (xy 123.913018 -163.812361)
			(xy 123.85231 -163.870245) (xy 123.786375 -163.922096) (xy 123.71581 -163.967445) (xy 123.641253 -164.005881)
			(xy 123.56338 -164.037056) (xy 123.482897 -164.060687) (xy 123.400532 -164.076561) (xy 123.31703 -164.084533)
			(xy 123.27509 -164.085016) (xy 123.2379 -164.084629) (xy 123.163787 -164.078339) (xy 123.090468 -164.065828)
			(xy 123.018462 -164.047187) (xy 122.983244 -164.035232) (xy 122.975047 -164.032718) (xy 122.957913 -164.032718)
			(xy 122.949716 -164.035232) (xy 122.907233 -164.049509) (xy 122.820068 -164.070379) (xy 122.775726 -164.076888)
			(xy 122.765804 -164.078672) (xy 122.748385 -164.088778) (xy 122.736231 -164.104835) (xy 122.733308 -164.11448)
			(xy 122.724748 -164.14638) (xy 122.70352 -164.20893) (xy 122.69089 -164.239448) (xy 122.687282 -164.249022)
			(xy 122.687136 -164.26946) (xy 122.690636 -164.279072) (xy 122.707671 -164.320445) (xy 122.734286 -164.405873)
			(xy 122.752187 -164.493543) (xy 122.756237 -164.53358) (xy 365.854996 -164.53358) (xy 365.855358 -164.495263)
			(xy 365.861892 -164.41891) (xy 365.874978 -164.343403) (xy 365.89452 -164.269304) (xy 365.907066 -164.233098)
			(xy 365.909662 -164.224784) (xy 365.909655 -164.207378) (xy 365.907066 -164.199062) (xy 365.894569 -164.162941)
			(xy 365.875081 -164.089028) (xy 365.861998 -164.013717) (xy 365.855418 -163.937561) (xy 365.854996 -163.899342)
			(xy 365.854996 -163.89858) (xy 365.855448 -163.857477) (xy 365.863034 -163.775622) (xy 365.878141 -163.694816)
			(xy 365.900639 -163.615749) (xy 365.930337 -163.539095) (xy 365.966981 -163.465508) (xy 366.010258 -163.395615)
			(xy 366.059799 -163.330014) (xy 366.115181 -163.269264) (xy 366.175933 -163.213883) (xy 366.241535 -163.164344)
			(xy 366.311429 -163.121069) (xy 366.385017 -163.084427) (xy 366.461672 -163.054732) (xy 366.54074 -163.032236)
			(xy 366.621546 -163.017131) (xy 366.703401 -163.009546) (xy 366.744504 -163.009072) (xy 366.745266 -163.009072)
			(xy 366.783487 -163.009474) (xy 366.859645 -163.01604) (xy 366.934958 -163.029126) (xy 367.008868 -163.048635)
			(xy 367.044986 -163.061142) (xy 367.053302 -163.063728) (xy 367.070706 -163.063728) (xy 367.079022 -163.061142)
			(xy 367.115235 -163.04862) (xy 367.189336 -163.029098) (xy 367.26484 -163.016015) (xy 367.341189 -163.009466)
			(xy 367.379504 -163.009072) (xy 367.419718 -163.009498) (xy 367.49982 -163.016721) (xy 367.578942 -163.031153)
			(xy 367.656435 -163.052677) (xy 367.69421 -163.066476) (xy 367.702997 -163.069383) (xy 367.721491 -163.069383)
			(xy 367.730278 -163.066476) (xy 367.768054 -163.052684) (xy 367.845551 -163.031177) (xy 367.924672 -163.016746)
			(xy 368.004771 -163.00951) (xy 368.044984 -163.009072) (xy 368.0833 -163.009446) (xy 368.159653 -163.015977)
			(xy 368.23516 -163.029059) (xy 368.309259 -163.048598) (xy 368.345466 -163.061142) (xy 368.353782 -163.063728)
			(xy 368.371186 -163.063728) (xy 368.379502 -163.061142) (xy 368.415717 -163.048626) (xy 368.489817 -163.029103)
			(xy 368.565321 -163.016017) (xy 368.641669 -163.009467) (xy 368.679984 -163.009072) (xy 368.7183 -163.009446)
			(xy 368.794653 -163.015977) (xy 368.87016 -163.029059) (xy 368.944259 -163.048598) (xy 368.980466 -163.061142)
			(xy 368.988782 -163.063728) (xy 369.006186 -163.063728) (xy 369.014502 -163.061142) (xy 369.050717 -163.048626)
			(xy 369.124817 -163.029103) (xy 369.200321 -163.016017) (xy 369.276669 -163.009467) (xy 369.314984 -163.009072)
			(xy 369.3533 -163.009446) (xy 369.429653 -163.015977) (xy 369.50516 -163.029059) (xy 369.579259 -163.048598)
			(xy 369.615466 -163.061142) (xy 369.623782 -163.063728) (xy 369.641186 -163.063728) (xy 369.649502 -163.061142)
			(xy 369.685717 -163.048626) (xy 369.759817 -163.029103) (xy 369.835321 -163.016017) (xy 369.911669 -163.009467)
			(xy 369.949984 -163.009072) (xy 369.994754 -163.009635) (xy 370.083841 -163.018637) (xy 370.171573 -163.03654)
			(xy 370.257063 -163.063164) (xy 370.298472 -163.080192) (xy 370.308063 -163.083757) (xy 370.328505 -163.083757)
			(xy 370.338096 -163.080192) (xy 370.379479 -163.063183) (xy 370.464904 -163.036561) (xy 370.55257 -163.018653)
			(xy 370.641592 -163.00964) (xy 370.68633 -163.009072) (xy 370.686584 -163.009072) (xy 370.727686 -163.009582)
			(xy 370.809538 -163.017165) (xy 370.890342 -163.032268) (xy 370.969408 -163.054763) (xy 371.046061 -163.084457)
			(xy 371.119647 -163.121096) (xy 371.189538 -163.16437) (xy 371.255139 -163.213907) (xy 371.315889 -163.269286)
			(xy 371.37127 -163.330033) (xy 371.42081 -163.395632) (xy 371.464086 -163.465522) (xy 371.500729 -163.539106)
			(xy 371.530426 -163.615758) (xy 371.552923 -163.694823) (xy 371.56803 -163.775626) (xy 371.575616 -163.857478)
			(xy 371.576092 -163.89858) (xy 371.576092 -163.899342) (xy 371.575679 -163.937562) (xy 371.569116 -164.013721)
			(xy 371.556033 -164.089033) (xy 371.536527 -164.162943) (xy 371.524022 -164.199062) (xy 371.521447 -164.207381)
			(xy 371.52144 -164.224782) (xy 371.524022 -164.233098) (xy 371.536535 -164.269314) (xy 371.55606 -164.343414)
			(xy 371.569146 -164.418917) (xy 371.575697 -164.495265) (xy 371.576092 -164.53358) (xy 371.575734 -164.571323)
			(xy 371.569392 -164.646543) (xy 371.556692 -164.720953) (xy 371.537726 -164.794018) (xy 371.525546 -164.829744)
			(xy 371.522818 -164.838516) (xy 371.52307 -164.85687) (xy 371.526054 -164.865558) (xy 371.541045 -164.904681)
			(xy 371.564495 -164.985121) (xy 371.58028 -165.067409) (xy 371.588259 -165.150817) (xy 371.588792 -165.19271)
			(xy 371.588792 -165.19398) (xy 371.588329 -165.235083) (xy 371.580745 -165.316939) (xy 371.565641 -165.397747)
			(xy 371.543146 -165.476815) (xy 371.51345 -165.553471) (xy 371.476808 -165.62706) (xy 371.433533 -165.696954)
			(xy 371.383993 -165.762556) (xy 371.328611 -165.823308) (xy 371.267859 -165.87869) (xy 371.202257 -165.92823)
			(xy 371.132363 -165.971506) (xy 371.058775 -166.008149) (xy 370.982119 -166.037844) (xy 370.90305 -166.06034)
			(xy 370.822243 -166.075445) (xy 370.740387 -166.083029) (xy 370.699284 -166.083488) (xy 370.69903 -166.083488)
			(xy 370.654291 -166.082927) (xy 370.56527 -166.07391) (xy 370.477602 -166.056003) (xy 370.392175 -166.029387)
			(xy 370.350796 -166.012368) (xy 370.341205 -166.008803) (xy 370.320763 -166.008803) (xy 370.311172 -166.012368)
			(xy 370.269762 -166.029396) (xy 370.184274 -166.056029) (xy 370.096542 -166.073935) (xy 370.007454 -166.082933)
			(xy 369.962684 -166.083488) (xy 369.924367 -166.083126) (xy 369.848014 -166.076592) (xy 369.772507 -166.063506)
			(xy 369.698408 -166.043964) (xy 369.662202 -166.031418) (xy 369.653886 -166.028832) (xy 369.636482 -166.028832)
			(xy 369.628166 -166.031418) (xy 369.591953 -166.043941) (xy 369.517852 -166.063463) (xy 369.442348 -166.076546)
			(xy 369.365999 -166.083094) (xy 369.327684 -166.083488) (xy 369.289367 -166.083126) (xy 369.213014 -166.076592)
			(xy 369.137507 -166.063506) (xy 369.063408 -166.043964) (xy 369.027202 -166.031418) (xy 369.018886 -166.028832)
			(xy 369.001482 -166.028832) (xy 368.993166 -166.031418) (xy 368.956953 -166.043941) (xy 368.882852 -166.063463)
			(xy 368.807348 -166.076546) (xy 368.730999 -166.083094) (xy 368.692684 -166.083488) (xy 368.654367 -166.083126)
			(xy 368.578014 -166.076592) (xy 368.502507 -166.063506) (xy 368.428408 -166.043964) (xy 368.392202 -166.031418)
			(xy 368.383886 -166.028832) (xy 368.366482 -166.028832) (xy 368.358166 -166.031418) (xy 368.321953 -166.043941)
			(xy 368.247852 -166.063463) (xy 368.172348 -166.076546) (xy 368.095999 -166.083094) (xy 368.057684 -166.083488)
			(xy 368.01747 -166.083062) (xy 367.937368 -166.075838) (xy 367.858246 -166.061406) (xy 367.780753 -166.039883)
			(xy 367.742978 -166.026084) (xy 367.734191 -166.023177) (xy 367.715697 -166.023177) (xy 367.70691 -166.026084)
			(xy 367.669134 -166.039877) (xy 367.591637 -166.061385) (xy 367.512517 -166.075815) (xy 367.432417 -166.083051)
			(xy 367.392204 -166.083488) (xy 367.353888 -166.08312) (xy 367.277534 -166.076588) (xy 367.202027 -166.063503)
			(xy 367.127928 -166.043963) (xy 367.091722 -166.031418) (xy 367.083406 -166.028832) (xy 367.066002 -166.028832)
			(xy 367.057686 -166.031418) (xy 367.021563 -166.043908) (xy 366.947651 -166.063398) (xy 366.87234 -166.076483)
			(xy 366.796185 -166.083065) (xy 366.757966 -166.083488) (xy 366.757204 -166.083488) (xy 366.7161 -166.083044)
			(xy 366.634244 -166.075459) (xy 366.553436 -166.060354) (xy 366.474367 -166.037857) (xy 366.397711 -166.00816)
			(xy 366.324122 -165.971516) (xy 366.254228 -165.928239) (xy 366.188625 -165.878698) (xy 366.127874 -165.823315)
			(xy 366.072492 -165.762562) (xy 366.022951 -165.696959) (xy 365.979676 -165.627064) (xy 365.943034 -165.553475)
			(xy 365.913338 -165.476818) (xy 365.890843 -165.397748) (xy 365.875739 -165.316941) (xy 365.868155 -165.235084)
			(xy 365.867696 -165.19398) (xy 365.867696 -165.192964) (xy 365.868115 -165.155349) (xy 365.874496 -165.080389)
			(xy 365.887191 -165.006237) (xy 365.906111 -164.933424) (xy 365.918242 -164.897816) (xy 365.920992 -164.889049)
			(xy 365.920727 -164.87069) (xy 365.917734 -164.862002) (xy 365.902679 -164.822733) (xy 365.879172 -164.741978)
			(xy 365.863391 -164.659366) (xy 365.855475 -164.575633) (xy 365.854996 -164.53358) (xy 122.756237 -164.53358)
			(xy 122.761192 -164.582567) (xy 122.761756 -164.627306) (xy 122.761756 -164.62756) (xy 122.761252 -164.669908)
			(xy 122.753201 -164.754222) (xy 122.737172 -164.837388) (xy 122.713311 -164.918655) (xy 122.681832 -164.997285)
			(xy 122.643021 -165.072566) (xy 122.597231 -165.143818) (xy 122.544875 -165.210394) (xy 122.486427 -165.271692)
			(xy 122.422417 -165.327157) (xy 122.353425 -165.376286) (xy 122.280075 -165.418635) (xy 122.203032 -165.453819)
			(xy 122.122993 -165.481521) (xy 122.040684 -165.501489) (xy 121.956849 -165.513542) (xy 121.872248 -165.517573)
			(xy 121.787647 -165.513542) (xy 121.703812 -165.501489) (xy 121.621503 -165.481521) (xy 121.541464 -165.453819)
			(xy 121.464421 -165.418635) (xy 121.391071 -165.376286) (xy 121.322079 -165.327157) (xy 121.258069 -165.271692)
			(xy 121.199621 -165.210394) (xy 121.147265 -165.143818) (xy 121.101475 -165.072566) (xy 121.062664 -164.997285)
			(xy 121.031185 -164.918655) (xy 121.007324 -164.837388) (xy 120.991295 -164.754222) (xy 120.983244 -164.669908)
			(xy 120.98274 -164.62756) (xy 120.98274 -164.627306) (xy 120.983291 -164.582567) (xy 120.992311 -164.493545)
			(xy 121.010221 -164.405878) (xy 121.03684 -164.320451) (xy 121.05386 -164.279072) (xy 121.057447 -164.269488)
			(xy 121.057432 -164.249039) (xy 121.05386 -164.239448) (xy 121.037012 -164.19848) (xy 121.010567 -164.113931)
			(xy 120.992664 -164.027171) (xy 120.983478 -163.939061) (xy 120.98274 -163.89477) (xy 120.982373 -163.885212)
			(xy 120.975335 -163.867438) (xy 120.962255 -163.853496) (xy 120.953784 -163.84905) (xy 120.870726 -163.809934)
			(xy 120.861899 -163.806187) (xy 120.842781 -163.804911) (xy 120.824539 -163.810771) (xy 120.816878 -163.816538)
			(xy 120.782853 -163.843559) (xy 120.710459 -163.891613) (xy 120.633724 -163.93238) (xy 120.55338 -163.965469)
			(xy 120.470192 -163.990568) (xy 120.384953 -164.007435) (xy 120.298476 -164.01591) (xy 120.25503 -164.016436)
			(xy 120.213915 -164.015973) (xy 120.132035 -164.008388) (xy 120.051204 -163.99328) (xy 119.972113 -163.970779)
			(xy 119.895435 -163.941075) (xy 119.821825 -163.904423) (xy 119.751911 -163.861135) (xy 119.686289 -163.811581)
			(xy 119.62552 -163.756183) (xy 119.570122 -163.695414) (xy 119.520567 -163.629793) (xy 119.477279 -163.559879)
			(xy 119.440626 -163.486269) (xy 119.410922 -163.409591) (xy 119.38842 -163.330499) (xy 119.373312 -163.249669)
			(xy 119.365727 -163.167789) (xy 119.365268 -163.126674) (xy 91.076082 -163.126674) (xy 91.074618 -163.131296)
			(xy 91.074629 -163.148971) (xy 91.077288 -163.157408) (xy 91.089816 -163.193591) (xy 91.109393 -163.267622)
			(xy 91.122545 -163.34306) (xy 91.129174 -163.419348) (xy 91.129612 -163.457636) (xy 91.129114 -163.500412)
			(xy 91.120898 -163.585569) (xy 91.104536 -163.669543) (xy 91.080178 -163.751555) (xy 91.064588 -163.791392)
			(xy 91.061544 -163.799848) (xy 91.060879 -163.817795) (xy 91.063318 -163.826444) (xy 91.07787 -163.871922)
			(xy 91.098306 -163.9652) (xy 91.108623 -164.060131) (xy 91.109292 -164.107876) (xy 91.108825 -164.148987)
			(xy 91.101239 -164.230857) (xy 91.08613 -164.311679) (xy 91.063626 -164.390761) (xy 91.033921 -164.467428)
			(xy 90.997266 -164.541027) (xy 90.953976 -164.610929) (xy 90.904419 -164.676538) (xy 90.849019 -164.737293)
			(xy 90.788249 -164.792677) (xy 90.722626 -164.842215) (xy 90.652712 -164.885486) (xy 90.579103 -164.92212)
			(xy 90.502427 -164.951804) (xy 90.423339 -164.974286) (xy 90.342514 -164.989373) (xy 90.260641 -164.996936)
			(xy 90.21953 -164.997384) (xy 90.177921 -164.996892) (xy 90.095064 -164.989136) (xy 90.013294 -164.97368)
			(xy 89.933323 -164.950659) (xy 89.89441 -164.935916) (xy 89.88572 -164.932926) (xy 89.867362 -164.932654)
			(xy 89.858596 -164.935408) (xy 89.822497 -164.947854) (xy 89.748643 -164.967275) (xy 89.673397 -164.980297)
			(xy 89.597312 -164.986825) (xy 89.55913 -164.987224) (xy 89.520814 -164.986846) (xy 89.444461 -164.980317)
			(xy 89.368954 -164.967235) (xy 89.294855 -164.947698) (xy 89.258648 -164.935154) (xy 89.250332 -164.932568)
			(xy 89.232928 -164.932568) (xy 89.224612 -164.935154) (xy 89.188396 -164.947666) (xy 89.114296 -164.96719)
			(xy 89.038793 -164.980277) (xy 88.962445 -164.986828) (xy 88.92413 -164.987224) (xy 88.885814 -164.986846)
			(xy 88.809461 -164.980317) (xy 88.733954 -164.967235) (xy 88.659855 -164.947698) (xy 88.623648 -164.935154)
			(xy 88.615332 -164.932568) (xy 88.597928 -164.932568) (xy 88.589612 -164.935154) (xy 88.553396 -164.947666)
			(xy 88.479296 -164.96719) (xy 88.403793 -164.980277) (xy 88.327445 -164.986828) (xy 88.28913 -164.987224)
			(xy 88.250814 -164.986846) (xy 88.174461 -164.980317) (xy 88.098954 -164.967235) (xy 88.024855 -164.947698)
			(xy 87.988648 -164.935154) (xy 87.980332 -164.932568) (xy 87.962928 -164.932568) (xy 87.954612 -164.935154)
			(xy 87.918396 -164.947666) (xy 87.844296 -164.96719) (xy 87.768793 -164.980277) (xy 87.692445 -164.986828)
			(xy 87.65413 -164.987224) (xy 87.615814 -164.986846) (xy 87.539461 -164.980317) (xy 87.463954 -164.967235)
			(xy 87.389855 -164.947698) (xy 87.353648 -164.935154) (xy 87.345332 -164.932568) (xy 87.327928 -164.932568)
			(xy 87.319612 -164.935154) (xy 87.283487 -164.947638) (xy 87.209575 -164.96713) (xy 87.134265 -164.980216)
			(xy 87.058111 -164.9868) (xy 87.019892 -164.987224) (xy 87.01913 -164.987224) (xy 86.978023 -164.986759)
			(xy 86.896158 -164.979177) (xy 86.815342 -164.964075) (xy 86.736265 -164.941581) (xy 86.659599 -164.911888)
			(xy 86.586 -164.875249) (xy 86.516095 -164.831976) (xy 86.45048 -164.782438) (xy 86.389716 -164.727058)
			(xy 86.334319 -164.666309) (xy 86.284763 -164.600708) (xy 86.241471 -164.530815) (xy 86.204811 -164.457226)
			(xy 86.175097 -164.380569) (xy 86.152582 -164.301497) (xy 86.137457 -164.220686) (xy 86.129853 -164.138823)
			(xy 86.129368 -164.097716) (xy 2.509012 -164.097716) (xy 2.509012 -166.86276) (xy 61.046868 -166.86276)
			(xy 61.047433 -166.81799) (xy 61.056443 -166.728905) (xy 61.074347 -166.641174) (xy 61.100966 -166.555683)
			(xy 61.117988 -166.514272) (xy 61.121578 -166.504688) (xy 61.121563 -166.484239) (xy 61.117988 -166.474648)
			(xy 61.100968 -166.433235) (xy 61.074329 -166.347749) (xy 61.05642 -166.260018) (xy 61.047422 -166.17093)
			(xy 61.046868 -166.12616) (xy 61.047433 -166.08139) (xy 61.056443 -165.992305) (xy 61.074347 -165.904574)
			(xy 61.100966 -165.819083) (xy 61.117988 -165.777672) (xy 61.121578 -165.768088) (xy 61.121563 -165.747639)
			(xy 61.117988 -165.738048) (xy 61.100968 -165.696635) (xy 61.074329 -165.611149) (xy 61.05642 -165.523418)
			(xy 61.047422 -165.43433) (xy 61.046868 -165.38956) (xy 61.047314 -165.348449) (xy 61.054905 -165.266579)
			(xy 61.070019 -165.185759) (xy 61.092527 -165.106679) (xy 61.122236 -165.030013) (xy 61.158893 -164.956415)
			(xy 61.202185 -164.886514) (xy 61.251743 -164.820907) (xy 61.307144 -164.760153) (xy 61.367915 -164.70477)
			(xy 61.433537 -164.655232) (xy 61.503451 -164.611961) (xy 61.57706 -164.575327) (xy 61.653735 -164.545641)
			(xy 61.732822 -164.523157) (xy 61.813647 -164.508068) (xy 61.895519 -164.500502) (xy 61.93663 -164.500052)
			(xy 61.978234 -164.500535) (xy 62.061081 -164.508266) (xy 62.142846 -164.523695) (xy 62.222813 -164.546687)
			(xy 62.300286 -164.577041) (xy 62.374588 -164.614493) (xy 62.410086 -164.636196) (xy 62.419228 -164.641351)
			(xy 62.439942 -164.644569) (xy 62.460215 -164.639239) (xy 62.46876 -164.633148) (xy 62.502383 -164.607191)
			(xy 62.573762 -164.561136) (xy 62.649206 -164.522094) (xy 62.728027 -164.49042) (xy 62.809509 -164.466402)
			(xy 62.892908 -164.450259) (xy 62.977466 -164.442138) (xy 63.01994 -164.441632) (xy 63.020194 -164.441632)
			(xy 63.0613 -164.442118) (xy 63.143163 -164.449702) (xy 63.223977 -164.464805) (xy 63.303052 -164.487299)
			(xy 63.379716 -164.516993) (xy 63.453313 -164.553631) (xy 63.523217 -164.596903) (xy 63.58883 -164.64644)
			(xy 63.649594 -164.701818) (xy 63.70499 -164.762565) (xy 63.754546 -164.828164) (xy 63.797839 -164.898054)
			(xy 63.8345 -164.971641) (xy 63.864216 -165.048295) (xy 63.886734 -165.127364) (xy 63.901861 -165.208173)
			(xy 63.909469 -165.290034) (xy 63.909956 -165.33114) (xy 63.909389 -165.375909) (xy 63.900379 -165.464994)
			(xy 63.882475 -165.552725) (xy 63.855858 -165.638217) (xy 63.838836 -165.679628) (xy 63.83525 -165.689212)
			(xy 63.835264 -165.709661) (xy 63.838836 -165.719252) (xy 63.855836 -165.760605) (xy 63.882448 -165.845966)
			(xy 63.900356 -165.933568) (xy 63.903248 -165.962076) (xy 81.591411 -165.962076) (xy 81.595416 -165.856327)
			(xy 81.607406 -165.751184) (xy 81.627315 -165.647249) (xy 81.655026 -165.545117) (xy 81.690383 -165.445373)
			(xy 81.733181 -165.348589) (xy 81.783177 -165.255319) (xy 81.840084 -165.166098) (xy 81.903575 -165.081435)
			(xy 81.973287 -165.001817) (xy 82.048821 -164.927699) (xy 82.129744 -164.859506) (xy 82.215593 -164.797628)
			(xy 82.305876 -164.742421) (xy 82.400075 -164.694199) (xy 82.497652 -164.653239) (xy 82.598047 -164.619777)
			(xy 82.700685 -164.594003) (xy 82.804978 -164.576065) (xy 82.910329 -164.566066) (xy 83.016135 -164.564063)
			(xy 83.121789 -164.570068) (xy 83.226686 -164.584047) (xy 83.330226 -164.605918) (xy 83.431815 -164.635558)
			(xy 83.530872 -164.672796) (xy 83.626829 -164.717418) (xy 83.719136 -164.76917) (xy 83.807265 -164.827755)
			(xy 83.890711 -164.892837) (xy 83.968995 -164.964043) (xy 84.04167 -165.040966) (xy 84.10832 -165.123166)
			(xy 84.168562 -165.21017) (xy 84.222051 -165.301481) (xy 84.268482 -165.396576) (xy 84.307587 -165.49491)
			(xy 84.339144 -165.595921) (xy 84.362971 -165.699028) (xy 84.378932 -165.803642) (xy 84.386936 -165.909164)
			(xy 84.387436 -165.962076) (xy 90.989411 -165.962076) (xy 90.993416 -165.856327) (xy 91.005406 -165.751184)
			(xy 91.025315 -165.647249) (xy 91.053026 -165.545117) (xy 91.088383 -165.445373) (xy 91.131181 -165.348589)
			(xy 91.181177 -165.255319) (xy 91.238084 -165.166098) (xy 91.301575 -165.081435) (xy 91.371287 -165.001817)
			(xy 91.446821 -164.927699) (xy 91.527744 -164.859506) (xy 91.613593 -164.797628) (xy 91.703876 -164.742421)
			(xy 91.798075 -164.694199) (xy 91.895652 -164.653239) (xy 91.996047 -164.619777) (xy 92.098685 -164.594003)
			(xy 92.202978 -164.576065) (xy 92.308329 -164.566066) (xy 92.414135 -164.564063) (xy 92.519789 -164.570068)
			(xy 92.624686 -164.584047) (xy 92.728226 -164.605918) (xy 92.829815 -164.635558) (xy 92.928872 -164.672796)
			(xy 93.024829 -164.717418) (xy 93.117136 -164.76917) (xy 93.205265 -164.827755) (xy 93.288711 -164.892837)
			(xy 93.366995 -164.964043) (xy 93.43967 -165.040966) (xy 93.50632 -165.123166) (xy 93.566562 -165.21017)
			(xy 93.620051 -165.301481) (xy 93.666482 -165.396576) (xy 93.705587 -165.49491) (xy 93.737144 -165.595921)
			(xy 93.760971 -165.699028) (xy 93.776932 -165.803642) (xy 93.784936 -165.909164) (xy 93.785436 -165.962076)
			(xy 93.784936 -166.014988) (xy 93.776932 -166.12051) (xy 93.760971 -166.225124) (xy 93.737144 -166.328231)
			(xy 93.705587 -166.429242) (xy 93.666482 -166.527576) (xy 93.620051 -166.622671) (xy 93.566562 -166.713982)
			(xy 93.50632 -166.800986) (xy 93.43967 -166.883186) (xy 93.366995 -166.960109) (xy 93.288711 -167.031315)
			(xy 93.205265 -167.096397) (xy 93.117136 -167.154982) (xy 93.024829 -167.206734) (xy 92.928872 -167.251356)
			(xy 92.829815 -167.288594) (xy 92.728226 -167.318234) (xy 92.624686 -167.340105) (xy 92.519789 -167.354084)
			(xy 92.414135 -167.360089) (xy 92.308329 -167.358086) (xy 92.202978 -167.348087) (xy 92.098685 -167.330149)
			(xy 91.996047 -167.304375) (xy 91.895652 -167.270913) (xy 91.798075 -167.229953) (xy 91.703876 -167.181731)
			(xy 91.613593 -167.126524) (xy 91.527744 -167.064646) (xy 91.446821 -166.996453) (xy 91.371287 -166.922335)
			(xy 91.301575 -166.842717) (xy 91.238084 -166.758054) (xy 91.181177 -166.668833) (xy 91.131181 -166.575563)
			(xy 91.088383 -166.478779) (xy 91.053026 -166.379035) (xy 91.025315 -166.276903) (xy 91.005406 -166.172968)
			(xy 90.993416 -166.067825) (xy 90.989411 -165.962076) (xy 84.387436 -165.962076) (xy 84.386936 -166.014988)
			(xy 84.378932 -166.12051) (xy 84.362971 -166.225124) (xy 84.339144 -166.328231) (xy 84.307587 -166.429242)
			(xy 84.268482 -166.527576) (xy 84.222051 -166.622671) (xy 84.168562 -166.713982) (xy 84.10832 -166.800986)
			(xy 84.04167 -166.883186) (xy 83.968995 -166.960109) (xy 83.890711 -167.031315) (xy 83.807265 -167.096397)
			(xy 83.719136 -167.154982) (xy 83.626829 -167.206734) (xy 83.530872 -167.251356) (xy 83.431815 -167.288594)
			(xy 83.330226 -167.318234) (xy 83.226686 -167.340105) (xy 83.121789 -167.354084) (xy 83.016135 -167.360089)
			(xy 82.910329 -167.358086) (xy 82.804978 -167.348087) (xy 82.700685 -167.330149) (xy 82.598047 -167.304375)
			(xy 82.497652 -167.270913) (xy 82.400075 -167.229953) (xy 82.305876 -167.181731) (xy 82.215593 -167.126524)
			(xy 82.129744 -167.064646) (xy 82.048821 -166.996453) (xy 81.973287 -166.922335) (xy 81.903575 -166.842717)
			(xy 81.840084 -166.758054) (xy 81.783177 -166.668833) (xy 81.733181 -166.575563) (xy 81.690383 -166.478779)
			(xy 81.655026 -166.379035) (xy 81.627315 -166.276903) (xy 81.607406 -166.172968) (xy 81.595416 -166.067825)
			(xy 81.591411 -165.962076) (xy 63.903248 -165.962076) (xy 63.909379 -166.022525) (xy 63.909956 -166.067232)
			(xy 63.909956 -166.068248) (xy 63.909702 -166.079678) (xy 63.936181 -166.085625) (xy 63.988416 -166.100367)
			(xy 64.014096 -166.109142) (xy 64.022293 -166.111656) (xy 64.039427 -166.111656) (xy 64.047624 -166.109142)
			(xy 64.082842 -166.097202) (xy 64.154852 -166.078613) (xy 64.228174 -166.066171) (xy 64.302285 -166.059965)
			(xy 64.33947 -166.059612) (xy 64.376654 -166.059989) (xy 64.450761 -166.066209) (xy 64.524081 -166.078649)
			(xy 64.596093 -166.097221) (xy 64.631316 -166.109142) (xy 64.639513 -166.111656) (xy 64.656647 -166.111656)
			(xy 64.664844 -166.109142) (xy 64.699939 -166.097233) (xy 64.771698 -166.078689) (xy 64.844763 -166.066249)
			(xy 64.918616 -166.060001) (xy 64.955674 -166.059612) (xy 64.95669 -166.059612) (xy 64.998618 -166.060035)
			(xy 65.082094 -166.068005) (xy 65.164434 -166.083874) (xy 65.244893 -166.107498) (xy 65.322742 -166.138663)
			(xy 65.397276 -166.177087) (xy 65.46782 -166.222422) (xy 65.533735 -166.274258) (xy 65.594424 -166.332124)
			(xy 65.649338 -166.395498) (xy 65.69798 -166.463804) (xy 65.739908 -166.536425) (xy 65.774743 -166.612703)
			(xy 65.802169 -166.691946) (xy 65.821939 -166.773438) (xy 65.833873 -166.85644) (xy 65.837863 -166.9402)
			(xy 65.833873 -167.02396) (xy 65.821939 -167.106962) (xy 65.802169 -167.188454) (xy 65.774743 -167.267697)
			(xy 65.739908 -167.343975) (xy 65.69798 -167.416596) (xy 65.688295 -167.430196) (xy 351.432876 -167.430196)
			(xy 351.433453 -167.385427) (xy 351.442459 -167.296342) (xy 351.46036 -167.208611) (xy 351.486975 -167.123119)
			(xy 351.503996 -167.081708) (xy 351.507565 -167.072118) (xy 351.507564 -167.051674) (xy 351.503996 -167.042084)
			(xy 351.486956 -167.000679) (xy 351.460322 -166.91519) (xy 351.442419 -166.827456) (xy 351.433427 -166.738367)
			(xy 351.432876 -166.693596) (xy 351.433453 -166.648827) (xy 351.442459 -166.559742) (xy 351.46036 -166.472011)
			(xy 351.486975 -166.386519) (xy 351.503996 -166.345108) (xy 351.507565 -166.335518) (xy 351.507564 -166.315074)
			(xy 351.503996 -166.305484) (xy 351.486956 -166.264079) (xy 351.460322 -166.17859) (xy 351.442419 -166.090856)
			(xy 351.433427 -166.001767) (xy 351.432876 -165.956996) (xy 351.433349 -165.915886) (xy 351.440937 -165.834016)
			(xy 351.456047 -165.753196) (xy 351.478552 -165.674116) (xy 351.508259 -165.597449) (xy 351.544914 -165.523852)
			(xy 351.588204 -165.453951) (xy 351.63776 -165.388343) (xy 351.693159 -165.327588) (xy 351.753929 -165.272205)
			(xy 351.81955 -165.222667) (xy 351.889463 -165.179396) (xy 351.963071 -165.142761) (xy 352.039745 -165.113075)
			(xy 352.118832 -165.090592) (xy 352.199656 -165.075503) (xy 352.281528 -165.067937) (xy 352.322638 -165.067488)
			(xy 352.364242 -165.067962) (xy 352.44709 -165.075694) (xy 352.528855 -165.091124) (xy 352.608822 -165.114117)
			(xy 352.686295 -165.144474) (xy 352.760597 -165.181928) (xy 352.796094 -165.203632) (xy 352.805234 -165.208789)
			(xy 352.825949 -165.212002) (xy 352.846222 -165.206673) (xy 352.854768 -165.200584) (xy 352.888392 -165.174629)
			(xy 352.959771 -165.128573) (xy 353.035214 -165.08953) (xy 353.114035 -165.057855) (xy 353.195516 -165.033837)
			(xy 353.278916 -165.017694) (xy 353.363474 -165.009574) (xy 353.405948 -165.009068) (xy 353.406202 -165.009068)
			(xy 353.44731 -165.009511) (xy 353.529174 -165.017096) (xy 353.60999 -165.0322) (xy 353.689068 -165.054696)
			(xy 353.765733 -165.084391) (xy 353.839332 -165.121033) (xy 353.909237 -165.164307) (xy 353.974851 -165.213846)
			(xy 354.035616 -165.269227) (xy 354.091012 -165.329978) (xy 354.140567 -165.39558) (xy 354.183859 -165.465474)
			(xy 354.220519 -165.539063) (xy 354.250233 -165.615721) (xy 354.272749 -165.694793) (xy 354.287874 -165.775606)
			(xy 354.295479 -165.857468) (xy 354.295964 -165.898576) (xy 354.295409 -165.943346) (xy 354.286396 -166.032431)
			(xy 354.268489 -166.120162) (xy 354.241868 -166.205653) (xy 354.224844 -166.247064) (xy 354.221294 -166.256659)
			(xy 354.221285 -166.277097) (xy 354.224844 -166.286688) (xy 354.241856 -166.328036) (xy 354.268465 -166.413399)
			(xy 354.286369 -166.501003) (xy 354.289105 -166.527988) (xy 401.547076 -166.527988) (xy 401.54765 -166.483219)
			(xy 401.556657 -166.394134) (xy 401.574559 -166.306403) (xy 401.601175 -166.220911) (xy 401.618196 -166.1795)
			(xy 401.62177 -166.169912) (xy 401.621765 -166.149466) (xy 401.618196 -166.139876) (xy 401.601153 -166.098472)
			(xy 401.574521 -166.012983) (xy 401.556618 -165.925248) (xy 401.547627 -165.836159) (xy 401.547076 -165.791388)
			(xy 401.54765 -165.746619) (xy 401.556657 -165.657534) (xy 401.574559 -165.569803) (xy 401.601175 -165.484311)
			(xy 401.618196 -165.4429) (xy 401.62177 -165.433312) (xy 401.621765 -165.412866) (xy 401.618196 -165.403276)
			(xy 401.601153 -165.361872) (xy 401.574521 -165.276383) (xy 401.556618 -165.188648) (xy 401.547627 -165.099559)
			(xy 401.547076 -165.054788) (xy 401.547541 -165.013678) (xy 401.55513 -164.931808) (xy 401.570241 -164.850988)
			(xy 401.592747 -164.771907) (xy 401.622454 -164.695241) (xy 401.659109 -164.621643) (xy 401.7024 -164.551742)
			(xy 401.751957 -164.486134) (xy 401.807357 -164.42538) (xy 401.868127 -164.369997) (xy 401.933748 -164.320459)
			(xy 402.003662 -164.277187) (xy 402.07727 -164.240553) (xy 402.153944 -164.210867) (xy 402.233031 -164.188384)
			(xy 402.313856 -164.173295) (xy 402.395728 -164.165729) (xy 402.436838 -164.16528) (xy 402.478442 -164.165755)
			(xy 402.56129 -164.173487) (xy 402.643054 -164.188917) (xy 402.723022 -164.21191) (xy 402.800495 -164.242266)
			(xy 402.874796 -164.27972) (xy 402.910294 -164.301424) (xy 402.919434 -164.306582) (xy 402.940149 -164.309796)
			(xy 402.960422 -164.304466) (xy 402.968968 -164.298376) (xy 403.002591 -164.27242) (xy 403.07397 -164.226364)
			(xy 403.149414 -164.187321) (xy 403.228235 -164.155647) (xy 403.309716 -164.131629) (xy 403.393116 -164.115486)
			(xy 403.477674 -164.107366) (xy 403.520148 -164.10686) (xy 403.520402 -164.10686) (xy 403.561509 -164.107311)
			(xy 403.643374 -164.114895) (xy 403.724189 -164.13) (xy 403.803267 -164.152496) (xy 403.879931 -164.182191)
			(xy 403.95353 -164.218831) (xy 404.023434 -164.262106) (xy 404.089048 -164.311644) (xy 404.149813 -164.367025)
			(xy 404.205209 -164.427775) (xy 404.254764 -164.493376) (xy 404.298057 -164.563269) (xy 404.334716 -164.636858)
			(xy 404.364431 -164.713515) (xy 404.386947 -164.792587) (xy 404.402073 -164.873398) (xy 404.409679 -164.955261)
			(xy 404.410164 -164.996368) (xy 404.409606 -165.041138) (xy 404.400594 -165.130223) (xy 404.382688 -165.217954)
			(xy 404.356068 -165.303445) (xy 404.339044 -165.344856) (xy 404.335498 -165.354452) (xy 404.335487 -165.374889)
			(xy 404.339044 -165.38448) (xy 404.356053 -165.425829) (xy 404.382663 -165.511192) (xy 404.400568 -165.598795)
			(xy 404.409589 -165.687753) (xy 404.410164 -165.73246) (xy 404.410164 -165.733476) (xy 404.40991 -165.744906)
			(xy 404.436389 -165.750851) (xy 404.488624 -165.765594) (xy 404.514304 -165.77437) (xy 404.522501 -165.776884)
			(xy 404.539635 -165.776884) (xy 404.547832 -165.77437) (xy 404.58305 -165.762429) (xy 404.655059 -165.74384)
			(xy 404.728382 -165.731398) (xy 404.802492 -165.725192) (xy 404.839678 -165.72484) (xy 404.876862 -165.725213)
			(xy 404.95097 -165.731434) (xy 405.02429 -165.743875) (xy 405.096301 -165.762448) (xy 405.131524 -165.77437)
			(xy 405.139721 -165.776884) (xy 405.156855 -165.776884) (xy 405.165052 -165.77437) (xy 405.200146 -165.76246)
			(xy 405.271906 -165.743916) (xy 405.344971 -165.731476) (xy 405.418824 -165.725229) (xy 405.455882 -165.72484)
			(xy 405.456898 -165.72484) (xy 405.498822 -165.725407) (xy 405.582291 -165.733377) (xy 405.664623 -165.749245)
			(xy 405.745075 -165.772868) (xy 405.822917 -165.804031) (xy 405.897444 -165.842452) (xy 405.967982 -165.887784)
			(xy 406.033891 -165.939615) (xy 406.094575 -165.997477) (xy 406.149484 -166.060845) (xy 406.198121 -166.129146)
			(xy 406.240045 -166.20176) (xy 406.274876 -166.278031) (xy 406.302301 -166.357268) (xy 406.322068 -166.438752)
			(xy 406.334001 -166.521747) (xy 406.337991 -166.6055) (xy 406.334001 -166.689253) (xy 406.322068 -166.772248)
			(xy 406.302301 -166.853732) (xy 406.274876 -166.932969) (xy 406.240045 -167.00924) (xy 406.198121 -167.081854)
			(xy 406.149484 -167.150155) (xy 406.094575 -167.213523) (xy 406.033891 -167.271385) (xy 405.967982 -167.323216)
			(xy 405.897444 -167.368548) (xy 405.822917 -167.406969) (xy 405.745075 -167.438132) (xy 405.664623 -167.461755)
			(xy 405.582291 -167.477623) (xy 405.498822 -167.485593) (xy 405.456898 -167.486076) (xy 405.455882 -167.486076)
			(xy 405.418825 -167.485672) (xy 405.344976 -167.479407) (xy 405.271913 -167.466964) (xy 405.200153 -167.448432)
			(xy 405.165052 -167.436546) (xy 405.156855 -167.434032) (xy 405.139721 -167.434032) (xy 405.131524 -167.436546)
			(xy 405.102638 -167.446383) (xy 405.043785 -167.462529) (xy 405.013922 -167.468804) (xy 405.004334 -167.471159)
			(xy 404.987889 -167.482054) (xy 404.976796 -167.498367) (xy 404.974298 -167.50792) (xy 404.96417 -167.552275)
			(xy 404.936046 -167.638805) (xy 404.918164 -167.68064) (xy 404.914347 -167.690579) (xy 404.914353 -167.711846)
			(xy 404.918164 -167.721788) (xy 404.936394 -167.764388) (xy 404.964909 -167.852556) (xy 404.984099 -167.943213)
			(xy 404.993757 -168.035373) (xy 404.994364 -168.081706) (xy 404.994364 -168.082214) (xy 404.99386 -168.124562)
			(xy 404.985809 -168.208876) (xy 404.96978 -168.292042) (xy 404.945919 -168.373309) (xy 404.91444 -168.451939)
			(xy 404.875629 -168.52722) (xy 404.829839 -168.598472) (xy 404.777483 -168.665048) (xy 404.719035 -168.726346)
			(xy 404.655025 -168.781811) (xy 404.586033 -168.83094) (xy 404.512683 -168.873289) (xy 404.43564 -168.908473)
			(xy 404.355601 -168.936175) (xy 404.273292 -168.956143) (xy 404.189457 -168.968196) (xy 404.104856 -168.972227)
			(xy 404.020255 -168.968196) (xy 403.93642 -168.956143) (xy 403.854111 -168.936175) (xy 403.774072 -168.908473)
			(xy 403.697029 -168.873289) (xy 403.623679 -168.83094) (xy 403.554687 -168.781811) (xy 403.490677 -168.726346)
			(xy 403.432229 -168.665048) (xy 403.379873 -168.598472) (xy 403.334083 -168.52722) (xy 403.295272 -168.451939)
			(xy 403.263793 -168.373309) (xy 403.239932 -168.292042) (xy 403.223903 -168.208876) (xy 403.215852 -168.124562)
			(xy 403.215348 -168.082214) (xy 403.215348 -168.081706) (xy 403.215963 -168.035374) (xy 403.225632 -167.943217)
			(xy 403.244825 -167.852563) (xy 403.273334 -167.764394) (xy 403.291548 -167.721788) (xy 403.295348 -167.711844)
			(xy 403.295353 -167.690582) (xy 403.291548 -167.68064) (xy 403.273311 -167.637974) (xy 403.244764 -167.549684)
			(xy 403.225569 -167.458899) (xy 403.215934 -167.36661) (xy 403.215348 -167.320214) (xy 403.215953 -167.272404)
			(xy 403.226131 -167.177329) (xy 403.235668 -167.130476) (xy 403.23764 -167.118071) (xy 403.230727 -167.093957)
			(xy 403.22246 -167.084502) (xy 403.18182 -167.042338) (xy 403.178264 -167.0431) (xy 403.169416 -167.045411)
			(xy 403.154053 -167.055303) (xy 403.148292 -167.062404) (xy 403.123137 -167.095067) (xy 403.067717 -167.15611)
			(xy 403.006886 -167.211763) (xy 402.941166 -167.261548) (xy 402.871121 -167.305037) (xy 402.797352 -167.341858)
			(xy 402.720492 -167.371694) (xy 402.641201 -167.39429) (xy 402.560159 -167.409451) (xy 402.478062 -167.417047)
			(xy 402.436838 -167.417496) (xy 402.395733 -167.416951) (xy 402.313873 -167.409371) (xy 402.233061 -167.394271)
			(xy 402.153987 -167.37178) (xy 402.077325 -167.342091) (xy 402.003729 -167.305456) (xy 401.933826 -167.262187)
			(xy 401.868213 -167.212655) (xy 401.80745 -167.157281) (xy 401.752053 -167.096538) (xy 401.702497 -167.030943)
			(xy 401.659203 -166.961056) (xy 401.622541 -166.887473) (xy 401.592824 -166.810822) (xy 401.570304 -166.731756)
			(xy 401.555174 -166.65095) (xy 401.547564 -166.569093) (xy 401.547076 -166.527988) (xy 354.289105 -166.527988)
			(xy 354.295389 -166.589961) (xy 354.295964 -166.634668) (xy 354.295964 -166.635684) (xy 354.29571 -166.647114)
			(xy 354.322189 -166.653059) (xy 354.374424 -166.667802) (xy 354.400104 -166.676578) (xy 354.408301 -166.679092)
			(xy 354.425435 -166.679092) (xy 354.433632 -166.676578) (xy 354.468848 -166.664633) (xy 354.540859 -166.646046)
			(xy 354.614181 -166.633606) (xy 354.688292 -166.6274) (xy 354.725478 -166.627048) (xy 354.762662 -166.62742)
			(xy 354.83677 -166.633641) (xy 354.91009 -166.646083) (xy 354.982101 -166.664656) (xy 355.017324 -166.676578)
			(xy 355.025521 -166.679092) (xy 355.042655 -166.679092) (xy 355.050852 -166.676578) (xy 355.085946 -166.664669)
			(xy 355.157706 -166.646124) (xy 355.230771 -166.633684) (xy 355.304624 -166.627437) (xy 355.341682 -166.627048)
			(xy 355.342698 -166.627048) (xy 355.384622 -166.627599) (xy 355.468092 -166.635569) (xy 355.550425 -166.651437)
			(xy 355.630878 -166.67506) (xy 355.70872 -166.706224) (xy 355.783248 -166.744645) (xy 355.853787 -166.789977)
			(xy 355.919696 -166.841809) (xy 355.980381 -166.899671) (xy 356.03529 -166.96304) (xy 356.083927 -167.031341)
			(xy 356.125852 -167.103957) (xy 356.160684 -167.180228) (xy 356.188108 -167.259465) (xy 356.207876 -167.340951)
			(xy 356.219809 -167.423946) (xy 356.223799 -167.5077) (xy 356.219809 -167.591454) (xy 356.207876 -167.674449)
			(xy 356.188108 -167.755935) (xy 356.160684 -167.835172) (xy 356.125852 -167.911443) (xy 356.083927 -167.984059)
			(xy 356.03529 -168.05236) (xy 355.980381 -168.115729) (xy 355.919696 -168.173591) (xy 355.853787 -168.225423)
			(xy 355.783248 -168.270755) (xy 355.70872 -168.309176) (xy 355.630878 -168.34034) (xy 355.550425 -168.363963)
			(xy 355.468092 -168.379831) (xy 355.384622 -168.387801) (xy 355.342698 -168.388284) (xy 355.341682 -168.388284)
			(xy 355.304625 -168.387885) (xy 355.230776 -168.381619) (xy 355.157713 -168.369175) (xy 355.085953 -168.350641)
			(xy 355.050852 -168.338754) (xy 355.042655 -168.33624) (xy 355.025521 -168.33624) (xy 355.017324 -168.338754)
			(xy 354.989546 -168.348208) (xy 354.932984 -168.363843) (xy 354.904294 -168.369996) (xy 354.894532 -168.372423)
			(xy 354.877923 -168.383747) (xy 354.866932 -168.400579) (xy 354.86467 -168.410382) (xy 354.855142 -168.457509)
			(xy 354.827269 -168.549532) (xy 354.809044 -168.594024) (xy 354.805459 -168.603609) (xy 354.805473 -168.624057)
			(xy 354.809044 -168.633648) (xy 354.826071 -168.675024) (xy 354.852688 -168.760451) (xy 354.870591 -168.84812)
			(xy 354.879599 -168.937143) (xy 354.880164 -168.981882) (xy 354.880164 -168.982136) (xy 354.87966 -169.024484)
			(xy 354.871609 -169.108798) (xy 354.85558 -169.191964) (xy 354.831719 -169.273231) (xy 354.80024 -169.351861)
			(xy 354.761429 -169.427142) (xy 354.715639 -169.498394) (xy 354.663283 -169.56497) (xy 354.604835 -169.626268)
			(xy 354.540825 -169.681733) (xy 354.471833 -169.730862) (xy 354.398483 -169.773211) (xy 354.32144 -169.808395)
			(xy 354.241401 -169.836097) (xy 354.159092 -169.856065) (xy 354.075257 -169.868118) (xy 353.990656 -169.872149)
			(xy 353.906055 -169.868118) (xy 353.82222 -169.856065) (xy 353.739911 -169.836097) (xy 353.659872 -169.808395)
			(xy 353.582829 -169.773211) (xy 353.509479 -169.730862) (xy 353.440487 -169.681733) (xy 353.376477 -169.626268)
			(xy 353.318029 -169.56497) (xy 353.265673 -169.498394) (xy 353.219883 -169.427142) (xy 353.181072 -169.351861)
			(xy 353.149593 -169.273231) (xy 353.125732 -169.191964) (xy 353.109703 -169.108798) (xy 353.101652 -169.024484)
			(xy 353.101148 -168.982136) (xy 353.101148 -168.981882) (xy 353.101731 -168.937144) (xy 353.110743 -168.848123)
			(xy 353.128644 -168.760456) (xy 353.155252 -168.675028) (xy 353.172268 -168.633648) (xy 353.175811 -168.624051)
			(xy 353.175824 -168.603615) (xy 353.172268 -168.594024) (xy 353.155227 -168.55262) (xy 353.128597 -168.46713)
			(xy 353.110694 -168.379396) (xy 353.1017 -168.290307) (xy 353.101148 -168.245536) (xy 353.10149 -168.209754)
			(xy 353.107197 -168.138419) (xy 353.118619 -168.067773) (xy 353.126802 -168.032938) (xy 353.128529 -168.024629)
			(xy 353.126997 -168.007741) (xy 353.119979 -167.992303) (xy 353.114356 -167.985948) (xy 353.07397 -167.943276)
			(xy 353.064064 -167.945308) (xy 353.055164 -167.947623) (xy 353.039671 -167.957504) (xy 353.033838 -167.964612)
			(xy 353.008691 -167.997264) (xy 352.953283 -168.058281) (xy 352.892469 -168.113912) (xy 352.826771 -168.163681)
			(xy 352.756752 -168.207161) (xy 352.683013 -168.243979) (xy 352.606184 -168.273821) (xy 352.526925 -168.29643)
			(xy 352.445915 -168.311612) (xy 352.363848 -168.319237) (xy 352.322638 -168.319704) (xy 352.281533 -168.319151)
			(xy 352.199674 -168.311571) (xy 352.118862 -168.296471) (xy 352.039789 -168.273981) (xy 351.963127 -168.244292)
			(xy 351.889531 -168.207657) (xy 351.819629 -168.164389) (xy 351.754016 -168.114857) (xy 351.693252 -168.059484)
			(xy 351.637856 -167.998741) (xy 351.5883 -167.933147) (xy 351.545006 -167.863261) (xy 351.508343 -167.789678)
			(xy 351.478626 -167.713028) (xy 351.456106 -167.633963) (xy 351.440975 -167.553157) (xy 351.433364 -167.471301)
			(xy 351.432876 -167.430196) (xy 65.688295 -167.430196) (xy 65.649338 -167.484902) (xy 65.594424 -167.548276)
			(xy 65.533735 -167.606142) (xy 65.46782 -167.657978) (xy 65.397276 -167.703313) (xy 65.322742 -167.741737)
			(xy 65.244893 -167.772902) (xy 65.164434 -167.796526) (xy 65.082094 -167.812395) (xy 64.998618 -167.820365)
			(xy 64.95669 -167.820848) (xy 64.955674 -167.820848) (xy 64.918617 -167.820448) (xy 64.844768 -167.814181)
			(xy 64.771705 -167.801738) (xy 64.699945 -167.783204) (xy 64.664844 -167.771318) (xy 64.656647 -167.768804)
			(xy 64.639513 -167.768804) (xy 64.631316 -167.771318) (xy 64.597889 -167.782662) (xy 64.529607 -167.80059)
			(xy 64.494918 -167.807132) (xy 64.484907 -167.809437) (xy 64.467748 -167.820693) (xy 64.456372 -167.837772)
			(xy 64.454024 -167.847772) (xy 64.44452 -167.895628) (xy 64.416383 -167.989057) (xy 64.39789 -168.034208)
			(xy 64.394248 -168.043772) (xy 64.394124 -168.064219) (xy 64.397636 -168.073832) (xy 64.414658 -168.11521)
			(xy 64.441276 -168.200636) (xy 64.459181 -168.288304) (xy 64.46819 -168.377327) (xy 64.468756 -168.422066)
			(xy 64.468756 -168.42232) (xy 64.468252 -168.464668) (xy 64.460201 -168.548982) (xy 64.444172 -168.632148)
			(xy 64.420311 -168.713415) (xy 64.388832 -168.792045) (xy 64.350021 -168.867326) (xy 64.304231 -168.938578)
			(xy 64.251875 -169.005154) (xy 64.193427 -169.066452) (xy 64.129417 -169.121917) (xy 64.060425 -169.171046)
			(xy 63.987075 -169.213395) (xy 63.910032 -169.248579) (xy 63.829993 -169.276281) (xy 63.747684 -169.296249)
			(xy 63.663849 -169.308302) (xy 63.579248 -169.312333) (xy 63.494647 -169.308302) (xy 63.410812 -169.296249)
			(xy 63.328503 -169.276281) (xy 63.248464 -169.248579) (xy 63.171421 -169.213395) (xy 63.098071 -169.171046)
			(xy 63.029079 -169.121917) (xy 62.965069 -169.066452) (xy 62.906621 -169.005154) (xy 62.854265 -168.938578)
			(xy 62.808475 -168.867326) (xy 62.769664 -168.792045) (xy 62.738185 -168.713415) (xy 62.714324 -168.632148)
			(xy 62.698295 -168.548982) (xy 62.690244 -168.464668) (xy 62.68974 -168.42232) (xy 62.68974 -168.422066)
			(xy 62.690311 -168.377328) (xy 62.699325 -168.288306) (xy 62.71723 -168.200639) (xy 62.743842 -168.115211)
			(xy 62.76086 -168.073832) (xy 62.764412 -168.064238) (xy 62.76442 -168.043799) (xy 62.76086 -168.034208)
			(xy 62.743813 -167.992806) (xy 62.717185 -167.907315) (xy 62.699284 -167.81958) (xy 62.690292 -167.730491)
			(xy 62.68974 -167.68572) (xy 62.689828 -167.668048) (xy 62.691224 -167.632732) (xy 62.692534 -167.615108)
			(xy 62.692907 -167.605036) (xy 62.68662 -167.585904) (xy 62.673425 -167.57069) (xy 62.664594 -167.565832)
			(xy 62.566296 -167.516556) (xy 62.535816 -167.520366) (xy 62.524132 -167.53078) (xy 62.493735 -167.556935)
			(xy 62.428993 -167.604263) (xy 62.360251 -167.645567) (xy 62.288069 -167.680512) (xy 62.213032 -167.708812)
			(xy 62.135751 -167.730238) (xy 62.056854 -167.744617) (xy 61.976982 -167.75183) (xy 61.936884 -167.752268)
			(xy 61.93663 -167.752268) (xy 61.895524 -167.751759) (xy 61.813662 -167.744177) (xy 61.732849 -167.729076)
			(xy 61.653773 -167.706584) (xy 61.57711 -167.676893) (xy 61.503513 -167.640256) (xy 61.433609 -167.596985)
			(xy 61.367995 -167.547451) (xy 61.307231 -167.492074) (xy 61.251835 -167.431328) (xy 61.202279 -167.36573)
			(xy 61.158986 -167.295841) (xy 61.122325 -167.222256) (xy 61.092608 -167.145602) (xy 61.07009 -167.066534)
			(xy 61.054963 -166.985725) (xy 61.047355 -166.903866) (xy 61.046868 -166.86276) (xy 2.509012 -166.86276)
			(xy 2.509012 -170.29303) (xy 8.7249 -170.29303) (xy 8.7249 -169.42943) (xy 8.725386 -169.402179)
			(xy 8.733142 -169.348231) (xy 8.748497 -169.295936) (xy 8.771139 -169.246359) (xy 8.800605 -169.200509)
			(xy 8.836296 -169.159318) (xy 8.877487 -169.123627) (xy 8.923337 -169.094161) (xy 8.972914 -169.071519)
			(xy 9.025209 -169.056164) (xy 9.079157 -169.048408) (xy 9.133659 -169.048408) (xy 9.187607 -169.056164)
			(xy 9.239902 -169.071519) (xy 9.289479 -169.094161) (xy 9.335329 -169.123627) (xy 9.37652 -169.159318)
			(xy 9.412211 -169.200509) (xy 9.441677 -169.246359) (xy 9.464319 -169.295936) (xy 9.479674 -169.348231)
			(xy 9.48743 -169.402179) (xy 9.487916 -169.42943) (xy 9.487916 -169.857674) (xy 111.084868 -169.857674)
			(xy 111.085438 -169.812905) (xy 111.094447 -169.72382) (xy 111.112349 -169.636089) (xy 111.138966 -169.550597)
			(xy 111.155988 -169.509186) (xy 111.15957 -169.4996) (xy 111.15956 -169.479153) (xy 111.155988 -169.469562)
			(xy 111.13894 -169.42816) (xy 111.112309 -169.34267) (xy 111.094408 -169.254935) (xy 111.085418 -169.165845)
			(xy 111.084868 -169.121074) (xy 111.085438 -169.076305) (xy 111.094447 -168.98722) (xy 111.112349 -168.899489)
			(xy 111.138966 -168.813997) (xy 111.155988 -168.772586) (xy 111.15957 -168.763) (xy 111.15956 -168.742553)
			(xy 111.155988 -168.732962) (xy 111.13894 -168.69156) (xy 111.112309 -168.60607) (xy 111.094408 -168.518335)
			(xy 111.085418 -168.429245) (xy 111.084868 -168.384474) (xy 111.085274 -168.343358) (xy 111.092864 -168.261476)
			(xy 111.107976 -168.180645) (xy 111.130482 -168.101552) (xy 111.160191 -168.024873) (xy 111.196847 -167.951263)
			(xy 111.240139 -167.881349) (xy 111.289697 -167.815728) (xy 111.345099 -167.754959) (xy 111.405871 -167.699561)
			(xy 111.471495 -167.650007) (xy 111.541412 -167.60672) (xy 111.615025 -167.570068) (xy 111.691705 -167.540365)
			(xy 111.770799 -167.517863) (xy 111.851632 -167.502756) (xy 111.933514 -167.495171) (xy 111.97463 -167.494712)
			(xy 112.016241 -167.495173) (xy 112.099098 -167.502953) (xy 112.180867 -167.518431) (xy 112.260835 -167.541474)
			(xy 112.338303 -167.571879) (xy 112.412595 -167.609382) (xy 112.448086 -167.63111) (xy 112.457229 -167.636263)
			(xy 112.477942 -167.63948) (xy 112.498214 -167.634152) (xy 112.50676 -167.628062) (xy 112.540389 -167.602071)
			(xy 112.611783 -167.555946) (xy 112.687254 -167.516845) (xy 112.766112 -167.485124) (xy 112.847637 -167.461075)
			(xy 112.931085 -167.444915) (xy 113.015695 -167.436793) (xy 113.058194 -167.436292) (xy 113.099307 -167.436819)
			(xy 113.181182 -167.444405) (xy 113.262007 -167.459513) (xy 113.341094 -167.482013) (xy 113.417768 -167.511715)
			(xy 113.491374 -167.548365) (xy 113.561284 -167.59165) (xy 113.626903 -167.6412) (xy 113.68767 -167.696593)
			(xy 113.743067 -167.757357) (xy 113.792621 -167.822973) (xy 113.83591 -167.892881) (xy 113.872564 -167.966485)
			(xy 113.90227 -168.043156) (xy 113.924776 -168.122242) (xy 113.939888 -168.203067) (xy 113.947479 -168.284941)
			(xy 113.947956 -168.326054) (xy 113.947393 -168.370824) (xy 113.938383 -168.459909) (xy 113.920477 -168.54764)
			(xy 113.893859 -168.633131) (xy 113.876836 -168.674542) (xy 113.873299 -168.684141) (xy 113.873282 -168.704576)
			(xy 113.876836 -168.714166) (xy 113.89384 -168.755517) (xy 113.920451 -168.840879) (xy 113.938358 -168.928482)
			(xy 113.94738 -169.017439) (xy 113.947956 -169.062146) (xy 113.947956 -169.063162) (xy 113.947702 -169.074592)
			(xy 113.974181 -169.080538) (xy 114.026416 -169.095281) (xy 114.052096 -169.104056) (xy 114.060293 -169.10657)
			(xy 114.077427 -169.10657) (xy 114.085624 -169.104056) (xy 114.12084 -169.092095) (xy 114.192844 -169.073441)
			(xy 114.266165 -169.060932) (xy 114.34028 -169.054659) (xy 114.37747 -169.054272) (xy 114.414659 -169.054671)
			(xy 114.488772 -169.060958) (xy 114.562092 -169.073465) (xy 114.634098 -169.092103) (xy 114.669316 -169.104056)
			(xy 114.677513 -169.10657) (xy 114.694647 -169.10657) (xy 114.702844 -169.104056) (xy 114.738059 -169.092089)
			(xy 114.810062 -169.073437) (xy 114.883384 -169.06093) (xy 114.9575 -169.054658) (xy 114.99469 -169.054272)
			(xy 115.03663 -169.054667) (xy 115.120132 -169.062639) (xy 115.202497 -169.078513) (xy 115.28298 -169.102144)
			(xy 115.360853 -169.133319) (xy 115.43541 -169.171755) (xy 115.505975 -169.217104) (xy 115.57191 -169.268955)
			(xy 115.632618 -169.326839) (xy 115.687549 -169.390232) (xy 115.736205 -169.458559) (xy 115.778146 -169.531202)
			(xy 115.812991 -169.607503) (xy 115.840426 -169.68677) (xy 115.860202 -169.768287) (xy 115.87214 -169.851314)
			(xy 115.876131 -169.9351) (xy 115.87214 -170.018886) (xy 115.860202 -170.101913) (xy 115.840426 -170.18343)
			(xy 115.812991 -170.262697) (xy 115.778146 -170.338998) (xy 115.736205 -170.411641) (xy 115.687549 -170.479968)
			(xy 115.632618 -170.543361) (xy 115.57191 -170.601245) (xy 115.505975 -170.653096) (xy 115.498571 -170.657854)
			(xy 161.052951 -170.657854) (xy 161.052951 -170.603346) (xy 161.060709 -170.549393) (xy 161.076066 -170.497093)
			(xy 161.09871 -170.447511) (xy 161.12818 -170.401657) (xy 161.163876 -170.360463) (xy 161.205071 -170.324769)
			(xy 161.250927 -170.295301) (xy 161.30051 -170.27266) (xy 161.352811 -170.257305) (xy 161.406764 -170.24955)
			(xy 161.434018 -170.249088) (xy 162.297618 -170.249088) (xy 162.324868 -170.249583) (xy 162.378813 -170.257342)
			(xy 162.431105 -170.272698) (xy 162.48068 -170.29534) (xy 162.526528 -170.324806) (xy 162.567715 -170.360498)
			(xy 162.603404 -170.401687) (xy 162.632869 -170.447536) (xy 162.655508 -170.497111) (xy 162.670862 -170.549404)
			(xy 162.678618 -170.60335) (xy 162.678618 -170.65785) (xy 162.670862 -170.711796) (xy 162.655508 -170.764089)
			(xy 162.632869 -170.813664) (xy 162.603404 -170.859513) (xy 162.567715 -170.900702) (xy 162.526528 -170.936394)
			(xy 162.48068 -170.96586) (xy 162.431105 -170.988502) (xy 162.378813 -171.003858) (xy 162.324868 -171.011617)
			(xy 162.297618 -171.012104) (xy 161.434018 -171.012104) (xy 161.406764 -171.01165) (xy 161.352811 -171.003895)
			(xy 161.30051 -170.98854) (xy 161.250927 -170.965899) (xy 161.205071 -170.936431) (xy 161.163876 -170.900737)
			(xy 161.12818 -170.859543) (xy 161.09871 -170.813689) (xy 161.076066 -170.764107) (xy 161.060709 -170.711807)
			(xy 161.052951 -170.657854) (xy 115.498571 -170.657854) (xy 115.43541 -170.698445) (xy 115.360853 -170.736881)
			(xy 115.28298 -170.768056) (xy 115.202497 -170.791687) (xy 115.120132 -170.807561) (xy 115.03663 -170.815533)
			(xy 114.99469 -170.816016) (xy 114.9575 -170.815629) (xy 114.883387 -170.809339) (xy 114.810068 -170.796828)
			(xy 114.738062 -170.778187) (xy 114.702844 -170.766232) (xy 114.694647 -170.763718) (xy 114.677513 -170.763718)
			(xy 114.669316 -170.766232) (xy 114.625188 -170.781068) (xy 114.534574 -170.80245) (xy 114.488468 -170.808904)
			(xy 114.478735 -170.810567) (xy 114.461516 -170.820188) (xy 114.449244 -170.83563) (xy 114.44605 -170.844972)
			(xy 114.43848 -170.870441) (xy 114.420685 -170.920512) (xy 114.41049 -170.945048) (xy 114.406882 -170.954622)
			(xy 114.406736 -170.97506) (xy 114.410236 -170.984672) (xy 114.427271 -171.026045) (xy 114.453886 -171.111473)
			(xy 114.471787 -171.199143) (xy 114.480792 -171.288167) (xy 114.481356 -171.332906) (xy 114.481356 -171.33316)
			(xy 114.480852 -171.375508) (xy 114.472801 -171.459822) (xy 114.456772 -171.542988) (xy 114.432911 -171.624255)
			(xy 114.401432 -171.702885) (xy 114.362621 -171.778166) (xy 114.316831 -171.849418) (xy 114.264475 -171.915994)
			(xy 114.206027 -171.977292) (xy 114.142017 -172.032757) (xy 114.073025 -172.081886) (xy 113.999675 -172.124235)
			(xy 113.922632 -172.159419) (xy 113.842593 -172.187121) (xy 113.760284 -172.207089) (xy 113.676449 -172.219142)
			(xy 113.591848 -172.223173) (xy 113.507247 -172.219142) (xy 113.423412 -172.207089) (xy 113.341103 -172.187121)
			(xy 113.261064 -172.159419) (xy 113.184021 -172.124235) (xy 113.110671 -172.081886) (xy 113.041679 -172.032757)
			(xy 112.977669 -171.977292) (xy 112.919221 -171.915994) (xy 112.866865 -171.849418) (xy 112.821075 -171.778166)
			(xy 112.782264 -171.702885) (xy 112.750785 -171.624255) (xy 112.726924 -171.542988) (xy 112.710895 -171.459822)
			(xy 112.702844 -171.375508) (xy 112.70234 -171.33316) (xy 112.70234 -171.332906) (xy 112.702891 -171.288167)
			(xy 112.711911 -171.199145) (xy 112.729821 -171.111478) (xy 112.75644 -171.026051) (xy 112.77346 -170.984672)
			(xy 112.777047 -170.975088) (xy 112.777032 -170.954639) (xy 112.77346 -170.945048) (xy 112.757652 -170.906707)
			(xy 112.732373 -170.827716) (xy 112.714548 -170.746717) (xy 112.70433 -170.664411) (xy 112.702594 -170.622976)
			(xy 112.702594 -170.622722) (xy 112.701955 -170.613271) (xy 112.694549 -170.595846) (xy 112.681333 -170.582289)
			(xy 112.672876 -170.578018) (xy 112.589818 -170.540172) (xy 112.581121 -170.536666) (xy 112.562416 -170.535564)
			(xy 112.544562 -170.541248) (xy 112.536986 -170.546776) (xy 112.536986 -170.54703) (xy 112.536478 -170.54703)
			(xy 112.502475 -170.574102) (xy 112.430107 -170.622247) (xy 112.353386 -170.663099) (xy 112.273043 -170.696267)
			(xy 112.189846 -170.721435) (xy 112.104591 -170.738363) (xy 112.01809 -170.746889) (xy 111.97463 -170.747436)
			(xy 111.933515 -170.746973) (xy 111.851635 -170.739388) (xy 111.770804 -170.72428) (xy 111.691713 -170.701779)
			(xy 111.615035 -170.672075) (xy 111.541425 -170.635423) (xy 111.471511 -170.592135) (xy 111.405889 -170.542581)
			(xy 111.34512 -170.487183) (xy 111.289722 -170.426414) (xy 111.240167 -170.360793) (xy 111.196879 -170.290879)
			(xy 111.160226 -170.217269) (xy 111.130522 -170.140591) (xy 111.10802 -170.061499) (xy 111.092912 -169.980669)
			(xy 111.085327 -169.898789) (xy 111.084868 -169.857674) (xy 9.487916 -169.857674) (xy 9.487916 -170.29303)
			(xy 9.48743 -170.320281) (xy 9.479674 -170.374229) (xy 9.464319 -170.426524) (xy 9.441677 -170.476101)
			(xy 9.412211 -170.521951) (xy 9.37652 -170.563142) (xy 9.335329 -170.598833) (xy 9.289479 -170.628299)
			(xy 9.239902 -170.650941) (xy 9.187607 -170.666296) (xy 9.133659 -170.674052) (xy 9.079157 -170.674052)
			(xy 9.025209 -170.666296) (xy 8.972914 -170.650941) (xy 8.923337 -170.628299) (xy 8.877487 -170.598833)
			(xy 8.836296 -170.563142) (xy 8.800605 -170.521951) (xy 8.771139 -170.476101) (xy 8.748497 -170.426524)
			(xy 8.733142 -170.374229) (xy 8.725386 -170.320281) (xy 8.7249 -170.29303) (xy 2.509012 -170.29303)
			(xy 2.509012 -173.07814) (xy 8.7249 -173.07814) (xy 8.7249 -172.21454) (xy 8.725386 -172.187289)
			(xy 8.733142 -172.133341) (xy 8.748497 -172.081046) (xy 8.771139 -172.031469) (xy 8.800605 -171.985619)
			(xy 8.836296 -171.944428) (xy 8.877487 -171.908737) (xy 8.923337 -171.879271) (xy 8.972914 -171.856629)
			(xy 9.025209 -171.841274) (xy 9.079157 -171.833518) (xy 9.133659 -171.833518) (xy 9.187607 -171.841274)
			(xy 9.239902 -171.856629) (xy 9.289479 -171.879271) (xy 9.335329 -171.908737) (xy 9.37652 -171.944428)
			(xy 9.412211 -171.985619) (xy 9.441677 -172.031469) (xy 9.464319 -172.081046) (xy 9.479674 -172.133341)
			(xy 9.48743 -172.187289) (xy 9.487916 -172.21454) (xy 9.487916 -173.07814) (xy 9.48743 -173.105391)
			(xy 9.479674 -173.159339) (xy 9.464319 -173.211634) (xy 9.441677 -173.261211) (xy 9.412211 -173.307061)
			(xy 9.37652 -173.348252) (xy 9.335329 -173.383943) (xy 9.289479 -173.413409) (xy 9.239902 -173.436051)
			(xy 9.187607 -173.451406) (xy 9.133659 -173.459162) (xy 9.079157 -173.459162) (xy 9.025209 -173.451406)
			(xy 8.972914 -173.436051) (xy 8.923337 -173.413409) (xy 8.877487 -173.383943) (xy 8.836296 -173.348252)
			(xy 8.800605 -173.307061) (xy 8.771139 -173.261211) (xy 8.748497 -173.211634) (xy 8.733142 -173.159339)
			(xy 8.725386 -173.105391) (xy 8.7249 -173.07814) (xy 2.509012 -173.07814) (xy 2.509012 -175.848264)
			(xy 8.7249 -175.848264) (xy 8.7249 -174.984664) (xy 8.725386 -174.957413) (xy 8.733142 -174.903465)
			(xy 8.748497 -174.85117) (xy 8.771139 -174.801593) (xy 8.800605 -174.755743) (xy 8.836296 -174.714552)
			(xy 8.877487 -174.678861) (xy 8.923337 -174.649395) (xy 8.972914 -174.626753) (xy 9.025209 -174.611398)
			(xy 9.079157 -174.603642) (xy 9.133659 -174.603642) (xy 9.187607 -174.611398) (xy 9.239902 -174.626753)
			(xy 9.289479 -174.649395) (xy 9.335329 -174.678861) (xy 9.37652 -174.714552) (xy 9.412211 -174.755743)
			(xy 9.441677 -174.801593) (xy 9.464319 -174.85117) (xy 9.479674 -174.903465) (xy 9.48743 -174.957413)
			(xy 9.487916 -174.984664) (xy 9.487916 -175.559974) (xy 69.360288 -175.559974) (xy 69.360857 -175.515205)
			(xy 69.369865 -175.42612) (xy 69.387768 -175.338388) (xy 69.414386 -175.252897) (xy 69.431408 -175.211486)
			(xy 69.434989 -175.2019) (xy 69.43498 -175.181453) (xy 69.431408 -175.171862) (xy 69.414355 -175.130462)
			(xy 69.387726 -175.044971) (xy 69.369827 -174.957236) (xy 69.360838 -174.868145) (xy 69.360288 -174.823374)
			(xy 69.360857 -174.778605) (xy 69.369865 -174.68952) (xy 69.387768 -174.601788) (xy 69.414386 -174.516297)
			(xy 69.431408 -174.474886) (xy 69.434989 -174.4653) (xy 69.43498 -174.444853) (xy 69.431408 -174.435262)
			(xy 69.414355 -174.393862) (xy 69.387726 -174.308371) (xy 69.369827 -174.220636) (xy 69.360838 -174.131545)
			(xy 69.360288 -174.086774) (xy 69.360674 -174.045657) (xy 69.368264 -173.963775) (xy 69.383377 -173.882942)
			(xy 69.405884 -173.803848) (xy 69.435593 -173.727169) (xy 69.47225 -173.653557) (xy 69.515543 -173.583643)
			(xy 69.565103 -173.518021) (xy 69.620506 -173.457252) (xy 69.681279 -173.401854) (xy 69.746905 -173.3523)
			(xy 69.816824 -173.309013) (xy 69.890438 -173.272362) (xy 69.96712 -173.24266) (xy 70.046216 -173.220159)
			(xy 70.12705 -173.205053) (xy 70.208933 -173.19747) (xy 70.25005 -173.197012) (xy 70.29166 -173.197513)
			(xy 70.374516 -173.205285) (xy 70.456284 -173.220756) (xy 70.536252 -173.243791) (xy 70.613721 -173.274189)
			(xy 70.688014 -173.311686) (xy 70.723506 -173.33341) (xy 70.73264 -173.338581) (xy 70.753359 -173.341792)
			(xy 70.773635 -173.336456) (xy 70.78218 -173.330362) (xy 70.815836 -173.304408) (xy 70.887226 -173.258279)
			(xy 70.962691 -173.219173) (xy 71.041544 -173.187448) (xy 71.123065 -173.163392) (xy 71.20651 -173.147226)
			(xy 71.291116 -173.139097) (xy 71.333614 -173.138592) (xy 71.374727 -173.139099) (xy 71.456602 -173.146687)
			(xy 71.537428 -173.161797) (xy 71.616516 -173.1843) (xy 71.693189 -173.214003) (xy 71.703445 -173.21911)
			(xy 393.739116 -173.21911) (xy 393.739743 -173.172708) (xy 393.749432 -173.08041) (xy 393.768686 -172.989625)
			(xy 393.797294 -172.90134) (xy 393.81557 -172.858684) (xy 393.819371 -172.84874) (xy 393.819374 -172.827478)
			(xy 393.81557 -172.817536) (xy 393.797307 -172.774875) (xy 393.768715 -172.686587) (xy 393.749458 -172.595804)
			(xy 393.739745 -172.503511) (xy 393.739116 -172.45711) (xy 393.739622 -172.415997) (xy 393.747208 -172.33412)
			(xy 393.762316 -172.253293) (xy 393.784818 -172.174205) (xy 393.81452 -172.097531) (xy 393.851171 -172.023924)
			(xy 393.894457 -171.954012) (xy 393.944008 -171.888393) (xy 393.999403 -171.827626) (xy 394.060168 -171.772229)
			(xy 394.125786 -171.722675) (xy 394.195696 -171.679387) (xy 394.269301 -171.642733) (xy 394.345975 -171.613028)
			(xy 394.425062 -171.590524) (xy 394.505889 -171.575413) (xy 394.587765 -171.567824) (xy 394.628878 -171.567348)
			(xy 394.670013 -171.567796) (xy 394.75193 -171.575416) (xy 394.832794 -171.590566) (xy 394.911913 -171.613115)
			(xy 394.988614 -171.642872) (xy 395.06224 -171.679583) (xy 395.132163 -171.722933) (xy 395.197785 -171.772553)
			(xy 395.258547 -171.828019) (xy 395.313929 -171.888856) (xy 395.339062 -171.921424) (xy 395.345281 -171.928954)
			(xy 395.36201 -171.939002) (xy 395.371574 -171.940982) (xy 395.41286 -171.948033) (xy 395.493962 -171.968978)
			(xy 395.572736 -171.997455) (xy 395.648484 -172.033212) (xy 395.720535 -172.075931) (xy 395.78825 -172.125234)
			(xy 395.851031 -172.180685) (xy 395.908321 -172.241793) (xy 395.959613 -172.308015) (xy 396.004452 -172.378766)
			(xy 396.042441 -172.453419) (xy 396.073244 -172.531313) (xy 396.096588 -172.611757) (xy 396.112266 -172.69404)
			(xy 396.120139 -172.777432) (xy 396.12062 -172.819314) (xy 396.120152 -172.860082) (xy 396.112652 -172.941273)
			(xy 396.097752 -173.021436) (xy 396.075577 -173.099899) (xy 396.046313 -173.176003) (xy 396.028672 -173.21276)
			(xy 396.024359 -173.222451) (xy 396.023438 -173.243625) (xy 396.026894 -173.253654) (xy 396.041217 -173.292003)
			(xy 396.063564 -173.370761) (xy 396.07857 -173.451241) (xy 396.086111 -173.53276) (xy 396.086584 -173.573694)
			(xy 396.086007 -173.618463) (xy 396.077001 -173.707548) (xy 396.0591 -173.795279) (xy 396.032485 -173.880771)
			(xy 396.015464 -173.922182) (xy 396.011903 -173.931774) (xy 396.0119 -173.952215) (xy 396.015464 -173.961806)
			(xy 396.032477 -174.003153) (xy 396.059087 -174.088517) (xy 396.076991 -174.17612) (xy 396.08601 -174.265079)
			(xy 396.086584 -174.309786) (xy 396.086584 -174.310802) (xy 396.08633 -174.322232) (xy 396.112809 -174.328178)
			(xy 396.165044 -174.342921) (xy 396.190724 -174.351696) (xy 396.198921 -174.35421) (xy 396.216055 -174.35421)
			(xy 396.224252 -174.351696) (xy 396.259466 -174.339729) (xy 396.33147 -174.321076) (xy 396.404792 -174.308569)
			(xy 396.478908 -174.302297) (xy 396.516098 -174.301912) (xy 396.553288 -174.302301) (xy 396.627401 -174.30859)
			(xy 396.70072 -174.3211) (xy 396.772726 -174.339741) (xy 396.807944 -174.351696) (xy 396.816141 -174.35421)
			(xy 396.833275 -174.35421) (xy 396.841472 -174.351696) (xy 396.876685 -174.339723) (xy 396.948689 -174.321072)
			(xy 397.022011 -174.308567) (xy 397.096127 -174.302297) (xy 397.133318 -174.301912) (xy 397.175254 -174.302444)
			(xy 397.258746 -174.310418) (xy 397.341102 -174.326292) (xy 397.421577 -174.349923) (xy 397.49944 -174.381096)
			(xy 397.573988 -174.41953) (xy 397.644545 -174.464875) (xy 397.710473 -174.516722) (xy 397.771173 -174.574601)
			(xy 397.826097 -174.637988) (xy 397.874747 -174.706309) (xy 397.916683 -174.778944) (xy 397.951524 -174.855237)
			(xy 397.978955 -174.934497) (xy 397.998729 -175.016005) (xy 398.010665 -175.099023) (xy 398.014656 -175.1828)
			(xy 398.010665 -175.266577) (xy 397.998729 -175.349595) (xy 397.978955 -175.431103) (xy 397.951524 -175.510363)
			(xy 397.916683 -175.586656) (xy 397.874747 -175.659291) (xy 397.826097 -175.727612) (xy 397.771173 -175.790999)
			(xy 397.710473 -175.848878) (xy 397.644545 -175.900725) (xy 397.573988 -175.94607) (xy 397.49944 -175.984504)
			(xy 397.421577 -176.015677) (xy 397.341102 -176.039308) (xy 397.258746 -176.055182) (xy 397.175254 -176.063156)
			(xy 397.133318 -176.063656) (xy 397.096129 -176.063259) (xy 397.022016 -176.056971) (xy 396.948696 -176.044464)
			(xy 396.87669 -176.025825) (xy 396.841472 -176.013872) (xy 396.833275 -176.011358) (xy 396.816141 -176.011358)
			(xy 396.807944 -176.013872) (xy 396.778999 -176.023726) (xy 396.720017 -176.039869) (xy 396.690088 -176.04613)
			(xy 396.680511 -176.048515) (xy 396.664071 -176.059402) (xy 396.652972 -176.0757) (xy 396.650464 -176.085246)
			(xy 396.640294 -176.12901) (xy 396.612299 -176.21439) (xy 396.594584 -176.25568) (xy 396.590807 -176.265631)
			(xy 396.590789 -176.286886) (xy 396.594584 -176.296828) (xy 396.612789 -176.339438) (xy 396.641312 -176.427603)
			(xy 396.660509 -176.518256) (xy 396.670174 -176.610414) (xy 396.670784 -176.656746) (xy 396.670784 -176.657254)
			(xy 396.67028 -176.699602) (xy 396.662229 -176.783916) (xy 396.6462 -176.867082) (xy 396.622339 -176.948349)
			(xy 396.59086 -177.026979) (xy 396.552049 -177.10226) (xy 396.506259 -177.173512) (xy 396.453903 -177.240088)
			(xy 396.395455 -177.301386) (xy 396.331445 -177.356851) (xy 396.262453 -177.40598) (xy 396.189103 -177.448329)
			(xy 396.11206 -177.483513) (xy 396.032021 -177.511215) (xy 395.949712 -177.531183) (xy 395.865877 -177.543236)
			(xy 395.781276 -177.547267) (xy 395.696675 -177.543236) (xy 395.61284 -177.531183) (xy 395.530531 -177.511215)
			(xy 395.450492 -177.483513) (xy 395.373449 -177.448329) (xy 395.300099 -177.40598) (xy 395.231107 -177.356851)
			(xy 395.167097 -177.301386) (xy 395.108649 -177.240088) (xy 395.056293 -177.173512) (xy 395.010503 -177.10226)
			(xy 394.971692 -177.026979) (xy 394.940213 -176.948349) (xy 394.916352 -176.867082) (xy 394.900323 -176.783916)
			(xy 394.892272 -176.699602) (xy 394.891768 -176.657254) (xy 394.891768 -176.656746) (xy 394.892395 -176.610415)
			(xy 394.902061 -176.518257) (xy 394.92125 -176.427603) (xy 394.949756 -176.339434) (xy 394.967968 -176.296828)
			(xy 394.971802 -176.286894) (xy 394.971784 -176.265622) (xy 394.967968 -176.25568) (xy 394.949707 -176.213025)
			(xy 394.921167 -176.12473) (xy 394.901979 -176.033943) (xy 394.89235 -175.941651) (xy 394.891768 -175.895254)
			(xy 394.89209 -175.858508) (xy 394.898067 -175.785262) (xy 394.903706 -175.74895) (xy 394.905149 -175.737024)
			(xy 394.898112 -175.714088) (xy 394.890244 -175.705008) (xy 394.824966 -175.637698) (xy 394.80236 -175.629824)
			(xy 394.790168 -175.631602) (xy 394.748357 -175.636737) (xy 394.664175 -175.639973) (xy 394.580064 -175.635239)
			(xy 394.496776 -175.622575) (xy 394.415059 -175.602096) (xy 394.335643 -175.573985) (xy 394.259239 -175.538493)
			(xy 394.186532 -175.495939) (xy 394.118173 -175.446704) (xy 394.054773 -175.391227) (xy 393.996901 -175.330007)
			(xy 393.945075 -175.26359) (xy 393.899757 -175.192573) (xy 393.861356 -175.11759) (xy 393.830213 -175.039313)
			(xy 393.806608 -174.958443) (xy 393.790753 -174.875704) (xy 393.782789 -174.791836) (xy 393.782296 -174.749714)
			(xy 393.782793 -174.706976) (xy 393.790968 -174.621894) (xy 393.807264 -174.537986) (xy 393.831529 -174.456028)
			(xy 393.847066 -174.416212) (xy 393.850705 -174.406179) (xy 393.85003 -174.384863) (xy 393.845796 -174.375064)
			(xy 393.828734 -174.338786) (xy 393.800425 -174.263775) (xy 393.778984 -174.18652) (xy 393.764586 -174.107649)
			(xy 393.757348 -174.027801) (xy 393.756896 -173.987714) (xy 393.757452 -173.943459) (xy 393.766275 -173.855391)
			(xy 393.783795 -173.768633) (xy 393.809839 -173.684042) (xy 393.826492 -173.643036) (xy 393.830085 -173.632871)
			(xy 393.829579 -173.611348) (xy 393.825476 -173.60138) (xy 393.808875 -173.565511) (xy 393.781358 -173.491412)
			(xy 393.760529 -173.415162) (xy 393.746554 -173.337364) (xy 393.739543 -173.258632) (xy 393.739116 -173.21911)
			(xy 71.703445 -173.21911) (xy 71.766795 -173.250654) (xy 71.836706 -173.29394) (xy 71.902324 -173.343492)
			(xy 71.963091 -173.398886) (xy 72.018488 -173.459651) (xy 72.068042 -173.525268) (xy 72.11133 -173.595177)
			(xy 72.147984 -173.668781) (xy 72.17769 -173.745454) (xy 72.200196 -173.82454) (xy 72.215308 -173.905366)
			(xy 72.222899 -173.987241) (xy 72.223376 -174.028354) (xy 72.22282 -174.073124) (xy 72.213808 -174.162209)
			(xy 72.195901 -174.24994) (xy 72.16928 -174.335431) (xy 72.152256 -174.376842) (xy 72.148718 -174.38644)
			(xy 72.148701 -174.406876) (xy 72.152256 -174.416466) (xy 72.169272 -174.457846) (xy 72.195896 -174.543271)
			(xy 72.213802 -174.630939) (xy 72.222811 -174.719961) (xy 72.223376 -174.7647) (xy 72.223376 -174.765208)
			(xy 72.223122 -174.77867) (xy 72.249601 -174.784615) (xy 72.301836 -174.799358) (xy 72.327516 -174.808134)
			(xy 72.335713 -174.810648) (xy 72.352847 -174.810648) (xy 72.361044 -174.808134) (xy 72.39626 -174.796188)
			(xy 72.46827 -174.777601) (xy 72.541593 -174.765161) (xy 72.615704 -174.758956) (xy 72.65289 -174.758604)
			(xy 72.690074 -174.75897) (xy 72.764182 -174.765192) (xy 72.837502 -174.777635) (xy 72.909513 -174.796211)
			(xy 72.944736 -174.808134) (xy 72.952933 -174.810648) (xy 72.970067 -174.810648) (xy 72.978264 -174.808134)
			(xy 73.013366 -174.796247) (xy 73.085122 -174.777697) (xy 73.158185 -174.765251) (xy 73.232036 -174.758997)
			(xy 73.269094 -174.758604) (xy 73.27011 -174.758604) (xy 73.312036 -174.759059) (xy 73.395508 -174.767031)
			(xy 73.477845 -174.7829) (xy 73.5583 -174.806525) (xy 73.636145 -174.83769) (xy 73.710676 -174.876114)
			(xy 73.781216 -174.921448) (xy 73.847128 -174.973283) (xy 73.907814 -175.031148) (xy 73.962725 -175.094519)
			(xy 74.011364 -175.162823) (xy 74.053289 -175.235441) (xy 74.088123 -175.311716) (xy 74.115548 -175.390956)
			(xy 74.135316 -175.472444) (xy 74.14725 -175.555443) (xy 74.15124 -175.6392) (xy 74.14725 -175.722957)
			(xy 74.135316 -175.805956) (xy 74.115548 -175.887444) (xy 74.088123 -175.966684) (xy 74.053289 -176.042959)
			(xy 74.01685 -176.106074) (xy 102.855268 -176.106074) (xy 102.855838 -176.061305) (xy 102.864847 -175.97222)
			(xy 102.882749 -175.884489) (xy 102.909366 -175.798997) (xy 102.926388 -175.757586) (xy 102.92997 -175.748)
			(xy 102.92996 -175.727553) (xy 102.926388 -175.717962) (xy 102.90934 -175.67656) (xy 102.882709 -175.59107)
			(xy 102.864808 -175.503335) (xy 102.855818 -175.414245) (xy 102.855268 -175.369474) (xy 102.855838 -175.324705)
			(xy 102.864847 -175.23562) (xy 102.882749 -175.147889) (xy 102.909366 -175.062397) (xy 102.926388 -175.020986)
			(xy 102.92997 -175.0114) (xy 102.92996 -174.990953) (xy 102.926388 -174.981362) (xy 102.90934 -174.93996)
			(xy 102.882709 -174.85447) (xy 102.864808 -174.766735) (xy 102.855818 -174.677645) (xy 102.855268 -174.632874)
			(xy 102.855674 -174.591758) (xy 102.863264 -174.509876) (xy 102.878376 -174.429045) (xy 102.900882 -174.349952)
			(xy 102.930591 -174.273273) (xy 102.967247 -174.199663) (xy 103.010539 -174.129749) (xy 103.060097 -174.064128)
			(xy 103.115499 -174.003359) (xy 103.176271 -173.947961) (xy 103.241895 -173.898407) (xy 103.311812 -173.85512)
			(xy 103.385425 -173.818468) (xy 103.462105 -173.788765) (xy 103.541199 -173.766263) (xy 103.622032 -173.751156)
			(xy 103.703914 -173.743571) (xy 103.74503 -173.743112) (xy 103.786641 -173.743573) (xy 103.869498 -173.751353)
			(xy 103.951267 -173.766831) (xy 104.031235 -173.789874) (xy 104.108703 -173.820279) (xy 104.182995 -173.857782)
			(xy 104.218486 -173.87951) (xy 104.227629 -173.884663) (xy 104.248342 -173.88788) (xy 104.268614 -173.882552)
			(xy 104.27716 -173.876462) (xy 104.310789 -173.850471) (xy 104.382183 -173.804346) (xy 104.457654 -173.765245)
			(xy 104.536512 -173.733524) (xy 104.618037 -173.709475) (xy 104.701485 -173.693315) (xy 104.786095 -173.685193)
			(xy 104.828594 -173.684692) (xy 104.869707 -173.685219) (xy 104.951582 -173.692805) (xy 105.032407 -173.707913)
			(xy 105.111494 -173.730413) (xy 105.188168 -173.760115) (xy 105.261774 -173.796765) (xy 105.331684 -173.84005)
			(xy 105.397303 -173.8896) (xy 105.45807 -173.944993) (xy 105.513467 -174.005757) (xy 105.563021 -174.071373)
			(xy 105.60631 -174.141281) (xy 105.642964 -174.214885) (xy 105.67267 -174.291556) (xy 105.695176 -174.370642)
			(xy 105.710288 -174.451467) (xy 105.717879 -174.533341) (xy 105.718356 -174.574454) (xy 105.717793 -174.619224)
			(xy 105.708783 -174.708309) (xy 105.690877 -174.79604) (xy 105.664259 -174.881531) (xy 105.647236 -174.922942)
			(xy 105.643699 -174.932541) (xy 105.643682 -174.952976) (xy 105.647236 -174.962566) (xy 105.66424 -175.003917)
			(xy 105.690851 -175.089279) (xy 105.708758 -175.176882) (xy 105.71778 -175.265839) (xy 105.718356 -175.310546)
			(xy 105.718356 -175.311562) (xy 105.718102 -175.322992) (xy 105.744581 -175.328938) (xy 105.796816 -175.343681)
			(xy 105.822496 -175.352456) (xy 105.830693 -175.35497) (xy 105.847827 -175.35497) (xy 105.856024 -175.352456)
			(xy 105.89124 -175.340495) (xy 105.963244 -175.321841) (xy 106.036565 -175.309332) (xy 106.11068 -175.303059)
			(xy 106.14787 -175.302672) (xy 106.185059 -175.303071) (xy 106.259172 -175.309358) (xy 106.332492 -175.321865)
			(xy 106.404498 -175.340503) (xy 106.439716 -175.352456) (xy 106.447913 -175.35497) (xy 106.465047 -175.35497)
			(xy 106.473244 -175.352456) (xy 106.508459 -175.340489) (xy 106.580462 -175.321837) (xy 106.653784 -175.30933)
			(xy 106.7279 -175.303058) (xy 106.76509 -175.302672) (xy 106.80703 -175.303067) (xy 106.890532 -175.311039)
			(xy 106.972897 -175.326913) (xy 107.05338 -175.350544) (xy 107.131253 -175.381719) (xy 107.20581 -175.420155)
			(xy 107.276375 -175.465504) (xy 107.34231 -175.517355) (xy 107.403018 -175.575239) (xy 107.457949 -175.638632)
			(xy 107.505577 -175.705516) (xy 359.713276 -175.705516) (xy 359.713826 -175.660746) (xy 359.72284 -175.571661)
			(xy 359.740749 -175.48393) (xy 359.767371 -175.398439) (xy 359.784396 -175.357028) (xy 359.787954 -175.347435)
			(xy 359.78796 -175.326994) (xy 359.784396 -175.317404) (xy 359.767362 -175.275997) (xy 359.740727 -175.190508)
			(xy 359.722822 -175.102775) (xy 359.713828 -175.013687) (xy 359.713276 -174.968916) (xy 359.713826 -174.924146)
			(xy 359.72284 -174.835061) (xy 359.740749 -174.74733) (xy 359.767371 -174.661839) (xy 359.784396 -174.620428)
			(xy 359.787954 -174.610835) (xy 359.78796 -174.590394) (xy 359.784396 -174.580804) (xy 359.767362 -174.539397)
			(xy 359.740727 -174.453908) (xy 359.722822 -174.366175) (xy 359.713828 -174.277087) (xy 359.713276 -174.232316)
			(xy 359.713768 -174.191206) (xy 359.721354 -174.109337) (xy 359.736463 -174.028517) (xy 359.758966 -173.949437)
			(xy 359.788671 -173.872771) (xy 359.825324 -173.799173) (xy 359.868613 -173.729272) (xy 359.918168 -173.663664)
			(xy 359.973567 -173.602909) (xy 360.034335 -173.547526) (xy 360.099955 -173.497988) (xy 360.169867 -173.454716)
			(xy 360.243474 -173.418081) (xy 360.320148 -173.388396) (xy 360.399234 -173.365912) (xy 360.480057 -173.350823)
			(xy 360.561928 -173.343257) (xy 360.603038 -173.342808) (xy 360.644642 -173.343279) (xy 360.72749 -173.351011)
			(xy 360.809255 -173.366441) (xy 360.889223 -173.389435) (xy 360.966695 -173.419793) (xy 361.040997 -173.457248)
			(xy 361.076494 -173.478952) (xy 361.08563 -173.48412) (xy 361.106349 -173.487339) (xy 361.126625 -173.482001)
			(xy 361.135168 -173.475904) (xy 361.168794 -173.449952) (xy 361.240172 -173.403895) (xy 361.315615 -173.364851)
			(xy 361.394436 -173.333176) (xy 361.475917 -173.309157) (xy 361.559316 -173.293014) (xy 361.643874 -173.284894)
			(xy 361.686348 -173.284388) (xy 361.686602 -173.284388) (xy 361.72771 -173.284811) (xy 361.809576 -173.292396)
			(xy 361.890393 -173.307501) (xy 361.969472 -173.329998) (xy 362.046138 -173.359694) (xy 362.119738 -173.396336)
			(xy 362.189643 -173.439612) (xy 362.255258 -173.489152) (xy 362.316023 -173.544534) (xy 362.371419 -173.605287)
			(xy 362.420974 -173.67089) (xy 362.464266 -173.740786) (xy 362.500925 -173.814377) (xy 362.530638 -173.891036)
			(xy 362.553153 -173.97011) (xy 362.568276 -174.050924) (xy 362.57588 -174.132788) (xy 362.576364 -174.173896)
			(xy 362.575781 -174.218665) (xy 362.566776 -174.307749) (xy 362.548877 -174.395481) (xy 362.522264 -174.480972)
			(xy 362.505244 -174.522384) (xy 362.501683 -174.531976) (xy 362.501681 -174.552417) (xy 362.505244 -174.562008)
			(xy 362.522284 -174.603413) (xy 362.548917 -174.688902) (xy 362.56682 -174.776636) (xy 362.575812 -174.865725)
			(xy 362.576364 -174.910496) (xy 362.575094 -174.953676) (xy 362.575044 -174.965402) (xy 362.584373 -174.986895)
			(xy 362.602231 -175.002063) (xy 362.613448 -175.005492) (xy 362.632331 -175.010413) (xy 362.669682 -175.021721)
			(xy 362.688124 -175.028098) (xy 362.696321 -175.030612) (xy 362.713455 -175.030612) (xy 362.721652 -175.028098)
			(xy 362.756876 -175.016176) (xy 362.828883 -174.997583) (xy 362.902204 -174.985136) (xy 362.976313 -174.978924)
			(xy 363.013498 -174.978568) (xy 363.050682 -174.978934) (xy 363.12479 -174.985156) (xy 363.19811 -174.997599)
			(xy 363.270121 -175.016175) (xy 363.305344 -175.028098) (xy 363.313541 -175.030612) (xy 363.330675 -175.030612)
			(xy 363.338872 -175.028098) (xy 363.373974 -175.016212) (xy 363.44573 -174.997661) (xy 363.518793 -174.985214)
			(xy 363.592644 -174.978961) (xy 363.629702 -174.978568) (xy 363.630718 -174.978568) (xy 363.672642 -174.979095)
			(xy 363.75611 -174.987067) (xy 363.838443 -175.002937) (xy 363.918894 -175.026561) (xy 363.996736 -175.057726)
			(xy 364.071262 -175.096148) (xy 364.141799 -175.141481) (xy 364.207708 -175.193313) (xy 364.268391 -175.251175)
			(xy 364.323299 -175.314544) (xy 364.371935 -175.382845) (xy 364.413859 -175.45546) (xy 364.44869 -175.531731)
			(xy 364.476114 -175.610968) (xy 364.495881 -175.692452) (xy 364.507814 -175.775447) (xy 364.511804 -175.8592)
			(xy 364.507814 -175.942953) (xy 364.495881 -176.025948) (xy 364.476114 -176.107432) (xy 364.44869 -176.186669)
			(xy 364.413859 -176.26294) (xy 364.371935 -176.335555) (xy 364.323299 -176.403856) (xy 364.268391 -176.467225)
			(xy 364.207708 -176.525087) (xy 364.141799 -176.576919) (xy 364.071262 -176.622252) (xy 363.996736 -176.660674)
			(xy 363.918894 -176.691839) (xy 363.838443 -176.715463) (xy 363.75611 -176.731333) (xy 363.672642 -176.739305)
			(xy 363.630718 -176.739804) (xy 363.629702 -176.739804) (xy 363.592645 -176.739398) (xy 363.518796 -176.733134)
			(xy 363.445733 -176.720692) (xy 363.373973 -176.70216) (xy 363.338872 -176.690274) (xy 363.330675 -176.68776)
			(xy 363.313541 -176.68776) (xy 363.305344 -176.690274) (xy 363.271298 -176.701763) (xy 363.201741 -176.719817)
			(xy 363.166406 -176.726342) (xy 363.157048 -176.728326) (xy 363.140733 -176.738296) (xy 363.129218 -176.75356)
			(xy 363.126274 -176.762664) (xy 363.118487 -176.78918) (xy 363.100057 -176.841287) (xy 363.089444 -176.866804)
			(xy 363.085871 -176.876392) (xy 363.085877 -176.896837) (xy 363.089444 -176.906428) (xy 363.106465 -176.947806)
			(xy 363.133084 -177.033233) (xy 363.150988 -177.120901) (xy 363.159998 -177.209923) (xy 363.160564 -177.254662)
			(xy 363.160564 -177.254916) (xy 363.16006 -177.297264) (xy 363.152009 -177.381578) (xy 363.13598 -177.464744)
			(xy 363.112119 -177.546011) (xy 363.08064 -177.624641) (xy 363.041829 -177.699922) (xy 362.996039 -177.771174)
			(xy 362.943683 -177.83775) (xy 362.885235 -177.899048) (xy 362.821225 -177.954513) (xy 362.752233 -178.003642)
			(xy 362.678883 -178.045991) (xy 362.60184 -178.081175) (xy 362.521801 -178.108877) (xy 362.439492 -178.128845)
			(xy 362.355657 -178.140898) (xy 362.271056 -178.144929) (xy 362.186455 -178.140898) (xy 362.10262 -178.128845)
			(xy 362.020311 -178.108877) (xy 361.940272 -178.081175) (xy 361.863229 -178.045991) (xy 361.789879 -178.003642)
			(xy 361.720887 -177.954513) (xy 361.656877 -177.899048) (xy 361.598429 -177.83775) (xy 361.546073 -177.771174)
			(xy 361.500283 -177.699922) (xy 361.461472 -177.624641) (xy 361.429993 -177.546011) (xy 361.406132 -177.464744)
			(xy 361.390103 -177.381578) (xy 361.382052 -177.297264) (xy 361.381548 -177.254916) (xy 361.381548 -177.254662)
			(xy 361.382124 -177.209924) (xy 361.391138 -177.120903) (xy 361.409041 -177.033235) (xy 361.435651 -176.947807)
			(xy 361.452668 -176.906428) (xy 361.456222 -176.896834) (xy 361.456228 -176.876395) (xy 361.452668 -176.866804)
			(xy 361.435658 -176.825422) (xy 361.409036 -176.739997) (xy 361.391129 -176.65233) (xy 361.382115 -176.563308)
			(xy 361.381548 -176.51857) (xy 361.381548 -176.518316) (xy 361.38189 -176.482968) (xy 361.387504 -176.412495)
			(xy 361.39869 -176.34269) (xy 361.406694 -176.308258) (xy 361.409002 -176.295757) (xy 361.402463 -176.271224)
			(xy 361.394248 -176.261522) (xy 361.353608 -176.218596) (xy 361.34421 -176.220628) (xy 361.335443 -176.222892)
			(xy 361.32021 -176.232657) (xy 361.314492 -176.239678) (xy 361.289344 -176.272353) (xy 361.233931 -176.333418)
			(xy 361.173106 -176.389094) (xy 361.10739 -176.438902) (xy 361.037347 -176.482416) (xy 360.963578 -176.519263)
			(xy 360.886716 -176.549126) (xy 360.807421 -176.571748) (xy 360.726373 -176.586937) (xy 360.644268 -176.594561)
			(xy 360.603038 -176.595024) (xy 360.561931 -176.594551) (xy 360.480067 -176.58697) (xy 360.399251 -176.571868)
			(xy 360.320173 -176.549375) (xy 360.243508 -176.519683) (xy 360.169909 -176.483044) (xy 360.100004 -176.439772)
			(xy 360.034389 -176.390235) (xy 359.973624 -176.334856) (xy 359.918228 -176.274107) (xy 359.868672 -176.208506)
			(xy 359.825379 -176.138613) (xy 359.78872 -176.065025) (xy 359.759005 -175.988368) (xy 359.73649 -175.909296)
			(xy 359.721365 -175.828485) (xy 359.713761 -175.746623) (xy 359.713276 -175.705516) (xy 107.505577 -175.705516)
			(xy 107.506605 -175.706959) (xy 107.548546 -175.779602) (xy 107.583391 -175.855903) (xy 107.610826 -175.93517)
			(xy 107.630602 -176.016687) (xy 107.64254 -176.099714) (xy 107.646531 -176.1835) (xy 107.64254 -176.267286)
			(xy 107.630602 -176.350313) (xy 107.610826 -176.43183) (xy 107.583391 -176.511097) (xy 107.548546 -176.587398)
			(xy 107.506605 -176.660041) (xy 107.457949 -176.728368) (xy 107.403018 -176.791761) (xy 107.34231 -176.849645)
			(xy 107.276375 -176.901496) (xy 107.20581 -176.946845) (xy 107.131253 -176.985281) (xy 107.05338 -177.016456)
			(xy 106.972897 -177.040087) (xy 106.890532 -177.055961) (xy 106.80703 -177.063933) (xy 106.76509 -177.064416)
			(xy 106.7279 -177.064029) (xy 106.653787 -177.057739) (xy 106.580468 -177.045228) (xy 106.508462 -177.026587)
			(xy 106.473244 -177.014632) (xy 106.465047 -177.012118) (xy 106.447913 -177.012118) (xy 106.439716 -177.014632)
			(xy 106.394061 -177.029945) (xy 106.300252 -177.051713) (xy 106.252518 -177.058066) (xy 106.242041 -177.059824)
			(xy 106.223772 -177.070618) (xy 106.211473 -177.087908) (xy 106.20883 -177.098198) (xy 106.199325 -177.142161)
			(xy 106.1726 -177.22805) (xy 106.15549 -177.269648) (xy 106.151882 -177.279222) (xy 106.151736 -177.29966)
			(xy 106.155236 -177.309272) (xy 106.172271 -177.350645) (xy 106.198886 -177.436073) (xy 106.216787 -177.523743)
			(xy 106.225792 -177.612767) (xy 106.226356 -177.657506) (xy 106.226356 -177.65776) (xy 106.225852 -177.700108)
			(xy 106.217801 -177.784422) (xy 106.201772 -177.867588) (xy 106.177911 -177.948855) (xy 106.146432 -178.027485)
			(xy 106.107621 -178.102766) (xy 106.061831 -178.174018) (xy 106.009475 -178.240594) (xy 105.951027 -178.301892)
			(xy 105.887017 -178.357357) (xy 105.818025 -178.406486) (xy 105.744675 -178.448835) (xy 105.667632 -178.484019)
			(xy 105.587593 -178.511721) (xy 105.505284 -178.531689) (xy 105.421449 -178.543742) (xy 105.336848 -178.547773)
			(xy 105.252247 -178.543742) (xy 105.168412 -178.531689) (xy 105.086103 -178.511721) (xy 105.006064 -178.484019)
			(xy 104.929021 -178.448835) (xy 104.855671 -178.406486) (xy 104.786679 -178.357357) (xy 104.722669 -178.301892)
			(xy 104.664221 -178.240594) (xy 104.611865 -178.174018) (xy 104.566075 -178.102766) (xy 104.527264 -178.027485)
			(xy 104.495785 -177.948855) (xy 104.471924 -177.867588) (xy 104.455895 -177.784422) (xy 104.447844 -177.700108)
			(xy 104.44734 -177.65776) (xy 104.44734 -177.657506) (xy 104.447891 -177.612767) (xy 104.456911 -177.523745)
			(xy 104.474821 -177.436078) (xy 104.50144 -177.350651) (xy 104.51846 -177.309272) (xy 104.522047 -177.299688)
			(xy 104.522032 -177.279239) (xy 104.51846 -177.269648) (xy 104.501426 -177.228241) (xy 104.474794 -177.142752)
			(xy 104.456889 -177.055019) (xy 104.447894 -176.965931) (xy 104.44734 -176.92116) (xy 104.447594 -176.89703)
			(xy 104.44745 -176.887477) (xy 104.440882 -176.869548) (xy 104.428227 -176.855249) (xy 104.419908 -176.850548)
			(xy 104.33812 -176.808638) (xy 104.329507 -176.804642) (xy 104.310627 -176.802733) (xy 104.292347 -176.807824)
			(xy 104.284526 -176.81321) (xy 104.284526 -176.813464) (xy 104.284018 -176.813464) (xy 104.250823 -176.838169)
			(xy 104.180649 -176.882028) (xy 104.106709 -176.919187) (xy 104.029639 -176.949324) (xy 103.950105 -176.97218)
			(xy 103.868793 -176.987556) (xy 103.786406 -176.995321) (xy 103.74503 -176.995836) (xy 103.703915 -176.995373)
			(xy 103.622035 -176.987788) (xy 103.541204 -176.97268) (xy 103.462113 -176.950179) (xy 103.385435 -176.920475)
			(xy 103.311825 -176.883823) (xy 103.241911 -176.840535) (xy 103.176289 -176.790981) (xy 103.11552 -176.735583)
			(xy 103.060122 -176.674814) (xy 103.010567 -176.609193) (xy 102.967279 -176.539279) (xy 102.930626 -176.465669)
			(xy 102.900922 -176.388991) (xy 102.87842 -176.309899) (xy 102.863312 -176.229069) (xy 102.855727 -176.147189)
			(xy 102.855268 -176.106074) (xy 74.01685 -176.106074) (xy 74.011364 -176.115577) (xy 73.962725 -176.183881)
			(xy 73.907814 -176.247252) (xy 73.847128 -176.305117) (xy 73.781216 -176.356952) (xy 73.710676 -176.402286)
			(xy 73.636145 -176.44071) (xy 73.5583 -176.471875) (xy 73.477845 -176.4955) (xy 73.395508 -176.511369)
			(xy 73.312036 -176.519341) (xy 73.27011 -176.51984) (xy 73.269094 -176.51984) (xy 73.232037 -176.519434)
			(xy 73.158188 -176.51317) (xy 73.085125 -176.500728) (xy 73.013365 -176.482196) (xy 72.978264 -176.47031)
			(xy 72.970067 -176.467796) (xy 72.952933 -176.467796) (xy 72.944736 -176.47031) (xy 72.910756 -176.481853)
			(xy 72.841327 -176.500034) (xy 72.806052 -176.506632) (xy 72.796116 -176.508916) (xy 72.779041 -176.520017)
			(xy 72.767603 -176.536869) (xy 72.765158 -176.546764) (xy 72.755578 -176.591455) (xy 72.728473 -176.67875)
			(xy 72.711056 -176.721008) (xy 72.70748 -176.730595) (xy 72.707488 -176.751041) (xy 72.711056 -176.760632)
			(xy 72.728073 -176.802012) (xy 72.754694 -176.887437) (xy 72.7726 -176.975105) (xy 72.78161 -177.064127)
			(xy 72.782176 -177.108866) (xy 72.782176 -177.10912) (xy 72.781672 -177.151468) (xy 72.773621 -177.235782)
			(xy 72.757592 -177.318948) (xy 72.733731 -177.400215) (xy 72.702252 -177.478845) (xy 72.663441 -177.554126)
			(xy 72.617651 -177.625378) (xy 72.565295 -177.691954) (xy 72.506847 -177.753252) (xy 72.442837 -177.808717)
			(xy 72.373845 -177.857846) (xy 72.300495 -177.900195) (xy 72.223452 -177.935379) (xy 72.143413 -177.963081)
			(xy 72.061104 -177.983049) (xy 71.977269 -177.995102) (xy 71.892668 -177.999133) (xy 71.808067 -177.995102)
			(xy 71.724232 -177.983049) (xy 71.641923 -177.963081) (xy 71.561884 -177.935379) (xy 71.484841 -177.900195)
			(xy 71.411491 -177.857846) (xy 71.342499 -177.808717) (xy 71.278489 -177.753252) (xy 71.220041 -177.691954)
			(xy 71.167685 -177.625378) (xy 71.121895 -177.554126) (xy 71.083084 -177.478845) (xy 71.051605 -177.400215)
			(xy 71.027744 -177.318948) (xy 71.011715 -177.235782) (xy 71.003664 -177.151468) (xy 71.00316 -177.10912)
			(xy 71.00316 -177.108866) (xy 71.003737 -177.064128) (xy 71.01275 -176.975107) (xy 71.030653 -176.887439)
			(xy 71.057263 -176.802011) (xy 71.07428 -176.760632) (xy 71.077831 -176.751038) (xy 71.077839 -176.730599)
			(xy 71.07428 -176.721008) (xy 71.057235 -176.679605) (xy 71.030605 -176.594115) (xy 71.012704 -176.50638)
			(xy 71.003712 -176.417291) (xy 71.00316 -176.37252) (xy 71.003216 -176.357395) (xy 71.004231 -176.327162)
			(xy 71.005192 -176.312068) (xy 71.005427 -176.302019) (xy 70.999034 -176.282984) (xy 70.985815 -176.267867)
			(xy 70.976998 -176.263046) (xy 70.8787 -176.214532) (xy 70.84822 -176.218596) (xy 70.83679 -176.228756)
			(xy 70.806403 -176.254854) (xy 70.741691 -176.302073) (xy 70.672994 -176.343279) (xy 70.60087 -176.378141)
			(xy 70.525902 -176.406374) (xy 70.4487 -176.427751) (xy 70.369887 -176.442098) (xy 70.290104 -176.449298)
			(xy 70.25005 -176.449736) (xy 70.208935 -176.449254) (xy 70.127056 -176.441671) (xy 70.046226 -176.426565)
			(xy 69.967134 -176.404065) (xy 69.890456 -176.374363) (xy 69.816846 -176.337712) (xy 69.746932 -176.294426)
			(xy 69.68131 -176.244873) (xy 69.620541 -176.189476) (xy 69.565143 -176.128708) (xy 69.515588 -176.063088)
			(xy 69.472299 -175.993175) (xy 69.435647 -175.919566) (xy 69.405943 -175.842889) (xy 69.383441 -175.763798)
			(xy 69.368332 -175.682968) (xy 69.360747 -175.601089) (xy 69.360288 -175.559974) (xy 9.487916 -175.559974)
			(xy 9.487916 -175.848264) (xy 9.48743 -175.875515) (xy 9.479674 -175.929463) (xy 9.464319 -175.981758)
			(xy 9.441677 -176.031335) (xy 9.412211 -176.077185) (xy 9.37652 -176.118376) (xy 9.335329 -176.154067)
			(xy 9.289479 -176.183533) (xy 9.239902 -176.206175) (xy 9.187607 -176.22153) (xy 9.133659 -176.229286)
			(xy 9.079157 -176.229286) (xy 9.025209 -176.22153) (xy 8.972914 -176.206175) (xy 8.923337 -176.183533)
			(xy 8.877487 -176.154067) (xy 8.836296 -176.118376) (xy 8.800605 -176.077185) (xy 8.771139 -176.031335)
			(xy 8.748497 -175.981758) (xy 8.733142 -175.929463) (xy 8.725386 -175.875515) (xy 8.7249 -175.848264)
			(xy 2.509012 -175.848264) (xy 2.509012 -178.618388) (xy 8.7249 -178.618388) (xy 8.7249 -177.754788)
			(xy 8.725386 -177.727537) (xy 8.733142 -177.673589) (xy 8.748497 -177.621294) (xy 8.771139 -177.571717)
			(xy 8.800605 -177.525867) (xy 8.836296 -177.484676) (xy 8.877487 -177.448985) (xy 8.923337 -177.419519)
			(xy 8.972914 -177.396877) (xy 9.025209 -177.381522) (xy 9.079157 -177.373766) (xy 9.133659 -177.373766)
			(xy 9.187607 -177.381522) (xy 9.239902 -177.396877) (xy 9.289479 -177.419519) (xy 9.335329 -177.448985)
			(xy 9.37652 -177.484676) (xy 9.412211 -177.525867) (xy 9.441677 -177.571717) (xy 9.464319 -177.621294)
			(xy 9.479674 -177.673589) (xy 9.48743 -177.727537) (xy 9.487916 -177.754788) (xy 9.487916 -178.618388)
			(xy 9.48743 -178.645639) (xy 9.479674 -178.699587) (xy 9.464319 -178.751882) (xy 9.44304 -178.798474)
			(xy 77.963268 -178.798474) (xy 77.963886 -178.752072) (xy 77.973579 -178.659774) (xy 77.992835 -178.568989)
			(xy 78.021445 -178.480704) (xy 78.039722 -178.438048) (xy 78.043541 -178.42811) (xy 78.043531 -178.406843)
			(xy 78.039722 -178.3969) (xy 78.021451 -178.354243) (xy 77.99286 -178.265953) (xy 77.973605 -178.175169)
			(xy 77.963896 -178.082875) (xy 77.963268 -178.036474) (xy 77.963674 -177.995358) (xy 77.971264 -177.913476)
			(xy 77.986376 -177.832645) (xy 78.008882 -177.753552) (xy 78.038591 -177.676873) (xy 78.075247 -177.603263)
			(xy 78.118539 -177.533349) (xy 78.168097 -177.467728) (xy 78.223499 -177.406959) (xy 78.284271 -177.351561)
			(xy 78.349895 -177.302007) (xy 78.419812 -177.25872) (xy 78.493425 -177.222068) (xy 78.570105 -177.192365)
			(xy 78.649199 -177.169863) (xy 78.730032 -177.154756) (xy 78.811914 -177.147171) (xy 78.85303 -177.146712)
			(xy 78.893848 -177.147168) (xy 78.975141 -177.154659) (xy 79.055405 -177.169568) (xy 79.133966 -177.191768)
			(xy 79.210162 -177.221072) (xy 79.283352 -177.257234) (xy 79.352922 -177.29995) (xy 79.418285 -177.348861)
			(xy 79.478892 -177.403555) (xy 79.534233 -177.463571) (xy 79.559404 -177.495708) (xy 79.565179 -177.502627)
			(xy 79.580393 -177.512264) (xy 79.589122 -177.514504) (xy 79.631283 -177.524073) (xy 79.713687 -177.550242)
			(xy 79.793163 -177.584282) (xy 79.868962 -177.625872) (xy 79.940368 -177.67462) (xy 80.006708 -177.730066)
			(xy 80.067355 -177.791686) (xy 80.121738 -177.8589) (xy 80.169343 -177.931073) (xy 80.209721 -178.007525)
			(xy 80.242492 -178.087533) (xy 80.267345 -178.170343) (xy 80.284047 -178.255173) (xy 80.29244 -178.341224)
			(xy 80.292956 -178.384454) (xy 80.292766 -178.411062) (xy 80.289588 -178.464184) (xy 80.286606 -178.490626)
			(xy 80.285833 -178.501873) (xy 80.292962 -178.523233) (xy 80.300322 -178.531774) (xy 80.329261 -178.562798)
			(xy 80.381784 -178.629432) (xy 80.427728 -178.700761) (xy 80.466676 -178.776139) (xy 80.498274 -178.854881)
			(xy 80.522235 -178.936272) (xy 80.538342 -179.019574) (xy 80.546449 -179.104032) (xy 80.546956 -179.146454)
			(xy 80.546393 -179.191224) (xy 80.537383 -179.280309) (xy 80.519477 -179.36804) (xy 80.492859 -179.453531)
			(xy 80.475836 -179.494942) (xy 80.472299 -179.504541) (xy 80.472282 -179.524976) (xy 80.475836 -179.534566)
			(xy 80.49284 -179.575917) (xy 80.519451 -179.661279) (xy 80.537358 -179.748882) (xy 80.54638 -179.837839)
			(xy 80.546956 -179.882546) (xy 80.546956 -179.883562) (xy 80.546702 -179.894992) (xy 80.573181 -179.900938)
			(xy 80.625416 -179.915681) (xy 80.651096 -179.924456) (xy 80.659293 -179.92697) (xy 80.676427 -179.92697)
			(xy 80.684624 -179.924456) (xy 80.71984 -179.912495) (xy 80.791844 -179.893841) (xy 80.865165 -179.881332)
			(xy 80.93928 -179.875059) (xy 80.97647 -179.874672) (xy 81.013659 -179.875071) (xy 81.087772 -179.881358)
			(xy 81.161092 -179.893865) (xy 81.233098 -179.912503) (xy 81.268316 -179.924456) (xy 81.276513 -179.92697)
			(xy 81.293647 -179.92697) (xy 81.301844 -179.924456) (xy 81.337059 -179.912489) (xy 81.409062 -179.893837)
			(xy 81.482384 -179.88133) (xy 81.5565 -179.875058) (xy 81.59369 -179.874672) (xy 81.63563 -179.875067)
			(xy 81.719132 -179.883039) (xy 81.801497 -179.898913) (xy 81.88198 -179.922544) (xy 81.959853 -179.953719)
			(xy 82.03441 -179.992155) (xy 82.104975 -180.037504) (xy 82.17091 -180.089355) (xy 82.231618 -180.147239)
			(xy 82.286549 -180.210632) (xy 82.335205 -180.278959) (xy 82.377146 -180.351602) (xy 82.411991 -180.427903)
			(xy 82.439426 -180.50717) (xy 82.459202 -180.588687) (xy 82.462267 -180.610002) (xy 86.081108 -180.610002)
			(xy 86.081685 -180.565233) (xy 86.090691 -180.476148) (xy 86.108592 -180.388417) (xy 86.135207 -180.302925)
			(xy 86.152228 -180.261514) (xy 86.155792 -180.251923) (xy 86.155793 -180.231481) (xy 86.152228 -180.22189)
			(xy 86.135186 -180.180486) (xy 86.108554 -180.094996) (xy 86.090651 -180.007262) (xy 86.081659 -179.918173)
			(xy 86.081108 -179.873402) (xy 86.081685 -179.828633) (xy 86.090691 -179.739548) (xy 86.108592 -179.651817)
			(xy 86.135207 -179.566325) (xy 86.152228 -179.524914) (xy 86.155792 -179.515323) (xy 86.155793 -179.494881)
			(xy 86.152228 -179.48529) (xy 86.135186 -179.443886) (xy 86.108554 -179.358396) (xy 86.090651 -179.270662)
			(xy 86.081659 -179.181573) (xy 86.081108 -179.136802) (xy 86.081615 -179.095689) (xy 86.089201 -179.013813)
			(xy 86.10431 -178.932986) (xy 86.126812 -178.853898) (xy 86.156515 -178.777224) (xy 86.193165 -178.703617)
			(xy 86.236451 -178.633706) (xy 86.286003 -178.568087) (xy 86.341397 -178.50732) (xy 86.402163 -178.451923)
			(xy 86.46778 -178.402369) (xy 86.537689 -178.359081) (xy 86.611295 -178.322428) (xy 86.687968 -178.292722)
			(xy 86.767055 -178.270217) (xy 86.847881 -178.255106) (xy 86.929757 -178.247516) (xy 86.97087 -178.24704)
			(xy 87.01248 -178.247527) (xy 87.095336 -178.255301) (xy 87.177105 -178.270774) (xy 87.257073 -178.293812)
			(xy 87.334542 -178.324213) (xy 87.408835 -178.361712) (xy 87.444326 -178.383438) (xy 87.453453 -178.388623)
			(xy 87.474176 -178.391826) (xy 87.494454 -178.386485) (xy 87.503 -178.38039) (xy 87.536641 -178.354416)
			(xy 87.608034 -178.30829) (xy 87.683503 -178.269188) (xy 87.762359 -178.237466) (xy 87.843882 -178.213414)
			(xy 87.927328 -178.19725) (xy 88.011936 -178.189124) (xy 88.054434 -178.18862) (xy 88.095548 -178.18908)
			(xy 88.177426 -178.19667) (xy 88.258254 -178.211782) (xy 88.337343 -178.234287) (xy 88.414018 -178.263994)
			(xy 88.487625 -178.300648) (xy 88.557536 -178.343937) (xy 88.623155 -178.393491) (xy 88.683922 -178.448889)
			(xy 88.739319 -178.509657) (xy 88.788872 -178.575277) (xy 88.83216 -178.645189) (xy 88.868813 -178.718797)
			(xy 88.898518 -178.795473) (xy 88.921021 -178.874562) (xy 88.936132 -178.95539) (xy 88.94372 -179.037268)
			(xy 88.944196 -179.078382) (xy 88.943648 -179.123152) (xy 88.934633 -179.212238) (xy 88.916724 -179.299969)
			(xy 88.890101 -179.38546) (xy 88.873076 -179.42687) (xy 88.869521 -179.436464) (xy 88.869514 -179.456904)
			(xy 88.873076 -179.466494) (xy 88.890086 -179.507843) (xy 88.916696 -179.593206) (xy 88.934602 -179.680809)
			(xy 88.943621 -179.769767) (xy 88.944196 -179.814474) (xy 88.944196 -179.81549) (xy 88.943942 -179.82692)
			(xy 88.970422 -179.832862) (xy 89.022656 -179.847607) (xy 89.048336 -179.856384) (xy 89.056533 -179.858898)
			(xy 89.073667 -179.858898) (xy 89.081864 -179.856384) (xy 89.117077 -179.844413) (xy 89.189082 -179.825761)
			(xy 89.262404 -179.813256) (xy 89.33652 -179.806985) (xy 89.37371 -179.8066) (xy 89.4109 -179.806986)
			(xy 89.485013 -179.813277) (xy 89.558333 -179.825787) (xy 89.630338 -179.844429) (xy 89.665556 -179.856384)
			(xy 89.673753 -179.858898) (xy 89.690887 -179.858898) (xy 89.699084 -179.856384) (xy 89.734295 -179.844408)
			(xy 89.8063 -179.825757) (xy 89.879623 -179.813253) (xy 89.953739 -179.806984) (xy 89.99093 -179.8066)
			(xy 90.032865 -179.807156) (xy 90.116355 -179.815131) (xy 90.198709 -179.831006) (xy 90.279182 -179.854637)
			(xy 90.357043 -179.885811) (xy 90.431589 -179.924244) (xy 90.502144 -179.969589) (xy 90.56807 -180.021436)
			(xy 90.628768 -180.079314) (xy 90.683691 -180.1427) (xy 90.732339 -180.211019) (xy 90.774274 -180.283653)
			(xy 90.809114 -180.359944) (xy 90.836544 -180.439202) (xy 90.856317 -180.520708) (xy 90.868253 -180.603725)
			(xy 90.869375 -180.627274) (xy 94.473268 -180.627274) (xy 94.473838 -180.582505) (xy 94.482847 -180.49342)
			(xy 94.500749 -180.405689) (xy 94.527366 -180.320197) (xy 94.544388 -180.278786) (xy 94.54797 -180.2692)
			(xy 94.54796 -180.248753) (xy 94.544388 -180.239162) (xy 94.52734 -180.19776) (xy 94.500709 -180.11227)
			(xy 94.482808 -180.024535) (xy 94.473818 -179.935445) (xy 94.473268 -179.890674) (xy 94.473838 -179.845905)
			(xy 94.482847 -179.75682) (xy 94.500749 -179.669089) (xy 94.527366 -179.583597) (xy 94.544388 -179.542186)
			(xy 94.54797 -179.5326) (xy 94.54796 -179.512153) (xy 94.544388 -179.502562) (xy 94.52734 -179.46116)
			(xy 94.500709 -179.37567) (xy 94.482808 -179.287935) (xy 94.473818 -179.198845) (xy 94.473268 -179.154074)
			(xy 94.473674 -179.112958) (xy 94.481264 -179.031076) (xy 94.496376 -178.950245) (xy 94.518882 -178.871152)
			(xy 94.548591 -178.794473) (xy 94.585247 -178.720863) (xy 94.628539 -178.650949) (xy 94.678097 -178.585328)
			(xy 94.733499 -178.524559) (xy 94.794271 -178.469161) (xy 94.859895 -178.419607) (xy 94.929812 -178.37632)
			(xy 95.003425 -178.339668) (xy 95.080105 -178.309965) (xy 95.159199 -178.287463) (xy 95.240032 -178.272356)
			(xy 95.321914 -178.264771) (xy 95.36303 -178.264312) (xy 95.404641 -178.264773) (xy 95.487498 -178.272553)
			(xy 95.569267 -178.288031) (xy 95.649235 -178.311074) (xy 95.726703 -178.341479) (xy 95.800995 -178.378982)
			(xy 95.836486 -178.40071) (xy 95.845629 -178.405863) (xy 95.866342 -178.40908) (xy 95.886614 -178.403752)
			(xy 95.89516 -178.397662) (xy 95.928789 -178.371671) (xy 96.000183 -178.325546) (xy 96.075654 -178.286445)
			(xy 96.154512 -178.254724) (xy 96.236037 -178.230675) (xy 96.319485 -178.214515) (xy 96.404095 -178.206393)
			(xy 96.446594 -178.205892) (xy 96.487707 -178.206419) (xy 96.569582 -178.214005) (xy 96.650407 -178.229113)
			(xy 96.729494 -178.251613) (xy 96.806168 -178.281315) (xy 96.879774 -178.317965) (xy 96.949684 -178.36125)
			(xy 97.015303 -178.4108) (xy 97.07607 -178.466193) (xy 97.131467 -178.526957) (xy 97.181021 -178.592573)
			(xy 97.22431 -178.662481) (xy 97.260964 -178.736085) (xy 97.29067 -178.812756) (xy 97.313176 -178.891842)
			(xy 97.328288 -178.972667) (xy 97.335879 -179.054541) (xy 97.336356 -179.095654) (xy 97.335793 -179.140424)
			(xy 97.329275 -179.204874) (xy 368.074448 -179.204874) (xy 368.075006 -179.161932) (xy 368.083288 -179.076448)
			(xy 368.099773 -178.99216) (xy 368.124306 -178.909855) (xy 368.15666 -178.830297) (xy 368.196533 -178.75423)
			(xy 368.243554 -178.682361) (xy 368.297284 -178.615359) (xy 368.357224 -178.55385) (xy 368.422813 -178.498405)
			(xy 368.493443 -178.449542) (xy 368.568454 -178.407716) (xy 368.607594 -178.390042) (xy 368.615999 -178.385919)
			(xy 368.629281 -178.372745) (xy 368.633502 -178.364388) (xy 368.645948 -178.33721) (xy 368.64947 -178.328554)
			(xy 368.650638 -178.309919) (xy 368.648234 -178.300888) (xy 368.635415 -178.257999) (xy 368.617464 -178.170297)
			(xy 368.608423 -178.081234) (xy 368.607848 -178.036474) (xy 368.608352 -177.994113) (xy 368.616405 -177.909776)
			(xy 368.632439 -177.826586) (xy 368.656307 -177.745296) (xy 368.687795 -177.666644) (xy 368.726617 -177.591341)
			(xy 368.77242 -177.520069) (xy 368.824791 -177.453473) (xy 368.883256 -177.392158) (xy 368.947284 -177.336677)
			(xy 369.016296 -177.287534) (xy 369.089666 -177.245174) (xy 369.166731 -177.209979) (xy 369.246793 -177.18227)
			(xy 369.329126 -177.162296) (xy 369.412985 -177.150239) (xy 369.49761 -177.146208) (xy 369.582235 -177.150239)
			(xy 369.666094 -177.162296) (xy 369.748427 -177.18227) (xy 369.828489 -177.209979) (xy 369.905554 -177.245174)
			(xy 369.978924 -177.287534) (xy 370.047936 -177.336677) (xy 370.111964 -177.392158) (xy 370.170429 -177.453473)
			(xy 370.2228 -177.520069) (xy 370.268603 -177.591341) (xy 370.307425 -177.666644) (xy 370.338913 -177.745296)
			(xy 370.362781 -177.826586) (xy 370.378815 -177.909776) (xy 370.386868 -177.994113) (xy 370.387372 -178.036474)
			(xy 370.387372 -178.036728) (xy 370.386948 -178.075094) (xy 370.380306 -178.151538) (xy 370.367099 -178.227125)
			(xy 370.357654 -178.264312) (xy 370.35562 -178.273261) (xy 370.357441 -178.291512) (xy 370.365595 -178.307941)
			(xy 370.37903 -178.320427) (xy 370.387372 -178.324256) (xy 370.427603 -178.341379) (xy 370.50477 -178.382506)
			(xy 370.577528 -178.431007) (xy 370.645175 -178.486413) (xy 370.707059 -178.548191) (xy 370.762582 -178.615743)
			(xy 370.811207 -178.688417) (xy 370.852467 -178.765513) (xy 370.885962 -178.846285) (xy 370.911369 -178.929954)
			(xy 370.928442 -179.015713) (xy 370.937018 -179.102733) (xy 370.937536 -179.146454) (xy 370.936975 -179.191224)
			(xy 370.927964 -179.280309) (xy 370.910058 -179.36804) (xy 370.883439 -179.453531) (xy 370.866416 -179.494942)
			(xy 370.86288 -179.504541) (xy 370.862862 -179.524975) (xy 370.866416 -179.534566) (xy 370.883441 -179.575977)
			(xy 370.910078 -179.661464) (xy 370.927986 -179.749196) (xy 370.936982 -179.838284) (xy 370.937536 -179.883054)
			(xy 370.937282 -179.903882) (xy 370.937631 -179.91519) (xy 370.946776 -179.935848) (xy 370.963889 -179.950596)
			(xy 370.97462 -179.954174) (xy 370.989618 -179.95835) (xy 371.019344 -179.967623) (xy 371.034056 -179.972716)
			(xy 371.042253 -179.97523) (xy 371.059387 -179.97523) (xy 371.067584 -179.972716) (xy 371.102796 -179.960741)
			(xy 371.174801 -179.94209) (xy 371.248123 -179.929585) (xy 371.322239 -179.923316) (xy 371.35943 -179.922932)
			(xy 371.396619 -179.923339) (xy 371.470732 -179.929623) (xy 371.544052 -179.942128) (xy 371.616058 -179.960764)
			(xy 371.651276 -179.972716) (xy 371.659473 -179.97523) (xy 371.676607 -179.97523) (xy 371.684804 -179.972716)
			(xy 371.720023 -179.960763) (xy 371.792025 -179.942106) (xy 371.865345 -179.929595) (xy 371.93946 -179.923319)
			(xy 371.97665 -179.922932) (xy 372.01859 -179.923405) (xy 372.10209 -179.931374) (xy 372.184455 -179.947244)
			(xy 372.264938 -179.970872) (xy 372.34281 -180.002043) (xy 372.417367 -180.040476) (xy 372.487932 -180.085822)
			(xy 372.553868 -180.137671) (xy 372.614576 -180.195553) (xy 372.669507 -180.258944) (xy 372.718163 -180.327269)
			(xy 372.760105 -180.39991) (xy 372.794951 -180.476209) (xy 372.822386 -180.555475) (xy 372.842162 -180.63699)
			(xy 372.848069 -180.678074) (xy 376.477276 -180.678074) (xy 376.477846 -180.633305) (xy 376.486854 -180.54422)
			(xy 376.504757 -180.456489) (xy 376.531374 -180.370997) (xy 376.548396 -180.329586) (xy 376.551978 -180.32)
			(xy 376.551968 -180.299553) (xy 376.548396 -180.289962) (xy 376.531349 -180.24856) (xy 376.504717 -180.16307)
			(xy 376.486816 -180.075335) (xy 376.477826 -179.986245) (xy 376.477276 -179.941474) (xy 376.477846 -179.896705)
			(xy 376.486854 -179.80762) (xy 376.504757 -179.719889) (xy 376.531374 -179.634397) (xy 376.548396 -179.592986)
			(xy 376.551978 -179.5834) (xy 376.551968 -179.562953) (xy 376.548396 -179.553362) (xy 376.531349 -179.51196)
			(xy 376.504717 -179.42647) (xy 376.486816 -179.338735) (xy 376.477826 -179.249645) (xy 376.477276 -179.204874)
			(xy 376.477674 -179.163758) (xy 376.485264 -179.081876) (xy 376.500376 -179.001043) (xy 376.522883 -178.92195)
			(xy 376.552591 -178.845272) (xy 376.589248 -178.771661) (xy 376.632541 -178.701747) (xy 376.682099 -178.636125)
			(xy 376.737501 -178.575356) (xy 376.798274 -178.519958) (xy 376.863899 -178.470404) (xy 376.933817 -178.427117)
			(xy 377.00743 -178.390466) (xy 377.084111 -178.360763) (xy 377.163206 -178.338262) (xy 377.244039 -178.323155)
			(xy 377.325922 -178.315571) (xy 377.367038 -178.315112) (xy 377.408648 -178.315619) (xy 377.491503 -178.323389)
			(xy 377.573272 -178.338859) (xy 377.65324 -178.361894) (xy 377.730709 -178.392291) (xy 377.805002 -178.429786)
			(xy 377.840494 -178.45151) (xy 377.849633 -178.45667) (xy 377.870349 -178.459885) (xy 377.890623 -178.454554)
			(xy 377.899168 -178.448462) (xy 377.932829 -178.422514) (xy 378.004217 -178.376384) (xy 378.079682 -178.337278)
			(xy 378.158534 -178.305551) (xy 378.240054 -178.281495) (xy 378.323498 -178.265328) (xy 378.408104 -178.257198)
			(xy 378.450602 -178.256692) (xy 378.491715 -178.257211) (xy 378.57359 -178.264798) (xy 378.654416 -178.279906)
			(xy 378.733503 -178.302408) (xy 378.810176 -178.33211) (xy 378.883782 -178.368761) (xy 378.953693 -178.412046)
			(xy 379.019312 -178.461597) (xy 379.080078 -178.51699) (xy 379.135475 -178.577755) (xy 379.185029 -178.643371)
			(xy 379.228318 -178.713279) (xy 379.264972 -178.786883) (xy 379.294678 -178.863555) (xy 379.317184 -178.942641)
			(xy 379.332296 -179.023466) (xy 379.339887 -179.105341) (xy 379.340364 -179.146454) (xy 379.339801 -179.191224)
			(xy 379.330791 -179.280309) (xy 379.312886 -179.36804) (xy 379.286267 -179.453531) (xy 379.269244 -179.494942)
			(xy 379.265706 -179.50454) (xy 379.265689 -179.524976) (xy 379.269244 -179.534566) (xy 379.286249 -179.575917)
			(xy 379.31286 -179.661279) (xy 379.330766 -179.748882) (xy 379.339788 -179.837839) (xy 379.340364 -179.882546)
			(xy 379.340364 -179.883562) (xy 379.34011 -179.894992) (xy 379.366589 -179.900938) (xy 379.418824 -179.915681)
			(xy 379.444504 -179.924456) (xy 379.452701 -179.92697) (xy 379.469835 -179.92697) (xy 379.478032 -179.924456)
			(xy 379.513248 -179.912493) (xy 379.585251 -179.893839) (xy 379.658572 -179.881331) (xy 379.732688 -179.875058)
			(xy 379.769878 -179.874672) (xy 379.807067 -179.875069) (xy 379.88118 -179.881356) (xy 379.9545 -179.893864)
			(xy 380.026506 -179.912502) (xy 380.061724 -179.924456) (xy 380.069921 -179.92697) (xy 380.087055 -179.92697)
			(xy 380.095252 -179.924456) (xy 380.130466 -179.912487) (xy 380.20247 -179.893835) (xy 380.275792 -179.881329)
			(xy 380.349908 -179.875057) (xy 380.387098 -179.874672) (xy 380.429038 -179.875067) (xy 380.512539 -179.88304)
			(xy 380.594904 -179.898915) (xy 380.675386 -179.922546) (xy 380.753258 -179.953722) (xy 380.827814 -179.992158)
			(xy 380.898379 -180.037507) (xy 380.964314 -180.089358) (xy 381.025021 -180.147242) (xy 381.079951 -180.210635)
			(xy 381.128607 -180.278962) (xy 381.170547 -180.351604) (xy 381.205392 -180.427905) (xy 381.232827 -180.507172)
			(xy 381.252602 -180.588688) (xy 381.26454 -180.671715) (xy 381.264843 -180.678074) (xy 384.808476 -180.678074)
			(xy 384.809046 -180.633305) (xy 384.818054 -180.54422) (xy 384.835957 -180.456489) (xy 384.862574 -180.370997)
			(xy 384.879596 -180.329586) (xy 384.883178 -180.32) (xy 384.883168 -180.299553) (xy 384.879596 -180.289962)
			(xy 384.862549 -180.24856) (xy 384.835917 -180.16307) (xy 384.818016 -180.075335) (xy 384.809026 -179.986245)
			(xy 384.808476 -179.941474) (xy 384.809046 -179.896705) (xy 384.818054 -179.80762) (xy 384.835957 -179.719889)
			(xy 384.862574 -179.634397) (xy 384.879596 -179.592986) (xy 384.883178 -179.5834) (xy 384.883168 -179.562953)
			(xy 384.879596 -179.553362) (xy 384.862549 -179.51196) (xy 384.835917 -179.42647) (xy 384.818016 -179.338735)
			(xy 384.809026 -179.249645) (xy 384.808476 -179.204874) (xy 384.808874 -179.163758) (xy 384.816464 -179.081876)
			(xy 384.831576 -179.001043) (xy 384.854083 -178.92195) (xy 384.883791 -178.845272) (xy 384.920448 -178.771661)
			(xy 384.963741 -178.701747) (xy 385.013299 -178.636125) (xy 385.068701 -178.575356) (xy 385.129474 -178.519958)
			(xy 385.195099 -178.470404) (xy 385.265017 -178.427117) (xy 385.33863 -178.390466) (xy 385.415311 -178.360763)
			(xy 385.494406 -178.338262) (xy 385.575239 -178.323155) (xy 385.657122 -178.315571) (xy 385.698238 -178.315112)
			(xy 385.739848 -178.315619) (xy 385.822703 -178.323389) (xy 385.904472 -178.338859) (xy 385.98444 -178.361894)
			(xy 386.061909 -178.392291) (xy 386.136202 -178.429786) (xy 386.171694 -178.45151) (xy 386.180833 -178.45667)
			(xy 386.201549 -178.459885) (xy 386.221823 -178.454554) (xy 386.230368 -178.448462) (xy 386.264029 -178.422514)
			(xy 386.335417 -178.376384) (xy 386.410882 -178.337278) (xy 386.489734 -178.305551) (xy 386.571254 -178.281495)
			(xy 386.654698 -178.265328) (xy 386.739304 -178.257198) (xy 386.781802 -178.256692) (xy 386.822915 -178.257211)
			(xy 386.90479 -178.264798) (xy 386.985616 -178.279906) (xy 387.064703 -178.302408) (xy 387.141376 -178.33211)
			(xy 387.214982 -178.368761) (xy 387.284893 -178.412046) (xy 387.350512 -178.461597) (xy 387.411278 -178.51699)
			(xy 387.466675 -178.577755) (xy 387.516229 -178.643371) (xy 387.559518 -178.713279) (xy 387.596172 -178.786883)
			(xy 387.625878 -178.863555) (xy 387.648384 -178.942641) (xy 387.663496 -179.023466) (xy 387.671087 -179.105341)
			(xy 387.671564 -179.146454) (xy 387.671001 -179.191224) (xy 387.661991 -179.280309) (xy 387.644086 -179.36804)
			(xy 387.617467 -179.453531) (xy 387.600444 -179.494942) (xy 387.596906 -179.50454) (xy 387.596889 -179.524976)
			(xy 387.600444 -179.534566) (xy 387.617449 -179.575917) (xy 387.64406 -179.661279) (xy 387.661966 -179.748882)
			(xy 387.670988 -179.837839) (xy 387.671564 -179.882546) (xy 387.671564 -179.883562) (xy 387.67131 -179.894992)
			(xy 387.697789 -179.900938) (xy 387.750024 -179.915681) (xy 387.775704 -179.924456) (xy 387.783901 -179.92697)
			(xy 387.801035 -179.92697) (xy 387.809232 -179.924456) (xy 387.844448 -179.912493) (xy 387.916451 -179.893839)
			(xy 387.989772 -179.881331) (xy 388.063888 -179.875058) (xy 388.101078 -179.874672) (xy 388.138267 -179.875069)
			(xy 388.21238 -179.881356) (xy 388.2857 -179.893864) (xy 388.357706 -179.912502) (xy 388.392924 -179.924456)
			(xy 388.401121 -179.92697) (xy 388.418255 -179.92697) (xy 388.426452 -179.924456) (xy 388.461666 -179.912487)
			(xy 388.53367 -179.893835) (xy 388.606992 -179.881329) (xy 388.681108 -179.875057) (xy 388.718298 -179.874672)
			(xy 388.760238 -179.875067) (xy 388.843739 -179.88304) (xy 388.926104 -179.898915) (xy 389.006586 -179.922546)
			(xy 389.084458 -179.953722) (xy 389.159014 -179.992158) (xy 389.229579 -180.037507) (xy 389.295514 -180.089358)
			(xy 389.356221 -180.147242) (xy 389.411151 -180.210635) (xy 389.459807 -180.278962) (xy 389.501747 -180.351604)
			(xy 389.536592 -180.427905) (xy 389.564027 -180.507172) (xy 389.583802 -180.588688) (xy 389.59574 -180.671715)
			(xy 389.599731 -180.7555) (xy 389.59574 -180.839285) (xy 389.583802 -180.922312) (xy 389.564027 -181.003828)
			(xy 389.536592 -181.083095) (xy 389.501747 -181.159396) (xy 389.459807 -181.232038) (xy 389.411151 -181.300365)
			(xy 389.356221 -181.363758) (xy 389.295514 -181.421642) (xy 389.229579 -181.473493) (xy 389.159014 -181.518842)
			(xy 389.084458 -181.557278) (xy 389.006586 -181.588454) (xy 388.926104 -181.612085) (xy 388.843739 -181.62796)
			(xy 388.760238 -181.635933) (xy 388.718298 -181.636416) (xy 388.681108 -181.636027) (xy 388.606996 -181.629737)
			(xy 388.533676 -181.617227) (xy 388.46167 -181.598587) (xy 388.426452 -181.586632) (xy 388.418255 -181.584118)
			(xy 388.401121 -181.584118) (xy 388.392924 -181.586632) (xy 388.365208 -181.596078) (xy 388.308773 -181.611711)
			(xy 388.280148 -181.617874) (xy 388.270401 -181.620348) (xy 388.25379 -181.63165) (xy 388.242792 -181.648464)
			(xy 388.240524 -181.65826) (xy 388.231054 -181.705587) (xy 388.203179 -181.797995) (xy 388.184898 -181.842664)
			(xy 388.181281 -181.852235) (xy 388.18114 -181.872676) (xy 388.184644 -181.882288) (xy 388.201684 -181.923659)
			(xy 388.228298 -182.009088) (xy 388.246197 -182.096758) (xy 388.255201 -182.185783) (xy 388.255764 -182.230522)
			(xy 388.255764 -182.230776) (xy 388.25526 -182.273124) (xy 388.247209 -182.357438) (xy 388.23118 -182.440604)
			(xy 388.207319 -182.521871) (xy 388.17584 -182.600501) (xy 388.137029 -182.675782) (xy 388.091239 -182.747034)
			(xy 388.038883 -182.81361) (xy 387.980435 -182.874908) (xy 387.916425 -182.930373) (xy 387.847433 -182.979502)
			(xy 387.774083 -183.021851) (xy 387.69704 -183.057035) (xy 387.617001 -183.084737) (xy 387.534692 -183.104705)
			(xy 387.450857 -183.116758) (xy 387.366256 -183.120789) (xy 387.281655 -183.116758) (xy 387.19782 -183.104705)
			(xy 387.115511 -183.084737) (xy 387.035472 -183.057035) (xy 386.958429 -183.021851) (xy 386.885079 -182.979502)
			(xy 386.816087 -182.930373) (xy 386.752077 -182.874908) (xy 386.693629 -182.81361) (xy 386.641273 -182.747034)
			(xy 386.595483 -182.675782) (xy 386.556672 -182.600501) (xy 386.525193 -182.521871) (xy 386.501332 -182.440604)
			(xy 386.485303 -182.357438) (xy 386.477252 -182.273124) (xy 386.476748 -182.230776) (xy 386.476748 -182.230522)
			(xy 386.477311 -182.185784) (xy 386.486329 -182.096762) (xy 386.504235 -182.009095) (xy 386.53085 -181.923667)
			(xy 386.547868 -181.882288) (xy 386.551445 -181.872701) (xy 386.551436 -181.852255) (xy 386.547868 -181.842664)
			(xy 386.53084 -181.801254) (xy 386.504206 -181.715766) (xy 386.4863 -181.628034) (xy 386.477302 -181.538946)
			(xy 386.476748 -181.494176) (xy 386.477087 -181.458262) (xy 386.482864 -181.386666) (xy 386.494395 -181.315769)
			(xy 386.502656 -181.280816) (xy 386.504356 -181.272508) (xy 386.502799 -181.255633) (xy 386.495808 -181.240195)
			(xy 386.49021 -181.233826) (xy 386.44957 -181.1909) (xy 386.43941 -181.193186) (xy 386.430637 -181.195432)
			(xy 386.415405 -181.205208) (xy 386.409692 -181.212236) (xy 386.384552 -181.244927) (xy 386.329156 -181.306026)
			(xy 386.268343 -181.361734) (xy 386.202634 -181.411575) (xy 386.132593 -181.455119) (xy 386.058822 -181.491993)
			(xy 385.981955 -181.521881) (xy 385.902652 -181.544524) (xy 385.821593 -181.55973) (xy 385.739474 -181.567368)
			(xy 385.698238 -181.567836) (xy 385.657123 -181.567365) (xy 385.575243 -181.559781) (xy 385.494413 -181.544674)
			(xy 385.415321 -181.522173) (xy 385.338643 -181.49247) (xy 385.265033 -181.455819) (xy 385.195119 -181.412532)
			(xy 385.129497 -181.362978) (xy 385.068728 -181.30758) (xy 385.01333 -181.246812) (xy 384.963775 -181.181191)
			(xy 384.920487 -181.111277) (xy 384.883834 -181.037668) (xy 384.854131 -180.96099) (xy 384.831629 -180.881899)
			(xy 384.81652 -180.801068) (xy 384.808935 -180.719189) (xy 384.808476 -180.678074) (xy 381.264843 -180.678074)
			(xy 381.268531 -180.7555) (xy 381.26454 -180.839285) (xy 381.252602 -180.922312) (xy 381.232827 -181.003828)
			(xy 381.205392 -181.083095) (xy 381.170547 -181.159396) (xy 381.128607 -181.232038) (xy 381.079951 -181.300365)
			(xy 381.025021 -181.363758) (xy 380.964314 -181.421642) (xy 380.898379 -181.473493) (xy 380.827814 -181.518842)
			(xy 380.753258 -181.557278) (xy 380.675386 -181.588454) (xy 380.594904 -181.612085) (xy 380.512539 -181.62796)
			(xy 380.429038 -181.635933) (xy 380.387098 -181.636416) (xy 380.349908 -181.636027) (xy 380.275796 -181.629737)
			(xy 380.202476 -181.617227) (xy 380.13047 -181.598587) (xy 380.095252 -181.586632) (xy 380.087055 -181.584118)
			(xy 380.069921 -181.584118) (xy 380.061724 -181.586632) (xy 380.034008 -181.596078) (xy 379.977573 -181.611711)
			(xy 379.948948 -181.617874) (xy 379.939201 -181.620348) (xy 379.92259 -181.63165) (xy 379.911592 -181.648464)
			(xy 379.909324 -181.65826) (xy 379.899854 -181.705587) (xy 379.871979 -181.797995) (xy 379.853698 -181.842664)
			(xy 379.850081 -181.852235) (xy 379.84994 -181.872676) (xy 379.853444 -181.882288) (xy 379.870484 -181.923659)
			(xy 379.897098 -182.009088) (xy 379.914997 -182.096758) (xy 379.924001 -182.185783) (xy 379.924564 -182.230522)
			(xy 379.924564 -182.230776) (xy 379.92406 -182.273124) (xy 379.916009 -182.357438) (xy 379.89998 -182.440604)
			(xy 379.876119 -182.521871) (xy 379.84464 -182.600501) (xy 379.805829 -182.675782) (xy 379.760039 -182.747034)
			(xy 379.707683 -182.81361) (xy 379.649235 -182.874908) (xy 379.585225 -182.930373) (xy 379.516233 -182.979502)
			(xy 379.442883 -183.021851) (xy 379.36584 -183.057035) (xy 379.285801 -183.084737) (xy 379.203492 -183.104705)
			(xy 379.119657 -183.116758) (xy 379.035056 -183.120789) (xy 378.950455 -183.116758) (xy 378.86662 -183.104705)
			(xy 378.784311 -183.084737) (xy 378.704272 -183.057035) (xy 378.627229 -183.021851) (xy 378.553879 -182.979502)
			(xy 378.484887 -182.930373) (xy 378.420877 -182.874908) (xy 378.362429 -182.81361) (xy 378.310073 -182.747034)
			(xy 378.264283 -182.675782) (xy 378.225472 -182.600501) (xy 378.193993 -182.521871) (xy 378.170132 -182.440604)
			(xy 378.154103 -182.357438) (xy 378.146052 -182.273124) (xy 378.145548 -182.230776) (xy 378.145548 -182.230522)
			(xy 378.146111 -182.185784) (xy 378.155129 -182.096762) (xy 378.173035 -182.009095) (xy 378.19965 -181.923667)
			(xy 378.216668 -181.882288) (xy 378.220245 -181.872701) (xy 378.220236 -181.852255) (xy 378.216668 -181.842664)
			(xy 378.19964 -181.801254) (xy 378.173006 -181.715766) (xy 378.1551 -181.628034) (xy 378.146102 -181.538946)
			(xy 378.145548 -181.494176) (xy 378.145887 -181.458262) (xy 378.151664 -181.386666) (xy 378.163195 -181.315769)
			(xy 378.171456 -181.280816) (xy 378.173156 -181.272508) (xy 378.171599 -181.255633) (xy 378.164608 -181.240195)
			(xy 378.15901 -181.233826) (xy 378.11837 -181.1909) (xy 378.10821 -181.193186) (xy 378.099437 -181.195432)
			(xy 378.084205 -181.205208) (xy 378.078492 -181.212236) (xy 378.053352 -181.244927) (xy 377.997956 -181.306026)
			(xy 377.937143 -181.361734) (xy 377.871434 -181.411575) (xy 377.801393 -181.455119) (xy 377.727622 -181.491993)
			(xy 377.650755 -181.521881) (xy 377.571452 -181.544524) (xy 377.490393 -181.55973) (xy 377.408274 -181.567368)
			(xy 377.367038 -181.567836) (xy 377.325923 -181.567365) (xy 377.244043 -181.559781) (xy 377.163213 -181.544674)
			(xy 377.084121 -181.522173) (xy 377.007443 -181.49247) (xy 376.933833 -181.455819) (xy 376.863919 -181.412532)
			(xy 376.798297 -181.362978) (xy 376.737528 -181.30758) (xy 376.68213 -181.246812) (xy 376.632575 -181.181191)
			(xy 376.589287 -181.111277) (xy 376.552634 -181.037668) (xy 376.522931 -180.96099) (xy 376.500429 -180.881899)
			(xy 376.48532 -180.801068) (xy 376.477735 -180.719189) (xy 376.477276 -180.678074) (xy 372.848069 -180.678074)
			(xy 372.8541 -180.720015) (xy 372.858091 -180.8038) (xy 372.8541 -180.887585) (xy 372.842162 -180.97061)
			(xy 372.822386 -181.052125) (xy 372.794951 -181.131391) (xy 372.760105 -181.20769) (xy 372.718163 -181.280331)
			(xy 372.669507 -181.348656) (xy 372.614576 -181.412047) (xy 372.553868 -181.469929) (xy 372.487932 -181.521778)
			(xy 372.417367 -181.567124) (xy 372.34281 -181.605557) (xy 372.264938 -181.636728) (xy 372.184455 -181.660356)
			(xy 372.10209 -181.676226) (xy 372.01859 -181.684195) (xy 371.97665 -181.684676) (xy 371.939461 -181.684274)
			(xy 371.865348 -181.677988) (xy 371.792028 -181.665482) (xy 371.720022 -181.646845) (xy 371.684804 -181.634892)
			(xy 371.676607 -181.632378) (xy 371.659473 -181.632378) (xy 371.651276 -181.634892) (xy 371.611916 -181.648156)
			(xy 371.531285 -181.66812) (xy 371.449135 -181.680416) (xy 371.40769 -181.683152) (xy 371.397889 -181.684131)
			(xy 371.380113 -181.692579) (xy 371.36683 -181.707102) (xy 371.362986 -181.716172) (xy 371.348 -181.753764)
			(xy 371.344428 -181.763418) (xy 371.344429 -181.783987) (xy 371.348 -181.793642) (xy 371.365038 -181.835014)
			(xy 371.391656 -181.920442) (xy 371.409557 -182.008112) (xy 371.418559 -182.097137) (xy 371.41912 -182.141876)
			(xy 371.418616 -182.184237) (xy 371.410563 -182.268574) (xy 371.394529 -182.351764) (xy 371.370661 -182.433054)
			(xy 371.339173 -182.511706) (xy 371.300351 -182.587009) (xy 371.254548 -182.658281) (xy 371.202177 -182.724877)
			(xy 371.143712 -182.786192) (xy 371.079684 -182.841673) (xy 371.010672 -182.890816) (xy 370.937302 -182.933176)
			(xy 370.860237 -182.968371) (xy 370.780175 -182.99608) (xy 370.697842 -183.016054) (xy 370.613983 -183.028111)
			(xy 370.529358 -183.032143) (xy 370.444733 -183.028111) (xy 370.360874 -183.016054) (xy 370.278541 -182.99608)
			(xy 370.198479 -182.968371) (xy 370.121414 -182.933176) (xy 370.048044 -182.890816) (xy 369.979032 -182.841673)
			(xy 369.915004 -182.786192) (xy 369.856539 -182.724877) (xy 369.804168 -182.658281) (xy 369.758365 -182.587009)
			(xy 369.719543 -182.511706) (xy 369.688055 -182.433054) (xy 369.664187 -182.351764) (xy 369.648153 -182.268574)
			(xy 369.6401 -182.184237) (xy 369.639596 -182.141876) (xy 369.640165 -182.097107) (xy 369.649173 -182.008022)
			(xy 369.667076 -181.92029) (xy 369.693694 -181.834799) (xy 369.710716 -181.793388) (xy 369.714296 -181.783802)
			(xy 369.714287 -181.763355) (xy 369.710716 -181.753764) (xy 369.693665 -181.712364) (xy 369.667035 -181.626872)
			(xy 369.649135 -181.539137) (xy 369.640146 -181.450047) (xy 369.639596 -181.405276) (xy 369.639771 -181.384669)
			(xy 369.641804 -181.343504) (xy 369.64366 -181.32298) (xy 369.644023 -181.312283) (xy 369.63707 -181.292069)
			(xy 369.630198 -181.283864) (xy 369.57127 -181.22011) (xy 369.551204 -181.211728) (xy 369.540282 -181.211982)
			(xy 369.523264 -181.212236) (xy 369.522756 -181.212236) (xy 369.481649 -181.211766) (xy 369.399787 -181.204159)
			(xy 369.318976 -181.189032) (xy 369.239905 -181.166515) (xy 369.163248 -181.136799) (xy 369.08966 -181.100138)
			(xy 369.019768 -181.056844) (xy 368.954168 -181.007287) (xy 368.893419 -180.95189) (xy 368.83804 -180.891125)
			(xy 368.788503 -180.825509) (xy 368.745231 -180.755604) (xy 368.708592 -180.682005) (xy 368.678899 -180.605339)
			(xy 368.656406 -180.526261) (xy 368.641304 -180.445446) (xy 368.633721 -180.363581) (xy 368.633248 -180.322474)
			(xy 368.6337 -180.283493) (xy 368.640575 -180.205835) (xy 368.654226 -180.129077) (xy 368.663982 -180.091334)
			(xy 368.666037 -180.082278) (xy 368.664208 -180.063813) (xy 368.655908 -180.047218) (xy 368.642231 -180.034679)
			(xy 368.633756 -180.030882) (xy 368.596114 -180.015301) (xy 368.523548 -179.97826) (xy 368.454673 -179.934739)
			(xy 368.390066 -179.885102) (xy 368.330268 -179.829767) (xy 368.27578 -179.769195) (xy 368.227059 -179.703896)
			(xy 368.184512 -179.634415) (xy 368.148496 -179.561335) (xy 368.119314 -179.485268) (xy 368.097208 -179.406851)
			(xy 368.082365 -179.326741) (xy 368.074909 -179.24561) (xy 368.074448 -179.204874) (xy 97.329275 -179.204874)
			(xy 97.326783 -179.229509) (xy 97.308877 -179.31724) (xy 97.282259 -179.402731) (xy 97.265236 -179.444142)
			(xy 97.261699 -179.453741) (xy 97.261682 -179.474176) (xy 97.265236 -179.483766) (xy 97.28224 -179.525117)
			(xy 97.308851 -179.610479) (xy 97.326758 -179.698082) (xy 97.33578 -179.787039) (xy 97.336356 -179.831746)
			(xy 97.336356 -179.832762) (xy 97.336102 -179.844192) (xy 97.362581 -179.850138) (xy 97.414816 -179.864881)
			(xy 97.440496 -179.873656) (xy 97.448693 -179.87617) (xy 97.465827 -179.87617) (xy 97.474024 -179.873656)
			(xy 97.50924 -179.861695) (xy 97.581244 -179.843041) (xy 97.654565 -179.830532) (xy 97.72868 -179.824259)
			(xy 97.76587 -179.823872) (xy 97.803059 -179.824271) (xy 97.877172 -179.830558) (xy 97.950492 -179.843065)
			(xy 98.022498 -179.861703) (xy 98.057716 -179.873656) (xy 98.065913 -179.87617) (xy 98.083047 -179.87617)
			(xy 98.091244 -179.873656) (xy 98.126459 -179.861689) (xy 98.198462 -179.843037) (xy 98.271784 -179.83053)
			(xy 98.3459 -179.824258) (xy 98.38309 -179.823872) (xy 98.42503 -179.824267) (xy 98.508532 -179.832239)
			(xy 98.590897 -179.848113) (xy 98.67138 -179.871744) (xy 98.749253 -179.902919) (xy 98.82381 -179.941355)
			(xy 98.894375 -179.986704) (xy 98.96031 -180.038555) (xy 99.021018 -180.096439) (xy 99.075949 -180.159832)
			(xy 99.124605 -180.228159) (xy 99.166546 -180.300802) (xy 99.201391 -180.377103) (xy 99.228826 -180.45637)
			(xy 99.248602 -180.537887) (xy 99.26054 -180.620914) (xy 99.264531 -180.7047) (xy 99.26054 -180.788486)
			(xy 99.248602 -180.871513) (xy 99.228826 -180.95303) (xy 99.201391 -181.032297) (xy 99.166546 -181.108598)
			(xy 99.124605 -181.181241) (xy 99.075949 -181.249568) (xy 99.021018 -181.312961) (xy 98.96031 -181.370845)
			(xy 98.894375 -181.422696) (xy 98.82381 -181.468045) (xy 98.749253 -181.506481) (xy 98.67138 -181.537656)
			(xy 98.590897 -181.561287) (xy 98.508532 -181.577161) (xy 98.42503 -181.585133) (xy 98.38309 -181.585616)
			(xy 98.3459 -181.585229) (xy 98.271787 -181.578939) (xy 98.198468 -181.566428) (xy 98.126462 -181.547787)
			(xy 98.091244 -181.535832) (xy 98.083047 -181.533318) (xy 98.065913 -181.533318) (xy 98.057716 -181.535832)
			(xy 98.015534 -181.549982) (xy 97.929009 -181.570726) (xy 97.884996 -181.577234) (xy 97.875031 -181.57898)
			(xy 97.85759 -181.589205) (xy 97.845466 -181.605383) (xy 97.842578 -181.61508) (xy 97.833805 -181.648299)
			(xy 97.811813 -181.713397) (xy 97.798636 -181.745128) (xy 97.79505 -181.754712) (xy 97.795064 -181.775161)
			(xy 97.798636 -181.784752) (xy 97.815664 -181.826127) (xy 97.842281 -181.911555) (xy 97.860184 -181.999224)
			(xy 97.869191 -182.088247) (xy 97.869756 -182.132986) (xy 97.869756 -182.13324) (xy 97.869252 -182.175588)
			(xy 97.861201 -182.259902) (xy 97.845172 -182.343068) (xy 97.821311 -182.424335) (xy 97.789832 -182.502965)
			(xy 97.751021 -182.578246) (xy 97.705231 -182.649498) (xy 97.652875 -182.716074) (xy 97.594427 -182.777372)
			(xy 97.530417 -182.832837) (xy 97.461425 -182.881966) (xy 97.388075 -182.924315) (xy 97.311032 -182.959499)
			(xy 97.230993 -182.987201) (xy 97.148684 -183.007169) (xy 97.064849 -183.019222) (xy 96.980248 -183.023253)
			(xy 96.895647 -183.019222) (xy 96.811812 -183.007169) (xy 96.729503 -182.987201) (xy 96.649464 -182.959499)
			(xy 96.572421 -182.924315) (xy 96.499071 -182.881966) (xy 96.430079 -182.832837) (xy 96.366069 -182.777372)
			(xy 96.307621 -182.716074) (xy 96.255265 -182.649498) (xy 96.209475 -182.578246) (xy 96.170664 -182.502965)
			(xy 96.139185 -182.424335) (xy 96.115324 -182.343068) (xy 96.099295 -182.259902) (xy 96.091244 -182.175588)
			(xy 96.09074 -182.13324) (xy 96.09074 -182.132986) (xy 96.091318 -182.088248) (xy 96.10033 -181.999226)
			(xy 96.118232 -181.911559) (xy 96.144843 -181.826131) (xy 96.16186 -181.784752) (xy 96.165401 -181.775154)
			(xy 96.165416 -181.754718) (xy 96.16186 -181.745128) (xy 96.144825 -181.703755) (xy 96.11821 -181.618327)
			(xy 96.100309 -181.530657) (xy 96.091304 -181.441633) (xy 96.09074 -181.396894) (xy 96.09074 -181.395878)
			(xy 96.090368 -181.38632) (xy 96.083332 -181.368547) (xy 96.070254 -181.354605) (xy 96.061784 -181.350158)
			(xy 95.965264 -181.304184) (xy 95.936308 -181.30774) (xy 95.924878 -181.317138) (xy 95.890853 -181.344159)
			(xy 95.818459 -181.392213) (xy 95.741724 -181.43298) (xy 95.66138 -181.466069) (xy 95.578192 -181.491168)
			(xy 95.492953 -181.508035) (xy 95.406476 -181.51651) (xy 95.36303 -181.517036) (xy 95.321915 -181.516573)
			(xy 95.240035 -181.508988) (xy 95.159204 -181.49388) (xy 95.080113 -181.471379) (xy 95.003435 -181.441675)
			(xy 94.929825 -181.405023) (xy 94.859911 -181.361735) (xy 94.794289 -181.312181) (xy 94.73352 -181.256783)
			(xy 94.678122 -181.196014) (xy 94.628567 -181.130393) (xy 94.585279 -181.060479) (xy 94.548626 -180.986869)
			(xy 94.518922 -180.910191) (xy 94.49642 -180.831099) (xy 94.481312 -180.750269) (xy 94.473727 -180.668389)
			(xy 94.473268 -180.627274) (xy 90.869375 -180.627274) (xy 90.872244 -180.6875) (xy 90.868253 -180.771275)
			(xy 90.856317 -180.854292) (xy 90.836544 -180.935798) (xy 90.809114 -181.015056) (xy 90.774274 -181.091347)
			(xy 90.732339 -181.163981) (xy 90.683691 -181.2323) (xy 90.628768 -181.295686) (xy 90.56807 -181.353564)
			(xy 90.502144 -181.405411) (xy 90.431589 -181.450756) (xy 90.357043 -181.489189) (xy 90.279182 -181.520363)
			(xy 90.198709 -181.543994) (xy 90.116355 -181.559869) (xy 90.032865 -181.567844) (xy 89.99093 -181.568344)
			(xy 89.953741 -181.567944) (xy 89.879628 -181.561657) (xy 89.806308 -181.54915) (xy 89.734302 -181.530513)
			(xy 89.699084 -181.51856) (xy 89.690887 -181.516046) (xy 89.673753 -181.516046) (xy 89.665556 -181.51856)
			(xy 89.630433 -181.5305) (xy 89.558617 -181.54912) (xy 89.485489 -181.561626) (xy 89.411567 -181.56793)
			(xy 89.374472 -181.568344) (xy 89.372948 -181.568344) (xy 89.365328 -181.56809) (xy 89.355809 -181.6135)
			(xy 89.328579 -181.702202) (xy 89.310972 -181.745128) (xy 89.307384 -181.754712) (xy 89.307399 -181.775161)
			(xy 89.310972 -181.784752) (xy 89.327996 -181.826163) (xy 89.354632 -181.91165) (xy 89.37254 -181.999382)
			(xy 89.381538 -182.08847) (xy 89.382092 -182.13324) (xy 89.381588 -182.175601) (xy 89.373535 -182.259938)
			(xy 89.357501 -182.343128) (xy 89.333633 -182.424418) (xy 89.302145 -182.50307) (xy 89.263323 -182.578373)
			(xy 89.21752 -182.649645) (xy 89.165149 -182.716241) (xy 89.106684 -182.777556) (xy 89.042656 -182.833037)
			(xy 88.973644 -182.88218) (xy 88.900274 -182.92454) (xy 88.823209 -182.959735) (xy 88.743147 -182.987444)
			(xy 88.660814 -183.007418) (xy 88.576955 -183.019475) (xy 88.49233 -183.023507) (xy 88.407705 -183.019475)
			(xy 88.323846 -183.007418) (xy 88.241513 -182.987444) (xy 88.161451 -182.959735) (xy 88.084386 -182.92454)
			(xy 88.011016 -182.88218) (xy 87.942004 -182.833037) (xy 87.877976 -182.777556) (xy 87.819511 -182.716241)
			(xy 87.76714 -182.649645) (xy 87.721337 -182.578373) (xy 87.682515 -182.50307) (xy 87.651027 -182.424418)
			(xy 87.627159 -182.343128) (xy 87.611125 -182.259938) (xy 87.603072 -182.175601) (xy 87.602568 -182.13324)
			(xy 87.603127 -182.08847) (xy 87.612138 -181.999385) (xy 87.630045 -181.911654) (xy 87.656665 -181.826163)
			(xy 87.673688 -181.784752) (xy 87.677232 -181.775155) (xy 87.677247 -181.754718) (xy 87.673688 -181.745128)
			(xy 87.65877 -181.708939) (xy 87.634581 -181.634489) (xy 87.617023 -181.558202) (xy 87.606232 -181.480668)
			(xy 87.603838 -181.441598) (xy 87.602983 -181.432757) (xy 87.596138 -181.416387) (xy 87.58411 -181.403342)
			(xy 87.576406 -181.398926) (xy 87.486236 -181.352444) (xy 87.459312 -181.35346) (xy 87.447882 -181.360826)
			(xy 87.412209 -181.38294) (xy 87.337447 -181.421096) (xy 87.259425 -181.452047) (xy 87.178837 -181.475518)
			(xy 87.096397 -181.4913) (xy 87.012838 -181.499253) (xy 86.97087 -181.499764) (xy 86.929755 -181.499316)
			(xy 86.847877 -181.491726) (xy 86.767048 -181.476614) (xy 86.687959 -181.454109) (xy 86.611283 -181.424402)
			(xy 86.537675 -181.387748) (xy 86.467763 -181.344458) (xy 86.402144 -181.294902) (xy 86.341376 -181.239504)
			(xy 86.28598 -181.178735) (xy 86.236426 -181.113114) (xy 86.193139 -181.043201) (xy 86.156487 -180.969592)
			(xy 86.126782 -180.892915) (xy 86.10428 -180.813824) (xy 86.08917 -180.732995) (xy 86.081583 -180.651117)
			(xy 86.081108 -180.610002) (xy 82.462267 -180.610002) (xy 82.47114 -180.671714) (xy 82.475131 -180.7555)
			(xy 82.47114 -180.839286) (xy 82.459202 -180.922313) (xy 82.439426 -181.00383) (xy 82.411991 -181.083097)
			(xy 82.377146 -181.159398) (xy 82.335205 -181.232041) (xy 82.286549 -181.300368) (xy 82.231618 -181.363761)
			(xy 82.17091 -181.421645) (xy 82.104975 -181.473496) (xy 82.03441 -181.518845) (xy 81.959853 -181.557281)
			(xy 81.88198 -181.588456) (xy 81.801497 -181.612087) (xy 81.719132 -181.627961) (xy 81.63563 -181.635933)
			(xy 81.59369 -181.636416) (xy 81.5565 -181.636029) (xy 81.482387 -181.629739) (xy 81.409068 -181.617228)
			(xy 81.337062 -181.598587) (xy 81.301844 -181.586632) (xy 81.293647 -181.584118) (xy 81.276513 -181.584118)
			(xy 81.268316 -181.586632) (xy 81.24011 -181.596266) (xy 81.182657 -181.612157) (xy 81.153508 -181.618382)
			(xy 81.143879 -181.620834) (xy 81.127394 -181.631892) (xy 81.116335 -181.648377) (xy 81.113884 -181.658006)
			(xy 81.104396 -181.702491) (xy 81.07755 -181.789404) (xy 81.06029 -181.831488) (xy 81.056659 -181.841055)
			(xy 81.056528 -181.861499) (xy 81.060036 -181.871112) (xy 81.077051 -181.912492) (xy 81.103672 -181.997918)
			(xy 81.121578 -182.085585) (xy 81.130589 -182.174608) (xy 81.131156 -182.219346) (xy 81.131156 -182.2196)
			(xy 81.130652 -182.261948) (xy 81.122601 -182.346262) (xy 81.106572 -182.429428) (xy 81.082711 -182.510695)
			(xy 81.051232 -182.589325) (xy 81.012421 -182.664606) (xy 80.966631 -182.735858) (xy 80.914275 -182.802434)
			(xy 80.855827 -182.863732) (xy 80.791817 -182.919197) (xy 80.722825 -182.968326) (xy 80.649475 -183.010675)
			(xy 80.572432 -183.045859) (xy 80.492393 -183.073561) (xy 80.410084 -183.093529) (xy 80.326249 -183.105582)
			(xy 80.241648 -183.109613) (xy 80.157047 -183.105582) (xy 80.073212 -183.093529) (xy 79.990903 -183.073561)
			(xy 79.910864 -183.045859) (xy 79.833821 -183.010675) (xy 79.760471 -182.968326) (xy 79.691479 -182.919197)
			(xy 79.627469 -182.863732) (xy 79.569021 -182.802434) (xy 79.516665 -182.735858) (xy 79.470875 -182.664606)
			(xy 79.432064 -182.589325) (xy 79.400585 -182.510695) (xy 79.376724 -182.429428) (xy 79.360695 -182.346262)
			(xy 79.352644 -182.261948) (xy 79.35214 -182.2196) (xy 79.35214 -182.219346) (xy 79.352704 -182.174608)
			(xy 79.361721 -182.085586) (xy 79.379627 -181.997918) (xy 79.406242 -181.912491) (xy 79.42326 -181.871112)
			(xy 79.426824 -181.861521) (xy 79.426824 -181.841079) (xy 79.42326 -181.831488) (xy 79.406239 -181.790076)
			(xy 79.379604 -181.704589) (xy 79.361695 -181.616857) (xy 79.352696 -181.52777) (xy 79.35214 -181.483)
			(xy 79.352578 -181.44277) (xy 79.359832 -181.362636) (xy 79.366618 -181.32298) (xy 79.366618 -181.322726)
			(xy 79.368105 -181.310829) (xy 79.361202 -181.287898) (xy 79.35341 -181.278784) (xy 79.287878 -181.210204)
			(xy 79.265018 -181.202076) (xy 79.252826 -181.203854) (xy 79.222877 -181.207733) (xy 79.162627 -181.21193)
			(xy 79.13243 -181.212236) (xy 79.091315 -181.211773) (xy 79.009435 -181.204188) (xy 78.928604 -181.18908)
			(xy 78.849513 -181.166579) (xy 78.772835 -181.136875) (xy 78.699225 -181.100223) (xy 78.629311 -181.056935)
			(xy 78.563689 -181.007381) (xy 78.50292 -180.951983) (xy 78.447522 -180.891214) (xy 78.397967 -180.825593)
			(xy 78.354679 -180.755679) (xy 78.318026 -180.682069) (xy 78.288322 -180.605391) (xy 78.26582 -180.526299)
			(xy 78.250712 -180.445469) (xy 78.243127 -180.363589) (xy 78.242668 -180.322474) (xy 78.243154 -180.279736)
			(xy 78.251333 -180.194653) (xy 78.267631 -180.110746) (xy 78.2919 -180.028788) (xy 78.307438 -179.988972)
			(xy 78.311043 -179.978929) (xy 78.310391 -179.957622) (xy 78.306168 -179.947824) (xy 78.289089 -179.911553)
			(xy 78.260784 -179.836541) (xy 78.239347 -179.759284) (xy 78.224953 -179.680411) (xy 78.217719 -179.600562)
			(xy 78.217268 -179.560474) (xy 78.21746 -179.533866) (xy 78.220637 -179.480744) (xy 78.223618 -179.454302)
			(xy 78.224368 -179.443055) (xy 78.217254 -179.421697) (xy 78.209902 -179.413154) (xy 78.180933 -179.382157)
			(xy 78.128411 -179.31552) (xy 78.082469 -179.244186) (xy 78.043525 -179.168805) (xy 78.011931 -179.090059)
			(xy 77.987974 -179.008663) (xy 77.971872 -178.925358) (xy 77.963772 -178.840898) (xy 77.963268 -178.798474)
			(xy 9.44304 -178.798474) (xy 9.441677 -178.801459) (xy 9.412211 -178.847309) (xy 9.37652 -178.8885)
			(xy 9.335329 -178.924191) (xy 9.289479 -178.953657) (xy 9.239902 -178.976299) (xy 9.187607 -178.991654)
			(xy 9.133659 -178.99941) (xy 9.079157 -178.99941) (xy 9.025209 -178.991654) (xy 8.972914 -178.976299)
			(xy 8.923337 -178.953657) (xy 8.877487 -178.924191) (xy 8.836296 -178.8885) (xy 8.800605 -178.847309)
			(xy 8.771139 -178.801459) (xy 8.748497 -178.751882) (xy 8.733142 -178.699587) (xy 8.725386 -178.645639)
			(xy 8.7249 -178.618388) (xy 2.509012 -178.618388) (xy 2.509012 -190.64715) (xy 220.414866 -190.64715)
			(xy 220.414866 -190.59265) (xy 220.422621 -190.538705) (xy 220.437974 -190.486413) (xy 220.460612 -190.436837)
			(xy 220.490075 -190.390988) (xy 220.525762 -190.349798) (xy 220.566948 -190.314105) (xy 220.612793 -190.284636)
			(xy 220.662366 -190.261992) (xy 220.714656 -190.246632) (xy 220.7686 -190.238869) (xy 220.79585 -190.23838)
			(xy 221.78645 -190.23838) (xy 221.813704 -190.238864) (xy 221.867659 -190.246615) (xy 221.919961 -190.261966)
			(xy 221.969546 -190.284605) (xy 222.015404 -190.314071) (xy 222.056601 -190.349763) (xy 222.092299 -190.390956)
			(xy 222.121771 -190.43681) (xy 222.144416 -190.486392) (xy 222.159775 -190.538692) (xy 222.167533 -190.592646)
			(xy 222.167533 -190.647154) (xy 222.159775 -190.701108) (xy 222.144416 -190.753408) (xy 222.121771 -190.80299)
			(xy 222.092299 -190.848844) (xy 222.056601 -190.890037) (xy 222.015404 -190.925729) (xy 221.969546 -190.955195)
			(xy 221.919961 -190.977834) (xy 221.867659 -190.993185) (xy 221.813704 -191.000936) (xy 221.78645 -191.001396)
			(xy 220.79585 -191.001396) (xy 220.7686 -191.000931) (xy 220.714656 -190.993168) (xy 220.662366 -190.977808)
			(xy 220.612793 -190.955164) (xy 220.566948 -190.925695) (xy 220.525762 -190.890002) (xy 220.490075 -190.848812)
			(xy 220.460612 -190.802963) (xy 220.437974 -190.753387) (xy 220.422621 -190.701095) (xy 220.414866 -190.64715)
			(xy 2.509012 -190.64715) (xy 2.509012 -194.296284) (xy 255.545336 -194.296284) (xy 255.545336 -193.432684)
			(xy 255.545822 -193.405415) (xy 255.553584 -193.351431) (xy 255.568949 -193.299101) (xy 255.591606 -193.249491)
			(xy 255.621092 -193.20361) (xy 255.656807 -193.162393) (xy 255.698024 -193.126678) (xy 255.743905 -193.097192)
			(xy 255.793515 -193.074535) (xy 255.845845 -193.05917) (xy 255.899829 -193.051408) (xy 255.954367 -193.051408)
			(xy 256.008351 -193.05917) (xy 256.060681 -193.074535) (xy 256.110291 -193.097192) (xy 256.156172 -193.126678)
			(xy 256.197389 -193.162393) (xy 256.233104 -193.20361) (xy 256.26259 -193.249491) (xy 256.285247 -193.299101)
			(xy 256.300612 -193.351431) (xy 256.308374 -193.405415) (xy 256.30886 -193.432684) (xy 256.30886 -194.296284)
			(xy 256.308374 -194.323553) (xy 256.300612 -194.377537) (xy 256.285247 -194.429867) (xy 256.26259 -194.479477)
			(xy 256.25414 -194.492626) (xy 260.09346 -194.492626) (xy 260.09346 -193.502026) (xy 260.093946 -193.474757)
			(xy 260.101708 -193.420773) (xy 260.117073 -193.368443) (xy 260.13973 -193.318833) (xy 260.169216 -193.272952)
			(xy 260.204931 -193.231735) (xy 260.246148 -193.19602) (xy 260.292029 -193.166534) (xy 260.341639 -193.143877)
			(xy 260.393969 -193.128512) (xy 260.447953 -193.12075) (xy 260.502491 -193.12075) (xy 260.556475 -193.128512)
			(xy 260.608805 -193.143877) (xy 260.658415 -193.166534) (xy 260.704296 -193.19602) (xy 260.745513 -193.231735)
			(xy 260.781228 -193.272952) (xy 260.810714 -193.318833) (xy 260.833371 -193.368443) (xy 260.848736 -193.420773)
			(xy 260.856498 -193.474757) (xy 260.856984 -193.502026) (xy 260.856984 -194.492626) (xy 260.856498 -194.519895)
			(xy 260.848736 -194.573879) (xy 260.833371 -194.626209) (xy 260.810714 -194.675819) (xy 260.781228 -194.7217)
			(xy 260.745513 -194.762917) (xy 260.704296 -194.798632) (xy 260.658415 -194.828118) (xy 260.608805 -194.850775)
			(xy 260.556475 -194.86614) (xy 260.502491 -194.873902) (xy 260.447953 -194.873902) (xy 260.393969 -194.86614)
			(xy 260.341639 -194.850775) (xy 260.292029 -194.828118) (xy 260.246148 -194.798632) (xy 260.204931 -194.762917)
			(xy 260.169216 -194.7217) (xy 260.13973 -194.675819) (xy 260.117073 -194.626209) (xy 260.101708 -194.573879)
			(xy 260.093946 -194.519895) (xy 260.09346 -194.492626) (xy 256.25414 -194.492626) (xy 256.233104 -194.525358)
			(xy 256.197389 -194.566575) (xy 256.156172 -194.60229) (xy 256.110291 -194.631776) (xy 256.060681 -194.654433)
			(xy 256.008351 -194.669798) (xy 255.954367 -194.67756) (xy 255.899829 -194.67756) (xy 255.845845 -194.669798)
			(xy 255.793515 -194.654433) (xy 255.743905 -194.631776) (xy 255.698024 -194.60229) (xy 255.656807 -194.566575)
			(xy 255.621092 -194.525358) (xy 255.591606 -194.479477) (xy 255.568949 -194.429867) (xy 255.553584 -194.377537)
			(xy 255.545822 -194.323553) (xy 255.545336 -194.296284) (xy 2.509012 -194.296284) (xy 2.509012 -197.07352)
			(xy 255.545336 -197.07352) (xy 255.545336 -196.20992) (xy 255.545822 -196.182651) (xy 255.553584 -196.128667)
			(xy 255.568949 -196.076337) (xy 255.591606 -196.026727) (xy 255.621092 -195.980846) (xy 255.656807 -195.939629)
			(xy 255.698024 -195.903914) (xy 255.743905 -195.874428) (xy 255.793515 -195.851771) (xy 255.845845 -195.836406)
			(xy 255.899829 -195.828644) (xy 255.954367 -195.828644) (xy 256.008351 -195.836406) (xy 256.060681 -195.851771)
			(xy 256.110291 -195.874428) (xy 256.156172 -195.903914) (xy 256.197389 -195.939629) (xy 256.233104 -195.980846)
			(xy 256.26259 -196.026727) (xy 256.285247 -196.076337) (xy 256.300612 -196.128667) (xy 256.308374 -196.182651)
			(xy 256.30886 -196.20992) (xy 256.30886 -197.07352) (xy 256.308374 -197.100789) (xy 256.300612 -197.154773)
			(xy 256.285247 -197.207103) (xy 256.26259 -197.256713) (xy 256.233104 -197.302594) (xy 256.197389 -197.343811)
			(xy 256.156172 -197.379526) (xy 256.110291 -197.409012) (xy 256.060681 -197.431669) (xy 256.008351 -197.447034)
			(xy 255.954367 -197.454796) (xy 255.899829 -197.454796) (xy 255.845845 -197.447034) (xy 255.793515 -197.431669)
			(xy 255.743905 -197.409012) (xy 255.698024 -197.379526) (xy 255.656807 -197.343811) (xy 255.621092 -197.302594)
			(xy 255.591606 -197.256713) (xy 255.568949 -197.207103) (xy 255.553584 -197.154773) (xy 255.545822 -197.100789)
			(xy 255.545336 -197.07352) (xy 2.509012 -197.07352) (xy 2.509012 -199.868028) (xy 255.545336 -199.868028)
			(xy 255.545336 -199.004428) (xy 255.545822 -198.977159) (xy 255.553584 -198.923175) (xy 255.568949 -198.870845)
			(xy 255.591606 -198.821235) (xy 255.621092 -198.775354) (xy 255.656807 -198.734137) (xy 255.698024 -198.698422)
			(xy 255.743905 -198.668936) (xy 255.793515 -198.646279) (xy 255.845845 -198.630914) (xy 255.899829 -198.623152)
			(xy 255.954367 -198.623152) (xy 256.008351 -198.630914) (xy 256.060681 -198.646279) (xy 256.110291 -198.668936)
			(xy 256.156172 -198.698422) (xy 256.197389 -198.734137) (xy 256.233104 -198.775354) (xy 256.26259 -198.821235)
			(xy 256.285247 -198.870845) (xy 256.300612 -198.923175) (xy 256.308374 -198.977159) (xy 256.30886 -199.004428)
			(xy 256.30886 -199.868028) (xy 256.308374 -199.895297) (xy 256.300612 -199.949281) (xy 256.285247 -200.001611)
			(xy 256.26259 -200.051221) (xy 256.233104 -200.097102) (xy 256.197389 -200.138319) (xy 256.156172 -200.174034)
			(xy 256.110291 -200.20352) (xy 256.060681 -200.226177) (xy 256.008351 -200.241542) (xy 255.954367 -200.249304)
			(xy 255.899829 -200.249304) (xy 255.845845 -200.241542) (xy 255.793515 -200.226177) (xy 255.743905 -200.20352)
			(xy 255.698024 -200.174034) (xy 255.656807 -200.138319) (xy 255.621092 -200.097102) (xy 255.591606 -200.051221)
			(xy 255.568949 -200.001611) (xy 255.553584 -199.949281) (xy 255.545822 -199.895297) (xy 255.545336 -199.868028)
			(xy 2.509012 -199.868028) (xy 2.509012 -202.662536) (xy 255.545336 -202.662536) (xy 255.545336 -201.798936)
			(xy 255.545822 -201.771667) (xy 255.553584 -201.717683) (xy 255.568949 -201.665353) (xy 255.591606 -201.615743)
			(xy 255.621092 -201.569862) (xy 255.656807 -201.528645) (xy 255.698024 -201.49293) (xy 255.743905 -201.463444)
			(xy 255.793515 -201.440787) (xy 255.845845 -201.425422) (xy 255.899829 -201.41766) (xy 255.954367 -201.41766)
			(xy 256.008351 -201.425422) (xy 256.060681 -201.440787) (xy 256.110291 -201.463444) (xy 256.156172 -201.49293)
			(xy 256.197389 -201.528645) (xy 256.233104 -201.569862) (xy 256.26259 -201.615743) (xy 256.285247 -201.665353)
			(xy 256.300612 -201.717683) (xy 256.308374 -201.771667) (xy 256.30886 -201.798936) (xy 256.30886 -202.662536)
			(xy 256.308374 -202.689805) (xy 256.300612 -202.743789) (xy 256.285247 -202.796119) (xy 256.26259 -202.845729)
			(xy 256.233104 -202.89161) (xy 256.197389 -202.932827) (xy 256.156172 -202.968542) (xy 256.110291 -202.998028)
			(xy 256.060681 -203.020685) (xy 256.008351 -203.03605) (xy 255.954367 -203.043812) (xy 255.899829 -203.043812)
			(xy 255.845845 -203.03605) (xy 255.793515 -203.020685) (xy 255.743905 -202.998028) (xy 255.698024 -202.968542)
			(xy 255.656807 -202.932827) (xy 255.621092 -202.89161) (xy 255.591606 -202.845729) (xy 255.568949 -202.796119)
			(xy 255.553584 -202.743789) (xy 255.545822 -202.689805) (xy 255.545336 -202.662536) (xy 2.509012 -202.662536)
			(xy 2.509012 -205.439772) (xy 255.545336 -205.439772) (xy 255.545336 -204.576172) (xy 255.545822 -204.548903)
			(xy 255.553584 -204.494919) (xy 255.568949 -204.442589) (xy 255.591606 -204.392979) (xy 255.621092 -204.347098)
			(xy 255.656807 -204.305881) (xy 255.698024 -204.270166) (xy 255.743905 -204.24068) (xy 255.793515 -204.218023)
			(xy 255.845845 -204.202658) (xy 255.899829 -204.194896) (xy 255.954367 -204.194896) (xy 256.008351 -204.202658)
			(xy 256.060681 -204.218023) (xy 256.110291 -204.24068) (xy 256.156172 -204.270166) (xy 256.197389 -204.305881)
			(xy 256.233104 -204.347098) (xy 256.26259 -204.392979) (xy 256.285247 -204.442589) (xy 256.300612 -204.494919)
			(xy 256.308374 -204.548903) (xy 256.30886 -204.576172) (xy 256.30886 -205.439772) (xy 256.308374 -205.467041)
			(xy 256.300612 -205.521025) (xy 256.285247 -205.573355) (xy 256.26259 -205.622965) (xy 256.233104 -205.668846)
			(xy 256.197389 -205.710063) (xy 256.156172 -205.745778) (xy 256.110291 -205.775264) (xy 256.060681 -205.797921)
			(xy 256.008351 -205.813286) (xy 255.954367 -205.821048) (xy 255.899829 -205.821048) (xy 255.845845 -205.813286)
			(xy 255.793515 -205.797921) (xy 255.743905 -205.775264) (xy 255.698024 -205.745778) (xy 255.656807 -205.710063)
			(xy 255.621092 -205.668846) (xy 255.591606 -205.622965) (xy 255.568949 -205.573355) (xy 255.553584 -205.521025)
			(xy 255.545822 -205.467041) (xy 255.545336 -205.439772) (xy 2.509012 -205.439772) (xy 2.509012 -207.499458)
			(xy 97.408492 -207.499458) (xy 97.408492 -206.635858) (xy 97.408978 -206.608589) (xy 97.41674 -206.554605)
			(xy 97.432105 -206.502275) (xy 97.454762 -206.452665) (xy 97.484248 -206.406784) (xy 97.519963 -206.365567)
			(xy 97.56118 -206.329852) (xy 97.607061 -206.300366) (xy 97.656671 -206.277709) (xy 97.709001 -206.262344)
			(xy 97.762985 -206.254582) (xy 97.817523 -206.254582) (xy 97.871507 -206.262344) (xy 97.923837 -206.277709)
			(xy 97.973447 -206.300366) (xy 98.019328 -206.329852) (xy 98.060545 -206.365567) (xy 98.09626 -206.406784)
			(xy 98.125746 -206.452665) (xy 98.148403 -206.502275) (xy 98.163768 -206.554605) (xy 98.17153 -206.608589)
			(xy 98.172016 -206.635858) (xy 98.172016 -207.499458) (xy 98.17153 -207.526727) (xy 98.163768 -207.580711)
			(xy 98.148403 -207.633041) (xy 98.125746 -207.682651) (xy 98.09626 -207.728532) (xy 98.060545 -207.769749)
			(xy 98.019328 -207.805464) (xy 97.973447 -207.83495) (xy 97.923837 -207.857607) (xy 97.871507 -207.872972)
			(xy 97.817523 -207.880734) (xy 97.762985 -207.880734) (xy 97.709001 -207.872972) (xy 97.656671 -207.857607)
			(xy 97.607061 -207.83495) (xy 97.56118 -207.805464) (xy 97.519963 -207.769749) (xy 97.484248 -207.728532)
			(xy 97.454762 -207.682651) (xy 97.432105 -207.633041) (xy 97.41674 -207.580711) (xy 97.408978 -207.526727)
			(xy 97.408492 -207.499458) (xy 2.509012 -207.499458) (xy 2.509012 -209.023458) (xy 94.105984 -209.023458)
			(xy 94.105984 -208.159858) (xy 94.10647 -208.132589) (xy 94.114232 -208.078605) (xy 94.129597 -208.026275)
			(xy 94.152254 -207.976665) (xy 94.18174 -207.930784) (xy 94.217455 -207.889567) (xy 94.258672 -207.853852)
			(xy 94.304553 -207.824366) (xy 94.354163 -207.801709) (xy 94.406493 -207.786344) (xy 94.460477 -207.778582)
			(xy 94.515015 -207.778582) (xy 94.568999 -207.786344) (xy 94.621329 -207.801709) (xy 94.670939 -207.824366)
			(xy 94.71682 -207.853852) (xy 94.758037 -207.889567) (xy 94.793752 -207.930784) (xy 94.823238 -207.976665)
			(xy 94.845895 -208.026275) (xy 94.86126 -208.078605) (xy 94.869022 -208.132589) (xy 94.869508 -208.159858)
			(xy 94.869508 -208.217008) (xy 255.545336 -208.217008) (xy 255.545336 -207.353408) (xy 255.545822 -207.326139)
			(xy 255.553584 -207.272155) (xy 255.568949 -207.219825) (xy 255.591606 -207.170215) (xy 255.621092 -207.124334)
			(xy 255.656807 -207.083117) (xy 255.698024 -207.047402) (xy 255.743905 -207.017916) (xy 255.793515 -206.995259)
			(xy 255.845845 -206.979894) (xy 255.899829 -206.972132) (xy 255.954367 -206.972132) (xy 256.008351 -206.979894)
			(xy 256.060681 -206.995259) (xy 256.110291 -207.017916) (xy 256.156172 -207.047402) (xy 256.197389 -207.083117)
			(xy 256.233104 -207.124334) (xy 256.26259 -207.170215) (xy 256.285247 -207.219825) (xy 256.300612 -207.272155)
			(xy 256.308374 -207.326139) (xy 256.30886 -207.353408) (xy 256.30886 -208.217008) (xy 256.308374 -208.244277)
			(xy 256.300612 -208.298261) (xy 256.285247 -208.350591) (xy 256.26259 -208.400201) (xy 256.233104 -208.446082)
			(xy 256.197389 -208.487299) (xy 256.156172 -208.523014) (xy 256.110291 -208.5525) (xy 256.060681 -208.575157)
			(xy 256.008351 -208.590522) (xy 255.954367 -208.598284) (xy 255.899829 -208.598284) (xy 255.845845 -208.590522)
			(xy 255.793515 -208.575157) (xy 255.743905 -208.5525) (xy 255.698024 -208.523014) (xy 255.656807 -208.487299)
			(xy 255.621092 -208.446082) (xy 255.591606 -208.400201) (xy 255.568949 -208.350591) (xy 255.553584 -208.298261)
			(xy 255.545822 -208.244277) (xy 255.545336 -208.217008) (xy 94.869508 -208.217008) (xy 94.869508 -209.023458)
			(xy 94.869022 -209.050727) (xy 94.86126 -209.104711) (xy 94.845895 -209.157041) (xy 94.823238 -209.206651)
			(xy 94.793752 -209.252532) (xy 94.758037 -209.293749) (xy 94.71682 -209.329464) (xy 94.670939 -209.35895)
			(xy 94.621329 -209.381607) (xy 94.568999 -209.396972) (xy 94.515015 -209.404734) (xy 94.460477 -209.404734)
			(xy 94.406493 -209.396972) (xy 94.354163 -209.381607) (xy 94.304553 -209.35895) (xy 94.258672 -209.329464)
			(xy 94.217455 -209.293749) (xy 94.18174 -209.252532) (xy 94.152254 -209.206651) (xy 94.129597 -209.157041)
			(xy 94.114232 -209.104711) (xy 94.10647 -209.050727) (xy 94.105984 -209.023458) (xy 2.509012 -209.023458)
			(xy 2.509012 -212.98027) (xy 78.81214 -212.98027) (xy 78.81617 -212.837935) (xy 78.828245 -212.696055)
			(xy 78.848328 -212.555087) (xy 78.876355 -212.41548) (xy 78.912235 -212.277682) (xy 78.955853 -212.142135)
			(xy 79.00707 -212.009273) (xy 79.065721 -211.879521) (xy 79.131619 -211.753295) (xy 79.204553 -211.630999)
			(xy 79.28429 -211.513026) (xy 79.370572 -211.399753) (xy 79.463125 -211.291542) (xy 79.561652 -211.188741)
			(xy 79.665837 -211.091679) (xy 79.775346 -211.000667) (xy 79.889829 -210.915995) (xy 80.008919 -210.837937)
			(xy 80.132234 -210.766741) (xy 80.25938 -210.702635) (xy 80.389949 -210.645826) (xy 80.523523 -210.596494)
			(xy 80.659674 -210.554798) (xy 80.797965 -210.520872) (xy 80.937955 -210.494824) (xy 81.079194 -210.476738)
			(xy 81.22123 -210.466671) (xy 81.363608 -210.464656) (xy 81.505872 -210.470699) (xy 81.647566 -210.484781)
			(xy 81.788236 -210.506857) (xy 81.927433 -210.536857) (xy 82.064709 -210.574683) (xy 82.199625 -210.620215)
			(xy 82.331749 -210.673306) (xy 82.460658 -210.733788) (xy 82.585939 -210.801466) (xy 82.70719 -210.876123)
			(xy 82.824023 -210.957521) (xy 82.936064 -211.045398) (xy 83.042954 -211.139473) (xy 83.144351 -211.239445)
			(xy 83.239929 -211.344993) (xy 83.329383 -211.455779) (xy 83.412425 -211.571448) (xy 83.488791 -211.691631)
			(xy 83.558235 -211.815941) (xy 83.620535 -211.943982) (xy 83.675491 -212.075341) (xy 83.69835 -212.140038)
			(xy 94.106492 -212.140038) (xy 94.106492 -211.276438) (xy 94.106978 -211.249187) (xy 94.114734 -211.195239)
			(xy 94.130089 -211.142944) (xy 94.152731 -211.093367) (xy 94.182197 -211.047517) (xy 94.217888 -211.006326)
			(xy 94.259079 -210.970635) (xy 94.304929 -210.941169) (xy 94.354506 -210.918527) (xy 94.406801 -210.903172)
			(xy 94.460749 -210.895416) (xy 94.515251 -210.895416) (xy 94.569199 -210.903172) (xy 94.621494 -210.918527)
			(xy 94.671071 -210.941169) (xy 94.716921 -210.970635) (xy 94.758112 -211.006326) (xy 94.793803 -211.047517)
			(xy 94.823269 -211.093367) (xy 94.845911 -211.142944) (xy 94.861266 -211.195239) (xy 94.869022 -211.249187)
			(xy 94.869508 -211.276438) (xy 94.869508 -212.140038) (xy 94.869022 -212.167289) (xy 94.861266 -212.221237)
			(xy 94.845911 -212.273532) (xy 94.823269 -212.323109) (xy 94.793803 -212.368959) (xy 94.758112 -212.41015)
			(xy 94.716921 -212.445841) (xy 94.671071 -212.475307) (xy 94.621494 -212.497949) (xy 94.569199 -212.513304)
			(xy 94.515251 -212.52106) (xy 94.460749 -212.52106) (xy 94.406801 -212.513304) (xy 94.354506 -212.497949)
			(xy 94.304929 -212.475307) (xy 94.259079 -212.445841) (xy 94.217888 -212.41015) (xy 94.182197 -212.368959)
			(xy 94.152731 -212.323109) (xy 94.130089 -212.273532) (xy 94.114734 -212.221237) (xy 94.106978 -212.167289)
			(xy 94.106492 -212.140038) (xy 83.69835 -212.140038) (xy 83.722928 -212.2096) (xy 83.762692 -212.346327)
			(xy 83.794658 -212.485085) (xy 83.818723 -212.625429) (xy 83.834809 -212.76691) (xy 83.842864 -212.909074)
			(xy 83.843368 -212.98027) (xy 140.011408 -212.98027) (xy 140.015438 -212.837906) (xy 140.027516 -212.695998)
			(xy 140.047604 -212.555001) (xy 140.075636 -212.415366) (xy 140.111523 -212.27754) (xy 140.15515 -212.141966)
			(xy 140.206377 -212.009077) (xy 140.26504 -211.879298) (xy 140.330952 -211.753047) (xy 140.403901 -211.630727)
			(xy 140.483653 -211.51273) (xy 140.569953 -211.399434) (xy 140.662525 -211.291201) (xy 140.761071 -211.188379)
			(xy 140.865277 -211.091298) (xy 140.974809 -211.000267) (xy 141.089315 -210.915579) (xy 141.208429 -210.837504)
			(xy 141.331769 -210.766294) (xy 141.45894 -210.702175) (xy 141.589536 -210.645354) (xy 141.723136 -210.596013)
			(xy 141.859315 -210.554308) (xy 141.997634 -210.520375) (xy 142.137652 -210.494322) (xy 142.278919 -210.476232)
			(xy 142.420984 -210.466163) (xy 142.563391 -210.464148) (xy 142.705684 -210.470192) (xy 142.847406 -210.484278)
			(xy 142.988105 -210.506358) (xy 143.12733 -210.536363) (xy 143.264634 -210.574197) (xy 143.399577 -210.619738)
			(xy 143.531728 -210.672841) (xy 143.660663 -210.733335) (xy 143.785969 -210.801026) (xy 143.907245 -210.875699)
			(xy 144.024101 -210.957113) (xy 144.093464 -211.011516) (xy 255.545336 -211.011516) (xy 255.545336 -210.147916)
			(xy 255.545822 -210.120647) (xy 255.553584 -210.066663) (xy 255.568949 -210.014333) (xy 255.591606 -209.964723)
			(xy 255.621092 -209.918842) (xy 255.656807 -209.877625) (xy 255.698024 -209.84191) (xy 255.743905 -209.812424)
			(xy 255.793515 -209.789767) (xy 255.845845 -209.774402) (xy 255.899829 -209.76664) (xy 255.954367 -209.76664)
			(xy 256.008351 -209.774402) (xy 256.060681 -209.789767) (xy 256.110291 -209.812424) (xy 256.156172 -209.84191)
			(xy 256.197389 -209.877625) (xy 256.233104 -209.918842) (xy 256.26259 -209.964723) (xy 256.285247 -210.014333)
			(xy 256.300612 -210.066663) (xy 256.308374 -210.120647) (xy 256.30886 -210.147916) (xy 256.30886 -211.011516)
			(xy 256.308374 -211.038785) (xy 256.300612 -211.092769) (xy 256.285247 -211.145099) (xy 256.26259 -211.194709)
			(xy 256.233104 -211.24059) (xy 256.197389 -211.281807) (xy 256.156172 -211.317522) (xy 256.110291 -211.347008)
			(xy 256.060681 -211.369665) (xy 256.008351 -211.38503) (xy 255.954367 -211.392792) (xy 255.899829 -211.392792)
			(xy 255.845845 -211.38503) (xy 255.793515 -211.369665) (xy 255.743905 -211.347008) (xy 255.698024 -211.317522)
			(xy 255.656807 -211.281807) (xy 255.621092 -211.24059) (xy 255.591606 -211.194709) (xy 255.568949 -211.145099)
			(xy 255.553584 -211.092769) (xy 255.545822 -211.038785) (xy 255.545336 -211.011516) (xy 144.093464 -211.011516)
			(xy 144.136165 -211.045007) (xy 144.243077 -211.139101) (xy 144.344494 -211.239093) (xy 144.440091 -211.344662)
			(xy 144.529563 -211.455471) (xy 144.612622 -211.571164) (xy 144.689003 -211.691371) (xy 144.758461 -211.815706)
			(xy 144.820774 -211.943772) (xy 144.875741 -212.075159) (xy 144.923187 -212.209444) (xy 144.96296 -212.346199)
			(xy 144.994932 -212.484985) (xy 145.019002 -212.625357) (xy 145.035091 -212.766867) (xy 145.043148 -212.909059)
			(xy 145.043652 -212.98027) (xy 145.043148 -213.051481) (xy 145.035091 -213.193673) (xy 145.019002 -213.335183)
			(xy 144.994932 -213.475555) (xy 144.96296 -213.614341) (xy 144.923187 -213.751096) (xy 144.90378 -213.806024)
			(xy 255.545336 -213.806024) (xy 255.545336 -212.942424) (xy 255.545822 -212.915155) (xy 255.553584 -212.861171)
			(xy 255.568949 -212.808841) (xy 255.591606 -212.759231) (xy 255.621092 -212.71335) (xy 255.656807 -212.672133)
			(xy 255.698024 -212.636418) (xy 255.743905 -212.606932) (xy 255.793515 -212.584275) (xy 255.845845 -212.56891)
			(xy 255.899829 -212.561148) (xy 255.954367 -212.561148) (xy 256.008351 -212.56891) (xy 256.060681 -212.584275)
			(xy 256.110291 -212.606932) (xy 256.156172 -212.636418) (xy 256.197389 -212.672133) (xy 256.233104 -212.71335)
			(xy 256.26259 -212.759231) (xy 256.285247 -212.808841) (xy 256.300612 -212.861171) (xy 256.308374 -212.915155)
			(xy 256.30886 -212.942424) (xy 256.30886 -212.980016) (xy 326.752208 -212.980016) (xy 326.756238 -212.837681)
			(xy 326.768313 -212.695801) (xy 326.788396 -212.554833) (xy 326.816423 -212.415226) (xy 326.852303 -212.277428)
			(xy 326.895921 -212.141881) (xy 326.947138 -212.009019) (xy 327.005789 -211.879267) (xy 327.071687 -211.753041)
			(xy 327.144621 -211.630745) (xy 327.224358 -211.512772) (xy 327.31064 -211.399499) (xy 327.403193 -211.291288)
			(xy 327.50172 -211.188487) (xy 327.605905 -211.091425) (xy 327.715414 -211.000413) (xy 327.829897 -210.915741)
			(xy 327.948987 -210.837683) (xy 328.072302 -210.766487) (xy 328.199448 -210.702381) (xy 328.330017 -210.645572)
			(xy 328.463591 -210.59624) (xy 328.599742 -210.554544) (xy 328.738033 -210.520618) (xy 328.878023 -210.49457)
			(xy 329.019262 -210.476484) (xy 329.161298 -210.466417) (xy 329.303676 -210.464402) (xy 329.44594 -210.470445)
			(xy 329.587634 -210.484527) (xy 329.728304 -210.506603) (xy 329.867501 -210.536603) (xy 330.004777 -210.574429)
			(xy 330.139693 -210.619961) (xy 330.271817 -210.673052) (xy 330.400726 -210.733534) (xy 330.526007 -210.801212)
			(xy 330.647258 -210.875869) (xy 330.764091 -210.957267) (xy 330.876132 -211.045144) (xy 330.983022 -211.139219)
			(xy 331.084419 -211.239191) (xy 331.179997 -211.344739) (xy 331.269451 -211.455525) (xy 331.352493 -211.571194)
			(xy 331.428859 -211.691377) (xy 331.498303 -211.815687) (xy 331.560603 -211.943728) (xy 331.615559 -212.075087)
			(xy 331.662996 -212.209346) (xy 331.70276 -212.346073) (xy 331.734726 -212.484831) (xy 331.758791 -212.625175)
			(xy 331.774877 -212.766656) (xy 331.782932 -212.90882) (xy 331.783436 -212.980016) (xy 387.951476 -212.980016)
			(xy 387.955506 -212.837652) (xy 387.967584 -212.695744) (xy 387.987672 -212.554747) (xy 388.015704 -212.415112)
			(xy 388.051591 -212.277286) (xy 388.095218 -212.141712) (xy 388.146445 -212.008823) (xy 388.205108 -211.879044)
			(xy 388.27102 -211.752793) (xy 388.343969 -211.630473) (xy 388.423721 -211.512476) (xy 388.510021 -211.39918)
			(xy 388.602593 -211.290947) (xy 388.701139 -211.188125) (xy 388.805345 -211.091044) (xy 388.914877 -211.000013)
			(xy 389.029383 -210.915325) (xy 389.148497 -210.83725) (xy 389.271837 -210.76604) (xy 389.399008 -210.701921)
			(xy 389.529604 -210.6451) (xy 389.663204 -210.595759) (xy 389.799383 -210.554054) (xy 389.937702 -210.520121)
			(xy 390.07772 -210.494068) (xy 390.218987 -210.475978) (xy 390.361052 -210.465909) (xy 390.503459 -210.463894)
			(xy 390.645752 -210.469938) (xy 390.787474 -210.484024) (xy 390.928173 -210.506104) (xy 391.067398 -210.536109)
			(xy 391.204702 -210.573943) (xy 391.339645 -210.619484) (xy 391.471796 -210.672587) (xy 391.600731 -210.733081)
			(xy 391.726037 -210.800772) (xy 391.847313 -210.875445) (xy 391.964169 -210.956859) (xy 392.076233 -211.044753)
			(xy 392.183145 -211.138847) (xy 392.284562 -211.238839) (xy 392.380159 -211.344408) (xy 392.469631 -211.455217)
			(xy 392.55269 -211.57091) (xy 392.629071 -211.691117) (xy 392.698529 -211.815452) (xy 392.760842 -211.943518)
			(xy 392.815809 -212.074905) (xy 392.863255 -212.20919) (xy 392.903028 -212.345945) (xy 392.935 -212.484731)
			(xy 392.95907 -212.625103) (xy 392.975159 -212.766613) (xy 392.983216 -212.908805) (xy 392.98372 -212.980016)
			(xy 392.983216 -213.051227) (xy 392.975159 -213.193419) (xy 392.95907 -213.334929) (xy 392.935 -213.475301)
			(xy 392.903028 -213.614087) (xy 392.863255 -213.750842) (xy 392.815809 -213.885127) (xy 392.760842 -214.016514)
			(xy 392.698529 -214.14458) (xy 392.629071 -214.268915) (xy 392.55269 -214.389122) (xy 392.469631 -214.504815)
			(xy 392.380159 -214.615624) (xy 392.284562 -214.721193) (xy 392.183145 -214.821185) (xy 392.076233 -214.915279)
			(xy 391.964169 -215.003173) (xy 391.847313 -215.084587) (xy 391.726037 -215.15926) (xy 391.600731 -215.226951)
			(xy 391.471796 -215.287445) (xy 391.339645 -215.340548) (xy 391.204702 -215.386089) (xy 391.067398 -215.423923)
			(xy 390.928173 -215.453928) (xy 390.787474 -215.476008) (xy 390.645752 -215.490094) (xy 390.503459 -215.496138)
			(xy 390.361052 -215.494123) (xy 390.218987 -215.484054) (xy 390.07772 -215.465964) (xy 389.937702 -215.439911)
			(xy 389.799383 -215.405978) (xy 389.663204 -215.364273) (xy 389.529604 -215.314932) (xy 389.399008 -215.258111)
			(xy 389.271837 -215.193992) (xy 389.148497 -215.122782) (xy 389.029383 -215.044707) (xy 388.914877 -214.960019)
			(xy 388.805345 -214.868988) (xy 388.701139 -214.771907) (xy 388.602593 -214.669085) (xy 388.510021 -214.560852)
			(xy 388.423721 -214.447556) (xy 388.343969 -214.329559) (xy 388.27102 -214.207239) (xy 388.205108 -214.080988)
			(xy 388.146445 -213.951209) (xy 388.095218 -213.81832) (xy 388.051591 -213.682746) (xy 388.015704 -213.54492)
			(xy 387.987672 -213.405285) (xy 387.967584 -213.264288) (xy 387.955506 -213.12238) (xy 387.951476 -212.980016)
			(xy 331.783436 -212.980016) (xy 331.782932 -213.051212) (xy 331.774877 -213.193376) (xy 331.758791 -213.334857)
			(xy 331.734726 -213.475201) (xy 331.70276 -213.613959) (xy 331.662996 -213.750686) (xy 331.615559 -213.884945)
			(xy 331.560603 -214.016304) (xy 331.498303 -214.144345) (xy 331.428859 -214.268655) (xy 331.352493 -214.388838)
			(xy 331.269451 -214.504507) (xy 331.179997 -214.615293) (xy 331.084419 -214.720841) (xy 330.983022 -214.820813)
			(xy 330.876132 -214.914888) (xy 330.764091 -215.002765) (xy 330.647258 -215.084163) (xy 330.526007 -215.15882)
			(xy 330.400726 -215.226498) (xy 330.271817 -215.28698) (xy 330.139693 -215.340071) (xy 330.004777 -215.385603)
			(xy 329.867501 -215.423429) (xy 329.728304 -215.453429) (xy 329.587634 -215.475505) (xy 329.44594 -215.489587)
			(xy 329.303676 -215.49563) (xy 329.161298 -215.493615) (xy 329.019262 -215.483548) (xy 328.878023 -215.465462)
			(xy 328.738033 -215.439414) (xy 328.599742 -215.405488) (xy 328.463591 -215.363792) (xy 328.330017 -215.31446)
			(xy 328.199448 -215.257651) (xy 328.072302 -215.193545) (xy 327.948987 -215.122349) (xy 327.829897 -215.044291)
			(xy 327.715414 -214.959619) (xy 327.605905 -214.868607) (xy 327.50172 -214.771545) (xy 327.403193 -214.668744)
			(xy 327.31064 -214.560533) (xy 327.224358 -214.44726) (xy 327.144621 -214.329287) (xy 327.071687 -214.206991)
			(xy 327.005789 -214.080765) (xy 326.947138 -213.951013) (xy 326.895921 -213.818151) (xy 326.852303 -213.682604)
			(xy 326.816423 -213.544806) (xy 326.788396 -213.405199) (xy 326.768313 -213.264231) (xy 326.756238 -213.122351)
			(xy 326.752208 -212.980016) (xy 256.30886 -212.980016) (xy 256.30886 -213.806024) (xy 256.308374 -213.833293)
			(xy 256.300612 -213.887277) (xy 256.285247 -213.939607) (xy 256.26259 -213.989217) (xy 256.233104 -214.035098)
			(xy 256.197389 -214.076315) (xy 256.156172 -214.11203) (xy 256.110291 -214.141516) (xy 256.060681 -214.164173)
			(xy 256.008351 -214.179538) (xy 255.954367 -214.1873) (xy 255.899829 -214.1873) (xy 255.845845 -214.179538)
			(xy 255.793515 -214.164173) (xy 255.743905 -214.141516) (xy 255.698024 -214.11203) (xy 255.656807 -214.076315)
			(xy 255.621092 -214.035098) (xy 255.591606 -213.989217) (xy 255.568949 -213.939607) (xy 255.553584 -213.887277)
			(xy 255.545822 -213.833293) (xy 255.545336 -213.806024) (xy 144.90378 -213.806024) (xy 144.875741 -213.885381)
			(xy 144.820774 -214.016768) (xy 144.758461 -214.144834) (xy 144.689003 -214.269169) (xy 144.612622 -214.389376)
			(xy 144.529563 -214.505069) (xy 144.440091 -214.615878) (xy 144.344494 -214.721447) (xy 144.243077 -214.821439)
			(xy 144.136165 -214.915533) (xy 144.024101 -215.003427) (xy 143.907245 -215.084841) (xy 143.785969 -215.159514)
			(xy 143.660663 -215.227205) (xy 143.531728 -215.287699) (xy 143.399577 -215.340802) (xy 143.264634 -215.386343)
			(xy 143.12733 -215.424177) (xy 142.988105 -215.454182) (xy 142.847406 -215.476262) (xy 142.705684 -215.490348)
			(xy 142.563391 -215.496392) (xy 142.420984 -215.494377) (xy 142.278919 -215.484308) (xy 142.137652 -215.466218)
			(xy 141.997634 -215.440165) (xy 141.859315 -215.406232) (xy 141.723136 -215.364527) (xy 141.589536 -215.315186)
			(xy 141.45894 -215.258365) (xy 141.331769 -215.194246) (xy 141.208429 -215.123036) (xy 141.089315 -215.044961)
			(xy 140.974809 -214.960273) (xy 140.865277 -214.869242) (xy 140.761071 -214.772161) (xy 140.662525 -214.669339)
			(xy 140.569953 -214.561106) (xy 140.483653 -214.44781) (xy 140.403901 -214.329813) (xy 140.330952 -214.207493)
			(xy 140.26504 -214.081242) (xy 140.206377 -213.951463) (xy 140.15515 -213.818574) (xy 140.111523 -213.683)
			(xy 140.075636 -213.545174) (xy 140.047604 -213.405539) (xy 140.027516 -213.264542) (xy 140.015438 -213.122634)
			(xy 140.011408 -212.98027) (xy 83.843368 -212.98027) (xy 83.842864 -213.051466) (xy 83.834809 -213.19363)
			(xy 83.818723 -213.335111) (xy 83.794658 -213.475455) (xy 83.762692 -213.614213) (xy 83.722928 -213.75094)
			(xy 83.675491 -213.885199) (xy 83.620535 -214.016558) (xy 83.558235 -214.144599) (xy 83.488791 -214.268909)
			(xy 83.412425 -214.389092) (xy 83.329383 -214.504761) (xy 83.239929 -214.615547) (xy 83.144351 -214.721095)
			(xy 83.042954 -214.821067) (xy 82.936064 -214.915142) (xy 82.837488 -214.992458) (xy 94.106492 -214.992458)
			(xy 94.106492 -214.128858) (xy 94.106978 -214.101607) (xy 94.114734 -214.047659) (xy 94.130089 -213.995364)
			(xy 94.152731 -213.945787) (xy 94.182197 -213.899937) (xy 94.217888 -213.858746) (xy 94.259079 -213.823055)
			(xy 94.304929 -213.793589) (xy 94.354506 -213.770947) (xy 94.406801 -213.755592) (xy 94.460749 -213.747836)
			(xy 94.515251 -213.747836) (xy 94.569199 -213.755592) (xy 94.621494 -213.770947) (xy 94.671071 -213.793589)
			(xy 94.716921 -213.823055) (xy 94.758112 -213.858746) (xy 94.793803 -213.899937) (xy 94.823269 -213.945787)
			(xy 94.845911 -213.995364) (xy 94.861266 -214.047659) (xy 94.869022 -214.101607) (xy 94.869508 -214.128858)
			(xy 94.869508 -214.992458) (xy 94.869022 -215.019709) (xy 94.861266 -215.073657) (xy 94.845911 -215.125952)
			(xy 94.823269 -215.175529) (xy 94.793803 -215.221379) (xy 94.758112 -215.26257) (xy 94.716921 -215.298261)
			(xy 94.671071 -215.327727) (xy 94.621494 -215.350369) (xy 94.569199 -215.365724) (xy 94.515251 -215.37348)
			(xy 94.460749 -215.37348) (xy 94.406801 -215.365724) (xy 94.354506 -215.350369) (xy 94.304929 -215.327727)
			(xy 94.259079 -215.298261) (xy 94.217888 -215.26257) (xy 94.182197 -215.221379) (xy 94.152731 -215.175529)
			(xy 94.130089 -215.125952) (xy 94.114734 -215.073657) (xy 94.106978 -215.019709) (xy 94.106492 -214.992458)
			(xy 82.837488 -214.992458) (xy 82.824023 -215.003019) (xy 82.70719 -215.084417) (xy 82.585939 -215.159074)
			(xy 82.460658 -215.226752) (xy 82.331749 -215.287234) (xy 82.199625 -215.340325) (xy 82.064709 -215.385857)
			(xy 81.927433 -215.423683) (xy 81.788236 -215.453683) (xy 81.647566 -215.475759) (xy 81.505872 -215.489841)
			(xy 81.363608 -215.495884) (xy 81.22123 -215.493869) (xy 81.079194 -215.483802) (xy 80.937955 -215.465716)
			(xy 80.797965 -215.439668) (xy 80.659674 -215.405742) (xy 80.523523 -215.364046) (xy 80.389949 -215.314714)
			(xy 80.25938 -215.257905) (xy 80.132234 -215.193799) (xy 80.008919 -215.122603) (xy 79.889829 -215.044545)
			(xy 79.775346 -214.959873) (xy 79.665837 -214.868861) (xy 79.561652 -214.771799) (xy 79.463125 -214.668998)
			(xy 79.370572 -214.560787) (xy 79.28429 -214.447514) (xy 79.204553 -214.329541) (xy 79.131619 -214.207245)
			(xy 79.065721 -214.081019) (xy 79.00707 -213.951267) (xy 78.955853 -213.818405) (xy 78.912235 -213.682858)
			(xy 78.876355 -213.54506) (xy 78.848328 -213.405453) (xy 78.828245 -213.264485) (xy 78.81617 -213.122605)
			(xy 78.81214 -212.98027) (xy 2.509012 -212.98027) (xy 2.509012 -217.548574) (xy 338.152884 -217.548574)
			(xy 338.152884 -217.494026) (xy 338.160647 -217.440032) (xy 338.176017 -217.387693) (xy 338.198679 -217.338074)
			(xy 338.228172 -217.292186) (xy 338.263897 -217.250963) (xy 338.305125 -217.215244) (xy 338.351016 -217.185756)
			(xy 338.400638 -217.1631) (xy 338.452979 -217.147737) (xy 338.506973 -217.13998) (xy 338.534248 -217.13952)
			(xy 339.550248 -217.13952) (xy 339.577514 -217.140046) (xy 339.63149 -217.147813) (xy 339.683811 -217.163181)
			(xy 339.733413 -217.185839) (xy 339.779286 -217.215325) (xy 339.820495 -217.251039) (xy 339.856204 -217.292253)
			(xy 339.885684 -217.338129) (xy 339.908336 -217.387734) (xy 339.923698 -217.440057) (xy 339.931458 -217.494034)
			(xy 339.931458 -217.548566) (xy 339.923698 -217.602543) (xy 339.908336 -217.654866) (xy 339.885684 -217.704471)
			(xy 339.856204 -217.750347) (xy 339.820495 -217.791561) (xy 339.779286 -217.827275) (xy 339.733413 -217.856761)
			(xy 339.683811 -217.879419) (xy 339.63149 -217.894787) (xy 339.577514 -217.902554) (xy 339.550248 -217.903044)
			(xy 338.534248 -217.903044) (xy 338.506973 -217.90262) (xy 338.452979 -217.894863) (xy 338.400638 -217.8795)
			(xy 338.351016 -217.856844) (xy 338.305125 -217.827356) (xy 338.263897 -217.791637) (xy 338.228172 -217.750414)
			(xy 338.198679 -217.704526) (xy 338.176017 -217.654907) (xy 338.160647 -217.602568) (xy 338.152884 -217.548574)
			(xy 2.509012 -217.548574) (xy 2.509012 -219.820372) (xy 129.049982 -219.820372) (xy 129.049982 -219.765828)
			(xy 129.057745 -219.71184) (xy 129.073111 -219.659505) (xy 129.095769 -219.609891) (xy 129.125257 -219.564005)
			(xy 129.160975 -219.522783) (xy 129.202196 -219.487064) (xy 129.24808 -219.457575) (xy 129.297694 -219.434915)
			(xy 129.350028 -219.419547) (xy 129.404016 -219.411783) (xy 129.431288 -219.411296) (xy 130.447288 -219.411296)
			(xy 130.474557 -219.411843) (xy 130.528539 -219.419602) (xy 130.580867 -219.434966) (xy 130.630476 -219.45762)
			(xy 130.676357 -219.487104) (xy 130.717574 -219.522818) (xy 130.753288 -219.564034) (xy 130.782774 -219.609913)
			(xy 130.80543 -219.659522) (xy 130.820795 -219.711849) (xy 130.828557 -219.765831) (xy 130.828557 -219.820369)
			(xy 130.820795 -219.874351) (xy 130.80543 -219.926678) (xy 130.782774 -219.976287) (xy 130.753288 -220.022166)
			(xy 130.717574 -220.063382) (xy 130.676357 -220.099096) (xy 130.630476 -220.12858) (xy 130.580867 -220.151234)
			(xy 130.528539 -220.166598) (xy 130.474557 -220.174357) (xy 130.447288 -220.17482) (xy 129.431288 -220.17482)
			(xy 129.404016 -220.174417) (xy 129.350028 -220.166653) (xy 129.297694 -220.151285) (xy 129.24808 -220.128625)
			(xy 129.202196 -220.099136) (xy 129.160975 -220.063417) (xy 129.125257 -220.022195) (xy 129.095769 -219.976309)
			(xy 129.073111 -219.926695) (xy 129.057745 -219.87436) (xy 129.049982 -219.820372) (xy 2.509012 -219.820372)
			(xy 2.509012 -258.880356) (xy 67.312036 -258.880356) (xy 67.316066 -258.738021) (xy 67.328141 -258.596141)
			(xy 67.348224 -258.455173) (xy 67.376251 -258.315566) (xy 67.412131 -258.177768) (xy 67.455749 -258.042221)
			(xy 67.506966 -257.909359) (xy 67.565617 -257.779607) (xy 67.631515 -257.653381) (xy 67.704449 -257.531085)
			(xy 67.784186 -257.413112) (xy 67.870468 -257.299839) (xy 67.963021 -257.191628) (xy 68.061548 -257.088827)
			(xy 68.165733 -256.991765) (xy 68.275242 -256.900753) (xy 68.389725 -256.816081) (xy 68.508815 -256.738023)
			(xy 68.63213 -256.666827) (xy 68.759276 -256.602721) (xy 68.889845 -256.545912) (xy 69.023419 -256.49658)
			(xy 69.15957 -256.454884) (xy 69.297861 -256.420958) (xy 69.437851 -256.39491) (xy 69.57909 -256.376824)
			(xy 69.721126 -256.366757) (xy 69.863504 -256.364742) (xy 70.005768 -256.370785) (xy 70.147462 -256.384867)
			(xy 70.288132 -256.406943) (xy 70.427329 -256.436943) (xy 70.564605 -256.474769) (xy 70.699521 -256.520301)
			(xy 70.831645 -256.573392) (xy 70.960554 -256.633874) (xy 71.085835 -256.701552) (xy 71.207086 -256.776209)
			(xy 71.323919 -256.857607) (xy 71.43596 -256.945484) (xy 71.54285 -257.039559) (xy 71.644247 -257.139531)
			(xy 71.739825 -257.245079) (xy 71.829279 -257.355865) (xy 71.912321 -257.471534) (xy 71.988687 -257.591717)
			(xy 72.058131 -257.716027) (xy 72.120431 -257.844068) (xy 72.175387 -257.975427) (xy 72.222824 -258.109686)
			(xy 72.262588 -258.246413) (xy 72.294554 -258.385171) (xy 72.318619 -258.525515) (xy 72.334705 -258.666996)
			(xy 72.34276 -258.80916) (xy 72.343264 -258.880356) (xy 151.51202 -258.880356) (xy 151.51605 -258.738021)
			(xy 151.528125 -258.596141) (xy 151.548208 -258.455173) (xy 151.576235 -258.315566) (xy 151.612115 -258.177768)
			(xy 151.655733 -258.042221) (xy 151.70695 -257.909359) (xy 151.765601 -257.779607) (xy 151.831499 -257.653381)
			(xy 151.904433 -257.531085) (xy 151.98417 -257.413112) (xy 152.070452 -257.299839) (xy 152.163005 -257.191628)
			(xy 152.261532 -257.088827) (xy 152.365717 -256.991765) (xy 152.475226 -256.900753) (xy 152.589709 -256.816081)
			(xy 152.708799 -256.738023) (xy 152.832114 -256.666827) (xy 152.95926 -256.602721) (xy 153.089829 -256.545912)
			(xy 153.223403 -256.49658) (xy 153.359554 -256.454884) (xy 153.497845 -256.420958) (xy 153.637835 -256.39491)
			(xy 153.779074 -256.376824) (xy 153.92111 -256.366757) (xy 154.063488 -256.364742) (xy 154.205752 -256.370785)
			(xy 154.347446 -256.384867) (xy 154.488116 -256.406943) (xy 154.627313 -256.436943) (xy 154.764589 -256.474769)
			(xy 154.899505 -256.520301) (xy 155.031629 -256.573392) (xy 155.160538 -256.633874) (xy 155.285819 -256.701552)
			(xy 155.40707 -256.776209) (xy 155.523903 -256.857607) (xy 155.635944 -256.945484) (xy 155.742834 -257.039559)
			(xy 155.844231 -257.139531) (xy 155.939809 -257.245079) (xy 156.029263 -257.355865) (xy 156.112305 -257.471534)
			(xy 156.188671 -257.591717) (xy 156.258115 -257.716027) (xy 156.320415 -257.844068) (xy 156.375371 -257.975427)
			(xy 156.422808 -258.109686) (xy 156.462572 -258.246413) (xy 156.494538 -258.385171) (xy 156.518603 -258.525515)
			(xy 156.534689 -258.666996) (xy 156.542744 -258.80916) (xy 156.543246 -258.880102) (xy 315.252104 -258.880102)
			(xy 315.256134 -258.737767) (xy 315.268209 -258.595887) (xy 315.288292 -258.454919) (xy 315.316319 -258.315312)
			(xy 315.352199 -258.177514) (xy 315.395817 -258.041967) (xy 315.447034 -257.909105) (xy 315.505685 -257.779353)
			(xy 315.571583 -257.653127) (xy 315.644517 -257.530831) (xy 315.724254 -257.412858) (xy 315.810536 -257.299585)
			(xy 315.903089 -257.191374) (xy 316.001616 -257.088573) (xy 316.105801 -256.991511) (xy 316.21531 -256.900499)
			(xy 316.329793 -256.815827) (xy 316.448883 -256.737769) (xy 316.572198 -256.666573) (xy 316.699344 -256.602467)
			(xy 316.829913 -256.545658) (xy 316.963487 -256.496326) (xy 317.099638 -256.45463) (xy 317.237929 -256.420704)
			(xy 317.377919 -256.394656) (xy 317.519158 -256.37657) (xy 317.661194 -256.366503) (xy 317.803572 -256.364488)
			(xy 317.945836 -256.370531) (xy 318.08753 -256.384613) (xy 318.2282 -256.406689) (xy 318.367397 -256.436689)
			(xy 318.504673 -256.474515) (xy 318.639589 -256.520047) (xy 318.771713 -256.573138) (xy 318.900622 -256.63362)
			(xy 319.025903 -256.701298) (xy 319.147154 -256.775955) (xy 319.263987 -256.857353) (xy 319.376028 -256.94523)
			(xy 319.482918 -257.039305) (xy 319.584315 -257.139277) (xy 319.679893 -257.244825) (xy 319.769347 -257.355611)
			(xy 319.852389 -257.47128) (xy 319.928755 -257.591463) (xy 319.998199 -257.715773) (xy 320.060499 -257.843814)
			(xy 320.115455 -257.975173) (xy 320.162892 -258.109432) (xy 320.202656 -258.246159) (xy 320.234622 -258.384917)
			(xy 320.258687 -258.525261) (xy 320.274773 -258.666742) (xy 320.282828 -258.808906) (xy 320.283332 -258.880102)
			(xy 399.452088 -258.880102) (xy 399.456118 -258.737767) (xy 399.468193 -258.595887) (xy 399.488276 -258.454919)
			(xy 399.516303 -258.315312) (xy 399.552183 -258.177514) (xy 399.595801 -258.041967) (xy 399.647018 -257.909105)
			(xy 399.705669 -257.779353) (xy 399.771567 -257.653127) (xy 399.844501 -257.530831) (xy 399.924238 -257.412858)
			(xy 400.01052 -257.299585) (xy 400.103073 -257.191374) (xy 400.2016 -257.088573) (xy 400.305785 -256.991511)
			(xy 400.415294 -256.900499) (xy 400.529777 -256.815827) (xy 400.648867 -256.737769) (xy 400.772182 -256.666573)
			(xy 400.899328 -256.602467) (xy 401.029897 -256.545658) (xy 401.163471 -256.496326) (xy 401.299622 -256.45463)
			(xy 401.437913 -256.420704) (xy 401.577903 -256.394656) (xy 401.719142 -256.37657) (xy 401.861178 -256.366503)
			(xy 402.003556 -256.364488) (xy 402.14582 -256.370531) (xy 402.287514 -256.384613) (xy 402.428184 -256.406689)
			(xy 402.567381 -256.436689) (xy 402.704657 -256.474515) (xy 402.839573 -256.520047) (xy 402.971697 -256.573138)
			(xy 403.100606 -256.63362) (xy 403.225887 -256.701298) (xy 403.347138 -256.775955) (xy 403.463971 -256.857353)
			(xy 403.576012 -256.94523) (xy 403.682902 -257.039305) (xy 403.784299 -257.139277) (xy 403.879877 -257.244825)
			(xy 403.969331 -257.355611) (xy 404.052373 -257.47128) (xy 404.128739 -257.591463) (xy 404.198183 -257.715773)
			(xy 404.260483 -257.843814) (xy 404.315439 -257.975173) (xy 404.362876 -258.109432) (xy 404.40264 -258.246159)
			(xy 404.434606 -258.384917) (xy 404.458671 -258.525261) (xy 404.474757 -258.666742) (xy 404.482812 -258.808906)
			(xy 404.483316 -258.880102) (xy 404.482812 -258.951298) (xy 404.474757 -259.093462) (xy 404.458671 -259.234943)
			(xy 404.434606 -259.375287) (xy 404.40264 -259.514045) (xy 404.362876 -259.650772) (xy 404.315439 -259.785031)
			(xy 404.260483 -259.91639) (xy 404.198183 -260.044431) (xy 404.128739 -260.168741) (xy 404.052373 -260.288924)
			(xy 403.969331 -260.404593) (xy 403.879877 -260.515379) (xy 403.784299 -260.620927) (xy 403.682902 -260.720899)
			(xy 403.576012 -260.814974) (xy 403.463971 -260.902851) (xy 403.347138 -260.984249) (xy 403.225887 -261.058906)
			(xy 403.100606 -261.126584) (xy 402.971697 -261.187066) (xy 402.839573 -261.240157) (xy 402.704657 -261.285689)
			(xy 402.567381 -261.323515) (xy 402.428184 -261.353515) (xy 402.287514 -261.375591) (xy 402.14582 -261.389673)
			(xy 402.003556 -261.395716) (xy 401.861178 -261.393701) (xy 401.719142 -261.383634) (xy 401.577903 -261.365548)
			(xy 401.437913 -261.3395) (xy 401.299622 -261.305574) (xy 401.163471 -261.263878) (xy 401.029897 -261.214546)
			(xy 400.899328 -261.157737) (xy 400.772182 -261.093631) (xy 400.648867 -261.022435) (xy 400.529777 -260.944377)
			(xy 400.415294 -260.859705) (xy 400.305785 -260.768693) (xy 400.2016 -260.671631) (xy 400.103073 -260.56883)
			(xy 400.01052 -260.460619) (xy 399.924238 -260.347346) (xy 399.844501 -260.229373) (xy 399.771567 -260.107077)
			(xy 399.705669 -259.980851) (xy 399.647018 -259.851099) (xy 399.595801 -259.718237) (xy 399.552183 -259.58269)
			(xy 399.516303 -259.444892) (xy 399.488276 -259.305285) (xy 399.468193 -259.164317) (xy 399.456118 -259.022437)
			(xy 399.452088 -258.880102) (xy 320.283332 -258.880102) (xy 320.282828 -258.951298) (xy 320.274773 -259.093462)
			(xy 320.258687 -259.234943) (xy 320.234622 -259.375287) (xy 320.202656 -259.514045) (xy 320.162892 -259.650772)
			(xy 320.115455 -259.785031) (xy 320.060499 -259.91639) (xy 319.998199 -260.044431) (xy 319.928755 -260.168741)
			(xy 319.852389 -260.288924) (xy 319.769347 -260.404593) (xy 319.679893 -260.515379) (xy 319.584315 -260.620927)
			(xy 319.482918 -260.720899) (xy 319.376028 -260.814974) (xy 319.263987 -260.902851) (xy 319.147154 -260.984249)
			(xy 319.025903 -261.058906) (xy 318.900622 -261.126584) (xy 318.771713 -261.187066) (xy 318.639589 -261.240157)
			(xy 318.504673 -261.285689) (xy 318.367397 -261.323515) (xy 318.2282 -261.353515) (xy 318.08753 -261.375591)
			(xy 317.945836 -261.389673) (xy 317.803572 -261.395716) (xy 317.661194 -261.393701) (xy 317.519158 -261.383634)
			(xy 317.377919 -261.365548) (xy 317.237929 -261.3395) (xy 317.099638 -261.305574) (xy 316.963487 -261.263878)
			(xy 316.829913 -261.214546) (xy 316.699344 -261.157737) (xy 316.572198 -261.093631) (xy 316.448883 -261.022435)
			(xy 316.329793 -260.944377) (xy 316.21531 -260.859705) (xy 316.105801 -260.768693) (xy 316.001616 -260.671631)
			(xy 315.903089 -260.56883) (xy 315.810536 -260.460619) (xy 315.724254 -260.347346) (xy 315.644517 -260.229373)
			(xy 315.571583 -260.107077) (xy 315.505685 -259.980851) (xy 315.447034 -259.851099) (xy 315.395817 -259.718237)
			(xy 315.352199 -259.58269) (xy 315.316319 -259.444892) (xy 315.288292 -259.305285) (xy 315.268209 -259.164317)
			(xy 315.256134 -259.022437) (xy 315.252104 -258.880102) (xy 156.543246 -258.880102) (xy 156.543248 -258.880356)
			(xy 156.542744 -258.951552) (xy 156.534689 -259.093716) (xy 156.518603 -259.235197) (xy 156.494538 -259.375541)
			(xy 156.462572 -259.514299) (xy 156.422808 -259.651026) (xy 156.375371 -259.785285) (xy 156.320415 -259.916644)
			(xy 156.258115 -260.044685) (xy 156.188671 -260.168995) (xy 156.112305 -260.289178) (xy 156.029263 -260.404847)
			(xy 155.939809 -260.515633) (xy 155.844231 -260.621181) (xy 155.742834 -260.721153) (xy 155.635944 -260.815228)
			(xy 155.523903 -260.903105) (xy 155.40707 -260.984503) (xy 155.285819 -261.05916) (xy 155.160538 -261.126838)
			(xy 155.031629 -261.18732) (xy 154.899505 -261.240411) (xy 154.764589 -261.285943) (xy 154.627313 -261.323769)
			(xy 154.488116 -261.353769) (xy 154.347446 -261.375845) (xy 154.205752 -261.389927) (xy 154.063488 -261.39597)
			(xy 153.92111 -261.393955) (xy 153.779074 -261.383888) (xy 153.637835 -261.365802) (xy 153.497845 -261.339754)
			(xy 153.359554 -261.305828) (xy 153.223403 -261.264132) (xy 153.089829 -261.2148) (xy 152.95926 -261.157991)
			(xy 152.832114 -261.093885) (xy 152.708799 -261.022689) (xy 152.589709 -260.944631) (xy 152.475226 -260.859959)
			(xy 152.365717 -260.768947) (xy 152.261532 -260.671885) (xy 152.163005 -260.569084) (xy 152.070452 -260.460873)
			(xy 151.98417 -260.3476) (xy 151.904433 -260.229627) (xy 151.831499 -260.107331) (xy 151.765601 -259.981105)
			(xy 151.70695 -259.851353) (xy 151.655733 -259.718491) (xy 151.612115 -259.582944) (xy 151.576235 -259.445146)
			(xy 151.548208 -259.305539) (xy 151.528125 -259.164571) (xy 151.51605 -259.022691) (xy 151.51202 -258.880356)
			(xy 72.343264 -258.880356) (xy 72.34276 -258.951552) (xy 72.334705 -259.093716) (xy 72.318619 -259.235197)
			(xy 72.294554 -259.375541) (xy 72.262588 -259.514299) (xy 72.222824 -259.651026) (xy 72.175387 -259.785285)
			(xy 72.120431 -259.916644) (xy 72.058131 -260.044685) (xy 71.988687 -260.168995) (xy 71.912321 -260.289178)
			(xy 71.829279 -260.404847) (xy 71.739825 -260.515633) (xy 71.644247 -260.621181) (xy 71.54285 -260.721153)
			(xy 71.43596 -260.815228) (xy 71.323919 -260.903105) (xy 71.207086 -260.984503) (xy 71.085835 -261.05916)
			(xy 70.960554 -261.126838) (xy 70.831645 -261.18732) (xy 70.699521 -261.240411) (xy 70.564605 -261.285943)
			(xy 70.427329 -261.323769) (xy 70.288132 -261.353769) (xy 70.147462 -261.375845) (xy 70.005768 -261.389927)
			(xy 69.863504 -261.39597) (xy 69.721126 -261.393955) (xy 69.57909 -261.383888) (xy 69.437851 -261.365802)
			(xy 69.297861 -261.339754) (xy 69.15957 -261.305828) (xy 69.023419 -261.264132) (xy 68.889845 -261.2148)
			(xy 68.759276 -261.157991) (xy 68.63213 -261.093885) (xy 68.508815 -261.022689) (xy 68.389725 -260.944631)
			(xy 68.275242 -260.859959) (xy 68.165733 -260.768947) (xy 68.061548 -260.671885) (xy 67.963021 -260.569084)
			(xy 67.870468 -260.460873) (xy 67.784186 -260.3476) (xy 67.704449 -260.229627) (xy 67.631515 -260.107331)
			(xy 67.565617 -259.981105) (xy 67.506966 -259.851353) (xy 67.455749 -259.718491) (xy 67.412131 -259.582944)
			(xy 67.376251 -259.445146) (xy 67.348224 -259.305539) (xy 67.328141 -259.164571) (xy 67.316066 -259.022691)
			(xy 67.312036 -258.880356) (xy 2.509012 -258.880356) (xy 2.509012 -300.146974) (xy 340.219284 -300.146974)
			(xy 340.219284 -299.130974) (xy 340.21977 -299.103723) (xy 340.227526 -299.049775) (xy 340.242881 -298.99748)
			(xy 340.265523 -298.947903) (xy 340.294989 -298.902053) (xy 340.33068 -298.860862) (xy 340.371871 -298.825171)
			(xy 340.417721 -298.795705) (xy 340.467298 -298.773063) (xy 340.519593 -298.757708) (xy 340.573541 -298.749952)
			(xy 340.628043 -298.749952) (xy 340.681991 -298.757708) (xy 340.734286 -298.773063) (xy 340.783863 -298.795705)
			(xy 340.829713 -298.825171) (xy 340.870904 -298.860862) (xy 340.906595 -298.902053) (xy 340.936061 -298.947903)
			(xy 340.958703 -298.99748) (xy 340.974058 -299.049775) (xy 340.981814 -299.103723) (xy 340.9823 -299.130974)
			(xy 340.9823 -300.146974) (xy 340.981814 -300.174225) (xy 340.974058 -300.228173) (xy 340.958703 -300.280468)
			(xy 340.936061 -300.330045) (xy 340.906595 -300.375895) (xy 340.870904 -300.417086) (xy 340.829713 -300.452777)
			(xy 340.783863 -300.482243) (xy 340.734286 -300.504885) (xy 340.681991 -300.52024) (xy 340.628043 -300.527996)
			(xy 340.573541 -300.527996) (xy 340.519593 -300.52024) (xy 340.467298 -300.504885) (xy 340.417721 -300.482243)
			(xy 340.371871 -300.452777) (xy 340.33068 -300.417086) (xy 340.294989 -300.375895) (xy 340.265523 -300.330045)
			(xy 340.242881 -300.280468) (xy 340.227526 -300.228173) (xy 340.21977 -300.174225) (xy 340.219284 -300.146974)
			(xy 2.509012 -300.146974) (xy 2.509012 -304.780442) (xy 78.811632 -304.780442) (xy 78.815662 -304.638078)
			(xy 78.82774 -304.49617) (xy 78.847828 -304.355173) (xy 78.87586 -304.215538) (xy 78.911747 -304.077712)
			(xy 78.955374 -303.942138) (xy 79.006601 -303.809249) (xy 79.065264 -303.67947) (xy 79.131176 -303.553219)
			(xy 79.204125 -303.430899) (xy 79.283877 -303.312902) (xy 79.370177 -303.199606) (xy 79.462749 -303.091373)
			(xy 79.561295 -302.988551) (xy 79.665501 -302.89147) (xy 79.775033 -302.800439) (xy 79.889539 -302.715751)
			(xy 80.008653 -302.637676) (xy 80.131993 -302.566466) (xy 80.259164 -302.502347) (xy 80.38976 -302.445526)
			(xy 80.52336 -302.396185) (xy 80.659539 -302.35448) (xy 80.797858 -302.320547) (xy 80.937876 -302.294494)
			(xy 81.079143 -302.276404) (xy 81.221208 -302.266335) (xy 81.363615 -302.26432) (xy 81.505908 -302.270364)
			(xy 81.64763 -302.28445) (xy 81.788329 -302.30653) (xy 81.927554 -302.336535) (xy 82.064858 -302.374369)
			(xy 82.199801 -302.41991) (xy 82.331952 -302.473013) (xy 82.460887 -302.533507) (xy 82.586193 -302.601198)
			(xy 82.707469 -302.675871) (xy 82.824325 -302.757285) (xy 82.936389 -302.845179) (xy 83.043301 -302.939273)
			(xy 83.144718 -303.039265) (xy 83.240315 -303.144834) (xy 83.329787 -303.255643) (xy 83.412846 -303.371336)
			(xy 83.489227 -303.491543) (xy 83.558685 -303.615878) (xy 83.620998 -303.743944) (xy 83.675965 -303.875331)
			(xy 83.723411 -304.009616) (xy 83.763184 -304.146371) (xy 83.795156 -304.285157) (xy 83.819226 -304.425529)
			(xy 83.835315 -304.567039) (xy 83.843372 -304.709231) (xy 83.843876 -304.780442) (xy 140.011408 -304.780442)
			(xy 140.015438 -304.638078) (xy 140.027516 -304.49617) (xy 140.047604 -304.355173) (xy 140.075636 -304.215538)
			(xy 140.111523 -304.077712) (xy 140.15515 -303.942138) (xy 140.206377 -303.809249) (xy 140.26504 -303.67947)
			(xy 140.330952 -303.553219) (xy 140.403901 -303.430899) (xy 140.483653 -303.312902) (xy 140.569953 -303.199606)
			(xy 140.662525 -303.091373) (xy 140.761071 -302.988551) (xy 140.865277 -302.89147) (xy 140.974809 -302.800439)
			(xy 141.089315 -302.715751) (xy 141.208429 -302.637676) (xy 141.331769 -302.566466) (xy 141.45894 -302.502347)
			(xy 141.589536 -302.445526) (xy 141.723136 -302.396185) (xy 141.859315 -302.35448) (xy 141.997634 -302.320547)
			(xy 142.137652 -302.294494) (xy 142.278919 -302.276404) (xy 142.420984 -302.266335) (xy 142.563391 -302.26432)
			(xy 142.705684 -302.270364) (xy 142.847406 -302.28445) (xy 142.988105 -302.30653) (xy 143.12733 -302.336535)
			(xy 143.264634 -302.374369) (xy 143.399577 -302.41991) (xy 143.531728 -302.473013) (xy 143.660663 -302.533507)
			(xy 143.785969 -302.601198) (xy 143.907245 -302.675871) (xy 144.024101 -302.757285) (xy 144.136165 -302.845179)
			(xy 144.243077 -302.939273) (xy 144.344494 -303.039265) (xy 144.440091 -303.144834) (xy 144.529563 -303.255643)
			(xy 144.612622 -303.371336) (xy 144.689003 -303.491543) (xy 144.758461 -303.615878) (xy 144.820774 -303.743944)
			(xy 144.875741 -303.875331) (xy 144.923187 -304.009616) (xy 144.96296 -304.146371) (xy 144.994932 -304.285157)
			(xy 145.019002 -304.425529) (xy 145.035091 -304.567039) (xy 145.043148 -304.709231) (xy 145.04365 -304.780188)
			(xy 326.7517 -304.780188) (xy 326.75573 -304.637824) (xy 326.767808 -304.495916) (xy 326.787896 -304.354919)
			(xy 326.815928 -304.215284) (xy 326.851815 -304.077458) (xy 326.895442 -303.941884) (xy 326.946669 -303.808995)
			(xy 327.005332 -303.679216) (xy 327.071244 -303.552965) (xy 327.144193 -303.430645) (xy 327.223945 -303.312648)
			(xy 327.310245 -303.199352) (xy 327.402817 -303.091119) (xy 327.501363 -302.988297) (xy 327.605569 -302.891216)
			(xy 327.715101 -302.800185) (xy 327.829607 -302.715497) (xy 327.948721 -302.637422) (xy 328.072061 -302.566212)
			(xy 328.199232 -302.502093) (xy 328.329828 -302.445272) (xy 328.463428 -302.395931) (xy 328.599607 -302.354226)
			(xy 328.737926 -302.320293) (xy 328.877944 -302.29424) (xy 329.019211 -302.27615) (xy 329.161276 -302.266081)
			(xy 329.303683 -302.264066) (xy 329.445976 -302.27011) (xy 329.587698 -302.284196) (xy 329.728397 -302.306276)
			(xy 329.867622 -302.336281) (xy 330.004926 -302.374115) (xy 330.139869 -302.419656) (xy 330.27202 -302.472759)
			(xy 330.400955 -302.533253) (xy 330.526261 -302.600944) (xy 330.647537 -302.675617) (xy 330.764393 -302.757031)
			(xy 330.876457 -302.844925) (xy 330.983369 -302.939019) (xy 331.084786 -303.039011) (xy 331.180383 -303.14458)
			(xy 331.269855 -303.255389) (xy 331.352914 -303.371082) (xy 331.429295 -303.491289) (xy 331.498753 -303.615624)
			(xy 331.561066 -303.74369) (xy 331.616033 -303.875077) (xy 331.663479 -304.009362) (xy 331.703252 -304.146117)
			(xy 331.735224 -304.284903) (xy 331.759294 -304.425275) (xy 331.775383 -304.566785) (xy 331.781862 -304.681128)
			(xy 333.795116 -304.681128) (xy 333.795116 -303.817528) (xy 333.795602 -303.790259) (xy 333.803364 -303.736275)
			(xy 333.818729 -303.683945) (xy 333.841386 -303.634335) (xy 333.870872 -303.588454) (xy 333.906587 -303.547237)
			(xy 333.947804 -303.511522) (xy 333.993685 -303.482036) (xy 334.043295 -303.459379) (xy 334.095625 -303.444014)
			(xy 334.149609 -303.436252) (xy 334.204147 -303.436252) (xy 334.258131 -303.444014) (xy 334.310461 -303.459379)
			(xy 334.360071 -303.482036) (xy 334.405952 -303.511522) (xy 334.447169 -303.547237) (xy 334.482884 -303.588454)
			(xy 334.51237 -303.634335) (xy 334.535027 -303.683945) (xy 334.550392 -303.736275) (xy 334.558154 -303.790259)
			(xy 334.55864 -303.817528) (xy 334.55864 -304.681128) (xy 334.558154 -304.708397) (xy 334.550392 -304.762381)
			(xy 334.545164 -304.780188) (xy 387.951476 -304.780188) (xy 387.955506 -304.637824) (xy 387.967584 -304.495916)
			(xy 387.987672 -304.354919) (xy 388.015704 -304.215284) (xy 388.051591 -304.077458) (xy 388.095218 -303.941884)
			(xy 388.146445 -303.808995) (xy 388.205108 -303.679216) (xy 388.27102 -303.552965) (xy 388.343969 -303.430645)
			(xy 388.423721 -303.312648) (xy 388.510021 -303.199352) (xy 388.602593 -303.091119) (xy 388.701139 -302.988297)
			(xy 388.805345 -302.891216) (xy 388.914877 -302.800185) (xy 389.029383 -302.715497) (xy 389.148497 -302.637422)
			(xy 389.271837 -302.566212) (xy 389.399008 -302.502093) (xy 389.529604 -302.445272) (xy 389.663204 -302.395931)
			(xy 389.799383 -302.354226) (xy 389.937702 -302.320293) (xy 390.07772 -302.29424) (xy 390.218987 -302.27615)
			(xy 390.361052 -302.266081) (xy 390.503459 -302.264066) (xy 390.645752 -302.27011) (xy 390.787474 -302.284196)
			(xy 390.928173 -302.306276) (xy 391.067398 -302.336281) (xy 391.204702 -302.374115) (xy 391.339645 -302.419656)
			(xy 391.471796 -302.472759) (xy 391.600731 -302.533253) (xy 391.726037 -302.600944) (xy 391.847313 -302.675617)
			(xy 391.964169 -302.757031) (xy 392.076233 -302.844925) (xy 392.183145 -302.939019) (xy 392.284562 -303.039011)
			(xy 392.380159 -303.14458) (xy 392.469631 -303.255389) (xy 392.55269 -303.371082) (xy 392.629071 -303.491289)
			(xy 392.698529 -303.615624) (xy 392.760842 -303.74369) (xy 392.815809 -303.875077) (xy 392.863255 -304.009362)
			(xy 392.903028 -304.146117) (xy 392.935 -304.284903) (xy 392.95907 -304.425275) (xy 392.975159 -304.566785)
			(xy 392.983216 -304.708977) (xy 392.98372 -304.780188) (xy 392.983216 -304.851399) (xy 392.975159 -304.993591)
			(xy 392.95907 -305.135101) (xy 392.935 -305.275473) (xy 392.903028 -305.414259) (xy 392.863255 -305.551014)
			(xy 392.815809 -305.685299) (xy 392.760842 -305.816686) (xy 392.698529 -305.944752) (xy 392.629071 -306.069087)
			(xy 392.55269 -306.189294) (xy 392.469631 -306.304987) (xy 392.380159 -306.415796) (xy 392.284562 -306.521365)
			(xy 392.183145 -306.621357) (xy 392.076233 -306.715451) (xy 391.964169 -306.803345) (xy 391.847313 -306.884759)
			(xy 391.726037 -306.959432) (xy 391.600731 -307.027123) (xy 391.471796 -307.087617) (xy 391.339645 -307.14072)
			(xy 391.204702 -307.186261) (xy 391.067398 -307.224095) (xy 390.928173 -307.2541) (xy 390.787474 -307.27618)
			(xy 390.645752 -307.290266) (xy 390.503459 -307.29631) (xy 390.361052 -307.294295) (xy 390.218987 -307.284226)
			(xy 390.07772 -307.266136) (xy 389.937702 -307.240083) (xy 389.799383 -307.20615) (xy 389.663204 -307.164445)
			(xy 389.529604 -307.115104) (xy 389.399008 -307.058283) (xy 389.271837 -306.994164) (xy 389.148497 -306.922954)
			(xy 389.029383 -306.844879) (xy 388.914877 -306.760191) (xy 388.805345 -306.66916) (xy 388.701139 -306.572079)
			(xy 388.602593 -306.469257) (xy 388.510021 -306.361024) (xy 388.423721 -306.247728) (xy 388.343969 -306.129731)
			(xy 388.27102 -306.007411) (xy 388.205108 -305.88116) (xy 388.146445 -305.751381) (xy 388.095218 -305.618492)
			(xy 388.051591 -305.482918) (xy 388.015704 -305.345092) (xy 387.987672 -305.205457) (xy 387.967584 -305.06446)
			(xy 387.955506 -304.922552) (xy 387.951476 -304.780188) (xy 334.545164 -304.780188) (xy 334.535027 -304.814711)
			(xy 334.51237 -304.864321) (xy 334.482884 -304.910202) (xy 334.447169 -304.951419) (xy 334.405952 -304.987134)
			(xy 334.360071 -305.01662) (xy 334.310461 -305.039277) (xy 334.258131 -305.054642) (xy 334.204147 -305.062404)
			(xy 334.149609 -305.062404) (xy 334.095625 -305.054642) (xy 334.043295 -305.039277) (xy 333.993685 -305.01662)
			(xy 333.947804 -304.987134) (xy 333.906587 -304.951419) (xy 333.870872 -304.910202) (xy 333.841386 -304.864321)
			(xy 333.818729 -304.814711) (xy 333.803364 -304.762381) (xy 333.795602 -304.708397) (xy 333.795116 -304.681128)
			(xy 331.781862 -304.681128) (xy 331.78344 -304.708977) (xy 331.783944 -304.780188) (xy 331.78344 -304.851399)
			(xy 331.775383 -304.993591) (xy 331.759294 -305.135101) (xy 331.735224 -305.275473) (xy 331.703252 -305.414259)
			(xy 331.663479 -305.551014) (xy 331.616033 -305.685299) (xy 331.561066 -305.816686) (xy 331.498753 -305.944752)
			(xy 331.429295 -306.069087) (xy 331.352914 -306.189294) (xy 331.269855 -306.304987) (xy 331.180383 -306.415796)
			(xy 331.164835 -306.432966) (xy 340.495636 -306.432966) (xy 340.495636 -305.569366) (xy 340.496122 -305.542115)
			(xy 340.503878 -305.488167) (xy 340.519233 -305.435872) (xy 340.541875 -305.386295) (xy 340.571341 -305.340445)
			(xy 340.607032 -305.299254) (xy 340.648223 -305.263563) (xy 340.694073 -305.234097) (xy 340.74365 -305.211455)
			(xy 340.795945 -305.1961) (xy 340.849893 -305.188344) (xy 340.904395 -305.188344) (xy 340.958343 -305.1961)
			(xy 341.010638 -305.211455) (xy 341.060215 -305.234097) (xy 341.106065 -305.263563) (xy 341.147256 -305.299254)
			(xy 341.182947 -305.340445) (xy 341.212413 -305.386295) (xy 341.235055 -305.435872) (xy 341.25041 -305.488167)
			(xy 341.258166 -305.542115) (xy 341.258652 -305.569366) (xy 341.258652 -306.432966) (xy 341.258166 -306.460217)
			(xy 341.25041 -306.514165) (xy 341.235055 -306.56646) (xy 341.212413 -306.616037) (xy 341.182947 -306.661887)
			(xy 341.147256 -306.703078) (xy 341.106065 -306.738769) (xy 341.060215 -306.768235) (xy 341.010638 -306.790877)
			(xy 340.958343 -306.806232) (xy 340.904395 -306.813988) (xy 340.849893 -306.813988) (xy 340.795945 -306.806232)
			(xy 340.74365 -306.790877) (xy 340.694073 -306.768235) (xy 340.648223 -306.738769) (xy 340.607032 -306.703078)
			(xy 340.571341 -306.661887) (xy 340.541875 -306.616037) (xy 340.519233 -306.56646) (xy 340.503878 -306.514165)
			(xy 340.496122 -306.460217) (xy 340.495636 -306.432966) (xy 331.164835 -306.432966) (xy 331.084786 -306.521365)
			(xy 330.983369 -306.621357) (xy 330.876457 -306.715451) (xy 330.764393 -306.803345) (xy 330.647537 -306.884759)
			(xy 330.526261 -306.959432) (xy 330.400955 -307.027123) (xy 330.27202 -307.087617) (xy 330.139869 -307.14072)
			(xy 330.004926 -307.186261) (xy 329.867622 -307.224095) (xy 329.728397 -307.2541) (xy 329.587698 -307.27618)
			(xy 329.445976 -307.290266) (xy 329.303683 -307.29631) (xy 329.161276 -307.294295) (xy 329.019211 -307.284226)
			(xy 328.877944 -307.266136) (xy 328.737926 -307.240083) (xy 328.599607 -307.20615) (xy 328.463428 -307.164445)
			(xy 328.329828 -307.115104) (xy 328.199232 -307.058283) (xy 328.072061 -306.994164) (xy 327.948721 -306.922954)
			(xy 327.829607 -306.844879) (xy 327.715101 -306.760191) (xy 327.605569 -306.66916) (xy 327.501363 -306.572079)
			(xy 327.402817 -306.469257) (xy 327.310245 -306.361024) (xy 327.223945 -306.247728) (xy 327.144193 -306.129731)
			(xy 327.071244 -306.007411) (xy 327.005332 -305.88116) (xy 326.946669 -305.751381) (xy 326.895442 -305.618492)
			(xy 326.851815 -305.482918) (xy 326.815928 -305.345092) (xy 326.787896 -305.205457) (xy 326.767808 -305.06446)
			(xy 326.75573 -304.922552) (xy 326.7517 -304.780188) (xy 145.04365 -304.780188) (xy 145.043652 -304.780442)
			(xy 145.043148 -304.851653) (xy 145.035091 -304.993845) (xy 145.019002 -305.135355) (xy 144.994932 -305.275727)
			(xy 144.96296 -305.414513) (xy 144.923187 -305.551268) (xy 144.875741 -305.685553) (xy 144.820774 -305.81694)
			(xy 144.758461 -305.945006) (xy 144.689003 -306.069341) (xy 144.612622 -306.189548) (xy 144.529563 -306.305241)
			(xy 144.440091 -306.41605) (xy 144.344494 -306.521619) (xy 144.243077 -306.621611) (xy 144.136165 -306.715705)
			(xy 144.024101 -306.803599) (xy 143.907245 -306.885013) (xy 143.785969 -306.959686) (xy 143.660663 -307.027377)
			(xy 143.531728 -307.087871) (xy 143.399577 -307.140974) (xy 143.264634 -307.186515) (xy 143.12733 -307.224349)
			(xy 142.988105 -307.254354) (xy 142.847406 -307.276434) (xy 142.705684 -307.29052) (xy 142.563391 -307.296564)
			(xy 142.420984 -307.294549) (xy 142.278919 -307.28448) (xy 142.137652 -307.26639) (xy 141.997634 -307.240337)
			(xy 141.859315 -307.206404) (xy 141.723136 -307.164699) (xy 141.589536 -307.115358) (xy 141.45894 -307.058537)
			(xy 141.331769 -306.994418) (xy 141.208429 -306.923208) (xy 141.089315 -306.845133) (xy 140.974809 -306.760445)
			(xy 140.865277 -306.669414) (xy 140.761071 -306.572333) (xy 140.662525 -306.469511) (xy 140.569953 -306.361278)
			(xy 140.483653 -306.247982) (xy 140.403901 -306.129985) (xy 140.330952 -306.007665) (xy 140.26504 -305.881414)
			(xy 140.206377 -305.751635) (xy 140.15515 -305.618746) (xy 140.111523 -305.483172) (xy 140.075636 -305.345346)
			(xy 140.047604 -305.205711) (xy 140.027516 -305.064714) (xy 140.015438 -304.922806) (xy 140.011408 -304.780442)
			(xy 83.843876 -304.780442) (xy 83.843372 -304.851653) (xy 83.835315 -304.993845) (xy 83.819226 -305.135355)
			(xy 83.795156 -305.275727) (xy 83.763184 -305.414513) (xy 83.723411 -305.551268) (xy 83.675965 -305.685553)
			(xy 83.620998 -305.81694) (xy 83.558685 -305.945006) (xy 83.489227 -306.069341) (xy 83.412846 -306.189548)
			(xy 83.329787 -306.305241) (xy 83.240315 -306.41605) (xy 83.144718 -306.521619) (xy 83.043301 -306.621611)
			(xy 82.936389 -306.715705) (xy 82.824325 -306.803599) (xy 82.707469 -306.885013) (xy 82.586193 -306.959686)
			(xy 82.460887 -307.027377) (xy 82.331952 -307.087871) (xy 82.199801 -307.140974) (xy 82.064858 -307.186515)
			(xy 81.927554 -307.224349) (xy 81.788329 -307.254354) (xy 81.64763 -307.276434) (xy 81.505908 -307.29052)
			(xy 81.363615 -307.296564) (xy 81.221208 -307.294549) (xy 81.079143 -307.28448) (xy 80.937876 -307.26639)
			(xy 80.797858 -307.240337) (xy 80.659539 -307.206404) (xy 80.52336 -307.164699) (xy 80.38976 -307.115358)
			(xy 80.259164 -307.058537) (xy 80.131993 -306.994418) (xy 80.008653 -306.923208) (xy 79.889539 -306.845133)
			(xy 79.775033 -306.760445) (xy 79.665501 -306.669414) (xy 79.561295 -306.572333) (xy 79.462749 -306.469511)
			(xy 79.370177 -306.361278) (xy 79.283877 -306.247982) (xy 79.204125 -306.129985) (xy 79.131176 -306.007665)
			(xy 79.065264 -305.881414) (xy 79.006601 -305.751635) (xy 78.955374 -305.618746) (xy 78.911747 -305.483172)
			(xy 78.87586 -305.345346) (xy 78.847828 -305.205711) (xy 78.82774 -305.064714) (xy 78.815662 -304.922806)
			(xy 78.811632 -304.780442) (xy 2.509012 -304.780442) (xy 2.509012 -309.504588) (xy 79.192628 -309.504588)
			(xy 79.192628 -308.640988) (xy 79.193114 -308.613737) (xy 79.20087 -308.559789) (xy 79.216225 -308.507494)
			(xy 79.238867 -308.457917) (xy 79.268333 -308.412067) (xy 79.304024 -308.370876) (xy 79.345215 -308.335185)
			(xy 79.391065 -308.305719) (xy 79.440642 -308.283077) (xy 79.492937 -308.267722) (xy 79.546885 -308.259966)
			(xy 79.601387 -308.259966) (xy 79.655335 -308.267722) (xy 79.70763 -308.283077) (xy 79.757207 -308.305719)
			(xy 79.803057 -308.335185) (xy 79.844248 -308.370876) (xy 79.879939 -308.412067) (xy 79.909405 -308.457917)
			(xy 79.92811 -308.498873) (xy 93.275072 -308.498873) (xy 93.275072 -308.444327) (xy 93.282834 -308.390335)
			(xy 93.298202 -308.337998) (xy 93.320862 -308.288381) (xy 93.350352 -308.242493) (xy 93.386073 -308.20127)
			(xy 93.427297 -308.16555) (xy 93.473184 -308.13606) (xy 93.522802 -308.113401) (xy 93.575139 -308.098034)
			(xy 93.629131 -308.090271) (xy 93.656404 -308.089808) (xy 94.520004 -308.089808) (xy 94.547271 -308.090355)
			(xy 94.60125 -308.098116) (xy 94.653575 -308.113481) (xy 94.703181 -308.136135) (xy 94.749058 -308.165619)
			(xy 94.790271 -308.201331) (xy 94.825983 -308.242546) (xy 94.855467 -308.288423) (xy 94.878121 -308.338029)
			(xy 94.893485 -308.390354) (xy 94.901246 -308.444333) (xy 94.901246 -308.498867) (xy 94.893485 -308.552846)
			(xy 94.878121 -308.605171) (xy 94.855467 -308.654777) (xy 94.825983 -308.700654) (xy 94.790271 -308.741869)
			(xy 94.749058 -308.777581) (xy 94.703181 -308.807065) (xy 94.653575 -308.829719) (xy 94.60125 -308.845084)
			(xy 94.547271 -308.852845) (xy 94.520004 -308.853332) (xy 93.656404 -308.853332) (xy 93.629131 -308.852929)
			(xy 93.575139 -308.845166) (xy 93.522802 -308.829799) (xy 93.473184 -308.80714) (xy 93.427297 -308.77765)
			(xy 93.386073 -308.74193) (xy 93.350352 -308.700707) (xy 93.320862 -308.654819) (xy 93.298202 -308.605202)
			(xy 93.282834 -308.552865) (xy 93.275072 -308.498873) (xy 79.92811 -308.498873) (xy 79.932047 -308.507494)
			(xy 79.947402 -308.559789) (xy 79.955158 -308.613737) (xy 79.955644 -308.640988) (xy 79.955644 -309.303166)
			(xy 341.51824 -309.303166) (xy 341.51824 -308.439566) (xy 341.518726 -308.412297) (xy 341.526488 -308.358313)
			(xy 341.541853 -308.305983) (xy 341.56451 -308.256373) (xy 341.593996 -308.210492) (xy 341.629711 -308.169275)
			(xy 341.670928 -308.13356) (xy 341.716809 -308.104074) (xy 341.766419 -308.081417) (xy 341.818749 -308.066052)
			(xy 341.872733 -308.05829) (xy 341.927271 -308.05829) (xy 341.981255 -308.066052) (xy 342.033585 -308.081417)
			(xy 342.083195 -308.104074) (xy 342.129076 -308.13356) (xy 342.170293 -308.169275) (xy 342.206008 -308.210492)
			(xy 342.235494 -308.256373) (xy 342.258151 -308.305983) (xy 342.273516 -308.358313) (xy 342.281278 -308.412297)
			(xy 342.281764 -308.439566) (xy 342.281764 -309.303166) (xy 342.281278 -309.330435) (xy 342.273516 -309.384419)
			(xy 342.258151 -309.436749) (xy 342.235494 -309.486359) (xy 342.206008 -309.53224) (xy 342.170293 -309.573457)
			(xy 342.129076 -309.609172) (xy 342.083195 -309.638658) (xy 342.033585 -309.661315) (xy 341.981255 -309.67668)
			(xy 341.927271 -309.684442) (xy 341.872733 -309.684442) (xy 341.818749 -309.67668) (xy 341.766419 -309.661315)
			(xy 341.716809 -309.638658) (xy 341.670928 -309.609172) (xy 341.629711 -309.573457) (xy 341.593996 -309.53224)
			(xy 341.56451 -309.486359) (xy 341.541853 -309.436749) (xy 341.526488 -309.384419) (xy 341.518726 -309.330435)
			(xy 341.51824 -309.303166) (xy 79.955644 -309.303166) (xy 79.955644 -309.504588) (xy 79.955158 -309.531839)
			(xy 79.947402 -309.585787) (xy 79.932047 -309.638082) (xy 79.909405 -309.687659) (xy 79.879939 -309.733509)
			(xy 79.844248 -309.7747) (xy 79.803057 -309.810391) (xy 79.757207 -309.839857) (xy 79.70763 -309.862499)
			(xy 79.655335 -309.877854) (xy 79.601387 -309.88561) (xy 79.546885 -309.88561) (xy 79.492937 -309.877854)
			(xy 79.440642 -309.862499) (xy 79.391065 -309.839857) (xy 79.345215 -309.810391) (xy 79.304024 -309.7747)
			(xy 79.268333 -309.733509) (xy 79.238867 -309.687659) (xy 79.216225 -309.638082) (xy 79.20087 -309.585787)
			(xy 79.193114 -309.531839) (xy 79.192628 -309.504588) (xy 2.509012 -309.504588) (xy 2.509012 -310.603646)
			(xy 98.925888 -310.603646) (xy 98.925888 -309.740046) (xy 98.926374 -309.712795) (xy 98.93413 -309.658847)
			(xy 98.949485 -309.606552) (xy 98.972127 -309.556975) (xy 99.001593 -309.511125) (xy 99.037284 -309.469934)
			(xy 99.078475 -309.434243) (xy 99.124325 -309.404777) (xy 99.173902 -309.382135) (xy 99.226197 -309.36678)
			(xy 99.280145 -309.359024) (xy 99.334647 -309.359024) (xy 99.388595 -309.36678) (xy 99.44089 -309.382135)
			(xy 99.490467 -309.404777) (xy 99.536317 -309.434243) (xy 99.577508 -309.469934) (xy 99.613199 -309.511125)
			(xy 99.642665 -309.556975) (xy 99.665307 -309.606552) (xy 99.680662 -309.658847) (xy 99.688418 -309.712795)
			(xy 99.688904 -309.740046) (xy 99.688904 -310.603646) (xy 99.688418 -310.630897) (xy 99.680662 -310.684845)
			(xy 99.665307 -310.73714) (xy 99.642665 -310.786717) (xy 99.613199 -310.832567) (xy 99.577508 -310.873758)
			(xy 99.536317 -310.909449) (xy 99.490467 -310.938915) (xy 99.44089 -310.961557) (xy 99.388595 -310.976912)
			(xy 99.334647 -310.984668) (xy 99.280145 -310.984668) (xy 99.226197 -310.976912) (xy 99.173902 -310.961557)
			(xy 99.124325 -310.938915) (xy 99.078475 -310.909449) (xy 99.037284 -310.873758) (xy 99.001593 -310.832567)
			(xy 98.972127 -310.786717) (xy 98.949485 -310.73714) (xy 98.93413 -310.684845) (xy 98.926374 -310.630897)
			(xy 98.925888 -310.603646) (xy 2.509012 -310.603646) (xy 2.509012 -311.513728) (xy 347.772228 -311.513728)
			(xy 347.772228 -310.650128) (xy 347.772714 -310.622859) (xy 347.780476 -310.568875) (xy 347.795841 -310.516545)
			(xy 347.818498 -310.466935) (xy 347.847984 -310.421054) (xy 347.883699 -310.379837) (xy 347.924916 -310.344122)
			(xy 347.970797 -310.314636) (xy 348.020407 -310.291979) (xy 348.072737 -310.276614) (xy 348.126721 -310.268852)
			(xy 348.181259 -310.268852) (xy 348.235243 -310.276614) (xy 348.287573 -310.291979) (xy 348.337183 -310.314636)
			(xy 348.383064 -310.344122) (xy 348.424281 -310.379837) (xy 348.459996 -310.421054) (xy 348.489482 -310.466935)
			(xy 348.512139 -310.516545) (xy 348.527504 -310.568875) (xy 348.535266 -310.622859) (xy 348.535752 -310.650128)
			(xy 348.535752 -311.513728) (xy 348.535266 -311.540997) (xy 348.527504 -311.594981) (xy 348.512139 -311.647311)
			(xy 348.489482 -311.696921) (xy 348.459996 -311.742802) (xy 348.424281 -311.784019) (xy 348.383064 -311.819734)
			(xy 348.337183 -311.84922) (xy 348.287573 -311.871877) (xy 348.235243 -311.887242) (xy 348.181259 -311.895004)
			(xy 348.126721 -311.895004) (xy 348.072737 -311.887242) (xy 348.020407 -311.871877) (xy 347.970797 -311.84922)
			(xy 347.924916 -311.819734) (xy 347.883699 -311.784019) (xy 347.847984 -311.742802) (xy 347.818498 -311.696921)
			(xy 347.795841 -311.647311) (xy 347.780476 -311.594981) (xy 347.772714 -311.540997) (xy 347.772228 -311.513728)
			(xy 2.509012 -311.513728) (xy 2.509012 -314.997338) (xy 98.330512 -314.997338) (xy 98.330512 -314.133738)
			(xy 98.330998 -314.106487) (xy 98.338754 -314.052539) (xy 98.354109 -314.000244) (xy 98.376751 -313.950667)
			(xy 98.406217 -313.904817) (xy 98.441908 -313.863626) (xy 98.483099 -313.827935) (xy 98.528949 -313.798469)
			(xy 98.578526 -313.775827) (xy 98.630821 -313.760472) (xy 98.684769 -313.752716) (xy 98.739271 -313.752716)
			(xy 98.793219 -313.760472) (xy 98.845514 -313.775827) (xy 98.895091 -313.798469) (xy 98.940941 -313.827935)
			(xy 98.982132 -313.863626) (xy 99.017823 -313.904817) (xy 99.047289 -313.950667) (xy 99.069931 -314.000244)
			(xy 99.085286 -314.052539) (xy 99.093042 -314.106487) (xy 99.093528 -314.133738) (xy 99.093528 -314.997338)
			(xy 99.093042 -315.024589) (xy 99.085286 -315.078537) (xy 99.069931 -315.130832) (xy 99.047289 -315.180409)
			(xy 99.017823 -315.226259) (xy 98.982132 -315.26745) (xy 98.940941 -315.303141) (xy 98.895091 -315.332607)
			(xy 98.845514 -315.355249) (xy 98.793219 -315.370604) (xy 98.739271 -315.37836) (xy 98.684769 -315.37836)
			(xy 98.630821 -315.370604) (xy 98.578526 -315.355249) (xy 98.528949 -315.332607) (xy 98.483099 -315.303141)
			(xy 98.441908 -315.26745) (xy 98.406217 -315.226259) (xy 98.376751 -315.180409) (xy 98.354109 -315.130832)
			(xy 98.338754 -315.078537) (xy 98.330998 -315.024589) (xy 98.330512 -314.997338) (xy 2.509012 -314.997338)
			(xy 2.509012 -336.9884) (xy 70.218517 -336.9884) (xy 70.222508 -336.904617) (xy 70.234446 -336.821593)
			(xy 70.254221 -336.74008) (xy 70.281655 -336.660815) (xy 70.3165 -336.584518) (xy 70.35844 -336.511878)
			(xy 70.407095 -336.443554) (xy 70.462025 -336.380164) (xy 70.522731 -336.322283) (xy 70.588664 -336.270435)
			(xy 70.659228 -336.225089) (xy 70.733783 -336.186656) (xy 70.811653 -336.155484) (xy 70.892134 -336.131855)
			(xy 70.974497 -336.115984) (xy 71.057995 -336.108014) (xy 71.099934 -336.107532) (xy 71.137123 -336.107938)
			(xy 71.211236 -336.114223) (xy 71.284556 -336.126727) (xy 71.356562 -336.145363) (xy 71.39178 -336.157316)
			(xy 71.399977 -336.15983) (xy 71.417111 -336.15983) (xy 71.425308 -336.157316) (xy 71.460496 -336.145371)
			(xy 71.532436 -336.126725) (xy 71.605692 -336.114215) (xy 71.679742 -336.107929) (xy 71.7169 -336.107532)
			(xy 71.717408 -336.107532) (xy 71.748142 -336.108294) (xy 71.757646 -336.056715) (xy 71.787316 -335.956115)
			(xy 71.807324 -335.907634) (xy 71.810983 -335.897931) (xy 71.810971 -335.877211) (xy 71.807324 -335.867502)
			(xy 71.790219 -335.826242) (xy 71.763427 -335.741032) (xy 71.74539 -335.653549) (xy 71.736293 -335.564691)
			(xy 71.735696 -335.52003) (xy 71.735696 -335.519268) (xy 71.736195 -335.477343) (xy 71.744165 -335.393872)
			(xy 71.760034 -335.311537) (xy 71.783657 -335.231083) (xy 71.814821 -335.153239) (xy 71.853244 -335.078709)
			(xy 71.898577 -335.00817) (xy 71.95041 -334.942259) (xy 72.008273 -334.881573) (xy 72.071643 -334.826663)
			(xy 72.139946 -334.778025) (xy 72.212563 -334.7361) (xy 72.288836 -334.701267) (xy 72.368075 -334.673842)
			(xy 72.449561 -334.654073) (xy 72.532558 -334.64214) (xy 72.616314 -334.638151) (xy 72.70007 -334.64214)
			(xy 72.783067 -334.654073) (xy 72.864553 -334.673842) (xy 72.943792 -334.701267) (xy 73.020065 -334.7361)
			(xy 73.092682 -334.778025) (xy 73.160985 -334.826663) (xy 73.224355 -334.881573) (xy 73.282218 -334.942259)
			(xy 73.334051 -335.00817) (xy 73.379384 -335.078709) (xy 73.417807 -335.153239) (xy 73.448971 -335.231083)
			(xy 73.472594 -335.311537) (xy 73.488463 -335.393872) (xy 73.496433 -335.477343) (xy 73.496932 -335.519268)
			(xy 73.496932 -335.52003) (xy 73.496371 -335.564694) (xy 73.487295 -335.653559) (xy 73.46926 -335.741047)
			(xy 73.442452 -335.826257) (xy 73.425304 -335.867502) (xy 73.421681 -335.877216) (xy 73.421669 -335.897926)
			(xy 73.425304 -335.907634) (xy 73.441139 -335.945575) (xy 73.466487 -336.02379) (xy 73.484436 -336.104027)
			(xy 73.494829 -336.185587) (xy 73.496678 -336.226658) (xy 73.496932 -336.24012) (xy 73.51141 -336.263234)
			(xy 73.61301 -336.31759) (xy 73.639934 -336.316828) (xy 73.651618 -336.309462) (xy 73.686811 -336.288202)
			(xy 73.76042 -336.251553) (xy 73.837094 -336.221845) (xy 73.91618 -336.199333) (xy 73.997005 -336.184209)
			(xy 74.07888 -336.1766) (xy 74.119994 -336.176112) (xy 74.161107 -336.176619) (xy 74.242983 -336.184205)
			(xy 74.32381 -336.199313) (xy 74.402898 -336.221815) (xy 74.479573 -336.251518) (xy 74.553179 -336.288168)
			(xy 74.623091 -336.331454) (xy 74.68871 -336.381006) (xy 74.749477 -336.4364) (xy 74.804874 -336.497166)
			(xy 74.854428 -336.562783) (xy 74.897716 -336.632693) (xy 74.934369 -336.706298) (xy 74.964075 -336.782971)
			(xy 74.986579 -336.862059) (xy 75.001691 -336.942885) (xy 75.005252 -336.9813) (xy 78.574105 -336.9813)
			(xy 78.578096 -336.897517) (xy 78.590033 -336.814493) (xy 78.609809 -336.732979) (xy 78.637243 -336.653715)
			(xy 78.672087 -336.577417) (xy 78.714027 -336.504776) (xy 78.762681 -336.436452) (xy 78.81761 -336.373061)
			(xy 78.878316 -336.31518) (xy 78.94425 -336.26333) (xy 79.014813 -336.217984) (xy 79.089367 -336.179549)
			(xy 79.167237 -336.148376) (xy 79.247718 -336.124747) (xy 79.330081 -336.108874) (xy 79.413579 -336.100902)
			(xy 79.455518 -336.10042) (xy 79.492708 -336.100802) (xy 79.566821 -336.107094) (xy 79.640141 -336.119606)
			(xy 79.712146 -336.138248) (xy 79.747364 -336.150204) (xy 79.755561 -336.152718) (xy 79.772695 -336.152718)
			(xy 79.780892 -336.150204) (xy 79.816103 -336.138226) (xy 79.888108 -336.119576) (xy 79.961431 -336.107072)
			(xy 80.035547 -336.100804) (xy 80.072738 -336.10042) (xy 80.10906 -336.101182) (xy 80.115245 -336.066241)
			(xy 80.132513 -335.997409) (xy 80.155273 -335.930194) (xy 80.169004 -335.897474) (xy 80.172641 -335.887764)
			(xy 80.172644 -335.86705) (xy 80.169004 -335.857342) (xy 80.151879 -335.81609) (xy 80.125092 -335.730877)
			(xy 80.107061 -335.643392) (xy 80.09797 -335.554532) (xy 80.097376 -335.50987) (xy 80.097376 -335.509108)
			(xy 80.097875 -335.467183) (xy 80.105845 -335.383712) (xy 80.121714 -335.301377) (xy 80.145337 -335.220923)
			(xy 80.176501 -335.143079) (xy 80.214924 -335.068549) (xy 80.260257 -334.99801) (xy 80.31209 -334.932099)
			(xy 80.369953 -334.871413) (xy 80.433323 -334.816503) (xy 80.501626 -334.767865) (xy 80.574243 -334.72594)
			(xy 80.650516 -334.691107) (xy 80.729755 -334.663682) (xy 80.811241 -334.643913) (xy 80.894238 -334.63198)
			(xy 80.977994 -334.627991) (xy 81.06175 -334.63198) (xy 81.144747 -334.643913) (xy 81.226233 -334.663682)
			(xy 81.305472 -334.691107) (xy 81.381745 -334.72594) (xy 81.454362 -334.767865) (xy 81.522665 -334.816503)
			(xy 81.586035 -334.871413) (xy 81.643898 -334.932099) (xy 81.695731 -334.99801) (xy 81.741064 -335.068549)
			(xy 81.779487 -335.143079) (xy 81.810651 -335.220923) (xy 81.834274 -335.301377) (xy 81.850143 -335.383712)
			(xy 81.858113 -335.467183) (xy 81.858612 -335.509108) (xy 81.858612 -335.50987) (xy 81.858066 -335.554534)
			(xy 81.848986 -335.6434) (xy 81.830947 -335.730888) (xy 81.804134 -335.816098) (xy 81.786984 -335.857342)
			(xy 81.783338 -335.867049) (xy 81.783341 -335.887765) (xy 81.786984 -335.897474) (xy 81.802748 -335.935334)
			(xy 81.827987 -336.013369) (xy 81.845871 -336.093411) (xy 81.856247 -336.174768) (xy 81.858104 -336.215736)
			(xy 81.858828 -336.22455) (xy 81.865419 -336.240944) (xy 81.877182 -336.254128) (xy 81.884774 -336.258662)
			(xy 81.973928 -336.306922) (xy 82.000852 -336.30616) (xy 82.012536 -336.299048) (xy 82.047432 -336.278305)
			(xy 82.120306 -336.242523) (xy 82.19614 -336.213534) (xy 82.2743 -336.191579) (xy 82.354137 -336.176843)
			(xy 82.434985 -336.169448) (xy 82.475578 -336.169) (xy 82.516691 -336.169534) (xy 82.598566 -336.177119)
			(xy 82.679391 -336.192225) (xy 82.758479 -336.214725) (xy 82.835153 -336.244426) (xy 82.908759 -336.281075)
			(xy 82.97867 -336.324359) (xy 83.044289 -336.373909) (xy 83.105056 -336.429302) (xy 83.160453 -336.490065)
			(xy 83.210007 -336.555681) (xy 83.253296 -336.625589) (xy 83.28995 -336.699193) (xy 83.319656 -336.775864)
			(xy 83.342161 -336.85495) (xy 83.357273 -336.935775) (xy 83.360149 -336.9668) (xy 86.931981 -336.9668)
			(xy 86.935971 -336.883042) (xy 86.947905 -336.800043) (xy 86.967674 -336.718554) (xy 86.9951 -336.639313)
			(xy 87.029935 -336.563039) (xy 87.071862 -336.490421) (xy 87.120503 -336.422117) (xy 87.175416 -336.358746)
			(xy 87.236104 -336.300883) (xy 87.302018 -336.24905) (xy 87.37256 -336.203717) (xy 87.447092 -336.165296)
			(xy 87.52494 -336.134133) (xy 87.605396 -336.110512) (xy 87.687734 -336.094645) (xy 87.771208 -336.086677)
			(xy 87.813134 -336.086196) (xy 87.81415 -336.086196) (xy 87.851207 -336.086587) (xy 87.925057 -336.092856)
			(xy 87.998119 -336.105302) (xy 88.069879 -336.123838) (xy 88.10498 -336.135726) (xy 88.113177 -336.13824)
			(xy 88.130311 -336.13824) (xy 88.138508 -336.135726) (xy 88.173727 -336.123789) (xy 88.245736 -336.1052)
			(xy 88.319058 -336.092757) (xy 88.393169 -336.086549) (xy 88.430354 -336.086196) (xy 88.454992 -336.08645)
			(xy 88.464629 -336.040549) (xy 88.49238 -335.950951) (xy 88.510364 -335.907634) (xy 88.514021 -335.89793)
			(xy 88.514009 -335.877211) (xy 88.510364 -335.867502) (xy 88.493256 -335.826243) (xy 88.466465 -335.741033)
			(xy 88.448429 -335.65355) (xy 88.439333 -335.564691) (xy 88.438736 -335.52003) (xy 88.438736 -335.519268)
			(xy 88.439235 -335.477343) (xy 88.447205 -335.393872) (xy 88.463074 -335.311537) (xy 88.486697 -335.231083)
			(xy 88.517861 -335.153239) (xy 88.556284 -335.078709) (xy 88.601617 -335.00817) (xy 88.65345 -334.942259)
			(xy 88.711313 -334.881573) (xy 88.774683 -334.826663) (xy 88.842986 -334.778025) (xy 88.915603 -334.7361)
			(xy 88.991876 -334.701267) (xy 89.071115 -334.673842) (xy 89.152601 -334.654073) (xy 89.235598 -334.64214)
			(xy 89.319354 -334.638151) (xy 89.40311 -334.64214) (xy 89.486107 -334.654073) (xy 89.567593 -334.673842)
			(xy 89.646832 -334.701267) (xy 89.723105 -334.7361) (xy 89.795722 -334.778025) (xy 89.864025 -334.826663)
			(xy 89.927395 -334.881573) (xy 89.985258 -334.942259) (xy 90.037091 -335.00817) (xy 90.082424 -335.078709)
			(xy 90.120847 -335.153239) (xy 90.152011 -335.231083) (xy 90.175634 -335.311537) (xy 90.191503 -335.393872)
			(xy 90.199473 -335.477343) (xy 90.199972 -335.519268) (xy 90.199972 -335.52003) (xy 90.199408 -335.564694)
			(xy 90.190332 -335.653559) (xy 90.172298 -335.741047) (xy 90.145491 -335.826257) (xy 90.128344 -335.867502)
			(xy 90.124724 -335.877216) (xy 90.124712 -335.897925) (xy 90.128344 -335.907634) (xy 90.14352 -335.944017)
			(xy 90.168055 -336.018939) (xy 90.185802 -336.095753) (xy 90.196619 -336.173844) (xy 90.198956 -336.213196)
			(xy 90.198956 -336.21345) (xy 90.199799 -336.222253) (xy 90.206694 -336.238523) (xy 90.218709 -336.251482)
			(xy 90.226388 -336.255868) (xy 90.316812 -336.302604) (xy 90.343482 -336.301334) (xy 90.355166 -336.293968)
			(xy 90.390883 -336.271832) (xy 90.465707 -336.233583) (xy 90.543804 -336.20256) (xy 90.624479 -336.17904)
			(xy 90.707013 -336.163233) (xy 90.790669 -336.155279) (xy 90.832686 -336.154776) (xy 90.833194 -336.154776)
			(xy 90.874302 -336.155218) (xy 90.956167 -336.162803) (xy 91.036983 -336.177907) (xy 91.116061 -336.200402)
			(xy 91.192727 -336.230097) (xy 91.266326 -336.266738) (xy 91.336231 -336.310013) (xy 91.401845 -336.359552)
			(xy 91.46261 -336.414933) (xy 91.518006 -336.475684) (xy 91.567562 -336.541286) (xy 91.610854 -336.61118)
			(xy 91.647513 -336.68477) (xy 91.677227 -336.761428) (xy 91.699742 -336.840501) (xy 91.714867 -336.921313)
			(xy 91.722471 -337.003176) (xy 91.722641 -337.0176) (xy 95.263181 -337.0176) (xy 95.267171 -336.933842)
			(xy 95.279105 -336.850843) (xy 95.298874 -336.769354) (xy 95.3263 -336.690113) (xy 95.361135 -336.613839)
			(xy 95.403062 -336.541221) (xy 95.451703 -336.472917) (xy 95.506616 -336.409546) (xy 95.567304 -336.351683)
			(xy 95.633218 -336.29985) (xy 95.70376 -336.254517) (xy 95.778292 -336.216096) (xy 95.85614 -336.184933)
			(xy 95.936596 -336.161312) (xy 96.018934 -336.145445) (xy 96.102408 -336.137477) (xy 96.144334 -336.136996)
			(xy 96.14535 -336.136996) (xy 96.182407 -336.137387) (xy 96.256257 -336.143656) (xy 96.329319 -336.156102)
			(xy 96.401079 -336.174638) (xy 96.43618 -336.186526) (xy 96.444377 -336.18904) (xy 96.461511 -336.18904)
			(xy 96.469708 -336.186526) (xy 96.504897 -336.174599) (xy 96.576843 -336.15602) (xy 96.650101 -336.143577)
			(xy 96.724146 -336.137359) (xy 96.7613 -336.136996) (xy 96.761808 -336.136996) (xy 96.796352 -336.137504)
			(xy 96.805918 -336.09484) (xy 96.832381 -336.0115) (xy 96.849184 -335.971134) (xy 96.852845 -335.961431)
			(xy 96.852833 -335.940711) (xy 96.849184 -335.931002) (xy 96.832077 -335.889743) (xy 96.805286 -335.804532)
			(xy 96.78725 -335.717049) (xy 96.778153 -335.628191) (xy 96.777556 -335.58353) (xy 96.777556 -335.582768)
			(xy 96.778055 -335.540843) (xy 96.786025 -335.457372) (xy 96.801894 -335.375037) (xy 96.825517 -335.294583)
			(xy 96.856681 -335.216739) (xy 96.895104 -335.142209) (xy 96.940437 -335.07167) (xy 96.99227 -335.005759)
			(xy 97.050133 -334.945073) (xy 97.113503 -334.890163) (xy 97.181806 -334.841525) (xy 97.254423 -334.7996)
			(xy 97.330696 -334.764767) (xy 97.409935 -334.737342) (xy 97.491421 -334.717573) (xy 97.574418 -334.70564)
			(xy 97.658174 -334.701651) (xy 97.74193 -334.70564) (xy 97.824927 -334.717573) (xy 97.906413 -334.737342)
			(xy 97.985652 -334.764767) (xy 98.061925 -334.7996) (xy 98.134542 -334.841525) (xy 98.202845 -334.890163)
			(xy 98.266215 -334.945073) (xy 98.324078 -335.005759) (xy 98.375911 -335.07167) (xy 98.421244 -335.142209)
			(xy 98.459667 -335.216739) (xy 98.490831 -335.294583) (xy 98.514454 -335.375037) (xy 98.530323 -335.457372)
			(xy 98.538293 -335.540843) (xy 98.538792 -335.582768) (xy 98.538792 -335.58353) (xy 98.538226 -335.628194)
			(xy 98.529151 -335.717059) (xy 98.511117 -335.804547) (xy 98.484311 -335.889757) (xy 98.467164 -335.931002)
			(xy 98.463542 -335.940716) (xy 98.463531 -335.961426) (xy 98.467164 -335.971134) (xy 98.48433 -336.012473)
			(xy 98.511159 -336.097874) (xy 98.529194 -336.185554) (xy 98.538249 -336.27461) (xy 98.538792 -336.319368)
			(xy 98.538552 -336.350973) (xy 98.534101 -336.414026) (xy 98.529902 -336.445352) (xy 98.528378 -336.45602)
			(xy 98.53422 -336.477102) (xy 98.590608 -336.543396) (xy 98.597904 -336.55118) (xy 98.617064 -336.560504)
			(xy 98.627692 -336.56143) (xy 98.6282 -336.56143) (xy 98.671147 -336.563026) (xy 98.756458 -336.573467)
			(xy 98.840365 -336.592088) (xy 98.922084 -336.618714) (xy 99.000854 -336.653099) (xy 99.07594 -336.69492)
			(xy 99.146643 -336.743788) (xy 99.212303 -336.799248) (xy 99.272307 -336.860782) (xy 99.326097 -336.927817)
			(xy 99.362614 -336.9836) (xy 318.155561 -336.9836) (xy 318.15955 -336.899842) (xy 318.171484 -336.816843)
			(xy 318.191253 -336.735354) (xy 318.218678 -336.656114) (xy 318.253512 -336.579839) (xy 318.295438 -336.50722)
			(xy 318.344078 -336.438916) (xy 318.398989 -336.375544) (xy 318.459676 -336.317679) (xy 318.525589 -336.265845)
			(xy 318.59613 -336.220511) (xy 318.670661 -336.182087) (xy 318.748507 -336.150922) (xy 318.828963 -336.127298)
			(xy 318.911301 -336.111429) (xy 318.994774 -336.103459) (xy 319.0367 -336.10296) (xy 319.037716 -336.10296)
			(xy 319.074773 -336.103363) (xy 319.148622 -336.109628) (xy 319.221685 -336.122071) (xy 319.293445 -336.140604)
			(xy 319.328546 -336.15249) (xy 319.336743 -336.155004) (xy 319.353877 -336.155004) (xy 319.362074 -336.15249)
			(xy 319.397267 -336.140575) (xy 319.469212 -336.121992) (xy 319.542468 -336.109546) (xy 319.616513 -336.103324)
			(xy 319.653666 -336.10296) (xy 319.654174 -336.10296) (xy 319.681606 -336.103214) (xy 319.687655 -336.066844)
			(xy 319.704988 -335.995173) (xy 319.728195 -335.925184) (xy 319.742312 -335.891124) (xy 319.745871 -335.881532)
			(xy 319.745875 -335.86109) (xy 319.742312 -335.8515) (xy 319.725303 -335.810117) (xy 319.698681 -335.724692)
			(xy 319.680772 -335.637026) (xy 319.671759 -335.548004) (xy 319.671192 -335.503266) (xy 319.671192 -335.503012)
			(xy 319.671696 -335.460664) (xy 319.679747 -335.37635) (xy 319.695776 -335.293184) (xy 319.719637 -335.211917)
			(xy 319.751116 -335.133287) (xy 319.789927 -335.058006) (xy 319.835717 -334.986754) (xy 319.888073 -334.920178)
			(xy 319.946521 -334.85888) (xy 320.010531 -334.803415) (xy 320.079523 -334.754286) (xy 320.152873 -334.711937)
			(xy 320.229916 -334.676753) (xy 320.309955 -334.649051) (xy 320.392264 -334.629083) (xy 320.476099 -334.61703)
			(xy 320.5607 -334.613) (xy 320.645301 -334.61703) (xy 320.729136 -334.629083) (xy 320.811445 -334.649051)
			(xy 320.891484 -334.676753) (xy 320.968527 -334.711937) (xy 321.041877 -334.754286) (xy 321.110869 -334.803415)
			(xy 321.174879 -334.85888) (xy 321.233327 -334.920178) (xy 321.285683 -334.986754) (xy 321.331473 -335.058006)
			(xy 321.370284 -335.133287) (xy 321.401763 -335.211917) (xy 321.425624 -335.293184) (xy 321.441653 -335.37635)
			(xy 321.449704 -335.460664) (xy 321.450208 -335.503012) (xy 321.450208 -335.503266) (xy 321.449645 -335.548004)
			(xy 321.440627 -335.637026) (xy 321.422721 -335.724694) (xy 321.396107 -335.810121) (xy 321.379088 -335.8515)
			(xy 321.375596 -335.861115) (xy 321.37573 -335.881553) (xy 321.379342 -335.891124) (xy 321.395061 -335.929255)
			(xy 321.42019 -336.007817) (xy 321.437947 -336.088366) (xy 321.448179 -336.170212) (xy 321.449954 -336.211418)
			(xy 321.450208 -336.22488) (xy 321.464178 -336.24774) (xy 321.564762 -336.303112) (xy 321.591432 -336.302604)
			(xy 321.603116 -336.295746) (xy 321.637431 -336.275914) (xy 321.708951 -336.241747) (xy 321.783227 -336.214078)
			(xy 321.859671 -336.193127) (xy 321.937675 -336.179058) (xy 322.016621 -336.171985) (xy 322.056252 -336.17154)
			(xy 322.05676 -336.17154) (xy 322.097864 -336.17199) (xy 322.179721 -336.179572) (xy 322.26053 -336.194675)
			(xy 322.3396 -336.21717) (xy 322.416257 -336.246866) (xy 322.489847 -336.283508) (xy 322.559742 -336.326784)
			(xy 322.625346 -336.376325) (xy 322.686098 -336.431708) (xy 322.74148 -336.492461) (xy 322.791021 -336.558064)
			(xy 322.834296 -336.62796) (xy 322.870938 -336.70155) (xy 322.900632 -336.778207) (xy 322.923127 -336.857278)
			(xy 322.938229 -336.938087) (xy 322.941787 -336.9765) (xy 326.511148 -336.9765) (xy 326.515138 -336.892742)
			(xy 326.527072 -336.809743) (xy 326.546841 -336.728254) (xy 326.574266 -336.649013) (xy 326.609099 -336.572737)
			(xy 326.651025 -336.500118) (xy 326.699664 -336.431814) (xy 326.754575 -336.368441) (xy 326.815262 -336.310576)
			(xy 326.881174 -336.258741) (xy 326.951715 -336.213406) (xy 327.026246 -336.174981) (xy 327.104092 -336.143815)
			(xy 327.184547 -336.12019) (xy 327.266885 -336.104319) (xy 327.350358 -336.096347) (xy 327.392284 -336.095848)
			(xy 327.3933 -336.095848) (xy 327.430357 -336.096256) (xy 327.504206 -336.10252) (xy 327.577268 -336.114961)
			(xy 327.649028 -336.133493) (xy 327.68413 -336.145378) (xy 327.692327 -336.147892) (xy 327.709461 -336.147892)
			(xy 327.717658 -336.145378) (xy 327.752881 -336.133453) (xy 327.824889 -336.114861) (xy 327.898209 -336.102415)
			(xy 327.972319 -336.096203) (xy 328.009504 -336.095848) (xy 328.043286 -336.096356) (xy 328.05281 -336.047304)
			(xy 328.081456 -335.951571) (xy 328.100436 -335.905348) (xy 328.10398 -335.895751) (xy 328.103994 -335.875314)
			(xy 328.100436 -335.865724) (xy 328.083404 -335.82435) (xy 328.056787 -335.738922) (xy 328.038886 -335.651253)
			(xy 328.02988 -335.562229) (xy 328.029316 -335.51749) (xy 328.029316 -335.517236) (xy 328.02982 -335.474888)
			(xy 328.037871 -335.390574) (xy 328.0539 -335.307408) (xy 328.077761 -335.226141) (xy 328.10924 -335.147511)
			(xy 328.148051 -335.07223) (xy 328.193841 -335.000978) (xy 328.246197 -334.934402) (xy 328.304645 -334.873104)
			(xy 328.368655 -334.817639) (xy 328.437647 -334.76851) (xy 328.510997 -334.726161) (xy 328.58804 -334.690977)
			(xy 328.668079 -334.663275) (xy 328.750388 -334.643307) (xy 328.834223 -334.631254) (xy 328.918824 -334.627224)
			(xy 329.003425 -334.631254) (xy 329.08726 -334.643307) (xy 329.169569 -334.663275) (xy 329.249608 -334.690977)
			(xy 329.326651 -334.726161) (xy 329.400001 -334.76851) (xy 329.468993 -334.817639) (xy 329.533003 -334.873104)
			(xy 329.591451 -334.934402) (xy 329.643807 -335.000978) (xy 329.689597 -335.07223) (xy 329.728408 -335.147511)
			(xy 329.759887 -335.226141) (xy 329.783748 -335.307408) (xy 329.799777 -335.390574) (xy 329.807828 -335.474888)
			(xy 329.808332 -335.517236) (xy 329.808332 -335.51749) (xy 329.807775 -335.562229) (xy 329.798756 -335.651251)
			(xy 329.780848 -335.738918) (xy 329.754231 -335.824345) (xy 329.737212 -335.865724) (xy 329.733624 -335.875308)
			(xy 329.733638 -335.895757) (xy 329.737212 -335.905348) (xy 329.752022 -335.941175) (xy 329.776095 -336.014872)
			(xy 329.793653 -336.090386) (xy 329.804563 -336.167144) (xy 329.807062 -336.20583) (xy 329.807824 -336.219038)
			(xy 329.822048 -336.24139) (xy 329.91044 -336.288888) (xy 329.918254 -336.292745) (xy 329.93547 -336.295369)
			(xy 329.95256 -336.292022) (xy 329.960224 -336.287872) (xy 329.994483 -336.268147) (xy 330.065868 -336.23417)
			(xy 330.139986 -336.206662) (xy 330.216254 -336.18584) (xy 330.294068 -336.171868) (xy 330.372815 -336.164856)
			(xy 330.412344 -336.164428) (xy 330.453448 -336.164825) (xy 330.535306 -336.172414) (xy 330.616114 -336.187524)
			(xy 330.695183 -336.210025) (xy 330.771839 -336.239726) (xy 330.845427 -336.276373) (xy 330.91532 -336.319653)
			(xy 330.980922 -336.369198) (xy 331.041672 -336.424584) (xy 331.097053 -336.48534) (xy 331.146592 -336.550946)
			(xy 331.189866 -336.620843) (xy 331.226507 -336.694434) (xy 331.256201 -336.771093) (xy 331.278695 -336.850164)
			(xy 331.293797 -336.930973) (xy 331.296671 -336.962) (xy 334.868517 -336.962) (xy 334.872507 -336.878219)
			(xy 334.884444 -336.795197) (xy 334.904219 -336.713686) (xy 334.931652 -336.634423) (xy 334.966495 -336.558127)
			(xy 335.008433 -336.485488) (xy 335.057086 -336.417165) (xy 335.112013 -336.353776) (xy 335.172717 -336.295895)
			(xy 335.238647 -336.244046) (xy 335.309208 -336.198699) (xy 335.38376 -336.160265) (xy 335.461628 -336.129092)
			(xy 335.542106 -336.105461) (xy 335.624466 -336.089588) (xy 335.707962 -336.081615) (xy 335.7499 -336.081116)
			(xy 335.78709 -336.081504) (xy 335.861203 -336.087794) (xy 335.934522 -336.100304) (xy 336.006528 -336.118945)
			(xy 336.041746 -336.1309) (xy 336.049943 -336.133414) (xy 336.067077 -336.133414) (xy 336.075274 -336.1309)
			(xy 336.110487 -336.118927) (xy 336.182491 -336.100276) (xy 336.255813 -336.08777) (xy 336.329929 -336.0815)
			(xy 336.36712 -336.081116) (xy 336.407506 -336.082132) (xy 336.417036 -336.036786) (xy 336.444265 -335.948213)
			(xy 336.461862 -335.905348) (xy 336.465474 -335.895775) (xy 336.465619 -335.875336) (xy 336.462116 -335.865724)
			(xy 336.445083 -335.824351) (xy 336.418467 -335.738922) (xy 336.400565 -335.651253) (xy 336.39156 -335.562229)
			(xy 336.390996 -335.51749) (xy 336.390996 -335.517236) (xy 336.3915 -335.474888) (xy 336.399551 -335.390574)
			(xy 336.41558 -335.307408) (xy 336.439441 -335.226141) (xy 336.47092 -335.147511) (xy 336.509731 -335.07223)
			(xy 336.555521 -335.000978) (xy 336.607877 -334.934402) (xy 336.666325 -334.873104) (xy 336.730335 -334.817639)
			(xy 336.799327 -334.76851) (xy 336.872677 -334.726161) (xy 336.94972 -334.690977) (xy 337.029759 -334.663275)
			(xy 337.112068 -334.643307) (xy 337.195903 -334.631254) (xy 337.280504 -334.627224) (xy 337.365105 -334.631254)
			(xy 337.44894 -334.643307) (xy 337.531249 -334.663275) (xy 337.611288 -334.690977) (xy 337.688331 -334.726161)
			(xy 337.761681 -334.76851) (xy 337.830673 -334.817639) (xy 337.894683 -334.873104) (xy 337.953131 -334.934402)
			(xy 338.005487 -335.000978) (xy 338.051277 -335.07223) (xy 338.090088 -335.147511) (xy 338.121567 -335.226141)
			(xy 338.145428 -335.307408) (xy 338.161457 -335.390574) (xy 338.169508 -335.474888) (xy 338.170012 -335.517236)
			(xy 338.170012 -335.51749) (xy 338.169456 -335.562229) (xy 338.160437 -335.651251) (xy 338.142528 -335.738918)
			(xy 338.115912 -335.824345) (xy 338.098892 -335.865724) (xy 338.095386 -335.875335) (xy 338.09553 -335.895777)
			(xy 338.099146 -335.905348) (xy 338.117792 -335.95091) (xy 338.146101 -336.045203) (xy 338.163844 -336.142042)
			(xy 338.16798 -336.191098) (xy 338.168919 -336.199672) (xy 338.175759 -336.215494) (xy 338.187449 -336.228161)
			(xy 338.194904 -336.2325) (xy 338.283042 -336.278728) (xy 338.309204 -336.27822) (xy 338.320634 -336.271616)
			(xy 338.354723 -336.252133) (xy 338.425722 -336.218592) (xy 338.499399 -336.191437) (xy 338.575183 -336.170878)
			(xy 338.652483 -336.157075) (xy 338.730699 -336.150137) (xy 338.76996 -336.149696) (xy 338.81107 -336.150191)
			(xy 338.89294 -336.157775) (xy 338.97376 -336.172882) (xy 339.052841 -336.195384) (xy 339.129508 -336.225088)
			(xy 339.203107 -336.261741) (xy 339.273008 -336.305029) (xy 339.338617 -336.354584) (xy 339.399372 -336.409982)
			(xy 339.454755 -336.470751) (xy 339.504294 -336.536372) (xy 339.547565 -336.606284) (xy 339.5842 -336.679891)
			(xy 339.613885 -336.756566) (xy 339.636368 -336.835652) (xy 339.651455 -336.916476) (xy 339.659019 -336.998348)
			(xy 339.659177 -337.0128) (xy 343.199717 -337.0128) (xy 343.203707 -336.929019) (xy 343.215644 -336.845997)
			(xy 343.235419 -336.764486) (xy 343.262852 -336.685223) (xy 343.297695 -336.608927) (xy 343.339633 -336.536288)
			(xy 343.388286 -336.467965) (xy 343.443213 -336.404576) (xy 343.503917 -336.346695) (xy 343.569847 -336.294846)
			(xy 343.640408 -336.249499) (xy 343.71496 -336.211065) (xy 343.792828 -336.179892) (xy 343.873306 -336.156261)
			(xy 343.955666 -336.140388) (xy 344.039162 -336.132415) (xy 344.0811 -336.131916) (xy 344.11829 -336.132304)
			(xy 344.192403 -336.138594) (xy 344.265722 -336.151104) (xy 344.337728 -336.169745) (xy 344.372946 -336.1817)
			(xy 344.381143 -336.184214) (xy 344.398277 -336.184214) (xy 344.406474 -336.1817) (xy 344.441687 -336.169727)
			(xy 344.513691 -336.151076) (xy 344.587013 -336.13857) (xy 344.661129 -336.1323) (xy 344.69832 -336.131916)
			(xy 344.712798 -336.13217) (xy 344.724169 -336.131792) (xy 344.744841 -336.122355) (xy 344.759419 -336.104924)
			(xy 344.762836 -336.09407) (xy 344.771457 -336.062103) (xy 344.792812 -335.999426) (xy 344.805508 -335.968848)
			(xy 344.809054 -335.959252) (xy 344.809067 -335.938814) (xy 344.805508 -335.929224) (xy 344.788475 -335.887851)
			(xy 344.761859 -335.802423) (xy 344.743957 -335.714753) (xy 344.734952 -335.625729) (xy 344.734388 -335.58099)
			(xy 344.734388 -335.580736) (xy 344.734892 -335.538388) (xy 344.742943 -335.454074) (xy 344.758972 -335.370908)
			(xy 344.782833 -335.289641) (xy 344.814312 -335.211011) (xy 344.853123 -335.13573) (xy 344.898913 -335.064478)
			(xy 344.951269 -334.997902) (xy 345.009717 -334.936604) (xy 345.073727 -334.881139) (xy 345.142719 -334.83201)
			(xy 345.216069 -334.789661) (xy 345.293112 -334.754477) (xy 345.373151 -334.726775) (xy 345.45546 -334.706807)
			(xy 345.539295 -334.694754) (xy 345.623896 -334.690724) (xy 345.708497 -334.694754) (xy 345.792332 -334.706807)
			(xy 345.874641 -334.726775) (xy 345.95468 -334.754477) (xy 346.031723 -334.789661) (xy 346.105073 -334.83201)
			(xy 346.174065 -334.881139) (xy 346.238075 -334.936604) (xy 346.296523 -334.997902) (xy 346.348879 -335.064478)
			(xy 346.394669 -335.13573) (xy 346.43348 -335.211011) (xy 346.464959 -335.289641) (xy 346.48882 -335.370908)
			(xy 346.504849 -335.454074) (xy 346.5129 -335.538388) (xy 346.513404 -335.580736) (xy 346.513404 -335.58099)
			(xy 346.512849 -335.625729) (xy 346.50383 -335.714751) (xy 346.485921 -335.802418) (xy 346.459304 -335.887845)
			(xy 346.442284 -335.929224) (xy 346.438698 -335.938808) (xy 346.438711 -335.959257) (xy 346.442284 -335.968848)
			(xy 346.459319 -336.010255) (xy 346.48595 -336.095744) (xy 346.503854 -336.183477) (xy 346.51285 -336.272565)
			(xy 346.513404 -336.317336) (xy 346.513182 -336.348682) (xy 346.508857 -336.411225) (xy 346.504768 -336.442304)
			(xy 346.503244 -336.452972) (xy 346.508832 -336.473546) (xy 346.56268 -336.539586) (xy 346.569651 -336.547336)
			(xy 346.588142 -336.55691) (xy 346.598494 -336.558128) (xy 346.599002 -336.558128) (xy 346.640786 -336.561293)
			(xy 346.723543 -336.574476) (xy 346.804694 -336.595383) (xy 346.883519 -336.62383) (xy 346.959319 -336.659564)
			(xy 347.031422 -336.702268) (xy 347.09919 -336.751564) (xy 347.162022 -336.807015) (xy 347.21936 -336.868129)
			(xy 347.270696 -336.934365) (xy 347.315576 -337.005135) (xy 347.353601 -337.079812) (xy 347.384434 -337.157734)
			(xy 347.407802 -337.238211) (xy 347.423499 -337.320529) (xy 347.431384 -337.403958) (xy 347.431868 -337.445858)
			(xy 347.431868 -337.446874) (xy 347.431339 -337.489485) (xy 347.423121 -337.57431) (xy 347.406824 -337.657959)
			(xy 347.382599 -337.739665) (xy 347.367098 -337.77936) (xy 347.363634 -337.789438) (xy 347.36443 -337.810709)
			(xy 347.368622 -337.820508) (xy 347.385666 -337.856788) (xy 347.413917 -337.931808) (xy 347.435302 -338.009067)
			(xy 347.449648 -338.087936) (xy 347.456838 -338.167776) (xy 347.457268 -338.207858) (xy 347.456674 -338.254253)
			(xy 347.447033 -338.346541) (xy 347.42784 -338.437325) (xy 347.399305 -338.525619) (xy 347.381068 -338.568284)
			(xy 347.377284 -338.578233) (xy 347.377268 -338.599491) (xy 347.381068 -338.609432) (xy 347.399296 -338.652101)
			(xy 347.427845 -338.740391) (xy 347.447043 -338.831174) (xy 347.456681 -338.923462) (xy 347.457268 -338.969858)
			(xy 347.456674 -339.016253) (xy 347.447033 -339.108541) (xy 347.42784 -339.199325) (xy 347.399305 -339.287619)
			(xy 347.381068 -339.330284) (xy 347.377284 -339.340233) (xy 347.377268 -339.361491) (xy 347.381068 -339.371432)
			(xy 347.39928 -339.414039) (xy 347.427799 -339.502205) (xy 347.446995 -339.592859) (xy 347.456658 -339.685018)
			(xy 347.457268 -339.73135) (xy 347.457268 -339.731858) (xy 347.456747 -339.772964) (xy 347.449167 -339.854825)
			(xy 347.434067 -339.935639) (xy 347.411576 -340.014714) (xy 347.381885 -340.091377) (xy 347.345249 -340.164975)
			(xy 347.30198 -340.234878) (xy 347.252446 -340.300492) (xy 347.19707 -340.361256) (xy 347.136324 -340.416653)
			(xy 347.070727 -340.466209) (xy 347.000838 -340.509502) (xy 346.927254 -340.546163) (xy 346.8506 -340.575879)
			(xy 346.771533 -340.598397) (xy 346.690725 -340.613525) (xy 346.608866 -340.621133) (xy 346.56776 -340.62162)
			(xy 346.525159 -340.621134) (xy 346.440349 -340.612975) (xy 346.356708 -340.596745) (xy 346.275001 -340.572593)
			(xy 346.195978 -340.540739) (xy 346.120362 -340.501477) (xy 346.048846 -340.455165) (xy 345.982085 -340.402229)
			(xy 345.920691 -340.343152) (xy 345.865226 -340.278476) (xy 345.840304 -340.243922) (xy 345.834713 -340.236567)
			(xy 345.819465 -340.226159) (xy 345.810586 -340.223602) (xy 345.769427 -340.213207) (xy 345.689122 -340.185668)
			(xy 345.611806 -340.150603) (xy 345.538183 -340.108332) (xy 345.468921 -340.05924) (xy 345.40465 -340.003772)
			(xy 345.345957 -339.942434) (xy 345.293373 -339.875784) (xy 345.247379 -339.804427) (xy 345.208391 -339.729013)
			(xy 345.176765 -339.650228) (xy 345.152789 -339.568788) (xy 345.136679 -339.485435) (xy 345.128584 -339.400926)
			(xy 345.128088 -339.358478) (xy 345.128088 -339.358224) (xy 345.128648 -339.313485) (xy 345.137666 -339.224464)
			(xy 345.155574 -339.136796) (xy 345.182189 -339.051369) (xy 345.199208 -339.00999) (xy 345.202787 -339.000403)
			(xy 345.202779 -338.979957) (xy 345.199208 -338.970366) (xy 345.182177 -338.928958) (xy 345.155545 -338.843469)
			(xy 345.13764 -338.755736) (xy 345.128642 -338.666649) (xy 345.128088 -338.621878) (xy 345.128637 -338.577108)
			(xy 345.137642 -338.488021) (xy 345.15555 -338.400289) (xy 345.182178 -338.314799) (xy 345.199208 -338.27339)
			(xy 345.202787 -338.263803) (xy 345.202779 -338.243357) (xy 345.199208 -338.233766) (xy 345.182177 -338.192358)
			(xy 345.155545 -338.106869) (xy 345.13764 -338.019136) (xy 345.128642 -337.930049) (xy 345.128088 -337.885278)
			(xy 345.128088 -337.87334) (xy 345.101609 -337.867394) (xy 345.049374 -337.852651) (xy 345.023694 -337.843876)
			(xy 345.015497 -337.841362) (xy 344.998363 -337.841362) (xy 344.990166 -337.843876) (xy 344.95495 -337.855837)
			(xy 344.882946 -337.874492) (xy 344.809626 -337.887) (xy 344.73551 -337.893274) (xy 344.69832 -337.89366)
			(xy 344.661131 -337.893262) (xy 344.587018 -337.886974) (xy 344.513698 -337.874467) (xy 344.441692 -337.855829)
			(xy 344.406474 -337.843876) (xy 344.398277 -337.841362) (xy 344.381143 -337.841362) (xy 344.372946 -337.843876)
			(xy 344.337731 -337.855842) (xy 344.265728 -337.874496) (xy 344.192406 -337.887003) (xy 344.11829 -337.893275)
			(xy 344.0811 -337.89366) (xy 344.039162 -337.893185) (xy 343.955666 -337.885212) (xy 343.873306 -337.869339)
			(xy 343.792828 -337.845708) (xy 343.71496 -337.814535) (xy 343.640408 -337.776101) (xy 343.569847 -337.730754)
			(xy 343.503917 -337.678905) (xy 343.443213 -337.621024) (xy 343.388286 -337.557635) (xy 343.339633 -337.489312)
			(xy 343.297695 -337.416673) (xy 343.262852 -337.340377) (xy 343.235419 -337.261114) (xy 343.215644 -337.179603)
			(xy 343.203707 -337.096581) (xy 343.199717 -337.0128) (xy 339.659177 -337.0128) (xy 339.659468 -337.039458)
			(xy 339.6589 -337.084228) (xy 339.649901 -337.173314) (xy 339.631999 -337.261046) (xy 339.605375 -337.346537)
			(xy 339.588348 -337.387946) (xy 339.584808 -337.397544) (xy 339.584792 -337.41798) (xy 339.588348 -337.42757)
			(xy 339.605388 -337.468975) (xy 339.632018 -337.554465) (xy 339.649921 -337.642198) (xy 339.658915 -337.731287)
			(xy 339.659468 -337.776058) (xy 339.6589 -337.820828) (xy 339.649901 -337.909914) (xy 339.631999 -337.997646)
			(xy 339.605375 -338.083137) (xy 339.588348 -338.124546) (xy 339.584808 -338.134144) (xy 339.584792 -338.15458)
			(xy 339.588348 -338.16417) (xy 339.605377 -338.205545) (xy 339.631995 -338.290972) (xy 339.649897 -338.378641)
			(xy 339.658904 -338.467665) (xy 339.659468 -338.512404) (xy 339.659468 -338.512658) (xy 339.658947 -338.553764)
			(xy 339.651367 -338.635625) (xy 339.636267 -338.716439) (xy 339.613776 -338.795514) (xy 339.584085 -338.872177)
			(xy 339.547449 -338.945775) (xy 339.50418 -339.015678) (xy 339.454646 -339.081292) (xy 339.39927 -339.142056)
			(xy 339.338524 -339.197453) (xy 339.272927 -339.247009) (xy 339.203038 -339.290302) (xy 339.129454 -339.326963)
			(xy 339.0528 -339.356679) (xy 338.973733 -339.379197) (xy 338.892925 -339.394325) (xy 338.811066 -339.401933)
			(xy 338.76996 -339.40242) (xy 338.728351 -339.40191) (xy 338.645495 -339.394139) (xy 338.563727 -339.378669)
			(xy 338.483759 -339.355636) (xy 338.40629 -339.325239) (xy 338.331996 -339.287745) (xy 338.296504 -339.266022)
			(xy 338.287367 -339.260856) (xy 338.26665 -339.257639) (xy 338.246374 -339.262975) (xy 338.23783 -339.26907)
			(xy 338.204174 -339.295024) (xy 338.132784 -339.341153) (xy 338.057318 -339.380258) (xy 337.978465 -339.411983)
			(xy 337.896945 -339.436039) (xy 337.8135 -339.452205) (xy 337.728894 -339.460335) (xy 337.686396 -339.46084)
			(xy 337.645286 -339.460351) (xy 337.563418 -339.452764) (xy 337.482599 -339.437653) (xy 337.403519 -339.415149)
			(xy 337.326853 -339.385443) (xy 337.253256 -339.348789) (xy 337.183356 -339.3055) (xy 337.117748 -339.255944)
			(xy 337.056994 -339.200546) (xy 337.001611 -339.139778) (xy 336.952073 -339.074158) (xy 336.908801 -339.004246)
			(xy 336.872166 -338.93064) (xy 336.842479 -338.853967) (xy 336.819995 -338.774881) (xy 336.804905 -338.694058)
			(xy 336.797338 -338.612188) (xy 336.796888 -338.571078) (xy 336.797437 -338.526308) (xy 336.806442 -338.437221)
			(xy 336.82435 -338.349489) (xy 336.850978 -338.263999) (xy 336.868008 -338.22259) (xy 336.871587 -338.213003)
			(xy 336.871579 -338.192557) (xy 336.868008 -338.182966) (xy 336.850977 -338.141558) (xy 336.824345 -338.056069)
			(xy 336.80644 -337.968336) (xy 336.797442 -337.879249) (xy 336.796888 -337.834478) (xy 336.796888 -337.82254)
			(xy 336.770409 -337.816594) (xy 336.718174 -337.801851) (xy 336.692494 -337.793076) (xy 336.684297 -337.790562)
			(xy 336.667163 -337.790562) (xy 336.658966 -337.793076) (xy 336.62375 -337.805037) (xy 336.551746 -337.823692)
			(xy 336.478426 -337.8362) (xy 336.40431 -337.842474) (xy 336.36712 -337.84286) (xy 336.329931 -337.842462)
			(xy 336.255818 -337.836174) (xy 336.182498 -337.823667) (xy 336.110492 -337.805029) (xy 336.075274 -337.793076)
			(xy 336.067077 -337.790562) (xy 336.049943 -337.790562) (xy 336.041746 -337.793076) (xy 336.006531 -337.805042)
			(xy 335.934528 -337.823696) (xy 335.861206 -337.836203) (xy 335.78709 -337.842475) (xy 335.7499 -337.84286)
			(xy 335.707962 -337.842385) (xy 335.624466 -337.834412) (xy 335.542106 -337.818539) (xy 335.461628 -337.794908)
			(xy 335.38376 -337.763735) (xy 335.309208 -337.725301) (xy 335.238647 -337.679954) (xy 335.172717 -337.628105)
			(xy 335.112013 -337.570224) (xy 335.057086 -337.506835) (xy 335.008433 -337.438512) (xy 334.966495 -337.365873)
			(xy 334.931652 -337.289577) (xy 334.904219 -337.210314) (xy 334.884444 -337.128803) (xy 334.872507 -337.045781)
			(xy 334.868517 -336.962) (xy 331.296671 -336.962) (xy 331.301379 -337.012832) (xy 331.301852 -337.053936)
			(xy 331.301852 -337.05419) (xy 331.301293 -337.098929) (xy 331.292274 -337.18795) (xy 331.274367 -337.275618)
			(xy 331.247751 -337.361045) (xy 331.230732 -337.402424) (xy 331.227148 -337.412009) (xy 331.227161 -337.432457)
			(xy 331.230732 -337.442048) (xy 331.247764 -337.483456) (xy 331.274397 -337.568945) (xy 331.292302 -337.656677)
			(xy 331.301298 -337.745765) (xy 331.301852 -337.790536) (xy 331.301312 -337.835307) (xy 331.292305 -337.924394)
			(xy 331.274395 -338.012126) (xy 331.247763 -338.097615) (xy 331.230732 -338.139024) (xy 331.227148 -338.148609)
			(xy 331.227161 -338.169057) (xy 331.230732 -338.178648) (xy 331.247759 -338.220024) (xy 331.274376 -338.305451)
			(xy 331.292279 -338.39312) (xy 331.301287 -338.482143) (xy 331.301852 -338.526882) (xy 331.301852 -338.527136)
			(xy 331.301368 -338.568238) (xy 331.29378 -338.65009) (xy 331.278673 -338.730894) (xy 331.256175 -338.809959)
			(xy 331.226478 -338.886611) (xy 331.189836 -338.960196) (xy 331.14656 -339.030087) (xy 331.097021 -339.095686)
			(xy 331.041641 -339.156436) (xy 330.980892 -339.211816) (xy 330.915293 -339.261356) (xy 330.845403 -339.304632)
			(xy 330.771818 -339.341275) (xy 330.695167 -339.370972) (xy 330.616102 -339.393471) (xy 330.535298 -339.408579)
			(xy 330.453446 -339.416167) (xy 330.412344 -339.416644) (xy 330.411582 -339.416644) (xy 330.370042 -339.416142)
			(xy 330.287326 -339.408361) (xy 330.205695 -339.392907) (xy 330.125859 -339.369913) (xy 330.048513 -339.339581)
			(xy 329.97433 -339.302172) (xy 329.938888 -339.2805) (xy 329.929757 -339.275322) (xy 329.909036 -339.272112)
			(xy 329.888759 -339.277452) (xy 329.880214 -339.283548) (xy 329.846565 -339.30947) (xy 329.775191 -339.355528)
			(xy 329.699752 -339.394575) (xy 329.620935 -339.426254) (xy 329.539458 -339.450278) (xy 329.456062 -339.466427)
			(xy 329.371506 -339.474554) (xy 329.329034 -339.475064) (xy 329.32878 -339.475064) (xy 329.287675 -339.474667)
			(xy 329.205817 -339.46708) (xy 329.125007 -339.451972) (xy 329.045936 -339.429472) (xy 328.969279 -339.399772)
			(xy 328.895689 -339.363126) (xy 328.825795 -339.319846) (xy 328.760192 -339.270301) (xy 328.69944 -339.214915)
			(xy 328.644058 -339.154159) (xy 328.594518 -339.088553) (xy 328.551243 -339.018655) (xy 328.514602 -338.945062)
			(xy 328.484908 -338.868403) (xy 328.462414 -338.789331) (xy 328.447312 -338.70852) (xy 328.43973 -338.626661)
			(xy 328.439272 -338.585556) (xy 328.439272 -338.585302) (xy 328.43986 -338.540564) (xy 328.44887 -338.451543)
			(xy 328.466769 -338.363876) (xy 328.493377 -338.278448) (xy 328.510392 -338.237068) (xy 328.513984 -338.227485)
			(xy 328.513968 -338.207035) (xy 328.510392 -338.197444) (xy 328.493353 -338.156039) (xy 328.466723 -338.070549)
			(xy 328.44882 -337.982815) (xy 328.439825 -337.893727) (xy 328.439272 -337.848956) (xy 328.439272 -337.837018)
			(xy 328.412793 -337.831074) (xy 328.360558 -337.81633) (xy 328.334878 -337.807554) (xy 328.326681 -337.80504)
			(xy 328.309547 -337.80504) (xy 328.30135 -337.807554) (xy 328.266125 -337.819474) (xy 328.194118 -337.838068)
			(xy 328.120798 -337.850516) (xy 328.046689 -337.856728) (xy 328.009504 -337.857084) (xy 327.97232 -337.856715)
			(xy 327.898212 -337.850493) (xy 327.824892 -337.838051) (xy 327.752881 -337.819476) (xy 327.717658 -337.807554)
			(xy 327.709461 -337.80504) (xy 327.692327 -337.80504) (xy 327.68413 -337.807554) (xy 327.649029 -337.819442)
			(xy 327.577272 -337.837992) (xy 327.504209 -337.850438) (xy 327.430358 -337.856691) (xy 327.3933 -337.857084)
			(xy 327.392284 -337.857084) (xy 327.350358 -337.856653) (xy 327.266885 -337.848681) (xy 327.184547 -337.83281)
			(xy 327.104092 -337.809185) (xy 327.026246 -337.778019) (xy 326.951715 -337.739594) (xy 326.881174 -337.694259)
			(xy 326.815262 -337.642424) (xy 326.754575 -337.584559) (xy 326.699664 -337.521186) (xy 326.651025 -337.452882)
			(xy 326.609099 -337.380263) (xy 326.574266 -337.303987) (xy 326.546841 -337.224746) (xy 326.527072 -337.143257)
			(xy 326.515138 -337.060258) (xy 326.511148 -336.9765) (xy 322.941787 -336.9765) (xy 322.94581 -337.019944)
			(xy 322.946268 -337.061048) (xy 322.946268 -337.061302) (xy 322.945685 -337.10604) (xy 322.936674 -337.195061)
			(xy 322.918774 -337.282729) (xy 322.892164 -337.368156) (xy 322.875148 -337.409536) (xy 322.871556 -337.419119)
			(xy 322.871574 -337.439569) (xy 322.875148 -337.44916) (xy 322.892185 -337.490566) (xy 322.918816 -337.576056)
			(xy 322.93672 -337.663789) (xy 322.945715 -337.752877) (xy 322.946268 -337.797648) (xy 322.945697 -337.842418)
			(xy 322.936698 -337.931504) (xy 322.918797 -338.019236) (xy 322.892175 -338.104727) (xy 322.875148 -338.146136)
			(xy 322.871556 -338.155719) (xy 322.871574 -338.176169) (xy 322.875148 -338.18576) (xy 322.892174 -338.227136)
			(xy 322.918792 -338.312563) (xy 322.936696 -338.400232) (xy 322.945704 -338.489255) (xy 322.946268 -338.533994)
			(xy 322.946268 -338.534248) (xy 322.945879 -338.575352) (xy 322.938289 -338.65721) (xy 322.923179 -338.738019)
			(xy 322.900678 -338.817088) (xy 322.870976 -338.893744) (xy 322.834329 -338.967333) (xy 322.791048 -339.037226)
			(xy 322.741503 -339.102828) (xy 322.686116 -339.163578) (xy 322.62536 -339.218959) (xy 322.559753 -339.268498)
			(xy 322.489856 -339.311772) (xy 322.416264 -339.348412) (xy 322.339605 -339.378106) (xy 322.260533 -339.400599)
			(xy 322.179723 -339.415702) (xy 322.097864 -339.423283) (xy 322.05676 -339.423756) (xy 322.055998 -339.423756)
			(xy 322.014458 -339.423244) (xy 321.931742 -339.415465) (xy 321.850112 -339.400013) (xy 321.770276 -339.377021)
			(xy 321.69293 -339.34669) (xy 321.618746 -339.309284) (xy 321.583304 -339.287612) (xy 321.574167 -339.282447)
			(xy 321.55345 -339.279232) (xy 321.533175 -339.284566) (xy 321.52463 -339.29066) (xy 321.491012 -339.316622)
			(xy 321.419631 -339.362677) (xy 321.344187 -339.401718) (xy 321.265365 -339.433392) (xy 321.183883 -339.457409)
			(xy 321.100483 -339.47355) (xy 321.015924 -339.48167) (xy 320.97345 -339.482176) (xy 320.973196 -339.482176)
			(xy 320.932092 -339.481752) (xy 320.850234 -339.474166) (xy 320.769426 -339.459059) (xy 320.690356 -339.436561)
			(xy 320.613699 -339.406863) (xy 320.54011 -339.370219) (xy 320.470216 -339.326941) (xy 320.404613 -339.277398)
			(xy 320.343861 -339.222013) (xy 320.288479 -339.161259) (xy 320.238939 -339.095655) (xy 320.195664 -339.025759)
			(xy 320.159022 -338.952168) (xy 320.129327 -338.87551) (xy 320.106832 -338.796439) (xy 320.091729 -338.71563)
			(xy 320.084147 -338.633772) (xy 320.083688 -338.592668) (xy 320.083688 -338.592414) (xy 320.084245 -338.547675)
			(xy 320.093264 -338.458653) (xy 320.111172 -338.370986) (xy 320.137789 -338.285559) (xy 320.154808 -338.24418)
			(xy 320.158393 -338.234595) (xy 320.158381 -338.214147) (xy 320.154808 -338.204556) (xy 320.137774 -338.163149)
			(xy 320.111142 -338.07766) (xy 320.093238 -337.989927) (xy 320.084242 -337.900839) (xy 320.083688 -337.856068)
			(xy 320.083688 -337.84413) (xy 320.057209 -337.838184) (xy 320.004974 -337.823441) (xy 319.979294 -337.814666)
			(xy 319.971097 -337.812152) (xy 319.953963 -337.812152) (xy 319.945766 -337.814666) (xy 319.910549 -337.82661)
			(xy 319.838539 -337.845197) (xy 319.765217 -337.857638) (xy 319.691106 -337.863844) (xy 319.65392 -337.864196)
			(xy 319.616736 -337.863827) (xy 319.542628 -337.857606) (xy 319.469308 -337.845164) (xy 319.397297 -337.826589)
			(xy 319.362074 -337.814666) (xy 319.353877 -337.812152) (xy 319.336743 -337.812152) (xy 319.328546 -337.814666)
			(xy 319.293452 -337.826578) (xy 319.221693 -337.845121) (xy 319.148627 -337.85756) (xy 319.074774 -337.863807)
			(xy 319.037716 -337.864196) (xy 319.0367 -337.864196) (xy 318.994774 -337.863741) (xy 318.911301 -337.855771)
			(xy 318.828963 -337.839902) (xy 318.748507 -337.816278) (xy 318.670661 -337.785113) (xy 318.59613 -337.746689)
			(xy 318.525589 -337.701355) (xy 318.459676 -337.649521) (xy 318.398989 -337.591656) (xy 318.344078 -337.528284)
			(xy 318.295438 -337.45998) (xy 318.253512 -337.387361) (xy 318.218678 -337.311086) (xy 318.191253 -337.231846)
			(xy 318.171484 -337.150357) (xy 318.15955 -337.067358) (xy 318.155561 -336.9836) (xy 99.362614 -336.9836)
			(xy 99.373171 -336.999727) (xy 99.41309 -337.075842) (xy 99.445481 -337.155452) (xy 99.470043 -337.237815)
			(xy 99.486546 -337.322163) (xy 99.494837 -337.40771) (xy 99.495356 -337.450684) (xy 99.494854 -337.493421)
			(xy 99.48668 -337.578504) (xy 99.470386 -337.662411) (xy 99.446122 -337.744369) (xy 99.430586 -337.784186)
			(xy 99.426944 -337.794219) (xy 99.427619 -337.815536) (xy 99.431856 -337.825334) (xy 99.448914 -337.861614)
			(xy 99.477225 -337.936624) (xy 99.498666 -338.013878) (xy 99.513065 -338.092749) (xy 99.520304 -338.172597)
			(xy 99.520756 -338.212684) (xy 99.520272 -338.252763) (xy 99.512982 -338.33259) (xy 99.498549 -338.411439)
			(xy 99.488244 -338.450174) (xy 99.485843 -338.460698) (xy 99.489132 -338.482012) (xy 99.494594 -338.491322)
			(xy 99.517345 -338.52734) (xy 99.556637 -338.602937) (xy 99.588514 -338.681946) (xy 99.612684 -338.763644)
			(xy 99.628925 -338.847279) (xy 99.637089 -338.932085) (xy 99.637596 -338.974684) (xy 99.637001 -339.021087)
			(xy 99.627302 -339.113385) (xy 99.608039 -339.204171) (xy 99.579422 -339.292455) (xy 99.561142 -339.33511)
			(xy 99.557344 -339.345055) (xy 99.557338 -339.366316) (xy 99.561142 -339.376258) (xy 99.579397 -339.418922)
			(xy 99.607993 -339.507209) (xy 99.627252 -339.597991) (xy 99.636966 -339.690283) (xy 99.637596 -339.736684)
			(xy 99.637118 -339.777779) (xy 99.629538 -339.859619) (xy 99.614439 -339.94041) (xy 99.591952 -340.019465)
			(xy 99.562267 -340.096107) (xy 99.525639 -340.169684) (xy 99.482378 -340.239568) (xy 99.432856 -340.305164)
			(xy 99.377493 -340.36591) (xy 99.316762 -340.421291) (xy 99.251181 -340.470833) (xy 99.18131 -340.514113)
			(xy 99.107743 -340.550763) (xy 99.031109 -340.58047) (xy 98.952062 -340.60298) (xy 98.871275 -340.618102)
			(xy 98.789437 -340.625707) (xy 98.748342 -340.626192) (xy 98.747834 -340.626192) (xy 98.704859 -340.625663)
			(xy 98.619309 -340.617375) (xy 98.534957 -340.600874) (xy 98.45259 -340.576313) (xy 98.372977 -340.543922)
			(xy 98.296859 -340.504001) (xy 98.224947 -340.456925) (xy 98.157912 -340.403131) (xy 98.096378 -340.343122)
			(xy 98.040919 -340.277458) (xy 98.01606 -340.242398) (xy 98.010455 -340.235056) (xy 97.995216 -340.224641)
			(xy 97.986342 -340.222078) (xy 97.94544 -340.211492) (xy 97.865683 -340.183605) (xy 97.788928 -340.148281)
			(xy 97.715869 -340.105839) (xy 97.647164 -340.05666) (xy 97.583432 -340.001188) (xy 97.525246 -339.939922)
			(xy 97.473132 -339.873416) (xy 97.427559 -339.802268) (xy 97.388937 -339.727119) (xy 97.357615 -339.648646)
			(xy 97.333875 -339.567557) (xy 97.317931 -339.484583) (xy 97.309927 -339.40047) (xy 97.309432 -339.358224)
			(xy 97.309829 -339.321956) (xy 97.315809 -339.249667) (xy 97.327648 -339.178103) (xy 97.336102 -339.142832)
			(xy 97.338115 -339.132729) (xy 97.334853 -339.112411) (xy 97.329752 -339.103462) (xy 97.30766 -339.067807)
			(xy 97.269551 -338.993079) (xy 97.238646 -338.915096) (xy 97.215218 -338.83455) (xy 97.199477 -338.752156)
			(xy 97.191562 -338.668646) (xy 97.191068 -338.626704) (xy 97.191648 -338.581935) (xy 97.200654 -338.49285)
			(xy 97.218554 -338.405119) (xy 97.245168 -338.319627) (xy 97.262188 -338.278216) (xy 97.265753 -338.268625)
			(xy 97.265754 -338.248182) (xy 97.262188 -338.238592) (xy 97.245172 -338.197246) (xy 97.218563 -338.111882)
			(xy 97.20066 -338.024278) (xy 97.191642 -337.935319) (xy 97.191068 -337.890612) (xy 97.191068 -337.889596)
			(xy 97.191322 -337.878166) (xy 97.164844 -337.872216) (xy 97.112609 -337.857476) (xy 97.086928 -337.848702)
			(xy 97.078731 -337.846188) (xy 97.061597 -337.846188) (xy 97.0534 -337.848702) (xy 97.01818 -337.860638)
			(xy 96.946171 -337.879227) (xy 96.87285 -337.89167) (xy 96.798739 -337.897878) (xy 96.761554 -337.898232)
			(xy 96.724369 -337.89788) (xy 96.650261 -337.891654) (xy 96.576941 -337.879206) (xy 96.504931 -337.860627)
			(xy 96.469708 -337.848702) (xy 96.461511 -337.846188) (xy 96.444377 -337.846188) (xy 96.43618 -337.848702)
			(xy 96.401082 -337.860602) (xy 96.329324 -337.879149) (xy 96.25626 -337.891592) (xy 96.182408 -337.897841)
			(xy 96.14535 -337.898232) (xy 96.144334 -337.898232) (xy 96.102408 -337.897723) (xy 96.018934 -337.889755)
			(xy 95.936596 -337.873888) (xy 95.85614 -337.850267) (xy 95.778292 -337.819104) (xy 95.70376 -337.780683)
			(xy 95.633218 -337.73535) (xy 95.567304 -337.683517) (xy 95.506616 -337.625654) (xy 95.451703 -337.562283)
			(xy 95.403062 -337.493979) (xy 95.361135 -337.421361) (xy 95.3263 -337.345087) (xy 95.298874 -337.265846)
			(xy 95.279105 -337.184357) (xy 95.267171 -337.101358) (xy 95.263181 -337.0176) (xy 91.722641 -337.0176)
			(xy 91.722956 -337.044284) (xy 91.722404 -337.089054) (xy 91.71339 -337.178139) (xy 91.695482 -337.26587)
			(xy 91.668861 -337.351361) (xy 91.651836 -337.392772) (xy 91.648282 -337.402366) (xy 91.648276 -337.422805)
			(xy 91.651836 -337.432396) (xy 91.668872 -337.473803) (xy 91.695506 -337.559291) (xy 91.71341 -337.647024)
			(xy 91.722404 -337.736113) (xy 91.722956 -337.780884) (xy 91.722404 -337.825654) (xy 91.71339 -337.914739)
			(xy 91.695482 -338.00247) (xy 91.668861 -338.087961) (xy 91.651836 -338.129372) (xy 91.648282 -338.138966)
			(xy 91.648276 -338.159405) (xy 91.651836 -338.168996) (xy 91.668872 -338.210403) (xy 91.695506 -338.295891)
			(xy 91.71341 -338.383624) (xy 91.722404 -338.472713) (xy 91.722956 -338.517484) (xy 91.722432 -338.558593)
			(xy 91.714846 -338.64046) (xy 91.699738 -338.721278) (xy 91.677236 -338.800357) (xy 91.647532 -338.877021)
			(xy 91.610881 -338.950618) (xy 91.567594 -339.020518) (xy 91.518041 -339.086125) (xy 91.462645 -339.146879)
			(xy 91.401879 -339.202262) (xy 91.336261 -339.251801) (xy 91.266352 -339.295073) (xy 91.192747 -339.331709)
			(xy 91.116076 -339.361396) (xy 91.036993 -339.383882) (xy 90.956172 -339.398973) (xy 90.874303 -339.406541)
			(xy 90.833194 -339.406992) (xy 90.791589 -339.406554) (xy 90.70874 -339.398816) (xy 90.626975 -339.383379)
			(xy 90.547007 -339.360379) (xy 90.469535 -339.330016) (xy 90.395235 -339.292555) (xy 90.359738 -339.270848)
			(xy 90.350631 -339.26562) (xy 90.329893 -339.262421) (xy 90.309608 -339.267785) (xy 90.301064 -339.273896)
			(xy 90.267427 -339.299833) (xy 90.196051 -339.345891) (xy 90.12061 -339.384937) (xy 90.041791 -339.416615)
			(xy 89.960312 -339.440636) (xy 89.876914 -339.456781) (xy 89.792357 -339.464905) (xy 89.749884 -339.465412)
			(xy 89.74963 -339.465412) (xy 89.708522 -339.464959) (xy 89.626657 -339.457377) (xy 89.545841 -339.442274)
			(xy 89.466762 -339.41978) (xy 89.390096 -339.390087) (xy 89.316497 -339.353447) (xy 89.246591 -339.310173)
			(xy 89.180976 -339.260635) (xy 89.120211 -339.205254) (xy 89.064815 -339.144504) (xy 89.015259 -339.078902)
			(xy 88.971967 -339.009008) (xy 88.935308 -338.935418) (xy 88.905594 -338.85876) (xy 88.883079 -338.779687)
			(xy 88.867956 -338.698875) (xy 88.860352 -338.617012) (xy 88.859868 -338.575904) (xy 88.860448 -338.531135)
			(xy 88.869454 -338.44205) (xy 88.887354 -338.354319) (xy 88.913968 -338.268827) (xy 88.930988 -338.227416)
			(xy 88.934553 -338.217825) (xy 88.934554 -338.197382) (xy 88.930988 -338.187792) (xy 88.913972 -338.146446)
			(xy 88.887363 -338.061082) (xy 88.86946 -337.973478) (xy 88.860442 -337.884519) (xy 88.859868 -337.839812)
			(xy 88.859868 -337.838796) (xy 88.860122 -337.827366) (xy 88.833644 -337.821416) (xy 88.781409 -337.806676)
			(xy 88.755728 -337.797902) (xy 88.747531 -337.795388) (xy 88.730397 -337.795388) (xy 88.7222 -337.797902)
			(xy 88.68698 -337.809838) (xy 88.614971 -337.828427) (xy 88.54165 -337.84087) (xy 88.467539 -337.847078)
			(xy 88.430354 -337.847432) (xy 88.393169 -337.84708) (xy 88.319061 -337.840854) (xy 88.245741 -337.828406)
			(xy 88.173731 -337.809827) (xy 88.138508 -337.797902) (xy 88.130311 -337.795388) (xy 88.113177 -337.795388)
			(xy 88.10498 -337.797902) (xy 88.069882 -337.809802) (xy 87.998124 -337.828349) (xy 87.92506 -337.840792)
			(xy 87.851208 -337.847041) (xy 87.81415 -337.847432) (xy 87.813134 -337.847432) (xy 87.771208 -337.846923)
			(xy 87.687734 -337.838955) (xy 87.605396 -337.823088) (xy 87.52494 -337.799467) (xy 87.447092 -337.768304)
			(xy 87.37256 -337.729883) (xy 87.302018 -337.68455) (xy 87.236104 -337.632717) (xy 87.175416 -337.574854)
			(xy 87.120503 -337.511483) (xy 87.071862 -337.443179) (xy 87.029935 -337.370561) (xy 86.9951 -337.294287)
			(xy 86.967674 -337.215046) (xy 86.947905 -337.133557) (xy 86.935971 -337.050558) (xy 86.931981 -336.9668)
			(xy 83.360149 -336.9668) (xy 83.364863 -337.017649) (xy 83.36534 -337.058762) (xy 83.364781 -337.103532)
			(xy 83.35577 -337.192617) (xy 83.337863 -337.280348) (xy 83.311243 -337.365839) (xy 83.29422 -337.40725)
			(xy 83.290679 -337.416847) (xy 83.290665 -337.437283) (xy 83.29422 -337.446874) (xy 83.311248 -337.488284)
			(xy 83.337884 -337.573771) (xy 83.355791 -337.661503) (xy 83.364787 -337.750591) (xy 83.36534 -337.795362)
			(xy 83.364781 -337.840132) (xy 83.35577 -337.929217) (xy 83.337863 -338.016948) (xy 83.311243 -338.102439)
			(xy 83.29422 -338.14385) (xy 83.290679 -338.153447) (xy 83.290665 -338.173883) (xy 83.29422 -338.183474)
			(xy 83.311248 -338.224884) (xy 83.337884 -338.310371) (xy 83.355791 -338.398103) (xy 83.364787 -338.487191)
			(xy 83.36534 -338.531962) (xy 83.364865 -338.573077) (xy 83.357281 -338.654956) (xy 83.342174 -338.735786)
			(xy 83.319674 -338.814878) (xy 83.289971 -338.891556) (xy 83.253319 -338.965166) (xy 83.210032 -339.03508)
			(xy 83.160479 -339.100701) (xy 83.105082 -339.16147) (xy 83.044313 -339.216869) (xy 82.978693 -339.266423)
			(xy 82.90878 -339.309712) (xy 82.83517 -339.346364) (xy 82.758493 -339.376068) (xy 82.679402 -339.398571)
			(xy 82.598572 -339.413679) (xy 82.516693 -339.421265) (xy 82.475578 -339.421724) (xy 82.433968 -339.421253)
			(xy 82.351111 -339.413475) (xy 82.269342 -339.397998) (xy 82.189374 -339.374957) (xy 82.111906 -339.344554)
			(xy 82.037613 -339.307053) (xy 82.002122 -339.285326) (xy 81.992978 -339.280175) (xy 81.972265 -339.276953)
			(xy 81.951992 -339.282282) (xy 81.943448 -339.288374) (xy 81.909821 -339.314367) (xy 81.838426 -339.360491)
			(xy 81.762954 -339.399592) (xy 81.684096 -339.431311) (xy 81.602571 -339.455361) (xy 81.519123 -339.471521)
			(xy 81.434513 -339.479643) (xy 81.392014 -339.480144) (xy 81.350899 -339.479688) (xy 81.269019 -339.472102)
			(xy 81.188189 -339.456993) (xy 81.109097 -339.434491) (xy 81.032419 -339.404786) (xy 80.95881 -339.368133)
			(xy 80.888896 -339.324845) (xy 80.823275 -339.27529) (xy 80.762506 -339.219892) (xy 80.707108 -339.159122)
			(xy 80.657553 -339.093501) (xy 80.614265 -339.023587) (xy 80.577612 -338.949977) (xy 80.547908 -338.873299)
			(xy 80.525406 -338.794207) (xy 80.510297 -338.713377) (xy 80.502712 -338.631497) (xy 80.502252 -338.590382)
			(xy 80.502826 -338.545613) (xy 80.511834 -338.456528) (xy 80.529735 -338.368797) (xy 80.556351 -338.283305)
			(xy 80.573372 -338.241894) (xy 80.576945 -338.232306) (xy 80.576939 -338.211861) (xy 80.573372 -338.20227)
			(xy 80.556348 -338.160927) (xy 80.529742 -338.075562) (xy 80.511841 -337.987957) (xy 80.502825 -337.898997)
			(xy 80.502252 -337.85429) (xy 80.502252 -337.853274) (xy 80.502506 -337.841844) (xy 80.476028 -337.835896)
			(xy 80.423793 -337.821155) (xy 80.398112 -337.81238) (xy 80.389915 -337.809866) (xy 80.372781 -337.809866)
			(xy 80.364584 -337.81238) (xy 80.329366 -337.824336) (xy 80.257364 -337.842992) (xy 80.184043 -337.855502)
			(xy 80.109928 -337.861777) (xy 80.072738 -337.862164) (xy 80.035549 -337.861761) (xy 79.961436 -337.855475)
			(xy 79.888116 -337.842969) (xy 79.81611 -337.824332) (xy 79.780892 -337.81238) (xy 79.772695 -337.809866)
			(xy 79.755561 -337.809866) (xy 79.747364 -337.81238) (xy 79.712148 -337.824342) (xy 79.640145 -337.842996)
			(xy 79.566824 -337.855505) (xy 79.492708 -337.861778) (xy 79.455518 -337.862164) (xy 79.413579 -337.861698)
			(xy 79.330081 -337.853726) (xy 79.247718 -337.837853) (xy 79.167237 -337.814224) (xy 79.089367 -337.783051)
			(xy 79.014813 -337.744616) (xy 78.94425 -337.69927) (xy 78.878316 -337.64742) (xy 78.81761 -337.589539)
			(xy 78.762681 -337.526148) (xy 78.714027 -337.457824) (xy 78.672087 -337.385183) (xy 78.637243 -337.308885)
			(xy 78.609809 -337.229621) (xy 78.590033 -337.148107) (xy 78.578096 -337.065083) (xy 78.574105 -336.9813)
			(xy 75.005252 -336.9813) (xy 75.00928 -337.024761) (xy 75.009756 -337.065874) (xy 75.009201 -337.110644)
			(xy 75.000188 -337.199729) (xy 74.982281 -337.28746) (xy 74.95566 -337.372951) (xy 74.938636 -337.414362)
			(xy 74.935088 -337.423957) (xy 74.935078 -337.444395) (xy 74.938636 -337.453986) (xy 74.955669 -337.495394)
			(xy 74.982303 -337.580882) (xy 75.000209 -337.668615) (xy 75.009203 -337.757703) (xy 75.009756 -337.802474)
			(xy 75.009201 -337.847244) (xy 75.000188 -337.936329) (xy 74.982281 -338.02406) (xy 74.95566 -338.109551)
			(xy 74.938636 -338.150962) (xy 74.935088 -338.160557) (xy 74.935078 -338.180995) (xy 74.938636 -338.190586)
			(xy 74.955669 -338.231994) (xy 74.982303 -338.317482) (xy 75.000209 -338.405215) (xy 75.009203 -338.494303)
			(xy 75.009756 -338.539074) (xy 75.009277 -338.580189) (xy 75.001692 -338.662067) (xy 74.986584 -338.742897)
			(xy 74.964083 -338.821988) (xy 74.93438 -338.898665) (xy 74.897729 -338.972274) (xy 74.854442 -339.042187)
			(xy 74.804888 -339.107809) (xy 74.749492 -339.168577) (xy 74.688724 -339.223976) (xy 74.623104 -339.27353)
			(xy 74.553192 -339.316819) (xy 74.479583 -339.353472) (xy 74.402907 -339.383177) (xy 74.323816 -339.40568)
			(xy 74.242987 -339.420789) (xy 74.161109 -339.428376) (xy 74.119994 -339.428836) (xy 74.078384 -339.428356)
			(xy 73.995528 -339.420579) (xy 73.913759 -339.405104) (xy 73.833791 -339.382065) (xy 73.756322 -339.351663)
			(xy 73.682029 -339.314164) (xy 73.646538 -339.292438) (xy 73.63743 -339.287211) (xy 73.616693 -339.284013)
			(xy 73.596408 -339.289376) (xy 73.587864 -339.295486) (xy 73.554233 -339.321473) (xy 73.482838 -339.367598)
			(xy 73.407368 -339.406699) (xy 73.32851 -339.438419) (xy 73.246986 -339.46247) (xy 73.163538 -339.47863)
			(xy 73.078929 -339.486754) (xy 73.03643 -339.487256) (xy 72.995315 -339.486773) (xy 72.913437 -339.479188)
			(xy 72.832607 -339.464081) (xy 72.753517 -339.44158) (xy 72.67684 -339.411877) (xy 72.60323 -339.375226)
			(xy 72.533317 -339.33194) (xy 72.467696 -339.282387) (xy 72.406927 -339.22699) (xy 72.351529 -339.166223)
			(xy 72.301974 -339.100603) (xy 72.258685 -339.030691) (xy 72.222032 -338.957082) (xy 72.192327 -338.880406)
			(xy 72.169824 -338.801316) (xy 72.154715 -338.720487) (xy 72.147128 -338.638609) (xy 72.146668 -338.597494)
			(xy 72.147245 -338.552725) (xy 72.156251 -338.46364) (xy 72.174152 -338.375909) (xy 72.200767 -338.290417)
			(xy 72.217788 -338.249006) (xy 72.221359 -338.239417) (xy 72.221356 -338.218972) (xy 72.217788 -338.209382)
			(xy 72.200768 -338.168037) (xy 72.174161 -338.082673) (xy 72.156259 -337.995068) (xy 72.147241 -337.906109)
			(xy 72.146668 -337.861402) (xy 72.146668 -337.860386) (xy 72.146922 -337.848956) (xy 72.120444 -337.843006)
			(xy 72.068209 -337.828266) (xy 72.042528 -337.819492) (xy 72.034331 -337.816978) (xy 72.017197 -337.816978)
			(xy 72.009 -337.819492) (xy 71.973781 -337.831444) (xy 71.901779 -337.850101) (xy 71.828459 -337.862612)
			(xy 71.754344 -337.868888) (xy 71.717154 -337.869276) (xy 71.679965 -337.868873) (xy 71.605852 -337.862587)
			(xy 71.532532 -337.850082) (xy 71.460526 -337.831445) (xy 71.425308 -337.819492) (xy 71.417111 -337.816978)
			(xy 71.399977 -337.816978) (xy 71.39178 -337.819492) (xy 71.356562 -337.83145) (xy 71.28456 -337.850105)
			(xy 71.211239 -337.862615) (xy 71.137124 -337.868889) (xy 71.099934 -337.869276) (xy 71.057995 -337.868786)
			(xy 70.974497 -337.860816) (xy 70.892134 -337.844945) (xy 70.811653 -337.821316) (xy 70.733783 -337.790144)
			(xy 70.659228 -337.751711) (xy 70.588664 -337.706365) (xy 70.522731 -337.654517) (xy 70.462025 -337.596636)
			(xy 70.407095 -337.533246) (xy 70.35844 -337.464922) (xy 70.3165 -337.392282) (xy 70.281655 -337.315985)
			(xy 70.254221 -337.23672) (xy 70.234446 -337.155207) (xy 70.222508 -337.072183) (xy 70.218517 -336.9884)
			(xy 2.509012 -336.9884) (xy 2.509012 -341.9277) (xy 103.538816 -341.9277) (xy 103.542807 -341.843921)
			(xy 103.554743 -341.760902) (xy 103.574517 -341.679392) (xy 103.601948 -341.600131) (xy 103.63679 -341.523837)
			(xy 103.678726 -341.4512) (xy 103.727376 -341.382878) (xy 103.7823 -341.319489) (xy 103.843001 -341.261608)
			(xy 103.908929 -341.20976) (xy 103.979486 -341.164412) (xy 104.054035 -341.125977) (xy 104.131899 -341.094802)
			(xy 104.212375 -341.071169) (xy 104.294732 -341.055293) (xy 104.378225 -341.047317) (xy 104.420162 -341.046816)
			(xy 104.457351 -341.047215) (xy 104.531464 -341.053502) (xy 104.604784 -341.066008) (xy 104.67679 -341.084646)
			(xy 104.712008 -341.0966) (xy 104.720205 -341.099114) (xy 104.737339 -341.099114) (xy 104.745536 -341.0966)
			(xy 104.780752 -341.084638) (xy 104.852755 -341.065983) (xy 104.926076 -341.053475) (xy 105.000192 -341.047202)
			(xy 105.037382 -341.046816) (xy 105.07218 -341.047578) (xy 105.081741 -341.004913) (xy 105.108207 -340.921573)
			(xy 105.125012 -340.881208) (xy 105.128629 -340.871492) (xy 105.128644 -340.850784) (xy 105.125012 -340.841076)
			(xy 105.107898 -340.799819) (xy 105.081109 -340.714608) (xy 105.063074 -340.627124) (xy 105.053979 -340.538265)
			(xy 105.053384 -340.493604) (xy 105.053384 -340.492842) (xy 105.053883 -340.450917) (xy 105.061853 -340.367446)
			(xy 105.077722 -340.285111) (xy 105.101345 -340.204657) (xy 105.132509 -340.126813) (xy 105.170932 -340.052283)
			(xy 105.216265 -339.981744) (xy 105.268098 -339.915833) (xy 105.325961 -339.855147) (xy 105.389331 -339.800237)
			(xy 105.457634 -339.751599) (xy 105.530251 -339.709674) (xy 105.606524 -339.674841) (xy 105.685763 -339.647416)
			(xy 105.767249 -339.627647) (xy 105.850246 -339.615714) (xy 105.934002 -339.611725) (xy 106.017758 -339.615714)
			(xy 106.100755 -339.627647) (xy 106.182241 -339.647416) (xy 106.26148 -339.674841) (xy 106.337753 -339.709674)
			(xy 106.41037 -339.751599) (xy 106.478673 -339.800237) (xy 106.542043 -339.855147) (xy 106.599906 -339.915833)
			(xy 106.651739 -339.981744) (xy 106.697072 -340.052283) (xy 106.735495 -340.126813) (xy 106.766659 -340.204657)
			(xy 106.790282 -340.285111) (xy 106.806151 -340.367446) (xy 106.814121 -340.450917) (xy 106.81462 -340.492842)
			(xy 106.81462 -340.493604) (xy 106.814051 -340.538267) (xy 106.804977 -340.627133) (xy 106.786945 -340.714621)
			(xy 106.760139 -340.799831) (xy 106.742992 -340.841076) (xy 106.739326 -340.850777) (xy 106.739342 -340.871499)
			(xy 106.742992 -340.881208) (xy 106.751628 -340.901528) (xy 106.756582 -340.912278) (xy 106.774248 -340.927996)
			(xy 106.797062 -340.934212) (xy 106.808778 -340.932516) (xy 106.8525 -340.924198) (xy 106.941059 -340.915292)
			(xy 106.985562 -340.914736) (xy 106.98607 -340.914736) (xy 107.027176 -340.915241) (xy 107.109038 -340.922823)
			(xy 107.189852 -340.937924) (xy 107.268928 -340.960416) (xy 107.345591 -340.990108) (xy 107.419189 -341.026745)
			(xy 107.489092 -341.070016) (xy 107.554706 -341.119551) (xy 107.61547 -341.174927) (xy 107.670867 -341.235674)
			(xy 107.720423 -341.301272) (xy 107.763716 -341.371161) (xy 107.800377 -341.444747) (xy 107.830093 -341.521401)
			(xy 107.85261 -341.60047) (xy 107.867738 -341.681278) (xy 107.875346 -341.763138) (xy 107.875832 -341.804244)
			(xy 107.875268 -341.849014) (xy 107.867795 -341.9229) (xy 351.475729 -341.9229) (xy 351.479719 -341.839138)
			(xy 351.491654 -341.756134) (xy 351.511424 -341.674641) (xy 351.538852 -341.595396) (xy 351.573688 -341.519117)
			(xy 351.615617 -341.446494) (xy 351.66426 -341.378187) (xy 351.719176 -341.314813) (xy 351.779867 -341.256945)
			(xy 351.845785 -341.205109) (xy 351.916331 -341.159774) (xy 351.990867 -341.12135) (xy 352.068718 -341.090185)
			(xy 352.149179 -341.066562) (xy 352.231522 -341.050694) (xy 352.314999 -341.042726) (xy 352.356928 -341.042244)
			(xy 352.357944 -341.042244) (xy 352.395001 -341.04264) (xy 352.46885 -341.048907) (xy 352.541913 -341.061352)
			(xy 352.613673 -341.079887) (xy 352.648774 -341.091774) (xy 352.656971 -341.094288) (xy 352.674105 -341.094288)
			(xy 352.682302 -341.091774) (xy 352.717522 -341.079841) (xy 352.789531 -341.06125) (xy 352.862852 -341.048806)
			(xy 352.936963 -341.042598) (xy 352.974148 -341.042244) (xy 352.988626 -341.042244) (xy 352.999994 -341.041829)
			(xy 353.020668 -341.032414) (xy 353.035248 -341.014994) (xy 353.038664 -341.004144) (xy 353.047281 -340.972176)
			(xy 353.068638 -340.909499) (xy 353.081336 -340.878922) (xy 353.084895 -340.86933) (xy 353.084899 -340.848889)
			(xy 353.081336 -340.839298) (xy 353.064328 -340.797915) (xy 353.037705 -340.71249) (xy 353.019796 -340.624824)
			(xy 353.010783 -340.535802) (xy 353.010216 -340.491064) (xy 353.010216 -340.49081) (xy 353.01072 -340.448462)
			(xy 353.018771 -340.364148) (xy 353.0348 -340.280982) (xy 353.058661 -340.199715) (xy 353.09014 -340.121085)
			(xy 353.128951 -340.045804) (xy 353.174741 -339.974552) (xy 353.227097 -339.907976) (xy 353.285545 -339.846678)
			(xy 353.349555 -339.791213) (xy 353.418547 -339.742084) (xy 353.491897 -339.699735) (xy 353.56894 -339.664551)
			(xy 353.648979 -339.636849) (xy 353.731288 -339.616881) (xy 353.815123 -339.604828) (xy 353.899724 -339.600798)
			(xy 353.984325 -339.604828) (xy 354.06816 -339.616881) (xy 354.150469 -339.636849) (xy 354.230508 -339.664551)
			(xy 354.307551 -339.699735) (xy 354.380901 -339.742084) (xy 354.449893 -339.791213) (xy 354.513903 -339.846678)
			(xy 354.572351 -339.907976) (xy 354.624707 -339.974552) (xy 354.670497 -340.045804) (xy 354.709308 -340.121085)
			(xy 354.740787 -340.199715) (xy 354.764648 -340.280982) (xy 354.780677 -340.364148) (xy 354.788728 -340.448462)
			(xy 354.789232 -340.49081) (xy 354.789232 -340.491064) (xy 354.788666 -340.535802) (xy 354.779649 -340.624824)
			(xy 354.761744 -340.712491) (xy 354.73513 -340.797919) (xy 354.718112 -340.839298) (xy 354.714539 -340.848887)
			(xy 354.714543 -340.869332) (xy 354.718112 -340.878922) (xy 354.735129 -340.920302) (xy 354.761749 -341.005728)
			(xy 354.779655 -341.093395) (xy 354.788666 -341.182417) (xy 354.789232 -341.227156) (xy 354.789232 -341.228172)
			(xy 354.789643 -341.238195) (xy 354.79731 -341.256718) (xy 354.811486 -341.270892) (xy 354.830009 -341.278557)
			(xy 354.840032 -341.278972) (xy 354.840286 -341.278972) (xy 354.84794 -341.278603) (xy 354.862532 -341.273956)
			(xy 354.868988 -341.269828) (xy 354.869242 -341.269828) (xy 354.906515 -341.244617) (xy 354.985224 -341.200991)
			(xy 355.067937 -341.165538) (xy 355.153807 -341.13862) (xy 355.241957 -341.120513) (xy 355.331485 -341.111402)
			(xy 355.37648 -341.110824) (xy 355.376988 -341.110824) (xy 355.418092 -341.111264) (xy 355.499949 -341.118848)
			(xy 355.580757 -341.133953) (xy 355.659827 -341.15645) (xy 355.736484 -341.186147) (xy 355.810073 -341.22279)
			(xy 355.879967 -341.266067) (xy 355.94557 -341.315609) (xy 356.006322 -341.370992) (xy 356.061704 -341.431745)
			(xy 356.111244 -341.497349) (xy 356.15452 -341.567245) (xy 356.191162 -341.640835) (xy 356.220857 -341.717492)
			(xy 356.243352 -341.796562) (xy 356.258455 -341.877371) (xy 356.266037 -341.959228) (xy 356.266496 -342.000332)
			(xy 356.266496 -342.000586) (xy 356.26594 -342.045325) (xy 356.256921 -342.134347) (xy 356.239013 -342.222014)
			(xy 356.212396 -342.307441) (xy 356.195376 -342.34882) (xy 356.191792 -342.358405) (xy 356.191804 -342.378853)
			(xy 356.195376 -342.388444) (xy 356.212409 -342.429852) (xy 356.239041 -342.515341) (xy 356.256946 -342.603073)
			(xy 356.265942 -342.692161) (xy 356.266496 -342.736932) (xy 356.265952 -342.781703) (xy 356.256945 -342.87079)
			(xy 356.239036 -342.958522) (xy 356.212407 -343.044011) (xy 356.195376 -343.08542) (xy 356.191792 -343.095005)
			(xy 356.191804 -343.115453) (xy 356.195376 -343.125044) (xy 356.212398 -343.166422) (xy 356.239017 -343.251848)
			(xy 356.256922 -343.339516) (xy 356.265931 -343.428539) (xy 356.266496 -343.473278) (xy 356.266496 -343.473532)
			(xy 356.266064 -343.514635) (xy 356.258476 -343.596491) (xy 356.243368 -343.677298) (xy 356.220868 -343.756366)
			(xy 356.191169 -343.83302) (xy 356.154525 -343.906608) (xy 356.111246 -343.9765) (xy 356.061704 -344.042101)
			(xy 356.00632 -344.102851) (xy 355.945567 -344.158232) (xy 355.879964 -344.207771) (xy 355.810069 -344.251046)
			(xy 355.73648 -344.287687) (xy 355.659824 -344.317382) (xy 355.580755 -344.339878) (xy 355.499948 -344.354982)
			(xy 355.418091 -344.362566) (xy 355.376988 -344.36304) (xy 355.376226 -344.36304) (xy 355.334685 -344.362565)
			(xy 355.251968 -344.35478) (xy 355.170337 -344.33932) (xy 355.090501 -344.316321) (xy 355.013156 -344.285984)
			(xy 354.938974 -344.248571) (xy 354.903532 -344.226896) (xy 354.894382 -344.221758) (xy 354.873674 -344.218535)
			(xy 354.853403 -344.223857) (xy 354.844858 -344.229944) (xy 354.811228 -344.255891) (xy 354.73985 -344.301947)
			(xy 354.664408 -344.340991) (xy 354.585588 -344.372667) (xy 354.504107 -344.396686) (xy 354.420709 -344.412831)
			(xy 354.336151 -344.420953) (xy 354.293678 -344.42146) (xy 354.293424 -344.42146) (xy 354.25232 -344.421025)
			(xy 354.170462 -344.413441) (xy 354.089653 -344.398337) (xy 354.010583 -344.375841) (xy 353.933926 -344.346144)
			(xy 353.860336 -344.309501) (xy 353.790441 -344.266224) (xy 353.724837 -344.216682) (xy 353.664085 -344.161298)
			(xy 353.608703 -344.100544) (xy 353.559163 -344.03494) (xy 353.515887 -343.965043) (xy 353.479246 -343.891453)
			(xy 353.449552 -343.814794) (xy 353.427057 -343.735723) (xy 353.411955 -343.654914) (xy 353.404374 -343.573056)
			(xy 353.403916 -343.531952) (xy 353.403916 -343.531698) (xy 353.4045 -343.48696) (xy 353.413511 -343.397939)
			(xy 353.431411 -343.310272) (xy 353.45802 -343.224844) (xy 353.475036 -343.183464) (xy 353.478628 -343.173881)
			(xy 353.47861 -343.153431) (xy 353.475036 -343.14384) (xy 353.457998 -343.102434) (xy 353.431368 -343.016945)
			(xy 353.413464 -342.929211) (xy 353.404469 -342.840123) (xy 353.403916 -342.795352) (xy 353.403916 -342.783414)
			(xy 353.377438 -342.777466) (xy 353.325203 -342.762725) (xy 353.299522 -342.75395) (xy 353.291325 -342.751436)
			(xy 353.274191 -342.751436) (xy 353.265994 -342.75395) (xy 353.230774 -342.765885) (xy 353.158765 -342.784475)
			(xy 353.085444 -342.796919) (xy 353.011333 -342.803127) (xy 352.974148 -342.80348) (xy 352.936964 -342.803098)
			(xy 352.862857 -342.79688) (xy 352.789537 -342.784441) (xy 352.717525 -342.76587) (xy 352.682302 -342.75395)
			(xy 352.674105 -342.751436) (xy 352.656971 -342.751436) (xy 352.648774 -342.75395) (xy 352.613678 -342.765853)
			(xy 352.541919 -342.784399) (xy 352.468854 -342.796841) (xy 352.395002 -342.80309) (xy 352.357944 -342.80348)
			(xy 352.356928 -342.80348) (xy 352.314999 -342.803074) (xy 352.231522 -342.795106) (xy 352.149179 -342.779238)
			(xy 352.068718 -342.755615) (xy 351.990867 -342.72445) (xy 351.916331 -342.686026) (xy 351.845785 -342.640691)
			(xy 351.779867 -342.588855) (xy 351.719176 -342.530987) (xy 351.66426 -342.467613) (xy 351.615617 -342.399306)
			(xy 351.573688 -342.326683) (xy 351.538852 -342.250404) (xy 351.511424 -342.171159) (xy 351.491654 -342.089666)
			(xy 351.479719 -342.006662) (xy 351.475729 -341.9229) (xy 107.867795 -341.9229) (xy 107.866258 -341.938099)
			(xy 107.848353 -342.02583) (xy 107.821735 -342.111321) (xy 107.804712 -342.152732) (xy 107.80112 -342.162315)
			(xy 107.801136 -342.182765) (xy 107.804712 -342.192356) (xy 107.821734 -342.233768) (xy 107.848372 -342.319255)
			(xy 107.86628 -342.406986) (xy 107.875278 -342.496074) (xy 107.875832 -342.540844) (xy 107.875405 -342.579435)
			(xy 107.868704 -342.656327) (xy 107.855365 -342.732349) (xy 107.835489 -342.806929) (xy 107.822746 -342.843358)
			(xy 107.81982 -342.852801) (xy 107.820595 -342.872535) (xy 107.82427 -342.881712) (xy 107.843314 -342.925129)
			(xy 107.873091 -343.015145) (xy 107.893121 -343.107819) (xy 107.903177 -343.202097) (xy 107.903772 -343.249504)
			(xy 107.903199 -343.294273) (xy 107.894192 -343.383358) (xy 107.87629 -343.471089) (xy 107.849674 -343.556581)
			(xy 107.832652 -343.597992) (xy 107.829086 -343.607582) (xy 107.829087 -343.628025) (xy 107.832652 -343.637616)
			(xy 107.849695 -343.67902) (xy 107.876327 -343.76451) (xy 107.894229 -343.852244) (xy 107.903221 -343.941333)
			(xy 107.903772 -343.986104) (xy 107.903338 -344.0272) (xy 107.895755 -344.109042) (xy 107.880654 -344.189835)
			(xy 107.858164 -344.268891) (xy 107.828477 -344.345534) (xy 107.791846 -344.419112) (xy 107.748583 -344.488997)
			(xy 107.699057 -344.554593) (xy 107.643692 -344.61534) (xy 107.582958 -344.670721) (xy 107.517374 -344.720262)
			(xy 107.447499 -344.763541) (xy 107.37393 -344.80019) (xy 107.297294 -344.829896) (xy 107.218244 -344.852405)
			(xy 107.137454 -344.867525) (xy 107.055614 -344.875128) (xy 107.014518 -344.875612) (xy 107.01401 -344.875612)
			(xy 106.971454 -344.875048) (xy 106.886731 -344.866913) (xy 106.803172 -344.850725) (xy 106.72154 -344.826633)
			(xy 106.642582 -344.794856) (xy 106.567018 -344.755685) (xy 106.49554 -344.709478) (xy 106.428801 -344.656658)
			(xy 106.36741 -344.597706) (xy 106.311928 -344.533162) (xy 106.262863 -344.463615) (xy 106.220663 -344.389701)
			(xy 106.202734 -344.351102) (xy 106.197143 -344.340314) (xy 106.178175 -344.325188) (xy 106.166412 -344.322146)
			(xy 106.123815 -344.31302) (xy 106.04054 -344.287419) (xy 105.960165 -344.253801) (xy 105.883461 -344.212489)
			(xy 105.811162 -344.163878) (xy 105.74396 -344.108434) (xy 105.682498 -344.046687) (xy 105.627365 -343.979229)
			(xy 105.579089 -343.906705) (xy 105.538133 -343.829811) (xy 105.504888 -343.749281) (xy 105.479672 -343.665888)
			(xy 105.462727 -343.58043) (xy 105.454216 -343.493725) (xy 105.453688 -343.450164) (xy 105.454253 -343.405394)
			(xy 105.463263 -343.316309) (xy 105.481167 -343.228578) (xy 105.507785 -343.143087) (xy 105.524808 -343.101676)
			(xy 105.528395 -343.092092) (xy 105.528382 -343.071643) (xy 105.524808 -343.062052) (xy 105.508891 -343.02338)
			(xy 105.483531 -342.943684) (xy 105.46577 -342.861957) (xy 105.460292 -342.820498) (xy 105.458558 -342.81058)
			(xy 105.448632 -342.793088) (xy 105.43277 -342.780723) (xy 105.423208 -342.777572) (xy 105.40795 -342.773353)
			(xy 105.377717 -342.763951) (xy 105.362756 -342.758776) (xy 105.354559 -342.756262) (xy 105.337425 -342.756262)
			(xy 105.329228 -342.758776) (xy 105.294015 -342.770747) (xy 105.222011 -342.789399) (xy 105.148689 -342.801905)
			(xy 105.074572 -342.808175) (xy 105.037382 -342.80856) (xy 105.000192 -342.808173) (xy 104.926079 -342.801882)
			(xy 104.85276 -342.789372) (xy 104.780754 -342.770731) (xy 104.745536 -342.758776) (xy 104.737339 -342.756262)
			(xy 104.720205 -342.756262) (xy 104.712008 -342.758776) (xy 104.676797 -342.770753) (xy 104.604792 -342.789403)
			(xy 104.531469 -342.801908) (xy 104.457353 -342.808176) (xy 104.420162 -342.80856) (xy 104.378225 -342.808083)
			(xy 104.294732 -342.800107) (xy 104.212375 -342.784231) (xy 104.131899 -342.760598) (xy 104.054035 -342.729423)
			(xy 103.979486 -342.690988) (xy 103.908929 -342.64564) (xy 103.843001 -342.593792) (xy 103.7823 -342.535911)
			(xy 103.727376 -342.472522) (xy 103.678726 -342.4042) (xy 103.63679 -342.331563) (xy 103.601948 -342.255269)
			(xy 103.574517 -342.176008) (xy 103.554743 -342.094498) (xy 103.542807 -342.011479) (xy 103.538816 -341.9277)
			(xy 2.509012 -341.9277) (xy 2.509012 -345.238324) (xy 88.42502 -345.238324) (xy 88.42502 -345.237562)
			(xy 88.425476 -345.196455) (xy 88.433064 -345.114592) (xy 88.448171 -345.033778) (xy 88.470668 -344.954703)
			(xy 88.500364 -344.87804) (xy 88.537005 -344.804443) (xy 88.58028 -344.73454) (xy 88.629818 -344.668927)
			(xy 88.685198 -344.608163) (xy 88.745947 -344.552768) (xy 88.811546 -344.503212) (xy 88.881438 -344.459919)
			(xy 88.955025 -344.423259) (xy 89.031681 -344.393542) (xy 89.110751 -344.371024) (xy 89.19156 -344.355896)
			(xy 89.273421 -344.348287) (xy 89.314528 -344.3478) (xy 89.358923 -344.348358) (xy 89.447268 -344.357247)
			(xy 89.534288 -344.374894) (xy 89.619117 -344.401123) (xy 89.660222 -344.417904) (xy 89.668919 -344.421068)
			(xy 89.687398 -344.421734) (xy 89.69629 -344.419174) (xy 89.742575 -344.404089) (xy 89.837607 -344.382956)
			(xy 89.934379 -344.372329) (xy 89.983056 -344.371676) (xy 90.021372 -344.372058) (xy 90.097725 -344.378586)
			(xy 90.173232 -344.391667) (xy 90.247331 -344.411203) (xy 90.283538 -344.423746) (xy 90.291854 -344.426332)
			(xy 90.309258 -344.426332) (xy 90.317574 -344.423746) (xy 90.353782 -344.41121) (xy 90.427885 -344.391692)
			(xy 90.503391 -344.378612) (xy 90.579741 -344.372068) (xy 90.618056 -344.371676) (xy 90.664451 -344.372276)
			(xy 90.756739 -344.381916) (xy 90.847523 -344.401107) (xy 90.935817 -344.429641) (xy 90.978482 -344.447876)
			(xy 90.988424 -344.451682) (xy 91.009688 -344.451682) (xy 91.01963 -344.447876) (xy 91.062298 -344.429645)
			(xy 91.150588 -344.401097) (xy 91.241371 -344.381901) (xy 91.33366 -344.372263) (xy 91.380056 -344.371676)
			(xy 91.418372 -344.372058) (xy 91.494725 -344.378586) (xy 91.570232 -344.391667) (xy 91.644331 -344.411203)
			(xy 91.680538 -344.423746) (xy 91.688854 -344.426332) (xy 91.706258 -344.426332) (xy 91.714574 -344.423746)
			(xy 91.750782 -344.41121) (xy 91.824885 -344.391692) (xy 91.900391 -344.378612) (xy 91.976741 -344.372068)
			(xy 92.015056 -344.371676) (xy 92.053372 -344.372058) (xy 92.129725 -344.378586) (xy 92.205232 -344.391667)
			(xy 92.279331 -344.411203) (xy 92.315538 -344.423746) (xy 92.323854 -344.426332) (xy 92.341258 -344.426332)
			(xy 92.349574 -344.423746) (xy 92.385691 -344.411238) (xy 92.459606 -344.391753) (xy 92.534918 -344.378674)
			(xy 92.611074 -344.372097) (xy 92.649294 -344.371676) (xy 92.650056 -344.371676) (xy 92.691158 -344.372194)
			(xy 92.773012 -344.379775) (xy 92.853817 -344.394876) (xy 92.932883 -344.417369) (xy 93.009537 -344.447061)
			(xy 93.083125 -344.4837) (xy 93.153018 -344.526972) (xy 93.21862 -344.576508) (xy 93.279371 -344.631887)
			(xy 93.334753 -344.692634) (xy 93.384294 -344.758233) (xy 93.427571 -344.828123) (xy 93.464215 -344.901708)
			(xy 93.493912 -344.97836) (xy 93.51641 -345.057425) (xy 93.531517 -345.138229) (xy 93.539103 -345.220082)
			(xy 93.539564 -345.261184) (xy 93.539564 -345.261692) (xy 93.539139 -345.302203) (xy 93.531771 -345.38289)
			(xy 93.517086 -345.462571) (xy 93.495207 -345.540583) (xy 93.466315 -345.616279) (xy 93.448886 -345.652852)
			(xy 93.444973 -345.661871) (xy 93.443532 -345.68146) (xy 93.446092 -345.690952) (xy 93.460285 -345.736019)
			(xy 93.480192 -345.828387) (xy 93.490186 -345.922345) (xy 93.490796 -345.96959) (xy 93.490238 -346.015229)
			(xy 93.480936 -346.106032) (xy 93.462388 -346.195406) (xy 93.44914 -346.239084) (xy 93.446696 -346.248096)
			(xy 93.447735 -346.266724) (xy 93.451172 -346.275406) (xy 93.469867 -346.318487) (xy 93.49915 -346.407722)
			(xy 93.518862 -346.499547) (xy 93.527728 -346.583) (xy 200.85558 -346.583) (xy 200.856207 -346.536598)
			(xy 200.865897 -346.444301) (xy 200.88515 -346.353515) (xy 200.913758 -346.26523) (xy 200.932034 -346.222574)
			(xy 200.935843 -346.212632) (xy 200.935843 -346.191368) (xy 200.932034 -346.181426) (xy 200.913772 -346.138765)
			(xy 200.885179 -346.050477) (xy 200.865922 -345.959694) (xy 200.856209 -345.867401) (xy 200.85558 -345.821)
			(xy 200.856064 -345.779859) (xy 200.863695 -345.69793) (xy 200.878855 -345.617056) (xy 200.901414 -345.537926)
			(xy 200.931179 -345.461215) (xy 200.967897 -345.38758) (xy 200.989184 -345.35237) (xy 200.993752 -345.344157)
			(xy 200.997195 -345.3257) (xy 200.993752 -345.307243) (xy 200.989184 -345.29903) (xy 200.967885 -345.263826)
			(xy 200.931155 -345.190194) (xy 200.901383 -345.113484) (xy 200.878824 -345.034352) (xy 200.86367 -344.953474)
			(xy 200.856051 -344.871542) (xy 200.85558 -344.8304) (xy 200.856207 -344.783998) (xy 200.865897 -344.691701)
			(xy 200.88515 -344.600915) (xy 200.913758 -344.51263) (xy 200.932034 -344.469974) (xy 200.935843 -344.460032)
			(xy 200.935843 -344.438768) (xy 200.932034 -344.428826) (xy 200.913772 -344.386165) (xy 200.885179 -344.297877)
			(xy 200.865922 -344.207094) (xy 200.856209 -344.114801) (xy 200.85558 -344.0684) (xy 200.856084 -344.026039)
			(xy 200.864137 -343.941702) (xy 200.880171 -343.858512) (xy 200.904039 -343.777222) (xy 200.935527 -343.69857)
			(xy 200.974349 -343.623267) (xy 201.020152 -343.551995) (xy 201.072523 -343.485399) (xy 201.130988 -343.424084)
			(xy 201.195016 -343.368603) (xy 201.264028 -343.31946) (xy 201.337398 -343.2771) (xy 201.414463 -343.241905)
			(xy 201.494525 -343.214196) (xy 201.576858 -343.194222) (xy 201.660717 -343.182165) (xy 201.745342 -343.178134)
			(xy 201.829967 -343.182165) (xy 201.913826 -343.194222) (xy 201.996159 -343.214196) (xy 202.076221 -343.241905)
			(xy 202.153286 -343.2771) (xy 202.226656 -343.31946) (xy 202.295668 -343.368603) (xy 202.359696 -343.424084)
			(xy 202.418161 -343.485399) (xy 202.470532 -343.551995) (xy 202.516335 -343.623267) (xy 202.555157 -343.69857)
			(xy 202.586645 -343.777222) (xy 202.610513 -343.858512) (xy 202.626547 -343.941702) (xy 202.6346 -344.026039)
			(xy 202.635104 -344.0684) (xy 202.634479 -344.114802) (xy 202.624789 -344.2071) (xy 202.605534 -344.297885)
			(xy 202.576926 -344.38617) (xy 202.55865 -344.428826) (xy 202.554842 -344.438768) (xy 202.554842 -344.460032)
			(xy 202.55865 -344.469974) (xy 202.576911 -344.512635) (xy 202.605505 -344.600923) (xy 202.624762 -344.691706)
			(xy 202.634475 -344.783999) (xy 202.635104 -344.8304) (xy 202.634622 -344.871541) (xy 202.626991 -344.95347)
			(xy 202.611831 -345.034344) (xy 202.589272 -345.113474) (xy 202.559506 -345.190185) (xy 202.522787 -345.263821)
			(xy 202.5015 -345.29903) (xy 202.496933 -345.307243) (xy 202.493491 -345.3257) (xy 202.496933 -345.344157)
			(xy 202.5015 -345.35237) (xy 202.522797 -345.387575) (xy 202.559528 -345.461207) (xy 202.5893 -345.537917)
			(xy 202.61186 -345.617049) (xy 202.627014 -345.697926) (xy 202.634633 -345.779858) (xy 202.635104 -345.821)
			(xy 202.634479 -345.867402) (xy 202.624789 -345.9597) (xy 202.605534 -346.050485) (xy 202.576926 -346.13877)
			(xy 202.55865 -346.181426) (xy 202.554842 -346.191368) (xy 202.554842 -346.212632) (xy 202.55865 -346.222574)
			(xy 202.576911 -346.265235) (xy 202.605505 -346.353523) (xy 202.624762 -346.444306) (xy 202.634475 -346.536599)
			(xy 202.635104 -346.583) (xy 202.6346 -346.625361) (xy 202.626547 -346.709698) (xy 202.610513 -346.792888)
			(xy 202.586645 -346.874178) (xy 202.555157 -346.95283) (xy 202.516335 -347.028133) (xy 202.470532 -347.099405)
			(xy 202.418161 -347.166001) (xy 202.359696 -347.227316) (xy 202.295668 -347.282797) (xy 202.226656 -347.33194)
			(xy 202.153286 -347.3743) (xy 202.076221 -347.409495) (xy 201.996159 -347.437204) (xy 201.913826 -347.457178)
			(xy 201.829967 -347.469235) (xy 201.745342 -347.473267) (xy 201.660717 -347.469235) (xy 201.576858 -347.457178)
			(xy 201.494525 -347.437204) (xy 201.414463 -347.409495) (xy 201.337398 -347.3743) (xy 201.264028 -347.33194)
			(xy 201.195016 -347.282797) (xy 201.130988 -347.227316) (xy 201.072523 -347.166001) (xy 201.020152 -347.099405)
			(xy 200.974349 -347.028133) (xy 200.935527 -346.95283) (xy 200.904039 -346.874178) (xy 200.880171 -346.792888)
			(xy 200.864137 -346.709698) (xy 200.856084 -346.625361) (xy 200.85558 -346.583) (xy 93.527728 -346.583)
			(xy 93.528784 -346.592938) (xy 93.529404 -346.639896) (xy 93.528944 -346.681007) (xy 93.521356 -346.762877)
			(xy 93.506246 -346.843698) (xy 93.483741 -346.92278) (xy 93.454034 -346.999447) (xy 93.417379 -347.073045)
			(xy 93.374088 -347.142947) (xy 93.324531 -347.208555) (xy 93.269131 -347.26931) (xy 93.20836 -347.324693)
			(xy 93.142737 -347.374232) (xy 93.072823 -347.417503) (xy 92.999214 -347.454137) (xy 92.922539 -347.483822)
			(xy 92.843451 -347.506304) (xy 92.762626 -347.521391) (xy 92.680753 -347.528955) (xy 92.639642 -347.529404)
			(xy 92.601326 -347.529024) (xy 92.524973 -347.522495) (xy 92.449466 -347.509414) (xy 92.375367 -347.489878)
			(xy 92.33916 -347.477334) (xy 92.330844 -347.474748) (xy 92.31344 -347.474748) (xy 92.305124 -347.477334)
			(xy 92.268906 -347.489842) (xy 92.194807 -347.509368) (xy 92.119304 -347.522455) (xy 92.042956 -347.529008)
			(xy 92.004642 -347.529404) (xy 91.961529 -347.52892) (xy 91.875703 -347.520642) (xy 91.791081 -347.504091)
			(xy 91.70846 -347.479423) (xy 91.668346 -347.463618) (xy 91.658977 -347.460281) (xy 91.639107 -347.460281)
			(xy 91.629738 -347.463618) (xy 91.589623 -347.479419) (xy 91.506999 -347.504075) (xy 91.422379 -347.520627)
			(xy 91.336554 -347.528919) (xy 91.293442 -347.529404) (xy 91.255126 -347.529024) (xy 91.178773 -347.522495)
			(xy 91.103266 -347.509414) (xy 91.029167 -347.489878) (xy 90.99296 -347.477334) (xy 90.984644 -347.474748)
			(xy 90.96724 -347.474748) (xy 90.958924 -347.477334) (xy 90.922706 -347.489842) (xy 90.848607 -347.509368)
			(xy 90.773104 -347.522455) (xy 90.696756 -347.529008) (xy 90.658442 -347.529404) (xy 90.620126 -347.529024)
			(xy 90.543773 -347.522495) (xy 90.468266 -347.509414) (xy 90.394167 -347.489878) (xy 90.35796 -347.477334)
			(xy 90.349644 -347.474748) (xy 90.33224 -347.474748) (xy 90.323924 -347.477334) (xy 90.287706 -347.489842)
			(xy 90.213607 -347.509368) (xy 90.138104 -347.522455) (xy 90.061756 -347.529008) (xy 90.023442 -347.529404)
			(xy 89.985126 -347.529024) (xy 89.908773 -347.522495) (xy 89.833266 -347.509414) (xy 89.759167 -347.489878)
			(xy 89.72296 -347.477334) (xy 89.714644 -347.474748) (xy 89.69724 -347.474748) (xy 89.688924 -347.477334)
			(xy 89.652807 -347.489842) (xy 89.578892 -347.509327) (xy 89.50358 -347.522407) (xy 89.427424 -347.528983)
			(xy 89.389204 -347.529404) (xy 89.388442 -347.529404) (xy 89.347337 -347.528847) (xy 89.265478 -347.521267)
			(xy 89.184667 -347.506168) (xy 89.105593 -347.483678) (xy 89.028932 -347.453989) (xy 88.955336 -347.417355)
			(xy 88.885433 -347.374087) (xy 88.81982 -347.324556) (xy 88.759057 -347.269183) (xy 88.70366 -347.20844)
			(xy 88.654104 -347.142846) (xy 88.61081 -347.07296) (xy 88.574148 -346.999378) (xy 88.54443 -346.922728)
			(xy 88.52191 -346.843663) (xy 88.506779 -346.762857) (xy 88.499168 -346.681001) (xy 88.49868 -346.639896)
			(xy 88.49928 -346.594251) (xy 88.508675 -346.503445) (xy 88.527305 -346.414075) (xy 88.54059 -346.370402)
			(xy 88.543039 -346.361391) (xy 88.541996 -346.342762) (xy 88.538558 -346.33408) (xy 88.519895 -346.290993)
			(xy 88.490688 -346.201748) (xy 88.471043 -346.109924) (xy 88.461176 -346.016541) (xy 88.46058 -345.96959)
			(xy 88.460997 -345.930463) (xy 88.467845 -345.852508) (xy 88.481506 -345.775455) (xy 88.501874 -345.699897)
			(xy 88.514936 -345.663012) (xy 88.517951 -345.653293) (xy 88.516917 -345.632991) (xy 88.512904 -345.623642)
			(xy 88.496039 -345.587523) (xy 88.46806 -345.512874) (xy 88.44687 -345.436021) (xy 88.432638 -345.357582)
			(xy 88.425479 -345.278184) (xy 88.42502 -345.238324) (xy 2.509012 -345.238324) (xy 2.509012 -348.70949)
			(xy 28.410141 -348.70949) (xy 28.414132 -348.625708) (xy 28.426069 -348.542686) (xy 28.445844 -348.461173)
			(xy 28.473277 -348.38191) (xy 28.508121 -348.305613) (xy 28.550059 -348.232974) (xy 28.598712 -348.16465)
			(xy 28.65364 -348.101261) (xy 28.714345 -348.043379) (xy 28.780276 -347.99153) (xy 28.850838 -347.946183)
			(xy 28.92539 -347.907749) (xy 29.003259 -347.876576) (xy 29.083738 -347.852945) (xy 29.166099 -347.837072)
			(xy 29.249596 -347.829099) (xy 29.291534 -347.828616) (xy 29.328723 -347.829023) (xy 29.402836 -347.835307)
			(xy 29.476156 -347.847812) (xy 29.548162 -347.866448) (xy 29.58338 -347.8784) (xy 29.591577 -347.880914)
			(xy 29.608711 -347.880914) (xy 29.616908 -347.8784) (xy 29.652035 -347.866473) (xy 29.723849 -347.847849)
			(xy 29.796976 -347.835339) (xy 29.870898 -347.829031) (xy 29.907992 -347.828616) (xy 29.909516 -347.828616)
			(xy 29.916374 -347.82887) (xy 29.922431 -347.792721) (xy 29.939716 -347.721486) (xy 29.962803 -347.651915)
			(xy 29.976826 -347.61805) (xy 29.980289 -347.608427) (xy 29.980173 -347.587996) (xy 29.976572 -347.578426)
			(xy 29.959544 -347.537016) (xy 29.932908 -347.451529) (xy 29.915001 -347.363797) (xy 29.906005 -347.274709)
			(xy 29.905452 -347.229938) (xy 29.905933 -347.189355) (xy 29.913331 -347.108527) (xy 29.928059 -347.028709)
			(xy 29.949995 -346.950564) (xy 29.978957 -346.874741) (xy 30.014703 -346.801871) (xy 30.056938 -346.732559)
			(xy 30.10531 -346.667382) (xy 30.159416 -346.606881) (xy 30.218807 -346.551559) (xy 30.28299 -346.501876)
			(xy 30.351431 -346.458245) (xy 30.38729 -346.439236) (xy 30.395816 -346.434265) (xy 30.408633 -346.419285)
			(xy 30.414885 -346.400588) (xy 30.414722 -346.390722) (xy 30.41396 -346.365322) (xy 30.414481 -346.337437)
			(xy 30.422793 -346.28229) (xy 30.439231 -346.228998) (xy 30.463429 -346.178752) (xy 30.494845 -346.132673)
			(xy 30.532778 -346.091791) (xy 30.57638 -346.057019) (xy 30.624678 -346.029134) (xy 30.676593 -346.008759)
			(xy 30.730964 -345.996349) (xy 30.786578 -345.992182) (xy 30.842192 -345.996349) (xy 30.896563 -346.008759)
			(xy 30.948478 -346.029134) (xy 30.996776 -346.057019) (xy 31.040378 -346.091791) (xy 31.078311 -346.132673)
			(xy 31.109727 -346.178752) (xy 31.133925 -346.228998) (xy 31.150363 -346.28229) (xy 31.158675 -346.337437)
			(xy 31.159196 -346.365322) (xy 31.158688 -346.383356) (xy 31.15866 -346.393249) (xy 31.165282 -346.411875)
			(xy 31.178455 -346.426614) (xy 31.187136 -346.431362) (xy 31.224041 -346.449965) (xy 31.294555 -346.49308)
			(xy 31.360766 -346.542551) (xy 31.4221 -346.597952) (xy 31.47803 -346.658805) (xy 31.528073 -346.724585)
			(xy 31.571797 -346.794724) (xy 31.608825 -346.868616) (xy 31.638837 -346.945626) (xy 31.661575 -347.025088)
			(xy 31.676842 -347.106317) (xy 31.684507 -347.188612) (xy 31.684976 -347.229938) (xy 31.684414 -347.274708)
			(xy 31.675404 -347.363793) (xy 31.657499 -347.451524) (xy 31.630879 -347.537015) (xy 31.613856 -347.578426)
			(xy 31.61027 -347.58801) (xy 31.610284 -347.608459) (xy 31.613856 -347.61805) (xy 31.630031 -347.657368)
			(xy 31.655701 -347.738424) (xy 31.673532 -347.821557) (xy 31.68336 -347.906011) (xy 31.684722 -347.948504)
			(xy 31.684976 -347.96222) (xy 31.6992 -347.985588) (xy 31.788862 -348.034102) (xy 31.796927 -348.038113)
			(xy 31.814734 -348.040741) (xy 31.832352 -348.037052) (xy 31.84017 -348.032578) (xy 31.875522 -348.010993)
			(xy 31.949529 -347.973778) (xy 32.026677 -347.943609) (xy 32.106297 -347.920748) (xy 32.187699 -347.905393)
			(xy 32.270176 -347.897677) (xy 32.311594 -347.897196) (xy 32.352707 -347.897719) (xy 32.434582 -347.905305)
			(xy 32.515408 -347.920413) (xy 32.594495 -347.942914) (xy 32.671169 -347.972616) (xy 32.744775 -348.009266)
			(xy 32.814686 -348.05255) (xy 32.880304 -348.102101) (xy 32.941071 -348.157495) (xy 32.996468 -348.218259)
			(xy 33.046022 -348.283875) (xy 33.089311 -348.353783) (xy 33.125965 -348.427387) (xy 33.155671 -348.504059)
			(xy 33.178176 -348.583145) (xy 33.193289 -348.66397) (xy 33.197509 -348.70949) (xy 36.690541 -348.70949)
			(xy 36.694532 -348.625708) (xy 36.706469 -348.542686) (xy 36.726244 -348.461173) (xy 36.753677 -348.38191)
			(xy 36.788521 -348.305613) (xy 36.830459 -348.232974) (xy 36.879112 -348.16465) (xy 36.93404 -348.101261)
			(xy 36.994745 -348.043379) (xy 37.060676 -347.99153) (xy 37.131238 -347.946183) (xy 37.20579 -347.907749)
			(xy 37.283659 -347.876576) (xy 37.364138 -347.852945) (xy 37.446499 -347.837072) (xy 37.529996 -347.829099)
			(xy 37.571934 -347.828616) (xy 37.609123 -347.829023) (xy 37.683236 -347.835307) (xy 37.756556 -347.847812)
			(xy 37.828562 -347.866448) (xy 37.86378 -347.8784) (xy 37.871977 -347.880914) (xy 37.889111 -347.880914)
			(xy 37.897308 -347.8784) (xy 37.93549 -347.865472) (xy 38.013674 -347.845816) (xy 38.093328 -347.833391)
			(xy 38.133528 -347.830394) (xy 38.144516 -347.829167) (xy 38.163935 -347.818636) (xy 38.177169 -347.800949)
			(xy 38.18001 -347.790262) (xy 38.189419 -347.748079) (xy 38.215379 -347.665637) (xy 38.231826 -347.62567)
			(xy 38.235335 -347.61606) (xy 38.235189 -347.595617) (xy 38.231572 -347.586046) (xy 38.21455 -347.544634)
			(xy 38.187912 -347.459147) (xy 38.170004 -347.371416) (xy 38.161006 -347.282328) (xy 38.160452 -347.237558)
			(xy 38.160956 -347.195197) (xy 38.169009 -347.11086) (xy 38.185043 -347.02767) (xy 38.208911 -346.94638)
			(xy 38.240399 -346.867728) (xy 38.279221 -346.792425) (xy 38.325024 -346.721153) (xy 38.377395 -346.654557)
			(xy 38.43586 -346.593242) (xy 38.499888 -346.537761) (xy 38.5689 -346.488618) (xy 38.64227 -346.446258)
			(xy 38.719335 -346.411063) (xy 38.799397 -346.383354) (xy 38.88173 -346.36338) (xy 38.965589 -346.351323)
			(xy 39.050214 -346.347292) (xy 39.134839 -346.351323) (xy 39.218698 -346.36338) (xy 39.301031 -346.383354)
			(xy 39.381093 -346.411063) (xy 39.458158 -346.446258) (xy 39.531528 -346.488618) (xy 39.60054 -346.537761)
			(xy 39.664568 -346.593242) (xy 39.723033 -346.654557) (xy 39.775404 -346.721153) (xy 39.821207 -346.792425)
			(xy 39.860029 -346.867728) (xy 39.891517 -346.94638) (xy 39.915385 -347.02767) (xy 39.931419 -347.11086)
			(xy 39.939472 -347.195197) (xy 39.939976 -347.237558) (xy 39.939421 -347.282328) (xy 39.930409 -347.371413)
			(xy 39.912502 -347.459144) (xy 39.88588 -347.544635) (xy 39.868856 -347.586046) (xy 39.865251 -347.595621)
			(xy 39.865104 -347.616057) (xy 39.868602 -347.62567) (xy 39.88516 -347.665899) (xy 39.911278 -347.748887)
			(xy 39.929176 -347.834027) (xy 39.938683 -347.920507) (xy 39.939722 -347.963998) (xy 39.939722 -347.964252)
			(xy 39.94031 -347.973302) (xy 39.94696 -347.990157) (xy 39.959055 -348.003648) (xy 39.9669 -348.008194)
			(xy 40.058086 -348.056454) (xy 40.086026 -348.05493) (xy 40.09771 -348.04731) (xy 40.134305 -348.023444)
			(xy 40.211348 -347.98223) (xy 40.292061 -347.948768) (xy 40.375665 -347.923381) (xy 40.461356 -347.906311)
			(xy 40.548307 -347.897725) (xy 40.591994 -347.897196) (xy 40.633107 -347.897719) (xy 40.714982 -347.905305)
			(xy 40.795808 -347.920413) (xy 40.874895 -347.942914) (xy 40.951569 -347.972616) (xy 41.025175 -348.009266)
			(xy 41.095086 -348.05255) (xy 41.160704 -348.102101) (xy 41.221471 -348.157495) (xy 41.276868 -348.218259)
			(xy 41.326422 -348.283875) (xy 41.369711 -348.353783) (xy 41.406365 -348.427387) (xy 41.436071 -348.504059)
			(xy 41.458576 -348.583145) (xy 41.473689 -348.66397) (xy 41.47791 -348.7095) (xy 44.996301 -348.7095)
			(xy 45.000292 -348.625716) (xy 45.01223 -348.54269) (xy 45.032006 -348.461175) (xy 45.05944 -348.381909)
			(xy 45.094286 -348.30561) (xy 45.136227 -348.232969) (xy 45.184883 -348.164644) (xy 45.239813 -348.101253)
			(xy 45.30052 -348.043371) (xy 45.366455 -347.991522) (xy 45.43702 -347.946175) (xy 45.511576 -347.907741)
			(xy 45.589448 -347.876568) (xy 45.66993 -347.852939) (xy 45.752294 -347.837068) (xy 45.835794 -347.829098)
			(xy 45.877734 -347.828616) (xy 45.914923 -347.829023) (xy 45.989036 -347.835307) (xy 46.062356 -347.847812)
			(xy 46.134362 -347.866448) (xy 46.16958 -347.8784) (xy 46.177777 -347.880914) (xy 46.194911 -347.880914)
			(xy 46.203108 -347.8784) (xy 46.238327 -347.866445) (xy 46.310329 -347.847789) (xy 46.383649 -347.835279)
			(xy 46.457764 -347.829003) (xy 46.494954 -347.828616) (xy 46.496732 -347.82887) (xy 46.506097 -347.78788)
			(xy 46.53154 -347.707736) (xy 46.547532 -347.66885) (xy 46.551076 -347.659253) (xy 46.55109 -347.638816)
			(xy 46.547532 -347.629226) (xy 46.530501 -347.587817) (xy 46.503866 -347.502329) (xy 46.485961 -347.414597)
			(xy 46.476965 -347.325509) (xy 46.476412 -347.280738) (xy 46.476916 -347.238377) (xy 46.484969 -347.15404)
			(xy 46.501003 -347.07085) (xy 46.524871 -346.98956) (xy 46.556359 -346.910908) (xy 46.595181 -346.835605)
			(xy 46.640984 -346.764333) (xy 46.693355 -346.697737) (xy 46.75182 -346.636422) (xy 46.815848 -346.580941)
			(xy 46.88486 -346.531798) (xy 46.95823 -346.489438) (xy 47.035295 -346.454243) (xy 47.115357 -346.426534)
			(xy 47.19769 -346.40656) (xy 47.281549 -346.394503) (xy 47.366174 -346.390472) (xy 47.450799 -346.394503)
			(xy 47.534658 -346.40656) (xy 47.616991 -346.426534) (xy 47.697053 -346.454243) (xy 47.774118 -346.489438)
			(xy 47.847488 -346.531798) (xy 47.9165 -346.580941) (xy 47.980528 -346.636422) (xy 48.038993 -346.697737)
			(xy 48.091364 -346.764333) (xy 48.137167 -346.835605) (xy 48.175989 -346.910908) (xy 48.207477 -346.98956)
			(xy 48.231345 -347.07085) (xy 48.247379 -347.15404) (xy 48.255432 -347.238377) (xy 48.255936 -347.280738)
			(xy 48.25537 -347.325508) (xy 48.24636 -347.414592) (xy 48.228456 -347.502324) (xy 48.201838 -347.587815)
			(xy 48.184816 -347.629226) (xy 48.181232 -347.638811) (xy 48.181246 -347.659259) (xy 48.184816 -347.66885)
			(xy 48.199304 -347.703977) (xy 48.222973 -347.776187) (xy 48.2404 -347.850153) (xy 48.251457 -347.925335)
			(xy 48.254158 -347.963236) (xy 48.255104 -347.972078) (xy 48.26215 -347.988388) (xy 48.274337 -348.001315)
			(xy 48.282098 -348.005654) (xy 48.37303 -348.051374) (xy 48.3997 -348.04985) (xy 48.41113 -348.04223)
			(xy 48.447343 -348.019182) (xy 48.523387 -347.979349) (xy 48.602912 -347.947022) (xy 48.685181 -347.922504)
			(xy 48.769429 -347.90602) (xy 48.854872 -347.897725) (xy 48.897794 -347.897196) (xy 48.938907 -347.897719)
			(xy 49.020782 -347.905305) (xy 49.101608 -347.920413) (xy 49.180695 -347.942914) (xy 49.257369 -347.972616)
			(xy 49.330975 -348.009266) (xy 49.400886 -348.05255) (xy 49.466504 -348.102101) (xy 49.527271 -348.157495)
			(xy 49.582668 -348.218259) (xy 49.632222 -348.283875) (xy 49.675511 -348.353783) (xy 49.712165 -348.427387)
			(xy 49.741871 -348.504059) (xy 49.764376 -348.583145) (xy 49.779489 -348.66397) (xy 49.78371 -348.7095)
			(xy 53.352901 -348.7095) (xy 53.356892 -348.625716) (xy 53.36883 -348.54269) (xy 53.388606 -348.461175)
			(xy 53.41604 -348.381909) (xy 53.450886 -348.30561) (xy 53.492827 -348.232969) (xy 53.541483 -348.164644)
			(xy 53.596413 -348.101253) (xy 53.65712 -348.043371) (xy 53.723055 -347.991522) (xy 53.79362 -347.946175)
			(xy 53.868176 -347.907741) (xy 53.946048 -347.876568) (xy 54.02653 -347.852939) (xy 54.108894 -347.837068)
			(xy 54.192394 -347.829098) (xy 54.234334 -347.828616) (xy 54.271523 -347.829023) (xy 54.345636 -347.835307)
			(xy 54.418956 -347.847812) (xy 54.490962 -347.866448) (xy 54.52618 -347.8784) (xy 54.534377 -347.880914)
			(xy 54.551511 -347.880914) (xy 54.559708 -347.8784) (xy 54.594654 -347.86653) (xy 54.66609 -347.847969)
			(xy 54.738831 -347.835458) (xy 54.812365 -347.829087) (xy 54.849268 -347.828616) (xy 54.85384 -347.82887)
			(xy 54.854348 -347.82887) (xy 54.863907 -347.782599) (xy 54.89152 -347.692237) (xy 54.909466 -347.64853)
			(xy 54.912939 -347.63891) (xy 54.912815 -347.618477) (xy 54.909212 -347.608906) (xy 54.892173 -347.5675)
			(xy 54.865541 -347.482011) (xy 54.847637 -347.394278) (xy 54.838644 -347.305189) (xy 54.838092 -347.260418)
			(xy 54.838596 -347.218057) (xy 54.846649 -347.13372) (xy 54.862683 -347.05053) (xy 54.886551 -346.96924)
			(xy 54.918039 -346.890588) (xy 54.956861 -346.815285) (xy 55.002664 -346.744013) (xy 55.055035 -346.677417)
			(xy 55.1135 -346.616102) (xy 55.177528 -346.560621) (xy 55.24654 -346.511478) (xy 55.31991 -346.469118)
			(xy 55.396975 -346.433923) (xy 55.477037 -346.406214) (xy 55.55937 -346.38624) (xy 55.643229 -346.374183)
			(xy 55.727854 -346.370152) (xy 55.812479 -346.374183) (xy 55.896338 -346.38624) (xy 55.978671 -346.406214)
			(xy 56.058733 -346.433923) (xy 56.135798 -346.469118) (xy 56.209168 -346.511478) (xy 56.27818 -346.560621)
			(xy 56.342208 -346.616102) (xy 56.400673 -346.677417) (xy 56.453044 -346.744013) (xy 56.498847 -346.815285)
			(xy 56.537669 -346.890588) (xy 56.569157 -346.96924) (xy 56.593025 -347.05053) (xy 56.609059 -347.13372)
			(xy 56.617112 -347.218057) (xy 56.617616 -347.260418) (xy 56.617044 -347.305187) (xy 56.608037 -347.394272)
			(xy 56.590134 -347.482003) (xy 56.563518 -347.567495) (xy 56.546496 -347.608906) (xy 56.542919 -347.618493)
			(xy 56.542926 -347.63894) (xy 56.546496 -347.64853) (xy 56.561684 -347.685398) (xy 56.586189 -347.761282)
			(xy 56.603812 -347.839053) (xy 56.614411 -347.918088) (xy 56.6166 -347.957902) (xy 56.617108 -347.971364)
			(xy 56.63184 -347.994224) (xy 56.734456 -348.047564) (xy 56.761634 -348.04604) (xy 56.773064 -348.038674)
			(xy 56.808981 -348.016152) (xy 56.88432 -347.977266) (xy 56.963017 -347.945725) (xy 57.044358 -347.921816)
			(xy 57.127605 -347.905754) (xy 57.212003 -347.897686) (xy 57.254394 -347.897196) (xy 57.295507 -347.897719)
			(xy 57.377382 -347.905305) (xy 57.458208 -347.920413) (xy 57.537295 -347.942914) (xy 57.613969 -347.972616)
			(xy 57.687575 -348.009266) (xy 57.757486 -348.05255) (xy 57.823104 -348.102101) (xy 57.883871 -348.157495)
			(xy 57.939268 -348.218259) (xy 57.988822 -348.283875) (xy 58.032111 -348.353783) (xy 58.068765 -348.427387)
			(xy 58.098471 -348.504059) (xy 58.120976 -348.583145) (xy 58.136089 -348.66397) (xy 58.14031 -348.7095)
			(xy 61.684101 -348.7095) (xy 61.688092 -348.625716) (xy 61.70003 -348.54269) (xy 61.719806 -348.461175)
			(xy 61.74724 -348.381909) (xy 61.782086 -348.30561) (xy 61.824027 -348.232969) (xy 61.872683 -348.164644)
			(xy 61.927613 -348.101253) (xy 61.98832 -348.043371) (xy 62.054255 -347.991522) (xy 62.12482 -347.946175)
			(xy 62.199376 -347.907741) (xy 62.277248 -347.876568) (xy 62.35773 -347.852939) (xy 62.440094 -347.837068)
			(xy 62.523594 -347.829098) (xy 62.565534 -347.828616) (xy 62.602723 -347.829023) (xy 62.676836 -347.835307)
			(xy 62.750156 -347.847812) (xy 62.822162 -347.866448) (xy 62.85738 -347.8784) (xy 62.865577 -347.880914)
			(xy 62.882711 -347.880914) (xy 62.890908 -347.8784) (xy 62.926096 -347.866455) (xy 62.998036 -347.847809)
			(xy 63.071292 -347.835299) (xy 63.145342 -347.829013) (xy 63.1825 -347.828616) (xy 63.183008 -347.828616)
			(xy 63.206122 -347.829124) (xy 63.215205 -347.793715) (xy 63.238479 -347.724411) (xy 63.252604 -347.690694)
			(xy 63.256229 -347.680981) (xy 63.25624 -347.66027) (xy 63.252604 -347.650562) (xy 63.235485 -347.609307)
			(xy 63.208697 -347.524095) (xy 63.190664 -347.436611) (xy 63.181571 -347.347751) (xy 63.180976 -347.30309)
			(xy 63.180976 -347.302328) (xy 63.181475 -347.260403) (xy 63.189445 -347.176932) (xy 63.205314 -347.094597)
			(xy 63.228937 -347.014143) (xy 63.260101 -346.936299) (xy 63.298524 -346.861769) (xy 63.343857 -346.79123)
			(xy 63.39569 -346.725319) (xy 63.453553 -346.664633) (xy 63.516923 -346.609723) (xy 63.585226 -346.561085)
			(xy 63.657843 -346.51916) (xy 63.734116 -346.484327) (xy 63.813355 -346.456902) (xy 63.894841 -346.437133)
			(xy 63.977838 -346.4252) (xy 64.061594 -346.421211) (xy 64.14535 -346.4252) (xy 64.228347 -346.437133)
			(xy 64.309833 -346.456902) (xy 64.389072 -346.484327) (xy 64.465345 -346.51916) (xy 64.537962 -346.561085)
			(xy 64.606265 -346.609723) (xy 64.669635 -346.664633) (xy 64.727498 -346.725319) (xy 64.779331 -346.79123)
			(xy 64.824664 -346.861769) (xy 64.863087 -346.936299) (xy 64.894251 -347.014143) (xy 64.917874 -347.094597)
			(xy 64.933743 -347.176932) (xy 64.941713 -347.260403) (xy 64.942212 -347.302328) (xy 64.942212 -347.30309)
			(xy 64.941639 -347.347753) (xy 64.932567 -347.436619) (xy 64.914535 -347.524107) (xy 64.88773 -347.609317)
			(xy 64.870584 -347.650562) (xy 64.866927 -347.660266) (xy 64.866937 -347.680985) (xy 64.870584 -347.690694)
			(xy 64.888862 -347.734789) (xy 64.91689 -347.826038) (xy 64.934892 -347.919782) (xy 64.939418 -347.9673)
			(xy 64.940434 -347.980508) (xy 64.955674 -348.00286) (xy 65.046352 -348.047056) (xy 65.054393 -348.050544)
			(xy 65.071798 -348.052482) (xy 65.088843 -348.048463) (xy 65.09639 -348.044008) (xy 65.096644 -348.043754)
			(xy 65.132959 -348.020439) (xy 65.209305 -347.980191) (xy 65.289189 -347.947525) (xy 65.371861 -347.922748)
			(xy 65.456544 -347.906093) (xy 65.542442 -347.897716) (xy 65.585594 -347.897196) (xy 65.626707 -347.897719)
			(xy 65.708582 -347.905305) (xy 65.789408 -347.920413) (xy 65.868495 -347.942914) (xy 65.945169 -347.972616)
			(xy 66.018775 -348.009266) (xy 66.088686 -348.05255) (xy 66.154304 -348.102101) (xy 66.215071 -348.157495)
			(xy 66.270468 -348.218259) (xy 66.320022 -348.283875) (xy 66.363311 -348.353783) (xy 66.399965 -348.427387)
			(xy 66.429671 -348.504059) (xy 66.452176 -348.583145) (xy 66.467289 -348.66397) (xy 66.474879 -348.745845)
			(xy 66.475356 -348.786958) (xy 66.474795 -348.831728) (xy 66.467942 -348.89948) (xy 81.294224 -348.89948)
			(xy 81.294687 -348.858913) (xy 81.30208 -348.778118) (xy 81.316804 -348.698332) (xy 81.338734 -348.620219)
			(xy 81.36769 -348.544429) (xy 81.385156 -348.507812) (xy 81.389058 -348.498717) (xy 81.390365 -348.478988)
			(xy 81.387696 -348.469458) (xy 81.373498 -348.424437) (xy 81.353605 -348.332151) (xy 81.343609 -348.238277)
			(xy 81.342992 -348.191074) (xy 81.343496 -348.148713) (xy 81.351549 -348.064376) (xy 81.367583 -347.981186)
			(xy 81.391451 -347.899896) (xy 81.422939 -347.821244) (xy 81.461761 -347.745941) (xy 81.507564 -347.674669)
			(xy 81.559935 -347.608073) (xy 81.6184 -347.546758) (xy 81.682428 -347.491277) (xy 81.75144 -347.442134)
			(xy 81.82481 -347.399774) (xy 81.901875 -347.364579) (xy 81.981937 -347.33687) (xy 82.06427 -347.316896)
			(xy 82.148129 -347.304839) (xy 82.232754 -347.300808) (xy 82.317379 -347.304839) (xy 82.401238 -347.316896)
			(xy 82.483571 -347.33687) (xy 82.563633 -347.364579) (xy 82.640698 -347.399774) (xy 82.714068 -347.442134)
			(xy 82.78308 -347.491277) (xy 82.847108 -347.546758) (xy 82.905573 -347.608073) (xy 82.957944 -347.674669)
			(xy 83.003747 -347.745941) (xy 83.042569 -347.821244) (xy 83.074057 -347.899896) (xy 83.097925 -347.981186)
			(xy 83.113959 -348.064376) (xy 83.122012 -348.148713) (xy 83.122516 -348.191074) (xy 83.12207 -348.231641)
			(xy 83.114672 -348.312437) (xy 83.099945 -348.392223) (xy 83.07801 -348.470336) (xy 83.049051 -348.546125)
			(xy 83.031584 -348.582742) (xy 83.027707 -348.591846) (xy 83.026383 -348.611567) (xy 83.029044 -348.621096)
			(xy 83.043232 -348.66612) (xy 83.063129 -348.758404) (xy 83.073129 -348.852278) (xy 83.073245 -348.861126)
			(xy 83.956144 -348.861126) (xy 83.956552 -348.820564) (xy 83.963891 -348.739773) (xy 83.978566 -348.659987)
			(xy 84.000454 -348.581872) (xy 84.029373 -348.506078) (xy 84.046822 -348.469458) (xy 84.05073 -348.460437)
			(xy 84.052174 -348.440849) (xy 84.049616 -348.431358) (xy 84.035467 -348.386455) (xy 84.015597 -348.294425)
			(xy 84.005567 -348.200811) (xy 84.004912 -348.153736) (xy 84.004912 -348.15272) (xy 84.005416 -348.110372)
			(xy 84.013467 -348.026058) (xy 84.029496 -347.942892) (xy 84.053357 -347.861625) (xy 84.084836 -347.782995)
			(xy 84.123647 -347.707714) (xy 84.169437 -347.636462) (xy 84.221793 -347.569886) (xy 84.280241 -347.508588)
			(xy 84.344251 -347.453123) (xy 84.413243 -347.403994) (xy 84.486593 -347.361645) (xy 84.563636 -347.326461)
			(xy 84.643675 -347.298759) (xy 84.725984 -347.278791) (xy 84.809819 -347.266738) (xy 84.89442 -347.262708)
			(xy 84.979021 -347.266738) (xy 85.062856 -347.278791) (xy 85.145165 -347.298759) (xy 85.225204 -347.326461)
			(xy 85.302247 -347.361645) (xy 85.375597 -347.403994) (xy 85.444589 -347.453123) (xy 85.508599 -347.508588)
			(xy 85.567047 -347.569886) (xy 85.619403 -347.636462) (xy 85.665193 -347.707714) (xy 85.704004 -347.782995)
			(xy 85.735483 -347.861625) (xy 85.759344 -347.942892) (xy 85.775373 -348.026058) (xy 85.783424 -348.110372)
			(xy 85.783928 -348.15272) (xy 85.783928 -348.153228) (xy 85.783471 -348.193738) (xy 85.77611 -348.274424)
			(xy 85.761432 -348.354104) (xy 85.73956 -348.432117) (xy 85.710675 -348.507814) (xy 85.69325 -348.544388)
			(xy 85.689318 -348.553401) (xy 85.687887 -348.572996) (xy 85.690456 -348.582488) (xy 85.70466 -348.627551)
			(xy 85.721282 -348.7047) (xy 275.231844 -348.7047) (xy 275.235834 -348.620942) (xy 275.247768 -348.537942)
			(xy 275.267537 -348.456452) (xy 275.294962 -348.377211) (xy 275.329796 -348.300935) (xy 275.371722 -348.228316)
			(xy 275.420361 -348.16001) (xy 275.475273 -348.096638) (xy 275.53596 -348.038772) (xy 275.601873 -347.986937)
			(xy 275.672414 -347.941602) (xy 275.746946 -347.903177) (xy 275.824792 -347.872011) (xy 275.905248 -347.848386)
			(xy 275.987586 -347.832515) (xy 276.071059 -347.824543) (xy 276.112986 -347.824044) (xy 276.114002 -347.824044)
			(xy 276.151059 -347.824452) (xy 276.224908 -347.830716) (xy 276.29797 -347.843157) (xy 276.36973 -347.861689)
			(xy 276.404832 -347.873574) (xy 276.413029 -347.876088) (xy 276.430163 -347.876088) (xy 276.43836 -347.873574)
			(xy 276.478966 -347.8599) (xy 276.562216 -347.839604) (xy 276.647042 -347.827484) (xy 276.68982 -347.82506)
			(xy 276.700434 -347.823969) (xy 276.719453 -347.814348) (xy 276.732947 -347.797851) (xy 276.736302 -347.787722)
			(xy 276.744404 -347.759433) (xy 276.763852 -347.703889) (xy 276.775164 -347.676724) (xy 276.778721 -347.667131)
			(xy 276.778725 -347.646691) (xy 276.775164 -347.6371) (xy 276.758127 -347.595694) (xy 276.731493 -347.510205)
			(xy 276.713589 -347.422472) (xy 276.704596 -347.333383) (xy 276.704044 -347.288612) (xy 276.704548 -347.246251)
			(xy 276.712601 -347.161914) (xy 276.728635 -347.078724) (xy 276.752503 -346.997434) (xy 276.783991 -346.918782)
			(xy 276.822813 -346.843479) (xy 276.868616 -346.772207) (xy 276.920987 -346.705611) (xy 276.979452 -346.644296)
			(xy 277.04348 -346.588815) (xy 277.112492 -346.539672) (xy 277.185862 -346.497312) (xy 277.262927 -346.462117)
			(xy 277.342989 -346.434408) (xy 277.425322 -346.414434) (xy 277.509181 -346.402377) (xy 277.593806 -346.398346)
			(xy 277.678431 -346.402377) (xy 277.76229 -346.414434) (xy 277.844623 -346.434408) (xy 277.924685 -346.462117)
			(xy 278.00175 -346.497312) (xy 278.07512 -346.539672) (xy 278.144132 -346.588815) (xy 278.20816 -346.644296)
			(xy 278.266625 -346.705611) (xy 278.318996 -346.772207) (xy 278.364799 -346.843479) (xy 278.403621 -346.918782)
			(xy 278.435109 -346.997434) (xy 278.458977 -347.078724) (xy 278.475011 -347.161914) (xy 278.483064 -347.246251)
			(xy 278.483568 -347.288612) (xy 278.482998 -347.333381) (xy 278.47399 -347.422466) (xy 278.456088 -347.510198)
			(xy 278.42947 -347.595689) (xy 278.412448 -347.6371) (xy 278.408812 -347.646665) (xy 278.408686 -347.667111)
			(xy 278.412194 -347.676724) (xy 278.426408 -347.711074) (xy 278.449728 -347.781668) (xy 278.467082 -347.85396)
			(xy 278.478348 -347.927447) (xy 278.481282 -347.964506) (xy 278.482267 -347.973327) (xy 278.489457 -347.989544)
			(xy 278.501708 -348.002373) (xy 278.509476 -348.00667) (xy 278.600662 -348.051628) (xy 278.62784 -348.049596)
			(xy 278.639016 -348.04223) (xy 278.675581 -348.018458) (xy 278.752524 -347.977387) (xy 278.833117 -347.944041)
			(xy 278.916586 -347.91874) (xy 279.00213 -347.901729) (xy 279.088929 -347.893169) (xy 279.132538 -347.892624)
			(xy 279.133046 -347.892624) (xy 279.174153 -347.893069) (xy 279.256016 -347.900657) (xy 279.336831 -347.915765)
			(xy 279.415907 -347.938263) (xy 279.49257 -347.96796) (xy 279.566167 -348.004602) (xy 279.63607 -348.047877)
			(xy 279.701683 -348.097416) (xy 279.762447 -348.152796) (xy 279.817842 -348.213546) (xy 279.867398 -348.279147)
			(xy 279.91069 -348.349039) (xy 279.947351 -348.422627) (xy 279.977067 -348.499283) (xy 279.999585 -348.578353)
			(xy 280.014712 -348.659164) (xy 280.018945 -348.7047) (xy 283.512244 -348.7047) (xy 283.516234 -348.620942)
			(xy 283.528168 -348.537942) (xy 283.547937 -348.456452) (xy 283.575362 -348.377211) (xy 283.610196 -348.300935)
			(xy 283.652122 -348.228316) (xy 283.700761 -348.16001) (xy 283.755673 -348.096638) (xy 283.81636 -348.038772)
			(xy 283.882273 -347.986937) (xy 283.952814 -347.941602) (xy 284.027346 -347.903177) (xy 284.105192 -347.872011)
			(xy 284.185648 -347.848386) (xy 284.267986 -347.832515) (xy 284.351459 -347.824543) (xy 284.393386 -347.824044)
			(xy 284.394402 -347.824044) (xy 284.431459 -347.824452) (xy 284.505308 -347.830716) (xy 284.57837 -347.843157)
			(xy 284.65013 -347.861689) (xy 284.685232 -347.873574) (xy 284.693429 -347.876088) (xy 284.710563 -347.876088)
			(xy 284.71876 -347.873574) (xy 284.756938 -347.860634) (xy 284.835124 -347.840982) (xy 284.91478 -347.828562)
			(xy 284.95498 -347.825568) (xy 284.965838 -347.82436) (xy 284.985096 -347.814096) (xy 284.99831 -347.79673)
			(xy 285.001208 -347.786198) (xy 285.010486 -347.747118) (xy 285.035162 -347.670674) (xy 285.050484 -347.633544)
			(xy 285.054028 -347.623948) (xy 285.05404 -347.603511) (xy 285.050484 -347.59392) (xy 285.033454 -347.552511)
			(xy 285.006819 -347.467023) (xy 284.988912 -347.379291) (xy 284.979917 -347.290203) (xy 284.979364 -347.245432)
			(xy 284.979868 -347.203071) (xy 284.987921 -347.118734) (xy 285.003955 -347.035544) (xy 285.027823 -346.954254)
			(xy 285.059311 -346.875602) (xy 285.098133 -346.800299) (xy 285.143936 -346.729027) (xy 285.196307 -346.662431)
			(xy 285.254772 -346.601116) (xy 285.3188 -346.545635) (xy 285.387812 -346.496492) (xy 285.461182 -346.454132)
			(xy 285.538247 -346.418937) (xy 285.618309 -346.391228) (xy 285.700642 -346.371254) (xy 285.784501 -346.359197)
			(xy 285.869126 -346.355166) (xy 285.953751 -346.359197) (xy 286.03761 -346.371254) (xy 286.119943 -346.391228)
			(xy 286.200005 -346.418937) (xy 286.27707 -346.454132) (xy 286.35044 -346.496492) (xy 286.419452 -346.545635)
			(xy 286.48348 -346.601116) (xy 286.541945 -346.662431) (xy 286.594316 -346.729027) (xy 286.640119 -346.800299)
			(xy 286.678941 -346.875602) (xy 286.710429 -346.954254) (xy 286.734297 -347.035544) (xy 286.750331 -347.118734)
			(xy 286.758384 -347.203071) (xy 286.758888 -347.245432) (xy 286.758323 -347.290202) (xy 286.749314 -347.379287)
			(xy 286.73141 -347.467018) (xy 286.704791 -347.552509) (xy 286.687768 -347.59392) (xy 286.684185 -347.603505)
			(xy 286.684197 -347.623953) (xy 286.687768 -347.633544) (xy 286.703871 -347.672618) (xy 286.72945 -347.753174)
			(xy 286.747275 -347.835792) (xy 286.757183 -347.919728) (xy 286.758634 -347.961966) (xy 286.758888 -347.975936)
			(xy 286.77362 -347.999558) (xy 286.86506 -348.047056) (xy 286.873276 -348.050887) (xy 286.891249 -348.053129)
			(xy 286.908879 -348.048973) (xy 286.916622 -348.044262) (xy 286.916876 -348.044008) (xy 286.95358 -348.019938)
			(xy 287.030887 -347.978361) (xy 287.111915 -347.944605) (xy 287.195876 -347.918998) (xy 287.281951 -347.901791)
			(xy 287.369303 -347.893149) (xy 287.413192 -347.892624) (xy 287.413446 -347.892624) (xy 287.454553 -347.893069)
			(xy 287.536416 -347.900657) (xy 287.617231 -347.915765) (xy 287.696307 -347.938263) (xy 287.77297 -347.96796)
			(xy 287.846567 -348.004602) (xy 287.91647 -348.047877) (xy 287.982083 -348.097416) (xy 288.042847 -348.152796)
			(xy 288.098242 -348.213546) (xy 288.147798 -348.279147) (xy 288.19109 -348.349039) (xy 288.227751 -348.422627)
			(xy 288.257467 -348.499283) (xy 288.279985 -348.578353) (xy 288.295112 -348.659164) (xy 288.299345 -348.7047)
			(xy 291.818044 -348.7047) (xy 291.822034 -348.620942) (xy 291.833968 -348.537942) (xy 291.853737 -348.456452)
			(xy 291.881162 -348.377211) (xy 291.915996 -348.300935) (xy 291.957922 -348.228316) (xy 292.006561 -348.16001)
			(xy 292.061473 -348.096638) (xy 292.12216 -348.038772) (xy 292.188073 -347.986937) (xy 292.258614 -347.941602)
			(xy 292.333146 -347.903177) (xy 292.410992 -347.872011) (xy 292.491448 -347.848386) (xy 292.573786 -347.832515)
			(xy 292.657259 -347.824543) (xy 292.699186 -347.824044) (xy 292.700202 -347.824044) (xy 292.737259 -347.824452)
			(xy 292.811108 -347.830716) (xy 292.88417 -347.843157) (xy 292.95593 -347.861689) (xy 292.991032 -347.873574)
			(xy 292.999229 -347.876088) (xy 293.016363 -347.876088) (xy 293.02456 -347.873574) (xy 293.057737 -347.862322)
			(xy 293.125493 -347.844496) (xy 293.194454 -347.832123) (xy 293.229284 -347.828362) (xy 293.240044 -347.82673)
			(xy 293.258819 -347.815766) (xy 293.271409 -347.798041) (xy 293.273988 -347.787468) (xy 293.28351 -347.742121)
			(xy 293.310744 -347.653548) (xy 293.328344 -347.610684) (xy 293.331924 -347.601098) (xy 293.331914 -347.580651)
			(xy 293.328344 -347.57106) (xy 293.311293 -347.529659) (xy 293.284663 -347.444168) (xy 293.266763 -347.356433)
			(xy 293.257774 -347.267343) (xy 293.257224 -347.222572) (xy 293.257728 -347.180211) (xy 293.265781 -347.095874)
			(xy 293.281815 -347.012684) (xy 293.305683 -346.931394) (xy 293.337171 -346.852742) (xy 293.375993 -346.777439)
			(xy 293.421796 -346.706167) (xy 293.474167 -346.639571) (xy 293.532632 -346.578256) (xy 293.59666 -346.522775)
			(xy 293.665672 -346.473632) (xy 293.739042 -346.431272) (xy 293.816107 -346.396077) (xy 293.896169 -346.368368)
			(xy 293.978502 -346.348394) (xy 294.062361 -346.336337) (xy 294.146986 -346.332306) (xy 294.231611 -346.336337)
			(xy 294.31547 -346.348394) (xy 294.397803 -346.368368) (xy 294.477865 -346.396077) (xy 294.55493 -346.431272)
			(xy 294.6283 -346.473632) (xy 294.697312 -346.522775) (xy 294.76134 -346.578256) (xy 294.819805 -346.639571)
			(xy 294.872176 -346.706167) (xy 294.917979 -346.777439) (xy 294.956801 -346.852742) (xy 294.988289 -346.931394)
			(xy 295.012157 -347.012684) (xy 295.028191 -347.095874) (xy 295.036244 -347.180211) (xy 295.036748 -347.222572)
			(xy 295.036192 -347.267342) (xy 295.027179 -347.356427) (xy 295.009272 -347.444158) (xy 294.982652 -347.529649)
			(xy 294.965628 -347.57106) (xy 294.962081 -347.580656) (xy 294.96207 -347.601093) (xy 294.965628 -347.610684)
			(xy 294.982659 -347.652092) (xy 295.009295 -347.73758) (xy 295.0272 -347.825313) (xy 295.036195 -347.914401)
			(xy 295.036748 -347.959172) (xy 295.036494 -347.977206) (xy 295.03624 -347.991684) (xy 295.050718 -348.016576)
			(xy 295.157144 -348.071948) (xy 295.185846 -348.069916) (xy 295.19753 -348.061534) (xy 295.230035 -348.038582)
			(xy 295.298406 -347.997866) (xy 295.370142 -347.963421) (xy 295.444669 -347.935524) (xy 295.521391 -347.914398)
			(xy 295.599693 -347.900211) (xy 295.67895 -347.893078) (xy 295.718738 -347.892624) (xy 295.719246 -347.892624)
			(xy 295.760353 -347.893069) (xy 295.842216 -347.900657) (xy 295.923031 -347.915765) (xy 296.002107 -347.938263)
			(xy 296.07877 -347.96796) (xy 296.152367 -348.004602) (xy 296.22227 -348.047877) (xy 296.287883 -348.097416)
			(xy 296.348647 -348.152796) (xy 296.404042 -348.213546) (xy 296.453598 -348.279147) (xy 296.49689 -348.349039)
			(xy 296.533551 -348.422627) (xy 296.563267 -348.499283) (xy 296.585785 -348.578353) (xy 296.600912 -348.659164)
			(xy 296.605145 -348.7047) (xy 300.174644 -348.7047) (xy 300.178634 -348.620942) (xy 300.190568 -348.537942)
			(xy 300.210337 -348.456452) (xy 300.237762 -348.377211) (xy 300.272596 -348.300935) (xy 300.314522 -348.228316)
			(xy 300.363161 -348.16001) (xy 300.418073 -348.096638) (xy 300.47876 -348.038772) (xy 300.544673 -347.986937)
			(xy 300.615214 -347.941602) (xy 300.689746 -347.903177) (xy 300.767592 -347.872011) (xy 300.848048 -347.848386)
			(xy 300.930386 -347.832515) (xy 301.013859 -347.824543) (xy 301.055786 -347.824044) (xy 301.056802 -347.824044)
			(xy 301.093859 -347.824452) (xy 301.167708 -347.830716) (xy 301.24077 -347.843157) (xy 301.31253 -347.861689)
			(xy 301.347632 -347.873574) (xy 301.355829 -347.876088) (xy 301.372963 -347.876088) (xy 301.38116 -347.873574)
			(xy 301.419296 -347.860641) (xy 301.497398 -347.840993) (xy 301.576968 -347.828568) (xy 301.617126 -347.825568)
			(xy 301.627844 -347.824451) (xy 301.646914 -347.814446) (xy 301.660249 -347.797535) (xy 301.663354 -347.787214)
			(xy 301.672203 -347.75314) (xy 301.694583 -347.686387) (xy 301.708058 -347.653864) (xy 301.711569 -347.644255)
			(xy 301.711421 -347.623811) (xy 301.707804 -347.61424) (xy 301.690776 -347.57283) (xy 301.66414 -347.487343)
			(xy 301.646234 -347.39961) (xy 301.637237 -347.310523) (xy 301.636684 -347.265752) (xy 301.637188 -347.223391)
			(xy 301.645241 -347.139054) (xy 301.661275 -347.055864) (xy 301.685143 -346.974574) (xy 301.716631 -346.895922)
			(xy 301.755453 -346.820619) (xy 301.801256 -346.749347) (xy 301.853627 -346.682751) (xy 301.912092 -346.621436)
			(xy 301.97612 -346.565955) (xy 302.045132 -346.516812) (xy 302.118502 -346.474452) (xy 302.195567 -346.439257)
			(xy 302.275629 -346.411548) (xy 302.357962 -346.391574) (xy 302.441821 -346.379517) (xy 302.526446 -346.375486)
			(xy 302.611071 -346.379517) (xy 302.69493 -346.391574) (xy 302.777263 -346.411548) (xy 302.857325 -346.439257)
			(xy 302.93439 -346.474452) (xy 303.00776 -346.516812) (xy 303.076772 -346.565955) (xy 303.1408 -346.621436)
			(xy 303.199265 -346.682751) (xy 303.251636 -346.749347) (xy 303.297439 -346.820619) (xy 303.336261 -346.895922)
			(xy 303.367749 -346.974574) (xy 303.391617 -347.055864) (xy 303.407651 -347.139054) (xy 303.415704 -347.223391)
			(xy 303.416208 -347.265752) (xy 303.415649 -347.310522) (xy 303.406637 -347.399607) (xy 303.388731 -347.487338)
			(xy 303.362111 -347.572829) (xy 303.345088 -347.61424) (xy 303.341549 -347.623838) (xy 303.341532 -347.644274)
			(xy 303.345088 -347.653864) (xy 303.36051 -347.691224) (xy 303.385289 -347.768163) (xy 303.402976 -347.847034)
			(xy 303.413426 -347.927187) (xy 303.415446 -347.967554) (xy 303.415954 -347.981524) (xy 303.430686 -348.004638)
			(xy 303.535334 -348.057216) (xy 303.562766 -348.055184) (xy 303.574196 -348.04731) (xy 303.611146 -348.022772)
			(xy 303.689046 -347.980345) (xy 303.770779 -347.945874) (xy 303.855535 -347.919702) (xy 303.942473 -347.902087)
			(xy 304.030732 -347.893205) (xy 304.075084 -347.892624) (xy 304.075846 -347.892624) (xy 304.116953 -347.893069)
			(xy 304.198816 -347.900657) (xy 304.279631 -347.915765) (xy 304.358707 -347.938263) (xy 304.43537 -347.96796)
			(xy 304.508967 -348.004602) (xy 304.57887 -348.047877) (xy 304.644483 -348.097416) (xy 304.705247 -348.152796)
			(xy 304.760642 -348.213546) (xy 304.810198 -348.279147) (xy 304.85349 -348.349039) (xy 304.890151 -348.422627)
			(xy 304.919867 -348.499283) (xy 304.942385 -348.578353) (xy 304.957512 -348.659164) (xy 304.961745 -348.7047)
			(xy 308.505844 -348.7047) (xy 308.509834 -348.620942) (xy 308.521768 -348.537942) (xy 308.541537 -348.456452)
			(xy 308.568962 -348.377211) (xy 308.603796 -348.300935) (xy 308.645722 -348.228316) (xy 308.694361 -348.16001)
			(xy 308.749273 -348.096638) (xy 308.80996 -348.038772) (xy 308.875873 -347.986937) (xy 308.946414 -347.941602)
			(xy 309.020946 -347.903177) (xy 309.098792 -347.872011) (xy 309.179248 -347.848386) (xy 309.261586 -347.832515)
			(xy 309.345059 -347.824543) (xy 309.386986 -347.824044) (xy 309.388002 -347.824044) (xy 309.425059 -347.824452)
			(xy 309.498908 -347.830716) (xy 309.57197 -347.843157) (xy 309.64373 -347.861689) (xy 309.678832 -347.873574)
			(xy 309.687029 -347.876088) (xy 309.704163 -347.876088) (xy 309.71236 -347.873574) (xy 309.752087 -347.860214)
			(xy 309.833476 -347.84017) (xy 309.916402 -347.827952) (xy 309.958232 -347.825314) (xy 309.969008 -347.824123)
			(xy 309.988202 -347.814097) (xy 310.001607 -347.79709) (xy 310.004714 -347.786706) (xy 310.013576 -347.75276)
			(xy 310.035956 -347.686262) (xy 310.049418 -347.653864) (xy 310.052931 -347.644255) (xy 310.052783 -347.623811)
			(xy 310.049164 -347.61424) (xy 310.03214 -347.572829) (xy 310.005503 -347.487342) (xy 309.987595 -347.39961)
			(xy 309.978598 -347.310522) (xy 309.978044 -347.265752) (xy 309.978548 -347.223391) (xy 309.986601 -347.139054)
			(xy 310.002635 -347.055864) (xy 310.026503 -346.974574) (xy 310.057991 -346.895922) (xy 310.096813 -346.820619)
			(xy 310.142616 -346.749347) (xy 310.194987 -346.682751) (xy 310.253452 -346.621436) (xy 310.31748 -346.565955)
			(xy 310.386492 -346.516812) (xy 310.459862 -346.474452) (xy 310.536927 -346.439257) (xy 310.616989 -346.411548)
			(xy 310.699322 -346.391574) (xy 310.783181 -346.379517) (xy 310.867806 -346.375486) (xy 310.952431 -346.379517)
			(xy 311.03629 -346.391574) (xy 311.118623 -346.411548) (xy 311.198685 -346.439257) (xy 311.27575 -346.474452)
			(xy 311.34912 -346.516812) (xy 311.418132 -346.565955) (xy 311.48216 -346.621436) (xy 311.540625 -346.682751)
			(xy 311.592996 -346.749347) (xy 311.638799 -346.820619) (xy 311.677621 -346.895922) (xy 311.709109 -346.974574)
			(xy 311.732977 -347.055864) (xy 311.749011 -347.139054) (xy 311.757064 -347.223391) (xy 311.757568 -347.265752)
			(xy 311.757012 -347.310522) (xy 311.748 -347.399607) (xy 311.730093 -347.487338) (xy 311.703472 -347.572829)
			(xy 311.686448 -347.61424) (xy 311.682911 -347.623839) (xy 311.682894 -347.644274) (xy 311.686448 -347.653864)
			(xy 311.701578 -347.690518) (xy 311.725997 -347.765967) (xy 311.743615 -347.843288) (xy 311.754293 -347.921869)
			(xy 311.756552 -347.961458) (xy 311.757251 -347.970429) (xy 311.764179 -347.987026) (xy 311.776392 -348.000229)
			(xy 311.784238 -348.004638) (xy 311.875678 -348.050866) (xy 311.902856 -348.049088) (xy 311.914286 -348.041468)
			(xy 311.950798 -348.017804) (xy 312.027605 -347.976914) (xy 312.10804 -347.943725) (xy 312.191333 -347.918554)
			(xy 312.276687 -347.901641) (xy 312.363285 -347.893148) (xy 312.406792 -347.892624) (xy 312.407046 -347.892624)
			(xy 312.448153 -347.893069) (xy 312.530016 -347.900657) (xy 312.610831 -347.915765) (xy 312.689907 -347.938263)
			(xy 312.76657 -347.96796) (xy 312.840167 -348.004602) (xy 312.91007 -348.047877) (xy 312.975683 -348.097416)
			(xy 313.036447 -348.152796) (xy 313.091842 -348.213546) (xy 313.141398 -348.279147) (xy 313.18469 -348.349039)
			(xy 313.221351 -348.422627) (xy 313.251067 -348.499283) (xy 313.273585 -348.578353) (xy 313.288712 -348.659164)
			(xy 313.296321 -348.741025) (xy 313.296808 -348.782132) (xy 313.296242 -348.826902) (xy 313.287233 -348.915987)
			(xy 313.269329 -349.003718) (xy 313.242711 -349.089209) (xy 313.225688 -349.13062) (xy 313.222104 -349.140205)
			(xy 313.222115 -349.160653) (xy 313.225688 -349.170244) (xy 313.242711 -349.211656) (xy 313.269347 -349.297143)
			(xy 313.287256 -349.384874) (xy 313.291976 -349.43161) (xy 326.552821 -349.43161) (xy 326.556826 -349.325861)
			(xy 326.568816 -349.220718) (xy 326.588725 -349.116783) (xy 326.616436 -349.014651) (xy 326.651793 -348.914907)
			(xy 326.694591 -348.818123) (xy 326.744587 -348.724853) (xy 326.801494 -348.635632) (xy 326.864985 -348.550969)
			(xy 326.934697 -348.471351) (xy 327.010231 -348.397233) (xy 327.091154 -348.32904) (xy 327.177003 -348.267162)
			(xy 327.267286 -348.211955) (xy 327.361485 -348.163733) (xy 327.459062 -348.122773) (xy 327.559457 -348.089311)
			(xy 327.662095 -348.063537) (xy 327.766388 -348.045599) (xy 327.871739 -348.0356) (xy 327.977545 -348.033597)
			(xy 328.083199 -348.039602) (xy 328.188096 -348.053581) (xy 328.291636 -348.075452) (xy 328.393225 -348.105092)
			(xy 328.492282 -348.14233) (xy 328.588239 -348.186952) (xy 328.680546 -348.238704) (xy 328.768675 -348.297289)
			(xy 328.852121 -348.362371) (xy 328.930405 -348.433577) (xy 329.00308 -348.5105) (xy 329.06973 -348.5927)
			(xy 329.129972 -348.679704) (xy 329.183461 -348.771015) (xy 329.229892 -348.86611) (xy 329.268997 -348.964444)
			(xy 329.300554 -349.065455) (xy 329.324381 -349.168562) (xy 329.340342 -349.273176) (xy 329.348346 -349.378698)
			(xy 329.348846 -349.43161) (xy 334.012801 -349.43161) (xy 334.016806 -349.325861) (xy 334.028796 -349.220718)
			(xy 334.048705 -349.116783) (xy 334.076416 -349.014651) (xy 334.111773 -348.914907) (xy 334.154571 -348.818123)
			(xy 334.204567 -348.724853) (xy 334.261474 -348.635632) (xy 334.324965 -348.550969) (xy 334.394677 -348.471351)
			(xy 334.470211 -348.397233) (xy 334.551134 -348.32904) (xy 334.636983 -348.267162) (xy 334.727266 -348.211955)
			(xy 334.821465 -348.163733) (xy 334.919042 -348.122773) (xy 335.019437 -348.089311) (xy 335.122075 -348.063537)
			(xy 335.226368 -348.045599) (xy 335.331719 -348.0356) (xy 335.437525 -348.033597) (xy 335.543179 -348.039602)
			(xy 335.648076 -348.053581) (xy 335.751616 -348.075452) (xy 335.853205 -348.105092) (xy 335.952262 -348.14233)
			(xy 336.048219 -348.186952) (xy 336.140526 -348.238704) (xy 336.228655 -348.297289) (xy 336.312101 -348.362371)
			(xy 336.390385 -348.433577) (xy 336.46306 -348.5105) (xy 336.52971 -348.5927) (xy 336.589952 -348.679704)
			(xy 336.643441 -348.771015) (xy 336.689872 -348.86611) (xy 336.728977 -348.964444) (xy 336.760534 -349.065455)
			(xy 336.784361 -349.168562) (xy 336.800322 -349.273176) (xy 336.808326 -349.378698) (xy 336.808826 -349.43161)
			(xy 336.808326 -349.484522) (xy 336.800322 -349.590044) (xy 336.784361 -349.694658) (xy 336.760534 -349.797765)
			(xy 336.728977 -349.898776) (xy 336.689872 -349.99711) (xy 336.643441 -350.092205) (xy 336.589952 -350.183516)
			(xy 336.52971 -350.27052) (xy 336.46306 -350.35272) (xy 336.390385 -350.429643) (xy 336.312101 -350.500849)
			(xy 336.228655 -350.565931) (xy 336.140526 -350.624516) (xy 336.048219 -350.676268) (xy 335.952262 -350.72089)
			(xy 335.853205 -350.758128) (xy 335.751616 -350.787768) (xy 335.648076 -350.809639) (xy 335.543179 -350.823618)
			(xy 335.437525 -350.829623) (xy 335.331719 -350.82762) (xy 335.226368 -350.817621) (xy 335.122075 -350.799683)
			(xy 335.019437 -350.773909) (xy 334.919042 -350.740447) (xy 334.821465 -350.699487) (xy 334.727266 -350.651265)
			(xy 334.636983 -350.596058) (xy 334.551134 -350.53418) (xy 334.470211 -350.465987) (xy 334.394677 -350.391869)
			(xy 334.324965 -350.312251) (xy 334.261474 -350.227588) (xy 334.204567 -350.138367) (xy 334.154571 -350.045097)
			(xy 334.111773 -349.948313) (xy 334.076416 -349.848569) (xy 334.048705 -349.746437) (xy 334.028796 -349.642502)
			(xy 334.016806 -349.537359) (xy 334.012801 -349.43161) (xy 329.348846 -349.43161) (xy 329.348346 -349.484522)
			(xy 329.340342 -349.590044) (xy 329.324381 -349.694658) (xy 329.300554 -349.797765) (xy 329.268997 -349.898776)
			(xy 329.229892 -349.99711) (xy 329.183461 -350.092205) (xy 329.129972 -350.183516) (xy 329.06973 -350.27052)
			(xy 329.00308 -350.35272) (xy 328.930405 -350.429643) (xy 328.852121 -350.500849) (xy 328.768675 -350.565931)
			(xy 328.680546 -350.624516) (xy 328.588239 -350.676268) (xy 328.492282 -350.72089) (xy 328.393225 -350.758128)
			(xy 328.291636 -350.787768) (xy 328.188096 -350.809639) (xy 328.083199 -350.823618) (xy 327.977545 -350.829623)
			(xy 327.871739 -350.82762) (xy 327.766388 -350.817621) (xy 327.662095 -350.799683) (xy 327.559457 -350.773909)
			(xy 327.459062 -350.740447) (xy 327.361485 -350.699487) (xy 327.267286 -350.651265) (xy 327.177003 -350.596058)
			(xy 327.091154 -350.53418) (xy 327.010231 -350.465987) (xy 326.934697 -350.391869) (xy 326.864985 -350.312251)
			(xy 326.801494 -350.227588) (xy 326.744587 -350.138367) (xy 326.694591 -350.045097) (xy 326.651793 -349.948313)
			(xy 326.616436 -349.848569) (xy 326.588725 -349.746437) (xy 326.568816 -349.642502) (xy 326.556826 -349.537359)
			(xy 326.552821 -349.43161) (xy 313.291976 -349.43161) (xy 313.296254 -349.473962) (xy 313.296808 -349.518732)
			(xy 313.296242 -349.563502) (xy 313.287233 -349.652587) (xy 313.269329 -349.740318) (xy 313.242711 -349.825809)
			(xy 313.225688 -349.86722) (xy 313.222104 -349.876805) (xy 313.222115 -349.897253) (xy 313.225688 -349.906844)
			(xy 313.242711 -349.948256) (xy 313.269347 -350.033743) (xy 313.287256 -350.121474) (xy 313.296254 -350.210562)
			(xy 313.296808 -350.255332) (xy 313.296378 -350.296443) (xy 313.288787 -350.378314) (xy 313.273674 -350.459136)
			(xy 313.251166 -350.538217) (xy 313.221457 -350.614885) (xy 313.184799 -350.688483) (xy 313.141506 -350.758385)
			(xy 313.091947 -350.823993) (xy 313.036545 -350.884747) (xy 312.975772 -350.94013) (xy 312.910148 -350.989668)
			(xy 312.840233 -351.032938) (xy 312.766623 -351.069572) (xy 312.689946 -351.099257) (xy 312.610857 -351.121739)
			(xy 312.530031 -351.136827) (xy 312.448157 -351.144391) (xy 312.407046 -351.14484) (xy 312.365442 -351.14437)
			(xy 312.282594 -351.136637) (xy 312.200829 -351.121206) (xy 312.120862 -351.098211) (xy 312.043389 -351.067854)
			(xy 311.969088 -351.0304) (xy 311.93359 -351.008696) (xy 311.924458 -351.003521) (xy 311.903738 -351.00031)
			(xy 311.883461 -351.005649) (xy 311.874916 -351.011744) (xy 311.841266 -351.037664) (xy 311.769892 -351.083723)
			(xy 311.694453 -351.12277) (xy 311.615637 -351.15445) (xy 311.53416 -351.178473) (xy 311.450764 -351.194623)
			(xy 311.366208 -351.20275) (xy 311.323736 -351.20326) (xy 311.323482 -351.20326) (xy 311.282375 -351.202805)
			(xy 311.200511 -351.195219) (xy 311.119697 -351.180113) (xy 311.04062 -351.157617) (xy 310.963956 -351.127921)
			(xy 310.890359 -351.09128) (xy 310.820455 -351.048006) (xy 310.754841 -350.998468) (xy 310.694077 -350.943088)
			(xy 310.638682 -350.882339) (xy 310.589126 -350.816738) (xy 310.545833 -350.746846) (xy 310.509173 -350.673258)
			(xy 310.479458 -350.596602) (xy 310.456941 -350.517531) (xy 310.441814 -350.43672) (xy 310.434206 -350.354859)
			(xy 310.43372 -350.313752) (xy 310.434279 -350.268982) (xy 310.44329 -350.179897) (xy 310.461196 -350.092166)
			(xy 310.487816 -350.006675) (xy 310.50484 -349.965264) (xy 310.508432 -349.955681) (xy 310.508415 -349.935231)
			(xy 310.50484 -349.92564) (xy 310.487836 -349.884289) (xy 310.461225 -349.798927) (xy 310.443318 -349.711324)
			(xy 310.434296 -349.622367) (xy 310.43372 -349.57766) (xy 310.43372 -349.576644) (xy 310.433974 -349.565214)
			(xy 310.407495 -349.559269) (xy 310.35526 -349.544526) (xy 310.32958 -349.53575) (xy 310.321383 -349.533236)
			(xy 310.304249 -349.533236) (xy 310.296052 -349.53575) (xy 310.260836 -349.547697) (xy 310.188826 -349.566284)
			(xy 310.115503 -349.578724) (xy 310.041392 -349.584928) (xy 310.004206 -349.58528) (xy 309.967022 -349.584911)
			(xy 309.892914 -349.578689) (xy 309.819594 -349.566246) (xy 309.747583 -349.547672) (xy 309.71236 -349.53575)
			(xy 309.704163 -349.533236) (xy 309.687029 -349.533236) (xy 309.678832 -349.53575) (xy 309.64373 -349.547637)
			(xy 309.571974 -349.566187) (xy 309.498911 -349.578634) (xy 309.42506 -349.584887) (xy 309.388002 -349.58528)
			(xy 309.386986 -349.58528) (xy 309.345059 -349.584857) (xy 309.261586 -349.576885) (xy 309.179248 -349.561014)
			(xy 309.098792 -349.537389) (xy 309.020946 -349.506223) (xy 308.946414 -349.467798) (xy 308.875873 -349.422463)
			(xy 308.80996 -349.370628) (xy 308.749273 -349.312762) (xy 308.694361 -349.24939) (xy 308.645722 -349.181084)
			(xy 308.603796 -349.108465) (xy 308.568962 -349.032189) (xy 308.541537 -348.952948) (xy 308.521768 -348.871458)
			(xy 308.509834 -348.788458) (xy 308.505844 -348.7047) (xy 304.961745 -348.7047) (xy 304.965121 -348.741025)
			(xy 304.965608 -348.782132) (xy 304.965042 -348.826902) (xy 304.956033 -348.915987) (xy 304.938129 -349.003718)
			(xy 304.911511 -349.089209) (xy 304.894488 -349.13062) (xy 304.890904 -349.140205) (xy 304.890915 -349.160653)
			(xy 304.894488 -349.170244) (xy 304.911511 -349.211656) (xy 304.938147 -349.297143) (xy 304.956056 -349.384874)
			(xy 304.965054 -349.473962) (xy 304.965608 -349.518732) (xy 304.965042 -349.563502) (xy 304.956033 -349.652587)
			(xy 304.938129 -349.740318) (xy 304.911511 -349.825809) (xy 304.894488 -349.86722) (xy 304.890904 -349.876805)
			(xy 304.890915 -349.897253) (xy 304.894488 -349.906844) (xy 304.911511 -349.948256) (xy 304.938147 -350.033743)
			(xy 304.956056 -350.121474) (xy 304.965054 -350.210562) (xy 304.965608 -350.255332) (xy 304.965178 -350.296443)
			(xy 304.957587 -350.378314) (xy 304.942474 -350.459136) (xy 304.919966 -350.538217) (xy 304.890257 -350.614885)
			(xy 304.853599 -350.688483) (xy 304.810306 -350.758385) (xy 304.760747 -350.823993) (xy 304.705345 -350.884747)
			(xy 304.644572 -350.94013) (xy 304.578948 -350.989668) (xy 304.509033 -351.032938) (xy 304.435423 -351.069572)
			(xy 304.358746 -351.099257) (xy 304.279657 -351.121739) (xy 304.198831 -351.136827) (xy 304.116957 -351.144391)
			(xy 304.075846 -351.14484) (xy 304.034242 -351.14437) (xy 303.951394 -351.136637) (xy 303.869629 -351.121206)
			(xy 303.789662 -351.098211) (xy 303.712189 -351.067854) (xy 303.637888 -351.0304) (xy 303.60239 -351.008696)
			(xy 303.593258 -351.003521) (xy 303.572538 -351.00031) (xy 303.552261 -351.005649) (xy 303.543716 -351.011744)
			(xy 303.510066 -351.037664) (xy 303.438692 -351.083723) (xy 303.363253 -351.12277) (xy 303.284437 -351.15445)
			(xy 303.20296 -351.178473) (xy 303.119564 -351.194623) (xy 303.035008 -351.20275) (xy 302.992536 -351.20326)
			(xy 302.992282 -351.20326) (xy 302.951175 -351.202805) (xy 302.869311 -351.195219) (xy 302.788497 -351.180113)
			(xy 302.70942 -351.157617) (xy 302.632756 -351.127921) (xy 302.559159 -351.09128) (xy 302.489255 -351.048006)
			(xy 302.423641 -350.998468) (xy 302.362877 -350.943088) (xy 302.307482 -350.882339) (xy 302.257926 -350.816738)
			(xy 302.214633 -350.746846) (xy 302.177973 -350.673258) (xy 302.148258 -350.596602) (xy 302.125741 -350.517531)
			(xy 302.110614 -350.43672) (xy 302.103006 -350.354859) (xy 302.10252 -350.313752) (xy 302.103079 -350.268982)
			(xy 302.11209 -350.179897) (xy 302.129996 -350.092166) (xy 302.156616 -350.006675) (xy 302.17364 -349.965264)
			(xy 302.177232 -349.955681) (xy 302.177215 -349.935231) (xy 302.17364 -349.92564) (xy 302.156636 -349.884289)
			(xy 302.130025 -349.798927) (xy 302.112118 -349.711324) (xy 302.103096 -349.622367) (xy 302.10252 -349.57766)
			(xy 302.10252 -349.576644) (xy 302.102774 -349.565214) (xy 302.076295 -349.559269) (xy 302.02406 -349.544526)
			(xy 301.99838 -349.53575) (xy 301.990183 -349.533236) (xy 301.973049 -349.533236) (xy 301.964852 -349.53575)
			(xy 301.929636 -349.547697) (xy 301.857626 -349.566284) (xy 301.784303 -349.578724) (xy 301.710192 -349.584928)
			(xy 301.673006 -349.58528) (xy 301.635822 -349.584911) (xy 301.561714 -349.578689) (xy 301.488394 -349.566246)
			(xy 301.416383 -349.547672) (xy 301.38116 -349.53575) (xy 301.372963 -349.533236) (xy 301.355829 -349.533236)
			(xy 301.347632 -349.53575) (xy 301.31253 -349.547637) (xy 301.240774 -349.566187) (xy 301.167711 -349.578634)
			(xy 301.09386 -349.584887) (xy 301.056802 -349.58528) (xy 301.055786 -349.58528) (xy 301.013859 -349.584857)
			(xy 300.930386 -349.576885) (xy 300.848048 -349.561014) (xy 300.767592 -349.537389) (xy 300.689746 -349.506223)
			(xy 300.615214 -349.467798) (xy 300.544673 -349.422463) (xy 300.47876 -349.370628) (xy 300.418073 -349.312762)
			(xy 300.363161 -349.24939) (xy 300.314522 -349.181084) (xy 300.272596 -349.108465) (xy 300.237762 -349.032189)
			(xy 300.210337 -348.952948) (xy 300.190568 -348.871458) (xy 300.178634 -348.788458) (xy 300.174644 -348.7047)
			(xy 296.605145 -348.7047) (xy 296.608521 -348.741025) (xy 296.609008 -348.782132) (xy 296.608442 -348.826902)
			(xy 296.599433 -348.915987) (xy 296.581529 -349.003718) (xy 296.554911 -349.089209) (xy 296.537888 -349.13062)
			(xy 296.534304 -349.140205) (xy 296.534315 -349.160653) (xy 296.537888 -349.170244) (xy 296.554911 -349.211656)
			(xy 296.581547 -349.297143) (xy 296.599456 -349.384874) (xy 296.608454 -349.473962) (xy 296.609008 -349.518732)
			(xy 296.608442 -349.563502) (xy 296.599433 -349.652587) (xy 296.581529 -349.740318) (xy 296.554911 -349.825809)
			(xy 296.537888 -349.86722) (xy 296.534304 -349.876805) (xy 296.534315 -349.897253) (xy 296.537888 -349.906844)
			(xy 296.554911 -349.948256) (xy 296.581547 -350.033743) (xy 296.599456 -350.121474) (xy 296.608454 -350.210562)
			(xy 296.609008 -350.255332) (xy 296.608578 -350.296443) (xy 296.600987 -350.378314) (xy 296.585874 -350.459136)
			(xy 296.563366 -350.538217) (xy 296.533657 -350.614885) (xy 296.496999 -350.688483) (xy 296.453706 -350.758385)
			(xy 296.404147 -350.823993) (xy 296.348745 -350.884747) (xy 296.287972 -350.94013) (xy 296.222348 -350.989668)
			(xy 296.152433 -351.032938) (xy 296.078823 -351.069572) (xy 296.002146 -351.099257) (xy 295.923057 -351.121739)
			(xy 295.842231 -351.136827) (xy 295.760357 -351.144391) (xy 295.719246 -351.14484) (xy 295.677642 -351.14437)
			(xy 295.594794 -351.136637) (xy 295.513029 -351.121206) (xy 295.433062 -351.098211) (xy 295.355589 -351.067854)
			(xy 295.281288 -351.0304) (xy 295.24579 -351.008696) (xy 295.236658 -351.003521) (xy 295.215938 -351.00031)
			(xy 295.195661 -351.005649) (xy 295.187116 -351.011744) (xy 295.153466 -351.037664) (xy 295.082092 -351.083723)
			(xy 295.006653 -351.12277) (xy 294.927837 -351.15445) (xy 294.84636 -351.178473) (xy 294.762964 -351.194623)
			(xy 294.678408 -351.20275) (xy 294.635936 -351.20326) (xy 294.635682 -351.20326) (xy 294.594575 -351.202805)
			(xy 294.512711 -351.195219) (xy 294.431897 -351.180113) (xy 294.35282 -351.157617) (xy 294.276156 -351.127921)
			(xy 294.202559 -351.09128) (xy 294.132655 -351.048006) (xy 294.067041 -350.998468) (xy 294.006277 -350.943088)
			(xy 293.950882 -350.882339) (xy 293.901326 -350.816738) (xy 293.858033 -350.746846) (xy 293.821373 -350.673258)
			(xy 293.791658 -350.596602) (xy 293.769141 -350.517531) (xy 293.754014 -350.43672) (xy 293.746406 -350.354859)
			(xy 293.74592 -350.313752) (xy 293.746479 -350.268982) (xy 293.75549 -350.179897) (xy 293.773396 -350.092166)
			(xy 293.800016 -350.006675) (xy 293.81704 -349.965264) (xy 293.820632 -349.955681) (xy 293.820615 -349.935231)
			(xy 293.81704 -349.92564) (xy 293.800036 -349.884289) (xy 293.773425 -349.798927) (xy 293.755518 -349.711324)
			(xy 293.746496 -349.622367) (xy 293.74592 -349.57766) (xy 293.74592 -349.576644) (xy 293.746174 -349.565214)
			(xy 293.719695 -349.559269) (xy 293.66746 -349.544526) (xy 293.64178 -349.53575) (xy 293.633583 -349.533236)
			(xy 293.616449 -349.533236) (xy 293.608252 -349.53575) (xy 293.573036 -349.547697) (xy 293.501026 -349.566284)
			(xy 293.427703 -349.578724) (xy 293.353592 -349.584928) (xy 293.316406 -349.58528) (xy 293.279222 -349.584911)
			(xy 293.205114 -349.578689) (xy 293.131794 -349.566246) (xy 293.059783 -349.547672) (xy 293.02456 -349.53575)
			(xy 293.016363 -349.533236) (xy 292.999229 -349.533236) (xy 292.991032 -349.53575) (xy 292.95593 -349.547637)
			(xy 292.884174 -349.566187) (xy 292.811111 -349.578634) (xy 292.73726 -349.584887) (xy 292.700202 -349.58528)
			(xy 292.699186 -349.58528) (xy 292.657259 -349.584857) (xy 292.573786 -349.576885) (xy 292.491448 -349.561014)
			(xy 292.410992 -349.537389) (xy 292.333146 -349.506223) (xy 292.258614 -349.467798) (xy 292.188073 -349.422463)
			(xy 292.12216 -349.370628) (xy 292.061473 -349.312762) (xy 292.006561 -349.24939) (xy 291.957922 -349.181084)
			(xy 291.915996 -349.108465) (xy 291.881162 -349.032189) (xy 291.853737 -348.952948) (xy 291.833968 -348.871458)
			(xy 291.822034 -348.788458) (xy 291.818044 -348.7047) (xy 288.299345 -348.7047) (xy 288.302721 -348.741025)
			(xy 288.303208 -348.782132) (xy 288.302642 -348.826902) (xy 288.293633 -348.915987) (xy 288.275729 -349.003718)
			(xy 288.249111 -349.089209) (xy 288.232088 -349.13062) (xy 288.228504 -349.140205) (xy 288.228515 -349.160653)
			(xy 288.232088 -349.170244) (xy 288.249111 -349.211656) (xy 288.275747 -349.297143) (xy 288.293656 -349.384874)
			(xy 288.302654 -349.473962) (xy 288.303208 -349.518732) (xy 288.302642 -349.563502) (xy 288.293633 -349.652587)
			(xy 288.275729 -349.740318) (xy 288.249111 -349.825809) (xy 288.232088 -349.86722) (xy 288.228504 -349.876805)
			(xy 288.228515 -349.897253) (xy 288.232088 -349.906844) (xy 288.249111 -349.948256) (xy 288.275747 -350.033743)
			(xy 288.293656 -350.121474) (xy 288.302654 -350.210562) (xy 288.303208 -350.255332) (xy 288.302778 -350.296443)
			(xy 288.295187 -350.378314) (xy 288.280074 -350.459136) (xy 288.257566 -350.538217) (xy 288.227857 -350.614885)
			(xy 288.191199 -350.688483) (xy 288.147906 -350.758385) (xy 288.098347 -350.823993) (xy 288.042945 -350.884747)
			(xy 287.982172 -350.94013) (xy 287.916548 -350.989668) (xy 287.846633 -351.032938) (xy 287.773023 -351.069572)
			(xy 287.696346 -351.099257) (xy 287.617257 -351.121739) (xy 287.536431 -351.136827) (xy 287.454557 -351.144391)
			(xy 287.413446 -351.14484) (xy 287.371842 -351.14437) (xy 287.288994 -351.136637) (xy 287.207229 -351.121206)
			(xy 287.127262 -351.098211) (xy 287.049789 -351.067854) (xy 286.975488 -351.0304) (xy 286.93999 -351.008696)
			(xy 286.930858 -351.003521) (xy 286.910138 -351.00031) (xy 286.889861 -351.005649) (xy 286.881316 -351.011744)
			(xy 286.847666 -351.037664) (xy 286.776292 -351.083723) (xy 286.700853 -351.12277) (xy 286.622037 -351.15445)
			(xy 286.54056 -351.178473) (xy 286.457164 -351.194623) (xy 286.372608 -351.20275) (xy 286.330136 -351.20326)
			(xy 286.329882 -351.20326) (xy 286.288775 -351.202805) (xy 286.206911 -351.195219) (xy 286.126097 -351.180113)
			(xy 286.04702 -351.157617) (xy 285.970356 -351.127921) (xy 285.896759 -351.09128) (xy 285.826855 -351.048006)
			(xy 285.761241 -350.998468) (xy 285.700477 -350.943088) (xy 285.645082 -350.882339) (xy 285.595526 -350.816738)
			(xy 285.552233 -350.746846) (xy 285.515573 -350.673258) (xy 285.485858 -350.596602) (xy 285.463341 -350.517531)
			(xy 285.448214 -350.43672) (xy 285.440606 -350.354859) (xy 285.44012 -350.313752) (xy 285.440679 -350.268982)
			(xy 285.44969 -350.179897) (xy 285.467596 -350.092166) (xy 285.494216 -350.006675) (xy 285.51124 -349.965264)
			(xy 285.514832 -349.955681) (xy 285.514815 -349.935231) (xy 285.51124 -349.92564) (xy 285.494236 -349.884289)
			(xy 285.467625 -349.798927) (xy 285.449718 -349.711324) (xy 285.440696 -349.622367) (xy 285.44012 -349.57766)
			(xy 285.44012 -349.576644) (xy 285.440374 -349.565214) (xy 285.413895 -349.559269) (xy 285.36166 -349.544526)
			(xy 285.33598 -349.53575) (xy 285.327783 -349.533236) (xy 285.310649 -349.533236) (xy 285.302452 -349.53575)
			(xy 285.267236 -349.547697) (xy 285.195226 -349.566284) (xy 285.121903 -349.578724) (xy 285.047792 -349.584928)
			(xy 285.010606 -349.58528) (xy 284.973422 -349.584911) (xy 284.899314 -349.578689) (xy 284.825994 -349.566246)
			(xy 284.753983 -349.547672) (xy 284.71876 -349.53575) (xy 284.710563 -349.533236) (xy 284.693429 -349.533236)
			(xy 284.685232 -349.53575) (xy 284.65013 -349.547637) (xy 284.578374 -349.566187) (xy 284.505311 -349.578634)
			(xy 284.43146 -349.584887) (xy 284.394402 -349.58528) (xy 284.393386 -349.58528) (xy 284.351459 -349.584857)
			(xy 284.267986 -349.576885) (xy 284.185648 -349.561014) (xy 284.105192 -349.537389) (xy 284.027346 -349.506223)
			(xy 283.952814 -349.467798) (xy 283.882273 -349.422463) (xy 283.81636 -349.370628) (xy 283.755673 -349.312762)
			(xy 283.700761 -349.24939) (xy 283.652122 -349.181084) (xy 283.610196 -349.108465) (xy 283.575362 -349.032189)
			(xy 283.547937 -348.952948) (xy 283.528168 -348.871458) (xy 283.516234 -348.788458) (xy 283.512244 -348.7047)
			(xy 280.018945 -348.7047) (xy 280.022321 -348.741025) (xy 280.022808 -348.782132) (xy 280.022242 -348.826902)
			(xy 280.013233 -348.915987) (xy 279.995329 -349.003718) (xy 279.968711 -349.089209) (xy 279.951688 -349.13062)
			(xy 279.948104 -349.140205) (xy 279.948115 -349.160653) (xy 279.951688 -349.170244) (xy 279.968711 -349.211656)
			(xy 279.995347 -349.297143) (xy 280.013256 -349.384874) (xy 280.022254 -349.473962) (xy 280.022808 -349.518732)
			(xy 280.022242 -349.563502) (xy 280.013233 -349.652587) (xy 279.995329 -349.740318) (xy 279.968711 -349.825809)
			(xy 279.951688 -349.86722) (xy 279.948104 -349.876805) (xy 279.948115 -349.897253) (xy 279.951688 -349.906844)
			(xy 279.968711 -349.948256) (xy 279.995347 -350.033743) (xy 280.013256 -350.121474) (xy 280.022254 -350.210562)
			(xy 280.022808 -350.255332) (xy 280.022378 -350.296443) (xy 280.014787 -350.378314) (xy 279.999674 -350.459136)
			(xy 279.977166 -350.538217) (xy 279.947457 -350.614885) (xy 279.910799 -350.688483) (xy 279.867506 -350.758385)
			(xy 279.817947 -350.823993) (xy 279.762545 -350.884747) (xy 279.701772 -350.94013) (xy 279.636148 -350.989668)
			(xy 279.566233 -351.032938) (xy 279.492623 -351.069572) (xy 279.415946 -351.099257) (xy 279.336857 -351.121739)
			(xy 279.256031 -351.136827) (xy 279.174157 -351.144391) (xy 279.133046 -351.14484) (xy 279.091442 -351.14437)
			(xy 279.008594 -351.136637) (xy 278.926829 -351.121206) (xy 278.846862 -351.098211) (xy 278.769389 -351.067854)
			(xy 278.695088 -351.0304) (xy 278.65959 -351.008696) (xy 278.650458 -351.003521) (xy 278.629738 -351.00031)
			(xy 278.609461 -351.005649) (xy 278.600916 -351.011744) (xy 278.567266 -351.037664) (xy 278.495892 -351.083723)
			(xy 278.420453 -351.12277) (xy 278.341637 -351.15445) (xy 278.26016 -351.178473) (xy 278.176764 -351.194623)
			(xy 278.092208 -351.20275) (xy 278.049736 -351.20326) (xy 278.049482 -351.20326) (xy 278.008375 -351.202805)
			(xy 277.926511 -351.195219) (xy 277.845697 -351.180113) (xy 277.76662 -351.157617) (xy 277.689956 -351.127921)
			(xy 277.616359 -351.09128) (xy 277.546455 -351.048006) (xy 277.480841 -350.998468) (xy 277.420077 -350.943088)
			(xy 277.364682 -350.882339) (xy 277.315126 -350.816738) (xy 277.271833 -350.746846) (xy 277.235173 -350.673258)
			(xy 277.205458 -350.596602) (xy 277.182941 -350.517531) (xy 277.167814 -350.43672) (xy 277.160206 -350.354859)
			(xy 277.15972 -350.313752) (xy 277.160279 -350.268982) (xy 277.16929 -350.179897) (xy 277.187196 -350.092166)
			(xy 277.213816 -350.006675) (xy 277.23084 -349.965264) (xy 277.234432 -349.955681) (xy 277.234415 -349.935231)
			(xy 277.23084 -349.92564) (xy 277.213836 -349.884289) (xy 277.187225 -349.798927) (xy 277.169318 -349.711324)
			(xy 277.160296 -349.622367) (xy 277.15972 -349.57766) (xy 277.15972 -349.576644) (xy 277.159974 -349.565214)
			(xy 277.133495 -349.559269) (xy 277.08126 -349.544526) (xy 277.05558 -349.53575) (xy 277.047383 -349.533236)
			(xy 277.030249 -349.533236) (xy 277.022052 -349.53575) (xy 276.986836 -349.547697) (xy 276.914826 -349.566284)
			(xy 276.841503 -349.578724) (xy 276.767392 -349.584928) (xy 276.730206 -349.58528) (xy 276.693022 -349.584911)
			(xy 276.618914 -349.578689) (xy 276.545594 -349.566246) (xy 276.473583 -349.547672) (xy 276.43836 -349.53575)
			(xy 276.430163 -349.533236) (xy 276.413029 -349.533236) (xy 276.404832 -349.53575) (xy 276.36973 -349.547637)
			(xy 276.297974 -349.566187) (xy 276.224911 -349.578634) (xy 276.15106 -349.584887) (xy 276.114002 -349.58528)
			(xy 276.112986 -349.58528) (xy 276.071059 -349.584857) (xy 275.987586 -349.576885) (xy 275.905248 -349.561014)
			(xy 275.824792 -349.537389) (xy 275.746946 -349.506223) (xy 275.672414 -349.467798) (xy 275.601873 -349.422463)
			(xy 275.53596 -349.370628) (xy 275.475273 -349.312762) (xy 275.420361 -349.24939) (xy 275.371722 -349.181084)
			(xy 275.329796 -349.108465) (xy 275.294962 -349.032189) (xy 275.267537 -348.952948) (xy 275.247768 -348.871458)
			(xy 275.235834 -348.788458) (xy 275.231844 -348.7047) (xy 85.721282 -348.7047) (xy 85.724562 -348.719921)
			(xy 85.734552 -348.813881) (xy 85.73516 -348.861126) (xy 85.734613 -348.906766) (xy 85.725307 -348.997569)
			(xy 85.706754 -349.086942) (xy 85.693504 -349.13062) (xy 85.691044 -349.139629) (xy 85.692095 -349.15826)
			(xy 85.695536 -349.166942) (xy 85.714247 -349.210016) (xy 85.743525 -349.299254) (xy 85.763232 -349.391081)
			(xy 85.77315 -349.484473) (xy 85.773768 -349.531432) (xy 85.77323 -349.574377) (xy 85.764932 -349.659867)
			(xy 85.748446 -349.744161) (xy 85.723925 -349.826477) (xy 85.708236 -349.866458) (xy 85.704966 -349.875707)
			(xy 85.704968 -349.895308) (xy 85.708236 -349.904558) (xy 85.723959 -349.944561) (xy 85.748521 -350.026936)
			(xy 85.765013 -350.111298) (xy 85.773281 -350.196858) (xy 85.773768 -350.239838) (xy 85.773264 -350.282199)
			(xy 85.765211 -350.366536) (xy 85.749177 -350.449726) (xy 85.725309 -350.531016) (xy 85.693821 -350.609668)
			(xy 85.654999 -350.684971) (xy 85.609196 -350.756243) (xy 85.556825 -350.822839) (xy 85.49836 -350.884154)
			(xy 85.434332 -350.939635) (xy 85.36532 -350.988778) (xy 85.29195 -351.031138) (xy 85.214885 -351.066333)
			(xy 85.134823 -351.094042) (xy 85.05249 -351.114016) (xy 84.968631 -351.126073) (xy 84.884006 -351.130105)
			(xy 84.799381 -351.126073) (xy 84.715522 -351.114016) (xy 84.633189 -351.094042) (xy 84.553127 -351.066333)
			(xy 84.476062 -351.031138) (xy 84.402692 -350.988778) (xy 84.33368 -350.939635) (xy 84.269652 -350.884154)
			(xy 84.211187 -350.822839) (xy 84.158816 -350.756243) (xy 84.113013 -350.684971) (xy 84.074191 -350.609668)
			(xy 84.042703 -350.531016) (xy 84.018835 -350.449726) (xy 84.002801 -350.366536) (xy 83.994748 -350.282199)
			(xy 83.994244 -350.239838) (xy 83.994769 -350.196861) (xy 84.003053 -350.111306) (xy 84.01954 -350.026947)
			(xy 84.044076 -349.944568) (xy 84.059776 -349.904558) (xy 84.063037 -349.895306) (xy 84.06304 -349.875708)
			(xy 84.059776 -349.866458) (xy 84.044053 -349.826489) (xy 84.019511 -349.744174) (xy 84.003027 -349.659876)
			(xy 83.994754 -349.57438) (xy 83.994244 -349.531432) (xy 83.994855 -349.485787) (xy 84.004246 -349.394981)
			(xy 84.022872 -349.305612) (xy 84.036154 -349.261938) (xy 84.038586 -349.252923) (xy 84.037555 -349.234298)
			(xy 84.034122 -349.225616) (xy 84.015469 -349.182525) (xy 83.98626 -349.093282) (xy 83.966612 -349.001459)
			(xy 83.956742 -348.908077) (xy 83.956144 -348.861126) (xy 83.073245 -348.861126) (xy 83.073748 -348.89948)
			(xy 83.073141 -348.945125) (xy 83.063748 -349.035931) (xy 83.045121 -349.1253) (xy 83.031838 -349.168974)
			(xy 83.0294 -349.177987) (xy 83.030435 -349.196614) (xy 83.03387 -349.205296) (xy 83.052527 -349.248385)
			(xy 83.081735 -349.337629) (xy 83.101382 -349.429453) (xy 83.111251 -349.522835) (xy 83.111848 -349.569786)
			(xy 83.111412 -349.610119) (xy 83.104141 -349.690457) (xy 83.08963 -349.769807) (xy 83.067997 -349.847519)
			(xy 83.039422 -349.922954) (xy 83.022186 -349.959422) (xy 83.017653 -349.970011) (xy 83.017661 -349.993024)
			(xy 83.022186 -350.003618) (xy 83.039397 -350.040069) (xy 83.067953 -350.115455) (xy 83.089579 -350.193114)
			(xy 83.104099 -350.27241) (xy 83.111393 -350.352693) (xy 83.111848 -350.393) (xy 83.111344 -350.435361)
			(xy 83.103291 -350.519698) (xy 83.087257 -350.602888) (xy 83.063389 -350.684178) (xy 83.031901 -350.76283)
			(xy 82.993079 -350.838133) (xy 82.947276 -350.909405) (xy 82.894905 -350.976001) (xy 82.83644 -351.037316)
			(xy 82.772412 -351.092797) (xy 82.7034 -351.14194) (xy 82.63003 -351.1843) (xy 82.552965 -351.219495)
			(xy 82.472903 -351.247204) (xy 82.39057 -351.267178) (xy 82.306711 -351.279235) (xy 82.222086 -351.283267)
			(xy 82.137461 -351.279235) (xy 82.053602 -351.267178) (xy 81.971269 -351.247204) (xy 81.891207 -351.219495)
			(xy 81.814142 -351.1843) (xy 81.740772 -351.14194) (xy 81.67176 -351.092797) (xy 81.607732 -351.037316)
			(xy 81.549267 -350.976001) (xy 81.496896 -350.909405) (xy 81.451093 -350.838133) (xy 81.412271 -350.76283)
			(xy 81.380783 -350.684178) (xy 81.356915 -350.602888) (xy 81.340881 -350.519698) (xy 81.332828 -350.435361)
			(xy 81.332324 -350.393) (xy 81.332778 -350.35266) (xy 81.340081 -350.272312) (xy 81.354637 -350.192956)
			(xy 81.376326 -350.115246) (xy 81.404968 -350.039822) (xy 81.42224 -350.003364) (xy 81.426812 -349.992711)
			(xy 81.426828 -349.969558) (xy 81.42224 -349.958914) (xy 81.405059 -349.922483) (xy 81.376548 -349.847143)
			(xy 81.35497 -349.769534) (xy 81.340501 -349.69029) (xy 81.33326 -349.610063) (xy 81.332832 -349.569786)
			(xy 81.333382 -349.524146) (xy 81.342687 -349.433343) (xy 81.361239 -349.34397) (xy 81.374488 -349.300292)
			(xy 81.376942 -349.291282) (xy 81.375896 -349.272652) (xy 81.372456 -349.26397) (xy 81.353748 -349.220894)
			(xy 81.32447 -349.131657) (xy 81.304762 -349.039831) (xy 81.294843 -348.946439) (xy 81.294224 -348.89948)
			(xy 66.467942 -348.89948) (xy 66.465784 -348.920813) (xy 66.447878 -349.008544) (xy 66.421259 -349.094035)
			(xy 66.404236 -349.135446) (xy 66.400697 -349.145044) (xy 66.400681 -349.16548) (xy 66.404236 -349.17507)
			(xy 66.421263 -349.21648) (xy 66.4479 -349.301967) (xy 66.465806 -349.3897) (xy 66.474803 -349.478787)
			(xy 66.475356 -349.523558) (xy 66.474795 -349.568328) (xy 66.465784 -349.657413) (xy 66.447878 -349.745144)
			(xy 66.421259 -349.830635) (xy 66.404236 -349.872046) (xy 66.400697 -349.881644) (xy 66.400681 -349.90208)
			(xy 66.404236 -349.91167) (xy 66.421263 -349.95308) (xy 66.4479 -350.038567) (xy 66.465806 -350.1263)
			(xy 66.474803 -350.215387) (xy 66.475356 -350.260158) (xy 66.474861 -350.301272) (xy 66.467278 -350.383151)
			(xy 66.452172 -350.46398) (xy 66.429672 -350.54307) (xy 66.39997 -350.619748) (xy 66.36332 -350.693357)
			(xy 66.320034 -350.76327) (xy 66.270482 -350.828891) (xy 66.215086 -350.88966) (xy 66.154319 -350.945059)
			(xy 66.0887 -350.994614) (xy 66.018788 -351.037902) (xy 65.94518 -351.074555) (xy 65.868505 -351.10426)
			(xy 65.789415 -351.126764) (xy 65.708586 -351.141873) (xy 65.626708 -351.14946) (xy 65.585594 -351.14992)
			(xy 65.543984 -351.149442) (xy 65.461127 -351.141665) (xy 65.379358 -351.12619) (xy 65.299391 -351.10315)
			(xy 65.221922 -351.072748) (xy 65.147629 -351.035248) (xy 65.112138 -351.013522) (xy 65.10303 -351.008297)
			(xy 65.082293 -351.005101) (xy 65.062008 -351.010462) (xy 65.053464 -351.01657) (xy 65.019831 -351.042555)
			(xy 64.948437 -351.08868) (xy 64.872967 -351.127782) (xy 64.79411 -351.159503) (xy 64.712585 -351.183553)
			(xy 64.629138 -351.199714) (xy 64.544529 -351.207838) (xy 64.50203 -351.20834) (xy 64.460915 -351.207873)
			(xy 64.379035 -351.200288) (xy 64.298205 -351.185181) (xy 64.219114 -351.162679) (xy 64.142436 -351.132976)
			(xy 64.068826 -351.096324) (xy 63.998912 -351.053036) (xy 63.93329 -351.003482) (xy 63.872521 -350.948084)
			(xy 63.817123 -350.887316) (xy 63.767568 -350.821695) (xy 63.72428 -350.751781) (xy 63.687628 -350.678172)
			(xy 63.657923 -350.601494) (xy 63.635421 -350.522403) (xy 63.620313 -350.441573) (xy 63.612727 -350.359693)
			(xy 63.612268 -350.318578) (xy 63.61284 -350.273809) (xy 63.621847 -350.184724) (xy 63.63975 -350.096993)
			(xy 63.666366 -350.011501) (xy 63.683388 -349.97009) (xy 63.686968 -349.960503) (xy 63.68696 -349.940056)
			(xy 63.683388 -349.930466) (xy 63.666363 -349.889123) (xy 63.639757 -349.803758) (xy 63.621856 -349.716153)
			(xy 63.612841 -349.627193) (xy 63.612268 -349.582486) (xy 63.612268 -349.58147) (xy 63.612522 -349.57004)
			(xy 63.586044 -349.564091) (xy 63.533809 -349.54935) (xy 63.508128 -349.540576) (xy 63.499931 -349.538062)
			(xy 63.482797 -349.538062) (xy 63.4746 -349.540576) (xy 63.43938 -349.552528) (xy 63.367379 -349.571185)
			(xy 63.294059 -349.583696) (xy 63.219944 -349.589972) (xy 63.182754 -349.59036) (xy 63.145565 -349.589952)
			(xy 63.071452 -349.583667) (xy 62.998133 -349.571163) (xy 62.926126 -349.552528) (xy 62.890908 -349.540576)
			(xy 62.882711 -349.538062) (xy 62.865577 -349.538062) (xy 62.85738 -349.540576) (xy 62.822162 -349.552533)
			(xy 62.75016 -349.571189) (xy 62.676839 -349.583699) (xy 62.602724 -349.589973) (xy 62.565534 -349.59036)
			(xy 62.523594 -349.589902) (xy 62.440094 -349.581932) (xy 62.35773 -349.566061) (xy 62.277248 -349.542432)
			(xy 62.199376 -349.511259) (xy 62.12482 -349.472825) (xy 62.054255 -349.427478) (xy 61.98832 -349.375629)
			(xy 61.927613 -349.317747) (xy 61.872683 -349.254356) (xy 61.824027 -349.186031) (xy 61.782086 -349.11339)
			(xy 61.74724 -349.037091) (xy 61.719806 -348.957825) (xy 61.70003 -348.87631) (xy 61.688092 -348.793284)
			(xy 61.684101 -348.7095) (xy 58.14031 -348.7095) (xy 58.143679 -348.745845) (xy 58.144156 -348.786958)
			(xy 58.143595 -348.831728) (xy 58.134584 -348.920813) (xy 58.116678 -349.008544) (xy 58.090059 -349.094035)
			(xy 58.073036 -349.135446) (xy 58.069497 -349.145044) (xy 58.069481 -349.16548) (xy 58.073036 -349.17507)
			(xy 58.090063 -349.21648) (xy 58.1167 -349.301967) (xy 58.134606 -349.3897) (xy 58.143603 -349.478787)
			(xy 58.144156 -349.523558) (xy 58.143595 -349.568328) (xy 58.134584 -349.657413) (xy 58.116678 -349.745144)
			(xy 58.090059 -349.830635) (xy 58.073036 -349.872046) (xy 58.069497 -349.881644) (xy 58.069481 -349.90208)
			(xy 58.073036 -349.91167) (xy 58.090063 -349.95308) (xy 58.1167 -350.038567) (xy 58.134606 -350.1263)
			(xy 58.143603 -350.215387) (xy 58.144156 -350.260158) (xy 58.143661 -350.301272) (xy 58.136078 -350.383151)
			(xy 58.120972 -350.46398) (xy 58.098472 -350.54307) (xy 58.06877 -350.619748) (xy 58.03212 -350.693357)
			(xy 57.988834 -350.76327) (xy 57.939282 -350.828891) (xy 57.883886 -350.88966) (xy 57.823119 -350.945059)
			(xy 57.7575 -350.994614) (xy 57.687588 -351.037902) (xy 57.61398 -351.074555) (xy 57.537305 -351.10426)
			(xy 57.458215 -351.126764) (xy 57.377386 -351.141873) (xy 57.295508 -351.14946) (xy 57.254394 -351.14992)
			(xy 57.212784 -351.149442) (xy 57.129927 -351.141665) (xy 57.048158 -351.12619) (xy 56.968191 -351.10315)
			(xy 56.890722 -351.072748) (xy 56.816429 -351.035248) (xy 56.780938 -351.013522) (xy 56.77183 -351.008297)
			(xy 56.751093 -351.005101) (xy 56.730808 -351.010462) (xy 56.722264 -351.01657) (xy 56.688631 -351.042555)
			(xy 56.617237 -351.08868) (xy 56.541767 -351.127782) (xy 56.46291 -351.159503) (xy 56.381385 -351.183553)
			(xy 56.297938 -351.199714) (xy 56.213329 -351.207838) (xy 56.17083 -351.20834) (xy 56.129715 -351.207873)
			(xy 56.047835 -351.200288) (xy 55.967005 -351.185181) (xy 55.887914 -351.162679) (xy 55.811236 -351.132976)
			(xy 55.737626 -351.096324) (xy 55.667712 -351.053036) (xy 55.60209 -351.003482) (xy 55.541321 -350.948084)
			(xy 55.485923 -350.887316) (xy 55.436368 -350.821695) (xy 55.39308 -350.751781) (xy 55.356428 -350.678172)
			(xy 55.326723 -350.601494) (xy 55.304221 -350.522403) (xy 55.289113 -350.441573) (xy 55.281527 -350.359693)
			(xy 55.281068 -350.318578) (xy 55.28164 -350.273809) (xy 55.290647 -350.184724) (xy 55.30855 -350.096993)
			(xy 55.335166 -350.011501) (xy 55.352188 -349.97009) (xy 55.355768 -349.960503) (xy 55.35576 -349.940056)
			(xy 55.352188 -349.930466) (xy 55.335163 -349.889123) (xy 55.308557 -349.803758) (xy 55.290656 -349.716153)
			(xy 55.281641 -349.627193) (xy 55.281068 -349.582486) (xy 55.281068 -349.58147) (xy 55.281322 -349.57004)
			(xy 55.254844 -349.564091) (xy 55.202609 -349.54935) (xy 55.176928 -349.540576) (xy 55.168731 -349.538062)
			(xy 55.151597 -349.538062) (xy 55.1434 -349.540576) (xy 55.10818 -349.552528) (xy 55.036179 -349.571185)
			(xy 54.962859 -349.583696) (xy 54.888744 -349.589972) (xy 54.851554 -349.59036) (xy 54.814365 -349.589952)
			(xy 54.740252 -349.583667) (xy 54.666933 -349.571163) (xy 54.594926 -349.552528) (xy 54.559708 -349.540576)
			(xy 54.551511 -349.538062) (xy 54.534377 -349.538062) (xy 54.52618 -349.540576) (xy 54.490962 -349.552533)
			(xy 54.41896 -349.571189) (xy 54.345639 -349.583699) (xy 54.271524 -349.589973) (xy 54.234334 -349.59036)
			(xy 54.192394 -349.589902) (xy 54.108894 -349.581932) (xy 54.02653 -349.566061) (xy 53.946048 -349.542432)
			(xy 53.868176 -349.511259) (xy 53.79362 -349.472825) (xy 53.723055 -349.427478) (xy 53.65712 -349.375629)
			(xy 53.596413 -349.317747) (xy 53.541483 -349.254356) (xy 53.492827 -349.186031) (xy 53.450886 -349.11339)
			(xy 53.41604 -349.037091) (xy 53.388606 -348.957825) (xy 53.36883 -348.87631) (xy 53.356892 -348.793284)
			(xy 53.352901 -348.7095) (xy 49.78371 -348.7095) (xy 49.787079 -348.745845) (xy 49.787556 -348.786958)
			(xy 49.786995 -348.831728) (xy 49.777984 -348.920813) (xy 49.760078 -349.008544) (xy 49.733459 -349.094035)
			(xy 49.716436 -349.135446) (xy 49.712897 -349.145044) (xy 49.712881 -349.16548) (xy 49.716436 -349.17507)
			(xy 49.733463 -349.21648) (xy 49.7601 -349.301967) (xy 49.778006 -349.3897) (xy 49.787003 -349.478787)
			(xy 49.787556 -349.523558) (xy 49.786995 -349.568328) (xy 49.777984 -349.657413) (xy 49.760078 -349.745144)
			(xy 49.733459 -349.830635) (xy 49.716436 -349.872046) (xy 49.712897 -349.881644) (xy 49.712881 -349.90208)
			(xy 49.716436 -349.91167) (xy 49.733463 -349.95308) (xy 49.7601 -350.038567) (xy 49.778006 -350.1263)
			(xy 49.787003 -350.215387) (xy 49.787556 -350.260158) (xy 49.787061 -350.301272) (xy 49.779478 -350.383151)
			(xy 49.764372 -350.46398) (xy 49.741872 -350.54307) (xy 49.71217 -350.619748) (xy 49.67552 -350.693357)
			(xy 49.632234 -350.76327) (xy 49.582682 -350.828891) (xy 49.527286 -350.88966) (xy 49.466519 -350.945059)
			(xy 49.4009 -350.994614) (xy 49.330988 -351.037902) (xy 49.25738 -351.074555) (xy 49.180705 -351.10426)
			(xy 49.101615 -351.126764) (xy 49.020786 -351.141873) (xy 48.938908 -351.14946) (xy 48.897794 -351.14992)
			(xy 48.856184 -351.149442) (xy 48.773327 -351.141665) (xy 48.691558 -351.12619) (xy 48.611591 -351.10315)
			(xy 48.534122 -351.072748) (xy 48.459829 -351.035248) (xy 48.424338 -351.013522) (xy 48.41523 -351.008297)
			(xy 48.394493 -351.005101) (xy 48.374208 -351.010462) (xy 48.365664 -351.01657) (xy 48.332031 -351.042555)
			(xy 48.260637 -351.08868) (xy 48.185167 -351.127782) (xy 48.10631 -351.159503) (xy 48.024785 -351.183553)
			(xy 47.941338 -351.199714) (xy 47.856729 -351.207838) (xy 47.81423 -351.20834) (xy 47.773115 -351.207873)
			(xy 47.691235 -351.200288) (xy 47.610405 -351.185181) (xy 47.531314 -351.162679) (xy 47.454636 -351.132976)
			(xy 47.381026 -351.096324) (xy 47.311112 -351.053036) (xy 47.24549 -351.003482) (xy 47.184721 -350.948084)
			(xy 47.129323 -350.887316) (xy 47.079768 -350.821695) (xy 47.03648 -350.751781) (xy 46.999828 -350.678172)
			(xy 46.970123 -350.601494) (xy 46.947621 -350.522403) (xy 46.932513 -350.441573) (xy 46.924927 -350.359693)
			(xy 46.924468 -350.318578) (xy 46.92504 -350.273809) (xy 46.934047 -350.184724) (xy 46.95195 -350.096993)
			(xy 46.978566 -350.011501) (xy 46.995588 -349.97009) (xy 46.999168 -349.960503) (xy 46.99916 -349.940056)
			(xy 46.995588 -349.930466) (xy 46.978563 -349.889123) (xy 46.951957 -349.803758) (xy 46.934056 -349.716153)
			(xy 46.925041 -349.627193) (xy 46.924468 -349.582486) (xy 46.924468 -349.58147) (xy 46.924722 -349.57004)
			(xy 46.898244 -349.564091) (xy 46.846009 -349.54935) (xy 46.820328 -349.540576) (xy 46.812131 -349.538062)
			(xy 46.794997 -349.538062) (xy 46.7868 -349.540576) (xy 46.75158 -349.552528) (xy 46.679579 -349.571185)
			(xy 46.606259 -349.583696) (xy 46.532144 -349.589972) (xy 46.494954 -349.59036) (xy 46.457765 -349.589952)
			(xy 46.383652 -349.583667) (xy 46.310333 -349.571163) (xy 46.238326 -349.552528) (xy 46.203108 -349.540576)
			(xy 46.194911 -349.538062) (xy 46.177777 -349.538062) (xy 46.16958 -349.540576) (xy 46.134362 -349.552533)
			(xy 46.06236 -349.571189) (xy 45.989039 -349.583699) (xy 45.914924 -349.589973) (xy 45.877734 -349.59036)
			(xy 45.835794 -349.589902) (xy 45.752294 -349.581932) (xy 45.66993 -349.566061) (xy 45.589448 -349.542432)
			(xy 45.511576 -349.511259) (xy 45.43702 -349.472825) (xy 45.366455 -349.427478) (xy 45.30052 -349.375629)
			(xy 45.239813 -349.317747) (xy 45.184883 -349.254356) (xy 45.136227 -349.186031) (xy 45.094286 -349.11339)
			(xy 45.05944 -349.037091) (xy 45.032006 -348.957825) (xy 45.01223 -348.87631) (xy 45.000292 -348.793284)
			(xy 44.996301 -348.7095) (xy 41.47791 -348.7095) (xy 41.481279 -348.745845) (xy 41.481756 -348.786958)
			(xy 41.481195 -348.831728) (xy 41.472184 -348.920813) (xy 41.454278 -349.008544) (xy 41.427659 -349.094035)
			(xy 41.410636 -349.135446) (xy 41.407097 -349.145044) (xy 41.407081 -349.16548) (xy 41.410636 -349.17507)
			(xy 41.427663 -349.21648) (xy 41.4543 -349.301967) (xy 41.472206 -349.3897) (xy 41.481203 -349.478787)
			(xy 41.481756 -349.523558) (xy 41.481195 -349.568328) (xy 41.472184 -349.657413) (xy 41.454278 -349.745144)
			(xy 41.427659 -349.830635) (xy 41.410636 -349.872046) (xy 41.407097 -349.881644) (xy 41.407081 -349.90208)
			(xy 41.410636 -349.91167) (xy 41.427663 -349.95308) (xy 41.4543 -350.038567) (xy 41.472206 -350.1263)
			(xy 41.481203 -350.215387) (xy 41.481756 -350.260158) (xy 41.481261 -350.301272) (xy 41.473678 -350.383151)
			(xy 41.458572 -350.46398) (xy 41.436072 -350.54307) (xy 41.40637 -350.619748) (xy 41.36972 -350.693357)
			(xy 41.326434 -350.76327) (xy 41.276882 -350.828891) (xy 41.221486 -350.88966) (xy 41.160719 -350.945059)
			(xy 41.0951 -350.994614) (xy 41.025188 -351.037902) (xy 40.95158 -351.074555) (xy 40.874905 -351.10426)
			(xy 40.795815 -351.126764) (xy 40.714986 -351.141873) (xy 40.633108 -351.14946) (xy 40.591994 -351.14992)
			(xy 40.550384 -351.149442) (xy 40.467527 -351.141665) (xy 40.385758 -351.12619) (xy 40.305791 -351.10315)
			(xy 40.228322 -351.072748) (xy 40.154029 -351.035248) (xy 40.118538 -351.013522) (xy 40.10943 -351.008297)
			(xy 40.088693 -351.005101) (xy 40.068408 -351.010462) (xy 40.059864 -351.01657) (xy 40.026231 -351.042555)
			(xy 39.954837 -351.08868) (xy 39.879367 -351.127782) (xy 39.80051 -351.159503) (xy 39.718985 -351.183553)
			(xy 39.635538 -351.199714) (xy 39.550929 -351.207838) (xy 39.50843 -351.20834) (xy 39.467315 -351.207873)
			(xy 39.385435 -351.200288) (xy 39.304605 -351.185181) (xy 39.225514 -351.162679) (xy 39.148836 -351.132976)
			(xy 39.075226 -351.096324) (xy 39.005312 -351.053036) (xy 38.93969 -351.003482) (xy 38.878921 -350.948084)
			(xy 38.823523 -350.887316) (xy 38.773968 -350.821695) (xy 38.73068 -350.751781) (xy 38.694028 -350.678172)
			(xy 38.664323 -350.601494) (xy 38.641821 -350.522403) (xy 38.626713 -350.441573) (xy 38.619127 -350.359693)
			(xy 38.618668 -350.318578) (xy 38.61924 -350.273809) (xy 38.628247 -350.184724) (xy 38.64615 -350.096993)
			(xy 38.672766 -350.011501) (xy 38.689788 -349.97009) (xy 38.693368 -349.960503) (xy 38.69336 -349.940056)
			(xy 38.689788 -349.930466) (xy 38.672763 -349.889123) (xy 38.646157 -349.803758) (xy 38.628256 -349.716153)
			(xy 38.619241 -349.627193) (xy 38.618668 -349.582486) (xy 38.618668 -349.58147) (xy 38.618922 -349.57004)
			(xy 38.592444 -349.564091) (xy 38.540209 -349.54935) (xy 38.514528 -349.540576) (xy 38.506331 -349.538062)
			(xy 38.489197 -349.538062) (xy 38.481 -349.540576) (xy 38.44578 -349.552528) (xy 38.373779 -349.571185)
			(xy 38.300459 -349.583696) (xy 38.226344 -349.589972) (xy 38.189154 -349.59036) (xy 38.151965 -349.589952)
			(xy 38.077852 -349.583667) (xy 38.004533 -349.571163) (xy 37.932526 -349.552528) (xy 37.897308 -349.540576)
			(xy 37.889111 -349.538062) (xy 37.871977 -349.538062) (xy 37.86378 -349.540576) (xy 37.828562 -349.552533)
			(xy 37.75656 -349.571189) (xy 37.683239 -349.583699) (xy 37.609124 -349.589973) (xy 37.571934 -349.59036)
			(xy 37.529996 -349.589881) (xy 37.446499 -349.581908) (xy 37.364138 -349.566035) (xy 37.283659 -349.542404)
			(xy 37.20579 -349.511231) (xy 37.131238 -349.472797) (xy 37.060676 -349.42745) (xy 36.994745 -349.375601)
			(xy 36.93404 -349.317719) (xy 36.879112 -349.25433) (xy 36.830459 -349.186006) (xy 36.788521 -349.113367)
			(xy 36.753677 -349.03707) (xy 36.726244 -348.957807) (xy 36.706469 -348.876294) (xy 36.694532 -348.793272)
			(xy 36.690541 -348.70949) (xy 33.197509 -348.70949) (xy 33.200879 -348.745845) (xy 33.201356 -348.786958)
			(xy 33.200795 -348.831728) (xy 33.191784 -348.920813) (xy 33.173878 -349.008544) (xy 33.147259 -349.094035)
			(xy 33.130236 -349.135446) (xy 33.126697 -349.145044) (xy 33.126681 -349.16548) (xy 33.130236 -349.17507)
			(xy 33.147263 -349.21648) (xy 33.1739 -349.301967) (xy 33.191806 -349.3897) (xy 33.200803 -349.478787)
			(xy 33.201356 -349.523558) (xy 33.200795 -349.568328) (xy 33.191784 -349.657413) (xy 33.173878 -349.745144)
			(xy 33.147259 -349.830635) (xy 33.130236 -349.872046) (xy 33.126697 -349.881644) (xy 33.126681 -349.90208)
			(xy 33.130236 -349.91167) (xy 33.147263 -349.95308) (xy 33.1739 -350.038567) (xy 33.191806 -350.1263)
			(xy 33.200803 -350.215387) (xy 33.201356 -350.260158) (xy 33.200861 -350.301272) (xy 33.193278 -350.383151)
			(xy 33.178172 -350.46398) (xy 33.155672 -350.54307) (xy 33.12597 -350.619748) (xy 33.08932 -350.693357)
			(xy 33.046034 -350.76327) (xy 32.996482 -350.828891) (xy 32.941086 -350.88966) (xy 32.880319 -350.945059)
			(xy 32.8147 -350.994614) (xy 32.744788 -351.037902) (xy 32.67118 -351.074555) (xy 32.594505 -351.10426)
			(xy 32.515415 -351.126764) (xy 32.434586 -351.141873) (xy 32.352708 -351.14946) (xy 32.311594 -351.14992)
			(xy 32.269984 -351.149442) (xy 32.187127 -351.141665) (xy 32.105358 -351.12619) (xy 32.025391 -351.10315)
			(xy 31.947922 -351.072748) (xy 31.873629 -351.035248) (xy 31.838138 -351.013522) (xy 31.82903 -351.008297)
			(xy 31.808293 -351.005101) (xy 31.788008 -351.010462) (xy 31.779464 -351.01657) (xy 31.745831 -351.042555)
			(xy 31.674437 -351.08868) (xy 31.598967 -351.127782) (xy 31.52011 -351.159503) (xy 31.438585 -351.183553)
			(xy 31.355138 -351.199714) (xy 31.270529 -351.207838) (xy 31.22803 -351.20834) (xy 31.186915 -351.207873)
			(xy 31.105035 -351.200288) (xy 31.024205 -351.185181) (xy 30.945114 -351.162679) (xy 30.868436 -351.132976)
			(xy 30.794826 -351.096324) (xy 30.724912 -351.053036) (xy 30.65929 -351.003482) (xy 30.598521 -350.948084)
			(xy 30.543123 -350.887316) (xy 30.493568 -350.821695) (xy 30.45028 -350.751781) (xy 30.413628 -350.678172)
			(xy 30.383923 -350.601494) (xy 30.361421 -350.522403) (xy 30.346313 -350.441573) (xy 30.338727 -350.359693)
			(xy 30.338268 -350.318578) (xy 30.33884 -350.273809) (xy 30.347847 -350.184724) (xy 30.36575 -350.096993)
			(xy 30.392366 -350.011501) (xy 30.409388 -349.97009) (xy 30.412968 -349.960503) (xy 30.41296 -349.940056)
			(xy 30.409388 -349.930466) (xy 30.392363 -349.889123) (xy 30.365757 -349.803758) (xy 30.347856 -349.716153)
			(xy 30.338841 -349.627193) (xy 30.338268 -349.582486) (xy 30.338268 -349.58147) (xy 30.338522 -349.57004)
			(xy 30.312044 -349.564091) (xy 30.259809 -349.54935) (xy 30.234128 -349.540576) (xy 30.225931 -349.538062)
			(xy 30.208797 -349.538062) (xy 30.2006 -349.540576) (xy 30.16538 -349.552528) (xy 30.093379 -349.571185)
			(xy 30.020059 -349.583696) (xy 29.945944 -349.589972) (xy 29.908754 -349.59036) (xy 29.871565 -349.589952)
			(xy 29.797452 -349.583667) (xy 29.724133 -349.571163) (xy 29.652126 -349.552528) (xy 29.616908 -349.540576)
			(xy 29.608711 -349.538062) (xy 29.591577 -349.538062) (xy 29.58338 -349.540576) (xy 29.548162 -349.552533)
			(xy 29.47616 -349.571189) (xy 29.402839 -349.583699) (xy 29.328724 -349.589973) (xy 29.291534 -349.59036)
			(xy 29.249596 -349.589881) (xy 29.166099 -349.581908) (xy 29.083738 -349.566035) (xy 29.003259 -349.542404)
			(xy 28.92539 -349.511231) (xy 28.850838 -349.472797) (xy 28.780276 -349.42745) (xy 28.714345 -349.375601)
			(xy 28.65364 -349.317719) (xy 28.598712 -349.25433) (xy 28.550059 -349.186006) (xy 28.508121 -349.113367)
			(xy 28.473277 -349.03707) (xy 28.445844 -348.957807) (xy 28.426069 -348.876294) (xy 28.414132 -348.793272)
			(xy 28.410141 -348.70949) (xy 2.509012 -348.70949) (xy 2.509012 -351.637854) (xy 73.92162 -351.637854)
			(xy 73.922073 -351.597287) (xy 73.929469 -351.516491) (xy 73.944194 -351.436705) (xy 73.966127 -351.358593)
			(xy 73.995085 -351.282803) (xy 74.012552 -351.246186) (xy 74.016468 -351.237096) (xy 74.017766 -351.217362)
			(xy 74.015092 -351.207832) (xy 74.000912 -351.162806) (xy 73.981012 -351.070523) (xy 73.971009 -350.97665)
			(xy 73.970388 -350.929448) (xy 73.970892 -350.887087) (xy 73.978945 -350.80275) (xy 73.994979 -350.71956)
			(xy 74.018847 -350.63827) (xy 74.050335 -350.559618) (xy 74.089157 -350.484315) (xy 74.13496 -350.413043)
			(xy 74.187331 -350.346447) (xy 74.245796 -350.285132) (xy 74.309824 -350.229651) (xy 74.378836 -350.180508)
			(xy 74.452206 -350.138148) (xy 74.529271 -350.102953) (xy 74.609333 -350.075244) (xy 74.691666 -350.05527)
			(xy 74.775525 -350.043213) (xy 74.86015 -350.039182) (xy 74.944775 -350.043213) (xy 75.028634 -350.05527)
			(xy 75.110967 -350.075244) (xy 75.191029 -350.102953) (xy 75.268094 -350.138148) (xy 75.341464 -350.180508)
			(xy 75.410476 -350.229651) (xy 75.474504 -350.285132) (xy 75.532969 -350.346447) (xy 75.58534 -350.413043)
			(xy 75.631143 -350.484315) (xy 75.669965 -350.559618) (xy 75.701453 -350.63827) (xy 75.725321 -350.71956)
			(xy 75.741355 -350.80275) (xy 75.749408 -350.887087) (xy 75.749912 -350.929448) (xy 75.749456 -350.970015)
			(xy 75.742061 -351.05081) (xy 75.727336 -351.130596) (xy 75.705403 -351.208709) (xy 75.676446 -351.284499)
			(xy 75.65898 -351.321116) (xy 75.655063 -351.330206) (xy 75.653765 -351.34994) (xy 75.65644 -351.35947)
			(xy 75.670621 -351.404496) (xy 75.69052 -351.496779) (xy 75.700524 -351.590652) (xy 75.70064 -351.5995)
			(xy 76.58354 -351.5995) (xy 76.583977 -351.558938) (xy 76.59131 -351.478148) (xy 76.605978 -351.398363)
			(xy 76.62786 -351.320247) (xy 76.656772 -351.244452) (xy 76.674218 -351.207832) (xy 76.67814 -351.198816)
			(xy 76.679575 -351.179224) (xy 76.677012 -351.169732) (xy 76.662856 -351.124831) (xy 76.642989 -351.0328)
			(xy 76.632962 -350.939185) (xy 76.632308 -350.89211) (xy 76.632308 -350.891094) (xy 76.632812 -350.848746)
			(xy 76.640863 -350.764432) (xy 76.656892 -350.681266) (xy 76.680753 -350.599999) (xy 76.712232 -350.521369)
			(xy 76.751043 -350.446088) (xy 76.796833 -350.374836) (xy 76.849189 -350.30826) (xy 76.907637 -350.246962)
			(xy 76.971647 -350.191497) (xy 77.040639 -350.142368) (xy 77.113989 -350.100019) (xy 77.191032 -350.064835)
			(xy 77.271071 -350.037133) (xy 77.35338 -350.017165) (xy 77.437215 -350.005112) (xy 77.521816 -350.001082)
			(xy 77.606417 -350.005112) (xy 77.690252 -350.017165) (xy 77.772561 -350.037133) (xy 77.8526 -350.064835)
			(xy 77.929643 -350.100019) (xy 78.002993 -350.142368) (xy 78.071985 -350.191497) (xy 78.135995 -350.246962)
			(xy 78.194443 -350.30826) (xy 78.246799 -350.374836) (xy 78.292589 -350.446088) (xy 78.3314 -350.521369)
			(xy 78.362879 -350.599999) (xy 78.38674 -350.681266) (xy 78.402769 -350.764432) (xy 78.41082 -350.848746)
			(xy 78.411324 -350.891094) (xy 78.411324 -350.891602) (xy 78.410897 -350.932113) (xy 78.403528 -351.0128)
			(xy 78.388844 -351.09248) (xy 78.366965 -351.170492) (xy 78.338074 -351.246189) (xy 78.320646 -351.282762)
			(xy 78.316728 -351.291779) (xy 78.315288 -351.31137) (xy 78.317852 -351.320862) (xy 78.33205 -351.365927)
			(xy 78.351954 -351.458296) (xy 78.361947 -351.552255) (xy 78.362556 -351.5995) (xy 78.362003 -351.645139)
			(xy 78.352699 -351.735943) (xy 78.334149 -351.825316) (xy 78.3209 -351.868994) (xy 78.318454 -351.878006)
			(xy 78.319496 -351.896634) (xy 78.322932 -351.905316) (xy 78.341634 -351.948394) (xy 78.370914 -352.03763)
			(xy 78.390624 -352.129456) (xy 78.400545 -352.222848) (xy 78.401164 -352.269806) (xy 78.400653 -352.312784)
			(xy 78.392364 -352.398339) (xy 78.375873 -352.482698) (xy 78.351334 -352.565076) (xy 78.335632 -352.605086)
			(xy 78.332346 -352.614331) (xy 78.332359 -352.633935) (xy 78.335632 -352.643186) (xy 78.351338 -352.683162)
			(xy 78.375884 -352.765474) (xy 78.392373 -352.84977) (xy 78.400651 -352.935265) (xy 78.401164 -352.978212)
			(xy 78.40066 -353.020573) (xy 78.392607 -353.10491) (xy 78.376573 -353.1881) (xy 78.352705 -353.26939)
			(xy 78.346936 -353.2838) (xy 182.729656 -353.2838) (xy 182.733646 -353.200045) (xy 182.745579 -353.117047)
			(xy 182.765347 -353.035561) (xy 182.792771 -352.956321) (xy 182.827603 -352.880048) (xy 182.869527 -352.807431)
			(xy 182.918163 -352.739127) (xy 182.973072 -352.675756) (xy 183.033756 -352.617891) (xy 183.099666 -352.566056)
			(xy 183.170204 -352.520721) (xy 183.244732 -352.482296) (xy 183.322575 -352.451129) (xy 183.403028 -352.427503)
			(xy 183.485362 -352.411631) (xy 183.568833 -352.403656) (xy 183.610758 -352.403156) (xy 183.611774 -352.403156)
			(xy 183.648831 -352.403571) (xy 183.72268 -352.409833) (xy 183.795742 -352.422272) (xy 183.867502 -352.440802)
			(xy 183.902604 -352.452686) (xy 183.910801 -352.4552) (xy 183.927935 -352.4552) (xy 183.936132 -352.452686)
			(xy 183.964337 -352.443048) (xy 184.021791 -352.42716) (xy 184.05094 -352.420936) (xy 184.060579 -352.41851)
			(xy 184.077071 -352.407448) (xy 184.088123 -352.390948) (xy 184.090564 -352.381312) (xy 184.100088 -352.337416)
			(xy 184.126813 -352.251655) (xy 184.143904 -352.210116) (xy 184.147468 -352.200525) (xy 184.147469 -352.180082)
			(xy 184.143904 -352.170492) (xy 184.126892 -352.12911) (xy 184.100271 -352.043685) (xy 184.082363 -351.956018)
			(xy 184.073351 -351.866996) (xy 184.072784 -351.822258) (xy 184.072784 -351.822004) (xy 184.073288 -351.779656)
			(xy 184.081339 -351.695342) (xy 184.097368 -351.612176) (xy 184.121229 -351.530909) (xy 184.152708 -351.452279)
			(xy 184.191519 -351.376998) (xy 184.237309 -351.305746) (xy 184.289665 -351.23917) (xy 184.348113 -351.177872)
			(xy 184.412123 -351.122407) (xy 184.481115 -351.073278) (xy 184.554465 -351.030929) (xy 184.631508 -350.995745)
			(xy 184.711547 -350.968043) (xy 184.793856 -350.948075) (xy 184.877691 -350.936022) (xy 184.962292 -350.931992)
			(xy 185.046893 -350.936022) (xy 185.130728 -350.948075) (xy 185.213037 -350.968043) (xy 185.293076 -350.995745)
			(xy 185.370119 -351.030929) (xy 185.443469 -351.073278) (xy 185.512461 -351.122407) (xy 185.576471 -351.177872)
			(xy 185.634919 -351.23917) (xy 185.687275 -351.305746) (xy 185.733065 -351.376998) (xy 185.771876 -351.452279)
			(xy 185.803355 -351.530909) (xy 185.827216 -351.612176) (xy 185.843245 -351.695342) (xy 185.851296 -351.779656)
			(xy 185.8518 -351.822004) (xy 185.8518 -351.822258) (xy 185.851234 -351.866996) (xy 185.842218 -351.956018)
			(xy 185.824312 -352.043685) (xy 185.797698 -352.129113) (xy 185.78068 -352.170492) (xy 185.777112 -352.180082)
			(xy 185.777113 -352.200525) (xy 185.78068 -352.210116) (xy 185.797704 -352.251527) (xy 185.824339 -352.337015)
			(xy 185.842246 -352.424746) (xy 185.851245 -352.513834) (xy 185.8518 -352.558604) (xy 185.85116 -352.609084)
			(xy 185.839825 -352.709404) (xy 185.829194 -352.758756) (xy 185.826997 -352.771225) (xy 185.833664 -352.795617)
			(xy 185.841894 -352.805238) (xy 185.882534 -352.847656) (xy 185.889646 -352.846132) (xy 185.898412 -352.843862)
			(xy 185.913646 -352.834103) (xy 185.919364 -352.827082) (xy 185.944527 -352.794419) (xy 185.999939 -352.733355)
			(xy 186.060764 -352.67768) (xy 186.126478 -352.627872) (xy 186.196519 -352.584357) (xy 186.270286 -352.547509)
			(xy 186.347146 -352.517645) (xy 186.426439 -352.49502) (xy 186.507485 -352.479828) (xy 186.589589 -352.472201)
			(xy 186.630818 -352.471736) (xy 186.671925 -352.472195) (xy 186.753788 -352.479781) (xy 186.834603 -352.494887)
			(xy 186.913679 -352.517383) (xy 186.990343 -352.547078) (xy 187.06394 -352.583719) (xy 187.133844 -352.626993)
			(xy 187.199457 -352.676531) (xy 187.260221 -352.73191) (xy 187.315617 -352.792659) (xy 187.365173 -352.85826)
			(xy 187.408465 -352.928152) (xy 187.445126 -353.001739) (xy 187.474841 -353.078395) (xy 187.497359 -353.157466)
			(xy 187.512486 -353.238276) (xy 187.519078 -353.3092) (xy 191.056256 -353.3092) (xy 191.060246 -353.225443)
			(xy 191.07218 -353.142444) (xy 191.091948 -353.060956) (xy 191.119373 -352.981715) (xy 191.154206 -352.90544)
			(xy 191.196132 -352.832822) (xy 191.244771 -352.764518) (xy 191.299682 -352.701146) (xy 191.360368 -352.643281)
			(xy 191.42628 -352.591447) (xy 191.49682 -352.546112) (xy 191.57135 -352.507688) (xy 191.649196 -352.476522)
			(xy 191.729651 -352.452897) (xy 191.811988 -352.437027) (xy 191.89546 -352.429055) (xy 191.937386 -352.428556)
			(xy 191.938402 -352.428556) (xy 191.975459 -352.428963) (xy 192.049308 -352.435227) (xy 192.12237 -352.447669)
			(xy 192.194131 -352.466201) (xy 192.229232 -352.478086) (xy 192.237429 -352.4806) (xy 192.254563 -352.4806)
			(xy 192.26276 -352.478086) (xy 192.290041 -352.468747) (xy 192.345585 -352.453243) (xy 192.373758 -352.447098)
			(xy 192.383527 -352.444576) (xy 192.400163 -352.433196) (xy 192.411142 -352.416293) (xy 192.413382 -352.406458)
			(xy 192.422838 -352.357349) (xy 192.451357 -352.261489) (xy 192.470278 -352.215196) (xy 192.473919 -352.205632)
			(xy 192.474045 -352.185185) (xy 192.470532 -352.175572) (xy 192.453515 -352.134192) (xy 192.426895 -352.048766)
			(xy 192.408989 -351.961099) (xy 192.399978 -351.872077) (xy 192.399412 -351.827338) (xy 192.399412 -351.827084)
			(xy 192.399916 -351.784736) (xy 192.407967 -351.700422) (xy 192.423996 -351.617256) (xy 192.447857 -351.535989)
			(xy 192.479336 -351.457359) (xy 192.518147 -351.382078) (xy 192.563937 -351.310826) (xy 192.616293 -351.24425)
			(xy 192.674741 -351.182952) (xy 192.738751 -351.127487) (xy 192.807743 -351.078358) (xy 192.881093 -351.036009)
			(xy 192.958136 -351.000825) (xy 193.038175 -350.973123) (xy 193.120484 -350.953155) (xy 193.204319 -350.941102)
			(xy 193.28892 -350.937072) (xy 193.373521 -350.941102) (xy 193.457356 -350.953155) (xy 193.539665 -350.973123)
			(xy 193.619704 -351.000825) (xy 193.696747 -351.036009) (xy 193.770097 -351.078358) (xy 193.839089 -351.127487)
			(xy 193.903099 -351.182952) (xy 193.961547 -351.24425) (xy 194.013903 -351.310826) (xy 194.059693 -351.382078)
			(xy 194.098504 -351.457359) (xy 194.129983 -351.535989) (xy 194.153844 -351.617256) (xy 194.169873 -351.700422)
			(xy 194.177924 -351.784736) (xy 194.178428 -351.827084) (xy 194.178428 -351.827338) (xy 194.177853 -351.872076)
			(xy 194.168839 -351.961098) (xy 194.150936 -352.048765) (xy 194.124325 -352.134193) (xy 194.107308 -352.175572)
			(xy 194.10375 -352.185165) (xy 194.103744 -352.205606) (xy 194.107308 -352.215196) (xy 194.12436 -352.256596)
			(xy 194.150986 -352.342088) (xy 194.165052 -352.41103) (xy 206.449676 -352.41103) (xy 206.449676 -351.54743)
			(xy 206.450162 -351.520179) (xy 206.457918 -351.466231) (xy 206.473273 -351.413936) (xy 206.495915 -351.364359)
			(xy 206.525381 -351.318509) (xy 206.561072 -351.277318) (xy 206.602263 -351.241627) (xy 206.648113 -351.212161)
			(xy 206.69769 -351.189519) (xy 206.749985 -351.174164) (xy 206.803933 -351.166408) (xy 206.858435 -351.166408)
			(xy 206.912383 -351.174164) (xy 206.964678 -351.189519) (xy 207.014255 -351.212161) (xy 207.060105 -351.241627)
			(xy 207.101296 -351.277318) (xy 207.136987 -351.318509) (xy 207.166453 -351.364359) (xy 207.189095 -351.413936)
			(xy 207.20445 -351.466231) (xy 207.212206 -351.520179) (xy 207.212692 -351.54743) (xy 207.212692 -352.41103)
			(xy 207.212206 -352.438281) (xy 207.20445 -352.492229) (xy 207.189095 -352.544524) (xy 207.166453 -352.594101)
			(xy 207.136987 -352.639951) (xy 207.101296 -352.681142) (xy 207.060105 -352.716833) (xy 207.014255 -352.746299)
			(xy 206.964678 -352.768941) (xy 206.912383 -352.784296) (xy 206.858435 -352.792052) (xy 206.803933 -352.792052)
			(xy 206.749985 -352.784296) (xy 206.69769 -352.768941) (xy 206.648113 -352.746299) (xy 206.602263 -352.716833)
			(xy 206.561072 -352.681142) (xy 206.525381 -352.639951) (xy 206.495915 -352.594101) (xy 206.473273 -352.544524)
			(xy 206.457918 -352.492229) (xy 206.450162 -352.438281) (xy 206.449676 -352.41103) (xy 194.165052 -352.41103)
			(xy 194.168886 -352.429823) (xy 194.177877 -352.518913) (xy 194.178428 -352.563684) (xy 194.178055 -352.600778)
			(xy 194.171875 -352.674709) (xy 194.159556 -352.747868) (xy 194.150742 -352.783902) (xy 194.149 -352.792252)
			(xy 194.15051 -352.809229) (xy 194.157543 -352.824754) (xy 194.163188 -352.831146) (xy 194.203574 -352.874326)
			(xy 194.216274 -352.871532) (xy 194.225043 -352.869274) (xy 194.240276 -352.859506) (xy 194.245992 -352.852482)
			(xy 194.271138 -352.819805) (xy 194.326552 -352.758742) (xy 194.387379 -352.703068) (xy 194.453095 -352.65326)
			(xy 194.523138 -352.609746) (xy 194.596907 -352.5729) (xy 194.673768 -352.543037) (xy 194.753063 -352.520414)
			(xy 194.834111 -352.505225) (xy 194.916217 -352.4976) (xy 194.957446 -352.497136) (xy 194.998553 -352.497569)
			(xy 195.080417 -352.505157) (xy 195.161232 -352.520265) (xy 195.240309 -352.542764) (xy 195.316973 -352.572461)
			(xy 195.390571 -352.609104) (xy 195.460474 -352.652379) (xy 195.526087 -352.701919) (xy 195.586851 -352.757301)
			(xy 195.642247 -352.818051) (xy 195.691802 -352.883653) (xy 195.735094 -352.953546) (xy 195.744851 -352.973132)
			(xy 338.849208 -352.973132) (xy 338.849825 -352.926972) (xy 338.859426 -352.835153) (xy 338.878488 -352.744823)
			(xy 338.906804 -352.656953) (xy 338.9249 -352.614484) (xy 338.928699 -352.60454) (xy 338.928703 -352.583278)
			(xy 338.9249 -352.573336) (xy 338.90688 -352.530918) (xy 338.878719 -352.443158) (xy 338.859786 -352.352956)
			(xy 338.850284 -352.26128) (xy 338.849716 -352.215196) (xy 338.850295 -352.1688) (xy 338.859941 -352.076512)
			(xy 338.879138 -351.985728) (xy 338.907678 -351.897435) (xy 338.925916 -351.85477) (xy 338.929722 -351.844828)
			(xy 338.929721 -351.823565) (xy 338.925916 -351.813622) (xy 338.907694 -351.771019) (xy 338.879176 -351.682852)
			(xy 338.859983 -351.592196) (xy 338.850324 -351.500036) (xy 338.849716 -351.453704) (xy 338.849716 -351.453196)
			(xy 338.850148 -351.412092) (xy 338.857734 -351.330235) (xy 338.87284 -351.249427) (xy 338.895338 -351.170357)
			(xy 338.925036 -351.093701) (xy 338.96168 -351.020112) (xy 339.004958 -350.950218) (xy 339.0545 -350.884616)
			(xy 339.109884 -350.823864) (xy 339.170637 -350.768482) (xy 339.236241 -350.718942) (xy 339.306137 -350.675666)
			(xy 339.379727 -350.639025) (xy 339.456384 -350.609329) (xy 339.535454 -350.586834) (xy 339.616263 -350.57173)
			(xy 339.69812 -350.564147) (xy 339.739224 -350.563688) (xy 339.739732 -350.563688) (xy 339.786063 -350.564321)
			(xy 339.87822 -350.573985) (xy 339.968874 -350.593172) (xy 340.057044 -350.621677) (xy 340.09965 -350.639888)
			(xy 340.109592 -350.643694) (xy 340.130856 -350.643694) (xy 340.140798 -350.639888) (xy 340.183457 -350.621635)
			(xy 340.27175 -350.593093) (xy 340.362537 -350.573902) (xy 340.454828 -350.564272) (xy 340.501224 -350.563688)
			(xy 340.547619 -350.564298) (xy 340.639906 -350.573935) (xy 340.73069 -350.593123) (xy 340.818984 -350.621654)
			(xy 340.86165 -350.639888) (xy 340.871592 -350.643694) (xy 340.892856 -350.643694) (xy 340.902798 -350.639888)
			(xy 340.945457 -350.621635) (xy 341.03375 -350.593093) (xy 341.124537 -350.573902) (xy 341.216828 -350.564272)
			(xy 341.263224 -350.563688) (xy 341.309619 -350.564298) (xy 341.401906 -350.573935) (xy 341.49269 -350.593123)
			(xy 341.580984 -350.621654) (xy 341.62365 -350.639888) (xy 341.633592 -350.643694) (xy 341.654856 -350.643694)
			(xy 341.664798 -350.639888) (xy 341.707457 -350.621635) (xy 341.79575 -350.593093) (xy 341.886537 -350.573902)
			(xy 341.978828 -350.564272) (xy 342.025224 -350.563688) (xy 342.071619 -350.564298) (xy 342.163906 -350.573935)
			(xy 342.25469 -350.593123) (xy 342.342984 -350.621654) (xy 342.38565 -350.639888) (xy 342.395592 -350.643694)
			(xy 342.416856 -350.643694) (xy 342.426798 -350.639888) (xy 342.469457 -350.621635) (xy 342.55775 -350.593093)
			(xy 342.648537 -350.573902) (xy 342.740828 -350.564272) (xy 342.787224 -350.563688) (xy 342.833689 -350.564308)
			(xy 342.926112 -350.573988) (xy 343.017025 -350.593241) (xy 343.105438 -350.621857) (xy 343.148158 -350.640142)
			(xy 343.156911 -350.643584) (xy 343.175683 -350.644482) (xy 343.184734 -350.64192) (xy 343.230109 -350.62753)
			(xy 343.323147 -350.607378) (xy 343.417806 -350.597287) (xy 343.465404 -350.596708) (xy 343.506508 -350.597148)
			(xy 343.588364 -350.604734) (xy 343.669172 -350.61984) (xy 343.748241 -350.642338) (xy 343.824897 -350.672035)
			(xy 343.898486 -350.708679) (xy 343.968379 -350.751956) (xy 344.033982 -350.801498) (xy 344.094733 -350.856881)
			(xy 344.150115 -350.917634) (xy 344.199655 -350.983237) (xy 344.242931 -351.053132) (xy 344.279573 -351.126721)
			(xy 344.309269 -351.203378) (xy 344.331765 -351.282448) (xy 344.346869 -351.363255) (xy 344.354453 -351.445112)
			(xy 344.354912 -351.486216) (xy 344.354912 -351.486724) (xy 344.354311 -351.533056) (xy 344.344638 -351.625214)
			(xy 344.325441 -351.715868) (xy 344.296928 -351.804037) (xy 344.278712 -351.846642) (xy 344.274897 -351.856581)
			(xy 344.274903 -351.877848) (xy 344.278712 -351.88779) (xy 344.296962 -351.93045) (xy 344.325505 -352.018743)
			(xy 344.344696 -352.109529) (xy 344.354328 -352.20182) (xy 344.354912 -352.248216) (xy 344.354328 -352.294369)
			(xy 344.344776 -352.386179) (xy 344.325776 -352.476508) (xy 344.297531 -352.564386) (xy 344.279474 -352.606864)
			(xy 344.275648 -352.6168) (xy 344.275662 -352.638069) (xy 344.279474 -352.648012) (xy 344.29749 -352.690438)
			(xy 344.325707 -352.77819) (xy 344.344711 -352.868387) (xy 344.354297 -352.960064) (xy 344.354912 -353.006152)
			(xy 344.354402 -353.047262) (xy 344.34922 -353.1032) (xy 423.453493 -353.1032) (xy 423.457484 -353.019415)
			(xy 423.469422 -352.936388) (xy 423.489198 -352.854872) (xy 423.516634 -352.775605) (xy 423.55148 -352.699305)
			(xy 423.593421 -352.626663) (xy 423.642078 -352.558337) (xy 423.697009 -352.494945) (xy 423.757718 -352.437063)
			(xy 423.823654 -352.385213) (xy 423.89422 -352.339866) (xy 423.968777 -352.301432) (xy 424.04665 -352.270259)
			(xy 424.127133 -352.24663) (xy 424.209499 -352.230759) (xy 424.293 -352.222789) (xy 424.33494 -352.222308)
			(xy 424.372129 -352.222714) (xy 424.446242 -352.228999) (xy 424.519562 -352.241503) (xy 424.591568 -352.260139)
			(xy 424.626786 -352.272092) (xy 424.634983 -352.274606) (xy 424.652117 -352.274606) (xy 424.660314 -352.272092)
			(xy 424.687596 -352.262757) (xy 424.74314 -352.24725) (xy 424.771312 -352.241104) (xy 424.781089 -352.238609)
			(xy 424.797722 -352.227214) (xy 424.808697 -352.210302) (xy 424.810936 -352.200464) (xy 424.820391 -352.151355)
			(xy 424.84891 -352.055495) (xy 424.867832 -352.009202) (xy 424.871403 -351.999613) (xy 424.871399 -351.979169)
			(xy 424.867832 -351.969578) (xy 424.850786 -351.928175) (xy 424.824155 -351.842685) (xy 424.806254 -351.754951)
			(xy 424.797263 -351.665861) (xy 424.796712 -351.62109) (xy 424.797216 -351.578729) (xy 424.805269 -351.494392)
			(xy 424.821303 -351.411202) (xy 424.845171 -351.329912) (xy 424.876659 -351.25126) (xy 424.915481 -351.175957)
			(xy 424.961284 -351.104685) (xy 425.013655 -351.038089) (xy 425.07212 -350.976774) (xy 425.136148 -350.921293)
			(xy 425.20516 -350.87215) (xy 425.27853 -350.82979) (xy 425.355595 -350.794595) (xy 425.435657 -350.766886)
			(xy 425.51799 -350.746912) (xy 425.601849 -350.734855) (xy 425.686474 -350.730824) (xy 425.771099 -350.734855)
			(xy 425.854958 -350.746912) (xy 425.937291 -350.766886) (xy 426.017353 -350.794595) (xy 426.094418 -350.82979)
			(xy 426.167788 -350.87215) (xy 426.2368 -350.921293) (xy 426.300828 -350.976774) (xy 426.359293 -351.038089)
			(xy 426.411664 -351.104685) (xy 426.457467 -351.175957) (xy 426.496289 -351.25126) (xy 426.527777 -351.329912)
			(xy 426.551645 -351.411202) (xy 426.567679 -351.494392) (xy 426.575732 -351.578729) (xy 426.576236 -351.62109)
			(xy 426.575653 -351.665859) (xy 426.566649 -351.754944) (xy 426.548749 -351.842675) (xy 426.522136 -351.928167)
			(xy 426.505116 -351.969578) (xy 426.501559 -351.979171) (xy 426.501555 -351.999611) (xy 426.505116 -352.009202)
			(xy 426.522153 -352.050608) (xy 426.548787 -352.136097) (xy 426.566691 -352.22383) (xy 426.575684 -352.312919)
			(xy 426.576236 -352.35769) (xy 426.575843 -352.394784) (xy 426.569667 -352.468714) (xy 426.557358 -352.541873)
			(xy 426.54855 -352.577908) (xy 426.5467 -352.586267) (xy 426.54815 -352.603318) (xy 426.55512 -352.618947)
			(xy 426.560742 -352.625406) (xy 426.601128 -352.668332) (xy 426.613574 -352.665538) (xy 426.622391 -352.663274)
			(xy 426.637739 -352.653501) (xy 426.643546 -352.646488) (xy 426.66867 -352.613784) (xy 426.724067 -352.552685)
			(xy 426.784882 -352.496976) (xy 426.850593 -352.447136) (xy 426.920635 -352.403592) (xy 426.994408 -352.366719)
			(xy 427.071277 -352.336834) (xy 427.150582 -352.314192) (xy 427.231643 -352.298989) (xy 427.313763 -352.291354)
			(xy 427.355 -352.290888) (xy 427.396111 -352.291352) (xy 427.477981 -352.29894) (xy 427.558801 -352.314051)
			(xy 427.637882 -352.336556) (xy 427.714549 -352.366262) (xy 427.788147 -352.402918) (xy 427.858049 -352.446208)
			(xy 427.923657 -352.495765) (xy 427.984412 -352.551165) (xy 428.039795 -352.611935) (xy 428.089333 -352.677557)
			(xy 428.132604 -352.747471) (xy 428.169239 -352.82108) (xy 428.198924 -352.897755) (xy 428.221406 -352.976842)
			(xy 428.236494 -353.057667) (xy 428.243048 -353.1286) (xy 431.780208 -353.1286) (xy 431.784199 -353.04482)
			(xy 431.796136 -352.961799) (xy 431.815909 -352.880289) (xy 431.843342 -352.801027) (xy 431.878184 -352.724732)
			(xy 431.92012 -352.652094) (xy 431.968771 -352.583771) (xy 432.023696 -352.520381) (xy 432.084398 -352.4625)
			(xy 432.150327 -352.410651) (xy 432.220886 -352.365303) (xy 432.295436 -352.326868) (xy 432.373301 -352.295693)
			(xy 432.453778 -352.27206) (xy 432.536136 -352.256184) (xy 432.619631 -352.248208) (xy 432.661568 -352.247708)
			(xy 432.698757 -352.248106) (xy 432.77287 -352.254393) (xy 432.84619 -352.2669) (xy 432.918196 -352.285538)
			(xy 432.953414 -352.297492) (xy 432.961611 -352.300006) (xy 432.978745 -352.300006) (xy 432.986942 -352.297492)
			(xy 433.014223 -352.288155) (xy 433.069768 -352.27265) (xy 433.09794 -352.266504) (xy 433.107722 -352.264025)
			(xy 433.124353 -352.252622) (xy 433.135327 -352.235704) (xy 433.137564 -352.225864) (xy 433.147017 -352.176755)
			(xy 433.175537 -352.080895) (xy 433.19446 -352.034602) (xy 433.19803 -352.025013) (xy 433.198026 -352.004569)
			(xy 433.19446 -351.994978) (xy 433.177416 -351.953575) (xy 433.150784 -351.868085) (xy 433.132882 -351.780351)
			(xy 433.123891 -351.691261) (xy 433.12334 -351.64649) (xy 433.123844 -351.604129) (xy 433.131897 -351.519792)
			(xy 433.147931 -351.436602) (xy 433.171799 -351.355312) (xy 433.203287 -351.27666) (xy 433.242109 -351.201357)
			(xy 433.287912 -351.130085) (xy 433.340283 -351.063489) (xy 433.398748 -351.002174) (xy 433.462776 -350.946693)
			(xy 433.531788 -350.89755) (xy 433.605158 -350.85519) (xy 433.682223 -350.819995) (xy 433.762285 -350.792286)
			(xy 433.844618 -350.772312) (xy 433.928477 -350.760255) (xy 434.013102 -350.756224) (xy 434.097727 -350.760255)
			(xy 434.181586 -350.772312) (xy 434.263919 -350.792286) (xy 434.343981 -350.819995) (xy 434.421046 -350.85519)
			(xy 434.494416 -350.89755) (xy 434.563428 -350.946693) (xy 434.627456 -351.002174) (xy 434.685921 -351.063489)
			(xy 434.738292 -351.130085) (xy 434.784095 -351.201357) (xy 434.822917 -351.27666) (xy 434.854405 -351.355312)
			(xy 434.878273 -351.436602) (xy 434.894307 -351.519792) (xy 434.90236 -351.604129) (xy 434.902864 -351.64649)
			(xy 434.902279 -351.691259) (xy 434.893275 -351.780343) (xy 434.875376 -351.868074) (xy 434.848764 -351.953566)
			(xy 434.831744 -351.994978) (xy 434.828186 -352.00457) (xy 434.828182 -352.025011) (xy 434.831744 -352.034602)
			(xy 434.848782 -352.076008) (xy 434.875415 -352.161497) (xy 434.893319 -352.24923) (xy 434.902312 -352.338319)
			(xy 434.902864 -352.38309) (xy 434.90247 -352.420184) (xy 434.896295 -352.494114) (xy 434.883986 -352.567273)
			(xy 434.875178 -352.603308) (xy 434.873347 -352.611669) (xy 434.874795 -352.628716) (xy 434.881755 -352.644345)
			(xy 434.88737 -352.650806) (xy 434.927756 -352.693732) (xy 434.940202 -352.690938) (xy 434.94901 -352.688645)
			(xy 434.964363 -352.678893) (xy 434.970174 -352.671888) (xy 434.995281 -352.639171) (xy 435.05068 -352.578072)
			(xy 435.111497 -352.522364) (xy 435.17721 -352.472524) (xy 435.247255 -352.428982) (xy 435.321029 -352.39211)
			(xy 435.3979 -352.362226) (xy 435.477207 -352.339586) (xy 435.558269 -352.324385) (xy 435.64039 -352.316753)
			(xy 435.681628 -352.316288) (xy 435.722739 -352.316726) (xy 435.80461 -352.324316) (xy 435.885431 -352.339429)
			(xy 435.964512 -352.361936) (xy 436.041179 -352.391645) (xy 436.114778 -352.428302) (xy 436.184679 -352.471595)
			(xy 436.250287 -352.521154) (xy 436.311041 -352.576555) (xy 436.366424 -352.637327) (xy 436.415962 -352.70295)
			(xy 436.459233 -352.772865) (xy 436.495867 -352.846475) (xy 436.525552 -352.923151) (xy 436.548034 -353.00224)
			(xy 436.563122 -353.083066) (xy 436.570687 -353.164939) (xy 436.571136 -353.20605) (xy 436.570568 -353.25082)
			(xy 436.561569 -353.339906) (xy 436.543667 -353.427639) (xy 436.517044 -353.513129) (xy 436.500016 -353.554538)
			(xy 436.496425 -353.564121) (xy 436.496444 -353.58457) (xy 436.500016 -353.594162) (xy 436.517052 -353.635569)
			(xy 436.543684 -353.721058) (xy 436.561588 -353.808791) (xy 436.570583 -353.897879) (xy 436.571136 -353.94265)
			(xy 436.570568 -353.98742) (xy 436.561569 -354.076506) (xy 436.543667 -354.164239) (xy 436.517044 -354.249729)
			(xy 436.500016 -354.291138) (xy 436.496425 -354.300721) (xy 436.496444 -354.32117) (xy 436.500016 -354.330762)
			(xy 436.517046 -354.372136) (xy 436.543663 -354.457564) (xy 436.561565 -354.545233) (xy 436.570572 -354.634257)
			(xy 436.571136 -354.678996) (xy 436.571136 -354.67925) (xy 436.57064 -354.720357) (xy 436.56306 -354.80222)
			(xy 436.547959 -354.883035) (xy 436.525468 -354.962112) (xy 436.495777 -355.038776) (xy 436.45914 -355.112375)
			(xy 436.415869 -355.18228) (xy 436.366333 -355.247894) (xy 436.310956 -355.308659) (xy 436.250208 -355.364056)
			(xy 436.184609 -355.413612) (xy 436.114718 -355.456904) (xy 436.041131 -355.493565) (xy 435.964475 -355.523279)
			(xy 435.885405 -355.545796) (xy 435.804595 -355.560921) (xy 435.722735 -355.568527) (xy 435.681628 -355.569012)
			(xy 435.640018 -355.568519) (xy 435.557162 -355.560745) (xy 435.475393 -355.545272) (xy 435.395426 -355.522236)
			(xy 435.317957 -355.491836) (xy 435.243663 -355.454339) (xy 435.208172 -355.432614) (xy 435.199049 -355.42742)
			(xy 435.178322 -355.424214) (xy 435.158043 -355.429561) (xy 435.149498 -355.435662) (xy 435.115852 -355.46163)
			(xy 435.044461 -355.507757) (xy 434.968993 -355.546861) (xy 434.890138 -355.578584) (xy 434.808616 -355.602638)
			(xy 434.72517 -355.618802) (xy 434.640562 -355.626929) (xy 434.598064 -355.627432) (xy 434.556953 -355.626982)
			(xy 434.475084 -355.619391) (xy 434.394263 -355.604278) (xy 434.315183 -355.581771) (xy 434.238517 -355.552062)
			(xy 434.164919 -355.515405) (xy 434.095019 -355.472113) (xy 434.029411 -355.422555) (xy 433.968657 -355.367155)
			(xy 433.913275 -355.306384) (xy 433.863736 -355.240762) (xy 433.820465 -355.170848) (xy 433.783831 -355.09724)
			(xy 433.754145 -355.020565) (xy 433.731661 -354.941477) (xy 433.716572 -354.860653) (xy 433.709006 -354.778781)
			(xy 433.708556 -354.73767) (xy 433.709098 -354.692899) (xy 433.718104 -354.603812) (xy 433.736014 -354.51608)
			(xy 433.762645 -354.430591) (xy 433.779676 -354.389182) (xy 433.783256 -354.379596) (xy 433.783245 -354.359149)
			(xy 433.779676 -354.349558) (xy 433.762646 -354.308149) (xy 433.736013 -354.222661) (xy 433.718107 -354.134928)
			(xy 433.70911 -354.045841) (xy 433.708556 -354.00107) (xy 433.708556 -353.989132) (xy 433.682076 -353.983189)
			(xy 433.629842 -353.968444) (xy 433.604162 -353.959668) (xy 433.595965 -353.957154) (xy 433.578831 -353.957154)
			(xy 433.570634 -353.959668) (xy 433.535422 -353.971642) (xy 433.463417 -353.990292) (xy 433.390095 -354.002797)
			(xy 433.315979 -354.009067) (xy 433.278788 -354.009452) (xy 433.241598 -354.009064) (xy 433.167486 -354.002773)
			(xy 433.094166 -353.990263) (xy 433.02216 -353.971623) (xy 432.986942 -353.959668) (xy 432.978745 -353.957154)
			(xy 432.961611 -353.957154) (xy 432.953414 -353.959668) (xy 432.918203 -353.971647) (xy 432.846198 -353.990296)
			(xy 432.772875 -354.0028) (xy 432.698759 -354.009068) (xy 432.661568 -354.009452) (xy 432.619631 -354.008992)
			(xy 432.536136 -354.001016) (xy 432.453778 -353.98514) (xy 432.373301 -353.961507) (xy 432.295436 -353.930332)
			(xy 432.220886 -353.891897) (xy 432.150327 -353.846549) (xy 432.084398 -353.7947) (xy 432.023696 -353.736819)
			(xy 431.968771 -353.673429) (xy 431.92012 -353.605106) (xy 431.878184 -353.532468) (xy 431.843342 -353.456173)
			(xy 431.815909 -353.376911) (xy 431.796136 -353.295401) (xy 431.784199 -353.21238) (xy 431.780208 -353.1286)
			(xy 428.243048 -353.1286) (xy 428.244059 -353.139539) (xy 428.244508 -353.18065) (xy 428.243935 -353.22542)
			(xy 428.234936 -353.314506) (xy 428.217036 -353.402238) (xy 428.190415 -353.487729) (xy 428.173388 -353.529138)
			(xy 428.169793 -353.53872) (xy 428.169812 -353.559171) (xy 428.173388 -353.568762) (xy 428.190428 -353.610167)
			(xy 428.217058 -353.695657) (xy 428.23496 -353.783391) (xy 428.243955 -353.872479) (xy 428.244508 -353.91725)
			(xy 428.243935 -353.96202) (xy 428.234936 -354.051106) (xy 428.217036 -354.138838) (xy 428.190415 -354.224329)
			(xy 428.173388 -354.265738) (xy 428.169793 -354.27532) (xy 428.169812 -354.295771) (xy 428.173388 -354.305362)
			(xy 428.190417 -354.346737) (xy 428.217034 -354.432165) (xy 428.234937 -354.519833) (xy 428.243944 -354.608857)
			(xy 428.244508 -354.653596) (xy 428.244508 -354.65385) (xy 428.24394 -354.694955) (xy 428.23636 -354.776814)
			(xy 428.221262 -354.857624) (xy 428.198773 -354.936698) (xy 428.169085 -355.013359) (xy 428.132451 -355.086955)
			(xy 428.089184 -355.156857) (xy 428.039654 -355.22247) (xy 427.984281 -355.283233) (xy 427.923539 -355.33863)
			(xy 427.857946 -355.388186) (xy 427.788061 -355.431481) (xy 427.714479 -355.468143) (xy 427.63783 -355.497861)
			(xy 427.558765 -355.520382) (xy 427.47796 -355.535512) (xy 427.396104 -355.543124) (xy 427.355 -355.543612)
			(xy 427.31339 -355.543132) (xy 427.230533 -355.535356) (xy 427.148764 -355.519881) (xy 427.068797 -355.496842)
			(xy 426.991328 -355.46644) (xy 426.917035 -355.42894) (xy 426.881544 -355.407214) (xy 426.872433 -355.401996)
			(xy 426.851698 -355.398798) (xy 426.831415 -355.404156) (xy 426.82287 -355.410262) (xy 426.789234 -355.436243)
			(xy 426.717841 -355.482369) (xy 426.642371 -355.521471) (xy 426.563514 -355.553192) (xy 426.481991 -355.577244)
			(xy 426.398543 -355.593405) (xy 426.313935 -355.60153) (xy 426.271436 -355.602032) (xy 426.230327 -355.601513)
			(xy 426.148459 -355.593929) (xy 426.06764 -355.578822) (xy 425.98856 -355.556321) (xy 425.911894 -355.526617)
			(xy 425.838297 -355.489966) (xy 425.768396 -355.446679) (xy 425.702788 -355.397126) (xy 425.642034 -355.341729)
			(xy 425.58665 -355.280962) (xy 425.537111 -355.215344) (xy 425.49384 -355.145433) (xy 425.457204 -355.071828)
			(xy 425.427518 -354.995156) (xy 425.405034 -354.916071) (xy 425.389944 -354.835249) (xy 425.382378 -354.753379)
			(xy 425.381928 -354.71227) (xy 425.382471 -354.667499) (xy 425.391478 -354.578412) (xy 425.409387 -354.49068)
			(xy 425.436017 -354.40519) (xy 425.453048 -354.363782) (xy 425.45663 -354.354196) (xy 425.456619 -354.333749)
			(xy 425.453048 -354.324158) (xy 425.436017 -354.28275) (xy 425.409384 -354.197261) (xy 425.391479 -354.109528)
			(xy 425.382482 -354.020441) (xy 425.381928 -353.97567) (xy 425.381928 -353.963732) (xy 425.35545 -353.957782)
			(xy 425.303215 -353.943042) (xy 425.277534 -353.934268) (xy 425.269337 -353.931754) (xy 425.252203 -353.931754)
			(xy 425.244006 -353.934268) (xy 425.208787 -353.946222) (xy 425.136785 -353.964878) (xy 425.063465 -353.977388)
			(xy 424.98935 -353.983664) (xy 424.95216 -353.984052) (xy 424.914971 -353.983643) (xy 424.840858 -353.977359)
			(xy 424.767539 -353.964855) (xy 424.695532 -353.94622) (xy 424.660314 -353.934268) (xy 424.652117 -353.931754)
			(xy 424.634983 -353.931754) (xy 424.626786 -353.934268) (xy 424.591569 -353.946227) (xy 424.519566 -353.964882)
			(xy 424.446245 -353.977391) (xy 424.37213 -353.983665) (xy 424.33494 -353.984052) (xy 424.293 -353.983611)
			(xy 424.209499 -353.975641) (xy 424.127133 -353.95977) (xy 424.04665 -353.936141) (xy 423.968777 -353.904968)
			(xy 423.89422 -353.866534) (xy 423.823654 -353.821187) (xy 423.757718 -353.769337) (xy 423.697009 -353.711455)
			(xy 423.642078 -353.648063) (xy 423.593421 -353.579737) (xy 423.55148 -353.507095) (xy 423.516634 -353.430795)
			(xy 423.489198 -353.351528) (xy 423.469422 -353.270012) (xy 423.457484 -353.186985) (xy 423.453493 -353.1032)
			(xy 344.34922 -353.1032) (xy 344.346818 -353.129131) (xy 344.331712 -353.20995) (xy 344.309211 -353.289031)
			(xy 344.279508 -353.365698) (xy 344.242856 -353.439296) (xy 344.199569 -353.509197) (xy 344.150015 -353.574806)
			(xy 344.094618 -353.635561) (xy 344.03385 -353.690944) (xy 343.968231 -353.740483) (xy 343.898319 -353.783755)
			(xy 343.824713 -353.82039) (xy 343.748039 -353.850075) (xy 343.668954 -353.872558) (xy 343.58813 -353.887646)
			(xy 343.50626 -353.895211) (xy 343.46515 -353.89566) (xy 343.421566 -353.895134) (xy 343.334811 -353.886653)
			(xy 343.249302 -353.869729) (xy 343.165858 -353.844524) (xy 343.085279 -353.81128) (xy 343.046558 -353.791266)
			(xy 343.035092 -353.785848) (xy 343.009764 -353.785848) (xy 342.998298 -353.791266) (xy 342.959077 -353.812027)
			(xy 342.877306 -353.846516) (xy 342.792508 -353.872694) (xy 342.705525 -353.890299) (xy 342.617221 -353.899159)
			(xy 342.572848 -353.899724) (xy 342.534532 -353.899341) (xy 342.458179 -353.892813) (xy 342.382672 -353.879733)
			(xy 342.308573 -353.860197) (xy 342.272366 -353.847654) (xy 342.26405 -353.845068) (xy 342.246646 -353.845068)
			(xy 342.23833 -353.847654) (xy 342.202121 -353.860189) (xy 342.128019 -353.879707) (xy 342.052513 -353.892787)
			(xy 341.976163 -353.899332) (xy 341.937848 -353.899724) (xy 341.899532 -353.899341) (xy 341.823179 -353.892813)
			(xy 341.747672 -353.879733) (xy 341.673573 -353.860197) (xy 341.637366 -353.847654) (xy 341.62905 -353.845068)
			(xy 341.611646 -353.845068) (xy 341.60333 -353.847654) (xy 341.567121 -353.860189) (xy 341.493019 -353.879707)
			(xy 341.417513 -353.892787) (xy 341.341163 -353.899332) (xy 341.302848 -353.899724) (xy 341.264532 -353.899341)
			(xy 341.188179 -353.892813) (xy 341.112672 -353.879733) (xy 341.038573 -353.860197) (xy 341.002366 -353.847654)
			(xy 340.99405 -353.845068) (xy 340.976646 -353.845068) (xy 340.96833 -353.847654) (xy 340.932121 -353.860189)
			(xy 340.858019 -353.879707) (xy 340.782513 -353.892787) (xy 340.706163 -353.899332) (xy 340.667848 -353.899724)
			(xy 340.626539 -353.899263) (xy 340.544274 -353.89164) (xy 340.463071 -353.876418) (xy 340.38363 -353.853729)
			(xy 340.306637 -353.823768) (xy 340.232755 -353.786793) (xy 340.19744 -353.765358) (xy 340.189803 -353.761082)
			(xy 340.172701 -353.75742) (xy 340.155358 -353.759679) (xy 340.147402 -353.763326) (xy 340.109501 -353.782381)
			(xy 340.030769 -353.813979) (xy 339.949386 -353.837938) (xy 339.866091 -353.85404) (xy 339.781642 -353.862138)
			(xy 339.739224 -353.86264) (xy 339.73897 -353.86264) (xy 339.697862 -353.862216) (xy 339.615997 -353.854629)
			(xy 339.535181 -353.839522) (xy 339.456103 -353.817024) (xy 339.379438 -353.787327) (xy 339.30584 -353.750684)
			(xy 339.235936 -353.707408) (xy 339.170322 -353.657867) (xy 339.109558 -353.602485) (xy 339.054162 -353.541734)
			(xy 339.004606 -353.476131) (xy 338.961314 -353.406237) (xy 338.924655 -353.332646) (xy 338.89494 -353.255988)
			(xy 338.872425 -353.176916) (xy 338.857299 -353.096103) (xy 338.849693 -353.01424) (xy 338.849208 -352.973132)
			(xy 195.744851 -352.973132) (xy 195.771754 -353.027135) (xy 195.80147 -353.103792) (xy 195.823987 -353.182863)
			(xy 195.839114 -353.263674) (xy 195.846722 -353.345537) (xy 195.847208 -353.386644) (xy 195.846646 -353.431414)
			(xy 195.837635 -353.520499) (xy 195.81973 -353.60823) (xy 195.793111 -353.693721) (xy 195.776088 -353.735132)
			(xy 195.772497 -353.744715) (xy 195.772513 -353.765165) (xy 195.776088 -353.774756) (xy 195.793114 -353.816166)
			(xy 195.81975 -353.901654) (xy 195.837657 -353.989386) (xy 195.846654 -354.078474) (xy 195.847208 -354.123244)
			(xy 195.846646 -354.168014) (xy 195.837635 -354.257099) (xy 195.81973 -354.34483) (xy 195.793111 -354.430321)
			(xy 195.776088 -354.471732) (xy 195.772497 -354.481315) (xy 195.772513 -354.501765) (xy 195.776088 -354.511356)
			(xy 195.793114 -354.552766) (xy 195.81975 -354.638254) (xy 195.837657 -354.725986) (xy 195.846654 -354.815074)
			(xy 195.847208 -354.859844) (xy 195.84679 -354.900955) (xy 195.839198 -354.982827) (xy 195.824083 -355.063648)
			(xy 195.801575 -355.14273) (xy 195.771864 -355.219398) (xy 195.742079 -355.279198) (xy 285.476188 -355.279198)
			(xy 285.476597 -355.238082) (xy 285.484185 -355.1562) (xy 285.499295 -355.075367) (xy 285.5218 -354.996274)
			(xy 285.551507 -354.919594) (xy 285.588163 -354.845983) (xy 285.631455 -354.776069) (xy 285.681013 -354.710447)
			(xy 285.736414 -354.649677) (xy 285.797187 -354.594279) (xy 285.862811 -354.544725) (xy 285.932729 -354.501438)
			(xy 286.006342 -354.464786) (xy 286.083023 -354.435084) (xy 286.162118 -354.412584) (xy 286.242951 -354.397477)
			(xy 286.324834 -354.389894) (xy 286.36595 -354.389436) (xy 286.404239 -354.389856) (xy 286.480533 -354.39646)
			(xy 286.555976 -354.409605) (xy 286.630007 -354.429194) (xy 286.666178 -354.44176) (xy 286.674615 -354.444411)
			(xy 286.692285 -354.444411) (xy 286.700722 -354.44176) (xy 286.736903 -354.429226) (xy 286.810935 -354.409651)
			(xy 286.886373 -354.396501) (xy 286.962662 -354.389874) (xy 287.00095 -354.389436) (xy 287.039239 -354.389856)
			(xy 287.115533 -354.39646) (xy 287.190976 -354.409605) (xy 287.265007 -354.429194) (xy 287.301178 -354.44176)
			(xy 287.309615 -354.444411) (xy 287.327285 -354.444411) (xy 287.335722 -354.44176) (xy 287.371903 -354.429226)
			(xy 287.445935 -354.409651) (xy 287.521373 -354.396501) (xy 287.597662 -354.389874) (xy 287.63595 -354.389436)
			(xy 287.674239 -354.389856) (xy 287.750533 -354.39646) (xy 287.825976 -354.409605) (xy 287.900007 -354.429194)
			(xy 287.936178 -354.44176) (xy 287.944615 -354.444411) (xy 287.962285 -354.444411) (xy 287.970722 -354.44176)
			(xy 288.006903 -354.429226) (xy 288.080935 -354.409651) (xy 288.156373 -354.396501) (xy 288.232662 -354.389874)
			(xy 288.27095 -354.389436) (xy 288.309239 -354.389856) (xy 288.385533 -354.39646) (xy 288.460976 -354.409605)
			(xy 288.535007 -354.429194) (xy 288.571178 -354.44176) (xy 288.579615 -354.444411) (xy 288.597285 -354.444411)
			(xy 288.605722 -354.44176) (xy 288.641903 -354.429226) (xy 288.715935 -354.409651) (xy 288.791373 -354.396501)
			(xy 288.867662 -354.389874) (xy 288.90595 -354.389436) (xy 288.947064 -354.389946) (xy 289.028942 -354.397529)
			(xy 289.10977 -354.412634) (xy 289.18886 -354.435133) (xy 289.265537 -354.464834) (xy 289.339146 -354.501483)
			(xy 289.409059 -354.544768) (xy 289.47468 -354.594319) (xy 289.535449 -354.649714) (xy 289.590847 -354.71048)
			(xy 289.640402 -354.776098) (xy 289.683691 -354.846009) (xy 289.720345 -354.919615) (xy 289.75005 -354.99629)
			(xy 289.772554 -355.075379) (xy 289.787664 -355.156207) (xy 289.795251 -355.238084) (xy 289.795712 -355.279198)
			(xy 289.795298 -355.318061) (xy 289.788487 -355.395488) (xy 289.77495 -355.472025) (xy 289.75479 -355.547092)
			(xy 289.741864 -355.583744) (xy 289.739034 -355.592628) (xy 289.739308 -355.611259) (xy 289.742372 -355.620066)
			(xy 289.757559 -355.659473) (xy 289.781314 -355.740522) (xy 289.797291 -355.823456) (xy 289.805346 -355.907529)
			(xy 289.805872 -355.949758) (xy 289.805454 -355.988048) (xy 289.79885 -356.064341) (xy 289.785704 -356.139784)
			(xy 289.766114 -356.213815) (xy 289.753548 -356.249986) (xy 289.750918 -356.258428) (xy 289.750905 -356.276094)
			(xy 289.753548 -356.28453) (xy 289.766084 -356.32071) (xy 289.785659 -356.394742) (xy 289.798808 -356.470181)
			(xy 289.805435 -356.54647) (xy 289.805872 -356.584758) (xy 289.805362 -356.625872) (xy 289.797778 -356.707749)
			(xy 289.782672 -356.788578) (xy 289.760173 -356.867667) (xy 289.730472 -356.944344) (xy 289.693822 -357.017952)
			(xy 289.650537 -357.087865) (xy 289.600986 -357.153486) (xy 289.545592 -357.214255) (xy 289.484826 -357.269653)
			(xy 289.419208 -357.319208) (xy 289.349298 -357.362497) (xy 289.275691 -357.399151) (xy 289.199017 -357.428856)
			(xy 289.119928 -357.45136) (xy 289.039101 -357.466471) (xy 288.957224 -357.474059) (xy 288.91611 -357.47452)
			(xy 288.87782 -357.474114) (xy 288.801526 -357.467506) (xy 288.726084 -357.454357) (xy 288.652053 -357.434764)
			(xy 288.615882 -357.422196) (xy 288.607445 -357.419545) (xy 288.589775 -357.419545) (xy 288.581338 -357.422196)
			(xy 288.54516 -357.434739) (xy 288.471127 -357.454312) (xy 288.395688 -357.46746) (xy 288.319398 -357.474084)
			(xy 288.28111 -357.47452) (xy 288.24282 -357.474114) (xy 288.166526 -357.467506) (xy 288.091084 -357.454357)
			(xy 288.017053 -357.434764) (xy 287.980882 -357.422196) (xy 287.972445 -357.419545) (xy 287.954775 -357.419545)
			(xy 287.946338 -357.422196) (xy 287.91016 -357.434739) (xy 287.836127 -357.454312) (xy 287.760688 -357.46746)
			(xy 287.684398 -357.474084) (xy 287.64611 -357.47452) (xy 287.60782 -357.474114) (xy 287.531526 -357.467506)
			(xy 287.456084 -357.454357) (xy 287.382053 -357.434764) (xy 287.345882 -357.422196) (xy 287.337445 -357.419545)
			(xy 287.319775 -357.419545) (xy 287.311338 -357.422196) (xy 287.27516 -357.434739) (xy 287.201127 -357.454312)
			(xy 287.125688 -357.46746) (xy 287.049398 -357.474084) (xy 287.01111 -357.47452) (xy 286.97282 -357.474114)
			(xy 286.896526 -357.467506) (xy 286.821084 -357.454357) (xy 286.747053 -357.434764) (xy 286.710882 -357.422196)
			(xy 286.702445 -357.419545) (xy 286.684775 -357.419545) (xy 286.676338 -357.422196) (xy 286.64016 -357.434739)
			(xy 286.566127 -357.454312) (xy 286.490688 -357.46746) (xy 286.414398 -357.474084) (xy 286.37611 -357.47452)
			(xy 286.334994 -357.474092) (xy 286.253113 -357.466505) (xy 286.172281 -357.451395) (xy 286.093188 -357.428892)
			(xy 286.016509 -357.399186) (xy 285.942899 -357.362532) (xy 285.872984 -357.319241) (xy 285.807362 -357.269685)
			(xy 285.746593 -357.214284) (xy 285.691195 -357.153513) (xy 285.641641 -357.08789) (xy 285.598353 -357.017973)
			(xy 285.561701 -356.944361) (xy 285.531998 -356.867681) (xy 285.509497 -356.788588) (xy 285.49439 -356.707755)
			(xy 285.486807 -356.625874) (xy 285.486348 -356.584758) (xy 285.48677 -356.546469) (xy 285.493373 -356.470175)
			(xy 285.506518 -356.394732) (xy 285.526107 -356.320701) (xy 285.538672 -356.28453) (xy 285.541343 -356.276098)
			(xy 285.541329 -356.258423) (xy 285.538672 -356.249986) (xy 285.526141 -356.213804) (xy 285.506565 -356.139773)
			(xy 285.493414 -356.064334) (xy 285.486786 -355.988046) (xy 285.486348 -355.949758) (xy 285.486781 -355.910896)
			(xy 285.493587 -355.833469) (xy 285.507119 -355.756932) (xy 285.527272 -355.681865) (xy 285.540196 -355.645212)
			(xy 285.542998 -355.636321) (xy 285.542744 -355.617697) (xy 285.539688 -355.60889) (xy 285.524486 -355.569489)
			(xy 285.500735 -355.488437) (xy 285.484763 -355.405502) (xy 285.476712 -355.321427) (xy 285.476188 -355.279198)
			(xy 195.742079 -355.279198) (xy 195.735206 -355.292996) (xy 195.691912 -355.362897) (xy 195.642352 -355.428505)
			(xy 195.586949 -355.48926) (xy 195.526176 -355.544642) (xy 195.460551 -355.59418) (xy 195.390636 -355.637451)
			(xy 195.317025 -355.674085) (xy 195.240348 -355.703769) (xy 195.161258 -355.726251) (xy 195.080432 -355.741339)
			(xy 194.998557 -355.748903) (xy 194.957446 -355.749352) (xy 194.915842 -355.74888) (xy 194.832994 -355.741147)
			(xy 194.75123 -355.725716) (xy 194.671262 -355.702722) (xy 194.593789 -355.672366) (xy 194.519488 -355.634911)
			(xy 194.48399 -355.613208) (xy 194.474858 -355.608031) (xy 194.454138 -355.60482) (xy 194.433861 -355.61016)
			(xy 194.425316 -355.616256) (xy 194.391667 -355.642178) (xy 194.320293 -355.688236) (xy 194.244854 -355.727283)
			(xy 194.166037 -355.758962) (xy 194.08456 -355.782986) (xy 194.001164 -355.799135) (xy 193.916608 -355.807262)
			(xy 193.874136 -355.807772) (xy 193.873882 -355.807772) (xy 193.832775 -355.807305) (xy 193.750912 -355.799719)
			(xy 193.670098 -355.784614) (xy 193.591023 -355.762118) (xy 193.514359 -355.732423) (xy 193.440762 -355.695782)
			(xy 193.370859 -355.652509) (xy 193.305245 -355.602971) (xy 193.244482 -355.547592) (xy 193.189086 -355.486844)
			(xy 193.13953 -355.421244) (xy 193.096237 -355.351353) (xy 193.059577 -355.277766) (xy 193.029861 -355.201111)
			(xy 193.007343 -355.122041) (xy 192.992215 -355.041231) (xy 192.984607 -354.959371) (xy 192.98412 -354.918264)
			(xy 192.984683 -354.873494) (xy 192.993693 -354.784409) (xy 193.011598 -354.696678) (xy 193.038217 -354.611187)
			(xy 193.05524 -354.569776) (xy 193.058825 -354.560191) (xy 193.058812 -354.539743) (xy 193.05524 -354.530152)
			(xy 193.03824 -354.4888) (xy 193.011628 -354.403438) (xy 192.99372 -354.315836) (xy 192.984697 -354.226879)
			(xy 192.98412 -354.182172) (xy 192.98412 -354.181156) (xy 192.984374 -354.169726) (xy 192.957895 -354.163781)
			(xy 192.90566 -354.149038) (xy 192.87998 -354.140262) (xy 192.871783 -354.137748) (xy 192.854649 -354.137748)
			(xy 192.846452 -354.140262) (xy 192.811236 -354.152209) (xy 192.739226 -354.170796) (xy 192.665903 -354.183236)
			(xy 192.591792 -354.18944) (xy 192.554606 -354.189792) (xy 192.517422 -354.189422) (xy 192.443314 -354.1832)
			(xy 192.369994 -354.170758) (xy 192.297983 -354.152184) (xy 192.26276 -354.140262) (xy 192.254563 -354.137748)
			(xy 192.237429 -354.137748) (xy 192.229232 -354.140262) (xy 192.19413 -354.15215) (xy 192.122374 -354.1707)
			(xy 192.049311 -354.183146) (xy 191.97546 -354.189399) (xy 191.938402 -354.189792) (xy 191.937386 -354.189792)
			(xy 191.89546 -354.189345) (xy 191.811988 -354.181373) (xy 191.729651 -354.165503) (xy 191.649196 -354.141878)
			(xy 191.57135 -354.110712) (xy 191.49682 -354.072288) (xy 191.42628 -354.026953) (xy 191.360368 -353.975119)
			(xy 191.299682 -353.917254) (xy 191.244771 -353.853882) (xy 191.196132 -353.785578) (xy 191.154206 -353.71296)
			(xy 191.119373 -353.636685) (xy 191.091948 -353.557444) (xy 191.07218 -353.475956) (xy 191.060246 -353.392957)
			(xy 191.056256 -353.3092) (xy 187.519078 -353.3092) (xy 187.520094 -353.320137) (xy 187.52058 -353.361244)
			(xy 187.52002 -353.406014) (xy 187.511009 -353.495099) (xy 187.493104 -353.58283) (xy 187.466484 -353.668321)
			(xy 187.44946 -353.709732) (xy 187.44587 -353.719315) (xy 187.445886 -353.739765) (xy 187.44946 -353.749356)
			(xy 187.466484 -353.790767) (xy 187.493121 -353.876254) (xy 187.511029 -353.963986) (xy 187.520026 -354.053074)
			(xy 187.52058 -354.097844) (xy 187.52002 -354.142614) (xy 187.511009 -354.231699) (xy 187.493104 -354.31943)
			(xy 187.466484 -354.404921) (xy 187.44946 -354.446332) (xy 187.44587 -354.455915) (xy 187.445886 -354.476365)
			(xy 187.44946 -354.485956) (xy 187.466484 -354.527367) (xy 187.493121 -354.612854) (xy 187.511029 -354.700586)
			(xy 187.520026 -354.789674) (xy 187.52058 -354.834444) (xy 187.520189 -354.875556) (xy 187.512597 -354.957429)
			(xy 187.497482 -355.038252) (xy 187.474973 -355.117336) (xy 187.445261 -355.194004) (xy 187.408601 -355.267604)
			(xy 187.365306 -355.337506) (xy 187.315744 -355.403115) (xy 187.260339 -355.46387) (xy 187.199564 -355.519252)
			(xy 187.133937 -355.56879) (xy 187.064019 -355.61206) (xy 186.990406 -355.648693) (xy 186.913727 -355.678376)
			(xy 186.834635 -355.700857) (xy 186.753806 -355.715942) (xy 186.67193 -355.723505) (xy 186.630818 -355.723952)
			(xy 186.589214 -355.723494) (xy 186.506365 -355.715758) (xy 186.424601 -355.700325) (xy 186.344633 -355.677328)
			(xy 186.267161 -355.646969) (xy 186.192859 -355.609513) (xy 186.157362 -355.587808) (xy 186.148243 -355.582606)
			(xy 186.127514 -355.579404) (xy 186.107233 -355.584754) (xy 186.098688 -355.590856) (xy 186.065049 -355.616791)
			(xy 185.993673 -355.662848) (xy 185.918232 -355.701893) (xy 185.839413 -355.73357) (xy 185.757935 -355.757592)
			(xy 185.674537 -355.773739) (xy 185.589981 -355.781864) (xy 185.547508 -355.782372) (xy 185.547254 -355.782372)
			(xy 185.506147 -355.781931) (xy 185.424283 -355.774343) (xy 185.343469 -355.759235) (xy 185.264393 -355.736737)
			(xy 185.187729 -355.70704) (xy 185.114132 -355.670398) (xy 185.044229 -355.627122) (xy 184.978615 -355.577583)
			(xy 184.917852 -355.522202) (xy 184.862456 -355.461452) (xy 184.812901 -355.395851) (xy 184.769609 -355.325959)
			(xy 184.732948 -355.252371) (xy 184.703232 -355.175714) (xy 184.680715 -355.096644) (xy 184.665587 -355.015833)
			(xy 184.657979 -354.933971) (xy 184.657492 -354.892864) (xy 184.658057 -354.848094) (xy 184.667066 -354.759009)
			(xy 184.684971 -354.671278) (xy 184.711589 -354.585787) (xy 184.728612 -354.544376) (xy 184.732199 -354.534792)
			(xy 184.732185 -354.514343) (xy 184.728612 -354.504752) (xy 184.711616 -354.463398) (xy 184.685002 -354.378037)
			(xy 184.667093 -354.290435) (xy 184.658069 -354.201478) (xy 184.657492 -354.156772) (xy 184.657492 -354.155756)
			(xy 184.657746 -354.144326) (xy 184.631266 -354.138384) (xy 184.579032 -354.123639) (xy 184.553352 -354.114862)
			(xy 184.545155 -354.112348) (xy 184.528021 -354.112348) (xy 184.519824 -354.114862) (xy 184.484602 -354.126789)
			(xy 184.412594 -354.145381) (xy 184.339273 -354.157827) (xy 184.265163 -354.164037) (xy 184.227978 -354.164392)
			(xy 184.190794 -354.16403) (xy 184.116686 -354.157806) (xy 184.043366 -354.145361) (xy 183.971355 -354.126785)
			(xy 183.936132 -354.114862) (xy 183.927935 -354.112348) (xy 183.910801 -354.112348) (xy 183.902604 -354.114862)
			(xy 183.867505 -354.126757) (xy 183.795747 -354.145305) (xy 183.722684 -354.157749) (xy 183.648832 -354.164001)
			(xy 183.611774 -354.164392) (xy 183.610758 -354.164392) (xy 183.568833 -354.163944) (xy 183.485362 -354.155969)
			(xy 183.403028 -354.140097) (xy 183.322575 -354.11647) (xy 183.244732 -354.085304) (xy 183.170204 -354.046879)
			(xy 183.099666 -354.001544) (xy 183.033756 -353.949709) (xy 182.973072 -353.891844) (xy 182.918163 -353.828473)
			(xy 182.869527 -353.760169) (xy 182.827603 -353.687552) (xy 182.792771 -353.611278) (xy 182.765347 -353.532039)
			(xy 182.745579 -353.450553) (xy 182.733646 -353.367555) (xy 182.729656 -353.2838) (xy 78.346936 -353.2838)
			(xy 78.321217 -353.348042) (xy 78.282395 -353.423345) (xy 78.236592 -353.494617) (xy 78.184221 -353.561213)
			(xy 78.125756 -353.622528) (xy 78.061728 -353.678009) (xy 77.992716 -353.727152) (xy 77.919346 -353.769512)
			(xy 77.842281 -353.804707) (xy 77.762219 -353.832416) (xy 77.679886 -353.85239) (xy 77.596027 -353.864447)
			(xy 77.511402 -353.868479) (xy 77.426777 -353.864447) (xy 77.342918 -353.85239) (xy 77.260585 -353.832416)
			(xy 77.180523 -353.804707) (xy 77.103458 -353.769512) (xy 77.030088 -353.727152) (xy 76.961076 -353.678009)
			(xy 76.897048 -353.622528) (xy 76.838583 -353.561213) (xy 76.786212 -353.494617) (xy 76.740409 -353.423345)
			(xy 76.701587 -353.348042) (xy 76.670099 -353.26939) (xy 76.646231 -353.1881) (xy 76.630197 -353.10491)
			(xy 76.622144 -353.020573) (xy 76.62164 -352.978212) (xy 76.622159 -352.935266) (xy 76.630462 -352.849776)
			(xy 76.646954 -352.765482) (xy 76.671481 -352.683166) (xy 76.687172 -352.643186) (xy 76.690418 -352.63393)
			(xy 76.690431 -352.614336) (xy 76.687172 -352.605086) (xy 76.671432 -352.565089) (xy 76.646875 -352.482712)
			(xy 76.630388 -352.398348) (xy 76.622124 -352.312786) (xy 76.62164 -352.269806) (xy 76.622244 -352.224161)
			(xy 76.631638 -352.133355) (xy 76.650266 -352.043985) (xy 76.66355 -352.000312) (xy 76.665996 -351.9913)
			(xy 76.664956 -351.972672) (xy 76.661518 -351.96399) (xy 76.642856 -351.920903) (xy 76.61365 -351.831658)
			(xy 76.594004 -351.739834) (xy 76.584137 -351.646451) (xy 76.58354 -351.5995) (xy 75.70064 -351.5995)
			(xy 75.701144 -351.637854) (xy 75.70053 -351.683499) (xy 75.691141 -351.774304) (xy 75.672516 -351.863674)
			(xy 75.659234 -351.907348) (xy 75.65681 -351.916364) (xy 75.657836 -351.934988) (xy 75.661266 -351.94367)
			(xy 75.679947 -351.986749) (xy 75.709149 -352.075997) (xy 75.728789 -352.167824) (xy 75.738651 -352.261208)
			(xy 75.739244 -352.30816) (xy 75.738798 -352.348493) (xy 75.731529 -352.428831) (xy 75.71702 -352.508181)
			(xy 75.69539 -352.585893) (xy 75.666817 -352.661328) (xy 75.649582 -352.697796) (xy 75.645066 -352.708391)
			(xy 75.645063 -352.731399) (xy 75.649582 -352.741992) (xy 75.666819 -352.778431) (xy 75.69537 -352.853821)
			(xy 75.716991 -352.931483) (xy 75.731505 -353.010781) (xy 75.738793 -353.091066) (xy 75.739244 -353.131374)
			(xy 75.73874 -353.173735) (xy 75.730687 -353.258072) (xy 75.714653 -353.341262) (xy 75.690785 -353.422552)
			(xy 75.659297 -353.501204) (xy 75.620475 -353.576507) (xy 75.574672 -353.647779) (xy 75.522301 -353.714375)
			(xy 75.463836 -353.77569) (xy 75.399808 -353.831171) (xy 75.330796 -353.880314) (xy 75.257426 -353.922674)
			(xy 75.180361 -353.957869) (xy 75.100299 -353.985578) (xy 75.017966 -354.005552) (xy 74.934107 -354.017609)
			(xy 74.849482 -354.021641) (xy 74.764857 -354.017609) (xy 74.680998 -354.005552) (xy 74.598665 -353.985578)
			(xy 74.518603 -353.957869) (xy 74.441538 -353.922674) (xy 74.368168 -353.880314) (xy 74.299156 -353.831171)
			(xy 74.235128 -353.77569) (xy 74.176663 -353.714375) (xy 74.124292 -353.647779) (xy 74.078489 -353.576507)
			(xy 74.039667 -353.501204) (xy 74.008179 -353.422552) (xy 73.984311 -353.341262) (xy 73.968277 -353.258072)
			(xy 73.960224 -353.173735) (xy 73.95972 -353.131374) (xy 73.960164 -353.091034) (xy 73.96747 -353.010685)
			(xy 73.982028 -352.931329) (xy 74.003719 -352.85362) (xy 74.032363 -352.778196) (xy 74.049636 -352.741738)
			(xy 74.054225 -352.731091) (xy 74.054231 -352.707932) (xy 74.049636 -352.697288) (xy 74.032445 -352.660861)
			(xy 74.003936 -352.58552) (xy 73.98236 -352.50791) (xy 73.967893 -352.428665) (xy 73.960655 -352.348437)
			(xy 73.960228 -352.30816) (xy 73.960797 -352.262521) (xy 73.970094 -352.171718) (xy 73.988639 -352.082344)
			(xy 74.001884 -352.038666) (xy 74.004352 -352.029659) (xy 74.003297 -352.011026) (xy 73.999852 -352.002344)
			(xy 73.981136 -351.959272) (xy 73.95186 -351.870033) (xy 73.932154 -351.778206) (xy 73.922237 -351.684813)
			(xy 73.92162 -351.637854) (xy 2.509012 -351.637854) (xy 2.509012 -358.071674) (xy 14.438884 -358.071674)
			(xy 14.438884 -357.208074) (xy 14.43937 -357.180805) (xy 14.447132 -357.126821) (xy 14.462497 -357.074491)
			(xy 14.485154 -357.024881) (xy 14.51464 -356.979) (xy 14.550355 -356.937783) (xy 14.591572 -356.902068)
			(xy 14.637453 -356.872582) (xy 14.687063 -356.849925) (xy 14.739393 -356.83456) (xy 14.793377 -356.826798)
			(xy 14.847915 -356.826798) (xy 14.901899 -356.83456) (xy 14.954229 -356.849925) (xy 15.003839 -356.872582)
			(xy 15.04972 -356.902068) (xy 15.090937 -356.937783) (xy 15.126652 -356.979) (xy 15.156138 -357.024881)
			(xy 15.178795 -357.074491) (xy 15.19416 -357.126821) (xy 15.201922 -357.180805) (xy 15.202408 -357.208074)
			(xy 15.202408 -358.071674) (xy 15.201922 -358.098943) (xy 15.19416 -358.152927) (xy 15.178795 -358.205257)
			(xy 15.156138 -358.254867) (xy 15.126652 -358.300748) (xy 15.090937 -358.341965) (xy 15.04972 -358.37768)
			(xy 15.003839 -358.407166) (xy 14.954229 -358.429823) (xy 14.901899 -358.445188) (xy 14.847915 -358.45295)
			(xy 14.793377 -358.45295) (xy 14.739393 -358.445188) (xy 14.687063 -358.429823) (xy 14.637453 -358.407166)
			(xy 14.591572 -358.37768) (xy 14.550355 -358.341965) (xy 14.51464 -358.300748) (xy 14.485154 -358.254867)
			(xy 14.462497 -358.205257) (xy 14.447132 -358.152927) (xy 14.43937 -358.098943) (xy 14.438884 -358.071674)
			(xy 2.509012 -358.071674) (xy 2.509012 -358.549194) (xy 40.47998 -358.549194) (xy 40.480352 -358.511134)
			(xy 40.486825 -358.435291) (xy 40.499758 -358.360279) (xy 40.519056 -358.286646) (xy 40.544577 -358.214933)
			(xy 40.55999 -358.180132) (xy 40.563435 -358.171803) (xy 40.56487 -358.153848) (xy 40.562784 -358.14508)
			(xy 40.551663 -358.104882) (xy 40.536092 -358.022938) (xy 40.528245 -357.939897) (xy 40.527732 -357.898192)
			(xy 40.528135 -357.859902) (xy 40.534744 -357.783608) (xy 40.547894 -357.708165) (xy 40.567488 -357.634135)
			(xy 40.580056 -357.597964) (xy 40.58271 -357.589528) (xy 40.582708 -357.571857) (xy 40.580056 -357.56342)
			(xy 40.567506 -357.527245) (xy 40.547935 -357.453211) (xy 40.53479 -357.37777) (xy 40.528167 -357.30148)
			(xy 40.527732 -357.263192) (xy 40.528236 -357.220831) (xy 40.536289 -357.136494) (xy 40.552323 -357.053304)
			(xy 40.576191 -356.972014) (xy 40.607679 -356.893362) (xy 40.646501 -356.818059) (xy 40.692304 -356.746787)
			(xy 40.744675 -356.680191) (xy 40.80314 -356.618876) (xy 40.867168 -356.563395) (xy 40.93618 -356.514252)
			(xy 41.00955 -356.471892) (xy 41.086615 -356.436697) (xy 41.166677 -356.408988) (xy 41.24901 -356.389014)
			(xy 41.332869 -356.376957) (xy 41.417494 -356.372926) (xy 41.502119 -356.376957) (xy 41.585978 -356.389014)
			(xy 41.668311 -356.408988) (xy 41.748373 -356.436697) (xy 41.825438 -356.471892) (xy 41.898808 -356.514252)
			(xy 41.96782 -356.563395) (xy 42.031848 -356.618876) (xy 42.090313 -356.680191) (xy 42.142684 -356.746787)
			(xy 42.188487 -356.818059) (xy 42.227309 -356.893362) (xy 42.258797 -356.972014) (xy 42.282665 -357.053304)
			(xy 42.298699 -357.136494) (xy 42.306752 -357.220831) (xy 42.307256 -357.263192) (xy 42.306849 -357.301482)
			(xy 42.300241 -357.377776) (xy 42.287093 -357.453218) (xy 42.2675 -357.527249) (xy 42.254932 -357.56342)
			(xy 42.252286 -357.571858) (xy 42.252283 -357.589527) (xy 42.254932 -357.597964) (xy 42.267477 -357.634141)
			(xy 42.28705 -357.708174) (xy 42.300196 -357.783614) (xy 42.30682 -357.859904) (xy 42.307256 -357.898192)
			(xy 42.306876 -357.936251) (xy 42.300404 -358.012094) (xy 42.287473 -358.087107) (xy 42.268177 -358.160739)
			(xy 42.242658 -358.232452) (xy 42.227246 -358.267254) (xy 42.223809 -358.275586) (xy 42.222368 -358.293538)
			(xy 42.224452 -358.302306) (xy 42.23557 -358.342505) (xy 42.251142 -358.424449) (xy 42.258991 -358.507489)
			(xy 42.259032 -358.51084) (xy 43.046396 -358.51084) (xy 43.046759 -358.47278) (xy 43.053225 -358.396935)
			(xy 43.066156 -358.321921) (xy 43.085458 -358.248289) (xy 43.110988 -358.176577) (xy 43.126406 -358.141778)
			(xy 43.129746 -358.133421) (xy 43.131033 -358.115482) (xy 43.128946 -358.106726) (xy 43.117873 -358.066521)
			(xy 43.102375 -357.984574) (xy 43.094614 -357.901538) (xy 43.094148 -357.859838) (xy 43.094524 -357.821522)
			(xy 43.101053 -357.745169) (xy 43.114136 -357.669662) (xy 43.133673 -357.595562) (xy 43.146218 -357.559356)
			(xy 43.148787 -357.551035) (xy 43.148799 -357.533636) (xy 43.146218 -357.52532) (xy 43.13374 -357.489193)
			(xy 43.114246 -357.415282) (xy 43.101158 -357.339973) (xy 43.094573 -357.263819) (xy 43.094148 -357.2256)
			(xy 43.094148 -357.224838) (xy 43.094652 -357.18249) (xy 43.102703 -357.098176) (xy 43.118732 -357.01501)
			(xy 43.142593 -356.933743) (xy 43.174072 -356.855113) (xy 43.212883 -356.779832) (xy 43.258673 -356.70858)
			(xy 43.311029 -356.642004) (xy 43.369477 -356.580706) (xy 43.433487 -356.525241) (xy 43.502479 -356.476112)
			(xy 43.575829 -356.433763) (xy 43.652872 -356.398579) (xy 43.732911 -356.370877) (xy 43.81522 -356.350909)
			(xy 43.899055 -356.338856) (xy 43.983656 -356.334826) (xy 44.068257 -356.338856) (xy 44.152092 -356.350909)
			(xy 44.234401 -356.370877) (xy 44.31444 -356.398579) (xy 44.391483 -356.433763) (xy 44.464833 -356.476112)
			(xy 44.533825 -356.525241) (xy 44.597835 -356.580706) (xy 44.656283 -356.642004) (xy 44.708639 -356.70858)
			(xy 44.754429 -356.779832) (xy 44.79324 -356.855113) (xy 44.824719 -356.933743) (xy 44.84858 -357.01501)
			(xy 44.864609 -357.098176) (xy 44.87266 -357.18249) (xy 44.873164 -357.224838) (xy 44.873164 -357.2256)
			(xy 44.87277 -357.263821) (xy 44.866201 -357.339979) (xy 44.853113 -357.415292) (xy 44.833602 -357.489202)
			(xy 44.821094 -357.52532) (xy 44.818487 -357.533631) (xy 44.818499 -357.55104) (xy 44.821094 -357.559356)
			(xy 44.833623 -357.595567) (xy 44.853143 -357.669669) (xy 44.866225 -357.745173) (xy 44.872771 -357.821523)
			(xy 44.873164 -357.859838) (xy 44.872788 -357.897898) (xy 44.866324 -357.973742) (xy 44.853395 -358.048756)
			(xy 44.837736 -358.108504) (xy 46.991016 -358.108504) (xy 46.991397 -358.070445) (xy 46.997869 -357.994602)
			(xy 47.0108 -357.919589) (xy 47.030096 -357.845957) (xy 47.055615 -357.774244) (xy 47.071026 -357.739442)
			(xy 47.074466 -357.731111) (xy 47.075906 -357.713158) (xy 47.07382 -357.70439) (xy 47.0627 -357.664192)
			(xy 47.047129 -357.582247) (xy 47.039281 -357.499207) (xy 47.038768 -357.457502) (xy 47.039173 -357.419212)
			(xy 47.045781 -357.342918) (xy 47.05893 -357.267476) (xy 47.078524 -357.193445) (xy 47.091092 -357.157274)
			(xy 47.09374 -357.148837) (xy 47.093741 -357.131167) (xy 47.091092 -357.12273) (xy 47.078546 -357.086553)
			(xy 47.058974 -357.01252) (xy 47.045827 -356.93708) (xy 47.039204 -356.86079) (xy 47.038768 -356.822502)
			(xy 47.0392 -356.781386) (xy 47.046788 -356.699506) (xy 47.061898 -356.618674) (xy 47.084402 -356.539582)
			(xy 47.114108 -356.462904) (xy 47.150762 -356.389293) (xy 47.194052 -356.319379) (xy 47.243609 -356.253758)
			(xy 47.299008 -356.192989) (xy 47.359779 -356.137591) (xy 47.425402 -356.088036) (xy 47.495318 -356.044749)
			(xy 47.568929 -356.008097) (xy 47.645609 -355.978393) (xy 47.724702 -355.955891) (xy 47.805533 -355.940784)
			(xy 47.887414 -355.933199) (xy 47.92853 -355.93274) (xy 47.969637 -355.933252) (xy 48.051499 -355.940877)
			(xy 48.132307 -355.956023) (xy 48.211373 -355.97856) (xy 48.288023 -356.008296) (xy 48.325024 -356.026212)
			(xy 48.335846 -356.030917) (xy 48.359414 -356.030917) (xy 48.370236 -356.026212) (xy 48.407247 -356.008316)
			(xy 48.483894 -355.978575) (xy 48.562957 -355.956031) (xy 48.643763 -355.940876) (xy 48.725623 -355.93324)
			(xy 48.76673 -355.93274) (xy 48.80502 -355.933136) (xy 48.881314 -355.939747) (xy 48.956757 -355.952899)
			(xy 49.030787 -355.972495) (xy 49.066958 -355.985064) (xy 49.075395 -355.987715) (xy 49.093065 -355.987715)
			(xy 49.101502 -355.985064) (xy 49.137675 -355.972508) (xy 49.21171 -355.952938) (xy 49.287151 -355.939795)
			(xy 49.363442 -355.933174) (xy 49.40173 -355.93274) (xy 49.44002 -355.933136) (xy 49.516314 -355.939747)
			(xy 49.591757 -355.952899) (xy 49.665787 -355.972495) (xy 49.701958 -355.985064) (xy 49.710395 -355.987715)
			(xy 49.728065 -355.987715) (xy 49.736502 -355.985064) (xy 49.772675 -355.972508) (xy 49.84671 -355.952938)
			(xy 49.922151 -355.939795) (xy 49.998442 -355.933174) (xy 50.03673 -355.93274) (xy 50.07502 -355.933136)
			(xy 50.151314 -355.939747) (xy 50.226757 -355.952899) (xy 50.300787 -355.972495) (xy 50.336958 -355.985064)
			(xy 50.345395 -355.987715) (xy 50.363065 -355.987715) (xy 50.371502 -355.985064) (xy 50.407675 -355.972508)
			(xy 50.48171 -355.952938) (xy 50.557151 -355.939795) (xy 50.633442 -355.933174) (xy 50.67173 -355.93274)
			(xy 50.712845 -355.933184) (xy 50.794723 -355.940774) (xy 50.875552 -355.955886) (xy 50.954642 -355.978392)
			(xy 51.031318 -356.008098) (xy 51.104926 -356.044753) (xy 51.174838 -356.088043) (xy 51.240458 -356.137599)
			(xy 51.301225 -356.192997) (xy 51.356622 -356.253767) (xy 51.406175 -356.319388) (xy 51.449463 -356.389302)
			(xy 51.486115 -356.462911) (xy 51.515819 -356.539588) (xy 51.538321 -356.618679) (xy 51.55343 -356.699508)
			(xy 51.561017 -356.781387) (xy 51.561492 -356.822502) (xy 51.561091 -356.860792) (xy 51.554482 -356.937086)
			(xy 51.541332 -357.012529) (xy 51.521737 -357.086559) (xy 51.509168 -357.12273) (xy 51.506515 -357.131166)
			(xy 51.506516 -357.148837) (xy 51.509168 -357.157274) (xy 51.521713 -357.193451) (xy 51.541286 -357.267484)
			(xy 51.554433 -357.342924) (xy 51.561057 -357.419214) (xy 51.561492 -357.457502) (xy 51.561112 -357.495561)
			(xy 51.55464 -357.571404) (xy 51.541708 -357.646417) (xy 51.522413 -357.720049) (xy 51.496894 -357.791762)
			(xy 51.481482 -357.826564) (xy 51.478039 -357.834894) (xy 51.476603 -357.852848) (xy 51.478688 -357.861616)
			(xy 51.48981 -357.901814) (xy 51.50538 -357.983758) (xy 51.513227 -358.066799) (xy 51.51374 -358.108504)
			(xy 51.513251 -358.149614) (xy 51.505664 -358.231482) (xy 51.490553 -358.312301) (xy 51.468049 -358.391381)
			(xy 51.438343 -358.468047) (xy 51.401689 -358.541644) (xy 51.3584 -358.611544) (xy 51.308844 -358.677152)
			(xy 51.253446 -358.737906) (xy 51.192678 -358.793289) (xy 51.127058 -358.842827) (xy 51.057146 -358.886099)
			(xy 50.98354 -358.922734) (xy 50.906867 -358.952421) (xy 50.827781 -358.974905) (xy 50.746958 -358.989995)
			(xy 50.665088 -358.997562) (xy 50.623978 -358.998012) (xy 50.585661 -358.99765) (xy 50.509308 -358.991116)
			(xy 50.433801 -358.97803) (xy 50.359702 -358.958488) (xy 50.323496 -358.945942) (xy 50.31518 -358.943356)
			(xy 50.297776 -358.943356) (xy 50.28946 -358.945942) (xy 50.253248 -358.958468) (xy 50.179147 -358.977989)
			(xy 50.103642 -358.991071) (xy 50.027293 -358.997619) (xy 49.988978 -358.998012) (xy 49.950661 -358.99765)
			(xy 49.874308 -358.991116) (xy 49.798801 -358.97803) (xy 49.724702 -358.958488) (xy 49.688496 -358.945942)
			(xy 49.68018 -358.943356) (xy 49.662776 -358.943356) (xy 49.65446 -358.945942) (xy 49.618248 -358.958468)
			(xy 49.544147 -358.977989) (xy 49.468642 -358.991071) (xy 49.392293 -358.997619) (xy 49.353978 -358.998012)
			(xy 49.315661 -358.99765) (xy 49.239308 -358.991116) (xy 49.163801 -358.97803) (xy 49.089702 -358.958488)
			(xy 49.053496 -358.945942) (xy 49.04518 -358.943356) (xy 49.027776 -358.943356) (xy 49.01946 -358.945942)
			(xy 48.983339 -358.95844) (xy 48.909426 -358.977928) (xy 48.834115 -358.99101) (xy 48.757959 -358.99759)
			(xy 48.71974 -358.998012) (xy 48.718978 -358.998012) (xy 48.677876 -358.99753) (xy 48.596022 -358.989953)
			(xy 48.515216 -358.974857) (xy 48.436148 -358.95237) (xy 48.359491 -358.922685) (xy 48.322484 -358.904794)
			(xy 48.311662 -358.900089) (xy 48.288094 -358.900089) (xy 48.277272 -358.904794) (xy 48.240271 -358.922698)
			(xy 48.163612 -358.952379) (xy 48.084542 -358.974864) (xy 48.003735 -358.98996) (xy 47.92188 -358.997539)
			(xy 47.880778 -358.998012) (xy 47.839669 -358.997608) (xy 47.757803 -358.990022) (xy 47.676986 -358.974915)
			(xy 47.597907 -358.952416) (xy 47.52124 -358.922719) (xy 47.447641 -358.886075) (xy 47.377735 -358.842798)
			(xy 47.312121 -358.793256) (xy 47.251356 -358.737873) (xy 47.19596 -358.677119) (xy 47.146405 -358.611515)
			(xy 47.103114 -358.541618) (xy 47.066455 -358.468026) (xy 47.036742 -358.391366) (xy 47.014227 -358.312292)
			(xy 46.999104 -358.231477) (xy 46.9915 -358.149612) (xy 46.991016 -358.108504) (xy 44.837736 -358.108504)
			(xy 44.834097 -358.122388) (xy 44.808571 -358.1941) (xy 44.793154 -358.2289) (xy 44.789778 -358.237249)
			(xy 44.788481 -358.255202) (xy 44.790614 -358.263952) (xy 44.801704 -358.304153) (xy 44.817195 -358.386101)
			(xy 44.82495 -358.46914) (xy 44.825412 -358.51084) (xy 44.824852 -358.556303) (xy 44.815599 -358.646758)
			(xy 44.797171 -358.735798) (xy 44.78401 -358.779318) (xy 44.78146 -358.788893) (xy 44.783017 -358.808626)
			(xy 44.787058 -358.817672) (xy 44.805431 -358.855048) (xy 44.835897 -358.932566) (xy 44.858991 -359.012591)
			(xy 44.87451 -359.094423) (xy 44.882318 -359.177347) (xy 44.882816 -359.218992) (xy 44.882816 -359.219246)
			(xy 44.882312 -359.261594) (xy 44.874261 -359.345908) (xy 44.858232 -359.429074) (xy 44.834371 -359.510341)
			(xy 44.802892 -359.588971) (xy 44.764081 -359.664252) (xy 44.718291 -359.735504) (xy 44.665935 -359.80208)
			(xy 44.607487 -359.863378) (xy 44.543477 -359.918843) (xy 44.474485 -359.967972) (xy 44.401135 -360.010321)
			(xy 44.324092 -360.045505) (xy 44.244053 -360.073207) (xy 44.161744 -360.093175) (xy 44.077909 -360.105228)
			(xy 43.993308 -360.109259) (xy 43.908707 -360.105228) (xy 43.824872 -360.093175) (xy 43.742563 -360.073207)
			(xy 43.662524 -360.045505) (xy 43.585481 -360.010321) (xy 43.512131 -359.967972) (xy 43.443139 -359.918843)
			(xy 43.379129 -359.863378) (xy 43.320681 -359.80208) (xy 43.268325 -359.735504) (xy 43.222535 -359.664252)
			(xy 43.183724 -359.588971) (xy 43.152245 -359.510341) (xy 43.128384 -359.429074) (xy 43.112355 -359.345908)
			(xy 43.104304 -359.261594) (xy 43.1038 -359.219246) (xy 43.104356 -359.173782) (xy 43.113611 -359.083328)
			(xy 43.13204 -358.994288) (xy 43.145202 -358.950768) (xy 43.147759 -358.941194) (xy 43.146197 -358.921461)
			(xy 43.142154 -358.912414) (xy 43.123767 -358.875016) (xy 43.093286 -358.797449) (xy 43.070189 -358.717372)
			(xy 43.054676 -358.635487) (xy 43.046883 -358.552511) (xy 43.046396 -358.51084) (xy 42.259032 -358.51084)
			(xy 42.259504 -358.549194) (xy 42.258889 -358.594663) (xy 42.249552 -358.685121) (xy 42.231047 -358.774157)
			(xy 42.217848 -358.817672) (xy 42.215273 -358.827242) (xy 42.216849 -358.846979) (xy 42.220896 -358.856026)
			(xy 42.239309 -358.893418) (xy 42.269845 -358.970977) (xy 42.292996 -359.051051) (xy 42.308559 -359.132939)
			(xy 42.316398 -359.215923) (xy 42.316908 -359.2576) (xy 42.316404 -359.299961) (xy 42.308351 -359.384298)
			(xy 42.292317 -359.467488) (xy 42.268449 -359.548778) (xy 42.236961 -359.62743) (xy 42.198139 -359.702733)
			(xy 42.152336 -359.774005) (xy 42.099965 -359.840601) (xy 42.0415 -359.901916) (xy 41.977472 -359.957397)
			(xy 41.90846 -360.00654) (xy 41.83509 -360.0489) (xy 41.758025 -360.084095) (xy 41.677963 -360.111804)
			(xy 41.59563 -360.131778) (xy 41.511771 -360.143835) (xy 41.427146 -360.147867) (xy 41.342521 -360.143835)
			(xy 41.258662 -360.131778) (xy 41.176329 -360.111804) (xy 41.096267 -360.084095) (xy 41.019202 -360.0489)
			(xy 40.945832 -360.00654) (xy 40.87682 -359.957397) (xy 40.812792 -359.901916) (xy 40.754327 -359.840601)
			(xy 40.701956 -359.774005) (xy 40.656153 -359.702733) (xy 40.617331 -359.62743) (xy 40.585843 -359.548778)
			(xy 40.561975 -359.467488) (xy 40.545941 -359.384298) (xy 40.537888 -359.299961) (xy 40.537384 -359.2576)
			(xy 40.537998 -359.212131) (xy 40.547335 -359.121673) (xy 40.565841 -359.032637) (xy 40.57904 -358.989122)
			(xy 40.581619 -358.979553) (xy 40.580041 -358.959815) (xy 40.575992 -358.950768) (xy 40.557613 -358.91336)
			(xy 40.527071 -358.835806) (xy 40.503913 -358.755736) (xy 40.488342 -358.673851) (xy 40.480494 -358.59087)
			(xy 40.47998 -358.549194) (xy 2.509012 -358.549194) (xy 2.509012 -361.825848) (xy 5.986007 -361.825848)
			(xy 5.986007 -361.696708) (xy 5.993957 -361.567813) (xy 6.009827 -361.439653) (xy 6.033556 -361.312712)
			(xy 6.065055 -361.187473) (xy 6.104204 -361.06441) (xy 6.150855 -360.943991) (xy 6.20483 -360.826672)
			(xy 6.265925 -360.712898) (xy 6.333908 -360.603101) (xy 6.408522 -360.497698) (xy 6.489483 -360.397088)
			(xy 6.576483 -360.301653) (xy 6.669194 -360.211754) (xy 6.767264 -360.127733) (xy 6.870319 -360.049909)
			(xy 6.97797 -359.978577) (xy 7.089809 -359.914007) (xy 7.20541 -359.856445) (xy 7.324335 -359.806108)
			(xy 7.446134 -359.763188) (xy 7.570344 -359.727847) (xy 7.696493 -359.70022) (xy 7.824105 -359.680411)
			(xy 7.952694 -359.668495) (xy 8.081772 -359.664519) (xy 8.21085 -359.668495) (xy 8.339439 -359.680411)
			(xy 8.467051 -359.70022) (xy 8.5932 -359.727847) (xy 8.71741 -359.763188) (xy 8.839209 -359.806108)
			(xy 8.958134 -359.856445) (xy 9.073735 -359.914007) (xy 9.185574 -359.978577) (xy 9.293225 -360.049909)
			(xy 9.39628 -360.127733) (xy 9.49435 -360.211754) (xy 9.587061 -360.301653) (xy 9.674061 -360.397088)
			(xy 9.689764 -360.416602) (xy 12.542012 -360.416602) (xy 12.542012 -359.553002) (xy 12.542498 -359.525751)
			(xy 12.550254 -359.471803) (xy 12.565609 -359.419508) (xy 12.588251 -359.369931) (xy 12.617717 -359.324081)
			(xy 12.653408 -359.28289) (xy 12.694599 -359.247199) (xy 12.740449 -359.217733) (xy 12.790026 -359.195091)
			(xy 12.842321 -359.179736) (xy 12.896269 -359.17198) (xy 12.950771 -359.17198) (xy 13.004719 -359.179736)
			(xy 13.057014 -359.195091) (xy 13.106591 -359.217733) (xy 13.152441 -359.247199) (xy 13.193632 -359.28289)
			(xy 13.229323 -359.324081) (xy 13.258789 -359.369931) (xy 13.281431 -359.419508) (xy 13.296786 -359.471803)
			(xy 13.304542 -359.525751) (xy 13.305028 -359.553002) (xy 13.305028 -360.416602) (xy 13.304542 -360.443853)
			(xy 13.296786 -360.497801) (xy 13.281431 -360.550096) (xy 13.258789 -360.599673) (xy 13.229323 -360.645523)
			(xy 13.193632 -360.686714) (xy 13.152441 -360.722405) (xy 13.106591 -360.751871) (xy 13.057014 -360.774513)
			(xy 13.004719 -360.789868) (xy 12.950771 -360.797624) (xy 12.896269 -360.797624) (xy 12.842321 -360.789868)
			(xy 12.790026 -360.774513) (xy 12.740449 -360.751871) (xy 12.694599 -360.722405) (xy 12.653408 -360.686714)
			(xy 12.617717 -360.645523) (xy 12.588251 -360.599673) (xy 12.565609 -360.550096) (xy 12.550254 -360.497801)
			(xy 12.542498 -360.443853) (xy 12.542012 -360.416602) (xy 9.689764 -360.416602) (xy 9.755022 -360.497698)
			(xy 9.829636 -360.603101) (xy 9.897619 -360.712898) (xy 9.958714 -360.826672) (xy 10.012689 -360.943991)
			(xy 10.05934 -361.06441) (xy 10.098489 -361.187473) (xy 10.129988 -361.312712) (xy 10.153717 -361.439653)
			(xy 10.169587 -361.567813) (xy 10.177537 -361.696708) (xy 10.178034 -361.761278) (xy 10.177537 -361.825848)
			(xy 10.169587 -361.954743) (xy 10.153717 -362.082903) (xy 10.129988 -362.209844) (xy 10.098489 -362.335083)
			(xy 10.079022 -362.396278) (xy 165.733984 -362.396278) (xy 165.733984 -361.532678) (xy 165.73447 -361.505409)
			(xy 165.742232 -361.451425) (xy 165.757597 -361.399095) (xy 165.780254 -361.349485) (xy 165.80974 -361.303604)
			(xy 165.845455 -361.262387) (xy 165.886672 -361.226672) (xy 165.932553 -361.197186) (xy 165.982163 -361.174529)
			(xy 166.034493 -361.159164) (xy 166.088477 -361.151402) (xy 166.143015 -361.151402) (xy 166.196999 -361.159164)
			(xy 166.249329 -361.174529) (xy 166.298939 -361.197186) (xy 166.34482 -361.226672) (xy 166.386037 -361.262387)
			(xy 166.421752 -361.303604) (xy 166.451238 -361.349485) (xy 166.473895 -361.399095) (xy 166.48926 -361.451425)
			(xy 166.497022 -361.505409) (xy 166.497508 -361.532678) (xy 166.497508 -362.234988) (xy 185.144664 -362.234988)
			(xy 185.144664 -362.23448) (xy 185.145268 -362.188148) (xy 185.154941 -362.09599) (xy 185.174137 -362.005336)
			(xy 185.202649 -361.917167) (xy 185.220864 -361.874562) (xy 185.224678 -361.864622) (xy 185.224673 -361.843356)
			(xy 185.220864 -361.833414) (xy 185.202614 -361.790754) (xy 185.174071 -361.702461) (xy 185.15488 -361.611675)
			(xy 185.145248 -361.519384) (xy 185.144664 -361.472988) (xy 185.145245 -361.426592) (xy 185.154891 -361.334304)
			(xy 185.174088 -361.24352) (xy 185.202626 -361.155227) (xy 185.220864 -361.112562) (xy 185.224678 -361.102622)
			(xy 185.224673 -361.081356) (xy 185.220864 -361.071414) (xy 185.202636 -361.028813) (xy 185.17412 -360.940645)
			(xy 185.154929 -360.849989) (xy 185.145271 -360.757828) (xy 185.144664 -360.711496) (xy 185.144664 -360.710988)
			(xy 185.145155 -360.669886) (xy 185.152741 -360.588033) (xy 185.167846 -360.507229) (xy 185.190343 -360.428164)
			(xy 185.220039 -360.351511) (xy 185.25668 -360.277925) (xy 185.299955 -360.208034) (xy 185.349493 -360.142434)
			(xy 185.404873 -360.081684) (xy 185.465622 -360.026303) (xy 185.531221 -359.976764) (xy 185.601111 -359.933488)
			(xy 185.674696 -359.896845) (xy 185.751348 -359.867148) (xy 185.830414 -359.84465) (xy 185.911217 -359.829543)
			(xy 185.99307 -359.821956) (xy 186.034172 -359.82148) (xy 186.03468 -359.82148) (xy 186.081011 -359.822097)
			(xy 186.173169 -359.831765) (xy 186.263823 -359.850958) (xy 186.351992 -359.879466) (xy 186.394598 -359.89768)
			(xy 186.40454 -359.901486) (xy 186.425804 -359.901486) (xy 186.435746 -359.89768) (xy 186.478352 -359.879466)
			(xy 186.566519 -359.850947) (xy 186.657173 -359.831752) (xy 186.749332 -359.822089) (xy 186.795664 -359.82148)
			(xy 186.796172 -359.82148) (xy 186.837274 -359.821979) (xy 186.919129 -359.829561) (xy 186.999934 -359.844664)
			(xy 187.079001 -359.867158) (xy 187.155656 -359.896852) (xy 187.229243 -359.933492) (xy 187.299136 -359.976765)
			(xy 187.364738 -360.026303) (xy 187.425489 -360.081682) (xy 187.480872 -360.142431) (xy 187.530412 -360.208031)
			(xy 187.573689 -360.277922) (xy 187.610332 -360.351508) (xy 187.640029 -360.428161) (xy 187.662527 -360.507227)
			(xy 187.677633 -360.588032) (xy 187.685219 -360.669886) (xy 187.68568 -360.710988) (xy 187.68568 -360.711496)
			(xy 187.685072 -360.757828) (xy 187.684417 -360.764074) (xy 211.161635 -360.764074) (xy 211.16566 -360.621882)
			(xy 211.177723 -360.480146) (xy 211.197786 -360.33932) (xy 211.225784 -360.199854) (xy 211.261628 -360.062195)
			(xy 211.305202 -359.926785) (xy 211.356367 -359.794057) (xy 211.41496 -359.664436) (xy 211.480791 -359.538338)
			(xy 211.553652 -359.416166) (xy 211.633307 -359.298312) (xy 211.719503 -359.185153) (xy 211.811962 -359.077051)
			(xy 211.91039 -358.974354) (xy 212.014469 -358.87739) (xy 212.123868 -358.78647) (xy 212.238236 -358.701884)
			(xy 212.357205 -358.623904) (xy 212.480396 -358.55278) (xy 212.607413 -358.488739) (xy 212.73785 -358.431987)
			(xy 212.871289 -358.382705) (xy 213.007302 -358.341051) (xy 213.145454 -358.307159) (xy 213.285303 -358.281138)
			(xy 213.426399 -358.26307) (xy 213.568291 -358.253013) (xy 213.710526 -358.251) (xy 213.852646 -358.257037)
			(xy 213.994197 -358.271105) (xy 214.134726 -358.293159) (xy 214.273781 -358.323128) (xy 214.410919 -358.360916)
			(xy 214.545699 -358.406402) (xy 214.67769 -358.45944) (xy 214.806469 -358.519861) (xy 214.931623 -358.58747)
			(xy 215.052751 -358.662052) (xy 215.169467 -358.743368) (xy 215.281395 -358.831156) (xy 215.388177 -358.925136)
			(xy 215.489471 -359.025006) (xy 215.584952 -359.130448) (xy 215.674316 -359.241122) (xy 215.757274 -359.356675)
			(xy 215.833563 -359.476736) (xy 215.902937 -359.600921) (xy 215.965174 -359.728832) (xy 216.020075 -359.860059)
			(xy 216.067463 -359.994182) (xy 216.107188 -360.130771) (xy 216.139121 -360.269389) (xy 216.163162 -360.409591)
			(xy 216.179231 -360.550929) (xy 216.187279 -360.69295) (xy 216.187782 -360.764074) (xy 255.611635 -360.764074)
			(xy 255.61566 -360.621882) (xy 255.627723 -360.480146) (xy 255.647786 -360.33932) (xy 255.675784 -360.199854)
			(xy 255.711628 -360.062195) (xy 255.755202 -359.926785) (xy 255.806367 -359.794057) (xy 255.86496 -359.664436)
			(xy 255.930791 -359.538338) (xy 256.003652 -359.416166) (xy 256.083307 -359.298312) (xy 256.169503 -359.185153)
			(xy 256.261962 -359.077051) (xy 256.36039 -358.974354) (xy 256.464469 -358.87739) (xy 256.573868 -358.78647)
			(xy 256.688236 -358.701884) (xy 256.807205 -358.623904) (xy 256.930396 -358.55278) (xy 257.057413 -358.488739)
			(xy 257.18785 -358.431987) (xy 257.321289 -358.382705) (xy 257.457302 -358.341051) (xy 257.595454 -358.307159)
			(xy 257.735303 -358.281138) (xy 257.876399 -358.26307) (xy 258.018291 -358.253013) (xy 258.160526 -358.251)
			(xy 258.302646 -358.257037) (xy 258.444197 -358.271105) (xy 258.584726 -358.293159) (xy 258.723781 -358.323128)
			(xy 258.860919 -358.360916) (xy 258.995699 -358.406402) (xy 259.12769 -358.45944) (xy 259.256469 -358.519861)
			(xy 259.381623 -358.58747) (xy 259.502751 -358.662052) (xy 259.619467 -358.743368) (xy 259.652996 -358.769666)
			(xy 294.901627 -358.769666) (xy 294.905632 -358.663917) (xy 294.917622 -358.558774) (xy 294.937531 -358.454839)
			(xy 294.965242 -358.352707) (xy 295.000599 -358.252963) (xy 295.043397 -358.156179) (xy 295.093393 -358.062909)
			(xy 295.1503 -357.973688) (xy 295.213791 -357.889025) (xy 295.283503 -357.809407) (xy 295.359037 -357.735289)
			(xy 295.43996 -357.667096) (xy 295.525809 -357.605218) (xy 295.616092 -357.550011) (xy 295.710291 -357.501789)
			(xy 295.807868 -357.460829) (xy 295.908263 -357.427367) (xy 296.010901 -357.401593) (xy 296.115194 -357.383655)
			(xy 296.220545 -357.373656) (xy 296.326351 -357.371653) (xy 296.432005 -357.377658) (xy 296.536902 -357.391637)
			(xy 296.640442 -357.413508) (xy 296.742031 -357.443148) (xy 296.841088 -357.480386) (xy 296.937045 -357.525008)
			(xy 297.029352 -357.57676) (xy 297.117481 -357.635345) (xy 297.200927 -357.700427) (xy 297.279211 -357.771633)
			(xy 297.351886 -357.848556) (xy 297.418536 -357.930756) (xy 297.478778 -358.01776) (xy 297.532267 -358.109071)
			(xy 297.578698 -358.204166) (xy 297.617803 -358.3025) (xy 297.64936 -358.403511) (xy 297.673187 -358.506618)
			(xy 297.689148 -358.611232) (xy 297.697152 -358.716754) (xy 297.697652 -358.769666) (xy 297.697152 -358.822578)
			(xy 297.689148 -358.9281) (xy 297.673187 -359.032714) (xy 297.64936 -359.135821) (xy 297.617803 -359.236832)
			(xy 297.578698 -359.335166) (xy 297.532267 -359.430261) (xy 297.478778 -359.521572) (xy 297.418536 -359.608576)
			(xy 297.351886 -359.690776) (xy 297.279211 -359.767699) (xy 297.200927 -359.838905) (xy 297.117481 -359.903987)
			(xy 297.029352 -359.962572) (xy 296.937045 -360.014324) (xy 296.841088 -360.058946) (xy 296.742031 -360.096184)
			(xy 296.640442 -360.125824) (xy 296.536902 -360.147695) (xy 296.432005 -360.161674) (xy 296.326351 -360.167679)
			(xy 296.220545 -360.165676) (xy 296.115194 -360.155677) (xy 296.010901 -360.137739) (xy 295.908263 -360.111965)
			(xy 295.807868 -360.078503) (xy 295.710291 -360.037543) (xy 295.616092 -359.989321) (xy 295.525809 -359.934114)
			(xy 295.43996 -359.872236) (xy 295.359037 -359.804043) (xy 295.283503 -359.729925) (xy 295.213791 -359.650307)
			(xy 295.1503 -359.565644) (xy 295.093393 -359.476423) (xy 295.043397 -359.383153) (xy 295.000599 -359.286369)
			(xy 294.965242 -359.186625) (xy 294.937531 -359.084493) (xy 294.917622 -358.980558) (xy 294.905632 -358.875415)
			(xy 294.901627 -358.769666) (xy 259.652996 -358.769666) (xy 259.731395 -358.831156) (xy 259.838177 -358.925136)
			(xy 259.939471 -359.025006) (xy 260.034952 -359.130448) (xy 260.124316 -359.241122) (xy 260.207274 -359.356675)
			(xy 260.283563 -359.476736) (xy 260.352937 -359.600921) (xy 260.415174 -359.728832) (xy 260.470075 -359.860059)
			(xy 260.517463 -359.994182) (xy 260.557188 -360.130771) (xy 260.589121 -360.269389) (xy 260.613162 -360.409591)
			(xy 260.629231 -360.550929) (xy 260.637279 -360.69295) (xy 260.637782 -360.764074) (xy 260.637279 -360.835198)
			(xy 260.629231 -360.977219) (xy 260.613162 -361.118557) (xy 260.589121 -361.258759) (xy 260.557188 -361.397377)
			(xy 260.517463 -361.533966) (xy 260.470075 -361.668089) (xy 260.415174 -361.799316) (xy 260.401302 -361.827826)
			(xy 430.615097 -361.827826) (xy 430.619102 -361.722077) (xy 430.631092 -361.616934) (xy 430.651001 -361.512999)
			(xy 430.678712 -361.410867) (xy 430.714069 -361.311123) (xy 430.756867 -361.214339) (xy 430.806863 -361.121069)
			(xy 430.86377 -361.031848) (xy 430.927261 -360.947185) (xy 430.996973 -360.867567) (xy 431.072507 -360.793449)
			(xy 431.15343 -360.725256) (xy 431.239279 -360.663378) (xy 431.329562 -360.608171) (xy 431.423761 -360.559949)
			(xy 431.521338 -360.518989) (xy 431.621733 -360.485527) (xy 431.724371 -360.459753) (xy 431.828664 -360.441815)
			(xy 431.934015 -360.431816) (xy 432.039821 -360.429813) (xy 432.145475 -360.435818) (xy 432.250372 -360.449797)
			(xy 432.353912 -360.471668) (xy 432.455501 -360.501308) (xy 432.554558 -360.538546) (xy 432.650515 -360.583168)
			(xy 432.742822 -360.63492) (xy 432.830951 -360.693505) (xy 432.914397 -360.758587) (xy 432.992681 -360.829793)
			(xy 433.065356 -360.906716) (xy 433.132006 -360.988916) (xy 433.192248 -361.07592) (xy 433.245737 -361.167231)
			(xy 433.292168 -361.262326) (xy 433.331273 -361.36066) (xy 433.36283 -361.461671) (xy 433.370787 -361.496102)
			(xy 434.579776 -361.496102) (xy 434.580404 -361.4497) (xy 434.590093 -361.357403) (xy 434.609347 -361.266617)
			(xy 434.637954 -361.178332) (xy 434.65623 -361.135676) (xy 434.660038 -361.125734) (xy 434.660039 -361.10447)
			(xy 434.65623 -361.094528) (xy 434.637968 -361.051867) (xy 434.609375 -360.963579) (xy 434.590118 -360.872796)
			(xy 434.580405 -360.780503) (xy 434.579776 -360.734102) (xy 434.580404 -360.6877) (xy 434.590093 -360.595403)
			(xy 434.609347 -360.504617) (xy 434.637954 -360.416332) (xy 434.65623 -360.373676) (xy 434.660038 -360.363734)
			(xy 434.660039 -360.34247) (xy 434.65623 -360.332528) (xy 434.637968 -360.289867) (xy 434.609375 -360.201579)
			(xy 434.590118 -360.110796) (xy 434.580405 -360.018503) (xy 434.579776 -359.972102) (xy 434.5802 -359.930986)
			(xy 434.587788 -359.849105) (xy 434.602898 -359.768273) (xy 434.625402 -359.68918) (xy 434.655109 -359.612502)
			(xy 434.691763 -359.538891) (xy 434.735054 -359.468977) (xy 434.784611 -359.403355) (xy 434.840011 -359.342586)
			(xy 434.900783 -359.287188) (xy 434.966406 -359.237634) (xy 435.036323 -359.194346) (xy 435.109935 -359.157694)
			(xy 435.186615 -359.127991) (xy 435.265708 -359.10549) (xy 435.346541 -359.090383) (xy 435.428422 -359.082799)
			(xy 435.469538 -359.08234) (xy 435.51594 -359.082957) (xy 435.608238 -359.09265) (xy 435.699023 -359.111907)
			(xy 435.787308 -359.140517) (xy 435.829964 -359.158794) (xy 435.839906 -359.1626) (xy 435.86117 -359.1626)
			(xy 435.871112 -359.158794) (xy 435.913767 -359.140517) (xy 436.002057 -359.111928) (xy 436.092842 -359.092675)
			(xy 436.185137 -359.082967) (xy 436.231538 -359.08234) (xy 436.272653 -359.082777) (xy 436.354532 -359.090367)
			(xy 436.435361 -359.10548) (xy 436.514451 -359.127986) (xy 436.591127 -359.157693) (xy 436.664735 -359.194349)
			(xy 436.734647 -359.237639) (xy 436.800266 -359.287195) (xy 436.861034 -359.342595) (xy 436.91643 -359.403364)
			(xy 436.965984 -359.468986) (xy 437.009271 -359.5389) (xy 437.045923 -359.61251) (xy 437.075627 -359.689187)
			(xy 437.098129 -359.768278) (xy 437.113238 -359.849108) (xy 437.120825 -359.930987) (xy 437.1213 -359.972102)
			(xy 437.120676 -360.018504) (xy 437.110985 -360.110802) (xy 437.091731 -360.201587) (xy 437.063122 -360.289872)
			(xy 437.044846 -360.332528) (xy 437.041037 -360.34247) (xy 437.041038 -360.363734) (xy 437.044846 -360.373676)
			(xy 437.063108 -360.416337) (xy 437.091701 -360.504625) (xy 437.110959 -360.595408) (xy 437.120671 -360.687701)
			(xy 437.1213 -360.734102) (xy 437.120676 -360.780504) (xy 437.110985 -360.872802) (xy 437.091731 -360.963587)
			(xy 437.063122 -361.051872) (xy 437.044846 -361.094528) (xy 437.041037 -361.10447) (xy 437.041038 -361.125734)
			(xy 437.044846 -361.135676) (xy 437.063108 -361.178337) (xy 437.091701 -361.266625) (xy 437.110959 -361.357408)
			(xy 437.120671 -361.449701) (xy 437.1213 -361.496102) (xy 437.120789 -361.537215) (xy 437.113202 -361.619091)
			(xy 437.098093 -361.699917) (xy 437.075592 -361.779004) (xy 437.045889 -361.855678) (xy 437.009238 -361.929285)
			(xy 436.965952 -361.999196) (xy 436.916401 -362.064814) (xy 436.861007 -362.125581) (xy 436.800242 -362.180978)
			(xy 436.734625 -362.230532) (xy 436.664716 -362.273821) (xy 436.591111 -362.310474) (xy 436.514439 -362.34018)
			(xy 436.435352 -362.362685) (xy 436.354526 -362.377797) (xy 436.272651 -362.385387) (xy 436.231538 -362.385864)
			(xy 436.185135 -362.385256) (xy 436.092838 -362.37556) (xy 436.002052 -362.356301) (xy 435.913768 -362.327688)
			(xy 435.871112 -362.30941) (xy 435.86117 -362.305604) (xy 435.839906 -362.305604) (xy 435.829964 -362.30941)
			(xy 435.787299 -362.327662) (xy 435.699012 -362.356257) (xy 435.608231 -362.375517) (xy 435.515939 -362.385233)
			(xy 435.469538 -362.385864) (xy 435.428424 -362.385365) (xy 435.346546 -362.377782) (xy 435.265717 -362.362675)
			(xy 435.186627 -362.340175) (xy 435.10995 -362.310473) (xy 435.036341 -362.273823) (xy 434.966428 -362.230538)
			(xy 434.900807 -362.180986) (xy 434.840038 -362.12559) (xy 434.78464 -362.064824) (xy 434.735085 -361.999205)
			(xy 434.691796 -361.929294) (xy 434.655143 -361.855686) (xy 434.625438 -361.779011) (xy 434.602934 -361.699922)
			(xy 434.587824 -361.619094) (xy 434.580237 -361.537216) (xy 434.579776 -361.496102) (xy 433.370787 -361.496102)
			(xy 433.386657 -361.564778) (xy 433.402618 -361.669392) (xy 433.410622 -361.774914) (xy 433.411122 -361.827826)
			(xy 433.410622 -361.880738) (xy 433.402618 -361.98626) (xy 433.386657 -362.090874) (xy 433.36283 -362.193981)
			(xy 433.331273 -362.294992) (xy 433.292168 -362.393326) (xy 433.245737 -362.488421) (xy 433.192248 -362.579732)
			(xy 433.132006 -362.666736) (xy 433.065356 -362.748936) (xy 432.992681 -362.825859) (xy 432.914397 -362.897065)
			(xy 432.830951 -362.962147) (xy 432.742822 -363.020732) (xy 432.650515 -363.072484) (xy 432.554558 -363.117106)
			(xy 432.455501 -363.154344) (xy 432.353912 -363.183984) (xy 432.250372 -363.205855) (xy 432.145475 -363.219834)
			(xy 432.039821 -363.225839) (xy 431.934015 -363.223836) (xy 431.828664 -363.213837) (xy 431.724371 -363.195899)
			(xy 431.621733 -363.170125) (xy 431.521338 -363.136663) (xy 431.423761 -363.095703) (xy 431.329562 -363.047481)
			(xy 431.239279 -362.992274) (xy 431.15343 -362.930396) (xy 431.072507 -362.862203) (xy 430.996973 -362.788085)
			(xy 430.927261 -362.708467) (xy 430.86377 -362.623804) (xy 430.806863 -362.534583) (xy 430.756867 -362.441313)
			(xy 430.714069 -362.344529) (xy 430.678712 -362.244785) (xy 430.651001 -362.142653) (xy 430.631092 -362.038718)
			(xy 430.619102 -361.933575) (xy 430.615097 -361.827826) (xy 260.401302 -361.827826) (xy 260.352937 -361.927227)
			(xy 260.283563 -362.051412) (xy 260.207274 -362.171473) (xy 260.124316 -362.287026) (xy 260.034952 -362.3977)
			(xy 259.939471 -362.503142) (xy 259.838177 -362.603012) (xy 259.731395 -362.696992) (xy 259.619467 -362.78478)
			(xy 259.502751 -362.866096) (xy 259.381623 -362.940678) (xy 259.256469 -363.008287) (xy 259.12769 -363.068708)
			(xy 258.995699 -363.121746) (xy 258.860919 -363.167232) (xy 258.723781 -363.20502) (xy 258.584726 -363.234989)
			(xy 258.444197 -363.257043) (xy 258.302646 -363.271111) (xy 258.160526 -363.277148) (xy 258.018291 -363.275135)
			(xy 257.876399 -363.265078) (xy 257.735303 -363.24701) (xy 257.595454 -363.220989) (xy 257.457302 -363.187097)
			(xy 257.321289 -363.145443) (xy 257.18785 -363.096161) (xy 257.057413 -363.039409) (xy 256.930396 -362.975368)
			(xy 256.807205 -362.904244) (xy 256.688236 -362.826264) (xy 256.573868 -362.741678) (xy 256.464469 -362.650758)
			(xy 256.36039 -362.553794) (xy 256.261962 -362.451097) (xy 256.169503 -362.342995) (xy 256.083307 -362.229836)
			(xy 256.003652 -362.111982) (xy 255.930791 -361.98981) (xy 255.86496 -361.863712) (xy 255.806367 -361.734091)
			(xy 255.755202 -361.601363) (xy 255.711628 -361.465953) (xy 255.675784 -361.328294) (xy 255.647786 -361.188828)
			(xy 255.627723 -361.048002) (xy 255.61566 -360.906266) (xy 255.611635 -360.764074) (xy 216.187782 -360.764074)
			(xy 216.187279 -360.835198) (xy 216.179231 -360.977219) (xy 216.163162 -361.118557) (xy 216.139121 -361.258759)
			(xy 216.107188 -361.397377) (xy 216.067463 -361.533966) (xy 216.020075 -361.668089) (xy 215.965174 -361.799316)
			(xy 215.902937 -361.927227) (xy 215.833563 -362.051412) (xy 215.757274 -362.171473) (xy 215.674316 -362.287026)
			(xy 215.584952 -362.3977) (xy 215.489471 -362.503142) (xy 215.388177 -362.603012) (xy 215.281395 -362.696992)
			(xy 215.169467 -362.78478) (xy 215.052751 -362.866096) (xy 214.931623 -362.940678) (xy 214.806469 -363.008287)
			(xy 214.67769 -363.068708) (xy 214.545699 -363.121746) (xy 214.410919 -363.167232) (xy 214.273781 -363.20502)
			(xy 214.134726 -363.234989) (xy 213.994197 -363.257043) (xy 213.852646 -363.271111) (xy 213.710526 -363.277148)
			(xy 213.568291 -363.275135) (xy 213.426399 -363.265078) (xy 213.285303 -363.24701) (xy 213.145454 -363.220989)
			(xy 213.007302 -363.187097) (xy 212.871289 -363.145443) (xy 212.73785 -363.096161) (xy 212.607413 -363.039409)
			(xy 212.480396 -362.975368) (xy 212.357205 -362.904244) (xy 212.238236 -362.826264) (xy 212.123868 -362.741678)
			(xy 212.014469 -362.650758) (xy 211.91039 -362.553794) (xy 211.811962 -362.451097) (xy 211.719503 -362.342995)
			(xy 211.633307 -362.229836) (xy 211.553652 -362.111982) (xy 211.480791 -361.98981) (xy 211.41496 -361.863712)
			(xy 211.356367 -361.734091) (xy 211.305202 -361.601363) (xy 211.261628 -361.465953) (xy 211.225784 -361.328294)
			(xy 211.197786 -361.188828) (xy 211.177723 -361.048002) (xy 211.16566 -360.906266) (xy 211.161635 -360.764074)
			(xy 187.684417 -360.764074) (xy 187.675402 -360.849986) (xy 187.656207 -360.94064) (xy 187.627695 -361.028809)
			(xy 187.60948 -361.071414) (xy 187.605683 -361.081359) (xy 187.605679 -361.10262) (xy 187.60948 -361.112562)
			(xy 187.627719 -361.155227) (xy 187.656265 -361.243518) (xy 187.67546 -361.334302) (xy 187.685094 -361.426592)
			(xy 187.68568 -361.472988) (xy 187.685095 -361.519384) (xy 187.675451 -361.611672) (xy 187.656256 -361.702456)
			(xy 187.627718 -361.790749) (xy 187.60948 -361.833414) (xy 187.605683 -361.843359) (xy 187.605679 -361.86462)
			(xy 187.60948 -361.874562) (xy 187.627696 -361.917167) (xy 187.656216 -362.005334) (xy 187.67541 -362.095988)
			(xy 187.685071 -362.188148) (xy 187.68568 -362.23448) (xy 187.68568 -362.234988) (xy 187.685236 -362.276092)
			(xy 187.677652 -362.357949) (xy 187.664078 -362.430568) (xy 190.281567 -362.430568) (xy 190.285572 -362.324819)
			(xy 190.297562 -362.219676) (xy 190.317471 -362.115741) (xy 190.345182 -362.013609) (xy 190.380539 -361.913865)
			(xy 190.423337 -361.817081) (xy 190.473333 -361.723811) (xy 190.53024 -361.63459) (xy 190.593731 -361.549927)
			(xy 190.663443 -361.470309) (xy 190.738977 -361.396191) (xy 190.8199 -361.327998) (xy 190.905749 -361.26612)
			(xy 190.996032 -361.210913) (xy 191.090231 -361.162691) (xy 191.187808 -361.121731) (xy 191.288203 -361.088269)
			(xy 191.390841 -361.062495) (xy 191.495134 -361.044557) (xy 191.600485 -361.034558) (xy 191.706291 -361.032555)
			(xy 191.811945 -361.03856) (xy 191.916842 -361.052539) (xy 192.020382 -361.07441) (xy 192.121971 -361.10405)
			(xy 192.221028 -361.141288) (xy 192.316985 -361.18591) (xy 192.409292 -361.237662) (xy 192.497421 -361.296247)
			(xy 192.580867 -361.361329) (xy 192.659151 -361.432535) (xy 192.731826 -361.509458) (xy 192.798476 -361.591658)
			(xy 192.858718 -361.678662) (xy 192.912207 -361.769973) (xy 192.958638 -361.865068) (xy 192.997743 -361.963402)
			(xy 193.0293 -362.064413) (xy 193.053127 -362.16752) (xy 193.069088 -362.272134) (xy 193.077092 -362.377656)
			(xy 193.077592 -362.430568) (xy 193.077092 -362.48348) (xy 193.069088 -362.589002) (xy 193.053127 -362.693616)
			(xy 193.0293 -362.796723) (xy 192.997743 -362.897734) (xy 192.958638 -362.996068) (xy 192.912207 -363.091163)
			(xy 192.858718 -363.182474) (xy 192.798476 -363.269478) (xy 192.731826 -363.351678) (xy 192.659151 -363.428601)
			(xy 192.580867 -363.499807) (xy 192.497421 -363.564889) (xy 192.409292 -363.623474) (xy 192.316985 -363.675226)
			(xy 192.221028 -363.719848) (xy 192.121971 -363.757086) (xy 192.020382 -363.786726) (xy 191.916842 -363.808597)
			(xy 191.811945 -363.822576) (xy 191.706291 -363.828581) (xy 191.600485 -363.826578) (xy 191.495134 -363.816579)
			(xy 191.390841 -363.798641) (xy 191.288203 -363.772867) (xy 191.187808 -363.739405) (xy 191.090231 -363.698445)
			(xy 190.996032 -363.650223) (xy 190.905749 -363.595016) (xy 190.8199 -363.533138) (xy 190.738977 -363.464945)
			(xy 190.663443 -363.390827) (xy 190.593731 -363.311209) (xy 190.53024 -363.226546) (xy 190.473333 -363.137325)
			(xy 190.423337 -363.044055) (xy 190.380539 -362.947271) (xy 190.345182 -362.847527) (xy 190.317471 -362.745395)
			(xy 190.297562 -362.64146) (xy 190.285572 -362.536317) (xy 190.281567 -362.430568) (xy 187.664078 -362.430568)
			(xy 187.662547 -362.438757) (xy 187.64005 -362.517826) (xy 187.610354 -362.594483) (xy 187.573711 -362.668072)
			(xy 187.530434 -362.737966) (xy 187.480892 -362.803569) (xy 187.425509 -362.86432) (xy 187.364756 -362.919703)
			(xy 187.299153 -362.969243) (xy 187.229258 -363.012519) (xy 187.155668 -363.04916) (xy 187.079011 -363.078856)
			(xy 186.999941 -363.101351) (xy 186.919133 -363.116454) (xy 186.837276 -363.124037) (xy 186.796172 -363.124496)
			(xy 186.795664 -363.124496) (xy 186.749333 -363.123866) (xy 186.657176 -363.114202) (xy 186.566521 -363.095013)
			(xy 186.478352 -363.066508) (xy 186.435746 -363.048296) (xy 186.425804 -363.04449) (xy 186.40454 -363.04449)
			(xy 186.394598 -363.048296) (xy 186.351999 -363.066527) (xy 186.26383 -363.095042) (xy 186.173173 -363.114232)
			(xy 186.081013 -363.123889) (xy 186.03468 -363.124496) (xy 186.034172 -363.124496) (xy 185.993069 -363.12406)
			(xy 185.911213 -363.116473) (xy 185.830407 -363.101365) (xy 185.751339 -363.078866) (xy 185.674684 -363.049167)
			(xy 185.601097 -363.012522) (xy 185.531204 -362.969244) (xy 185.465603 -362.919702) (xy 185.404853 -362.864319)
			(xy 185.349472 -362.803566) (xy 185.299933 -362.737963) (xy 185.256658 -362.668068) (xy 185.220017 -362.594479)
			(xy 185.190322 -362.517823) (xy 185.167826 -362.438755) (xy 185.152722 -362.357947) (xy 185.145138 -362.276091)
			(xy 185.144664 -362.234988) (xy 166.497508 -362.234988) (xy 166.497508 -362.396278) (xy 166.497022 -362.423547)
			(xy 166.48926 -362.477531) (xy 166.473895 -362.529861) (xy 166.451238 -362.579471) (xy 166.421752 -362.625352)
			(xy 166.386037 -362.666569) (xy 166.34482 -362.702284) (xy 166.298939 -362.73177) (xy 166.249329 -362.754427)
			(xy 166.196999 -362.769792) (xy 166.143015 -362.777554) (xy 166.088477 -362.777554) (xy 166.034493 -362.769792)
			(xy 165.982163 -362.754427) (xy 165.932553 -362.73177) (xy 165.886672 -362.702284) (xy 165.845455 -362.666569)
			(xy 165.80974 -362.625352) (xy 165.780254 -362.579471) (xy 165.757597 -362.529861) (xy 165.742232 -362.477531)
			(xy 165.73447 -362.423547) (xy 165.733984 -362.396278) (xy 10.079022 -362.396278) (xy 10.05934 -362.458146)
			(xy 10.012689 -362.578565) (xy 9.958714 -362.695884) (xy 9.897619 -362.809658) (xy 9.829636 -362.919455)
			(xy 9.755022 -363.024858) (xy 9.674061 -363.125468) (xy 9.587061 -363.220903) (xy 9.49435 -363.310802)
			(xy 9.39628 -363.394823) (xy 9.293225 -363.472647) (xy 9.185574 -363.543979) (xy 9.073735 -363.608549)
			(xy 8.958134 -363.666111) (xy 8.839209 -363.716448) (xy 8.71741 -363.759368) (xy 8.5932 -363.794709)
			(xy 8.467051 -363.822336) (xy 8.339439 -363.842145) (xy 8.21085 -363.854061) (xy 8.081772 -363.858038)
			(xy 7.952694 -363.854061) (xy 7.824105 -363.842145) (xy 7.696493 -363.822336) (xy 7.570344 -363.794709)
			(xy 7.446134 -363.759368) (xy 7.324335 -363.716448) (xy 7.20541 -363.666111) (xy 7.089809 -363.608549)
			(xy 6.97797 -363.543979) (xy 6.870319 -363.472647) (xy 6.767264 -363.394823) (xy 6.669194 -363.310802)
			(xy 6.576483 -363.220903) (xy 6.489483 -363.125468) (xy 6.408522 -363.024858) (xy 6.333908 -362.919455)
			(xy 6.265925 -362.809658) (xy 6.20483 -362.695884) (xy 6.150855 -362.578565) (xy 6.104204 -362.458146)
			(xy 6.065055 -362.335083) (xy 6.033556 -362.209844) (xy 6.009827 -362.082903) (xy 5.993957 -361.954743)
			(xy 5.986007 -361.825848) (xy 2.509012 -361.825848) (xy 2.509012 -369.062565) (xy 44.335754 -369.062565)
			(xy 44.335754 -369.008035) (xy 44.343514 -368.95406) (xy 44.358876 -368.901738) (xy 44.381527 -368.852135)
			(xy 44.411006 -368.806259) (xy 44.446714 -368.765046) (xy 44.487923 -368.729334) (xy 44.533794 -368.699849)
			(xy 44.583395 -368.677192) (xy 44.635715 -368.661824) (xy 44.689689 -368.654057) (xy 44.716954 -368.653568)
			(xy 45.580554 -368.653568) (xy 45.607829 -368.653968) (xy 45.661825 -368.661726) (xy 45.714168 -368.677089)
			(xy 45.763791 -368.699746) (xy 45.809684 -368.729235) (xy 45.850912 -368.764955) (xy 45.886638 -368.80618)
			(xy 45.916132 -368.852069) (xy 45.938795 -368.901689) (xy 45.954164 -368.95403) (xy 45.961928 -369.008025)
			(xy 45.961928 -369.062565) (xy 51.142954 -369.062565) (xy 51.142954 -369.008035) (xy 51.150714 -368.95406)
			(xy 51.166076 -368.901738) (xy 51.188727 -368.852135) (xy 51.218206 -368.806259) (xy 51.253914 -368.765046)
			(xy 51.295123 -368.729334) (xy 51.340994 -368.699849) (xy 51.390595 -368.677192) (xy 51.442915 -368.661824)
			(xy 51.496889 -368.654057) (xy 51.524154 -368.653568) (xy 52.387754 -368.653568) (xy 52.415029 -368.653968)
			(xy 52.469025 -368.661726) (xy 52.521368 -368.677089) (xy 52.570991 -368.699746) (xy 52.616884 -368.729235)
			(xy 52.658112 -368.764955) (xy 52.693838 -368.80618) (xy 52.723332 -368.852069) (xy 52.745995 -368.901689)
			(xy 52.761364 -368.95403) (xy 52.769128 -369.008025) (xy 52.769128 -369.062565) (xy 57.950154 -369.062565)
			(xy 57.950154 -369.008035) (xy 57.957914 -368.95406) (xy 57.973276 -368.901738) (xy 57.995927 -368.852135)
			(xy 58.025406 -368.806259) (xy 58.061114 -368.765046) (xy 58.102323 -368.729334) (xy 58.148194 -368.699849)
			(xy 58.197795 -368.677192) (xy 58.250115 -368.661824) (xy 58.304089 -368.654057) (xy 58.331354 -368.653568)
			(xy 59.194954 -368.653568) (xy 59.222229 -368.653968) (xy 59.276225 -368.661726) (xy 59.328568 -368.677089)
			(xy 59.378191 -368.699746) (xy 59.424084 -368.729235) (xy 59.465312 -368.764955) (xy 59.501038 -368.80618)
			(xy 59.530532 -368.852069) (xy 59.553195 -368.901689) (xy 59.568564 -368.95403) (xy 59.576328 -369.008025)
			(xy 59.576328 -369.062565) (xy 64.757354 -369.062565) (xy 64.757354 -369.008035) (xy 64.765114 -368.95406)
			(xy 64.780476 -368.901738) (xy 64.803127 -368.852135) (xy 64.832606 -368.806259) (xy 64.868314 -368.765046)
			(xy 64.909523 -368.729334) (xy 64.955394 -368.699849) (xy 65.004995 -368.677192) (xy 65.057315 -368.661824)
			(xy 65.111289 -368.654057) (xy 65.138554 -368.653568) (xy 66.002154 -368.653568) (xy 66.029429 -368.653968)
			(xy 66.083425 -368.661726) (xy 66.135768 -368.677089) (xy 66.185391 -368.699746) (xy 66.231284 -368.729235)
			(xy 66.272512 -368.764955) (xy 66.308238 -368.80618) (xy 66.337732 -368.852069) (xy 66.360395 -368.901689)
			(xy 66.375764 -368.95403) (xy 66.383528 -369.008025) (xy 66.383528 -369.062565) (xy 68.160954 -369.062565)
			(xy 68.160954 -369.008035) (xy 68.168714 -368.95406) (xy 68.184076 -368.901738) (xy 68.206727 -368.852135)
			(xy 68.236206 -368.806259) (xy 68.271914 -368.765046) (xy 68.313123 -368.729334) (xy 68.358994 -368.699849)
			(xy 68.408595 -368.677192) (xy 68.460915 -368.661824) (xy 68.514889 -368.654057) (xy 68.542154 -368.653568)
			(xy 69.405754 -368.653568) (xy 69.433029 -368.653968) (xy 69.487025 -368.661726) (xy 69.539368 -368.677089)
			(xy 69.588991 -368.699746) (xy 69.634884 -368.729235) (xy 69.676112 -368.764955) (xy 69.711838 -368.80618)
			(xy 69.741332 -368.852069) (xy 69.763995 -368.901689) (xy 69.779364 -368.95403) (xy 69.787128 -369.008025)
			(xy 69.787128 -369.062569) (xy 76.863431 -369.062569) (xy 76.863431 -369.008031) (xy 76.871193 -368.954048)
			(xy 76.886558 -368.90172) (xy 76.909214 -368.85211) (xy 76.9387 -368.80623) (xy 76.974414 -368.765013)
			(xy 77.015632 -368.729298) (xy 77.061512 -368.699813) (xy 77.111121 -368.677157) (xy 77.16345 -368.661793)
			(xy 77.217433 -368.654031) (xy 77.244702 -368.653568) (xy 78.108302 -368.653568) (xy 78.135573 -368.653995)
			(xy 78.189561 -368.661757) (xy 78.241894 -368.677124) (xy 78.291508 -368.699782) (xy 78.337393 -368.72927)
			(xy 78.378613 -368.764988) (xy 78.414331 -368.806209) (xy 78.443819 -368.852093) (xy 78.466477 -368.901707)
			(xy 78.481843 -368.954041) (xy 78.489606 -369.008029) (xy 78.489606 -369.062569) (xy 83.670631 -369.062569)
			(xy 83.670631 -369.008031) (xy 83.678393 -368.954048) (xy 83.693758 -368.90172) (xy 83.716414 -368.85211)
			(xy 83.7459 -368.80623) (xy 83.781614 -368.765013) (xy 83.822832 -368.729298) (xy 83.868712 -368.699813)
			(xy 83.918321 -368.677157) (xy 83.97065 -368.661793) (xy 84.024633 -368.654031) (xy 84.051902 -368.653568)
			(xy 84.915502 -368.653568) (xy 84.942773 -368.653995) (xy 84.996761 -368.661757) (xy 85.049094 -368.677124)
			(xy 85.098708 -368.699782) (xy 85.144593 -368.72927) (xy 85.185813 -368.764988) (xy 85.221531 -368.806209)
			(xy 85.251019 -368.852093) (xy 85.273677 -368.901707) (xy 85.289043 -368.954041) (xy 85.296806 -369.008029)
			(xy 85.296806 -369.062569) (xy 90.477831 -369.062569) (xy 90.477831 -369.008031) (xy 90.485593 -368.954048)
			(xy 90.500958 -368.90172) (xy 90.523614 -368.85211) (xy 90.5531 -368.80623) (xy 90.588814 -368.765013)
			(xy 90.630032 -368.729298) (xy 90.675912 -368.699813) (xy 90.725521 -368.677157) (xy 90.77785 -368.661793)
			(xy 90.831833 -368.654031) (xy 90.859102 -368.653568) (xy 91.722702 -368.653568) (xy 91.749973 -368.653995)
			(xy 91.803961 -368.661757) (xy 91.856294 -368.677124) (xy 91.905908 -368.699782) (xy 91.951793 -368.72927)
			(xy 91.993013 -368.764988) (xy 92.028731 -368.806209) (xy 92.058219 -368.852093) (xy 92.080877 -368.901707)
			(xy 92.096243 -368.954041) (xy 92.104006 -369.008029) (xy 92.104006 -369.062569) (xy 97.285031 -369.062569)
			(xy 97.285031 -369.008031) (xy 97.292793 -368.954048) (xy 97.308158 -368.90172) (xy 97.330814 -368.85211)
			(xy 97.3603 -368.80623) (xy 97.396014 -368.765013) (xy 97.437232 -368.729298) (xy 97.483112 -368.699813)
			(xy 97.532721 -368.677157) (xy 97.58505 -368.661793) (xy 97.639033 -368.654031) (xy 97.666302 -368.653568)
			(xy 98.529902 -368.653568) (xy 98.557173 -368.653995) (xy 98.611161 -368.661757) (xy 98.663494 -368.677124)
			(xy 98.713108 -368.699782) (xy 98.758993 -368.72927) (xy 98.800213 -368.764988) (xy 98.835931 -368.806209)
			(xy 98.865419 -368.852093) (xy 98.888077 -368.901707) (xy 98.903443 -368.954041) (xy 98.911206 -369.008029)
			(xy 98.911206 -369.062569) (xy 100.688631 -369.062569) (xy 100.688631 -369.008031) (xy 100.696393 -368.954048)
			(xy 100.711758 -368.90172) (xy 100.734414 -368.85211) (xy 100.7639 -368.80623) (xy 100.799614 -368.765013)
			(xy 100.840832 -368.729298) (xy 100.886712 -368.699813) (xy 100.936321 -368.677157) (xy 100.98865 -368.661793)
			(xy 101.042633 -368.654031) (xy 101.069902 -368.653568) (xy 101.933502 -368.653568) (xy 101.960773 -368.653995)
			(xy 102.014761 -368.661757) (xy 102.067094 -368.677124) (xy 102.116708 -368.699782) (xy 102.162593 -368.72927)
			(xy 102.203813 -368.764988) (xy 102.239531 -368.806209) (xy 102.269019 -368.852093) (xy 102.291677 -368.901707)
			(xy 102.307043 -368.954041) (xy 102.314806 -369.008029) (xy 102.314806 -369.062567) (xy 111.435654 -369.062567)
			(xy 111.435654 -369.008033) (xy 111.443415 -368.954054) (xy 111.458779 -368.901729) (xy 111.481433 -368.852123)
			(xy 111.510917 -368.806246) (xy 111.546629 -368.765031) (xy 111.587842 -368.729319) (xy 111.633719 -368.699835)
			(xy 111.683325 -368.677181) (xy 111.73565 -368.661816) (xy 111.789629 -368.654055) (xy 111.816896 -368.653568)
			(xy 112.680496 -368.653568) (xy 112.707769 -368.653971) (xy 112.761761 -368.661734) (xy 112.814098 -368.677101)
			(xy 112.863716 -368.69976) (xy 112.909603 -368.72925) (xy 112.950827 -368.76497) (xy 112.986548 -368.806193)
			(xy 113.016038 -368.852081) (xy 113.038698 -368.901698) (xy 113.054066 -368.954035) (xy 113.061828 -369.008027)
			(xy 113.061828 -369.062567) (xy 118.242854 -369.062567) (xy 118.242854 -369.008033) (xy 118.250615 -368.954054)
			(xy 118.265979 -368.901729) (xy 118.288633 -368.852123) (xy 118.318117 -368.806246) (xy 118.353829 -368.765031)
			(xy 118.395042 -368.729319) (xy 118.440919 -368.699835) (xy 118.490525 -368.677181) (xy 118.54285 -368.661816)
			(xy 118.596829 -368.654055) (xy 118.624096 -368.653568) (xy 119.487696 -368.653568) (xy 119.514969 -368.653971)
			(xy 119.568961 -368.661734) (xy 119.621298 -368.677101) (xy 119.670916 -368.69976) (xy 119.716803 -368.72925)
			(xy 119.758027 -368.76497) (xy 119.793748 -368.806193) (xy 119.823238 -368.852081) (xy 119.845898 -368.901698)
			(xy 119.861266 -368.954035) (xy 119.869028 -369.008027) (xy 119.869028 -369.062567) (xy 125.050054 -369.062567)
			(xy 125.050054 -369.008033) (xy 125.057815 -368.954054) (xy 125.073179 -368.901729) (xy 125.095833 -368.852123)
			(xy 125.125317 -368.806246) (xy 125.161029 -368.765031) (xy 125.202242 -368.729319) (xy 125.248119 -368.699835)
			(xy 125.297725 -368.677181) (xy 125.35005 -368.661816) (xy 125.404029 -368.654055) (xy 125.431296 -368.653568)
			(xy 126.294896 -368.653568) (xy 126.322169 -368.653971) (xy 126.376161 -368.661734) (xy 126.428498 -368.677101)
			(xy 126.478116 -368.69976) (xy 126.524003 -368.72925) (xy 126.565227 -368.76497) (xy 126.600948 -368.806193)
			(xy 126.630438 -368.852081) (xy 126.653098 -368.901698) (xy 126.668466 -368.954035) (xy 126.676228 -369.008027)
			(xy 126.676228 -369.062567) (xy 131.857254 -369.062567) (xy 131.857254 -369.008033) (xy 131.865015 -368.954054)
			(xy 131.880379 -368.901729) (xy 131.903033 -368.852123) (xy 131.932517 -368.806246) (xy 131.968229 -368.765031)
			(xy 132.009442 -368.729319) (xy 132.055319 -368.699835) (xy 132.104925 -368.677181) (xy 132.15725 -368.661816)
			(xy 132.211229 -368.654055) (xy 132.238496 -368.653568) (xy 133.102096 -368.653568) (xy 133.129369 -368.653971)
			(xy 133.183361 -368.661734) (xy 133.235698 -368.677101) (xy 133.285316 -368.69976) (xy 133.331203 -368.72925)
			(xy 133.372427 -368.76497) (xy 133.408148 -368.806193) (xy 133.437638 -368.852081) (xy 133.460298 -368.901698)
			(xy 133.475666 -368.954035) (xy 133.483428 -369.008027) (xy 133.483428 -369.062567) (xy 135.260854 -369.062567)
			(xy 135.260854 -369.008033) (xy 135.268615 -368.954054) (xy 135.283979 -368.901729) (xy 135.306633 -368.852123)
			(xy 135.336117 -368.806246) (xy 135.371829 -368.765031) (xy 135.413042 -368.729319) (xy 135.458919 -368.699835)
			(xy 135.508525 -368.677181) (xy 135.56085 -368.661816) (xy 135.614829 -368.654055) (xy 135.642096 -368.653568)
			(xy 136.505696 -368.653568) (xy 136.532969 -368.653971) (xy 136.586961 -368.661734) (xy 136.639298 -368.677101)
			(xy 136.688916 -368.69976) (xy 136.734803 -368.72925) (xy 136.776027 -368.76497) (xy 136.811748 -368.806193)
			(xy 136.841238 -368.852081) (xy 136.863898 -368.901698) (xy 136.879266 -368.954035) (xy 136.887028 -369.008027)
			(xy 136.887028 -369.062573) (xy 136.879266 -369.116565) (xy 136.863898 -369.168902) (xy 136.841238 -369.218519)
			(xy 136.811748 -369.264407) (xy 136.776027 -369.30563) (xy 136.734803 -369.34135) (xy 136.688916 -369.37084)
			(xy 136.639298 -369.393499) (xy 136.586961 -369.408866) (xy 136.532969 -369.416629) (xy 136.505696 -369.417092)
			(xy 135.642096 -369.417092) (xy 135.614829 -369.416545) (xy 135.56085 -369.408784) (xy 135.508525 -369.393419)
			(xy 135.458919 -369.370765) (xy 135.413042 -369.341281) (xy 135.371829 -369.305569) (xy 135.336117 -369.264354)
			(xy 135.306633 -369.218477) (xy 135.283979 -369.168871) (xy 135.268615 -369.116546) (xy 135.260854 -369.062567)
			(xy 133.483428 -369.062567) (xy 133.483428 -369.062573) (xy 133.475666 -369.116565) (xy 133.460298 -369.168902)
			(xy 133.437638 -369.218519) (xy 133.408148 -369.264407) (xy 133.372427 -369.30563) (xy 133.331203 -369.34135)
			(xy 133.285316 -369.37084) (xy 133.235698 -369.393499) (xy 133.183361 -369.408866) (xy 133.129369 -369.416629)
			(xy 133.102096 -369.417092) (xy 132.238496 -369.417092) (xy 132.211229 -369.416545) (xy 132.15725 -369.408784)
			(xy 132.104925 -369.393419) (xy 132.055319 -369.370765) (xy 132.009442 -369.341281) (xy 131.968229 -369.305569)
			(xy 131.932517 -369.264354) (xy 131.903033 -369.218477) (xy 131.880379 -369.168871) (xy 131.865015 -369.116546)
			(xy 131.857254 -369.062567) (xy 126.676228 -369.062567) (xy 126.676228 -369.062573) (xy 126.668466 -369.116565)
			(xy 126.653098 -369.168902) (xy 126.630438 -369.218519) (xy 126.600948 -369.264407) (xy 126.565227 -369.30563)
			(xy 126.524003 -369.34135) (xy 126.478116 -369.37084) (xy 126.428498 -369.393499) (xy 126.376161 -369.408866)
			(xy 126.322169 -369.416629) (xy 126.294896 -369.417092) (xy 125.431296 -369.417092) (xy 125.404029 -369.416545)
			(xy 125.35005 -369.408784) (xy 125.297725 -369.393419) (xy 125.248119 -369.370765) (xy 125.202242 -369.341281)
			(xy 125.161029 -369.305569) (xy 125.125317 -369.264354) (xy 125.095833 -369.218477) (xy 125.073179 -369.168871)
			(xy 125.057815 -369.116546) (xy 125.050054 -369.062567) (xy 119.869028 -369.062567) (xy 119.869028 -369.062573)
			(xy 119.861266 -369.116565) (xy 119.845898 -369.168902) (xy 119.823238 -369.218519) (xy 119.793748 -369.264407)
			(xy 119.758027 -369.30563) (xy 119.716803 -369.34135) (xy 119.670916 -369.37084) (xy 119.621298 -369.393499)
			(xy 119.568961 -369.408866) (xy 119.514969 -369.416629) (xy 119.487696 -369.417092) (xy 118.624096 -369.417092)
			(xy 118.596829 -369.416545) (xy 118.54285 -369.408784) (xy 118.490525 -369.393419) (xy 118.440919 -369.370765)
			(xy 118.395042 -369.341281) (xy 118.353829 -369.305569) (xy 118.318117 -369.264354) (xy 118.288633 -369.218477)
			(xy 118.265979 -369.168871) (xy 118.250615 -369.116546) (xy 118.242854 -369.062567) (xy 113.061828 -369.062567)
			(xy 113.061828 -369.062573) (xy 113.054066 -369.116565) (xy 113.038698 -369.168902) (xy 113.016038 -369.218519)
			(xy 112.986548 -369.264407) (xy 112.950827 -369.30563) (xy 112.909603 -369.34135) (xy 112.863716 -369.37084)
			(xy 112.814098 -369.393499) (xy 112.761761 -369.408866) (xy 112.707769 -369.416629) (xy 112.680496 -369.417092)
			(xy 111.816896 -369.417092) (xy 111.789629 -369.416545) (xy 111.73565 -369.408784) (xy 111.683325 -369.393419)
			(xy 111.633719 -369.370765) (xy 111.587842 -369.341281) (xy 111.546629 -369.305569) (xy 111.510917 -369.264354)
			(xy 111.481433 -369.218477) (xy 111.458779 -369.168871) (xy 111.443415 -369.116546) (xy 111.435654 -369.062567)
			(xy 102.314806 -369.062567) (xy 102.314806 -369.062571) (xy 102.307043 -369.116559) (xy 102.291677 -369.168893)
			(xy 102.269019 -369.218507) (xy 102.239531 -369.264391) (xy 102.203813 -369.305612) (xy 102.162593 -369.34133)
			(xy 102.116708 -369.370818) (xy 102.067094 -369.393476) (xy 102.014761 -369.408843) (xy 101.960773 -369.416605)
			(xy 101.933502 -369.417092) (xy 101.069902 -369.417092) (xy 101.042633 -369.416569) (xy 100.98865 -369.408807)
			(xy 100.936321 -369.393443) (xy 100.886712 -369.370787) (xy 100.840832 -369.341302) (xy 100.799614 -369.305587)
			(xy 100.7639 -369.26437) (xy 100.734414 -369.21849) (xy 100.711758 -369.16888) (xy 100.696393 -369.116552)
			(xy 100.688631 -369.062569) (xy 98.911206 -369.062569) (xy 98.911206 -369.062571) (xy 98.903443 -369.116559)
			(xy 98.888077 -369.168893) (xy 98.865419 -369.218507) (xy 98.835931 -369.264391) (xy 98.800213 -369.305612)
			(xy 98.758993 -369.34133) (xy 98.713108 -369.370818) (xy 98.663494 -369.393476) (xy 98.611161 -369.408843)
			(xy 98.557173 -369.416605) (xy 98.529902 -369.417092) (xy 97.666302 -369.417092) (xy 97.639033 -369.416569)
			(xy 97.58505 -369.408807) (xy 97.532721 -369.393443) (xy 97.483112 -369.370787) (xy 97.437232 -369.341302)
			(xy 97.396014 -369.305587) (xy 97.3603 -369.26437) (xy 97.330814 -369.21849) (xy 97.308158 -369.16888)
			(xy 97.292793 -369.116552) (xy 97.285031 -369.062569) (xy 92.104006 -369.062569) (xy 92.104006 -369.062571)
			(xy 92.096243 -369.116559) (xy 92.080877 -369.168893) (xy 92.058219 -369.218507) (xy 92.028731 -369.264391)
			(xy 91.993013 -369.305612) (xy 91.951793 -369.34133) (xy 91.905908 -369.370818) (xy 91.856294 -369.393476)
			(xy 91.803961 -369.408843) (xy 91.749973 -369.416605) (xy 91.722702 -369.417092) (xy 90.859102 -369.417092)
			(xy 90.831833 -369.416569) (xy 90.77785 -369.408807) (xy 90.725521 -369.393443) (xy 90.675912 -369.370787)
			(xy 90.630032 -369.341302) (xy 90.588814 -369.305587) (xy 90.5531 -369.26437) (xy 90.523614 -369.21849)
			(xy 90.500958 -369.16888) (xy 90.485593 -369.116552) (xy 90.477831 -369.062569) (xy 85.296806 -369.062569)
			(xy 85.296806 -369.062571) (xy 85.289043 -369.116559) (xy 85.273677 -369.168893) (xy 85.251019 -369.218507)
			(xy 85.221531 -369.264391) (xy 85.185813 -369.305612) (xy 85.144593 -369.34133) (xy 85.098708 -369.370818)
			(xy 85.049094 -369.393476) (xy 84.996761 -369.408843) (xy 84.942773 -369.416605) (xy 84.915502 -369.417092)
			(xy 84.051902 -369.417092) (xy 84.024633 -369.416569) (xy 83.97065 -369.408807) (xy 83.918321 -369.393443)
			(xy 83.868712 -369.370787) (xy 83.822832 -369.341302) (xy 83.781614 -369.305587) (xy 83.7459 -369.26437)
			(xy 83.716414 -369.21849) (xy 83.693758 -369.16888) (xy 83.678393 -369.116552) (xy 83.670631 -369.062569)
			(xy 78.489606 -369.062569) (xy 78.489606 -369.062571) (xy 78.481843 -369.116559) (xy 78.466477 -369.168893)
			(xy 78.443819 -369.218507) (xy 78.414331 -369.264391) (xy 78.378613 -369.305612) (xy 78.337393 -369.34133)
			(xy 78.291508 -369.370818) (xy 78.241894 -369.393476) (xy 78.189561 -369.408843) (xy 78.135573 -369.416605)
			(xy 78.108302 -369.417092) (xy 77.244702 -369.417092) (xy 77.217433 -369.416569) (xy 77.16345 -369.408807)
			(xy 77.111121 -369.393443) (xy 77.061512 -369.370787) (xy 77.015632 -369.341302) (xy 76.974414 -369.305587)
			(xy 76.9387 -369.26437) (xy 76.909214 -369.21849) (xy 76.886558 -369.16888) (xy 76.871193 -369.116552)
			(xy 76.863431 -369.062569) (xy 69.787128 -369.062569) (xy 69.787128 -369.062575) (xy 69.779364 -369.11657)
			(xy 69.763995 -369.168911) (xy 69.741332 -369.218531) (xy 69.711838 -369.26442) (xy 69.676112 -369.305645)
			(xy 69.634884 -369.341365) (xy 69.588991 -369.370854) (xy 69.539368 -369.393511) (xy 69.487025 -369.408874)
			(xy 69.433029 -369.416632) (xy 69.405754 -369.417092) (xy 68.542154 -369.417092) (xy 68.514889 -369.416543)
			(xy 68.460915 -369.408776) (xy 68.408595 -369.393408) (xy 68.358994 -369.370751) (xy 68.313123 -369.341266)
			(xy 68.271914 -369.305554) (xy 68.236206 -369.264341) (xy 68.206727 -369.218465) (xy 68.184076 -369.168862)
			(xy 68.168714 -369.11654) (xy 68.160954 -369.062565) (xy 66.383528 -369.062565) (xy 66.383528 -369.062575)
			(xy 66.375764 -369.11657) (xy 66.360395 -369.168911) (xy 66.337732 -369.218531) (xy 66.308238 -369.26442)
			(xy 66.272512 -369.305645) (xy 66.231284 -369.341365) (xy 66.185391 -369.370854) (xy 66.135768 -369.393511)
			(xy 66.083425 -369.408874) (xy 66.029429 -369.416632) (xy 66.002154 -369.417092) (xy 65.138554 -369.417092)
			(xy 65.111289 -369.416543) (xy 65.057315 -369.408776) (xy 65.004995 -369.393408) (xy 64.955394 -369.370751)
			(xy 64.909523 -369.341266) (xy 64.868314 -369.305554) (xy 64.832606 -369.264341) (xy 64.803127 -369.218465)
			(xy 64.780476 -369.168862) (xy 64.765114 -369.11654) (xy 64.757354 -369.062565) (xy 59.576328 -369.062565)
			(xy 59.576328 -369.062575) (xy 59.568564 -369.11657) (xy 59.553195 -369.168911) (xy 59.530532 -369.218531)
			(xy 59.501038 -369.26442) (xy 59.465312 -369.305645) (xy 59.424084 -369.341365) (xy 59.378191 -369.370854)
			(xy 59.328568 -369.393511) (xy 59.276225 -369.408874) (xy 59.222229 -369.416632) (xy 59.194954 -369.417092)
			(xy 58.331354 -369.417092) (xy 58.304089 -369.416543) (xy 58.250115 -369.408776) (xy 58.197795 -369.393408)
			(xy 58.148194 -369.370751) (xy 58.102323 -369.341266) (xy 58.061114 -369.305554) (xy 58.025406 -369.264341)
			(xy 57.995927 -369.218465) (xy 57.973276 -369.168862) (xy 57.957914 -369.11654) (xy 57.950154 -369.062565)
			(xy 52.769128 -369.062565) (xy 52.769128 -369.062575) (xy 52.761364 -369.11657) (xy 52.745995 -369.168911)
			(xy 52.723332 -369.218531) (xy 52.693838 -369.26442) (xy 52.658112 -369.305645) (xy 52.616884 -369.341365)
			(xy 52.570991 -369.370854) (xy 52.521368 -369.393511) (xy 52.469025 -369.408874) (xy 52.415029 -369.416632)
			(xy 52.387754 -369.417092) (xy 51.524154 -369.417092) (xy 51.496889 -369.416543) (xy 51.442915 -369.408776)
			(xy 51.390595 -369.393408) (xy 51.340994 -369.370751) (xy 51.295123 -369.341266) (xy 51.253914 -369.305554)
			(xy 51.218206 -369.264341) (xy 51.188727 -369.218465) (xy 51.166076 -369.168862) (xy 51.150714 -369.11654)
			(xy 51.142954 -369.062565) (xy 45.961928 -369.062565) (xy 45.961928 -369.062575) (xy 45.954164 -369.11657)
			(xy 45.938795 -369.168911) (xy 45.916132 -369.218531) (xy 45.886638 -369.26442) (xy 45.850912 -369.305645)
			(xy 45.809684 -369.341365) (xy 45.763791 -369.370854) (xy 45.714168 -369.393511) (xy 45.661825 -369.408874)
			(xy 45.607829 -369.416632) (xy 45.580554 -369.417092) (xy 44.716954 -369.417092) (xy 44.689689 -369.416543)
			(xy 44.635715 -369.408776) (xy 44.583395 -369.393408) (xy 44.533794 -369.370751) (xy 44.487923 -369.341266)
			(xy 44.446714 -369.305554) (xy 44.411006 -369.264341) (xy 44.381527 -369.218465) (xy 44.358876 -369.168862)
			(xy 44.343514 -369.11654) (xy 44.335754 -369.062565) (xy 2.509012 -369.062565) (xy 2.509012 -370.206778)
			(xy 138.3665 -370.206778) (xy 138.3665 -369.343178) (xy 138.366986 -369.315909) (xy 138.374748 -369.261925)
			(xy 138.390113 -369.209595) (xy 138.41277 -369.159985) (xy 138.442256 -369.114104) (xy 138.477971 -369.072887)
			(xy 138.519188 -369.037172) (xy 138.565069 -369.007686) (xy 138.614679 -368.985029) (xy 138.667009 -368.969664)
			(xy 138.720993 -368.961902) (xy 138.775531 -368.961902) (xy 138.829515 -368.969664) (xy 138.881845 -368.985029)
			(xy 138.931455 -369.007686) (xy 138.977336 -369.037172) (xy 139.006648 -369.062571) (xy 143.963332 -369.062571)
			(xy 143.963332 -369.008029) (xy 143.971094 -368.954043) (xy 143.986461 -368.901711) (xy 144.009121 -368.852098)
			(xy 144.03861 -368.806216) (xy 144.074329 -368.764998) (xy 144.115551 -368.729284) (xy 144.161437 -368.699799)
			(xy 144.211052 -368.677146) (xy 144.263386 -368.661785) (xy 144.317373 -368.654028) (xy 144.344644 -368.653568)
			(xy 145.208244 -368.653568) (xy 145.235513 -368.653998) (xy 145.289497 -368.661765) (xy 145.341825 -368.677135)
			(xy 145.391433 -368.699796) (xy 145.437312 -368.729285) (xy 145.478528 -368.765003) (xy 145.514241 -368.806223)
			(xy 145.543725 -368.852105) (xy 145.56638 -368.901716) (xy 145.581744 -368.954047) (xy 145.589506 -369.00803)
			(xy 145.589506 -369.06257) (xy 145.589506 -369.062571) (xy 150.770532 -369.062571) (xy 150.770532 -369.008029)
			(xy 150.778294 -368.954043) (xy 150.793661 -368.901711) (xy 150.816321 -368.852098) (xy 150.84581 -368.806216)
			(xy 150.881529 -368.764998) (xy 150.922751 -368.729284) (xy 150.968637 -368.699799) (xy 151.018252 -368.677146)
			(xy 151.070586 -368.661785) (xy 151.124573 -368.654028) (xy 151.151844 -368.653568) (xy 152.015444 -368.653568)
			(xy 152.042713 -368.653998) (xy 152.096697 -368.661765) (xy 152.149025 -368.677135) (xy 152.198633 -368.699796)
			(xy 152.244512 -368.729285) (xy 152.285728 -368.765003) (xy 152.321441 -368.806223) (xy 152.350925 -368.852105)
			(xy 152.37358 -368.901716) (xy 152.388944 -368.954047) (xy 152.396706 -369.00803) (xy 152.396706 -369.06257)
			(xy 152.396706 -369.062571) (xy 157.577732 -369.062571) (xy 157.577732 -369.008029) (xy 157.585494 -368.954043)
			(xy 157.600861 -368.901711) (xy 157.623521 -368.852098) (xy 157.65301 -368.806216) (xy 157.688729 -368.764998)
			(xy 157.729951 -368.729284) (xy 157.775837 -368.699799) (xy 157.825452 -368.677146) (xy 157.877786 -368.661785)
			(xy 157.931773 -368.654028) (xy 157.959044 -368.653568) (xy 158.822644 -368.653568) (xy 158.849913 -368.653998)
			(xy 158.903897 -368.661765) (xy 158.956225 -368.677135) (xy 159.005833 -368.699796) (xy 159.051712 -368.729285)
			(xy 159.092928 -368.765003) (xy 159.128641 -368.806223) (xy 159.158125 -368.852105) (xy 159.18078 -368.901716)
			(xy 159.196144 -368.954047) (xy 159.203906 -369.00803) (xy 159.203906 -369.06257) (xy 159.203906 -369.062571)
			(xy 164.384932 -369.062571) (xy 164.384932 -369.008029) (xy 164.392694 -368.954043) (xy 164.408061 -368.901711)
			(xy 164.430721 -368.852098) (xy 164.46021 -368.806216) (xy 164.495929 -368.764998) (xy 164.537151 -368.729284)
			(xy 164.583037 -368.699799) (xy 164.632652 -368.677146) (xy 164.684986 -368.661785) (xy 164.738973 -368.654028)
			(xy 164.766244 -368.653568) (xy 165.629844 -368.653568) (xy 165.657113 -368.653998) (xy 165.711097 -368.661765)
			(xy 165.763425 -368.677135) (xy 165.813033 -368.699796) (xy 165.858912 -368.729285) (xy 165.900128 -368.765003)
			(xy 165.935841 -368.806223) (xy 165.965325 -368.852105) (xy 165.98798 -368.901716) (xy 166.003344 -368.954047)
			(xy 166.011106 -369.00803) (xy 166.011106 -369.06257) (xy 166.011106 -369.062571) (xy 167.788532 -369.062571)
			(xy 167.788532 -369.008029) (xy 167.796294 -368.954043) (xy 167.811661 -368.901711) (xy 167.834321 -368.852098)
			(xy 167.86381 -368.806216) (xy 167.899529 -368.764998) (xy 167.940751 -368.729284) (xy 167.986637 -368.699799)
			(xy 168.036252 -368.677146) (xy 168.088586 -368.661785) (xy 168.142573 -368.654028) (xy 168.169844 -368.653568)
			(xy 169.033444 -368.653568) (xy 169.060713 -368.653998) (xy 169.114697 -368.661765) (xy 169.167025 -368.677135)
			(xy 169.216633 -368.699796) (xy 169.262512 -368.729285) (xy 169.303728 -368.765003) (xy 169.339441 -368.806223)
			(xy 169.368925 -368.852105) (xy 169.39158 -368.901716) (xy 169.406944 -368.954047) (xy 169.414706 -369.00803)
			(xy 169.414706 -369.06257) (xy 169.406944 -369.116553) (xy 169.39158 -369.168884) (xy 169.368925 -369.218495)
			(xy 169.339441 -369.264377) (xy 169.303728 -369.305597) (xy 169.262512 -369.341315) (xy 169.216633 -369.370804)
			(xy 169.167025 -369.393465) (xy 169.114697 -369.408835) (xy 169.060713 -369.416602) (xy 169.033444 -369.417092)
			(xy 168.169844 -369.417092) (xy 168.142573 -369.416572) (xy 168.088586 -369.408815) (xy 168.036252 -369.393454)
			(xy 167.986637 -369.370801) (xy 167.940751 -369.341316) (xy 167.899529 -369.305602) (xy 167.86381 -369.264384)
			(xy 167.834321 -369.218502) (xy 167.811661 -369.168889) (xy 167.796294 -369.116557) (xy 167.788532 -369.062571)
			(xy 166.011106 -369.062571) (xy 166.003344 -369.116553) (xy 165.98798 -369.168884) (xy 165.965325 -369.218495)
			(xy 165.935841 -369.264377) (xy 165.900128 -369.305597) (xy 165.858912 -369.341315) (xy 165.813033 -369.370804)
			(xy 165.763425 -369.393465) (xy 165.711097 -369.408835) (xy 165.657113 -369.416602) (xy 165.629844 -369.417092)
			(xy 164.766244 -369.417092) (xy 164.738973 -369.416572) (xy 164.684986 -369.408815) (xy 164.632652 -369.393454)
			(xy 164.583037 -369.370801) (xy 164.537151 -369.341316) (xy 164.495929 -369.305602) (xy 164.46021 -369.264384)
			(xy 164.430721 -369.218502) (xy 164.408061 -369.168889) (xy 164.392694 -369.116557) (xy 164.384932 -369.062571)
			(xy 159.203906 -369.062571) (xy 159.196144 -369.116553) (xy 159.18078 -369.168884) (xy 159.158125 -369.218495)
			(xy 159.128641 -369.264377) (xy 159.092928 -369.305597) (xy 159.051712 -369.341315) (xy 159.005833 -369.370804)
			(xy 158.956225 -369.393465) (xy 158.903897 -369.408835) (xy 158.849913 -369.416602) (xy 158.822644 -369.417092)
			(xy 157.959044 -369.417092) (xy 157.931773 -369.416572) (xy 157.877786 -369.408815) (xy 157.825452 -369.393454)
			(xy 157.775837 -369.370801) (xy 157.729951 -369.341316) (xy 157.688729 -369.305602) (xy 157.65301 -369.264384)
			(xy 157.623521 -369.218502) (xy 157.600861 -369.168889) (xy 157.585494 -369.116557) (xy 157.577732 -369.062571)
			(xy 152.396706 -369.062571) (xy 152.388944 -369.116553) (xy 152.37358 -369.168884) (xy 152.350925 -369.218495)
			(xy 152.321441 -369.264377) (xy 152.285728 -369.305597) (xy 152.244512 -369.341315) (xy 152.198633 -369.370804)
			(xy 152.149025 -369.393465) (xy 152.096697 -369.408835) (xy 152.042713 -369.416602) (xy 152.015444 -369.417092)
			(xy 151.151844 -369.417092) (xy 151.124573 -369.416572) (xy 151.070586 -369.408815) (xy 151.018252 -369.393454)
			(xy 150.968637 -369.370801) (xy 150.922751 -369.341316) (xy 150.881529 -369.305602) (xy 150.84581 -369.264384)
			(xy 150.816321 -369.218502) (xy 150.793661 -369.168889) (xy 150.778294 -369.116557) (xy 150.770532 -369.062571)
			(xy 145.589506 -369.062571) (xy 145.581744 -369.116553) (xy 145.56638 -369.168884) (xy 145.543725 -369.218495)
			(xy 145.514241 -369.264377) (xy 145.478528 -369.305597) (xy 145.437312 -369.341315) (xy 145.391433 -369.370804)
			(xy 145.341825 -369.393465) (xy 145.289497 -369.408835) (xy 145.235513 -369.416602) (xy 145.208244 -369.417092)
			(xy 144.344644 -369.417092) (xy 144.317373 -369.416572) (xy 144.263386 -369.408815) (xy 144.211052 -369.393454)
			(xy 144.161437 -369.370801) (xy 144.115551 -369.341316) (xy 144.074329 -369.305602) (xy 144.03861 -369.264384)
			(xy 144.009121 -369.218502) (xy 143.986461 -369.168889) (xy 143.971094 -369.116557) (xy 143.963332 -369.062571)
			(xy 139.006648 -369.062571) (xy 139.018553 -369.072887) (xy 139.054268 -369.114104) (xy 139.083754 -369.159985)
			(xy 139.106411 -369.209595) (xy 139.121776 -369.261925) (xy 139.129538 -369.315909) (xy 139.130024 -369.343178)
			(xy 139.130024 -370.206778) (xy 139.129538 -370.234047) (xy 139.121776 -370.288031) (xy 139.106411 -370.340361)
			(xy 139.083754 -370.389971) (xy 139.071223 -370.40947) (xy 141.572996 -370.40947) (xy 141.572996 -369.54587)
			(xy 141.573482 -369.518619) (xy 141.581238 -369.464671) (xy 141.596593 -369.412376) (xy 141.619235 -369.362799)
			(xy 141.648701 -369.316949) (xy 141.684392 -369.275758) (xy 141.725583 -369.240067) (xy 141.771433 -369.210601)
			(xy 141.82101 -369.187959) (xy 141.873305 -369.172604) (xy 141.927253 -369.164848) (xy 141.981755 -369.164848)
			(xy 142.035703 -369.172604) (xy 142.087998 -369.187959) (xy 142.137575 -369.210601) (xy 142.183425 -369.240067)
			(xy 142.224616 -369.275758) (xy 142.260307 -369.316949) (xy 142.289773 -369.362799) (xy 142.312415 -369.412376)
			(xy 142.32777 -369.464671) (xy 142.335526 -369.518619) (xy 142.336012 -369.54587) (xy 142.336012 -369.62565)
			(xy 175.203103 -369.62565) (xy 175.203103 -369.57115) (xy 175.210859 -369.517206) (xy 175.226214 -369.464914)
			(xy 175.248854 -369.41534) (xy 175.278318 -369.369493) (xy 175.314008 -369.328305) (xy 175.355196 -369.292616)
			(xy 175.401044 -369.263152) (xy 175.450618 -369.240512) (xy 175.50291 -369.225158) (xy 175.556854 -369.217403)
			(xy 175.584104 -369.21694) (xy 176.447704 -369.21694) (xy 176.474958 -369.21733) (xy 176.528913 -369.225088)
			(xy 176.581213 -369.240446) (xy 176.630796 -369.26309) (xy 176.676652 -369.29256) (xy 176.717847 -369.328256)
			(xy 176.753543 -369.369451) (xy 176.783012 -369.415307) (xy 176.805656 -369.46489) (xy 176.821013 -369.517191)
			(xy 176.82877 -369.571146) (xy 176.82877 -369.625654) (xy 176.821013 -369.679609) (xy 176.805656 -369.73191)
			(xy 176.783012 -369.781493) (xy 176.753543 -369.827349) (xy 176.717847 -369.868544) (xy 176.676652 -369.90424)
			(xy 176.630796 -369.93371) (xy 176.581213 -369.956354) (xy 176.528913 -369.971712) (xy 176.474958 -369.97947)
			(xy 176.447704 -369.979956) (xy 175.584104 -369.979956) (xy 175.556854 -369.979397) (xy 175.50291 -369.971642)
			(xy 175.450618 -369.956288) (xy 175.401044 -369.933648) (xy 175.355196 -369.904184) (xy 175.314008 -369.868495)
			(xy 175.278318 -369.827307) (xy 175.248854 -369.78146) (xy 175.226214 -369.731886) (xy 175.210859 -369.679594)
			(xy 175.203103 -369.62565) (xy 142.336012 -369.62565) (xy 142.336012 -370.40947) (xy 142.335526 -370.436721)
			(xy 142.32777 -370.490669) (xy 142.312415 -370.542964) (xy 142.289773 -370.592541) (xy 142.260307 -370.638391)
			(xy 142.224616 -370.679582) (xy 142.183425 -370.715273) (xy 142.137575 -370.744739) (xy 142.087998 -370.767381)
			(xy 142.035703 -370.782736) (xy 141.981755 -370.790492) (xy 141.927253 -370.790492) (xy 141.873305 -370.782736)
			(xy 141.82101 -370.767381) (xy 141.771433 -370.744739) (xy 141.725583 -370.715273) (xy 141.684392 -370.679582)
			(xy 141.648701 -370.638391) (xy 141.619235 -370.592541) (xy 141.596593 -370.542964) (xy 141.581238 -370.490669)
			(xy 141.573482 -370.436721) (xy 141.572996 -370.40947) (xy 139.071223 -370.40947) (xy 139.054268 -370.435852)
			(xy 139.018553 -370.477069) (xy 138.977336 -370.512784) (xy 138.931455 -370.54227) (xy 138.881845 -370.564927)
			(xy 138.829515 -370.580292) (xy 138.775531 -370.588054) (xy 138.720993 -370.588054) (xy 138.667009 -370.580292)
			(xy 138.614679 -370.564927) (xy 138.565069 -370.54227) (xy 138.519188 -370.512784) (xy 138.477971 -370.477069)
			(xy 138.442256 -370.435852) (xy 138.41277 -370.389971) (xy 138.390113 -370.340361) (xy 138.374748 -370.288031)
			(xy 138.366986 -370.234047) (xy 138.3665 -370.206778) (xy 2.509012 -370.206778) (xy 2.509012 -371.526365)
			(xy 42.633954 -371.526365) (xy 42.633954 -371.471835) (xy 42.641714 -371.41786) (xy 42.657076 -371.365538)
			(xy 42.679727 -371.315935) (xy 42.709206 -371.270059) (xy 42.744914 -371.228846) (xy 42.786123 -371.193134)
			(xy 42.831994 -371.163649) (xy 42.881595 -371.140992) (xy 42.933915 -371.125624) (xy 42.987889 -371.117857)
			(xy 43.015154 -371.117368) (xy 43.878754 -371.117368) (xy 43.906029 -371.117768) (xy 43.960025 -371.125526)
			(xy 44.012368 -371.140889) (xy 44.061991 -371.163546) (xy 44.107884 -371.193035) (xy 44.149112 -371.228755)
			(xy 44.184838 -371.26998) (xy 44.214332 -371.315869) (xy 44.236995 -371.365489) (xy 44.252364 -371.41783)
			(xy 44.260128 -371.471825) (xy 44.260128 -371.526365) (xy 49.441154 -371.526365) (xy 49.441154 -371.471835)
			(xy 49.448914 -371.41786) (xy 49.464276 -371.365538) (xy 49.486927 -371.315935) (xy 49.516406 -371.270059)
			(xy 49.552114 -371.228846) (xy 49.593323 -371.193134) (xy 49.639194 -371.163649) (xy 49.688795 -371.140992)
			(xy 49.741115 -371.125624) (xy 49.795089 -371.117857) (xy 49.822354 -371.117368) (xy 50.685954 -371.117368)
			(xy 50.713229 -371.117768) (xy 50.767225 -371.125526) (xy 50.819568 -371.140889) (xy 50.869191 -371.163546)
			(xy 50.915084 -371.193035) (xy 50.956312 -371.228755) (xy 50.992038 -371.26998) (xy 51.021532 -371.315869)
			(xy 51.044195 -371.365489) (xy 51.059564 -371.41783) (xy 51.067328 -371.471825) (xy 51.067328 -371.526365)
			(xy 56.248354 -371.526365) (xy 56.248354 -371.471835) (xy 56.256114 -371.41786) (xy 56.271476 -371.365538)
			(xy 56.294127 -371.315935) (xy 56.323606 -371.270059) (xy 56.359314 -371.228846) (xy 56.400523 -371.193134)
			(xy 56.446394 -371.163649) (xy 56.495995 -371.140992) (xy 56.548315 -371.125624) (xy 56.602289 -371.117857)
			(xy 56.629554 -371.117368) (xy 57.493154 -371.117368) (xy 57.520429 -371.117768) (xy 57.574425 -371.125526)
			(xy 57.626768 -371.140889) (xy 57.676391 -371.163546) (xy 57.722284 -371.193035) (xy 57.763512 -371.228755)
			(xy 57.799238 -371.26998) (xy 57.828732 -371.315869) (xy 57.851395 -371.365489) (xy 57.866764 -371.41783)
			(xy 57.874528 -371.471825) (xy 57.874528 -371.526365) (xy 63.055554 -371.526365) (xy 63.055554 -371.471835)
			(xy 63.063314 -371.41786) (xy 63.078676 -371.365538) (xy 63.101327 -371.315935) (xy 63.130806 -371.270059)
			(xy 63.166514 -371.228846) (xy 63.207723 -371.193134) (xy 63.253594 -371.163649) (xy 63.303195 -371.140992)
			(xy 63.355515 -371.125624) (xy 63.409489 -371.117857) (xy 63.436754 -371.117368) (xy 64.300354 -371.117368)
			(xy 64.327629 -371.117768) (xy 64.381625 -371.125526) (xy 64.433968 -371.140889) (xy 64.483591 -371.163546)
			(xy 64.529484 -371.193035) (xy 64.570712 -371.228755) (xy 64.606438 -371.26998) (xy 64.635932 -371.315869)
			(xy 64.658595 -371.365489) (xy 64.673964 -371.41783) (xy 64.681728 -371.471825) (xy 64.681728 -371.526369)
			(xy 75.161631 -371.526369) (xy 75.161631 -371.471831) (xy 75.169393 -371.417848) (xy 75.184758 -371.36552)
			(xy 75.207414 -371.31591) (xy 75.2369 -371.27003) (xy 75.272614 -371.228813) (xy 75.313832 -371.193098)
			(xy 75.359712 -371.163613) (xy 75.409321 -371.140957) (xy 75.46165 -371.125593) (xy 75.515633 -371.117831)
			(xy 75.542902 -371.117368) (xy 76.406502 -371.117368) (xy 76.433773 -371.117795) (xy 76.487761 -371.125557)
			(xy 76.540094 -371.140924) (xy 76.589708 -371.163582) (xy 76.635593 -371.19307) (xy 76.676813 -371.228788)
			(xy 76.712531 -371.270009) (xy 76.742019 -371.315893) (xy 76.764677 -371.365507) (xy 76.780043 -371.417841)
			(xy 76.787806 -371.471829) (xy 76.787806 -371.526369) (xy 81.968831 -371.526369) (xy 81.968831 -371.471831)
			(xy 81.976593 -371.417848) (xy 81.991958 -371.36552) (xy 82.014614 -371.31591) (xy 82.0441 -371.27003)
			(xy 82.079814 -371.228813) (xy 82.121032 -371.193098) (xy 82.166912 -371.163613) (xy 82.216521 -371.140957)
			(xy 82.26885 -371.125593) (xy 82.322833 -371.117831) (xy 82.350102 -371.117368) (xy 83.213702 -371.117368)
			(xy 83.240973 -371.117795) (xy 83.294961 -371.125557) (xy 83.347294 -371.140924) (xy 83.396908 -371.163582)
			(xy 83.442793 -371.19307) (xy 83.484013 -371.228788) (xy 83.519731 -371.270009) (xy 83.549219 -371.315893)
			(xy 83.571877 -371.365507) (xy 83.587243 -371.417841) (xy 83.595006 -371.471829) (xy 83.595006 -371.526369)
			(xy 88.776031 -371.526369) (xy 88.776031 -371.471831) (xy 88.783793 -371.417848) (xy 88.799158 -371.36552)
			(xy 88.821814 -371.31591) (xy 88.8513 -371.27003) (xy 88.887014 -371.228813) (xy 88.928232 -371.193098)
			(xy 88.974112 -371.163613) (xy 89.023721 -371.140957) (xy 89.07605 -371.125593) (xy 89.130033 -371.117831)
			(xy 89.157302 -371.117368) (xy 90.020902 -371.117368) (xy 90.048173 -371.117795) (xy 90.102161 -371.125557)
			(xy 90.154494 -371.140924) (xy 90.204108 -371.163582) (xy 90.249993 -371.19307) (xy 90.291213 -371.228788)
			(xy 90.326931 -371.270009) (xy 90.356419 -371.315893) (xy 90.379077 -371.365507) (xy 90.394443 -371.417841)
			(xy 90.402206 -371.471829) (xy 90.402206 -371.526369) (xy 95.583231 -371.526369) (xy 95.583231 -371.471831)
			(xy 95.590993 -371.417848) (xy 95.606358 -371.36552) (xy 95.629014 -371.31591) (xy 95.6585 -371.27003)
			(xy 95.694214 -371.228813) (xy 95.735432 -371.193098) (xy 95.781312 -371.163613) (xy 95.830921 -371.140957)
			(xy 95.88325 -371.125593) (xy 95.937233 -371.117831) (xy 95.964502 -371.117368) (xy 96.828102 -371.117368)
			(xy 96.855373 -371.117795) (xy 96.909361 -371.125557) (xy 96.961694 -371.140924) (xy 97.011308 -371.163582)
			(xy 97.057193 -371.19307) (xy 97.098413 -371.228788) (xy 97.134131 -371.270009) (xy 97.163619 -371.315893)
			(xy 97.186277 -371.365507) (xy 97.201643 -371.417841) (xy 97.209406 -371.471829) (xy 97.209406 -371.526367)
			(xy 109.733854 -371.526367) (xy 109.733854 -371.471833) (xy 109.741615 -371.417854) (xy 109.756979 -371.365529)
			(xy 109.779633 -371.315923) (xy 109.809117 -371.270046) (xy 109.844829 -371.228831) (xy 109.886042 -371.193119)
			(xy 109.931919 -371.163635) (xy 109.981525 -371.140981) (xy 110.03385 -371.125616) (xy 110.087829 -371.117855)
			(xy 110.115096 -371.117368) (xy 110.978696 -371.117368) (xy 111.005969 -371.117771) (xy 111.059961 -371.125534)
			(xy 111.112298 -371.140901) (xy 111.161916 -371.16356) (xy 111.207803 -371.19305) (xy 111.249027 -371.22877)
			(xy 111.284748 -371.269993) (xy 111.314238 -371.315881) (xy 111.336898 -371.365498) (xy 111.352266 -371.417835)
			(xy 111.360028 -371.471827) (xy 111.360028 -371.526367) (xy 116.541054 -371.526367) (xy 116.541054 -371.471833)
			(xy 116.548815 -371.417854) (xy 116.564179 -371.365529) (xy 116.586833 -371.315923) (xy 116.616317 -371.270046)
			(xy 116.652029 -371.228831) (xy 116.693242 -371.193119) (xy 116.739119 -371.163635) (xy 116.788725 -371.140981)
			(xy 116.84105 -371.125616) (xy 116.895029 -371.117855) (xy 116.922296 -371.117368) (xy 117.785896 -371.117368)
			(xy 117.813169 -371.117771) (xy 117.867161 -371.125534) (xy 117.919498 -371.140901) (xy 117.969116 -371.16356)
			(xy 118.015003 -371.19305) (xy 118.056227 -371.22877) (xy 118.091948 -371.269993) (xy 118.121438 -371.315881)
			(xy 118.144098 -371.365498) (xy 118.159466 -371.417835) (xy 118.167228 -371.471827) (xy 118.167228 -371.526367)
			(xy 123.348254 -371.526367) (xy 123.348254 -371.471833) (xy 123.356015 -371.417854) (xy 123.371379 -371.365529)
			(xy 123.394033 -371.315923) (xy 123.423517 -371.270046) (xy 123.459229 -371.228831) (xy 123.500442 -371.193119)
			(xy 123.546319 -371.163635) (xy 123.595925 -371.140981) (xy 123.64825 -371.125616) (xy 123.702229 -371.117855)
			(xy 123.729496 -371.117368) (xy 124.593096 -371.117368) (xy 124.620369 -371.117771) (xy 124.674361 -371.125534)
			(xy 124.726698 -371.140901) (xy 124.776316 -371.16356) (xy 124.822203 -371.19305) (xy 124.863427 -371.22877)
			(xy 124.899148 -371.269993) (xy 124.928638 -371.315881) (xy 124.951298 -371.365498) (xy 124.966666 -371.417835)
			(xy 124.974428 -371.471827) (xy 124.974428 -371.526367) (xy 130.155454 -371.526367) (xy 130.155454 -371.471833)
			(xy 130.163215 -371.417854) (xy 130.178579 -371.365529) (xy 130.201233 -371.315923) (xy 130.230717 -371.270046)
			(xy 130.266429 -371.228831) (xy 130.307642 -371.193119) (xy 130.353519 -371.163635) (xy 130.403125 -371.140981)
			(xy 130.45545 -371.125616) (xy 130.509429 -371.117855) (xy 130.536696 -371.117368) (xy 131.400296 -371.117368)
			(xy 131.427569 -371.117771) (xy 131.481561 -371.125534) (xy 131.533898 -371.140901) (xy 131.583516 -371.16356)
			(xy 131.629403 -371.19305) (xy 131.670627 -371.22877) (xy 131.706348 -371.269993) (xy 131.735838 -371.315881)
			(xy 131.758498 -371.365498) (xy 131.773866 -371.417835) (xy 131.781628 -371.471827) (xy 131.781628 -371.526371)
			(xy 142.261532 -371.526371) (xy 142.261532 -371.471829) (xy 142.269294 -371.417843) (xy 142.284661 -371.365511)
			(xy 142.307321 -371.315898) (xy 142.33681 -371.270016) (xy 142.372529 -371.228798) (xy 142.413751 -371.193084)
			(xy 142.459637 -371.163599) (xy 142.509252 -371.140946) (xy 142.561586 -371.125585) (xy 142.615573 -371.117828)
			(xy 142.642844 -371.117368) (xy 143.506444 -371.117368) (xy 143.533713 -371.117798) (xy 143.587697 -371.125565)
			(xy 143.640025 -371.140935) (xy 143.689633 -371.163596) (xy 143.735512 -371.193085) (xy 143.776728 -371.228803)
			(xy 143.812441 -371.270023) (xy 143.841925 -371.315905) (xy 143.86458 -371.365516) (xy 143.879944 -371.417847)
			(xy 143.887706 -371.47183) (xy 143.887706 -371.52637) (xy 143.887706 -371.526371) (xy 149.068732 -371.526371)
			(xy 149.068732 -371.471829) (xy 149.076494 -371.417843) (xy 149.091861 -371.365511) (xy 149.114521 -371.315898)
			(xy 149.14401 -371.270016) (xy 149.179729 -371.228798) (xy 149.220951 -371.193084) (xy 149.266837 -371.163599)
			(xy 149.316452 -371.140946) (xy 149.368786 -371.125585) (xy 149.422773 -371.117828) (xy 149.450044 -371.117368)
			(xy 150.313644 -371.117368) (xy 150.340913 -371.117798) (xy 150.394897 -371.125565) (xy 150.447225 -371.140935)
			(xy 150.496833 -371.163596) (xy 150.542712 -371.193085) (xy 150.583928 -371.228803) (xy 150.619641 -371.270023)
			(xy 150.649125 -371.315905) (xy 150.67178 -371.365516) (xy 150.687144 -371.417847) (xy 150.694906 -371.47183)
			(xy 150.694906 -371.52637) (xy 150.694906 -371.526371) (xy 155.875932 -371.526371) (xy 155.875932 -371.471829)
			(xy 155.883694 -371.417843) (xy 155.899061 -371.365511) (xy 155.921721 -371.315898) (xy 155.95121 -371.270016)
			(xy 155.986929 -371.228798) (xy 156.028151 -371.193084) (xy 156.074037 -371.163599) (xy 156.123652 -371.140946)
			(xy 156.175986 -371.125585) (xy 156.229973 -371.117828) (xy 156.257244 -371.117368) (xy 157.120844 -371.117368)
			(xy 157.148113 -371.117798) (xy 157.202097 -371.125565) (xy 157.254425 -371.140935) (xy 157.304033 -371.163596)
			(xy 157.349912 -371.193085) (xy 157.391128 -371.228803) (xy 157.426841 -371.270023) (xy 157.456325 -371.315905)
			(xy 157.47898 -371.365516) (xy 157.494344 -371.417847) (xy 157.502106 -371.47183) (xy 157.502106 -371.52637)
			(xy 157.502106 -371.526371) (xy 162.683132 -371.526371) (xy 162.683132 -371.471829) (xy 162.690894 -371.417843)
			(xy 162.706261 -371.365511) (xy 162.728921 -371.315898) (xy 162.75841 -371.270016) (xy 162.794129 -371.228798)
			(xy 162.835351 -371.193084) (xy 162.881237 -371.163599) (xy 162.930852 -371.140946) (xy 162.983186 -371.125585)
			(xy 163.037173 -371.117828) (xy 163.064444 -371.117368) (xy 163.928044 -371.117368) (xy 163.955313 -371.117798)
			(xy 164.009297 -371.125565) (xy 164.061625 -371.140935) (xy 164.111233 -371.163596) (xy 164.157112 -371.193085)
			(xy 164.198328 -371.228803) (xy 164.234041 -371.270023) (xy 164.263525 -371.315905) (xy 164.28618 -371.365516)
			(xy 164.301544 -371.417847) (xy 164.309306 -371.47183) (xy 164.309306 -371.52637) (xy 164.301544 -371.580353)
			(xy 164.28618 -371.632684) (xy 164.263525 -371.682295) (xy 164.234041 -371.728177) (xy 164.198328 -371.769397)
			(xy 164.157112 -371.805115) (xy 164.111233 -371.834604) (xy 164.061625 -371.857265) (xy 164.009297 -371.872635)
			(xy 163.955313 -371.880402) (xy 163.928044 -371.880892) (xy 163.064444 -371.880892) (xy 163.037173 -371.880372)
			(xy 162.983186 -371.872615) (xy 162.930852 -371.857254) (xy 162.881237 -371.834601) (xy 162.835351 -371.805116)
			(xy 162.794129 -371.769402) (xy 162.75841 -371.728184) (xy 162.728921 -371.682302) (xy 162.706261 -371.632689)
			(xy 162.690894 -371.580357) (xy 162.683132 -371.526371) (xy 157.502106 -371.526371) (xy 157.494344 -371.580353)
			(xy 157.47898 -371.632684) (xy 157.456325 -371.682295) (xy 157.426841 -371.728177) (xy 157.391128 -371.769397)
			(xy 157.349912 -371.805115) (xy 157.304033 -371.834604) (xy 157.254425 -371.857265) (xy 157.202097 -371.872635)
			(xy 157.148113 -371.880402) (xy 157.120844 -371.880892) (xy 156.257244 -371.880892) (xy 156.229973 -371.880372)
			(xy 156.175986 -371.872615) (xy 156.123652 -371.857254) (xy 156.074037 -371.834601) (xy 156.028151 -371.805116)
			(xy 155.986929 -371.769402) (xy 155.95121 -371.728184) (xy 155.921721 -371.682302) (xy 155.899061 -371.632689)
			(xy 155.883694 -371.580357) (xy 155.875932 -371.526371) (xy 150.694906 -371.526371) (xy 150.687144 -371.580353)
			(xy 150.67178 -371.632684) (xy 150.649125 -371.682295) (xy 150.619641 -371.728177) (xy 150.583928 -371.769397)
			(xy 150.542712 -371.805115) (xy 150.496833 -371.834604) (xy 150.447225 -371.857265) (xy 150.394897 -371.872635)
			(xy 150.340913 -371.880402) (xy 150.313644 -371.880892) (xy 149.450044 -371.880892) (xy 149.422773 -371.880372)
			(xy 149.368786 -371.872615) (xy 149.316452 -371.857254) (xy 149.266837 -371.834601) (xy 149.220951 -371.805116)
			(xy 149.179729 -371.769402) (xy 149.14401 -371.728184) (xy 149.114521 -371.682302) (xy 149.091861 -371.632689)
			(xy 149.076494 -371.580357) (xy 149.068732 -371.526371) (xy 143.887706 -371.526371) (xy 143.879944 -371.580353)
			(xy 143.86458 -371.632684) (xy 143.841925 -371.682295) (xy 143.812441 -371.728177) (xy 143.776728 -371.769397)
			(xy 143.735512 -371.805115) (xy 143.689633 -371.834604) (xy 143.640025 -371.857265) (xy 143.587697 -371.872635)
			(xy 143.533713 -371.880402) (xy 143.506444 -371.880892) (xy 142.642844 -371.880892) (xy 142.615573 -371.880372)
			(xy 142.561586 -371.872615) (xy 142.509252 -371.857254) (xy 142.459637 -371.834601) (xy 142.413751 -371.805116)
			(xy 142.372529 -371.769402) (xy 142.33681 -371.728184) (xy 142.307321 -371.682302) (xy 142.284661 -371.632689)
			(xy 142.269294 -371.580357) (xy 142.261532 -371.526371) (xy 131.781628 -371.526371) (xy 131.781628 -371.526373)
			(xy 131.773866 -371.580365) (xy 131.758498 -371.632702) (xy 131.735838 -371.682319) (xy 131.706348 -371.728207)
			(xy 131.670627 -371.76943) (xy 131.629403 -371.80515) (xy 131.583516 -371.83464) (xy 131.533898 -371.857299)
			(xy 131.481561 -371.872666) (xy 131.427569 -371.880429) (xy 131.400296 -371.880892) (xy 130.536696 -371.880892)
			(xy 130.509429 -371.880345) (xy 130.45545 -371.872584) (xy 130.403125 -371.857219) (xy 130.353519 -371.834565)
			(xy 130.307642 -371.805081) (xy 130.266429 -371.769369) (xy 130.230717 -371.728154) (xy 130.201233 -371.682277)
			(xy 130.178579 -371.632671) (xy 130.163215 -371.580346) (xy 130.155454 -371.526367) (xy 124.974428 -371.526367)
			(xy 124.974428 -371.526373) (xy 124.966666 -371.580365) (xy 124.951298 -371.632702) (xy 124.928638 -371.682319)
			(xy 124.899148 -371.728207) (xy 124.863427 -371.76943) (xy 124.822203 -371.80515) (xy 124.776316 -371.83464)
			(xy 124.726698 -371.857299) (xy 124.674361 -371.872666) (xy 124.620369 -371.880429) (xy 124.593096 -371.880892)
			(xy 123.729496 -371.880892) (xy 123.702229 -371.880345) (xy 123.64825 -371.872584) (xy 123.595925 -371.857219)
			(xy 123.546319 -371.834565) (xy 123.500442 -371.805081) (xy 123.459229 -371.769369) (xy 123.423517 -371.728154)
			(xy 123.394033 -371.682277) (xy 123.371379 -371.632671) (xy 123.356015 -371.580346) (xy 123.348254 -371.526367)
			(xy 118.167228 -371.526367) (xy 118.167228 -371.526373) (xy 118.159466 -371.580365) (xy 118.144098 -371.632702)
			(xy 118.121438 -371.682319) (xy 118.091948 -371.728207) (xy 118.056227 -371.76943) (xy 118.015003 -371.80515)
			(xy 117.969116 -371.83464) (xy 117.919498 -371.857299) (xy 117.867161 -371.872666) (xy 117.813169 -371.880429)
			(xy 117.785896 -371.880892) (xy 116.922296 -371.880892) (xy 116.895029 -371.880345) (xy 116.84105 -371.872584)
			(xy 116.788725 -371.857219) (xy 116.739119 -371.834565) (xy 116.693242 -371.805081) (xy 116.652029 -371.769369)
			(xy 116.616317 -371.728154) (xy 116.586833 -371.682277) (xy 116.564179 -371.632671) (xy 116.548815 -371.580346)
			(xy 116.541054 -371.526367) (xy 111.360028 -371.526367) (xy 111.360028 -371.526373) (xy 111.352266 -371.580365)
			(xy 111.336898 -371.632702) (xy 111.314238 -371.682319) (xy 111.284748 -371.728207) (xy 111.249027 -371.76943)
			(xy 111.207803 -371.80515) (xy 111.161916 -371.83464) (xy 111.112298 -371.857299) (xy 111.059961 -371.872666)
			(xy 111.005969 -371.880429) (xy 110.978696 -371.880892) (xy 110.115096 -371.880892) (xy 110.087829 -371.880345)
			(xy 110.03385 -371.872584) (xy 109.981525 -371.857219) (xy 109.931919 -371.834565) (xy 109.886042 -371.805081)
			(xy 109.844829 -371.769369) (xy 109.809117 -371.728154) (xy 109.779633 -371.682277) (xy 109.756979 -371.632671)
			(xy 109.741615 -371.580346) (xy 109.733854 -371.526367) (xy 97.209406 -371.526367) (xy 97.209406 -371.526371)
			(xy 97.201643 -371.580359) (xy 97.186277 -371.632693) (xy 97.163619 -371.682307) (xy 97.134131 -371.728191)
			(xy 97.098413 -371.769412) (xy 97.057193 -371.80513) (xy 97.011308 -371.834618) (xy 96.961694 -371.857276)
			(xy 96.909361 -371.872643) (xy 96.855373 -371.880405) (xy 96.828102 -371.880892) (xy 95.964502 -371.880892)
			(xy 95.937233 -371.880369) (xy 95.88325 -371.872607) (xy 95.830921 -371.857243) (xy 95.781312 -371.834587)
			(xy 95.735432 -371.805102) (xy 95.694214 -371.769387) (xy 95.6585 -371.72817) (xy 95.629014 -371.68229)
			(xy 95.606358 -371.63268) (xy 95.590993 -371.580352) (xy 95.583231 -371.526369) (xy 90.402206 -371.526369)
			(xy 90.402206 -371.526371) (xy 90.394443 -371.580359) (xy 90.379077 -371.632693) (xy 90.356419 -371.682307)
			(xy 90.326931 -371.728191) (xy 90.291213 -371.769412) (xy 90.249993 -371.80513) (xy 90.204108 -371.834618)
			(xy 90.154494 -371.857276) (xy 90.102161 -371.872643) (xy 90.048173 -371.880405) (xy 90.020902 -371.880892)
			(xy 89.157302 -371.880892) (xy 89.130033 -371.880369) (xy 89.07605 -371.872607) (xy 89.023721 -371.857243)
			(xy 88.974112 -371.834587) (xy 88.928232 -371.805102) (xy 88.887014 -371.769387) (xy 88.8513 -371.72817)
			(xy 88.821814 -371.68229) (xy 88.799158 -371.63268) (xy 88.783793 -371.580352) (xy 88.776031 -371.526369)
			(xy 83.595006 -371.526369) (xy 83.595006 -371.526371) (xy 83.587243 -371.580359) (xy 83.571877 -371.632693)
			(xy 83.549219 -371.682307) (xy 83.519731 -371.728191) (xy 83.484013 -371.769412) (xy 83.442793 -371.80513)
			(xy 83.396908 -371.834618) (xy 83.347294 -371.857276) (xy 83.294961 -371.872643) (xy 83.240973 -371.880405)
			(xy 83.213702 -371.880892) (xy 82.350102 -371.880892) (xy 82.322833 -371.880369) (xy 82.26885 -371.872607)
			(xy 82.216521 -371.857243) (xy 82.166912 -371.834587) (xy 82.121032 -371.805102) (xy 82.079814 -371.769387)
			(xy 82.0441 -371.72817) (xy 82.014614 -371.68229) (xy 81.991958 -371.63268) (xy 81.976593 -371.580352)
			(xy 81.968831 -371.526369) (xy 76.787806 -371.526369) (xy 76.787806 -371.526371) (xy 76.780043 -371.580359)
			(xy 76.764677 -371.632693) (xy 76.742019 -371.682307) (xy 76.712531 -371.728191) (xy 76.676813 -371.769412)
			(xy 76.635593 -371.80513) (xy 76.589708 -371.834618) (xy 76.540094 -371.857276) (xy 76.487761 -371.872643)
			(xy 76.433773 -371.880405) (xy 76.406502 -371.880892) (xy 75.542902 -371.880892) (xy 75.515633 -371.880369)
			(xy 75.46165 -371.872607) (xy 75.409321 -371.857243) (xy 75.359712 -371.834587) (xy 75.313832 -371.805102)
			(xy 75.272614 -371.769387) (xy 75.2369 -371.72817) (xy 75.207414 -371.68229) (xy 75.184758 -371.63268)
			(xy 75.169393 -371.580352) (xy 75.161631 -371.526369) (xy 64.681728 -371.526369) (xy 64.681728 -371.526375)
			(xy 64.673964 -371.58037) (xy 64.658595 -371.632711) (xy 64.635932 -371.682331) (xy 64.606438 -371.72822)
			(xy 64.570712 -371.769445) (xy 64.529484 -371.805165) (xy 64.483591 -371.834654) (xy 64.433968 -371.857311)
			(xy 64.381625 -371.872674) (xy 64.327629 -371.880432) (xy 64.300354 -371.880892) (xy 63.436754 -371.880892)
			(xy 63.409489 -371.880343) (xy 63.355515 -371.872576) (xy 63.303195 -371.857208) (xy 63.253594 -371.834551)
			(xy 63.207723 -371.805066) (xy 63.166514 -371.769354) (xy 63.130806 -371.728141) (xy 63.101327 -371.682265)
			(xy 63.078676 -371.632662) (xy 63.063314 -371.58034) (xy 63.055554 -371.526365) (xy 57.874528 -371.526365)
			(xy 57.874528 -371.526375) (xy 57.866764 -371.58037) (xy 57.851395 -371.632711) (xy 57.828732 -371.682331)
			(xy 57.799238 -371.72822) (xy 57.763512 -371.769445) (xy 57.722284 -371.805165) (xy 57.676391 -371.834654)
			(xy 57.626768 -371.857311) (xy 57.574425 -371.872674) (xy 57.520429 -371.880432) (xy 57.493154 -371.880892)
			(xy 56.629554 -371.880892) (xy 56.602289 -371.880343) (xy 56.548315 -371.872576) (xy 56.495995 -371.857208)
			(xy 56.446394 -371.834551) (xy 56.400523 -371.805066) (xy 56.359314 -371.769354) (xy 56.323606 -371.728141)
			(xy 56.294127 -371.682265) (xy 56.271476 -371.632662) (xy 56.256114 -371.58034) (xy 56.248354 -371.526365)
			(xy 51.067328 -371.526365) (xy 51.067328 -371.526375) (xy 51.059564 -371.58037) (xy 51.044195 -371.632711)
			(xy 51.021532 -371.682331) (xy 50.992038 -371.72822) (xy 50.956312 -371.769445) (xy 50.915084 -371.805165)
			(xy 50.869191 -371.834654) (xy 50.819568 -371.857311) (xy 50.767225 -371.872674) (xy 50.713229 -371.880432)
			(xy 50.685954 -371.880892) (xy 49.822354 -371.880892) (xy 49.795089 -371.880343) (xy 49.741115 -371.872576)
			(xy 49.688795 -371.857208) (xy 49.639194 -371.834551) (xy 49.593323 -371.805066) (xy 49.552114 -371.769354)
			(xy 49.516406 -371.728141) (xy 49.486927 -371.682265) (xy 49.464276 -371.632662) (xy 49.448914 -371.58034)
			(xy 49.441154 -371.526365) (xy 44.260128 -371.526365) (xy 44.260128 -371.526375) (xy 44.252364 -371.58037)
			(xy 44.236995 -371.632711) (xy 44.214332 -371.682331) (xy 44.184838 -371.72822) (xy 44.149112 -371.769445)
			(xy 44.107884 -371.805165) (xy 44.061991 -371.834654) (xy 44.012368 -371.857311) (xy 43.960025 -371.872674)
			(xy 43.906029 -371.880432) (xy 43.878754 -371.880892) (xy 43.015154 -371.880892) (xy 42.987889 -371.880343)
			(xy 42.933915 -371.872576) (xy 42.881595 -371.857208) (xy 42.831994 -371.834551) (xy 42.786123 -371.805066)
			(xy 42.744914 -371.769354) (xy 42.709206 -371.728141) (xy 42.679727 -371.682265) (xy 42.657076 -371.632662)
			(xy 42.641714 -371.58034) (xy 42.633954 -371.526365) (xy 2.509012 -371.526365) (xy 2.509012 -376.489976)
			(xy 31.068784 -376.489976) (xy 31.072756 -376.311733) (xy 31.084664 -376.133844) (xy 31.104485 -375.956662)
			(xy 31.132179 -375.780538) (xy 31.167691 -375.605823) (xy 31.210951 -375.432864) (xy 31.261873 -375.262003)
			(xy 31.320356 -375.093581) (xy 31.386283 -374.927931) (xy 31.459524 -374.765382) (xy 31.539934 -374.606257)
			(xy 31.627352 -374.450872) (xy 31.721605 -374.299536) (xy 31.822506 -374.152548) (xy 31.929855 -374.010201)
			(xy 32.043438 -373.872778) (xy 32.163031 -373.740551) (xy 32.288395 -373.613782) (xy 32.419282 -373.492724)
			(xy 32.555431 -373.377617) (xy 32.696573 -373.268689) (xy 32.842428 -373.166157) (xy 32.992705 -373.070223)
			(xy 33.147106 -372.98108) (xy 33.305325 -372.898903) (xy 33.467048 -372.823855) (xy 33.631953 -372.756087)
			(xy 33.799714 -372.695731) (xy 33.969997 -372.642909) (xy 34.142464 -372.597725) (xy 34.316772 -372.560268)
			(xy 34.492576 -372.530614) (xy 34.669526 -372.508821) (xy 34.847272 -372.494931) (xy 35.025459 -372.488974)
			(xy 35.203736 -372.49096) (xy 35.381747 -372.500886) (xy 35.559139 -372.518732) (xy 35.735559 -372.544462)
			(xy 35.910659 -372.578026) (xy 36.08409 -372.619356) (xy 36.255507 -372.668372) (xy 36.42457 -372.724974)
			(xy 36.590945 -372.789052) (xy 36.754299 -372.860478) (xy 36.91431 -372.93911) (xy 37.070659 -373.024791)
			(xy 37.223036 -373.117353) (xy 37.371139 -373.21661) (xy 37.514673 -373.322367) (xy 37.653353 -373.434412)
			(xy 37.786904 -373.552524) (xy 37.915061 -373.676468) (xy 38.03757 -373.805998) (xy 38.154187 -373.940857)
			(xy 38.193125 -373.990165) (xy 47.739354 -373.990165) (xy 47.739354 -373.935635) (xy 47.747114 -373.88166)
			(xy 47.762476 -373.829338) (xy 47.785127 -373.779735) (xy 47.814606 -373.733859) (xy 47.850314 -373.692646)
			(xy 47.891523 -373.656934) (xy 47.937394 -373.627449) (xy 47.986995 -373.604792) (xy 48.039315 -373.589424)
			(xy 48.093289 -373.581657) (xy 48.120554 -373.581168) (xy 48.984154 -373.581168) (xy 49.011429 -373.581568)
			(xy 49.065425 -373.589326) (xy 49.117768 -373.604689) (xy 49.167391 -373.627346) (xy 49.213284 -373.656835)
			(xy 49.254512 -373.692555) (xy 49.290238 -373.73378) (xy 49.319732 -373.779669) (xy 49.342395 -373.829289)
			(xy 49.357764 -373.88163) (xy 49.365528 -373.935625) (xy 49.365528 -373.990165) (xy 54.546554 -373.990165)
			(xy 54.546554 -373.935635) (xy 54.554314 -373.88166) (xy 54.569676 -373.829338) (xy 54.592327 -373.779735)
			(xy 54.621806 -373.733859) (xy 54.657514 -373.692646) (xy 54.698723 -373.656934) (xy 54.744594 -373.627449)
			(xy 54.794195 -373.604792) (xy 54.846515 -373.589424) (xy 54.900489 -373.581657) (xy 54.927754 -373.581168)
			(xy 55.791354 -373.581168) (xy 55.818629 -373.581568) (xy 55.872625 -373.589326) (xy 55.924968 -373.604689)
			(xy 55.974591 -373.627346) (xy 56.020484 -373.656835) (xy 56.061712 -373.692555) (xy 56.097438 -373.73378)
			(xy 56.126932 -373.779669) (xy 56.149595 -373.829289) (xy 56.164964 -373.88163) (xy 56.172728 -373.935625)
			(xy 56.172728 -373.990165) (xy 61.353754 -373.990165) (xy 61.353754 -373.935635) (xy 61.361514 -373.88166)
			(xy 61.376876 -373.829338) (xy 61.399527 -373.779735) (xy 61.429006 -373.733859) (xy 61.464714 -373.692646)
			(xy 61.505923 -373.656934) (xy 61.551794 -373.627449) (xy 61.601395 -373.604792) (xy 61.653715 -373.589424)
			(xy 61.707689 -373.581657) (xy 61.734954 -373.581168) (xy 62.598554 -373.581168) (xy 62.625829 -373.581568)
			(xy 62.679825 -373.589326) (xy 62.732168 -373.604689) (xy 62.781791 -373.627346) (xy 62.827684 -373.656835)
			(xy 62.868912 -373.692555) (xy 62.904638 -373.73378) (xy 62.934132 -373.779669) (xy 62.956795 -373.829289)
			(xy 62.972164 -373.88163) (xy 62.979928 -373.935625) (xy 62.979928 -373.990169) (xy 80.267031 -373.990169)
			(xy 80.267031 -373.935631) (xy 80.274793 -373.881648) (xy 80.290158 -373.82932) (xy 80.312814 -373.77971)
			(xy 80.3423 -373.73383) (xy 80.378014 -373.692613) (xy 80.419232 -373.656898) (xy 80.465112 -373.627413)
			(xy 80.514721 -373.604757) (xy 80.56705 -373.589393) (xy 80.621033 -373.581631) (xy 80.648302 -373.581168)
			(xy 81.511902 -373.581168) (xy 81.539173 -373.581595) (xy 81.593161 -373.589357) (xy 81.645494 -373.604724)
			(xy 81.695108 -373.627382) (xy 81.740993 -373.65687) (xy 81.782213 -373.692588) (xy 81.817931 -373.733809)
			(xy 81.847419 -373.779693) (xy 81.870077 -373.829307) (xy 81.885443 -373.881641) (xy 81.893206 -373.935629)
			(xy 81.893206 -373.990169) (xy 87.074231 -373.990169) (xy 87.074231 -373.935631) (xy 87.081993 -373.881648)
			(xy 87.097358 -373.82932) (xy 87.120014 -373.77971) (xy 87.1495 -373.73383) (xy 87.185214 -373.692613)
			(xy 87.226432 -373.656898) (xy 87.272312 -373.627413) (xy 87.321921 -373.604757) (xy 87.37425 -373.589393)
			(xy 87.428233 -373.581631) (xy 87.455502 -373.581168) (xy 88.319102 -373.581168) (xy 88.346373 -373.581595)
			(xy 88.400361 -373.589357) (xy 88.452694 -373.604724) (xy 88.502308 -373.627382) (xy 88.548193 -373.65687)
			(xy 88.589413 -373.692588) (xy 88.625131 -373.733809) (xy 88.654619 -373.779693) (xy 88.677277 -373.829307)
			(xy 88.692643 -373.881641) (xy 88.700406 -373.935629) (xy 88.700406 -373.990169) (xy 93.881431 -373.990169)
			(xy 93.881431 -373.935631) (xy 93.889193 -373.881648) (xy 93.904558 -373.82932) (xy 93.927214 -373.77971)
			(xy 93.9567 -373.73383) (xy 93.992414 -373.692613) (xy 94.033632 -373.656898) (xy 94.079512 -373.627413)
			(xy 94.129121 -373.604757) (xy 94.18145 -373.589393) (xy 94.235433 -373.581631) (xy 94.262702 -373.581168)
			(xy 95.126302 -373.581168) (xy 95.153573 -373.581595) (xy 95.207561 -373.589357) (xy 95.259894 -373.604724)
			(xy 95.309508 -373.627382) (xy 95.355393 -373.65687) (xy 95.396613 -373.692588) (xy 95.432331 -373.733809)
			(xy 95.461819 -373.779693) (xy 95.484477 -373.829307) (xy 95.499843 -373.881641) (xy 95.507606 -373.935629)
			(xy 95.507606 -373.990167) (xy 114.839254 -373.990167) (xy 114.839254 -373.935633) (xy 114.847015 -373.881654)
			(xy 114.862379 -373.829329) (xy 114.885033 -373.779723) (xy 114.914517 -373.733846) (xy 114.950229 -373.692631)
			(xy 114.991442 -373.656919) (xy 115.037319 -373.627435) (xy 115.086925 -373.604781) (xy 115.13925 -373.589416)
			(xy 115.193229 -373.581655) (xy 115.220496 -373.581168) (xy 116.084096 -373.581168) (xy 116.111369 -373.581571)
			(xy 116.165361 -373.589334) (xy 116.217698 -373.604701) (xy 116.267316 -373.62736) (xy 116.313203 -373.65685)
			(xy 116.354427 -373.69257) (xy 116.390148 -373.733793) (xy 116.419638 -373.779681) (xy 116.442298 -373.829298)
			(xy 116.457666 -373.881635) (xy 116.465428 -373.935627) (xy 116.465428 -373.990167) (xy 121.646454 -373.990167)
			(xy 121.646454 -373.935633) (xy 121.654215 -373.881654) (xy 121.669579 -373.829329) (xy 121.692233 -373.779723)
			(xy 121.721717 -373.733846) (xy 121.757429 -373.692631) (xy 121.798642 -373.656919) (xy 121.844519 -373.627435)
			(xy 121.894125 -373.604781) (xy 121.94645 -373.589416) (xy 122.000429 -373.581655) (xy 122.027696 -373.581168)
			(xy 122.891296 -373.581168) (xy 122.918569 -373.581571) (xy 122.972561 -373.589334) (xy 123.024898 -373.604701)
			(xy 123.074516 -373.62736) (xy 123.120403 -373.65685) (xy 123.161627 -373.69257) (xy 123.197348 -373.733793)
			(xy 123.226838 -373.779681) (xy 123.249498 -373.829298) (xy 123.264866 -373.881635) (xy 123.272628 -373.935627)
			(xy 123.272628 -373.990167) (xy 128.453654 -373.990167) (xy 128.453654 -373.935633) (xy 128.461415 -373.881654)
			(xy 128.476779 -373.829329) (xy 128.499433 -373.779723) (xy 128.528917 -373.733846) (xy 128.564629 -373.692631)
			(xy 128.605842 -373.656919) (xy 128.651719 -373.627435) (xy 128.701325 -373.604781) (xy 128.75365 -373.589416)
			(xy 128.807629 -373.581655) (xy 128.834896 -373.581168) (xy 129.698496 -373.581168) (xy 129.725769 -373.581571)
			(xy 129.779761 -373.589334) (xy 129.832098 -373.604701) (xy 129.881716 -373.62736) (xy 129.927603 -373.65685)
			(xy 129.968827 -373.69257) (xy 130.004548 -373.733793) (xy 130.034038 -373.779681) (xy 130.056698 -373.829298)
			(xy 130.072066 -373.881635) (xy 130.079828 -373.935627) (xy 130.079828 -373.990171) (xy 147.366932 -373.990171)
			(xy 147.366932 -373.935629) (xy 147.374694 -373.881643) (xy 147.390061 -373.829311) (xy 147.412721 -373.779698)
			(xy 147.44221 -373.733816) (xy 147.477929 -373.692598) (xy 147.519151 -373.656884) (xy 147.565037 -373.627399)
			(xy 147.614652 -373.604746) (xy 147.666986 -373.589385) (xy 147.720973 -373.581628) (xy 147.748244 -373.581168)
			(xy 148.611844 -373.581168) (xy 148.639113 -373.581598) (xy 148.693097 -373.589365) (xy 148.745425 -373.604735)
			(xy 148.795033 -373.627396) (xy 148.840912 -373.656885) (xy 148.882128 -373.692603) (xy 148.917841 -373.733823)
			(xy 148.947325 -373.779705) (xy 148.96998 -373.829316) (xy 148.985344 -373.881647) (xy 148.993106 -373.93563)
			(xy 148.993106 -373.99017) (xy 148.993106 -373.990171) (xy 154.174132 -373.990171) (xy 154.174132 -373.935629)
			(xy 154.181894 -373.881643) (xy 154.197261 -373.829311) (xy 154.219921 -373.779698) (xy 154.24941 -373.733816)
			(xy 154.285129 -373.692598) (xy 154.326351 -373.656884) (xy 154.372237 -373.627399) (xy 154.421852 -373.604746)
			(xy 154.474186 -373.589385) (xy 154.528173 -373.581628) (xy 154.555444 -373.581168) (xy 155.419044 -373.581168)
			(xy 155.446313 -373.581598) (xy 155.500297 -373.589365) (xy 155.552625 -373.604735) (xy 155.602233 -373.627396)
			(xy 155.648112 -373.656885) (xy 155.689328 -373.692603) (xy 155.725041 -373.733823) (xy 155.754525 -373.779705)
			(xy 155.77718 -373.829316) (xy 155.792544 -373.881647) (xy 155.800306 -373.93563) (xy 155.800306 -373.99017)
			(xy 155.800306 -373.990171) (xy 160.981332 -373.990171) (xy 160.981332 -373.935629) (xy 160.989094 -373.881643)
			(xy 161.004461 -373.829311) (xy 161.027121 -373.779698) (xy 161.05661 -373.733816) (xy 161.092329 -373.692598)
			(xy 161.133551 -373.656884) (xy 161.179437 -373.627399) (xy 161.229052 -373.604746) (xy 161.281386 -373.589385)
			(xy 161.335373 -373.581628) (xy 161.362644 -373.581168) (xy 162.226244 -373.581168) (xy 162.253513 -373.581598)
			(xy 162.307497 -373.589365) (xy 162.359825 -373.604735) (xy 162.409433 -373.627396) (xy 162.455312 -373.656885)
			(xy 162.496528 -373.692603) (xy 162.532241 -373.733823) (xy 162.561725 -373.779705) (xy 162.58438 -373.829316)
			(xy 162.599744 -373.881647) (xy 162.607506 -373.93563) (xy 162.607506 -373.99017) (xy 162.599744 -374.044153)
			(xy 162.58438 -374.096484) (xy 162.561725 -374.146095) (xy 162.532241 -374.191977) (xy 162.496528 -374.233197)
			(xy 162.455312 -374.268915) (xy 162.409433 -374.298404) (xy 162.359825 -374.321065) (xy 162.307497 -374.336435)
			(xy 162.253513 -374.344202) (xy 162.226244 -374.344692) (xy 161.362644 -374.344692) (xy 161.335373 -374.344172)
			(xy 161.281386 -374.336415) (xy 161.229052 -374.321054) (xy 161.179437 -374.298401) (xy 161.133551 -374.268916)
			(xy 161.092329 -374.233202) (xy 161.05661 -374.191984) (xy 161.027121 -374.146102) (xy 161.004461 -374.096489)
			(xy 160.989094 -374.044157) (xy 160.981332 -373.990171) (xy 155.800306 -373.990171) (xy 155.792544 -374.044153)
			(xy 155.77718 -374.096484) (xy 155.754525 -374.146095) (xy 155.725041 -374.191977) (xy 155.689328 -374.233197)
			(xy 155.648112 -374.268915) (xy 155.602233 -374.298404) (xy 155.552625 -374.321065) (xy 155.500297 -374.336435)
			(xy 155.446313 -374.344202) (xy 155.419044 -374.344692) (xy 154.555444 -374.344692) (xy 154.528173 -374.344172)
			(xy 154.474186 -374.336415) (xy 154.421852 -374.321054) (xy 154.372237 -374.298401) (xy 154.326351 -374.268916)
			(xy 154.285129 -374.233202) (xy 154.24941 -374.191984) (xy 154.219921 -374.146102) (xy 154.197261 -374.096489)
			(xy 154.181894 -374.044157) (xy 154.174132 -373.990171) (xy 148.993106 -373.990171) (xy 148.985344 -374.044153)
			(xy 148.96998 -374.096484) (xy 148.947325 -374.146095) (xy 148.917841 -374.191977) (xy 148.882128 -374.233197)
			(xy 148.840912 -374.268915) (xy 148.795033 -374.298404) (xy 148.745425 -374.321065) (xy 148.693097 -374.336435)
			(xy 148.639113 -374.344202) (xy 148.611844 -374.344692) (xy 147.748244 -374.344692) (xy 147.720973 -374.344172)
			(xy 147.666986 -374.336415) (xy 147.614652 -374.321054) (xy 147.565037 -374.298401) (xy 147.519151 -374.268916)
			(xy 147.477929 -374.233202) (xy 147.44221 -374.191984) (xy 147.412721 -374.146102) (xy 147.390061 -374.096489)
			(xy 147.374694 -374.044157) (xy 147.366932 -373.990171) (xy 130.079828 -373.990171) (xy 130.079828 -373.990173)
			(xy 130.072066 -374.044165) (xy 130.056698 -374.096502) (xy 130.034038 -374.146119) (xy 130.004548 -374.192007)
			(xy 129.968827 -374.23323) (xy 129.927603 -374.26895) (xy 129.881716 -374.29844) (xy 129.832098 -374.321099)
			(xy 129.779761 -374.336466) (xy 129.725769 -374.344229) (xy 129.698496 -374.344692) (xy 128.834896 -374.344692)
			(xy 128.807629 -374.344145) (xy 128.75365 -374.336384) (xy 128.701325 -374.321019) (xy 128.651719 -374.298365)
			(xy 128.605842 -374.268881) (xy 128.564629 -374.233169) (xy 128.528917 -374.191954) (xy 128.499433 -374.146077)
			(xy 128.476779 -374.096471) (xy 128.461415 -374.044146) (xy 128.453654 -373.990167) (xy 123.272628 -373.990167)
			(xy 123.272628 -373.990173) (xy 123.264866 -374.044165) (xy 123.249498 -374.096502) (xy 123.226838 -374.146119)
			(xy 123.197348 -374.192007) (xy 123.161627 -374.23323) (xy 123.120403 -374.26895) (xy 123.074516 -374.29844)
			(xy 123.024898 -374.321099) (xy 122.972561 -374.336466) (xy 122.918569 -374.344229) (xy 122.891296 -374.344692)
			(xy 122.027696 -374.344692) (xy 122.000429 -374.344145) (xy 121.94645 -374.336384) (xy 121.894125 -374.321019)
			(xy 121.844519 -374.298365) (xy 121.798642 -374.268881) (xy 121.757429 -374.233169) (xy 121.721717 -374.191954)
			(xy 121.692233 -374.146077) (xy 121.669579 -374.096471) (xy 121.654215 -374.044146) (xy 121.646454 -373.990167)
			(xy 116.465428 -373.990167) (xy 116.465428 -373.990173) (xy 116.457666 -374.044165) (xy 116.442298 -374.096502)
			(xy 116.419638 -374.146119) (xy 116.390148 -374.192007) (xy 116.354427 -374.23323) (xy 116.313203 -374.26895)
			(xy 116.267316 -374.29844) (xy 116.217698 -374.321099) (xy 116.165361 -374.336466) (xy 116.111369 -374.344229)
			(xy 116.084096 -374.344692) (xy 115.220496 -374.344692) (xy 115.193229 -374.344145) (xy 115.13925 -374.336384)
			(xy 115.086925 -374.321019) (xy 115.037319 -374.298365) (xy 114.991442 -374.268881) (xy 114.950229 -374.233169)
			(xy 114.914517 -374.191954) (xy 114.885033 -374.146077) (xy 114.862379 -374.096471) (xy 114.847015 -374.044146)
			(xy 114.839254 -373.990167) (xy 95.507606 -373.990167) (xy 95.507606 -373.990171) (xy 95.499843 -374.044159)
			(xy 95.484477 -374.096493) (xy 95.461819 -374.146107) (xy 95.432331 -374.191991) (xy 95.396613 -374.233212)
			(xy 95.355393 -374.26893) (xy 95.309508 -374.298418) (xy 95.259894 -374.321076) (xy 95.207561 -374.336443)
			(xy 95.153573 -374.344205) (xy 95.126302 -374.344692) (xy 94.262702 -374.344692) (xy 94.235433 -374.344169)
			(xy 94.18145 -374.336407) (xy 94.129121 -374.321043) (xy 94.079512 -374.298387) (xy 94.033632 -374.268902)
			(xy 93.992414 -374.233187) (xy 93.9567 -374.19197) (xy 93.927214 -374.14609) (xy 93.904558 -374.09648)
			(xy 93.889193 -374.044152) (xy 93.881431 -373.990169) (xy 88.700406 -373.990169) (xy 88.700406 -373.990171)
			(xy 88.692643 -374.044159) (xy 88.677277 -374.096493) (xy 88.654619 -374.146107) (xy 88.625131 -374.191991)
			(xy 88.589413 -374.233212) (xy 88.548193 -374.26893) (xy 88.502308 -374.298418) (xy 88.452694 -374.321076)
			(xy 88.400361 -374.336443) (xy 88.346373 -374.344205) (xy 88.319102 -374.344692) (xy 87.455502 -374.344692)
			(xy 87.428233 -374.344169) (xy 87.37425 -374.336407) (xy 87.321921 -374.321043) (xy 87.272312 -374.298387)
			(xy 87.226432 -374.268902) (xy 87.185214 -374.233187) (xy 87.1495 -374.19197) (xy 87.120014 -374.14609)
			(xy 87.097358 -374.09648) (xy 87.081993 -374.044152) (xy 87.074231 -373.990169) (xy 81.893206 -373.990169)
			(xy 81.893206 -373.990171) (xy 81.885443 -374.044159) (xy 81.870077 -374.096493) (xy 81.847419 -374.146107)
			(xy 81.817931 -374.191991) (xy 81.782213 -374.233212) (xy 81.740993 -374.26893) (xy 81.695108 -374.298418)
			(xy 81.645494 -374.321076) (xy 81.593161 -374.336443) (xy 81.539173 -374.344205) (xy 81.511902 -374.344692)
			(xy 80.648302 -374.344692) (xy 80.621033 -374.344169) (xy 80.56705 -374.336407) (xy 80.514721 -374.321043)
			(xy 80.465112 -374.298387) (xy 80.419232 -374.268902) (xy 80.378014 -374.233187) (xy 80.3423 -374.19197)
			(xy 80.312814 -374.14609) (xy 80.290158 -374.09648) (xy 80.274793 -374.044152) (xy 80.267031 -373.990169)
			(xy 62.979928 -373.990169) (xy 62.979928 -373.990175) (xy 62.972164 -374.04417) (xy 62.956795 -374.096511)
			(xy 62.934132 -374.146131) (xy 62.904638 -374.19202) (xy 62.868912 -374.233245) (xy 62.827684 -374.268965)
			(xy 62.781791 -374.298454) (xy 62.732168 -374.321111) (xy 62.679825 -374.336474) (xy 62.625829 -374.344232)
			(xy 62.598554 -374.344692) (xy 61.734954 -374.344692) (xy 61.707689 -374.344143) (xy 61.653715 -374.336376)
			(xy 61.601395 -374.321008) (xy 61.551794 -374.298351) (xy 61.505923 -374.268866) (xy 61.464714 -374.233154)
			(xy 61.429006 -374.191941) (xy 61.399527 -374.146065) (xy 61.376876 -374.096462) (xy 61.361514 -374.04414)
			(xy 61.353754 -373.990165) (xy 56.172728 -373.990165) (xy 56.172728 -373.990175) (xy 56.164964 -374.04417)
			(xy 56.149595 -374.096511) (xy 56.126932 -374.146131) (xy 56.097438 -374.19202) (xy 56.061712 -374.233245)
			(xy 56.020484 -374.268965) (xy 55.974591 -374.298454) (xy 55.924968 -374.321111) (xy 55.872625 -374.336474)
			(xy 55.818629 -374.344232) (xy 55.791354 -374.344692) (xy 54.927754 -374.344692) (xy 54.900489 -374.344143)
			(xy 54.846515 -374.336376) (xy 54.794195 -374.321008) (xy 54.744594 -374.298351) (xy 54.698723 -374.268866)
			(xy 54.657514 -374.233154) (xy 54.621806 -374.191941) (xy 54.592327 -374.146065) (xy 54.569676 -374.096462)
			(xy 54.554314 -374.04414) (xy 54.546554 -373.990165) (xy 49.365528 -373.990165) (xy 49.365528 -373.990175)
			(xy 49.357764 -374.04417) (xy 49.342395 -374.096511) (xy 49.319732 -374.146131) (xy 49.290238 -374.19202)
			(xy 49.254512 -374.233245) (xy 49.213284 -374.268965) (xy 49.167391 -374.298454) (xy 49.117768 -374.321111)
			(xy 49.065425 -374.336474) (xy 49.011429 -374.344232) (xy 48.984154 -374.344692) (xy 48.120554 -374.344692)
			(xy 48.093289 -374.344143) (xy 48.039315 -374.336376) (xy 47.986995 -374.321008) (xy 47.937394 -374.298351)
			(xy 47.891523 -374.268866) (xy 47.850314 -374.233154) (xy 47.814606 -374.191941) (xy 47.785127 -374.146065)
			(xy 47.762476 -374.096462) (xy 47.747114 -374.04414) (xy 47.739354 -373.990165) (xy 38.193125 -373.990165)
			(xy 38.26468 -374.080777) (xy 38.368831 -374.22548) (xy 38.466433 -374.374679) (xy 38.557291 -374.528078)
			(xy 38.641225 -374.685372) (xy 38.71807 -374.846248) (xy 38.787671 -375.010389) (xy 38.849892 -375.177466)
			(xy 38.904608 -375.34715) (xy 38.95171 -375.519103) (xy 38.991106 -375.692983) (xy 39.022717 -375.868446)
			(xy 39.046481 -376.045142) (xy 39.062349 -376.222722) (xy 39.070291 -376.400832) (xy 39.070788 -376.489976)
			(xy 39.070291 -376.57912) (xy 39.062349 -376.75723) (xy 39.05568 -376.83186) (xy 41.04894 -376.83186)
			(xy 41.04894 -375.96826) (xy 41.049426 -375.940991) (xy 41.057188 -375.887007) (xy 41.072553 -375.834677)
			(xy 41.09521 -375.785067) (xy 41.124696 -375.739186) (xy 41.160411 -375.697969) (xy 41.201628 -375.662254)
			(xy 41.247509 -375.632768) (xy 41.297119 -375.610111) (xy 41.349449 -375.594746) (xy 41.403433 -375.586984)
			(xy 41.457971 -375.586984) (xy 41.511955 -375.594746) (xy 41.564285 -375.610111) (xy 41.613895 -375.632768)
			(xy 41.659776 -375.662254) (xy 41.700993 -375.697969) (xy 41.736708 -375.739186) (xy 41.766194 -375.785067)
			(xy 41.788851 -375.834677) (xy 41.804216 -375.887007) (xy 41.811978 -375.940991) (xy 41.812464 -375.96826)
			(xy 41.812464 -376.83186) (xy 41.811978 -376.859129) (xy 41.804216 -376.913113) (xy 41.791381 -376.956828)
			(xy 70.895972 -376.956828) (xy 70.895972 -376.093228) (xy 70.896458 -376.065959) (xy 70.90422 -376.011975)
			(xy 70.919585 -375.959645) (xy 70.942242 -375.910035) (xy 70.971728 -375.864154) (xy 71.007443 -375.822937)
			(xy 71.04866 -375.787222) (xy 71.094541 -375.757736) (xy 71.144151 -375.735079) (xy 71.196481 -375.719714)
			(xy 71.250465 -375.711952) (xy 71.305003 -375.711952) (xy 71.358987 -375.719714) (xy 71.411317 -375.735079)
			(xy 71.460927 -375.757736) (xy 71.506808 -375.787222) (xy 71.548025 -375.822937) (xy 71.58374 -375.864154)
			(xy 71.613226 -375.910035) (xy 71.635883 -375.959645) (xy 71.651248 -376.011975) (xy 71.65901 -376.065959)
			(xy 71.659496 -376.093228) (xy 71.659496 -376.83186) (xy 73.576688 -376.83186) (xy 73.576688 -375.96826)
			(xy 73.577174 -375.940991) (xy 73.584936 -375.887007) (xy 73.600301 -375.834677) (xy 73.622958 -375.785067)
			(xy 73.652444 -375.739186) (xy 73.688159 -375.697969) (xy 73.729376 -375.662254) (xy 73.775257 -375.632768)
			(xy 73.824867 -375.610111) (xy 73.877197 -375.594746) (xy 73.931181 -375.586984) (xy 73.985719 -375.586984)
			(xy 74.039703 -375.594746) (xy 74.092033 -375.610111) (xy 74.141643 -375.632768) (xy 74.187524 -375.662254)
			(xy 74.228741 -375.697969) (xy 74.264456 -375.739186) (xy 74.293942 -375.785067) (xy 74.316599 -375.834677)
			(xy 74.331964 -375.887007) (xy 74.339726 -375.940991) (xy 74.340212 -375.96826) (xy 74.340212 -376.83186)
			(xy 74.339726 -376.859129) (xy 74.331964 -376.913113) (xy 74.319129 -376.956828) (xy 103.42372 -376.956828)
			(xy 103.42372 -376.093228) (xy 103.424206 -376.065959) (xy 103.431968 -376.011975) (xy 103.447333 -375.959645)
			(xy 103.46999 -375.910035) (xy 103.499476 -375.864154) (xy 103.535191 -375.822937) (xy 103.576408 -375.787222)
			(xy 103.622289 -375.757736) (xy 103.671899 -375.735079) (xy 103.724229 -375.719714) (xy 103.778213 -375.711952)
			(xy 103.832751 -375.711952) (xy 103.886735 -375.719714) (xy 103.939065 -375.735079) (xy 103.988675 -375.757736)
			(xy 104.034556 -375.787222) (xy 104.075773 -375.822937) (xy 104.111488 -375.864154) (xy 104.140974 -375.910035)
			(xy 104.163631 -375.959645) (xy 104.178996 -376.011975) (xy 104.186758 -376.065959) (xy 104.187244 -376.093228)
			(xy 104.187244 -376.83186) (xy 108.149136 -376.83186) (xy 108.149136 -375.96826) (xy 108.149622 -375.941009)
			(xy 108.157378 -375.887061) (xy 108.172733 -375.834766) (xy 108.195375 -375.785189) (xy 108.224841 -375.739339)
			(xy 108.260532 -375.698148) (xy 108.301723 -375.662457) (xy 108.347573 -375.632991) (xy 108.39715 -375.610349)
			(xy 108.449445 -375.594994) (xy 108.503393 -375.587238) (xy 108.557895 -375.587238) (xy 108.611843 -375.594994)
			(xy 108.664138 -375.610349) (xy 108.713715 -375.632991) (xy 108.759565 -375.662457) (xy 108.800756 -375.698148)
			(xy 108.836447 -375.739339) (xy 108.865913 -375.785189) (xy 108.888555 -375.834766) (xy 108.90391 -375.887061)
			(xy 108.911666 -375.941009) (xy 108.912152 -375.96826) (xy 108.912152 -376.83186) (xy 108.911666 -376.859111)
			(xy 108.90391 -376.913059) (xy 108.891058 -376.956828) (xy 137.996168 -376.956828) (xy 137.996168 -376.093228)
			(xy 137.996654 -376.065977) (xy 138.00441 -376.012029) (xy 138.019765 -375.959734) (xy 138.042407 -375.910157)
			(xy 138.071873 -375.864307) (xy 138.107564 -375.823116) (xy 138.148755 -375.787425) (xy 138.194605 -375.757959)
			(xy 138.244182 -375.735317) (xy 138.296477 -375.719962) (xy 138.350425 -375.712206) (xy 138.404927 -375.712206)
			(xy 138.458875 -375.719962) (xy 138.51117 -375.735317) (xy 138.560747 -375.757959) (xy 138.606597 -375.787425)
			(xy 138.647788 -375.823116) (xy 138.683479 -375.864307) (xy 138.712945 -375.910157) (xy 138.735587 -375.959734)
			(xy 138.750942 -376.012029) (xy 138.758698 -376.065977) (xy 138.759184 -376.093228) (xy 138.759184 -376.83186)
			(xy 140.676884 -376.83186) (xy 140.676884 -375.96826) (xy 140.67737 -375.941009) (xy 140.685126 -375.887061)
			(xy 140.700481 -375.834766) (xy 140.723123 -375.785189) (xy 140.752589 -375.739339) (xy 140.78828 -375.698148)
			(xy 140.829471 -375.662457) (xy 140.875321 -375.632991) (xy 140.924898 -375.610349) (xy 140.977193 -375.594994)
			(xy 141.031141 -375.587238) (xy 141.085643 -375.587238) (xy 141.139591 -375.594994) (xy 141.191886 -375.610349)
			(xy 141.241463 -375.632991) (xy 141.287313 -375.662457) (xy 141.328504 -375.698148) (xy 141.364195 -375.739339)
			(xy 141.393661 -375.785189) (xy 141.416303 -375.834766) (xy 141.431658 -375.887061) (xy 141.439414 -375.941009)
			(xy 141.4399 -375.96826) (xy 141.4399 -376.83186) (xy 141.439414 -376.859111) (xy 141.431658 -376.913059)
			(xy 141.418806 -376.956828) (xy 170.523916 -376.956828) (xy 170.523916 -376.093228) (xy 170.524402 -376.065977)
			(xy 170.532158 -376.012029) (xy 170.547513 -375.959734) (xy 170.570155 -375.910157) (xy 170.599621 -375.864307)
			(xy 170.635312 -375.823116) (xy 170.676503 -375.787425) (xy 170.722353 -375.757959) (xy 170.77193 -375.735317)
			(xy 170.824225 -375.719962) (xy 170.878173 -375.712206) (xy 170.932675 -375.712206) (xy 170.986623 -375.719962)
			(xy 171.038918 -375.735317) (xy 171.088495 -375.757959) (xy 171.134345 -375.787425) (xy 171.175536 -375.823116)
			(xy 171.211227 -375.864307) (xy 171.240693 -375.910157) (xy 171.263335 -375.959734) (xy 171.27869 -376.012029)
			(xy 171.286446 -376.065977) (xy 171.286932 -376.093228) (xy 171.286932 -376.489976) (xy 173.498776 -376.489976)
			(xy 173.502748 -376.311733) (xy 173.514656 -376.133844) (xy 173.534477 -375.956662) (xy 173.562171 -375.780538)
			(xy 173.597683 -375.605823) (xy 173.640943 -375.432864) (xy 173.691865 -375.262003) (xy 173.750348 -375.093581)
			(xy 173.816275 -374.927931) (xy 173.889516 -374.765382) (xy 173.969926 -374.606257) (xy 174.057344 -374.450872)
			(xy 174.151597 -374.299536) (xy 174.252498 -374.152548) (xy 174.359847 -374.010201) (xy 174.47343 -373.872778)
			(xy 174.593023 -373.740551) (xy 174.718387 -373.613782) (xy 174.849274 -373.492724) (xy 174.985423 -373.377617)
			(xy 175.126565 -373.268689) (xy 175.27242 -373.166157) (xy 175.422697 -373.070223) (xy 175.577098 -372.98108)
			(xy 175.735317 -372.898903) (xy 175.89704 -372.823855) (xy 176.061945 -372.756087) (xy 176.229706 -372.695731)
			(xy 176.399989 -372.642909) (xy 176.572456 -372.597725) (xy 176.746764 -372.560268) (xy 176.922568 -372.530614)
			(xy 177.099518 -372.508821) (xy 177.277264 -372.494931) (xy 177.455451 -372.488974) (xy 177.633728 -372.49096)
			(xy 177.811739 -372.500886) (xy 177.989131 -372.518732) (xy 178.165551 -372.544462) (xy 178.340651 -372.578026)
			(xy 178.514082 -372.619356) (xy 178.685499 -372.668372) (xy 178.854562 -372.724974) (xy 179.020937 -372.789052)
			(xy 179.184291 -372.860478) (xy 179.344302 -372.93911) (xy 179.500651 -373.024791) (xy 179.653028 -373.117353)
			(xy 179.801131 -373.21661) (xy 179.944665 -373.322367) (xy 180.083345 -373.434412) (xy 180.216896 -373.552524)
			(xy 180.345053 -373.676468) (xy 180.467562 -373.805998) (xy 180.584179 -373.940857) (xy 180.596796 -373.956834)
			(xy 282.853384 -373.956834) (xy 282.853384 -373.093234) (xy 282.85387 -373.065983) (xy 282.861626 -373.012035)
			(xy 282.876981 -372.95974) (xy 282.899623 -372.910163) (xy 282.929089 -372.864313) (xy 282.96478 -372.823122)
			(xy 283.005971 -372.787431) (xy 283.051821 -372.757965) (xy 283.101398 -372.735323) (xy 283.153693 -372.719968)
			(xy 283.207641 -372.712212) (xy 283.262143 -372.712212) (xy 283.316091 -372.719968) (xy 283.368386 -372.735323)
			(xy 283.417963 -372.757965) (xy 283.463813 -372.787431) (xy 283.505004 -372.823122) (xy 283.540695 -372.864313)
			(xy 283.570161 -372.910163) (xy 283.592803 -372.95974) (xy 283.608158 -373.012035) (xy 283.615914 -373.065983)
			(xy 283.6164 -373.093234) (xy 283.6164 -373.956834) (xy 283.615914 -373.984085) (xy 283.608158 -374.038033)
			(xy 283.592803 -374.090328) (xy 283.570161 -374.139905) (xy 283.540695 -374.185755) (xy 283.505004 -374.226946)
			(xy 283.463813 -374.262637) (xy 283.417963 -374.292103) (xy 283.368386 -374.314745) (xy 283.316091 -374.3301)
			(xy 283.262143 -374.337856) (xy 283.207641 -374.337856) (xy 283.153693 -374.3301) (xy 283.101398 -374.314745)
			(xy 283.051821 -374.292103) (xy 283.005971 -374.262637) (xy 282.96478 -374.226946) (xy 282.929089 -374.185755)
			(xy 282.899623 -374.139905) (xy 282.876981 -374.090328) (xy 282.861626 -374.038033) (xy 282.85387 -373.984085)
			(xy 282.853384 -373.956834) (xy 180.596796 -373.956834) (xy 180.694672 -374.080777) (xy 180.798823 -374.22548)
			(xy 180.896425 -374.374679) (xy 180.987283 -374.528078) (xy 181.071217 -374.685372) (xy 181.148062 -374.846248)
			(xy 181.217663 -375.010389) (xy 181.279884 -375.177466) (xy 181.3346 -375.34715) (xy 181.381702 -375.519103)
			(xy 181.421098 -375.692983) (xy 181.452709 -375.868446) (xy 181.476473 -376.045142) (xy 181.492341 -376.222722)
			(xy 181.500283 -376.400832) (xy 181.50078 -376.489976) (xy 181.500283 -376.57912) (xy 181.492341 -376.75723)
			(xy 181.476473 -376.93481) (xy 181.452709 -377.111506) (xy 181.421098 -377.286969) (xy 181.381702 -377.460849)
			(xy 181.3346 -377.632802) (xy 181.319901 -377.678385) (xy 193.900548 -377.678385) (xy 193.900548 -377.593663)
			(xy 193.908601 -377.509326) (xy 193.924635 -377.426136) (xy 193.948503 -377.344846) (xy 193.979991 -377.266194)
			(xy 194.018813 -377.190891) (xy 194.064616 -377.119619) (xy 194.116987 -377.053023) (xy 194.175452 -376.991708)
			(xy 194.23948 -376.936227) (xy 194.308492 -376.887084) (xy 194.381862 -376.844724) (xy 194.458927 -376.809529)
			(xy 194.538989 -376.78182) (xy 194.621322 -376.761846) (xy 194.705181 -376.749789) (xy 194.789806 -376.745758)
			(xy 194.874431 -376.749789) (xy 194.95829 -376.761846) (xy 195.040623 -376.78182) (xy 195.120685 -376.809529)
			(xy 195.19775 -376.844724) (xy 195.27112 -376.887084) (xy 195.340132 -376.936227) (xy 195.40416 -376.991708)
			(xy 195.462625 -377.053023) (xy 195.514996 -377.119619) (xy 195.560799 -377.190891) (xy 195.599621 -377.266194)
			(xy 195.631109 -377.344846) (xy 195.654977 -377.426136) (xy 195.671011 -377.509326) (xy 195.679064 -377.593663)
			(xy 195.679568 -377.636024) (xy 195.679064 -377.678385) (xy 195.671011 -377.762722) (xy 195.654977 -377.845912)
			(xy 195.631109 -377.927202) (xy 195.599621 -378.005854) (xy 195.560799 -378.081157) (xy 195.514996 -378.152429)
			(xy 195.47531 -378.202895) (xy 199.443082 -378.202895) (xy 199.443082 -378.118173) (xy 199.451135 -378.033836)
			(xy 199.467169 -377.950646) (xy 199.491037 -377.869356) (xy 199.522525 -377.790704) (xy 199.561347 -377.715401)
			(xy 199.60715 -377.644129) (xy 199.659521 -377.577533) (xy 199.717986 -377.516218) (xy 199.782014 -377.460737)
			(xy 199.851026 -377.411594) (xy 199.924396 -377.369234) (xy 200.001461 -377.334039) (xy 200.081523 -377.30633)
			(xy 200.163856 -377.286356) (xy 200.247715 -377.274299) (xy 200.33234 -377.270268) (xy 200.416965 -377.274299)
			(xy 200.500824 -377.286356) (xy 200.583157 -377.30633) (xy 200.663219 -377.334039) (xy 200.740284 -377.369234)
			(xy 200.813654 -377.411594) (xy 200.859958 -377.444567) (xy 300.335454 -377.444567) (xy 300.335454 -377.390033)
			(xy 300.343215 -377.336054) (xy 300.358579 -377.283729) (xy 300.381233 -377.234123) (xy 300.410717 -377.188246)
			(xy 300.446429 -377.147031) (xy 300.487642 -377.111319) (xy 300.533519 -377.081835) (xy 300.583125 -377.059181)
			(xy 300.63545 -377.043816) (xy 300.689429 -377.036055) (xy 300.716696 -377.035568) (xy 301.580296 -377.035568)
			(xy 301.607569 -377.035971) (xy 301.661561 -377.043734) (xy 301.713898 -377.059101) (xy 301.763516 -377.08176)
			(xy 301.809403 -377.11125) (xy 301.850627 -377.14697) (xy 301.886348 -377.188193) (xy 301.915838 -377.234081)
			(xy 301.938498 -377.283698) (xy 301.953866 -377.336035) (xy 301.961628 -377.390027) (xy 301.961628 -377.444567)
			(xy 307.142654 -377.444567) (xy 307.142654 -377.390033) (xy 307.150415 -377.336054) (xy 307.165779 -377.283729)
			(xy 307.188433 -377.234123) (xy 307.217917 -377.188246) (xy 307.253629 -377.147031) (xy 307.294842 -377.111319)
			(xy 307.340719 -377.081835) (xy 307.390325 -377.059181) (xy 307.44265 -377.043816) (xy 307.496629 -377.036055)
			(xy 307.523896 -377.035568) (xy 308.387496 -377.035568) (xy 308.414769 -377.035971) (xy 308.468761 -377.043734)
			(xy 308.521098 -377.059101) (xy 308.570716 -377.08176) (xy 308.616603 -377.11125) (xy 308.657827 -377.14697)
			(xy 308.693548 -377.188193) (xy 308.723038 -377.234081) (xy 308.745698 -377.283698) (xy 308.761066 -377.336035)
			(xy 308.768828 -377.390027) (xy 308.768828 -377.444567) (xy 313.949854 -377.444567) (xy 313.949854 -377.390033)
			(xy 313.957615 -377.336054) (xy 313.972979 -377.283729) (xy 313.995633 -377.234123) (xy 314.025117 -377.188246)
			(xy 314.060829 -377.147031) (xy 314.102042 -377.111319) (xy 314.147919 -377.081835) (xy 314.197525 -377.059181)
			(xy 314.24985 -377.043816) (xy 314.303829 -377.036055) (xy 314.331096 -377.035568) (xy 315.194696 -377.035568)
			(xy 315.221969 -377.035971) (xy 315.275961 -377.043734) (xy 315.328298 -377.059101) (xy 315.377916 -377.08176)
			(xy 315.423803 -377.11125) (xy 315.465027 -377.14697) (xy 315.500748 -377.188193) (xy 315.530238 -377.234081)
			(xy 315.552898 -377.283698) (xy 315.568266 -377.336035) (xy 315.576028 -377.390027) (xy 315.576028 -377.444567)
			(xy 320.757054 -377.444567) (xy 320.757054 -377.390033) (xy 320.764815 -377.336054) (xy 320.780179 -377.283729)
			(xy 320.802833 -377.234123) (xy 320.832317 -377.188246) (xy 320.868029 -377.147031) (xy 320.909242 -377.111319)
			(xy 320.955119 -377.081835) (xy 321.004725 -377.059181) (xy 321.05705 -377.043816) (xy 321.111029 -377.036055)
			(xy 321.138296 -377.035568) (xy 322.001896 -377.035568) (xy 322.029169 -377.035971) (xy 322.083161 -377.043734)
			(xy 322.135498 -377.059101) (xy 322.185116 -377.08176) (xy 322.231003 -377.11125) (xy 322.272227 -377.14697)
			(xy 322.307948 -377.188193) (xy 322.337438 -377.234081) (xy 322.360098 -377.283698) (xy 322.375466 -377.336035)
			(xy 322.383228 -377.390027) (xy 322.383228 -377.444567) (xy 324.160654 -377.444567) (xy 324.160654 -377.390033)
			(xy 324.168415 -377.336054) (xy 324.183779 -377.283729) (xy 324.206433 -377.234123) (xy 324.235917 -377.188246)
			(xy 324.271629 -377.147031) (xy 324.312842 -377.111319) (xy 324.358719 -377.081835) (xy 324.408325 -377.059181)
			(xy 324.46065 -377.043816) (xy 324.514629 -377.036055) (xy 324.541896 -377.035568) (xy 325.405496 -377.035568)
			(xy 325.432769 -377.035971) (xy 325.486761 -377.043734) (xy 325.539098 -377.059101) (xy 325.588716 -377.08176)
			(xy 325.634603 -377.11125) (xy 325.675827 -377.14697) (xy 325.711548 -377.188193) (xy 325.741038 -377.234081)
			(xy 325.763698 -377.283698) (xy 325.779066 -377.336035) (xy 325.786828 -377.390027) (xy 325.786828 -377.444571)
			(xy 332.863132 -377.444571) (xy 332.863132 -377.390029) (xy 332.870894 -377.336043) (xy 332.886261 -377.283711)
			(xy 332.908921 -377.234098) (xy 332.93841 -377.188216) (xy 332.974129 -377.146998) (xy 333.015351 -377.111284)
			(xy 333.061237 -377.081799) (xy 333.110852 -377.059146) (xy 333.163186 -377.043785) (xy 333.217173 -377.036028)
			(xy 333.244444 -377.035568) (xy 334.108044 -377.035568) (xy 334.135313 -377.035998) (xy 334.189297 -377.043765)
			(xy 334.241625 -377.059135) (xy 334.291233 -377.081796) (xy 334.337112 -377.111285) (xy 334.378328 -377.147003)
			(xy 334.414041 -377.188223) (xy 334.443525 -377.234105) (xy 334.46618 -377.283716) (xy 334.481544 -377.336047)
			(xy 334.489306 -377.39003) (xy 334.489306 -377.44457) (xy 334.489306 -377.444571) (xy 339.670332 -377.444571)
			(xy 339.670332 -377.390029) (xy 339.678094 -377.336043) (xy 339.693461 -377.283711) (xy 339.716121 -377.234098)
			(xy 339.74561 -377.188216) (xy 339.781329 -377.146998) (xy 339.822551 -377.111284) (xy 339.868437 -377.081799)
			(xy 339.918052 -377.059146) (xy 339.970386 -377.043785) (xy 340.024373 -377.036028) (xy 340.051644 -377.035568)
			(xy 340.915244 -377.035568) (xy 340.942513 -377.035998) (xy 340.996497 -377.043765) (xy 341.048825 -377.059135)
			(xy 341.098433 -377.081796) (xy 341.144312 -377.111285) (xy 341.185528 -377.147003) (xy 341.221241 -377.188223)
			(xy 341.250725 -377.234105) (xy 341.27338 -377.283716) (xy 341.288744 -377.336047) (xy 341.296506 -377.39003)
			(xy 341.296506 -377.44457) (xy 341.296506 -377.444571) (xy 346.477532 -377.444571) (xy 346.477532 -377.390029)
			(xy 346.485294 -377.336043) (xy 346.500661 -377.283711) (xy 346.523321 -377.234098) (xy 346.55281 -377.188216)
			(xy 346.588529 -377.146998) (xy 346.629751 -377.111284) (xy 346.675637 -377.081799) (xy 346.725252 -377.059146)
			(xy 346.777586 -377.043785) (xy 346.831573 -377.036028) (xy 346.858844 -377.035568) (xy 347.722444 -377.035568)
			(xy 347.749713 -377.035998) (xy 347.803697 -377.043765) (xy 347.856025 -377.059135) (xy 347.905633 -377.081796)
			(xy 347.951512 -377.111285) (xy 347.992728 -377.147003) (xy 348.028441 -377.188223) (xy 348.057925 -377.234105)
			(xy 348.08058 -377.283716) (xy 348.095944 -377.336047) (xy 348.103706 -377.39003) (xy 348.103706 -377.44457)
			(xy 348.103706 -377.444571) (xy 353.284732 -377.444571) (xy 353.284732 -377.390029) (xy 353.292494 -377.336043)
			(xy 353.307861 -377.283711) (xy 353.330521 -377.234098) (xy 353.36001 -377.188216) (xy 353.395729 -377.146998)
			(xy 353.436951 -377.111284) (xy 353.482837 -377.081799) (xy 353.532452 -377.059146) (xy 353.584786 -377.043785)
			(xy 353.638773 -377.036028) (xy 353.666044 -377.035568) (xy 354.529644 -377.035568) (xy 354.556913 -377.035998)
			(xy 354.610897 -377.043765) (xy 354.663225 -377.059135) (xy 354.712833 -377.081796) (xy 354.758712 -377.111285)
			(xy 354.799928 -377.147003) (xy 354.835641 -377.188223) (xy 354.865125 -377.234105) (xy 354.88778 -377.283716)
			(xy 354.903144 -377.336047) (xy 354.910906 -377.39003) (xy 354.910906 -377.44457) (xy 354.910906 -377.444571)
			(xy 356.688332 -377.444571) (xy 356.688332 -377.390029) (xy 356.696094 -377.336043) (xy 356.711461 -377.283711)
			(xy 356.734121 -377.234098) (xy 356.76361 -377.188216) (xy 356.799329 -377.146998) (xy 356.840551 -377.111284)
			(xy 356.886437 -377.081799) (xy 356.936052 -377.059146) (xy 356.988386 -377.043785) (xy 357.042373 -377.036028)
			(xy 357.069644 -377.035568) (xy 357.933244 -377.035568) (xy 357.960513 -377.035998) (xy 358.014497 -377.043765)
			(xy 358.066825 -377.059135) (xy 358.116433 -377.081796) (xy 358.162312 -377.111285) (xy 358.203528 -377.147003)
			(xy 358.239241 -377.188223) (xy 358.268725 -377.234105) (xy 358.29138 -377.283716) (xy 358.306744 -377.336047)
			(xy 358.314506 -377.39003) (xy 358.314506 -377.444567) (xy 367.435654 -377.444567) (xy 367.435654 -377.390033)
			(xy 367.443415 -377.336054) (xy 367.458779 -377.28373) (xy 367.481433 -377.234124) (xy 367.510916 -377.188247)
			(xy 367.546627 -377.147033) (xy 367.587841 -377.11132) (xy 367.633717 -377.081837) (xy 367.683322 -377.059182)
			(xy 367.735647 -377.043817) (xy 367.789625 -377.036055) (xy 367.816892 -377.035568) (xy 368.680492 -377.035568)
			(xy 368.707766 -377.035971) (xy 368.761757 -377.043733) (xy 368.814095 -377.0591) (xy 368.863713 -377.081759)
			(xy 368.909602 -377.111248) (xy 368.950826 -377.146968) (xy 368.986547 -377.188192) (xy 369.016038 -377.23408)
			(xy 369.038698 -377.283697) (xy 369.054065 -377.336035) (xy 369.061828 -377.390026) (xy 369.061828 -377.444567)
			(xy 374.242854 -377.444567) (xy 374.242854 -377.390033) (xy 374.250615 -377.336054) (xy 374.265979 -377.28373)
			(xy 374.288633 -377.234124) (xy 374.318116 -377.188247) (xy 374.353827 -377.147033) (xy 374.395041 -377.11132)
			(xy 374.440917 -377.081837) (xy 374.490522 -377.059182) (xy 374.542847 -377.043817) (xy 374.596825 -377.036055)
			(xy 374.624092 -377.035568) (xy 375.487692 -377.035568) (xy 375.514966 -377.035971) (xy 375.568957 -377.043733)
			(xy 375.621295 -377.0591) (xy 375.670913 -377.081759) (xy 375.716802 -377.111248) (xy 375.758026 -377.146968)
			(xy 375.793747 -377.188192) (xy 375.823238 -377.23408) (xy 375.845898 -377.283697) (xy 375.861265 -377.336035)
			(xy 375.869028 -377.390026) (xy 375.869028 -377.444567) (xy 381.050054 -377.444567) (xy 381.050054 -377.390033)
			(xy 381.057815 -377.336054) (xy 381.073179 -377.28373) (xy 381.095833 -377.234124) (xy 381.125316 -377.188247)
			(xy 381.161027 -377.147033) (xy 381.202241 -377.11132) (xy 381.248117 -377.081837) (xy 381.297722 -377.059182)
			(xy 381.350047 -377.043817) (xy 381.404025 -377.036055) (xy 381.431292 -377.035568) (xy 382.294892 -377.035568)
			(xy 382.322166 -377.035971) (xy 382.376157 -377.043733) (xy 382.428495 -377.0591) (xy 382.478113 -377.081759)
			(xy 382.524002 -377.111248) (xy 382.565226 -377.146968) (xy 382.600947 -377.188192) (xy 382.630438 -377.23408)
			(xy 382.653098 -377.283697) (xy 382.668465 -377.336035) (xy 382.676228 -377.390026) (xy 382.676228 -377.444567)
			(xy 387.857254 -377.444567) (xy 387.857254 -377.390033) (xy 387.865015 -377.336054) (xy 387.880379 -377.28373)
			(xy 387.903033 -377.234124) (xy 387.932516 -377.188247) (xy 387.968227 -377.147033) (xy 388.009441 -377.11132)
			(xy 388.055317 -377.081837) (xy 388.104922 -377.059182) (xy 388.157247 -377.043817) (xy 388.211225 -377.036055)
			(xy 388.238492 -377.035568) (xy 389.102092 -377.035568) (xy 389.129366 -377.035971) (xy 389.183357 -377.043733)
			(xy 389.235695 -377.0591) (xy 389.285313 -377.081759) (xy 389.331202 -377.111248) (xy 389.372426 -377.146968)
			(xy 389.408147 -377.188192) (xy 389.437638 -377.23408) (xy 389.460298 -377.283697) (xy 389.475665 -377.336035)
			(xy 389.483428 -377.390026) (xy 389.483428 -377.444567) (xy 391.260854 -377.444567) (xy 391.260854 -377.390033)
			(xy 391.268615 -377.336054) (xy 391.283979 -377.28373) (xy 391.306633 -377.234124) (xy 391.336116 -377.188247)
			(xy 391.371827 -377.147033) (xy 391.413041 -377.11132) (xy 391.458917 -377.081837) (xy 391.508522 -377.059182)
			(xy 391.560847 -377.043817) (xy 391.614825 -377.036055) (xy 391.642092 -377.035568) (xy 392.505692 -377.035568)
			(xy 392.532966 -377.035971) (xy 392.586957 -377.043733) (xy 392.639295 -377.0591) (xy 392.688913 -377.081759)
			(xy 392.734802 -377.111248) (xy 392.776026 -377.146968) (xy 392.811747 -377.188192) (xy 392.841238 -377.23408)
			(xy 392.863898 -377.283697) (xy 392.879265 -377.336035) (xy 392.887028 -377.390026) (xy 392.887028 -377.444571)
			(xy 399.963332 -377.444571) (xy 399.963332 -377.390029) (xy 399.971094 -377.336043) (xy 399.986461 -377.283711)
			(xy 400.00912 -377.234099) (xy 400.038609 -377.188217) (xy 400.074328 -377.147) (xy 400.11555 -377.111285)
			(xy 400.161435 -377.081801) (xy 400.211049 -377.059147) (xy 400.263382 -377.043786) (xy 400.317369 -377.036029)
			(xy 400.34464 -377.035568) (xy 401.20824 -377.035568) (xy 401.23551 -377.035997) (xy 401.289493 -377.043764)
			(xy 401.341822 -377.059134) (xy 401.391431 -377.081794) (xy 401.437311 -377.111284) (xy 401.478527 -377.147002)
			(xy 401.51424 -377.188222) (xy 401.543725 -377.234104) (xy 401.56638 -377.283716) (xy 401.581744 -377.336046)
			(xy 401.589506 -377.39003) (xy 401.589506 -377.44457) (xy 401.589506 -377.444571) (xy 406.770532 -377.444571)
			(xy 406.770532 -377.390029) (xy 406.778294 -377.336043) (xy 406.793661 -377.283711) (xy 406.81632 -377.234099)
			(xy 406.845809 -377.188217) (xy 406.881528 -377.147) (xy 406.92275 -377.111285) (xy 406.968635 -377.081801)
			(xy 407.018249 -377.059147) (xy 407.070582 -377.043786) (xy 407.124569 -377.036029) (xy 407.15184 -377.035568)
			(xy 408.01544 -377.035568) (xy 408.04271 -377.035997) (xy 408.096693 -377.043764) (xy 408.149022 -377.059134)
			(xy 408.198631 -377.081794) (xy 408.244511 -377.111284) (xy 408.285727 -377.147002) (xy 408.32144 -377.188222)
			(xy 408.350925 -377.234104) (xy 408.37358 -377.283716) (xy 408.388944 -377.336046) (xy 408.396706 -377.39003)
			(xy 408.396706 -377.44457) (xy 408.396706 -377.444571) (xy 413.577732 -377.444571) (xy 413.577732 -377.390029)
			(xy 413.585494 -377.336043) (xy 413.600861 -377.283711) (xy 413.62352 -377.234099) (xy 413.653009 -377.188217)
			(xy 413.688728 -377.147) (xy 413.72995 -377.111285) (xy 413.775835 -377.081801) (xy 413.825449 -377.059147)
			(xy 413.877782 -377.043786) (xy 413.931769 -377.036029) (xy 413.95904 -377.035568) (xy 414.82264 -377.035568)
			(xy 414.84991 -377.035997) (xy 414.903893 -377.043764) (xy 414.956222 -377.059134) (xy 415.005831 -377.081794)
			(xy 415.051711 -377.111284) (xy 415.092927 -377.147002) (xy 415.12864 -377.188222) (xy 415.158125 -377.234104)
			(xy 415.18078 -377.283716) (xy 415.196144 -377.336046) (xy 415.203906 -377.39003) (xy 415.203906 -377.44457)
			(xy 415.203906 -377.444571) (xy 420.384932 -377.444571) (xy 420.384932 -377.390029) (xy 420.392694 -377.336043)
			(xy 420.408061 -377.283711) (xy 420.43072 -377.234099) (xy 420.460209 -377.188217) (xy 420.495928 -377.147)
			(xy 420.53715 -377.111285) (xy 420.583035 -377.081801) (xy 420.632649 -377.059147) (xy 420.684982 -377.043786)
			(xy 420.738969 -377.036029) (xy 420.76624 -377.035568) (xy 421.62984 -377.035568) (xy 421.65711 -377.035997)
			(xy 421.711093 -377.043764) (xy 421.763422 -377.059134) (xy 421.813031 -377.081794) (xy 421.858911 -377.111284)
			(xy 421.900127 -377.147002) (xy 421.93584 -377.188222) (xy 421.965325 -377.234104) (xy 421.98798 -377.283716)
			(xy 422.003344 -377.336046) (xy 422.011106 -377.39003) (xy 422.011106 -377.44457) (xy 422.011106 -377.444571)
			(xy 423.788532 -377.444571) (xy 423.788532 -377.390029) (xy 423.796294 -377.336043) (xy 423.811661 -377.283711)
			(xy 423.83432 -377.234099) (xy 423.863809 -377.188217) (xy 423.899528 -377.147) (xy 423.94075 -377.111285)
			(xy 423.986635 -377.081801) (xy 424.036249 -377.059147) (xy 424.088582 -377.043786) (xy 424.142569 -377.036029)
			(xy 424.16984 -377.035568) (xy 425.03344 -377.035568) (xy 425.06071 -377.035997) (xy 425.114693 -377.043764)
			(xy 425.167022 -377.059134) (xy 425.216631 -377.081794) (xy 425.262511 -377.111284) (xy 425.303727 -377.147002)
			(xy 425.33944 -377.188222) (xy 425.368925 -377.234104) (xy 425.39158 -377.283716) (xy 425.406944 -377.336046)
			(xy 425.414706 -377.39003) (xy 425.414706 -377.44457) (xy 425.406944 -377.498554) (xy 425.39158 -377.550884)
			(xy 425.368925 -377.600496) (xy 425.33944 -377.646378) (xy 425.303727 -377.687598) (xy 425.262511 -377.723316)
			(xy 425.216631 -377.752806) (xy 425.167022 -377.775466) (xy 425.114693 -377.790836) (xy 425.06071 -377.798603)
			(xy 425.03344 -377.799092) (xy 424.16984 -377.799092) (xy 424.142569 -377.798571) (xy 424.088582 -377.790814)
			(xy 424.036249 -377.775453) (xy 423.986635 -377.752799) (xy 423.94075 -377.723315) (xy 423.899528 -377.6876)
			(xy 423.863809 -377.646383) (xy 423.83432 -377.600501) (xy 423.811661 -377.550889) (xy 423.796294 -377.498557)
			(xy 423.788532 -377.444571) (xy 422.011106 -377.444571) (xy 422.003344 -377.498554) (xy 421.98798 -377.550884)
			(xy 421.965325 -377.600496) (xy 421.93584 -377.646378) (xy 421.900127 -377.687598) (xy 421.858911 -377.723316)
			(xy 421.813031 -377.752806) (xy 421.763422 -377.775466) (xy 421.711093 -377.790836) (xy 421.65711 -377.798603)
			(xy 421.62984 -377.799092) (xy 420.76624 -377.799092) (xy 420.738969 -377.798571) (xy 420.684982 -377.790814)
			(xy 420.632649 -377.775453) (xy 420.583035 -377.752799) (xy 420.53715 -377.723315) (xy 420.495928 -377.6876)
			(xy 420.460209 -377.646383) (xy 420.43072 -377.600501) (xy 420.408061 -377.550889) (xy 420.392694 -377.498557)
			(xy 420.384932 -377.444571) (xy 415.203906 -377.444571) (xy 415.196144 -377.498554) (xy 415.18078 -377.550884)
			(xy 415.158125 -377.600496) (xy 415.12864 -377.646378) (xy 415.092927 -377.687598) (xy 415.051711 -377.723316)
			(xy 415.005831 -377.752806) (xy 414.956222 -377.775466) (xy 414.903893 -377.790836) (xy 414.84991 -377.798603)
			(xy 414.82264 -377.799092) (xy 413.95904 -377.799092) (xy 413.931769 -377.798571) (xy 413.877782 -377.790814)
			(xy 413.825449 -377.775453) (xy 413.775835 -377.752799) (xy 413.72995 -377.723315) (xy 413.688728 -377.6876)
			(xy 413.653009 -377.646383) (xy 413.62352 -377.600501) (xy 413.600861 -377.550889) (xy 413.585494 -377.498557)
			(xy 413.577732 -377.444571) (xy 408.396706 -377.444571) (xy 408.388944 -377.498554) (xy 408.37358 -377.550884)
			(xy 408.350925 -377.600496) (xy 408.32144 -377.646378) (xy 408.285727 -377.687598) (xy 408.244511 -377.723316)
			(xy 408.198631 -377.752806) (xy 408.149022 -377.775466) (xy 408.096693 -377.790836) (xy 408.04271 -377.798603)
			(xy 408.01544 -377.799092) (xy 407.15184 -377.799092) (xy 407.124569 -377.798571) (xy 407.070582 -377.790814)
			(xy 407.018249 -377.775453) (xy 406.968635 -377.752799) (xy 406.92275 -377.723315) (xy 406.881528 -377.6876)
			(xy 406.845809 -377.646383) (xy 406.81632 -377.600501) (xy 406.793661 -377.550889) (xy 406.778294 -377.498557)
			(xy 406.770532 -377.444571) (xy 401.589506 -377.444571) (xy 401.581744 -377.498554) (xy 401.56638 -377.550884)
			(xy 401.543725 -377.600496) (xy 401.51424 -377.646378) (xy 401.478527 -377.687598) (xy 401.437311 -377.723316)
			(xy 401.391431 -377.752806) (xy 401.341822 -377.775466) (xy 401.289493 -377.790836) (xy 401.23551 -377.798603)
			(xy 401.20824 -377.799092) (xy 400.34464 -377.799092) (xy 400.317369 -377.798571) (xy 400.263382 -377.790814)
			(xy 400.211049 -377.775453) (xy 400.161435 -377.752799) (xy 400.11555 -377.723315) (xy 400.074328 -377.6876)
			(xy 400.038609 -377.646383) (xy 400.00912 -377.600501) (xy 399.986461 -377.550889) (xy 399.971094 -377.498557)
			(xy 399.963332 -377.444571) (xy 392.887028 -377.444571) (xy 392.887028 -377.444574) (xy 392.879265 -377.498565)
			(xy 392.863898 -377.550903) (xy 392.841238 -377.60052) (xy 392.811747 -377.646408) (xy 392.776026 -377.687632)
			(xy 392.734802 -377.723352) (xy 392.688913 -377.752841) (xy 392.639295 -377.7755) (xy 392.586957 -377.790867)
			(xy 392.532966 -377.798629) (xy 392.505692 -377.799092) (xy 391.642092 -377.799092) (xy 391.614825 -377.798545)
			(xy 391.560847 -377.790783) (xy 391.508522 -377.775418) (xy 391.458917 -377.752763) (xy 391.413041 -377.72328)
			(xy 391.371827 -377.687567) (xy 391.336116 -377.646353) (xy 391.306633 -377.600476) (xy 391.283979 -377.55087)
			(xy 391.268615 -377.498546) (xy 391.260854 -377.444567) (xy 389.483428 -377.444567) (xy 389.483428 -377.444574)
			(xy 389.475665 -377.498565) (xy 389.460298 -377.550903) (xy 389.437638 -377.60052) (xy 389.408147 -377.646408)
			(xy 389.372426 -377.687632) (xy 389.331202 -377.723352) (xy 389.285313 -377.752841) (xy 389.235695 -377.7755)
			(xy 389.183357 -377.790867) (xy 389.129366 -377.798629) (xy 389.102092 -377.799092) (xy 388.238492 -377.799092)
			(xy 388.211225 -377.798545) (xy 388.157247 -377.790783) (xy 388.104922 -377.775418) (xy 388.055317 -377.752763)
			(xy 388.009441 -377.72328) (xy 387.968227 -377.687567) (xy 387.932516 -377.646353) (xy 387.903033 -377.600476)
			(xy 387.880379 -377.55087) (xy 387.865015 -377.498546) (xy 387.857254 -377.444567) (xy 382.676228 -377.444567)
			(xy 382.676228 -377.444574) (xy 382.668465 -377.498565) (xy 382.653098 -377.550903) (xy 382.630438 -377.60052)
			(xy 382.600947 -377.646408) (xy 382.565226 -377.687632) (xy 382.524002 -377.723352) (xy 382.478113 -377.752841)
			(xy 382.428495 -377.7755) (xy 382.376157 -377.790867) (xy 382.322166 -377.798629) (xy 382.294892 -377.799092)
			(xy 381.431292 -377.799092) (xy 381.404025 -377.798545) (xy 381.350047 -377.790783) (xy 381.297722 -377.775418)
			(xy 381.248117 -377.752763) (xy 381.202241 -377.72328) (xy 381.161027 -377.687567) (xy 381.125316 -377.646353)
			(xy 381.095833 -377.600476) (xy 381.073179 -377.55087) (xy 381.057815 -377.498546) (xy 381.050054 -377.444567)
			(xy 375.869028 -377.444567) (xy 375.869028 -377.444574) (xy 375.861265 -377.498565) (xy 375.845898 -377.550903)
			(xy 375.823238 -377.60052) (xy 375.793747 -377.646408) (xy 375.758026 -377.687632) (xy 375.716802 -377.723352)
			(xy 375.670913 -377.752841) (xy 375.621295 -377.7755) (xy 375.568957 -377.790867) (xy 375.514966 -377.798629)
			(xy 375.487692 -377.799092) (xy 374.624092 -377.799092) (xy 374.596825 -377.798545) (xy 374.542847 -377.790783)
			(xy 374.490522 -377.775418) (xy 374.440917 -377.752763) (xy 374.395041 -377.72328) (xy 374.353827 -377.687567)
			(xy 374.318116 -377.646353) (xy 374.288633 -377.600476) (xy 374.265979 -377.55087) (xy 374.250615 -377.498546)
			(xy 374.242854 -377.444567) (xy 369.061828 -377.444567) (xy 369.061828 -377.444574) (xy 369.054065 -377.498565)
			(xy 369.038698 -377.550903) (xy 369.016038 -377.60052) (xy 368.986547 -377.646408) (xy 368.950826 -377.687632)
			(xy 368.909602 -377.723352) (xy 368.863713 -377.752841) (xy 368.814095 -377.7755) (xy 368.761757 -377.790867)
			(xy 368.707766 -377.798629) (xy 368.680492 -377.799092) (xy 367.816892 -377.799092) (xy 367.789625 -377.798545)
			(xy 367.735647 -377.790783) (xy 367.683322 -377.775418) (xy 367.633717 -377.752763) (xy 367.587841 -377.72328)
			(xy 367.546627 -377.687567) (xy 367.510916 -377.646353) (xy 367.481433 -377.600476) (xy 367.458779 -377.55087)
			(xy 367.443415 -377.498546) (xy 367.435654 -377.444567) (xy 358.314506 -377.444567) (xy 358.314506 -377.44457)
			(xy 358.306744 -377.498553) (xy 358.29138 -377.550884) (xy 358.268725 -377.600495) (xy 358.239241 -377.646377)
			(xy 358.203528 -377.687597) (xy 358.162312 -377.723315) (xy 358.116433 -377.752804) (xy 358.066825 -377.775465)
			(xy 358.014497 -377.790835) (xy 357.960513 -377.798602) (xy 357.933244 -377.799092) (xy 357.069644 -377.799092)
			(xy 357.042373 -377.798572) (xy 356.988386 -377.790815) (xy 356.936052 -377.775454) (xy 356.886437 -377.752801)
			(xy 356.840551 -377.723316) (xy 356.799329 -377.687602) (xy 356.76361 -377.646384) (xy 356.734121 -377.600502)
			(xy 356.711461 -377.550889) (xy 356.696094 -377.498557) (xy 356.688332 -377.444571) (xy 354.910906 -377.444571)
			(xy 354.903144 -377.498553) (xy 354.88778 -377.550884) (xy 354.865125 -377.600495) (xy 354.835641 -377.646377)
			(xy 354.799928 -377.687597) (xy 354.758712 -377.723315) (xy 354.712833 -377.752804) (xy 354.663225 -377.775465)
			(xy 354.610897 -377.790835) (xy 354.556913 -377.798602) (xy 354.529644 -377.799092) (xy 353.666044 -377.799092)
			(xy 353.638773 -377.798572) (xy 353.584786 -377.790815) (xy 353.532452 -377.775454) (xy 353.482837 -377.752801)
			(xy 353.436951 -377.723316) (xy 353.395729 -377.687602) (xy 353.36001 -377.646384) (xy 353.330521 -377.600502)
			(xy 353.307861 -377.550889) (xy 353.292494 -377.498557) (xy 353.284732 -377.444571) (xy 348.103706 -377.444571)
			(xy 348.095944 -377.498553) (xy 348.08058 -377.550884) (xy 348.057925 -377.600495) (xy 348.028441 -377.646377)
			(xy 347.992728 -377.687597) (xy 347.951512 -377.723315) (xy 347.905633 -377.752804) (xy 347.856025 -377.775465)
			(xy 347.803697 -377.790835) (xy 347.749713 -377.798602) (xy 347.722444 -377.799092) (xy 346.858844 -377.799092)
			(xy 346.831573 -377.798572) (xy 346.777586 -377.790815) (xy 346.725252 -377.775454) (xy 346.675637 -377.752801)
			(xy 346.629751 -377.723316) (xy 346.588529 -377.687602) (xy 346.55281 -377.646384) (xy 346.523321 -377.600502)
			(xy 346.500661 -377.550889) (xy 346.485294 -377.498557) (xy 346.477532 -377.444571) (xy 341.296506 -377.444571)
			(xy 341.288744 -377.498553) (xy 341.27338 -377.550884) (xy 341.250725 -377.600495) (xy 341.221241 -377.646377)
			(xy 341.185528 -377.687597) (xy 341.144312 -377.723315) (xy 341.098433 -377.752804) (xy 341.048825 -377.775465)
			(xy 340.996497 -377.790835) (xy 340.942513 -377.798602) (xy 340.915244 -377.799092) (xy 340.051644 -377.799092)
			(xy 340.024373 -377.798572) (xy 339.970386 -377.790815) (xy 339.918052 -377.775454) (xy 339.868437 -377.752801)
			(xy 339.822551 -377.723316) (xy 339.781329 -377.687602) (xy 339.74561 -377.646384) (xy 339.716121 -377.600502)
			(xy 339.693461 -377.550889) (xy 339.678094 -377.498557) (xy 339.670332 -377.444571) (xy 334.489306 -377.444571)
			(xy 334.481544 -377.498553) (xy 334.46618 -377.550884) (xy 334.443525 -377.600495) (xy 334.414041 -377.646377)
			(xy 334.378328 -377.687597) (xy 334.337112 -377.723315) (xy 334.291233 -377.752804) (xy 334.241625 -377.775465)
			(xy 334.189297 -377.790835) (xy 334.135313 -377.798602) (xy 334.108044 -377.799092) (xy 333.244444 -377.799092)
			(xy 333.217173 -377.798572) (xy 333.163186 -377.790815) (xy 333.110852 -377.775454) (xy 333.061237 -377.752801)
			(xy 333.015351 -377.723316) (xy 332.974129 -377.687602) (xy 332.93841 -377.646384) (xy 332.908921 -377.600502)
			(xy 332.886261 -377.550889) (xy 332.870894 -377.498557) (xy 332.863132 -377.444571) (xy 325.786828 -377.444571)
			(xy 325.786828 -377.444573) (xy 325.779066 -377.498565) (xy 325.763698 -377.550902) (xy 325.741038 -377.600519)
			(xy 325.711548 -377.646407) (xy 325.675827 -377.68763) (xy 325.634603 -377.72335) (xy 325.588716 -377.75284)
			(xy 325.539098 -377.775499) (xy 325.486761 -377.790866) (xy 325.432769 -377.798629) (xy 325.405496 -377.799092)
			(xy 324.541896 -377.799092) (xy 324.514629 -377.798545) (xy 324.46065 -377.790784) (xy 324.408325 -377.775419)
			(xy 324.358719 -377.752765) (xy 324.312842 -377.723281) (xy 324.271629 -377.687569) (xy 324.235917 -377.646354)
			(xy 324.206433 -377.600477) (xy 324.183779 -377.550871) (xy 324.168415 -377.498546) (xy 324.160654 -377.444567)
			(xy 322.383228 -377.444567) (xy 322.383228 -377.444573) (xy 322.375466 -377.498565) (xy 322.360098 -377.550902)
			(xy 322.337438 -377.600519) (xy 322.307948 -377.646407) (xy 322.272227 -377.68763) (xy 322.231003 -377.72335)
			(xy 322.185116 -377.75284) (xy 322.135498 -377.775499) (xy 322.083161 -377.790866) (xy 322.029169 -377.798629)
			(xy 322.001896 -377.799092) (xy 321.138296 -377.799092) (xy 321.111029 -377.798545) (xy 321.05705 -377.790784)
			(xy 321.004725 -377.775419) (xy 320.955119 -377.752765) (xy 320.909242 -377.723281) (xy 320.868029 -377.687569)
			(xy 320.832317 -377.646354) (xy 320.802833 -377.600477) (xy 320.780179 -377.550871) (xy 320.764815 -377.498546)
			(xy 320.757054 -377.444567) (xy 315.576028 -377.444567) (xy 315.576028 -377.444573) (xy 315.568266 -377.498565)
			(xy 315.552898 -377.550902) (xy 315.530238 -377.600519) (xy 315.500748 -377.646407) (xy 315.465027 -377.68763)
			(xy 315.423803 -377.72335) (xy 315.377916 -377.75284) (xy 315.328298 -377.775499) (xy 315.275961 -377.790866)
			(xy 315.221969 -377.798629) (xy 315.194696 -377.799092) (xy 314.331096 -377.799092) (xy 314.303829 -377.798545)
			(xy 314.24985 -377.790784) (xy 314.197525 -377.775419) (xy 314.147919 -377.752765) (xy 314.102042 -377.723281)
			(xy 314.060829 -377.687569) (xy 314.025117 -377.646354) (xy 313.995633 -377.600477) (xy 313.972979 -377.550871)
			(xy 313.957615 -377.498546) (xy 313.949854 -377.444567) (xy 308.768828 -377.444567) (xy 308.768828 -377.444573)
			(xy 308.761066 -377.498565) (xy 308.745698 -377.550902) (xy 308.723038 -377.600519) (xy 308.693548 -377.646407)
			(xy 308.657827 -377.68763) (xy 308.616603 -377.72335) (xy 308.570716 -377.75284) (xy 308.521098 -377.775499)
			(xy 308.468761 -377.790866) (xy 308.414769 -377.798629) (xy 308.387496 -377.799092) (xy 307.523896 -377.799092)
			(xy 307.496629 -377.798545) (xy 307.44265 -377.790784) (xy 307.390325 -377.775419) (xy 307.340719 -377.752765)
			(xy 307.294842 -377.723281) (xy 307.253629 -377.687569) (xy 307.217917 -377.646354) (xy 307.188433 -377.600477)
			(xy 307.165779 -377.550871) (xy 307.150415 -377.498546) (xy 307.142654 -377.444567) (xy 301.961628 -377.444567)
			(xy 301.961628 -377.444573) (xy 301.953866 -377.498565) (xy 301.938498 -377.550902) (xy 301.915838 -377.600519)
			(xy 301.886348 -377.646407) (xy 301.850627 -377.68763) (xy 301.809403 -377.72335) (xy 301.763516 -377.75284)
			(xy 301.713898 -377.775499) (xy 301.661561 -377.790866) (xy 301.607569 -377.798629) (xy 301.580296 -377.799092)
			(xy 300.716696 -377.799092) (xy 300.689429 -377.798545) (xy 300.63545 -377.790784) (xy 300.583125 -377.775419)
			(xy 300.533519 -377.752765) (xy 300.487642 -377.723281) (xy 300.446429 -377.687569) (xy 300.410717 -377.646354)
			(xy 300.381233 -377.600477) (xy 300.358579 -377.550871) (xy 300.343215 -377.498546) (xy 300.335454 -377.444567)
			(xy 200.859958 -377.444567) (xy 200.882666 -377.460737) (xy 200.946694 -377.516218) (xy 201.005159 -377.577533)
			(xy 201.05753 -377.644129) (xy 201.103333 -377.715401) (xy 201.142155 -377.790704) (xy 201.173643 -377.869356)
			(xy 201.197511 -377.950646) (xy 201.213545 -378.033836) (xy 201.221598 -378.118173) (xy 201.222102 -378.160534)
			(xy 201.221598 -378.202895) (xy 201.213545 -378.287232) (xy 201.197511 -378.370422) (xy 201.173643 -378.451712)
			(xy 201.142155 -378.530364) (xy 201.103333 -378.605667) (xy 201.05753 -378.676939) (xy 201.005159 -378.743535)
			(xy 200.946694 -378.80485) (xy 200.882666 -378.860331) (xy 200.813654 -378.909474) (xy 200.740284 -378.951834)
			(xy 200.663219 -378.987029) (xy 200.583157 -379.014738) (xy 200.500824 -379.034712) (xy 200.416965 -379.046769)
			(xy 200.33234 -379.050801) (xy 200.247715 -379.046769) (xy 200.163856 -379.034712) (xy 200.081523 -379.014738)
			(xy 200.001461 -378.987029) (xy 199.924396 -378.951834) (xy 199.851026 -378.909474) (xy 199.782014 -378.860331)
			(xy 199.717986 -378.80485) (xy 199.659521 -378.743535) (xy 199.60715 -378.676939) (xy 199.561347 -378.605667)
			(xy 199.522525 -378.530364) (xy 199.491037 -378.451712) (xy 199.467169 -378.370422) (xy 199.451135 -378.287232)
			(xy 199.443082 -378.202895) (xy 195.47531 -378.202895) (xy 195.462625 -378.219025) (xy 195.40416 -378.28034)
			(xy 195.340132 -378.335821) (xy 195.27112 -378.384964) (xy 195.19775 -378.427324) (xy 195.120685 -378.462519)
			(xy 195.040623 -378.490228) (xy 194.95829 -378.510202) (xy 194.874431 -378.522259) (xy 194.789806 -378.526291)
			(xy 194.705181 -378.522259) (xy 194.621322 -378.510202) (xy 194.538989 -378.490228) (xy 194.458927 -378.462519)
			(xy 194.381862 -378.427324) (xy 194.308492 -378.384964) (xy 194.23948 -378.335821) (xy 194.175452 -378.28034)
			(xy 194.116987 -378.219025) (xy 194.064616 -378.152429) (xy 194.018813 -378.081157) (xy 193.979991 -378.005854)
			(xy 193.948503 -377.927202) (xy 193.924635 -377.845912) (xy 193.908601 -377.762722) (xy 193.900548 -377.678385)
			(xy 181.319901 -377.678385) (xy 181.279884 -377.802486) (xy 181.217663 -377.969563) (xy 181.148062 -378.133704)
			(xy 181.071217 -378.29458) (xy 180.987283 -378.451874) (xy 180.896425 -378.605273) (xy 180.798823 -378.754472)
			(xy 180.694672 -378.899175) (xy 180.584179 -379.039095) (xy 180.467562 -379.173954) (xy 180.345053 -379.303484)
			(xy 180.216896 -379.427428) (xy 180.083345 -379.54554) (xy 179.944665 -379.657585) (xy 179.801131 -379.763342)
			(xy 179.653028 -379.862599) (xy 179.577684 -379.908367) (xy 298.633654 -379.908367) (xy 298.633654 -379.853833)
			(xy 298.641415 -379.799854) (xy 298.656779 -379.747529) (xy 298.679433 -379.697923) (xy 298.708917 -379.652046)
			(xy 298.744629 -379.610831) (xy 298.785842 -379.575119) (xy 298.831719 -379.545635) (xy 298.881325 -379.522981)
			(xy 298.93365 -379.507616) (xy 298.987629 -379.499855) (xy 299.014896 -379.499368) (xy 299.878496 -379.499368)
			(xy 299.905769 -379.499771) (xy 299.959761 -379.507534) (xy 300.012098 -379.522901) (xy 300.061716 -379.54556)
			(xy 300.107603 -379.57505) (xy 300.148827 -379.61077) (xy 300.184548 -379.651993) (xy 300.214038 -379.697881)
			(xy 300.236698 -379.747498) (xy 300.252066 -379.799835) (xy 300.259828 -379.853827) (xy 300.259828 -379.908367)
			(xy 305.440854 -379.908367) (xy 305.440854 -379.853833) (xy 305.448615 -379.799854) (xy 305.463979 -379.747529)
			(xy 305.486633 -379.697923) (xy 305.516117 -379.652046) (xy 305.551829 -379.610831) (xy 305.593042 -379.575119)
			(xy 305.638919 -379.545635) (xy 305.688525 -379.522981) (xy 305.74085 -379.507616) (xy 305.794829 -379.499855)
			(xy 305.822096 -379.499368) (xy 306.685696 -379.499368) (xy 306.712969 -379.499771) (xy 306.766961 -379.507534)
			(xy 306.819298 -379.522901) (xy 306.868916 -379.54556) (xy 306.914803 -379.57505) (xy 306.956027 -379.61077)
			(xy 306.991748 -379.651993) (xy 307.021238 -379.697881) (xy 307.043898 -379.747498) (xy 307.059266 -379.799835)
			(xy 307.067028 -379.853827) (xy 307.067028 -379.908367) (xy 312.248054 -379.908367) (xy 312.248054 -379.853833)
			(xy 312.255815 -379.799854) (xy 312.271179 -379.747529) (xy 312.293833 -379.697923) (xy 312.323317 -379.652046)
			(xy 312.359029 -379.610831) (xy 312.400242 -379.575119) (xy 312.446119 -379.545635) (xy 312.495725 -379.522981)
			(xy 312.54805 -379.507616) (xy 312.602029 -379.499855) (xy 312.629296 -379.499368) (xy 313.492896 -379.499368)
			(xy 313.520169 -379.499771) (xy 313.574161 -379.507534) (xy 313.626498 -379.522901) (xy 313.676116 -379.54556)
			(xy 313.722003 -379.57505) (xy 313.763227 -379.61077) (xy 313.798948 -379.651993) (xy 313.828438 -379.697881)
			(xy 313.851098 -379.747498) (xy 313.866466 -379.799835) (xy 313.874228 -379.853827) (xy 313.874228 -379.908367)
			(xy 319.055254 -379.908367) (xy 319.055254 -379.853833) (xy 319.063015 -379.799854) (xy 319.078379 -379.747529)
			(xy 319.101033 -379.697923) (xy 319.130517 -379.652046) (xy 319.166229 -379.610831) (xy 319.207442 -379.575119)
			(xy 319.253319 -379.545635) (xy 319.302925 -379.522981) (xy 319.35525 -379.507616) (xy 319.409229 -379.499855)
			(xy 319.436496 -379.499368) (xy 320.300096 -379.499368) (xy 320.327369 -379.499771) (xy 320.381361 -379.507534)
			(xy 320.433698 -379.522901) (xy 320.483316 -379.54556) (xy 320.529203 -379.57505) (xy 320.570427 -379.61077)
			(xy 320.606148 -379.651993) (xy 320.635638 -379.697881) (xy 320.658298 -379.747498) (xy 320.673666 -379.799835)
			(xy 320.681428 -379.853827) (xy 320.681428 -379.908371) (xy 331.161332 -379.908371) (xy 331.161332 -379.853829)
			(xy 331.169094 -379.799843) (xy 331.184461 -379.747511) (xy 331.207121 -379.697898) (xy 331.23661 -379.652016)
			(xy 331.272329 -379.610798) (xy 331.313551 -379.575084) (xy 331.359437 -379.545599) (xy 331.409052 -379.522946)
			(xy 331.461386 -379.507585) (xy 331.515373 -379.499828) (xy 331.542644 -379.499368) (xy 332.406244 -379.499368)
			(xy 332.433513 -379.499798) (xy 332.487497 -379.507565) (xy 332.539825 -379.522935) (xy 332.589433 -379.545596)
			(xy 332.635312 -379.575085) (xy 332.676528 -379.610803) (xy 332.712241 -379.652023) (xy 332.741725 -379.697905)
			(xy 332.76438 -379.747516) (xy 332.779744 -379.799847) (xy 332.787506 -379.85383) (xy 332.787506 -379.90837)
			(xy 332.787506 -379.908371) (xy 337.968532 -379.908371) (xy 337.968532 -379.853829) (xy 337.976294 -379.799843)
			(xy 337.991661 -379.747511) (xy 338.014321 -379.697898) (xy 338.04381 -379.652016) (xy 338.079529 -379.610798)
			(xy 338.120751 -379.575084) (xy 338.166637 -379.545599) (xy 338.216252 -379.522946) (xy 338.268586 -379.507585)
			(xy 338.322573 -379.499828) (xy 338.349844 -379.499368) (xy 339.213444 -379.499368) (xy 339.240713 -379.499798)
			(xy 339.294697 -379.507565) (xy 339.347025 -379.522935) (xy 339.396633 -379.545596) (xy 339.442512 -379.575085)
			(xy 339.483728 -379.610803) (xy 339.519441 -379.652023) (xy 339.548925 -379.697905) (xy 339.57158 -379.747516)
			(xy 339.586944 -379.799847) (xy 339.594706 -379.85383) (xy 339.594706 -379.90837) (xy 339.594706 -379.908371)
			(xy 344.775732 -379.908371) (xy 344.775732 -379.853829) (xy 344.783494 -379.799843) (xy 344.798861 -379.747511)
			(xy 344.821521 -379.697898) (xy 344.85101 -379.652016) (xy 344.886729 -379.610798) (xy 344.927951 -379.575084)
			(xy 344.973837 -379.545599) (xy 345.023452 -379.522946) (xy 345.075786 -379.507585) (xy 345.129773 -379.499828)
			(xy 345.157044 -379.499368) (xy 346.020644 -379.499368) (xy 346.047913 -379.499798) (xy 346.101897 -379.507565)
			(xy 346.154225 -379.522935) (xy 346.203833 -379.545596) (xy 346.249712 -379.575085) (xy 346.290928 -379.610803)
			(xy 346.326641 -379.652023) (xy 346.356125 -379.697905) (xy 346.37878 -379.747516) (xy 346.394144 -379.799847)
			(xy 346.401906 -379.85383) (xy 346.401906 -379.90837) (xy 346.401906 -379.908371) (xy 351.582932 -379.908371)
			(xy 351.582932 -379.853829) (xy 351.590694 -379.799843) (xy 351.606061 -379.747511) (xy 351.628721 -379.697898)
			(xy 351.65821 -379.652016) (xy 351.693929 -379.610798) (xy 351.735151 -379.575084) (xy 351.781037 -379.545599)
			(xy 351.830652 -379.522946) (xy 351.882986 -379.507585) (xy 351.936973 -379.499828) (xy 351.964244 -379.499368)
			(xy 352.827844 -379.499368) (xy 352.855113 -379.499798) (xy 352.909097 -379.507565) (xy 352.961425 -379.522935)
			(xy 353.011033 -379.545596) (xy 353.056912 -379.575085) (xy 353.098128 -379.610803) (xy 353.133841 -379.652023)
			(xy 353.163325 -379.697905) (xy 353.18598 -379.747516) (xy 353.201344 -379.799847) (xy 353.209106 -379.85383)
			(xy 353.209106 -379.908367) (xy 365.733854 -379.908367) (xy 365.733854 -379.853833) (xy 365.741615 -379.799854)
			(xy 365.756979 -379.74753) (xy 365.779633 -379.697924) (xy 365.809116 -379.652047) (xy 365.844827 -379.610833)
			(xy 365.886041 -379.57512) (xy 365.931917 -379.545637) (xy 365.981522 -379.522982) (xy 366.033847 -379.507617)
			(xy 366.087825 -379.499855) (xy 366.115092 -379.499368) (xy 366.978692 -379.499368) (xy 367.005966 -379.499771)
			(xy 367.059957 -379.507533) (xy 367.112295 -379.5229) (xy 367.161913 -379.545559) (xy 367.207802 -379.575048)
			(xy 367.249026 -379.610768) (xy 367.284747 -379.651992) (xy 367.314238 -379.69788) (xy 367.336898 -379.747497)
			(xy 367.352265 -379.799835) (xy 367.360028 -379.853826) (xy 367.360028 -379.908367) (xy 372.541054 -379.908367)
			(xy 372.541054 -379.853833) (xy 372.548815 -379.799854) (xy 372.564179 -379.74753) (xy 372.586833 -379.697924)
			(xy 372.616316 -379.652047) (xy 372.652027 -379.610833) (xy 372.693241 -379.57512) (xy 372.739117 -379.545637)
			(xy 372.788722 -379.522982) (xy 372.841047 -379.507617) (xy 372.895025 -379.499855) (xy 372.922292 -379.499368)
			(xy 373.785892 -379.499368) (xy 373.813166 -379.499771) (xy 373.867157 -379.507533) (xy 373.919495 -379.5229)
			(xy 373.969113 -379.545559) (xy 374.015002 -379.575048) (xy 374.056226 -379.610768) (xy 374.091947 -379.651992)
			(xy 374.121438 -379.69788) (xy 374.144098 -379.747497) (xy 374.159465 -379.799835) (xy 374.167228 -379.853826)
			(xy 374.167228 -379.908367) (xy 379.348254 -379.908367) (xy 379.348254 -379.853833) (xy 379.356015 -379.799854)
			(xy 379.371379 -379.74753) (xy 379.394033 -379.697924) (xy 379.423516 -379.652047) (xy 379.459227 -379.610833)
			(xy 379.500441 -379.57512) (xy 379.546317 -379.545637) (xy 379.595922 -379.522982) (xy 379.648247 -379.507617)
			(xy 379.702225 -379.499855) (xy 379.729492 -379.499368) (xy 380.593092 -379.499368) (xy 380.620366 -379.499771)
			(xy 380.674357 -379.507533) (xy 380.726695 -379.5229) (xy 380.776313 -379.545559) (xy 380.822202 -379.575048)
			(xy 380.863426 -379.610768) (xy 380.899147 -379.651992) (xy 380.928638 -379.69788) (xy 380.951298 -379.747497)
			(xy 380.966665 -379.799835) (xy 380.974428 -379.853826) (xy 380.974428 -379.908367) (xy 386.155454 -379.908367)
			(xy 386.155454 -379.853833) (xy 386.163215 -379.799854) (xy 386.178579 -379.74753) (xy 386.201233 -379.697924)
			(xy 386.230716 -379.652047) (xy 386.266427 -379.610833) (xy 386.307641 -379.57512) (xy 386.353517 -379.545637)
			(xy 386.403122 -379.522982) (xy 386.455447 -379.507617) (xy 386.509425 -379.499855) (xy 386.536692 -379.499368)
			(xy 387.400292 -379.499368) (xy 387.427566 -379.499771) (xy 387.481557 -379.507533) (xy 387.533895 -379.5229)
			(xy 387.583513 -379.545559) (xy 387.629402 -379.575048) (xy 387.670626 -379.610768) (xy 387.706347 -379.651992)
			(xy 387.735838 -379.69788) (xy 387.758498 -379.747497) (xy 387.773865 -379.799835) (xy 387.781628 -379.853826)
			(xy 387.781628 -379.908371) (xy 398.261532 -379.908371) (xy 398.261532 -379.853829) (xy 398.269294 -379.799843)
			(xy 398.284661 -379.747511) (xy 398.30732 -379.697899) (xy 398.336809 -379.652017) (xy 398.372528 -379.6108)
			(xy 398.41375 -379.575085) (xy 398.459635 -379.545601) (xy 398.509249 -379.522947) (xy 398.561582 -379.507586)
			(xy 398.615569 -379.499829) (xy 398.64284 -379.499368) (xy 399.50644 -379.499368) (xy 399.53371 -379.499797)
			(xy 399.587693 -379.507564) (xy 399.640022 -379.522934) (xy 399.689631 -379.545594) (xy 399.735511 -379.575084)
			(xy 399.776727 -379.610802) (xy 399.81244 -379.652022) (xy 399.841925 -379.697904) (xy 399.86458 -379.747516)
			(xy 399.879944 -379.799846) (xy 399.887706 -379.85383) (xy 399.887706 -379.90837) (xy 399.887706 -379.908371)
			(xy 405.068732 -379.908371) (xy 405.068732 -379.853829) (xy 405.076494 -379.799843) (xy 405.091861 -379.747511)
			(xy 405.11452 -379.697899) (xy 405.144009 -379.652017) (xy 405.179728 -379.6108) (xy 405.22095 -379.575085)
			(xy 405.266835 -379.545601) (xy 405.316449 -379.522947) (xy 405.368782 -379.507586) (xy 405.422769 -379.499829)
			(xy 405.45004 -379.499368) (xy 406.31364 -379.499368) (xy 406.34091 -379.499797) (xy 406.394893 -379.507564)
			(xy 406.447222 -379.522934) (xy 406.496831 -379.545594) (xy 406.542711 -379.575084) (xy 406.583927 -379.610802)
			(xy 406.61964 -379.652022) (xy 406.649125 -379.697904) (xy 406.67178 -379.747516) (xy 406.687144 -379.799846)
			(xy 406.694906 -379.85383) (xy 406.694906 -379.90837) (xy 406.694906 -379.908371) (xy 411.875932 -379.908371)
			(xy 411.875932 -379.853829) (xy 411.883694 -379.799843) (xy 411.899061 -379.747511) (xy 411.92172 -379.697899)
			(xy 411.951209 -379.652017) (xy 411.986928 -379.6108) (xy 412.02815 -379.575085) (xy 412.074035 -379.545601)
			(xy 412.123649 -379.522947) (xy 412.175982 -379.507586) (xy 412.229969 -379.499829) (xy 412.25724 -379.499368)
			(xy 413.12084 -379.499368) (xy 413.14811 -379.499797) (xy 413.202093 -379.507564) (xy 413.254422 -379.522934)
			(xy 413.304031 -379.545594) (xy 413.349911 -379.575084) (xy 413.391127 -379.610802) (xy 413.42684 -379.652022)
			(xy 413.456325 -379.697904) (xy 413.47898 -379.747516) (xy 413.494344 -379.799846) (xy 413.502106 -379.85383)
			(xy 413.502106 -379.90837) (xy 413.502106 -379.908371) (xy 418.683132 -379.908371) (xy 418.683132 -379.853829)
			(xy 418.690894 -379.799843) (xy 418.706261 -379.747511) (xy 418.72892 -379.697899) (xy 418.758409 -379.652017)
			(xy 418.794128 -379.6108) (xy 418.83535 -379.575085) (xy 418.881235 -379.545601) (xy 418.930849 -379.522947)
			(xy 418.983182 -379.507586) (xy 419.037169 -379.499829) (xy 419.06444 -379.499368) (xy 419.92804 -379.499368)
			(xy 419.95531 -379.499797) (xy 420.009293 -379.507564) (xy 420.061622 -379.522934) (xy 420.111231 -379.545594)
			(xy 420.157111 -379.575084) (xy 420.198327 -379.610802) (xy 420.23404 -379.652022) (xy 420.263525 -379.697904)
			(xy 420.28618 -379.747516) (xy 420.301544 -379.799846) (xy 420.309306 -379.85383) (xy 420.309306 -379.90837)
			(xy 420.301544 -379.962354) (xy 420.28618 -380.014684) (xy 420.263525 -380.064296) (xy 420.23404 -380.110178)
			(xy 420.198327 -380.151398) (xy 420.157111 -380.187116) (xy 420.111231 -380.216606) (xy 420.061622 -380.239266)
			(xy 420.009293 -380.254636) (xy 419.95531 -380.262403) (xy 419.92804 -380.262892) (xy 419.06444 -380.262892)
			(xy 419.037169 -380.262371) (xy 418.983182 -380.254614) (xy 418.930849 -380.239253) (xy 418.881235 -380.216599)
			(xy 418.83535 -380.187115) (xy 418.794128 -380.1514) (xy 418.758409 -380.110183) (xy 418.72892 -380.064301)
			(xy 418.706261 -380.014689) (xy 418.690894 -379.962357) (xy 418.683132 -379.908371) (xy 413.502106 -379.908371)
			(xy 413.494344 -379.962354) (xy 413.47898 -380.014684) (xy 413.456325 -380.064296) (xy 413.42684 -380.110178)
			(xy 413.391127 -380.151398) (xy 413.349911 -380.187116) (xy 413.304031 -380.216606) (xy 413.254422 -380.239266)
			(xy 413.202093 -380.254636) (xy 413.14811 -380.262403) (xy 413.12084 -380.262892) (xy 412.25724 -380.262892)
			(xy 412.229969 -380.262371) (xy 412.175982 -380.254614) (xy 412.123649 -380.239253) (xy 412.074035 -380.216599)
			(xy 412.02815 -380.187115) (xy 411.986928 -380.1514) (xy 411.951209 -380.110183) (xy 411.92172 -380.064301)
			(xy 411.899061 -380.014689) (xy 411.883694 -379.962357) (xy 411.875932 -379.908371) (xy 406.694906 -379.908371)
			(xy 406.687144 -379.962354) (xy 406.67178 -380.014684) (xy 406.649125 -380.064296) (xy 406.61964 -380.110178)
			(xy 406.583927 -380.151398) (xy 406.542711 -380.187116) (xy 406.496831 -380.216606) (xy 406.447222 -380.239266)
			(xy 406.394893 -380.254636) (xy 406.34091 -380.262403) (xy 406.31364 -380.262892) (xy 405.45004 -380.262892)
			(xy 405.422769 -380.262371) (xy 405.368782 -380.254614) (xy 405.316449 -380.239253) (xy 405.266835 -380.216599)
			(xy 405.22095 -380.187115) (xy 405.179728 -380.1514) (xy 405.144009 -380.110183) (xy 405.11452 -380.064301)
			(xy 405.091861 -380.014689) (xy 405.076494 -379.962357) (xy 405.068732 -379.908371) (xy 399.887706 -379.908371)
			(xy 399.879944 -379.962354) (xy 399.86458 -380.014684) (xy 399.841925 -380.064296) (xy 399.81244 -380.110178)
			(xy 399.776727 -380.151398) (xy 399.735511 -380.187116) (xy 399.689631 -380.216606) (xy 399.640022 -380.239266)
			(xy 399.587693 -380.254636) (xy 399.53371 -380.262403) (xy 399.50644 -380.262892) (xy 398.64284 -380.262892)
			(xy 398.615569 -380.262371) (xy 398.561582 -380.254614) (xy 398.509249 -380.239253) (xy 398.459635 -380.216599)
			(xy 398.41375 -380.187115) (xy 398.372528 -380.1514) (xy 398.336809 -380.110183) (xy 398.30732 -380.064301)
			(xy 398.284661 -380.014689) (xy 398.269294 -379.962357) (xy 398.261532 -379.908371) (xy 387.781628 -379.908371)
			(xy 387.781628 -379.908374) (xy 387.773865 -379.962365) (xy 387.758498 -380.014703) (xy 387.735838 -380.06432)
			(xy 387.706347 -380.110208) (xy 387.670626 -380.151432) (xy 387.629402 -380.187152) (xy 387.583513 -380.216641)
			(xy 387.533895 -380.2393) (xy 387.481557 -380.254667) (xy 387.427566 -380.262429) (xy 387.400292 -380.262892)
			(xy 386.536692 -380.262892) (xy 386.509425 -380.262345) (xy 386.455447 -380.254583) (xy 386.403122 -380.239218)
			(xy 386.353517 -380.216563) (xy 386.307641 -380.18708) (xy 386.266427 -380.151367) (xy 386.230716 -380.110153)
			(xy 386.201233 -380.064276) (xy 386.178579 -380.01467) (xy 386.163215 -379.962346) (xy 386.155454 -379.908367)
			(xy 380.974428 -379.908367) (xy 380.974428 -379.908374) (xy 380.966665 -379.962365) (xy 380.951298 -380.014703)
			(xy 380.928638 -380.06432) (xy 380.899147 -380.110208) (xy 380.863426 -380.151432) (xy 380.822202 -380.187152)
			(xy 380.776313 -380.216641) (xy 380.726695 -380.2393) (xy 380.674357 -380.254667) (xy 380.620366 -380.262429)
			(xy 380.593092 -380.262892) (xy 379.729492 -380.262892) (xy 379.702225 -380.262345) (xy 379.648247 -380.254583)
			(xy 379.595922 -380.239218) (xy 379.546317 -380.216563) (xy 379.500441 -380.18708) (xy 379.459227 -380.151367)
			(xy 379.423516 -380.110153) (xy 379.394033 -380.064276) (xy 379.371379 -380.01467) (xy 379.356015 -379.962346)
			(xy 379.348254 -379.908367) (xy 374.167228 -379.908367) (xy 374.167228 -379.908374) (xy 374.159465 -379.962365)
			(xy 374.144098 -380.014703) (xy 374.121438 -380.06432) (xy 374.091947 -380.110208) (xy 374.056226 -380.151432)
			(xy 374.015002 -380.187152) (xy 373.969113 -380.216641) (xy 373.919495 -380.2393) (xy 373.867157 -380.254667)
			(xy 373.813166 -380.262429) (xy 373.785892 -380.262892) (xy 372.922292 -380.262892) (xy 372.895025 -380.262345)
			(xy 372.841047 -380.254583) (xy 372.788722 -380.239218) (xy 372.739117 -380.216563) (xy 372.693241 -380.18708)
			(xy 372.652027 -380.151367) (xy 372.616316 -380.110153) (xy 372.586833 -380.064276) (xy 372.564179 -380.01467)
			(xy 372.548815 -379.962346) (xy 372.541054 -379.908367) (xy 367.360028 -379.908367) (xy 367.360028 -379.908374)
			(xy 367.352265 -379.962365) (xy 367.336898 -380.014703) (xy 367.314238 -380.06432) (xy 367.284747 -380.110208)
			(xy 367.249026 -380.151432) (xy 367.207802 -380.187152) (xy 367.161913 -380.216641) (xy 367.112295 -380.2393)
			(xy 367.059957 -380.254667) (xy 367.005966 -380.262429) (xy 366.978692 -380.262892) (xy 366.115092 -380.262892)
			(xy 366.087825 -380.262345) (xy 366.033847 -380.254583) (xy 365.981522 -380.239218) (xy 365.931917 -380.216563)
			(xy 365.886041 -380.18708) (xy 365.844827 -380.151367) (xy 365.809116 -380.110153) (xy 365.779633 -380.064276)
			(xy 365.756979 -380.01467) (xy 365.741615 -379.962346) (xy 365.733854 -379.908367) (xy 353.209106 -379.908367)
			(xy 353.209106 -379.90837) (xy 353.201344 -379.962353) (xy 353.18598 -380.014684) (xy 353.163325 -380.064295)
			(xy 353.133841 -380.110177) (xy 353.098128 -380.151397) (xy 353.056912 -380.187115) (xy 353.011033 -380.216604)
			(xy 352.961425 -380.239265) (xy 352.909097 -380.254635) (xy 352.855113 -380.262402) (xy 352.827844 -380.262892)
			(xy 351.964244 -380.262892) (xy 351.936973 -380.262372) (xy 351.882986 -380.254615) (xy 351.830652 -380.239254)
			(xy 351.781037 -380.216601) (xy 351.735151 -380.187116) (xy 351.693929 -380.151402) (xy 351.65821 -380.110184)
			(xy 351.628721 -380.064302) (xy 351.606061 -380.014689) (xy 351.590694 -379.962357) (xy 351.582932 -379.908371)
			(xy 346.401906 -379.908371) (xy 346.394144 -379.962353) (xy 346.37878 -380.014684) (xy 346.356125 -380.064295)
			(xy 346.326641 -380.110177) (xy 346.290928 -380.151397) (xy 346.249712 -380.187115) (xy 346.203833 -380.216604)
			(xy 346.154225 -380.239265) (xy 346.101897 -380.254635) (xy 346.047913 -380.262402) (xy 346.020644 -380.262892)
			(xy 345.157044 -380.262892) (xy 345.129773 -380.262372) (xy 345.075786 -380.254615) (xy 345.023452 -380.239254)
			(xy 344.973837 -380.216601) (xy 344.927951 -380.187116) (xy 344.886729 -380.151402) (xy 344.85101 -380.110184)
			(xy 344.821521 -380.064302) (xy 344.798861 -380.014689) (xy 344.783494 -379.962357) (xy 344.775732 -379.908371)
			(xy 339.594706 -379.908371) (xy 339.586944 -379.962353) (xy 339.57158 -380.014684) (xy 339.548925 -380.064295)
			(xy 339.519441 -380.110177) (xy 339.483728 -380.151397) (xy 339.442512 -380.187115) (xy 339.396633 -380.216604)
			(xy 339.347025 -380.239265) (xy 339.294697 -380.254635) (xy 339.240713 -380.262402) (xy 339.213444 -380.262892)
			(xy 338.349844 -380.262892) (xy 338.322573 -380.262372) (xy 338.268586 -380.254615) (xy 338.216252 -380.239254)
			(xy 338.166637 -380.216601) (xy 338.120751 -380.187116) (xy 338.079529 -380.151402) (xy 338.04381 -380.110184)
			(xy 338.014321 -380.064302) (xy 337.991661 -380.014689) (xy 337.976294 -379.962357) (xy 337.968532 -379.908371)
			(xy 332.787506 -379.908371) (xy 332.779744 -379.962353) (xy 332.76438 -380.014684) (xy 332.741725 -380.064295)
			(xy 332.712241 -380.110177) (xy 332.676528 -380.151397) (xy 332.635312 -380.187115) (xy 332.589433 -380.216604)
			(xy 332.539825 -380.239265) (xy 332.487497 -380.254635) (xy 332.433513 -380.262402) (xy 332.406244 -380.262892)
			(xy 331.542644 -380.262892) (xy 331.515373 -380.262372) (xy 331.461386 -380.254615) (xy 331.409052 -380.239254)
			(xy 331.359437 -380.216601) (xy 331.313551 -380.187116) (xy 331.272329 -380.151402) (xy 331.23661 -380.110184)
			(xy 331.207121 -380.064302) (xy 331.184461 -380.014689) (xy 331.169094 -379.962357) (xy 331.161332 -379.908371)
			(xy 320.681428 -379.908371) (xy 320.681428 -379.908373) (xy 320.673666 -379.962365) (xy 320.658298 -380.014702)
			(xy 320.635638 -380.064319) (xy 320.606148 -380.110207) (xy 320.570427 -380.15143) (xy 320.529203 -380.18715)
			(xy 320.483316 -380.21664) (xy 320.433698 -380.239299) (xy 320.381361 -380.254666) (xy 320.327369 -380.262429)
			(xy 320.300096 -380.262892) (xy 319.436496 -380.262892) (xy 319.409229 -380.262345) (xy 319.35525 -380.254584)
			(xy 319.302925 -380.239219) (xy 319.253319 -380.216565) (xy 319.207442 -380.187081) (xy 319.166229 -380.151369)
			(xy 319.130517 -380.110154) (xy 319.101033 -380.064277) (xy 319.078379 -380.014671) (xy 319.063015 -379.962346)
			(xy 319.055254 -379.908367) (xy 313.874228 -379.908367) (xy 313.874228 -379.908373) (xy 313.866466 -379.962365)
			(xy 313.851098 -380.014702) (xy 313.828438 -380.064319) (xy 313.798948 -380.110207) (xy 313.763227 -380.15143)
			(xy 313.722003 -380.18715) (xy 313.676116 -380.21664) (xy 313.626498 -380.239299) (xy 313.574161 -380.254666)
			(xy 313.520169 -380.262429) (xy 313.492896 -380.262892) (xy 312.629296 -380.262892) (xy 312.602029 -380.262345)
			(xy 312.54805 -380.254584) (xy 312.495725 -380.239219) (xy 312.446119 -380.216565) (xy 312.400242 -380.187081)
			(xy 312.359029 -380.151369) (xy 312.323317 -380.110154) (xy 312.293833 -380.064277) (xy 312.271179 -380.014671)
			(xy 312.255815 -379.962346) (xy 312.248054 -379.908367) (xy 307.067028 -379.908367) (xy 307.067028 -379.908373)
			(xy 307.059266 -379.962365) (xy 307.043898 -380.014702) (xy 307.021238 -380.064319) (xy 306.991748 -380.110207)
			(xy 306.956027 -380.15143) (xy 306.914803 -380.18715) (xy 306.868916 -380.21664) (xy 306.819298 -380.239299)
			(xy 306.766961 -380.254666) (xy 306.712969 -380.262429) (xy 306.685696 -380.262892) (xy 305.822096 -380.262892)
			(xy 305.794829 -380.262345) (xy 305.74085 -380.254584) (xy 305.688525 -380.239219) (xy 305.638919 -380.216565)
			(xy 305.593042 -380.187081) (xy 305.551829 -380.151369) (xy 305.516117 -380.110154) (xy 305.486633 -380.064277)
			(xy 305.463979 -380.014671) (xy 305.448615 -379.962346) (xy 305.440854 -379.908367) (xy 300.259828 -379.908367)
			(xy 300.259828 -379.908373) (xy 300.252066 -379.962365) (xy 300.236698 -380.014702) (xy 300.214038 -380.064319)
			(xy 300.184548 -380.110207) (xy 300.148827 -380.15143) (xy 300.107603 -380.18715) (xy 300.061716 -380.21664)
			(xy 300.012098 -380.239299) (xy 299.959761 -380.254666) (xy 299.905769 -380.262429) (xy 299.878496 -380.262892)
			(xy 299.014896 -380.262892) (xy 298.987629 -380.262345) (xy 298.93365 -380.254584) (xy 298.881325 -380.239219)
			(xy 298.831719 -380.216565) (xy 298.785842 -380.187081) (xy 298.744629 -380.151369) (xy 298.708917 -380.110154)
			(xy 298.679433 -380.064277) (xy 298.656779 -380.014671) (xy 298.641415 -379.962346) (xy 298.633654 -379.908367)
			(xy 179.577684 -379.908367) (xy 179.500651 -379.955161) (xy 179.344302 -380.040842) (xy 179.184291 -380.119474)
			(xy 179.020937 -380.1909) (xy 178.854562 -380.254978) (xy 178.685499 -380.31158) (xy 178.514082 -380.360596)
			(xy 178.340651 -380.401926) (xy 178.165551 -380.43549) (xy 177.989131 -380.46122) (xy 177.811739 -380.479066)
			(xy 177.633728 -380.488992) (xy 177.455451 -380.490978) (xy 177.277264 -380.485021) (xy 177.099518 -380.471131)
			(xy 176.922568 -380.449338) (xy 176.746764 -380.419684) (xy 176.572456 -380.382227) (xy 176.399989 -380.337043)
			(xy 176.229706 -380.284221) (xy 176.061945 -380.223865) (xy 175.89704 -380.156097) (xy 175.735317 -380.081049)
			(xy 175.577098 -379.998872) (xy 175.422697 -379.909729) (xy 175.27242 -379.813795) (xy 175.126565 -379.711263)
			(xy 174.985423 -379.602335) (xy 174.849274 -379.487228) (xy 174.718387 -379.36617) (xy 174.593023 -379.239401)
			(xy 174.47343 -379.107174) (xy 174.359847 -378.969751) (xy 174.252498 -378.827404) (xy 174.151597 -378.680416)
			(xy 174.057344 -378.52908) (xy 173.969926 -378.373695) (xy 173.889516 -378.21457) (xy 173.816275 -378.052021)
			(xy 173.750348 -377.886371) (xy 173.691865 -377.717949) (xy 173.640943 -377.547088) (xy 173.597683 -377.374129)
			(xy 173.562171 -377.199414) (xy 173.534477 -377.02329) (xy 173.514656 -376.846108) (xy 173.502748 -376.668219)
			(xy 173.498776 -376.489976) (xy 171.286932 -376.489976) (xy 171.286932 -376.956828) (xy 171.286446 -376.984079)
			(xy 171.27869 -377.038027) (xy 171.263335 -377.090322) (xy 171.240693 -377.139899) (xy 171.211227 -377.185749)
			(xy 171.175536 -377.22694) (xy 171.134345 -377.262631) (xy 171.088495 -377.292097) (xy 171.038918 -377.314739)
			(xy 170.986623 -377.330094) (xy 170.932675 -377.33785) (xy 170.878173 -377.33785) (xy 170.824225 -377.330094)
			(xy 170.77193 -377.314739) (xy 170.722353 -377.292097) (xy 170.676503 -377.262631) (xy 170.635312 -377.22694)
			(xy 170.599621 -377.185749) (xy 170.570155 -377.139899) (xy 170.547513 -377.090322) (xy 170.532158 -377.038027)
			(xy 170.524402 -376.984079) (xy 170.523916 -376.956828) (xy 141.418806 -376.956828) (xy 141.416303 -376.965354)
			(xy 141.393661 -377.014931) (xy 141.364195 -377.060781) (xy 141.328504 -377.101972) (xy 141.287313 -377.137663)
			(xy 141.241463 -377.167129) (xy 141.191886 -377.189771) (xy 141.139591 -377.205126) (xy 141.085643 -377.212882)
			(xy 141.031141 -377.212882) (xy 140.977193 -377.205126) (xy 140.924898 -377.189771) (xy 140.875321 -377.167129)
			(xy 140.829471 -377.137663) (xy 140.78828 -377.101972) (xy 140.752589 -377.060781) (xy 140.723123 -377.014931)
			(xy 140.700481 -376.965354) (xy 140.685126 -376.913059) (xy 140.67737 -376.859111) (xy 140.676884 -376.83186)
			(xy 138.759184 -376.83186) (xy 138.759184 -376.956828) (xy 138.758698 -376.984079) (xy 138.750942 -377.038027)
			(xy 138.735587 -377.090322) (xy 138.712945 -377.139899) (xy 138.683479 -377.185749) (xy 138.647788 -377.22694)
			(xy 138.606597 -377.262631) (xy 138.560747 -377.292097) (xy 138.51117 -377.314739) (xy 138.458875 -377.330094)
			(xy 138.404927 -377.33785) (xy 138.350425 -377.33785) (xy 138.296477 -377.330094) (xy 138.244182 -377.314739)
			(xy 138.194605 -377.292097) (xy 138.148755 -377.262631) (xy 138.107564 -377.22694) (xy 138.071873 -377.185749)
			(xy 138.042407 -377.139899) (xy 138.019765 -377.090322) (xy 138.00441 -377.038027) (xy 137.996654 -376.984079)
			(xy 137.996168 -376.956828) (xy 108.891058 -376.956828) (xy 108.888555 -376.965354) (xy 108.865913 -377.014931)
			(xy 108.836447 -377.060781) (xy 108.800756 -377.101972) (xy 108.759565 -377.137663) (xy 108.713715 -377.167129)
			(xy 108.664138 -377.189771) (xy 108.611843 -377.205126) (xy 108.557895 -377.212882) (xy 108.503393 -377.212882)
			(xy 108.449445 -377.205126) (xy 108.39715 -377.189771) (xy 108.347573 -377.167129) (xy 108.301723 -377.137663)
			(xy 108.260532 -377.101972) (xy 108.224841 -377.060781) (xy 108.195375 -377.014931) (xy 108.172733 -376.965354)
			(xy 108.157378 -376.913059) (xy 108.149622 -376.859111) (xy 108.149136 -376.83186) (xy 104.187244 -376.83186)
			(xy 104.187244 -376.956828) (xy 104.186758 -376.984097) (xy 104.178996 -377.038081) (xy 104.163631 -377.090411)
			(xy 104.140974 -377.140021) (xy 104.111488 -377.185902) (xy 104.075773 -377.227119) (xy 104.034556 -377.262834)
			(xy 103.988675 -377.29232) (xy 103.939065 -377.314977) (xy 103.886735 -377.330342) (xy 103.832751 -377.338104)
			(xy 103.778213 -377.338104) (xy 103.724229 -377.330342) (xy 103.671899 -377.314977) (xy 103.622289 -377.29232)
			(xy 103.576408 -377.262834) (xy 103.535191 -377.227119) (xy 103.499476 -377.185902) (xy 103.46999 -377.140021)
			(xy 103.447333 -377.090411) (xy 103.431968 -377.038081) (xy 103.424206 -376.984097) (xy 103.42372 -376.956828)
			(xy 74.319129 -376.956828) (xy 74.316599 -376.965443) (xy 74.293942 -377.015053) (xy 74.264456 -377.060934)
			(xy 74.228741 -377.102151) (xy 74.187524 -377.137866) (xy 74.141643 -377.167352) (xy 74.092033 -377.190009)
			(xy 74.039703 -377.205374) (xy 73.985719 -377.213136) (xy 73.931181 -377.213136) (xy 73.877197 -377.205374)
			(xy 73.824867 -377.190009) (xy 73.775257 -377.167352) (xy 73.729376 -377.137866) (xy 73.688159 -377.102151)
			(xy 73.652444 -377.060934) (xy 73.622958 -377.015053) (xy 73.600301 -376.965443) (xy 73.584936 -376.913113)
			(xy 73.577174 -376.859129) (xy 73.576688 -376.83186) (xy 71.659496 -376.83186) (xy 71.659496 -376.956828)
			(xy 71.65901 -376.984097) (xy 71.651248 -377.038081) (xy 71.635883 -377.090411) (xy 71.613226 -377.140021)
			(xy 71.58374 -377.185902) (xy 71.548025 -377.227119) (xy 71.506808 -377.262834) (xy 71.460927 -377.29232)
			(xy 71.411317 -377.314977) (xy 71.358987 -377.330342) (xy 71.305003 -377.338104) (xy 71.250465 -377.338104)
			(xy 71.196481 -377.330342) (xy 71.144151 -377.314977) (xy 71.094541 -377.29232) (xy 71.04866 -377.262834)
			(xy 71.007443 -377.227119) (xy 70.971728 -377.185902) (xy 70.942242 -377.140021) (xy 70.919585 -377.090411)
			(xy 70.90422 -377.038081) (xy 70.896458 -376.984097) (xy 70.895972 -376.956828) (xy 41.791381 -376.956828)
			(xy 41.788851 -376.965443) (xy 41.766194 -377.015053) (xy 41.736708 -377.060934) (xy 41.700993 -377.102151)
			(xy 41.659776 -377.137866) (xy 41.613895 -377.167352) (xy 41.564285 -377.190009) (xy 41.511955 -377.205374)
			(xy 41.457971 -377.213136) (xy 41.403433 -377.213136) (xy 41.349449 -377.205374) (xy 41.297119 -377.190009)
			(xy 41.247509 -377.167352) (xy 41.201628 -377.137866) (xy 41.160411 -377.102151) (xy 41.124696 -377.060934)
			(xy 41.09521 -377.015053) (xy 41.072553 -376.965443) (xy 41.057188 -376.913113) (xy 41.049426 -376.859129)
			(xy 41.04894 -376.83186) (xy 39.05568 -376.83186) (xy 39.046481 -376.93481) (xy 39.022717 -377.111506)
			(xy 38.991106 -377.286969) (xy 38.95171 -377.460849) (xy 38.904608 -377.632802) (xy 38.849892 -377.802486)
			(xy 38.787671 -377.969563) (xy 38.71807 -378.133704) (xy 38.641225 -378.29458) (xy 38.557291 -378.451874)
			(xy 38.466433 -378.605273) (xy 38.368831 -378.754472) (xy 38.26468 -378.899175) (xy 38.154187 -379.039095)
			(xy 38.03757 -379.173954) (xy 37.915061 -379.303484) (xy 37.786904 -379.427428) (xy 37.653353 -379.54554)
			(xy 37.514673 -379.657585) (xy 37.371139 -379.763342) (xy 37.223036 -379.862599) (xy 37.070659 -379.955161)
			(xy 36.91431 -380.040842) (xy 36.754299 -380.119474) (xy 36.590945 -380.1909) (xy 36.42457 -380.254978)
			(xy 36.255507 -380.31158) (xy 36.084678 -380.360428) (xy 70.895972 -380.360428) (xy 70.895972 -379.496828)
			(xy 70.896458 -379.469559) (xy 70.90422 -379.415575) (xy 70.919585 -379.363245) (xy 70.942242 -379.313635)
			(xy 70.971728 -379.267754) (xy 71.007443 -379.226537) (xy 71.04866 -379.190822) (xy 71.094541 -379.161336)
			(xy 71.144151 -379.138679) (xy 71.196481 -379.123314) (xy 71.250465 -379.115552) (xy 71.305003 -379.115552)
			(xy 71.358987 -379.123314) (xy 71.411317 -379.138679) (xy 71.460927 -379.161336) (xy 71.506808 -379.190822)
			(xy 71.548025 -379.226537) (xy 71.58374 -379.267754) (xy 71.613226 -379.313635) (xy 71.635883 -379.363245)
			(xy 71.651248 -379.415575) (xy 71.65901 -379.469559) (xy 71.659496 -379.496828) (xy 71.659496 -380.360428)
			(xy 103.42372 -380.360428) (xy 103.42372 -379.496828) (xy 103.424206 -379.469559) (xy 103.431968 -379.415575)
			(xy 103.447333 -379.363245) (xy 103.46999 -379.313635) (xy 103.499476 -379.267754) (xy 103.535191 -379.226537)
			(xy 103.576408 -379.190822) (xy 103.622289 -379.161336) (xy 103.671899 -379.138679) (xy 103.724229 -379.123314)
			(xy 103.778213 -379.115552) (xy 103.832751 -379.115552) (xy 103.886735 -379.123314) (xy 103.939065 -379.138679)
			(xy 103.988675 -379.161336) (xy 104.034556 -379.190822) (xy 104.075773 -379.226537) (xy 104.111488 -379.267754)
			(xy 104.140974 -379.313635) (xy 104.163631 -379.363245) (xy 104.178996 -379.415575) (xy 104.186758 -379.469559)
			(xy 104.187244 -379.496828) (xy 104.187244 -380.360428) (xy 137.996168 -380.360428) (xy 137.996168 -379.496828)
			(xy 137.996654 -379.469577) (xy 138.00441 -379.415629) (xy 138.019765 -379.363334) (xy 138.042407 -379.313757)
			(xy 138.071873 -379.267907) (xy 138.107564 -379.226716) (xy 138.148755 -379.191025) (xy 138.194605 -379.161559)
			(xy 138.244182 -379.138917) (xy 138.296477 -379.123562) (xy 138.350425 -379.115806) (xy 138.404927 -379.115806)
			(xy 138.458875 -379.123562) (xy 138.51117 -379.138917) (xy 138.560747 -379.161559) (xy 138.606597 -379.191025)
			(xy 138.647788 -379.226716) (xy 138.683479 -379.267907) (xy 138.712945 -379.313757) (xy 138.735587 -379.363334)
			(xy 138.750942 -379.415629) (xy 138.758698 -379.469577) (xy 138.759184 -379.496828) (xy 138.759184 -380.360428)
			(xy 170.523916 -380.360428) (xy 170.523916 -379.496828) (xy 170.524402 -379.469577) (xy 170.532158 -379.415629)
			(xy 170.547513 -379.363334) (xy 170.570155 -379.313757) (xy 170.599621 -379.267907) (xy 170.635312 -379.226716)
			(xy 170.676503 -379.191025) (xy 170.722353 -379.161559) (xy 170.77193 -379.138917) (xy 170.824225 -379.123562)
			(xy 170.878173 -379.115806) (xy 170.932675 -379.115806) (xy 170.986623 -379.123562) (xy 171.038918 -379.138917)
			(xy 171.088495 -379.161559) (xy 171.134345 -379.191025) (xy 171.175536 -379.226716) (xy 171.211227 -379.267907)
			(xy 171.240693 -379.313757) (xy 171.263335 -379.363334) (xy 171.27869 -379.415629) (xy 171.286446 -379.469577)
			(xy 171.286932 -379.496828) (xy 171.286932 -380.360428) (xy 171.286446 -380.387679) (xy 171.27869 -380.441627)
			(xy 171.263335 -380.493922) (xy 171.240693 -380.543499) (xy 171.211227 -380.589349) (xy 171.175536 -380.63054)
			(xy 171.134345 -380.666231) (xy 171.088495 -380.695697) (xy 171.038918 -380.718339) (xy 170.986623 -380.733694)
			(xy 170.932675 -380.74145) (xy 170.878173 -380.74145) (xy 170.824225 -380.733694) (xy 170.77193 -380.718339)
			(xy 170.722353 -380.695697) (xy 170.676503 -380.666231) (xy 170.635312 -380.63054) (xy 170.599621 -380.589349)
			(xy 170.570155 -380.543499) (xy 170.547513 -380.493922) (xy 170.532158 -380.441627) (xy 170.524402 -380.387679)
			(xy 170.523916 -380.360428) (xy 138.759184 -380.360428) (xy 138.758698 -380.387679) (xy 138.750942 -380.441627)
			(xy 138.735587 -380.493922) (xy 138.712945 -380.543499) (xy 138.683479 -380.589349) (xy 138.647788 -380.63054)
			(xy 138.606597 -380.666231) (xy 138.560747 -380.695697) (xy 138.51117 -380.718339) (xy 138.458875 -380.733694)
			(xy 138.404927 -380.74145) (xy 138.350425 -380.74145) (xy 138.296477 -380.733694) (xy 138.244182 -380.718339)
			(xy 138.194605 -380.695697) (xy 138.148755 -380.666231) (xy 138.107564 -380.63054) (xy 138.071873 -380.589349)
			(xy 138.042407 -380.543499) (xy 138.019765 -380.493922) (xy 138.00441 -380.441627) (xy 137.996654 -380.387679)
			(xy 137.996168 -380.360428) (xy 104.187244 -380.360428) (xy 104.186758 -380.387697) (xy 104.178996 -380.441681)
			(xy 104.163631 -380.494011) (xy 104.140974 -380.543621) (xy 104.111488 -380.589502) (xy 104.075773 -380.630719)
			(xy 104.034556 -380.666434) (xy 103.988675 -380.69592) (xy 103.939065 -380.718577) (xy 103.886735 -380.733942)
			(xy 103.832751 -380.741704) (xy 103.778213 -380.741704) (xy 103.724229 -380.733942) (xy 103.671899 -380.718577)
			(xy 103.622289 -380.69592) (xy 103.576408 -380.666434) (xy 103.535191 -380.630719) (xy 103.499476 -380.589502)
			(xy 103.46999 -380.543621) (xy 103.447333 -380.494011) (xy 103.431968 -380.441681) (xy 103.424206 -380.387697)
			(xy 103.42372 -380.360428) (xy 71.659496 -380.360428) (xy 71.65901 -380.387697) (xy 71.651248 -380.441681)
			(xy 71.635883 -380.494011) (xy 71.613226 -380.543621) (xy 71.58374 -380.589502) (xy 71.548025 -380.630719)
			(xy 71.506808 -380.666434) (xy 71.460927 -380.69592) (xy 71.411317 -380.718577) (xy 71.358987 -380.733942)
			(xy 71.305003 -380.741704) (xy 71.250465 -380.741704) (xy 71.196481 -380.733942) (xy 71.144151 -380.718577)
			(xy 71.094541 -380.69592) (xy 71.04866 -380.666434) (xy 71.007443 -380.630719) (xy 70.971728 -380.589502)
			(xy 70.942242 -380.543621) (xy 70.919585 -380.494011) (xy 70.90422 -380.441681) (xy 70.896458 -380.387697)
			(xy 70.895972 -380.360428) (xy 36.084678 -380.360428) (xy 36.08409 -380.360596) (xy 35.910659 -380.401926)
			(xy 35.735559 -380.43549) (xy 35.559139 -380.46122) (xy 35.381747 -380.479066) (xy 35.203736 -380.488992)
			(xy 35.025459 -380.490978) (xy 34.847272 -380.485021) (xy 34.669526 -380.471131) (xy 34.492576 -380.449338)
			(xy 34.316772 -380.419684) (xy 34.142464 -380.382227) (xy 33.969997 -380.337043) (xy 33.799714 -380.284221)
			(xy 33.631953 -380.223865) (xy 33.467048 -380.156097) (xy 33.305325 -380.081049) (xy 33.147106 -379.998872)
			(xy 32.992705 -379.909729) (xy 32.842428 -379.813795) (xy 32.696573 -379.711263) (xy 32.555431 -379.602335)
			(xy 32.419282 -379.487228) (xy 32.288395 -379.36617) (xy 32.163031 -379.239401) (xy 32.043438 -379.107174)
			(xy 31.929855 -378.969751) (xy 31.822506 -378.827404) (xy 31.721605 -378.680416) (xy 31.627352 -378.52908)
			(xy 31.539934 -378.373695) (xy 31.459524 -378.21457) (xy 31.386283 -378.052021) (xy 31.320356 -377.886371)
			(xy 31.261873 -377.717949) (xy 31.210951 -377.547088) (xy 31.167691 -377.374129) (xy 31.132179 -377.199414)
			(xy 31.104485 -377.02329) (xy 31.084664 -376.846108) (xy 31.072756 -376.668219) (xy 31.068784 -376.489976)
			(xy 2.509012 -376.489976) (xy 2.509012 -382.36906) (xy 41.04894 -382.36906) (xy 41.04894 -381.50546)
			(xy 41.049426 -381.478191) (xy 41.057188 -381.424207) (xy 41.072553 -381.371877) (xy 41.09521 -381.322267)
			(xy 41.124696 -381.276386) (xy 41.160411 -381.235169) (xy 41.201628 -381.199454) (xy 41.247509 -381.169968)
			(xy 41.297119 -381.147311) (xy 41.349449 -381.131946) (xy 41.403433 -381.124184) (xy 41.457971 -381.124184)
			(xy 41.511955 -381.131946) (xy 41.564285 -381.147311) (xy 41.613895 -381.169968) (xy 41.659776 -381.199454)
			(xy 41.700993 -381.235169) (xy 41.736708 -381.276386) (xy 41.766194 -381.322267) (xy 41.788851 -381.371877)
			(xy 41.804216 -381.424207) (xy 41.811978 -381.478191) (xy 41.812464 -381.50546) (xy 41.812464 -382.36906)
			(xy 73.576688 -382.36906) (xy 73.576688 -381.50546) (xy 73.577174 -381.478191) (xy 73.584936 -381.424207)
			(xy 73.600301 -381.371877) (xy 73.622958 -381.322267) (xy 73.652444 -381.276386) (xy 73.688159 -381.235169)
			(xy 73.729376 -381.199454) (xy 73.775257 -381.169968) (xy 73.824867 -381.147311) (xy 73.877197 -381.131946)
			(xy 73.931181 -381.124184) (xy 73.985719 -381.124184) (xy 74.039703 -381.131946) (xy 74.092033 -381.147311)
			(xy 74.141643 -381.169968) (xy 74.187524 -381.199454) (xy 74.228741 -381.235169) (xy 74.264456 -381.276386)
			(xy 74.293942 -381.322267) (xy 74.316599 -381.371877) (xy 74.331964 -381.424207) (xy 74.339726 -381.478191)
			(xy 74.340212 -381.50546) (xy 74.340212 -382.36906) (xy 108.149136 -382.36906) (xy 108.149136 -381.50546)
			(xy 108.149622 -381.478209) (xy 108.157378 -381.424261) (xy 108.172733 -381.371966) (xy 108.195375 -381.322389)
			(xy 108.224841 -381.276539) (xy 108.260532 -381.235348) (xy 108.301723 -381.199657) (xy 108.347573 -381.170191)
			(xy 108.39715 -381.147549) (xy 108.449445 -381.132194) (xy 108.503393 -381.124438) (xy 108.557895 -381.124438)
			(xy 108.611843 -381.132194) (xy 108.664138 -381.147549) (xy 108.713715 -381.170191) (xy 108.759565 -381.199657)
			(xy 108.800756 -381.235348) (xy 108.836447 -381.276539) (xy 108.865913 -381.322389) (xy 108.888555 -381.371966)
			(xy 108.90391 -381.424261) (xy 108.911666 -381.478209) (xy 108.912152 -381.50546) (xy 108.912152 -382.36906)
			(xy 140.676884 -382.36906) (xy 140.676884 -381.50546) (xy 140.67737 -381.478209) (xy 140.685126 -381.424261)
			(xy 140.700481 -381.371966) (xy 140.723123 -381.322389) (xy 140.752589 -381.276539) (xy 140.78828 -381.235348)
			(xy 140.829471 -381.199657) (xy 140.875321 -381.170191) (xy 140.924898 -381.147549) (xy 140.977193 -381.132194)
			(xy 141.031141 -381.124438) (xy 141.085643 -381.124438) (xy 141.139591 -381.132194) (xy 141.191886 -381.147549)
			(xy 141.241463 -381.170191) (xy 141.287313 -381.199657) (xy 141.328504 -381.235348) (xy 141.364195 -381.276539)
			(xy 141.393661 -381.322389) (xy 141.416303 -381.371966) (xy 141.431658 -381.424261) (xy 141.439414 -381.478209)
			(xy 141.4399 -381.50546) (xy 141.4399 -382.36906) (xy 141.439414 -382.396311) (xy 141.431658 -382.450259)
			(xy 141.416303 -382.502554) (xy 141.393661 -382.552131) (xy 141.364195 -382.597981) (xy 141.328504 -382.639172)
			(xy 141.287313 -382.674863) (xy 141.241463 -382.704329) (xy 141.191886 -382.726971) (xy 141.139591 -382.742326)
			(xy 141.085643 -382.750082) (xy 141.031141 -382.750082) (xy 140.977193 -382.742326) (xy 140.924898 -382.726971)
			(xy 140.875321 -382.704329) (xy 140.829471 -382.674863) (xy 140.78828 -382.639172) (xy 140.752589 -382.597981)
			(xy 140.723123 -382.552131) (xy 140.700481 -382.502554) (xy 140.685126 -382.450259) (xy 140.67737 -382.396311)
			(xy 140.676884 -382.36906) (xy 108.912152 -382.36906) (xy 108.911666 -382.396311) (xy 108.90391 -382.450259)
			(xy 108.888555 -382.502554) (xy 108.865913 -382.552131) (xy 108.836447 -382.597981) (xy 108.800756 -382.639172)
			(xy 108.759565 -382.674863) (xy 108.713715 -382.704329) (xy 108.664138 -382.726971) (xy 108.611843 -382.742326)
			(xy 108.557895 -382.750082) (xy 108.503393 -382.750082) (xy 108.449445 -382.742326) (xy 108.39715 -382.726971)
			(xy 108.347573 -382.704329) (xy 108.301723 -382.674863) (xy 108.260532 -382.639172) (xy 108.224841 -382.597981)
			(xy 108.195375 -382.552131) (xy 108.172733 -382.502554) (xy 108.157378 -382.450259) (xy 108.149622 -382.396311)
			(xy 108.149136 -382.36906) (xy 74.340212 -382.36906) (xy 74.339726 -382.396329) (xy 74.331964 -382.450313)
			(xy 74.316599 -382.502643) (xy 74.293942 -382.552253) (xy 74.264456 -382.598134) (xy 74.228741 -382.639351)
			(xy 74.187524 -382.675066) (xy 74.141643 -382.704552) (xy 74.092033 -382.727209) (xy 74.039703 -382.742574)
			(xy 73.985719 -382.750336) (xy 73.931181 -382.750336) (xy 73.877197 -382.742574) (xy 73.824867 -382.727209)
			(xy 73.775257 -382.704552) (xy 73.729376 -382.675066) (xy 73.688159 -382.639351) (xy 73.652444 -382.598134)
			(xy 73.622958 -382.552253) (xy 73.600301 -382.502643) (xy 73.584936 -382.450313) (xy 73.577174 -382.396329)
			(xy 73.576688 -382.36906) (xy 41.812464 -382.36906) (xy 41.811978 -382.396329) (xy 41.804216 -382.450313)
			(xy 41.788851 -382.502643) (xy 41.766194 -382.552253) (xy 41.736708 -382.598134) (xy 41.700993 -382.639351)
			(xy 41.659776 -382.675066) (xy 41.613895 -382.704552) (xy 41.564285 -382.727209) (xy 41.511955 -382.742574)
			(xy 41.457971 -382.750336) (xy 41.403433 -382.750336) (xy 41.349449 -382.742574) (xy 41.297119 -382.727209)
			(xy 41.247509 -382.704552) (xy 41.201628 -382.675066) (xy 41.160411 -382.639351) (xy 41.124696 -382.598134)
			(xy 41.09521 -382.552253) (xy 41.072553 -382.502643) (xy 41.057188 -382.450313) (xy 41.049426 -382.396329)
			(xy 41.04894 -382.36906) (xy 2.509012 -382.36906) (xy 2.509012 -385.310888) (xy 47.485808 -385.310888)
			(xy 47.485808 -385.31038) (xy 47.486243 -385.2864) (xy 47.493745 -385.239031) (xy 47.508561 -385.193417)
			(xy 47.530326 -385.15068) (xy 47.558505 -385.111872) (xy 47.592406 -385.077947) (xy 47.631194 -385.04974)
			(xy 47.673915 -385.027944) (xy 47.719518 -385.013096) (xy 47.766882 -385.00556) (xy 47.790862 -385.005072)
			(xy 47.79137 -385.005072) (xy 47.815305 -385.005523) (xy 47.862591 -385.012984) (xy 47.908134 -385.027728)
			(xy 47.950821 -385.049394) (xy 47.989606 -385.077452) (xy 48.023541 -385.111216) (xy 48.051795 -385.149858)
			(xy 48.06315 -385.170934) (xy 48.063658 -385.17195) (xy 48.143964 -385.310888) (xy 48.685704 -385.310888)
			(xy 48.685704 -385.31038) (xy 48.686143 -385.2864) (xy 48.693645 -385.239031) (xy 48.70846 -385.193417)
			(xy 48.730225 -385.150681) (xy 48.758404 -385.111873) (xy 48.792304 -385.077949) (xy 48.831092 -385.049741)
			(xy 48.873812 -385.027945) (xy 48.919415 -385.013097) (xy 48.966779 -385.005561) (xy 48.990758 -385.005072)
			(xy 48.991266 -385.005072) (xy 49.015201 -385.005526) (xy 49.062486 -385.012986) (xy 49.10803 -385.02773)
			(xy 49.150716 -385.049395) (xy 49.189502 -385.077453) (xy 49.223437 -385.111216) (xy 49.251691 -385.149859)
			(xy 49.263046 -385.170934) (xy 49.263554 -385.17195) (xy 49.34386 -385.310888) (xy 49.8856 -385.310888)
			(xy 49.8856 -385.31038) (xy 49.886043 -385.286401) (xy 49.893545 -385.239032) (xy 49.90836 -385.193418)
			(xy 49.930124 -385.150682) (xy 49.958303 -385.111875) (xy 49.992203 -385.07795) (xy 50.030989 -385.049743)
			(xy 50.073709 -385.027946) (xy 50.119312 -385.013097) (xy 50.166675 -385.005561) (xy 50.190654 -385.005072)
			(xy 50.191162 -385.005072) (xy 50.215097 -385.005529) (xy 50.262382 -385.012989) (xy 50.307925 -385.027732)
			(xy 50.350612 -385.049397) (xy 50.389397 -385.077454) (xy 50.423333 -385.111217) (xy 50.451587 -385.149859)
			(xy 50.462942 -385.170934) (xy 50.46345 -385.17195) (xy 50.543756 -385.310888) (xy 51.086004 -385.310888)
			(xy 51.086004 -385.31038) (xy 51.086444 -385.286388) (xy 51.093954 -385.238994) (xy 51.108785 -385.193359)
			(xy 51.130572 -385.150605) (xy 51.158779 -385.111786) (xy 51.192711 -385.077858) (xy 51.231533 -385.049655)
			(xy 51.274288 -385.027872) (xy 51.319925 -385.013046) (xy 51.36732 -385.005542) (xy 51.391312 -385.005072)
			(xy 51.415246 -385.00557) (xy 51.462529 -385.013022) (xy 51.508071 -385.027757) (xy 51.550758 -385.049416)
			(xy 51.589544 -385.077467) (xy 51.62348 -385.111224) (xy 51.651736 -385.149861) (xy 51.663092 -385.170934)
			(xy 51.6636 -385.17195) (xy 51.743906 -385.310888) (xy 52.2859 -385.310888) (xy 52.2859 -385.31038)
			(xy 52.286344 -385.286388) (xy 52.293854 -385.238995) (xy 52.308684 -385.19336) (xy 52.330471 -385.150606)
			(xy 52.358677 -385.111788) (xy 52.392609 -385.077859) (xy 52.43143 -385.049656) (xy 52.474186 -385.027873)
			(xy 52.519822 -385.013047) (xy 52.567216 -385.005542) (xy 52.591208 -385.005072) (xy 52.615141 -385.005573)
			(xy 52.662424 -385.013024) (xy 52.707967 -385.027759) (xy 52.750653 -385.049417) (xy 52.789439 -385.077468)
			(xy 52.823376 -385.111224) (xy 52.851632 -385.149861) (xy 52.862988 -385.170934) (xy 52.863496 -385.17195)
			(xy 52.943802 -385.310888) (xy 53.485796 -385.310888) (xy 53.485796 -385.31038) (xy 53.486243 -385.286401)
			(xy 53.493744 -385.239032) (xy 53.508559 -385.193419) (xy 53.530324 -385.150684) (xy 53.558502 -385.111876)
			(xy 53.592401 -385.077951) (xy 53.631187 -385.049744) (xy 53.673907 -385.027948) (xy 53.719508 -385.013098)
			(xy 53.766871 -385.005561) (xy 53.79085 -385.005072) (xy 53.791358 -385.005072) (xy 53.815293 -385.005532)
			(xy 53.862578 -385.012992) (xy 53.908121 -385.027734) (xy 53.950807 -385.049398) (xy 53.989593 -385.077455)
			(xy 54.023528 -385.111217) (xy 54.051783 -385.149859) (xy 54.063138 -385.170934) (xy 54.063646 -385.17195)
			(xy 54.143952 -385.310888) (xy 54.685692 -385.310888) (xy 54.685692 -385.31038) (xy 54.686143 -385.286401)
			(xy 54.693644 -385.239033) (xy 54.708459 -385.19342) (xy 54.730223 -385.150685) (xy 54.758401 -385.111877)
			(xy 54.792299 -385.077953) (xy 54.831085 -385.049745) (xy 54.873804 -385.027949) (xy 54.919405 -385.013099)
			(xy 54.966767 -385.005562) (xy 54.990746 -385.005072) (xy 54.991254 -385.005072) (xy 55.015189 -385.005536)
			(xy 55.062474 -385.012994) (xy 55.108017 -385.027736) (xy 55.150703 -385.0494) (xy 55.189489 -385.077456)
			(xy 55.223424 -385.111218) (xy 55.251679 -385.149859) (xy 55.263034 -385.170934) (xy 55.263542 -385.17195)
			(xy 55.343848 -385.310888) (xy 55.885588 -385.310888) (xy 55.885588 -385.31038) (xy 55.886043 -385.286401)
			(xy 55.893544 -385.239034) (xy 55.908359 -385.193421) (xy 55.930122 -385.150686) (xy 55.958299 -385.111879)
			(xy 55.992198 -385.077954) (xy 56.030983 -385.049747) (xy 56.073701 -385.02795) (xy 56.119302 -385.0131)
			(xy 56.166663 -385.005562) (xy 56.190642 -385.005072) (xy 56.19115 -385.005072) (xy 56.215085 -385.005539)
			(xy 56.262369 -385.012997) (xy 56.307912 -385.027738) (xy 56.350599 -385.049401) (xy 56.389384 -385.077457)
			(xy 56.42332 -385.111218) (xy 56.451575 -385.149859) (xy 56.46293 -385.170934) (xy 56.463438 -385.17195)
			(xy 56.543744 -385.310888) (xy 57.085992 -385.310888) (xy 57.085992 -385.31038) (xy 57.086444 -385.286388)
			(xy 57.093953 -385.238996) (xy 57.108783 -385.193362) (xy 57.130569 -385.150609) (xy 57.158775 -385.11179)
			(xy 57.192706 -385.077862) (xy 57.231526 -385.049659) (xy 57.27428 -385.027876) (xy 57.319915 -385.013049)
			(xy 57.367308 -385.005543) (xy 57.3913 -385.005072) (xy 57.391554 -385.005072) (xy 57.415489 -385.005536)
			(xy 57.462774 -385.012994) (xy 57.508317 -385.027736) (xy 57.551003 -385.0494) (xy 57.589789 -385.077456)
			(xy 57.623724 -385.111218) (xy 57.651979 -385.149859) (xy 57.663334 -385.170934) (xy 57.663842 -385.17195)
			(xy 57.744148 -385.310888) (xy 58.285888 -385.310888) (xy 58.285888 -385.31038) (xy 58.286344 -385.286388)
			(xy 58.293853 -385.238996) (xy 58.308683 -385.193362) (xy 58.330469 -385.15061) (xy 58.358674 -385.111792)
			(xy 58.392604 -385.077863) (xy 58.431424 -385.04966) (xy 58.474177 -385.027877) (xy 58.519812 -385.013049)
			(xy 58.567204 -385.005543) (xy 58.591196 -385.005072) (xy 58.59145 -385.005072) (xy 58.615385 -385.005539)
			(xy 58.662669 -385.012997) (xy 58.708212 -385.027738) (xy 58.750899 -385.049401) (xy 58.789684 -385.077457)
			(xy 58.82362 -385.111218) (xy 58.851875 -385.149859) (xy 58.86323 -385.170934) (xy 58.863738 -385.17195)
			(xy 58.944044 -385.310888) (xy 59.485784 -385.310888) (xy 59.485784 -385.31038) (xy 59.486221 -385.286374)
			(xy 59.493738 -385.238954) (xy 59.508584 -385.193295) (xy 59.530394 -385.150522) (xy 59.558628 -385.11169)
			(xy 59.592593 -385.077755) (xy 59.63145 -385.049554) (xy 59.674241 -385.027782) (xy 59.719913 -385.012976)
			(xy 59.76734 -385.0055) (xy 59.791346 -385.005072) (xy 59.7916 -385.005072) (xy 59.815533 -385.00558)
			(xy 59.862816 -385.01303) (xy 59.908358 -385.027764) (xy 59.951044 -385.04942) (xy 59.989831 -385.07747)
			(xy 60.023768 -385.111226) (xy 60.052024 -385.149862) (xy 60.06338 -385.170934) (xy 60.063888 -385.17195)
			(xy 60.144194 -385.310888) (xy 60.68568 -385.310888) (xy 60.68568 -385.31038) (xy 60.686121 -385.286374)
			(xy 60.693638 -385.238955) (xy 60.708484 -385.193296) (xy 60.730293 -385.150524) (xy 60.758527 -385.111692)
			(xy 60.792491 -385.077757) (xy 60.831347 -385.049556) (xy 60.874139 -385.027783) (xy 60.91981 -385.012977)
			(xy 60.967236 -385.0055) (xy 60.991242 -385.005072) (xy 60.991496 -385.005072) (xy 61.015432 -385.005502)
			(xy 61.062718 -385.012966) (xy 61.108262 -385.027714) (xy 61.150949 -385.049384) (xy 61.189734 -385.077445)
			(xy 61.223668 -385.111212) (xy 61.251922 -385.149857) (xy 61.263276 -385.170934) (xy 61.263784 -385.17195)
			(xy 61.34409 -385.310888) (xy 61.885576 -385.310888) (xy 61.885576 -385.31038) (xy 61.886021 -385.286374)
			(xy 61.893538 -385.238955) (xy 61.908383 -385.193297) (xy 61.930192 -385.150525) (xy 61.958426 -385.111693)
			(xy 61.992389 -385.077758) (xy 62.031245 -385.049557) (xy 62.074036 -385.027785) (xy 62.119707 -385.012977)
			(xy 62.167132 -385.0055) (xy 62.191138 -385.005072) (xy 62.191392 -385.005072) (xy 62.215328 -385.005505)
			(xy 62.262614 -385.012969) (xy 62.308158 -385.027716) (xy 62.350844 -385.049385) (xy 62.38963 -385.077446)
			(xy 62.423564 -385.111212) (xy 62.451818 -385.149857) (xy 62.463172 -385.170934) (xy 62.46368 -385.17195)
			(xy 62.543986 -385.310888) (xy 63.08598 -385.310888) (xy 63.08598 -385.31038) (xy 63.086444 -385.286389)
			(xy 63.093953 -385.238998) (xy 63.108782 -385.193364) (xy 63.130567 -385.150612) (xy 63.158771 -385.111795)
			(xy 63.192701 -385.077866) (xy 63.231519 -385.049663) (xy 63.274272 -385.027879) (xy 63.319905 -385.013051)
			(xy 63.367297 -385.005543) (xy 63.391288 -385.005072) (xy 63.391542 -385.005072) (xy 63.415476 -385.005545)
			(xy 63.462761 -385.013002) (xy 63.508303 -385.027742) (xy 63.55099 -385.049404) (xy 63.589776 -385.077459)
			(xy 63.623712 -385.11122) (xy 63.651967 -385.14986) (xy 63.663322 -385.170934) (xy 63.66383 -385.17195)
			(xy 63.744136 -385.310888) (xy 64.285876 -385.310888) (xy 64.285876 -385.31038) (xy 64.286344 -385.286389)
			(xy 64.293853 -385.238998) (xy 64.308682 -385.193365) (xy 64.330467 -385.150614) (xy 64.35867 -385.111796)
			(xy 64.392599 -385.077868) (xy 64.431417 -385.049664) (xy 64.474169 -385.02788) (xy 64.519802 -385.013052)
			(xy 64.567193 -385.005544) (xy 64.591184 -385.005072) (xy 64.591438 -385.005072) (xy 64.615372 -385.005549)
			(xy 64.662656 -385.013005) (xy 64.708199 -385.027744) (xy 64.750886 -385.049406) (xy 64.789672 -385.07746)
			(xy 64.823607 -385.11122) (xy 64.851863 -385.14986) (xy 64.863218 -385.170934) (xy 64.863726 -385.17195)
			(xy 64.944032 -385.310888) (xy 65.485772 -385.310888) (xy 65.485772 -385.31038) (xy 65.486221 -385.286375)
			(xy 65.493738 -385.238956) (xy 65.508583 -385.193298) (xy 65.530391 -385.150526) (xy 65.558625 -385.111694)
			(xy 65.592588 -385.07776) (xy 65.631443 -385.049558) (xy 65.674233 -385.027786) (xy 65.719903 -385.012978)
			(xy 65.767328 -385.005501) (xy 65.791334 -385.005072) (xy 65.791588 -385.005072) (xy 65.815524 -385.005508)
			(xy 65.86281 -385.012972) (xy 65.908353 -385.027718) (xy 65.95104 -385.049387) (xy 65.989825 -385.077447)
			(xy 66.02376 -385.111213) (xy 66.052014 -385.149858) (xy 66.063368 -385.170934) (xy 66.063876 -385.17195)
			(xy 66.144182 -385.310888) (xy 80.013556 -385.310888) (xy 80.013556 -385.31038) (xy 80.014043 -385.286403)
			(xy 80.021543 -385.239038) (xy 80.036355 -385.193429) (xy 80.058116 -385.150695) (xy 80.08629 -385.11189)
			(xy 80.120184 -385.077966) (xy 80.158965 -385.049758) (xy 80.201679 -385.027959) (xy 80.247275 -385.013106)
			(xy 80.294633 -385.005564) (xy 80.31861 -385.005072) (xy 80.319118 -385.005072) (xy 80.343052 -385.005565)
			(xy 80.390335 -385.013018) (xy 80.435877 -385.027754) (xy 80.478564 -385.049413) (xy 80.51735 -385.077465)
			(xy 80.551287 -385.111223) (xy 80.579542 -385.149861) (xy 80.590898 -385.170934) (xy 80.591406 -385.17195)
			(xy 80.671712 -385.310888) (xy 81.213452 -385.310888) (xy 81.213452 -385.31038) (xy 81.213943 -385.286403)
			(xy 81.221443 -385.239039) (xy 81.236255 -385.193429) (xy 81.258015 -385.150697) (xy 81.286189 -385.111891)
			(xy 81.320082 -385.077967) (xy 81.358863 -385.049759) (xy 81.401576 -385.02796) (xy 81.447172 -385.013107)
			(xy 81.494529 -385.005565) (xy 81.518506 -385.005072) (xy 81.519014 -385.005072) (xy 81.542948 -385.005568)
			(xy 81.590231 -385.013021) (xy 81.635773 -385.027756) (xy 81.67846 -385.049415) (xy 81.717246 -385.077466)
			(xy 81.751182 -385.111224) (xy 81.779438 -385.149861) (xy 81.790794 -385.170934) (xy 81.791302 -385.17195)
			(xy 81.871608 -385.310888) (xy 82.413348 -385.310888) (xy 82.413348 -385.31038) (xy 82.413843 -385.286403)
			(xy 82.421343 -385.239039) (xy 82.436155 -385.19343) (xy 82.457915 -385.150698) (xy 82.486088 -385.111892)
			(xy 82.519981 -385.077969) (xy 82.55876 -385.04976) (xy 82.601473 -385.027961) (xy 82.647069 -385.013108)
			(xy 82.694426 -385.005565) (xy 82.718402 -385.005072) (xy 82.71891 -385.005072) (xy 82.742843 -385.005571)
			(xy 82.790127 -385.013023) (xy 82.835669 -385.027758) (xy 82.878355 -385.049416) (xy 82.917142 -385.077467)
			(xy 82.951078 -385.111224) (xy 82.979334 -385.149861) (xy 82.99069 -385.170934) (xy 82.991198 -385.17195)
			(xy 83.071504 -385.310888) (xy 83.613752 -385.310888) (xy 83.613752 -385.31038) (xy 83.614244 -385.28639)
			(xy 83.621752 -385.239002) (xy 83.63658 -385.193371) (xy 83.658362 -385.150621) (xy 83.686563 -385.111804)
			(xy 83.720489 -385.077876) (xy 83.759304 -385.049673) (xy 83.802052 -385.027887) (xy 83.847682 -385.013057)
			(xy 83.89507 -385.005546) (xy 83.91906 -385.005072) (xy 83.942995 -385.005531) (xy 83.99028 -385.01299)
			(xy 84.035823 -385.027733) (xy 84.07851 -385.049398) (xy 84.117295 -385.077455) (xy 84.151231 -385.111217)
			(xy 84.179485 -385.149859) (xy 84.19084 -385.170934) (xy 84.191348 -385.17195) (xy 84.271654 -385.310888)
			(xy 84.813648 -385.310888) (xy 84.813648 -385.31038) (xy 84.814144 -385.28639) (xy 84.821652 -385.239002)
			(xy 84.836479 -385.193372) (xy 84.858261 -385.150622) (xy 84.886462 -385.111805) (xy 84.920387 -385.077878)
			(xy 84.959201 -385.049674) (xy 85.001949 -385.027888) (xy 85.047579 -385.013057) (xy 85.094966 -385.005546)
			(xy 85.118956 -385.005072) (xy 85.142891 -385.005534) (xy 85.190176 -385.012993) (xy 85.235719 -385.027735)
			(xy 85.278405 -385.049399) (xy 85.317191 -385.077456) (xy 85.351126 -385.111218) (xy 85.379381 -385.149859)
			(xy 85.390736 -385.170934) (xy 85.391244 -385.17195) (xy 85.47155 -385.310888) (xy 86.013544 -385.310888)
			(xy 86.013544 -385.31038) (xy 86.014043 -385.286403) (xy 86.021543 -385.23904) (xy 86.036354 -385.193431)
			(xy 86.058114 -385.150699) (xy 86.086287 -385.111894) (xy 86.120179 -385.07797) (xy 86.158958 -385.049762)
			(xy 86.20167 -385.027962) (xy 86.247265 -385.013109) (xy 86.294622 -385.005565) (xy 86.318598 -385.005072)
			(xy 86.319106 -385.005072) (xy 86.343039 -385.005575) (xy 86.390322 -385.013026) (xy 86.435864 -385.02776)
			(xy 86.478551 -385.049418) (xy 86.517337 -385.077468) (xy 86.551274 -385.111225) (xy 86.57953 -385.149861)
			(xy 86.590886 -385.170934) (xy 86.591394 -385.17195) (xy 86.6717 -385.310888) (xy 87.21344 -385.310888)
			(xy 87.21344 -385.31038) (xy 87.213843 -385.286399) (xy 87.221346 -385.239026) (xy 87.236164 -385.193409)
			(xy 87.257932 -385.15067) (xy 87.286115 -385.111861) (xy 87.320019 -385.077936) (xy 87.358812 -385.049729)
			(xy 87.401537 -385.027935) (xy 87.447145 -385.013089) (xy 87.494513 -385.005558) (xy 87.518494 -385.005072)
			(xy 87.519002 -385.005072) (xy 87.542935 -385.005578) (xy 87.590218 -385.013028) (xy 87.63576 -385.027763)
			(xy 87.678447 -385.04942) (xy 87.717233 -385.077469) (xy 87.75117 -385.111225) (xy 87.779426 -385.149861)
			(xy 87.790782 -385.170934) (xy 87.79129 -385.17195) (xy 87.871596 -385.310888) (xy 88.413336 -385.310888)
			(xy 88.413336 -385.31038) (xy 88.413743 -385.286399) (xy 88.421246 -385.239027) (xy 88.436063 -385.19341)
			(xy 88.457831 -385.150672) (xy 88.486013 -385.111862) (xy 88.519918 -385.077937) (xy 88.558709 -385.04973)
			(xy 88.601434 -385.027936) (xy 88.647041 -385.01309) (xy 88.694409 -385.005558) (xy 88.71839 -385.005072)
			(xy 88.718898 -385.005072) (xy 88.742834 -385.0055) (xy 88.790121 -385.012965) (xy 88.835664 -385.027713)
			(xy 88.878351 -385.049383) (xy 88.917136 -385.077445) (xy 88.95107 -385.111212) (xy 88.979324 -385.149857)
			(xy 88.990678 -385.170934) (xy 88.991186 -385.17195) (xy 89.071492 -385.310888) (xy 89.61374 -385.310888)
			(xy 89.61374 -385.31038) (xy 89.61412 -385.286384) (xy 89.621631 -385.238983) (xy 89.636465 -385.193341)
			(xy 89.658257 -385.150582) (xy 89.68647 -385.111758) (xy 89.72041 -385.077826) (xy 89.75924 -385.049622)
			(xy 89.802004 -385.027839) (xy 89.847649 -385.013015) (xy 89.895052 -385.005515) (xy 89.919048 -385.005072)
			(xy 89.942983 -385.005541) (xy 89.990267 -385.012998) (xy 90.03581 -385.027739) (xy 90.078497 -385.049402)
			(xy 90.117282 -385.077458) (xy 90.151218 -385.111219) (xy 90.179473 -385.149859) (xy 90.190828 -385.170934)
			(xy 90.191336 -385.17195) (xy 90.271642 -385.310888) (xy 90.813636 -385.310888) (xy 90.813636 -385.31038)
			(xy 90.81402 -385.286384) (xy 90.821531 -385.238984) (xy 90.836365 -385.193342) (xy 90.858157 -385.150583)
			(xy 90.886369 -385.111759) (xy 90.920308 -385.077828) (xy 90.959138 -385.049623) (xy 91.001901 -385.02784)
			(xy 91.047546 -385.013016) (xy 91.094948 -385.005515) (xy 91.118944 -385.005072) (xy 91.142878 -385.005544)
			(xy 91.190163 -385.013001) (xy 91.235706 -385.027741) (xy 91.278392 -385.049404) (xy 91.317178 -385.077459)
			(xy 91.351114 -385.111219) (xy 91.379369 -385.14986) (xy 91.390724 -385.170934) (xy 91.391232 -385.17195)
			(xy 91.471538 -385.310888) (xy 92.013532 -385.310888) (xy 92.013532 -385.31038) (xy 92.013943 -385.286399)
			(xy 92.021446 -385.239027) (xy 92.036263 -385.193411) (xy 92.05803 -385.150673) (xy 92.086212 -385.111864)
			(xy 92.120116 -385.077939) (xy 92.158907 -385.049732) (xy 92.201632 -385.027937) (xy 92.247238 -385.013091)
			(xy 92.294605 -385.005559) (xy 92.318586 -385.005072) (xy 92.319094 -385.005072) (xy 92.34303 -385.005503)
			(xy 92.390316 -385.012968) (xy 92.43586 -385.027715) (xy 92.478547 -385.049385) (xy 92.517332 -385.077446)
			(xy 92.551266 -385.111212) (xy 92.57952 -385.149857) (xy 92.590874 -385.170934) (xy 92.591382 -385.17195)
			(xy 92.671688 -385.310888) (xy 93.213428 -385.310888) (xy 93.213428 -385.31038) (xy 93.213843 -385.286399)
			(xy 93.221346 -385.239028) (xy 93.236162 -385.193412) (xy 93.257929 -385.150674) (xy 93.286111 -385.111865)
			(xy 93.320014 -385.07794) (xy 93.358805 -385.049733) (xy 93.401529 -385.027938) (xy 93.447135 -385.013092)
			(xy 93.494501 -385.005559) (xy 93.518482 -385.005072) (xy 93.51899 -385.005072) (xy 93.542926 -385.005506)
			(xy 93.590212 -385.01297) (xy 93.635756 -385.027717) (xy 93.678442 -385.049386) (xy 93.717227 -385.077447)
			(xy 93.751162 -385.111213) (xy 93.779416 -385.149857) (xy 93.79077 -385.170934) (xy 93.791278 -385.17195)
			(xy 93.871584 -385.310888) (xy 94.413324 -385.310888) (xy 94.413324 -385.31038) (xy 94.413743 -385.286399)
			(xy 94.421245 -385.239028) (xy 94.436062 -385.193413) (xy 94.457829 -385.150675) (xy 94.48601 -385.111866)
			(xy 94.519913 -385.077941) (xy 94.558703 -385.049734) (xy 94.601426 -385.02794) (xy 94.647032 -385.013093)
			(xy 94.694398 -385.005559) (xy 94.718378 -385.005072) (xy 94.718886 -385.005072) (xy 94.742822 -385.00551)
			(xy 94.790108 -385.012973) (xy 94.835651 -385.027719) (xy 94.878338 -385.049388) (xy 94.917123 -385.077448)
			(xy 94.951058 -385.111213) (xy 94.979312 -385.149858) (xy 94.990666 -385.170934) (xy 94.991174 -385.17195)
			(xy 95.07148 -385.310888) (xy 95.613728 -385.310888) (xy 95.613728 -385.31038) (xy 95.61412 -385.286385)
			(xy 95.621631 -385.238985) (xy 95.636464 -385.193344) (xy 95.658255 -385.150585) (xy 95.686467 -385.111762)
			(xy 95.720405 -385.07783) (xy 95.759233 -385.049626) (xy 95.801996 -385.027843) (xy 95.847639 -385.013018)
			(xy 95.89504 -385.005515) (xy 95.919036 -385.005072) (xy 95.94297 -385.00555) (xy 95.990254 -385.013006)
			(xy 96.035797 -385.027745) (xy 96.078484 -385.049407) (xy 96.117269 -385.077461) (xy 96.151205 -385.11122)
			(xy 96.179461 -385.14986) (xy 96.190816 -385.170934) (xy 96.191324 -385.17195) (xy 96.27163 -385.310888)
			(xy 96.813624 -385.310888) (xy 96.813624 -385.31038) (xy 96.81402 -385.286385) (xy 96.821531 -385.238985)
			(xy 96.836364 -385.193345) (xy 96.858154 -385.150586) (xy 96.886366 -385.111764) (xy 96.920303 -385.077832)
			(xy 96.959131 -385.049627) (xy 97.001893 -385.027844) (xy 97.047536 -385.013018) (xy 97.094937 -385.005516)
			(xy 97.118932 -385.005072) (xy 97.142866 -385.005554) (xy 97.19015 -385.013009) (xy 97.235693 -385.027747)
			(xy 97.278379 -385.049408) (xy 97.317165 -385.077462) (xy 97.351101 -385.111221) (xy 97.379357 -385.14986)
			(xy 97.390712 -385.170934) (xy 97.39122 -385.17195) (xy 97.471526 -385.310888) (xy 98.01352 -385.310888)
			(xy 98.01352 -385.31038) (xy 98.013943 -385.2864) (xy 98.021445 -385.239029) (xy 98.036262 -385.193414)
			(xy 98.058028 -385.150676) (xy 98.086209 -385.111868) (xy 98.120111 -385.077943) (xy 98.1589 -385.049736)
			(xy 98.201623 -385.027941) (xy 98.247228 -385.013093) (xy 98.294594 -385.005559) (xy 98.318574 -385.005072)
			(xy 98.319082 -385.005072) (xy 98.343018 -385.005513) (xy 98.390303 -385.012976) (xy 98.435847 -385.027721)
			(xy 98.478534 -385.049389) (xy 98.517319 -385.077449) (xy 98.551254 -385.111214) (xy 98.579508 -385.149858)
			(xy 98.590862 -385.170934) (xy 98.59137 -385.17195) (xy 98.671676 -385.310888) (xy 114.586004 -385.310888)
			(xy 114.586004 -385.31038) (xy 114.586444 -385.286388) (xy 114.593954 -385.238994) (xy 114.608785 -385.193359)
			(xy 114.630572 -385.150605) (xy 114.658779 -385.111786) (xy 114.692711 -385.077858) (xy 114.731533 -385.049655)
			(xy 114.774288 -385.027872) (xy 114.819925 -385.013046) (xy 114.86732 -385.005542) (xy 114.891312 -385.005072)
			(xy 114.915246 -385.00557) (xy 114.962529 -385.013022) (xy 115.008071 -385.027757) (xy 115.050758 -385.049416)
			(xy 115.089544 -385.077467) (xy 115.12348 -385.111224) (xy 115.151736 -385.149861) (xy 115.163092 -385.170934)
			(xy 115.1636 -385.17195) (xy 115.243906 -385.310888) (xy 115.7859 -385.310888) (xy 115.7859 -385.31038)
			(xy 115.786344 -385.286388) (xy 115.793854 -385.238995) (xy 115.808684 -385.19336) (xy 115.830471 -385.150606)
			(xy 115.858677 -385.111788) (xy 115.892609 -385.077859) (xy 115.93143 -385.049656) (xy 115.974186 -385.027873)
			(xy 116.019822 -385.013047) (xy 116.067216 -385.005542) (xy 116.091208 -385.005072) (xy 116.115141 -385.005573)
			(xy 116.162424 -385.013024) (xy 116.207967 -385.027759) (xy 116.250653 -385.049417) (xy 116.289439 -385.077468)
			(xy 116.323376 -385.111224) (xy 116.351632 -385.149861) (xy 116.362988 -385.170934) (xy 116.363496 -385.17195)
			(xy 116.443802 -385.310888) (xy 116.985796 -385.310888) (xy 116.985796 -385.31038) (xy 116.986244 -385.286388)
			(xy 116.993753 -385.238995) (xy 117.008584 -385.193361) (xy 117.03037 -385.150608) (xy 117.058576 -385.111789)
			(xy 117.092507 -385.077861) (xy 117.131328 -385.049658) (xy 117.174083 -385.027875) (xy 117.219719 -385.013048)
			(xy 117.267112 -385.005542) (xy 117.291104 -385.005072) (xy 117.315037 -385.005576) (xy 117.36232 -385.013027)
			(xy 117.407862 -385.027762) (xy 117.450549 -385.049419) (xy 117.489335 -385.077469) (xy 117.523272 -385.111225)
			(xy 117.551528 -385.149861) (xy 117.562884 -385.170934) (xy 117.563392 -385.17195) (xy 117.643698 -385.310888)
			(xy 118.185692 -385.310888) (xy 118.185692 -385.31038) (xy 118.186143 -385.286401) (xy 118.193644 -385.239033)
			(xy 118.208459 -385.19342) (xy 118.230223 -385.150685) (xy 118.258401 -385.111877) (xy 118.292299 -385.077953)
			(xy 118.331085 -385.049745) (xy 118.373804 -385.027949) (xy 118.419405 -385.013099) (xy 118.466767 -385.005562)
			(xy 118.490746 -385.005072) (xy 118.491254 -385.005072) (xy 118.515189 -385.005536) (xy 118.562474 -385.012994)
			(xy 118.608017 -385.027736) (xy 118.650703 -385.0494) (xy 118.689489 -385.077456) (xy 118.723424 -385.111218)
			(xy 118.751679 -385.149859) (xy 118.763034 -385.170934) (xy 118.763542 -385.17195) (xy 118.843848 -385.310888)
			(xy 119.385588 -385.310888) (xy 119.385588 -385.31038) (xy 119.386043 -385.286401) (xy 119.393544 -385.239034)
			(xy 119.408359 -385.193421) (xy 119.430122 -385.150686) (xy 119.458299 -385.111879) (xy 119.492198 -385.077954)
			(xy 119.530983 -385.049747) (xy 119.573701 -385.02795) (xy 119.619302 -385.0131) (xy 119.666663 -385.005562)
			(xy 119.690642 -385.005072) (xy 119.69115 -385.005072) (xy 119.715085 -385.005539) (xy 119.762369 -385.012997)
			(xy 119.807912 -385.027738) (xy 119.850599 -385.049401) (xy 119.889384 -385.077457) (xy 119.92332 -385.111218)
			(xy 119.951575 -385.149859) (xy 119.96293 -385.170934) (xy 119.963438 -385.17195) (xy 120.043744 -385.310888)
			(xy 120.585992 -385.310888) (xy 120.585992 -385.31038) (xy 120.586444 -385.286388) (xy 120.593953 -385.238996)
			(xy 120.608783 -385.193362) (xy 120.630569 -385.150609) (xy 120.658775 -385.11179) (xy 120.692706 -385.077862)
			(xy 120.731526 -385.049659) (xy 120.77428 -385.027876) (xy 120.819915 -385.013049) (xy 120.867308 -385.005543)
			(xy 120.8913 -385.005072) (xy 120.915233 -385.00558) (xy 120.962516 -385.01303) (xy 121.008058 -385.027764)
			(xy 121.050744 -385.04942) (xy 121.089531 -385.07747) (xy 121.123468 -385.111226) (xy 121.151724 -385.149862)
			(xy 121.16308 -385.170934) (xy 121.163588 -385.17195) (xy 121.243894 -385.310888) (xy 121.785888 -385.310888)
			(xy 121.785888 -385.31038) (xy 121.786344 -385.286388) (xy 121.793853 -385.238996) (xy 121.808683 -385.193362)
			(xy 121.830469 -385.15061) (xy 121.858674 -385.111792) (xy 121.892604 -385.077863) (xy 121.931424 -385.04966)
			(xy 121.974177 -385.027877) (xy 122.019812 -385.013049) (xy 122.067204 -385.005543) (xy 122.091196 -385.005072)
			(xy 122.115132 -385.005502) (xy 122.162418 -385.012966) (xy 122.207962 -385.027714) (xy 122.250649 -385.049384)
			(xy 122.289434 -385.077445) (xy 122.323368 -385.111212) (xy 122.351622 -385.149857) (xy 122.362976 -385.170934)
			(xy 122.363484 -385.17195) (xy 122.44379 -385.310888) (xy 122.985784 -385.310888) (xy 122.985784 -385.31038)
			(xy 122.986244 -385.286389) (xy 122.993753 -385.238997) (xy 123.008583 -385.193363) (xy 123.030368 -385.150611)
			(xy 123.058573 -385.111793) (xy 123.092502 -385.077865) (xy 123.131321 -385.049662) (xy 123.174074 -385.027878)
			(xy 123.219709 -385.01305) (xy 123.267101 -385.005543) (xy 123.291092 -385.005072) (xy 123.315028 -385.005505)
			(xy 123.362314 -385.012969) (xy 123.407858 -385.027716) (xy 123.450544 -385.049385) (xy 123.48933 -385.077446)
			(xy 123.523264 -385.111212) (xy 123.551518 -385.149857) (xy 123.562872 -385.170934) (xy 123.56338 -385.17195)
			(xy 123.643686 -385.310888) (xy 124.18568 -385.310888) (xy 124.18568 -385.31038) (xy 124.186143 -385.286402)
			(xy 124.193644 -385.239035) (xy 124.208458 -385.193423) (xy 124.230221 -385.150688) (xy 124.258397 -385.111882)
			(xy 124.292294 -385.077957) (xy 124.331078 -385.049749) (xy 124.373795 -385.027952) (xy 124.419395 -385.013101)
			(xy 124.466756 -385.005562) (xy 124.490734 -385.005072) (xy 124.491242 -385.005072) (xy 124.515176 -385.005545)
			(xy 124.562461 -385.013002) (xy 124.608003 -385.027742) (xy 124.65069 -385.049404) (xy 124.689476 -385.077459)
			(xy 124.723412 -385.11122) (xy 124.751667 -385.14986) (xy 124.763022 -385.170934) (xy 124.76353 -385.17195)
			(xy 124.843836 -385.310888) (xy 125.385576 -385.310888) (xy 125.385576 -385.31038) (xy 125.386043 -385.286402)
			(xy 125.393544 -385.239035) (xy 125.408357 -385.193424) (xy 125.43012 -385.150689) (xy 125.458296 -385.111883)
			(xy 125.492192 -385.077959) (xy 125.530976 -385.049751) (xy 125.573693 -385.027953) (xy 125.619292 -385.013102)
			(xy 125.666652 -385.005563) (xy 125.69063 -385.005072) (xy 125.691138 -385.005072) (xy 125.715072 -385.005549)
			(xy 125.762356 -385.013005) (xy 125.807899 -385.027744) (xy 125.850586 -385.049406) (xy 125.889372 -385.07746)
			(xy 125.923307 -385.11122) (xy 125.951563 -385.14986) (xy 125.962918 -385.170934) (xy 125.963426 -385.17195)
			(xy 126.043732 -385.310888) (xy 126.58598 -385.310888) (xy 126.58598 -385.31038) (xy 126.586444 -385.286389)
			(xy 126.593953 -385.238998) (xy 126.608782 -385.193364) (xy 126.630567 -385.150612) (xy 126.658771 -385.111795)
			(xy 126.692701 -385.077866) (xy 126.731519 -385.049663) (xy 126.774272 -385.027879) (xy 126.819905 -385.013051)
			(xy 126.867297 -385.005543) (xy 126.891288 -385.005072) (xy 126.915224 -385.005508) (xy 126.96251 -385.012972)
			(xy 127.008053 -385.027718) (xy 127.05074 -385.049387) (xy 127.089525 -385.077447) (xy 127.12346 -385.111213)
			(xy 127.151714 -385.149858) (xy 127.163068 -385.170934) (xy 127.163576 -385.17195) (xy 127.243882 -385.310888)
			(xy 127.785876 -385.310888) (xy 127.785876 -385.31038) (xy 127.786344 -385.286389) (xy 127.793853 -385.238998)
			(xy 127.808682 -385.193365) (xy 127.830467 -385.150614) (xy 127.85867 -385.111796) (xy 127.892599 -385.077868)
			(xy 127.931417 -385.049664) (xy 127.974169 -385.02788) (xy 128.019802 -385.013052) (xy 128.067193 -385.005544)
			(xy 128.091184 -385.005072) (xy 128.11512 -385.005511) (xy 128.162406 -385.012974) (xy 128.207949 -385.02772)
			(xy 128.250636 -385.049388) (xy 128.289421 -385.077448) (xy 128.323356 -385.111214) (xy 128.35161 -385.149858)
			(xy 128.362964 -385.170934) (xy 128.363472 -385.17195) (xy 128.443778 -385.310888) (xy 128.985772 -385.310888)
			(xy 128.985772 -385.31038) (xy 128.986244 -385.286389) (xy 128.993753 -385.238999) (xy 129.008581 -385.193366)
			(xy 129.030366 -385.150615) (xy 129.058569 -385.111797) (xy 129.092497 -385.077869) (xy 129.131315 -385.049666)
			(xy 129.174066 -385.027881) (xy 129.219699 -385.013053) (xy 129.267089 -385.005544) (xy 129.29108 -385.005072)
			(xy 129.315016 -385.005515) (xy 129.362301 -385.012977) (xy 129.407845 -385.027722) (xy 129.450531 -385.04939)
			(xy 129.489317 -385.077449) (xy 129.523252 -385.111214) (xy 129.551506 -385.149858) (xy 129.56286 -385.170934)
			(xy 129.563368 -385.17195) (xy 129.643674 -385.310888) (xy 130.185668 -385.310888) (xy 130.185668 -385.31038)
			(xy 130.186143 -385.286402) (xy 130.193643 -385.239036) (xy 130.208457 -385.193426) (xy 130.230218 -385.150692)
			(xy 130.258394 -385.111886) (xy 130.292289 -385.077961) (xy 130.331072 -385.049753) (xy 130.373787 -385.027956)
			(xy 130.419385 -385.013104) (xy 130.466745 -385.005563) (xy 130.490722 -385.005072) (xy 130.49123 -385.005072)
			(xy 130.515164 -385.005555) (xy 130.562448 -385.01301) (xy 130.60799 -385.027748) (xy 130.650677 -385.049409)
			(xy 130.689463 -385.077462) (xy 130.723399 -385.111221) (xy 130.751655 -385.14986) (xy 130.76301 -385.170934)
			(xy 130.763518 -385.17195) (xy 130.843824 -385.310888) (xy 131.385564 -385.310888) (xy 131.385564 -385.31038)
			(xy 131.386043 -385.286402) (xy 131.393543 -385.239037) (xy 131.408356 -385.193427) (xy 131.430118 -385.150693)
			(xy 131.458292 -385.111887) (xy 131.492187 -385.077963) (xy 131.530969 -385.049755) (xy 131.573684 -385.027957)
			(xy 131.619282 -385.013105) (xy 131.666641 -385.005564) (xy 131.690618 -385.005072) (xy 131.691126 -385.005072)
			(xy 131.71506 -385.005558) (xy 131.762344 -385.013013) (xy 131.807886 -385.02775) (xy 131.850573 -385.04941)
			(xy 131.889359 -385.077463) (xy 131.923295 -385.111222) (xy 131.951551 -385.14986) (xy 131.962906 -385.170934)
			(xy 131.963414 -385.17195) (xy 132.04372 -385.310888) (xy 132.585968 -385.310888) (xy 132.585968 -385.31038)
			(xy 132.586444 -385.286389) (xy 132.593952 -385.238999) (xy 132.608781 -385.193367) (xy 132.630565 -385.150616)
			(xy 132.658768 -385.111799) (xy 132.692696 -385.077871) (xy 132.731513 -385.049667) (xy 132.774263 -385.027883)
			(xy 132.819895 -385.013053) (xy 132.867285 -385.005544) (xy 132.891276 -385.005072) (xy 132.915211 -385.005518)
			(xy 132.962497 -385.01298) (xy 133.00804 -385.027724) (xy 133.050727 -385.049391) (xy 133.089512 -385.07745)
			(xy 133.123447 -385.111215) (xy 133.151701 -385.149858) (xy 133.163056 -385.170934) (xy 133.163564 -385.17195)
			(xy 133.24387 -385.310888) (xy 147.113752 -385.310888) (xy 147.113752 -385.31038) (xy 147.114244 -385.28639)
			(xy 147.121752 -385.239002) (xy 147.13658 -385.193371) (xy 147.158362 -385.150621) (xy 147.186563 -385.111804)
			(xy 147.220489 -385.077876) (xy 147.259304 -385.049673) (xy 147.302052 -385.027887) (xy 147.347682 -385.013057)
			(xy 147.39507 -385.005546) (xy 147.41906 -385.005072) (xy 147.442995 -385.005531) (xy 147.49028 -385.01299)
			(xy 147.535823 -385.027733) (xy 147.57851 -385.049398) (xy 147.617295 -385.077455) (xy 147.651231 -385.111217)
			(xy 147.679485 -385.149859) (xy 147.69084 -385.170934) (xy 147.691348 -385.17195) (xy 147.771654 -385.310888)
			(xy 148.313648 -385.310888) (xy 148.313648 -385.31038) (xy 148.314144 -385.28639) (xy 148.321652 -385.239002)
			(xy 148.336479 -385.193372) (xy 148.358261 -385.150622) (xy 148.386462 -385.111805) (xy 148.420387 -385.077878)
			(xy 148.459201 -385.049674) (xy 148.501949 -385.027888) (xy 148.547579 -385.013057) (xy 148.594966 -385.005546)
			(xy 148.618956 -385.005072) (xy 148.642891 -385.005534) (xy 148.690176 -385.012993) (xy 148.735719 -385.027735)
			(xy 148.778405 -385.049399) (xy 148.817191 -385.077456) (xy 148.851126 -385.111218) (xy 148.879381 -385.149859)
			(xy 148.890736 -385.170934) (xy 148.891244 -385.17195) (xy 148.97155 -385.310888) (xy 149.513544 -385.310888)
			(xy 149.513544 -385.31038) (xy 149.514044 -385.286391) (xy 149.521552 -385.239003) (xy 149.536379 -385.193373)
			(xy 149.558161 -385.150623) (xy 149.586361 -385.111807) (xy 149.620286 -385.077879) (xy 149.659099 -385.049675)
			(xy 149.701847 -385.02789) (xy 149.747476 -385.013058) (xy 149.794863 -385.005546) (xy 149.818852 -385.005072)
			(xy 149.842787 -385.005537) (xy 149.890071 -385.012995) (xy 149.935614 -385.027737) (xy 149.978301 -385.049401)
			(xy 150.017087 -385.077457) (xy 150.051022 -385.111218) (xy 150.079277 -385.149859) (xy 150.090632 -385.170934)
			(xy 150.09114 -385.17195) (xy 150.171446 -385.310888) (xy 150.71344 -385.310888) (xy 150.71344 -385.31038)
			(xy 150.713843 -385.286399) (xy 150.721346 -385.239026) (xy 150.736164 -385.193409) (xy 150.757932 -385.15067)
			(xy 150.786115 -385.111861) (xy 150.820019 -385.077936) (xy 150.858812 -385.049729) (xy 150.901537 -385.027935)
			(xy 150.947145 -385.013089) (xy 150.994513 -385.005558) (xy 151.018494 -385.005072) (xy 151.019002 -385.005072)
			(xy 151.042935 -385.005578) (xy 151.090218 -385.013028) (xy 151.13576 -385.027763) (xy 151.178447 -385.04942)
			(xy 151.217233 -385.077469) (xy 151.25117 -385.111225) (xy 151.279426 -385.149861) (xy 151.290782 -385.170934)
			(xy 151.29129 -385.17195) (xy 151.371596 -385.310888) (xy 151.913336 -385.310888) (xy 151.913336 -385.31038)
			(xy 151.913743 -385.286399) (xy 151.921246 -385.239027) (xy 151.936063 -385.19341) (xy 151.957831 -385.150672)
			(xy 151.986013 -385.111862) (xy 152.019918 -385.077937) (xy 152.058709 -385.04973) (xy 152.101434 -385.027936)
			(xy 152.147041 -385.01309) (xy 152.194409 -385.005558) (xy 152.21839 -385.005072) (xy 152.218898 -385.005072)
			(xy 152.242834 -385.0055) (xy 152.290121 -385.012965) (xy 152.335664 -385.027713) (xy 152.378351 -385.049383)
			(xy 152.417136 -385.077445) (xy 152.45107 -385.111212) (xy 152.479324 -385.149857) (xy 152.490678 -385.170934)
			(xy 152.491186 -385.17195) (xy 152.571492 -385.310888) (xy 153.11374 -385.310888) (xy 153.11374 -385.31038)
			(xy 153.11412 -385.286384) (xy 153.121631 -385.238983) (xy 153.136465 -385.193341) (xy 153.158257 -385.150582)
			(xy 153.18647 -385.111758) (xy 153.22041 -385.077826) (xy 153.25924 -385.049622) (xy 153.302004 -385.027839)
			(xy 153.347649 -385.013015) (xy 153.395052 -385.005515) (xy 153.419048 -385.005072) (xy 153.442983 -385.005541)
			(xy 153.490267 -385.012998) (xy 153.53581 -385.027739) (xy 153.578497 -385.049402) (xy 153.617282 -385.077458)
			(xy 153.651218 -385.111219) (xy 153.679473 -385.149859) (xy 153.690828 -385.170934) (xy 153.691336 -385.17195)
			(xy 153.771642 -385.310888) (xy 154.313636 -385.310888) (xy 154.313636 -385.31038) (xy 154.31402 -385.286384)
			(xy 154.321531 -385.238984) (xy 154.336365 -385.193342) (xy 154.358157 -385.150583) (xy 154.386369 -385.111759)
			(xy 154.420308 -385.077828) (xy 154.459138 -385.049623) (xy 154.501901 -385.02784) (xy 154.547546 -385.013016)
			(xy 154.594948 -385.005515) (xy 154.618944 -385.005072) (xy 154.642878 -385.005544) (xy 154.690163 -385.013001)
			(xy 154.735706 -385.027741) (xy 154.778392 -385.049404) (xy 154.817178 -385.077459) (xy 154.851114 -385.111219)
			(xy 154.879369 -385.14986) (xy 154.890724 -385.170934) (xy 154.891232 -385.17195) (xy 154.971538 -385.310888)
			(xy 155.513532 -385.310888) (xy 155.513532 -385.31038) (xy 155.51392 -385.286384) (xy 155.521431 -385.238984)
			(xy 155.536265 -385.193343) (xy 155.558056 -385.150584) (xy 155.586268 -385.111761) (xy 155.620206 -385.077829)
			(xy 155.659035 -385.049624) (xy 155.701798 -385.027842) (xy 155.747443 -385.013017) (xy 155.794844 -385.005515)
			(xy 155.81884 -385.005072) (xy 155.842774 -385.005547) (xy 155.890059 -385.013003) (xy 155.935601 -385.027743)
			(xy 155.978288 -385.049405) (xy 156.017074 -385.07746) (xy 156.05101 -385.11122) (xy 156.079265 -385.14986)
			(xy 156.09062 -385.170934) (xy 156.091128 -385.17195) (xy 156.171434 -385.310888) (xy 156.713428 -385.310888)
			(xy 156.713428 -385.31038) (xy 156.713843 -385.286399) (xy 156.721346 -385.239028) (xy 156.736162 -385.193412)
			(xy 156.757929 -385.150674) (xy 156.786111 -385.111865) (xy 156.820014 -385.07794) (xy 156.858805 -385.049733)
			(xy 156.901529 -385.027938) (xy 156.947135 -385.013092) (xy 156.994501 -385.005559) (xy 157.018482 -385.005072)
			(xy 157.01899 -385.005072) (xy 157.042926 -385.005506) (xy 157.090212 -385.01297) (xy 157.135756 -385.027717)
			(xy 157.178442 -385.049386) (xy 157.217227 -385.077447) (xy 157.251162 -385.111213) (xy 157.279416 -385.149857)
			(xy 157.29077 -385.170934) (xy 157.291278 -385.17195) (xy 157.371584 -385.310888) (xy 157.913324 -385.310888)
			(xy 157.913324 -385.31038) (xy 157.913743 -385.286399) (xy 157.921245 -385.239028) (xy 157.936062 -385.193413)
			(xy 157.957829 -385.150675) (xy 157.98601 -385.111866) (xy 158.019913 -385.077941) (xy 158.058703 -385.049734)
			(xy 158.101426 -385.02794) (xy 158.147032 -385.013093) (xy 158.194398 -385.005559) (xy 158.218378 -385.005072)
			(xy 158.218886 -385.005072) (xy 158.242822 -385.00551) (xy 158.290108 -385.012973) (xy 158.335651 -385.027719)
			(xy 158.378338 -385.049388) (xy 158.417123 -385.077448) (xy 158.451058 -385.111213) (xy 158.479312 -385.149858)
			(xy 158.490666 -385.170934) (xy 158.491174 -385.17195) (xy 158.57148 -385.310888) (xy 159.113728 -385.310888)
			(xy 159.113728 -385.31038) (xy 159.11412 -385.286385) (xy 159.121631 -385.238985) (xy 159.136464 -385.193344)
			(xy 159.158255 -385.150585) (xy 159.186467 -385.111762) (xy 159.220405 -385.07783) (xy 159.259233 -385.049626)
			(xy 159.301996 -385.027843) (xy 159.347639 -385.013018) (xy 159.39504 -385.005515) (xy 159.419036 -385.005072)
			(xy 159.44297 -385.00555) (xy 159.490254 -385.013006) (xy 159.535797 -385.027745) (xy 159.578484 -385.049407)
			(xy 159.617269 -385.077461) (xy 159.651205 -385.11122) (xy 159.679461 -385.14986) (xy 159.690816 -385.170934)
			(xy 159.691324 -385.17195) (xy 159.77163 -385.310888) (xy 160.313624 -385.310888) (xy 160.313624 -385.31038)
			(xy 160.31402 -385.286385) (xy 160.321531 -385.238985) (xy 160.336364 -385.193345) (xy 160.358154 -385.150586)
			(xy 160.386366 -385.111764) (xy 160.420303 -385.077832) (xy 160.459131 -385.049627) (xy 160.501893 -385.027844)
			(xy 160.547536 -385.013018) (xy 160.594937 -385.005516) (xy 160.618932 -385.005072) (xy 160.642866 -385.005554)
			(xy 160.69015 -385.013009) (xy 160.735693 -385.027747) (xy 160.778379 -385.049408) (xy 160.817165 -385.077462)
			(xy 160.851101 -385.111221) (xy 160.879357 -385.14986) (xy 160.890712 -385.170934) (xy 160.89122 -385.17195)
			(xy 160.971526 -385.310888) (xy 161.51352 -385.310888) (xy 161.51352 -385.31038) (xy 161.51392 -385.286385)
			(xy 161.52143 -385.238986) (xy 161.536263 -385.193346) (xy 161.558054 -385.150588) (xy 161.586265 -385.111765)
			(xy 161.620201 -385.077833) (xy 161.659029 -385.049629) (xy 161.70179 -385.027845) (xy 161.747433 -385.013019)
			(xy 161.794833 -385.005516) (xy 161.818828 -385.005072) (xy 161.842762 -385.005557) (xy 161.890046 -385.013011)
			(xy 161.935588 -385.027749) (xy 161.978275 -385.04941) (xy 162.017061 -385.077463) (xy 162.050997 -385.111222)
			(xy 162.079253 -385.14986) (xy 162.090608 -385.170934) (xy 162.091116 -385.17195) (xy 162.171422 -385.310888)
			(xy 162.713416 -385.310888) (xy 162.713416 -385.31038) (xy 162.713843 -385.2864) (xy 162.721345 -385.239029)
			(xy 162.736161 -385.193415) (xy 162.757927 -385.150678) (xy 162.786108 -385.111869) (xy 162.820009 -385.077944)
			(xy 162.858798 -385.049737) (xy 162.90152 -385.027942) (xy 162.947125 -385.013094) (xy 162.99449 -385.00556)
			(xy 163.01847 -385.005072) (xy 163.018978 -385.005072) (xy 163.042913 -385.005516) (xy 163.090199 -385.012978)
			(xy 163.135743 -385.027723) (xy 163.178429 -385.049391) (xy 163.217215 -385.07745) (xy 163.251149 -385.111214)
			(xy 163.279404 -385.149858) (xy 163.290758 -385.170934) (xy 163.291266 -385.17195) (xy 163.371572 -385.310888)
			(xy 163.913312 -385.310888) (xy 163.913312 -385.31038) (xy 163.913743 -385.2864) (xy 163.921245 -385.23903)
			(xy 163.936061 -385.193416) (xy 163.957827 -385.150679) (xy 163.986006 -385.111871) (xy 164.019908 -385.077946)
			(xy 164.058696 -385.049739) (xy 164.101418 -385.027943) (xy 164.147022 -385.013095) (xy 164.194386 -385.00556)
			(xy 164.218366 -385.005072) (xy 164.218874 -385.005072) (xy 164.242809 -385.005519) (xy 164.290095 -385.012981)
			(xy 164.335638 -385.027726) (xy 164.378325 -385.049392) (xy 164.41711 -385.077451) (xy 164.451045 -385.111215)
			(xy 164.479299 -385.149858) (xy 164.490654 -385.170934) (xy 164.491162 -385.17195) (xy 164.571468 -385.310888)
			(xy 165.113716 -385.310888) (xy 165.113716 -385.31038) (xy 165.11412 -385.286385) (xy 165.12163 -385.238987)
			(xy 165.136463 -385.193347) (xy 165.158253 -385.150589) (xy 165.186463 -385.111766) (xy 165.2204 -385.077835)
			(xy 165.259226 -385.04963) (xy 165.301987 -385.027846) (xy 165.347629 -385.01302) (xy 165.395029 -385.005516)
			(xy 165.419024 -385.005072) (xy 165.442958 -385.00556) (xy 165.490242 -385.013014) (xy 165.535784 -385.027751)
			(xy 165.578471 -385.049411) (xy 165.617257 -385.077464) (xy 165.651193 -385.111222) (xy 165.679449 -385.14986)
			(xy 165.690804 -385.170934) (xy 165.691312 -385.17195) (xy 166.083742 -385.850892) (xy 166.096567 -385.874224)
			(xy 166.114787 -385.924247) (xy 166.124047 -385.976673) (xy 166.124636 -386.003292) (xy 166.124131 -386.027269)
			(xy 166.116635 -386.074633) (xy 166.101826 -386.120243) (xy 166.080068 -386.162977) (xy 166.051896 -386.201783)
			(xy 166.018004 -386.235708) (xy 165.979224 -386.263916) (xy 165.936511 -386.285715) (xy 165.890916 -386.300567)
			(xy 165.843558 -386.308108) (xy 165.819582 -386.3086) (xy 165.819074 -386.3086) (xy 165.795499 -386.308227)
			(xy 165.74891 -386.300982) (xy 165.703991 -386.286652) (xy 165.661813 -386.26558) (xy 165.62338 -386.238267)
			(xy 165.589609 -386.205365) (xy 165.561304 -386.167657) (xy 165.549834 -386.147056) (xy 165.549326 -386.146294)
			(xy 165.151562 -385.457954) (xy 165.139704 -385.435268) (xy 165.122846 -385.38694) (xy 165.114266 -385.33648)
			(xy 165.113716 -385.310888) (xy 164.571468 -385.310888) (xy 164.883592 -385.850892) (xy 164.896324 -385.87421)
			(xy 164.914419 -385.924158) (xy 164.923635 -385.976477) (xy 164.924232 -386.003038) (xy 164.924232 -386.003292)
			(xy 164.92373 -386.027282) (xy 164.916226 -386.074671) (xy 164.901401 -386.120303) (xy 164.879621 -386.163054)
			(xy 164.851421 -386.201871) (xy 164.817496 -386.2358) (xy 164.778681 -386.264004) (xy 164.735932 -386.285789)
			(xy 164.690302 -386.300618) (xy 164.642914 -386.308128) (xy 164.618924 -386.3086) (xy 164.595351 -386.308187)
			(xy 164.548763 -386.300949) (xy 164.503845 -386.286627) (xy 164.461667 -386.265561) (xy 164.423233 -386.238255)
			(xy 164.389461 -386.205358) (xy 164.361155 -386.167655) (xy 164.349684 -386.147056) (xy 164.349176 -386.146294)
			(xy 163.951412 -385.457954) (xy 163.939479 -385.435295) (xy 163.922547 -385.386965) (xy 163.913895 -385.336491)
			(xy 163.913312 -385.310888) (xy 163.371572 -385.310888) (xy 163.683696 -385.850892) (xy 163.696428 -385.87421)
			(xy 163.714523 -385.924158) (xy 163.723739 -385.976477) (xy 163.724336 -386.003038) (xy 163.724336 -386.003292)
			(xy 163.72383 -386.027282) (xy 163.716326 -386.07467) (xy 163.701501 -386.120302) (xy 163.679721 -386.163053)
			(xy 163.651522 -386.20187) (xy 163.617597 -386.235798) (xy 163.578783 -386.264002) (xy 163.536035 -386.285788)
			(xy 163.490405 -386.300618) (xy 163.443018 -386.308127) (xy 163.419028 -386.3086) (xy 163.395455 -386.308184)
			(xy 163.348868 -386.300946) (xy 163.30395 -386.286625) (xy 163.261771 -386.26556) (xy 163.223338 -386.238254)
			(xy 163.189565 -386.205357) (xy 163.161259 -386.167654) (xy 163.149788 -386.147056) (xy 163.14928 -386.146294)
			(xy 162.751516 -385.457954) (xy 162.739583 -385.435294) (xy 162.722652 -385.386965) (xy 162.713999 -385.336491)
			(xy 162.713416 -385.310888) (xy 162.171422 -385.310888) (xy 162.483546 -385.850892) (xy 162.496371 -385.874224)
			(xy 162.514591 -385.924247) (xy 162.523851 -385.976673) (xy 162.52444 -386.003292) (xy 162.523931 -386.027269)
			(xy 162.516435 -386.074633) (xy 162.501626 -386.120242) (xy 162.479869 -386.162976) (xy 162.451698 -386.201782)
			(xy 162.417806 -386.235706) (xy 162.379027 -386.263915) (xy 162.336314 -386.285714) (xy 162.290719 -386.300566)
			(xy 162.243362 -386.308108) (xy 162.219386 -386.3086) (xy 162.218878 -386.3086) (xy 162.195303 -386.308224)
			(xy 162.148714 -386.300979) (xy 162.103795 -386.28665) (xy 162.061617 -386.265579) (xy 162.023184 -386.238266)
			(xy 161.989413 -386.205364) (xy 161.961108 -386.167657) (xy 161.949638 -386.147056) (xy 161.94913 -386.146294)
			(xy 161.551366 -385.457954) (xy 161.539508 -385.435268) (xy 161.52265 -385.38694) (xy 161.51407 -385.33648)
			(xy 161.51352 -385.310888) (xy 160.971526 -385.310888) (xy 161.28365 -385.850892) (xy 161.296476 -385.874224)
			(xy 161.314695 -385.924247) (xy 161.323955 -385.976673) (xy 161.324544 -386.003292) (xy 161.324031 -386.027269)
			(xy 161.316535 -386.074632) (xy 161.301727 -386.120241) (xy 161.279969 -386.162974) (xy 161.251799 -386.20178)
			(xy 161.217907 -386.235705) (xy 161.179129 -386.263913) (xy 161.136417 -386.285712) (xy 161.090822 -386.300566)
			(xy 161.043466 -386.308108) (xy 161.01949 -386.3086) (xy 161.018982 -386.3086) (xy 160.995407 -386.308221)
			(xy 160.948819 -386.300977) (xy 160.9039 -386.286648) (xy 160.861721 -386.265577) (xy 160.823288 -386.238265)
			(xy 160.789517 -386.205364) (xy 160.761212 -386.167657) (xy 160.749742 -386.147056) (xy 160.749234 -386.146294)
			(xy 160.35147 -385.457954) (xy 160.339612 -385.435268) (xy 160.322755 -385.386939) (xy 160.314174 -385.33648)
			(xy 160.313624 -385.310888) (xy 159.77163 -385.310888) (xy 160.083754 -385.850892) (xy 160.09658 -385.874224)
			(xy 160.114799 -385.924247) (xy 160.124059 -385.976673) (xy 160.124648 -386.003292) (xy 160.124131 -386.027268)
			(xy 160.116636 -386.074632) (xy 160.101827 -386.12024) (xy 160.08007 -386.162973) (xy 160.0519 -386.201779)
			(xy 160.018009 -386.235703) (xy 159.979231 -386.263912) (xy 159.93652 -386.285711) (xy 159.890926 -386.300565)
			(xy 159.84357 -386.308107) (xy 159.819594 -386.3086) (xy 159.819086 -386.3086) (xy 159.795512 -386.308217)
			(xy 159.748923 -386.300974) (xy 159.704004 -386.286646) (xy 159.661826 -386.265576) (xy 159.623393 -386.238264)
			(xy 159.589621 -386.205363) (xy 159.561316 -386.167656) (xy 159.549846 -386.147056) (xy 159.549338 -386.146294)
			(xy 159.151574 -385.457954) (xy 159.139717 -385.435268) (xy 159.122859 -385.386939) (xy 159.114278 -385.336479)
			(xy 159.113728 -385.310888) (xy 158.57148 -385.310888) (xy 158.883604 -385.850892) (xy 158.896337 -385.87421)
			(xy 158.914431 -385.924158) (xy 158.923647 -385.976477) (xy 158.924244 -386.003038) (xy 158.924244 -386.003292)
			(xy 158.92373 -386.027281) (xy 158.916226 -386.074669) (xy 158.901402 -386.1203) (xy 158.879623 -386.16305)
			(xy 158.851424 -386.201867) (xy 158.817501 -386.235796) (xy 158.778688 -386.264) (xy 158.735941 -386.285785)
			(xy 158.690312 -386.300616) (xy 158.642925 -386.308127) (xy 158.618936 -386.3086) (xy 158.595363 -386.308177)
			(xy 158.548776 -386.300941) (xy 158.503858 -386.286621) (xy 158.46168 -386.265557) (xy 158.423246 -386.238252)
			(xy 158.389474 -386.205356) (xy 158.361167 -386.167654) (xy 158.349696 -386.147056) (xy 158.349188 -386.146294)
			(xy 157.951424 -385.457954) (xy 157.939492 -385.435294) (xy 157.92256 -385.386965) (xy 157.913907 -385.336491)
			(xy 157.913324 -385.310888) (xy 157.371584 -385.310888) (xy 157.683708 -385.850892) (xy 157.696441 -385.87421)
			(xy 157.714535 -385.924158) (xy 157.723751 -385.976477) (xy 157.724348 -386.003038) (xy 157.724348 -386.003292)
			(xy 157.72383 -386.027281) (xy 157.716326 -386.074669) (xy 157.701503 -386.120299) (xy 157.679724 -386.163049)
			(xy 157.651525 -386.201866) (xy 157.617603 -386.235794) (xy 157.57879 -386.263998) (xy 157.536043 -386.285784)
			(xy 157.490415 -386.300615) (xy 157.443029 -386.308126) (xy 157.41904 -386.3086) (xy 157.395467 -386.308174)
			(xy 157.34888 -386.300939) (xy 157.303963 -386.286618) (xy 157.261784 -386.265555) (xy 157.223351 -386.238251)
			(xy 157.189578 -386.205355) (xy 157.161271 -386.167654) (xy 157.1498 -386.147056) (xy 157.149292 -386.146294)
			(xy 156.751528 -385.457954) (xy 156.739596 -385.435294) (xy 156.722664 -385.386965) (xy 156.714011 -385.336491)
			(xy 156.713428 -385.310888) (xy 156.171434 -385.310888) (xy 156.483558 -385.850892) (xy 156.496384 -385.874224)
			(xy 156.514604 -385.924247) (xy 156.523863 -385.976673) (xy 156.524452 -386.003292) (xy 156.523931 -386.027268)
			(xy 156.516436 -386.074631) (xy 156.501627 -386.120239) (xy 156.479871 -386.162972) (xy 156.451701 -386.201778)
			(xy 156.417811 -386.235702) (xy 156.379033 -386.263911) (xy 156.336323 -386.28571) (xy 156.290729 -386.300564)
			(xy 156.243374 -386.308107) (xy 156.219398 -386.3086) (xy 156.21889 -386.3086) (xy 156.195316 -386.308214)
			(xy 156.148727 -386.300971) (xy 156.103808 -386.286644) (xy 156.06163 -386.265574) (xy 156.023197 -386.238263)
			(xy 155.989426 -386.205363) (xy 155.96112 -386.167656) (xy 155.94965 -386.147056) (xy 155.949142 -386.146294)
			(xy 155.551378 -385.457954) (xy 155.539521 -385.435268) (xy 155.522663 -385.386939) (xy 155.514082 -385.336479)
			(xy 155.513532 -385.310888) (xy 154.971538 -385.310888) (xy 155.283662 -385.850892) (xy 155.296489 -385.874224)
			(xy 155.314708 -385.924247) (xy 155.323967 -385.976673) (xy 155.324556 -386.003292) (xy 155.324031 -386.027268)
			(xy 155.316536 -386.07463) (xy 155.301728 -386.120239) (xy 155.279972 -386.162971) (xy 155.251802 -386.201776)
			(xy 155.217912 -386.235701) (xy 155.179135 -386.263909) (xy 155.136425 -386.285709) (xy 155.090832 -386.300563)
			(xy 155.043477 -386.308107) (xy 155.019502 -386.3086) (xy 155.018994 -386.3086) (xy 154.99542 -386.308211)
			(xy 154.948831 -386.300969) (xy 154.903913 -386.286642) (xy 154.861734 -386.265573) (xy 154.823301 -386.238262)
			(xy 154.78953 -386.205362) (xy 154.761224 -386.167656) (xy 154.749754 -386.147056) (xy 154.749246 -386.146294)
			(xy 154.351482 -385.457954) (xy 154.339625 -385.435268) (xy 154.322767 -385.386939) (xy 154.314186 -385.336479)
			(xy 154.313636 -385.310888) (xy 153.771642 -385.310888) (xy 154.083766 -385.850892) (xy 154.096593 -385.874223)
			(xy 154.114812 -385.924247) (xy 154.124071 -385.976673) (xy 154.12466 -386.003292) (xy 154.124231 -386.027273)
			(xy 154.116732 -386.074644) (xy 154.101919 -386.120261) (xy 154.080154 -386.162999) (xy 154.051974 -386.201809)
			(xy 154.018072 -386.235735) (xy 153.979282 -386.263942) (xy 153.936559 -386.285737) (xy 153.890953 -386.300582)
			(xy 153.843586 -386.308114) (xy 153.819606 -386.3086) (xy 153.819098 -386.3086) (xy 153.795524 -386.308208)
			(xy 153.748936 -386.300966) (xy 153.704017 -386.28664) (xy 153.661839 -386.265571) (xy 153.623406 -386.238261)
			(xy 153.589634 -386.205361) (xy 153.561328 -386.167656) (xy 153.549858 -386.147056) (xy 153.54935 -386.146294)
			(xy 153.151586 -385.457954) (xy 153.13973 -385.435267) (xy 153.122871 -385.386939) (xy 153.11429 -385.336479)
			(xy 153.11374 -385.310888) (xy 152.571492 -385.310888) (xy 152.883616 -385.850892) (xy 152.89635 -385.874209)
			(xy 152.914443 -385.924158) (xy 152.923659 -385.976477) (xy 152.924256 -386.003038) (xy 152.924256 -386.003292)
			(xy 152.92373 -386.027281) (xy 152.916227 -386.074667) (xy 152.901403 -386.120297) (xy 152.879625 -386.163047)
			(xy 152.851428 -386.201863) (xy 152.817506 -386.235791) (xy 152.778694 -386.263996) (xy 152.735949 -386.285782)
			(xy 152.690322 -386.300614) (xy 152.642937 -386.308126) (xy 152.618948 -386.3086) (xy 152.595375 -386.308168)
			(xy 152.548789 -386.300933) (xy 152.503871 -386.286614) (xy 152.461693 -386.265552) (xy 152.423259 -386.238248)
			(xy 152.389486 -386.205354) (xy 152.361179 -386.167654) (xy 152.349708 -386.147056) (xy 152.3492 -386.146294)
			(xy 151.951436 -385.457954) (xy 151.939505 -385.435294) (xy 151.922572 -385.386964) (xy 151.913919 -385.336491)
			(xy 151.913336 -385.310888) (xy 151.371596 -385.310888) (xy 151.68372 -385.850892) (xy 151.696454 -385.874209)
			(xy 151.714548 -385.924158) (xy 151.723763 -385.976476) (xy 151.72436 -386.003038) (xy 151.72436 -386.003292)
			(xy 151.723954 -386.027287) (xy 151.716447 -386.074687) (xy 151.701617 -386.120329) (xy 151.679828 -386.163088)
			(xy 151.651618 -386.201912) (xy 151.617682 -386.235844) (xy 151.578854 -386.264049) (xy 151.536092 -386.285832)
			(xy 151.490448 -386.300657) (xy 151.443047 -386.308157) (xy 151.419052 -386.3086) (xy 151.395479 -386.308164)
			(xy 151.348893 -386.300931) (xy 151.303976 -386.286612) (xy 151.261797 -386.265551) (xy 151.223364 -386.238247)
			(xy 151.189591 -386.205354) (xy 151.161283 -386.167653) (xy 151.149812 -386.147056) (xy 151.149304 -386.146294)
			(xy 150.75154 -385.457954) (xy 150.739609 -385.435293) (xy 150.722676 -385.386964) (xy 150.714023 -385.336491)
			(xy 150.71344 -385.310888) (xy 150.171446 -385.310888) (xy 150.48357 -385.850892) (xy 150.496397 -385.874223)
			(xy 150.514616 -385.924247) (xy 150.523875 -385.976673) (xy 150.524464 -386.003292) (xy 150.524031 -386.027273)
			(xy 150.516533 -386.074644) (xy 150.501719 -386.12026) (xy 150.479955 -386.162998) (xy 150.451775 -386.201808)
			(xy 150.417874 -386.235733) (xy 150.379084 -386.263941) (xy 150.336361 -386.285735) (xy 150.290756 -386.300581)
			(xy 150.24339 -386.308114) (xy 150.21941 -386.3086) (xy 150.218902 -386.3086) (xy 150.195328 -386.308205)
			(xy 150.14874 -386.300963) (xy 150.103821 -386.286638) (xy 150.061643 -386.26557) (xy 150.02321 -386.23826)
			(xy 149.989438 -386.205361) (xy 149.961133 -386.167656) (xy 149.949662 -386.147056) (xy 149.949154 -386.146294)
			(xy 149.55139 -385.457954) (xy 149.539534 -385.435267) (xy 149.522675 -385.386939) (xy 149.514094 -385.336479)
			(xy 149.513544 -385.310888) (xy 148.97155 -385.310888) (xy 149.283674 -385.850892) (xy 149.296501 -385.874223)
			(xy 149.31472 -385.924247) (xy 149.323979 -385.976673) (xy 149.324568 -386.003292) (xy 149.324131 -386.027272)
			(xy 149.316633 -386.074643) (xy 149.301819 -386.120259) (xy 149.280055 -386.162997) (xy 149.251876 -386.201806)
			(xy 149.217975 -386.235732) (xy 149.179187 -386.263939) (xy 149.136464 -386.285734) (xy 149.090859 -386.300581)
			(xy 149.043494 -386.308113) (xy 149.019514 -386.3086) (xy 149.019006 -386.3086) (xy 148.995432 -386.308201)
			(xy 148.948844 -386.300961) (xy 148.903926 -386.286636) (xy 148.861747 -386.265568) (xy 148.823314 -386.238259)
			(xy 148.789542 -386.20536) (xy 148.761237 -386.167655) (xy 148.749766 -386.147056) (xy 148.749258 -386.146294)
			(xy 148.351494 -385.457954) (xy 148.339638 -385.435267) (xy 148.322779 -385.386939) (xy 148.314198 -385.336479)
			(xy 148.313648 -385.310888) (xy 147.771654 -385.310888) (xy 148.083778 -385.850892) (xy 148.096606 -385.874223)
			(xy 148.114824 -385.924247) (xy 148.124083 -385.976673) (xy 148.124672 -386.003292) (xy 148.124231 -386.027272)
			(xy 148.116733 -386.074643) (xy 148.10192 -386.120258) (xy 148.080156 -386.162996) (xy 148.051978 -386.201805)
			(xy 148.018077 -386.235731) (xy 147.979289 -386.263938) (xy 147.936567 -386.285733) (xy 147.890963 -386.30058)
			(xy 147.843598 -386.308113) (xy 147.819618 -386.3086) (xy 147.81911 -386.3086) (xy 147.795536 -386.308198)
			(xy 147.748948 -386.300958) (xy 147.70403 -386.286634) (xy 147.661852 -386.265566) (xy 147.623418 -386.238258)
			(xy 147.589647 -386.20536) (xy 147.561341 -386.167655) (xy 147.54987 -386.147056) (xy 147.549362 -386.146294)
			(xy 147.151598 -385.457954) (xy 147.139742 -385.435267) (xy 147.122883 -385.386939) (xy 147.114302 -385.336479)
			(xy 147.113752 -385.310888) (xy 133.24387 -385.310888) (xy 133.555994 -385.850892) (xy 133.568823 -385.874222)
			(xy 133.587041 -385.924246) (xy 133.596299 -385.976673) (xy 133.596888 -386.003292) (xy 133.596431 -386.027271)
			(xy 133.588933 -386.07464) (xy 133.574121 -386.120254) (xy 133.552359 -386.162991) (xy 133.524182 -386.2018)
			(xy 133.490284 -386.235725) (xy 133.451498 -386.263932) (xy 133.408778 -386.285728) (xy 133.363176 -386.300577)
			(xy 133.315813 -386.308112) (xy 133.291834 -386.3086) (xy 133.291326 -386.3086) (xy 133.267753 -386.308185)
			(xy 133.221165 -386.300948) (xy 133.176247 -386.286626) (xy 133.134069 -386.26556) (xy 133.095636 -386.238254)
			(xy 133.061863 -386.205357) (xy 133.033557 -386.167655) (xy 133.022086 -386.147056) (xy 133.021578 -386.146294)
			(xy 132.623814 -385.457954) (xy 132.611952 -385.43527) (xy 132.595097 -385.38694) (xy 132.586517 -385.33648)
			(xy 132.585968 -385.310888) (xy 132.04372 -385.310888) (xy 132.355844 -385.850892) (xy 132.36858 -385.874208)
			(xy 132.386672 -385.924157) (xy 132.395888 -385.976476) (xy 132.396484 -386.003038) (xy 132.396484 -386.003292)
			(xy 132.396054 -386.027286) (xy 132.388548 -386.074684) (xy 132.373719 -386.120323) (xy 132.351933 -386.163081)
			(xy 132.323725 -386.201904) (xy 132.289792 -386.235836) (xy 132.250967 -386.264041) (xy 132.208208 -386.285825)
			(xy 132.162568 -386.300652) (xy 132.11517 -386.308156) (xy 132.091176 -386.3086) (xy 132.067601 -386.308226)
			(xy 132.021012 -386.30098) (xy 131.976093 -386.286651) (xy 131.933915 -386.265579) (xy 131.895482 -386.238267)
			(xy 131.861711 -386.205365) (xy 131.833406 -386.167657) (xy 131.821936 -386.147056) (xy 131.821428 -386.146294)
			(xy 131.423664 -385.457954) (xy 131.411735 -385.435292) (xy 131.394801 -385.386964) (xy 131.386148 -385.336491)
			(xy 131.385564 -385.310888) (xy 130.843824 -385.310888) (xy 131.155948 -385.850892) (xy 131.168685 -385.874208)
			(xy 131.186776 -385.924157) (xy 131.195992 -385.976476) (xy 131.196588 -386.003038) (xy 131.196588 -386.003292)
			(xy 131.196154 -386.027286) (xy 131.188648 -386.074683) (xy 131.17382 -386.120322) (xy 131.152033 -386.16308)
			(xy 131.123826 -386.201902) (xy 131.089893 -386.235834) (xy 131.05107 -386.26404) (xy 131.008311 -386.285824)
			(xy 130.962671 -386.300651) (xy 130.915274 -386.308155) (xy 130.89128 -386.3086) (xy 130.867705 -386.308222)
			(xy 130.821116 -386.300978) (xy 130.776197 -386.286649) (xy 130.734019 -386.265578) (xy 130.695586 -386.238266)
			(xy 130.661815 -386.205364) (xy 130.63351 -386.167657) (xy 130.62204 -386.147056) (xy 130.621532 -386.146294)
			(xy 130.223768 -385.457954) (xy 130.211839 -385.435292) (xy 130.194906 -385.386964) (xy 130.186252 -385.336491)
			(xy 130.185668 -385.310888) (xy 129.643674 -385.310888) (xy 129.955798 -385.850892) (xy 129.968619 -385.874226)
			(xy 129.986842 -385.924248) (xy 129.996103 -385.976674) (xy 129.996692 -386.003292) (xy 129.996231 -386.027271)
			(xy 129.988734 -386.07464) (xy 129.973922 -386.120253) (xy 129.95216 -386.16299) (xy 129.923983 -386.201798)
			(xy 129.890086 -386.235723) (xy 129.8513 -386.263931) (xy 129.808581 -386.285727) (xy 129.762979 -386.300576)
			(xy 129.715617 -386.308112) (xy 129.691638 -386.3086) (xy 129.69113 -386.3086) (xy 129.667557 -386.308182)
			(xy 129.62097 -386.300945) (xy 129.576052 -386.286624) (xy 129.533873 -386.265559) (xy 129.49544 -386.238253)
			(xy 129.461668 -386.205357) (xy 129.433361 -386.167654) (xy 129.42189 -386.147056) (xy 129.421382 -386.146294)
			(xy 129.023618 -385.457954) (xy 129.011756 -385.43527) (xy 128.994901 -385.38694) (xy 128.986321 -385.33648)
			(xy 128.985772 -385.310888) (xy 128.443778 -385.310888) (xy 128.755902 -385.850892) (xy 128.768724 -385.874226)
			(xy 128.786946 -385.924248) (xy 128.796207 -385.976674) (xy 128.796796 -386.003292) (xy 128.796331 -386.027271)
			(xy 128.788834 -386.074639) (xy 128.774022 -386.120252) (xy 128.752261 -386.162989) (xy 128.724085 -386.201797)
			(xy 128.690187 -386.235722) (xy 128.651402 -386.26393) (xy 128.608684 -386.285726) (xy 128.563083 -386.300575)
			(xy 128.515721 -386.308111) (xy 128.491742 -386.3086) (xy 128.491234 -386.3086) (xy 128.467661 -386.308179)
			(xy 128.421074 -386.300942) (xy 128.376156 -386.286622) (xy 128.333978 -386.265557) (xy 128.295544 -386.238252)
			(xy 128.261772 -386.205356) (xy 128.233465 -386.167654) (xy 128.221994 -386.147056) (xy 128.221486 -386.146294)
			(xy 127.823722 -385.457954) (xy 127.811861 -385.43527) (xy 127.795005 -385.38694) (xy 127.786426 -385.33648)
			(xy 127.785876 -385.310888) (xy 127.243882 -385.310888) (xy 127.556006 -385.850892) (xy 127.568828 -385.874226)
			(xy 127.58705 -385.924248) (xy 127.596311 -385.976674) (xy 127.5969 -386.003292) (xy 127.596431 -386.027271)
			(xy 127.588934 -386.074639) (xy 127.574122 -386.120251) (xy 127.552361 -386.162988) (xy 127.524186 -386.201795)
			(xy 127.490289 -386.235721) (xy 127.451504 -386.263928) (xy 127.408786 -386.285725) (xy 127.363186 -386.300574)
			(xy 127.315824 -386.308111) (xy 127.291846 -386.3086) (xy 127.291338 -386.3086) (xy 127.267765 -386.308176)
			(xy 127.221178 -386.30094) (xy 127.17626 -386.28662) (xy 127.134082 -386.265556) (xy 127.095648 -386.238251)
			(xy 127.061876 -386.205356) (xy 127.033569 -386.167654) (xy 127.022098 -386.147056) (xy 127.02159 -386.146294)
			(xy 126.623826 -385.457954) (xy 126.611965 -385.43527) (xy 126.595109 -385.38694) (xy 126.58653 -385.33648)
			(xy 126.58598 -385.310888) (xy 126.043732 -385.310888) (xy 126.355856 -385.850892) (xy 126.368593 -385.874208)
			(xy 126.386685 -385.924157) (xy 126.3959 -385.976476) (xy 126.396496 -386.003038) (xy 126.396496 -386.003292)
			(xy 126.396054 -386.027286) (xy 126.388548 -386.074682) (xy 126.37372 -386.12032) (xy 126.351935 -386.163077)
			(xy 126.323729 -386.2019) (xy 126.289797 -386.235831) (xy 126.250974 -386.264037) (xy 126.208217 -386.285822)
			(xy 126.162578 -386.300649) (xy 126.115182 -386.308155) (xy 126.091188 -386.3086) (xy 126.067614 -386.308216)
			(xy 126.021025 -386.300973) (xy 125.976106 -386.286645) (xy 125.933928 -386.265575) (xy 125.895495 -386.238264)
			(xy 125.861723 -386.205363) (xy 125.833418 -386.167656) (xy 125.821948 -386.147056) (xy 125.82144 -386.146294)
			(xy 125.423676 -385.457954) (xy 125.41174 -385.435296) (xy 125.39481 -385.386965) (xy 125.386159 -385.336492)
			(xy 125.385576 -385.310888) (xy 124.843836 -385.310888) (xy 125.15596 -385.850892) (xy 125.168698 -385.874207)
			(xy 125.186789 -385.924157) (xy 125.196004 -385.976476) (xy 125.1966 -386.003038) (xy 125.1966 -386.003292)
			(xy 125.196154 -386.027285) (xy 125.188649 -386.074681) (xy 125.173821 -386.12032) (xy 125.152036 -386.163076)
			(xy 125.12383 -386.201898) (xy 125.089898 -386.23583) (xy 125.051076 -386.264036) (xy 125.00832 -386.285821)
			(xy 124.962681 -386.300649) (xy 124.915285 -386.308154) (xy 124.891292 -386.3086) (xy 124.867718 -386.308213)
			(xy 124.821129 -386.30097) (xy 124.77621 -386.286643) (xy 124.734032 -386.265573) (xy 124.695599 -386.238263)
			(xy 124.661828 -386.205362) (xy 124.633522 -386.167656) (xy 124.622052 -386.147056) (xy 124.621544 -386.146294)
			(xy 124.22378 -385.457954) (xy 124.211844 -385.435296) (xy 124.194915 -385.386965) (xy 124.186263 -385.336492)
			(xy 124.18568 -385.310888) (xy 123.643686 -385.310888) (xy 123.95581 -385.850892) (xy 123.968632 -385.874226)
			(xy 123.986854 -385.924248) (xy 123.996115 -385.976673) (xy 123.996704 -386.003292) (xy 123.996231 -386.027271)
			(xy 123.988734 -386.074638) (xy 123.973923 -386.120251) (xy 123.952162 -386.162986) (xy 123.923987 -386.201794)
			(xy 123.890091 -386.235719) (xy 123.851307 -386.263927) (xy 123.808589 -386.285724) (xy 123.762989 -386.300574)
			(xy 123.715628 -386.308111) (xy 123.69165 -386.3086) (xy 123.691142 -386.3086) (xy 123.667569 -386.308172)
			(xy 123.620983 -386.300937) (xy 123.576065 -386.286617) (xy 123.533886 -386.265554) (xy 123.495453 -386.23825)
			(xy 123.46168 -386.205355) (xy 123.433373 -386.167654) (xy 123.421902 -386.147056) (xy 123.421394 -386.146294)
			(xy 123.02363 -385.457954) (xy 123.011769 -385.43527) (xy 122.994913 -385.38694) (xy 122.986334 -385.33648)
			(xy 122.985784 -385.310888) (xy 122.44379 -385.310888) (xy 122.755914 -385.850892) (xy 122.768737 -385.874226)
			(xy 122.786958 -385.924248) (xy 122.796219 -385.976673) (xy 122.796808 -386.003292) (xy 122.796331 -386.02727)
			(xy 122.788834 -386.074637) (xy 122.774023 -386.12025) (xy 122.752263 -386.162985) (xy 122.724088 -386.201793)
			(xy 122.690192 -386.235718) (xy 122.651409 -386.263926) (xy 122.608692 -386.285723) (xy 122.563092 -386.300573)
			(xy 122.515732 -386.30811) (xy 122.491754 -386.3086) (xy 122.491246 -386.3086) (xy 122.467673 -386.308169)
			(xy 122.421087 -386.300935) (xy 122.376169 -386.286615) (xy 122.333991 -386.265553) (xy 122.295557 -386.238249)
			(xy 122.261784 -386.205355) (xy 122.233477 -386.167654) (xy 122.222006 -386.147056) (xy 122.221498 -386.146294)
			(xy 121.823734 -385.457954) (xy 121.811874 -385.43527) (xy 121.795018 -385.38694) (xy 121.786438 -385.33648)
			(xy 121.785888 -385.310888) (xy 121.243894 -385.310888) (xy 121.556018 -385.850892) (xy 121.568841 -385.874226)
			(xy 121.587062 -385.924248) (xy 121.596323 -385.976673) (xy 121.596912 -386.003292) (xy 121.596431 -386.02727)
			(xy 121.588934 -386.074637) (xy 121.574124 -386.120249) (xy 121.552364 -386.162984) (xy 121.524189 -386.201791)
			(xy 121.490294 -386.235716) (xy 121.451511 -386.263924) (xy 121.408795 -386.285722) (xy 121.363196 -386.300572)
			(xy 121.315836 -386.30811) (xy 121.291858 -386.3086) (xy 121.29135 -386.3086) (xy 121.267777 -386.308166)
			(xy 121.221191 -386.300932) (xy 121.176273 -386.286613) (xy 121.134095 -386.265551) (xy 121.095661 -386.238248)
			(xy 121.061888 -386.205354) (xy 121.033581 -386.167653) (xy 121.02211 -386.147056) (xy 121.021602 -386.146294)
			(xy 120.623838 -385.457954) (xy 120.611978 -385.435269) (xy 120.595122 -385.38694) (xy 120.586542 -385.33648)
			(xy 120.585992 -385.310888) (xy 120.043744 -385.310888) (xy 120.355868 -385.850892) (xy 120.368606 -385.874207)
			(xy 120.386697 -385.924157) (xy 120.395912 -385.976476) (xy 120.396508 -386.003038) (xy 120.396508 -386.003292)
			(xy 120.396054 -386.027285) (xy 120.388549 -386.07468) (xy 120.373721 -386.120318) (xy 120.351937 -386.163074)
			(xy 120.323732 -386.201896) (xy 120.289802 -386.235827) (xy 120.250981 -386.264033) (xy 120.208225 -386.285818)
			(xy 120.162588 -386.300647) (xy 120.115193 -386.308154) (xy 120.0912 -386.3086) (xy 120.067626 -386.308206)
			(xy 120.021038 -386.300965) (xy 119.976119 -386.286639) (xy 119.933941 -386.26557) (xy 119.895508 -386.238261)
			(xy 119.861736 -386.205361) (xy 119.83343 -386.167656) (xy 119.82196 -386.147056) (xy 119.821452 -386.146294)
			(xy 119.423688 -385.457954) (xy 119.411753 -385.435296) (xy 119.394823 -385.386965) (xy 119.386171 -385.336491)
			(xy 119.385588 -385.310888) (xy 118.843848 -385.310888) (xy 119.155972 -385.850892) (xy 119.168711 -385.874207)
			(xy 119.186801 -385.924157) (xy 119.196016 -385.976476) (xy 119.196612 -386.003038) (xy 119.196612 -386.003292)
			(xy 119.196154 -386.027285) (xy 119.188649 -386.07468) (xy 119.173822 -386.120317) (xy 119.152038 -386.163073)
			(xy 119.123834 -386.201894) (xy 119.089903 -386.235826) (xy 119.051083 -386.264032) (xy 119.008328 -386.285817)
			(xy 118.962691 -386.300646) (xy 118.915297 -386.308154) (xy 118.891304 -386.3086) (xy 118.86773 -386.308203)
			(xy 118.821142 -386.300962) (xy 118.776223 -386.286637) (xy 118.734045 -386.265569) (xy 118.695612 -386.23826)
			(xy 118.66184 -386.205361) (xy 118.633535 -386.167656) (xy 118.622064 -386.147056) (xy 118.621556 -386.146294)
			(xy 118.223792 -385.457954) (xy 118.211857 -385.435295) (xy 118.194927 -385.386965) (xy 118.186275 -385.336491)
			(xy 118.185692 -385.310888) (xy 117.643698 -385.310888) (xy 117.955822 -385.850892) (xy 117.968645 -385.874225)
			(xy 117.986866 -385.924248) (xy 117.996127 -385.976673) (xy 117.996716 -386.003292) (xy 117.996231 -386.02727)
			(xy 117.988734 -386.074636) (xy 117.973924 -386.120248) (xy 117.952164 -386.162983) (xy 117.92399 -386.20179)
			(xy 117.890096 -386.235715) (xy 117.851313 -386.263923) (xy 117.808598 -386.28572) (xy 117.762999 -386.300571)
			(xy 117.71564 -386.30811) (xy 117.691662 -386.3086) (xy 117.691154 -386.3086) (xy 117.667582 -386.308163)
			(xy 117.620995 -386.300929) (xy 117.576078 -386.286611) (xy 117.533899 -386.26555) (xy 117.495466 -386.238247)
			(xy 117.461693 -386.205353) (xy 117.433385 -386.167653) (xy 117.421914 -386.147056) (xy 117.421406 -386.146294)
			(xy 117.023642 -385.457954) (xy 117.011782 -385.435269) (xy 116.994926 -385.38694) (xy 116.986346 -385.33648)
			(xy 116.985796 -385.310888) (xy 116.443802 -385.310888) (xy 116.755926 -385.850892) (xy 116.76875 -385.874225)
			(xy 116.786971 -385.924247) (xy 116.796231 -385.976673) (xy 116.79682 -386.003292) (xy 116.796331 -386.02727)
			(xy 116.788835 -386.074636) (xy 116.774024 -386.120247) (xy 116.752265 -386.162982) (xy 116.724092 -386.201789)
			(xy 116.690197 -386.235713) (xy 116.651416 -386.263922) (xy 116.6087 -386.285719) (xy 116.563102 -386.30057)
			(xy 116.515743 -386.30811) (xy 116.491766 -386.3086) (xy 116.491258 -386.3086) (xy 116.467686 -386.308159)
			(xy 116.4211 -386.300927) (xy 116.376182 -386.286609) (xy 116.334004 -386.265548) (xy 116.29557 -386.238246)
			(xy 116.261797 -386.205353) (xy 116.23349 -386.167653) (xy 116.222018 -386.147056) (xy 116.22151 -386.146294)
			(xy 115.823746 -385.457954) (xy 115.811886 -385.435269) (xy 115.79503 -385.38694) (xy 115.78645 -385.33648)
			(xy 115.7859 -385.310888) (xy 115.243906 -385.310888) (xy 115.55603 -385.850892) (xy 115.568854 -385.874225)
			(xy 115.587075 -385.924247) (xy 115.596335 -385.976673) (xy 115.596924 -386.003292) (xy 115.596431 -386.02727)
			(xy 115.588935 -386.074635) (xy 115.574125 -386.120246) (xy 115.552366 -386.16298) (xy 115.524193 -386.201787)
			(xy 115.490299 -386.235712) (xy 115.451518 -386.26392) (xy 115.408803 -386.285718) (xy 115.363206 -386.30057)
			(xy 115.315847 -386.308109) (xy 115.29187 -386.3086) (xy 115.291362 -386.3086) (xy 115.26779 -386.308156)
			(xy 115.221204 -386.300924) (xy 115.176286 -386.286607) (xy 115.134108 -386.265547) (xy 115.095674 -386.238245)
			(xy 115.061901 -386.205352) (xy 115.033594 -386.167653) (xy 115.022122 -386.147056) (xy 115.021614 -386.146294)
			(xy 114.62385 -385.457954) (xy 114.611991 -385.435269) (xy 114.595134 -385.38694) (xy 114.586554 -385.33648)
			(xy 114.586004 -385.310888) (xy 98.671676 -385.310888) (xy 98.9838 -385.850892) (xy 98.996533 -385.87421)
			(xy 99.014627 -385.924158) (xy 99.023843 -385.976477) (xy 99.02444 -386.003038) (xy 99.02444 -386.003292)
			(xy 99.02393 -386.027281) (xy 99.016426 -386.07467) (xy 99.001602 -386.120301) (xy 98.979822 -386.163051)
			(xy 98.951623 -386.201869) (xy 98.917699 -386.235797) (xy 98.878886 -386.264001) (xy 98.836138 -386.285787)
			(xy 98.790509 -386.300617) (xy 98.743121 -386.308127) (xy 98.719132 -386.3086) (xy 98.695559 -386.30818)
			(xy 98.648972 -386.300944) (xy 98.604054 -386.286623) (xy 98.561875 -386.265558) (xy 98.523442 -386.238253)
			(xy 98.48967 -386.205357) (xy 98.461363 -386.167654) (xy 98.449892 -386.147056) (xy 98.449384 -386.146294)
			(xy 98.05162 -385.457954) (xy 98.039687 -385.435294) (xy 98.022756 -385.386965) (xy 98.014103 -385.336491)
			(xy 98.01352 -385.310888) (xy 97.471526 -385.310888) (xy 97.78365 -385.850892) (xy 97.796476 -385.874224)
			(xy 97.814695 -385.924247) (xy 97.823955 -385.976673) (xy 97.824544 -386.003292) (xy 97.824031 -386.027269)
			(xy 97.816535 -386.074632) (xy 97.801727 -386.120241) (xy 97.779969 -386.162974) (xy 97.751799 -386.20178)
			(xy 97.717907 -386.235705) (xy 97.679129 -386.263913) (xy 97.636417 -386.285712) (xy 97.590822 -386.300566)
			(xy 97.543466 -386.308108) (xy 97.51949 -386.3086) (xy 97.518982 -386.3086) (xy 97.495407 -386.308221)
			(xy 97.448819 -386.300977) (xy 97.4039 -386.286648) (xy 97.361721 -386.265577) (xy 97.323288 -386.238265)
			(xy 97.289517 -386.205364) (xy 97.261212 -386.167657) (xy 97.249742 -386.147056) (xy 97.249234 -386.146294)
			(xy 96.85147 -385.457954) (xy 96.839612 -385.435268) (xy 96.822755 -385.386939) (xy 96.814174 -385.33648)
			(xy 96.813624 -385.310888) (xy 96.27163 -385.310888) (xy 96.583754 -385.850892) (xy 96.59658 -385.874224)
			(xy 96.614799 -385.924247) (xy 96.624059 -385.976673) (xy 96.624648 -386.003292) (xy 96.624131 -386.027268)
			(xy 96.616636 -386.074632) (xy 96.601827 -386.12024) (xy 96.58007 -386.162973) (xy 96.5519 -386.201779)
			(xy 96.518009 -386.235703) (xy 96.479231 -386.263912) (xy 96.43652 -386.285711) (xy 96.390926 -386.300565)
			(xy 96.34357 -386.308107) (xy 96.319594 -386.3086) (xy 96.319086 -386.3086) (xy 96.295512 -386.308217)
			(xy 96.248923 -386.300974) (xy 96.204004 -386.286646) (xy 96.161826 -386.265576) (xy 96.123393 -386.238264)
			(xy 96.089621 -386.205363) (xy 96.061316 -386.167656) (xy 96.049846 -386.147056) (xy 96.049338 -386.146294)
			(xy 95.651574 -385.457954) (xy 95.639717 -385.435268) (xy 95.622859 -385.386939) (xy 95.614278 -385.336479)
			(xy 95.613728 -385.310888) (xy 95.07148 -385.310888) (xy 95.383604 -385.850892) (xy 95.396337 -385.87421)
			(xy 95.414431 -385.924158) (xy 95.423647 -385.976477) (xy 95.424244 -386.003038) (xy 95.424244 -386.003292)
			(xy 95.42373 -386.027281) (xy 95.416226 -386.074669) (xy 95.401402 -386.1203) (xy 95.379623 -386.16305)
			(xy 95.351424 -386.201867) (xy 95.317501 -386.235796) (xy 95.278688 -386.264) (xy 95.235941 -386.285785)
			(xy 95.190312 -386.300616) (xy 95.142925 -386.308127) (xy 95.118936 -386.3086) (xy 95.095363 -386.308177)
			(xy 95.048776 -386.300941) (xy 95.003858 -386.286621) (xy 94.96168 -386.265557) (xy 94.923246 -386.238252)
			(xy 94.889474 -386.205356) (xy 94.861167 -386.167654) (xy 94.849696 -386.147056) (xy 94.849188 -386.146294)
			(xy 94.451424 -385.457954) (xy 94.439492 -385.435294) (xy 94.42256 -385.386965) (xy 94.413907 -385.336491)
			(xy 94.413324 -385.310888) (xy 93.871584 -385.310888) (xy 94.183708 -385.850892) (xy 94.196441 -385.87421)
			(xy 94.214535 -385.924158) (xy 94.223751 -385.976477) (xy 94.224348 -386.003038) (xy 94.224348 -386.003292)
			(xy 94.22383 -386.027281) (xy 94.216326 -386.074669) (xy 94.201503 -386.120299) (xy 94.179724 -386.163049)
			(xy 94.151525 -386.201866) (xy 94.117603 -386.235794) (xy 94.07879 -386.263998) (xy 94.036043 -386.285784)
			(xy 93.990415 -386.300615) (xy 93.943029 -386.308126) (xy 93.91904 -386.3086) (xy 93.895467 -386.308174)
			(xy 93.84888 -386.300939) (xy 93.803963 -386.286618) (xy 93.761784 -386.265555) (xy 93.723351 -386.238251)
			(xy 93.689578 -386.205355) (xy 93.661271 -386.167654) (xy 93.6498 -386.147056) (xy 93.649292 -386.146294)
			(xy 93.251528 -385.457954) (xy 93.239596 -385.435294) (xy 93.222664 -385.386965) (xy 93.214011 -385.336491)
			(xy 93.213428 -385.310888) (xy 92.671688 -385.310888) (xy 92.983812 -385.850892) (xy 92.996546 -385.87421)
			(xy 93.014639 -385.924158) (xy 93.023855 -385.976477) (xy 93.024452 -386.003038) (xy 93.024452 -386.003292)
			(xy 93.02393 -386.027281) (xy 93.016427 -386.074668) (xy 93.001603 -386.120298) (xy 92.979824 -386.163048)
			(xy 92.951627 -386.201865) (xy 92.917704 -386.235793) (xy 92.878892 -386.263997) (xy 92.836146 -386.285783)
			(xy 92.790519 -386.300614) (xy 92.743133 -386.308126) (xy 92.719144 -386.3086) (xy 92.695571 -386.308171)
			(xy 92.648985 -386.300936) (xy 92.604067 -386.286616) (xy 92.561889 -386.265554) (xy 92.523455 -386.238249)
			(xy 92.489682 -386.205355) (xy 92.461375 -386.167654) (xy 92.449904 -386.147056) (xy 92.449396 -386.146294)
			(xy 92.051632 -385.457954) (xy 92.0397 -385.435294) (xy 92.022768 -385.386965) (xy 92.014115 -385.336491)
			(xy 92.013532 -385.310888) (xy 91.471538 -385.310888) (xy 91.783662 -385.850892) (xy 91.796489 -385.874224)
			(xy 91.814708 -385.924247) (xy 91.823967 -385.976673) (xy 91.824556 -386.003292) (xy 91.824031 -386.027268)
			(xy 91.816536 -386.07463) (xy 91.801728 -386.120239) (xy 91.779972 -386.162971) (xy 91.751802 -386.201776)
			(xy 91.717912 -386.235701) (xy 91.679135 -386.263909) (xy 91.636425 -386.285709) (xy 91.590832 -386.300563)
			(xy 91.543477 -386.308107) (xy 91.519502 -386.3086) (xy 91.518994 -386.3086) (xy 91.49542 -386.308211)
			(xy 91.448831 -386.300969) (xy 91.403913 -386.286642) (xy 91.361734 -386.265573) (xy 91.323301 -386.238262)
			(xy 91.28953 -386.205362) (xy 91.261224 -386.167656) (xy 91.249754 -386.147056) (xy 91.249246 -386.146294)
			(xy 90.851482 -385.457954) (xy 90.839625 -385.435268) (xy 90.822767 -385.386939) (xy 90.814186 -385.336479)
			(xy 90.813636 -385.310888) (xy 90.271642 -385.310888) (xy 90.583766 -385.850892) (xy 90.596593 -385.874223)
			(xy 90.614812 -385.924247) (xy 90.624071 -385.976673) (xy 90.62466 -386.003292) (xy 90.624231 -386.027273)
			(xy 90.616732 -386.074644) (xy 90.601919 -386.120261) (xy 90.580154 -386.162999) (xy 90.551974 -386.201809)
			(xy 90.518072 -386.235735) (xy 90.479282 -386.263942) (xy 90.436559 -386.285737) (xy 90.390953 -386.300582)
			(xy 90.343586 -386.308114) (xy 90.319606 -386.3086) (xy 90.319098 -386.3086) (xy 90.295524 -386.308208)
			(xy 90.248936 -386.300966) (xy 90.204017 -386.28664) (xy 90.161839 -386.265571) (xy 90.123406 -386.238261)
			(xy 90.089634 -386.205361) (xy 90.061328 -386.167656) (xy 90.049858 -386.147056) (xy 90.04935 -386.146294)
			(xy 89.651586 -385.457954) (xy 89.63973 -385.435267) (xy 89.622871 -385.386939) (xy 89.61429 -385.336479)
			(xy 89.61374 -385.310888) (xy 89.071492 -385.310888) (xy 89.383616 -385.850892) (xy 89.39635 -385.874209)
			(xy 89.414443 -385.924158) (xy 89.423659 -385.976477) (xy 89.424256 -386.003038) (xy 89.424256 -386.003292)
			(xy 89.42373 -386.027281) (xy 89.416227 -386.074667) (xy 89.401403 -386.120297) (xy 89.379625 -386.163047)
			(xy 89.351428 -386.201863) (xy 89.317506 -386.235791) (xy 89.278694 -386.263996) (xy 89.235949 -386.285782)
			(xy 89.190322 -386.300614) (xy 89.142937 -386.308126) (xy 89.118948 -386.3086) (xy 89.095375 -386.308168)
			(xy 89.048789 -386.300933) (xy 89.003871 -386.286614) (xy 88.961693 -386.265552) (xy 88.923259 -386.238248)
			(xy 88.889486 -386.205354) (xy 88.861179 -386.167654) (xy 88.849708 -386.147056) (xy 88.8492 -386.146294)
			(xy 88.451436 -385.457954) (xy 88.439505 -385.435294) (xy 88.422572 -385.386964) (xy 88.413919 -385.336491)
			(xy 88.413336 -385.310888) (xy 87.871596 -385.310888) (xy 88.18372 -385.850892) (xy 88.196454 -385.874209)
			(xy 88.214548 -385.924158) (xy 88.223763 -385.976476) (xy 88.22436 -386.003038) (xy 88.22436 -386.003292)
			(xy 88.223954 -386.027287) (xy 88.216447 -386.074687) (xy 88.201617 -386.120329) (xy 88.179828 -386.163088)
			(xy 88.151618 -386.201912) (xy 88.117682 -386.235844) (xy 88.078854 -386.264049) (xy 88.036092 -386.285832)
			(xy 87.990448 -386.300657) (xy 87.943047 -386.308157) (xy 87.919052 -386.3086) (xy 87.895479 -386.308164)
			(xy 87.848893 -386.300931) (xy 87.803976 -386.286612) (xy 87.761797 -386.265551) (xy 87.723364 -386.238247)
			(xy 87.689591 -386.205354) (xy 87.661283 -386.167653) (xy 87.649812 -386.147056) (xy 87.649304 -386.146294)
			(xy 87.25154 -385.457954) (xy 87.239609 -385.435293) (xy 87.222676 -385.386964) (xy 87.214023 -385.336491)
			(xy 87.21344 -385.310888) (xy 86.6717 -385.310888) (xy 86.983824 -385.850892) (xy 86.996559 -385.874209)
			(xy 87.014652 -385.924158) (xy 87.023867 -385.976476) (xy 87.024464 -386.003038) (xy 87.024464 -386.003292)
			(xy 87.024054 -386.027287) (xy 87.016547 -386.074687) (xy 87.001717 -386.120328) (xy 86.979929 -386.163087)
			(xy 86.951719 -386.201911) (xy 86.917783 -386.235843) (xy 86.878956 -386.264048) (xy 86.836195 -386.285831)
			(xy 86.790552 -386.300656) (xy 86.743151 -386.308157) (xy 86.719156 -386.3086) (xy 86.695584 -386.308161)
			(xy 86.648997 -386.300928) (xy 86.60408 -386.28661) (xy 86.561902 -386.265549) (xy 86.523468 -386.238246)
			(xy 86.489695 -386.205353) (xy 86.461387 -386.167653) (xy 86.449916 -386.147056) (xy 86.449408 -386.146294)
			(xy 86.051644 -385.457954) (xy 86.039713 -385.435293) (xy 86.02278 -385.386964) (xy 86.014127 -385.336491)
			(xy 86.013544 -385.310888) (xy 85.47155 -385.310888) (xy 85.783674 -385.850892) (xy 85.796501 -385.874223)
			(xy 85.81472 -385.924247) (xy 85.823979 -385.976673) (xy 85.824568 -386.003292) (xy 85.824131 -386.027272)
			(xy 85.816633 -386.074643) (xy 85.801819 -386.120259) (xy 85.780055 -386.162997) (xy 85.751876 -386.201806)
			(xy 85.717975 -386.235732) (xy 85.679187 -386.263939) (xy 85.636464 -386.285734) (xy 85.590859 -386.300581)
			(xy 85.543494 -386.308113) (xy 85.519514 -386.3086) (xy 85.519006 -386.3086) (xy 85.495432 -386.308201)
			(xy 85.448844 -386.300961) (xy 85.403926 -386.286636) (xy 85.361747 -386.265568) (xy 85.323314 -386.238259)
			(xy 85.289542 -386.20536) (xy 85.261237 -386.167655) (xy 85.249766 -386.147056) (xy 85.249258 -386.146294)
			(xy 84.851494 -385.457954) (xy 84.839638 -385.435267) (xy 84.822779 -385.386939) (xy 84.814198 -385.336479)
			(xy 84.813648 -385.310888) (xy 84.271654 -385.310888) (xy 84.583778 -385.850892) (xy 84.596606 -385.874223)
			(xy 84.614824 -385.924247) (xy 84.624083 -385.976673) (xy 84.624672 -386.003292) (xy 84.624231 -386.027272)
			(xy 84.616733 -386.074643) (xy 84.60192 -386.120258) (xy 84.580156 -386.162996) (xy 84.551978 -386.201805)
			(xy 84.518077 -386.235731) (xy 84.479289 -386.263938) (xy 84.436567 -386.285733) (xy 84.390963 -386.30058)
			(xy 84.343598 -386.308113) (xy 84.319618 -386.3086) (xy 84.31911 -386.3086) (xy 84.295536 -386.308198)
			(xy 84.248948 -386.300958) (xy 84.20403 -386.286634) (xy 84.161852 -386.265566) (xy 84.123418 -386.238258)
			(xy 84.089647 -386.20536) (xy 84.061341 -386.167655) (xy 84.04987 -386.147056) (xy 84.049362 -386.146294)
			(xy 83.651598 -385.457954) (xy 83.639742 -385.435267) (xy 83.622883 -385.386939) (xy 83.614302 -385.336479)
			(xy 83.613752 -385.310888) (xy 83.071504 -385.310888) (xy 83.383628 -385.850892) (xy 83.396363 -385.874209)
			(xy 83.414456 -385.924157) (xy 83.423671 -385.976476) (xy 83.424268 -386.003038) (xy 83.424268 -386.003292)
			(xy 83.423854 -386.027287) (xy 83.416348 -386.074686) (xy 83.401518 -386.120327) (xy 83.37973 -386.163086)
			(xy 83.351521 -386.201909) (xy 83.317585 -386.235841) (xy 83.278758 -386.264047) (xy 83.235997 -386.28583)
			(xy 83.190355 -386.300655) (xy 83.142955 -386.308157) (xy 83.11896 -386.3086) (xy 83.095388 -386.308158)
			(xy 83.048802 -386.300925) (xy 83.003884 -386.286608) (xy 82.961706 -386.265548) (xy 82.923272 -386.238245)
			(xy 82.889499 -386.205353) (xy 82.861192 -386.167653) (xy 82.84972 -386.147056) (xy 82.849212 -386.146294)
			(xy 82.451448 -385.457954) (xy 82.439517 -385.435293) (xy 82.422585 -385.386964) (xy 82.413931 -385.336491)
			(xy 82.413348 -385.310888) (xy 81.871608 -385.310888) (xy 82.183732 -385.850892) (xy 82.196467 -385.874209)
			(xy 82.21456 -385.924157) (xy 82.223775 -385.976476) (xy 82.224372 -386.003038) (xy 82.224372 -386.003292)
			(xy 82.223954 -386.027287) (xy 82.216448 -386.074685) (xy 82.201618 -386.120326) (xy 82.179831 -386.163085)
			(xy 82.151622 -386.201908) (xy 82.117687 -386.23584) (xy 82.078861 -386.264045) (xy 82.0361 -386.285829)
			(xy 81.990458 -386.300654) (xy 81.943059 -386.308156) (xy 81.919064 -386.3086) (xy 81.895492 -386.308155)
			(xy 81.848906 -386.300923) (xy 81.803989 -386.286606) (xy 81.76181 -386.265546) (xy 81.723376 -386.238244)
			(xy 81.689603 -386.205352) (xy 81.661296 -386.167653) (xy 81.649824 -386.147056) (xy 81.649316 -386.146294)
			(xy 81.251552 -385.457954) (xy 81.239622 -385.435293) (xy 81.222689 -385.386964) (xy 81.214035 -385.336491)
			(xy 81.213452 -385.310888) (xy 80.671712 -385.310888) (xy 80.983836 -385.850892) (xy 80.996572 -385.874209)
			(xy 81.014664 -385.924157) (xy 81.023879 -385.976476) (xy 81.024476 -386.003038) (xy 81.024476 -386.003292)
			(xy 81.024054 -386.027287) (xy 81.016548 -386.074685) (xy 81.001718 -386.120325) (xy 80.979931 -386.163083)
			(xy 80.951723 -386.201907) (xy 80.917788 -386.235839) (xy 80.878963 -386.264044) (xy 80.836203 -386.285828)
			(xy 80.790561 -386.300653) (xy 80.743163 -386.308156) (xy 80.719168 -386.3086) (xy 80.695596 -386.308151)
			(xy 80.64901 -386.30092) (xy 80.604093 -386.286604) (xy 80.561915 -386.265545) (xy 80.523481 -386.238243)
			(xy 80.489707 -386.205351) (xy 80.4614 -386.167653) (xy 80.449928 -386.147056) (xy 80.44942 -386.146294)
			(xy 80.051656 -385.457954) (xy 80.039726 -385.435293) (xy 80.022793 -385.386964) (xy 80.014139 -385.336491)
			(xy 80.013556 -385.310888) (xy 66.144182 -385.310888) (xy 66.456306 -385.850892) (xy 66.469128 -385.874226)
			(xy 66.48735 -385.924248) (xy 66.496611 -385.976674) (xy 66.4972 -386.003292) (xy 66.496754 -386.027298)
			(xy 66.48924 -386.074718) (xy 66.474396 -386.120378) (xy 66.452589 -386.163152) (xy 66.424356 -386.201985)
			(xy 66.390392 -386.235921) (xy 66.351535 -386.264122) (xy 66.308743 -386.285894) (xy 66.263071 -386.300699)
			(xy 66.215644 -386.308173) (xy 66.191638 -386.3086) (xy 66.191384 -386.3086) (xy 66.16781 -386.308219)
			(xy 66.121221 -386.300975) (xy 66.076302 -386.286647) (xy 66.034123 -386.265576) (xy 65.995691 -386.238265)
			(xy 65.961919 -386.205363) (xy 65.933614 -386.167656) (xy 65.922144 -386.147056) (xy 65.921636 -386.146294)
			(xy 65.523872 -385.457954) (xy 65.511936 -385.435296) (xy 65.495006 -385.386965) (xy 65.486355 -385.336492)
			(xy 65.485772 -385.310888) (xy 64.944032 -385.310888) (xy 65.256156 -385.850892) (xy 65.268893 -385.874208)
			(xy 65.286985 -385.924157) (xy 65.2962 -385.976476) (xy 65.296796 -386.003038) (xy 65.296796 -386.003292)
			(xy 65.296354 -386.027286) (xy 65.288848 -386.074682) (xy 65.27402 -386.12032) (xy 65.252235 -386.163077)
			(xy 65.224029 -386.2019) (xy 65.190097 -386.235831) (xy 65.151274 -386.264037) (xy 65.108517 -386.285822)
			(xy 65.062878 -386.300649) (xy 65.015482 -386.308155) (xy 64.991488 -386.3086) (xy 64.991234 -386.3086)
			(xy 64.967661 -386.308179) (xy 64.921074 -386.300942) (xy 64.876156 -386.286622) (xy 64.833978 -386.265557)
			(xy 64.795544 -386.238252) (xy 64.761772 -386.205356) (xy 64.733465 -386.167654) (xy 64.721994 -386.147056)
			(xy 64.721486 -386.146294) (xy 64.323722 -385.457954) (xy 64.311861 -385.43527) (xy 64.295005 -385.38694)
			(xy 64.286426 -385.33648) (xy 64.285876 -385.310888) (xy 63.744136 -385.310888) (xy 64.05626 -385.850892)
			(xy 64.068998 -385.874207) (xy 64.087089 -385.924157) (xy 64.096304 -385.976476) (xy 64.0969 -386.003038)
			(xy 64.0969 -386.003292) (xy 64.096454 -386.027285) (xy 64.088949 -386.074681) (xy 64.074121 -386.12032)
			(xy 64.052336 -386.163076) (xy 64.02413 -386.201898) (xy 63.990198 -386.23583) (xy 63.951376 -386.264036)
			(xy 63.90862 -386.285821) (xy 63.862981 -386.300649) (xy 63.815585 -386.308154) (xy 63.791592 -386.3086)
			(xy 63.791338 -386.3086) (xy 63.767765 -386.308176) (xy 63.721178 -386.30094) (xy 63.67626 -386.28662)
			(xy 63.634082 -386.265556) (xy 63.595648 -386.238251) (xy 63.561876 -386.205356) (xy 63.533569 -386.167654)
			(xy 63.522098 -386.147056) (xy 63.52159 -386.146294) (xy 63.123826 -385.457954) (xy 63.111965 -385.43527)
			(xy 63.095109 -385.38694) (xy 63.08653 -385.33648) (xy 63.08598 -385.310888) (xy 62.543986 -385.310888)
			(xy 62.85611 -385.850892) (xy 62.868932 -385.874226) (xy 62.887154 -385.924248) (xy 62.896415 -385.976673)
			(xy 62.897004 -386.003292) (xy 62.896554 -386.027298) (xy 62.88904 -386.074718) (xy 62.874197 -386.120377)
			(xy 62.85239 -386.163151) (xy 62.824157 -386.201984) (xy 62.790194 -386.23592) (xy 62.751337 -386.264121)
			(xy 62.708546 -386.285893) (xy 62.662874 -386.300698) (xy 62.615448 -386.308173) (xy 62.591442 -386.3086)
			(xy 62.591188 -386.3086) (xy 62.567614 -386.308216) (xy 62.521025 -386.300973) (xy 62.476106 -386.286645)
			(xy 62.433928 -386.265575) (xy 62.395495 -386.238264) (xy 62.361723 -386.205363) (xy 62.333418 -386.167656)
			(xy 62.321948 -386.147056) (xy 62.32144 -386.146294) (xy 61.923676 -385.457954) (xy 61.91174 -385.435296)
			(xy 61.89481 -385.386965) (xy 61.886159 -385.336492) (xy 61.885576 -385.310888) (xy 61.34409 -385.310888)
			(xy 61.656214 -385.850892) (xy 61.669037 -385.874226) (xy 61.687258 -385.924248) (xy 61.696519 -385.976673)
			(xy 61.697108 -386.003292) (xy 61.696654 -386.027298) (xy 61.68914 -386.074717) (xy 61.674297 -386.120377)
			(xy 61.652491 -386.16315) (xy 61.624258 -386.201983) (xy 61.590295 -386.235918) (xy 61.55144 -386.264119)
			(xy 61.508649 -386.285891) (xy 61.462978 -386.300698) (xy 61.415552 -386.308173) (xy 61.391546 -386.3086)
			(xy 61.391292 -386.3086) (xy 61.367718 -386.308213) (xy 61.321129 -386.30097) (xy 61.27621 -386.286643)
			(xy 61.234032 -386.265573) (xy 61.195599 -386.238263) (xy 61.161828 -386.205362) (xy 61.133522 -386.167656)
			(xy 61.122052 -386.147056) (xy 61.121544 -386.146294) (xy 60.72378 -385.457954) (xy 60.711844 -385.435296)
			(xy 60.694915 -385.386965) (xy 60.686263 -385.336492) (xy 60.68568 -385.310888) (xy 60.144194 -385.310888)
			(xy 60.456318 -385.850892) (xy 60.469141 -385.874226) (xy 60.487362 -385.924248) (xy 60.496623 -385.976673)
			(xy 60.497212 -386.003292) (xy 60.496754 -386.027297) (xy 60.48924 -386.074717) (xy 60.474398 -386.120376)
			(xy 60.452591 -386.163149) (xy 60.424359 -386.201981) (xy 60.390397 -386.235917) (xy 60.351542 -386.264118)
			(xy 60.308752 -386.28589) (xy 60.263081 -386.300697) (xy 60.215656 -386.308172) (xy 60.19165 -386.3086)
			(xy 60.191396 -386.3086) (xy 60.167822 -386.308209) (xy 60.121233 -386.300967) (xy 60.076315 -386.286641)
			(xy 60.034136 -386.265572) (xy 59.995703 -386.238262) (xy 59.961932 -386.205362) (xy 59.933626 -386.167656)
			(xy 59.922156 -386.147056) (xy 59.921648 -386.146294) (xy 59.523884 -385.457954) (xy 59.511948 -385.435296)
			(xy 59.495019 -385.386965) (xy 59.486367 -385.336492) (xy 59.485784 -385.310888) (xy 58.944044 -385.310888)
			(xy 59.256168 -385.850892) (xy 59.268906 -385.874207) (xy 59.286997 -385.924157) (xy 59.296212 -385.976476)
			(xy 59.296808 -386.003038) (xy 59.296808 -386.003292) (xy 59.296354 -386.027285) (xy 59.288849 -386.07468)
			(xy 59.274021 -386.120318) (xy 59.252237 -386.163074) (xy 59.224032 -386.201896) (xy 59.190102 -386.235827)
			(xy 59.151281 -386.264033) (xy 59.108525 -386.285818) (xy 59.062888 -386.300647) (xy 59.015493 -386.308154)
			(xy 58.9915 -386.3086) (xy 58.991246 -386.3086) (xy 58.967673 -386.308169) (xy 58.921087 -386.300935)
			(xy 58.876169 -386.286615) (xy 58.833991 -386.265553) (xy 58.795557 -386.238249) (xy 58.761784 -386.205355)
			(xy 58.733477 -386.167654) (xy 58.722006 -386.147056) (xy 58.721498 -386.146294) (xy 58.323734 -385.457954)
			(xy 58.311874 -385.43527) (xy 58.295018 -385.38694) (xy 58.286438 -385.33648) (xy 58.285888 -385.310888)
			(xy 57.744148 -385.310888) (xy 58.056272 -385.850892) (xy 58.069011 -385.874207) (xy 58.087101 -385.924157)
			(xy 58.096316 -385.976476) (xy 58.096912 -386.003038) (xy 58.096912 -386.003292) (xy 58.096454 -386.027285)
			(xy 58.088949 -386.07468) (xy 58.074122 -386.120317) (xy 58.052338 -386.163073) (xy 58.024134 -386.201894)
			(xy 57.990203 -386.235826) (xy 57.951383 -386.264032) (xy 57.908628 -386.285817) (xy 57.862991 -386.300646)
			(xy 57.815597 -386.308154) (xy 57.791604 -386.3086) (xy 57.79135 -386.3086) (xy 57.767777 -386.308166)
			(xy 57.721191 -386.300932) (xy 57.676273 -386.286613) (xy 57.634095 -386.265551) (xy 57.595661 -386.238248)
			(xy 57.561888 -386.205354) (xy 57.533581 -386.167653) (xy 57.52211 -386.147056) (xy 57.521602 -386.146294)
			(xy 57.123838 -385.457954) (xy 57.111978 -385.435269) (xy 57.095122 -385.38694) (xy 57.086542 -385.33648)
			(xy 57.085992 -385.310888) (xy 56.543744 -385.310888) (xy 56.855868 -385.850892) (xy 56.868606 -385.874207)
			(xy 56.886697 -385.924157) (xy 56.895912 -385.976476) (xy 56.896508 -386.003038) (xy 56.896508 -386.003292)
			(xy 56.896054 -386.027285) (xy 56.888549 -386.07468) (xy 56.873721 -386.120318) (xy 56.851937 -386.163074)
			(xy 56.823732 -386.201896) (xy 56.789802 -386.235827) (xy 56.750981 -386.264033) (xy 56.708225 -386.285818)
			(xy 56.662588 -386.300647) (xy 56.615193 -386.308154) (xy 56.5912 -386.3086) (xy 56.567626 -386.308206)
			(xy 56.521038 -386.300965) (xy 56.476119 -386.286639) (xy 56.433941 -386.26557) (xy 56.395508 -386.238261)
			(xy 56.361736 -386.205361) (xy 56.33343 -386.167656) (xy 56.32196 -386.147056) (xy 56.321452 -386.146294)
			(xy 55.923688 -385.457954) (xy 55.911753 -385.435296) (xy 55.894823 -385.386965) (xy 55.886171 -385.336491)
			(xy 55.885588 -385.310888) (xy 55.343848 -385.310888) (xy 55.655972 -385.850892) (xy 55.668711 -385.874207)
			(xy 55.686801 -385.924157) (xy 55.696016 -385.976476) (xy 55.696612 -386.003038) (xy 55.696612 -386.003292)
			(xy 55.696154 -386.027285) (xy 55.688649 -386.07468) (xy 55.673822 -386.120317) (xy 55.652038 -386.163073)
			(xy 55.623834 -386.201894) (xy 55.589903 -386.235826) (xy 55.551083 -386.264032) (xy 55.508328 -386.285817)
			(xy 55.462691 -386.300646) (xy 55.415297 -386.308154) (xy 55.391304 -386.3086) (xy 55.36773 -386.308203)
			(xy 55.321142 -386.300962) (xy 55.276223 -386.286637) (xy 55.234045 -386.265569) (xy 55.195612 -386.23826)
			(xy 55.16184 -386.205361) (xy 55.133535 -386.167656) (xy 55.122064 -386.147056) (xy 55.121556 -386.146294)
			(xy 54.723792 -385.457954) (xy 54.711857 -385.435295) (xy 54.694927 -385.386965) (xy 54.686275 -385.336491)
			(xy 54.685692 -385.310888) (xy 54.143952 -385.310888) (xy 54.456076 -385.850892) (xy 54.468815 -385.874207)
			(xy 54.486905 -385.924157) (xy 54.49612 -385.976476) (xy 54.496716 -386.003038) (xy 54.496716 -386.003292)
			(xy 54.49623 -386.027283) (xy 54.488725 -386.074673) (xy 54.4739 -386.120306) (xy 54.452118 -386.163059)
			(xy 54.423916 -386.201877) (xy 54.389989 -386.235806) (xy 54.351172 -386.264009) (xy 54.308421 -386.285793)
			(xy 54.262789 -386.300622) (xy 54.215399 -386.308129) (xy 54.191408 -386.3086) (xy 54.167834 -386.3082)
			(xy 54.121246 -386.30096) (xy 54.076328 -386.286635) (xy 54.034149 -386.265567) (xy 53.995716 -386.238259)
			(xy 53.961944 -386.20536) (xy 53.933639 -386.167655) (xy 53.922168 -386.147056) (xy 53.92166 -386.146294)
			(xy 53.523896 -385.457954) (xy 53.511961 -385.435295) (xy 53.495031 -385.386965) (xy 53.486379 -385.336491)
			(xy 53.485796 -385.310888) (xy 52.943802 -385.310888) (xy 53.255926 -385.850892) (xy 53.26875 -385.874225)
			(xy 53.286971 -385.924247) (xy 53.296231 -385.976673) (xy 53.29682 -386.003292) (xy 53.296331 -386.02727)
			(xy 53.288835 -386.074636) (xy 53.274024 -386.120247) (xy 53.252265 -386.162982) (xy 53.224092 -386.201789)
			(xy 53.190197 -386.235713) (xy 53.151416 -386.263922) (xy 53.1087 -386.285719) (xy 53.063102 -386.30057)
			(xy 53.015743 -386.30811) (xy 52.991766 -386.3086) (xy 52.991258 -386.3086) (xy 52.967686 -386.308159)
			(xy 52.9211 -386.300927) (xy 52.876182 -386.286609) (xy 52.834004 -386.265548) (xy 52.79557 -386.238246)
			(xy 52.761797 -386.205353) (xy 52.73349 -386.167653) (xy 52.722018 -386.147056) (xy 52.72151 -386.146294)
			(xy 52.323746 -385.457954) (xy 52.311886 -385.435269) (xy 52.29503 -385.38694) (xy 52.28645 -385.33648)
			(xy 52.2859 -385.310888) (xy 51.743906 -385.310888) (xy 52.05603 -385.850892) (xy 52.068854 -385.874225)
			(xy 52.087075 -385.924247) (xy 52.096335 -385.976673) (xy 52.096924 -386.003292) (xy 52.096431 -386.02727)
			(xy 52.088935 -386.074635) (xy 52.074125 -386.120246) (xy 52.052366 -386.16298) (xy 52.024193 -386.201787)
			(xy 51.990299 -386.235712) (xy 51.951518 -386.26392) (xy 51.908803 -386.285718) (xy 51.863206 -386.30057)
			(xy 51.815847 -386.308109) (xy 51.79187 -386.3086) (xy 51.791362 -386.3086) (xy 51.76779 -386.308156)
			(xy 51.721204 -386.300924) (xy 51.676286 -386.286607) (xy 51.634108 -386.265547) (xy 51.595674 -386.238245)
			(xy 51.561901 -386.205352) (xy 51.533594 -386.167653) (xy 51.522122 -386.147056) (xy 51.521614 -386.146294)
			(xy 51.12385 -385.457954) (xy 51.111991 -385.435269) (xy 51.095134 -385.38694) (xy 51.086554 -385.33648)
			(xy 51.086004 -385.310888) (xy 50.543756 -385.310888) (xy 50.85588 -385.850892) (xy 50.868619 -385.874207)
			(xy 50.886709 -385.924157) (xy 50.895924 -385.976476) (xy 50.89652 -386.003038) (xy 50.89652 -386.003292)
			(xy 50.89603 -386.027282) (xy 50.888526 -386.074673) (xy 50.8737 -386.120306) (xy 50.851918 -386.163057)
			(xy 50.823717 -386.201876) (xy 50.789791 -386.235804) (xy 50.750974 -386.264008) (xy 50.708224 -386.285792)
			(xy 50.662592 -386.300621) (xy 50.615202 -386.308128) (xy 50.591212 -386.3086) (xy 50.567638 -386.308197)
			(xy 50.521051 -386.300957) (xy 50.476132 -386.286633) (xy 50.433954 -386.265566) (xy 50.395521 -386.238258)
			(xy 50.361749 -386.205359) (xy 50.333443 -386.167655) (xy 50.321972 -386.147056) (xy 50.321464 -386.146294)
			(xy 49.9237 -385.457954) (xy 49.911766 -385.435295) (xy 49.894835 -385.386965) (xy 49.886183 -385.336491)
			(xy 49.8856 -385.310888) (xy 49.34386 -385.310888) (xy 49.655984 -385.850892) (xy 49.668715 -385.874211)
			(xy 49.68681 -385.924158) (xy 49.696027 -385.976477) (xy 49.696624 -386.003038) (xy 49.696624 -386.003292)
			(xy 49.69613 -386.027282) (xy 49.688626 -386.074672) (xy 49.6738 -386.120305) (xy 49.652019 -386.163056)
			(xy 49.623818 -386.201874) (xy 49.589892 -386.235803) (xy 49.551077 -386.264007) (xy 49.508327 -386.285791)
			(xy 49.462695 -386.30062) (xy 49.415306 -386.308128) (xy 49.391316 -386.3086) (xy 49.367742 -386.308193)
			(xy 49.321155 -386.300954) (xy 49.276236 -386.286631) (xy 49.234058 -386.265564) (xy 49.195625 -386.238257)
			(xy 49.161853 -386.205359) (xy 49.133547 -386.167655) (xy 49.122076 -386.147056) (xy 49.121568 -386.146294)
			(xy 48.723804 -385.457954) (xy 48.71187 -385.435295) (xy 48.694939 -385.386965) (xy 48.686287 -385.336491)
			(xy 48.685704 -385.310888) (xy 48.143964 -385.310888) (xy 48.456088 -385.850892) (xy 48.46882 -385.874211)
			(xy 48.486915 -385.924158) (xy 48.496131 -385.976477) (xy 48.496728 -386.003038) (xy 48.496728 -386.003292)
			(xy 48.49623 -386.027282) (xy 48.488726 -386.074672) (xy 48.473901 -386.120304) (xy 48.45212 -386.163055)
			(xy 48.42392 -386.201873) (xy 48.389994 -386.235801) (xy 48.351179 -386.264005) (xy 48.30843 -386.28579)
			(xy 48.262799 -386.300619) (xy 48.21541 -386.308128) (xy 48.19142 -386.3086) (xy 48.167847 -386.30819)
			(xy 48.121259 -386.300952) (xy 48.076341 -386.286629) (xy 48.034162 -386.265563) (xy 47.995729 -386.238256)
			(xy 47.961957 -386.205358) (xy 47.933651 -386.167655) (xy 47.92218 -386.147056) (xy 47.921672 -386.146294)
			(xy 47.523908 -385.457954) (xy 47.511974 -385.435295) (xy 47.495043 -385.386965) (xy 47.486391 -385.336491)
			(xy 47.485808 -385.310888) (xy 2.509012 -385.310888) (xy 2.509012 -387.789674) (xy 40.901112 -387.789674)
			(xy 40.901112 -386.926074) (xy 40.901598 -386.898805) (xy 40.90936 -386.844821) (xy 40.924725 -386.792491)
			(xy 40.947382 -386.742881) (xy 40.976868 -386.697) (xy 41.012583 -386.655783) (xy 41.0538 -386.620068)
			(xy 41.099681 -386.590582) (xy 41.149291 -386.567925) (xy 41.201621 -386.55256) (xy 41.255605 -386.544798)
			(xy 41.310143 -386.544798) (xy 41.364127 -386.55256) (xy 41.416457 -386.567925) (xy 41.466067 -386.590582)
			(xy 41.511948 -386.620068) (xy 41.553165 -386.655783) (xy 41.58888 -386.697) (xy 41.618366 -386.742881)
			(xy 41.641023 -386.792491) (xy 41.656388 -386.844821) (xy 41.66415 -386.898805) (xy 41.664636 -386.926074)
			(xy 41.664636 -387.789674) (xy 73.42886 -387.789674) (xy 73.42886 -386.926074) (xy 73.429346 -386.898805)
			(xy 73.437108 -386.844821) (xy 73.452473 -386.792491) (xy 73.47513 -386.742881) (xy 73.504616 -386.697)
			(xy 73.540331 -386.655783) (xy 73.581548 -386.620068) (xy 73.627429 -386.590582) (xy 73.677039 -386.567925)
			(xy 73.729369 -386.55256) (xy 73.783353 -386.544798) (xy 73.837891 -386.544798) (xy 73.891875 -386.55256)
			(xy 73.944205 -386.567925) (xy 73.993815 -386.590582) (xy 74.039696 -386.620068) (xy 74.080913 -386.655783)
			(xy 74.116628 -386.697) (xy 74.146114 -386.742881) (xy 74.168771 -386.792491) (xy 74.184136 -386.844821)
			(xy 74.191898 -386.898805) (xy 74.192384 -386.926074) (xy 74.192384 -387.789674) (xy 108.001308 -387.789674)
			(xy 108.001308 -386.926074) (xy 108.001794 -386.898823) (xy 108.00955 -386.844875) (xy 108.024905 -386.79258)
			(xy 108.047547 -386.743003) (xy 108.077013 -386.697153) (xy 108.112704 -386.655962) (xy 108.153895 -386.620271)
			(xy 108.199745 -386.590805) (xy 108.249322 -386.568163) (xy 108.301617 -386.552808) (xy 108.355565 -386.545052)
			(xy 108.410067 -386.545052) (xy 108.464015 -386.552808) (xy 108.51631 -386.568163) (xy 108.565887 -386.590805)
			(xy 108.611737 -386.620271) (xy 108.652928 -386.655962) (xy 108.688619 -386.697153) (xy 108.718085 -386.743003)
			(xy 108.740727 -386.79258) (xy 108.756082 -386.844875) (xy 108.763838 -386.898823) (xy 108.764324 -386.926074)
			(xy 108.764324 -387.789674) (xy 140.529056 -387.789674) (xy 140.529056 -386.926074) (xy 140.529542 -386.898823)
			(xy 140.537298 -386.844875) (xy 140.552653 -386.79258) (xy 140.575295 -386.743003) (xy 140.604761 -386.697153)
			(xy 140.640452 -386.655962) (xy 140.681643 -386.620271) (xy 140.727493 -386.590805) (xy 140.77707 -386.568163)
			(xy 140.829365 -386.552808) (xy 140.883313 -386.545052) (xy 140.937815 -386.545052) (xy 140.991763 -386.552808)
			(xy 141.044058 -386.568163) (xy 141.093635 -386.590805) (xy 141.139485 -386.620271) (xy 141.180676 -386.655962)
			(xy 141.216367 -386.697153) (xy 141.245833 -386.743003) (xy 141.268475 -386.79258) (xy 141.28383 -386.844875)
			(xy 141.291586 -386.898823) (xy 141.292072 -386.926074) (xy 141.292072 -387.789674) (xy 141.291586 -387.816925)
			(xy 141.28383 -387.870873) (xy 141.268475 -387.923168) (xy 141.245833 -387.972745) (xy 141.216367 -388.018595)
			(xy 141.180676 -388.059786) (xy 141.139485 -388.095477) (xy 141.093635 -388.124943) (xy 141.044058 -388.147585)
			(xy 140.991763 -388.16294) (xy 140.937815 -388.170696) (xy 140.883313 -388.170696) (xy 140.829365 -388.16294)
			(xy 140.77707 -388.147585) (xy 140.727493 -388.124943) (xy 140.681643 -388.095477) (xy 140.640452 -388.059786)
			(xy 140.604761 -388.018595) (xy 140.575295 -387.972745) (xy 140.552653 -387.923168) (xy 140.537298 -387.870873)
			(xy 140.529542 -387.816925) (xy 140.529056 -387.789674) (xy 108.764324 -387.789674) (xy 108.763838 -387.816925)
			(xy 108.756082 -387.870873) (xy 108.740727 -387.923168) (xy 108.718085 -387.972745) (xy 108.688619 -388.018595)
			(xy 108.652928 -388.059786) (xy 108.611737 -388.095477) (xy 108.565887 -388.124943) (xy 108.51631 -388.147585)
			(xy 108.464015 -388.16294) (xy 108.410067 -388.170696) (xy 108.355565 -388.170696) (xy 108.301617 -388.16294)
			(xy 108.249322 -388.147585) (xy 108.199745 -388.124943) (xy 108.153895 -388.095477) (xy 108.112704 -388.059786)
			(xy 108.077013 -388.018595) (xy 108.047547 -387.972745) (xy 108.024905 -387.923168) (xy 108.00955 -387.870873)
			(xy 108.001794 -387.816925) (xy 108.001308 -387.789674) (xy 74.192384 -387.789674) (xy 74.191898 -387.816943)
			(xy 74.184136 -387.870927) (xy 74.168771 -387.923257) (xy 74.146114 -387.972867) (xy 74.116628 -388.018748)
			(xy 74.080913 -388.059965) (xy 74.039696 -388.09568) (xy 73.993815 -388.125166) (xy 73.944205 -388.147823)
			(xy 73.891875 -388.163188) (xy 73.837891 -388.17095) (xy 73.783353 -388.17095) (xy 73.729369 -388.163188)
			(xy 73.677039 -388.147823) (xy 73.627429 -388.125166) (xy 73.581548 -388.09568) (xy 73.540331 -388.059965)
			(xy 73.504616 -388.018748) (xy 73.47513 -387.972867) (xy 73.452473 -387.923257) (xy 73.437108 -387.870927)
			(xy 73.429346 -387.816943) (xy 73.42886 -387.789674) (xy 41.664636 -387.789674) (xy 41.66415 -387.816943)
			(xy 41.656388 -387.870927) (xy 41.641023 -387.923257) (xy 41.618366 -387.972867) (xy 41.58888 -388.018748)
			(xy 41.553165 -388.059965) (xy 41.511948 -388.09568) (xy 41.466067 -388.125166) (xy 41.416457 -388.147823)
			(xy 41.364127 -388.163188) (xy 41.310143 -388.17095) (xy 41.255605 -388.17095) (xy 41.201621 -388.163188)
			(xy 41.149291 -388.147823) (xy 41.099681 -388.125166) (xy 41.0538 -388.09568) (xy 41.012583 -388.059965)
			(xy 40.976868 -388.018748) (xy 40.947382 -387.972867) (xy 40.924725 -387.923257) (xy 40.90936 -387.870927)
			(xy 40.901598 -387.816943) (xy 40.901112 -387.789674) (xy 2.509012 -387.789674) (xy 2.509012 -388.77494)
			(xy 47.485808 -388.77494) (xy 47.485808 -388.774432) (xy 47.486291 -388.750454) (xy 47.493785 -388.703086)
			(xy 47.508594 -388.657473) (xy 47.530352 -388.614736) (xy 47.558526 -388.575927) (xy 47.592422 -388.542002)
			(xy 47.631205 -388.513794) (xy 47.673923 -388.491997) (xy 47.719523 -388.477148) (xy 47.766884 -388.469612)
			(xy 47.790862 -388.469124) (xy 47.79137 -388.469124) (xy 47.815307 -388.469547) (xy 47.862595 -388.477009)
			(xy 47.90814 -388.491756) (xy 47.950828 -388.513426) (xy 47.989613 -388.541489) (xy 48.023547 -388.575259)
			(xy 48.051798 -388.613907) (xy 48.06315 -388.634986) (xy 48.063658 -388.636002) (xy 48.143964 -388.77494)
			(xy 48.685704 -388.77494) (xy 48.685704 -388.774432) (xy 48.686191 -388.750454) (xy 48.693685 -388.703086)
			(xy 48.708493 -388.657473) (xy 48.730252 -388.614737) (xy 48.758425 -388.575929) (xy 48.79232 -388.542003)
			(xy 48.831103 -388.513795) (xy 48.87382 -388.491998) (xy 48.91942 -388.477149) (xy 48.96678 -388.469613)
			(xy 48.990758 -388.469124) (xy 48.991266 -388.469124) (xy 49.015203 -388.46955) (xy 49.06249 -388.477012)
			(xy 49.108036 -388.491758) (xy 49.150724 -388.513428) (xy 49.189509 -388.54149) (xy 49.223443 -388.575259)
			(xy 49.251694 -388.613908) (xy 49.263046 -388.634986) (xy 49.263554 -388.636002) (xy 49.34386 -388.77494)
			(xy 49.8856 -388.77494) (xy 49.8856 -388.774432) (xy 49.886091 -388.750454) (xy 49.893585 -388.703087)
			(xy 49.908393 -388.657474) (xy 49.930151 -388.614738) (xy 49.958324 -388.57593) (xy 49.992219 -388.542005)
			(xy 50.031001 -388.513796) (xy 50.073717 -388.491999) (xy 50.119316 -388.47715) (xy 50.166676 -388.469613)
			(xy 50.190654 -388.469124) (xy 50.191162 -388.469124) (xy 50.215098 -388.469553) (xy 50.262386 -388.477014)
			(xy 50.307931 -388.49176) (xy 50.350619 -388.513429) (xy 50.389405 -388.541491) (xy 50.423338 -388.57526)
			(xy 50.45159 -388.613908) (xy 50.462942 -388.634986) (xy 50.46345 -388.636002) (xy 50.543756 -388.77494)
			(xy 51.086004 -388.77494) (xy 51.086004 -388.774432) (xy 51.086468 -388.750439) (xy 51.09397 -388.703044)
			(xy 51.108795 -388.657405) (xy 51.130577 -388.614648) (xy 51.158781 -388.575826) (xy 51.192711 -388.541894)
			(xy 51.231531 -388.513688) (xy 51.274287 -388.491903) (xy 51.319924 -388.477075) (xy 51.367319 -388.469569)
			(xy 51.391312 -388.469124) (xy 51.415247 -388.469594) (xy 51.462533 -388.477047) (xy 51.508077 -388.491786)
			(xy 51.550765 -388.513448) (xy 51.589551 -388.541504) (xy 51.623486 -388.575267) (xy 51.651739 -388.61391)
			(xy 51.663092 -388.634986) (xy 51.6636 -388.636002) (xy 51.743906 -388.77494) (xy 52.2859 -388.77494)
			(xy 52.2859 -388.774432) (xy 52.286368 -388.750439) (xy 52.29387 -388.703044) (xy 52.308695 -388.657406)
			(xy 52.330477 -388.61465) (xy 52.35868 -388.575827) (xy 52.392609 -388.541895) (xy 52.431429 -388.513689)
			(xy 52.474184 -388.491904) (xy 52.519821 -388.477076) (xy 52.567215 -388.46957) (xy 52.591208 -388.469124)
			(xy 52.615143 -388.469597) (xy 52.662429 -388.47705) (xy 52.707973 -388.491788) (xy 52.750661 -388.51345)
			(xy 52.789447 -388.541505) (xy 52.823382 -388.575268) (xy 52.851635 -388.61391) (xy 52.862988 -388.634986)
			(xy 52.863496 -388.636002) (xy 52.943802 -388.77494) (xy 53.485796 -388.77494) (xy 53.485796 -388.774432)
			(xy 53.486291 -388.750454) (xy 53.493785 -388.703088) (xy 53.508592 -388.657475) (xy 53.53035 -388.61474)
			(xy 53.558523 -388.575932) (xy 53.592417 -388.542006) (xy 53.631199 -388.513798) (xy 53.673914 -388.492001)
			(xy 53.719513 -388.477151) (xy 53.766873 -388.469613) (xy 53.79085 -388.469124) (xy 53.791358 -388.469124)
			(xy 53.815294 -388.469556) (xy 53.862582 -388.477017) (xy 53.908127 -388.491762) (xy 53.950815 -388.513431)
			(xy 53.9896 -388.541492) (xy 54.023534 -388.57526) (xy 54.051786 -388.613908) (xy 54.063138 -388.634986)
			(xy 54.063646 -388.636002) (xy 54.143952 -388.77494) (xy 54.685692 -388.77494) (xy 54.685692 -388.774432)
			(xy 54.686191 -388.750454) (xy 54.693684 -388.703088) (xy 54.708492 -388.657476) (xy 54.730249 -388.614741)
			(xy 54.758422 -388.575933) (xy 54.792315 -388.542008) (xy 54.831097 -388.513799) (xy 54.873812 -388.492002)
			(xy 54.91941 -388.477151) (xy 54.966769 -388.469614) (xy 54.990746 -388.469124) (xy 54.991254 -388.469124)
			(xy 55.01519 -388.46956) (xy 55.062478 -388.47702) (xy 55.108023 -388.491764) (xy 55.150711 -388.513432)
			(xy 55.189496 -388.541493) (xy 55.22343 -388.575261) (xy 55.251681 -388.613908) (xy 55.263034 -388.634986)
			(xy 55.263542 -388.636002) (xy 55.343848 -388.77494) (xy 55.885588 -388.77494) (xy 55.885588 -388.774432)
			(xy 55.886091 -388.750455) (xy 55.893584 -388.703089) (xy 55.908392 -388.657477) (xy 55.930149 -388.614742)
			(xy 55.95832 -388.575934) (xy 55.992213 -388.542009) (xy 56.030994 -388.513801) (xy 56.073709 -388.492003)
			(xy 56.119306 -388.477152) (xy 56.166665 -388.469614) (xy 56.190642 -388.469124) (xy 56.19115 -388.469124)
			(xy 56.215086 -388.469563) (xy 56.262373 -388.477022) (xy 56.307918 -388.491766) (xy 56.350606 -388.513434)
			(xy 56.389392 -388.541494) (xy 56.423326 -388.575262) (xy 56.451577 -388.613908) (xy 56.46293 -388.634986)
			(xy 56.463438 -388.636002) (xy 56.543744 -388.77494) (xy 57.085992 -388.77494) (xy 57.085992 -388.774432)
			(xy 57.086468 -388.75044) (xy 57.09397 -388.703045) (xy 57.108794 -388.657408) (xy 57.130575 -388.614652)
			(xy 57.158777 -388.57583) (xy 57.192706 -388.541898) (xy 57.231525 -388.513692) (xy 57.274279 -388.491906)
			(xy 57.319914 -388.477077) (xy 57.367308 -388.46957) (xy 57.3913 -388.469124) (xy 57.415235 -388.469603)
			(xy 57.46252 -388.477055) (xy 57.508064 -388.491792) (xy 57.550752 -388.513453) (xy 57.589538 -388.541507)
			(xy 57.623473 -388.575269) (xy 57.651726 -388.613911) (xy 57.66308 -388.634986) (xy 57.663588 -388.636002)
			(xy 57.743894 -388.77494) (xy 58.285888 -388.77494) (xy 58.285888 -388.774432) (xy 58.286368 -388.75044)
			(xy 58.29387 -388.703046) (xy 58.308693 -388.657409) (xy 58.330474 -388.614653) (xy 58.358676 -388.575831)
			(xy 58.392604 -388.5419) (xy 58.431423 -388.513693) (xy 58.474176 -388.491907) (xy 58.519811 -388.477078)
			(xy 58.567204 -388.469571) (xy 58.591196 -388.469124) (xy 58.615133 -388.469526) (xy 58.662423 -388.476992)
			(xy 58.707968 -388.491742) (xy 58.750656 -388.513416) (xy 58.789441 -388.541483) (xy 58.823374 -388.575255)
			(xy 58.851624 -388.613906) (xy 58.862976 -388.634986) (xy 58.863484 -388.636002) (xy 58.94379 -388.77494)
			(xy 59.485784 -388.77494) (xy 59.485784 -388.774432) (xy 59.486291 -388.750455) (xy 59.493784 -388.703089)
			(xy 59.508591 -388.657478) (xy 59.530348 -388.614743) (xy 59.558519 -388.575936) (xy 59.592412 -388.54201)
			(xy 59.631192 -388.513802) (xy 59.673906 -388.492004) (xy 59.719503 -388.477153) (xy 59.766861 -388.469614)
			(xy 59.790838 -388.469124) (xy 59.791346 -388.469124) (xy 59.815282 -388.469566) (xy 59.862569 -388.477025)
			(xy 59.908114 -388.491768) (xy 59.950802 -388.513435) (xy 59.989587 -388.541495) (xy 60.023522 -388.575262)
			(xy 60.051773 -388.613909) (xy 60.063126 -388.634986) (xy 60.063634 -388.636002) (xy 60.14394 -388.77494)
			(xy 60.68568 -388.77494) (xy 60.68568 -388.774432) (xy 60.686191 -388.750455) (xy 60.693684 -388.70309)
			(xy 60.708491 -388.657479) (xy 60.730247 -388.614744) (xy 60.758418 -388.575937) (xy 60.79231 -388.542012)
			(xy 60.83109 -388.513803) (xy 60.873803 -388.492005) (xy 60.9194 -388.477154) (xy 60.966757 -388.469614)
			(xy 60.990734 -388.469124) (xy 60.991242 -388.469124) (xy 61.015178 -388.469569) (xy 61.062465 -388.477028)
			(xy 61.10801 -388.49177) (xy 61.150697 -388.513437) (xy 61.189483 -388.541496) (xy 61.223417 -388.575263)
			(xy 61.251669 -388.613909) (xy 61.263022 -388.634986) (xy 61.26353 -388.636002) (xy 61.343836 -388.77494)
			(xy 61.885576 -388.77494) (xy 61.885576 -388.774432) (xy 61.886091 -388.750455) (xy 61.893584 -388.70309)
			(xy 61.908391 -388.65748) (xy 61.930147 -388.614746) (xy 61.958317 -388.575938) (xy 61.992208 -388.542013)
			(xy 62.030988 -388.513805) (xy 62.073701 -388.492006) (xy 62.119296 -388.477155) (xy 62.166654 -388.469615)
			(xy 62.19063 -388.469124) (xy 62.191138 -388.469124) (xy 62.215074 -388.469573) (xy 62.262361 -388.47703)
			(xy 62.307905 -388.491772) (xy 62.350593 -388.513438) (xy 62.389379 -388.541498) (xy 62.423313 -388.575263)
			(xy 62.451565 -388.613909) (xy 62.462918 -388.634986) (xy 62.463426 -388.636002) (xy 62.543732 -388.77494)
			(xy 63.08598 -388.77494) (xy 63.08598 -388.774432) (xy 63.086468 -388.75044) (xy 63.093969 -388.703047)
			(xy 63.108793 -388.657411) (xy 63.130573 -388.614656) (xy 63.158774 -388.575834) (xy 63.192701 -388.541902)
			(xy 63.231518 -388.513696) (xy 63.27427 -388.49191) (xy 63.319904 -388.47708) (xy 63.367296 -388.469571)
			(xy 63.391288 -388.469124) (xy 63.415225 -388.469532) (xy 63.462514 -388.476997) (xy 63.50806 -388.491747)
			(xy 63.550747 -388.513419) (xy 63.589533 -388.541485) (xy 63.623466 -388.575256) (xy 63.651716 -388.613907)
			(xy 63.663068 -388.634986) (xy 63.663576 -388.636002) (xy 63.743882 -388.77494) (xy 64.285876 -388.77494)
			(xy 64.285876 -388.774432) (xy 64.286368 -388.750441) (xy 64.293869 -388.703048) (xy 64.308692 -388.657412)
			(xy 64.330472 -388.614657) (xy 64.358673 -388.575836) (xy 64.392599 -388.541904) (xy 64.431416 -388.513697)
			(xy 64.474167 -388.491911) (xy 64.519801 -388.47708) (xy 64.567193 -388.469571) (xy 64.591184 -388.469124)
			(xy 64.615121 -388.469535) (xy 64.66241 -388.477) (xy 64.707955 -388.491749) (xy 64.750643 -388.513421)
			(xy 64.789428 -388.541486) (xy 64.823361 -388.575257) (xy 64.851612 -388.613907) (xy 64.862964 -388.634986)
			(xy 64.863472 -388.636002) (xy 64.943778 -388.77494) (xy 65.485772 -388.77494) (xy 65.485772 -388.774432)
			(xy 65.486291 -388.750455) (xy 65.493784 -388.703091) (xy 65.50859 -388.657481) (xy 65.530346 -388.614747)
			(xy 65.558516 -388.57594) (xy 65.592407 -388.542015) (xy 65.631185 -388.513806) (xy 65.673898 -388.492007)
			(xy 65.719493 -388.477155) (xy 65.76685 -388.469615) (xy 65.790826 -388.469124) (xy 65.791334 -388.469124)
			(xy 65.81527 -388.469576) (xy 65.862556 -388.477033) (xy 65.908101 -388.491774) (xy 65.950789 -388.51344)
			(xy 65.989575 -388.541499) (xy 66.023509 -388.575264) (xy 66.051761 -388.613909) (xy 66.063114 -388.634986)
			(xy 66.063622 -388.636002) (xy 66.143928 -388.77494) (xy 80.013556 -388.77494) (xy 80.013556 -388.774432)
			(xy 80.014091 -388.750456) (xy 80.021583 -388.703093) (xy 80.036389 -388.657485) (xy 80.058143 -388.614751)
			(xy 80.086311 -388.575945) (xy 80.1202 -388.54202) (xy 80.158977 -388.513811) (xy 80.201687 -388.492012)
			(xy 80.24728 -388.477159) (xy 80.294635 -388.469616) (xy 80.31861 -388.469124) (xy 80.319118 -388.469124)
			(xy 80.343053 -388.469589) (xy 80.390339 -388.477043) (xy 80.435884 -388.491783) (xy 80.478571 -388.513446)
			(xy 80.517357 -388.541503) (xy 80.551292 -388.575266) (xy 80.579545 -388.61391) (xy 80.590898 -388.634986)
			(xy 80.591406 -388.636002) (xy 80.671712 -388.77494) (xy 81.213452 -388.77494) (xy 81.213452 -388.774432)
			(xy 81.213991 -388.750456) (xy 81.221483 -388.703094) (xy 81.236288 -388.657485) (xy 81.258042 -388.614753)
			(xy 81.28621 -388.575947) (xy 81.320098 -388.542022) (xy 81.358874 -388.513813) (xy 81.401584 -388.492013)
			(xy 81.447176 -388.477159) (xy 81.494531 -388.469617) (xy 81.518506 -388.469124) (xy 81.519014 -388.469124)
			(xy 81.542949 -388.469592) (xy 81.590235 -388.477046) (xy 81.635779 -388.491785) (xy 81.678467 -388.513447)
			(xy 81.717253 -388.541504) (xy 81.751188 -388.575267) (xy 81.779441 -388.61391) (xy 81.790794 -388.634986)
			(xy 81.791302 -388.636002) (xy 81.871608 -388.77494) (xy 82.413348 -388.77494) (xy 82.413348 -388.774432)
			(xy 82.413891 -388.750456) (xy 82.421383 -388.703095) (xy 82.436188 -388.657486) (xy 82.457941 -388.614754)
			(xy 82.486109 -388.575948) (xy 82.519997 -388.542023) (xy 82.558772 -388.513814) (xy 82.601481 -388.492014)
			(xy 82.647073 -388.47716) (xy 82.694427 -388.469617) (xy 82.718402 -388.469124) (xy 82.71891 -388.469124)
			(xy 82.742845 -388.469595) (xy 82.790131 -388.477049) (xy 82.835675 -388.491787) (xy 82.878363 -388.513449)
			(xy 82.917149 -388.541505) (xy 82.951084 -388.575267) (xy 82.979337 -388.61391) (xy 82.99069 -388.634986)
			(xy 82.991198 -388.636002) (xy 83.071504 -388.77494) (xy 83.613752 -388.77494) (xy 83.613752 -388.774432)
			(xy 83.614292 -388.750444) (xy 83.621792 -388.703057) (xy 83.636613 -388.657427) (xy 83.658389 -388.614677)
			(xy 83.686584 -388.57586) (xy 83.720505 -388.541931) (xy 83.759315 -388.513726) (xy 83.80206 -388.49194)
			(xy 83.847687 -388.477109) (xy 83.895072 -388.469598) (xy 83.91906 -388.469124) (xy 83.942996 -388.469555)
			(xy 83.990284 -388.477016) (xy 84.035829 -388.491761) (xy 84.078517 -388.51343) (xy 84.117303 -388.541492)
			(xy 84.151236 -388.57526) (xy 84.179488 -388.613908) (xy 84.19084 -388.634986) (xy 84.191348 -388.636002)
			(xy 84.271654 -388.77494) (xy 84.813648 -388.77494) (xy 84.813648 -388.774432) (xy 84.814192 -388.750444)
			(xy 84.821692 -388.703057) (xy 84.836512 -388.657428) (xy 84.858288 -388.614678) (xy 84.886483 -388.575861)
			(xy 84.920403 -388.541933) (xy 84.959213 -388.513728) (xy 85.001957 -388.491941) (xy 85.047583 -388.47711)
			(xy 85.094968 -388.469598) (xy 85.118956 -388.469124) (xy 85.142892 -388.469558) (xy 85.19018 -388.477018)
			(xy 85.235725 -388.491763) (xy 85.278413 -388.513431) (xy 85.317198 -388.541493) (xy 85.351132 -388.575261)
			(xy 85.379383 -388.613908) (xy 85.390736 -388.634986) (xy 85.391244 -388.636002) (xy 85.47155 -388.77494)
			(xy 86.013544 -388.77494) (xy 86.013544 -388.774432) (xy 86.014091 -388.750457) (xy 86.021583 -388.703095)
			(xy 86.036387 -388.657487) (xy 86.058141 -388.614755) (xy 86.086307 -388.575949) (xy 86.120195 -388.542025)
			(xy 86.15897 -388.513815) (xy 86.201678 -388.492016) (xy 86.24727 -388.477161) (xy 86.294623 -388.469617)
			(xy 86.318598 -388.469124) (xy 86.319106 -388.469124) (xy 86.343041 -388.469599) (xy 86.390326 -388.477051)
			(xy 86.435871 -388.491789) (xy 86.478558 -388.51345) (xy 86.517345 -388.541506) (xy 86.55128 -388.575268)
			(xy 86.579533 -388.61391) (xy 86.590886 -388.634986) (xy 86.591394 -388.636002) (xy 86.6717 -388.77494)
			(xy 87.21344 -388.77494) (xy 87.21344 -388.774432) (xy 87.213891 -388.750452) (xy 87.221386 -388.703081)
			(xy 87.236197 -388.657465) (xy 87.257958 -388.614726) (xy 87.286136 -388.575917) (xy 87.320035 -388.54199)
			(xy 87.358823 -388.513783) (xy 87.401545 -388.491988) (xy 87.447149 -388.477142) (xy 87.494514 -388.46961)
			(xy 87.518494 -388.469124) (xy 87.519002 -388.469124) (xy 87.542937 -388.469602) (xy 87.590222 -388.477054)
			(xy 87.635766 -388.491791) (xy 87.678454 -388.513452) (xy 87.71724 -388.541507) (xy 87.751175 -388.575268)
			(xy 87.779429 -388.61391) (xy 87.790782 -388.634986) (xy 87.79129 -388.636002) (xy 87.871596 -388.77494)
			(xy 88.413336 -388.77494) (xy 88.413336 -388.774432) (xy 88.413791 -388.750452) (xy 88.421286 -388.703082)
			(xy 88.436096 -388.657466) (xy 88.457858 -388.614728) (xy 88.486034 -388.575918) (xy 88.519934 -388.541992)
			(xy 88.558721 -388.513784) (xy 88.601442 -388.491989) (xy 88.647046 -388.477143) (xy 88.69441 -388.46961)
			(xy 88.71839 -388.469124) (xy 88.718898 -388.469124) (xy 88.742835 -388.469524) (xy 88.790125 -388.476991)
			(xy 88.835671 -388.491741) (xy 88.878358 -388.513415) (xy 88.917143 -388.541482) (xy 88.951076 -388.575255)
			(xy 88.979326 -388.613906) (xy 88.990678 -388.634986) (xy 88.991186 -388.636002) (xy 89.071492 -388.77494)
			(xy 89.61374 -388.77494) (xy 89.61374 -388.774432) (xy 89.614168 -388.750437) (xy 89.621671 -388.703038)
			(xy 89.636498 -388.657397) (xy 89.658284 -388.614638) (xy 89.686491 -388.575814) (xy 89.720426 -388.541881)
			(xy 89.759251 -388.513676) (xy 89.802012 -388.491892) (xy 89.847654 -388.477068) (xy 89.895053 -388.469567)
			(xy 89.919048 -388.469124) (xy 89.942984 -388.469565) (xy 89.990271 -388.477024) (xy 90.035816 -388.491767)
			(xy 90.078504 -388.513434) (xy 90.11729 -388.541495) (xy 90.151224 -388.575262) (xy 90.179475 -388.613908)
			(xy 90.190828 -388.634986) (xy 90.191336 -388.636002) (xy 90.271642 -388.77494) (xy 90.813636 -388.77494)
			(xy 90.813636 -388.774432) (xy 90.814068 -388.750438) (xy 90.821571 -388.703039) (xy 90.836398 -388.657398)
			(xy 90.858183 -388.614639) (xy 90.88639 -388.575815) (xy 90.920324 -388.541882) (xy 90.959149 -388.513677)
			(xy 91.001909 -388.491893) (xy 91.047551 -388.477068) (xy 91.09495 -388.469567) (xy 91.118944 -388.469124)
			(xy 91.14288 -388.469568) (xy 91.190167 -388.477026) (xy 91.235712 -388.491769) (xy 91.2784 -388.513436)
			(xy 91.317185 -388.541496) (xy 91.351119 -388.575262) (xy 91.379371 -388.613909) (xy 91.390724 -388.634986)
			(xy 91.391232 -388.636002) (xy 91.471538 -388.77494) (xy 92.013532 -388.77494) (xy 92.013532 -388.774432)
			(xy 92.013991 -388.750452) (xy 92.021486 -388.703082) (xy 92.036296 -388.657467) (xy 92.058057 -388.614729)
			(xy 92.086233 -388.575919) (xy 92.120132 -388.541993) (xy 92.158919 -388.513786) (xy 92.201639 -388.49199)
			(xy 92.247243 -388.477143) (xy 92.294607 -388.469611) (xy 92.318586 -388.469124) (xy 92.319094 -388.469124)
			(xy 92.343031 -388.469527) (xy 92.39032 -388.476993) (xy 92.435866 -388.491744) (xy 92.478554 -388.513417)
			(xy 92.517339 -388.541483) (xy 92.551272 -388.575255) (xy 92.579522 -388.613906) (xy 92.590874 -388.634986)
			(xy 92.591382 -388.636002) (xy 92.671688 -388.77494) (xy 93.213428 -388.77494) (xy 93.213428 -388.774432)
			(xy 93.213891 -388.750453) (xy 93.221386 -388.703083) (xy 93.236196 -388.657468) (xy 93.257956 -388.61473)
			(xy 93.286132 -388.575921) (xy 93.32003 -388.541995) (xy 93.358817 -388.513787) (xy 93.401537 -388.491991)
			(xy 93.447139 -388.477144) (xy 93.494503 -388.469611) (xy 93.518482 -388.469124) (xy 93.51899 -388.469124)
			(xy 93.542927 -388.46953) (xy 93.590216 -388.476996) (xy 93.635762 -388.491746) (xy 93.67845 -388.513419)
			(xy 93.717235 -388.541484) (xy 93.751168 -388.575256) (xy 93.779418 -388.613907) (xy 93.79077 -388.634986)
			(xy 93.791278 -388.636002) (xy 93.871584 -388.77494) (xy 94.413324 -388.77494) (xy 94.413324 -388.774432)
			(xy 94.413791 -388.750453) (xy 94.421286 -388.703083) (xy 94.436095 -388.657469) (xy 94.457855 -388.614731)
			(xy 94.486031 -388.575922) (xy 94.519929 -388.541996) (xy 94.558714 -388.513788) (xy 94.601434 -388.491993)
			(xy 94.647036 -388.477145) (xy 94.694399 -388.469611) (xy 94.718378 -388.469124) (xy 94.718886 -388.469124)
			(xy 94.742823 -388.469534) (xy 94.790112 -388.476998) (xy 94.835657 -388.491748) (xy 94.878345 -388.51342)
			(xy 94.91713 -388.541485) (xy 94.951064 -388.575256) (xy 94.979314 -388.613907) (xy 94.990666 -388.634986)
			(xy 94.991174 -388.636002) (xy 95.07148 -388.77494) (xy 95.613728 -388.77494) (xy 95.613728 -388.774432)
			(xy 95.614168 -388.750438) (xy 95.621671 -388.70304) (xy 95.636497 -388.6574) (xy 95.658282 -388.614641)
			(xy 95.686488 -388.575818) (xy 95.720421 -388.541885) (xy 95.759245 -388.51368) (xy 95.802004 -388.491896)
			(xy 95.847644 -388.47707) (xy 95.895042 -388.469568) (xy 95.919036 -388.469124) (xy 95.942972 -388.469574)
			(xy 95.990258 -388.477031) (xy 96.035803 -388.491773) (xy 96.078491 -388.513439) (xy 96.117277 -388.541498)
			(xy 96.151211 -388.575264) (xy 96.179463 -388.613909) (xy 96.190816 -388.634986) (xy 96.191324 -388.636002)
			(xy 96.27163 -388.77494) (xy 96.813624 -388.77494) (xy 96.813624 -388.774432) (xy 96.814068 -388.750438)
			(xy 96.821571 -388.703041) (xy 96.836397 -388.657401) (xy 96.858181 -388.614643) (xy 96.886387 -388.575819)
			(xy 96.920319 -388.541887) (xy 96.959143 -388.513681) (xy 97.001901 -388.491897) (xy 97.047541 -388.477071)
			(xy 97.094938 -388.469568) (xy 97.118932 -388.469124) (xy 97.142868 -388.469578) (xy 97.190154 -388.477034)
			(xy 97.235699 -388.491775) (xy 97.278387 -388.51344) (xy 97.317172 -388.541499) (xy 97.351107 -388.575264)
			(xy 97.379359 -388.613909) (xy 97.390712 -388.634986) (xy 97.39122 -388.636002) (xy 97.471526 -388.77494)
			(xy 98.01352 -388.77494) (xy 98.01352 -388.774432) (xy 98.013991 -388.750453) (xy 98.021485 -388.703084)
			(xy 98.036295 -388.65747) (xy 98.058055 -388.614732) (xy 98.08623 -388.575923) (xy 98.120127 -388.541998)
			(xy 98.158912 -388.51379) (xy 98.201631 -388.491994) (xy 98.247233 -388.477146) (xy 98.294595 -388.469612)
			(xy 98.318574 -388.469124) (xy 98.319082 -388.469124) (xy 98.343019 -388.469537) (xy 98.390308 -388.477001)
			(xy 98.435853 -388.49175) (xy 98.478541 -388.513422) (xy 98.517326 -388.541486) (xy 98.551259 -388.575257)
			(xy 98.57951 -388.613907) (xy 98.590862 -388.634986) (xy 98.59137 -388.636002) (xy 98.671676 -388.77494)
			(xy 114.586004 -388.77494) (xy 114.586004 -388.774432) (xy 114.586468 -388.750439) (xy 114.59397 -388.703044)
			(xy 114.608795 -388.657405) (xy 114.630577 -388.614648) (xy 114.658781 -388.575826) (xy 114.692711 -388.541894)
			(xy 114.731531 -388.513688) (xy 114.774287 -388.491903) (xy 114.819924 -388.477075) (xy 114.867319 -388.469569)
			(xy 114.891312 -388.469124) (xy 114.915247 -388.469594) (xy 114.962533 -388.477047) (xy 115.008077 -388.491786)
			(xy 115.050765 -388.513448) (xy 115.089551 -388.541504) (xy 115.123486 -388.575267) (xy 115.151739 -388.61391)
			(xy 115.163092 -388.634986) (xy 115.1636 -388.636002) (xy 115.243906 -388.77494) (xy 115.7859 -388.77494)
			(xy 115.7859 -388.774432) (xy 115.786368 -388.750439) (xy 115.79387 -388.703044) (xy 115.808695 -388.657406)
			(xy 115.830477 -388.61465) (xy 115.85868 -388.575827) (xy 115.892609 -388.541895) (xy 115.931429 -388.513689)
			(xy 115.974184 -388.491904) (xy 116.019821 -388.477076) (xy 116.067215 -388.46957) (xy 116.091208 -388.469124)
			(xy 116.115143 -388.469597) (xy 116.162429 -388.47705) (xy 116.207973 -388.491788) (xy 116.250661 -388.51345)
			(xy 116.289447 -388.541505) (xy 116.323382 -388.575268) (xy 116.351635 -388.61391) (xy 116.362988 -388.634986)
			(xy 116.363496 -388.636002) (xy 116.443802 -388.77494) (xy 116.985796 -388.77494) (xy 116.985796 -388.774432)
			(xy 116.986268 -388.75044) (xy 116.99377 -388.703045) (xy 117.008594 -388.657407) (xy 117.030376 -388.614651)
			(xy 117.058578 -388.575829) (xy 117.092507 -388.541897) (xy 117.131327 -388.513691) (xy 117.174081 -388.491905)
			(xy 117.219717 -388.477076) (xy 117.267112 -388.46957) (xy 117.291104 -388.469124) (xy 117.315039 -388.4696)
			(xy 117.362324 -388.477053) (xy 117.407868 -388.49179) (xy 117.450556 -388.513451) (xy 117.489342 -388.541506)
			(xy 117.523277 -388.575268) (xy 117.551531 -388.61391) (xy 117.562884 -388.634986) (xy 117.563392 -388.636002)
			(xy 117.643698 -388.77494) (xy 118.185692 -388.77494) (xy 118.185692 -388.774432) (xy 118.186191 -388.750454)
			(xy 118.193684 -388.703088) (xy 118.208492 -388.657476) (xy 118.230249 -388.614741) (xy 118.258422 -388.575933)
			(xy 118.292315 -388.542008) (xy 118.331097 -388.513799) (xy 118.373812 -388.492002) (xy 118.41941 -388.477151)
			(xy 118.466769 -388.469614) (xy 118.490746 -388.469124) (xy 118.491254 -388.469124) (xy 118.51519 -388.46956)
			(xy 118.562478 -388.47702) (xy 118.608023 -388.491764) (xy 118.650711 -388.513432) (xy 118.689496 -388.541493)
			(xy 118.72343 -388.575261) (xy 118.751681 -388.613908) (xy 118.763034 -388.634986) (xy 118.763542 -388.636002)
			(xy 118.843848 -388.77494) (xy 119.385588 -388.77494) (xy 119.385588 -388.774432) (xy 119.386091 -388.750455)
			(xy 119.393584 -388.703089) (xy 119.408392 -388.657477) (xy 119.430149 -388.614742) (xy 119.45832 -388.575934)
			(xy 119.492213 -388.542009) (xy 119.530994 -388.513801) (xy 119.573709 -388.492003) (xy 119.619306 -388.477152)
			(xy 119.666665 -388.469614) (xy 119.690642 -388.469124) (xy 119.69115 -388.469124) (xy 119.715086 -388.469563)
			(xy 119.762373 -388.477022) (xy 119.807918 -388.491766) (xy 119.850606 -388.513434) (xy 119.889392 -388.541494)
			(xy 119.923326 -388.575262) (xy 119.951577 -388.613908) (xy 119.96293 -388.634986) (xy 119.963438 -388.636002)
			(xy 120.043744 -388.77494) (xy 120.585992 -388.77494) (xy 120.585992 -388.774432) (xy 120.586468 -388.75044)
			(xy 120.59397 -388.703045) (xy 120.608794 -388.657408) (xy 120.630575 -388.614652) (xy 120.658777 -388.57583)
			(xy 120.692706 -388.541898) (xy 120.731525 -388.513692) (xy 120.774279 -388.491906) (xy 120.819914 -388.477077)
			(xy 120.867308 -388.46957) (xy 120.8913 -388.469124) (xy 120.915235 -388.469603) (xy 120.96252 -388.477055)
			(xy 121.008064 -388.491792) (xy 121.050752 -388.513453) (xy 121.089538 -388.541507) (xy 121.123473 -388.575269)
			(xy 121.151726 -388.613911) (xy 121.16308 -388.634986) (xy 121.163588 -388.636002) (xy 121.243894 -388.77494)
			(xy 121.785888 -388.77494) (xy 121.785888 -388.774432) (xy 121.786368 -388.75044) (xy 121.79387 -388.703046)
			(xy 121.808693 -388.657409) (xy 121.830474 -388.614653) (xy 121.858676 -388.575831) (xy 121.892604 -388.5419)
			(xy 121.931423 -388.513693) (xy 121.974176 -388.491907) (xy 122.019811 -388.477078) (xy 122.067204 -388.469571)
			(xy 122.091196 -388.469124) (xy 122.115133 -388.469526) (xy 122.162423 -388.476992) (xy 122.207968 -388.491742)
			(xy 122.250656 -388.513416) (xy 122.289441 -388.541483) (xy 122.323374 -388.575255) (xy 122.351624 -388.613906)
			(xy 122.362976 -388.634986) (xy 122.363484 -388.636002) (xy 122.44379 -388.77494) (xy 122.985784 -388.77494)
			(xy 122.985784 -388.774432) (xy 122.986268 -388.75044) (xy 122.993769 -388.703046) (xy 123.008593 -388.65741)
			(xy 123.030374 -388.614654) (xy 123.058575 -388.575833) (xy 123.092502 -388.541901) (xy 123.13132 -388.513695)
			(xy 123.174073 -388.491908) (xy 123.219708 -388.477079) (xy 123.2671 -388.469571) (xy 123.291092 -388.469124)
			(xy 123.315029 -388.469529) (xy 123.362318 -388.476995) (xy 123.407864 -388.491745) (xy 123.450552 -388.513418)
			(xy 123.489337 -388.541484) (xy 123.52327 -388.575256) (xy 123.55152 -388.613906) (xy 123.562872 -388.634986)
			(xy 123.56338 -388.636002) (xy 123.643686 -388.77494) (xy 124.18568 -388.77494) (xy 124.18568 -388.774432)
			(xy 124.186191 -388.750455) (xy 124.193684 -388.70309) (xy 124.208491 -388.657479) (xy 124.230247 -388.614744)
			(xy 124.258418 -388.575937) (xy 124.29231 -388.542012) (xy 124.33109 -388.513803) (xy 124.373803 -388.492005)
			(xy 124.4194 -388.477154) (xy 124.466757 -388.469614) (xy 124.490734 -388.469124) (xy 124.491242 -388.469124)
			(xy 124.515178 -388.469569) (xy 124.562465 -388.477028) (xy 124.60801 -388.49177) (xy 124.650697 -388.513437)
			(xy 124.689483 -388.541496) (xy 124.723417 -388.575263) (xy 124.751669 -388.613909) (xy 124.763022 -388.634986)
			(xy 124.76353 -388.636002) (xy 124.843836 -388.77494) (xy 125.385576 -388.77494) (xy 125.385576 -388.774432)
			(xy 125.386091 -388.750455) (xy 125.393584 -388.70309) (xy 125.408391 -388.65748) (xy 125.430147 -388.614746)
			(xy 125.458317 -388.575938) (xy 125.492208 -388.542013) (xy 125.530988 -388.513805) (xy 125.573701 -388.492006)
			(xy 125.619296 -388.477155) (xy 125.666654 -388.469615) (xy 125.69063 -388.469124) (xy 125.691138 -388.469124)
			(xy 125.715074 -388.469573) (xy 125.762361 -388.47703) (xy 125.807905 -388.491772) (xy 125.850593 -388.513438)
			(xy 125.889379 -388.541498) (xy 125.923313 -388.575263) (xy 125.951565 -388.613909) (xy 125.962918 -388.634986)
			(xy 125.963426 -388.636002) (xy 126.043732 -388.77494) (xy 126.58598 -388.77494) (xy 126.58598 -388.774432)
			(xy 126.586468 -388.75044) (xy 126.593969 -388.703047) (xy 126.608793 -388.657411) (xy 126.630573 -388.614656)
			(xy 126.658774 -388.575834) (xy 126.692701 -388.541902) (xy 126.731518 -388.513696) (xy 126.77427 -388.49191)
			(xy 126.819904 -388.47708) (xy 126.867296 -388.469571) (xy 126.891288 -388.469124) (xy 126.915225 -388.469532)
			(xy 126.962514 -388.476997) (xy 127.00806 -388.491747) (xy 127.050747 -388.513419) (xy 127.089533 -388.541485)
			(xy 127.123466 -388.575256) (xy 127.151716 -388.613907) (xy 127.163068 -388.634986) (xy 127.163576 -388.636002)
			(xy 127.243882 -388.77494) (xy 127.785876 -388.77494) (xy 127.785876 -388.774432) (xy 127.786368 -388.750441)
			(xy 127.793869 -388.703048) (xy 127.808692 -388.657412) (xy 127.830472 -388.614657) (xy 127.858673 -388.575836)
			(xy 127.892599 -388.541904) (xy 127.931416 -388.513697) (xy 127.974167 -388.491911) (xy 128.019801 -388.47708)
			(xy 128.067193 -388.469571) (xy 128.091184 -388.469124) (xy 128.115121 -388.469535) (xy 128.16241 -388.477)
			(xy 128.207955 -388.491749) (xy 128.250643 -388.513421) (xy 128.289428 -388.541486) (xy 128.323361 -388.575257)
			(xy 128.351612 -388.613907) (xy 128.362964 -388.634986) (xy 128.363472 -388.636002) (xy 128.443778 -388.77494)
			(xy 128.985772 -388.77494) (xy 128.985772 -388.774432) (xy 128.986268 -388.750441) (xy 128.993769 -388.703048)
			(xy 129.008592 -388.657413) (xy 129.030372 -388.614658) (xy 129.058571 -388.575837) (xy 129.092497 -388.541905)
			(xy 129.131314 -388.513699) (xy 129.174065 -388.491912) (xy 129.219698 -388.477081) (xy 129.267089 -388.469572)
			(xy 129.29108 -388.469124) (xy 129.315017 -388.469539) (xy 129.362305 -388.477002) (xy 129.407851 -388.491751)
			(xy 129.450539 -388.513422) (xy 129.489324 -388.541487) (xy 129.523257 -388.575257) (xy 129.551508 -388.613907)
			(xy 129.56286 -388.634986) (xy 129.563368 -388.636002) (xy 129.643674 -388.77494) (xy 130.185668 -388.77494)
			(xy 130.185668 -388.774432) (xy 130.186191 -388.750456) (xy 130.193684 -388.703092) (xy 130.20849 -388.657482)
			(xy 130.230245 -388.614748) (xy 130.258415 -388.575941) (xy 130.292305 -388.542016) (xy 130.331083 -388.513807)
			(xy 130.373795 -388.492009) (xy 130.41939 -388.477156) (xy 130.466746 -388.469615) (xy 130.490722 -388.469124)
			(xy 130.49123 -388.469124) (xy 130.515165 -388.469579) (xy 130.562452 -388.477035) (xy 130.607997 -388.491776)
			(xy 130.650684 -388.513441) (xy 130.68947 -388.5415) (xy 130.723405 -388.575264) (xy 130.751657 -388.613909)
			(xy 130.76301 -388.634986) (xy 130.763518 -388.636002) (xy 130.843824 -388.77494) (xy 131.385564 -388.77494)
			(xy 131.385564 -388.774432) (xy 131.386091 -388.750456) (xy 131.393583 -388.703092) (xy 131.408389 -388.657483)
			(xy 131.430144 -388.614749) (xy 131.458313 -388.575943) (xy 131.492203 -388.542018) (xy 131.530981 -388.513809)
			(xy 131.573692 -388.49201) (xy 131.619286 -388.477157) (xy 131.666642 -388.469616) (xy 131.690618 -388.469124)
			(xy 131.691126 -388.469124) (xy 131.715061 -388.469582) (xy 131.762348 -388.477038) (xy 131.807892 -388.491778)
			(xy 131.85058 -388.513443) (xy 131.889366 -388.541501) (xy 131.923301 -388.575265) (xy 131.951553 -388.613909)
			(xy 131.962906 -388.634986) (xy 131.963414 -388.636002) (xy 132.04372 -388.77494) (xy 132.585968 -388.77494)
			(xy 132.585968 -388.774432) (xy 132.586468 -388.750441) (xy 132.593969 -388.703049) (xy 132.608792 -388.657414)
			(xy 132.630571 -388.614659) (xy 132.65877 -388.575838) (xy 132.692696 -388.541907) (xy 132.731511 -388.5137)
			(xy 132.774262 -388.491913) (xy 132.819894 -388.477082) (xy 132.867285 -388.469572) (xy 132.891276 -388.469124)
			(xy 132.915213 -388.469542) (xy 132.962501 -388.477005) (xy 133.008047 -388.491753) (xy 133.050734 -388.513424)
			(xy 133.08952 -388.541488) (xy 133.123453 -388.575258) (xy 133.151704 -388.613907) (xy 133.163056 -388.634986)
			(xy 133.163564 -388.636002) (xy 133.24387 -388.77494) (xy 147.113752 -388.77494) (xy 147.113752 -388.774432)
			(xy 147.114292 -388.750444) (xy 147.121792 -388.703057) (xy 147.136613 -388.657427) (xy 147.158389 -388.614677)
			(xy 147.186584 -388.57586) (xy 147.220505 -388.541931) (xy 147.259315 -388.513726) (xy 147.30206 -388.49194)
			(xy 147.347687 -388.477109) (xy 147.395072 -388.469598) (xy 147.41906 -388.469124) (xy 147.442996 -388.469555)
			(xy 147.490284 -388.477016) (xy 147.535829 -388.491761) (xy 147.578517 -388.51343) (xy 147.617303 -388.541492)
			(xy 147.651236 -388.57526) (xy 147.679488 -388.613908) (xy 147.69084 -388.634986) (xy 147.691348 -388.636002)
			(xy 147.771654 -388.77494) (xy 148.313648 -388.77494) (xy 148.313648 -388.774432) (xy 148.314192 -388.750444)
			(xy 148.321692 -388.703057) (xy 148.336512 -388.657428) (xy 148.358288 -388.614678) (xy 148.386483 -388.575861)
			(xy 148.420403 -388.541933) (xy 148.459213 -388.513728) (xy 148.501957 -388.491941) (xy 148.547583 -388.47711)
			(xy 148.594968 -388.469598) (xy 148.618956 -388.469124) (xy 148.642892 -388.469558) (xy 148.69018 -388.477018)
			(xy 148.735725 -388.491763) (xy 148.778413 -388.513431) (xy 148.817198 -388.541493) (xy 148.851132 -388.575261)
			(xy 148.879383 -388.613908) (xy 148.890736 -388.634986) (xy 148.891244 -388.636002) (xy 148.97155 -388.77494)
			(xy 149.513544 -388.77494) (xy 149.513544 -388.774432) (xy 149.514092 -388.750444) (xy 149.521592 -388.703058)
			(xy 149.536412 -388.657429) (xy 149.558187 -388.614679) (xy 149.586382 -388.575862) (xy 149.620301 -388.541934)
			(xy 149.659111 -388.513729) (xy 149.701855 -388.491943) (xy 149.74748 -388.477111) (xy 149.794864 -388.469598)
			(xy 149.818852 -388.469124) (xy 149.842788 -388.469561) (xy 149.890076 -388.477021) (xy 149.935621 -388.491765)
			(xy 149.978308 -388.513433) (xy 150.017094 -388.541494) (xy 150.051028 -388.575261) (xy 150.079279 -388.613908)
			(xy 150.090632 -388.634986) (xy 150.09114 -388.636002) (xy 150.171446 -388.77494) (xy 150.71344 -388.77494)
			(xy 150.71344 -388.774432) (xy 150.713891 -388.750452) (xy 150.721386 -388.703081) (xy 150.736197 -388.657465)
			(xy 150.757958 -388.614726) (xy 150.786136 -388.575917) (xy 150.820035 -388.54199) (xy 150.858823 -388.513783)
			(xy 150.901545 -388.491988) (xy 150.947149 -388.477142) (xy 150.994514 -388.46961) (xy 151.018494 -388.469124)
			(xy 151.019002 -388.469124) (xy 151.042937 -388.469602) (xy 151.090222 -388.477054) (xy 151.135766 -388.491791)
			(xy 151.178454 -388.513452) (xy 151.21724 -388.541507) (xy 151.251175 -388.575268) (xy 151.279429 -388.61391)
			(xy 151.290782 -388.634986) (xy 151.29129 -388.636002) (xy 151.371596 -388.77494) (xy 151.913336 -388.77494)
			(xy 151.913336 -388.774432) (xy 151.913791 -388.750452) (xy 151.921286 -388.703082) (xy 151.936096 -388.657466)
			(xy 151.957858 -388.614728) (xy 151.986034 -388.575918) (xy 152.019934 -388.541992) (xy 152.058721 -388.513784)
			(xy 152.101442 -388.491989) (xy 152.147046 -388.477143) (xy 152.19441 -388.46961) (xy 152.21839 -388.469124)
			(xy 152.218898 -388.469124) (xy 152.242835 -388.469524) (xy 152.290125 -388.476991) (xy 152.335671 -388.491741)
			(xy 152.378358 -388.513415) (xy 152.417143 -388.541482) (xy 152.451076 -388.575255) (xy 152.479326 -388.613906)
			(xy 152.490678 -388.634986) (xy 152.491186 -388.636002) (xy 152.571492 -388.77494) (xy 153.11374 -388.77494)
			(xy 153.11374 -388.774432) (xy 153.114168 -388.750437) (xy 153.121671 -388.703038) (xy 153.136498 -388.657397)
			(xy 153.158284 -388.614638) (xy 153.186491 -388.575814) (xy 153.220426 -388.541881) (xy 153.259251 -388.513676)
			(xy 153.302012 -388.491892) (xy 153.347654 -388.477068) (xy 153.395053 -388.469567) (xy 153.419048 -388.469124)
			(xy 153.442984 -388.469565) (xy 153.490271 -388.477024) (xy 153.535816 -388.491767) (xy 153.578504 -388.513434)
			(xy 153.61729 -388.541495) (xy 153.651224 -388.575262) (xy 153.679475 -388.613908) (xy 153.690828 -388.634986)
			(xy 153.691336 -388.636002) (xy 153.771642 -388.77494) (xy 154.313636 -388.77494) (xy 154.313636 -388.774432)
			(xy 154.314068 -388.750438) (xy 154.321571 -388.703039) (xy 154.336398 -388.657398) (xy 154.358183 -388.614639)
			(xy 154.38639 -388.575815) (xy 154.420324 -388.541882) (xy 154.459149 -388.513677) (xy 154.501909 -388.491893)
			(xy 154.547551 -388.477068) (xy 154.59495 -388.469567) (xy 154.618944 -388.469124) (xy 154.64288 -388.469568)
			(xy 154.690167 -388.477026) (xy 154.735712 -388.491769) (xy 154.7784 -388.513436) (xy 154.817185 -388.541496)
			(xy 154.851119 -388.575262) (xy 154.879371 -388.613909) (xy 154.890724 -388.634986) (xy 154.891232 -388.636002)
			(xy 154.971538 -388.77494) (xy 155.513532 -388.77494) (xy 155.513532 -388.774432) (xy 155.513968 -388.750438)
			(xy 155.521471 -388.703039) (xy 155.536298 -388.657399) (xy 155.558083 -388.61464) (xy 155.586289 -388.575816)
			(xy 155.620222 -388.541884) (xy 155.659047 -388.513678) (xy 155.701806 -388.491895) (xy 155.747447 -388.477069)
			(xy 155.794846 -388.469567) (xy 155.81884 -388.469124) (xy 155.842776 -388.469571) (xy 155.890063 -388.477029)
			(xy 155.935608 -388.491771) (xy 155.978295 -388.513437) (xy 156.017081 -388.541497) (xy 156.051015 -388.575263)
			(xy 156.079267 -388.613909) (xy 156.09062 -388.634986) (xy 156.091128 -388.636002) (xy 156.171434 -388.77494)
			(xy 156.713428 -388.77494) (xy 156.713428 -388.774432) (xy 156.713891 -388.750453) (xy 156.721386 -388.703083)
			(xy 156.736196 -388.657468) (xy 156.757956 -388.61473) (xy 156.786132 -388.575921) (xy 156.82003 -388.541995)
			(xy 156.858817 -388.513787) (xy 156.901537 -388.491991) (xy 156.947139 -388.477144) (xy 156.994503 -388.469611)
			(xy 157.018482 -388.469124) (xy 157.01899 -388.469124) (xy 157.042927 -388.46953) (xy 157.090216 -388.476996)
			(xy 157.135762 -388.491746) (xy 157.17845 -388.513419) (xy 157.217235 -388.541484) (xy 157.251168 -388.575256)
			(xy 157.279418 -388.613907) (xy 157.29077 -388.634986) (xy 157.291278 -388.636002) (xy 157.371584 -388.77494)
			(xy 157.913324 -388.77494) (xy 157.913324 -388.774432) (xy 157.913791 -388.750453) (xy 157.921286 -388.703083)
			(xy 157.936095 -388.657469) (xy 157.957855 -388.614731) (xy 157.986031 -388.575922) (xy 158.019929 -388.541996)
			(xy 158.058714 -388.513788) (xy 158.101434 -388.491993) (xy 158.147036 -388.477145) (xy 158.194399 -388.469611)
			(xy 158.218378 -388.469124) (xy 158.218886 -388.469124) (xy 158.242823 -388.469534) (xy 158.290112 -388.476998)
			(xy 158.335657 -388.491748) (xy 158.378345 -388.51342) (xy 158.41713 -388.541485) (xy 158.451064 -388.575256)
			(xy 158.479314 -388.613907) (xy 158.490666 -388.634986) (xy 158.491174 -388.636002) (xy 158.57148 -388.77494)
			(xy 159.113728 -388.77494) (xy 159.113728 -388.774432) (xy 159.114168 -388.750438) (xy 159.121671 -388.70304)
			(xy 159.136497 -388.6574) (xy 159.158282 -388.614641) (xy 159.186488 -388.575818) (xy 159.220421 -388.541885)
			(xy 159.259245 -388.51368) (xy 159.302004 -388.491896) (xy 159.347644 -388.47707) (xy 159.395042 -388.469568)
			(xy 159.419036 -388.469124) (xy 159.442972 -388.469574) (xy 159.490258 -388.477031) (xy 159.535803 -388.491773)
			(xy 159.578491 -388.513439) (xy 159.617277 -388.541498) (xy 159.651211 -388.575264) (xy 159.679463 -388.613909)
			(xy 159.690816 -388.634986) (xy 159.691324 -388.636002) (xy 159.77163 -388.77494) (xy 160.313624 -388.77494)
			(xy 160.313624 -388.774432) (xy 160.314068 -388.750438) (xy 160.321571 -388.703041) (xy 160.336397 -388.657401)
			(xy 160.358181 -388.614643) (xy 160.386387 -388.575819) (xy 160.420319 -388.541887) (xy 160.459143 -388.513681)
			(xy 160.501901 -388.491897) (xy 160.547541 -388.477071) (xy 160.594938 -388.469568) (xy 160.618932 -388.469124)
			(xy 160.642868 -388.469578) (xy 160.690154 -388.477034) (xy 160.735699 -388.491775) (xy 160.778387 -388.51344)
			(xy 160.817172 -388.541499) (xy 160.851107 -388.575264) (xy 160.879359 -388.613909) (xy 160.890712 -388.634986)
			(xy 160.89122 -388.636002) (xy 160.971526 -388.77494) (xy 161.51352 -388.77494) (xy 161.51352 -388.774432)
			(xy 161.513968 -388.750438) (xy 161.521471 -388.703041) (xy 161.536297 -388.657402) (xy 161.55808 -388.614644)
			(xy 161.586286 -388.57582) (xy 161.620217 -388.541888) (xy 161.65904 -388.513682) (xy 161.701798 -388.491898)
			(xy 161.747437 -388.477072) (xy 161.794834 -388.469568) (xy 161.818828 -388.469124) (xy 161.842763 -388.469581)
			(xy 161.89005 -388.477037) (xy 161.935595 -388.491777) (xy 161.978282 -388.513442) (xy 162.017068 -388.5415)
			(xy 162.051003 -388.575265) (xy 162.079255 -388.613909) (xy 162.090608 -388.634986) (xy 162.091116 -388.636002)
			(xy 162.171422 -388.77494) (xy 162.713416 -388.77494) (xy 162.713416 -388.774432) (xy 162.713891 -388.750453)
			(xy 162.721385 -388.703085) (xy 162.736194 -388.657471) (xy 162.757954 -388.614734) (xy 162.786129 -388.575925)
			(xy 162.820025 -388.541999) (xy 162.85881 -388.513791) (xy 162.901528 -388.491995) (xy 162.947129 -388.477147)
			(xy 162.994492 -388.469612) (xy 163.01847 -388.469124) (xy 163.018978 -388.469124) (xy 163.042915 -388.46954)
			(xy 163.090203 -388.477004) (xy 163.135749 -388.491752) (xy 163.178437 -388.513423) (xy 163.217222 -388.541487)
			(xy 163.251155 -388.575258) (xy 163.279406 -388.613907) (xy 163.290758 -388.634986) (xy 163.291266 -388.636002)
			(xy 163.371572 -388.77494) (xy 163.913312 -388.77494) (xy 163.913312 -388.774432) (xy 163.913791 -388.750453)
			(xy 163.921285 -388.703085) (xy 163.936094 -388.657472) (xy 163.957853 -388.614735) (xy 163.986027 -388.575926)
			(xy 164.019924 -388.542) (xy 164.058708 -388.513792) (xy 164.101425 -388.491996) (xy 164.147026 -388.477147)
			(xy 164.194388 -388.469612) (xy 164.218366 -388.469124) (xy 164.218874 -388.469124) (xy 164.242811 -388.469543)
			(xy 164.290099 -388.477006) (xy 164.335644 -388.491754) (xy 164.378332 -388.513425) (xy 164.417118 -388.541488)
			(xy 164.451051 -388.575258) (xy 164.479302 -388.613907) (xy 164.490654 -388.634986) (xy 164.491162 -388.636002)
			(xy 164.571468 -388.77494) (xy 165.113716 -388.77494) (xy 165.113716 -388.774432) (xy 165.114168 -388.750439)
			(xy 165.121671 -388.703042) (xy 165.136496 -388.657403) (xy 165.15828 -388.614645) (xy 165.186484 -388.575822)
			(xy 165.220416 -388.54189) (xy 165.259238 -388.513684) (xy 165.301995 -388.491899) (xy 165.347634 -388.477072)
			(xy 165.395031 -388.469568) (xy 165.419024 -388.469124) (xy 165.442959 -388.469584) (xy 165.490246 -388.477039)
			(xy 165.53579 -388.491779) (xy 165.578478 -388.513444) (xy 165.617264 -388.541501) (xy 165.651198 -388.575265)
			(xy 165.679451 -388.61391) (xy 165.690804 -388.634986) (xy 165.691312 -388.636002) (xy 165.744132 -388.727385)
			(xy 193.900548 -388.727385) (xy 193.900548 -388.642663) (xy 193.908601 -388.558326) (xy 193.924635 -388.475136)
			(xy 193.948503 -388.393846) (xy 193.979991 -388.315194) (xy 194.018813 -388.239891) (xy 194.064616 -388.168619)
			(xy 194.116987 -388.102023) (xy 194.175452 -388.040708) (xy 194.23948 -387.985227) (xy 194.308492 -387.936084)
			(xy 194.381862 -387.893724) (xy 194.458927 -387.858529) (xy 194.538989 -387.83082) (xy 194.621322 -387.810846)
			(xy 194.705181 -387.798789) (xy 194.789806 -387.794758) (xy 194.874431 -387.798789) (xy 194.95829 -387.810846)
			(xy 195.040623 -387.83082) (xy 195.120685 -387.858529) (xy 195.19775 -387.893724) (xy 195.27112 -387.936084)
			(xy 195.340132 -387.985227) (xy 195.40416 -388.040708) (xy 195.462625 -388.102023) (xy 195.514996 -388.168619)
			(xy 195.560799 -388.239891) (xy 195.599621 -388.315194) (xy 195.631109 -388.393846) (xy 195.654977 -388.475136)
			(xy 195.671011 -388.558326) (xy 195.679064 -388.642663) (xy 195.679568 -388.685024) (xy 195.679064 -388.727385)
			(xy 195.671011 -388.811722) (xy 195.654977 -388.894912) (xy 195.631109 -388.976202) (xy 195.599621 -389.054854)
			(xy 195.560799 -389.130157) (xy 195.514996 -389.201429) (xy 195.462625 -389.268025) (xy 195.40416 -389.32934)
			(xy 195.340132 -389.384821) (xy 195.27112 -389.433964) (xy 195.19775 -389.476324) (xy 195.120685 -389.511519)
			(xy 195.040623 -389.539228) (xy 194.95829 -389.559202) (xy 194.874431 -389.571259) (xy 194.789806 -389.575291)
			(xy 194.705181 -389.571259) (xy 194.621322 -389.559202) (xy 194.538989 -389.539228) (xy 194.458927 -389.511519)
			(xy 194.381862 -389.476324) (xy 194.308492 -389.433964) (xy 194.23948 -389.384821) (xy 194.175452 -389.32934)
			(xy 194.116987 -389.268025) (xy 194.064616 -389.201429) (xy 194.018813 -389.130157) (xy 193.979991 -389.054854)
			(xy 193.948503 -388.976202) (xy 193.924635 -388.894912) (xy 193.908601 -388.811722) (xy 193.900548 -388.727385)
			(xy 165.744132 -388.727385) (xy 166.083742 -389.314944) (xy 166.096549 -389.338286) (xy 166.114776 -389.388304)
			(xy 166.124043 -389.440727) (xy 166.124636 -389.467344) (xy 166.124179 -389.491322) (xy 166.116675 -389.538688)
			(xy 166.101859 -389.584299) (xy 166.080095 -389.627033) (xy 166.051917 -389.665839) (xy 166.01802 -389.699762)
			(xy 165.979236 -389.72797) (xy 165.936519 -389.749768) (xy 165.89092 -389.76462) (xy 165.84356 -389.77216)
			(xy 165.819582 -389.772652) (xy 165.819074 -389.772652) (xy 165.795501 -389.772252) (xy 165.748914 -389.765008)
			(xy 165.703997 -389.750681) (xy 165.66182 -389.729613) (xy 165.623387 -389.702305) (xy 165.589614 -389.669408)
			(xy 165.561306 -389.631706) (xy 165.549834 -389.611108) (xy 165.549326 -389.610346) (xy 165.151562 -388.922006)
			(xy 165.139686 -388.899329) (xy 165.122835 -388.850996) (xy 165.114262 -388.800533) (xy 165.113716 -388.77494)
			(xy 164.571468 -388.77494) (xy 164.883592 -389.314944) (xy 164.896306 -389.338272) (xy 164.914407 -389.388215)
			(xy 164.923631 -389.44053) (xy 164.924232 -389.46709) (xy 164.924232 -389.467344) (xy 164.923778 -389.491335)
			(xy 164.916266 -389.538726) (xy 164.901434 -389.584359) (xy 164.879647 -389.62711) (xy 164.851442 -389.665927)
			(xy 164.817512 -389.699855) (xy 164.778693 -389.728058) (xy 164.73594 -389.749842) (xy 164.690307 -389.764671)
			(xy 164.642915 -389.77218) (xy 164.618924 -389.772652) (xy 164.595352 -389.772211) (xy 164.548767 -389.764975)
			(xy 164.503851 -389.750656) (xy 164.461674 -389.729594) (xy 164.423241 -389.702292) (xy 164.389467 -389.669401)
			(xy 164.361157 -389.631704) (xy 164.349684 -389.611108) (xy 164.349176 -389.610346) (xy 163.951412 -388.922006)
			(xy 163.939498 -388.899337) (xy 163.92256 -388.851012) (xy 163.9139 -388.800542) (xy 163.913312 -388.77494)
			(xy 163.371572 -388.77494) (xy 163.683696 -389.314944) (xy 163.69641 -389.338271) (xy 163.714511 -389.388215)
			(xy 163.723735 -389.44053) (xy 163.724336 -389.46709) (xy 163.724336 -389.467344) (xy 163.723878 -389.491335)
			(xy 163.716366 -389.538726) (xy 163.701535 -389.584358) (xy 163.679748 -389.627109) (xy 163.651543 -389.665926)
			(xy 163.617613 -389.699853) (xy 163.578795 -389.728056) (xy 163.536043 -389.749841) (xy 163.49041 -389.76467)
			(xy 163.443019 -389.772179) (xy 163.419028 -389.772652) (xy 163.395456 -389.772208) (xy 163.348872 -389.764972)
			(xy 163.303956 -389.750653) (xy 163.261778 -389.729592) (xy 163.223345 -389.702291) (xy 163.189571 -389.6694)
			(xy 163.161261 -389.631704) (xy 163.149788 -389.611108) (xy 163.14928 -389.610346) (xy 162.751516 -388.922006)
			(xy 162.739602 -388.899337) (xy 162.722664 -388.851012) (xy 162.714004 -388.800542) (xy 162.713416 -388.77494)
			(xy 162.171422 -388.77494) (xy 162.483546 -389.314944) (xy 162.496353 -389.338286) (xy 162.51458 -389.388304)
			(xy 162.523847 -389.440727) (xy 162.52444 -389.467344) (xy 162.523979 -389.491322) (xy 162.516475 -389.538688)
			(xy 162.501659 -389.584298) (xy 162.479895 -389.627032) (xy 162.451718 -389.665837) (xy 162.417822 -389.699761)
			(xy 162.379038 -389.727969) (xy 162.336322 -389.749767) (xy 162.290724 -389.764619) (xy 162.243364 -389.77216)
			(xy 162.219386 -389.772652) (xy 162.218878 -389.772652) (xy 162.195305 -389.772249) (xy 162.148718 -389.765005)
			(xy 162.103801 -389.750679) (xy 162.061624 -389.729611) (xy 162.023191 -389.702304) (xy 161.989418 -389.669408)
			(xy 161.96111 -389.631706) (xy 161.949638 -389.611108) (xy 161.94913 -389.610346) (xy 161.551366 -388.922006)
			(xy 161.539491 -388.899329) (xy 161.522639 -388.850996) (xy 161.514066 -388.800533) (xy 161.51352 -388.77494)
			(xy 160.971526 -388.77494) (xy 161.28365 -389.314944) (xy 161.296457 -389.338285) (xy 161.314684 -389.388304)
			(xy 161.323951 -389.440726) (xy 161.324544 -389.467344) (xy 161.324079 -389.491322) (xy 161.316576 -389.538687)
			(xy 161.30176 -389.584297) (xy 161.279996 -389.62703) (xy 161.25182 -389.665836) (xy 161.217923 -389.69976)
			(xy 161.17914 -389.727967) (xy 161.136425 -389.749765) (xy 161.090827 -389.764618) (xy 161.043468 -389.77216)
			(xy 161.01949 -389.772652) (xy 161.018982 -389.772652) (xy 160.995409 -389.772245) (xy 160.948822 -389.765003)
			(xy 160.903906 -389.750677) (xy 160.861728 -389.72961) (xy 160.823295 -389.702303) (xy 160.789523 -389.669407)
			(xy 160.761214 -389.631706) (xy 160.749742 -389.611108) (xy 160.749234 -389.610346) (xy 160.35147 -388.922006)
			(xy 160.339595 -388.899329) (xy 160.322743 -388.850996) (xy 160.31417 -388.800533) (xy 160.313624 -388.77494)
			(xy 159.77163 -388.77494) (xy 160.083754 -389.314944) (xy 160.096562 -389.338285) (xy 160.114788 -389.388304)
			(xy 160.124055 -389.440726) (xy 160.124648 -389.467344) (xy 160.124179 -389.491322) (xy 160.116676 -389.538687)
			(xy 160.10186 -389.584296) (xy 160.080097 -389.627029) (xy 160.051921 -389.665835) (xy 160.018025 -389.699758)
			(xy 159.979243 -389.727966) (xy 159.936528 -389.749764) (xy 159.89093 -389.764617) (xy 159.843571 -389.772159)
			(xy 159.819594 -389.772652) (xy 159.819086 -389.772652) (xy 159.795513 -389.772242) (xy 159.748927 -389.765)
			(xy 159.70401 -389.750675) (xy 159.661833 -389.729608) (xy 159.6234 -389.702302) (xy 159.589627 -389.669406)
			(xy 159.561319 -389.631705) (xy 159.549846 -389.611108) (xy 159.549338 -389.610346) (xy 159.151574 -388.922006)
			(xy 159.139699 -388.899329) (xy 159.122848 -388.850996) (xy 159.114274 -388.800533) (xy 159.113728 -388.77494)
			(xy 158.57148 -388.77494) (xy 158.883604 -389.314944) (xy 158.896319 -389.338271) (xy 158.91442 -389.388214)
			(xy 158.923643 -389.44053) (xy 158.924244 -389.46709) (xy 158.924244 -389.467344) (xy 158.923778 -389.491335)
			(xy 158.916267 -389.538724) (xy 158.901435 -389.584356) (xy 158.879649 -389.627106) (xy 158.851445 -389.665923)
			(xy 158.817517 -389.69985) (xy 158.778699 -389.728054) (xy 158.735949 -389.749838) (xy 158.690317 -389.764668)
			(xy 158.642927 -389.772179) (xy 158.618936 -389.772652) (xy 158.595364 -389.772202) (xy 158.54878 -389.764967)
			(xy 158.503864 -389.750649) (xy 158.461687 -389.729589) (xy 158.423253 -389.702289) (xy 158.389479 -389.669399)
			(xy 158.361169 -389.631703) (xy 158.349696 -389.611108) (xy 158.349188 -389.610346) (xy 157.951424 -388.922006)
			(xy 157.939511 -388.899337) (xy 157.922572 -388.851012) (xy 157.913912 -388.800542) (xy 157.913324 -388.77494)
			(xy 157.371584 -388.77494) (xy 157.683708 -389.314944) (xy 157.696423 -389.338271) (xy 157.714524 -389.388214)
			(xy 157.723747 -389.44053) (xy 157.724348 -389.46709) (xy 157.724348 -389.467344) (xy 157.723878 -389.491334)
			(xy 157.716367 -389.538724) (xy 157.701536 -389.584355) (xy 157.67975 -389.627105) (xy 157.651546 -389.665922)
			(xy 157.617618 -389.699849) (xy 157.578802 -389.728052) (xy 157.536051 -389.749837) (xy 157.49042 -389.764668)
			(xy 157.44303 -389.772178) (xy 157.41904 -389.772652) (xy 157.395469 -389.772199) (xy 157.348884 -389.764965)
			(xy 157.303969 -389.750647) (xy 157.261791 -389.729588) (xy 157.223358 -389.702288) (xy 157.189583 -389.669399)
			(xy 157.161273 -389.631703) (xy 157.1498 -389.611108) (xy 157.149292 -389.610346) (xy 156.751528 -388.922006)
			(xy 156.739615 -388.899337) (xy 156.722676 -388.851012) (xy 156.714016 -388.800542) (xy 156.713428 -388.77494)
			(xy 156.171434 -388.77494) (xy 156.483558 -389.314944) (xy 156.496366 -389.338285) (xy 156.514592 -389.388304)
			(xy 156.523859 -389.440726) (xy 156.524452 -389.467344) (xy 156.523979 -389.491322) (xy 156.516476 -389.538686)
			(xy 156.501661 -389.584295) (xy 156.479898 -389.627028) (xy 156.451722 -389.665833) (xy 156.417827 -389.699757)
			(xy 156.379045 -389.727965) (xy 156.33633 -389.749763) (xy 156.290733 -389.764616) (xy 156.243375 -389.772159)
			(xy 156.219398 -389.772652) (xy 156.21889 -389.772652) (xy 156.195317 -389.772239) (xy 156.148731 -389.764997)
			(xy 156.103814 -389.750673) (xy 156.061637 -389.729607) (xy 156.023204 -389.702301) (xy 155.989431 -389.669406)
			(xy 155.961123 -389.631705) (xy 155.94965 -389.611108) (xy 155.949142 -389.610346) (xy 155.551378 -388.922006)
			(xy 155.539503 -388.899328) (xy 155.522652 -388.850996) (xy 155.514078 -388.800533) (xy 155.513532 -388.77494)
			(xy 154.971538 -388.77494) (xy 155.283662 -389.314944) (xy 155.29647 -389.338285) (xy 155.314696 -389.388304)
			(xy 155.323963 -389.440726) (xy 155.324556 -389.467344) (xy 155.324079 -389.491321) (xy 155.316576 -389.538686)
			(xy 155.301761 -389.584295) (xy 155.279998 -389.627027) (xy 155.251823 -389.665832) (xy 155.217928 -389.699755)
			(xy 155.179147 -389.727963) (xy 155.136433 -389.749762) (xy 155.090837 -389.764616) (xy 155.043479 -389.772159)
			(xy 155.019502 -389.772652) (xy 155.018994 -389.772652) (xy 154.995421 -389.772236) (xy 154.948835 -389.764995)
			(xy 154.903919 -389.750671) (xy 154.861741 -389.729605) (xy 154.823308 -389.7023) (xy 154.789535 -389.669405)
			(xy 154.761227 -389.631705) (xy 154.749754 -389.611108) (xy 154.749246 -389.610346) (xy 154.351482 -388.922006)
			(xy 154.339608 -388.899328) (xy 154.322756 -388.850996) (xy 154.314182 -388.800533) (xy 154.313636 -388.77494)
			(xy 153.771642 -388.77494) (xy 154.083766 -389.314944) (xy 154.096575 -389.338285) (xy 154.1148 -389.388303)
			(xy 154.124067 -389.440726) (xy 154.12466 -389.467344) (xy 154.124279 -389.491326) (xy 154.116773 -389.5387)
			(xy 154.101952 -389.584317) (xy 154.080181 -389.627055) (xy 154.051995 -389.665865) (xy 154.018088 -389.69979)
			(xy 153.979294 -389.727996) (xy 153.936567 -389.74979) (xy 153.890957 -389.764635) (xy 153.843588 -389.772166)
			(xy 153.819606 -389.772652) (xy 153.819098 -389.772652) (xy 153.795525 -389.772232) (xy 153.74894 -389.764992)
			(xy 153.704023 -389.750669) (xy 153.661846 -389.729604) (xy 153.623413 -389.702299) (xy 153.589639 -389.669405)
			(xy 153.561331 -389.631705) (xy 153.549858 -389.611108) (xy 153.54935 -389.610346) (xy 153.151586 -388.922006)
			(xy 153.139712 -388.899328) (xy 153.12286 -388.850996) (xy 153.114286 -388.800533) (xy 153.11374 -388.77494)
			(xy 152.571492 -388.77494) (xy 152.883616 -389.314944) (xy 152.896332 -389.338271) (xy 152.914432 -389.388214)
			(xy 152.923655 -389.44053) (xy 152.924256 -389.46709) (xy 152.924256 -389.467344) (xy 152.923778 -389.491334)
			(xy 152.916267 -389.538723) (xy 152.901436 -389.584353) (xy 152.879652 -389.627103) (xy 152.851449 -389.665919)
			(xy 152.817522 -389.699846) (xy 152.778706 -389.72805) (xy 152.735957 -389.749835) (xy 152.690327 -389.764666)
			(xy 152.642938 -389.772178) (xy 152.618948 -389.772652) (xy 152.595377 -389.772192) (xy 152.548793 -389.764959)
			(xy 152.503877 -389.750643) (xy 152.4617 -389.729585) (xy 152.423266 -389.702286) (xy 152.389492 -389.669398)
			(xy 152.361182 -389.631703) (xy 152.349708 -389.611108) (xy 152.3492 -389.610346) (xy 151.951436 -388.922006)
			(xy 151.939523 -388.899336) (xy 151.922584 -388.851012) (xy 151.913924 -388.800542) (xy 151.913336 -388.77494)
			(xy 151.371596 -388.77494) (xy 151.68372 -389.314944) (xy 151.696436 -389.33827) (xy 151.714536 -389.388214)
			(xy 151.723759 -389.44053) (xy 151.72436 -389.46709) (xy 151.72436 -389.467344) (xy 151.724002 -389.491341)
			(xy 151.716487 -389.538742) (xy 151.70165 -389.584385) (xy 151.679855 -389.627144) (xy 151.651639 -389.665968)
			(xy 151.617698 -389.699899) (xy 151.578866 -389.728103) (xy 151.5361 -389.749885) (xy 151.490453 -389.764709)
			(xy 151.443049 -389.772209) (xy 151.419052 -389.772652) (xy 151.395481 -389.772189) (xy 151.348897 -389.764957)
			(xy 151.303982 -389.750641) (xy 151.261804 -389.729583) (xy 151.223371 -389.702285) (xy 151.189596 -389.669397)
			(xy 151.161286 -389.631703) (xy 151.149812 -389.611108) (xy 151.149304 -389.610346) (xy 150.75154 -388.922006)
			(xy 150.739628 -388.899336) (xy 150.722688 -388.851012) (xy 150.714028 -388.800542) (xy 150.71344 -388.77494)
			(xy 150.171446 -388.77494) (xy 150.48357 -389.314944) (xy 150.496379 -389.338285) (xy 150.514604 -389.388303)
			(xy 150.523871 -389.440726) (xy 150.524464 -389.467344) (xy 150.524079 -389.491326) (xy 150.516573 -389.538699)
			(xy 150.501752 -389.584316) (xy 150.479981 -389.627054) (xy 150.451796 -389.665863) (xy 150.41789 -389.699788)
			(xy 150.379096 -389.727994) (xy 150.336369 -389.749788) (xy 150.290761 -389.764634) (xy 150.243392 -389.772166)
			(xy 150.21941 -389.772652) (xy 150.218902 -389.772652) (xy 150.195329 -389.772229) (xy 150.148744 -389.76499)
			(xy 150.103827 -389.750667) (xy 150.06165 -389.729602) (xy 150.023217 -389.702298) (xy 149.989444 -389.669404)
			(xy 149.961135 -389.631705) (xy 149.949662 -389.611108) (xy 149.949154 -389.610346) (xy 149.55139 -388.922006)
			(xy 149.539516 -388.899328) (xy 149.522664 -388.850995) (xy 149.51409 -388.800533) (xy 149.513544 -388.77494)
			(xy 148.97155 -388.77494) (xy 149.283674 -389.314944) (xy 149.296483 -389.338284) (xy 149.314708 -389.388303)
			(xy 149.323975 -389.440726) (xy 149.324568 -389.467344) (xy 149.324179 -389.491326) (xy 149.316673 -389.538698)
			(xy 149.301852 -389.584315) (xy 149.280082 -389.627053) (xy 149.251897 -389.665862) (xy 149.217991 -389.699787)
			(xy 149.179198 -389.727993) (xy 149.136472 -389.749787) (xy 149.090864 -389.764633) (xy 149.043495 -389.772165)
			(xy 149.019514 -389.772652) (xy 149.019006 -389.772652) (xy 148.995434 -389.772226) (xy 148.948848 -389.764987)
			(xy 148.903932 -389.750665) (xy 148.861754 -389.729601) (xy 148.823321 -389.702297) (xy 148.789548 -389.669404)
			(xy 148.761239 -389.631705) (xy 148.749766 -389.611108) (xy 148.749258 -389.610346) (xy 148.351494 -388.922006)
			(xy 148.339621 -388.899328) (xy 148.322768 -388.850995) (xy 148.314194 -388.800532) (xy 148.313648 -388.77494)
			(xy 147.771654 -388.77494) (xy 148.083778 -389.314944) (xy 148.096588 -389.338284) (xy 148.114813 -389.388303)
			(xy 148.124079 -389.440726) (xy 148.124672 -389.467344) (xy 148.124279 -389.491326) (xy 148.116773 -389.538698)
			(xy 148.101953 -389.584314) (xy 148.080183 -389.627052) (xy 148.051999 -389.665861) (xy 148.018093 -389.699785)
			(xy 147.9793 -389.727992) (xy 147.936575 -389.749786) (xy 147.890967 -389.764632) (xy 147.843599 -389.772165)
			(xy 147.819618 -389.772652) (xy 147.81911 -389.772652) (xy 147.795538 -389.772223) (xy 147.748952 -389.764984)
			(xy 147.704036 -389.750663) (xy 147.661859 -389.729599) (xy 147.623425 -389.702296) (xy 147.589652 -389.669403)
			(xy 147.561343 -389.631704) (xy 147.54987 -389.611108) (xy 147.549362 -389.610346) (xy 147.151598 -388.922006)
			(xy 147.139725 -388.899328) (xy 147.122872 -388.850995) (xy 147.114298 -388.800532) (xy 147.113752 -388.77494)
			(xy 133.24387 -388.77494) (xy 133.555994 -389.314944) (xy 133.568805 -389.338283) (xy 133.587029 -389.388303)
			(xy 133.596295 -389.440726) (xy 133.596888 -389.467344) (xy 133.596479 -389.491325) (xy 133.588974 -389.538695)
			(xy 133.574154 -389.58431) (xy 133.552386 -389.627047) (xy 133.524203 -389.665855) (xy 133.4903 -389.69978)
			(xy 133.451509 -389.727986) (xy 133.408786 -389.749782) (xy 133.36318 -389.764629) (xy 133.315814 -389.772164)
			(xy 133.291834 -389.772652) (xy 133.291326 -389.772652) (xy 133.267754 -389.77221) (xy 133.221169 -389.764974)
			(xy 133.176253 -389.750654) (xy 133.134076 -389.729593) (xy 133.095643 -389.702292) (xy 133.061869 -389.669401)
			(xy 133.033559 -389.631704) (xy 133.022086 -389.611108) (xy 133.021578 -389.610346) (xy 132.623814 -388.922006)
			(xy 132.611935 -388.899331) (xy 132.595086 -388.850997) (xy 132.586514 -388.800533) (xy 132.585968 -388.77494)
			(xy 132.04372 -388.77494) (xy 132.355844 -389.314944) (xy 132.368562 -389.338269) (xy 132.386661 -389.388214)
			(xy 132.395883 -389.44053) (xy 132.396484 -389.46709) (xy 132.396484 -389.467344) (xy 132.396078 -389.491338)
			(xy 132.388564 -389.538733) (xy 132.37373 -389.58437) (xy 132.351938 -389.627124) (xy 132.323728 -389.665943)
			(xy 132.289792 -389.699872) (xy 132.250966 -389.728074) (xy 132.208207 -389.749856) (xy 132.162567 -389.76468)
			(xy 132.11517 -389.772183) (xy 132.091176 -389.772652) (xy 132.067603 -389.77225) (xy 132.021016 -389.765007)
			(xy 131.976099 -389.75068) (xy 131.933922 -389.729612) (xy 131.895489 -389.702305) (xy 131.861716 -389.669408)
			(xy 131.833408 -389.631706) (xy 131.821936 -389.611108) (xy 131.821428 -389.610346) (xy 131.423664 -388.922006)
			(xy 131.411754 -388.899335) (xy 131.394814 -388.851011) (xy 131.386152 -388.800542) (xy 131.385564 -388.77494)
			(xy 130.843824 -388.77494) (xy 131.155948 -389.314944) (xy 131.168667 -389.338269) (xy 131.186765 -389.388214)
			(xy 131.195987 -389.44053) (xy 131.196588 -389.46709) (xy 131.196588 -389.467344) (xy 131.196178 -389.491337)
			(xy 131.188665 -389.538733) (xy 131.17383 -389.584369) (xy 131.152039 -389.627123) (xy 131.123829 -389.665942)
			(xy 131.089893 -389.69987) (xy 131.051068 -389.728073) (xy 131.00831 -389.749854) (xy 130.96267 -389.76468)
			(xy 130.915274 -389.772183) (xy 130.89128 -389.772652) (xy 130.867707 -389.772247) (xy 130.82112 -389.765004)
			(xy 130.776203 -389.750678) (xy 130.734026 -389.729611) (xy 130.695593 -389.702304) (xy 130.661821 -389.669407)
			(xy 130.633512 -389.631706) (xy 130.62204 -389.611108) (xy 130.621532 -389.610346) (xy 130.223768 -388.922006)
			(xy 130.211858 -388.899335) (xy 130.194918 -388.851011) (xy 130.186256 -388.800542) (xy 130.185668 -388.77494)
			(xy 129.643674 -388.77494) (xy 129.955798 -389.314944) (xy 129.968601 -389.338288) (xy 129.98683 -389.388305)
			(xy 129.996099 -389.440727) (xy 129.996692 -389.467344) (xy 129.996279 -389.491325) (xy 129.988774 -389.538695)
			(xy 129.973955 -389.584309) (xy 129.952187 -389.627046) (xy 129.924004 -389.665854) (xy 129.890101 -389.699778)
			(xy 129.851312 -389.727985) (xy 129.808589 -389.74978) (xy 129.762984 -389.764628) (xy 129.715618 -389.772164)
			(xy 129.691638 -389.772652) (xy 129.69113 -389.772652) (xy 129.667558 -389.772207) (xy 129.620974 -389.764971)
			(xy 129.576058 -389.750652) (xy 129.53388 -389.729592) (xy 129.495447 -389.702291) (xy 129.461673 -389.6694)
			(xy 129.433363 -389.631704) (xy 129.42189 -389.611108) (xy 129.421382 -389.610346) (xy 129.023618 -388.922006)
			(xy 129.011739 -388.899331) (xy 128.99489 -388.850997) (xy 128.986318 -388.800533) (xy 128.985772 -388.77494)
			(xy 128.443778 -388.77494) (xy 128.755902 -389.314944) (xy 128.768705 -389.338288) (xy 128.786934 -389.388305)
			(xy 128.796203 -389.440727) (xy 128.796796 -389.467344) (xy 128.796379 -389.491324) (xy 128.788874 -389.538694)
			(xy 128.774055 -389.584308) (xy 128.752287 -389.627045) (xy 128.724106 -389.665852) (xy 128.690203 -389.699777)
			(xy 128.651414 -389.727984) (xy 128.608692 -389.749779) (xy 128.563087 -389.764628) (xy 128.515722 -389.772163)
			(xy 128.491742 -389.772652) (xy 128.491234 -389.772652) (xy 128.467662 -389.772203) (xy 128.421078 -389.764969)
			(xy 128.376162 -389.75065) (xy 128.333985 -389.72959) (xy 128.295551 -389.70229) (xy 128.261777 -389.6694)
			(xy 128.233467 -389.631703) (xy 128.221994 -389.611108) (xy 128.221486 -389.610346) (xy 127.823722 -388.922006)
			(xy 127.811843 -388.899331) (xy 127.794994 -388.850996) (xy 127.786422 -388.800533) (xy 127.785876 -388.77494)
			(xy 127.243882 -388.77494) (xy 127.556006 -389.314944) (xy 127.56881 -389.338287) (xy 127.587038 -389.388304)
			(xy 127.596307 -389.440727) (xy 127.5969 -389.467344) (xy 127.596479 -389.491324) (xy 127.588974 -389.538694)
			(xy 127.574156 -389.584307) (xy 127.552388 -389.627044) (xy 127.524207 -389.665851) (xy 127.490305 -389.699775)
			(xy 127.451516 -389.727982) (xy 127.408794 -389.749778) (xy 127.36319 -389.764627) (xy 127.315826 -389.772163)
			(xy 127.291846 -389.772652) (xy 127.291338 -389.772652) (xy 127.267766 -389.7722) (xy 127.221182 -389.764966)
			(xy 127.176266 -389.750648) (xy 127.134089 -389.729589) (xy 127.095656 -389.702289) (xy 127.061881 -389.669399)
			(xy 127.033571 -389.631703) (xy 127.022098 -389.611108) (xy 127.02159 -389.610346) (xy 126.623826 -388.922006)
			(xy 126.611947 -388.89933) (xy 126.595098 -388.850996) (xy 126.586526 -388.800533) (xy 126.58598 -388.77494)
			(xy 126.043732 -388.77494) (xy 126.355856 -389.314944) (xy 126.368575 -389.338269) (xy 126.386673 -389.388214)
			(xy 126.395895 -389.440529) (xy 126.396496 -389.46709) (xy 126.396496 -389.467344) (xy 126.396078 -389.491337)
			(xy 126.388565 -389.538731) (xy 126.373731 -389.584367) (xy 126.351941 -389.627121) (xy 126.323731 -389.665939)
			(xy 126.289797 -389.699868) (xy 126.250973 -389.72807) (xy 126.208215 -389.749852) (xy 126.162577 -389.764678)
			(xy 126.115181 -389.772182) (xy 126.091188 -389.772652) (xy 126.067615 -389.772241) (xy 126.021029 -389.764999)
			(xy 125.976112 -389.750674) (xy 125.933935 -389.729608) (xy 125.895502 -389.702301) (xy 125.861729 -389.669406)
			(xy 125.833421 -389.631705) (xy 125.821948 -389.611108) (xy 125.82144 -389.610346) (xy 125.423676 -388.922006)
			(xy 125.411759 -388.899339) (xy 125.394823 -388.851013) (xy 125.386163 -388.800542) (xy 125.385576 -388.77494)
			(xy 124.843836 -388.77494) (xy 125.15596 -389.314944) (xy 125.16868 -389.338269) (xy 125.186777 -389.388214)
			(xy 125.195999 -389.440529) (xy 125.1966 -389.46709) (xy 125.1966 -389.467344) (xy 125.196178 -389.491337)
			(xy 125.188665 -389.538731) (xy 125.173831 -389.584366) (xy 125.152041 -389.627119) (xy 125.123832 -389.665938)
			(xy 125.089898 -389.699866) (xy 125.051075 -389.728069) (xy 125.008318 -389.749851) (xy 124.96268 -389.764677)
			(xy 124.915285 -389.772182) (xy 124.891292 -389.772652) (xy 124.867719 -389.772237) (xy 124.821133 -389.764996)
			(xy 124.776216 -389.750672) (xy 124.734039 -389.729606) (xy 124.695606 -389.7023) (xy 124.661833 -389.669406)
			(xy 124.633525 -389.631705) (xy 124.622052 -389.611108) (xy 124.621544 -389.610346) (xy 124.22378 -388.922006)
			(xy 124.211863 -388.899339) (xy 124.194927 -388.851013) (xy 124.186267 -388.800542) (xy 124.18568 -388.77494)
			(xy 123.643686 -388.77494) (xy 123.95581 -389.314944) (xy 123.968614 -389.338287) (xy 123.986843 -389.388304)
			(xy 123.996111 -389.440727) (xy 123.996704 -389.467344) (xy 123.996279 -389.491324) (xy 123.988774 -389.538693)
			(xy 123.973956 -389.584307) (xy 123.952189 -389.627042) (xy 123.924008 -389.66585) (xy 123.890106 -389.699774)
			(xy 123.851318 -389.727981) (xy 123.808597 -389.749777) (xy 123.762994 -389.764626) (xy 123.71563 -389.772163)
			(xy 123.69165 -389.772652) (xy 123.691142 -389.772652) (xy 123.667571 -389.772197) (xy 123.620986 -389.764963)
			(xy 123.576071 -389.750646) (xy 123.533893 -389.729587) (xy 123.49546 -389.702288) (xy 123.461686 -389.669398)
			(xy 123.433376 -389.631703) (xy 123.421902 -389.611108) (xy 123.421394 -389.610346) (xy 123.02363 -388.922006)
			(xy 123.011752 -388.89933) (xy 122.994902 -388.850996) (xy 122.98633 -388.800533) (xy 122.985784 -388.77494)
			(xy 122.44379 -388.77494) (xy 122.755914 -389.314944) (xy 122.768718 -389.338287) (xy 122.786947 -389.388304)
			(xy 122.796215 -389.440727) (xy 122.796808 -389.467344) (xy 122.796379 -389.491324) (xy 122.788874 -389.538693)
			(xy 122.774056 -389.584306) (xy 122.752289 -389.627041) (xy 122.724109 -389.665848) (xy 122.690208 -389.699772)
			(xy 122.65142 -389.72798) (xy 122.6087 -389.749776) (xy 122.563097 -389.764625) (xy 122.515733 -389.772162)
			(xy 122.491754 -389.772652) (xy 122.491246 -389.772652) (xy 122.467675 -389.772194) (xy 122.421091 -389.764961)
			(xy 122.376175 -389.750644) (xy 122.333998 -389.729586) (xy 122.295564 -389.702287) (xy 122.26179 -389.669398)
			(xy 122.23348 -389.631703) (xy 122.222006 -389.611108) (xy 122.221498 -389.610346) (xy 121.823734 -388.922006)
			(xy 121.811856 -388.89933) (xy 121.795006 -388.850996) (xy 121.786434 -388.800533) (xy 121.785888 -388.77494)
			(xy 121.243894 -388.77494) (xy 121.556018 -389.314944) (xy 121.568823 -389.338287) (xy 121.587051 -389.388304)
			(xy 121.596319 -389.440727) (xy 121.596912 -389.467344) (xy 121.596479 -389.491324) (xy 121.588974 -389.538692)
			(xy 121.574157 -389.584305) (xy 121.55239 -389.62704) (xy 121.52421 -389.665847) (xy 121.49031 -389.699771)
			(xy 121.451523 -389.727978) (xy 121.408803 -389.749775) (xy 121.3632 -389.764624) (xy 121.315837 -389.772162)
			(xy 121.291858 -389.772652) (xy 121.29135 -389.772652) (xy 121.267779 -389.772191) (xy 121.221195 -389.764958)
			(xy 121.176279 -389.750642) (xy 121.134102 -389.729584) (xy 121.095668 -389.702286) (xy 121.061894 -389.669397)
			(xy 121.033584 -389.631703) (xy 121.02211 -389.611108) (xy 121.021602 -389.610346) (xy 120.623838 -388.922006)
			(xy 120.61196 -388.89933) (xy 120.595111 -388.850996) (xy 120.586538 -388.800533) (xy 120.585992 -388.77494)
			(xy 120.043744 -388.77494) (xy 120.355868 -389.314944) (xy 120.368588 -389.338268) (xy 120.386686 -389.388213)
			(xy 120.395908 -389.440529) (xy 120.396508 -389.46709) (xy 120.396508 -389.467344) (xy 120.396078 -389.491336)
			(xy 120.388565 -389.53873) (xy 120.373732 -389.584364) (xy 120.351943 -389.627117) (xy 120.323735 -389.665935)
			(xy 120.289802 -389.699863) (xy 120.250979 -389.728066) (xy 120.208224 -389.749849) (xy 120.162587 -389.764676)
			(xy 120.115192 -389.772181) (xy 120.0912 -389.772652) (xy 120.067627 -389.772231) (xy 120.021042 -389.764991)
			(xy 119.976125 -389.750668) (xy 119.933948 -389.729603) (xy 119.895515 -389.702298) (xy 119.861742 -389.669404)
			(xy 119.833433 -389.631705) (xy 119.82196 -389.611108) (xy 119.821452 -389.610346) (xy 119.423688 -388.922006)
			(xy 119.411772 -388.899338) (xy 119.394835 -388.851013) (xy 119.386175 -388.800542) (xy 119.385588 -388.77494)
			(xy 118.843848 -388.77494) (xy 119.155972 -389.314944) (xy 119.168693 -389.338268) (xy 119.18679 -389.388213)
			(xy 119.196012 -389.440529) (xy 119.196612 -389.46709) (xy 119.196612 -389.467344) (xy 119.196178 -389.491336)
			(xy 119.188665 -389.538729) (xy 119.173832 -389.584363) (xy 119.152044 -389.627116) (xy 119.123836 -389.665934)
			(xy 119.089903 -389.699862) (xy 119.051082 -389.728065) (xy 119.008326 -389.749848) (xy 118.96269 -389.764675)
			(xy 118.915296 -389.772181) (xy 118.891304 -389.772652) (xy 118.867732 -389.772228) (xy 118.821146 -389.764988)
			(xy 118.776229 -389.750666) (xy 118.734052 -389.729602) (xy 118.695619 -389.702297) (xy 118.661846 -389.669404)
			(xy 118.633537 -389.631705) (xy 118.622064 -389.611108) (xy 118.621556 -389.610346) (xy 118.223792 -388.922006)
			(xy 118.211876 -388.899338) (xy 118.194939 -388.851012) (xy 118.186279 -388.800542) (xy 118.185692 -388.77494)
			(xy 117.643698 -388.77494) (xy 117.955822 -389.314944) (xy 117.968627 -389.338287) (xy 117.986855 -389.388304)
			(xy 117.996123 -389.440727) (xy 117.996716 -389.467344) (xy 117.996279 -389.491323) (xy 117.988775 -389.538691)
			(xy 117.973957 -389.584304) (xy 117.952191 -389.627039) (xy 117.924011 -389.665846) (xy 117.890112 -389.69977)
			(xy 117.851325 -389.727977) (xy 117.808605 -389.749773) (xy 117.763004 -389.764624) (xy 117.715641 -389.772162)
			(xy 117.691662 -389.772652) (xy 117.691154 -389.772652) (xy 117.667583 -389.772187) (xy 117.620999 -389.764955)
			(xy 117.576084 -389.75064) (xy 117.533906 -389.729583) (xy 117.495473 -389.702285) (xy 117.461698 -389.669397)
			(xy 117.433388 -389.631702) (xy 117.421914 -389.611108) (xy 117.421406 -389.610346) (xy 117.023642 -388.922006)
			(xy 117.011765 -388.89933) (xy 116.994915 -388.850996) (xy 116.986342 -388.800533) (xy 116.985796 -388.77494)
			(xy 116.443802 -388.77494) (xy 116.755926 -389.314944) (xy 116.768731 -389.338286) (xy 116.786959 -389.388304)
			(xy 116.796227 -389.440727) (xy 116.79682 -389.467344) (xy 116.796379 -389.491323) (xy 116.788875 -389.538691)
			(xy 116.774057 -389.584303) (xy 116.752292 -389.627038) (xy 116.724113 -389.665844) (xy 116.690213 -389.699768)
			(xy 116.651427 -389.727975) (xy 116.608708 -389.749772) (xy 116.563107 -389.764623) (xy 116.515745 -389.772162)
			(xy 116.491766 -389.772652) (xy 116.491258 -389.772652) (xy 116.467687 -389.772184) (xy 116.421104 -389.764953)
			(xy 116.376188 -389.750638) (xy 116.334011 -389.729581) (xy 116.295577 -389.702284) (xy 116.261802 -389.669396)
			(xy 116.233492 -389.631702) (xy 116.222018 -389.611108) (xy 116.22151 -389.610346) (xy 115.823746 -388.922006)
			(xy 115.811869 -388.89933) (xy 115.795019 -388.850996) (xy 115.786446 -388.800533) (xy 115.7859 -388.77494)
			(xy 115.243906 -388.77494) (xy 115.55603 -389.314944) (xy 115.568836 -389.338286) (xy 115.587063 -389.388304)
			(xy 115.596331 -389.440727) (xy 115.596924 -389.467344) (xy 115.596479 -389.491323) (xy 115.588975 -389.53869)
			(xy 115.574158 -389.584302) (xy 115.552392 -389.627036) (xy 115.524214 -389.665843) (xy 115.490315 -389.699767)
			(xy 115.451529 -389.727974) (xy 115.408811 -389.749771) (xy 115.36321 -389.764622) (xy 115.315849 -389.772161)
			(xy 115.29187 -389.772652) (xy 115.291362 -389.772652) (xy 115.267791 -389.772181) (xy 115.221208 -389.76495)
			(xy 115.176292 -389.750636) (xy 115.134115 -389.72958) (xy 115.095681 -389.702283) (xy 115.061907 -389.669396)
			(xy 115.033596 -389.631702) (xy 115.022122 -389.611108) (xy 115.021614 -389.610346) (xy 114.62385 -388.922006)
			(xy 114.611973 -388.899329) (xy 114.595123 -388.850996) (xy 114.58655 -388.800533) (xy 114.586004 -388.77494)
			(xy 98.671676 -388.77494) (xy 98.9838 -389.314944) (xy 98.996515 -389.338271) (xy 99.014615 -389.388215)
			(xy 99.023839 -389.44053) (xy 99.02444 -389.46709) (xy 99.02444 -389.467344) (xy 99.023978 -389.491335)
			(xy 99.016466 -389.538725) (xy 99.001635 -389.584357) (xy 98.979849 -389.627107) (xy 98.951644 -389.665924)
			(xy 98.917715 -389.699852) (xy 98.878897 -389.728055) (xy 98.836146 -389.74984) (xy 98.790513 -389.764669)
			(xy 98.743123 -389.772179) (xy 98.719132 -389.772652) (xy 98.69556 -389.772205) (xy 98.648976 -389.76497)
			(xy 98.60406 -389.750651) (xy 98.561883 -389.729591) (xy 98.523449 -389.70229) (xy 98.489675 -389.6694)
			(xy 98.461365 -389.631703) (xy 98.449892 -389.611108) (xy 98.449384 -389.610346) (xy 98.05162 -388.922006)
			(xy 98.039706 -388.899337) (xy 98.022768 -388.851012) (xy 98.014108 -388.800542) (xy 98.01352 -388.77494)
			(xy 97.471526 -388.77494) (xy 97.78365 -389.314944) (xy 97.796457 -389.338285) (xy 97.814684 -389.388304)
			(xy 97.823951 -389.440726) (xy 97.824544 -389.467344) (xy 97.824079 -389.491322) (xy 97.816576 -389.538687)
			(xy 97.80176 -389.584297) (xy 97.779996 -389.62703) (xy 97.75182 -389.665836) (xy 97.717923 -389.69976)
			(xy 97.67914 -389.727967) (xy 97.636425 -389.749765) (xy 97.590827 -389.764618) (xy 97.543468 -389.77216)
			(xy 97.51949 -389.772652) (xy 97.518982 -389.772652) (xy 97.495409 -389.772245) (xy 97.448822 -389.765003)
			(xy 97.403906 -389.750677) (xy 97.361728 -389.72961) (xy 97.323295 -389.702303) (xy 97.289523 -389.669407)
			(xy 97.261214 -389.631706) (xy 97.249742 -389.611108) (xy 97.249234 -389.610346) (xy 96.85147 -388.922006)
			(xy 96.839595 -388.899329) (xy 96.822743 -388.850996) (xy 96.81417 -388.800533) (xy 96.813624 -388.77494)
			(xy 96.27163 -388.77494) (xy 96.583754 -389.314944) (xy 96.596562 -389.338285) (xy 96.614788 -389.388304)
			(xy 96.624055 -389.440726) (xy 96.624648 -389.467344) (xy 96.624179 -389.491322) (xy 96.616676 -389.538687)
			(xy 96.60186 -389.584296) (xy 96.580097 -389.627029) (xy 96.551921 -389.665835) (xy 96.518025 -389.699758)
			(xy 96.479243 -389.727966) (xy 96.436528 -389.749764) (xy 96.39093 -389.764617) (xy 96.343571 -389.772159)
			(xy 96.319594 -389.772652) (xy 96.319086 -389.772652) (xy 96.295513 -389.772242) (xy 96.248927 -389.765)
			(xy 96.20401 -389.750675) (xy 96.161833 -389.729608) (xy 96.1234 -389.702302) (xy 96.089627 -389.669406)
			(xy 96.061319 -389.631705) (xy 96.049846 -389.611108) (xy 96.049338 -389.610346) (xy 95.651574 -388.922006)
			(xy 95.639699 -388.899329) (xy 95.622848 -388.850996) (xy 95.614274 -388.800533) (xy 95.613728 -388.77494)
			(xy 95.07148 -388.77494) (xy 95.383604 -389.314944) (xy 95.396319 -389.338271) (xy 95.41442 -389.388214)
			(xy 95.423643 -389.44053) (xy 95.424244 -389.46709) (xy 95.424244 -389.467344) (xy 95.423778 -389.491335)
			(xy 95.416267 -389.538724) (xy 95.401435 -389.584356) (xy 95.379649 -389.627106) (xy 95.351445 -389.665923)
			(xy 95.317517 -389.69985) (xy 95.278699 -389.728054) (xy 95.235949 -389.749838) (xy 95.190317 -389.764668)
			(xy 95.142927 -389.772179) (xy 95.118936 -389.772652) (xy 95.095364 -389.772202) (xy 95.04878 -389.764967)
			(xy 95.003864 -389.750649) (xy 94.961687 -389.729589) (xy 94.923253 -389.702289) (xy 94.889479 -389.669399)
			(xy 94.861169 -389.631703) (xy 94.849696 -389.611108) (xy 94.849188 -389.610346) (xy 94.451424 -388.922006)
			(xy 94.439511 -388.899337) (xy 94.422572 -388.851012) (xy 94.413912 -388.800542) (xy 94.413324 -388.77494)
			(xy 93.871584 -388.77494) (xy 94.183708 -389.314944) (xy 94.196423 -389.338271) (xy 94.214524 -389.388214)
			(xy 94.223747 -389.44053) (xy 94.224348 -389.46709) (xy 94.224348 -389.467344) (xy 94.223878 -389.491334)
			(xy 94.216367 -389.538724) (xy 94.201536 -389.584355) (xy 94.17975 -389.627105) (xy 94.151546 -389.665922)
			(xy 94.117618 -389.699849) (xy 94.078802 -389.728052) (xy 94.036051 -389.749837) (xy 93.99042 -389.764668)
			(xy 93.94303 -389.772178) (xy 93.91904 -389.772652) (xy 93.895469 -389.772199) (xy 93.848884 -389.764965)
			(xy 93.803969 -389.750647) (xy 93.761791 -389.729588) (xy 93.723358 -389.702288) (xy 93.689583 -389.669399)
			(xy 93.661273 -389.631703) (xy 93.6498 -389.611108) (xy 93.649292 -389.610346) (xy 93.251528 -388.922006)
			(xy 93.239615 -388.899337) (xy 93.222676 -388.851012) (xy 93.214016 -388.800542) (xy 93.213428 -388.77494)
			(xy 92.671688 -388.77494) (xy 92.983812 -389.314944) (xy 92.996528 -389.338271) (xy 93.014628 -389.388214)
			(xy 93.023851 -389.44053) (xy 93.024452 -389.46709) (xy 93.024452 -389.467344) (xy 93.023978 -389.491334)
			(xy 93.016467 -389.538723) (xy 93.001636 -389.584354) (xy 92.979851 -389.627104) (xy 92.951648 -389.66592)
			(xy 92.91772 -389.699848) (xy 92.878904 -389.728051) (xy 92.836154 -389.749836) (xy 92.790523 -389.764667)
			(xy 92.743134 -389.772178) (xy 92.719144 -389.772652) (xy 92.695573 -389.772195) (xy 92.648989 -389.764962)
			(xy 92.604073 -389.750645) (xy 92.561896 -389.729586) (xy 92.523462 -389.702287) (xy 92.489688 -389.669398)
			(xy 92.461378 -389.631703) (xy 92.449904 -389.611108) (xy 92.449396 -389.610346) (xy 92.051632 -388.922006)
			(xy 92.039719 -388.899336) (xy 92.02278 -388.851012) (xy 92.01412 -388.800542) (xy 92.013532 -388.77494)
			(xy 91.471538 -388.77494) (xy 91.783662 -389.314944) (xy 91.79647 -389.338285) (xy 91.814696 -389.388304)
			(xy 91.823963 -389.440726) (xy 91.824556 -389.467344) (xy 91.824079 -389.491321) (xy 91.816576 -389.538686)
			(xy 91.801761 -389.584295) (xy 91.779998 -389.627027) (xy 91.751823 -389.665832) (xy 91.717928 -389.699755)
			(xy 91.679147 -389.727963) (xy 91.636433 -389.749762) (xy 91.590837 -389.764616) (xy 91.543479 -389.772159)
			(xy 91.519502 -389.772652) (xy 91.518994 -389.772652) (xy 91.495421 -389.772236) (xy 91.448835 -389.764995)
			(xy 91.403919 -389.750671) (xy 91.361741 -389.729605) (xy 91.323308 -389.7023) (xy 91.289535 -389.669405)
			(xy 91.261227 -389.631705) (xy 91.249754 -389.611108) (xy 91.249246 -389.610346) (xy 90.851482 -388.922006)
			(xy 90.839608 -388.899328) (xy 90.822756 -388.850996) (xy 90.814182 -388.800533) (xy 90.813636 -388.77494)
			(xy 90.271642 -388.77494) (xy 90.583766 -389.314944) (xy 90.596575 -389.338285) (xy 90.6148 -389.388303)
			(xy 90.624067 -389.440726) (xy 90.62466 -389.467344) (xy 90.624279 -389.491326) (xy 90.616773 -389.5387)
			(xy 90.601952 -389.584317) (xy 90.580181 -389.627055) (xy 90.551995 -389.665865) (xy 90.518088 -389.69979)
			(xy 90.479294 -389.727996) (xy 90.436567 -389.74979) (xy 90.390957 -389.764635) (xy 90.343588 -389.772166)
			(xy 90.319606 -389.772652) (xy 90.319098 -389.772652) (xy 90.295525 -389.772232) (xy 90.24894 -389.764992)
			(xy 90.204023 -389.750669) (xy 90.161846 -389.729604) (xy 90.123413 -389.702299) (xy 90.089639 -389.669405)
			(xy 90.061331 -389.631705) (xy 90.049858 -389.611108) (xy 90.04935 -389.610346) (xy 89.651586 -388.922006)
			(xy 89.639712 -388.899328) (xy 89.62286 -388.850996) (xy 89.614286 -388.800533) (xy 89.61374 -388.77494)
			(xy 89.071492 -388.77494) (xy 89.383616 -389.314944) (xy 89.396332 -389.338271) (xy 89.414432 -389.388214)
			(xy 89.423655 -389.44053) (xy 89.424256 -389.46709) (xy 89.424256 -389.467344) (xy 89.423778 -389.491334)
			(xy 89.416267 -389.538723) (xy 89.401436 -389.584353) (xy 89.379652 -389.627103) (xy 89.351449 -389.665919)
			(xy 89.317522 -389.699846) (xy 89.278706 -389.72805) (xy 89.235957 -389.749835) (xy 89.190327 -389.764666)
			(xy 89.142938 -389.772178) (xy 89.118948 -389.772652) (xy 89.095377 -389.772192) (xy 89.048793 -389.764959)
			(xy 89.003877 -389.750643) (xy 88.9617 -389.729585) (xy 88.923266 -389.702286) (xy 88.889492 -389.669398)
			(xy 88.861182 -389.631703) (xy 88.849708 -389.611108) (xy 88.8492 -389.610346) (xy 88.451436 -388.922006)
			(xy 88.439523 -388.899336) (xy 88.422584 -388.851012) (xy 88.413924 -388.800542) (xy 88.413336 -388.77494)
			(xy 87.871596 -388.77494) (xy 88.18372 -389.314944) (xy 88.196436 -389.33827) (xy 88.214536 -389.388214)
			(xy 88.223759 -389.44053) (xy 88.22436 -389.46709) (xy 88.22436 -389.467344) (xy 88.224002 -389.491341)
			(xy 88.216487 -389.538742) (xy 88.20165 -389.584385) (xy 88.179855 -389.627144) (xy 88.151639 -389.665968)
			(xy 88.117698 -389.699899) (xy 88.078866 -389.728103) (xy 88.0361 -389.749885) (xy 87.990453 -389.764709)
			(xy 87.943049 -389.772209) (xy 87.919052 -389.772652) (xy 87.895481 -389.772189) (xy 87.848897 -389.764957)
			(xy 87.803982 -389.750641) (xy 87.761804 -389.729583) (xy 87.723371 -389.702285) (xy 87.689596 -389.669397)
			(xy 87.661286 -389.631703) (xy 87.649812 -389.611108) (xy 87.649304 -389.610346) (xy 87.25154 -388.922006)
			(xy 87.239628 -388.899336) (xy 87.222688 -388.851012) (xy 87.214028 -388.800542) (xy 87.21344 -388.77494)
			(xy 86.6717 -388.77494) (xy 86.983824 -389.314944) (xy 86.996541 -389.33827) (xy 87.01464 -389.388214)
			(xy 87.023863 -389.44053) (xy 87.024464 -389.46709) (xy 87.024464 -389.467344) (xy 87.024078 -389.491339)
			(xy 87.016564 -389.538736) (xy 87.001728 -389.584375) (xy 86.979935 -389.62713) (xy 86.951722 -389.66595)
			(xy 86.917783 -389.699879) (xy 86.878955 -389.728081) (xy 86.836193 -389.749861) (xy 86.79055 -389.764684)
			(xy 86.743151 -389.772185) (xy 86.719156 -389.772652) (xy 86.695585 -389.772186) (xy 86.649001 -389.764954)
			(xy 86.604086 -389.750639) (xy 86.561909 -389.729582) (xy 86.523475 -389.702284) (xy 86.4897 -389.669396)
			(xy 86.46139 -389.631702) (xy 86.449916 -389.611108) (xy 86.449408 -389.610346) (xy 86.051644 -388.922006)
			(xy 86.039732 -388.899336) (xy 86.022793 -388.851012) (xy 86.014132 -388.800542) (xy 86.013544 -388.77494)
			(xy 85.47155 -388.77494) (xy 85.783674 -389.314944) (xy 85.796483 -389.338284) (xy 85.814708 -389.388303)
			(xy 85.823975 -389.440726) (xy 85.824568 -389.467344) (xy 85.824179 -389.491326) (xy 85.816673 -389.538698)
			(xy 85.801852 -389.584315) (xy 85.780082 -389.627053) (xy 85.751897 -389.665862) (xy 85.717991 -389.699787)
			(xy 85.679198 -389.727993) (xy 85.636472 -389.749787) (xy 85.590864 -389.764633) (xy 85.543495 -389.772165)
			(xy 85.519514 -389.772652) (xy 85.519006 -389.772652) (xy 85.495434 -389.772226) (xy 85.448848 -389.764987)
			(xy 85.403932 -389.750665) (xy 85.361754 -389.729601) (xy 85.323321 -389.702297) (xy 85.289548 -389.669404)
			(xy 85.261239 -389.631705) (xy 85.249766 -389.611108) (xy 85.249258 -389.610346) (xy 84.851494 -388.922006)
			(xy 84.839621 -388.899328) (xy 84.822768 -388.850995) (xy 84.814194 -388.800532) (xy 84.813648 -388.77494)
			(xy 84.271654 -388.77494) (xy 84.583778 -389.314944) (xy 84.596588 -389.338284) (xy 84.614813 -389.388303)
			(xy 84.624079 -389.440726) (xy 84.624672 -389.467344) (xy 84.624279 -389.491326) (xy 84.616773 -389.538698)
			(xy 84.601953 -389.584314) (xy 84.580183 -389.627052) (xy 84.551999 -389.665861) (xy 84.518093 -389.699785)
			(xy 84.4793 -389.727992) (xy 84.436575 -389.749786) (xy 84.390967 -389.764632) (xy 84.343599 -389.772165)
			(xy 84.319618 -389.772652) (xy 84.31911 -389.772652) (xy 84.295538 -389.772223) (xy 84.248952 -389.764984)
			(xy 84.204036 -389.750663) (xy 84.161859 -389.729599) (xy 84.123425 -389.702296) (xy 84.089652 -389.669403)
			(xy 84.061343 -389.631704) (xy 84.04987 -389.611108) (xy 84.049362 -389.610346) (xy 83.651598 -388.922006)
			(xy 83.639725 -388.899328) (xy 83.622872 -388.850995) (xy 83.614298 -388.800532) (xy 83.613752 -388.77494)
			(xy 83.071504 -388.77494) (xy 83.383628 -389.314944) (xy 83.396345 -389.33827) (xy 83.414444 -389.388214)
			(xy 83.423667 -389.44053) (xy 83.424268 -389.46709) (xy 83.424268 -389.467344) (xy 83.423878 -389.491338)
			(xy 83.416364 -389.538735) (xy 83.401528 -389.584374) (xy 83.379736 -389.627129) (xy 83.351523 -389.665949)
			(xy 83.317585 -389.699878) (xy 83.278757 -389.728079) (xy 83.235996 -389.74986) (xy 83.190354 -389.764684)
			(xy 83.142955 -389.772184) (xy 83.11896 -389.772652) (xy 83.095389 -389.772182) (xy 83.048806 -389.764951)
			(xy 83.00389 -389.750637) (xy 82.961713 -389.72958) (xy 82.923279 -389.702283) (xy 82.889504 -389.669396)
			(xy 82.861194 -389.631702) (xy 82.84972 -389.611108) (xy 82.849212 -389.610346) (xy 82.451448 -388.922006)
			(xy 82.439536 -388.899336) (xy 82.422597 -388.851012) (xy 82.413936 -388.800542) (xy 82.413348 -388.77494)
			(xy 81.871608 -388.77494) (xy 82.183732 -389.314944) (xy 82.196449 -389.33827) (xy 82.214548 -389.388214)
			(xy 82.223771 -389.44053) (xy 82.224372 -389.46709) (xy 82.224372 -389.467344) (xy 82.223978 -389.491338)
			(xy 82.216464 -389.538735) (xy 82.201628 -389.584373) (xy 82.179836 -389.627128) (xy 82.151624 -389.665948)
			(xy 82.117687 -389.699876) (xy 82.078859 -389.728078) (xy 82.036099 -389.749859) (xy 81.990457 -389.764683)
			(xy 81.943058 -389.772184) (xy 81.919064 -389.772652) (xy 81.895493 -389.772179) (xy 81.84891 -389.764949)
			(xy 81.803995 -389.750635) (xy 81.761817 -389.729579) (xy 81.723383 -389.702282) (xy 81.689609 -389.669395)
			(xy 81.661298 -389.631702) (xy 81.649824 -389.611108) (xy 81.649316 -389.610346) (xy 81.251552 -388.922006)
			(xy 81.239641 -388.899336) (xy 81.222701 -388.851012) (xy 81.21404 -388.800542) (xy 81.213452 -388.77494)
			(xy 80.671712 -388.77494) (xy 80.983836 -389.314944) (xy 80.996554 -389.33827) (xy 81.014653 -389.388214)
			(xy 81.023875 -389.44053) (xy 81.024476 -389.46709) (xy 81.024476 -389.467344) (xy 81.024078 -389.491338)
			(xy 81.016564 -389.538734) (xy 81.001729 -389.584372) (xy 80.979937 -389.627127) (xy 80.951725 -389.665946)
			(xy 80.917788 -389.699875) (xy 80.878962 -389.728077) (xy 80.836201 -389.749858) (xy 80.79056 -389.764682)
			(xy 80.743162 -389.772184) (xy 80.719168 -389.772652) (xy 80.695597 -389.772176) (xy 80.649014 -389.764946)
			(xy 80.604099 -389.750633) (xy 80.561922 -389.729577) (xy 80.523488 -389.702281) (xy 80.489713 -389.669395)
			(xy 80.461402 -389.631702) (xy 80.449928 -389.611108) (xy 80.44942 -389.610346) (xy 80.051656 -388.922006)
			(xy 80.039745 -388.899335) (xy 80.022805 -388.851011) (xy 80.014144 -388.800542) (xy 80.013556 -388.77494)
			(xy 66.143928 -388.77494) (xy 66.456052 -389.314944) (xy 66.468771 -389.338269) (xy 66.486869 -389.388214)
			(xy 66.496091 -389.44053) (xy 66.496692 -389.46709) (xy 66.496692 -389.467344) (xy 66.496278 -389.491337)
			(xy 66.488765 -389.538732) (xy 66.47393 -389.584368) (xy 66.45214 -389.627122) (xy 66.42393 -389.665941)
			(xy 66.389995 -389.699869) (xy 66.351171 -389.728071) (xy 66.308412 -389.749853) (xy 66.262774 -389.764679)
			(xy 66.215377 -389.772183) (xy 66.191384 -389.772652) (xy 66.167811 -389.772244) (xy 66.121225 -389.765001)
			(xy 66.076308 -389.750676) (xy 66.034131 -389.729609) (xy 65.995698 -389.702302) (xy 65.961925 -389.669407)
			(xy 65.933616 -389.631706) (xy 65.922144 -389.611108) (xy 65.921636 -389.610346) (xy 65.523872 -388.922006)
			(xy 65.511954 -388.899339) (xy 65.495018 -388.851013) (xy 65.486359 -388.800542) (xy 65.485772 -388.77494)
			(xy 64.943778 -388.77494) (xy 65.255902 -389.314944) (xy 65.268705 -389.338288) (xy 65.286934 -389.388305)
			(xy 65.296203 -389.440727) (xy 65.296796 -389.467344) (xy 65.296379 -389.491324) (xy 65.288874 -389.538694)
			(xy 65.274055 -389.584308) (xy 65.252287 -389.627045) (xy 65.224106 -389.665852) (xy 65.190203 -389.699777)
			(xy 65.151414 -389.727984) (xy 65.108692 -389.749779) (xy 65.063087 -389.764628) (xy 65.015722 -389.772163)
			(xy 64.991742 -389.772652) (xy 64.991234 -389.772652) (xy 64.967662 -389.772203) (xy 64.921078 -389.764969)
			(xy 64.876162 -389.75065) (xy 64.833985 -389.72959) (xy 64.795551 -389.70229) (xy 64.761777 -389.6694)
			(xy 64.733467 -389.631703) (xy 64.721994 -389.611108) (xy 64.721486 -389.610346) (xy 64.323722 -388.922006)
			(xy 64.311843 -388.899331) (xy 64.294994 -388.850996) (xy 64.286422 -388.800533) (xy 64.285876 -388.77494)
			(xy 63.743882 -388.77494) (xy 64.056006 -389.314944) (xy 64.06881 -389.338287) (xy 64.087038 -389.388304)
			(xy 64.096307 -389.440727) (xy 64.0969 -389.467344) (xy 64.096479 -389.491324) (xy 64.088974 -389.538694)
			(xy 64.074156 -389.584307) (xy 64.052388 -389.627044) (xy 64.024207 -389.665851) (xy 63.990305 -389.699775)
			(xy 63.951516 -389.727982) (xy 63.908794 -389.749778) (xy 63.86319 -389.764627) (xy 63.815826 -389.772163)
			(xy 63.791846 -389.772652) (xy 63.791338 -389.772652) (xy 63.767766 -389.7722) (xy 63.721182 -389.764966)
			(xy 63.676266 -389.750648) (xy 63.634089 -389.729589) (xy 63.595656 -389.702289) (xy 63.561881 -389.669399)
			(xy 63.533571 -389.631703) (xy 63.522098 -389.611108) (xy 63.52159 -389.610346) (xy 63.123826 -388.922006)
			(xy 63.111947 -388.89933) (xy 63.095098 -388.850996) (xy 63.086526 -388.800533) (xy 63.08598 -388.77494)
			(xy 62.543732 -388.77494) (xy 62.855856 -389.314944) (xy 62.868575 -389.338269) (xy 62.886673 -389.388214)
			(xy 62.895895 -389.440529) (xy 62.896496 -389.46709) (xy 62.896496 -389.467344) (xy 62.896078 -389.491337)
			(xy 62.888565 -389.538731) (xy 62.873731 -389.584367) (xy 62.851941 -389.627121) (xy 62.823731 -389.665939)
			(xy 62.789797 -389.699868) (xy 62.750973 -389.72807) (xy 62.708215 -389.749852) (xy 62.662577 -389.764678)
			(xy 62.615181 -389.772182) (xy 62.591188 -389.772652) (xy 62.567615 -389.772241) (xy 62.521029 -389.764999)
			(xy 62.476112 -389.750674) (xy 62.433935 -389.729608) (xy 62.395502 -389.702301) (xy 62.361729 -389.669406)
			(xy 62.333421 -389.631705) (xy 62.321948 -389.611108) (xy 62.32144 -389.610346) (xy 61.923676 -388.922006)
			(xy 61.911759 -388.899339) (xy 61.894823 -388.851013) (xy 61.886163 -388.800542) (xy 61.885576 -388.77494)
			(xy 61.343836 -388.77494) (xy 61.65596 -389.314944) (xy 61.66868 -389.338269) (xy 61.686777 -389.388214)
			(xy 61.695999 -389.440529) (xy 61.6966 -389.46709) (xy 61.6966 -389.467344) (xy 61.696178 -389.491337)
			(xy 61.688665 -389.538731) (xy 61.673831 -389.584366) (xy 61.652041 -389.627119) (xy 61.623832 -389.665938)
			(xy 61.589898 -389.699866) (xy 61.551075 -389.728069) (xy 61.508318 -389.749851) (xy 61.46268 -389.764677)
			(xy 61.415285 -389.772182) (xy 61.391292 -389.772652) (xy 61.367719 -389.772237) (xy 61.321133 -389.764996)
			(xy 61.276216 -389.750672) (xy 61.234039 -389.729606) (xy 61.195606 -389.7023) (xy 61.161833 -389.669406)
			(xy 61.133525 -389.631705) (xy 61.122052 -389.611108) (xy 61.121544 -389.610346) (xy 60.72378 -388.922006)
			(xy 60.711863 -388.899339) (xy 60.694927 -388.851013) (xy 60.686267 -388.800542) (xy 60.68568 -388.77494)
			(xy 60.14394 -388.77494) (xy 60.456064 -389.314944) (xy 60.468784 -389.338268) (xy 60.486881 -389.388213)
			(xy 60.496104 -389.440529) (xy 60.496704 -389.46709) (xy 60.496704 -389.467344) (xy 60.496278 -389.491337)
			(xy 60.488765 -389.53873) (xy 60.473931 -389.584365) (xy 60.452142 -389.627118) (xy 60.423933 -389.665937)
			(xy 60.39 -389.699865) (xy 60.351177 -389.728067) (xy 60.308421 -389.74985) (xy 60.262783 -389.764676)
			(xy 60.215389 -389.772182) (xy 60.191396 -389.772652) (xy 60.167823 -389.772234) (xy 60.121237 -389.764993)
			(xy 60.076321 -389.75067) (xy 60.034144 -389.729605) (xy 59.99571 -389.702299) (xy 59.961937 -389.669405)
			(xy 59.933629 -389.631705) (xy 59.922156 -389.611108) (xy 59.921648 -389.610346) (xy 59.523884 -388.922006)
			(xy 59.511967 -388.899338) (xy 59.495031 -388.851013) (xy 59.486371 -388.800542) (xy 59.485784 -388.77494)
			(xy 58.94379 -388.77494) (xy 59.255914 -389.314944) (xy 59.268718 -389.338287) (xy 59.286947 -389.388304)
			(xy 59.296215 -389.440727) (xy 59.296808 -389.467344) (xy 59.296379 -389.491324) (xy 59.288874 -389.538693)
			(xy 59.274056 -389.584306) (xy 59.252289 -389.627041) (xy 59.224109 -389.665848) (xy 59.190208 -389.699772)
			(xy 59.15142 -389.72798) (xy 59.1087 -389.749776) (xy 59.063097 -389.764625) (xy 59.015733 -389.772162)
			(xy 58.991754 -389.772652) (xy 58.991246 -389.772652) (xy 58.967675 -389.772194) (xy 58.921091 -389.764961)
			(xy 58.876175 -389.750644) (xy 58.833998 -389.729586) (xy 58.795564 -389.702287) (xy 58.76179 -389.669398)
			(xy 58.73348 -389.631703) (xy 58.722006 -389.611108) (xy 58.721498 -389.610346) (xy 58.323734 -388.922006)
			(xy 58.311856 -388.89933) (xy 58.295006 -388.850996) (xy 58.286434 -388.800533) (xy 58.285888 -388.77494)
			(xy 57.743894 -388.77494) (xy 58.056018 -389.314944) (xy 58.068823 -389.338287) (xy 58.087051 -389.388304)
			(xy 58.096319 -389.440727) (xy 58.096912 -389.467344) (xy 58.096479 -389.491324) (xy 58.088974 -389.538692)
			(xy 58.074157 -389.584305) (xy 58.05239 -389.62704) (xy 58.02421 -389.665847) (xy 57.99031 -389.699771)
			(xy 57.951523 -389.727978) (xy 57.908803 -389.749775) (xy 57.8632 -389.764624) (xy 57.815837 -389.772162)
			(xy 57.791858 -389.772652) (xy 57.79135 -389.772652) (xy 57.767779 -389.772191) (xy 57.721195 -389.764958)
			(xy 57.676279 -389.750642) (xy 57.634102 -389.729584) (xy 57.595668 -389.702286) (xy 57.561894 -389.669397)
			(xy 57.533584 -389.631703) (xy 57.52211 -389.611108) (xy 57.521602 -389.610346) (xy 57.123838 -388.922006)
			(xy 57.11196 -388.89933) (xy 57.095111 -388.850996) (xy 57.086538 -388.800533) (xy 57.085992 -388.77494)
			(xy 56.543744 -388.77494) (xy 56.855868 -389.314944) (xy 56.868588 -389.338268) (xy 56.886686 -389.388213)
			(xy 56.895908 -389.440529) (xy 56.896508 -389.46709) (xy 56.896508 -389.467344) (xy 56.896078 -389.491336)
			(xy 56.888565 -389.53873) (xy 56.873732 -389.584364) (xy 56.851943 -389.627117) (xy 56.823735 -389.665935)
			(xy 56.789802 -389.699863) (xy 56.750979 -389.728066) (xy 56.708224 -389.749849) (xy 56.662587 -389.764676)
			(xy 56.615192 -389.772181) (xy 56.5912 -389.772652) (xy 56.567627 -389.772231) (xy 56.521042 -389.764991)
			(xy 56.476125 -389.750668) (xy 56.433948 -389.729603) (xy 56.395515 -389.702298) (xy 56.361742 -389.669404)
			(xy 56.333433 -389.631705) (xy 56.32196 -389.611108) (xy 56.321452 -389.610346) (xy 55.923688 -388.922006)
			(xy 55.911772 -388.899338) (xy 55.894835 -388.851013) (xy 55.886175 -388.800542) (xy 55.885588 -388.77494)
			(xy 55.343848 -388.77494) (xy 55.655972 -389.314944) (xy 55.668693 -389.338268) (xy 55.68679 -389.388213)
			(xy 55.696012 -389.440529) (xy 55.696612 -389.46709) (xy 55.696612 -389.467344) (xy 55.696178 -389.491336)
			(xy 55.688665 -389.538729) (xy 55.673832 -389.584363) (xy 55.652044 -389.627116) (xy 55.623836 -389.665934)
			(xy 55.589903 -389.699862) (xy 55.551082 -389.728065) (xy 55.508326 -389.749848) (xy 55.46269 -389.764675)
			(xy 55.415296 -389.772181) (xy 55.391304 -389.772652) (xy 55.367732 -389.772228) (xy 55.321146 -389.764988)
			(xy 55.276229 -389.750666) (xy 55.234052 -389.729602) (xy 55.195619 -389.702297) (xy 55.161846 -389.669404)
			(xy 55.133537 -389.631705) (xy 55.122064 -389.611108) (xy 55.121556 -389.610346) (xy 54.723792 -388.922006)
			(xy 54.711876 -388.899338) (xy 54.694939 -388.851012) (xy 54.686279 -388.800542) (xy 54.685692 -388.77494)
			(xy 54.143952 -388.77494) (xy 54.456076 -389.314944) (xy 54.468797 -389.338268) (xy 54.486894 -389.388213)
			(xy 54.496116 -389.440529) (xy 54.496716 -389.46709) (xy 54.496716 -389.467344) (xy 54.496278 -389.491336)
			(xy 54.488766 -389.538728) (xy 54.473933 -389.584362) (xy 54.452144 -389.627115) (xy 54.423937 -389.665932)
			(xy 54.390005 -389.69986) (xy 54.351184 -389.728063) (xy 54.308429 -389.749846) (xy 54.262793 -389.764674)
			(xy 54.2154 -389.772181) (xy 54.191408 -389.772652) (xy 54.167836 -389.772224) (xy 54.12125 -389.764986)
			(xy 54.076334 -389.750664) (xy 54.034157 -389.7296) (xy 53.995723 -389.702296) (xy 53.96195 -389.669403)
			(xy 53.933641 -389.631704) (xy 53.922168 -389.611108) (xy 53.92166 -389.610346) (xy 53.523896 -388.922006)
			(xy 53.51198 -388.899338) (xy 53.495043 -388.851012) (xy 53.486383 -388.800542) (xy 53.485796 -388.77494)
			(xy 52.943802 -388.77494) (xy 53.255926 -389.314944) (xy 53.268731 -389.338286) (xy 53.286959 -389.388304)
			(xy 53.296227 -389.440727) (xy 53.29682 -389.467344) (xy 53.296379 -389.491323) (xy 53.288875 -389.538691)
			(xy 53.274057 -389.584303) (xy 53.252292 -389.627038) (xy 53.224113 -389.665844) (xy 53.190213 -389.699768)
			(xy 53.151427 -389.727975) (xy 53.108708 -389.749772) (xy 53.063107 -389.764623) (xy 53.015745 -389.772162)
			(xy 52.991766 -389.772652) (xy 52.991258 -389.772652) (xy 52.967687 -389.772184) (xy 52.921104 -389.764953)
			(xy 52.876188 -389.750638) (xy 52.834011 -389.729581) (xy 52.795577 -389.702284) (xy 52.761802 -389.669396)
			(xy 52.733492 -389.631702) (xy 52.722018 -389.611108) (xy 52.72151 -389.610346) (xy 52.323746 -388.922006)
			(xy 52.311869 -388.89933) (xy 52.295019 -388.850996) (xy 52.286446 -388.800533) (xy 52.2859 -388.77494)
			(xy 51.743906 -388.77494) (xy 52.05603 -389.314944) (xy 52.068836 -389.338286) (xy 52.087063 -389.388304)
			(xy 52.096331 -389.440727) (xy 52.096924 -389.467344) (xy 52.096479 -389.491323) (xy 52.088975 -389.53869)
			(xy 52.074158 -389.584302) (xy 52.052392 -389.627036) (xy 52.024214 -389.665843) (xy 51.990315 -389.699767)
			(xy 51.951529 -389.727974) (xy 51.908811 -389.749771) (xy 51.86321 -389.764622) (xy 51.815849 -389.772161)
			(xy 51.79187 -389.772652) (xy 51.791362 -389.772652) (xy 51.767791 -389.772181) (xy 51.721208 -389.76495)
			(xy 51.676292 -389.750636) (xy 51.634115 -389.72958) (xy 51.595681 -389.702283) (xy 51.561907 -389.669396)
			(xy 51.533596 -389.631702) (xy 51.522122 -389.611108) (xy 51.521614 -389.610346) (xy 51.12385 -388.922006)
			(xy 51.111973 -388.899329) (xy 51.095123 -388.850996) (xy 51.08655 -388.800533) (xy 51.086004 -388.77494)
			(xy 50.543756 -388.77494) (xy 50.85588 -389.314944) (xy 50.868601 -389.338268) (xy 50.886698 -389.388213)
			(xy 50.89592 -389.440529) (xy 50.89652 -389.46709) (xy 50.89652 -389.467344) (xy 50.896078 -389.491336)
			(xy 50.888566 -389.538728) (xy 50.873733 -389.584362) (xy 50.851945 -389.627113) (xy 50.823738 -389.665931)
			(xy 50.789807 -389.699859) (xy 50.750986 -389.728062) (xy 50.708232 -389.749845) (xy 50.662597 -389.764673)
			(xy 50.615204 -389.772181) (xy 50.591212 -389.772652) (xy 50.56764 -389.772221) (xy 50.521054 -389.764983)
			(xy 50.476138 -389.750662) (xy 50.433961 -389.729599) (xy 50.395528 -389.702295) (xy 50.361754 -389.669403)
			(xy 50.333445 -389.631704) (xy 50.321972 -389.611108) (xy 50.321464 -389.610346) (xy 49.9237 -388.922006)
			(xy 49.911785 -388.899338) (xy 49.894847 -388.851012) (xy 49.886188 -388.800542) (xy 49.8856 -388.77494)
			(xy 49.34386 -388.77494) (xy 49.655984 -389.314944) (xy 49.668697 -389.338272) (xy 49.686799 -389.388215)
			(xy 49.696023 -389.44053) (xy 49.696624 -389.46709) (xy 49.696624 -389.467344) (xy 49.696178 -389.491336)
			(xy 49.688666 -389.538727) (xy 49.673833 -389.584361) (xy 49.652046 -389.627112) (xy 49.623839 -389.66593)
			(xy 49.589908 -389.699858) (xy 49.551088 -389.72806) (xy 49.508335 -389.749844) (xy 49.4627 -389.764672)
			(xy 49.415308 -389.77218) (xy 49.391316 -389.772652) (xy 49.367744 -389.772218) (xy 49.321159 -389.76498)
			(xy 49.276242 -389.75066) (xy 49.234065 -389.729597) (xy 49.195632 -389.702294) (xy 49.161858 -389.669402)
			(xy 49.133549 -389.631704) (xy 49.122076 -389.611108) (xy 49.121568 -389.610346) (xy 48.723804 -388.922006)
			(xy 48.711889 -388.899338) (xy 48.694951 -388.851012) (xy 48.686292 -388.800542) (xy 48.685704 -388.77494)
			(xy 48.143964 -388.77494) (xy 48.456088 -389.314944) (xy 48.468802 -389.338272) (xy 48.486903 -389.388215)
			(xy 48.496127 -389.44053) (xy 48.496728 -389.46709) (xy 48.496728 -389.467344) (xy 48.496278 -389.491335)
			(xy 48.488766 -389.538727) (xy 48.473934 -389.58436) (xy 48.452147 -389.627111) (xy 48.423941 -389.665928)
			(xy 48.39001 -389.699856) (xy 48.351191 -389.728059) (xy 48.308437 -389.749843) (xy 48.262803 -389.764672)
			(xy 48.215411 -389.77218) (xy 48.19142 -389.772652) (xy 48.167848 -389.772215) (xy 48.121263 -389.764978)
			(xy 48.076347 -389.750658) (xy 48.03417 -389.729595) (xy 47.995736 -389.702293) (xy 47.961962 -389.669402)
			(xy 47.933653 -389.631704) (xy 47.92218 -389.611108) (xy 47.921672 -389.610346) (xy 47.523908 -388.922006)
			(xy 47.511993 -388.899337) (xy 47.495055 -388.851012) (xy 47.486396 -388.800542) (xy 47.485808 -388.77494)
			(xy 2.509012 -388.77494) (xy 2.509012 -393.292838) (xy 47.435008 -393.292838) (xy 47.435008 -392.429238)
			(xy 47.435494 -392.401987) (xy 47.44325 -392.348039) (xy 47.458605 -392.295744) (xy 47.481247 -392.246167)
			(xy 47.510713 -392.200317) (xy 47.546404 -392.159126) (xy 47.587595 -392.123435) (xy 47.633445 -392.093969)
			(xy 47.683022 -392.071327) (xy 47.735317 -392.055972) (xy 47.789265 -392.048216) (xy 47.843767 -392.048216)
			(xy 47.897715 -392.055972) (xy 47.95001 -392.071327) (xy 47.999587 -392.093969) (xy 48.045437 -392.123435)
			(xy 48.086628 -392.159126) (xy 48.122319 -392.200317) (xy 48.151785 -392.246167) (xy 48.174427 -392.295744)
			(xy 48.189782 -392.348039) (xy 48.197538 -392.401987) (xy 48.198024 -392.429238) (xy 48.198024 -393.292838)
			(xy 48.634904 -393.292838) (xy 48.634904 -392.429238) (xy 48.63539 -392.401987) (xy 48.643146 -392.348039)
			(xy 48.658501 -392.295744) (xy 48.681143 -392.246167) (xy 48.710609 -392.200317) (xy 48.7463 -392.159126)
			(xy 48.787491 -392.123435) (xy 48.833341 -392.093969) (xy 48.882918 -392.071327) (xy 48.935213 -392.055972)
			(xy 48.989161 -392.048216) (xy 49.043663 -392.048216) (xy 49.097611 -392.055972) (xy 49.149906 -392.071327)
			(xy 49.199483 -392.093969) (xy 49.245333 -392.123435) (xy 49.286524 -392.159126) (xy 49.322215 -392.200317)
			(xy 49.351681 -392.246167) (xy 49.374323 -392.295744) (xy 49.389678 -392.348039) (xy 49.397434 -392.401987)
			(xy 49.39792 -392.429238) (xy 49.39792 -393.292838) (xy 49.8348 -393.292838) (xy 49.8348 -392.429238)
			(xy 49.835286 -392.401969) (xy 49.843048 -392.347985) (xy 49.858413 -392.295655) (xy 49.88107 -392.246045)
			(xy 49.910556 -392.200164) (xy 49.946271 -392.158947) (xy 49.987488 -392.123232) (xy 50.033369 -392.093746)
			(xy 50.082979 -392.071089) (xy 50.135309 -392.055724) (xy 50.189293 -392.047962) (xy 50.243831 -392.047962)
			(xy 50.297815 -392.055724) (xy 50.350145 -392.071089) (xy 50.399755 -392.093746) (xy 50.445636 -392.123232)
			(xy 50.486853 -392.158947) (xy 50.522568 -392.200164) (xy 50.552054 -392.246045) (xy 50.574711 -392.295655)
			(xy 50.590076 -392.347985) (xy 50.597838 -392.401969) (xy 50.598324 -392.429238) (xy 50.598324 -393.292838)
			(xy 51.034696 -393.292838) (xy 51.034696 -392.429238) (xy 51.035182 -392.401969) (xy 51.042944 -392.347985)
			(xy 51.058309 -392.295655) (xy 51.080966 -392.246045) (xy 51.110452 -392.200164) (xy 51.146167 -392.158947)
			(xy 51.187384 -392.123232) (xy 51.233265 -392.093746) (xy 51.282875 -392.071089) (xy 51.335205 -392.055724)
			(xy 51.389189 -392.047962) (xy 51.443727 -392.047962) (xy 51.497711 -392.055724) (xy 51.550041 -392.071089)
			(xy 51.599651 -392.093746) (xy 51.645532 -392.123232) (xy 51.686749 -392.158947) (xy 51.722464 -392.200164)
			(xy 51.75195 -392.246045) (xy 51.774607 -392.295655) (xy 51.789972 -392.347985) (xy 51.797734 -392.401969)
			(xy 51.79822 -392.429238) (xy 51.79822 -393.292838) (xy 52.2351 -393.292838) (xy 52.2351 -392.429238)
			(xy 52.235586 -392.401987) (xy 52.243342 -392.348039) (xy 52.258697 -392.295744) (xy 52.281339 -392.246167)
			(xy 52.310805 -392.200317) (xy 52.346496 -392.159126) (xy 52.387687 -392.123435) (xy 52.433537 -392.093969)
			(xy 52.483114 -392.071327) (xy 52.535409 -392.055972) (xy 52.589357 -392.048216) (xy 52.643859 -392.048216)
			(xy 52.697807 -392.055972) (xy 52.750102 -392.071327) (xy 52.799679 -392.093969) (xy 52.845529 -392.123435)
			(xy 52.88672 -392.159126) (xy 52.922411 -392.200317) (xy 52.951877 -392.246167) (xy 52.974519 -392.295744)
			(xy 52.989874 -392.348039) (xy 52.99763 -392.401987) (xy 52.998116 -392.429238) (xy 52.998116 -393.292838)
			(xy 53.434996 -393.292838) (xy 53.434996 -392.429238) (xy 53.435482 -392.401987) (xy 53.443238 -392.348039)
			(xy 53.458593 -392.295744) (xy 53.481235 -392.246167) (xy 53.510701 -392.200317) (xy 53.546392 -392.159126)
			(xy 53.587583 -392.123435) (xy 53.633433 -392.093969) (xy 53.68301 -392.071327) (xy 53.735305 -392.055972)
			(xy 53.789253 -392.048216) (xy 53.843755 -392.048216) (xy 53.897703 -392.055972) (xy 53.949998 -392.071327)
			(xy 53.999575 -392.093969) (xy 54.045425 -392.123435) (xy 54.086616 -392.159126) (xy 54.122307 -392.200317)
			(xy 54.151773 -392.246167) (xy 54.174415 -392.295744) (xy 54.18977 -392.348039) (xy 54.197526 -392.401987)
			(xy 54.198012 -392.429238) (xy 54.198012 -393.292838) (xy 54.634892 -393.292838) (xy 54.634892 -392.429238)
			(xy 54.635378 -392.401969) (xy 54.64314 -392.347985) (xy 54.658505 -392.295655) (xy 54.681162 -392.246045)
			(xy 54.710648 -392.200164) (xy 54.746363 -392.158947) (xy 54.78758 -392.123232) (xy 54.833461 -392.093746)
			(xy 54.883071 -392.071089) (xy 54.935401 -392.055724) (xy 54.989385 -392.047962) (xy 55.043923 -392.047962)
			(xy 55.097907 -392.055724) (xy 55.150237 -392.071089) (xy 55.199847 -392.093746) (xy 55.245728 -392.123232)
			(xy 55.286945 -392.158947) (xy 55.32266 -392.200164) (xy 55.352146 -392.246045) (xy 55.374803 -392.295655)
			(xy 55.390168 -392.347985) (xy 55.39793 -392.401969) (xy 55.398416 -392.429238) (xy 55.398416 -393.292838)
			(xy 55.834788 -393.292838) (xy 55.834788 -392.429238) (xy 55.835274 -392.401969) (xy 55.843036 -392.347985)
			(xy 55.858401 -392.295655) (xy 55.881058 -392.246045) (xy 55.910544 -392.200164) (xy 55.946259 -392.158947)
			(xy 55.987476 -392.123232) (xy 56.033357 -392.093746) (xy 56.082967 -392.071089) (xy 56.135297 -392.055724)
			(xy 56.189281 -392.047962) (xy 56.243819 -392.047962) (xy 56.297803 -392.055724) (xy 56.350133 -392.071089)
			(xy 56.399743 -392.093746) (xy 56.445624 -392.123232) (xy 56.486841 -392.158947) (xy 56.522556 -392.200164)
			(xy 56.552042 -392.246045) (xy 56.574699 -392.295655) (xy 56.590064 -392.347985) (xy 56.597826 -392.401969)
			(xy 56.598312 -392.429238) (xy 56.598312 -393.292838) (xy 57.035192 -393.292838) (xy 57.035192 -392.429238)
			(xy 57.035678 -392.401987) (xy 57.043434 -392.348039) (xy 57.058789 -392.295744) (xy 57.081431 -392.246167)
			(xy 57.110897 -392.200317) (xy 57.146588 -392.159126) (xy 57.187779 -392.123435) (xy 57.233629 -392.093969)
			(xy 57.283206 -392.071327) (xy 57.335501 -392.055972) (xy 57.389449 -392.048216) (xy 57.443951 -392.048216)
			(xy 57.497899 -392.055972) (xy 57.550194 -392.071327) (xy 57.599771 -392.093969) (xy 57.645621 -392.123435)
			(xy 57.686812 -392.159126) (xy 57.722503 -392.200317) (xy 57.751969 -392.246167) (xy 57.774611 -392.295744)
			(xy 57.789966 -392.348039) (xy 57.797722 -392.401987) (xy 57.798208 -392.429238) (xy 57.798208 -393.292838)
			(xy 58.235088 -393.292838) (xy 58.235088 -392.429238) (xy 58.235574 -392.401987) (xy 58.24333 -392.348039)
			(xy 58.258685 -392.295744) (xy 58.281327 -392.246167) (xy 58.310793 -392.200317) (xy 58.346484 -392.159126)
			(xy 58.387675 -392.123435) (xy 58.433525 -392.093969) (xy 58.483102 -392.071327) (xy 58.535397 -392.055972)
			(xy 58.589345 -392.048216) (xy 58.643847 -392.048216) (xy 58.697795 -392.055972) (xy 58.75009 -392.071327)
			(xy 58.799667 -392.093969) (xy 58.845517 -392.123435) (xy 58.886708 -392.159126) (xy 58.922399 -392.200317)
			(xy 58.951865 -392.246167) (xy 58.974507 -392.295744) (xy 58.989862 -392.348039) (xy 58.997618 -392.401987)
			(xy 58.998104 -392.429238) (xy 58.998104 -393.292838) (xy 59.434984 -393.292838) (xy 59.434984 -392.429238)
			(xy 59.43547 -392.401969) (xy 59.443232 -392.347985) (xy 59.458597 -392.295655) (xy 59.481254 -392.246045)
			(xy 59.51074 -392.200164) (xy 59.546455 -392.158947) (xy 59.587672 -392.123232) (xy 59.633553 -392.093746)
			(xy 59.683163 -392.071089) (xy 59.735493 -392.055724) (xy 59.789477 -392.047962) (xy 59.844015 -392.047962)
			(xy 59.897999 -392.055724) (xy 59.950329 -392.071089) (xy 59.999939 -392.093746) (xy 60.04582 -392.123232)
			(xy 60.087037 -392.158947) (xy 60.122752 -392.200164) (xy 60.152238 -392.246045) (xy 60.174895 -392.295655)
			(xy 60.19026 -392.347985) (xy 60.198022 -392.401969) (xy 60.198508 -392.429238) (xy 60.198508 -393.292838)
			(xy 60.63488 -393.292838) (xy 60.63488 -392.429238) (xy 60.635366 -392.401969) (xy 60.643128 -392.347985)
			(xy 60.658493 -392.295655) (xy 60.68115 -392.246045) (xy 60.710636 -392.200164) (xy 60.746351 -392.158947)
			(xy 60.787568 -392.123232) (xy 60.833449 -392.093746) (xy 60.883059 -392.071089) (xy 60.935389 -392.055724)
			(xy 60.989373 -392.047962) (xy 61.043911 -392.047962) (xy 61.097895 -392.055724) (xy 61.150225 -392.071089)
			(xy 61.199835 -392.093746) (xy 61.245716 -392.123232) (xy 61.286933 -392.158947) (xy 61.322648 -392.200164)
			(xy 61.352134 -392.246045) (xy 61.374791 -392.295655) (xy 61.390156 -392.347985) (xy 61.397918 -392.401969)
			(xy 61.398404 -392.429238) (xy 61.398404 -393.292838) (xy 61.834776 -393.292838) (xy 61.834776 -392.429238)
			(xy 61.835262 -392.401969) (xy 61.843024 -392.347985) (xy 61.858389 -392.295655) (xy 61.881046 -392.246045)
			(xy 61.910532 -392.200164) (xy 61.946247 -392.158947) (xy 61.987464 -392.123232) (xy 62.033345 -392.093746)
			(xy 62.082955 -392.071089) (xy 62.135285 -392.055724) (xy 62.189269 -392.047962) (xy 62.243807 -392.047962)
			(xy 62.297791 -392.055724) (xy 62.350121 -392.071089) (xy 62.399731 -392.093746) (xy 62.445612 -392.123232)
			(xy 62.486829 -392.158947) (xy 62.522544 -392.200164) (xy 62.55203 -392.246045) (xy 62.574687 -392.295655)
			(xy 62.590052 -392.347985) (xy 62.597814 -392.401969) (xy 62.5983 -392.429238) (xy 62.5983 -393.292838)
			(xy 63.034672 -393.292838) (xy 63.034672 -392.429238) (xy 63.035158 -392.401969) (xy 63.04292 -392.347985)
			(xy 63.058285 -392.295655) (xy 63.080942 -392.246045) (xy 63.110428 -392.200164) (xy 63.146143 -392.158947)
			(xy 63.18736 -392.123232) (xy 63.233241 -392.093746) (xy 63.282851 -392.071089) (xy 63.335181 -392.055724)
			(xy 63.389165 -392.047962) (xy 63.443703 -392.047962) (xy 63.497687 -392.055724) (xy 63.550017 -392.071089)
			(xy 63.599627 -392.093746) (xy 63.645508 -392.123232) (xy 63.686725 -392.158947) (xy 63.72244 -392.200164)
			(xy 63.751926 -392.246045) (xy 63.774583 -392.295655) (xy 63.789948 -392.347985) (xy 63.79771 -392.401969)
			(xy 63.798196 -392.429238) (xy 63.798196 -393.292838) (xy 64.235076 -393.292838) (xy 64.235076 -392.429238)
			(xy 64.235562 -392.401987) (xy 64.243318 -392.348039) (xy 64.258673 -392.295744) (xy 64.281315 -392.246167)
			(xy 64.310781 -392.200317) (xy 64.346472 -392.159126) (xy 64.387663 -392.123435) (xy 64.433513 -392.093969)
			(xy 64.48309 -392.071327) (xy 64.535385 -392.055972) (xy 64.589333 -392.048216) (xy 64.643835 -392.048216)
			(xy 64.697783 -392.055972) (xy 64.750078 -392.071327) (xy 64.799655 -392.093969) (xy 64.845505 -392.123435)
			(xy 64.886696 -392.159126) (xy 64.922387 -392.200317) (xy 64.951853 -392.246167) (xy 64.974495 -392.295744)
			(xy 64.98985 -392.348039) (xy 64.997606 -392.401987) (xy 64.998092 -392.429238) (xy 64.998092 -393.292838)
			(xy 65.434972 -393.292838) (xy 65.434972 -392.429238) (xy 65.435458 -392.401987) (xy 65.443214 -392.348039)
			(xy 65.458569 -392.295744) (xy 65.481211 -392.246167) (xy 65.510677 -392.200317) (xy 65.546368 -392.159126)
			(xy 65.587559 -392.123435) (xy 65.633409 -392.093969) (xy 65.682986 -392.071327) (xy 65.735281 -392.055972)
			(xy 65.789229 -392.048216) (xy 65.843731 -392.048216) (xy 65.897679 -392.055972) (xy 65.949974 -392.071327)
			(xy 65.999551 -392.093969) (xy 66.045401 -392.123435) (xy 66.086592 -392.159126) (xy 66.122283 -392.200317)
			(xy 66.151749 -392.246167) (xy 66.174391 -392.295744) (xy 66.189746 -392.348039) (xy 66.197502 -392.401987)
			(xy 66.197988 -392.429238) (xy 66.197988 -393.292838) (xy 79.962756 -393.292838) (xy 79.962756 -392.429238)
			(xy 79.963242 -392.401987) (xy 79.970998 -392.348039) (xy 79.986353 -392.295744) (xy 80.008995 -392.246167)
			(xy 80.038461 -392.200317) (xy 80.074152 -392.159126) (xy 80.115343 -392.123435) (xy 80.161193 -392.093969)
			(xy 80.21077 -392.071327) (xy 80.263065 -392.055972) (xy 80.317013 -392.048216) (xy 80.371515 -392.048216)
			(xy 80.425463 -392.055972) (xy 80.477758 -392.071327) (xy 80.527335 -392.093969) (xy 80.573185 -392.123435)
			(xy 80.614376 -392.159126) (xy 80.650067 -392.200317) (xy 80.679533 -392.246167) (xy 80.702175 -392.295744)
			(xy 80.71753 -392.348039) (xy 80.725286 -392.401987) (xy 80.725772 -392.429238) (xy 80.725772 -393.292838)
			(xy 81.162652 -393.292838) (xy 81.162652 -392.429238) (xy 81.163138 -392.401987) (xy 81.170894 -392.348039)
			(xy 81.186249 -392.295744) (xy 81.208891 -392.246167) (xy 81.238357 -392.200317) (xy 81.274048 -392.159126)
			(xy 81.315239 -392.123435) (xy 81.361089 -392.093969) (xy 81.410666 -392.071327) (xy 81.462961 -392.055972)
			(xy 81.516909 -392.048216) (xy 81.571411 -392.048216) (xy 81.625359 -392.055972) (xy 81.677654 -392.071327)
			(xy 81.727231 -392.093969) (xy 81.773081 -392.123435) (xy 81.814272 -392.159126) (xy 81.849963 -392.200317)
			(xy 81.879429 -392.246167) (xy 81.902071 -392.295744) (xy 81.917426 -392.348039) (xy 81.925182 -392.401987)
			(xy 81.925668 -392.429238) (xy 81.925668 -393.292838) (xy 82.362548 -393.292838) (xy 82.362548 -392.429238)
			(xy 82.363034 -392.401969) (xy 82.370796 -392.347985) (xy 82.386161 -392.295655) (xy 82.408818 -392.246045)
			(xy 82.438304 -392.200164) (xy 82.474019 -392.158947) (xy 82.515236 -392.123232) (xy 82.561117 -392.093746)
			(xy 82.610727 -392.071089) (xy 82.663057 -392.055724) (xy 82.717041 -392.047962) (xy 82.771579 -392.047962)
			(xy 82.825563 -392.055724) (xy 82.877893 -392.071089) (xy 82.927503 -392.093746) (xy 82.973384 -392.123232)
			(xy 83.014601 -392.158947) (xy 83.050316 -392.200164) (xy 83.079802 -392.246045) (xy 83.102459 -392.295655)
			(xy 83.117824 -392.347985) (xy 83.125586 -392.401969) (xy 83.126072 -392.429238) (xy 83.126072 -393.292838)
			(xy 83.562444 -393.292838) (xy 83.562444 -392.429238) (xy 83.56293 -392.401969) (xy 83.570692 -392.347985)
			(xy 83.586057 -392.295655) (xy 83.608714 -392.246045) (xy 83.6382 -392.200164) (xy 83.673915 -392.158947)
			(xy 83.715132 -392.123232) (xy 83.761013 -392.093746) (xy 83.810623 -392.071089) (xy 83.862953 -392.055724)
			(xy 83.916937 -392.047962) (xy 83.971475 -392.047962) (xy 84.025459 -392.055724) (xy 84.077789 -392.071089)
			(xy 84.127399 -392.093746) (xy 84.17328 -392.123232) (xy 84.214497 -392.158947) (xy 84.250212 -392.200164)
			(xy 84.279698 -392.246045) (xy 84.302355 -392.295655) (xy 84.31772 -392.347985) (xy 84.325482 -392.401969)
			(xy 84.325968 -392.429238) (xy 84.325968 -393.292838) (xy 84.762848 -393.292838) (xy 84.762848 -392.429238)
			(xy 84.763334 -392.401987) (xy 84.77109 -392.348039) (xy 84.786445 -392.295744) (xy 84.809087 -392.246167)
			(xy 84.838553 -392.200317) (xy 84.874244 -392.159126) (xy 84.915435 -392.123435) (xy 84.961285 -392.093969)
			(xy 85.010862 -392.071327) (xy 85.063157 -392.055972) (xy 85.117105 -392.048216) (xy 85.171607 -392.048216)
			(xy 85.225555 -392.055972) (xy 85.27785 -392.071327) (xy 85.327427 -392.093969) (xy 85.373277 -392.123435)
			(xy 85.414468 -392.159126) (xy 85.450159 -392.200317) (xy 85.479625 -392.246167) (xy 85.502267 -392.295744)
			(xy 85.517622 -392.348039) (xy 85.525378 -392.401987) (xy 85.525864 -392.429238) (xy 85.525864 -393.292838)
			(xy 85.962744 -393.292838) (xy 85.962744 -392.429238) (xy 85.96323 -392.401987) (xy 85.970986 -392.348039)
			(xy 85.986341 -392.295744) (xy 86.008983 -392.246167) (xy 86.038449 -392.200317) (xy 86.07414 -392.159126)
			(xy 86.115331 -392.123435) (xy 86.161181 -392.093969) (xy 86.210758 -392.071327) (xy 86.263053 -392.055972)
			(xy 86.317001 -392.048216) (xy 86.371503 -392.048216) (xy 86.425451 -392.055972) (xy 86.477746 -392.071327)
			(xy 86.527323 -392.093969) (xy 86.573173 -392.123435) (xy 86.614364 -392.159126) (xy 86.650055 -392.200317)
			(xy 86.679521 -392.246167) (xy 86.702163 -392.295744) (xy 86.717518 -392.348039) (xy 86.725274 -392.401987)
			(xy 86.72576 -392.429238) (xy 86.72576 -393.292838) (xy 87.16264 -393.292838) (xy 87.16264 -392.429238)
			(xy 87.163126 -392.401969) (xy 87.170888 -392.347985) (xy 87.186253 -392.295655) (xy 87.20891 -392.246045)
			(xy 87.238396 -392.200164) (xy 87.274111 -392.158947) (xy 87.315328 -392.123232) (xy 87.361209 -392.093746)
			(xy 87.410819 -392.071089) (xy 87.463149 -392.055724) (xy 87.517133 -392.047962) (xy 87.571671 -392.047962)
			(xy 87.625655 -392.055724) (xy 87.677985 -392.071089) (xy 87.727595 -392.093746) (xy 87.773476 -392.123232)
			(xy 87.814693 -392.158947) (xy 87.850408 -392.200164) (xy 87.879894 -392.246045) (xy 87.902551 -392.295655)
			(xy 87.917916 -392.347985) (xy 87.925678 -392.401969) (xy 87.926164 -392.429238) (xy 87.926164 -393.292838)
			(xy 88.362536 -393.292838) (xy 88.362536 -392.429238) (xy 88.363022 -392.401969) (xy 88.370784 -392.347985)
			(xy 88.386149 -392.295655) (xy 88.408806 -392.246045) (xy 88.438292 -392.200164) (xy 88.474007 -392.158947)
			(xy 88.515224 -392.123232) (xy 88.561105 -392.093746) (xy 88.610715 -392.071089) (xy 88.663045 -392.055724)
			(xy 88.717029 -392.047962) (xy 88.771567 -392.047962) (xy 88.825551 -392.055724) (xy 88.877881 -392.071089)
			(xy 88.927491 -392.093746) (xy 88.973372 -392.123232) (xy 89.014589 -392.158947) (xy 89.050304 -392.200164)
			(xy 89.07979 -392.246045) (xy 89.102447 -392.295655) (xy 89.117812 -392.347985) (xy 89.125574 -392.401969)
			(xy 89.12606 -392.429238) (xy 89.12606 -393.292838) (xy 89.56294 -393.292838) (xy 89.56294 -392.429238)
			(xy 89.563426 -392.401987) (xy 89.571182 -392.348039) (xy 89.586537 -392.295744) (xy 89.609179 -392.246167)
			(xy 89.638645 -392.200317) (xy 89.674336 -392.159126) (xy 89.715527 -392.123435) (xy 89.761377 -392.093969)
			(xy 89.810954 -392.071327) (xy 89.863249 -392.055972) (xy 89.917197 -392.048216) (xy 89.971699 -392.048216)
			(xy 90.025647 -392.055972) (xy 90.077942 -392.071327) (xy 90.127519 -392.093969) (xy 90.173369 -392.123435)
			(xy 90.21456 -392.159126) (xy 90.250251 -392.200317) (xy 90.279717 -392.246167) (xy 90.302359 -392.295744)
			(xy 90.317714 -392.348039) (xy 90.32547 -392.401987) (xy 90.325956 -392.429238) (xy 90.325956 -393.292838)
			(xy 90.762836 -393.292838) (xy 90.762836 -392.429238) (xy 90.763322 -392.401987) (xy 90.771078 -392.348039)
			(xy 90.786433 -392.295744) (xy 90.809075 -392.246167) (xy 90.838541 -392.200317) (xy 90.874232 -392.159126)
			(xy 90.915423 -392.123435) (xy 90.961273 -392.093969) (xy 91.01085 -392.071327) (xy 91.063145 -392.055972)
			(xy 91.117093 -392.048216) (xy 91.171595 -392.048216) (xy 91.225543 -392.055972) (xy 91.277838 -392.071327)
			(xy 91.327415 -392.093969) (xy 91.373265 -392.123435) (xy 91.414456 -392.159126) (xy 91.450147 -392.200317)
			(xy 91.479613 -392.246167) (xy 91.502255 -392.295744) (xy 91.51761 -392.348039) (xy 91.525366 -392.401987)
			(xy 91.525852 -392.429238) (xy 91.525852 -393.292838) (xy 91.962732 -393.292838) (xy 91.962732 -392.429238)
			(xy 91.963218 -392.401969) (xy 91.97098 -392.347985) (xy 91.986345 -392.295655) (xy 92.009002 -392.246045)
			(xy 92.038488 -392.200164) (xy 92.074203 -392.158947) (xy 92.11542 -392.123232) (xy 92.161301 -392.093746)
			(xy 92.210911 -392.071089) (xy 92.263241 -392.055724) (xy 92.317225 -392.047962) (xy 92.371763 -392.047962)
			(xy 92.425747 -392.055724) (xy 92.478077 -392.071089) (xy 92.527687 -392.093746) (xy 92.573568 -392.123232)
			(xy 92.614785 -392.158947) (xy 92.6505 -392.200164) (xy 92.679986 -392.246045) (xy 92.702643 -392.295655)
			(xy 92.718008 -392.347985) (xy 92.72577 -392.401969) (xy 92.726256 -392.429238) (xy 92.726256 -393.292838)
			(xy 93.162628 -393.292838) (xy 93.162628 -392.429238) (xy 93.163114 -392.401969) (xy 93.170876 -392.347985)
			(xy 93.186241 -392.295655) (xy 93.208898 -392.246045) (xy 93.238384 -392.200164) (xy 93.274099 -392.158947)
			(xy 93.315316 -392.123232) (xy 93.361197 -392.093746) (xy 93.410807 -392.071089) (xy 93.463137 -392.055724)
			(xy 93.517121 -392.047962) (xy 93.571659 -392.047962) (xy 93.625643 -392.055724) (xy 93.677973 -392.071089)
			(xy 93.727583 -392.093746) (xy 93.773464 -392.123232) (xy 93.814681 -392.158947) (xy 93.850396 -392.200164)
			(xy 93.879882 -392.246045) (xy 93.902539 -392.295655) (xy 93.917904 -392.347985) (xy 93.925666 -392.401969)
			(xy 93.926152 -392.429238) (xy 93.926152 -393.292838) (xy 94.362524 -393.292838) (xy 94.362524 -392.429238)
			(xy 94.36301 -392.401969) (xy 94.370772 -392.347985) (xy 94.386137 -392.295655) (xy 94.408794 -392.246045)
			(xy 94.43828 -392.200164) (xy 94.473995 -392.158947) (xy 94.515212 -392.123232) (xy 94.561093 -392.093746)
			(xy 94.610703 -392.071089) (xy 94.663033 -392.055724) (xy 94.717017 -392.047962) (xy 94.771555 -392.047962)
			(xy 94.825539 -392.055724) (xy 94.877869 -392.071089) (xy 94.927479 -392.093746) (xy 94.97336 -392.123232)
			(xy 95.014577 -392.158947) (xy 95.050292 -392.200164) (xy 95.079778 -392.246045) (xy 95.102435 -392.295655)
			(xy 95.1178 -392.347985) (xy 95.125562 -392.401969) (xy 95.126048 -392.429238) (xy 95.126048 -393.292838)
			(xy 95.56242 -393.292838) (xy 95.56242 -392.429238) (xy 95.562906 -392.401969) (xy 95.570668 -392.347985)
			(xy 95.586033 -392.295655) (xy 95.60869 -392.246045) (xy 95.638176 -392.200164) (xy 95.673891 -392.158947)
			(xy 95.715108 -392.123232) (xy 95.760989 -392.093746) (xy 95.810599 -392.071089) (xy 95.862929 -392.055724)
			(xy 95.916913 -392.047962) (xy 95.971451 -392.047962) (xy 96.025435 -392.055724) (xy 96.077765 -392.071089)
			(xy 96.127375 -392.093746) (xy 96.173256 -392.123232) (xy 96.214473 -392.158947) (xy 96.250188 -392.200164)
			(xy 96.279674 -392.246045) (xy 96.302331 -392.295655) (xy 96.317696 -392.347985) (xy 96.325458 -392.401969)
			(xy 96.325944 -392.429238) (xy 96.325944 -393.292838) (xy 96.762824 -393.292838) (xy 96.762824 -392.429238)
			(xy 96.76331 -392.401987) (xy 96.771066 -392.348039) (xy 96.786421 -392.295744) (xy 96.809063 -392.246167)
			(xy 96.838529 -392.200317) (xy 96.87422 -392.159126) (xy 96.915411 -392.123435) (xy 96.961261 -392.093969)
			(xy 97.010838 -392.071327) (xy 97.063133 -392.055972) (xy 97.117081 -392.048216) (xy 97.171583 -392.048216)
			(xy 97.225531 -392.055972) (xy 97.277826 -392.071327) (xy 97.327403 -392.093969) (xy 97.373253 -392.123435)
			(xy 97.414444 -392.159126) (xy 97.450135 -392.200317) (xy 97.479601 -392.246167) (xy 97.502243 -392.295744)
			(xy 97.517598 -392.348039) (xy 97.525354 -392.401987) (xy 97.52584 -392.429238) (xy 97.52584 -393.292838)
			(xy 97.96272 -393.292838) (xy 97.96272 -392.429238) (xy 97.963206 -392.401987) (xy 97.970962 -392.348039)
			(xy 97.986317 -392.295744) (xy 98.008959 -392.246167) (xy 98.038425 -392.200317) (xy 98.074116 -392.159126)
			(xy 98.115307 -392.123435) (xy 98.161157 -392.093969) (xy 98.210734 -392.071327) (xy 98.263029 -392.055972)
			(xy 98.316977 -392.048216) (xy 98.371479 -392.048216) (xy 98.425427 -392.055972) (xy 98.477722 -392.071327)
			(xy 98.527299 -392.093969) (xy 98.573149 -392.123435) (xy 98.61434 -392.159126) (xy 98.650031 -392.200317)
			(xy 98.679497 -392.246167) (xy 98.702139 -392.295744) (xy 98.717494 -392.348039) (xy 98.72525 -392.401987)
			(xy 98.725736 -392.429238) (xy 98.725736 -393.292838) (xy 114.534696 -393.292838) (xy 114.534696 -392.429238)
			(xy 114.535182 -392.401969) (xy 114.542944 -392.347985) (xy 114.558309 -392.295655) (xy 114.580966 -392.246045)
			(xy 114.610452 -392.200164) (xy 114.646167 -392.158947) (xy 114.687384 -392.123232) (xy 114.733265 -392.093746)
			(xy 114.782875 -392.071089) (xy 114.835205 -392.055724) (xy 114.889189 -392.047962) (xy 114.943727 -392.047962)
			(xy 114.997711 -392.055724) (xy 115.050041 -392.071089) (xy 115.099651 -392.093746) (xy 115.145532 -392.123232)
			(xy 115.186749 -392.158947) (xy 115.222464 -392.200164) (xy 115.25195 -392.246045) (xy 115.274607 -392.295655)
			(xy 115.289972 -392.347985) (xy 115.297734 -392.401969) (xy 115.29822 -392.429238) (xy 115.29822 -393.292838)
			(xy 115.734592 -393.292838) (xy 115.734592 -392.429238) (xy 115.735078 -392.401969) (xy 115.74284 -392.347985)
			(xy 115.758205 -392.295655) (xy 115.780862 -392.246045) (xy 115.810348 -392.200164) (xy 115.846063 -392.158947)
			(xy 115.88728 -392.123232) (xy 115.933161 -392.093746) (xy 115.982771 -392.071089) (xy 116.035101 -392.055724)
			(xy 116.089085 -392.047962) (xy 116.143623 -392.047962) (xy 116.197607 -392.055724) (xy 116.249937 -392.071089)
			(xy 116.299547 -392.093746) (xy 116.345428 -392.123232) (xy 116.386645 -392.158947) (xy 116.42236 -392.200164)
			(xy 116.451846 -392.246045) (xy 116.474503 -392.295655) (xy 116.489868 -392.347985) (xy 116.49763 -392.401969)
			(xy 116.498116 -392.429238) (xy 116.498116 -393.292838) (xy 116.934996 -393.292838) (xy 116.934996 -392.429238)
			(xy 116.935482 -392.401987) (xy 116.943238 -392.348039) (xy 116.958593 -392.295744) (xy 116.981235 -392.246167)
			(xy 117.010701 -392.200317) (xy 117.046392 -392.159126) (xy 117.087583 -392.123435) (xy 117.133433 -392.093969)
			(xy 117.18301 -392.071327) (xy 117.235305 -392.055972) (xy 117.289253 -392.048216) (xy 117.343755 -392.048216)
			(xy 117.397703 -392.055972) (xy 117.449998 -392.071327) (xy 117.499575 -392.093969) (xy 117.545425 -392.123435)
			(xy 117.586616 -392.159126) (xy 117.622307 -392.200317) (xy 117.651773 -392.246167) (xy 117.674415 -392.295744)
			(xy 117.68977 -392.348039) (xy 117.697526 -392.401987) (xy 117.698012 -392.429238) (xy 117.698012 -393.292838)
			(xy 118.134892 -393.292838) (xy 118.134892 -392.429238) (xy 118.135378 -392.401987) (xy 118.143134 -392.348039)
			(xy 118.158489 -392.295744) (xy 118.181131 -392.246167) (xy 118.210597 -392.200317) (xy 118.246288 -392.159126)
			(xy 118.287479 -392.123435) (xy 118.333329 -392.093969) (xy 118.382906 -392.071327) (xy 118.435201 -392.055972)
			(xy 118.489149 -392.048216) (xy 118.543651 -392.048216) (xy 118.597599 -392.055972) (xy 118.649894 -392.071327)
			(xy 118.699471 -392.093969) (xy 118.745321 -392.123435) (xy 118.786512 -392.159126) (xy 118.822203 -392.200317)
			(xy 118.851669 -392.246167) (xy 118.874311 -392.295744) (xy 118.889666 -392.348039) (xy 118.897422 -392.401987)
			(xy 118.897908 -392.429238) (xy 118.897908 -393.292838) (xy 119.334788 -393.292838) (xy 119.334788 -392.429238)
			(xy 119.335274 -392.401969) (xy 119.343036 -392.347985) (xy 119.358401 -392.295655) (xy 119.381058 -392.246045)
			(xy 119.410544 -392.200164) (xy 119.446259 -392.158947) (xy 119.487476 -392.123232) (xy 119.533357 -392.093746)
			(xy 119.582967 -392.071089) (xy 119.635297 -392.055724) (xy 119.689281 -392.047962) (xy 119.743819 -392.047962)
			(xy 119.797803 -392.055724) (xy 119.850133 -392.071089) (xy 119.899743 -392.093746) (xy 119.945624 -392.123232)
			(xy 119.986841 -392.158947) (xy 120.022556 -392.200164) (xy 120.052042 -392.246045) (xy 120.074699 -392.295655)
			(xy 120.090064 -392.347985) (xy 120.097826 -392.401969) (xy 120.098312 -392.429238) (xy 120.098312 -393.292838)
			(xy 120.534684 -393.292838) (xy 120.534684 -392.429238) (xy 120.53517 -392.401969) (xy 120.542932 -392.347985)
			(xy 120.558297 -392.295655) (xy 120.580954 -392.246045) (xy 120.61044 -392.200164) (xy 120.646155 -392.158947)
			(xy 120.687372 -392.123232) (xy 120.733253 -392.093746) (xy 120.782863 -392.071089) (xy 120.835193 -392.055724)
			(xy 120.889177 -392.047962) (xy 120.943715 -392.047962) (xy 120.997699 -392.055724) (xy 121.050029 -392.071089)
			(xy 121.099639 -392.093746) (xy 121.14552 -392.123232) (xy 121.186737 -392.158947) (xy 121.222452 -392.200164)
			(xy 121.251938 -392.246045) (xy 121.274595 -392.295655) (xy 121.28996 -392.347985) (xy 121.297722 -392.401969)
			(xy 121.298208 -392.429238) (xy 121.298208 -393.292838) (xy 121.735088 -393.292838) (xy 121.735088 -392.429238)
			(xy 121.735574 -392.401987) (xy 121.74333 -392.348039) (xy 121.758685 -392.295744) (xy 121.781327 -392.246167)
			(xy 121.810793 -392.200317) (xy 121.846484 -392.159126) (xy 121.887675 -392.123435) (xy 121.933525 -392.093969)
			(xy 121.983102 -392.071327) (xy 122.035397 -392.055972) (xy 122.089345 -392.048216) (xy 122.143847 -392.048216)
			(xy 122.197795 -392.055972) (xy 122.25009 -392.071327) (xy 122.299667 -392.093969) (xy 122.345517 -392.123435)
			(xy 122.386708 -392.159126) (xy 122.422399 -392.200317) (xy 122.451865 -392.246167) (xy 122.474507 -392.295744)
			(xy 122.489862 -392.348039) (xy 122.497618 -392.401987) (xy 122.498104 -392.429238) (xy 122.498104 -393.292838)
			(xy 122.934984 -393.292838) (xy 122.934984 -392.429238) (xy 122.93547 -392.401987) (xy 122.943226 -392.348039)
			(xy 122.958581 -392.295744) (xy 122.981223 -392.246167) (xy 123.010689 -392.200317) (xy 123.04638 -392.159126)
			(xy 123.087571 -392.123435) (xy 123.133421 -392.093969) (xy 123.182998 -392.071327) (xy 123.235293 -392.055972)
			(xy 123.289241 -392.048216) (xy 123.343743 -392.048216) (xy 123.397691 -392.055972) (xy 123.449986 -392.071327)
			(xy 123.499563 -392.093969) (xy 123.545413 -392.123435) (xy 123.586604 -392.159126) (xy 123.622295 -392.200317)
			(xy 123.651761 -392.246167) (xy 123.674403 -392.295744) (xy 123.689758 -392.348039) (xy 123.697514 -392.401987)
			(xy 123.698 -392.429238) (xy 123.698 -393.292838) (xy 124.13488 -393.292838) (xy 124.13488 -392.429238)
			(xy 124.135366 -392.401969) (xy 124.143128 -392.347985) (xy 124.158493 -392.295655) (xy 124.18115 -392.246045)
			(xy 124.210636 -392.200164) (xy 124.246351 -392.158947) (xy 124.287568 -392.123232) (xy 124.333449 -392.093746)
			(xy 124.383059 -392.071089) (xy 124.435389 -392.055724) (xy 124.489373 -392.047962) (xy 124.543911 -392.047962)
			(xy 124.597895 -392.055724) (xy 124.650225 -392.071089) (xy 124.699835 -392.093746) (xy 124.745716 -392.123232)
			(xy 124.786933 -392.158947) (xy 124.822648 -392.200164) (xy 124.852134 -392.246045) (xy 124.874791 -392.295655)
			(xy 124.890156 -392.347985) (xy 124.897918 -392.401969) (xy 124.898404 -392.429238) (xy 124.898404 -393.292838)
			(xy 125.334776 -393.292838) (xy 125.334776 -392.429238) (xy 125.335262 -392.401969) (xy 125.343024 -392.347985)
			(xy 125.358389 -392.295655) (xy 125.381046 -392.246045) (xy 125.410532 -392.200164) (xy 125.446247 -392.158947)
			(xy 125.487464 -392.123232) (xy 125.533345 -392.093746) (xy 125.582955 -392.071089) (xy 125.635285 -392.055724)
			(xy 125.689269 -392.047962) (xy 125.743807 -392.047962) (xy 125.797791 -392.055724) (xy 125.850121 -392.071089)
			(xy 125.899731 -392.093746) (xy 125.945612 -392.123232) (xy 125.986829 -392.158947) (xy 126.022544 -392.200164)
			(xy 126.05203 -392.246045) (xy 126.074687 -392.295655) (xy 126.090052 -392.347985) (xy 126.097814 -392.401969)
			(xy 126.0983 -392.429238) (xy 126.0983 -393.292838) (xy 126.53518 -393.292838) (xy 126.53518 -392.429238)
			(xy 126.535666 -392.401987) (xy 126.543422 -392.348039) (xy 126.558777 -392.295744) (xy 126.581419 -392.246167)
			(xy 126.610885 -392.200317) (xy 126.646576 -392.159126) (xy 126.687767 -392.123435) (xy 126.733617 -392.093969)
			(xy 126.783194 -392.071327) (xy 126.835489 -392.055972) (xy 126.889437 -392.048216) (xy 126.943939 -392.048216)
			(xy 126.997887 -392.055972) (xy 127.050182 -392.071327) (xy 127.099759 -392.093969) (xy 127.145609 -392.123435)
			(xy 127.1868 -392.159126) (xy 127.222491 -392.200317) (xy 127.251957 -392.246167) (xy 127.274599 -392.295744)
			(xy 127.289954 -392.348039) (xy 127.29771 -392.401987) (xy 127.298196 -392.429238) (xy 127.298196 -393.292838)
			(xy 127.735076 -393.292838) (xy 127.735076 -392.429238) (xy 127.735562 -392.401987) (xy 127.743318 -392.348039)
			(xy 127.758673 -392.295744) (xy 127.781315 -392.246167) (xy 127.810781 -392.200317) (xy 127.846472 -392.159126)
			(xy 127.887663 -392.123435) (xy 127.933513 -392.093969) (xy 127.98309 -392.071327) (xy 128.035385 -392.055972)
			(xy 128.089333 -392.048216) (xy 128.143835 -392.048216) (xy 128.197783 -392.055972) (xy 128.250078 -392.071327)
			(xy 128.299655 -392.093969) (xy 128.345505 -392.123435) (xy 128.386696 -392.159126) (xy 128.422387 -392.200317)
			(xy 128.451853 -392.246167) (xy 128.474495 -392.295744) (xy 128.48985 -392.348039) (xy 128.497606 -392.401987)
			(xy 128.498092 -392.429238) (xy 128.498092 -393.292838) (xy 128.934972 -393.292838) (xy 128.934972 -392.429238)
			(xy 128.935458 -392.401987) (xy 128.943214 -392.348039) (xy 128.958569 -392.295744) (xy 128.981211 -392.246167)
			(xy 129.010677 -392.200317) (xy 129.046368 -392.159126) (xy 129.087559 -392.123435) (xy 129.133409 -392.093969)
			(xy 129.182986 -392.071327) (xy 129.235281 -392.055972) (xy 129.289229 -392.048216) (xy 129.343731 -392.048216)
			(xy 129.397679 -392.055972) (xy 129.449974 -392.071327) (xy 129.499551 -392.093969) (xy 129.545401 -392.123435)
			(xy 129.586592 -392.159126) (xy 129.622283 -392.200317) (xy 129.651749 -392.246167) (xy 129.674391 -392.295744)
			(xy 129.689746 -392.348039) (xy 129.697502 -392.401987) (xy 129.697988 -392.429238) (xy 129.697988 -393.292838)
			(xy 130.134868 -393.292838) (xy 130.134868 -392.429238) (xy 130.135354 -392.401987) (xy 130.14311 -392.348039)
			(xy 130.158465 -392.295744) (xy 130.181107 -392.246167) (xy 130.210573 -392.200317) (xy 130.246264 -392.159126)
			(xy 130.287455 -392.123435) (xy 130.333305 -392.093969) (xy 130.382882 -392.071327) (xy 130.435177 -392.055972)
			(xy 130.489125 -392.048216) (xy 130.543627 -392.048216) (xy 130.597575 -392.055972) (xy 130.64987 -392.071327)
			(xy 130.699447 -392.093969) (xy 130.745297 -392.123435) (xy 130.786488 -392.159126) (xy 130.822179 -392.200317)
			(xy 130.851645 -392.246167) (xy 130.874287 -392.295744) (xy 130.889642 -392.348039) (xy 130.897398 -392.401987)
			(xy 130.897884 -392.429238) (xy 130.897884 -393.292838) (xy 131.334764 -393.292838) (xy 131.334764 -392.429238)
			(xy 131.33525 -392.401969) (xy 131.343012 -392.347985) (xy 131.358377 -392.295655) (xy 131.381034 -392.246045)
			(xy 131.41052 -392.200164) (xy 131.446235 -392.158947) (xy 131.487452 -392.123232) (xy 131.533333 -392.093746)
			(xy 131.582943 -392.071089) (xy 131.635273 -392.055724) (xy 131.689257 -392.047962) (xy 131.743795 -392.047962)
			(xy 131.797779 -392.055724) (xy 131.850109 -392.071089) (xy 131.899719 -392.093746) (xy 131.9456 -392.123232)
			(xy 131.986817 -392.158947) (xy 132.022532 -392.200164) (xy 132.052018 -392.246045) (xy 132.074675 -392.295655)
			(xy 132.09004 -392.347985) (xy 132.097802 -392.401969) (xy 132.098288 -392.429238) (xy 132.098288 -393.292838)
			(xy 132.53466 -393.292838) (xy 132.53466 -392.429238) (xy 132.535146 -392.401969) (xy 132.542908 -392.347985)
			(xy 132.558273 -392.295655) (xy 132.58093 -392.246045) (xy 132.610416 -392.200164) (xy 132.646131 -392.158947)
			(xy 132.687348 -392.123232) (xy 132.733229 -392.093746) (xy 132.782839 -392.071089) (xy 132.835169 -392.055724)
			(xy 132.889153 -392.047962) (xy 132.943691 -392.047962) (xy 132.997675 -392.055724) (xy 133.050005 -392.071089)
			(xy 133.099615 -392.093746) (xy 133.145496 -392.123232) (xy 133.186713 -392.158947) (xy 133.222428 -392.200164)
			(xy 133.251914 -392.246045) (xy 133.274571 -392.295655) (xy 133.289936 -392.347985) (xy 133.297698 -392.401969)
			(xy 133.298184 -392.429238) (xy 133.298184 -393.292838) (xy 147.062444 -393.292838) (xy 147.062444 -392.429238)
			(xy 147.06293 -392.401969) (xy 147.070692 -392.347985) (xy 147.086057 -392.295655) (xy 147.108714 -392.246045)
			(xy 147.1382 -392.200164) (xy 147.173915 -392.158947) (xy 147.215132 -392.123232) (xy 147.261013 -392.093746)
			(xy 147.310623 -392.071089) (xy 147.362953 -392.055724) (xy 147.416937 -392.047962) (xy 147.471475 -392.047962)
			(xy 147.525459 -392.055724) (xy 147.577789 -392.071089) (xy 147.627399 -392.093746) (xy 147.67328 -392.123232)
			(xy 147.714497 -392.158947) (xy 147.750212 -392.200164) (xy 147.779698 -392.246045) (xy 147.802355 -392.295655)
			(xy 147.81772 -392.347985) (xy 147.825482 -392.401969) (xy 147.825968 -392.429238) (xy 147.825968 -393.292838)
			(xy 148.26234 -393.292838) (xy 148.26234 -392.429238) (xy 148.262826 -392.401969) (xy 148.270588 -392.347985)
			(xy 148.285953 -392.295655) (xy 148.30861 -392.246045) (xy 148.338096 -392.200164) (xy 148.373811 -392.158947)
			(xy 148.415028 -392.123232) (xy 148.460909 -392.093746) (xy 148.510519 -392.071089) (xy 148.562849 -392.055724)
			(xy 148.616833 -392.047962) (xy 148.671371 -392.047962) (xy 148.725355 -392.055724) (xy 148.777685 -392.071089)
			(xy 148.827295 -392.093746) (xy 148.873176 -392.123232) (xy 148.914393 -392.158947) (xy 148.950108 -392.200164)
			(xy 148.979594 -392.246045) (xy 149.002251 -392.295655) (xy 149.017616 -392.347985) (xy 149.025378 -392.401969)
			(xy 149.025864 -392.429238) (xy 149.025864 -393.292838) (xy 149.462744 -393.292838) (xy 149.462744 -392.429238)
			(xy 149.46323 -392.401987) (xy 149.470986 -392.348039) (xy 149.486341 -392.295744) (xy 149.508983 -392.246167)
			(xy 149.538449 -392.200317) (xy 149.57414 -392.159126) (xy 149.615331 -392.123435) (xy 149.661181 -392.093969)
			(xy 149.710758 -392.071327) (xy 149.763053 -392.055972) (xy 149.817001 -392.048216) (xy 149.871503 -392.048216)
			(xy 149.925451 -392.055972) (xy 149.977746 -392.071327) (xy 150.027323 -392.093969) (xy 150.073173 -392.123435)
			(xy 150.114364 -392.159126) (xy 150.150055 -392.200317) (xy 150.179521 -392.246167) (xy 150.202163 -392.295744)
			(xy 150.217518 -392.348039) (xy 150.225274 -392.401987) (xy 150.22576 -392.429238) (xy 150.22576 -393.292838)
			(xy 150.66264 -393.292838) (xy 150.66264 -392.429238) (xy 150.663126 -392.401987) (xy 150.670882 -392.348039)
			(xy 150.686237 -392.295744) (xy 150.708879 -392.246167) (xy 150.738345 -392.200317) (xy 150.774036 -392.159126)
			(xy 150.815227 -392.123435) (xy 150.861077 -392.093969) (xy 150.910654 -392.071327) (xy 150.962949 -392.055972)
			(xy 151.016897 -392.048216) (xy 151.071399 -392.048216) (xy 151.125347 -392.055972) (xy 151.177642 -392.071327)
			(xy 151.227219 -392.093969) (xy 151.273069 -392.123435) (xy 151.31426 -392.159126) (xy 151.349951 -392.200317)
			(xy 151.379417 -392.246167) (xy 151.402059 -392.295744) (xy 151.417414 -392.348039) (xy 151.42517 -392.401987)
			(xy 151.425656 -392.429238) (xy 151.425656 -393.292838) (xy 151.862536 -393.292838) (xy 151.862536 -392.429238)
			(xy 151.863022 -392.401969) (xy 151.870784 -392.347985) (xy 151.886149 -392.295655) (xy 151.908806 -392.246045)
			(xy 151.938292 -392.200164) (xy 151.974007 -392.158947) (xy 152.015224 -392.123232) (xy 152.061105 -392.093746)
			(xy 152.110715 -392.071089) (xy 152.163045 -392.055724) (xy 152.217029 -392.047962) (xy 152.271567 -392.047962)
			(xy 152.325551 -392.055724) (xy 152.377881 -392.071089) (xy 152.427491 -392.093746) (xy 152.473372 -392.123232)
			(xy 152.514589 -392.158947) (xy 152.550304 -392.200164) (xy 152.57979 -392.246045) (xy 152.602447 -392.295655)
			(xy 152.617812 -392.347985) (xy 152.625574 -392.401969) (xy 152.62606 -392.429238) (xy 152.62606 -393.292838)
			(xy 153.062432 -393.292838) (xy 153.062432 -392.429238) (xy 153.062918 -392.401969) (xy 153.07068 -392.347985)
			(xy 153.086045 -392.295655) (xy 153.108702 -392.246045) (xy 153.138188 -392.200164) (xy 153.173903 -392.158947)
			(xy 153.21512 -392.123232) (xy 153.261001 -392.093746) (xy 153.310611 -392.071089) (xy 153.362941 -392.055724)
			(xy 153.416925 -392.047962) (xy 153.471463 -392.047962) (xy 153.525447 -392.055724) (xy 153.577777 -392.071089)
			(xy 153.627387 -392.093746) (xy 153.673268 -392.123232) (xy 153.714485 -392.158947) (xy 153.7502 -392.200164)
			(xy 153.779686 -392.246045) (xy 153.802343 -392.295655) (xy 153.817708 -392.347985) (xy 153.82547 -392.401969)
			(xy 153.825956 -392.429238) (xy 153.825956 -393.292838) (xy 154.262836 -393.292838) (xy 154.262836 -392.429238)
			(xy 154.263322 -392.401987) (xy 154.271078 -392.348039) (xy 154.286433 -392.295744) (xy 154.309075 -392.246167)
			(xy 154.338541 -392.200317) (xy 154.374232 -392.159126) (xy 154.415423 -392.123435) (xy 154.461273 -392.093969)
			(xy 154.51085 -392.071327) (xy 154.563145 -392.055972) (xy 154.617093 -392.048216) (xy 154.671595 -392.048216)
			(xy 154.725543 -392.055972) (xy 154.777838 -392.071327) (xy 154.827415 -392.093969) (xy 154.873265 -392.123435)
			(xy 154.914456 -392.159126) (xy 154.950147 -392.200317) (xy 154.979613 -392.246167) (xy 155.002255 -392.295744)
			(xy 155.01761 -392.348039) (xy 155.025366 -392.401987) (xy 155.025852 -392.429238) (xy 155.025852 -393.292838)
			(xy 155.462732 -393.292838) (xy 155.462732 -392.429238) (xy 155.463218 -392.401987) (xy 155.470974 -392.348039)
			(xy 155.486329 -392.295744) (xy 155.508971 -392.246167) (xy 155.538437 -392.200317) (xy 155.574128 -392.159126)
			(xy 155.615319 -392.123435) (xy 155.661169 -392.093969) (xy 155.710746 -392.071327) (xy 155.763041 -392.055972)
			(xy 155.816989 -392.048216) (xy 155.871491 -392.048216) (xy 155.925439 -392.055972) (xy 155.977734 -392.071327)
			(xy 156.027311 -392.093969) (xy 156.073161 -392.123435) (xy 156.114352 -392.159126) (xy 156.150043 -392.200317)
			(xy 156.179509 -392.246167) (xy 156.202151 -392.295744) (xy 156.217506 -392.348039) (xy 156.225262 -392.401987)
			(xy 156.225748 -392.429238) (xy 156.225748 -393.292838) (xy 156.662628 -393.292838) (xy 156.662628 -392.429238)
			(xy 156.663114 -392.401969) (xy 156.670876 -392.347985) (xy 156.686241 -392.295655) (xy 156.708898 -392.246045)
			(xy 156.738384 -392.200164) (xy 156.774099 -392.158947) (xy 156.815316 -392.123232) (xy 156.861197 -392.093746)
			(xy 156.910807 -392.071089) (xy 156.963137 -392.055724) (xy 157.017121 -392.047962) (xy 157.071659 -392.047962)
			(xy 157.125643 -392.055724) (xy 157.177973 -392.071089) (xy 157.227583 -392.093746) (xy 157.273464 -392.123232)
			(xy 157.314681 -392.158947) (xy 157.350396 -392.200164) (xy 157.379882 -392.246045) (xy 157.402539 -392.295655)
			(xy 157.417904 -392.347985) (xy 157.425666 -392.401969) (xy 157.426152 -392.429238) (xy 157.426152 -393.292838)
			(xy 157.862524 -393.292838) (xy 157.862524 -392.429238) (xy 157.86301 -392.401969) (xy 157.870772 -392.347985)
			(xy 157.886137 -392.295655) (xy 157.908794 -392.246045) (xy 157.93828 -392.200164) (xy 157.973995 -392.158947)
			(xy 158.015212 -392.123232) (xy 158.061093 -392.093746) (xy 158.110703 -392.071089) (xy 158.163033 -392.055724)
			(xy 158.217017 -392.047962) (xy 158.271555 -392.047962) (xy 158.325539 -392.055724) (xy 158.377869 -392.071089)
			(xy 158.427479 -392.093746) (xy 158.47336 -392.123232) (xy 158.514577 -392.158947) (xy 158.550292 -392.200164)
			(xy 158.579778 -392.246045) (xy 158.602435 -392.295655) (xy 158.6178 -392.347985) (xy 158.625562 -392.401969)
			(xy 158.626048 -392.429238) (xy 158.626048 -393.292838) (xy 159.062928 -393.292838) (xy 159.062928 -392.429238)
			(xy 159.063414 -392.401987) (xy 159.07117 -392.348039) (xy 159.086525 -392.295744) (xy 159.109167 -392.246167)
			(xy 159.138633 -392.200317) (xy 159.174324 -392.159126) (xy 159.215515 -392.123435) (xy 159.261365 -392.093969)
			(xy 159.310942 -392.071327) (xy 159.363237 -392.055972) (xy 159.417185 -392.048216) (xy 159.471687 -392.048216)
			(xy 159.525635 -392.055972) (xy 159.57793 -392.071327) (xy 159.627507 -392.093969) (xy 159.673357 -392.123435)
			(xy 159.714548 -392.159126) (xy 159.750239 -392.200317) (xy 159.779705 -392.246167) (xy 159.802347 -392.295744)
			(xy 159.817702 -392.348039) (xy 159.825458 -392.401987) (xy 159.825944 -392.429238) (xy 159.825944 -393.292838)
			(xy 160.262824 -393.292838) (xy 160.262824 -392.429238) (xy 160.26331 -392.401987) (xy 160.271066 -392.348039)
			(xy 160.286421 -392.295744) (xy 160.309063 -392.246167) (xy 160.338529 -392.200317) (xy 160.37422 -392.159126)
			(xy 160.415411 -392.123435) (xy 160.461261 -392.093969) (xy 160.510838 -392.071327) (xy 160.563133 -392.055972)
			(xy 160.617081 -392.048216) (xy 160.671583 -392.048216) (xy 160.725531 -392.055972) (xy 160.777826 -392.071327)
			(xy 160.827403 -392.093969) (xy 160.873253 -392.123435) (xy 160.914444 -392.159126) (xy 160.950135 -392.200317)
			(xy 160.979601 -392.246167) (xy 161.002243 -392.295744) (xy 161.017598 -392.348039) (xy 161.025354 -392.401987)
			(xy 161.02584 -392.429238) (xy 161.02584 -393.292838) (xy 161.46272 -393.292838) (xy 161.46272 -392.429238)
			(xy 161.463206 -392.401987) (xy 161.470962 -392.348039) (xy 161.486317 -392.295744) (xy 161.508959 -392.246167)
			(xy 161.538425 -392.200317) (xy 161.574116 -392.159126) (xy 161.615307 -392.123435) (xy 161.661157 -392.093969)
			(xy 161.710734 -392.071327) (xy 161.763029 -392.055972) (xy 161.816977 -392.048216) (xy 161.871479 -392.048216)
			(xy 161.925427 -392.055972) (xy 161.977722 -392.071327) (xy 162.027299 -392.093969) (xy 162.073149 -392.123435)
			(xy 162.11434 -392.159126) (xy 162.150031 -392.200317) (xy 162.179497 -392.246167) (xy 162.202139 -392.295744)
			(xy 162.217494 -392.348039) (xy 162.22525 -392.401987) (xy 162.225736 -392.429238) (xy 162.225736 -393.292838)
			(xy 162.662616 -393.292838) (xy 162.662616 -392.429238) (xy 162.663102 -392.401987) (xy 162.670858 -392.348039)
			(xy 162.686213 -392.295744) (xy 162.708855 -392.246167) (xy 162.738321 -392.200317) (xy 162.774012 -392.159126)
			(xy 162.815203 -392.123435) (xy 162.861053 -392.093969) (xy 162.91063 -392.071327) (xy 162.962925 -392.055972)
			(xy 163.016873 -392.048216) (xy 163.071375 -392.048216) (xy 163.125323 -392.055972) (xy 163.177618 -392.071327)
			(xy 163.227195 -392.093969) (xy 163.273045 -392.123435) (xy 163.314236 -392.159126) (xy 163.349927 -392.200317)
			(xy 163.379393 -392.246167) (xy 163.402035 -392.295744) (xy 163.41739 -392.348039) (xy 163.425146 -392.401987)
			(xy 163.425632 -392.429238) (xy 163.425632 -393.292838) (xy 163.862512 -393.292838) (xy 163.862512 -392.429238)
			(xy 163.862998 -392.401969) (xy 163.87076 -392.347985) (xy 163.886125 -392.295655) (xy 163.908782 -392.246045)
			(xy 163.938268 -392.200164) (xy 163.973983 -392.158947) (xy 164.0152 -392.123232) (xy 164.061081 -392.093746)
			(xy 164.110691 -392.071089) (xy 164.163021 -392.055724) (xy 164.217005 -392.047962) (xy 164.271543 -392.047962)
			(xy 164.325527 -392.055724) (xy 164.377857 -392.071089) (xy 164.427467 -392.093746) (xy 164.473348 -392.123232)
			(xy 164.514565 -392.158947) (xy 164.55028 -392.200164) (xy 164.579766 -392.246045) (xy 164.602423 -392.295655)
			(xy 164.617788 -392.347985) (xy 164.62555 -392.401969) (xy 164.626036 -392.429238) (xy 164.626036 -393.292838)
			(xy 165.062408 -393.292838) (xy 165.062408 -392.429238) (xy 165.062894 -392.401969) (xy 165.070656 -392.347985)
			(xy 165.086021 -392.295655) (xy 165.108678 -392.246045) (xy 165.138164 -392.200164) (xy 165.173879 -392.158947)
			(xy 165.215096 -392.123232) (xy 165.260977 -392.093746) (xy 165.310587 -392.071089) (xy 165.362917 -392.055724)
			(xy 165.416901 -392.047962) (xy 165.471439 -392.047962) (xy 165.525423 -392.055724) (xy 165.577753 -392.071089)
			(xy 165.627363 -392.093746) (xy 165.673244 -392.123232) (xy 165.714461 -392.158947) (xy 165.750176 -392.200164)
			(xy 165.779662 -392.246045) (xy 165.802319 -392.295655) (xy 165.817684 -392.347985) (xy 165.825446 -392.401969)
			(xy 165.825932 -392.429238) (xy 165.825932 -393.292838) (xy 165.825446 -393.320107) (xy 165.817684 -393.374091)
			(xy 165.802319 -393.426421) (xy 165.779662 -393.476031) (xy 165.750176 -393.521912) (xy 165.714461 -393.563129)
			(xy 165.673244 -393.598844) (xy 165.627363 -393.62833) (xy 165.577753 -393.650987) (xy 165.525423 -393.666352)
			(xy 165.471439 -393.674114) (xy 165.416901 -393.674114) (xy 165.362917 -393.666352) (xy 165.310587 -393.650987)
			(xy 165.260977 -393.62833) (xy 165.215096 -393.598844) (xy 165.173879 -393.563129) (xy 165.138164 -393.521912)
			(xy 165.108678 -393.476031) (xy 165.086021 -393.426421) (xy 165.070656 -393.374091) (xy 165.062894 -393.320107)
			(xy 165.062408 -393.292838) (xy 164.626036 -393.292838) (xy 164.62555 -393.320107) (xy 164.617788 -393.374091)
			(xy 164.602423 -393.426421) (xy 164.579766 -393.476031) (xy 164.55028 -393.521912) (xy 164.514565 -393.563129)
			(xy 164.473348 -393.598844) (xy 164.427467 -393.62833) (xy 164.377857 -393.650987) (xy 164.325527 -393.666352)
			(xy 164.271543 -393.674114) (xy 164.217005 -393.674114) (xy 164.163021 -393.666352) (xy 164.110691 -393.650987)
			(xy 164.061081 -393.62833) (xy 164.0152 -393.598844) (xy 163.973983 -393.563129) (xy 163.938268 -393.521912)
			(xy 163.908782 -393.476031) (xy 163.886125 -393.426421) (xy 163.87076 -393.374091) (xy 163.862998 -393.320107)
			(xy 163.862512 -393.292838) (xy 163.425632 -393.292838) (xy 163.425146 -393.320089) (xy 163.41739 -393.374037)
			(xy 163.402035 -393.426332) (xy 163.379393 -393.475909) (xy 163.349927 -393.521759) (xy 163.314236 -393.56295)
			(xy 163.273045 -393.598641) (xy 163.227195 -393.628107) (xy 163.177618 -393.650749) (xy 163.125323 -393.666104)
			(xy 163.071375 -393.67386) (xy 163.016873 -393.67386) (xy 162.962925 -393.666104) (xy 162.91063 -393.650749)
			(xy 162.861053 -393.628107) (xy 162.815203 -393.598641) (xy 162.774012 -393.56295) (xy 162.738321 -393.521759)
			(xy 162.708855 -393.475909) (xy 162.686213 -393.426332) (xy 162.670858 -393.374037) (xy 162.663102 -393.320089)
			(xy 162.662616 -393.292838) (xy 162.225736 -393.292838) (xy 162.22525 -393.320089) (xy 162.217494 -393.374037)
			(xy 162.202139 -393.426332) (xy 162.179497 -393.475909) (xy 162.150031 -393.521759) (xy 162.11434 -393.56295)
			(xy 162.073149 -393.598641) (xy 162.027299 -393.628107) (xy 161.977722 -393.650749) (xy 161.925427 -393.666104)
			(xy 161.871479 -393.67386) (xy 161.816977 -393.67386) (xy 161.763029 -393.666104) (xy 161.710734 -393.650749)
			(xy 161.661157 -393.628107) (xy 161.615307 -393.598641) (xy 161.574116 -393.56295) (xy 161.538425 -393.521759)
			(xy 161.508959 -393.475909) (xy 161.486317 -393.426332) (xy 161.470962 -393.374037) (xy 161.463206 -393.320089)
			(xy 161.46272 -393.292838) (xy 161.02584 -393.292838) (xy 161.025354 -393.320089) (xy 161.017598 -393.374037)
			(xy 161.002243 -393.426332) (xy 160.979601 -393.475909) (xy 160.950135 -393.521759) (xy 160.914444 -393.56295)
			(xy 160.873253 -393.598641) (xy 160.827403 -393.628107) (xy 160.777826 -393.650749) (xy 160.725531 -393.666104)
			(xy 160.671583 -393.67386) (xy 160.617081 -393.67386) (xy 160.563133 -393.666104) (xy 160.510838 -393.650749)
			(xy 160.461261 -393.628107) (xy 160.415411 -393.598641) (xy 160.37422 -393.56295) (xy 160.338529 -393.521759)
			(xy 160.309063 -393.475909) (xy 160.286421 -393.426332) (xy 160.271066 -393.374037) (xy 160.26331 -393.320089)
			(xy 160.262824 -393.292838) (xy 159.825944 -393.292838) (xy 159.825458 -393.320089) (xy 159.817702 -393.374037)
			(xy 159.802347 -393.426332) (xy 159.779705 -393.475909) (xy 159.750239 -393.521759) (xy 159.714548 -393.56295)
			(xy 159.673357 -393.598641) (xy 159.627507 -393.628107) (xy 159.57793 -393.650749) (xy 159.525635 -393.666104)
			(xy 159.471687 -393.67386) (xy 159.417185 -393.67386) (xy 159.363237 -393.666104) (xy 159.310942 -393.650749)
			(xy 159.261365 -393.628107) (xy 159.215515 -393.598641) (xy 159.174324 -393.56295) (xy 159.138633 -393.521759)
			(xy 159.109167 -393.475909) (xy 159.086525 -393.426332) (xy 159.07117 -393.374037) (xy 159.063414 -393.320089)
			(xy 159.062928 -393.292838) (xy 158.626048 -393.292838) (xy 158.625562 -393.320107) (xy 158.6178 -393.374091)
			(xy 158.602435 -393.426421) (xy 158.579778 -393.476031) (xy 158.550292 -393.521912) (xy 158.514577 -393.563129)
			(xy 158.47336 -393.598844) (xy 158.427479 -393.62833) (xy 158.377869 -393.650987) (xy 158.325539 -393.666352)
			(xy 158.271555 -393.674114) (xy 158.217017 -393.674114) (xy 158.163033 -393.666352) (xy 158.110703 -393.650987)
			(xy 158.061093 -393.62833) (xy 158.015212 -393.598844) (xy 157.973995 -393.563129) (xy 157.93828 -393.521912)
			(xy 157.908794 -393.476031) (xy 157.886137 -393.426421) (xy 157.870772 -393.374091) (xy 157.86301 -393.320107)
			(xy 157.862524 -393.292838) (xy 157.426152 -393.292838) (xy 157.425666 -393.320107) (xy 157.417904 -393.374091)
			(xy 157.402539 -393.426421) (xy 157.379882 -393.476031) (xy 157.350396 -393.521912) (xy 157.314681 -393.563129)
			(xy 157.273464 -393.598844) (xy 157.227583 -393.62833) (xy 157.177973 -393.650987) (xy 157.125643 -393.666352)
			(xy 157.071659 -393.674114) (xy 157.017121 -393.674114) (xy 156.963137 -393.666352) (xy 156.910807 -393.650987)
			(xy 156.861197 -393.62833) (xy 156.815316 -393.598844) (xy 156.774099 -393.563129) (xy 156.738384 -393.521912)
			(xy 156.708898 -393.476031) (xy 156.686241 -393.426421) (xy 156.670876 -393.374091) (xy 156.663114 -393.320107)
			(xy 156.662628 -393.292838) (xy 156.225748 -393.292838) (xy 156.225262 -393.320089) (xy 156.217506 -393.374037)
			(xy 156.202151 -393.426332) (xy 156.179509 -393.475909) (xy 156.150043 -393.521759) (xy 156.114352 -393.56295)
			(xy 156.073161 -393.598641) (xy 156.027311 -393.628107) (xy 155.977734 -393.650749) (xy 155.925439 -393.666104)
			(xy 155.871491 -393.67386) (xy 155.816989 -393.67386) (xy 155.763041 -393.666104) (xy 155.710746 -393.650749)
			(xy 155.661169 -393.628107) (xy 155.615319 -393.598641) (xy 155.574128 -393.56295) (xy 155.538437 -393.521759)
			(xy 155.508971 -393.475909) (xy 155.486329 -393.426332) (xy 155.470974 -393.374037) (xy 155.463218 -393.320089)
			(xy 155.462732 -393.292838) (xy 155.025852 -393.292838) (xy 155.025366 -393.320089) (xy 155.01761 -393.374037)
			(xy 155.002255 -393.426332) (xy 154.979613 -393.475909) (xy 154.950147 -393.521759) (xy 154.914456 -393.56295)
			(xy 154.873265 -393.598641) (xy 154.827415 -393.628107) (xy 154.777838 -393.650749) (xy 154.725543 -393.666104)
			(xy 154.671595 -393.67386) (xy 154.617093 -393.67386) (xy 154.563145 -393.666104) (xy 154.51085 -393.650749)
			(xy 154.461273 -393.628107) (xy 154.415423 -393.598641) (xy 154.374232 -393.56295) (xy 154.338541 -393.521759)
			(xy 154.309075 -393.475909) (xy 154.286433 -393.426332) (xy 154.271078 -393.374037) (xy 154.263322 -393.320089)
			(xy 154.262836 -393.292838) (xy 153.825956 -393.292838) (xy 153.82547 -393.320107) (xy 153.817708 -393.374091)
			(xy 153.802343 -393.426421) (xy 153.779686 -393.476031) (xy 153.7502 -393.521912) (xy 153.714485 -393.563129)
			(xy 153.673268 -393.598844) (xy 153.627387 -393.62833) (xy 153.577777 -393.650987) (xy 153.525447 -393.666352)
			(xy 153.471463 -393.674114) (xy 153.416925 -393.674114) (xy 153.362941 -393.666352) (xy 153.310611 -393.650987)
			(xy 153.261001 -393.62833) (xy 153.21512 -393.598844) (xy 153.173903 -393.563129) (xy 153.138188 -393.521912)
			(xy 153.108702 -393.476031) (xy 153.086045 -393.426421) (xy 153.07068 -393.374091) (xy 153.062918 -393.320107)
			(xy 153.062432 -393.292838) (xy 152.62606 -393.292838) (xy 152.625574 -393.320107) (xy 152.617812 -393.374091)
			(xy 152.602447 -393.426421) (xy 152.57979 -393.476031) (xy 152.550304 -393.521912) (xy 152.514589 -393.563129)
			(xy 152.473372 -393.598844) (xy 152.427491 -393.62833) (xy 152.377881 -393.650987) (xy 152.325551 -393.666352)
			(xy 152.271567 -393.674114) (xy 152.217029 -393.674114) (xy 152.163045 -393.666352) (xy 152.110715 -393.650987)
			(xy 152.061105 -393.62833) (xy 152.015224 -393.598844) (xy 151.974007 -393.563129) (xy 151.938292 -393.521912)
			(xy 151.908806 -393.476031) (xy 151.886149 -393.426421) (xy 151.870784 -393.374091) (xy 151.863022 -393.320107)
			(xy 151.862536 -393.292838) (xy 151.425656 -393.292838) (xy 151.42517 -393.320089) (xy 151.417414 -393.374037)
			(xy 151.402059 -393.426332) (xy 151.379417 -393.475909) (xy 151.349951 -393.521759) (xy 151.31426 -393.56295)
			(xy 151.273069 -393.598641) (xy 151.227219 -393.628107) (xy 151.177642 -393.650749) (xy 151.125347 -393.666104)
			(xy 151.071399 -393.67386) (xy 151.016897 -393.67386) (xy 150.962949 -393.666104) (xy 150.910654 -393.650749)
			(xy 150.861077 -393.628107) (xy 150.815227 -393.598641) (xy 150.774036 -393.56295) (xy 150.738345 -393.521759)
			(xy 150.708879 -393.475909) (xy 150.686237 -393.426332) (xy 150.670882 -393.374037) (xy 150.663126 -393.320089)
			(xy 150.66264 -393.292838) (xy 150.22576 -393.292838) (xy 150.225274 -393.320089) (xy 150.217518 -393.374037)
			(xy 150.202163 -393.426332) (xy 150.179521 -393.475909) (xy 150.150055 -393.521759) (xy 150.114364 -393.56295)
			(xy 150.073173 -393.598641) (xy 150.027323 -393.628107) (xy 149.977746 -393.650749) (xy 149.925451 -393.666104)
			(xy 149.871503 -393.67386) (xy 149.817001 -393.67386) (xy 149.763053 -393.666104) (xy 149.710758 -393.650749)
			(xy 149.661181 -393.628107) (xy 149.615331 -393.598641) (xy 149.57414 -393.56295) (xy 149.538449 -393.521759)
			(xy 149.508983 -393.475909) (xy 149.486341 -393.426332) (xy 149.470986 -393.374037) (xy 149.46323 -393.320089)
			(xy 149.462744 -393.292838) (xy 149.025864 -393.292838) (xy 149.025378 -393.320107) (xy 149.017616 -393.374091)
			(xy 149.002251 -393.426421) (xy 148.979594 -393.476031) (xy 148.950108 -393.521912) (xy 148.914393 -393.563129)
			(xy 148.873176 -393.598844) (xy 148.827295 -393.62833) (xy 148.777685 -393.650987) (xy 148.725355 -393.666352)
			(xy 148.671371 -393.674114) (xy 148.616833 -393.674114) (xy 148.562849 -393.666352) (xy 148.510519 -393.650987)
			(xy 148.460909 -393.62833) (xy 148.415028 -393.598844) (xy 148.373811 -393.563129) (xy 148.338096 -393.521912)
			(xy 148.30861 -393.476031) (xy 148.285953 -393.426421) (xy 148.270588 -393.374091) (xy 148.262826 -393.320107)
			(xy 148.26234 -393.292838) (xy 147.825968 -393.292838) (xy 147.825482 -393.320107) (xy 147.81772 -393.374091)
			(xy 147.802355 -393.426421) (xy 147.779698 -393.476031) (xy 147.750212 -393.521912) (xy 147.714497 -393.563129)
			(xy 147.67328 -393.598844) (xy 147.627399 -393.62833) (xy 147.577789 -393.650987) (xy 147.525459 -393.666352)
			(xy 147.471475 -393.674114) (xy 147.416937 -393.674114) (xy 147.362953 -393.666352) (xy 147.310623 -393.650987)
			(xy 147.261013 -393.62833) (xy 147.215132 -393.598844) (xy 147.173915 -393.563129) (xy 147.1382 -393.521912)
			(xy 147.108714 -393.476031) (xy 147.086057 -393.426421) (xy 147.070692 -393.374091) (xy 147.06293 -393.320107)
			(xy 147.062444 -393.292838) (xy 133.298184 -393.292838) (xy 133.297698 -393.320107) (xy 133.289936 -393.374091)
			(xy 133.274571 -393.426421) (xy 133.251914 -393.476031) (xy 133.222428 -393.521912) (xy 133.186713 -393.563129)
			(xy 133.145496 -393.598844) (xy 133.099615 -393.62833) (xy 133.050005 -393.650987) (xy 132.997675 -393.666352)
			(xy 132.943691 -393.674114) (xy 132.889153 -393.674114) (xy 132.835169 -393.666352) (xy 132.782839 -393.650987)
			(xy 132.733229 -393.62833) (xy 132.687348 -393.598844) (xy 132.646131 -393.563129) (xy 132.610416 -393.521912)
			(xy 132.58093 -393.476031) (xy 132.558273 -393.426421) (xy 132.542908 -393.374091) (xy 132.535146 -393.320107)
			(xy 132.53466 -393.292838) (xy 132.098288 -393.292838) (xy 132.097802 -393.320107) (xy 132.09004 -393.374091)
			(xy 132.074675 -393.426421) (xy 132.052018 -393.476031) (xy 132.022532 -393.521912) (xy 131.986817 -393.563129)
			(xy 131.9456 -393.598844) (xy 131.899719 -393.62833) (xy 131.850109 -393.650987) (xy 131.797779 -393.666352)
			(xy 131.743795 -393.674114) (xy 131.689257 -393.674114) (xy 131.635273 -393.666352) (xy 131.582943 -393.650987)
			(xy 131.533333 -393.62833) (xy 131.487452 -393.598844) (xy 131.446235 -393.563129) (xy 131.41052 -393.521912)
			(xy 131.381034 -393.476031) (xy 131.358377 -393.426421) (xy 131.343012 -393.374091) (xy 131.33525 -393.320107)
			(xy 131.334764 -393.292838) (xy 130.897884 -393.292838) (xy 130.897398 -393.320089) (xy 130.889642 -393.374037)
			(xy 130.874287 -393.426332) (xy 130.851645 -393.475909) (xy 130.822179 -393.521759) (xy 130.786488 -393.56295)
			(xy 130.745297 -393.598641) (xy 130.699447 -393.628107) (xy 130.64987 -393.650749) (xy 130.597575 -393.666104)
			(xy 130.543627 -393.67386) (xy 130.489125 -393.67386) (xy 130.435177 -393.666104) (xy 130.382882 -393.650749)
			(xy 130.333305 -393.628107) (xy 130.287455 -393.598641) (xy 130.246264 -393.56295) (xy 130.210573 -393.521759)
			(xy 130.181107 -393.475909) (xy 130.158465 -393.426332) (xy 130.14311 -393.374037) (xy 130.135354 -393.320089)
			(xy 130.134868 -393.292838) (xy 129.697988 -393.292838) (xy 129.697502 -393.320089) (xy 129.689746 -393.374037)
			(xy 129.674391 -393.426332) (xy 129.651749 -393.475909) (xy 129.622283 -393.521759) (xy 129.586592 -393.56295)
			(xy 129.545401 -393.598641) (xy 129.499551 -393.628107) (xy 129.449974 -393.650749) (xy 129.397679 -393.666104)
			(xy 129.343731 -393.67386) (xy 129.289229 -393.67386) (xy 129.235281 -393.666104) (xy 129.182986 -393.650749)
			(xy 129.133409 -393.628107) (xy 129.087559 -393.598641) (xy 129.046368 -393.56295) (xy 129.010677 -393.521759)
			(xy 128.981211 -393.475909) (xy 128.958569 -393.426332) (xy 128.943214 -393.374037) (xy 128.935458 -393.320089)
			(xy 128.934972 -393.292838) (xy 128.498092 -393.292838) (xy 128.497606 -393.320089) (xy 128.48985 -393.374037)
			(xy 128.474495 -393.426332) (xy 128.451853 -393.475909) (xy 128.422387 -393.521759) (xy 128.386696 -393.56295)
			(xy 128.345505 -393.598641) (xy 128.299655 -393.628107) (xy 128.250078 -393.650749) (xy 128.197783 -393.666104)
			(xy 128.143835 -393.67386) (xy 128.089333 -393.67386) (xy 128.035385 -393.666104) (xy 127.98309 -393.650749)
			(xy 127.933513 -393.628107) (xy 127.887663 -393.598641) (xy 127.846472 -393.56295) (xy 127.810781 -393.521759)
			(xy 127.781315 -393.475909) (xy 127.758673 -393.426332) (xy 127.743318 -393.374037) (xy 127.735562 -393.320089)
			(xy 127.735076 -393.292838) (xy 127.298196 -393.292838) (xy 127.29771 -393.320089) (xy 127.289954 -393.374037)
			(xy 127.274599 -393.426332) (xy 127.251957 -393.475909) (xy 127.222491 -393.521759) (xy 127.1868 -393.56295)
			(xy 127.145609 -393.598641) (xy 127.099759 -393.628107) (xy 127.050182 -393.650749) (xy 126.997887 -393.666104)
			(xy 126.943939 -393.67386) (xy 126.889437 -393.67386) (xy 126.835489 -393.666104) (xy 126.783194 -393.650749)
			(xy 126.733617 -393.628107) (xy 126.687767 -393.598641) (xy 126.646576 -393.56295) (xy 126.610885 -393.521759)
			(xy 126.581419 -393.475909) (xy 126.558777 -393.426332) (xy 126.543422 -393.374037) (xy 126.535666 -393.320089)
			(xy 126.53518 -393.292838) (xy 126.0983 -393.292838) (xy 126.097814 -393.320107) (xy 126.090052 -393.374091)
			(xy 126.074687 -393.426421) (xy 126.05203 -393.476031) (xy 126.022544 -393.521912) (xy 125.986829 -393.563129)
			(xy 125.945612 -393.598844) (xy 125.899731 -393.62833) (xy 125.850121 -393.650987) (xy 125.797791 -393.666352)
			(xy 125.743807 -393.674114) (xy 125.689269 -393.674114) (xy 125.635285 -393.666352) (xy 125.582955 -393.650987)
			(xy 125.533345 -393.62833) (xy 125.487464 -393.598844) (xy 125.446247 -393.563129) (xy 125.410532 -393.521912)
			(xy 125.381046 -393.476031) (xy 125.358389 -393.426421) (xy 125.343024 -393.374091) (xy 125.335262 -393.320107)
			(xy 125.334776 -393.292838) (xy 124.898404 -393.292838) (xy 124.897918 -393.320107) (xy 124.890156 -393.374091)
			(xy 124.874791 -393.426421) (xy 124.852134 -393.476031) (xy 124.822648 -393.521912) (xy 124.786933 -393.563129)
			(xy 124.745716 -393.598844) (xy 124.699835 -393.62833) (xy 124.650225 -393.650987) (xy 124.597895 -393.666352)
			(xy 124.543911 -393.674114) (xy 124.489373 -393.674114) (xy 124.435389 -393.666352) (xy 124.383059 -393.650987)
			(xy 124.333449 -393.62833) (xy 124.287568 -393.598844) (xy 124.246351 -393.563129) (xy 124.210636 -393.521912)
			(xy 124.18115 -393.476031) (xy 124.158493 -393.426421) (xy 124.143128 -393.374091) (xy 124.135366 -393.320107)
			(xy 124.13488 -393.292838) (xy 123.698 -393.292838) (xy 123.697514 -393.320089) (xy 123.689758 -393.374037)
			(xy 123.674403 -393.426332) (xy 123.651761 -393.475909) (xy 123.622295 -393.521759) (xy 123.586604 -393.56295)
			(xy 123.545413 -393.598641) (xy 123.499563 -393.628107) (xy 123.449986 -393.650749) (xy 123.397691 -393.666104)
			(xy 123.343743 -393.67386) (xy 123.289241 -393.67386) (xy 123.235293 -393.666104) (xy 123.182998 -393.650749)
			(xy 123.133421 -393.628107) (xy 123.087571 -393.598641) (xy 123.04638 -393.56295) (xy 123.010689 -393.521759)
			(xy 122.981223 -393.475909) (xy 122.958581 -393.426332) (xy 122.943226 -393.374037) (xy 122.93547 -393.320089)
			(xy 122.934984 -393.292838) (xy 122.498104 -393.292838) (xy 122.497618 -393.320089) (xy 122.489862 -393.374037)
			(xy 122.474507 -393.426332) (xy 122.451865 -393.475909) (xy 122.422399 -393.521759) (xy 122.386708 -393.56295)
			(xy 122.345517 -393.598641) (xy 122.299667 -393.628107) (xy 122.25009 -393.650749) (xy 122.197795 -393.666104)
			(xy 122.143847 -393.67386) (xy 122.089345 -393.67386) (xy 122.035397 -393.666104) (xy 121.983102 -393.650749)
			(xy 121.933525 -393.628107) (xy 121.887675 -393.598641) (xy 121.846484 -393.56295) (xy 121.810793 -393.521759)
			(xy 121.781327 -393.475909) (xy 121.758685 -393.426332) (xy 121.74333 -393.374037) (xy 121.735574 -393.320089)
			(xy 121.735088 -393.292838) (xy 121.298208 -393.292838) (xy 121.297722 -393.320107) (xy 121.28996 -393.374091)
			(xy 121.274595 -393.426421) (xy 121.251938 -393.476031) (xy 121.222452 -393.521912) (xy 121.186737 -393.563129)
			(xy 121.14552 -393.598844) (xy 121.099639 -393.62833) (xy 121.050029 -393.650987) (xy 120.997699 -393.666352)
			(xy 120.943715 -393.674114) (xy 120.889177 -393.674114) (xy 120.835193 -393.666352) (xy 120.782863 -393.650987)
			(xy 120.733253 -393.62833) (xy 120.687372 -393.598844) (xy 120.646155 -393.563129) (xy 120.61044 -393.521912)
			(xy 120.580954 -393.476031) (xy 120.558297 -393.426421) (xy 120.542932 -393.374091) (xy 120.53517 -393.320107)
			(xy 120.534684 -393.292838) (xy 120.098312 -393.292838) (xy 120.097826 -393.320107) (xy 120.090064 -393.374091)
			(xy 120.074699 -393.426421) (xy 120.052042 -393.476031) (xy 120.022556 -393.521912) (xy 119.986841 -393.563129)
			(xy 119.945624 -393.598844) (xy 119.899743 -393.62833) (xy 119.850133 -393.650987) (xy 119.797803 -393.666352)
			(xy 119.743819 -393.674114) (xy 119.689281 -393.674114) (xy 119.635297 -393.666352) (xy 119.582967 -393.650987)
			(xy 119.533357 -393.62833) (xy 119.487476 -393.598844) (xy 119.446259 -393.563129) (xy 119.410544 -393.521912)
			(xy 119.381058 -393.476031) (xy 119.358401 -393.426421) (xy 119.343036 -393.374091) (xy 119.335274 -393.320107)
			(xy 119.334788 -393.292838) (xy 118.897908 -393.292838) (xy 118.897422 -393.320089) (xy 118.889666 -393.374037)
			(xy 118.874311 -393.426332) (xy 118.851669 -393.475909) (xy 118.822203 -393.521759) (xy 118.786512 -393.56295)
			(xy 118.745321 -393.598641) (xy 118.699471 -393.628107) (xy 118.649894 -393.650749) (xy 118.597599 -393.666104)
			(xy 118.543651 -393.67386) (xy 118.489149 -393.67386) (xy 118.435201 -393.666104) (xy 118.382906 -393.650749)
			(xy 118.333329 -393.628107) (xy 118.287479 -393.598641) (xy 118.246288 -393.56295) (xy 118.210597 -393.521759)
			(xy 118.181131 -393.475909) (xy 118.158489 -393.426332) (xy 118.143134 -393.374037) (xy 118.135378 -393.320089)
			(xy 118.134892 -393.292838) (xy 117.698012 -393.292838) (xy 117.697526 -393.320089) (xy 117.68977 -393.374037)
			(xy 117.674415 -393.426332) (xy 117.651773 -393.475909) (xy 117.622307 -393.521759) (xy 117.586616 -393.56295)
			(xy 117.545425 -393.598641) (xy 117.499575 -393.628107) (xy 117.449998 -393.650749) (xy 117.397703 -393.666104)
			(xy 117.343755 -393.67386) (xy 117.289253 -393.67386) (xy 117.235305 -393.666104) (xy 117.18301 -393.650749)
			(xy 117.133433 -393.628107) (xy 117.087583 -393.598641) (xy 117.046392 -393.56295) (xy 117.010701 -393.521759)
			(xy 116.981235 -393.475909) (xy 116.958593 -393.426332) (xy 116.943238 -393.374037) (xy 116.935482 -393.320089)
			(xy 116.934996 -393.292838) (xy 116.498116 -393.292838) (xy 116.49763 -393.320107) (xy 116.489868 -393.374091)
			(xy 116.474503 -393.426421) (xy 116.451846 -393.476031) (xy 116.42236 -393.521912) (xy 116.386645 -393.563129)
			(xy 116.345428 -393.598844) (xy 116.299547 -393.62833) (xy 116.249937 -393.650987) (xy 116.197607 -393.666352)
			(xy 116.143623 -393.674114) (xy 116.089085 -393.674114) (xy 116.035101 -393.666352) (xy 115.982771 -393.650987)
			(xy 115.933161 -393.62833) (xy 115.88728 -393.598844) (xy 115.846063 -393.563129) (xy 115.810348 -393.521912)
			(xy 115.780862 -393.476031) (xy 115.758205 -393.426421) (xy 115.74284 -393.374091) (xy 115.735078 -393.320107)
			(xy 115.734592 -393.292838) (xy 115.29822 -393.292838) (xy 115.297734 -393.320107) (xy 115.289972 -393.374091)
			(xy 115.274607 -393.426421) (xy 115.25195 -393.476031) (xy 115.222464 -393.521912) (xy 115.186749 -393.563129)
			(xy 115.145532 -393.598844) (xy 115.099651 -393.62833) (xy 115.050041 -393.650987) (xy 114.997711 -393.666352)
			(xy 114.943727 -393.674114) (xy 114.889189 -393.674114) (xy 114.835205 -393.666352) (xy 114.782875 -393.650987)
			(xy 114.733265 -393.62833) (xy 114.687384 -393.598844) (xy 114.646167 -393.563129) (xy 114.610452 -393.521912)
			(xy 114.580966 -393.476031) (xy 114.558309 -393.426421) (xy 114.542944 -393.374091) (xy 114.535182 -393.320107)
			(xy 114.534696 -393.292838) (xy 98.725736 -393.292838) (xy 98.72525 -393.320089) (xy 98.717494 -393.374037)
			(xy 98.702139 -393.426332) (xy 98.679497 -393.475909) (xy 98.650031 -393.521759) (xy 98.61434 -393.56295)
			(xy 98.573149 -393.598641) (xy 98.527299 -393.628107) (xy 98.477722 -393.650749) (xy 98.425427 -393.666104)
			(xy 98.371479 -393.67386) (xy 98.316977 -393.67386) (xy 98.263029 -393.666104) (xy 98.210734 -393.650749)
			(xy 98.161157 -393.628107) (xy 98.115307 -393.598641) (xy 98.074116 -393.56295) (xy 98.038425 -393.521759)
			(xy 98.008959 -393.475909) (xy 97.986317 -393.426332) (xy 97.970962 -393.374037) (xy 97.963206 -393.320089)
			(xy 97.96272 -393.292838) (xy 97.52584 -393.292838) (xy 97.525354 -393.320089) (xy 97.517598 -393.374037)
			(xy 97.502243 -393.426332) (xy 97.479601 -393.475909) (xy 97.450135 -393.521759) (xy 97.414444 -393.56295)
			(xy 97.373253 -393.598641) (xy 97.327403 -393.628107) (xy 97.277826 -393.650749) (xy 97.225531 -393.666104)
			(xy 97.171583 -393.67386) (xy 97.117081 -393.67386) (xy 97.063133 -393.666104) (xy 97.010838 -393.650749)
			(xy 96.961261 -393.628107) (xy 96.915411 -393.598641) (xy 96.87422 -393.56295) (xy 96.838529 -393.521759)
			(xy 96.809063 -393.475909) (xy 96.786421 -393.426332) (xy 96.771066 -393.374037) (xy 96.76331 -393.320089)
			(xy 96.762824 -393.292838) (xy 96.325944 -393.292838) (xy 96.325458 -393.320107) (xy 96.317696 -393.374091)
			(xy 96.302331 -393.426421) (xy 96.279674 -393.476031) (xy 96.250188 -393.521912) (xy 96.214473 -393.563129)
			(xy 96.173256 -393.598844) (xy 96.127375 -393.62833) (xy 96.077765 -393.650987) (xy 96.025435 -393.666352)
			(xy 95.971451 -393.674114) (xy 95.916913 -393.674114) (xy 95.862929 -393.666352) (xy 95.810599 -393.650987)
			(xy 95.760989 -393.62833) (xy 95.715108 -393.598844) (xy 95.673891 -393.563129) (xy 95.638176 -393.521912)
			(xy 95.60869 -393.476031) (xy 95.586033 -393.426421) (xy 95.570668 -393.374091) (xy 95.562906 -393.320107)
			(xy 95.56242 -393.292838) (xy 95.126048 -393.292838) (xy 95.125562 -393.320107) (xy 95.1178 -393.374091)
			(xy 95.102435 -393.426421) (xy 95.079778 -393.476031) (xy 95.050292 -393.521912) (xy 95.014577 -393.563129)
			(xy 94.97336 -393.598844) (xy 94.927479 -393.62833) (xy 94.877869 -393.650987) (xy 94.825539 -393.666352)
			(xy 94.771555 -393.674114) (xy 94.717017 -393.674114) (xy 94.663033 -393.666352) (xy 94.610703 -393.650987)
			(xy 94.561093 -393.62833) (xy 94.515212 -393.598844) (xy 94.473995 -393.563129) (xy 94.43828 -393.521912)
			(xy 94.408794 -393.476031) (xy 94.386137 -393.426421) (xy 94.370772 -393.374091) (xy 94.36301 -393.320107)
			(xy 94.362524 -393.292838) (xy 93.926152 -393.292838) (xy 93.925666 -393.320107) (xy 93.917904 -393.374091)
			(xy 93.902539 -393.426421) (xy 93.879882 -393.476031) (xy 93.850396 -393.521912) (xy 93.814681 -393.563129)
			(xy 93.773464 -393.598844) (xy 93.727583 -393.62833) (xy 93.677973 -393.650987) (xy 93.625643 -393.666352)
			(xy 93.571659 -393.674114) (xy 93.517121 -393.674114) (xy 93.463137 -393.666352) (xy 93.410807 -393.650987)
			(xy 93.361197 -393.62833) (xy 93.315316 -393.598844) (xy 93.274099 -393.563129) (xy 93.238384 -393.521912)
			(xy 93.208898 -393.476031) (xy 93.186241 -393.426421) (xy 93.170876 -393.374091) (xy 93.163114 -393.320107)
			(xy 93.162628 -393.292838) (xy 92.726256 -393.292838) (xy 92.72577 -393.320107) (xy 92.718008 -393.374091)
			(xy 92.702643 -393.426421) (xy 92.679986 -393.476031) (xy 92.6505 -393.521912) (xy 92.614785 -393.563129)
			(xy 92.573568 -393.598844) (xy 92.527687 -393.62833) (xy 92.478077 -393.650987) (xy 92.425747 -393.666352)
			(xy 92.371763 -393.674114) (xy 92.317225 -393.674114) (xy 92.263241 -393.666352) (xy 92.210911 -393.650987)
			(xy 92.161301 -393.62833) (xy 92.11542 -393.598844) (xy 92.074203 -393.563129) (xy 92.038488 -393.521912)
			(xy 92.009002 -393.476031) (xy 91.986345 -393.426421) (xy 91.97098 -393.374091) (xy 91.963218 -393.320107)
			(xy 91.962732 -393.292838) (xy 91.525852 -393.292838) (xy 91.525366 -393.320089) (xy 91.51761 -393.374037)
			(xy 91.502255 -393.426332) (xy 91.479613 -393.475909) (xy 91.450147 -393.521759) (xy 91.414456 -393.56295)
			(xy 91.373265 -393.598641) (xy 91.327415 -393.628107) (xy 91.277838 -393.650749) (xy 91.225543 -393.666104)
			(xy 91.171595 -393.67386) (xy 91.117093 -393.67386) (xy 91.063145 -393.666104) (xy 91.01085 -393.650749)
			(xy 90.961273 -393.628107) (xy 90.915423 -393.598641) (xy 90.874232 -393.56295) (xy 90.838541 -393.521759)
			(xy 90.809075 -393.475909) (xy 90.786433 -393.426332) (xy 90.771078 -393.374037) (xy 90.763322 -393.320089)
			(xy 90.762836 -393.292838) (xy 90.325956 -393.292838) (xy 90.32547 -393.320089) (xy 90.317714 -393.374037)
			(xy 90.302359 -393.426332) (xy 90.279717 -393.475909) (xy 90.250251 -393.521759) (xy 90.21456 -393.56295)
			(xy 90.173369 -393.598641) (xy 90.127519 -393.628107) (xy 90.077942 -393.650749) (xy 90.025647 -393.666104)
			(xy 89.971699 -393.67386) (xy 89.917197 -393.67386) (xy 89.863249 -393.666104) (xy 89.810954 -393.650749)
			(xy 89.761377 -393.628107) (xy 89.715527 -393.598641) (xy 89.674336 -393.56295) (xy 89.638645 -393.521759)
			(xy 89.609179 -393.475909) (xy 89.586537 -393.426332) (xy 89.571182 -393.374037) (xy 89.563426 -393.320089)
			(xy 89.56294 -393.292838) (xy 89.12606 -393.292838) (xy 89.125574 -393.320107) (xy 89.117812 -393.374091)
			(xy 89.102447 -393.426421) (xy 89.07979 -393.476031) (xy 89.050304 -393.521912) (xy 89.014589 -393.563129)
			(xy 88.973372 -393.598844) (xy 88.927491 -393.62833) (xy 88.877881 -393.650987) (xy 88.825551 -393.666352)
			(xy 88.771567 -393.674114) (xy 88.717029 -393.674114) (xy 88.663045 -393.666352) (xy 88.610715 -393.650987)
			(xy 88.561105 -393.62833) (xy 88.515224 -393.598844) (xy 88.474007 -393.563129) (xy 88.438292 -393.521912)
			(xy 88.408806 -393.476031) (xy 88.386149 -393.426421) (xy 88.370784 -393.374091) (xy 88.363022 -393.320107)
			(xy 88.362536 -393.292838) (xy 87.926164 -393.292838) (xy 87.925678 -393.320107) (xy 87.917916 -393.374091)
			(xy 87.902551 -393.426421) (xy 87.879894 -393.476031) (xy 87.850408 -393.521912) (xy 87.814693 -393.563129)
			(xy 87.773476 -393.598844) (xy 87.727595 -393.62833) (xy 87.677985 -393.650987) (xy 87.625655 -393.666352)
			(xy 87.571671 -393.674114) (xy 87.517133 -393.674114) (xy 87.463149 -393.666352) (xy 87.410819 -393.650987)
			(xy 87.361209 -393.62833) (xy 87.315328 -393.598844) (xy 87.274111 -393.563129) (xy 87.238396 -393.521912)
			(xy 87.20891 -393.476031) (xy 87.186253 -393.426421) (xy 87.170888 -393.374091) (xy 87.163126 -393.320107)
			(xy 87.16264 -393.292838) (xy 86.72576 -393.292838) (xy 86.725274 -393.320089) (xy 86.717518 -393.374037)
			(xy 86.702163 -393.426332) (xy 86.679521 -393.475909) (xy 86.650055 -393.521759) (xy 86.614364 -393.56295)
			(xy 86.573173 -393.598641) (xy 86.527323 -393.628107) (xy 86.477746 -393.650749) (xy 86.425451 -393.666104)
			(xy 86.371503 -393.67386) (xy 86.317001 -393.67386) (xy 86.263053 -393.666104) (xy 86.210758 -393.650749)
			(xy 86.161181 -393.628107) (xy 86.115331 -393.598641) (xy 86.07414 -393.56295) (xy 86.038449 -393.521759)
			(xy 86.008983 -393.475909) (xy 85.986341 -393.426332) (xy 85.970986 -393.374037) (xy 85.96323 -393.320089)
			(xy 85.962744 -393.292838) (xy 85.525864 -393.292838) (xy 85.525378 -393.320089) (xy 85.517622 -393.374037)
			(xy 85.502267 -393.426332) (xy 85.479625 -393.475909) (xy 85.450159 -393.521759) (xy 85.414468 -393.56295)
			(xy 85.373277 -393.598641) (xy 85.327427 -393.628107) (xy 85.27785 -393.650749) (xy 85.225555 -393.666104)
			(xy 85.171607 -393.67386) (xy 85.117105 -393.67386) (xy 85.063157 -393.666104) (xy 85.010862 -393.650749)
			(xy 84.961285 -393.628107) (xy 84.915435 -393.598641) (xy 84.874244 -393.56295) (xy 84.838553 -393.521759)
			(xy 84.809087 -393.475909) (xy 84.786445 -393.426332) (xy 84.77109 -393.374037) (xy 84.763334 -393.320089)
			(xy 84.762848 -393.292838) (xy 84.325968 -393.292838) (xy 84.325482 -393.320107) (xy 84.31772 -393.374091)
			(xy 84.302355 -393.426421) (xy 84.279698 -393.476031) (xy 84.250212 -393.521912) (xy 84.214497 -393.563129)
			(xy 84.17328 -393.598844) (xy 84.127399 -393.62833) (xy 84.077789 -393.650987) (xy 84.025459 -393.666352)
			(xy 83.971475 -393.674114) (xy 83.916937 -393.674114) (xy 83.862953 -393.666352) (xy 83.810623 -393.650987)
			(xy 83.761013 -393.62833) (xy 83.715132 -393.598844) (xy 83.673915 -393.563129) (xy 83.6382 -393.521912)
			(xy 83.608714 -393.476031) (xy 83.586057 -393.426421) (xy 83.570692 -393.374091) (xy 83.56293 -393.320107)
			(xy 83.562444 -393.292838) (xy 83.126072 -393.292838) (xy 83.125586 -393.320107) (xy 83.117824 -393.374091)
			(xy 83.102459 -393.426421) (xy 83.079802 -393.476031) (xy 83.050316 -393.521912) (xy 83.014601 -393.563129)
			(xy 82.973384 -393.598844) (xy 82.927503 -393.62833) (xy 82.877893 -393.650987) (xy 82.825563 -393.666352)
			(xy 82.771579 -393.674114) (xy 82.717041 -393.674114) (xy 82.663057 -393.666352) (xy 82.610727 -393.650987)
			(xy 82.561117 -393.62833) (xy 82.515236 -393.598844) (xy 82.474019 -393.563129) (xy 82.438304 -393.521912)
			(xy 82.408818 -393.476031) (xy 82.386161 -393.426421) (xy 82.370796 -393.374091) (xy 82.363034 -393.320107)
			(xy 82.362548 -393.292838) (xy 81.925668 -393.292838) (xy 81.925182 -393.320089) (xy 81.917426 -393.374037)
			(xy 81.902071 -393.426332) (xy 81.879429 -393.475909) (xy 81.849963 -393.521759) (xy 81.814272 -393.56295)
			(xy 81.773081 -393.598641) (xy 81.727231 -393.628107) (xy 81.677654 -393.650749) (xy 81.625359 -393.666104)
			(xy 81.571411 -393.67386) (xy 81.516909 -393.67386) (xy 81.462961 -393.666104) (xy 81.410666 -393.650749)
			(xy 81.361089 -393.628107) (xy 81.315239 -393.598641) (xy 81.274048 -393.56295) (xy 81.238357 -393.521759)
			(xy 81.208891 -393.475909) (xy 81.186249 -393.426332) (xy 81.170894 -393.374037) (xy 81.163138 -393.320089)
			(xy 81.162652 -393.292838) (xy 80.725772 -393.292838) (xy 80.725286 -393.320089) (xy 80.71753 -393.374037)
			(xy 80.702175 -393.426332) (xy 80.679533 -393.475909) (xy 80.650067 -393.521759) (xy 80.614376 -393.56295)
			(xy 80.573185 -393.598641) (xy 80.527335 -393.628107) (xy 80.477758 -393.650749) (xy 80.425463 -393.666104)
			(xy 80.371515 -393.67386) (xy 80.317013 -393.67386) (xy 80.263065 -393.666104) (xy 80.21077 -393.650749)
			(xy 80.161193 -393.628107) (xy 80.115343 -393.598641) (xy 80.074152 -393.56295) (xy 80.038461 -393.521759)
			(xy 80.008995 -393.475909) (xy 79.986353 -393.426332) (xy 79.970998 -393.374037) (xy 79.963242 -393.320089)
			(xy 79.962756 -393.292838) (xy 66.197988 -393.292838) (xy 66.197502 -393.320089) (xy 66.189746 -393.374037)
			(xy 66.174391 -393.426332) (xy 66.151749 -393.475909) (xy 66.122283 -393.521759) (xy 66.086592 -393.56295)
			(xy 66.045401 -393.598641) (xy 65.999551 -393.628107) (xy 65.949974 -393.650749) (xy 65.897679 -393.666104)
			(xy 65.843731 -393.67386) (xy 65.789229 -393.67386) (xy 65.735281 -393.666104) (xy 65.682986 -393.650749)
			(xy 65.633409 -393.628107) (xy 65.587559 -393.598641) (xy 65.546368 -393.56295) (xy 65.510677 -393.521759)
			(xy 65.481211 -393.475909) (xy 65.458569 -393.426332) (xy 65.443214 -393.374037) (xy 65.435458 -393.320089)
			(xy 65.434972 -393.292838) (xy 64.998092 -393.292838) (xy 64.997606 -393.320089) (xy 64.98985 -393.374037)
			(xy 64.974495 -393.426332) (xy 64.951853 -393.475909) (xy 64.922387 -393.521759) (xy 64.886696 -393.56295)
			(xy 64.845505 -393.598641) (xy 64.799655 -393.628107) (xy 64.750078 -393.650749) (xy 64.697783 -393.666104)
			(xy 64.643835 -393.67386) (xy 64.589333 -393.67386) (xy 64.535385 -393.666104) (xy 64.48309 -393.650749)
			(xy 64.433513 -393.628107) (xy 64.387663 -393.598641) (xy 64.346472 -393.56295) (xy 64.310781 -393.521759)
			(xy 64.281315 -393.475909) (xy 64.258673 -393.426332) (xy 64.243318 -393.374037) (xy 64.235562 -393.320089)
			(xy 64.235076 -393.292838) (xy 63.798196 -393.292838) (xy 63.79771 -393.320107) (xy 63.789948 -393.374091)
			(xy 63.774583 -393.426421) (xy 63.751926 -393.476031) (xy 63.72244 -393.521912) (xy 63.686725 -393.563129)
			(xy 63.645508 -393.598844) (xy 63.599627 -393.62833) (xy 63.550017 -393.650987) (xy 63.497687 -393.666352)
			(xy 63.443703 -393.674114) (xy 63.389165 -393.674114) (xy 63.335181 -393.666352) (xy 63.282851 -393.650987)
			(xy 63.233241 -393.62833) (xy 63.18736 -393.598844) (xy 63.146143 -393.563129) (xy 63.110428 -393.521912)
			(xy 63.080942 -393.476031) (xy 63.058285 -393.426421) (xy 63.04292 -393.374091) (xy 63.035158 -393.320107)
			(xy 63.034672 -393.292838) (xy 62.5983 -393.292838) (xy 62.597814 -393.320107) (xy 62.590052 -393.374091)
			(xy 62.574687 -393.426421) (xy 62.55203 -393.476031) (xy 62.522544 -393.521912) (xy 62.486829 -393.563129)
			(xy 62.445612 -393.598844) (xy 62.399731 -393.62833) (xy 62.350121 -393.650987) (xy 62.297791 -393.666352)
			(xy 62.243807 -393.674114) (xy 62.189269 -393.674114) (xy 62.135285 -393.666352) (xy 62.082955 -393.650987)
			(xy 62.033345 -393.62833) (xy 61.987464 -393.598844) (xy 61.946247 -393.563129) (xy 61.910532 -393.521912)
			(xy 61.881046 -393.476031) (xy 61.858389 -393.426421) (xy 61.843024 -393.374091) (xy 61.835262 -393.320107)
			(xy 61.834776 -393.292838) (xy 61.398404 -393.292838) (xy 61.397918 -393.320107) (xy 61.390156 -393.374091)
			(xy 61.374791 -393.426421) (xy 61.352134 -393.476031) (xy 61.322648 -393.521912) (xy 61.286933 -393.563129)
			(xy 61.245716 -393.598844) (xy 61.199835 -393.62833) (xy 61.150225 -393.650987) (xy 61.097895 -393.666352)
			(xy 61.043911 -393.674114) (xy 60.989373 -393.674114) (xy 60.935389 -393.666352) (xy 60.883059 -393.650987)
			(xy 60.833449 -393.62833) (xy 60.787568 -393.598844) (xy 60.746351 -393.563129) (xy 60.710636 -393.521912)
			(xy 60.68115 -393.476031) (xy 60.658493 -393.426421) (xy 60.643128 -393.374091) (xy 60.635366 -393.320107)
			(xy 60.63488 -393.292838) (xy 60.198508 -393.292838) (xy 60.198022 -393.320107) (xy 60.19026 -393.374091)
			(xy 60.174895 -393.426421) (xy 60.152238 -393.476031) (xy 60.122752 -393.521912) (xy 60.087037 -393.563129)
			(xy 60.04582 -393.598844) (xy 59.999939 -393.62833) (xy 59.950329 -393.650987) (xy 59.897999 -393.666352)
			(xy 59.844015 -393.674114) (xy 59.789477 -393.674114) (xy 59.735493 -393.666352) (xy 59.683163 -393.650987)
			(xy 59.633553 -393.62833) (xy 59.587672 -393.598844) (xy 59.546455 -393.563129) (xy 59.51074 -393.521912)
			(xy 59.481254 -393.476031) (xy 59.458597 -393.426421) (xy 59.443232 -393.374091) (xy 59.43547 -393.320107)
			(xy 59.434984 -393.292838) (xy 58.998104 -393.292838) (xy 58.997618 -393.320089) (xy 58.989862 -393.374037)
			(xy 58.974507 -393.426332) (xy 58.951865 -393.475909) (xy 58.922399 -393.521759) (xy 58.886708 -393.56295)
			(xy 58.845517 -393.598641) (xy 58.799667 -393.628107) (xy 58.75009 -393.650749) (xy 58.697795 -393.666104)
			(xy 58.643847 -393.67386) (xy 58.589345 -393.67386) (xy 58.535397 -393.666104) (xy 58.483102 -393.650749)
			(xy 58.433525 -393.628107) (xy 58.387675 -393.598641) (xy 58.346484 -393.56295) (xy 58.310793 -393.521759)
			(xy 58.281327 -393.475909) (xy 58.258685 -393.426332) (xy 58.24333 -393.374037) (xy 58.235574 -393.320089)
			(xy 58.235088 -393.292838) (xy 57.798208 -393.292838) (xy 57.797722 -393.320089) (xy 57.789966 -393.374037)
			(xy 57.774611 -393.426332) (xy 57.751969 -393.475909) (xy 57.722503 -393.521759) (xy 57.686812 -393.56295)
			(xy 57.645621 -393.598641) (xy 57.599771 -393.628107) (xy 57.550194 -393.650749) (xy 57.497899 -393.666104)
			(xy 57.443951 -393.67386) (xy 57.389449 -393.67386) (xy 57.335501 -393.666104) (xy 57.283206 -393.650749)
			(xy 57.233629 -393.628107) (xy 57.187779 -393.598641) (xy 57.146588 -393.56295) (xy 57.110897 -393.521759)
			(xy 57.081431 -393.475909) (xy 57.058789 -393.426332) (xy 57.043434 -393.374037) (xy 57.035678 -393.320089)
			(xy 57.035192 -393.292838) (xy 56.598312 -393.292838) (xy 56.597826 -393.320107) (xy 56.590064 -393.374091)
			(xy 56.574699 -393.426421) (xy 56.552042 -393.476031) (xy 56.522556 -393.521912) (xy 56.486841 -393.563129)
			(xy 56.445624 -393.598844) (xy 56.399743 -393.62833) (xy 56.350133 -393.650987) (xy 56.297803 -393.666352)
			(xy 56.243819 -393.674114) (xy 56.189281 -393.674114) (xy 56.135297 -393.666352) (xy 56.082967 -393.650987)
			(xy 56.033357 -393.62833) (xy 55.987476 -393.598844) (xy 55.946259 -393.563129) (xy 55.910544 -393.521912)
			(xy 55.881058 -393.476031) (xy 55.858401 -393.426421) (xy 55.843036 -393.374091) (xy 55.835274 -393.320107)
			(xy 55.834788 -393.292838) (xy 55.398416 -393.292838) (xy 55.39793 -393.320107) (xy 55.390168 -393.374091)
			(xy 55.374803 -393.426421) (xy 55.352146 -393.476031) (xy 55.32266 -393.521912) (xy 55.286945 -393.563129)
			(xy 55.245728 -393.598844) (xy 55.199847 -393.62833) (xy 55.150237 -393.650987) (xy 55.097907 -393.666352)
			(xy 55.043923 -393.674114) (xy 54.989385 -393.674114) (xy 54.935401 -393.666352) (xy 54.883071 -393.650987)
			(xy 54.833461 -393.62833) (xy 54.78758 -393.598844) (xy 54.746363 -393.563129) (xy 54.710648 -393.521912)
			(xy 54.681162 -393.476031) (xy 54.658505 -393.426421) (xy 54.64314 -393.374091) (xy 54.635378 -393.320107)
			(xy 54.634892 -393.292838) (xy 54.198012 -393.292838) (xy 54.197526 -393.320089) (xy 54.18977 -393.374037)
			(xy 54.174415 -393.426332) (xy 54.151773 -393.475909) (xy 54.122307 -393.521759) (xy 54.086616 -393.56295)
			(xy 54.045425 -393.598641) (xy 53.999575 -393.628107) (xy 53.949998 -393.650749) (xy 53.897703 -393.666104)
			(xy 53.843755 -393.67386) (xy 53.789253 -393.67386) (xy 53.735305 -393.666104) (xy 53.68301 -393.650749)
			(xy 53.633433 -393.628107) (xy 53.587583 -393.598641) (xy 53.546392 -393.56295) (xy 53.510701 -393.521759)
			(xy 53.481235 -393.475909) (xy 53.458593 -393.426332) (xy 53.443238 -393.374037) (xy 53.435482 -393.320089)
			(xy 53.434996 -393.292838) (xy 52.998116 -393.292838) (xy 52.99763 -393.320089) (xy 52.989874 -393.374037)
			(xy 52.974519 -393.426332) (xy 52.951877 -393.475909) (xy 52.922411 -393.521759) (xy 52.88672 -393.56295)
			(xy 52.845529 -393.598641) (xy 52.799679 -393.628107) (xy 52.750102 -393.650749) (xy 52.697807 -393.666104)
			(xy 52.643859 -393.67386) (xy 52.589357 -393.67386) (xy 52.535409 -393.666104) (xy 52.483114 -393.650749)
			(xy 52.433537 -393.628107) (xy 52.387687 -393.598641) (xy 52.346496 -393.56295) (xy 52.310805 -393.521759)
			(xy 52.281339 -393.475909) (xy 52.258697 -393.426332) (xy 52.243342 -393.374037) (xy 52.235586 -393.320089)
			(xy 52.2351 -393.292838) (xy 51.79822 -393.292838) (xy 51.797734 -393.320107) (xy 51.789972 -393.374091)
			(xy 51.774607 -393.426421) (xy 51.75195 -393.476031) (xy 51.722464 -393.521912) (xy 51.686749 -393.563129)
			(xy 51.645532 -393.598844) (xy 51.599651 -393.62833) (xy 51.550041 -393.650987) (xy 51.497711 -393.666352)
			(xy 51.443727 -393.674114) (xy 51.389189 -393.674114) (xy 51.335205 -393.666352) (xy 51.282875 -393.650987)
			(xy 51.233265 -393.62833) (xy 51.187384 -393.598844) (xy 51.146167 -393.563129) (xy 51.110452 -393.521912)
			(xy 51.080966 -393.476031) (xy 51.058309 -393.426421) (xy 51.042944 -393.374091) (xy 51.035182 -393.320107)
			(xy 51.034696 -393.292838) (xy 50.598324 -393.292838) (xy 50.597838 -393.320107) (xy 50.590076 -393.374091)
			(xy 50.574711 -393.426421) (xy 50.552054 -393.476031) (xy 50.522568 -393.521912) (xy 50.486853 -393.563129)
			(xy 50.445636 -393.598844) (xy 50.399755 -393.62833) (xy 50.350145 -393.650987) (xy 50.297815 -393.666352)
			(xy 50.243831 -393.674114) (xy 50.189293 -393.674114) (xy 50.135309 -393.666352) (xy 50.082979 -393.650987)
			(xy 50.033369 -393.62833) (xy 49.987488 -393.598844) (xy 49.946271 -393.563129) (xy 49.910556 -393.521912)
			(xy 49.88107 -393.476031) (xy 49.858413 -393.426421) (xy 49.843048 -393.374091) (xy 49.835286 -393.320107)
			(xy 49.8348 -393.292838) (xy 49.39792 -393.292838) (xy 49.397434 -393.320089) (xy 49.389678 -393.374037)
			(xy 49.374323 -393.426332) (xy 49.351681 -393.475909) (xy 49.322215 -393.521759) (xy 49.286524 -393.56295)
			(xy 49.245333 -393.598641) (xy 49.199483 -393.628107) (xy 49.149906 -393.650749) (xy 49.097611 -393.666104)
			(xy 49.043663 -393.67386) (xy 48.989161 -393.67386) (xy 48.935213 -393.666104) (xy 48.882918 -393.650749)
			(xy 48.833341 -393.628107) (xy 48.787491 -393.598641) (xy 48.7463 -393.56295) (xy 48.710609 -393.521759)
			(xy 48.681143 -393.475909) (xy 48.658501 -393.426332) (xy 48.643146 -393.374037) (xy 48.63539 -393.320089)
			(xy 48.634904 -393.292838) (xy 48.198024 -393.292838) (xy 48.197538 -393.320089) (xy 48.189782 -393.374037)
			(xy 48.174427 -393.426332) (xy 48.151785 -393.475909) (xy 48.122319 -393.521759) (xy 48.086628 -393.56295)
			(xy 48.045437 -393.598641) (xy 47.999587 -393.628107) (xy 47.95001 -393.650749) (xy 47.897715 -393.666104)
			(xy 47.843767 -393.67386) (xy 47.789265 -393.67386) (xy 47.735317 -393.666104) (xy 47.683022 -393.650749)
			(xy 47.633445 -393.628107) (xy 47.587595 -393.598641) (xy 47.546404 -393.56295) (xy 47.510713 -393.521759)
			(xy 47.481247 -393.475909) (xy 47.458605 -393.426332) (xy 47.44325 -393.374037) (xy 47.435494 -393.320089)
			(xy 47.435008 -393.292838) (xy 2.509012 -393.292838) (xy 2.509012 -400.50847) (xy 103.485188 -400.50847)
			(xy 103.485723 -400.479553) (xy 103.494444 -400.422381) (xy 103.511697 -400.367182) (xy 103.537085 -400.315219)
			(xy 103.570027 -400.267685) (xy 103.609768 -400.225669) (xy 103.632254 -400.20748) (xy 103.641069 -400.199881)
			(xy 103.651246 -400.178974) (xy 103.651812 -400.167348) (xy 103.651812 -400.087592) (xy 103.651259 -400.075962)
			(xy 103.64108 -400.055053) (xy 103.632254 -400.04746) (xy 103.609742 -400.029303) (xy 103.57001 -399.987275)
			(xy 103.537076 -399.939733) (xy 103.511693 -399.887765) (xy 103.494443 -399.832562) (xy 103.48572 -399.775388)
			(xy 103.485188 -399.74647) (xy 103.485674 -399.719201) (xy 103.493436 -399.665217) (xy 103.508801 -399.612887)
			(xy 103.531458 -399.563277) (xy 103.560944 -399.517396) (xy 103.596659 -399.476179) (xy 103.637876 -399.440464)
			(xy 103.683757 -399.410978) (xy 103.733367 -399.388321) (xy 103.785697 -399.372956) (xy 103.839681 -399.365194)
			(xy 103.894219 -399.365194) (xy 103.948203 -399.372956) (xy 104.000533 -399.388321) (xy 104.050143 -399.410978)
			(xy 104.096024 -399.440464) (xy 104.137241 -399.476179) (xy 104.172956 -399.517396) (xy 104.202442 -399.563277)
			(xy 104.225099 -399.612887) (xy 104.240464 -399.665217) (xy 104.248226 -399.719201) (xy 104.248712 -399.74647)
			(xy 104.248206 -399.775388) (xy 104.239479 -399.832561) (xy 104.222221 -399.887762) (xy 104.196827 -399.939724)
			(xy 104.16388 -399.987257) (xy 104.124134 -400.029272) (xy 104.101646 -400.04746) (xy 104.092858 -400.055085)
			(xy 104.082666 -400.075972) (xy 104.082088 -400.087592) (xy 104.082088 -400.167348) (xy 104.082618 -400.178981)
			(xy 104.092814 -400.19989) (xy 104.101646 -400.20748) (xy 104.124129 -400.225671) (xy 104.163863 -400.267692)
			(xy 104.1968 -400.315227) (xy 104.222188 -400.367188) (xy 104.239445 -400.422385) (xy 104.248176 -400.479554)
			(xy 104.248712 -400.50847) (xy 104.248226 -400.535739) (xy 104.240464 -400.589723) (xy 104.225099 -400.642053)
			(xy 104.202442 -400.691663) (xy 104.172956 -400.737544) (xy 104.137241 -400.778761) (xy 104.096024 -400.814476)
			(xy 104.050143 -400.843962) (xy 104.000533 -400.866619) (xy 103.948203 -400.881984) (xy 103.894219 -400.889746)
			(xy 103.839681 -400.889746) (xy 103.785697 -400.881984) (xy 103.733367 -400.866619) (xy 103.683757 -400.843962)
			(xy 103.637876 -400.814476) (xy 103.596659 -400.778761) (xy 103.560944 -400.737544) (xy 103.531458 -400.691663)
			(xy 103.508801 -400.642053) (xy 103.493436 -400.589723) (xy 103.485674 -400.535739) (xy 103.485188 -400.50847)
			(xy 2.509012 -400.50847) (xy 2.509012 -403.371812) (xy 2.5095 -403.425034) (xy 2.517117 -403.531207)
			(xy 2.532283 -403.636566) (xy 2.554922 -403.740575) (xy 2.584919 -403.842706) (xy 2.622121 -403.942439)
			(xy 2.666338 -404.039266) (xy 2.717346 -404.132693) (xy 2.774884 -404.222247) (xy 2.838661 -404.307471)
			(xy 2.908351 -404.387931) (xy 2.945638 -404.425912) (xy 3.30962 -404.789894) (xy 37.568898 -404.789894)
			(xy 37.57287 -404.611651) (xy 37.584778 -404.433762) (xy 37.604599 -404.25658) (xy 37.632293 -404.080456)
			(xy 37.667805 -403.905741) (xy 37.711065 -403.732782) (xy 37.761987 -403.561921) (xy 37.82047 -403.393499)
			(xy 37.886397 -403.227849) (xy 37.959638 -403.0653) (xy 38.040048 -402.906175) (xy 38.127466 -402.75079)
			(xy 38.221719 -402.599454) (xy 38.32262 -402.452466) (xy 38.429969 -402.310119) (xy 38.543552 -402.172696)
			(xy 38.663145 -402.040469) (xy 38.788509 -401.9137) (xy 38.919396 -401.792642) (xy 39.055545 -401.677535)
			(xy 39.196687 -401.568607) (xy 39.342542 -401.466075) (xy 39.492819 -401.370141) (xy 39.64722 -401.280998)
			(xy 39.805439 -401.198821) (xy 39.967162 -401.123773) (xy 40.132067 -401.056005) (xy 40.299828 -400.995649)
			(xy 40.470111 -400.942827) (xy 40.642578 -400.897643) (xy 40.816886 -400.860186) (xy 40.99269 -400.830532)
			(xy 41.16964 -400.808739) (xy 41.347386 -400.794849) (xy 41.525573 -400.788892) (xy 41.70385 -400.790878)
			(xy 41.881861 -400.800804) (xy 42.059253 -400.81865) (xy 42.235673 -400.84438) (xy 42.410773 -400.877944)
			(xy 42.584204 -400.919274) (xy 42.755621 -400.96829) (xy 42.924684 -401.024892) (xy 43.091059 -401.08897)
			(xy 43.254413 -401.160396) (xy 43.414424 -401.239028) (xy 43.570773 -401.324709) (xy 43.72315 -401.417271)
			(xy 43.871253 -401.516528) (xy 44.014787 -401.622285) (xy 44.153467 -401.73433) (xy 44.287018 -401.852442)
			(xy 44.415175 -401.976386) (xy 44.537684 -402.105916) (xy 44.654301 -402.240775) (xy 44.764794 -402.380695)
			(xy 44.868945 -402.525398) (xy 44.966547 -402.674597) (xy 45.057405 -402.827996) (xy 45.141339 -402.98529)
			(xy 45.218184 -403.146166) (xy 45.287785 -403.310307) (xy 45.350006 -403.477384) (xy 45.404722 -403.647068)
			(xy 45.451824 -403.819021) (xy 45.49122 -403.992901) (xy 45.522831 -404.168364) (xy 45.546595 -404.34506)
			(xy 45.559703 -404.491748) (xy 47.413198 -404.491748) (xy 47.413198 -404.437252) (xy 47.420953 -404.38331)
			(xy 47.436306 -404.331021) (xy 47.458943 -404.281449) (xy 47.488404 -404.235603) (xy 47.52409 -404.194416)
			(xy 47.565274 -404.158726) (xy 47.611117 -404.12926) (xy 47.660687 -404.106618) (xy 47.712975 -404.091261)
			(xy 47.766916 -404.083501) (xy 47.794164 -404.083012) (xy 48.657764 -404.083012) (xy 48.68502 -404.083432)
			(xy 48.738978 -404.091186) (xy 48.791283 -404.106539) (xy 48.84087 -404.129181) (xy 48.88673 -404.15865)
			(xy 48.927929 -404.194345) (xy 48.963629 -404.235541) (xy 48.993102 -404.281398) (xy 49.015748 -404.330984)
			(xy 49.031107 -404.383287) (xy 49.038865 -404.437244) (xy 49.038865 -404.491752) (xy 50.476375 -404.491752)
			(xy 50.476375 -404.437248) (xy 50.484132 -404.3833) (xy 50.499487 -404.331005) (xy 50.522129 -404.281427)
			(xy 50.551596 -404.235576) (xy 50.587288 -404.194385) (xy 50.628479 -404.158693) (xy 50.67433 -404.129227)
			(xy 50.723908 -404.106586) (xy 50.776204 -404.091231) (xy 50.830152 -404.083475) (xy 50.857404 -404.083012)
			(xy 51.721004 -404.083012) (xy 51.748256 -404.083458) (xy 51.802207 -404.091215) (xy 51.854504 -404.106572)
			(xy 51.904083 -404.129214) (xy 51.949935 -404.158682) (xy 51.991127 -404.194376) (xy 52.02682 -404.235568)
			(xy 52.056288 -404.281421) (xy 52.07893 -404.331) (xy 52.094285 -404.383297) (xy 52.102042 -404.437248)
			(xy 52.102042 -404.491752) (xy 52.102042 -404.491753) (xy 53.539575 -404.491753) (xy 53.539575 -404.437247)
			(xy 53.547333 -404.383295) (xy 53.562691 -404.330996) (xy 53.585335 -404.281416) (xy 53.614806 -404.235563)
			(xy 53.650502 -404.194371) (xy 53.691698 -404.158679) (xy 53.737554 -404.129214) (xy 53.787137 -404.106575)
			(xy 53.839438 -404.091224) (xy 53.893391 -404.083472) (xy 53.920644 -404.083012) (xy 54.784244 -404.083012)
			(xy 54.811495 -404.083461) (xy 54.86544 -404.091223) (xy 54.917733 -404.106583) (xy 54.967307 -404.129227)
			(xy 55.013154 -404.158696) (xy 55.054341 -404.19439) (xy 55.09003 -404.235581) (xy 55.119494 -404.281432)
			(xy 55.142133 -404.331009) (xy 55.157487 -404.383303) (xy 55.165242 -404.437249) (xy 55.165242 -404.491749)
			(xy 56.602898 -404.491749) (xy 56.602898 -404.437251) (xy 56.610654 -404.383308) (xy 56.626007 -404.331017)
			(xy 56.648646 -404.281443) (xy 56.678109 -404.235596) (xy 56.713797 -404.194409) (xy 56.754983 -404.158719)
			(xy 56.800829 -404.129254) (xy 56.850402 -404.106613) (xy 56.902692 -404.091257) (xy 56.956635 -404.083499)
			(xy 56.983884 -404.083012) (xy 57.847484 -404.083012) (xy 57.874739 -404.083434) (xy 57.928695 -404.091189)
			(xy 57.980997 -404.106545) (xy 58.030582 -404.129188) (xy 58.07644 -404.158657) (xy 58.117636 -404.194352)
			(xy 58.153334 -404.235548) (xy 58.182805 -404.281404) (xy 58.20545 -404.330988) (xy 58.220807 -404.38329)
			(xy 58.228565 -404.437245) (xy 58.228565 -404.491753) (xy 59.666075 -404.491753) (xy 59.666075 -404.437247)
			(xy 59.673833 -404.383297) (xy 59.689189 -404.331) (xy 59.711832 -404.281421) (xy 59.741301 -404.235569)
			(xy 59.776995 -404.194378) (xy 59.818188 -404.158686) (xy 59.864042 -404.129221) (xy 59.913623 -404.106581)
			(xy 59.965921 -404.091227) (xy 60.019871 -404.083474) (xy 60.047124 -404.083012) (xy 60.910724 -404.083012)
			(xy 60.937976 -404.083459) (xy 60.991924 -404.091219) (xy 61.044218 -404.106577) (xy 61.093795 -404.129221)
			(xy 61.139645 -404.158689) (xy 61.180834 -404.194383) (xy 61.216525 -404.235575) (xy 61.245991 -404.281426)
			(xy 61.268631 -404.331004) (xy 61.283986 -404.3833) (xy 61.291742 -404.437248) (xy 61.291742 -404.491748)
			(xy 62.729398 -404.491748) (xy 62.729398 -404.437252) (xy 62.737153 -404.38331) (xy 62.752506 -404.331021)
			(xy 62.775143 -404.281449) (xy 62.804604 -404.235603) (xy 62.84029 -404.194416) (xy 62.881474 -404.158726)
			(xy 62.927317 -404.12926) (xy 62.976887 -404.106618) (xy 63.029175 -404.091261) (xy 63.083116 -404.083501)
			(xy 63.110364 -404.083012) (xy 63.973964 -404.083012) (xy 64.00122 -404.083432) (xy 64.055178 -404.091186)
			(xy 64.107483 -404.106539) (xy 64.15707 -404.129181) (xy 64.20293 -404.15865) (xy 64.244129 -404.194345)
			(xy 64.279829 -404.235541) (xy 64.309302 -404.281398) (xy 64.331948 -404.330984) (xy 64.347307 -404.383287)
			(xy 64.355065 -404.437244) (xy 64.355065 -404.491752) (xy 65.792575 -404.491752) (xy 65.792575 -404.437248)
			(xy 65.800332 -404.3833) (xy 65.815687 -404.331005) (xy 65.838329 -404.281427) (xy 65.867796 -404.235576)
			(xy 65.903488 -404.194385) (xy 65.944679 -404.158693) (xy 65.99053 -404.129227) (xy 66.040108 -404.106586)
			(xy 66.092404 -404.091231) (xy 66.146352 -404.083475) (xy 66.173604 -404.083012) (xy 67.037204 -404.083012)
			(xy 67.064456 -404.083458) (xy 67.118407 -404.091215) (xy 67.170704 -404.106572) (xy 67.220283 -404.129214)
			(xy 67.266135 -404.158682) (xy 67.307327 -404.194376) (xy 67.34302 -404.235568) (xy 67.372488 -404.281421)
			(xy 67.39513 -404.331) (xy 67.410485 -404.383297) (xy 67.418242 -404.437248) (xy 67.418242 -404.491752)
			(xy 67.418242 -404.491753) (xy 68.855775 -404.491753) (xy 68.855775 -404.437247) (xy 68.863533 -404.383295)
			(xy 68.878891 -404.330996) (xy 68.901535 -404.281416) (xy 68.931006 -404.235563) (xy 68.966702 -404.194371)
			(xy 69.007898 -404.158679) (xy 69.053754 -404.129214) (xy 69.103337 -404.106575) (xy 69.155638 -404.091224)
			(xy 69.209591 -404.083472) (xy 69.236844 -404.083012) (xy 70.100444 -404.083012) (xy 70.127695 -404.083461)
			(xy 70.18164 -404.091223) (xy 70.233933 -404.106583) (xy 70.283507 -404.129227) (xy 70.329354 -404.158696)
			(xy 70.370541 -404.19439) (xy 70.40623 -404.235581) (xy 70.435694 -404.281432) (xy 70.458333 -404.331009)
			(xy 70.473687 -404.383303) (xy 70.481442 -404.437249) (xy 70.481442 -404.491749) (xy 71.919098 -404.491749)
			(xy 71.919098 -404.437251) (xy 71.926854 -404.383308) (xy 71.942207 -404.331017) (xy 71.964846 -404.281443)
			(xy 71.994309 -404.235596) (xy 72.029997 -404.194409) (xy 72.071183 -404.158719) (xy 72.117029 -404.129254)
			(xy 72.166602 -404.106613) (xy 72.218892 -404.091257) (xy 72.272835 -404.083499) (xy 72.300084 -404.083012)
			(xy 73.163684 -404.083012) (xy 73.190939 -404.083434) (xy 73.244895 -404.091189) (xy 73.297197 -404.106545)
			(xy 73.346782 -404.129188) (xy 73.39264 -404.158657) (xy 73.433836 -404.194352) (xy 73.469534 -404.235548)
			(xy 73.499005 -404.281404) (xy 73.52165 -404.330988) (xy 73.537007 -404.38329) (xy 73.544765 -404.437245)
			(xy 73.544765 -404.491753) (xy 74.982275 -404.491753) (xy 74.982275 -404.437247) (xy 74.990033 -404.383297)
			(xy 75.005389 -404.331) (xy 75.028032 -404.281421) (xy 75.057501 -404.235569) (xy 75.093195 -404.194378)
			(xy 75.134388 -404.158686) (xy 75.180242 -404.129221) (xy 75.229823 -404.106581) (xy 75.282121 -404.091227)
			(xy 75.336071 -404.083474) (xy 75.363324 -404.083012) (xy 76.226924 -404.083012) (xy 76.254176 -404.083459)
			(xy 76.308124 -404.091219) (xy 76.360418 -404.106577) (xy 76.409995 -404.129221) (xy 76.455845 -404.158689)
			(xy 76.497034 -404.194383) (xy 76.532725 -404.235575) (xy 76.562191 -404.281426) (xy 76.584831 -404.331004)
			(xy 76.600186 -404.3833) (xy 76.607942 -404.437248) (xy 76.607942 -404.491748) (xy 78.045598 -404.491748)
			(xy 78.045598 -404.437252) (xy 78.053353 -404.38331) (xy 78.068706 -404.331021) (xy 78.091343 -404.281449)
			(xy 78.120804 -404.235603) (xy 78.15649 -404.194416) (xy 78.197674 -404.158726) (xy 78.243517 -404.12926)
			(xy 78.293087 -404.106618) (xy 78.345375 -404.091261) (xy 78.399316 -404.083501) (xy 78.426564 -404.083012)
			(xy 79.290164 -404.083012) (xy 79.31742 -404.083432) (xy 79.371378 -404.091186) (xy 79.423683 -404.106539)
			(xy 79.47327 -404.129181) (xy 79.51913 -404.15865) (xy 79.560329 -404.194345) (xy 79.596029 -404.235541)
			(xy 79.625502 -404.281398) (xy 79.648148 -404.330984) (xy 79.663507 -404.383287) (xy 79.671265 -404.437244)
			(xy 79.671265 -404.491752) (xy 81.108775 -404.491752) (xy 81.108775 -404.437248) (xy 81.116532 -404.3833)
			(xy 81.131887 -404.331005) (xy 81.154529 -404.281427) (xy 81.183996 -404.235576) (xy 81.219688 -404.194385)
			(xy 81.260879 -404.158693) (xy 81.30673 -404.129227) (xy 81.356308 -404.106586) (xy 81.408604 -404.091231)
			(xy 81.462552 -404.083475) (xy 81.489804 -404.083012) (xy 82.353404 -404.083012) (xy 82.380656 -404.083458)
			(xy 82.434607 -404.091215) (xy 82.486904 -404.106572) (xy 82.536483 -404.129214) (xy 82.582335 -404.158682)
			(xy 82.623527 -404.194376) (xy 82.65922 -404.235568) (xy 82.688688 -404.281421) (xy 82.71133 -404.331)
			(xy 82.726685 -404.383297) (xy 82.734442 -404.437248) (xy 82.734442 -404.491752) (xy 82.734442 -404.491753)
			(xy 84.171975 -404.491753) (xy 84.171975 -404.437247) (xy 84.179733 -404.383295) (xy 84.195091 -404.330996)
			(xy 84.217735 -404.281416) (xy 84.247206 -404.235563) (xy 84.282902 -404.194371) (xy 84.324098 -404.158679)
			(xy 84.369954 -404.129214) (xy 84.419537 -404.106575) (xy 84.471838 -404.091224) (xy 84.525791 -404.083472)
			(xy 84.553044 -404.083012) (xy 85.416644 -404.083012) (xy 85.443895 -404.083461) (xy 85.49784 -404.091223)
			(xy 85.550133 -404.106583) (xy 85.599707 -404.129227) (xy 85.645554 -404.158696) (xy 85.686741 -404.19439)
			(xy 85.72243 -404.235581) (xy 85.751894 -404.281432) (xy 85.774533 -404.331009) (xy 85.789887 -404.383303)
			(xy 85.797642 -404.437249) (xy 85.797642 -404.491749) (xy 87.235298 -404.491749) (xy 87.235298 -404.437251)
			(xy 87.243054 -404.383308) (xy 87.258407 -404.331017) (xy 87.281046 -404.281443) (xy 87.310509 -404.235596)
			(xy 87.346197 -404.194409) (xy 87.387383 -404.158719) (xy 87.433229 -404.129254) (xy 87.482802 -404.106613)
			(xy 87.535092 -404.091257) (xy 87.589035 -404.083499) (xy 87.616284 -404.083012) (xy 88.479884 -404.083012)
			(xy 88.507139 -404.083434) (xy 88.561095 -404.091189) (xy 88.613397 -404.106545) (xy 88.662982 -404.129188)
			(xy 88.70884 -404.158657) (xy 88.750036 -404.194352) (xy 88.785734 -404.235548) (xy 88.815205 -404.281404)
			(xy 88.83785 -404.330988) (xy 88.853207 -404.38329) (xy 88.860965 -404.437245) (xy 88.860965 -404.491753)
			(xy 90.298475 -404.491753) (xy 90.298475 -404.437247) (xy 90.306233 -404.383297) (xy 90.321589 -404.331)
			(xy 90.344232 -404.281421) (xy 90.373701 -404.235569) (xy 90.409395 -404.194378) (xy 90.450588 -404.158686)
			(xy 90.496442 -404.129221) (xy 90.546023 -404.106581) (xy 90.598321 -404.091227) (xy 90.652271 -404.083474)
			(xy 90.679524 -404.083012) (xy 91.543124 -404.083012) (xy 91.570376 -404.083459) (xy 91.624324 -404.091219)
			(xy 91.676618 -404.106577) (xy 91.726195 -404.129221) (xy 91.772045 -404.158689) (xy 91.813234 -404.194383)
			(xy 91.848925 -404.235575) (xy 91.878391 -404.281426) (xy 91.901031 -404.331004) (xy 91.916386 -404.3833)
			(xy 91.924142 -404.437248) (xy 91.924142 -404.491748) (xy 93.361798 -404.491748) (xy 93.361798 -404.437252)
			(xy 93.369553 -404.38331) (xy 93.384906 -404.331021) (xy 93.407543 -404.281449) (xy 93.437004 -404.235603)
			(xy 93.47269 -404.194416) (xy 93.513874 -404.158726) (xy 93.559717 -404.12926) (xy 93.609287 -404.106618)
			(xy 93.661575 -404.091261) (xy 93.715516 -404.083501) (xy 93.742764 -404.083012) (xy 94.606364 -404.083012)
			(xy 94.63362 -404.083432) (xy 94.687578 -404.091186) (xy 94.739883 -404.106539) (xy 94.78947 -404.129181)
			(xy 94.83533 -404.15865) (xy 94.876529 -404.194345) (xy 94.912229 -404.235541) (xy 94.941702 -404.281398)
			(xy 94.964348 -404.330984) (xy 94.979707 -404.383287) (xy 94.987465 -404.437244) (xy 94.987465 -404.491752)
			(xy 114.513075 -404.491752) (xy 114.513075 -404.437248) (xy 114.520832 -404.3833) (xy 114.536188 -404.331004)
			(xy 114.558829 -404.281426) (xy 114.588296 -404.235575) (xy 114.623989 -404.194384) (xy 114.66518 -404.158693)
			(xy 114.711031 -404.129226) (xy 114.76061 -404.106585) (xy 114.812906 -404.091231) (xy 114.866854 -404.083475)
			(xy 114.894106 -404.083012) (xy 115.757706 -404.083012) (xy 115.784958 -404.083458) (xy 115.838908 -404.091216)
			(xy 115.891205 -404.106572) (xy 115.940784 -404.129215) (xy 115.986636 -404.158683) (xy 116.027828 -404.194376)
			(xy 116.063521 -404.235569) (xy 116.092988 -404.281421) (xy 116.11563 -404.331001) (xy 116.130985 -404.383298)
			(xy 116.138742 -404.437248) (xy 116.138742 -404.491752) (xy 116.138742 -404.491754) (xy 117.576275 -404.491754)
			(xy 117.576275 -404.437246) (xy 117.584033 -404.383294) (xy 117.599391 -404.330996) (xy 117.622035 -404.281415)
			(xy 117.651506 -404.235562) (xy 117.687203 -404.19437) (xy 117.728399 -404.158679) (xy 117.774255 -404.129213)
			(xy 117.823839 -404.106575) (xy 117.876139 -404.091223) (xy 117.930092 -404.083472) (xy 117.957346 -404.083012)
			(xy 118.820946 -404.083012) (xy 118.848197 -404.083461) (xy 118.902142 -404.091223) (xy 118.954434 -404.106583)
			(xy 119.004008 -404.129228) (xy 119.049855 -404.158697) (xy 119.091042 -404.194391) (xy 119.12673 -404.235582)
			(xy 119.156194 -404.281432) (xy 119.178833 -404.331009) (xy 119.194187 -404.383303) (xy 119.201942 -404.437249)
			(xy 119.201942 -404.491749) (xy 120.639598 -404.491749) (xy 120.639598 -404.437251) (xy 120.647354 -404.383307)
			(xy 120.662708 -404.331016) (xy 120.685346 -404.281443) (xy 120.71481 -404.235596) (xy 120.750498 -404.194408)
			(xy 120.791684 -404.158718) (xy 120.83753 -404.129253) (xy 120.887103 -404.106612) (xy 120.939394 -404.091257)
			(xy 120.993337 -404.083499) (xy 121.020586 -404.083012) (xy 121.884186 -404.083012) (xy 121.911441 -404.083434)
			(xy 121.965396 -404.09119) (xy 122.017699 -404.106545) (xy 122.067283 -404.129188) (xy 122.113141 -404.158657)
			(xy 122.154337 -404.194353) (xy 122.190034 -404.235548) (xy 122.219505 -404.281405) (xy 122.24215 -404.330988)
			(xy 122.257507 -404.38329) (xy 122.265265 -404.437245) (xy 122.265265 -404.491753) (xy 123.702775 -404.491753)
			(xy 123.702775 -404.437247) (xy 123.710533 -404.383297) (xy 123.725889 -404.331) (xy 123.748532 -404.281421)
			(xy 123.778001 -404.235569) (xy 123.813696 -404.194377) (xy 123.854889 -404.158686) (xy 123.900743 -404.12922)
			(xy 123.950324 -404.10658) (xy 124.002622 -404.091227) (xy 124.056573 -404.083474) (xy 124.083826 -404.083012)
			(xy 124.947426 -404.083012) (xy 124.974677 -404.08346) (xy 125.028625 -404.09122) (xy 125.08092 -404.106578)
			(xy 125.130496 -404.129222) (xy 125.176346 -404.15869) (xy 125.217535 -404.194383) (xy 125.253226 -404.235575)
			(xy 125.282691 -404.281427) (xy 125.305331 -404.331005) (xy 125.320686 -404.3833) (xy 125.328442 -404.437249)
			(xy 125.328442 -404.491748) (xy 126.766098 -404.491748) (xy 126.766098 -404.437252) (xy 126.773853 -404.38331)
			(xy 126.789206 -404.331021) (xy 126.811843 -404.281448) (xy 126.841305 -404.235602) (xy 126.876991 -404.194415)
			(xy 126.918175 -404.158725) (xy 126.964018 -404.12926) (xy 127.013589 -404.106618) (xy 127.065877 -404.091261)
			(xy 127.119818 -404.083501) (xy 127.147066 -404.083012) (xy 128.010666 -404.083012) (xy 128.037922 -404.083433)
			(xy 128.091879 -404.091186) (xy 128.144184 -404.10654) (xy 128.193771 -404.129182) (xy 128.239631 -404.15865)
			(xy 128.28083 -404.194346) (xy 128.316529 -404.235542) (xy 128.346002 -404.281399) (xy 128.368648 -404.330984)
			(xy 128.384007 -404.383287) (xy 128.391765 -404.437244) (xy 128.391765 -404.491752) (xy 129.829275 -404.491752)
			(xy 129.829275 -404.437248) (xy 129.837032 -404.3833) (xy 129.852388 -404.331004) (xy 129.875029 -404.281426)
			(xy 129.904496 -404.235575) (xy 129.940189 -404.194384) (xy 129.98138 -404.158693) (xy 130.027231 -404.129226)
			(xy 130.07681 -404.106585) (xy 130.129106 -404.091231) (xy 130.183054 -404.083475) (xy 130.210306 -404.083012)
			(xy 131.073906 -404.083012) (xy 131.101158 -404.083458) (xy 131.155108 -404.091216) (xy 131.207405 -404.106572)
			(xy 131.256984 -404.129215) (xy 131.302836 -404.158683) (xy 131.344028 -404.194376) (xy 131.379721 -404.235569)
			(xy 131.409188 -404.281421) (xy 131.43183 -404.331001) (xy 131.447185 -404.383298) (xy 131.454942 -404.437248)
			(xy 131.454942 -404.491752) (xy 131.454942 -404.491754) (xy 132.892475 -404.491754) (xy 132.892475 -404.437246)
			(xy 132.900233 -404.383294) (xy 132.915591 -404.330996) (xy 132.938235 -404.281415) (xy 132.967706 -404.235562)
			(xy 133.003403 -404.19437) (xy 133.044599 -404.158679) (xy 133.090455 -404.129213) (xy 133.140039 -404.106575)
			(xy 133.192339 -404.091223) (xy 133.246292 -404.083472) (xy 133.273546 -404.083012) (xy 134.137146 -404.083012)
			(xy 134.164397 -404.083461) (xy 134.218342 -404.091223) (xy 134.270634 -404.106583) (xy 134.320208 -404.129228)
			(xy 134.366055 -404.158697) (xy 134.407242 -404.194391) (xy 134.44293 -404.235582) (xy 134.472394 -404.281432)
			(xy 134.495033 -404.331009) (xy 134.510387 -404.383303) (xy 134.518142 -404.437249) (xy 134.518142 -404.491749)
			(xy 135.955798 -404.491749) (xy 135.955798 -404.437251) (xy 135.963554 -404.383307) (xy 135.978908 -404.331016)
			(xy 136.001546 -404.281443) (xy 136.03101 -404.235596) (xy 136.066698 -404.194408) (xy 136.107884 -404.158718)
			(xy 136.15373 -404.129253) (xy 136.203303 -404.106612) (xy 136.255594 -404.091257) (xy 136.309537 -404.083499)
			(xy 136.336786 -404.083012) (xy 137.200386 -404.083012) (xy 137.227641 -404.083434) (xy 137.281596 -404.09119)
			(xy 137.333899 -404.106545) (xy 137.383483 -404.129188) (xy 137.429341 -404.158657) (xy 137.470537 -404.194353)
			(xy 137.506234 -404.235548) (xy 137.535705 -404.281405) (xy 137.55835 -404.330988) (xy 137.573707 -404.38329)
			(xy 137.581465 -404.437245) (xy 137.581465 -404.491753) (xy 139.018975 -404.491753) (xy 139.018975 -404.437247)
			(xy 139.026733 -404.383297) (xy 139.042089 -404.331) (xy 139.064732 -404.281421) (xy 139.094201 -404.235569)
			(xy 139.129896 -404.194377) (xy 139.171089 -404.158686) (xy 139.216943 -404.12922) (xy 139.266524 -404.10658)
			(xy 139.318822 -404.091227) (xy 139.372773 -404.083474) (xy 139.400026 -404.083012) (xy 140.263626 -404.083012)
			(xy 140.290877 -404.08346) (xy 140.344825 -404.09122) (xy 140.39712 -404.106578) (xy 140.446696 -404.129222)
			(xy 140.492546 -404.15869) (xy 140.533735 -404.194383) (xy 140.569426 -404.235575) (xy 140.598891 -404.281427)
			(xy 140.621531 -404.331005) (xy 140.636886 -404.3833) (xy 140.644642 -404.437249) (xy 140.644642 -404.491748)
			(xy 142.082298 -404.491748) (xy 142.082298 -404.437252) (xy 142.090053 -404.38331) (xy 142.105406 -404.331021)
			(xy 142.128043 -404.281448) (xy 142.157505 -404.235602) (xy 142.193191 -404.194415) (xy 142.234375 -404.158725)
			(xy 142.280218 -404.12926) (xy 142.329789 -404.106618) (xy 142.382077 -404.091261) (xy 142.436018 -404.083501)
			(xy 142.463266 -404.083012) (xy 143.326866 -404.083012) (xy 143.354122 -404.083433) (xy 143.408079 -404.091186)
			(xy 143.460384 -404.10654) (xy 143.509971 -404.129182) (xy 143.555831 -404.15865) (xy 143.59703 -404.194346)
			(xy 143.632729 -404.235542) (xy 143.662202 -404.281399) (xy 143.684848 -404.330984) (xy 143.700207 -404.383287)
			(xy 143.707965 -404.437244) (xy 143.707965 -404.491752) (xy 145.145475 -404.491752) (xy 145.145475 -404.437248)
			(xy 145.153232 -404.3833) (xy 145.168588 -404.331004) (xy 145.191229 -404.281426) (xy 145.220696 -404.235575)
			(xy 145.256389 -404.194384) (xy 145.29758 -404.158693) (xy 145.343431 -404.129226) (xy 145.39301 -404.106585)
			(xy 145.445306 -404.091231) (xy 145.499254 -404.083475) (xy 145.526506 -404.083012) (xy 146.390106 -404.083012)
			(xy 146.417358 -404.083458) (xy 146.471308 -404.091216) (xy 146.523605 -404.106572) (xy 146.573184 -404.129215)
			(xy 146.619036 -404.158683) (xy 146.660228 -404.194376) (xy 146.695921 -404.235569) (xy 146.725388 -404.281421)
			(xy 146.74803 -404.331001) (xy 146.763385 -404.383298) (xy 146.771142 -404.437248) (xy 146.771142 -404.491752)
			(xy 146.771142 -404.491754) (xy 148.208675 -404.491754) (xy 148.208675 -404.437246) (xy 148.216433 -404.383294)
			(xy 148.231791 -404.330996) (xy 148.254435 -404.281415) (xy 148.283906 -404.235562) (xy 148.319603 -404.19437)
			(xy 148.360799 -404.158679) (xy 148.406655 -404.129213) (xy 148.456239 -404.106575) (xy 148.508539 -404.091223)
			(xy 148.562492 -404.083472) (xy 148.589746 -404.083012) (xy 149.453346 -404.083012) (xy 149.480597 -404.083461)
			(xy 149.534542 -404.091223) (xy 149.586834 -404.106583) (xy 149.636408 -404.129228) (xy 149.682255 -404.158697)
			(xy 149.723442 -404.194391) (xy 149.75913 -404.235582) (xy 149.788594 -404.281432) (xy 149.811233 -404.331009)
			(xy 149.826587 -404.383303) (xy 149.834342 -404.437249) (xy 149.834342 -404.491749) (xy 151.271998 -404.491749)
			(xy 151.271998 -404.437251) (xy 151.279754 -404.383307) (xy 151.295108 -404.331016) (xy 151.317746 -404.281443)
			(xy 151.34721 -404.235596) (xy 151.382898 -404.194408) (xy 151.424084 -404.158718) (xy 151.46993 -404.129253)
			(xy 151.519503 -404.106612) (xy 151.571794 -404.091257) (xy 151.625737 -404.083499) (xy 151.652986 -404.083012)
			(xy 152.516586 -404.083012) (xy 152.543841 -404.083434) (xy 152.597796 -404.09119) (xy 152.650099 -404.106545)
			(xy 152.699683 -404.129188) (xy 152.745541 -404.158657) (xy 152.786737 -404.194353) (xy 152.822434 -404.235548)
			(xy 152.851905 -404.281405) (xy 152.87455 -404.330988) (xy 152.889907 -404.38329) (xy 152.897665 -404.437245)
			(xy 152.897665 -404.491753) (xy 154.335175 -404.491753) (xy 154.335175 -404.437247) (xy 154.342933 -404.383297)
			(xy 154.358289 -404.331) (xy 154.380932 -404.281421) (xy 154.410401 -404.235569) (xy 154.446096 -404.194377)
			(xy 154.487289 -404.158686) (xy 154.533143 -404.12922) (xy 154.582724 -404.10658) (xy 154.635022 -404.091227)
			(xy 154.688973 -404.083474) (xy 154.716226 -404.083012) (xy 155.579826 -404.083012) (xy 155.607077 -404.08346)
			(xy 155.661025 -404.09122) (xy 155.71332 -404.106578) (xy 155.762896 -404.129222) (xy 155.808746 -404.15869)
			(xy 155.849935 -404.194383) (xy 155.885626 -404.235575) (xy 155.915091 -404.281427) (xy 155.937731 -404.331005)
			(xy 155.953086 -404.3833) (xy 155.960842 -404.437249) (xy 155.960842 -404.491748) (xy 157.398498 -404.491748)
			(xy 157.398498 -404.437252) (xy 157.406253 -404.38331) (xy 157.421606 -404.331021) (xy 157.444243 -404.281448)
			(xy 157.473705 -404.235602) (xy 157.509391 -404.194415) (xy 157.550575 -404.158725) (xy 157.596418 -404.12926)
			(xy 157.645989 -404.106618) (xy 157.698277 -404.091261) (xy 157.752218 -404.083501) (xy 157.779466 -404.083012)
			(xy 158.643066 -404.083012) (xy 158.670322 -404.083433) (xy 158.724279 -404.091186) (xy 158.776584 -404.10654)
			(xy 158.826171 -404.129182) (xy 158.872031 -404.15865) (xy 158.91323 -404.194346) (xy 158.948929 -404.235542)
			(xy 158.978402 -404.281399) (xy 159.001048 -404.330984) (xy 159.016407 -404.383287) (xy 159.024165 -404.437244)
			(xy 159.024165 -404.491752) (xy 160.461675 -404.491752) (xy 160.461675 -404.437248) (xy 160.469432 -404.3833)
			(xy 160.484788 -404.331004) (xy 160.507429 -404.281426) (xy 160.536896 -404.235575) (xy 160.572589 -404.194384)
			(xy 160.61378 -404.158693) (xy 160.659631 -404.129226) (xy 160.70921 -404.106585) (xy 160.761506 -404.091231)
			(xy 160.815454 -404.083475) (xy 160.842706 -404.083012) (xy 161.706306 -404.083012) (xy 161.733558 -404.083458)
			(xy 161.787508 -404.091216) (xy 161.839805 -404.106572) (xy 161.889384 -404.129215) (xy 161.935236 -404.158683)
			(xy 161.976428 -404.194376) (xy 162.012121 -404.235569) (xy 162.041588 -404.281421) (xy 162.06423 -404.331001)
			(xy 162.079585 -404.383298) (xy 162.087342 -404.437248) (xy 162.087342 -404.491752) (xy 162.079585 -404.545702)
			(xy 162.06423 -404.597999) (xy 162.041588 -404.647579) (xy 162.012121 -404.693431) (xy 161.976428 -404.734624)
			(xy 161.935236 -404.770317) (xy 161.904774 -404.789894) (xy 166.998662 -404.789894) (xy 167.002634 -404.611651)
			(xy 167.014542 -404.433762) (xy 167.034363 -404.25658) (xy 167.062057 -404.080456) (xy 167.097569 -403.905741)
			(xy 167.140829 -403.732782) (xy 167.191751 -403.561921) (xy 167.250234 -403.393499) (xy 167.316161 -403.227849)
			(xy 167.389402 -403.0653) (xy 167.469812 -402.906175) (xy 167.55723 -402.75079) (xy 167.651483 -402.599454)
			(xy 167.752384 -402.452466) (xy 167.859733 -402.310119) (xy 167.973316 -402.172696) (xy 168.092909 -402.040469)
			(xy 168.218273 -401.9137) (xy 168.34916 -401.792642) (xy 168.485309 -401.677535) (xy 168.626451 -401.568607)
			(xy 168.772306 -401.466075) (xy 168.922583 -401.370141) (xy 169.076984 -401.280998) (xy 169.235203 -401.198821)
			(xy 169.396926 -401.123773) (xy 169.561831 -401.056005) (xy 169.729592 -400.995649) (xy 169.899875 -400.942827)
			(xy 170.072342 -400.897643) (xy 170.24665 -400.860186) (xy 170.422454 -400.830532) (xy 170.599404 -400.808739)
			(xy 170.77715 -400.794849) (xy 170.955337 -400.788892) (xy 171.133614 -400.790878) (xy 171.311625 -400.800804)
			(xy 171.489017 -400.81865) (xy 171.665437 -400.84438) (xy 171.840537 -400.877944) (xy 172.013968 -400.919274)
			(xy 172.185385 -400.96829) (xy 172.354448 -401.024892) (xy 172.520823 -401.08897) (xy 172.684177 -401.160396)
			(xy 172.844188 -401.239028) (xy 173.000537 -401.324709) (xy 173.152914 -401.417271) (xy 173.301017 -401.516528)
			(xy 173.444551 -401.622285) (xy 173.583231 -401.73433) (xy 173.716782 -401.852442) (xy 173.844939 -401.976386)
			(xy 173.967448 -402.105916) (xy 174.084065 -402.240775) (xy 174.194558 -402.380695) (xy 174.298709 -402.525398)
			(xy 174.396311 -402.674597) (xy 174.487169 -402.827996) (xy 174.571103 -402.98529) (xy 174.647948 -403.146166)
			(xy 174.717549 -403.310307) (xy 174.77977 -403.477384) (xy 174.834486 -403.647068) (xy 174.881588 -403.819021)
			(xy 174.920984 -403.992901) (xy 174.952595 -404.168364) (xy 174.976359 -404.34506) (xy 174.992227 -404.52264)
			(xy 175.000169 -404.70075) (xy 175.000666 -404.789894) (xy 175.000169 -404.879038) (xy 174.992227 -405.057148)
			(xy 174.976359 -405.234728) (xy 174.952595 -405.411424) (xy 174.920984 -405.586887) (xy 174.881588 -405.760767)
			(xy 174.834486 -405.93272) (xy 174.77977 -406.102404) (xy 174.717549 -406.269481) (xy 174.647948 -406.433622)
			(xy 174.571103 -406.594498) (xy 174.487169 -406.751792) (xy 174.396311 -406.905191) (xy 174.298709 -407.05439)
			(xy 174.194558 -407.199093) (xy 174.084065 -407.339013) (xy 173.967448 -407.473872) (xy 173.844939 -407.603402)
			(xy 173.716782 -407.727346) (xy 173.583231 -407.845458) (xy 173.444551 -407.957503) (xy 173.301017 -408.06326)
			(xy 173.152914 -408.162517) (xy 173.000537 -408.255079) (xy 172.844188 -408.34076) (xy 172.684177 -408.419392)
			(xy 172.520823 -408.490818) (xy 172.354448 -408.554896) (xy 172.185385 -408.611498) (xy 172.013968 -408.660514)
			(xy 171.840537 -408.701844) (xy 171.665437 -408.735408) (xy 171.489017 -408.761138) (xy 171.311625 -408.778984)
			(xy 171.133614 -408.78891) (xy 170.955337 -408.790896) (xy 170.77715 -408.784939) (xy 170.599404 -408.771049)
			(xy 170.422454 -408.749256) (xy 170.24665 -408.719602) (xy 170.072342 -408.682145) (xy 169.899875 -408.636961)
			(xy 169.729592 -408.584139) (xy 169.561831 -408.523783) (xy 169.396926 -408.456015) (xy 169.235203 -408.380967)
			(xy 169.076984 -408.29879) (xy 168.922583 -408.209647) (xy 168.772306 -408.113713) (xy 168.626451 -408.011181)
			(xy 168.485309 -407.902253) (xy 168.34916 -407.787146) (xy 168.218273 -407.666088) (xy 168.092909 -407.539319)
			(xy 167.973316 -407.407092) (xy 167.859733 -407.269669) (xy 167.752384 -407.127322) (xy 167.651483 -406.980334)
			(xy 167.55723 -406.828998) (xy 167.469812 -406.673613) (xy 167.389402 -406.514488) (xy 167.316161 -406.351939)
			(xy 167.250234 -406.186289) (xy 167.191751 -406.017867) (xy 167.140829 -405.847006) (xy 167.097569 -405.674047)
			(xy 167.062057 -405.499332) (xy 167.034363 -405.323208) (xy 167.014542 -405.146026) (xy 167.002634 -404.968137)
			(xy 166.998662 -404.789894) (xy 161.904774 -404.789894) (xy 161.889384 -404.799785) (xy 161.839805 -404.822428)
			(xy 161.787508 -404.837784) (xy 161.733558 -404.845542) (xy 161.706306 -404.846028) (xy 160.842706 -404.846028)
			(xy 160.815454 -404.845525) (xy 160.761506 -404.837769) (xy 160.70921 -404.822415) (xy 160.659631 -404.799774)
			(xy 160.61378 -404.770307) (xy 160.572589 -404.734616) (xy 160.536896 -404.693425) (xy 160.507429 -404.647574)
			(xy 160.484788 -404.597996) (xy 160.469432 -404.5457) (xy 160.461675 -404.491752) (xy 159.024165 -404.491752)
			(xy 159.024165 -404.491756) (xy 159.016407 -404.545713) (xy 159.001048 -404.598016) (xy 158.978402 -404.647601)
			(xy 158.948929 -404.693458) (xy 158.91323 -404.734654) (xy 158.872031 -404.77035) (xy 158.826171 -404.799818)
			(xy 158.776584 -404.82246) (xy 158.724279 -404.837814) (xy 158.670322 -404.845567) (xy 158.643066 -404.846028)
			(xy 157.779466 -404.846028) (xy 157.752218 -404.845499) (xy 157.698277 -404.837739) (xy 157.645989 -404.822382)
			(xy 157.596418 -404.79974) (xy 157.550575 -404.770275) (xy 157.509391 -404.734585) (xy 157.473705 -404.693398)
			(xy 157.444243 -404.647552) (xy 157.421606 -404.597979) (xy 157.406253 -404.54569) (xy 157.398498 -404.491748)
			(xy 155.960842 -404.491748) (xy 155.960842 -404.491751) (xy 155.953086 -404.5457) (xy 155.937731 -404.597995)
			(xy 155.915091 -404.647573) (xy 155.885626 -404.693425) (xy 155.849935 -404.734617) (xy 155.808746 -404.77031)
			(xy 155.762896 -404.799778) (xy 155.71332 -404.822422) (xy 155.661025 -404.83778) (xy 155.607077 -404.84554)
			(xy 155.579826 -404.846028) (xy 154.716226 -404.846028) (xy 154.688973 -404.845526) (xy 154.635022 -404.837773)
			(xy 154.582724 -404.82242) (xy 154.533143 -404.79978) (xy 154.487289 -404.770314) (xy 154.446096 -404.734623)
			(xy 154.410401 -404.693431) (xy 154.380932 -404.647579) (xy 154.358289 -404.598) (xy 154.342933 -404.545703)
			(xy 154.335175 -404.491753) (xy 152.897665 -404.491753) (xy 152.897665 -404.491755) (xy 152.889907 -404.54571)
			(xy 152.87455 -404.598012) (xy 152.851905 -404.647595) (xy 152.822434 -404.693452) (xy 152.786737 -404.734647)
			(xy 152.745541 -404.770343) (xy 152.699683 -404.799812) (xy 152.650099 -404.822455) (xy 152.597796 -404.83781)
			(xy 152.543841 -404.845566) (xy 152.516586 -404.846028) (xy 151.652986 -404.846028) (xy 151.625737 -404.845501)
			(xy 151.571794 -404.837743) (xy 151.519503 -404.822388) (xy 151.46993 -404.799747) (xy 151.424084 -404.770282)
			(xy 151.382898 -404.734592) (xy 151.34721 -404.693404) (xy 151.317746 -404.647557) (xy 151.295108 -404.597984)
			(xy 151.279754 -404.545693) (xy 151.271998 -404.491749) (xy 149.834342 -404.491749) (xy 149.834342 -404.491751)
			(xy 149.826587 -404.545697) (xy 149.811233 -404.597991) (xy 149.788594 -404.647568) (xy 149.75913 -404.693418)
			(xy 149.723442 -404.734609) (xy 149.682255 -404.770303) (xy 149.636408 -404.799772) (xy 149.586834 -404.822417)
			(xy 149.534542 -404.837777) (xy 149.480597 -404.845539) (xy 149.453346 -404.846028) (xy 148.589746 -404.846028)
			(xy 148.562492 -404.845528) (xy 148.508539 -404.837777) (xy 148.456239 -404.822425) (xy 148.406655 -404.799787)
			(xy 148.360799 -404.770321) (xy 148.319603 -404.73463) (xy 148.283906 -404.693438) (xy 148.254435 -404.647585)
			(xy 148.231791 -404.598004) (xy 148.216433 -404.545706) (xy 148.208675 -404.491754) (xy 146.771142 -404.491754)
			(xy 146.763385 -404.545702) (xy 146.74803 -404.597999) (xy 146.725388 -404.647579) (xy 146.695921 -404.693431)
			(xy 146.660228 -404.734624) (xy 146.619036 -404.770317) (xy 146.573184 -404.799785) (xy 146.523605 -404.822428)
			(xy 146.471308 -404.837784) (xy 146.417358 -404.845542) (xy 146.390106 -404.846028) (xy 145.526506 -404.846028)
			(xy 145.499254 -404.845525) (xy 145.445306 -404.837769) (xy 145.39301 -404.822415) (xy 145.343431 -404.799774)
			(xy 145.29758 -404.770307) (xy 145.256389 -404.734616) (xy 145.220696 -404.693425) (xy 145.191229 -404.647574)
			(xy 145.168588 -404.597996) (xy 145.153232 -404.5457) (xy 145.145475 -404.491752) (xy 143.707965 -404.491752)
			(xy 143.707965 -404.491756) (xy 143.700207 -404.545713) (xy 143.684848 -404.598016) (xy 143.662202 -404.647601)
			(xy 143.632729 -404.693458) (xy 143.59703 -404.734654) (xy 143.555831 -404.77035) (xy 143.509971 -404.799818)
			(xy 143.460384 -404.82246) (xy 143.408079 -404.837814) (xy 143.354122 -404.845567) (xy 143.326866 -404.846028)
			(xy 142.463266 -404.846028) (xy 142.436018 -404.845499) (xy 142.382077 -404.837739) (xy 142.329789 -404.822382)
			(xy 142.280218 -404.79974) (xy 142.234375 -404.770275) (xy 142.193191 -404.734585) (xy 142.157505 -404.693398)
			(xy 142.128043 -404.647552) (xy 142.105406 -404.597979) (xy 142.090053 -404.54569) (xy 142.082298 -404.491748)
			(xy 140.644642 -404.491748) (xy 140.644642 -404.491751) (xy 140.636886 -404.5457) (xy 140.621531 -404.597995)
			(xy 140.598891 -404.647573) (xy 140.569426 -404.693425) (xy 140.533735 -404.734617) (xy 140.492546 -404.77031)
			(xy 140.446696 -404.799778) (xy 140.39712 -404.822422) (xy 140.344825 -404.83778) (xy 140.290877 -404.84554)
			(xy 140.263626 -404.846028) (xy 139.400026 -404.846028) (xy 139.372773 -404.845526) (xy 139.318822 -404.837773)
			(xy 139.266524 -404.82242) (xy 139.216943 -404.79978) (xy 139.171089 -404.770314) (xy 139.129896 -404.734623)
			(xy 139.094201 -404.693431) (xy 139.064732 -404.647579) (xy 139.042089 -404.598) (xy 139.026733 -404.545703)
			(xy 139.018975 -404.491753) (xy 137.581465 -404.491753) (xy 137.581465 -404.491755) (xy 137.573707 -404.54571)
			(xy 137.55835 -404.598012) (xy 137.535705 -404.647595) (xy 137.506234 -404.693452) (xy 137.470537 -404.734647)
			(xy 137.429341 -404.770343) (xy 137.383483 -404.799812) (xy 137.333899 -404.822455) (xy 137.281596 -404.83781)
			(xy 137.227641 -404.845566) (xy 137.200386 -404.846028) (xy 136.336786 -404.846028) (xy 136.309537 -404.845501)
			(xy 136.255594 -404.837743) (xy 136.203303 -404.822388) (xy 136.15373 -404.799747) (xy 136.107884 -404.770282)
			(xy 136.066698 -404.734592) (xy 136.03101 -404.693404) (xy 136.001546 -404.647557) (xy 135.978908 -404.597984)
			(xy 135.963554 -404.545693) (xy 135.955798 -404.491749) (xy 134.518142 -404.491749) (xy 134.518142 -404.491751)
			(xy 134.510387 -404.545697) (xy 134.495033 -404.597991) (xy 134.472394 -404.647568) (xy 134.44293 -404.693418)
			(xy 134.407242 -404.734609) (xy 134.366055 -404.770303) (xy 134.320208 -404.799772) (xy 134.270634 -404.822417)
			(xy 134.218342 -404.837777) (xy 134.164397 -404.845539) (xy 134.137146 -404.846028) (xy 133.273546 -404.846028)
			(xy 133.246292 -404.845528) (xy 133.192339 -404.837777) (xy 133.140039 -404.822425) (xy 133.090455 -404.799787)
			(xy 133.044599 -404.770321) (xy 133.003403 -404.73463) (xy 132.967706 -404.693438) (xy 132.938235 -404.647585)
			(xy 132.915591 -404.598004) (xy 132.900233 -404.545706) (xy 132.892475 -404.491754) (xy 131.454942 -404.491754)
			(xy 131.447185 -404.545702) (xy 131.43183 -404.597999) (xy 131.409188 -404.647579) (xy 131.379721 -404.693431)
			(xy 131.344028 -404.734624) (xy 131.302836 -404.770317) (xy 131.256984 -404.799785) (xy 131.207405 -404.822428)
			(xy 131.155108 -404.837784) (xy 131.101158 -404.845542) (xy 131.073906 -404.846028) (xy 130.210306 -404.846028)
			(xy 130.183054 -404.845525) (xy 130.129106 -404.837769) (xy 130.07681 -404.822415) (xy 130.027231 -404.799774)
			(xy 129.98138 -404.770307) (xy 129.940189 -404.734616) (xy 129.904496 -404.693425) (xy 129.875029 -404.647574)
			(xy 129.852388 -404.597996) (xy 129.837032 -404.5457) (xy 129.829275 -404.491752) (xy 128.391765 -404.491752)
			(xy 128.391765 -404.491756) (xy 128.384007 -404.545713) (xy 128.368648 -404.598016) (xy 128.346002 -404.647601)
			(xy 128.316529 -404.693458) (xy 128.28083 -404.734654) (xy 128.239631 -404.77035) (xy 128.193771 -404.799818)
			(xy 128.144184 -404.82246) (xy 128.091879 -404.837814) (xy 128.037922 -404.845567) (xy 128.010666 -404.846028)
			(xy 127.147066 -404.846028) (xy 127.119818 -404.845499) (xy 127.065877 -404.837739) (xy 127.013589 -404.822382)
			(xy 126.964018 -404.79974) (xy 126.918175 -404.770275) (xy 126.876991 -404.734585) (xy 126.841305 -404.693398)
			(xy 126.811843 -404.647552) (xy 126.789206 -404.597979) (xy 126.773853 -404.54569) (xy 126.766098 -404.491748)
			(xy 125.328442 -404.491748) (xy 125.328442 -404.491751) (xy 125.320686 -404.5457) (xy 125.305331 -404.597995)
			(xy 125.282691 -404.647573) (xy 125.253226 -404.693425) (xy 125.217535 -404.734617) (xy 125.176346 -404.77031)
			(xy 125.130496 -404.799778) (xy 125.08092 -404.822422) (xy 125.028625 -404.83778) (xy 124.974677 -404.84554)
			(xy 124.947426 -404.846028) (xy 124.083826 -404.846028) (xy 124.056573 -404.845526) (xy 124.002622 -404.837773)
			(xy 123.950324 -404.82242) (xy 123.900743 -404.79978) (xy 123.854889 -404.770314) (xy 123.813696 -404.734623)
			(xy 123.778001 -404.693431) (xy 123.748532 -404.647579) (xy 123.725889 -404.598) (xy 123.710533 -404.545703)
			(xy 123.702775 -404.491753) (xy 122.265265 -404.491753) (xy 122.265265 -404.491755) (xy 122.257507 -404.54571)
			(xy 122.24215 -404.598012) (xy 122.219505 -404.647595) (xy 122.190034 -404.693452) (xy 122.154337 -404.734647)
			(xy 122.113141 -404.770343) (xy 122.067283 -404.799812) (xy 122.017699 -404.822455) (xy 121.965396 -404.83781)
			(xy 121.911441 -404.845566) (xy 121.884186 -404.846028) (xy 121.020586 -404.846028) (xy 120.993337 -404.845501)
			(xy 120.939394 -404.837743) (xy 120.887103 -404.822388) (xy 120.83753 -404.799747) (xy 120.791684 -404.770282)
			(xy 120.750498 -404.734592) (xy 120.71481 -404.693404) (xy 120.685346 -404.647557) (xy 120.662708 -404.597984)
			(xy 120.647354 -404.545693) (xy 120.639598 -404.491749) (xy 119.201942 -404.491749) (xy 119.201942 -404.491751)
			(xy 119.194187 -404.545697) (xy 119.178833 -404.597991) (xy 119.156194 -404.647568) (xy 119.12673 -404.693418)
			(xy 119.091042 -404.734609) (xy 119.049855 -404.770303) (xy 119.004008 -404.799772) (xy 118.954434 -404.822417)
			(xy 118.902142 -404.837777) (xy 118.848197 -404.845539) (xy 118.820946 -404.846028) (xy 117.957346 -404.846028)
			(xy 117.930092 -404.845528) (xy 117.876139 -404.837777) (xy 117.823839 -404.822425) (xy 117.774255 -404.799787)
			(xy 117.728399 -404.770321) (xy 117.687203 -404.73463) (xy 117.651506 -404.693438) (xy 117.622035 -404.647585)
			(xy 117.599391 -404.598004) (xy 117.584033 -404.545706) (xy 117.576275 -404.491754) (xy 116.138742 -404.491754)
			(xy 116.130985 -404.545702) (xy 116.11563 -404.597999) (xy 116.092988 -404.647579) (xy 116.063521 -404.693431)
			(xy 116.027828 -404.734624) (xy 115.986636 -404.770317) (xy 115.940784 -404.799785) (xy 115.891205 -404.822428)
			(xy 115.838908 -404.837784) (xy 115.784958 -404.845542) (xy 115.757706 -404.846028) (xy 114.894106 -404.846028)
			(xy 114.866854 -404.845525) (xy 114.812906 -404.837769) (xy 114.76061 -404.822415) (xy 114.711031 -404.799774)
			(xy 114.66518 -404.770307) (xy 114.623989 -404.734616) (xy 114.588296 -404.693425) (xy 114.558829 -404.647574)
			(xy 114.536188 -404.597996) (xy 114.520832 -404.5457) (xy 114.513075 -404.491752) (xy 94.987465 -404.491752)
			(xy 94.987465 -404.491756) (xy 94.979707 -404.545713) (xy 94.964348 -404.598016) (xy 94.941702 -404.647602)
			(xy 94.912229 -404.693459) (xy 94.876529 -404.734655) (xy 94.83533 -404.77035) (xy 94.78947 -404.799819)
			(xy 94.739883 -404.822461) (xy 94.687578 -404.837814) (xy 94.63362 -404.845568) (xy 94.606364 -404.846028)
			(xy 93.742764 -404.846028) (xy 93.715516 -404.845499) (xy 93.661575 -404.837739) (xy 93.609287 -404.822382)
			(xy 93.559717 -404.79974) (xy 93.513874 -404.770274) (xy 93.47269 -404.734584) (xy 93.437004 -404.693397)
			(xy 93.407543 -404.647551) (xy 93.384906 -404.597979) (xy 93.369553 -404.54569) (xy 93.361798 -404.491748)
			(xy 91.924142 -404.491748) (xy 91.924142 -404.491752) (xy 91.916386 -404.5457) (xy 91.901031 -404.597996)
			(xy 91.878391 -404.647574) (xy 91.848925 -404.693425) (xy 91.813234 -404.734617) (xy 91.772045 -404.770311)
			(xy 91.726195 -404.799779) (xy 91.676618 -404.822423) (xy 91.624324 -404.837781) (xy 91.570376 -404.845541)
			(xy 91.543124 -404.846028) (xy 90.679524 -404.846028) (xy 90.652271 -404.845526) (xy 90.598321 -404.837773)
			(xy 90.546023 -404.822419) (xy 90.496442 -404.799779) (xy 90.450588 -404.770314) (xy 90.409395 -404.734622)
			(xy 90.373701 -404.693431) (xy 90.344232 -404.647579) (xy 90.321589 -404.598) (xy 90.306233 -404.545703)
			(xy 90.298475 -404.491753) (xy 88.860965 -404.491753) (xy 88.860965 -404.491755) (xy 88.853207 -404.54571)
			(xy 88.83785 -404.598012) (xy 88.815205 -404.647596) (xy 88.785734 -404.693452) (xy 88.750036 -404.734648)
			(xy 88.70884 -404.770343) (xy 88.662982 -404.799812) (xy 88.613397 -404.822455) (xy 88.561095 -404.837811)
			(xy 88.507139 -404.845566) (xy 88.479884 -404.846028) (xy 87.616284 -404.846028) (xy 87.589035 -404.845501)
			(xy 87.535092 -404.837743) (xy 87.482802 -404.822387) (xy 87.433229 -404.799746) (xy 87.387383 -404.770281)
			(xy 87.346197 -404.734591) (xy 87.310509 -404.693404) (xy 87.281046 -404.647557) (xy 87.258407 -404.597983)
			(xy 87.243054 -404.545692) (xy 87.235298 -404.491749) (xy 85.797642 -404.491749) (xy 85.797642 -404.491751)
			(xy 85.789887 -404.545697) (xy 85.774533 -404.597991) (xy 85.751894 -404.647568) (xy 85.72243 -404.693419)
			(xy 85.686741 -404.73461) (xy 85.645554 -404.770304) (xy 85.599707 -404.799773) (xy 85.550133 -404.822417)
			(xy 85.49784 -404.837777) (xy 85.443895 -404.845539) (xy 85.416644 -404.846028) (xy 84.553044 -404.846028)
			(xy 84.525791 -404.845528) (xy 84.471838 -404.837776) (xy 84.419537 -404.822425) (xy 84.369954 -404.799786)
			(xy 84.324098 -404.770321) (xy 84.282902 -404.734629) (xy 84.247206 -404.693437) (xy 84.217735 -404.647584)
			(xy 84.195091 -404.598004) (xy 84.179733 -404.545705) (xy 84.171975 -404.491753) (xy 82.734442 -404.491753)
			(xy 82.726685 -404.545703) (xy 82.71133 -404.598) (xy 82.688688 -404.647579) (xy 82.65922 -404.693432)
			(xy 82.623527 -404.734624) (xy 82.582335 -404.770318) (xy 82.536483 -404.799786) (xy 82.486904 -404.822428)
			(xy 82.434607 -404.837785) (xy 82.380656 -404.845542) (xy 82.353404 -404.846028) (xy 81.489804 -404.846028)
			(xy 81.462552 -404.845525) (xy 81.408604 -404.837769) (xy 81.356308 -404.822414) (xy 81.30673 -404.799773)
			(xy 81.260879 -404.770307) (xy 81.219688 -404.734615) (xy 81.183996 -404.693424) (xy 81.154529 -404.647573)
			(xy 81.131887 -404.597995) (xy 81.116532 -404.5457) (xy 81.108775 -404.491752) (xy 79.671265 -404.491752)
			(xy 79.671265 -404.491756) (xy 79.663507 -404.545713) (xy 79.648148 -404.598016) (xy 79.625502 -404.647602)
			(xy 79.596029 -404.693459) (xy 79.560329 -404.734655) (xy 79.51913 -404.77035) (xy 79.47327 -404.799819)
			(xy 79.423683 -404.822461) (xy 79.371378 -404.837814) (xy 79.31742 -404.845568) (xy 79.290164 -404.846028)
			(xy 78.426564 -404.846028) (xy 78.399316 -404.845499) (xy 78.345375 -404.837739) (xy 78.293087 -404.822382)
			(xy 78.243517 -404.79974) (xy 78.197674 -404.770274) (xy 78.15649 -404.734584) (xy 78.120804 -404.693397)
			(xy 78.091343 -404.647551) (xy 78.068706 -404.597979) (xy 78.053353 -404.54569) (xy 78.045598 -404.491748)
			(xy 76.607942 -404.491748) (xy 76.607942 -404.491752) (xy 76.600186 -404.5457) (xy 76.584831 -404.597996)
			(xy 76.562191 -404.647574) (xy 76.532725 -404.693425) (xy 76.497034 -404.734617) (xy 76.455845 -404.770311)
			(xy 76.409995 -404.799779) (xy 76.360418 -404.822423) (xy 76.308124 -404.837781) (xy 76.254176 -404.845541)
			(xy 76.226924 -404.846028) (xy 75.363324 -404.846028) (xy 75.336071 -404.845526) (xy 75.282121 -404.837773)
			(xy 75.229823 -404.822419) (xy 75.180242 -404.799779) (xy 75.134388 -404.770314) (xy 75.093195 -404.734622)
			(xy 75.057501 -404.693431) (xy 75.028032 -404.647579) (xy 75.005389 -404.598) (xy 74.990033 -404.545703)
			(xy 74.982275 -404.491753) (xy 73.544765 -404.491753) (xy 73.544765 -404.491755) (xy 73.537007 -404.54571)
			(xy 73.52165 -404.598012) (xy 73.499005 -404.647596) (xy 73.469534 -404.693452) (xy 73.433836 -404.734648)
			(xy 73.39264 -404.770343) (xy 73.346782 -404.799812) (xy 73.297197 -404.822455) (xy 73.244895 -404.837811)
			(xy 73.190939 -404.845566) (xy 73.163684 -404.846028) (xy 72.300084 -404.846028) (xy 72.272835 -404.845501)
			(xy 72.218892 -404.837743) (xy 72.166602 -404.822387) (xy 72.117029 -404.799746) (xy 72.071183 -404.770281)
			(xy 72.029997 -404.734591) (xy 71.994309 -404.693404) (xy 71.964846 -404.647557) (xy 71.942207 -404.597983)
			(xy 71.926854 -404.545692) (xy 71.919098 -404.491749) (xy 70.481442 -404.491749) (xy 70.481442 -404.491751)
			(xy 70.473687 -404.545697) (xy 70.458333 -404.597991) (xy 70.435694 -404.647568) (xy 70.40623 -404.693419)
			(xy 70.370541 -404.73461) (xy 70.329354 -404.770304) (xy 70.283507 -404.799773) (xy 70.233933 -404.822417)
			(xy 70.18164 -404.837777) (xy 70.127695 -404.845539) (xy 70.100444 -404.846028) (xy 69.236844 -404.846028)
			(xy 69.209591 -404.845528) (xy 69.155638 -404.837776) (xy 69.103337 -404.822425) (xy 69.053754 -404.799786)
			(xy 69.007898 -404.770321) (xy 68.966702 -404.734629) (xy 68.931006 -404.693437) (xy 68.901535 -404.647584)
			(xy 68.878891 -404.598004) (xy 68.863533 -404.545705) (xy 68.855775 -404.491753) (xy 67.418242 -404.491753)
			(xy 67.410485 -404.545703) (xy 67.39513 -404.598) (xy 67.372488 -404.647579) (xy 67.34302 -404.693432)
			(xy 67.307327 -404.734624) (xy 67.266135 -404.770318) (xy 67.220283 -404.799786) (xy 67.170704 -404.822428)
			(xy 67.118407 -404.837785) (xy 67.064456 -404.845542) (xy 67.037204 -404.846028) (xy 66.173604 -404.846028)
			(xy 66.146352 -404.845525) (xy 66.092404 -404.837769) (xy 66.040108 -404.822414) (xy 65.99053 -404.799773)
			(xy 65.944679 -404.770307) (xy 65.903488 -404.734615) (xy 65.867796 -404.693424) (xy 65.838329 -404.647573)
			(xy 65.815687 -404.597995) (xy 65.800332 -404.5457) (xy 65.792575 -404.491752) (xy 64.355065 -404.491752)
			(xy 64.355065 -404.491756) (xy 64.347307 -404.545713) (xy 64.331948 -404.598016) (xy 64.309302 -404.647602)
			(xy 64.279829 -404.693459) (xy 64.244129 -404.734655) (xy 64.20293 -404.77035) (xy 64.15707 -404.799819)
			(xy 64.107483 -404.822461) (xy 64.055178 -404.837814) (xy 64.00122 -404.845568) (xy 63.973964 -404.846028)
			(xy 63.110364 -404.846028) (xy 63.083116 -404.845499) (xy 63.029175 -404.837739) (xy 62.976887 -404.822382)
			(xy 62.927317 -404.79974) (xy 62.881474 -404.770274) (xy 62.84029 -404.734584) (xy 62.804604 -404.693397)
			(xy 62.775143 -404.647551) (xy 62.752506 -404.597979) (xy 62.737153 -404.54569) (xy 62.729398 -404.491748)
			(xy 61.291742 -404.491748) (xy 61.291742 -404.491752) (xy 61.283986 -404.5457) (xy 61.268631 -404.597996)
			(xy 61.245991 -404.647574) (xy 61.216525 -404.693425) (xy 61.180834 -404.734617) (xy 61.139645 -404.770311)
			(xy 61.093795 -404.799779) (xy 61.044218 -404.822423) (xy 60.991924 -404.837781) (xy 60.937976 -404.845541)
			(xy 60.910724 -404.846028) (xy 60.047124 -404.846028) (xy 60.019871 -404.845526) (xy 59.965921 -404.837773)
			(xy 59.913623 -404.822419) (xy 59.864042 -404.799779) (xy 59.818188 -404.770314) (xy 59.776995 -404.734622)
			(xy 59.741301 -404.693431) (xy 59.711832 -404.647579) (xy 59.689189 -404.598) (xy 59.673833 -404.545703)
			(xy 59.666075 -404.491753) (xy 58.228565 -404.491753) (xy 58.228565 -404.491755) (xy 58.220807 -404.54571)
			(xy 58.20545 -404.598012) (xy 58.182805 -404.647596) (xy 58.153334 -404.693452) (xy 58.117636 -404.734648)
			(xy 58.07644 -404.770343) (xy 58.030582 -404.799812) (xy 57.980997 -404.822455) (xy 57.928695 -404.837811)
			(xy 57.874739 -404.845566) (xy 57.847484 -404.846028) (xy 56.983884 -404.846028) (xy 56.956635 -404.845501)
			(xy 56.902692 -404.837743) (xy 56.850402 -404.822387) (xy 56.800829 -404.799746) (xy 56.754983 -404.770281)
			(xy 56.713797 -404.734591) (xy 56.678109 -404.693404) (xy 56.648646 -404.647557) (xy 56.626007 -404.597983)
			(xy 56.610654 -404.545692) (xy 56.602898 -404.491749) (xy 55.165242 -404.491749) (xy 55.165242 -404.491751)
			(xy 55.157487 -404.545697) (xy 55.142133 -404.597991) (xy 55.119494 -404.647568) (xy 55.09003 -404.693419)
			(xy 55.054341 -404.73461) (xy 55.013154 -404.770304) (xy 54.967307 -404.799773) (xy 54.917733 -404.822417)
			(xy 54.86544 -404.837777) (xy 54.811495 -404.845539) (xy 54.784244 -404.846028) (xy 53.920644 -404.846028)
			(xy 53.893391 -404.845528) (xy 53.839438 -404.837776) (xy 53.787137 -404.822425) (xy 53.737554 -404.799786)
			(xy 53.691698 -404.770321) (xy 53.650502 -404.734629) (xy 53.614806 -404.693437) (xy 53.585335 -404.647584)
			(xy 53.562691 -404.598004) (xy 53.547333 -404.545705) (xy 53.539575 -404.491753) (xy 52.102042 -404.491753)
			(xy 52.094285 -404.545703) (xy 52.07893 -404.598) (xy 52.056288 -404.647579) (xy 52.02682 -404.693432)
			(xy 51.991127 -404.734624) (xy 51.949935 -404.770318) (xy 51.904083 -404.799786) (xy 51.854504 -404.822428)
			(xy 51.802207 -404.837785) (xy 51.748256 -404.845542) (xy 51.721004 -404.846028) (xy 50.857404 -404.846028)
			(xy 50.830152 -404.845525) (xy 50.776204 -404.837769) (xy 50.723908 -404.822414) (xy 50.67433 -404.799773)
			(xy 50.628479 -404.770307) (xy 50.587288 -404.734615) (xy 50.551596 -404.693424) (xy 50.522129 -404.647573)
			(xy 50.499487 -404.597995) (xy 50.484132 -404.5457) (xy 50.476375 -404.491752) (xy 49.038865 -404.491752)
			(xy 49.038865 -404.491756) (xy 49.031107 -404.545713) (xy 49.015748 -404.598016) (xy 48.993102 -404.647602)
			(xy 48.963629 -404.693459) (xy 48.927929 -404.734655) (xy 48.88673 -404.77035) (xy 48.84087 -404.799819)
			(xy 48.791283 -404.822461) (xy 48.738978 -404.837814) (xy 48.68502 -404.845568) (xy 48.657764 -404.846028)
			(xy 47.794164 -404.846028) (xy 47.766916 -404.845499) (xy 47.712975 -404.837739) (xy 47.660687 -404.822382)
			(xy 47.611117 -404.79974) (xy 47.565274 -404.770274) (xy 47.52409 -404.734584) (xy 47.488404 -404.693397)
			(xy 47.458943 -404.647551) (xy 47.436306 -404.597979) (xy 47.420953 -404.54569) (xy 47.413198 -404.491748)
			(xy 45.559703 -404.491748) (xy 45.562463 -404.52264) (xy 45.570405 -404.70075) (xy 45.570902 -404.789894)
			(xy 45.570405 -404.879038) (xy 45.562463 -405.057148) (xy 45.546595 -405.234728) (xy 45.522831 -405.411424)
			(xy 45.49122 -405.586887) (xy 45.479552 -405.638385) (xy 104.009796 -405.638385) (xy 104.013672 -405.584006)
			(xy 104.025246 -405.530732) (xy 104.044281 -405.479646) (xy 104.070391 -405.431789) (xy 104.103044 -405.388132)
			(xy 104.121966 -405.368506) (xy 104.732582 -404.757636) (xy 104.75423 -404.736857) (xy 104.802784 -404.701606)
			(xy 104.856253 -404.67438) (xy 104.91332 -404.655848) (xy 104.972583 -404.646465) (xy 105.002584 -404.645876)
			(xy 105.029856 -404.646316) (xy 105.083846 -404.654077) (xy 105.136181 -404.669444) (xy 105.185797 -404.692102)
			(xy 105.231683 -404.721592) (xy 105.272904 -404.757312) (xy 105.308622 -404.798535) (xy 105.338108 -404.844422)
			(xy 105.360764 -404.894039) (xy 105.376127 -404.946376) (xy 105.383885 -405.000366) (xy 105.384346 -405.027638)
			(xy 105.383744 -405.057639) (xy 105.374371 -405.116904) (xy 105.355845 -405.173974) (xy 105.328623 -405.227445)
			(xy 105.29971 -405.267273) (xy 106.824184 -405.267273) (xy 106.824184 -405.212727) (xy 106.831947 -405.158735)
			(xy 106.847315 -405.106398) (xy 106.869976 -405.05678) (xy 106.899467 -405.010893) (xy 106.935189 -404.969671)
			(xy 106.976414 -404.933951) (xy 107.022303 -404.904463) (xy 107.071922 -404.881806) (xy 107.12426 -404.866441)
			(xy 107.178252 -404.858682) (xy 107.205526 -404.85822) (xy 108.069126 -404.85822) (xy 108.096393 -404.858744)
			(xy 108.150371 -404.866508) (xy 108.202695 -404.881875) (xy 108.2523 -404.904532) (xy 108.298175 -404.934017)
			(xy 108.339388 -404.969731) (xy 108.375098 -405.010946) (xy 108.404581 -405.056823) (xy 108.427234 -405.106429)
			(xy 108.442597 -405.158754) (xy 108.450358 -405.212733) (xy 108.450358 -405.267267) (xy 108.442597 -405.321246)
			(xy 108.427234 -405.373571) (xy 108.404581 -405.423177) (xy 108.375098 -405.469054) (xy 108.339388 -405.510269)
			(xy 108.298175 -405.545983) (xy 108.2523 -405.575468) (xy 108.202695 -405.598125) (xy 108.150371 -405.613492)
			(xy 108.096393 -405.621256) (xy 108.069126 -405.621744) (xy 107.205526 -405.621744) (xy 107.178252 -405.621318)
			(xy 107.12426 -405.613559) (xy 107.071922 -405.598194) (xy 107.022303 -405.575537) (xy 106.976414 -405.546049)
			(xy 106.935189 -405.510329) (xy 106.899467 -405.469107) (xy 106.869976 -405.42322) (xy 106.847315 -405.373602)
			(xy 106.831947 -405.321265) (xy 106.824184 -405.267273) (xy 105.29971 -405.267273) (xy 105.293374 -405.276001)
			(xy 105.272586 -405.29764) (xy 104.661716 -405.908256) (xy 104.642167 -405.927256) (xy 104.598511 -405.959909)
			(xy 104.550654 -405.986019) (xy 104.499568 -406.005054) (xy 104.446294 -406.016628) (xy 104.391915 -406.020504)
			(xy 104.337538 -406.016603) (xy 104.284269 -406.005006) (xy 104.233192 -405.985949) (xy 104.185346 -405.959818)
			(xy 104.141704 -405.927145) (xy 104.103155 -405.888596) (xy 104.070482 -405.844954) (xy 104.044351 -405.797108)
			(xy 104.025294 -405.746031) (xy 104.013697 -405.692762) (xy 104.009796 -405.638385) (xy 45.479552 -405.638385)
			(xy 45.451824 -405.760767) (xy 45.404722 -405.93272) (xy 45.350006 -406.102404) (xy 45.287785 -406.269481)
			(xy 45.218184 -406.433622) (xy 45.141339 -406.594498) (xy 45.057405 -406.751792) (xy 44.966547 -406.905191)
			(xy 44.883756 -407.031749) (xy 48.944798 -407.031749) (xy 48.944798 -406.977251) (xy 48.952554 -406.923308)
			(xy 48.967907 -406.871017) (xy 48.990546 -406.821443) (xy 49.020009 -406.775596) (xy 49.055697 -406.734409)
			(xy 49.096883 -406.698719) (xy 49.142729 -406.669254) (xy 49.192302 -406.646613) (xy 49.244592 -406.631257)
			(xy 49.298535 -406.623499) (xy 49.325784 -406.623012) (xy 50.189384 -406.623012) (xy 50.216639 -406.623434)
			(xy 50.270595 -406.631189) (xy 50.322897 -406.646545) (xy 50.372482 -406.669188) (xy 50.41834 -406.698657)
			(xy 50.459536 -406.734352) (xy 50.495234 -406.775548) (xy 50.524705 -406.821404) (xy 50.54735 -406.870988)
			(xy 50.562707 -406.92329) (xy 50.570465 -406.977245) (xy 50.570465 -407.031753) (xy 52.007975 -407.031753)
			(xy 52.007975 -406.977247) (xy 52.015733 -406.923297) (xy 52.031089 -406.871) (xy 52.053732 -406.821421)
			(xy 52.083201 -406.775569) (xy 52.118895 -406.734378) (xy 52.160088 -406.698686) (xy 52.205942 -406.669221)
			(xy 52.255523 -406.646581) (xy 52.307821 -406.631227) (xy 52.361771 -406.623474) (xy 52.389024 -406.623012)
			(xy 53.252624 -406.623012) (xy 53.279876 -406.623459) (xy 53.333824 -406.631219) (xy 53.386118 -406.646577)
			(xy 53.435695 -406.669221) (xy 53.481545 -406.698689) (xy 53.522734 -406.734383) (xy 53.558425 -406.775575)
			(xy 53.587891 -406.821426) (xy 53.610531 -406.871004) (xy 53.625886 -406.9233) (xy 53.633642 -406.977248)
			(xy 53.633642 -407.031748) (xy 55.071298 -407.031748) (xy 55.071298 -406.977252) (xy 55.079053 -406.92331)
			(xy 55.094406 -406.871021) (xy 55.117043 -406.821449) (xy 55.146504 -406.775603) (xy 55.18219 -406.734416)
			(xy 55.223374 -406.698726) (xy 55.269217 -406.66926) (xy 55.318787 -406.646618) (xy 55.371075 -406.631261)
			(xy 55.425016 -406.623501) (xy 55.452264 -406.623012) (xy 56.315864 -406.623012) (xy 56.34312 -406.623432)
			(xy 56.397078 -406.631186) (xy 56.449383 -406.646539) (xy 56.49897 -406.669181) (xy 56.54483 -406.69865)
			(xy 56.586029 -406.734345) (xy 56.621729 -406.775541) (xy 56.651202 -406.821398) (xy 56.673848 -406.870984)
			(xy 56.689207 -406.923287) (xy 56.696965 -406.977244) (xy 56.696965 -407.031752) (xy 58.134475 -407.031752)
			(xy 58.134475 -406.977248) (xy 58.142232 -406.9233) (xy 58.157587 -406.871005) (xy 58.180229 -406.821427)
			(xy 58.209696 -406.775576) (xy 58.245388 -406.734385) (xy 58.286579 -406.698693) (xy 58.33243 -406.669227)
			(xy 58.382008 -406.646586) (xy 58.434304 -406.631231) (xy 58.488252 -406.623475) (xy 58.515504 -406.623012)
			(xy 59.379104 -406.623012) (xy 59.406356 -406.623458) (xy 59.460307 -406.631215) (xy 59.512604 -406.646572)
			(xy 59.562183 -406.669214) (xy 59.608035 -406.698682) (xy 59.649227 -406.734376) (xy 59.68492 -406.775568)
			(xy 59.714388 -406.821421) (xy 59.73703 -406.871) (xy 59.752385 -406.923297) (xy 59.760142 -406.977248)
			(xy 59.760142 -407.031752) (xy 59.760142 -407.031753) (xy 61.197675 -407.031753) (xy 61.197675 -406.977247)
			(xy 61.205433 -406.923295) (xy 61.220791 -406.870996) (xy 61.243435 -406.821416) (xy 61.272906 -406.775563)
			(xy 61.308602 -406.734371) (xy 61.349798 -406.698679) (xy 61.395654 -406.669214) (xy 61.445237 -406.646575)
			(xy 61.497538 -406.631224) (xy 61.551491 -406.623472) (xy 61.578744 -406.623012) (xy 62.442344 -406.623012)
			(xy 62.469595 -406.623461) (xy 62.52354 -406.631223) (xy 62.575833 -406.646583) (xy 62.625407 -406.669227)
			(xy 62.671254 -406.698696) (xy 62.712441 -406.73439) (xy 62.74813 -406.775581) (xy 62.777594 -406.821432)
			(xy 62.800233 -406.871009) (xy 62.815587 -406.923303) (xy 62.823342 -406.977249) (xy 62.823342 -407.031749)
			(xy 64.260998 -407.031749) (xy 64.260998 -406.977251) (xy 64.268754 -406.923308) (xy 64.284107 -406.871017)
			(xy 64.306746 -406.821443) (xy 64.336209 -406.775596) (xy 64.371897 -406.734409) (xy 64.413083 -406.698719)
			(xy 64.458929 -406.669254) (xy 64.508502 -406.646613) (xy 64.560792 -406.631257) (xy 64.614735 -406.623499)
			(xy 64.641984 -406.623012) (xy 65.505584 -406.623012) (xy 65.532839 -406.623434) (xy 65.586795 -406.631189)
			(xy 65.639097 -406.646545) (xy 65.688682 -406.669188) (xy 65.73454 -406.698657) (xy 65.775736 -406.734352)
			(xy 65.811434 -406.775548) (xy 65.840905 -406.821404) (xy 65.86355 -406.870988) (xy 65.878907 -406.92329)
			(xy 65.886665 -406.977245) (xy 65.886665 -407.031753) (xy 67.324175 -407.031753) (xy 67.324175 -406.977247)
			(xy 67.331933 -406.923297) (xy 67.347289 -406.871) (xy 67.369932 -406.821421) (xy 67.399401 -406.775569)
			(xy 67.435095 -406.734378) (xy 67.476288 -406.698686) (xy 67.522142 -406.669221) (xy 67.571723 -406.646581)
			(xy 67.624021 -406.631227) (xy 67.677971 -406.623474) (xy 67.705224 -406.623012) (xy 68.568824 -406.623012)
			(xy 68.596076 -406.623459) (xy 68.650024 -406.631219) (xy 68.702318 -406.646577) (xy 68.751895 -406.669221)
			(xy 68.797745 -406.698689) (xy 68.838934 -406.734383) (xy 68.874625 -406.775575) (xy 68.904091 -406.821426)
			(xy 68.926731 -406.871004) (xy 68.942086 -406.9233) (xy 68.949842 -406.977248) (xy 68.949842 -407.031748)
			(xy 70.387498 -407.031748) (xy 70.387498 -406.977252) (xy 70.395253 -406.92331) (xy 70.410606 -406.871021)
			(xy 70.433243 -406.821449) (xy 70.462704 -406.775603) (xy 70.49839 -406.734416) (xy 70.539574 -406.698726)
			(xy 70.585417 -406.66926) (xy 70.634987 -406.646618) (xy 70.687275 -406.631261) (xy 70.741216 -406.623501)
			(xy 70.768464 -406.623012) (xy 71.632064 -406.623012) (xy 71.65932 -406.623432) (xy 71.713278 -406.631186)
			(xy 71.765583 -406.646539) (xy 71.81517 -406.669181) (xy 71.86103 -406.69865) (xy 71.902229 -406.734345)
			(xy 71.937929 -406.775541) (xy 71.967402 -406.821398) (xy 71.990048 -406.870984) (xy 72.005407 -406.923287)
			(xy 72.013165 -406.977244) (xy 72.013165 -407.031752) (xy 73.450675 -407.031752) (xy 73.450675 -406.977248)
			(xy 73.458432 -406.9233) (xy 73.473787 -406.871005) (xy 73.496429 -406.821427) (xy 73.525896 -406.775576)
			(xy 73.561588 -406.734385) (xy 73.602779 -406.698693) (xy 73.64863 -406.669227) (xy 73.698208 -406.646586)
			(xy 73.750504 -406.631231) (xy 73.804452 -406.623475) (xy 73.831704 -406.623012) (xy 74.695304 -406.623012)
			(xy 74.722556 -406.623458) (xy 74.776507 -406.631215) (xy 74.828804 -406.646572) (xy 74.878383 -406.669214)
			(xy 74.924235 -406.698682) (xy 74.965427 -406.734376) (xy 75.00112 -406.775568) (xy 75.030588 -406.821421)
			(xy 75.05323 -406.871) (xy 75.068585 -406.923297) (xy 75.076342 -406.977248) (xy 75.076342 -407.031752)
			(xy 75.076342 -407.031753) (xy 76.513875 -407.031753) (xy 76.513875 -406.977247) (xy 76.521633 -406.923295)
			(xy 76.536991 -406.870996) (xy 76.559635 -406.821416) (xy 76.589106 -406.775563) (xy 76.624802 -406.734371)
			(xy 76.665998 -406.698679) (xy 76.711854 -406.669214) (xy 76.761437 -406.646575) (xy 76.813738 -406.631224)
			(xy 76.867691 -406.623472) (xy 76.894944 -406.623012) (xy 77.758544 -406.623012) (xy 77.785795 -406.623461)
			(xy 77.83974 -406.631223) (xy 77.892033 -406.646583) (xy 77.941607 -406.669227) (xy 77.987454 -406.698696)
			(xy 78.028641 -406.73439) (xy 78.06433 -406.775581) (xy 78.093794 -406.821432) (xy 78.116433 -406.871009)
			(xy 78.131787 -406.923303) (xy 78.139542 -406.977249) (xy 78.139542 -407.031749) (xy 79.577198 -407.031749)
			(xy 79.577198 -406.977251) (xy 79.584954 -406.923308) (xy 79.600307 -406.871017) (xy 79.622946 -406.821443)
			(xy 79.652409 -406.775596) (xy 79.688097 -406.734409) (xy 79.729283 -406.698719) (xy 79.775129 -406.669254)
			(xy 79.824702 -406.646613) (xy 79.876992 -406.631257) (xy 79.930935 -406.623499) (xy 79.958184 -406.623012)
			(xy 80.821784 -406.623012) (xy 80.849039 -406.623434) (xy 80.902995 -406.631189) (xy 80.955297 -406.646545)
			(xy 81.004882 -406.669188) (xy 81.05074 -406.698657) (xy 81.091936 -406.734352) (xy 81.127634 -406.775548)
			(xy 81.157105 -406.821404) (xy 81.17975 -406.870988) (xy 81.195107 -406.92329) (xy 81.202865 -406.977245)
			(xy 81.202865 -407.031753) (xy 82.640375 -407.031753) (xy 82.640375 -406.977247) (xy 82.648133 -406.923297)
			(xy 82.663489 -406.871) (xy 82.686132 -406.821421) (xy 82.715601 -406.775569) (xy 82.751295 -406.734378)
			(xy 82.792488 -406.698686) (xy 82.838342 -406.669221) (xy 82.887923 -406.646581) (xy 82.940221 -406.631227)
			(xy 82.994171 -406.623474) (xy 83.021424 -406.623012) (xy 83.885024 -406.623012) (xy 83.912276 -406.623459)
			(xy 83.966224 -406.631219) (xy 84.018518 -406.646577) (xy 84.068095 -406.669221) (xy 84.113945 -406.698689)
			(xy 84.155134 -406.734383) (xy 84.190825 -406.775575) (xy 84.220291 -406.821426) (xy 84.242931 -406.871004)
			(xy 84.258286 -406.9233) (xy 84.266042 -406.977248) (xy 84.266042 -407.031748) (xy 85.703698 -407.031748)
			(xy 85.703698 -406.977252) (xy 85.711453 -406.92331) (xy 85.726806 -406.871021) (xy 85.749443 -406.821449)
			(xy 85.778904 -406.775603) (xy 85.81459 -406.734416) (xy 85.855774 -406.698726) (xy 85.901617 -406.66926)
			(xy 85.951187 -406.646618) (xy 86.003475 -406.631261) (xy 86.057416 -406.623501) (xy 86.084664 -406.623012)
			(xy 86.948264 -406.623012) (xy 86.97552 -406.623432) (xy 87.029478 -406.631186) (xy 87.081783 -406.646539)
			(xy 87.13137 -406.669181) (xy 87.17723 -406.69865) (xy 87.218429 -406.734345) (xy 87.254129 -406.775541)
			(xy 87.283602 -406.821398) (xy 87.306248 -406.870984) (xy 87.321607 -406.923287) (xy 87.329365 -406.977244)
			(xy 87.329365 -407.031752) (xy 88.766875 -407.031752) (xy 88.766875 -406.977248) (xy 88.774632 -406.9233)
			(xy 88.789987 -406.871005) (xy 88.812629 -406.821427) (xy 88.842096 -406.775576) (xy 88.877788 -406.734385)
			(xy 88.918979 -406.698693) (xy 88.96483 -406.669227) (xy 89.014408 -406.646586) (xy 89.066704 -406.631231)
			(xy 89.120652 -406.623475) (xy 89.147904 -406.623012) (xy 90.011504 -406.623012) (xy 90.038756 -406.623458)
			(xy 90.092707 -406.631215) (xy 90.145004 -406.646572) (xy 90.194583 -406.669214) (xy 90.240435 -406.698682)
			(xy 90.281627 -406.734376) (xy 90.31732 -406.775568) (xy 90.346788 -406.821421) (xy 90.36943 -406.871)
			(xy 90.384785 -406.923297) (xy 90.392542 -406.977248) (xy 90.392542 -407.031752) (xy 90.392542 -407.031753)
			(xy 91.830075 -407.031753) (xy 91.830075 -406.977247) (xy 91.837833 -406.923295) (xy 91.853191 -406.870996)
			(xy 91.875835 -406.821416) (xy 91.905306 -406.775563) (xy 91.941002 -406.734371) (xy 91.982198 -406.698679)
			(xy 92.028054 -406.669214) (xy 92.077637 -406.646575) (xy 92.129938 -406.631224) (xy 92.183891 -406.623472)
			(xy 92.211144 -406.623012) (xy 93.074744 -406.623012) (xy 93.101995 -406.623461) (xy 93.15594 -406.631223)
			(xy 93.208233 -406.646583) (xy 93.257807 -406.669227) (xy 93.303654 -406.698696) (xy 93.344841 -406.73439)
			(xy 93.38053 -406.775581) (xy 93.409994 -406.821432) (xy 93.432633 -406.871009) (xy 93.447987 -406.923303)
			(xy 93.455742 -406.977249) (xy 93.455742 -407.031749) (xy 94.893398 -407.031749) (xy 94.893398 -406.977251)
			(xy 94.901154 -406.923308) (xy 94.916507 -406.871017) (xy 94.939146 -406.821443) (xy 94.968609 -406.775596)
			(xy 95.004297 -406.734409) (xy 95.045483 -406.698719) (xy 95.091329 -406.669254) (xy 95.140902 -406.646613)
			(xy 95.193192 -406.631257) (xy 95.247135 -406.623499) (xy 95.274384 -406.623012) (xy 96.137984 -406.623012)
			(xy 96.165239 -406.623434) (xy 96.219195 -406.631189) (xy 96.271497 -406.646545) (xy 96.321082 -406.669188)
			(xy 96.36694 -406.698657) (xy 96.408136 -406.734352) (xy 96.443834 -406.775548) (xy 96.473305 -406.821404)
			(xy 96.49595 -406.870988) (xy 96.511307 -406.92329) (xy 96.519065 -406.977245) (xy 96.519065 -407.031753)
			(xy 116.044675 -407.031753) (xy 116.044675 -406.977247) (xy 116.052433 -406.923297) (xy 116.067789 -406.871)
			(xy 116.090432 -406.821421) (xy 116.119901 -406.775569) (xy 116.155596 -406.734377) (xy 116.196789 -406.698686)
			(xy 116.242643 -406.66922) (xy 116.292224 -406.64658) (xy 116.344522 -406.631227) (xy 116.398473 -406.623474)
			(xy 116.425726 -406.623012) (xy 117.289326 -406.623012) (xy 117.316577 -406.62346) (xy 117.370525 -406.63122)
			(xy 117.42282 -406.646578) (xy 117.472396 -406.669222) (xy 117.518246 -406.69869) (xy 117.559435 -406.734383)
			(xy 117.595126 -406.775575) (xy 117.624591 -406.821427) (xy 117.647231 -406.871005) (xy 117.662586 -406.9233)
			(xy 117.670342 -406.977249) (xy 117.670342 -407.031748) (xy 119.107998 -407.031748) (xy 119.107998 -406.977252)
			(xy 119.115753 -406.92331) (xy 119.131106 -406.871021) (xy 119.153743 -406.821448) (xy 119.183205 -406.775602)
			(xy 119.218891 -406.734415) (xy 119.260075 -406.698725) (xy 119.305918 -406.66926) (xy 119.355489 -406.646618)
			(xy 119.407777 -406.631261) (xy 119.461718 -406.623501) (xy 119.488966 -406.623012) (xy 120.352566 -406.623012)
			(xy 120.379822 -406.623433) (xy 120.433779 -406.631186) (xy 120.486084 -406.64654) (xy 120.535671 -406.669182)
			(xy 120.581531 -406.69865) (xy 120.62273 -406.734346) (xy 120.658429 -406.775542) (xy 120.687902 -406.821399)
			(xy 120.710548 -406.870984) (xy 120.725907 -406.923287) (xy 120.733665 -406.977244) (xy 120.733665 -407.031752)
			(xy 122.171175 -407.031752) (xy 122.171175 -406.977248) (xy 122.178932 -406.9233) (xy 122.194288 -406.871004)
			(xy 122.216929 -406.821426) (xy 122.246396 -406.775575) (xy 122.282089 -406.734384) (xy 122.32328 -406.698693)
			(xy 122.369131 -406.669226) (xy 122.41871 -406.646585) (xy 122.471006 -406.631231) (xy 122.524954 -406.623475)
			(xy 122.552206 -406.623012) (xy 123.415806 -406.623012) (xy 123.443058 -406.623458) (xy 123.497008 -406.631216)
			(xy 123.549305 -406.646572) (xy 123.598884 -406.669215) (xy 123.644736 -406.698683) (xy 123.685928 -406.734376)
			(xy 123.721621 -406.775569) (xy 123.751088 -406.821421) (xy 123.77373 -406.871001) (xy 123.789085 -406.923298)
			(xy 123.796842 -406.977248) (xy 123.796842 -407.031752) (xy 123.796842 -407.031754) (xy 125.234375 -407.031754)
			(xy 125.234375 -406.977246) (xy 125.242133 -406.923294) (xy 125.257491 -406.870996) (xy 125.280135 -406.821415)
			(xy 125.309606 -406.775562) (xy 125.345303 -406.73437) (xy 125.386499 -406.698679) (xy 125.432355 -406.669213)
			(xy 125.481939 -406.646575) (xy 125.534239 -406.631223) (xy 125.588192 -406.623472) (xy 125.615446 -406.623012)
			(xy 126.479046 -406.623012) (xy 126.506297 -406.623461) (xy 126.560242 -406.631223) (xy 126.612534 -406.646583)
			(xy 126.662108 -406.669228) (xy 126.707955 -406.698697) (xy 126.749142 -406.734391) (xy 126.78483 -406.775582)
			(xy 126.814294 -406.821432) (xy 126.836933 -406.871009) (xy 126.852287 -406.923303) (xy 126.860042 -406.977249)
			(xy 126.860042 -407.031749) (xy 128.297698 -407.031749) (xy 128.297698 -406.977251) (xy 128.305454 -406.923307)
			(xy 128.320808 -406.871016) (xy 128.343446 -406.821443) (xy 128.37291 -406.775596) (xy 128.408598 -406.734408)
			(xy 128.449784 -406.698718) (xy 128.49563 -406.669253) (xy 128.545203 -406.646612) (xy 128.597494 -406.631257)
			(xy 128.651437 -406.623499) (xy 128.678686 -406.623012) (xy 129.542286 -406.623012) (xy 129.569541 -406.623434)
			(xy 129.623496 -406.63119) (xy 129.675799 -406.646545) (xy 129.725383 -406.669188) (xy 129.771241 -406.698657)
			(xy 129.812437 -406.734353) (xy 129.848134 -406.775548) (xy 129.877605 -406.821405) (xy 129.90025 -406.870988)
			(xy 129.915607 -406.92329) (xy 129.923365 -406.977245) (xy 129.923365 -407.031753) (xy 131.360875 -407.031753)
			(xy 131.360875 -406.977247) (xy 131.368633 -406.923297) (xy 131.383989 -406.871) (xy 131.406632 -406.821421)
			(xy 131.436101 -406.775569) (xy 131.471796 -406.734377) (xy 131.512989 -406.698686) (xy 131.558843 -406.66922)
			(xy 131.608424 -406.64658) (xy 131.660722 -406.631227) (xy 131.714673 -406.623474) (xy 131.741926 -406.623012)
			(xy 132.605526 -406.623012) (xy 132.632777 -406.62346) (xy 132.686725 -406.63122) (xy 132.73902 -406.646578)
			(xy 132.788596 -406.669222) (xy 132.834446 -406.69869) (xy 132.875635 -406.734383) (xy 132.911326 -406.775575)
			(xy 132.940791 -406.821427) (xy 132.963431 -406.871005) (xy 132.978786 -406.9233) (xy 132.986542 -406.977249)
			(xy 132.986542 -407.031748) (xy 134.424198 -407.031748) (xy 134.424198 -406.977252) (xy 134.431953 -406.92331)
			(xy 134.447306 -406.871021) (xy 134.469943 -406.821448) (xy 134.499405 -406.775602) (xy 134.535091 -406.734415)
			(xy 134.576275 -406.698725) (xy 134.622118 -406.66926) (xy 134.671689 -406.646618) (xy 134.723977 -406.631261)
			(xy 134.777918 -406.623501) (xy 134.805166 -406.623012) (xy 135.668766 -406.623012) (xy 135.696022 -406.623433)
			(xy 135.749979 -406.631186) (xy 135.802284 -406.64654) (xy 135.851871 -406.669182) (xy 135.897731 -406.69865)
			(xy 135.93893 -406.734346) (xy 135.974629 -406.775542) (xy 136.004102 -406.821399) (xy 136.026748 -406.870984)
			(xy 136.042107 -406.923287) (xy 136.049865 -406.977244) (xy 136.049865 -407.031752) (xy 137.487375 -407.031752)
			(xy 137.487375 -406.977248) (xy 137.495132 -406.9233) (xy 137.510488 -406.871004) (xy 137.533129 -406.821426)
			(xy 137.562596 -406.775575) (xy 137.598289 -406.734384) (xy 137.63948 -406.698693) (xy 137.685331 -406.669226)
			(xy 137.73491 -406.646585) (xy 137.787206 -406.631231) (xy 137.841154 -406.623475) (xy 137.868406 -406.623012)
			(xy 138.732006 -406.623012) (xy 138.759258 -406.623458) (xy 138.813208 -406.631216) (xy 138.865505 -406.646572)
			(xy 138.915084 -406.669215) (xy 138.960936 -406.698683) (xy 139.002128 -406.734376) (xy 139.037821 -406.775569)
			(xy 139.067288 -406.821421) (xy 139.08993 -406.871001) (xy 139.105285 -406.923298) (xy 139.113042 -406.977248)
			(xy 139.113042 -407.031752) (xy 139.113042 -407.031754) (xy 140.550575 -407.031754) (xy 140.550575 -406.977246)
			(xy 140.558333 -406.923294) (xy 140.573691 -406.870996) (xy 140.596335 -406.821415) (xy 140.625806 -406.775562)
			(xy 140.661503 -406.73437) (xy 140.702699 -406.698679) (xy 140.748555 -406.669213) (xy 140.798139 -406.646575)
			(xy 140.850439 -406.631223) (xy 140.904392 -406.623472) (xy 140.931646 -406.623012) (xy 141.795246 -406.623012)
			(xy 141.822497 -406.623461) (xy 141.876442 -406.631223) (xy 141.928734 -406.646583) (xy 141.978308 -406.669228)
			(xy 142.024155 -406.698697) (xy 142.065342 -406.734391) (xy 142.10103 -406.775582) (xy 142.130494 -406.821432)
			(xy 142.153133 -406.871009) (xy 142.168487 -406.923303) (xy 142.176242 -406.977249) (xy 142.176242 -407.031749)
			(xy 143.613898 -407.031749) (xy 143.613898 -406.977251) (xy 143.621654 -406.923307) (xy 143.637008 -406.871016)
			(xy 143.659646 -406.821443) (xy 143.68911 -406.775596) (xy 143.724798 -406.734408) (xy 143.765984 -406.698718)
			(xy 143.81183 -406.669253) (xy 143.861403 -406.646612) (xy 143.913694 -406.631257) (xy 143.967637 -406.623499)
			(xy 143.994886 -406.623012) (xy 144.858486 -406.623012) (xy 144.885741 -406.623434) (xy 144.939696 -406.63119)
			(xy 144.991999 -406.646545) (xy 145.041583 -406.669188) (xy 145.087441 -406.698657) (xy 145.128637 -406.734353)
			(xy 145.164334 -406.775548) (xy 145.193805 -406.821405) (xy 145.21645 -406.870988) (xy 145.231807 -406.92329)
			(xy 145.239565 -406.977245) (xy 145.239565 -407.031753) (xy 146.677075 -407.031753) (xy 146.677075 -406.977247)
			(xy 146.684833 -406.923297) (xy 146.700189 -406.871) (xy 146.722832 -406.821421) (xy 146.752301 -406.775569)
			(xy 146.787996 -406.734377) (xy 146.829189 -406.698686) (xy 146.875043 -406.66922) (xy 146.924624 -406.64658)
			(xy 146.976922 -406.631227) (xy 147.030873 -406.623474) (xy 147.058126 -406.623012) (xy 147.921726 -406.623012)
			(xy 147.948977 -406.62346) (xy 148.002925 -406.63122) (xy 148.05522 -406.646578) (xy 148.104796 -406.669222)
			(xy 148.150646 -406.69869) (xy 148.191835 -406.734383) (xy 148.227526 -406.775575) (xy 148.256991 -406.821427)
			(xy 148.279631 -406.871005) (xy 148.294986 -406.9233) (xy 148.302742 -406.977249) (xy 148.302742 -407.031748)
			(xy 149.740398 -407.031748) (xy 149.740398 -406.977252) (xy 149.748153 -406.92331) (xy 149.763506 -406.871021)
			(xy 149.786143 -406.821448) (xy 149.815605 -406.775602) (xy 149.851291 -406.734415) (xy 149.892475 -406.698725)
			(xy 149.938318 -406.66926) (xy 149.987889 -406.646618) (xy 150.040177 -406.631261) (xy 150.094118 -406.623501)
			(xy 150.121366 -406.623012) (xy 150.984966 -406.623012) (xy 151.012222 -406.623433) (xy 151.066179 -406.631186)
			(xy 151.118484 -406.64654) (xy 151.168071 -406.669182) (xy 151.213931 -406.69865) (xy 151.25513 -406.734346)
			(xy 151.290829 -406.775542) (xy 151.320302 -406.821399) (xy 151.342948 -406.870984) (xy 151.358307 -406.923287)
			(xy 151.366065 -406.977244) (xy 151.366065 -407.031752) (xy 152.803575 -407.031752) (xy 152.803575 -406.977248)
			(xy 152.811332 -406.9233) (xy 152.826688 -406.871004) (xy 152.849329 -406.821426) (xy 152.878796 -406.775575)
			(xy 152.914489 -406.734384) (xy 152.95568 -406.698693) (xy 153.001531 -406.669226) (xy 153.05111 -406.646585)
			(xy 153.103406 -406.631231) (xy 153.157354 -406.623475) (xy 153.184606 -406.623012) (xy 154.048206 -406.623012)
			(xy 154.075458 -406.623458) (xy 154.129408 -406.631216) (xy 154.181705 -406.646572) (xy 154.231284 -406.669215)
			(xy 154.277136 -406.698683) (xy 154.318328 -406.734376) (xy 154.354021 -406.775569) (xy 154.383488 -406.821421)
			(xy 154.40613 -406.871001) (xy 154.421485 -406.923298) (xy 154.429242 -406.977248) (xy 154.429242 -407.031752)
			(xy 154.429242 -407.031754) (xy 155.866775 -407.031754) (xy 155.866775 -406.977246) (xy 155.874533 -406.923294)
			(xy 155.889891 -406.870996) (xy 155.912535 -406.821415) (xy 155.942006 -406.775562) (xy 155.977703 -406.73437)
			(xy 156.018899 -406.698679) (xy 156.064755 -406.669213) (xy 156.114339 -406.646575) (xy 156.166639 -406.631223)
			(xy 156.220592 -406.623472) (xy 156.247846 -406.623012) (xy 157.111446 -406.623012) (xy 157.138697 -406.623461)
			(xy 157.192642 -406.631223) (xy 157.244934 -406.646583) (xy 157.294508 -406.669228) (xy 157.340355 -406.698697)
			(xy 157.381542 -406.734391) (xy 157.41723 -406.775582) (xy 157.446694 -406.821432) (xy 157.469333 -406.871009)
			(xy 157.484687 -406.923303) (xy 157.492442 -406.977249) (xy 157.492442 -407.031749) (xy 158.930098 -407.031749)
			(xy 158.930098 -406.977251) (xy 158.937854 -406.923307) (xy 158.953208 -406.871016) (xy 158.975846 -406.821443)
			(xy 159.00531 -406.775596) (xy 159.040998 -406.734408) (xy 159.082184 -406.698718) (xy 159.12803 -406.669253)
			(xy 159.177603 -406.646612) (xy 159.229894 -406.631257) (xy 159.283837 -406.623499) (xy 159.311086 -406.623012)
			(xy 160.174686 -406.623012) (xy 160.201941 -406.623434) (xy 160.255896 -406.63119) (xy 160.308199 -406.646545)
			(xy 160.357783 -406.669188) (xy 160.403641 -406.698657) (xy 160.444837 -406.734353) (xy 160.480534 -406.775548)
			(xy 160.510005 -406.821405) (xy 160.53265 -406.870988) (xy 160.548007 -406.92329) (xy 160.555765 -406.977245)
			(xy 160.555765 -407.031753) (xy 161.993275 -407.031753) (xy 161.993275 -406.977247) (xy 162.001033 -406.923297)
			(xy 162.016389 -406.871) (xy 162.039032 -406.821421) (xy 162.068501 -406.775569) (xy 162.104196 -406.734377)
			(xy 162.145389 -406.698686) (xy 162.191243 -406.66922) (xy 162.240824 -406.64658) (xy 162.293122 -406.631227)
			(xy 162.347073 -406.623474) (xy 162.374326 -406.623012) (xy 163.237926 -406.623012) (xy 163.265177 -406.62346)
			(xy 163.319125 -406.63122) (xy 163.37142 -406.646578) (xy 163.420996 -406.669222) (xy 163.466846 -406.69869)
			(xy 163.508035 -406.734383) (xy 163.543726 -406.775575) (xy 163.573191 -406.821427) (xy 163.595831 -406.871005)
			(xy 163.611186 -406.9233) (xy 163.618942 -406.977249) (xy 163.618942 -407.031751) (xy 163.611186 -407.0857)
			(xy 163.595831 -407.137995) (xy 163.573191 -407.187573) (xy 163.543726 -407.233425) (xy 163.508035 -407.274617)
			(xy 163.466846 -407.31031) (xy 163.420996 -407.339778) (xy 163.37142 -407.362422) (xy 163.319125 -407.37778)
			(xy 163.265177 -407.38554) (xy 163.237926 -407.386028) (xy 162.374326 -407.386028) (xy 162.347073 -407.385526)
			(xy 162.293122 -407.377773) (xy 162.240824 -407.36242) (xy 162.191243 -407.33978) (xy 162.145389 -407.310314)
			(xy 162.104196 -407.274623) (xy 162.068501 -407.233431) (xy 162.039032 -407.187579) (xy 162.016389 -407.138)
			(xy 162.001033 -407.085703) (xy 161.993275 -407.031753) (xy 160.555765 -407.031753) (xy 160.555765 -407.031755)
			(xy 160.548007 -407.08571) (xy 160.53265 -407.138012) (xy 160.510005 -407.187595) (xy 160.480534 -407.233452)
			(xy 160.444837 -407.274647) (xy 160.403641 -407.310343) (xy 160.357783 -407.339812) (xy 160.308199 -407.362455)
			(xy 160.255896 -407.37781) (xy 160.201941 -407.385566) (xy 160.174686 -407.386028) (xy 159.311086 -407.386028)
			(xy 159.283837 -407.385501) (xy 159.229894 -407.377743) (xy 159.177603 -407.362388) (xy 159.12803 -407.339747)
			(xy 159.082184 -407.310282) (xy 159.040998 -407.274592) (xy 159.00531 -407.233404) (xy 158.975846 -407.187557)
			(xy 158.953208 -407.137984) (xy 158.937854 -407.085693) (xy 158.930098 -407.031749) (xy 157.492442 -407.031749)
			(xy 157.492442 -407.031751) (xy 157.484687 -407.085697) (xy 157.469333 -407.137991) (xy 157.446694 -407.187568)
			(xy 157.41723 -407.233418) (xy 157.381542 -407.274609) (xy 157.340355 -407.310303) (xy 157.294508 -407.339772)
			(xy 157.244934 -407.362417) (xy 157.192642 -407.377777) (xy 157.138697 -407.385539) (xy 157.111446 -407.386028)
			(xy 156.247846 -407.386028) (xy 156.220592 -407.385528) (xy 156.166639 -407.377777) (xy 156.114339 -407.362425)
			(xy 156.064755 -407.339787) (xy 156.018899 -407.310321) (xy 155.977703 -407.27463) (xy 155.942006 -407.233438)
			(xy 155.912535 -407.187585) (xy 155.889891 -407.138004) (xy 155.874533 -407.085706) (xy 155.866775 -407.031754)
			(xy 154.429242 -407.031754) (xy 154.421485 -407.085702) (xy 154.40613 -407.137999) (xy 154.383488 -407.187579)
			(xy 154.354021 -407.233431) (xy 154.318328 -407.274624) (xy 154.277136 -407.310317) (xy 154.231284 -407.339785)
			(xy 154.181705 -407.362428) (xy 154.129408 -407.377784) (xy 154.075458 -407.385542) (xy 154.048206 -407.386028)
			(xy 153.184606 -407.386028) (xy 153.157354 -407.385525) (xy 153.103406 -407.377769) (xy 153.05111 -407.362415)
			(xy 153.001531 -407.339774) (xy 152.95568 -407.310307) (xy 152.914489 -407.274616) (xy 152.878796 -407.233425)
			(xy 152.849329 -407.187574) (xy 152.826688 -407.137996) (xy 152.811332 -407.0857) (xy 152.803575 -407.031752)
			(xy 151.366065 -407.031752) (xy 151.366065 -407.031756) (xy 151.358307 -407.085713) (xy 151.342948 -407.138016)
			(xy 151.320302 -407.187601) (xy 151.290829 -407.233458) (xy 151.25513 -407.274654) (xy 151.213931 -407.31035)
			(xy 151.168071 -407.339818) (xy 151.118484 -407.36246) (xy 151.066179 -407.377814) (xy 151.012222 -407.385567)
			(xy 150.984966 -407.386028) (xy 150.121366 -407.386028) (xy 150.094118 -407.385499) (xy 150.040177 -407.377739)
			(xy 149.987889 -407.362382) (xy 149.938318 -407.33974) (xy 149.892475 -407.310275) (xy 149.851291 -407.274585)
			(xy 149.815605 -407.233398) (xy 149.786143 -407.187552) (xy 149.763506 -407.137979) (xy 149.748153 -407.08569)
			(xy 149.740398 -407.031748) (xy 148.302742 -407.031748) (xy 148.302742 -407.031751) (xy 148.294986 -407.0857)
			(xy 148.279631 -407.137995) (xy 148.256991 -407.187573) (xy 148.227526 -407.233425) (xy 148.191835 -407.274617)
			(xy 148.150646 -407.31031) (xy 148.104796 -407.339778) (xy 148.05522 -407.362422) (xy 148.002925 -407.37778)
			(xy 147.948977 -407.38554) (xy 147.921726 -407.386028) (xy 147.058126 -407.386028) (xy 147.030873 -407.385526)
			(xy 146.976922 -407.377773) (xy 146.924624 -407.36242) (xy 146.875043 -407.33978) (xy 146.829189 -407.310314)
			(xy 146.787996 -407.274623) (xy 146.752301 -407.233431) (xy 146.722832 -407.187579) (xy 146.700189 -407.138)
			(xy 146.684833 -407.085703) (xy 146.677075 -407.031753) (xy 145.239565 -407.031753) (xy 145.239565 -407.031755)
			(xy 145.231807 -407.08571) (xy 145.21645 -407.138012) (xy 145.193805 -407.187595) (xy 145.164334 -407.233452)
			(xy 145.128637 -407.274647) (xy 145.087441 -407.310343) (xy 145.041583 -407.339812) (xy 144.991999 -407.362455)
			(xy 144.939696 -407.37781) (xy 144.885741 -407.385566) (xy 144.858486 -407.386028) (xy 143.994886 -407.386028)
			(xy 143.967637 -407.385501) (xy 143.913694 -407.377743) (xy 143.861403 -407.362388) (xy 143.81183 -407.339747)
			(xy 143.765984 -407.310282) (xy 143.724798 -407.274592) (xy 143.68911 -407.233404) (xy 143.659646 -407.187557)
			(xy 143.637008 -407.137984) (xy 143.621654 -407.085693) (xy 143.613898 -407.031749) (xy 142.176242 -407.031749)
			(xy 142.176242 -407.031751) (xy 142.168487 -407.085697) (xy 142.153133 -407.137991) (xy 142.130494 -407.187568)
			(xy 142.10103 -407.233418) (xy 142.065342 -407.274609) (xy 142.024155 -407.310303) (xy 141.978308 -407.339772)
			(xy 141.928734 -407.362417) (xy 141.876442 -407.377777) (xy 141.822497 -407.385539) (xy 141.795246 -407.386028)
			(xy 140.931646 -407.386028) (xy 140.904392 -407.385528) (xy 140.850439 -407.377777) (xy 140.798139 -407.362425)
			(xy 140.748555 -407.339787) (xy 140.702699 -407.310321) (xy 140.661503 -407.27463) (xy 140.625806 -407.233438)
			(xy 140.596335 -407.187585) (xy 140.573691 -407.138004) (xy 140.558333 -407.085706) (xy 140.550575 -407.031754)
			(xy 139.113042 -407.031754) (xy 139.105285 -407.085702) (xy 139.08993 -407.137999) (xy 139.067288 -407.187579)
			(xy 139.037821 -407.233431) (xy 139.002128 -407.274624) (xy 138.960936 -407.310317) (xy 138.915084 -407.339785)
			(xy 138.865505 -407.362428) (xy 138.813208 -407.377784) (xy 138.759258 -407.385542) (xy 138.732006 -407.386028)
			(xy 137.868406 -407.386028) (xy 137.841154 -407.385525) (xy 137.787206 -407.377769) (xy 137.73491 -407.362415)
			(xy 137.685331 -407.339774) (xy 137.63948 -407.310307) (xy 137.598289 -407.274616) (xy 137.562596 -407.233425)
			(xy 137.533129 -407.187574) (xy 137.510488 -407.137996) (xy 137.495132 -407.0857) (xy 137.487375 -407.031752)
			(xy 136.049865 -407.031752) (xy 136.049865 -407.031756) (xy 136.042107 -407.085713) (xy 136.026748 -407.138016)
			(xy 136.004102 -407.187601) (xy 135.974629 -407.233458) (xy 135.93893 -407.274654) (xy 135.897731 -407.31035)
			(xy 135.851871 -407.339818) (xy 135.802284 -407.36246) (xy 135.749979 -407.377814) (xy 135.696022 -407.385567)
			(xy 135.668766 -407.386028) (xy 134.805166 -407.386028) (xy 134.777918 -407.385499) (xy 134.723977 -407.377739)
			(xy 134.671689 -407.362382) (xy 134.622118 -407.33974) (xy 134.576275 -407.310275) (xy 134.535091 -407.274585)
			(xy 134.499405 -407.233398) (xy 134.469943 -407.187552) (xy 134.447306 -407.137979) (xy 134.431953 -407.08569)
			(xy 134.424198 -407.031748) (xy 132.986542 -407.031748) (xy 132.986542 -407.031751) (xy 132.978786 -407.0857)
			(xy 132.963431 -407.137995) (xy 132.940791 -407.187573) (xy 132.911326 -407.233425) (xy 132.875635 -407.274617)
			(xy 132.834446 -407.31031) (xy 132.788596 -407.339778) (xy 132.73902 -407.362422) (xy 132.686725 -407.37778)
			(xy 132.632777 -407.38554) (xy 132.605526 -407.386028) (xy 131.741926 -407.386028) (xy 131.714673 -407.385526)
			(xy 131.660722 -407.377773) (xy 131.608424 -407.36242) (xy 131.558843 -407.33978) (xy 131.512989 -407.310314)
			(xy 131.471796 -407.274623) (xy 131.436101 -407.233431) (xy 131.406632 -407.187579) (xy 131.383989 -407.138)
			(xy 131.368633 -407.085703) (xy 131.360875 -407.031753) (xy 129.923365 -407.031753) (xy 129.923365 -407.031755)
			(xy 129.915607 -407.08571) (xy 129.90025 -407.138012) (xy 129.877605 -407.187595) (xy 129.848134 -407.233452)
			(xy 129.812437 -407.274647) (xy 129.771241 -407.310343) (xy 129.725383 -407.339812) (xy 129.675799 -407.362455)
			(xy 129.623496 -407.37781) (xy 129.569541 -407.385566) (xy 129.542286 -407.386028) (xy 128.678686 -407.386028)
			(xy 128.651437 -407.385501) (xy 128.597494 -407.377743) (xy 128.545203 -407.362388) (xy 128.49563 -407.339747)
			(xy 128.449784 -407.310282) (xy 128.408598 -407.274592) (xy 128.37291 -407.233404) (xy 128.343446 -407.187557)
			(xy 128.320808 -407.137984) (xy 128.305454 -407.085693) (xy 128.297698 -407.031749) (xy 126.860042 -407.031749)
			(xy 126.860042 -407.031751) (xy 126.852287 -407.085697) (xy 126.836933 -407.137991) (xy 126.814294 -407.187568)
			(xy 126.78483 -407.233418) (xy 126.749142 -407.274609) (xy 126.707955 -407.310303) (xy 126.662108 -407.339772)
			(xy 126.612534 -407.362417) (xy 126.560242 -407.377777) (xy 126.506297 -407.385539) (xy 126.479046 -407.386028)
			(xy 125.615446 -407.386028) (xy 125.588192 -407.385528) (xy 125.534239 -407.377777) (xy 125.481939 -407.362425)
			(xy 125.432355 -407.339787) (xy 125.386499 -407.310321) (xy 125.345303 -407.27463) (xy 125.309606 -407.233438)
			(xy 125.280135 -407.187585) (xy 125.257491 -407.138004) (xy 125.242133 -407.085706) (xy 125.234375 -407.031754)
			(xy 123.796842 -407.031754) (xy 123.789085 -407.085702) (xy 123.77373 -407.137999) (xy 123.751088 -407.187579)
			(xy 123.721621 -407.233431) (xy 123.685928 -407.274624) (xy 123.644736 -407.310317) (xy 123.598884 -407.339785)
			(xy 123.549305 -407.362428) (xy 123.497008 -407.377784) (xy 123.443058 -407.385542) (xy 123.415806 -407.386028)
			(xy 122.552206 -407.386028) (xy 122.524954 -407.385525) (xy 122.471006 -407.377769) (xy 122.41871 -407.362415)
			(xy 122.369131 -407.339774) (xy 122.32328 -407.310307) (xy 122.282089 -407.274616) (xy 122.246396 -407.233425)
			(xy 122.216929 -407.187574) (xy 122.194288 -407.137996) (xy 122.178932 -407.0857) (xy 122.171175 -407.031752)
			(xy 120.733665 -407.031752) (xy 120.733665 -407.031756) (xy 120.725907 -407.085713) (xy 120.710548 -407.138016)
			(xy 120.687902 -407.187601) (xy 120.658429 -407.233458) (xy 120.62273 -407.274654) (xy 120.581531 -407.31035)
			(xy 120.535671 -407.339818) (xy 120.486084 -407.36246) (xy 120.433779 -407.377814) (xy 120.379822 -407.385567)
			(xy 120.352566 -407.386028) (xy 119.488966 -407.386028) (xy 119.461718 -407.385499) (xy 119.407777 -407.377739)
			(xy 119.355489 -407.362382) (xy 119.305918 -407.33974) (xy 119.260075 -407.310275) (xy 119.218891 -407.274585)
			(xy 119.183205 -407.233398) (xy 119.153743 -407.187552) (xy 119.131106 -407.137979) (xy 119.115753 -407.08569)
			(xy 119.107998 -407.031748) (xy 117.670342 -407.031748) (xy 117.670342 -407.031751) (xy 117.662586 -407.0857)
			(xy 117.647231 -407.137995) (xy 117.624591 -407.187573) (xy 117.595126 -407.233425) (xy 117.559435 -407.274617)
			(xy 117.518246 -407.31031) (xy 117.472396 -407.339778) (xy 117.42282 -407.362422) (xy 117.370525 -407.37778)
			(xy 117.316577 -407.38554) (xy 117.289326 -407.386028) (xy 116.425726 -407.386028) (xy 116.398473 -407.385526)
			(xy 116.344522 -407.377773) (xy 116.292224 -407.36242) (xy 116.242643 -407.33978) (xy 116.196789 -407.310314)
			(xy 116.155596 -407.274623) (xy 116.119901 -407.233431) (xy 116.090432 -407.187579) (xy 116.067789 -407.138)
			(xy 116.052433 -407.085703) (xy 116.044675 -407.031753) (xy 96.519065 -407.031753) (xy 96.519065 -407.031755)
			(xy 96.511307 -407.08571) (xy 96.49595 -407.138012) (xy 96.473305 -407.187596) (xy 96.443834 -407.233452)
			(xy 96.408136 -407.274648) (xy 96.36694 -407.310343) (xy 96.321082 -407.339812) (xy 96.271497 -407.362455)
			(xy 96.219195 -407.377811) (xy 96.165239 -407.385566) (xy 96.137984 -407.386028) (xy 95.274384 -407.386028)
			(xy 95.247135 -407.385501) (xy 95.193192 -407.377743) (xy 95.140902 -407.362387) (xy 95.091329 -407.339746)
			(xy 95.045483 -407.310281) (xy 95.004297 -407.274591) (xy 94.968609 -407.233404) (xy 94.939146 -407.187557)
			(xy 94.916507 -407.137983) (xy 94.901154 -407.085692) (xy 94.893398 -407.031749) (xy 93.455742 -407.031749)
			(xy 93.455742 -407.031751) (xy 93.447987 -407.085697) (xy 93.432633 -407.137991) (xy 93.409994 -407.187568)
			(xy 93.38053 -407.233419) (xy 93.344841 -407.27461) (xy 93.303654 -407.310304) (xy 93.257807 -407.339773)
			(xy 93.208233 -407.362417) (xy 93.15594 -407.377777) (xy 93.101995 -407.385539) (xy 93.074744 -407.386028)
			(xy 92.211144 -407.386028) (xy 92.183891 -407.385528) (xy 92.129938 -407.377776) (xy 92.077637 -407.362425)
			(xy 92.028054 -407.339786) (xy 91.982198 -407.310321) (xy 91.941002 -407.274629) (xy 91.905306 -407.233437)
			(xy 91.875835 -407.187584) (xy 91.853191 -407.138004) (xy 91.837833 -407.085705) (xy 91.830075 -407.031753)
			(xy 90.392542 -407.031753) (xy 90.384785 -407.085703) (xy 90.36943 -407.138) (xy 90.346788 -407.187579)
			(xy 90.31732 -407.233432) (xy 90.281627 -407.274624) (xy 90.240435 -407.310318) (xy 90.194583 -407.339786)
			(xy 90.145004 -407.362428) (xy 90.092707 -407.377785) (xy 90.038756 -407.385542) (xy 90.011504 -407.386028)
			(xy 89.147904 -407.386028) (xy 89.120652 -407.385525) (xy 89.066704 -407.377769) (xy 89.014408 -407.362414)
			(xy 88.96483 -407.339773) (xy 88.918979 -407.310307) (xy 88.877788 -407.274615) (xy 88.842096 -407.233424)
			(xy 88.812629 -407.187573) (xy 88.789987 -407.137995) (xy 88.774632 -407.0857) (xy 88.766875 -407.031752)
			(xy 87.329365 -407.031752) (xy 87.329365 -407.031756) (xy 87.321607 -407.085713) (xy 87.306248 -407.138016)
			(xy 87.283602 -407.187602) (xy 87.254129 -407.233459) (xy 87.218429 -407.274655) (xy 87.17723 -407.31035)
			(xy 87.13137 -407.339819) (xy 87.081783 -407.362461) (xy 87.029478 -407.377814) (xy 86.97552 -407.385568)
			(xy 86.948264 -407.386028) (xy 86.084664 -407.386028) (xy 86.057416 -407.385499) (xy 86.003475 -407.377739)
			(xy 85.951187 -407.362382) (xy 85.901617 -407.33974) (xy 85.855774 -407.310274) (xy 85.81459 -407.274584)
			(xy 85.778904 -407.233397) (xy 85.749443 -407.187551) (xy 85.726806 -407.137979) (xy 85.711453 -407.08569)
			(xy 85.703698 -407.031748) (xy 84.266042 -407.031748) (xy 84.266042 -407.031752) (xy 84.258286 -407.0857)
			(xy 84.242931 -407.137996) (xy 84.220291 -407.187574) (xy 84.190825 -407.233425) (xy 84.155134 -407.274617)
			(xy 84.113945 -407.310311) (xy 84.068095 -407.339779) (xy 84.018518 -407.362423) (xy 83.966224 -407.377781)
			(xy 83.912276 -407.385541) (xy 83.885024 -407.386028) (xy 83.021424 -407.386028) (xy 82.994171 -407.385526)
			(xy 82.940221 -407.377773) (xy 82.887923 -407.362419) (xy 82.838342 -407.339779) (xy 82.792488 -407.310314)
			(xy 82.751295 -407.274622) (xy 82.715601 -407.233431) (xy 82.686132 -407.187579) (xy 82.663489 -407.138)
			(xy 82.648133 -407.085703) (xy 82.640375 -407.031753) (xy 81.202865 -407.031753) (xy 81.202865 -407.031755)
			(xy 81.195107 -407.08571) (xy 81.17975 -407.138012) (xy 81.157105 -407.187596) (xy 81.127634 -407.233452)
			(xy 81.091936 -407.274648) (xy 81.05074 -407.310343) (xy 81.004882 -407.339812) (xy 80.955297 -407.362455)
			(xy 80.902995 -407.377811) (xy 80.849039 -407.385566) (xy 80.821784 -407.386028) (xy 79.958184 -407.386028)
			(xy 79.930935 -407.385501) (xy 79.876992 -407.377743) (xy 79.824702 -407.362387) (xy 79.775129 -407.339746)
			(xy 79.729283 -407.310281) (xy 79.688097 -407.274591) (xy 79.652409 -407.233404) (xy 79.622946 -407.187557)
			(xy 79.600307 -407.137983) (xy 79.584954 -407.085692) (xy 79.577198 -407.031749) (xy 78.139542 -407.031749)
			(xy 78.139542 -407.031751) (xy 78.131787 -407.085697) (xy 78.116433 -407.137991) (xy 78.093794 -407.187568)
			(xy 78.06433 -407.233419) (xy 78.028641 -407.27461) (xy 77.987454 -407.310304) (xy 77.941607 -407.339773)
			(xy 77.892033 -407.362417) (xy 77.83974 -407.377777) (xy 77.785795 -407.385539) (xy 77.758544 -407.386028)
			(xy 76.894944 -407.386028) (xy 76.867691 -407.385528) (xy 76.813738 -407.377776) (xy 76.761437 -407.362425)
			(xy 76.711854 -407.339786) (xy 76.665998 -407.310321) (xy 76.624802 -407.274629) (xy 76.589106 -407.233437)
			(xy 76.559635 -407.187584) (xy 76.536991 -407.138004) (xy 76.521633 -407.085705) (xy 76.513875 -407.031753)
			(xy 75.076342 -407.031753) (xy 75.068585 -407.085703) (xy 75.05323 -407.138) (xy 75.030588 -407.187579)
			(xy 75.00112 -407.233432) (xy 74.965427 -407.274624) (xy 74.924235 -407.310318) (xy 74.878383 -407.339786)
			(xy 74.828804 -407.362428) (xy 74.776507 -407.377785) (xy 74.722556 -407.385542) (xy 74.695304 -407.386028)
			(xy 73.831704 -407.386028) (xy 73.804452 -407.385525) (xy 73.750504 -407.377769) (xy 73.698208 -407.362414)
			(xy 73.64863 -407.339773) (xy 73.602779 -407.310307) (xy 73.561588 -407.274615) (xy 73.525896 -407.233424)
			(xy 73.496429 -407.187573) (xy 73.473787 -407.137995) (xy 73.458432 -407.0857) (xy 73.450675 -407.031752)
			(xy 72.013165 -407.031752) (xy 72.013165 -407.031756) (xy 72.005407 -407.085713) (xy 71.990048 -407.138016)
			(xy 71.967402 -407.187602) (xy 71.937929 -407.233459) (xy 71.902229 -407.274655) (xy 71.86103 -407.31035)
			(xy 71.81517 -407.339819) (xy 71.765583 -407.362461) (xy 71.713278 -407.377814) (xy 71.65932 -407.385568)
			(xy 71.632064 -407.386028) (xy 70.768464 -407.386028) (xy 70.741216 -407.385499) (xy 70.687275 -407.377739)
			(xy 70.634987 -407.362382) (xy 70.585417 -407.33974) (xy 70.539574 -407.310274) (xy 70.49839 -407.274584)
			(xy 70.462704 -407.233397) (xy 70.433243 -407.187551) (xy 70.410606 -407.137979) (xy 70.395253 -407.08569)
			(xy 70.387498 -407.031748) (xy 68.949842 -407.031748) (xy 68.949842 -407.031752) (xy 68.942086 -407.0857)
			(xy 68.926731 -407.137996) (xy 68.904091 -407.187574) (xy 68.874625 -407.233425) (xy 68.838934 -407.274617)
			(xy 68.797745 -407.310311) (xy 68.751895 -407.339779) (xy 68.702318 -407.362423) (xy 68.650024 -407.377781)
			(xy 68.596076 -407.385541) (xy 68.568824 -407.386028) (xy 67.705224 -407.386028) (xy 67.677971 -407.385526)
			(xy 67.624021 -407.377773) (xy 67.571723 -407.362419) (xy 67.522142 -407.339779) (xy 67.476288 -407.310314)
			(xy 67.435095 -407.274622) (xy 67.399401 -407.233431) (xy 67.369932 -407.187579) (xy 67.347289 -407.138)
			(xy 67.331933 -407.085703) (xy 67.324175 -407.031753) (xy 65.886665 -407.031753) (xy 65.886665 -407.031755)
			(xy 65.878907 -407.08571) (xy 65.86355 -407.138012) (xy 65.840905 -407.187596) (xy 65.811434 -407.233452)
			(xy 65.775736 -407.274648) (xy 65.73454 -407.310343) (xy 65.688682 -407.339812) (xy 65.639097 -407.362455)
			(xy 65.586795 -407.377811) (xy 65.532839 -407.385566) (xy 65.505584 -407.386028) (xy 64.641984 -407.386028)
			(xy 64.614735 -407.385501) (xy 64.560792 -407.377743) (xy 64.508502 -407.362387) (xy 64.458929 -407.339746)
			(xy 64.413083 -407.310281) (xy 64.371897 -407.274591) (xy 64.336209 -407.233404) (xy 64.306746 -407.187557)
			(xy 64.284107 -407.137983) (xy 64.268754 -407.085692) (xy 64.260998 -407.031749) (xy 62.823342 -407.031749)
			(xy 62.823342 -407.031751) (xy 62.815587 -407.085697) (xy 62.800233 -407.137991) (xy 62.777594 -407.187568)
			(xy 62.74813 -407.233419) (xy 62.712441 -407.27461) (xy 62.671254 -407.310304) (xy 62.625407 -407.339773)
			(xy 62.575833 -407.362417) (xy 62.52354 -407.377777) (xy 62.469595 -407.385539) (xy 62.442344 -407.386028)
			(xy 61.578744 -407.386028) (xy 61.551491 -407.385528) (xy 61.497538 -407.377776) (xy 61.445237 -407.362425)
			(xy 61.395654 -407.339786) (xy 61.349798 -407.310321) (xy 61.308602 -407.274629) (xy 61.272906 -407.233437)
			(xy 61.243435 -407.187584) (xy 61.220791 -407.138004) (xy 61.205433 -407.085705) (xy 61.197675 -407.031753)
			(xy 59.760142 -407.031753) (xy 59.752385 -407.085703) (xy 59.73703 -407.138) (xy 59.714388 -407.187579)
			(xy 59.68492 -407.233432) (xy 59.649227 -407.274624) (xy 59.608035 -407.310318) (xy 59.562183 -407.339786)
			(xy 59.512604 -407.362428) (xy 59.460307 -407.377785) (xy 59.406356 -407.385542) (xy 59.379104 -407.386028)
			(xy 58.515504 -407.386028) (xy 58.488252 -407.385525) (xy 58.434304 -407.377769) (xy 58.382008 -407.362414)
			(xy 58.33243 -407.339773) (xy 58.286579 -407.310307) (xy 58.245388 -407.274615) (xy 58.209696 -407.233424)
			(xy 58.180229 -407.187573) (xy 58.157587 -407.137995) (xy 58.142232 -407.0857) (xy 58.134475 -407.031752)
			(xy 56.696965 -407.031752) (xy 56.696965 -407.031756) (xy 56.689207 -407.085713) (xy 56.673848 -407.138016)
			(xy 56.651202 -407.187602) (xy 56.621729 -407.233459) (xy 56.586029 -407.274655) (xy 56.54483 -407.31035)
			(xy 56.49897 -407.339819) (xy 56.449383 -407.362461) (xy 56.397078 -407.377814) (xy 56.34312 -407.385568)
			(xy 56.315864 -407.386028) (xy 55.452264 -407.386028) (xy 55.425016 -407.385499) (xy 55.371075 -407.377739)
			(xy 55.318787 -407.362382) (xy 55.269217 -407.33974) (xy 55.223374 -407.310274) (xy 55.18219 -407.274584)
			(xy 55.146504 -407.233397) (xy 55.117043 -407.187551) (xy 55.094406 -407.137979) (xy 55.079053 -407.08569)
			(xy 55.071298 -407.031748) (xy 53.633642 -407.031748) (xy 53.633642 -407.031752) (xy 53.625886 -407.0857)
			(xy 53.610531 -407.137996) (xy 53.587891 -407.187574) (xy 53.558425 -407.233425) (xy 53.522734 -407.274617)
			(xy 53.481545 -407.310311) (xy 53.435695 -407.339779) (xy 53.386118 -407.362423) (xy 53.333824 -407.377781)
			(xy 53.279876 -407.385541) (xy 53.252624 -407.386028) (xy 52.389024 -407.386028) (xy 52.361771 -407.385526)
			(xy 52.307821 -407.377773) (xy 52.255523 -407.362419) (xy 52.205942 -407.339779) (xy 52.160088 -407.310314)
			(xy 52.118895 -407.274622) (xy 52.083201 -407.233431) (xy 52.053732 -407.187579) (xy 52.031089 -407.138)
			(xy 52.015733 -407.085703) (xy 52.007975 -407.031753) (xy 50.570465 -407.031753) (xy 50.570465 -407.031755)
			(xy 50.562707 -407.08571) (xy 50.54735 -407.138012) (xy 50.524705 -407.187596) (xy 50.495234 -407.233452)
			(xy 50.459536 -407.274648) (xy 50.41834 -407.310343) (xy 50.372482 -407.339812) (xy 50.322897 -407.362455)
			(xy 50.270595 -407.377811) (xy 50.216639 -407.385566) (xy 50.189384 -407.386028) (xy 49.325784 -407.386028)
			(xy 49.298535 -407.385501) (xy 49.244592 -407.377743) (xy 49.192302 -407.362387) (xy 49.142729 -407.339746)
			(xy 49.096883 -407.310281) (xy 49.055697 -407.274591) (xy 49.020009 -407.233404) (xy 48.990546 -407.187557)
			(xy 48.967907 -407.137983) (xy 48.952554 -407.085692) (xy 48.944798 -407.031749) (xy 44.883756 -407.031749)
			(xy 44.868945 -407.05439) (xy 44.764794 -407.199093) (xy 44.654301 -407.339013) (xy 44.537684 -407.473872)
			(xy 44.415175 -407.603402) (xy 44.287018 -407.727346) (xy 44.153467 -407.845458) (xy 44.014787 -407.957503)
			(xy 43.871253 -408.06326) (xy 43.72315 -408.162517) (xy 43.570773 -408.255079) (xy 43.414424 -408.34076)
			(xy 43.254413 -408.419392) (xy 43.091059 -408.490818) (xy 42.924684 -408.554896) (xy 42.755621 -408.611498)
			(xy 42.584204 -408.660514) (xy 42.410773 -408.701844) (xy 42.235673 -408.735408) (xy 42.059253 -408.761138)
			(xy 41.881861 -408.778984) (xy 41.70385 -408.78891) (xy 41.525573 -408.790896) (xy 41.347386 -408.784939)
			(xy 41.16964 -408.771049) (xy 40.99269 -408.749256) (xy 40.816886 -408.719602) (xy 40.642578 -408.682145)
			(xy 40.470111 -408.636961) (xy 40.299828 -408.584139) (xy 40.132067 -408.523783) (xy 39.967162 -408.456015)
			(xy 39.805439 -408.380967) (xy 39.64722 -408.29879) (xy 39.492819 -408.209647) (xy 39.342542 -408.113713)
			(xy 39.196687 -408.011181) (xy 39.055545 -407.902253) (xy 38.919396 -407.787146) (xy 38.788509 -407.666088)
			(xy 38.663145 -407.539319) (xy 38.543552 -407.407092) (xy 38.429969 -407.269669) (xy 38.32262 -407.127322)
			(xy 38.221719 -406.980334) (xy 38.127466 -406.828998) (xy 38.040048 -406.673613) (xy 37.959638 -406.514488)
			(xy 37.886397 -406.351939) (xy 37.82047 -406.186289) (xy 37.761987 -406.017867) (xy 37.711065 -405.847006)
			(xy 37.667805 -405.674047) (xy 37.632293 -405.499332) (xy 37.604599 -405.323208) (xy 37.584778 -405.146026)
			(xy 37.57287 -404.968137) (xy 37.568898 -404.789894) (xy 3.30962 -404.789894) (xy 6.274054 -407.754328)
			(xy 6.323479 -407.804444) (xy 6.417291 -407.909404) (xy 6.50507 -408.019459) (xy 6.58654 -408.134261)
			(xy 6.661445 -408.253452) (xy 6.72955 -408.376654) (xy 6.79064 -408.503481) (xy 6.844523 -408.633534)
			(xy 6.891029 -408.766403) (xy 6.918074 -408.860244) (xy 49.107852 -408.860244) (xy 49.107852 -408.174444)
			(xy 49.108396 -408.162401) (xy 49.115811 -408.139485) (xy 49.129932 -408.119972) (xy 49.149382 -408.105766)
			(xy 49.172265 -408.09825) (xy 49.184306 -408.097736) (xy 49.379378 -408.097736) (xy 49.390484 -408.098103)
			(xy 49.411776 -408.104436) (xy 49.421288 -408.110182) (xy 49.714912 -408.302714) (xy 49.724279 -408.308447)
			(xy 49.7453 -408.314775) (xy 49.767252 -408.314841) (xy 49.78831 -408.308637) (xy 49.797716 -408.302968)
			(xy 50.09388 -408.110182) (xy 50.103386 -408.104426) (xy 50.124683 -408.098106) (xy 50.13579 -408.097736)
			(xy 50.330354 -408.097736) (xy 50.342441 -408.098246) (xy 50.365439 -408.10569) (xy 50.38502 -408.119865)
			(xy 50.399272 -408.13939) (xy 50.406806 -408.162359) (xy 50.407316 -408.174444) (xy 50.407316 -408.860244)
			(xy 52.171092 -408.860244) (xy 52.171092 -408.174444) (xy 52.171597 -408.162397) (xy 52.179017 -408.139474)
			(xy 52.193146 -408.119958) (xy 52.212607 -408.105753) (xy 52.235501 -408.098244) (xy 52.247546 -408.097736)
			(xy 52.442618 -408.097736) (xy 52.453722 -408.098127) (xy 52.475014 -408.104444) (xy 52.484528 -408.110182)
			(xy 52.778152 -408.302714) (xy 52.7875 -408.308481) (xy 52.80853 -408.314802) (xy 52.830489 -408.314858)
			(xy 52.85155 -408.308643) (xy 52.860956 -408.302968) (xy 53.15712 -408.110182) (xy 53.166638 -408.104449)
			(xy 53.187926 -408.098114) (xy 53.19903 -408.097736) (xy 53.393594 -408.097736) (xy 53.405683 -408.098213)
			(xy 53.428683 -408.105667) (xy 53.448262 -408.119851) (xy 53.462513 -408.139383) (xy 53.470046 -408.162357)
			(xy 53.470556 -408.174444) (xy 53.470556 -408.860244) (xy 55.234332 -408.860244) (xy 55.234332 -408.174444)
			(xy 55.234798 -408.162393) (xy 55.242222 -408.139463) (xy 55.25636 -408.119944) (xy 55.275832 -408.10574)
			(xy 55.298737 -408.098239) (xy 55.310786 -408.097736) (xy 55.505858 -408.097736) (xy 55.516963 -408.098111)
			(xy 55.538255 -408.104439) (xy 55.547768 -408.110182) (xy 55.841392 -408.302714) (xy 55.850769 -408.30843)
			(xy 55.871785 -408.314762) (xy 55.893734 -408.314832) (xy 55.91479 -408.308634) (xy 55.924196 -408.302968)
			(xy 56.22036 -408.110182) (xy 56.22987 -408.104434) (xy 56.251164 -408.098108) (xy 56.26227 -408.097736)
			(xy 56.456834 -408.097736) (xy 56.468925 -408.098178) (xy 56.491926 -408.105644) (xy 56.511505 -408.119837)
			(xy 56.525755 -408.139375) (xy 56.533286 -408.162354) (xy 56.533796 -408.174444) (xy 56.533796 -408.860244)
			(xy 58.297572 -408.860244) (xy 58.297572 -408.174444) (xy 58.298097 -408.162399) (xy 58.305514 -408.139479)
			(xy 58.319639 -408.119965) (xy 58.339094 -408.105759) (xy 58.361983 -408.098247) (xy 58.374026 -408.097736)
			(xy 58.569098 -408.097736) (xy 58.580201 -408.098136) (xy 58.601493 -408.104447) (xy 58.611008 -408.110182)
			(xy 58.904632 -408.302714) (xy 58.91399 -408.308464) (xy 58.935015 -408.314789) (xy 58.95697 -408.314849)
			(xy 58.97803 -408.30864) (xy 58.987436 -408.302968) (xy 59.2836 -408.110182) (xy 59.293103 -408.104419)
			(xy 59.314402 -408.098103) (xy 59.32551 -408.097736) (xy 59.520074 -408.097736) (xy 59.532162 -408.098229)
			(xy 59.555161 -408.105679) (xy 59.574741 -408.119858) (xy 59.588992 -408.139386) (xy 59.596526 -408.162358)
			(xy 59.597036 -408.174444) (xy 59.597036 -408.860244) (xy 61.360812 -408.860244) (xy 61.360812 -408.174444)
			(xy 61.361298 -408.162395) (xy 61.36872 -408.139469) (xy 61.382853 -408.119951) (xy 61.40232 -408.105747)
			(xy 61.425219 -408.098242) (xy 61.437266 -408.097736) (xy 61.632338 -408.097736) (xy 61.643443 -408.098119)
			(xy 61.664735 -408.104441) (xy 61.674248 -408.110182) (xy 61.967872 -408.302714) (xy 61.977258 -408.308413)
			(xy 61.99827 -408.314749) (xy 62.020216 -408.314824) (xy 62.04127 -408.308632) (xy 62.050676 -408.302968)
			(xy 62.34684 -408.110182) (xy 62.356354 -408.104441) (xy 62.377645 -408.098111) (xy 62.38875 -408.097736)
			(xy 62.583314 -408.097736) (xy 62.595404 -408.098195) (xy 62.618404 -408.105655) (xy 62.637984 -408.119844)
			(xy 62.652234 -408.139379) (xy 62.659766 -408.162356) (xy 62.660276 -408.174444) (xy 62.660276 -408.860244)
			(xy 64.424052 -408.860244) (xy 64.424052 -408.174444) (xy 64.424596 -408.162401) (xy 64.432011 -408.139485)
			(xy 64.446132 -408.119972) (xy 64.465582 -408.105766) (xy 64.488465 -408.09825) (xy 64.500506 -408.097736)
			(xy 64.695578 -408.097736) (xy 64.706684 -408.098103) (xy 64.727976 -408.104436) (xy 64.737488 -408.110182)
			(xy 65.031112 -408.302714) (xy 65.040479 -408.308447) (xy 65.0615 -408.314775) (xy 65.083452 -408.314841)
			(xy 65.10451 -408.308637) (xy 65.113916 -408.302968) (xy 65.41008 -408.110182) (xy 65.419586 -408.104426)
			(xy 65.440883 -408.098106) (xy 65.45199 -408.097736) (xy 65.646554 -408.097736) (xy 65.658641 -408.098246)
			(xy 65.681639 -408.10569) (xy 65.70122 -408.119865) (xy 65.715472 -408.13939) (xy 65.723006 -408.162359)
			(xy 65.723516 -408.174444) (xy 65.723516 -408.860244) (xy 67.487292 -408.860244) (xy 67.487292 -408.174444)
			(xy 67.487797 -408.162397) (xy 67.495217 -408.139474) (xy 67.509346 -408.119958) (xy 67.528807 -408.105753)
			(xy 67.551701 -408.098244) (xy 67.563746 -408.097736) (xy 67.758818 -408.097736) (xy 67.769922 -408.098127)
			(xy 67.791214 -408.104444) (xy 67.800728 -408.110182) (xy 68.094352 -408.302714) (xy 68.1037 -408.308481)
			(xy 68.12473 -408.314802) (xy 68.146689 -408.314858) (xy 68.16775 -408.308643) (xy 68.177156 -408.302968)
			(xy 68.47332 -408.110182) (xy 68.482838 -408.104449) (xy 68.504126 -408.098114) (xy 68.51523 -408.097736)
			(xy 68.709794 -408.097736) (xy 68.721883 -408.098213) (xy 68.744883 -408.105667) (xy 68.764462 -408.119851)
			(xy 68.778713 -408.139383) (xy 68.786246 -408.162357) (xy 68.786756 -408.174444) (xy 68.786756 -408.860244)
			(xy 70.550532 -408.860244) (xy 70.550532 -408.174444) (xy 70.550998 -408.162393) (xy 70.558422 -408.139463)
			(xy 70.57256 -408.119944) (xy 70.592032 -408.10574) (xy 70.614937 -408.098239) (xy 70.626986 -408.097736)
			(xy 70.822058 -408.097736) (xy 70.833163 -408.098111) (xy 70.854455 -408.104439) (xy 70.863968 -408.110182)
			(xy 71.157592 -408.302714) (xy 71.166969 -408.30843) (xy 71.187985 -408.314762) (xy 71.209934 -408.314832)
			(xy 71.23099 -408.308634) (xy 71.240396 -408.302968) (xy 71.53656 -408.110182) (xy 71.54607 -408.104434)
			(xy 71.567364 -408.098108) (xy 71.57847 -408.097736) (xy 71.773034 -408.097736) (xy 71.785125 -408.098178)
			(xy 71.808126 -408.105644) (xy 71.827705 -408.119837) (xy 71.841955 -408.139375) (xy 71.849486 -408.162354)
			(xy 71.849996 -408.174444) (xy 71.849996 -408.860244) (xy 73.613772 -408.860244) (xy 73.613772 -408.174444)
			(xy 73.614297 -408.162399) (xy 73.621714 -408.139479) (xy 73.635839 -408.119965) (xy 73.655294 -408.105759)
			(xy 73.678183 -408.098247) (xy 73.690226 -408.097736) (xy 73.885298 -408.097736) (xy 73.896401 -408.098136)
			(xy 73.917693 -408.104447) (xy 73.927208 -408.110182) (xy 74.220832 -408.302714) (xy 74.23019 -408.308464)
			(xy 74.251215 -408.314789) (xy 74.27317 -408.314849) (xy 74.29423 -408.30864) (xy 74.303636 -408.302968)
			(xy 74.5998 -408.110182) (xy 74.609303 -408.104419) (xy 74.630602 -408.098103) (xy 74.64171 -408.097736)
			(xy 74.836274 -408.097736) (xy 74.848362 -408.098229) (xy 74.871361 -408.105679) (xy 74.890941 -408.119858)
			(xy 74.905192 -408.139386) (xy 74.912726 -408.162358) (xy 74.913236 -408.174444) (xy 74.913236 -408.860244)
			(xy 76.677012 -408.860244) (xy 76.677012 -408.174444) (xy 76.677498 -408.162395) (xy 76.68492 -408.139469)
			(xy 76.699053 -408.119951) (xy 76.71852 -408.105747) (xy 76.741419 -408.098242) (xy 76.753466 -408.097736)
			(xy 76.948538 -408.097736) (xy 76.959643 -408.098119) (xy 76.980935 -408.104441) (xy 76.990448 -408.110182)
			(xy 77.284072 -408.302714) (xy 77.293458 -408.308413) (xy 77.31447 -408.314749) (xy 77.336416 -408.314824)
			(xy 77.35747 -408.308632) (xy 77.366876 -408.302968) (xy 77.66304 -408.110182) (xy 77.672554 -408.104441)
			(xy 77.693845 -408.098111) (xy 77.70495 -408.097736) (xy 77.899514 -408.097736) (xy 77.911604 -408.098195)
			(xy 77.934604 -408.105655) (xy 77.954184 -408.119844) (xy 77.968434 -408.139379) (xy 77.975966 -408.162356)
			(xy 77.976476 -408.174444) (xy 77.976476 -408.860244) (xy 79.740252 -408.860244) (xy 79.740252 -408.174444)
			(xy 79.740796 -408.162401) (xy 79.748211 -408.139485) (xy 79.762332 -408.119972) (xy 79.781782 -408.105766)
			(xy 79.804665 -408.09825) (xy 79.816706 -408.097736) (xy 80.011778 -408.097736) (xy 80.022884 -408.098103)
			(xy 80.044176 -408.104436) (xy 80.053688 -408.110182) (xy 80.347312 -408.302714) (xy 80.356679 -408.308447)
			(xy 80.3777 -408.314775) (xy 80.399652 -408.314841) (xy 80.42071 -408.308637) (xy 80.430116 -408.302968)
			(xy 80.72628 -408.110182) (xy 80.735786 -408.104426) (xy 80.757083 -408.098106) (xy 80.76819 -408.097736)
			(xy 80.962754 -408.097736) (xy 80.974841 -408.098246) (xy 80.997839 -408.10569) (xy 81.01742 -408.119865)
			(xy 81.031672 -408.13939) (xy 81.039206 -408.162359) (xy 81.039716 -408.174444) (xy 81.039716 -408.860244)
			(xy 82.803492 -408.860244) (xy 82.803492 -408.174444) (xy 82.803997 -408.162397) (xy 82.811417 -408.139474)
			(xy 82.825546 -408.119958) (xy 82.845007 -408.105753) (xy 82.867901 -408.098244) (xy 82.879946 -408.097736)
			(xy 83.075018 -408.097736) (xy 83.086122 -408.098127) (xy 83.107414 -408.104444) (xy 83.116928 -408.110182)
			(xy 83.410552 -408.302714) (xy 83.4199 -408.308481) (xy 83.44093 -408.314802) (xy 83.462889 -408.314858)
			(xy 83.48395 -408.308643) (xy 83.493356 -408.302968) (xy 83.78952 -408.110182) (xy 83.799038 -408.104449)
			(xy 83.820326 -408.098114) (xy 83.83143 -408.097736) (xy 84.025994 -408.097736) (xy 84.038083 -408.098213)
			(xy 84.061083 -408.105667) (xy 84.080662 -408.119851) (xy 84.094913 -408.139383) (xy 84.102446 -408.162357)
			(xy 84.102956 -408.174444) (xy 84.102956 -408.860244) (xy 85.866732 -408.860244) (xy 85.866732 -408.174444)
			(xy 85.867198 -408.162393) (xy 85.874622 -408.139463) (xy 85.88876 -408.119944) (xy 85.908232 -408.10574)
			(xy 85.931137 -408.098239) (xy 85.943186 -408.097736) (xy 86.138258 -408.097736) (xy 86.149363 -408.098111)
			(xy 86.170655 -408.104439) (xy 86.180168 -408.110182) (xy 86.473792 -408.302714) (xy 86.483169 -408.30843)
			(xy 86.504185 -408.314762) (xy 86.526134 -408.314832) (xy 86.54719 -408.308634) (xy 86.556596 -408.302968)
			(xy 86.85276 -408.110182) (xy 86.86227 -408.104434) (xy 86.883564 -408.098108) (xy 86.89467 -408.097736)
			(xy 87.089234 -408.097736) (xy 87.101325 -408.098178) (xy 87.124326 -408.105644) (xy 87.143905 -408.119837)
			(xy 87.158155 -408.139375) (xy 87.165686 -408.162354) (xy 87.166196 -408.174444) (xy 87.166196 -408.860244)
			(xy 88.929972 -408.860244) (xy 88.929972 -408.174444) (xy 88.930497 -408.162399) (xy 88.937914 -408.139479)
			(xy 88.952039 -408.119965) (xy 88.971494 -408.105759) (xy 88.994383 -408.098247) (xy 89.006426 -408.097736)
			(xy 89.201498 -408.097736) (xy 89.212601 -408.098136) (xy 89.233893 -408.104447) (xy 89.243408 -408.110182)
			(xy 89.537032 -408.302714) (xy 89.54639 -408.308464) (xy 89.567415 -408.314789) (xy 89.58937 -408.314849)
			(xy 89.61043 -408.30864) (xy 89.619836 -408.302968) (xy 89.916 -408.110182) (xy 89.925503 -408.104419)
			(xy 89.946802 -408.098103) (xy 89.95791 -408.097736) (xy 90.152474 -408.097736) (xy 90.164562 -408.098229)
			(xy 90.187561 -408.105679) (xy 90.207141 -408.119858) (xy 90.221392 -408.139386) (xy 90.228926 -408.162358)
			(xy 90.229436 -408.174444) (xy 90.229436 -408.860244) (xy 91.993212 -408.860244) (xy 91.993212 -408.174444)
			(xy 91.993698 -408.162395) (xy 92.00112 -408.139469) (xy 92.015253 -408.119951) (xy 92.03472 -408.105747)
			(xy 92.057619 -408.098242) (xy 92.069666 -408.097736) (xy 92.264738 -408.097736) (xy 92.275843 -408.098119)
			(xy 92.297135 -408.104441) (xy 92.306648 -408.110182) (xy 92.600272 -408.302714) (xy 92.609658 -408.308413)
			(xy 92.63067 -408.314749) (xy 92.652616 -408.314824) (xy 92.67367 -408.308632) (xy 92.683076 -408.302968)
			(xy 92.97924 -408.110182) (xy 92.988754 -408.104441) (xy 93.010045 -408.098111) (xy 93.02115 -408.097736)
			(xy 93.215714 -408.097736) (xy 93.227804 -408.098195) (xy 93.250804 -408.105655) (xy 93.270384 -408.119844)
			(xy 93.284634 -408.139379) (xy 93.292166 -408.162356) (xy 93.292676 -408.174444) (xy 93.292676 -408.860244)
			(xy 95.056452 -408.860244) (xy 95.056452 -408.174444) (xy 95.056996 -408.162401) (xy 95.064411 -408.139485)
			(xy 95.078532 -408.119972) (xy 95.097982 -408.105766) (xy 95.120865 -408.09825) (xy 95.132906 -408.097736)
			(xy 95.327978 -408.097736) (xy 95.339084 -408.098103) (xy 95.360376 -408.104436) (xy 95.369888 -408.110182)
			(xy 95.663512 -408.302714) (xy 95.672879 -408.308447) (xy 95.6939 -408.314775) (xy 95.715852 -408.314841)
			(xy 95.73691 -408.308637) (xy 95.746316 -408.302968) (xy 96.04248 -408.110182) (xy 96.051986 -408.104426)
			(xy 96.073283 -408.098106) (xy 96.08439 -408.097736) (xy 96.278954 -408.097736) (xy 96.291041 -408.098246)
			(xy 96.314039 -408.10569) (xy 96.33362 -408.119865) (xy 96.347872 -408.13939) (xy 96.355406 -408.162359)
			(xy 96.355916 -408.174444) (xy 96.355916 -408.860244) (xy 96.355478 -408.872295) (xy 96.348035 -408.895219)
			(xy 96.333888 -408.914733) (xy 96.314415 -408.928935) (xy 96.291512 -408.936443) (xy 96.279462 -408.936952)
			(xy 96.08439 -408.936952) (xy 96.073283 -408.936581) (xy 96.051986 -408.930262) (xy 96.04248 -408.924506)
			(xy 95.747586 -408.731974) (xy 95.738199 -408.726271) (xy 95.717161 -408.719998) (xy 95.695207 -408.719998)
			(xy 95.674169 -408.726271) (xy 95.664782 -408.731974) (xy 95.371158 -408.924506) (xy 95.361643 -408.930247)
			(xy 95.340353 -408.936577) (xy 95.329248 -408.936952) (xy 95.133414 -408.936952) (xy 95.121324 -408.93648)
			(xy 95.098323 -408.929027) (xy 95.078742 -408.914841) (xy 95.064491 -408.895308) (xy 95.05696 -408.872332)
			(xy 95.056452 -408.860244) (xy 93.292676 -408.860244) (xy 93.292277 -408.872299) (xy 93.284829 -408.89523)
			(xy 93.270674 -408.914747) (xy 93.251189 -408.928948) (xy 93.228276 -408.936449) (xy 93.216222 -408.936952)
			(xy 93.02115 -408.936952) (xy 93.010041 -408.936597) (xy 92.988745 -408.930267) (xy 92.97924 -408.924506)
			(xy 92.684346 -408.731974) (xy 92.674959 -408.726271) (xy 92.653921 -408.719998) (xy 92.631967 -408.719998)
			(xy 92.610929 -408.726271) (xy 92.601542 -408.731974) (xy 92.307918 -408.924506) (xy 92.298411 -408.930261)
			(xy 92.277115 -408.936583) (xy 92.266008 -408.936952) (xy 92.070174 -408.936952) (xy 92.058082 -408.936515)
			(xy 92.035079 -408.92905) (xy 92.015499 -408.914856) (xy 92.00125 -408.895316) (xy 91.99372 -408.872334)
			(xy 91.993212 -408.860244) (xy 90.229436 -408.860244) (xy 90.228978 -408.872293) (xy 90.221538 -408.895214)
			(xy 90.207395 -408.914726) (xy 90.187927 -408.928929) (xy 90.165029 -408.936441) (xy 90.152982 -408.936952)
			(xy 89.95791 -408.936952) (xy 89.946803 -408.936572) (xy 89.925507 -408.930259) (xy 89.916 -408.924506)
			(xy 89.621106 -408.731974) (xy 89.611719 -408.726271) (xy 89.590681 -408.719998) (xy 89.568727 -408.719998)
			(xy 89.547689 -408.726271) (xy 89.538302 -408.731974) (xy 89.244678 -408.924506) (xy 89.235159 -408.930239)
			(xy 89.213872 -408.936574) (xy 89.202768 -408.936952) (xy 89.006934 -408.936952) (xy 88.994845 -408.936464)
			(xy 88.971845 -408.929015) (xy 88.952263 -408.914834) (xy 88.938012 -408.895305) (xy 88.930481 -408.872331)
			(xy 88.929972 -408.860244) (xy 87.166196 -408.860244) (xy 87.165778 -408.872297) (xy 87.158332 -408.895225)
			(xy 87.144181 -408.91474) (xy 87.124702 -408.928942) (xy 87.101794 -408.936446) (xy 87.089742 -408.936952)
			(xy 86.89467 -408.936952) (xy 86.883562 -408.936589) (xy 86.862266 -408.930265) (xy 86.85276 -408.924506)
			(xy 86.557866 -408.731974) (xy 86.548479 -408.726271) (xy 86.527441 -408.719998) (xy 86.505487 -408.719998)
			(xy 86.484449 -408.726271) (xy 86.475062 -408.731974) (xy 86.181438 -408.924506) (xy 86.171927 -408.930254)
			(xy 86.150634 -408.93658) (xy 86.139528 -408.936952) (xy 85.943694 -408.936952) (xy 85.931603 -408.936497)
			(xy 85.908601 -408.929038) (xy 85.889021 -408.914849) (xy 85.874771 -408.895312) (xy 85.86724 -408.872333)
			(xy 85.866732 -408.860244) (xy 84.102956 -408.860244) (xy 84.102479 -408.872291) (xy 84.095041 -408.895209)
			(xy 84.080902 -408.914719) (xy 84.06144 -408.928923) (xy 84.038547 -408.936438) (xy 84.026502 -408.936952)
			(xy 83.83143 -408.936952) (xy 83.820321 -408.936605) (xy 83.799024 -408.93027) (xy 83.78952 -408.924506)
			(xy 83.494626 -408.731974) (xy 83.485239 -408.726271) (xy 83.464201 -408.719998) (xy 83.442247 -408.719998)
			(xy 83.421209 -408.726271) (xy 83.411822 -408.731974) (xy 83.118198 -408.924506) (xy 83.108695 -408.930269)
			(xy 83.087396 -408.936585) (xy 83.076288 -408.936952) (xy 82.880454 -408.936952) (xy 82.868361 -408.936532)
			(xy 82.845358 -408.929061) (xy 82.825778 -408.914863) (xy 82.811529 -408.89532) (xy 82.804 -408.872335)
			(xy 82.803492 -408.860244) (xy 81.039716 -408.860244) (xy 81.039278 -408.872295) (xy 81.031835 -408.895219)
			(xy 81.017688 -408.914733) (xy 80.998215 -408.928935) (xy 80.975312 -408.936443) (xy 80.963262 -408.936952)
			(xy 80.76819 -408.936952) (xy 80.757083 -408.936581) (xy 80.735786 -408.930262) (xy 80.72628 -408.924506)
			(xy 80.431386 -408.731974) (xy 80.421999 -408.726271) (xy 80.400961 -408.719998) (xy 80.379007 -408.719998)
			(xy 80.357969 -408.726271) (xy 80.348582 -408.731974) (xy 80.054958 -408.924506) (xy 80.045443 -408.930247)
			(xy 80.024153 -408.936577) (xy 80.013048 -408.936952) (xy 79.817214 -408.936952) (xy 79.805124 -408.93648)
			(xy 79.782123 -408.929027) (xy 79.762542 -408.914841) (xy 79.748291 -408.895308) (xy 79.74076 -408.872332)
			(xy 79.740252 -408.860244) (xy 77.976476 -408.860244) (xy 77.976077 -408.872299) (xy 77.968629 -408.89523)
			(xy 77.954474 -408.914747) (xy 77.934989 -408.928948) (xy 77.912076 -408.936449) (xy 77.900022 -408.936952)
			(xy 77.70495 -408.936952) (xy 77.693841 -408.936597) (xy 77.672545 -408.930267) (xy 77.66304 -408.924506)
			(xy 77.368146 -408.731974) (xy 77.358759 -408.726271) (xy 77.337721 -408.719998) (xy 77.315767 -408.719998)
			(xy 77.294729 -408.726271) (xy 77.285342 -408.731974) (xy 76.991718 -408.924506) (xy 76.982211 -408.930261)
			(xy 76.960915 -408.936583) (xy 76.949808 -408.936952) (xy 76.753974 -408.936952) (xy 76.741882 -408.936515)
			(xy 76.718879 -408.92905) (xy 76.699299 -408.914856) (xy 76.68505 -408.895316) (xy 76.67752 -408.872334)
			(xy 76.677012 -408.860244) (xy 74.913236 -408.860244) (xy 74.912778 -408.872293) (xy 74.905338 -408.895214)
			(xy 74.891195 -408.914726) (xy 74.871727 -408.928929) (xy 74.848829 -408.936441) (xy 74.836782 -408.936952)
			(xy 74.64171 -408.936952) (xy 74.630603 -408.936572) (xy 74.609307 -408.930259) (xy 74.5998 -408.924506)
			(xy 74.304906 -408.731974) (xy 74.295519 -408.726271) (xy 74.274481 -408.719998) (xy 74.252527 -408.719998)
			(xy 74.231489 -408.726271) (xy 74.222102 -408.731974) (xy 73.928478 -408.924506) (xy 73.918959 -408.930239)
			(xy 73.897672 -408.936574) (xy 73.886568 -408.936952) (xy 73.690734 -408.936952) (xy 73.678645 -408.936464)
			(xy 73.655645 -408.929015) (xy 73.636063 -408.914834) (xy 73.621812 -408.895305) (xy 73.614281 -408.872331)
			(xy 73.613772 -408.860244) (xy 71.849996 -408.860244) (xy 71.849578 -408.872297) (xy 71.842132 -408.895225)
			(xy 71.827981 -408.91474) (xy 71.808502 -408.928942) (xy 71.785594 -408.936446) (xy 71.773542 -408.936952)
			(xy 71.57847 -408.936952) (xy 71.567362 -408.936589) (xy 71.546066 -408.930265) (xy 71.53656 -408.924506)
			(xy 71.241666 -408.731974) (xy 71.232279 -408.726271) (xy 71.211241 -408.719998) (xy 71.189287 -408.719998)
			(xy 71.168249 -408.726271) (xy 71.158862 -408.731974) (xy 70.865238 -408.924506) (xy 70.855727 -408.930254)
			(xy 70.834434 -408.93658) (xy 70.823328 -408.936952) (xy 70.627494 -408.936952) (xy 70.615403 -408.936497)
			(xy 70.592401 -408.929038) (xy 70.572821 -408.914849) (xy 70.558571 -408.895312) (xy 70.55104 -408.872333)
			(xy 70.550532 -408.860244) (xy 68.786756 -408.860244) (xy 68.786279 -408.872291) (xy 68.778841 -408.895209)
			(xy 68.764702 -408.914719) (xy 68.74524 -408.928923) (xy 68.722347 -408.936438) (xy 68.710302 -408.936952)
			(xy 68.51523 -408.936952) (xy 68.504121 -408.936605) (xy 68.482824 -408.93027) (xy 68.47332 -408.924506)
			(xy 68.178426 -408.731974) (xy 68.169039 -408.726271) (xy 68.148001 -408.719998) (xy 68.126047 -408.719998)
			(xy 68.105009 -408.726271) (xy 68.095622 -408.731974) (xy 67.801998 -408.924506) (xy 67.792495 -408.930269)
			(xy 67.771196 -408.936585) (xy 67.760088 -408.936952) (xy 67.564254 -408.936952) (xy 67.552161 -408.936532)
			(xy 67.529158 -408.929061) (xy 67.509578 -408.914863) (xy 67.495329 -408.89532) (xy 67.4878 -408.872335)
			(xy 67.487292 -408.860244) (xy 65.723516 -408.860244) (xy 65.723078 -408.872295) (xy 65.715635 -408.895219)
			(xy 65.701488 -408.914733) (xy 65.682015 -408.928935) (xy 65.659112 -408.936443) (xy 65.647062 -408.936952)
			(xy 65.45199 -408.936952) (xy 65.440883 -408.936581) (xy 65.419586 -408.930262) (xy 65.41008 -408.924506)
			(xy 65.115186 -408.731974) (xy 65.105799 -408.726271) (xy 65.084761 -408.719998) (xy 65.062807 -408.719998)
			(xy 65.041769 -408.726271) (xy 65.032382 -408.731974) (xy 64.738758 -408.924506) (xy 64.729243 -408.930247)
			(xy 64.707953 -408.936577) (xy 64.696848 -408.936952) (xy 64.501014 -408.936952) (xy 64.488924 -408.93648)
			(xy 64.465923 -408.929027) (xy 64.446342 -408.914841) (xy 64.432091 -408.895308) (xy 64.42456 -408.872332)
			(xy 64.424052 -408.860244) (xy 62.660276 -408.860244) (xy 62.659877 -408.872299) (xy 62.652429 -408.89523)
			(xy 62.638274 -408.914747) (xy 62.618789 -408.928948) (xy 62.595876 -408.936449) (xy 62.583822 -408.936952)
			(xy 62.38875 -408.936952) (xy 62.377641 -408.936597) (xy 62.356345 -408.930267) (xy 62.34684 -408.924506)
			(xy 62.051946 -408.731974) (xy 62.042559 -408.726271) (xy 62.021521 -408.719998) (xy 61.999567 -408.719998)
			(xy 61.978529 -408.726271) (xy 61.969142 -408.731974) (xy 61.675518 -408.924506) (xy 61.666011 -408.930261)
			(xy 61.644715 -408.936583) (xy 61.633608 -408.936952) (xy 61.437774 -408.936952) (xy 61.425682 -408.936515)
			(xy 61.402679 -408.92905) (xy 61.383099 -408.914856) (xy 61.36885 -408.895316) (xy 61.36132 -408.872334)
			(xy 61.360812 -408.860244) (xy 59.597036 -408.860244) (xy 59.596578 -408.872293) (xy 59.589138 -408.895214)
			(xy 59.574995 -408.914726) (xy 59.555527 -408.928929) (xy 59.532629 -408.936441) (xy 59.520582 -408.936952)
			(xy 59.32551 -408.936952) (xy 59.314403 -408.936572) (xy 59.293107 -408.930259) (xy 59.2836 -408.924506)
			(xy 58.988706 -408.731974) (xy 58.979319 -408.726271) (xy 58.958281 -408.719998) (xy 58.936327 -408.719998)
			(xy 58.915289 -408.726271) (xy 58.905902 -408.731974) (xy 58.612278 -408.924506) (xy 58.602759 -408.930239)
			(xy 58.581472 -408.936574) (xy 58.570368 -408.936952) (xy 58.374534 -408.936952) (xy 58.362445 -408.936464)
			(xy 58.339445 -408.929015) (xy 58.319863 -408.914834) (xy 58.305612 -408.895305) (xy 58.298081 -408.872331)
			(xy 58.297572 -408.860244) (xy 56.533796 -408.860244) (xy 56.533378 -408.872297) (xy 56.525932 -408.895225)
			(xy 56.511781 -408.91474) (xy 56.492302 -408.928942) (xy 56.469394 -408.936446) (xy 56.457342 -408.936952)
			(xy 56.26227 -408.936952) (xy 56.251162 -408.936589) (xy 56.229866 -408.930265) (xy 56.22036 -408.924506)
			(xy 55.925466 -408.731974) (xy 55.916079 -408.726271) (xy 55.895041 -408.719998) (xy 55.873087 -408.719998)
			(xy 55.852049 -408.726271) (xy 55.842662 -408.731974) (xy 55.549038 -408.924506) (xy 55.539527 -408.930254)
			(xy 55.518234 -408.93658) (xy 55.507128 -408.936952) (xy 55.311294 -408.936952) (xy 55.299203 -408.936497)
			(xy 55.276201 -408.929038) (xy 55.256621 -408.914849) (xy 55.242371 -408.895312) (xy 55.23484 -408.872333)
			(xy 55.234332 -408.860244) (xy 53.470556 -408.860244) (xy 53.470079 -408.872291) (xy 53.462641 -408.895209)
			(xy 53.448502 -408.914719) (xy 53.42904 -408.928923) (xy 53.406147 -408.936438) (xy 53.394102 -408.936952)
			(xy 53.19903 -408.936952) (xy 53.187921 -408.936605) (xy 53.166624 -408.93027) (xy 53.15712 -408.924506)
			(xy 52.862226 -408.731974) (xy 52.852839 -408.726271) (xy 52.831801 -408.719998) (xy 52.809847 -408.719998)
			(xy 52.788809 -408.726271) (xy 52.779422 -408.731974) (xy 52.485798 -408.924506) (xy 52.476295 -408.930269)
			(xy 52.454996 -408.936585) (xy 52.443888 -408.936952) (xy 52.248054 -408.936952) (xy 52.235961 -408.936532)
			(xy 52.212958 -408.929061) (xy 52.193378 -408.914863) (xy 52.179129 -408.89532) (xy 52.1716 -408.872335)
			(xy 52.171092 -408.860244) (xy 50.407316 -408.860244) (xy 50.406878 -408.872295) (xy 50.399435 -408.895219)
			(xy 50.385288 -408.914733) (xy 50.365815 -408.928935) (xy 50.342912 -408.936443) (xy 50.330862 -408.936952)
			(xy 50.13579 -408.936952) (xy 50.124683 -408.936581) (xy 50.103386 -408.930262) (xy 50.09388 -408.924506)
			(xy 49.798986 -408.731974) (xy 49.789599 -408.726271) (xy 49.768561 -408.719998) (xy 49.746607 -408.719998)
			(xy 49.725569 -408.726271) (xy 49.716182 -408.731974) (xy 49.422558 -408.924506) (xy 49.413043 -408.930247)
			(xy 49.391753 -408.936577) (xy 49.380648 -408.936952) (xy 49.184814 -408.936952) (xy 49.172724 -408.93648)
			(xy 49.149723 -408.929027) (xy 49.130142 -408.914841) (xy 49.115891 -408.895308) (xy 49.10836 -408.872332)
			(xy 49.107852 -408.860244) (xy 6.918074 -408.860244) (xy 6.930013 -408.901671) (xy 6.961351 -409.038912)
			(xy 6.984945 -409.177694) (xy 7.00072 -409.31758) (xy 7.008628 -409.458131) (xy 7.00913 -409.528518)
			(xy 7.00913 -409.563824) (xy 102.192836 -409.563824) (xy 102.192836 -408.700224) (xy 102.193322 -408.672955)
			(xy 102.201084 -408.618971) (xy 102.216449 -408.566641) (xy 102.239106 -408.517031) (xy 102.268592 -408.47115)
			(xy 102.304307 -408.429933) (xy 102.345524 -408.394218) (xy 102.391405 -408.364732) (xy 102.441015 -408.342075)
			(xy 102.493345 -408.32671) (xy 102.547329 -408.318948) (xy 102.601867 -408.318948) (xy 102.655851 -408.32671)
			(xy 102.708181 -408.342075) (xy 102.757791 -408.364732) (xy 102.803672 -408.394218) (xy 102.844889 -408.429933)
			(xy 102.880604 -408.47115) (xy 102.91009 -408.517031) (xy 102.932747 -408.566641) (xy 102.948112 -408.618971)
			(xy 102.955874 -408.672955) (xy 102.95636 -408.700224) (xy 102.95636 -409.563824) (xy 102.955874 -409.591093)
			(xy 102.948112 -409.645077) (xy 102.932747 -409.697407) (xy 102.91009 -409.747017) (xy 102.880604 -409.792898)
			(xy 102.844889 -409.834115) (xy 102.803672 -409.86983) (xy 102.757791 -409.899316) (xy 102.748244 -409.903676)
			(xy 110.559596 -409.903676) (xy 110.559596 -409.040076) (xy 110.560082 -409.012825) (xy 110.567838 -408.958877)
			(xy 110.583193 -408.906582) (xy 110.605835 -408.857005) (xy 110.635301 -408.811155) (xy 110.670992 -408.769964)
			(xy 110.712183 -408.734273) (xy 110.758033 -408.704807) (xy 110.80761 -408.682165) (xy 110.859905 -408.66681)
			(xy 110.913853 -408.659054) (xy 110.968355 -408.659054) (xy 111.022303 -408.66681) (xy 111.074598 -408.682165)
			(xy 111.124175 -408.704807) (xy 111.170025 -408.734273) (xy 111.211216 -408.769964) (xy 111.246907 -408.811155)
			(xy 111.276373 -408.857005) (xy 111.277852 -408.860244) (xy 116.208048 -408.860244) (xy 116.208048 -408.174444)
			(xy 116.208601 -408.162376) (xy 116.216046 -408.139418) (xy 116.230221 -408.119884) (xy 116.249739 -408.105686)
			(xy 116.272689 -408.098215) (xy 116.284756 -408.097736) (xy 116.47932 -408.097736) (xy 116.490424 -408.098126)
			(xy 116.511716 -408.104443) (xy 116.52123 -408.110182) (xy 116.814854 -408.302714) (xy 116.824249 -408.308397)
			(xy 116.845256 -408.314736) (xy 116.867199 -408.314816) (xy 116.888252 -408.308629) (xy 116.897658 -408.302968)
			(xy 117.193822 -408.110182) (xy 117.20334 -408.104448) (xy 117.224627 -408.098114) (xy 117.235732 -408.097736)
			(xy 117.430296 -408.097736) (xy 117.442383 -408.098116) (xy 117.465373 -408.105588) (xy 117.484927 -408.119801)
			(xy 117.49913 -408.139363) (xy 117.50659 -408.162357) (xy 117.507004 -408.174444) (xy 117.507004 -408.860244)
			(xy 119.271288 -408.860244) (xy 119.271288 -408.174444) (xy 119.27175 -408.162364) (xy 119.279205 -408.139383)
			(xy 119.293399 -408.119833) (xy 119.31294 -408.105627) (xy 119.335916 -408.098158) (xy 119.347996 -408.097736)
			(xy 119.54256 -408.097736) (xy 119.553665 -408.09811) (xy 119.574957 -408.104438) (xy 119.58447 -408.110182)
			(xy 119.878094 -408.302714) (xy 119.88747 -408.308431) (xy 119.908486 -408.314763) (xy 119.930436 -408.314833)
			(xy 119.951492 -408.308635) (xy 119.960898 -408.302968) (xy 120.257062 -408.110182) (xy 120.266572 -408.104433)
			(xy 120.287866 -408.098108) (xy 120.298972 -408.097736) (xy 120.493536 -408.097736) (xy 120.505625 -408.098083)
			(xy 120.528616 -408.105565) (xy 120.54817 -408.119787) (xy 120.562371 -408.139355) (xy 120.56983 -408.162355)
			(xy 120.570244 -408.174444) (xy 120.570244 -408.860244) (xy 122.334528 -408.860244) (xy 122.334528 -408.174444)
			(xy 122.334951 -408.16236) (xy 122.34241 -408.139373) (xy 122.356613 -408.119818) (xy 122.376165 -408.105614)
			(xy 122.399152 -408.098152) (xy 122.411236 -408.097736) (xy 122.6058 -408.097736) (xy 122.616903 -408.098135)
			(xy 122.638195 -408.104446) (xy 122.64771 -408.110182) (xy 122.941334 -408.302714) (xy 122.950691 -408.308465)
			(xy 122.971716 -408.31479) (xy 122.993672 -408.31485) (xy 123.014732 -408.30864) (xy 123.024138 -408.302968)
			(xy 123.320302 -408.110182) (xy 123.329804 -408.104418) (xy 123.351104 -408.098103) (xy 123.362212 -408.097736)
			(xy 123.556776 -408.097736) (xy 123.568862 -408.098134) (xy 123.591851 -408.1056) (xy 123.611406 -408.119809)
			(xy 123.625609 -408.139367) (xy 123.633069 -408.162358) (xy 123.633484 -408.174444) (xy 123.633484 -408.860244)
			(xy 125.397768 -408.860244) (xy 125.397768 -408.174444) (xy 125.39825 -408.162366) (xy 125.405702 -408.139389)
			(xy 125.419891 -408.11984) (xy 125.439428 -408.105633) (xy 125.462398 -408.09816) (xy 125.474476 -408.097736)
			(xy 125.66904 -408.097736) (xy 125.680145 -408.098118) (xy 125.701437 -408.104441) (xy 125.71095 -408.110182)
			(xy 126.004574 -408.302714) (xy 126.013959 -408.308414) (xy 126.034971 -408.31475) (xy 126.056918 -408.314825)
			(xy 126.077972 -408.308632) (xy 126.087378 -408.302968) (xy 126.383542 -408.110182) (xy 126.393056 -408.10444)
			(xy 126.414347 -408.098111) (xy 126.425452 -408.097736) (xy 126.620016 -408.097736) (xy 126.632104 -408.0981)
			(xy 126.655095 -408.105577) (xy 126.674649 -408.119794) (xy 126.688851 -408.139359) (xy 126.69631 -408.162356)
			(xy 126.696724 -408.174444) (xy 126.696724 -408.860244) (xy 128.461008 -408.860244) (xy 128.461008 -408.174444)
			(xy 128.46145 -408.162362) (xy 128.468908 -408.139378) (xy 128.483106 -408.119826) (xy 128.502653 -408.105621)
			(xy 128.525634 -408.098155) (xy 128.537716 -408.097736) (xy 128.73228 -408.097736) (xy 128.743386 -408.098103)
			(xy 128.764678 -408.104436) (xy 128.77419 -408.110182) (xy 129.067814 -408.302714) (xy 129.07718 -408.308448)
			(xy 129.098201 -408.314777) (xy 129.120154 -408.314842) (xy 129.141212 -408.308638) (xy 129.150618 -408.302968)
			(xy 129.446782 -408.110182) (xy 129.456288 -408.104426) (xy 129.477585 -408.098105) (xy 129.488692 -408.097736)
			(xy 129.683256 -408.097736) (xy 129.695341 -408.098151) (xy 129.71833 -408.105612) (xy 129.737884 -408.119816)
			(xy 129.752088 -408.13937) (xy 129.759549 -408.162359) (xy 129.759964 -408.174444) (xy 129.759964 -408.860244)
			(xy 131.524248 -408.860244) (xy 131.524248 -408.174444) (xy 131.524801 -408.162376) (xy 131.532246 -408.139418)
			(xy 131.546421 -408.119884) (xy 131.565939 -408.105686) (xy 131.588889 -408.098215) (xy 131.600956 -408.097736)
			(xy 131.79552 -408.097736) (xy 131.806624 -408.098126) (xy 131.827916 -408.104443) (xy 131.83743 -408.110182)
			(xy 132.131054 -408.302714) (xy 132.140449 -408.308397) (xy 132.161456 -408.314736) (xy 132.183399 -408.314816)
			(xy 132.204452 -408.308629) (xy 132.213858 -408.302968) (xy 132.510022 -408.110182) (xy 132.51954 -408.104448)
			(xy 132.540827 -408.098114) (xy 132.551932 -408.097736) (xy 132.746496 -408.097736) (xy 132.758583 -408.098116)
			(xy 132.781573 -408.105588) (xy 132.801127 -408.119801) (xy 132.81533 -408.139363) (xy 132.82279 -408.162357)
			(xy 132.823204 -408.174444) (xy 132.823204 -408.860244) (xy 134.587488 -408.860244) (xy 134.587488 -408.174444)
			(xy 134.58795 -408.162364) (xy 134.595405 -408.139383) (xy 134.609599 -408.119833) (xy 134.62914 -408.105627)
			(xy 134.652116 -408.098158) (xy 134.664196 -408.097736) (xy 134.85876 -408.097736) (xy 134.869865 -408.09811)
			(xy 134.891157 -408.104438) (xy 134.90067 -408.110182) (xy 135.194294 -408.302714) (xy 135.20367 -408.308431)
			(xy 135.224686 -408.314763) (xy 135.246636 -408.314833) (xy 135.267692 -408.308635) (xy 135.277098 -408.302968)
			(xy 135.573262 -408.110182) (xy 135.582772 -408.104433) (xy 135.604066 -408.098108) (xy 135.615172 -408.097736)
			(xy 135.809736 -408.097736) (xy 135.821825 -408.098083) (xy 135.844816 -408.105565) (xy 135.86437 -408.119787)
			(xy 135.878571 -408.139355) (xy 135.88603 -408.162355) (xy 135.886444 -408.174444) (xy 135.886444 -408.860244)
			(xy 137.650728 -408.860244) (xy 137.650728 -408.174444) (xy 137.651151 -408.16236) (xy 137.65861 -408.139373)
			(xy 137.672813 -408.119818) (xy 137.692365 -408.105614) (xy 137.715352 -408.098152) (xy 137.727436 -408.097736)
			(xy 137.922 -408.097736) (xy 137.933103 -408.098135) (xy 137.954395 -408.104446) (xy 137.96391 -408.110182)
			(xy 138.257534 -408.302714) (xy 138.266891 -408.308465) (xy 138.287916 -408.31479) (xy 138.309872 -408.31485)
			(xy 138.330932 -408.30864) (xy 138.340338 -408.302968) (xy 138.636502 -408.110182) (xy 138.646004 -408.104418)
			(xy 138.667304 -408.098103) (xy 138.678412 -408.097736) (xy 138.872976 -408.097736) (xy 138.885062 -408.098134)
			(xy 138.908051 -408.1056) (xy 138.927606 -408.119809) (xy 138.941809 -408.139367) (xy 138.949269 -408.162358)
			(xy 138.949684 -408.174444) (xy 138.949684 -408.860244) (xy 140.713968 -408.860244) (xy 140.713968 -408.174444)
			(xy 140.71445 -408.162366) (xy 140.721902 -408.139389) (xy 140.736091 -408.11984) (xy 140.755628 -408.105633)
			(xy 140.778598 -408.09816) (xy 140.790676 -408.097736) (xy 140.98524 -408.097736) (xy 140.996345 -408.098118)
			(xy 141.017637 -408.104441) (xy 141.02715 -408.110182) (xy 141.320774 -408.302714) (xy 141.330159 -408.308414)
			(xy 141.351171 -408.31475) (xy 141.373118 -408.314825) (xy 141.394172 -408.308632) (xy 141.403578 -408.302968)
			(xy 141.699742 -408.110182) (xy 141.709256 -408.10444) (xy 141.730547 -408.098111) (xy 141.741652 -408.097736)
			(xy 141.936216 -408.097736) (xy 141.948304 -408.0981) (xy 141.971295 -408.105577) (xy 141.990849 -408.119794)
			(xy 142.005051 -408.139359) (xy 142.01251 -408.162356) (xy 142.012924 -408.174444) (xy 142.012924 -408.860244)
			(xy 143.777208 -408.860244) (xy 143.777208 -408.174444) (xy 143.77765 -408.162362) (xy 143.785108 -408.139378)
			(xy 143.799306 -408.119826) (xy 143.818853 -408.105621) (xy 143.841834 -408.098155) (xy 143.853916 -408.097736)
			(xy 144.04848 -408.097736) (xy 144.059586 -408.098103) (xy 144.080878 -408.104436) (xy 144.09039 -408.110182)
			(xy 144.384014 -408.302714) (xy 144.39338 -408.308448) (xy 144.414401 -408.314777) (xy 144.436354 -408.314842)
			(xy 144.457412 -408.308638) (xy 144.466818 -408.302968) (xy 144.762982 -408.110182) (xy 144.772488 -408.104426)
			(xy 144.793785 -408.098105) (xy 144.804892 -408.097736) (xy 144.999456 -408.097736) (xy 145.011541 -408.098151)
			(xy 145.03453 -408.105612) (xy 145.054084 -408.119816) (xy 145.068288 -408.13937) (xy 145.075749 -408.162359)
			(xy 145.076164 -408.174444) (xy 145.076164 -408.860244) (xy 146.840448 -408.860244) (xy 146.840448 -408.174444)
			(xy 146.841001 -408.162376) (xy 146.848446 -408.139418) (xy 146.862621 -408.119884) (xy 146.882139 -408.105686)
			(xy 146.905089 -408.098215) (xy 146.917156 -408.097736) (xy 147.11172 -408.097736) (xy 147.122824 -408.098126)
			(xy 147.144116 -408.104443) (xy 147.15363 -408.110182) (xy 147.447254 -408.302714) (xy 147.456649 -408.308397)
			(xy 147.477656 -408.314736) (xy 147.499599 -408.314816) (xy 147.520652 -408.308629) (xy 147.530058 -408.302968)
			(xy 147.826222 -408.110182) (xy 147.83574 -408.104448) (xy 147.857027 -408.098114) (xy 147.868132 -408.097736)
			(xy 148.062696 -408.097736) (xy 148.074783 -408.098116) (xy 148.097773 -408.105588) (xy 148.117327 -408.119801)
			(xy 148.13153 -408.139363) (xy 148.13899 -408.162357) (xy 148.139404 -408.174444) (xy 148.139404 -408.860244)
			(xy 149.903688 -408.860244) (xy 149.903688 -408.174444) (xy 149.90415 -408.162364) (xy 149.911605 -408.139383)
			(xy 149.925799 -408.119833) (xy 149.94534 -408.105627) (xy 149.968316 -408.098158) (xy 149.980396 -408.097736)
			(xy 150.17496 -408.097736) (xy 150.186065 -408.09811) (xy 150.207357 -408.104438) (xy 150.21687 -408.110182)
			(xy 150.510494 -408.302714) (xy 150.51987 -408.308431) (xy 150.540886 -408.314763) (xy 150.562836 -408.314833)
			(xy 150.583892 -408.308635) (xy 150.593298 -408.302968) (xy 150.889462 -408.110182) (xy 150.898972 -408.104433)
			(xy 150.920266 -408.098108) (xy 150.931372 -408.097736) (xy 151.125936 -408.097736) (xy 151.138025 -408.098083)
			(xy 151.161016 -408.105565) (xy 151.18057 -408.119787) (xy 151.194771 -408.139355) (xy 151.20223 -408.162355)
			(xy 151.202644 -408.174444) (xy 151.202644 -408.860244) (xy 152.966928 -408.860244) (xy 152.966928 -408.174444)
			(xy 152.967351 -408.16236) (xy 152.97481 -408.139373) (xy 152.989013 -408.119818) (xy 153.008565 -408.105614)
			(xy 153.031552 -408.098152) (xy 153.043636 -408.097736) (xy 153.2382 -408.097736) (xy 153.249303 -408.098135)
			(xy 153.270595 -408.104446) (xy 153.28011 -408.110182) (xy 153.573734 -408.302714) (xy 153.583091 -408.308465)
			(xy 153.604116 -408.31479) (xy 153.626072 -408.31485) (xy 153.647132 -408.30864) (xy 153.656538 -408.302968)
			(xy 153.952702 -408.110182) (xy 153.962204 -408.104418) (xy 153.983504 -408.098103) (xy 153.994612 -408.097736)
			(xy 154.189176 -408.097736) (xy 154.201262 -408.098134) (xy 154.224251 -408.1056) (xy 154.243806 -408.119809)
			(xy 154.258009 -408.139367) (xy 154.265469 -408.162358) (xy 154.265884 -408.174444) (xy 154.265884 -408.860244)
			(xy 156.030168 -408.860244) (xy 156.030168 -408.174444) (xy 156.03065 -408.162366) (xy 156.038102 -408.139389)
			(xy 156.052291 -408.11984) (xy 156.071828 -408.105633) (xy 156.094798 -408.09816) (xy 156.106876 -408.097736)
			(xy 156.30144 -408.097736) (xy 156.312545 -408.098118) (xy 156.333837 -408.104441) (xy 156.34335 -408.110182)
			(xy 156.636974 -408.302714) (xy 156.646296 -408.308459) (xy 156.66726 -408.314763) (xy 156.68915 -408.314819)
			(xy 156.710147 -408.308625) (xy 156.719524 -408.302968) (xy 156.719778 -408.302968) (xy 157.015942 -408.110182)
			(xy 157.025456 -408.10444) (xy 157.046747 -408.098111) (xy 157.057852 -408.097736) (xy 157.252416 -408.097736)
			(xy 157.264504 -408.0981) (xy 157.287495 -408.105577) (xy 157.307049 -408.119794) (xy 157.321251 -408.139359)
			(xy 157.32871 -408.162356) (xy 157.329124 -408.174444) (xy 157.329124 -408.860244) (xy 159.093408 -408.860244)
			(xy 159.093408 -408.174444) (xy 159.09385 -408.162362) (xy 159.101308 -408.139378) (xy 159.115506 -408.119826)
			(xy 159.135053 -408.105621) (xy 159.158034 -408.098155) (xy 159.170116 -408.097736) (xy 159.36468 -408.097736)
			(xy 159.375786 -408.098103) (xy 159.397078 -408.104436) (xy 159.40659 -408.110182) (xy 159.700214 -408.302714)
			(xy 159.709564 -408.308408) (xy 159.730514 -408.314723) (xy 159.752396 -408.314794) (xy 159.773387 -408.308616)
			(xy 159.782764 -408.302968) (xy 159.783018 -408.302968) (xy 160.079182 -408.110182) (xy 160.088688 -408.104426)
			(xy 160.109985 -408.098105) (xy 160.121092 -408.097736) (xy 160.315656 -408.097736) (xy 160.327741 -408.098151)
			(xy 160.35073 -408.105612) (xy 160.370284 -408.119816) (xy 160.384488 -408.13937) (xy 160.391949 -408.162359)
			(xy 160.392364 -408.174444) (xy 160.392364 -408.860244) (xy 162.156648 -408.860244) (xy 162.156648 -408.174444)
			(xy 162.157201 -408.162376) (xy 162.164646 -408.139418) (xy 162.178821 -408.119884) (xy 162.198339 -408.105686)
			(xy 162.221289 -408.098215) (xy 162.233356 -408.097736) (xy 162.42792 -408.097736) (xy 162.439024 -408.098126)
			(xy 162.460316 -408.104443) (xy 162.46983 -408.110182) (xy 162.763454 -408.302714) (xy 162.772785 -408.308442)
			(xy 162.793745 -408.314749) (xy 162.815632 -408.314811) (xy 162.836627 -408.308622) (xy 162.846004 -408.302968)
			(xy 162.846258 -408.302968) (xy 163.142422 -408.110182) (xy 163.15194 -408.104448) (xy 163.173227 -408.098114)
			(xy 163.184332 -408.097736) (xy 163.378896 -408.097736) (xy 163.390983 -408.098116) (xy 163.413973 -408.105588)
			(xy 163.433527 -408.119801) (xy 163.44773 -408.139363) (xy 163.45519 -408.162357) (xy 163.455604 -408.174444)
			(xy 163.455604 -408.860244) (xy 163.455173 -408.872321) (xy 163.447698 -408.895291) (xy 163.433493 -408.914827)
			(xy 163.413948 -408.92902) (xy 163.390974 -408.936481) (xy 163.378896 -408.936952) (xy 163.184332 -408.936952)
			(xy 163.173223 -408.936604) (xy 163.151927 -408.930269) (xy 163.142422 -408.924506) (xy 162.847528 -408.731974)
			(xy 162.838175 -408.726274) (xy 162.8172 -408.72) (xy 162.795306 -408.72) (xy 162.774331 -408.726274)
			(xy 162.764978 -408.731974) (xy 162.764724 -408.731974) (xy 162.4711 -408.924506) (xy 162.461597 -408.930268)
			(xy 162.440298 -408.936585) (xy 162.42919 -408.936952) (xy 162.233356 -408.936952) (xy 162.221284 -408.936474)
			(xy 162.198322 -408.929005) (xy 162.17879 -408.91481) (xy 162.164595 -408.895278) (xy 162.157126 -408.872316)
			(xy 162.156648 -408.860244) (xy 160.392364 -408.860244) (xy 160.391973 -408.872325) (xy 160.384493 -408.895301)
			(xy 160.370279 -408.914842) (xy 160.350722 -408.929033) (xy 160.327738 -408.936487) (xy 160.315656 -408.936952)
			(xy 160.121092 -408.936952) (xy 160.109985 -408.93658) (xy 160.088688 -408.930262) (xy 160.079182 -408.924506)
			(xy 159.784288 -408.731974) (xy 159.774935 -408.726274) (xy 159.75396 -408.72) (xy 159.732066 -408.72)
			(xy 159.711091 -408.726274) (xy 159.701738 -408.731974) (xy 159.701484 -408.731974) (xy 159.40786 -408.924506)
			(xy 159.398345 -408.930246) (xy 159.377055 -408.936577) (xy 159.36595 -408.936952) (xy 159.170116 -408.936952)
			(xy 159.158047 -408.936423) (xy 159.135087 -408.92897) (xy 159.115554 -408.914789) (xy 159.101357 -408.895266)
			(xy 159.093887 -408.872313) (xy 159.093408 -408.860244) (xy 157.329124 -408.860244) (xy 157.328674 -408.872319)
			(xy 157.321201 -408.895285) (xy 157.307 -408.91482) (xy 157.28746 -408.929014) (xy 157.264491 -408.936478)
			(xy 157.252416 -408.936952) (xy 157.057852 -408.936952) (xy 157.046743 -408.936596) (xy 157.025447 -408.930267)
			(xy 157.015942 -408.924506) (xy 156.721048 -408.731974) (xy 156.711695 -408.726274) (xy 156.69072 -408.72)
			(xy 156.668826 -408.72) (xy 156.647851 -408.726274) (xy 156.638498 -408.731974) (xy 156.638244 -408.731974)
			(xy 156.34462 -408.924506) (xy 156.335113 -408.930261) (xy 156.313817 -408.936582) (xy 156.30271 -408.936952)
			(xy 156.106876 -408.936952) (xy 156.094805 -408.936457) (xy 156.071844 -408.928993) (xy 156.052311 -408.914803)
			(xy 156.038116 -408.895274) (xy 156.030646 -408.872315) (xy 156.030168 -408.860244) (xy 154.265884 -408.860244)
			(xy 154.265473 -408.872323) (xy 154.257996 -408.895296) (xy 154.243786 -408.914834) (xy 154.224235 -408.929027)
			(xy 154.201256 -408.936484) (xy 154.189176 -408.936952) (xy 153.994612 -408.936952) (xy 153.983505 -408.936571)
			(xy 153.962209 -408.930259) (xy 153.952702 -408.924506) (xy 153.657808 -408.731974) (xy 153.648421 -408.726271)
			(xy 153.627383 -408.719998) (xy 153.605429 -408.719998) (xy 153.584391 -408.726271) (xy 153.575004 -408.731974)
			(xy 153.28138 -408.924506) (xy 153.271861 -408.930239) (xy 153.250574 -408.936574) (xy 153.23947 -408.936952)
			(xy 153.043636 -408.936952) (xy 153.031568 -408.936406) (xy 153.008609 -408.928959) (xy 152.989075 -408.914782)
			(xy 152.974878 -408.895263) (xy 152.967407 -408.872312) (xy 152.966928 -408.860244) (xy 151.202644 -408.860244)
			(xy 151.202174 -408.872317) (xy 151.194704 -408.89528) (xy 151.180507 -408.914813) (xy 151.160973 -408.929007)
			(xy 151.138009 -408.936475) (xy 151.125936 -408.936952) (xy 150.931372 -408.936952) (xy 150.920264 -408.936588)
			(xy 150.898968 -408.930264) (xy 150.889462 -408.924506) (xy 150.594568 -408.731974) (xy 150.585181 -408.726271)
			(xy 150.564143 -408.719998) (xy 150.542189 -408.719998) (xy 150.521151 -408.726271) (xy 150.511764 -408.731974)
			(xy 150.21814 -408.924506) (xy 150.208629 -408.930253) (xy 150.187336 -408.936579) (xy 150.17623 -408.936952)
			(xy 149.980396 -408.936952) (xy 149.968326 -408.93644) (xy 149.945366 -408.928982) (xy 149.925833 -408.914796)
			(xy 149.911637 -408.89527) (xy 149.904167 -408.872314) (xy 149.903688 -408.860244) (xy 148.139404 -408.860244)
			(xy 148.138973 -408.872321) (xy 148.131498 -408.895291) (xy 148.117293 -408.914827) (xy 148.097748 -408.92902)
			(xy 148.074774 -408.936481) (xy 148.062696 -408.936952) (xy 147.868132 -408.936952) (xy 147.857023 -408.936604)
			(xy 147.835727 -408.930269) (xy 147.826222 -408.924506) (xy 147.531328 -408.731974) (xy 147.521941 -408.726271)
			(xy 147.500903 -408.719998) (xy 147.478949 -408.719998) (xy 147.457911 -408.726271) (xy 147.448524 -408.731974)
			(xy 147.1549 -408.924506) (xy 147.145397 -408.930268) (xy 147.124098 -408.936585) (xy 147.11299 -408.936952)
			(xy 146.917156 -408.936952) (xy 146.905084 -408.936474) (xy 146.882122 -408.929005) (xy 146.86259 -408.91481)
			(xy 146.848395 -408.895278) (xy 146.840926 -408.872316) (xy 146.840448 -408.860244) (xy 145.076164 -408.860244)
			(xy 145.075773 -408.872325) (xy 145.068293 -408.895301) (xy 145.054079 -408.914842) (xy 145.034522 -408.929033)
			(xy 145.011538 -408.936487) (xy 144.999456 -408.936952) (xy 144.804892 -408.936952) (xy 144.793785 -408.93658)
			(xy 144.772488 -408.930262) (xy 144.762982 -408.924506) (xy 144.468088 -408.731974) (xy 144.458701 -408.726271)
			(xy 144.437663 -408.719998) (xy 144.415709 -408.719998) (xy 144.394671 -408.726271) (xy 144.385284 -408.731974)
			(xy 144.09166 -408.924506) (xy 144.082145 -408.930246) (xy 144.060855 -408.936577) (xy 144.04975 -408.936952)
			(xy 143.853916 -408.936952) (xy 143.841847 -408.936423) (xy 143.818887 -408.92897) (xy 143.799354 -408.914789)
			(xy 143.785157 -408.895266) (xy 143.777687 -408.872313) (xy 143.777208 -408.860244) (xy 142.012924 -408.860244)
			(xy 142.012474 -408.872319) (xy 142.005001 -408.895285) (xy 141.9908 -408.91482) (xy 141.97126 -408.929014)
			(xy 141.948291 -408.936478) (xy 141.936216 -408.936952) (xy 141.741652 -408.936952) (xy 141.730543 -408.936596)
			(xy 141.709247 -408.930267) (xy 141.699742 -408.924506) (xy 141.404848 -408.731974) (xy 141.395461 -408.726271)
			(xy 141.374423 -408.719998) (xy 141.352469 -408.719998) (xy 141.331431 -408.726271) (xy 141.322044 -408.731974)
			(xy 141.02842 -408.924506) (xy 141.018913 -408.930261) (xy 140.997617 -408.936582) (xy 140.98651 -408.936952)
			(xy 140.790676 -408.936952) (xy 140.778605 -408.936457) (xy 140.755644 -408.928993) (xy 140.736111 -408.914803)
			(xy 140.721916 -408.895274) (xy 140.714446 -408.872315) (xy 140.713968 -408.860244) (xy 138.949684 -408.860244)
			(xy 138.949273 -408.872323) (xy 138.941796 -408.895296) (xy 138.927586 -408.914834) (xy 138.908035 -408.929027)
			(xy 138.885056 -408.936484) (xy 138.872976 -408.936952) (xy 138.678412 -408.936952) (xy 138.667305 -408.936571)
			(xy 138.646009 -408.930259) (xy 138.636502 -408.924506) (xy 138.341608 -408.731974) (xy 138.332221 -408.726271)
			(xy 138.311183 -408.719998) (xy 138.289229 -408.719998) (xy 138.268191 -408.726271) (xy 138.258804 -408.731974)
			(xy 137.96518 -408.924506) (xy 137.955661 -408.930239) (xy 137.934374 -408.936574) (xy 137.92327 -408.936952)
			(xy 137.727436 -408.936952) (xy 137.715368 -408.936406) (xy 137.692409 -408.928959) (xy 137.672875 -408.914782)
			(xy 137.658678 -408.895263) (xy 137.651207 -408.872312) (xy 137.650728 -408.860244) (xy 135.886444 -408.860244)
			(xy 135.885974 -408.872317) (xy 135.878504 -408.89528) (xy 135.864307 -408.914813) (xy 135.844773 -408.929007)
			(xy 135.821809 -408.936475) (xy 135.809736 -408.936952) (xy 135.615172 -408.936952) (xy 135.604064 -408.936588)
			(xy 135.582768 -408.930264) (xy 135.573262 -408.924506) (xy 135.278368 -408.731974) (xy 135.268981 -408.726271)
			(xy 135.247943 -408.719998) (xy 135.225989 -408.719998) (xy 135.204951 -408.726271) (xy 135.195564 -408.731974)
			(xy 134.90194 -408.924506) (xy 134.892429 -408.930253) (xy 134.871136 -408.936579) (xy 134.86003 -408.936952)
			(xy 134.664196 -408.936952) (xy 134.652126 -408.93644) (xy 134.629166 -408.928982) (xy 134.609633 -408.914796)
			(xy 134.595437 -408.89527) (xy 134.587967 -408.872314) (xy 134.587488 -408.860244) (xy 132.823204 -408.860244)
			(xy 132.822773 -408.872321) (xy 132.815298 -408.895291) (xy 132.801093 -408.914827) (xy 132.781548 -408.92902)
			(xy 132.758574 -408.936481) (xy 132.746496 -408.936952) (xy 132.551932 -408.936952) (xy 132.540823 -408.936604)
			(xy 132.519527 -408.930269) (xy 132.510022 -408.924506) (xy 132.215128 -408.731974) (xy 132.205741 -408.726271)
			(xy 132.184703 -408.719998) (xy 132.162749 -408.719998) (xy 132.141711 -408.726271) (xy 132.132324 -408.731974)
			(xy 131.8387 -408.924506) (xy 131.829197 -408.930268) (xy 131.807898 -408.936585) (xy 131.79679 -408.936952)
			(xy 131.600956 -408.936952) (xy 131.588884 -408.936474) (xy 131.565922 -408.929005) (xy 131.54639 -408.91481)
			(xy 131.532195 -408.895278) (xy 131.524726 -408.872316) (xy 131.524248 -408.860244) (xy 129.759964 -408.860244)
			(xy 129.759573 -408.872325) (xy 129.752093 -408.895301) (xy 129.737879 -408.914842) (xy 129.718322 -408.929033)
			(xy 129.695338 -408.936487) (xy 129.683256 -408.936952) (xy 129.488692 -408.936952) (xy 129.477585 -408.93658)
			(xy 129.456288 -408.930262) (xy 129.446782 -408.924506) (xy 129.151888 -408.731974) (xy 129.142501 -408.726271)
			(xy 129.121463 -408.719998) (xy 129.099509 -408.719998) (xy 129.078471 -408.726271) (xy 129.069084 -408.731974)
			(xy 128.77546 -408.924506) (xy 128.765945 -408.930246) (xy 128.744655 -408.936577) (xy 128.73355 -408.936952)
			(xy 128.537716 -408.936952) (xy 128.525647 -408.936423) (xy 128.502687 -408.92897) (xy 128.483154 -408.914789)
			(xy 128.468957 -408.895266) (xy 128.461487 -408.872313) (xy 128.461008 -408.860244) (xy 126.696724 -408.860244)
			(xy 126.696274 -408.872319) (xy 126.688801 -408.895285) (xy 126.6746 -408.91482) (xy 126.65506 -408.929014)
			(xy 126.632091 -408.936478) (xy 126.620016 -408.936952) (xy 126.425452 -408.936952) (xy 126.414343 -408.936596)
			(xy 126.393047 -408.930267) (xy 126.383542 -408.924506) (xy 126.088648 -408.731974) (xy 126.079261 -408.726271)
			(xy 126.058223 -408.719998) (xy 126.036269 -408.719998) (xy 126.015231 -408.726271) (xy 126.005844 -408.731974)
			(xy 125.71222 -408.924506) (xy 125.702713 -408.930261) (xy 125.681417 -408.936582) (xy 125.67031 -408.936952)
			(xy 125.474476 -408.936952) (xy 125.462405 -408.936457) (xy 125.439444 -408.928993) (xy 125.419911 -408.914803)
			(xy 125.405716 -408.895274) (xy 125.398246 -408.872315) (xy 125.397768 -408.860244) (xy 123.633484 -408.860244)
			(xy 123.633073 -408.872323) (xy 123.625596 -408.895296) (xy 123.611386 -408.914834) (xy 123.591835 -408.929027)
			(xy 123.568856 -408.936484) (xy 123.556776 -408.936952) (xy 123.362212 -408.936952) (xy 123.351105 -408.936571)
			(xy 123.329809 -408.930259) (xy 123.320302 -408.924506) (xy 123.025408 -408.731974) (xy 123.016021 -408.726271)
			(xy 122.994983 -408.719998) (xy 122.973029 -408.719998) (xy 122.951991 -408.726271) (xy 122.942604 -408.731974)
			(xy 122.64898 -408.924506) (xy 122.639461 -408.930239) (xy 122.618174 -408.936574) (xy 122.60707 -408.936952)
			(xy 122.411236 -408.936952) (xy 122.399168 -408.936406) (xy 122.376209 -408.928959) (xy 122.356675 -408.914782)
			(xy 122.342478 -408.895263) (xy 122.335007 -408.872312) (xy 122.334528 -408.860244) (xy 120.570244 -408.860244)
			(xy 120.569774 -408.872317) (xy 120.562304 -408.89528) (xy 120.548107 -408.914813) (xy 120.528573 -408.929007)
			(xy 120.505609 -408.936475) (xy 120.493536 -408.936952) (xy 120.298972 -408.936952) (xy 120.287864 -408.936588)
			(xy 120.266568 -408.930264) (xy 120.257062 -408.924506) (xy 119.962168 -408.731974) (xy 119.952781 -408.726271)
			(xy 119.931743 -408.719998) (xy 119.909789 -408.719998) (xy 119.888751 -408.726271) (xy 119.879364 -408.731974)
			(xy 119.58574 -408.924506) (xy 119.576229 -408.930253) (xy 119.554936 -408.936579) (xy 119.54383 -408.936952)
			(xy 119.347996 -408.936952) (xy 119.335926 -408.93644) (xy 119.312966 -408.928982) (xy 119.293433 -408.914796)
			(xy 119.279237 -408.89527) (xy 119.271767 -408.872314) (xy 119.271288 -408.860244) (xy 117.507004 -408.860244)
			(xy 117.506573 -408.872321) (xy 117.499098 -408.895291) (xy 117.484893 -408.914827) (xy 117.465348 -408.92902)
			(xy 117.442374 -408.936481) (xy 117.430296 -408.936952) (xy 117.235732 -408.936952) (xy 117.224623 -408.936604)
			(xy 117.203327 -408.930269) (xy 117.193822 -408.924506) (xy 116.898928 -408.731974) (xy 116.889541 -408.726271)
			(xy 116.868503 -408.719998) (xy 116.846549 -408.719998) (xy 116.825511 -408.726271) (xy 116.816124 -408.731974)
			(xy 116.5225 -408.924506) (xy 116.512997 -408.930268) (xy 116.491698 -408.936585) (xy 116.48059 -408.936952)
			(xy 116.284756 -408.936952) (xy 116.272684 -408.936474) (xy 116.249722 -408.929005) (xy 116.23019 -408.91481)
			(xy 116.215995 -408.895278) (xy 116.208526 -408.872316) (xy 116.208048 -408.860244) (xy 111.277852 -408.860244)
			(xy 111.299015 -408.906582) (xy 111.31437 -408.958877) (xy 111.322126 -409.012825) (xy 111.322612 -409.040076)
			(xy 111.322612 -409.903676) (xy 111.322126 -409.930927) (xy 111.31437 -409.984875) (xy 111.299015 -410.03717)
			(xy 111.28975 -410.057456) (xy 116.044623 -410.057456) (xy 116.044623 -410.002944) (xy 116.052381 -409.948986)
			(xy 116.06774 -409.896681) (xy 116.090386 -409.847095) (xy 116.119859 -409.801237) (xy 116.155559 -409.76004)
			(xy 116.196758 -409.724344) (xy 116.242618 -409.694874) (xy 116.292206 -409.672231) (xy 116.344511 -409.656876)
			(xy 116.39847 -409.649121) (xy 116.425726 -409.64866) (xy 117.289326 -409.64866) (xy 117.316574 -409.649212)
			(xy 117.370514 -409.656971) (xy 117.422801 -409.672327) (xy 117.472371 -409.694968) (xy 117.518214 -409.724432)
			(xy 117.559398 -409.760121) (xy 117.595084 -409.801307) (xy 117.624545 -409.847152) (xy 117.647182 -409.896723)
			(xy 117.662535 -409.949011) (xy 117.67029 -410.002952) (xy 117.67029 -410.057448) (xy 117.670289 -410.057452)
			(xy 119.107946 -410.057452) (xy 119.107946 -410.002948) (xy 119.115702 -409.948999) (xy 119.131057 -409.896702)
			(xy 119.153697 -409.847123) (xy 119.183163 -409.801271) (xy 119.218854 -409.760078) (xy 119.260043 -409.724383)
			(xy 119.305893 -409.694914) (xy 119.35547 -409.672269) (xy 119.407765 -409.656909) (xy 119.461714 -409.649148)
			(xy 119.488966 -409.64866) (xy 120.352566 -409.64866) (xy 120.379818 -409.649185) (xy 120.433768 -409.656937)
			(xy 120.486066 -409.672289) (xy 120.535646 -409.694928) (xy 120.5815 -409.724392) (xy 120.622693 -409.760083)
			(xy 120.658387 -409.801273) (xy 120.687856 -409.847124) (xy 120.710499 -409.896702) (xy 120.725855 -409.948999)
			(xy 120.733613 -410.002948) (xy 120.733613 -410.057452) (xy 120.733613 -410.057455) (xy 122.171123 -410.057455)
			(xy 122.171123 -410.002945) (xy 122.178881 -409.948989) (xy 122.194238 -409.896686) (xy 122.216883 -409.847101)
			(xy 122.246354 -409.801244) (xy 122.282052 -409.760047) (xy 122.323249 -409.724351) (xy 122.369106 -409.69488)
			(xy 122.418691 -409.672236) (xy 122.470994 -409.656879) (xy 122.524951 -409.649123) (xy 122.552206 -409.64866)
			(xy 123.415806 -409.64866) (xy 123.443055 -409.649211) (xy 123.496997 -409.656967) (xy 123.549287 -409.672321)
			(xy 123.598859 -409.694961) (xy 123.644705 -409.724425) (xy 123.685891 -409.760113) (xy 123.721579 -409.8013)
			(xy 123.751042 -409.847146) (xy 123.773681 -409.896719) (xy 123.789034 -409.949009) (xy 123.79679 -410.002951)
			(xy 123.79679 -410.057449) (xy 123.796789 -410.057457) (xy 125.234323 -410.057457) (xy 125.234323 -410.002943)
			(xy 125.242082 -409.948983) (xy 125.257442 -409.896677) (xy 125.280089 -409.84709) (xy 125.309564 -409.801231)
			(xy 125.345266 -409.760033) (xy 125.386467 -409.724337) (xy 125.43233 -409.694867) (xy 125.48192 -409.672225)
			(xy 125.534228 -409.656872) (xy 125.588189 -409.64912) (xy 125.615446 -409.64866) (xy 126.479046 -409.64866)
			(xy 126.506293 -409.649213) (xy 126.560231 -409.656975) (xy 126.612516 -409.672332) (xy 126.662083 -409.694974)
			(xy 126.707924 -409.724439) (xy 126.749105 -409.760128) (xy 126.784788 -409.801313) (xy 126.814248 -409.847157)
			(xy 126.836884 -409.896727) (xy 126.852235 -409.949014) (xy 126.85999 -410.002953) (xy 126.85999 -410.057447)
			(xy 126.859989 -410.057453) (xy 128.297646 -410.057453) (xy 128.297646 -410.002947) (xy 128.305403 -409.948996)
			(xy 128.320758 -409.896698) (xy 128.3434 -409.847118) (xy 128.372868 -409.801264) (xy 128.408561 -409.760071)
			(xy 128.449753 -409.724376) (xy 128.495605 -409.694907) (xy 128.545185 -409.672263) (xy 128.597482 -409.656906)
			(xy 128.651433 -409.649147) (xy 128.678686 -409.64866) (xy 129.542286 -409.64866) (xy 129.569537 -409.649186)
			(xy 129.623485 -409.656941) (xy 129.67578 -409.672295) (xy 129.725358 -409.694934) (xy 129.771209 -409.724399)
			(xy 129.8124 -409.76009) (xy 129.848092 -409.80128) (xy 129.877559 -409.84713) (xy 129.900201 -409.896707)
			(xy 129.915556 -409.949001) (xy 129.923313 -410.002949) (xy 129.923313 -410.057451) (xy 129.923312 -410.057456)
			(xy 131.360823 -410.057456) (xy 131.360823 -410.002944) (xy 131.368581 -409.948986) (xy 131.38394 -409.896681)
			(xy 131.406586 -409.847095) (xy 131.436059 -409.801237) (xy 131.471759 -409.76004) (xy 131.512958 -409.724344)
			(xy 131.558818 -409.694874) (xy 131.608406 -409.672231) (xy 131.660711 -409.656876) (xy 131.71467 -409.649121)
			(xy 131.741926 -409.64866) (xy 132.605526 -409.64866) (xy 132.632774 -409.649212) (xy 132.686714 -409.656971)
			(xy 132.739001 -409.672327) (xy 132.788571 -409.694968) (xy 132.834414 -409.724432) (xy 132.875598 -409.760121)
			(xy 132.911284 -409.801307) (xy 132.940745 -409.847152) (xy 132.963382 -409.896723) (xy 132.978735 -409.949011)
			(xy 132.98649 -410.002952) (xy 132.98649 -410.057448) (xy 132.986489 -410.057452) (xy 134.424146 -410.057452)
			(xy 134.424146 -410.002948) (xy 134.431902 -409.948999) (xy 134.447257 -409.896702) (xy 134.469897 -409.847123)
			(xy 134.499363 -409.801271) (xy 134.535054 -409.760078) (xy 134.576243 -409.724383) (xy 134.622093 -409.694914)
			(xy 134.67167 -409.672269) (xy 134.723965 -409.656909) (xy 134.777914 -409.649148) (xy 134.805166 -409.64866)
			(xy 135.668766 -409.64866) (xy 135.696018 -409.649185) (xy 135.749968 -409.656937) (xy 135.802266 -409.672289)
			(xy 135.851846 -409.694928) (xy 135.8977 -409.724392) (xy 135.938893 -409.760083) (xy 135.974587 -409.801273)
			(xy 136.004056 -409.847124) (xy 136.026699 -409.896702) (xy 136.042055 -409.948999) (xy 136.049813 -410.002948)
			(xy 136.049813 -410.057452) (xy 136.049813 -410.057455) (xy 137.487323 -410.057455) (xy 137.487323 -410.002945)
			(xy 137.495081 -409.948989) (xy 137.510438 -409.896686) (xy 137.533083 -409.847101) (xy 137.562554 -409.801244)
			(xy 137.598252 -409.760047) (xy 137.639449 -409.724351) (xy 137.685306 -409.69488) (xy 137.734891 -409.672236)
			(xy 137.787194 -409.656879) (xy 137.841151 -409.649123) (xy 137.868406 -409.64866) (xy 138.732006 -409.64866)
			(xy 138.759255 -409.649211) (xy 138.813197 -409.656967) (xy 138.865487 -409.672321) (xy 138.915059 -409.694961)
			(xy 138.960905 -409.724425) (xy 139.002091 -409.760113) (xy 139.037779 -409.8013) (xy 139.067242 -409.847146)
			(xy 139.089881 -409.896719) (xy 139.105234 -409.949009) (xy 139.11299 -410.002951) (xy 139.11299 -410.057449)
			(xy 139.112989 -410.057457) (xy 140.550523 -410.057457) (xy 140.550523 -410.002943) (xy 140.558282 -409.948983)
			(xy 140.573642 -409.896677) (xy 140.596289 -409.84709) (xy 140.625764 -409.801231) (xy 140.661466 -409.760033)
			(xy 140.702667 -409.724337) (xy 140.74853 -409.694867) (xy 140.79812 -409.672225) (xy 140.850428 -409.656872)
			(xy 140.904389 -409.64912) (xy 140.931646 -409.64866) (xy 141.795246 -409.64866) (xy 141.822493 -409.649213)
			(xy 141.876431 -409.656975) (xy 141.928716 -409.672332) (xy 141.978283 -409.694974) (xy 142.024124 -409.724439)
			(xy 142.065305 -409.760128) (xy 142.100988 -409.801313) (xy 142.130448 -409.847157) (xy 142.153084 -409.896727)
			(xy 142.168435 -409.949014) (xy 142.17619 -410.002953) (xy 142.17619 -410.057447) (xy 142.176189 -410.057453)
			(xy 143.613846 -410.057453) (xy 143.613846 -410.002947) (xy 143.621603 -409.948996) (xy 143.636958 -409.896698)
			(xy 143.6596 -409.847118) (xy 143.689068 -409.801264) (xy 143.724761 -409.760071) (xy 143.765953 -409.724376)
			(xy 143.811805 -409.694907) (xy 143.861385 -409.672263) (xy 143.913682 -409.656906) (xy 143.967633 -409.649147)
			(xy 143.994886 -409.64866) (xy 144.858486 -409.64866) (xy 144.885737 -409.649186) (xy 144.939685 -409.656941)
			(xy 144.99198 -409.672295) (xy 145.041558 -409.694934) (xy 145.087409 -409.724399) (xy 145.1286 -409.76009)
			(xy 145.164292 -409.80128) (xy 145.193759 -409.84713) (xy 145.216401 -409.896707) (xy 145.231756 -409.949001)
			(xy 145.239513 -410.002949) (xy 145.239513 -410.057451) (xy 145.239512 -410.057456) (xy 146.677023 -410.057456)
			(xy 146.677023 -410.002944) (xy 146.684781 -409.948986) (xy 146.70014 -409.896681) (xy 146.722786 -409.847095)
			(xy 146.752259 -409.801237) (xy 146.787959 -409.76004) (xy 146.829158 -409.724344) (xy 146.875018 -409.694874)
			(xy 146.924606 -409.672231) (xy 146.976911 -409.656876) (xy 147.03087 -409.649121) (xy 147.058126 -409.64866)
			(xy 147.921726 -409.64866) (xy 147.948974 -409.649212) (xy 148.002914 -409.656971) (xy 148.055201 -409.672327)
			(xy 148.104771 -409.694968) (xy 148.150614 -409.724432) (xy 148.191798 -409.760121) (xy 148.227484 -409.801307)
			(xy 148.256945 -409.847152) (xy 148.279582 -409.896723) (xy 148.294935 -409.949011) (xy 148.30269 -410.002952)
			(xy 148.30269 -410.057448) (xy 148.302689 -410.057452) (xy 149.740346 -410.057452) (xy 149.740346 -410.002948)
			(xy 149.748102 -409.948999) (xy 149.763457 -409.896702) (xy 149.786097 -409.847123) (xy 149.815563 -409.801271)
			(xy 149.851254 -409.760078) (xy 149.892443 -409.724383) (xy 149.938293 -409.694914) (xy 149.98787 -409.672269)
			(xy 150.040165 -409.656909) (xy 150.094114 -409.649148) (xy 150.121366 -409.64866) (xy 150.984966 -409.64866)
			(xy 151.012218 -409.649185) (xy 151.066168 -409.656937) (xy 151.118466 -409.672289) (xy 151.168046 -409.694928)
			(xy 151.2139 -409.724392) (xy 151.255093 -409.760083) (xy 151.290787 -409.801273) (xy 151.320256 -409.847124)
			(xy 151.342899 -409.896702) (xy 151.358255 -409.948999) (xy 151.366013 -410.002948) (xy 151.366013 -410.057452)
			(xy 151.366013 -410.057455) (xy 152.803523 -410.057455) (xy 152.803523 -410.002945) (xy 152.811281 -409.948989)
			(xy 152.826638 -409.896686) (xy 152.849283 -409.847101) (xy 152.878754 -409.801244) (xy 152.914452 -409.760047)
			(xy 152.955649 -409.724351) (xy 153.001506 -409.69488) (xy 153.051091 -409.672236) (xy 153.103394 -409.656879)
			(xy 153.157351 -409.649123) (xy 153.184606 -409.64866) (xy 154.048206 -409.64866) (xy 154.075455 -409.649211)
			(xy 154.129397 -409.656967) (xy 154.181687 -409.672321) (xy 154.231259 -409.694961) (xy 154.277105 -409.724425)
			(xy 154.318291 -409.760113) (xy 154.353979 -409.8013) (xy 154.383442 -409.847146) (xy 154.406081 -409.896719)
			(xy 154.421434 -409.949009) (xy 154.42919 -410.002951) (xy 154.42919 -410.057449) (xy 154.429189 -410.057457)
			(xy 155.866723 -410.057457) (xy 155.866723 -410.002943) (xy 155.874482 -409.948983) (xy 155.889842 -409.896677)
			(xy 155.912489 -409.84709) (xy 155.941964 -409.801231) (xy 155.977666 -409.760033) (xy 156.018867 -409.724337)
			(xy 156.06473 -409.694867) (xy 156.11432 -409.672225) (xy 156.166628 -409.656872) (xy 156.220589 -409.64912)
			(xy 156.247846 -409.64866) (xy 157.111446 -409.64866) (xy 157.138693 -409.649213) (xy 157.192631 -409.656975)
			(xy 157.244916 -409.672332) (xy 157.294483 -409.694974) (xy 157.340324 -409.724439) (xy 157.381505 -409.760128)
			(xy 157.417188 -409.801313) (xy 157.446648 -409.847157) (xy 157.469284 -409.896727) (xy 157.484635 -409.949014)
			(xy 157.49239 -410.002953) (xy 157.49239 -410.057447) (xy 157.492389 -410.057453) (xy 158.930046 -410.057453)
			(xy 158.930046 -410.002947) (xy 158.937803 -409.948996) (xy 158.953158 -409.896698) (xy 158.9758 -409.847118)
			(xy 159.005268 -409.801264) (xy 159.040961 -409.760071) (xy 159.082153 -409.724376) (xy 159.128005 -409.694907)
			(xy 159.177585 -409.672263) (xy 159.229882 -409.656906) (xy 159.283833 -409.649147) (xy 159.311086 -409.64866)
			(xy 160.174686 -409.64866) (xy 160.201937 -409.649186) (xy 160.255885 -409.656941) (xy 160.30818 -409.672295)
			(xy 160.357758 -409.694934) (xy 160.403609 -409.724399) (xy 160.4448 -409.76009) (xy 160.480492 -409.80128)
			(xy 160.509959 -409.84713) (xy 160.532601 -409.896707) (xy 160.547956 -409.949001) (xy 160.555713 -410.002949)
			(xy 160.555713 -410.057451) (xy 160.555712 -410.057456) (xy 161.993223 -410.057456) (xy 161.993223 -410.002944)
			(xy 162.000981 -409.948986) (xy 162.01634 -409.896681) (xy 162.038986 -409.847095) (xy 162.068459 -409.801237)
			(xy 162.104159 -409.76004) (xy 162.145358 -409.724344) (xy 162.191218 -409.694874) (xy 162.240806 -409.672231)
			(xy 162.293111 -409.656876) (xy 162.34707 -409.649121) (xy 162.374326 -409.64866) (xy 163.237926 -409.64866)
			(xy 163.265174 -409.649212) (xy 163.319114 -409.656971) (xy 163.371401 -409.672327) (xy 163.420971 -409.694968)
			(xy 163.466814 -409.724432) (xy 163.507998 -409.760121) (xy 163.543684 -409.801307) (xy 163.573145 -409.847152)
			(xy 163.595782 -409.896723) (xy 163.611135 -409.949011) (xy 163.61889 -410.002952) (xy 163.61889 -410.057448)
			(xy 163.611135 -410.111389) (xy 163.595782 -410.163677) (xy 163.573145 -410.213248) (xy 163.543684 -410.259093)
			(xy 163.507998 -410.300279) (xy 163.466814 -410.335968) (xy 163.420971 -410.365432) (xy 163.371401 -410.388073)
			(xy 163.319114 -410.403429) (xy 163.265174 -410.411188) (xy 163.237926 -410.411676) (xy 162.374326 -410.411676)
			(xy 162.34707 -410.411279) (xy 162.293111 -410.403524) (xy 162.240806 -410.388169) (xy 162.191218 -410.365526)
			(xy 162.145358 -410.336056) (xy 162.104159 -410.30036) (xy 162.068459 -410.259163) (xy 162.038986 -410.213305)
			(xy 162.01634 -410.163719) (xy 162.000981 -410.111414) (xy 161.993223 -410.057456) (xy 160.555712 -410.057456)
			(xy 160.547956 -410.111399) (xy 160.532601 -410.163693) (xy 160.509959 -410.21327) (xy 160.480492 -410.25912)
			(xy 160.4448 -410.30031) (xy 160.403609 -410.336001) (xy 160.357758 -410.365466) (xy 160.30818 -410.388105)
			(xy 160.255885 -410.403459) (xy 160.201937 -410.411214) (xy 160.174686 -410.411676) (xy 159.311086 -410.411676)
			(xy 159.283833 -410.411253) (xy 159.229882 -410.403494) (xy 159.177585 -410.388137) (xy 159.128005 -410.365493)
			(xy 159.082153 -410.336024) (xy 159.040961 -410.300329) (xy 159.005268 -410.259136) (xy 158.9758 -410.213282)
			(xy 158.953158 -410.163702) (xy 158.937803 -410.111404) (xy 158.930046 -410.057453) (xy 157.492389 -410.057453)
			(xy 157.484635 -410.111386) (xy 157.469284 -410.163673) (xy 157.446648 -410.213243) (xy 157.417188 -410.259087)
			(xy 157.381505 -410.300272) (xy 157.340324 -410.335961) (xy 157.294483 -410.365426) (xy 157.244916 -410.388068)
			(xy 157.192631 -410.403425) (xy 157.138693 -410.411187) (xy 157.111446 -410.411676) (xy 156.247846 -410.411676)
			(xy 156.220589 -410.41128) (xy 156.166628 -410.403528) (xy 156.11432 -410.388175) (xy 156.06473 -410.365533)
			(xy 156.018867 -410.336063) (xy 155.977666 -410.300367) (xy 155.941964 -410.259169) (xy 155.912489 -410.21331)
			(xy 155.889842 -410.163723) (xy 155.874482 -410.111417) (xy 155.866723 -410.057457) (xy 154.429189 -410.057457)
			(xy 154.421434 -410.111391) (xy 154.406081 -410.163681) (xy 154.383442 -410.213254) (xy 154.353979 -410.2591)
			(xy 154.318291 -410.300287) (xy 154.277105 -410.335975) (xy 154.231259 -410.365439) (xy 154.181687 -410.388079)
			(xy 154.129397 -410.403433) (xy 154.075455 -410.411189) (xy 154.048206 -410.411676) (xy 153.184606 -410.411676)
			(xy 153.157351 -410.411277) (xy 153.103394 -410.403521) (xy 153.051091 -410.388164) (xy 153.001506 -410.36552)
			(xy 152.955649 -410.336049) (xy 152.914452 -410.300353) (xy 152.878754 -410.259156) (xy 152.849283 -410.213299)
			(xy 152.826638 -410.163714) (xy 152.811281 -410.111411) (xy 152.803523 -410.057455) (xy 151.366013 -410.057455)
			(xy 151.358255 -410.111402) (xy 151.342899 -410.163698) (xy 151.320256 -410.213276) (xy 151.290787 -410.259127)
			(xy 151.255093 -410.300317) (xy 151.2139 -410.336008) (xy 151.168046 -410.365472) (xy 151.118466 -410.388111)
			(xy 151.066168 -410.403463) (xy 151.012218 -410.411215) (xy 150.984966 -410.411676) (xy 150.121366 -410.411676)
			(xy 150.094114 -410.411252) (xy 150.040165 -410.403491) (xy 149.98787 -410.388131) (xy 149.938293 -410.365486)
			(xy 149.892443 -410.336017) (xy 149.851254 -410.300322) (xy 149.815563 -410.259129) (xy 149.786097 -410.213277)
			(xy 149.763457 -410.163698) (xy 149.748102 -410.111401) (xy 149.740346 -410.057452) (xy 148.302689 -410.057452)
			(xy 148.294935 -410.111389) (xy 148.279582 -410.163677) (xy 148.256945 -410.213248) (xy 148.227484 -410.259093)
			(xy 148.191798 -410.300279) (xy 148.150614 -410.335968) (xy 148.104771 -410.365432) (xy 148.055201 -410.388073)
			(xy 148.002914 -410.403429) (xy 147.948974 -410.411188) (xy 147.921726 -410.411676) (xy 147.058126 -410.411676)
			(xy 147.03087 -410.411279) (xy 146.976911 -410.403524) (xy 146.924606 -410.388169) (xy 146.875018 -410.365526)
			(xy 146.829158 -410.336056) (xy 146.787959 -410.30036) (xy 146.752259 -410.259163) (xy 146.722786 -410.213305)
			(xy 146.70014 -410.163719) (xy 146.684781 -410.111414) (xy 146.677023 -410.057456) (xy 145.239512 -410.057456)
			(xy 145.231756 -410.111399) (xy 145.216401 -410.163693) (xy 145.193759 -410.21327) (xy 145.164292 -410.25912)
			(xy 145.1286 -410.30031) (xy 145.087409 -410.336001) (xy 145.041558 -410.365466) (xy 144.99198 -410.388105)
			(xy 144.939685 -410.403459) (xy 144.885737 -410.411214) (xy 144.858486 -410.411676) (xy 143.994886 -410.411676)
			(xy 143.967633 -410.411253) (xy 143.913682 -410.403494) (xy 143.861385 -410.388137) (xy 143.811805 -410.365493)
			(xy 143.765953 -410.336024) (xy 143.724761 -410.300329) (xy 143.689068 -410.259136) (xy 143.6596 -410.213282)
			(xy 143.636958 -410.163702) (xy 143.621603 -410.111404) (xy 143.613846 -410.057453) (xy 142.176189 -410.057453)
			(xy 142.168435 -410.111386) (xy 142.153084 -410.163673) (xy 142.130448 -410.213243) (xy 142.100988 -410.259087)
			(xy 142.065305 -410.300272) (xy 142.024124 -410.335961) (xy 141.978283 -410.365426) (xy 141.928716 -410.388068)
			(xy 141.876431 -410.403425) (xy 141.822493 -410.411187) (xy 141.795246 -410.411676) (xy 140.931646 -410.411676)
			(xy 140.904389 -410.41128) (xy 140.850428 -410.403528) (xy 140.79812 -410.388175) (xy 140.74853 -410.365533)
			(xy 140.702667 -410.336063) (xy 140.661466 -410.300367) (xy 140.625764 -410.259169) (xy 140.596289 -410.21331)
			(xy 140.573642 -410.163723) (xy 140.558282 -410.111417) (xy 140.550523 -410.057457) (xy 139.112989 -410.057457)
			(xy 139.105234 -410.111391) (xy 139.089881 -410.163681) (xy 139.067242 -410.213254) (xy 139.037779 -410.2591)
			(xy 139.002091 -410.300287) (xy 138.960905 -410.335975) (xy 138.915059 -410.365439) (xy 138.865487 -410.388079)
			(xy 138.813197 -410.403433) (xy 138.759255 -410.411189) (xy 138.732006 -410.411676) (xy 137.868406 -410.411676)
			(xy 137.841151 -410.411277) (xy 137.787194 -410.403521) (xy 137.734891 -410.388164) (xy 137.685306 -410.36552)
			(xy 137.639449 -410.336049) (xy 137.598252 -410.300353) (xy 137.562554 -410.259156) (xy 137.533083 -410.213299)
			(xy 137.510438 -410.163714) (xy 137.495081 -410.111411) (xy 137.487323 -410.057455) (xy 136.049813 -410.057455)
			(xy 136.042055 -410.111402) (xy 136.026699 -410.163698) (xy 136.004056 -410.213276) (xy 135.974587 -410.259127)
			(xy 135.938893 -410.300317) (xy 135.8977 -410.336008) (xy 135.851846 -410.365472) (xy 135.802266 -410.388111)
			(xy 135.749968 -410.403463) (xy 135.696018 -410.411215) (xy 135.668766 -410.411676) (xy 134.805166 -410.411676)
			(xy 134.777914 -410.411252) (xy 134.723965 -410.403491) (xy 134.67167 -410.388131) (xy 134.622093 -410.365486)
			(xy 134.576243 -410.336017) (xy 134.535054 -410.300322) (xy 134.499363 -410.259129) (xy 134.469897 -410.213277)
			(xy 134.447257 -410.163698) (xy 134.431902 -410.111401) (xy 134.424146 -410.057452) (xy 132.986489 -410.057452)
			(xy 132.978735 -410.111389) (xy 132.963382 -410.163677) (xy 132.940745 -410.213248) (xy 132.911284 -410.259093)
			(xy 132.875598 -410.300279) (xy 132.834414 -410.335968) (xy 132.788571 -410.365432) (xy 132.739001 -410.388073)
			(xy 132.686714 -410.403429) (xy 132.632774 -410.411188) (xy 132.605526 -410.411676) (xy 131.741926 -410.411676)
			(xy 131.71467 -410.411279) (xy 131.660711 -410.403524) (xy 131.608406 -410.388169) (xy 131.558818 -410.365526)
			(xy 131.512958 -410.336056) (xy 131.471759 -410.30036) (xy 131.436059 -410.259163) (xy 131.406586 -410.213305)
			(xy 131.38394 -410.163719) (xy 131.368581 -410.111414) (xy 131.360823 -410.057456) (xy 129.923312 -410.057456)
			(xy 129.915556 -410.111399) (xy 129.900201 -410.163693) (xy 129.877559 -410.21327) (xy 129.848092 -410.25912)
			(xy 129.8124 -410.30031) (xy 129.771209 -410.336001) (xy 129.725358 -410.365466) (xy 129.67578 -410.388105)
			(xy 129.623485 -410.403459) (xy 129.569537 -410.411214) (xy 129.542286 -410.411676) (xy 128.678686 -410.411676)
			(xy 128.651433 -410.411253) (xy 128.597482 -410.403494) (xy 128.545185 -410.388137) (xy 128.495605 -410.365493)
			(xy 128.449753 -410.336024) (xy 128.408561 -410.300329) (xy 128.372868 -410.259136) (xy 128.3434 -410.213282)
			(xy 128.320758 -410.163702) (xy 128.305403 -410.111404) (xy 128.297646 -410.057453) (xy 126.859989 -410.057453)
			(xy 126.852235 -410.111386) (xy 126.836884 -410.163673) (xy 126.814248 -410.213243) (xy 126.784788 -410.259087)
			(xy 126.749105 -410.300272) (xy 126.707924 -410.335961) (xy 126.662083 -410.365426) (xy 126.612516 -410.388068)
			(xy 126.560231 -410.403425) (xy 126.506293 -410.411187) (xy 126.479046 -410.411676) (xy 125.615446 -410.411676)
			(xy 125.588189 -410.41128) (xy 125.534228 -410.403528) (xy 125.48192 -410.388175) (xy 125.43233 -410.365533)
			(xy 125.386467 -410.336063) (xy 125.345266 -410.300367) (xy 125.309564 -410.259169) (xy 125.280089 -410.21331)
			(xy 125.257442 -410.163723) (xy 125.242082 -410.111417) (xy 125.234323 -410.057457) (xy 123.796789 -410.057457)
			(xy 123.789034 -410.111391) (xy 123.773681 -410.163681) (xy 123.751042 -410.213254) (xy 123.721579 -410.2591)
			(xy 123.685891 -410.300287) (xy 123.644705 -410.335975) (xy 123.598859 -410.365439) (xy 123.549287 -410.388079)
			(xy 123.496997 -410.403433) (xy 123.443055 -410.411189) (xy 123.415806 -410.411676) (xy 122.552206 -410.411676)
			(xy 122.524951 -410.411277) (xy 122.470994 -410.403521) (xy 122.418691 -410.388164) (xy 122.369106 -410.36552)
			(xy 122.323249 -410.336049) (xy 122.282052 -410.300353) (xy 122.246354 -410.259156) (xy 122.216883 -410.213299)
			(xy 122.194238 -410.163714) (xy 122.178881 -410.111411) (xy 122.171123 -410.057455) (xy 120.733613 -410.057455)
			(xy 120.725855 -410.111402) (xy 120.710499 -410.163698) (xy 120.687856 -410.213276) (xy 120.658387 -410.259127)
			(xy 120.622693 -410.300317) (xy 120.5815 -410.336008) (xy 120.535646 -410.365472) (xy 120.486066 -410.388111)
			(xy 120.433768 -410.403463) (xy 120.379818 -410.411215) (xy 120.352566 -410.411676) (xy 119.488966 -410.411676)
			(xy 119.461714 -410.411252) (xy 119.407765 -410.403491) (xy 119.35547 -410.388131) (xy 119.305893 -410.365486)
			(xy 119.260043 -410.336017) (xy 119.218854 -410.300322) (xy 119.183163 -410.259129) (xy 119.153697 -410.213277)
			(xy 119.131057 -410.163698) (xy 119.115702 -410.111401) (xy 119.107946 -410.057452) (xy 117.670289 -410.057452)
			(xy 117.662535 -410.111389) (xy 117.647182 -410.163677) (xy 117.624545 -410.213248) (xy 117.595084 -410.259093)
			(xy 117.559398 -410.300279) (xy 117.518214 -410.335968) (xy 117.472371 -410.365432) (xy 117.422801 -410.388073)
			(xy 117.370514 -410.403429) (xy 117.316574 -410.411188) (xy 117.289326 -410.411676) (xy 116.425726 -410.411676)
			(xy 116.39847 -410.411279) (xy 116.344511 -410.403524) (xy 116.292206 -410.388169) (xy 116.242618 -410.365526)
			(xy 116.196758 -410.336056) (xy 116.155559 -410.30036) (xy 116.119859 -410.259163) (xy 116.090386 -410.213305)
			(xy 116.06774 -410.163719) (xy 116.052381 -410.111414) (xy 116.044623 -410.057456) (xy 111.28975 -410.057456)
			(xy 111.276373 -410.086747) (xy 111.246907 -410.132597) (xy 111.211216 -410.173788) (xy 111.170025 -410.209479)
			(xy 111.124175 -410.238945) (xy 111.074598 -410.261587) (xy 111.022303 -410.276942) (xy 110.968355 -410.284698)
			(xy 110.913853 -410.284698) (xy 110.859905 -410.276942) (xy 110.80761 -410.261587) (xy 110.758033 -410.238945)
			(xy 110.712183 -410.209479) (xy 110.670992 -410.173788) (xy 110.635301 -410.132597) (xy 110.605835 -410.086747)
			(xy 110.583193 -410.03717) (xy 110.567838 -409.984875) (xy 110.560082 -409.930927) (xy 110.559596 -409.903676)
			(xy 102.748244 -409.903676) (xy 102.708181 -409.921973) (xy 102.655851 -409.937338) (xy 102.601867 -409.9451)
			(xy 102.547329 -409.9451) (xy 102.493345 -409.937338) (xy 102.441015 -409.921973) (xy 102.391405 -409.899316)
			(xy 102.345524 -409.86983) (xy 102.304307 -409.834115) (xy 102.268592 -409.792898) (xy 102.239106 -409.747017)
			(xy 102.216449 -409.697407) (xy 102.201084 -409.645077) (xy 102.193322 -409.591093) (xy 102.192836 -409.563824)
			(xy 7.00913 -409.563824) (xy 7.00913 -410.057453) (xy 48.944746 -410.057453) (xy 48.944746 -410.002947)
			(xy 48.952503 -409.948996) (xy 48.967858 -409.896698) (xy 48.9905 -409.847118) (xy 49.019967 -409.801265)
			(xy 49.05566 -409.760071) (xy 49.096852 -409.724377) (xy 49.142704 -409.694908) (xy 49.192283 -409.672264)
			(xy 49.244581 -409.656906) (xy 49.298531 -409.649147) (xy 49.325784 -409.64866) (xy 50.189384 -409.64866)
			(xy 50.216635 -409.649186) (xy 50.270583 -409.656941) (xy 50.322879 -409.672294) (xy 50.372457 -409.694934)
			(xy 50.418308 -409.724399) (xy 50.459499 -409.760089) (xy 50.495192 -409.801279) (xy 50.524659 -409.847129)
			(xy 50.5473 -409.896706) (xy 50.562656 -409.949001) (xy 50.570413 -410.002949) (xy 50.570413 -410.057451)
			(xy 50.570412 -410.057456) (xy 52.007923 -410.057456) (xy 52.007923 -410.002944) (xy 52.015681 -409.948986)
			(xy 52.03104 -409.896682) (xy 52.053686 -409.847096) (xy 52.083159 -409.801238) (xy 52.118858 -409.760041)
			(xy 52.160057 -409.724344) (xy 52.205917 -409.694874) (xy 52.255504 -409.672231) (xy 52.30781 -409.656876)
			(xy 52.361768 -409.649121) (xy 52.389024 -409.64866) (xy 53.252624 -409.64866) (xy 53.279872 -409.649212)
			(xy 53.333812 -409.65697) (xy 53.3861 -409.672326) (xy 53.43567 -409.694967) (xy 53.481513 -409.724431)
			(xy 53.522697 -409.76012) (xy 53.558383 -409.801306) (xy 53.587845 -409.847151) (xy 53.610482 -409.896723)
			(xy 53.625835 -409.949011) (xy 53.63359 -410.002952) (xy 53.63359 -410.057448) (xy 53.633589 -410.057452)
			(xy 55.071246 -410.057452) (xy 55.071246 -410.002948) (xy 55.079002 -409.948999) (xy 55.094357 -409.896703)
			(xy 55.116997 -409.847124) (xy 55.146462 -409.801271) (xy 55.182153 -409.760079) (xy 55.223342 -409.724384)
			(xy 55.269192 -409.694914) (xy 55.318769 -409.672269) (xy 55.371064 -409.65691) (xy 55.425012 -409.649148)
			(xy 55.452264 -409.64866) (xy 56.315864 -409.64866) (xy 56.343116 -409.649185) (xy 56.397067 -409.656937)
			(xy 56.449364 -409.672289) (xy 56.498945 -409.694927) (xy 56.544799 -409.724392) (xy 56.585992 -409.760082)
			(xy 56.621687 -409.801273) (xy 56.651156 -409.847124) (xy 56.673799 -409.896702) (xy 56.689155 -409.948998)
			(xy 56.696913 -410.002948) (xy 56.696913 -410.057452) (xy 56.696913 -410.057455) (xy 58.134423 -410.057455)
			(xy 58.134423 -410.002945) (xy 58.142181 -409.948989) (xy 58.157538 -409.896686) (xy 58.180183 -409.847102)
			(xy 58.209654 -409.801244) (xy 58.245351 -409.760048) (xy 58.286548 -409.724351) (xy 58.332405 -409.694881)
			(xy 58.38199 -409.672237) (xy 58.434293 -409.65688) (xy 58.488249 -409.649123) (xy 58.515504 -409.64866)
			(xy 59.379104 -409.64866) (xy 59.406353 -409.64921) (xy 59.460295 -409.656967) (xy 59.512585 -409.672321)
			(xy 59.562158 -409.69496) (xy 59.608004 -409.724424) (xy 59.64919 -409.760113) (xy 59.684878 -409.801299)
			(xy 59.714342 -409.847146) (xy 59.73698 -409.896718) (xy 59.752334 -409.949008) (xy 59.76009 -410.002951)
			(xy 59.76009 -410.057449) (xy 59.760089 -410.057457) (xy 61.197623 -410.057457) (xy 61.197623 -410.002943)
			(xy 61.205382 -409.948983) (xy 61.220741 -409.896678) (xy 61.243389 -409.84709) (xy 61.272864 -409.801231)
			(xy 61.308565 -409.760034) (xy 61.349767 -409.724337) (xy 61.395629 -409.694868) (xy 61.445219 -409.672226)
			(xy 61.497527 -409.656872) (xy 61.551487 -409.64912) (xy 61.578744 -409.64866) (xy 62.442344 -409.64866)
			(xy 62.469591 -409.649213) (xy 62.523529 -409.656974) (xy 62.575814 -409.672332) (xy 62.625382 -409.694973)
			(xy 62.671223 -409.724438) (xy 62.712404 -409.760127) (xy 62.748088 -409.801313) (xy 62.777548 -409.847157)
			(xy 62.800184 -409.896727) (xy 62.815535 -409.949014) (xy 62.82329 -410.002953) (xy 62.82329 -410.057447)
			(xy 62.823289 -410.057453) (xy 64.260946 -410.057453) (xy 64.260946 -410.002947) (xy 64.268703 -409.948996)
			(xy 64.284058 -409.896698) (xy 64.3067 -409.847118) (xy 64.336167 -409.801265) (xy 64.37186 -409.760071)
			(xy 64.413052 -409.724377) (xy 64.458904 -409.694908) (xy 64.508483 -409.672264) (xy 64.560781 -409.656906)
			(xy 64.614731 -409.649147) (xy 64.641984 -409.64866) (xy 65.505584 -409.64866) (xy 65.532835 -409.649186)
			(xy 65.586783 -409.656941) (xy 65.639079 -409.672294) (xy 65.688657 -409.694934) (xy 65.734508 -409.724399)
			(xy 65.775699 -409.760089) (xy 65.811392 -409.801279) (xy 65.840859 -409.847129) (xy 65.8635 -409.896706)
			(xy 65.878856 -409.949001) (xy 65.886613 -410.002949) (xy 65.886613 -410.057451) (xy 65.886612 -410.057456)
			(xy 67.324123 -410.057456) (xy 67.324123 -410.002944) (xy 67.331881 -409.948986) (xy 67.34724 -409.896682)
			(xy 67.369886 -409.847096) (xy 67.399359 -409.801238) (xy 67.435058 -409.760041) (xy 67.476257 -409.724344)
			(xy 67.522117 -409.694874) (xy 67.571704 -409.672231) (xy 67.62401 -409.656876) (xy 67.677968 -409.649121)
			(xy 67.705224 -409.64866) (xy 68.568824 -409.64866) (xy 68.596072 -409.649212) (xy 68.650012 -409.65697)
			(xy 68.7023 -409.672326) (xy 68.75187 -409.694967) (xy 68.797713 -409.724431) (xy 68.838897 -409.76012)
			(xy 68.874583 -409.801306) (xy 68.904045 -409.847151) (xy 68.926682 -409.896723) (xy 68.942035 -409.949011)
			(xy 68.94979 -410.002952) (xy 68.94979 -410.057448) (xy 68.949789 -410.057452) (xy 70.387446 -410.057452)
			(xy 70.387446 -410.002948) (xy 70.395202 -409.948999) (xy 70.410557 -409.896703) (xy 70.433197 -409.847124)
			(xy 70.462662 -409.801271) (xy 70.498353 -409.760079) (xy 70.539542 -409.724384) (xy 70.585392 -409.694914)
			(xy 70.634969 -409.672269) (xy 70.687264 -409.65691) (xy 70.741212 -409.649148) (xy 70.768464 -409.64866)
			(xy 71.632064 -409.64866) (xy 71.659316 -409.649185) (xy 71.713267 -409.656937) (xy 71.765564 -409.672289)
			(xy 71.815145 -409.694927) (xy 71.860999 -409.724392) (xy 71.902192 -409.760082) (xy 71.937887 -409.801273)
			(xy 71.967356 -409.847124) (xy 71.989999 -409.896702) (xy 72.005355 -409.948998) (xy 72.013113 -410.002948)
			(xy 72.013113 -410.057452) (xy 72.013113 -410.057455) (xy 73.450623 -410.057455) (xy 73.450623 -410.002945)
			(xy 73.458381 -409.948989) (xy 73.473738 -409.896686) (xy 73.496383 -409.847102) (xy 73.525854 -409.801244)
			(xy 73.561551 -409.760048) (xy 73.602748 -409.724351) (xy 73.648605 -409.694881) (xy 73.69819 -409.672237)
			(xy 73.750493 -409.65688) (xy 73.804449 -409.649123) (xy 73.831704 -409.64866) (xy 74.695304 -409.64866)
			(xy 74.722553 -409.64921) (xy 74.776495 -409.656967) (xy 74.828785 -409.672321) (xy 74.878358 -409.69496)
			(xy 74.924204 -409.724424) (xy 74.96539 -409.760113) (xy 75.001078 -409.801299) (xy 75.030542 -409.847146)
			(xy 75.05318 -409.896718) (xy 75.068534 -409.949008) (xy 75.07629 -410.002951) (xy 75.07629 -410.057449)
			(xy 75.076289 -410.057457) (xy 76.513823 -410.057457) (xy 76.513823 -410.002943) (xy 76.521582 -409.948983)
			(xy 76.536941 -409.896678) (xy 76.559589 -409.84709) (xy 76.589064 -409.801231) (xy 76.624765 -409.760034)
			(xy 76.665967 -409.724337) (xy 76.711829 -409.694868) (xy 76.761419 -409.672226) (xy 76.813727 -409.656872)
			(xy 76.867687 -409.64912) (xy 76.894944 -409.64866) (xy 77.758544 -409.64866) (xy 77.785791 -409.649213)
			(xy 77.839729 -409.656974) (xy 77.892014 -409.672332) (xy 77.941582 -409.694973) (xy 77.987423 -409.724438)
			(xy 78.028604 -409.760127) (xy 78.064288 -409.801313) (xy 78.093748 -409.847157) (xy 78.116384 -409.896727)
			(xy 78.131735 -409.949014) (xy 78.13949 -410.002953) (xy 78.13949 -410.057447) (xy 78.139489 -410.057453)
			(xy 79.577146 -410.057453) (xy 79.577146 -410.002947) (xy 79.584903 -409.948996) (xy 79.600258 -409.896698)
			(xy 79.6229 -409.847118) (xy 79.652367 -409.801265) (xy 79.68806 -409.760071) (xy 79.729252 -409.724377)
			(xy 79.775104 -409.694908) (xy 79.824683 -409.672264) (xy 79.876981 -409.656906) (xy 79.930931 -409.649147)
			(xy 79.958184 -409.64866) (xy 80.821784 -409.64866) (xy 80.849035 -409.649186) (xy 80.902983 -409.656941)
			(xy 80.955279 -409.672294) (xy 81.004857 -409.694934) (xy 81.050708 -409.724399) (xy 81.091899 -409.760089)
			(xy 81.127592 -409.801279) (xy 81.157059 -409.847129) (xy 81.1797 -409.896706) (xy 81.195056 -409.949001)
			(xy 81.202813 -410.002949) (xy 81.202813 -410.057451) (xy 81.202812 -410.057456) (xy 82.640323 -410.057456)
			(xy 82.640323 -410.002944) (xy 82.648081 -409.948986) (xy 82.66344 -409.896682) (xy 82.686086 -409.847096)
			(xy 82.715559 -409.801238) (xy 82.751258 -409.760041) (xy 82.792457 -409.724344) (xy 82.838317 -409.694874)
			(xy 82.887904 -409.672231) (xy 82.94021 -409.656876) (xy 82.994168 -409.649121) (xy 83.021424 -409.64866)
			(xy 83.885024 -409.64866) (xy 83.912272 -409.649212) (xy 83.966212 -409.65697) (xy 84.0185 -409.672326)
			(xy 84.06807 -409.694967) (xy 84.113913 -409.724431) (xy 84.155097 -409.76012) (xy 84.190783 -409.801306)
			(xy 84.220245 -409.847151) (xy 84.242882 -409.896723) (xy 84.258235 -409.949011) (xy 84.26599 -410.002952)
			(xy 84.26599 -410.057448) (xy 84.265989 -410.057452) (xy 85.703646 -410.057452) (xy 85.703646 -410.002948)
			(xy 85.711402 -409.948999) (xy 85.726757 -409.896703) (xy 85.749397 -409.847124) (xy 85.778862 -409.801271)
			(xy 85.814553 -409.760079) (xy 85.855742 -409.724384) (xy 85.901592 -409.694914) (xy 85.951169 -409.672269)
			(xy 86.003464 -409.65691) (xy 86.057412 -409.649148) (xy 86.084664 -409.64866) (xy 86.948264 -409.64866)
			(xy 86.975516 -409.649185) (xy 87.029467 -409.656937) (xy 87.081764 -409.672289) (xy 87.131345 -409.694927)
			(xy 87.177199 -409.724392) (xy 87.218392 -409.760082) (xy 87.254087 -409.801273) (xy 87.283556 -409.847124)
			(xy 87.306199 -409.896702) (xy 87.321555 -409.948998) (xy 87.329313 -410.002948) (xy 87.329313 -410.057452)
			(xy 87.329313 -410.057455) (xy 88.766823 -410.057455) (xy 88.766823 -410.002945) (xy 88.774581 -409.948989)
			(xy 88.789938 -409.896686) (xy 88.812583 -409.847102) (xy 88.842054 -409.801244) (xy 88.877751 -409.760048)
			(xy 88.918948 -409.724351) (xy 88.964805 -409.694881) (xy 89.01439 -409.672237) (xy 89.066693 -409.65688)
			(xy 89.120649 -409.649123) (xy 89.147904 -409.64866) (xy 90.011504 -409.64866) (xy 90.038753 -409.64921)
			(xy 90.092695 -409.656967) (xy 90.144985 -409.672321) (xy 90.194558 -409.69496) (xy 90.240404 -409.724424)
			(xy 90.28159 -409.760113) (xy 90.317278 -409.801299) (xy 90.346742 -409.847146) (xy 90.36938 -409.896718)
			(xy 90.384734 -409.949008) (xy 90.39249 -410.002951) (xy 90.39249 -410.057449) (xy 90.392489 -410.057457)
			(xy 91.830023 -410.057457) (xy 91.830023 -410.002943) (xy 91.837782 -409.948983) (xy 91.853141 -409.896678)
			(xy 91.875789 -409.84709) (xy 91.905264 -409.801231) (xy 91.940965 -409.760034) (xy 91.982167 -409.724337)
			(xy 92.028029 -409.694868) (xy 92.077619 -409.672226) (xy 92.129927 -409.656872) (xy 92.183887 -409.64912)
			(xy 92.211144 -409.64866) (xy 93.074744 -409.64866) (xy 93.101991 -409.649213) (xy 93.155929 -409.656974)
			(xy 93.208214 -409.672332) (xy 93.257782 -409.694973) (xy 93.303623 -409.724438) (xy 93.344804 -409.760127)
			(xy 93.380488 -409.801313) (xy 93.409948 -409.847157) (xy 93.432584 -409.896727) (xy 93.447935 -409.949014)
			(xy 93.45569 -410.002953) (xy 93.45569 -410.057447) (xy 93.455689 -410.057453) (xy 94.893346 -410.057453)
			(xy 94.893346 -410.002947) (xy 94.901103 -409.948996) (xy 94.916458 -409.896698) (xy 94.9391 -409.847118)
			(xy 94.968567 -409.801265) (xy 95.00426 -409.760071) (xy 95.045452 -409.724377) (xy 95.091304 -409.694908)
			(xy 95.140883 -409.672264) (xy 95.193181 -409.656906) (xy 95.247131 -409.649147) (xy 95.274384 -409.64866)
			(xy 96.137984 -409.64866) (xy 96.165235 -409.649186) (xy 96.219183 -409.656941) (xy 96.271479 -409.672294)
			(xy 96.321057 -409.694934) (xy 96.366908 -409.724399) (xy 96.408099 -409.760089) (xy 96.443792 -409.801279)
			(xy 96.473259 -409.847129) (xy 96.4959 -409.896706) (xy 96.511256 -409.949001) (xy 96.519013 -410.002949)
			(xy 96.519013 -410.057451) (xy 96.511256 -410.111399) (xy 96.4959 -410.163694) (xy 96.473259 -410.213271)
			(xy 96.443792 -410.259121) (xy 96.408099 -410.300311) (xy 96.366908 -410.336001) (xy 96.321057 -410.365466)
			(xy 96.271479 -410.388106) (xy 96.219183 -410.403459) (xy 96.165235 -410.411214) (xy 96.137984 -410.411676)
			(xy 95.274384 -410.411676) (xy 95.247131 -410.411253) (xy 95.193181 -410.403494) (xy 95.140883 -410.388136)
			(xy 95.091304 -410.365492) (xy 95.045452 -410.336023) (xy 95.00426 -410.300329) (xy 94.968567 -410.259135)
			(xy 94.9391 -410.213282) (xy 94.916458 -410.163702) (xy 94.901103 -410.111404) (xy 94.893346 -410.057453)
			(xy 93.455689 -410.057453) (xy 93.447935 -410.111386) (xy 93.432584 -410.163673) (xy 93.409948 -410.213243)
			(xy 93.380488 -410.259087) (xy 93.344804 -410.300273) (xy 93.303623 -410.335962) (xy 93.257782 -410.365427)
			(xy 93.208214 -410.388068) (xy 93.155929 -410.403426) (xy 93.101991 -410.411187) (xy 93.074744 -410.411676)
			(xy 92.211144 -410.411676) (xy 92.183887 -410.41128) (xy 92.129927 -410.403528) (xy 92.077619 -410.388174)
			(xy 92.028029 -410.365532) (xy 91.982167 -410.336063) (xy 91.940965 -410.300366) (xy 91.905264 -410.259169)
			(xy 91.875789 -410.21331) (xy 91.853141 -410.163722) (xy 91.837782 -410.111417) (xy 91.830023 -410.057457)
			(xy 90.392489 -410.057457) (xy 90.384734 -410.111392) (xy 90.36938 -410.163682) (xy 90.346742 -410.213254)
			(xy 90.317278 -410.259101) (xy 90.28159 -410.300287) (xy 90.240404 -410.335976) (xy 90.194558 -410.36544)
			(xy 90.144985 -410.388079) (xy 90.092695 -410.403433) (xy 90.038753 -410.41119) (xy 90.011504 -410.411676)
			(xy 89.147904 -410.411676) (xy 89.120649 -410.411277) (xy 89.066693 -410.40352) (xy 89.01439 -410.388163)
			(xy 88.964805 -410.365519) (xy 88.918948 -410.336049) (xy 88.877751 -410.300352) (xy 88.842054 -410.259156)
			(xy 88.812583 -410.213298) (xy 88.789938 -410.163714) (xy 88.774581 -410.111411) (xy 88.766823 -410.057455)
			(xy 87.329313 -410.057455) (xy 87.321555 -410.111402) (xy 87.306199 -410.163698) (xy 87.283556 -410.213276)
			(xy 87.254087 -410.259127) (xy 87.218392 -410.300318) (xy 87.177199 -410.336008) (xy 87.131345 -410.365473)
			(xy 87.081764 -410.388111) (xy 87.029467 -410.403463) (xy 86.975516 -410.411215) (xy 86.948264 -410.411676)
			(xy 86.084664 -410.411676) (xy 86.057412 -410.411252) (xy 86.003464 -410.40349) (xy 85.951169 -410.388131)
			(xy 85.901592 -410.365486) (xy 85.855742 -410.336016) (xy 85.814553 -410.300321) (xy 85.778862 -410.259129)
			(xy 85.749397 -410.213276) (xy 85.726757 -410.163697) (xy 85.711402 -410.111401) (xy 85.703646 -410.057452)
			(xy 84.265989 -410.057452) (xy 84.258235 -410.111389) (xy 84.242882 -410.163677) (xy 84.220245 -410.213249)
			(xy 84.190783 -410.259094) (xy 84.155097 -410.30028) (xy 84.113913 -410.335969) (xy 84.06807 -410.365433)
			(xy 84.0185 -410.388074) (xy 83.966212 -410.40343) (xy 83.912272 -410.411188) (xy 83.885024 -410.411676)
			(xy 83.021424 -410.411676) (xy 82.994168 -410.411279) (xy 82.94021 -410.403524) (xy 82.887904 -410.388169)
			(xy 82.838317 -410.365526) (xy 82.792457 -410.336056) (xy 82.751258 -410.300359) (xy 82.715559 -410.259162)
			(xy 82.686086 -410.213304) (xy 82.66344 -410.163718) (xy 82.648081 -410.111414) (xy 82.640323 -410.057456)
			(xy 81.202812 -410.057456) (xy 81.195056 -410.111399) (xy 81.1797 -410.163694) (xy 81.157059 -410.213271)
			(xy 81.127592 -410.259121) (xy 81.091899 -410.300311) (xy 81.050708 -410.336001) (xy 81.004857 -410.365466)
			(xy 80.955279 -410.388106) (xy 80.902983 -410.403459) (xy 80.849035 -410.411214) (xy 80.821784 -410.411676)
			(xy 79.958184 -410.411676) (xy 79.930931 -410.411253) (xy 79.876981 -410.403494) (xy 79.824683 -410.388136)
			(xy 79.775104 -410.365492) (xy 79.729252 -410.336023) (xy 79.68806 -410.300329) (xy 79.652367 -410.259135)
			(xy 79.6229 -410.213282) (xy 79.600258 -410.163702) (xy 79.584903 -410.111404) (xy 79.577146 -410.057453)
			(xy 78.139489 -410.057453) (xy 78.131735 -410.111386) (xy 78.116384 -410.163673) (xy 78.093748 -410.213243)
			(xy 78.064288 -410.259087) (xy 78.028604 -410.300273) (xy 77.987423 -410.335962) (xy 77.941582 -410.365427)
			(xy 77.892014 -410.388068) (xy 77.839729 -410.403426) (xy 77.785791 -410.411187) (xy 77.758544 -410.411676)
			(xy 76.894944 -410.411676) (xy 76.867687 -410.41128) (xy 76.813727 -410.403528) (xy 76.761419 -410.388174)
			(xy 76.711829 -410.365532) (xy 76.665967 -410.336063) (xy 76.624765 -410.300366) (xy 76.589064 -410.259169)
			(xy 76.559589 -410.21331) (xy 76.536941 -410.163722) (xy 76.521582 -410.111417) (xy 76.513823 -410.057457)
			(xy 75.076289 -410.057457) (xy 75.068534 -410.111392) (xy 75.05318 -410.163682) (xy 75.030542 -410.213254)
			(xy 75.001078 -410.259101) (xy 74.96539 -410.300287) (xy 74.924204 -410.335976) (xy 74.878358 -410.36544)
			(xy 74.828785 -410.388079) (xy 74.776495 -410.403433) (xy 74.722553 -410.41119) (xy 74.695304 -410.411676)
			(xy 73.831704 -410.411676) (xy 73.804449 -410.411277) (xy 73.750493 -410.40352) (xy 73.69819 -410.388163)
			(xy 73.648605 -410.365519) (xy 73.602748 -410.336049) (xy 73.561551 -410.300352) (xy 73.525854 -410.259156)
			(xy 73.496383 -410.213298) (xy 73.473738 -410.163714) (xy 73.458381 -410.111411) (xy 73.450623 -410.057455)
			(xy 72.013113 -410.057455) (xy 72.005355 -410.111402) (xy 71.989999 -410.163698) (xy 71.967356 -410.213276)
			(xy 71.937887 -410.259127) (xy 71.902192 -410.300318) (xy 71.860999 -410.336008) (xy 71.815145 -410.365473)
			(xy 71.765564 -410.388111) (xy 71.713267 -410.403463) (xy 71.659316 -410.411215) (xy 71.632064 -410.411676)
			(xy 70.768464 -410.411676) (xy 70.741212 -410.411252) (xy 70.687264 -410.40349) (xy 70.634969 -410.388131)
			(xy 70.585392 -410.365486) (xy 70.539542 -410.336016) (xy 70.498353 -410.300321) (xy 70.462662 -410.259129)
			(xy 70.433197 -410.213276) (xy 70.410557 -410.163697) (xy 70.395202 -410.111401) (xy 70.387446 -410.057452)
			(xy 68.949789 -410.057452) (xy 68.942035 -410.111389) (xy 68.926682 -410.163677) (xy 68.904045 -410.213249)
			(xy 68.874583 -410.259094) (xy 68.838897 -410.30028) (xy 68.797713 -410.335969) (xy 68.75187 -410.365433)
			(xy 68.7023 -410.388074) (xy 68.650012 -410.40343) (xy 68.596072 -410.411188) (xy 68.568824 -410.411676)
			(xy 67.705224 -410.411676) (xy 67.677968 -410.411279) (xy 67.62401 -410.403524) (xy 67.571704 -410.388169)
			(xy 67.522117 -410.365526) (xy 67.476257 -410.336056) (xy 67.435058 -410.300359) (xy 67.399359 -410.259162)
			(xy 67.369886 -410.213304) (xy 67.34724 -410.163718) (xy 67.331881 -410.111414) (xy 67.324123 -410.057456)
			(xy 65.886612 -410.057456) (xy 65.878856 -410.111399) (xy 65.8635 -410.163694) (xy 65.840859 -410.213271)
			(xy 65.811392 -410.259121) (xy 65.775699 -410.300311) (xy 65.734508 -410.336001) (xy 65.688657 -410.365466)
			(xy 65.639079 -410.388106) (xy 65.586783 -410.403459) (xy 65.532835 -410.411214) (xy 65.505584 -410.411676)
			(xy 64.641984 -410.411676) (xy 64.614731 -410.411253) (xy 64.560781 -410.403494) (xy 64.508483 -410.388136)
			(xy 64.458904 -410.365492) (xy 64.413052 -410.336023) (xy 64.37186 -410.300329) (xy 64.336167 -410.259135)
			(xy 64.3067 -410.213282) (xy 64.284058 -410.163702) (xy 64.268703 -410.111404) (xy 64.260946 -410.057453)
			(xy 62.823289 -410.057453) (xy 62.815535 -410.111386) (xy 62.800184 -410.163673) (xy 62.777548 -410.213243)
			(xy 62.748088 -410.259087) (xy 62.712404 -410.300273) (xy 62.671223 -410.335962) (xy 62.625382 -410.365427)
			(xy 62.575814 -410.388068) (xy 62.523529 -410.403426) (xy 62.469591 -410.411187) (xy 62.442344 -410.411676)
			(xy 61.578744 -410.411676) (xy 61.551487 -410.41128) (xy 61.497527 -410.403528) (xy 61.445219 -410.388174)
			(xy 61.395629 -410.365532) (xy 61.349767 -410.336063) (xy 61.308565 -410.300366) (xy 61.272864 -410.259169)
			(xy 61.243389 -410.21331) (xy 61.220741 -410.163722) (xy 61.205382 -410.111417) (xy 61.197623 -410.057457)
			(xy 59.760089 -410.057457) (xy 59.752334 -410.111392) (xy 59.73698 -410.163682) (xy 59.714342 -410.213254)
			(xy 59.684878 -410.259101) (xy 59.64919 -410.300287) (xy 59.608004 -410.335976) (xy 59.562158 -410.36544)
			(xy 59.512585 -410.388079) (xy 59.460295 -410.403433) (xy 59.406353 -410.41119) (xy 59.379104 -410.411676)
			(xy 58.515504 -410.411676) (xy 58.488249 -410.411277) (xy 58.434293 -410.40352) (xy 58.38199 -410.388163)
			(xy 58.332405 -410.365519) (xy 58.286548 -410.336049) (xy 58.245351 -410.300352) (xy 58.209654 -410.259156)
			(xy 58.180183 -410.213298) (xy 58.157538 -410.163714) (xy 58.142181 -410.111411) (xy 58.134423 -410.057455)
			(xy 56.696913 -410.057455) (xy 56.689155 -410.111402) (xy 56.673799 -410.163698) (xy 56.651156 -410.213276)
			(xy 56.621687 -410.259127) (xy 56.585992 -410.300318) (xy 56.544799 -410.336008) (xy 56.498945 -410.365473)
			(xy 56.449364 -410.388111) (xy 56.397067 -410.403463) (xy 56.343116 -410.411215) (xy 56.315864 -410.411676)
			(xy 55.452264 -410.411676) (xy 55.425012 -410.411252) (xy 55.371064 -410.40349) (xy 55.318769 -410.388131)
			(xy 55.269192 -410.365486) (xy 55.223342 -410.336016) (xy 55.182153 -410.300321) (xy 55.146462 -410.259129)
			(xy 55.116997 -410.213276) (xy 55.094357 -410.163697) (xy 55.079002 -410.111401) (xy 55.071246 -410.057452)
			(xy 53.633589 -410.057452) (xy 53.625835 -410.111389) (xy 53.610482 -410.163677) (xy 53.587845 -410.213249)
			(xy 53.558383 -410.259094) (xy 53.522697 -410.30028) (xy 53.481513 -410.335969) (xy 53.43567 -410.365433)
			(xy 53.3861 -410.388074) (xy 53.333812 -410.40343) (xy 53.279872 -410.411188) (xy 53.252624 -410.411676)
			(xy 52.389024 -410.411676) (xy 52.361768 -410.411279) (xy 52.30781 -410.403524) (xy 52.255504 -410.388169)
			(xy 52.205917 -410.365526) (xy 52.160057 -410.336056) (xy 52.118858 -410.300359) (xy 52.083159 -410.259162)
			(xy 52.053686 -410.213304) (xy 52.03104 -410.163718) (xy 52.015681 -410.111414) (xy 52.007923 -410.057456)
			(xy 50.570412 -410.057456) (xy 50.562656 -410.111399) (xy 50.5473 -410.163694) (xy 50.524659 -410.213271)
			(xy 50.495192 -410.259121) (xy 50.459499 -410.300311) (xy 50.418308 -410.336001) (xy 50.372457 -410.365466)
			(xy 50.322879 -410.388106) (xy 50.270583 -410.403459) (xy 50.216635 -410.411214) (xy 50.189384 -410.411676)
			(xy 49.325784 -410.411676) (xy 49.298531 -410.411253) (xy 49.244581 -410.403494) (xy 49.192283 -410.388136)
			(xy 49.142704 -410.365492) (xy 49.096852 -410.336023) (xy 49.05566 -410.300329) (xy 49.019967 -410.259135)
			(xy 48.9905 -410.213282) (xy 48.967858 -410.163702) (xy 48.952503 -410.111404) (xy 48.944746 -410.057453)
			(xy 7.00913 -410.057453) (xy 7.00913 -410.708348) (xy 183.940958 -410.708348) (xy 183.940958 -400.09572)
			(xy 183.941483 -400.070772) (xy 183.94929 -400.021491) (xy 183.964701 -399.974034) (xy 183.987336 -399.929568)
			(xy 184.01664 -399.889183) (xy 184.033922 -399.871184) (xy 184.239408 -399.665698) (xy 184.257395 -399.648399)
			(xy 184.297773 -399.619076) (xy 184.342241 -399.59643) (xy 184.389704 -399.581018) (xy 184.438993 -399.57322)
			(xy 184.463944 -399.572734) (xy 188.119004 -399.572734) (xy 188.143952 -399.57325) (xy 188.193234 -399.581061)
			(xy 188.24069 -399.596474) (xy 188.285156 -399.619111) (xy 188.32554 -399.648416) (xy 188.34354 -399.665698)
			(xy 188.528452 -399.85061) (xy 188.545762 -399.868588) (xy 188.575091 -399.908966) (xy 188.597741 -399.953436)
			(xy 188.613156 -400.000901) (xy 188.620956 -400.050193) (xy 188.621416 -400.075146) (xy 188.621416 -402.753322)
			(xy 188.621826 -402.763393) (xy 188.629557 -402.781991) (xy 188.636402 -402.78939) (xy 191.190372 -405.34336)
			(xy 191.197792 -405.350175) (xy 191.216376 -405.35791) (xy 191.22644 -405.358346) (xy 195.26631 -405.358346)
			(xy 195.276382 -405.35794) (xy 195.29498 -405.350207) (xy 195.302378 -405.34336) (xy 197.179184 -403.466554)
			(xy 197.185991 -403.459128) (xy 197.193731 -403.440549) (xy 197.19417 -403.430486) (xy 197.19417 -400.104356)
			(xy 197.194651 -400.079406) (xy 197.202469 -400.030123) (xy 197.217889 -399.982665) (xy 197.240534 -399.9382)
			(xy 197.269848 -399.897818) (xy 197.287134 -399.87982) (xy 197.53961 -399.627344) (xy 197.557604 -399.610052)
			(xy 197.597979 -399.580727) (xy 197.642445 -399.558078) (xy 197.689907 -399.542665) (xy 197.739195 -399.534866)
			(xy 197.764146 -399.53438) (xy 201.33818 -399.53438) (xy 201.363128 -399.534898) (xy 201.41241 -399.542706)
			(xy 201.459867 -399.558118) (xy 201.504334 -399.580755) (xy 201.544717 -399.610061) (xy 201.562716 -399.627344)
			(xy 201.823066 -399.887694) (xy 201.840352 -399.905693) (xy 201.869678 -399.946068) (xy 201.892327 -399.990532)
			(xy 201.907742 -400.037992) (xy 201.915543 -400.08728) (xy 201.91603 -400.11223) (xy 201.91603 -403.422612)
			(xy 201.916441 -403.432683) (xy 201.924171 -403.451281) (xy 201.931016 -403.45868) (xy 202.036172 -403.563836)
			(xy 202.053479 -403.581816) (xy 202.082802 -403.622195) (xy 202.105447 -403.666665) (xy 202.120857 -403.714129)
			(xy 202.128652 -403.76342) (xy 202.129136 -403.788372) (xy 202.129136 -406.516078) (xy 202.129564 -406.526147)
			(xy 202.137282 -406.544745) (xy 202.144122 -406.552146) (xy 203.391008 -407.799032) (xy 203.39839 -407.805645)
			(xy 203.416673 -407.813238) (xy 203.426568 -407.813764) (xy 203.457048 -407.814018) (xy 203.466471 -407.813752)
			(xy 203.484091 -407.807093) (xy 203.491338 -407.801064) (xy 203.512428 -407.782761) (xy 203.558955 -407.751881)
			(xy 203.609485 -407.728114) (xy 203.662941 -407.711966) (xy 203.71818 -407.703783) (xy 203.7461 -407.703274)
			(xy 203.772675 -407.703742) (xy 203.825312 -407.711107) (xy 203.876417 -407.72571) (xy 203.924999 -407.747267)
			(xy 203.970118 -407.77536) (xy 204.010899 -407.809446) (xy 204.046552 -407.848864) (xy 204.076387 -407.89285)
			(xy 204.099826 -407.940552) (xy 204.108558 -407.965656) (xy 204.112315 -407.97567) (xy 204.126611 -407.991551)
			(xy 204.146134 -408.00024) (xy 204.156818 -408.000708) (xy 205.795372 -408.000708) (xy 205.805443 -408.000292)
			(xy 205.824042 -407.992567) (xy 205.83144 -407.985722) (xy 207.658716 -406.158446) (xy 207.66553 -406.151026)
			(xy 207.673264 -406.132442) (xy 207.673702 -406.122378) (xy 207.673702 -403.722586) (xy 207.674193 -403.697637)
			(xy 207.682006 -403.648353) (xy 207.697424 -403.600896) (xy 207.720068 -403.55643) (xy 207.74938 -403.516048)
			(xy 207.766666 -403.49805) (xy 207.847184 -403.417532) (xy 207.854 -403.410113) (xy 207.861735 -403.391528)
			(xy 207.86217 -403.381464) (xy 207.86217 -400.079464) (xy 207.862656 -400.054515) (xy 207.870472 -400.005231)
			(xy 207.885892 -399.957774) (xy 207.908536 -399.913308) (xy 207.937848 -399.872926) (xy 207.955134 -399.854928)
			(xy 208.201514 -399.608548) (xy 208.21949 -399.591236) (xy 208.259869 -399.561908) (xy 208.304339 -399.539258)
			(xy 208.351805 -399.523843) (xy 208.401097 -399.516044) (xy 208.42605 -399.515584) (xy 211.971128 -399.515584)
			(xy 211.996077 -399.516071) (xy 212.045361 -399.523886) (xy 212.092818 -399.539306) (xy 212.137284 -399.561949)
			(xy 212.177666 -399.591262) (xy 212.195664 -399.608548) (xy 212.507576 -399.92046) (xy 212.524847 -399.938473)
			(xy 212.554175 -399.978843) (xy 212.576826 -400.023305) (xy 212.592245 -400.070762) (xy 212.600051 -400.120047)
			(xy 212.60054 -400.144996) (xy 212.60054 -403.480016) (xy 212.600947 -403.490088) (xy 212.608679 -403.508686)
			(xy 212.615526 -403.516084) (xy 212.638894 -403.539452) (xy 212.656213 -403.557421) (xy 212.685533 -403.597804)
			(xy 212.708176 -403.642276) (xy 212.723583 -403.689743) (xy 212.731376 -403.739036) (xy 212.731858 -403.763988)
			(xy 212.731858 -406.258014) (xy 212.732261 -406.268086) (xy 212.739995 -406.286685) (xy 212.746844 -406.294082)
			(xy 214.186008 -407.733246) (xy 214.193923 -407.74035) (xy 214.21371 -407.748063) (xy 214.234927 -407.747127)
			(xy 214.244682 -407.742898) (xy 214.271123 -407.730432) (xy 214.326854 -407.712801) (xy 214.38462 -407.703855)
			(xy 214.413846 -407.703274) (xy 214.4141 -407.703274) (xy 214.441972 -407.70378) (xy 214.497125 -407.71188)
			(xy 214.550512 -407.727922) (xy 214.600994 -407.751564) (xy 214.647498 -407.782303) (xy 214.689031 -407.819484)
			(xy 214.72471 -407.862315) (xy 214.753774 -407.909883) (xy 214.775604 -407.961175) (xy 214.783162 -407.988008)
			(xy 214.78748 -408.004772) (xy 214.814912 -408.025854) (xy 216.38895 -408.025854) (xy 216.399018 -408.025415)
			(xy 216.417617 -408.017705) (xy 216.425018 -408.010868) (xy 218.335098 -406.100788) (xy 218.341936 -406.093386)
			(xy 218.349657 -406.074788) (xy 218.350084 -406.06472) (xy 218.350084 -403.755606) (xy 218.350592 -403.730657)
			(xy 218.358403 -403.681375) (xy 218.373817 -403.633918) (xy 218.396456 -403.589452) (xy 218.425764 -403.549069)
			(xy 218.443048 -403.53107) (xy 218.50731 -403.466808) (xy 218.51414 -403.4594) (xy 218.521865 -403.440807)
			(xy 218.522296 -403.43074) (xy 218.522296 -400.095974) (xy 218.522781 -400.071024) (xy 218.530596 -400.021741)
			(xy 218.546016 -399.974283) (xy 218.56866 -399.929817) (xy 218.597974 -399.889436) (xy 218.61526 -399.871438)
			(xy 218.820746 -399.665952) (xy 218.838709 -399.648625) (xy 218.879091 -399.619299) (xy 218.923564 -399.596652)
			(xy 218.971033 -399.581241) (xy 219.020328 -399.573446) (xy 219.045282 -399.572988) (xy 222.709232 -399.572988)
			(xy 222.734182 -399.573471) (xy 222.783465 -399.581288) (xy 222.830923 -399.596707) (xy 222.875388 -399.619352)
			(xy 222.91577 -399.648666) (xy 222.933768 -399.665952) (xy 223.130618 -399.862802) (xy 223.147917 -399.880789)
			(xy 223.177239 -399.921168) (xy 223.199885 -399.965636) (xy 223.215297 -400.013098) (xy 223.223096 -400.062387)
			(xy 223.223582 -400.087338) (xy 223.223582 -403.455124) (xy 223.223973 -403.465198) (xy 223.231716 -403.483796)
			(xy 223.238568 -403.491192) (xy 223.323658 -403.576282) (xy 223.340937 -403.594288) (xy 223.370264 -403.63466)
			(xy 223.392915 -403.679123) (xy 223.408331 -403.726582) (xy 223.416134 -403.775868) (xy 223.416622 -403.800818)
			(xy 223.416622 -406.262078) (xy 223.417053 -406.272147) (xy 223.424769 -406.290745) (xy 223.431608 -406.298146)
			(xy 224.874328 -407.740866) (xy 224.905824 -407.7462) (xy 224.920302 -407.739342) (xy 224.945735 -407.727945)
			(xy 224.999097 -407.71187) (xy 225.054234 -407.703754) (xy 225.0821 -407.703274) (xy 225.111289 -407.703848)
			(xy 225.168987 -407.712721) (xy 225.224657 -407.730289) (xy 225.276997 -407.756142) (xy 225.324782 -407.789675)
			(xy 225.366893 -407.830104) (xy 225.402346 -407.876481) (xy 225.430312 -407.927723) (xy 225.440748 -407.954988)
			(xy 225.444773 -407.964592) (xy 225.459011 -407.979756) (xy 225.4781 -407.988017) (xy 225.4885 -407.988516)
			(xy 227.066094 -407.988516) (xy 227.076166 -407.98811) (xy 227.094765 -407.980378) (xy 227.102162 -407.97353)
			(xy 228.999288 -406.076404) (xy 229.006117 -406.068995) (xy 229.013844 -406.050403) (xy 229.014274 -406.040336)
			(xy 229.014274 -403.768052) (xy 229.014751 -403.743102) (xy 229.02257 -403.693818) (xy 229.037991 -403.646361)
			(xy 229.060637 -403.601896) (xy 229.089951 -403.561514) (xy 229.107238 -403.543516) (xy 229.183692 -403.467062)
			(xy 229.19054 -403.459668) (xy 229.198255 -403.441064) (xy 229.198678 -403.430994) (xy 229.198678 -400.11223)
			(xy 229.199203 -400.087282) (xy 229.20701 -400.038) (xy 229.22242 -399.990544) (xy 229.245055 -399.946077)
			(xy 229.27436 -399.905693) (xy 229.291642 -399.887694) (xy 229.521766 -399.65757) (xy 229.539767 -399.640284)
			(xy 229.580139 -399.610952) (xy 229.624602 -399.588297) (xy 229.672062 -399.572876) (xy 229.721351 -399.56507)
			(xy 229.746302 -399.564606) (xy 233.352594 -399.564606) (xy 233.377543 -399.565108) (xy 233.426826 -399.572919)
			(xy 233.474284 -399.588334) (xy 233.51875 -399.610975) (xy 233.559132 -399.640285) (xy 233.57713 -399.65757)
			(xy 233.798872 -399.879312) (xy 233.816168 -399.897302) (xy 233.845492 -399.937679) (xy 233.868139 -399.982146)
			(xy 233.883552 -400.029608) (xy 233.89135 -400.078897) (xy 233.891836 -400.103848) (xy 233.891836 -403.52091)
			(xy 233.892247 -403.530981) (xy 233.899977 -403.549579) (xy 233.906822 -403.556978) (xy 234.044998 -403.695154)
			(xy 234.062318 -403.713122) (xy 234.091638 -403.753505) (xy 234.114281 -403.797978) (xy 234.129687 -403.845445)
			(xy 234.13748 -403.894737) (xy 234.137962 -403.91969) (xy 234.137962 -404.702518) (xy 234.138361 -404.712591)
			(xy 234.146098 -404.731189) (xy 234.152948 -404.738586) (xy 234.63885 -405.224488) (xy 234.646275 -405.231297)
			(xy 234.664855 -405.239035) (xy 234.674918 -405.239474) (xy 238.514382 -405.239474) (xy 238.524405 -405.239065)
			(xy 238.542927 -405.231396) (xy 238.557101 -405.21722) (xy 238.564767 -405.198697) (xy 238.565182 -405.188674)
			(xy 238.565182 -394.001498) (xy 238.565686 -393.976549) (xy 238.573497 -393.927266) (xy 238.588912 -393.879809)
			(xy 238.611553 -393.835343) (xy 238.640862 -393.79496) (xy 238.658146 -393.776962) (xy 238.727234 -393.707874)
			(xy 238.733961 -393.700496) (xy 238.741558 -393.682047) (xy 238.741546 -393.662096) (xy 238.733929 -393.643656)
			(xy 238.727234 -393.636246) (xy 238.579914 -393.488672) (xy 238.553014 -393.461125) (xy 238.504928 -393.400988)
			(xy 238.463885 -393.33584) (xy 238.430403 -393.266502) (xy 238.404904 -393.193848) (xy 238.387709 -393.118794)
			(xy 238.379036 -393.042285) (xy 238.378492 -393.003786) (xy 238.378492 -384.337306) (xy 238.379215 -384.306679)
			(xy 238.390978 -384.246564) (xy 238.40186 -384.217926) (xy 238.457994 -384.079496) (xy 238.466633 -384.059188)
			(xy 238.488684 -384.020961) (xy 238.515818 -383.986157) (xy 238.5314 -383.97053) (xy 238.583216 -383.920746)
			(xy 238.583724 -383.920238) (xy 239.05718 -383.446782) (xy 239.084743 -383.419899) (xy 239.144878 -383.371812)
			(xy 239.210023 -383.330768) (xy 239.279359 -383.297284) (xy 239.35201 -383.271782) (xy 239.427061 -383.254584)
			(xy 239.503568 -383.245906) (xy 239.542066 -383.24536) (xy 273.481546 -383.24536) (xy 273.512174 -383.24607)
			(xy 273.572289 -383.257841) (xy 273.600926 -383.268728) (xy 273.739356 -383.324862) (xy 273.759667 -383.333494)
			(xy 273.797892 -383.355549) (xy 273.832695 -383.382685) (xy 273.848322 -383.398268) (xy 273.898106 -383.450084)
			(xy 273.898614 -383.450592) (xy 274.11807 -383.670048) (xy 274.141946 -383.69494) (xy 274.148804 -383.70256)
			(xy 274.167854 -383.71145) (xy 274.251674 -383.713482) (xy 274.262067 -383.713236) (xy 274.281342 -383.705512)
			(xy 274.289012 -383.698496) (xy 274.649184 -383.338324) (xy 274.667186 -383.321041) (xy 274.70756 -383.291715)
			(xy 274.752024 -383.269066) (xy 274.799483 -383.25365) (xy 274.84877 -383.245848) (xy 274.87372 -383.24536)
			(xy 280.202132 -383.24536) (xy 280.227081 -383.245851) (xy 280.276364 -383.253667) (xy 280.323821 -383.269085)
			(xy 280.368287 -383.291728) (xy 280.40867 -383.321039) (xy 280.426668 -383.338324) (xy 281.135836 -384.047492)
			(xy 281.153135 -384.065481) (xy 281.182465 -384.105856) (xy 281.205118 -384.150322) (xy 281.220536 -384.197785)
			(xy 281.228338 -384.247076) (xy 281.2288 -384.272028) (xy 281.2288 -384.869944) (xy 287.06878 -384.869944)
			(xy 287.072752 -384.691701) (xy 287.08466 -384.513812) (xy 287.104481 -384.33663) (xy 287.132175 -384.160506)
			(xy 287.167687 -383.985791) (xy 287.210947 -383.812832) (xy 287.261869 -383.641971) (xy 287.320352 -383.473549)
			(xy 287.386279 -383.307899) (xy 287.45952 -383.14535) (xy 287.53993 -382.986225) (xy 287.627348 -382.83084)
			(xy 287.721601 -382.679504) (xy 287.822502 -382.532516) (xy 287.929851 -382.390169) (xy 288.043434 -382.252746)
			(xy 288.163027 -382.120519) (xy 288.288391 -381.99375) (xy 288.419278 -381.872692) (xy 288.555427 -381.757585)
			(xy 288.696569 -381.648657) (xy 288.842424 -381.546125) (xy 288.992701 -381.450191) (xy 289.147102 -381.361048)
			(xy 289.305321 -381.278871) (xy 289.467044 -381.203823) (xy 289.631949 -381.136055) (xy 289.79971 -381.075699)
			(xy 289.969993 -381.022877) (xy 290.14246 -380.977693) (xy 290.316768 -380.940236) (xy 290.492572 -380.910582)
			(xy 290.669522 -380.888789) (xy 290.847268 -380.874899) (xy 291.025455 -380.868942) (xy 291.203732 -380.870928)
			(xy 291.381743 -380.880854) (xy 291.559135 -380.8987) (xy 291.735555 -380.92443) (xy 291.910655 -380.957994)
			(xy 292.084086 -380.999324) (xy 292.255503 -381.04834) (xy 292.424566 -381.104942) (xy 292.590941 -381.16902)
			(xy 292.754295 -381.240446) (xy 292.914306 -381.319078) (xy 293.070655 -381.404759) (xy 293.223032 -381.497321)
			(xy 293.371135 -381.596578) (xy 293.514669 -381.702335) (xy 293.653349 -381.81438) (xy 293.7869 -381.932492)
			(xy 293.915057 -382.056436) (xy 294.037566 -382.185966) (xy 294.154183 -382.320825) (xy 294.194727 -382.372167)
			(xy 303.739054 -382.372167) (xy 303.739054 -382.317633) (xy 303.746815 -382.263654) (xy 303.762179 -382.211329)
			(xy 303.784833 -382.161723) (xy 303.814317 -382.115846) (xy 303.850029 -382.074631) (xy 303.891242 -382.038919)
			(xy 303.937119 -382.009435) (xy 303.986725 -381.986781) (xy 304.03905 -381.971416) (xy 304.093029 -381.963655)
			(xy 304.120296 -381.963168) (xy 304.983896 -381.963168) (xy 305.011169 -381.963571) (xy 305.065161 -381.971334)
			(xy 305.117498 -381.986701) (xy 305.167116 -382.00936) (xy 305.213003 -382.03885) (xy 305.254227 -382.07457)
			(xy 305.289948 -382.115793) (xy 305.319438 -382.161681) (xy 305.342098 -382.211298) (xy 305.357466 -382.263635)
			(xy 305.365228 -382.317627) (xy 305.365228 -382.372167) (xy 310.546254 -382.372167) (xy 310.546254 -382.317633)
			(xy 310.554015 -382.263654) (xy 310.569379 -382.211329) (xy 310.592033 -382.161723) (xy 310.621517 -382.115846)
			(xy 310.657229 -382.074631) (xy 310.698442 -382.038919) (xy 310.744319 -382.009435) (xy 310.793925 -381.986781)
			(xy 310.84625 -381.971416) (xy 310.900229 -381.963655) (xy 310.927496 -381.963168) (xy 311.791096 -381.963168)
			(xy 311.818369 -381.963571) (xy 311.872361 -381.971334) (xy 311.924698 -381.986701) (xy 311.974316 -382.00936)
			(xy 312.020203 -382.03885) (xy 312.061427 -382.07457) (xy 312.097148 -382.115793) (xy 312.126638 -382.161681)
			(xy 312.149298 -382.211298) (xy 312.164666 -382.263635) (xy 312.172428 -382.317627) (xy 312.172428 -382.372167)
			(xy 317.353454 -382.372167) (xy 317.353454 -382.317633) (xy 317.361215 -382.263654) (xy 317.376579 -382.211329)
			(xy 317.399233 -382.161723) (xy 317.428717 -382.115846) (xy 317.464429 -382.074631) (xy 317.505642 -382.038919)
			(xy 317.551519 -382.009435) (xy 317.601125 -381.986781) (xy 317.65345 -381.971416) (xy 317.707429 -381.963655)
			(xy 317.734696 -381.963168) (xy 318.598296 -381.963168) (xy 318.625569 -381.963571) (xy 318.679561 -381.971334)
			(xy 318.731898 -381.986701) (xy 318.781516 -382.00936) (xy 318.827403 -382.03885) (xy 318.868627 -382.07457)
			(xy 318.904348 -382.115793) (xy 318.933838 -382.161681) (xy 318.956498 -382.211298) (xy 318.971866 -382.263635)
			(xy 318.979628 -382.317627) (xy 318.979628 -382.372171) (xy 336.266732 -382.372171) (xy 336.266732 -382.317629)
			(xy 336.274494 -382.263643) (xy 336.289861 -382.211311) (xy 336.312521 -382.161698) (xy 336.34201 -382.115816)
			(xy 336.377729 -382.074598) (xy 336.418951 -382.038884) (xy 336.464837 -382.009399) (xy 336.514452 -381.986746)
			(xy 336.566786 -381.971385) (xy 336.620773 -381.963628) (xy 336.648044 -381.963168) (xy 337.511644 -381.963168)
			(xy 337.538913 -381.963598) (xy 337.592897 -381.971365) (xy 337.645225 -381.986735) (xy 337.694833 -382.009396)
			(xy 337.740712 -382.038885) (xy 337.781928 -382.074603) (xy 337.817641 -382.115823) (xy 337.847125 -382.161705)
			(xy 337.86978 -382.211316) (xy 337.885144 -382.263647) (xy 337.892906 -382.31763) (xy 337.892906 -382.37217)
			(xy 337.892906 -382.372171) (xy 343.073932 -382.372171) (xy 343.073932 -382.317629) (xy 343.081694 -382.263643)
			(xy 343.097061 -382.211311) (xy 343.119721 -382.161698) (xy 343.14921 -382.115816) (xy 343.184929 -382.074598)
			(xy 343.226151 -382.038884) (xy 343.272037 -382.009399) (xy 343.321652 -381.986746) (xy 343.373986 -381.971385)
			(xy 343.427973 -381.963628) (xy 343.455244 -381.963168) (xy 344.318844 -381.963168) (xy 344.346113 -381.963598)
			(xy 344.400097 -381.971365) (xy 344.452425 -381.986735) (xy 344.502033 -382.009396) (xy 344.547912 -382.038885)
			(xy 344.589128 -382.074603) (xy 344.624841 -382.115823) (xy 344.654325 -382.161705) (xy 344.67698 -382.211316)
			(xy 344.692344 -382.263647) (xy 344.700106 -382.31763) (xy 344.700106 -382.37217) (xy 344.700106 -382.372171)
			(xy 349.881132 -382.372171) (xy 349.881132 -382.317629) (xy 349.888894 -382.263643) (xy 349.904261 -382.211311)
			(xy 349.926921 -382.161698) (xy 349.95641 -382.115816) (xy 349.992129 -382.074598) (xy 350.033351 -382.038884)
			(xy 350.079237 -382.009399) (xy 350.128852 -381.986746) (xy 350.181186 -381.971385) (xy 350.235173 -381.963628)
			(xy 350.262444 -381.963168) (xy 351.126044 -381.963168) (xy 351.153313 -381.963598) (xy 351.207297 -381.971365)
			(xy 351.259625 -381.986735) (xy 351.309233 -382.009396) (xy 351.355112 -382.038885) (xy 351.396328 -382.074603)
			(xy 351.432041 -382.115823) (xy 351.461525 -382.161705) (xy 351.48418 -382.211316) (xy 351.499544 -382.263647)
			(xy 351.507306 -382.31763) (xy 351.507306 -382.372167) (xy 370.839254 -382.372167) (xy 370.839254 -382.317633)
			(xy 370.847015 -382.263654) (xy 370.862379 -382.21133) (xy 370.885033 -382.161724) (xy 370.914516 -382.115847)
			(xy 370.950227 -382.074633) (xy 370.991441 -382.03892) (xy 371.037317 -382.009437) (xy 371.086922 -381.986782)
			(xy 371.139247 -381.971417) (xy 371.193225 -381.963655) (xy 371.220492 -381.963168) (xy 372.084092 -381.963168)
			(xy 372.111366 -381.963571) (xy 372.165357 -381.971333) (xy 372.217695 -381.9867) (xy 372.267313 -382.009359)
			(xy 372.313202 -382.038848) (xy 372.354426 -382.074568) (xy 372.390147 -382.115792) (xy 372.419638 -382.16168)
			(xy 372.442298 -382.211297) (xy 372.457665 -382.263635) (xy 372.465428 -382.317626) (xy 372.465428 -382.372167)
			(xy 377.646454 -382.372167) (xy 377.646454 -382.317633) (xy 377.654215 -382.263654) (xy 377.669579 -382.21133)
			(xy 377.692233 -382.161724) (xy 377.721716 -382.115847) (xy 377.757427 -382.074633) (xy 377.798641 -382.03892)
			(xy 377.844517 -382.009437) (xy 377.894122 -381.986782) (xy 377.946447 -381.971417) (xy 378.000425 -381.963655)
			(xy 378.027692 -381.963168) (xy 378.891292 -381.963168) (xy 378.918566 -381.963571) (xy 378.972557 -381.971333)
			(xy 379.024895 -381.9867) (xy 379.074513 -382.009359) (xy 379.120402 -382.038848) (xy 379.161626 -382.074568)
			(xy 379.197347 -382.115792) (xy 379.226838 -382.16168) (xy 379.249498 -382.211297) (xy 379.264865 -382.263635)
			(xy 379.272628 -382.317626) (xy 379.272628 -382.372167) (xy 384.453654 -382.372167) (xy 384.453654 -382.317633)
			(xy 384.461415 -382.263654) (xy 384.476779 -382.21133) (xy 384.499433 -382.161724) (xy 384.528916 -382.115847)
			(xy 384.564627 -382.074633) (xy 384.605841 -382.03892) (xy 384.651717 -382.009437) (xy 384.701322 -381.986782)
			(xy 384.753647 -381.971417) (xy 384.807625 -381.963655) (xy 384.834892 -381.963168) (xy 385.698492 -381.963168)
			(xy 385.725766 -381.963571) (xy 385.779757 -381.971333) (xy 385.832095 -381.9867) (xy 385.881713 -382.009359)
			(xy 385.927602 -382.038848) (xy 385.968826 -382.074568) (xy 386.004547 -382.115792) (xy 386.034038 -382.16168)
			(xy 386.056698 -382.211297) (xy 386.072065 -382.263635) (xy 386.079828 -382.317626) (xy 386.079828 -382.372171)
			(xy 403.366932 -382.372171) (xy 403.366932 -382.317629) (xy 403.374694 -382.263643) (xy 403.390061 -382.211311)
			(xy 403.41272 -382.161699) (xy 403.442209 -382.115817) (xy 403.477928 -382.0746) (xy 403.51915 -382.038885)
			(xy 403.565035 -382.009401) (xy 403.614649 -381.986747) (xy 403.666982 -381.971386) (xy 403.720969 -381.963629)
			(xy 403.74824 -381.963168) (xy 404.61184 -381.963168) (xy 404.63911 -381.963597) (xy 404.693093 -381.971364)
			(xy 404.745422 -381.986734) (xy 404.795031 -382.009394) (xy 404.840911 -382.038884) (xy 404.882127 -382.074602)
			(xy 404.91784 -382.115822) (xy 404.947325 -382.161704) (xy 404.96998 -382.211316) (xy 404.985344 -382.263646)
			(xy 404.993106 -382.31763) (xy 404.993106 -382.37217) (xy 404.993106 -382.372171) (xy 410.174132 -382.372171)
			(xy 410.174132 -382.317629) (xy 410.181894 -382.263643) (xy 410.197261 -382.211311) (xy 410.21992 -382.161699)
			(xy 410.249409 -382.115817) (xy 410.285128 -382.0746) (xy 410.32635 -382.038885) (xy 410.372235 -382.009401)
			(xy 410.421849 -381.986747) (xy 410.474182 -381.971386) (xy 410.528169 -381.963629) (xy 410.55544 -381.963168)
			(xy 411.41904 -381.963168) (xy 411.44631 -381.963597) (xy 411.500293 -381.971364) (xy 411.552622 -381.986734)
			(xy 411.602231 -382.009394) (xy 411.648111 -382.038884) (xy 411.689327 -382.074602) (xy 411.72504 -382.115822)
			(xy 411.754525 -382.161704) (xy 411.77718 -382.211316) (xy 411.792544 -382.263646) (xy 411.800306 -382.31763)
			(xy 411.800306 -382.37217) (xy 411.800306 -382.372171) (xy 416.981332 -382.372171) (xy 416.981332 -382.317629)
			(xy 416.989094 -382.263643) (xy 417.004461 -382.211311) (xy 417.02712 -382.161699) (xy 417.056609 -382.115817)
			(xy 417.092328 -382.0746) (xy 417.13355 -382.038885) (xy 417.179435 -382.009401) (xy 417.229049 -381.986747)
			(xy 417.281382 -381.971386) (xy 417.335369 -381.963629) (xy 417.36264 -381.963168) (xy 418.22624 -381.963168)
			(xy 418.25351 -381.963597) (xy 418.307493 -381.971364) (xy 418.359822 -381.986734) (xy 418.409431 -382.009394)
			(xy 418.455311 -382.038884) (xy 418.496527 -382.074602) (xy 418.53224 -382.115822) (xy 418.561725 -382.161704)
			(xy 418.58438 -382.211316) (xy 418.599744 -382.263646) (xy 418.607506 -382.31763) (xy 418.607506 -382.37217)
			(xy 418.599744 -382.426154) (xy 418.58438 -382.478484) (xy 418.561725 -382.528096) (xy 418.53224 -382.573978)
			(xy 418.496527 -382.615198) (xy 418.455311 -382.650916) (xy 418.409431 -382.680406) (xy 418.359822 -382.703066)
			(xy 418.307493 -382.718436) (xy 418.25351 -382.726203) (xy 418.22624 -382.726692) (xy 417.36264 -382.726692)
			(xy 417.335369 -382.726171) (xy 417.281382 -382.718414) (xy 417.229049 -382.703053) (xy 417.179435 -382.680399)
			(xy 417.13355 -382.650915) (xy 417.092328 -382.6152) (xy 417.056609 -382.573983) (xy 417.02712 -382.528101)
			(xy 417.004461 -382.478489) (xy 416.989094 -382.426157) (xy 416.981332 -382.372171) (xy 411.800306 -382.372171)
			(xy 411.792544 -382.426154) (xy 411.77718 -382.478484) (xy 411.754525 -382.528096) (xy 411.72504 -382.573978)
			(xy 411.689327 -382.615198) (xy 411.648111 -382.650916) (xy 411.602231 -382.680406) (xy 411.552622 -382.703066)
			(xy 411.500293 -382.718436) (xy 411.44631 -382.726203) (xy 411.41904 -382.726692) (xy 410.55544 -382.726692)
			(xy 410.528169 -382.726171) (xy 410.474182 -382.718414) (xy 410.421849 -382.703053) (xy 410.372235 -382.680399)
			(xy 410.32635 -382.650915) (xy 410.285128 -382.6152) (xy 410.249409 -382.573983) (xy 410.21992 -382.528101)
			(xy 410.197261 -382.478489) (xy 410.181894 -382.426157) (xy 410.174132 -382.372171) (xy 404.993106 -382.372171)
			(xy 404.985344 -382.426154) (xy 404.96998 -382.478484) (xy 404.947325 -382.528096) (xy 404.91784 -382.573978)
			(xy 404.882127 -382.615198) (xy 404.840911 -382.650916) (xy 404.795031 -382.680406) (xy 404.745422 -382.703066)
			(xy 404.693093 -382.718436) (xy 404.63911 -382.726203) (xy 404.61184 -382.726692) (xy 403.74824 -382.726692)
			(xy 403.720969 -382.726171) (xy 403.666982 -382.718414) (xy 403.614649 -382.703053) (xy 403.565035 -382.680399)
			(xy 403.51915 -382.650915) (xy 403.477928 -382.6152) (xy 403.442209 -382.573983) (xy 403.41272 -382.528101)
			(xy 403.390061 -382.478489) (xy 403.374694 -382.426157) (xy 403.366932 -382.372171) (xy 386.079828 -382.372171)
			(xy 386.079828 -382.372174) (xy 386.072065 -382.426165) (xy 386.056698 -382.478503) (xy 386.034038 -382.52812)
			(xy 386.004547 -382.574008) (xy 385.968826 -382.615232) (xy 385.927602 -382.650952) (xy 385.881713 -382.680441)
			(xy 385.832095 -382.7031) (xy 385.779757 -382.718467) (xy 385.725766 -382.726229) (xy 385.698492 -382.726692)
			(xy 384.834892 -382.726692) (xy 384.807625 -382.726145) (xy 384.753647 -382.718383) (xy 384.701322 -382.703018)
			(xy 384.651717 -382.680363) (xy 384.605841 -382.65088) (xy 384.564627 -382.615167) (xy 384.528916 -382.573953)
			(xy 384.499433 -382.528076) (xy 384.476779 -382.47847) (xy 384.461415 -382.426146) (xy 384.453654 -382.372167)
			(xy 379.272628 -382.372167) (xy 379.272628 -382.372174) (xy 379.264865 -382.426165) (xy 379.249498 -382.478503)
			(xy 379.226838 -382.52812) (xy 379.197347 -382.574008) (xy 379.161626 -382.615232) (xy 379.120402 -382.650952)
			(xy 379.074513 -382.680441) (xy 379.024895 -382.7031) (xy 378.972557 -382.718467) (xy 378.918566 -382.726229)
			(xy 378.891292 -382.726692) (xy 378.027692 -382.726692) (xy 378.000425 -382.726145) (xy 377.946447 -382.718383)
			(xy 377.894122 -382.703018) (xy 377.844517 -382.680363) (xy 377.798641 -382.65088) (xy 377.757427 -382.615167)
			(xy 377.721716 -382.573953) (xy 377.692233 -382.528076) (xy 377.669579 -382.47847) (xy 377.654215 -382.426146)
			(xy 377.646454 -382.372167) (xy 372.465428 -382.372167) (xy 372.465428 -382.372174) (xy 372.457665 -382.426165)
			(xy 372.442298 -382.478503) (xy 372.419638 -382.52812) (xy 372.390147 -382.574008) (xy 372.354426 -382.615232)
			(xy 372.313202 -382.650952) (xy 372.267313 -382.680441) (xy 372.217695 -382.7031) (xy 372.165357 -382.718467)
			(xy 372.111366 -382.726229) (xy 372.084092 -382.726692) (xy 371.220492 -382.726692) (xy 371.193225 -382.726145)
			(xy 371.139247 -382.718383) (xy 371.086922 -382.703018) (xy 371.037317 -382.680363) (xy 370.991441 -382.65088)
			(xy 370.950227 -382.615167) (xy 370.914516 -382.573953) (xy 370.885033 -382.528076) (xy 370.862379 -382.47847)
			(xy 370.847015 -382.426146) (xy 370.839254 -382.372167) (xy 351.507306 -382.372167) (xy 351.507306 -382.37217)
			(xy 351.499544 -382.426153) (xy 351.48418 -382.478484) (xy 351.461525 -382.528095) (xy 351.432041 -382.573977)
			(xy 351.396328 -382.615197) (xy 351.355112 -382.650915) (xy 351.309233 -382.680404) (xy 351.259625 -382.703065)
			(xy 351.207297 -382.718435) (xy 351.153313 -382.726202) (xy 351.126044 -382.726692) (xy 350.262444 -382.726692)
			(xy 350.235173 -382.726172) (xy 350.181186 -382.718415) (xy 350.128852 -382.703054) (xy 350.079237 -382.680401)
			(xy 350.033351 -382.650916) (xy 349.992129 -382.615202) (xy 349.95641 -382.573984) (xy 349.926921 -382.528102)
			(xy 349.904261 -382.478489) (xy 349.888894 -382.426157) (xy 349.881132 -382.372171) (xy 344.700106 -382.372171)
			(xy 344.692344 -382.426153) (xy 344.67698 -382.478484) (xy 344.654325 -382.528095) (xy 344.624841 -382.573977)
			(xy 344.589128 -382.615197) (xy 344.547912 -382.650915) (xy 344.502033 -382.680404) (xy 344.452425 -382.703065)
			(xy 344.400097 -382.718435) (xy 344.346113 -382.726202) (xy 344.318844 -382.726692) (xy 343.455244 -382.726692)
			(xy 343.427973 -382.726172) (xy 343.373986 -382.718415) (xy 343.321652 -382.703054) (xy 343.272037 -382.680401)
			(xy 343.226151 -382.650916) (xy 343.184929 -382.615202) (xy 343.14921 -382.573984) (xy 343.119721 -382.528102)
			(xy 343.097061 -382.478489) (xy 343.081694 -382.426157) (xy 343.073932 -382.372171) (xy 337.892906 -382.372171)
			(xy 337.885144 -382.426153) (xy 337.86978 -382.478484) (xy 337.847125 -382.528095) (xy 337.817641 -382.573977)
			(xy 337.781928 -382.615197) (xy 337.740712 -382.650915) (xy 337.694833 -382.680404) (xy 337.645225 -382.703065)
			(xy 337.592897 -382.718435) (xy 337.538913 -382.726202) (xy 337.511644 -382.726692) (xy 336.648044 -382.726692)
			(xy 336.620773 -382.726172) (xy 336.566786 -382.718415) (xy 336.514452 -382.703054) (xy 336.464837 -382.680401)
			(xy 336.418951 -382.650916) (xy 336.377729 -382.615202) (xy 336.34201 -382.573984) (xy 336.312521 -382.528102)
			(xy 336.289861 -382.478489) (xy 336.274494 -382.426157) (xy 336.266732 -382.372171) (xy 318.979628 -382.372171)
			(xy 318.979628 -382.372173) (xy 318.971866 -382.426165) (xy 318.956498 -382.478502) (xy 318.933838 -382.528119)
			(xy 318.904348 -382.574007) (xy 318.868627 -382.61523) (xy 318.827403 -382.65095) (xy 318.781516 -382.68044)
			(xy 318.731898 -382.703099) (xy 318.679561 -382.718466) (xy 318.625569 -382.726229) (xy 318.598296 -382.726692)
			(xy 317.734696 -382.726692) (xy 317.707429 -382.726145) (xy 317.65345 -382.718384) (xy 317.601125 -382.703019)
			(xy 317.551519 -382.680365) (xy 317.505642 -382.650881) (xy 317.464429 -382.615169) (xy 317.428717 -382.573954)
			(xy 317.399233 -382.528077) (xy 317.376579 -382.478471) (xy 317.361215 -382.426146) (xy 317.353454 -382.372167)
			(xy 312.172428 -382.372167) (xy 312.172428 -382.372173) (xy 312.164666 -382.426165) (xy 312.149298 -382.478502)
			(xy 312.126638 -382.528119) (xy 312.097148 -382.574007) (xy 312.061427 -382.61523) (xy 312.020203 -382.65095)
			(xy 311.974316 -382.68044) (xy 311.924698 -382.703099) (xy 311.872361 -382.718466) (xy 311.818369 -382.726229)
			(xy 311.791096 -382.726692) (xy 310.927496 -382.726692) (xy 310.900229 -382.726145) (xy 310.84625 -382.718384)
			(xy 310.793925 -382.703019) (xy 310.744319 -382.680365) (xy 310.698442 -382.650881) (xy 310.657229 -382.615169)
			(xy 310.621517 -382.573954) (xy 310.592033 -382.528077) (xy 310.569379 -382.478471) (xy 310.554015 -382.426146)
			(xy 310.546254 -382.372167) (xy 305.365228 -382.372167) (xy 305.365228 -382.372173) (xy 305.357466 -382.426165)
			(xy 305.342098 -382.478502) (xy 305.319438 -382.528119) (xy 305.289948 -382.574007) (xy 305.254227 -382.61523)
			(xy 305.213003 -382.65095) (xy 305.167116 -382.68044) (xy 305.117498 -382.703099) (xy 305.065161 -382.718466)
			(xy 305.011169 -382.726229) (xy 304.983896 -382.726692) (xy 304.120296 -382.726692) (xy 304.093029 -382.726145)
			(xy 304.03905 -382.718384) (xy 303.986725 -382.703019) (xy 303.937119 -382.680365) (xy 303.891242 -382.650881)
			(xy 303.850029 -382.615169) (xy 303.814317 -382.573954) (xy 303.784833 -382.528077) (xy 303.762179 -382.478471)
			(xy 303.746815 -382.426146) (xy 303.739054 -382.372167) (xy 294.194727 -382.372167) (xy 294.264676 -382.460745)
			(xy 294.368827 -382.605448) (xy 294.466429 -382.754647) (xy 294.557287 -382.908046) (xy 294.641221 -383.06534)
			(xy 294.718066 -383.226216) (xy 294.787667 -383.390357) (xy 294.849888 -383.557434) (xy 294.904604 -383.727118)
			(xy 294.951706 -383.899071) (xy 294.991102 -384.072951) (xy 295.022713 -384.248414) (xy 295.046477 -384.42511)
			(xy 295.062345 -384.60269) (xy 295.070287 -384.7808) (xy 295.070784 -384.869944) (xy 295.070287 -384.959088)
			(xy 295.062345 -385.137198) (xy 295.055495 -385.21386) (xy 297.048936 -385.21386) (xy 297.048936 -384.35026)
			(xy 297.049422 -384.323009) (xy 297.057178 -384.269061) (xy 297.072533 -384.216766) (xy 297.095175 -384.167189)
			(xy 297.124641 -384.121339) (xy 297.160332 -384.080148) (xy 297.201523 -384.044457) (xy 297.247373 -384.014991)
			(xy 297.29695 -383.992349) (xy 297.349245 -383.976994) (xy 297.403193 -383.969238) (xy 297.457695 -383.969238)
			(xy 297.511643 -383.976994) (xy 297.563938 -383.992349) (xy 297.613515 -384.014991) (xy 297.659365 -384.044457)
			(xy 297.700556 -384.080148) (xy 297.736247 -384.121339) (xy 297.765713 -384.167189) (xy 297.788355 -384.216766)
			(xy 297.80371 -384.269061) (xy 297.811466 -384.323009) (xy 297.811952 -384.35026) (xy 297.811952 -385.21386)
			(xy 297.811466 -385.241111) (xy 297.80371 -385.295059) (xy 297.790858 -385.338828) (xy 326.895968 -385.338828)
			(xy 326.895968 -384.475228) (xy 326.896454 -384.447977) (xy 326.90421 -384.394029) (xy 326.919565 -384.341734)
			(xy 326.942207 -384.292157) (xy 326.971673 -384.246307) (xy 327.007364 -384.205116) (xy 327.048555 -384.169425)
			(xy 327.094405 -384.139959) (xy 327.143982 -384.117317) (xy 327.196277 -384.101962) (xy 327.250225 -384.094206)
			(xy 327.304727 -384.094206) (xy 327.358675 -384.101962) (xy 327.41097 -384.117317) (xy 327.460547 -384.139959)
			(xy 327.506397 -384.169425) (xy 327.547588 -384.205116) (xy 327.583279 -384.246307) (xy 327.612745 -384.292157)
			(xy 327.635387 -384.341734) (xy 327.650742 -384.394029) (xy 327.658498 -384.447977) (xy 327.658984 -384.475228)
			(xy 327.658984 -385.21386) (xy 329.576684 -385.21386) (xy 329.576684 -384.35026) (xy 329.57717 -384.323009)
			(xy 329.584926 -384.269061) (xy 329.600281 -384.216766) (xy 329.622923 -384.167189) (xy 329.652389 -384.121339)
			(xy 329.68808 -384.080148) (xy 329.729271 -384.044457) (xy 329.775121 -384.014991) (xy 329.824698 -383.992349)
			(xy 329.876993 -383.976994) (xy 329.930941 -383.969238) (xy 329.985443 -383.969238) (xy 330.039391 -383.976994)
			(xy 330.091686 -383.992349) (xy 330.141263 -384.014991) (xy 330.187113 -384.044457) (xy 330.228304 -384.080148)
			(xy 330.263995 -384.121339) (xy 330.293461 -384.167189) (xy 330.316103 -384.216766) (xy 330.331458 -384.269061)
			(xy 330.339214 -384.323009) (xy 330.3397 -384.35026) (xy 330.3397 -385.21386) (xy 330.339214 -385.241111)
			(xy 330.331458 -385.295059) (xy 330.318606 -385.338828) (xy 359.423716 -385.338828) (xy 359.423716 -384.475228)
			(xy 359.424202 -384.447977) (xy 359.431958 -384.394029) (xy 359.447313 -384.341734) (xy 359.469955 -384.292157)
			(xy 359.499421 -384.246307) (xy 359.535112 -384.205116) (xy 359.576303 -384.169425) (xy 359.622153 -384.139959)
			(xy 359.67173 -384.117317) (xy 359.724025 -384.101962) (xy 359.777973 -384.094206) (xy 359.832475 -384.094206)
			(xy 359.886423 -384.101962) (xy 359.938718 -384.117317) (xy 359.988295 -384.139959) (xy 360.034145 -384.169425)
			(xy 360.075336 -384.205116) (xy 360.111027 -384.246307) (xy 360.140493 -384.292157) (xy 360.163135 -384.341734)
			(xy 360.17849 -384.394029) (xy 360.186246 -384.447977) (xy 360.186732 -384.475228) (xy 360.186732 -385.21386)
			(xy 364.149132 -385.21386) (xy 364.149132 -384.35026) (xy 364.149618 -384.323009) (xy 364.157374 -384.269061)
			(xy 364.172729 -384.216766) (xy 364.195371 -384.167189) (xy 364.224837 -384.121339) (xy 364.260528 -384.080148)
			(xy 364.301719 -384.044457) (xy 364.347569 -384.014991) (xy 364.397146 -383.992349) (xy 364.449441 -383.976994)
			(xy 364.503389 -383.969238) (xy 364.557891 -383.969238) (xy 364.611839 -383.976994) (xy 364.664134 -383.992349)
			(xy 364.713711 -384.014991) (xy 364.759561 -384.044457) (xy 364.800752 -384.080148) (xy 364.836443 -384.121339)
			(xy 364.865909 -384.167189) (xy 364.888551 -384.216766) (xy 364.903906 -384.269061) (xy 364.911662 -384.323009)
			(xy 364.912148 -384.35026) (xy 364.912148 -385.21386) (xy 364.911662 -385.241111) (xy 364.903906 -385.295059)
			(xy 364.891054 -385.338828) (xy 393.996164 -385.338828) (xy 393.996164 -384.475228) (xy 393.99665 -384.447977)
			(xy 394.004406 -384.394029) (xy 394.019761 -384.341734) (xy 394.042403 -384.292157) (xy 394.071869 -384.246307)
			(xy 394.10756 -384.205116) (xy 394.148751 -384.169425) (xy 394.194601 -384.139959) (xy 394.244178 -384.117317)
			(xy 394.296473 -384.101962) (xy 394.350421 -384.094206) (xy 394.404923 -384.094206) (xy 394.458871 -384.101962)
			(xy 394.511166 -384.117317) (xy 394.560743 -384.139959) (xy 394.606593 -384.169425) (xy 394.647784 -384.205116)
			(xy 394.683475 -384.246307) (xy 394.712941 -384.292157) (xy 394.735583 -384.341734) (xy 394.750938 -384.394029)
			(xy 394.758694 -384.447977) (xy 394.75918 -384.475228) (xy 394.75918 -385.21386) (xy 396.67688 -385.21386)
			(xy 396.67688 -384.35026) (xy 396.677366 -384.323009) (xy 396.685122 -384.269061) (xy 396.700477 -384.216766)
			(xy 396.723119 -384.167189) (xy 396.752585 -384.121339) (xy 396.788276 -384.080148) (xy 396.829467 -384.044457)
			(xy 396.875317 -384.014991) (xy 396.924894 -383.992349) (xy 396.977189 -383.976994) (xy 397.031137 -383.969238)
			(xy 397.085639 -383.969238) (xy 397.139587 -383.976994) (xy 397.191882 -383.992349) (xy 397.241459 -384.014991)
			(xy 397.287309 -384.044457) (xy 397.3285 -384.080148) (xy 397.364191 -384.121339) (xy 397.393657 -384.167189)
			(xy 397.416299 -384.216766) (xy 397.431654 -384.269061) (xy 397.43941 -384.323009) (xy 397.439896 -384.35026)
			(xy 397.439896 -385.21386) (xy 397.43941 -385.241111) (xy 397.431654 -385.295059) (xy 397.418802 -385.338828)
			(xy 426.523912 -385.338828) (xy 426.523912 -384.475228) (xy 426.524398 -384.447977) (xy 426.532154 -384.394029)
			(xy 426.547509 -384.341734) (xy 426.570151 -384.292157) (xy 426.599617 -384.246307) (xy 426.635308 -384.205116)
			(xy 426.676499 -384.169425) (xy 426.722349 -384.139959) (xy 426.771926 -384.117317) (xy 426.824221 -384.101962)
			(xy 426.878169 -384.094206) (xy 426.932671 -384.094206) (xy 426.986619 -384.101962) (xy 427.038914 -384.117317)
			(xy 427.088491 -384.139959) (xy 427.134341 -384.169425) (xy 427.175532 -384.205116) (xy 427.211223 -384.246307)
			(xy 427.240689 -384.292157) (xy 427.263331 -384.341734) (xy 427.278686 -384.394029) (xy 427.286442 -384.447977)
			(xy 427.286928 -384.475228) (xy 427.286928 -384.869944) (xy 429.498772 -384.869944) (xy 429.502744 -384.691701)
			(xy 429.514652 -384.513812) (xy 429.534473 -384.33663) (xy 429.562167 -384.160506) (xy 429.597679 -383.985791)
			(xy 429.640939 -383.812832) (xy 429.691861 -383.641971) (xy 429.750344 -383.473549) (xy 429.816271 -383.307899)
			(xy 429.889512 -383.14535) (xy 429.969922 -382.986225) (xy 430.05734 -382.83084) (xy 430.151593 -382.679504)
			(xy 430.252494 -382.532516) (xy 430.359843 -382.390169) (xy 430.473426 -382.252746) (xy 430.593019 -382.120519)
			(xy 430.718383 -381.99375) (xy 430.84927 -381.872692) (xy 430.985419 -381.757585) (xy 431.126561 -381.648657)
			(xy 431.272416 -381.546125) (xy 431.422693 -381.450191) (xy 431.577094 -381.361048) (xy 431.735313 -381.278871)
			(xy 431.897036 -381.203823) (xy 432.061941 -381.136055) (xy 432.229702 -381.075699) (xy 432.399985 -381.022877)
			(xy 432.572452 -380.977693) (xy 432.74676 -380.940236) (xy 432.922564 -380.910582) (xy 433.099514 -380.888789)
			(xy 433.27726 -380.874899) (xy 433.455447 -380.868942) (xy 433.633724 -380.870928) (xy 433.811735 -380.880854)
			(xy 433.989127 -380.8987) (xy 434.165547 -380.92443) (xy 434.340647 -380.957994) (xy 434.514078 -380.999324)
			(xy 434.685495 -381.04834) (xy 434.854558 -381.104942) (xy 435.020933 -381.16902) (xy 435.184287 -381.240446)
			(xy 435.344298 -381.319078) (xy 435.500647 -381.404759) (xy 435.653024 -381.497321) (xy 435.801127 -381.596578)
			(xy 435.944661 -381.702335) (xy 436.083341 -381.81438) (xy 436.216892 -381.932492) (xy 436.345049 -382.056436)
			(xy 436.467558 -382.185966) (xy 436.584175 -382.320825) (xy 436.694668 -382.460745) (xy 436.798819 -382.605448)
			(xy 436.896421 -382.754647) (xy 436.987279 -382.908046) (xy 437.071213 -383.06534) (xy 437.148058 -383.226216)
			(xy 437.217659 -383.390357) (xy 437.27988 -383.557434) (xy 437.334596 -383.727118) (xy 437.381698 -383.899071)
			(xy 437.421094 -384.072951) (xy 437.452705 -384.248414) (xy 437.476469 -384.42511) (xy 437.492337 -384.60269)
			(xy 437.500279 -384.7808) (xy 437.500776 -384.869944) (xy 437.500279 -384.959088) (xy 437.492337 -385.137198)
			(xy 437.476469 -385.314778) (xy 437.452705 -385.491474) (xy 437.421094 -385.666937) (xy 437.381698 -385.840817)
			(xy 437.334596 -386.01277) (xy 437.27988 -386.182454) (xy 437.217659 -386.349531) (xy 437.148058 -386.513672)
			(xy 437.071213 -386.674548) (xy 436.987279 -386.831842) (xy 436.896421 -386.985241) (xy 436.798819 -387.13444)
			(xy 436.694668 -387.279143) (xy 436.584175 -387.419063) (xy 436.467558 -387.553922) (xy 436.345049 -387.683452)
			(xy 436.216892 -387.807396) (xy 436.083341 -387.925508) (xy 435.944661 -388.037553) (xy 435.801127 -388.14331)
			(xy 435.653024 -388.242567) (xy 435.500647 -388.335129) (xy 435.344298 -388.42081) (xy 435.184287 -388.499442)
			(xy 435.020933 -388.570868) (xy 434.854558 -388.634946) (xy 434.685495 -388.691548) (xy 434.514078 -388.740564)
			(xy 434.340647 -388.781894) (xy 434.165547 -388.815458) (xy 433.989127 -388.841188) (xy 433.811735 -388.859034)
			(xy 433.633724 -388.86896) (xy 433.455447 -388.870946) (xy 433.27726 -388.864989) (xy 433.099514 -388.851099)
			(xy 432.922564 -388.829306) (xy 432.74676 -388.799652) (xy 432.572452 -388.762195) (xy 432.399985 -388.717011)
			(xy 432.229702 -388.664189) (xy 432.061941 -388.603833) (xy 431.897036 -388.536065) (xy 431.735313 -388.461017)
			(xy 431.577094 -388.37884) (xy 431.422693 -388.289697) (xy 431.272416 -388.193763) (xy 431.126561 -388.091231)
			(xy 430.985419 -387.982303) (xy 430.84927 -387.867196) (xy 430.718383 -387.746138) (xy 430.593019 -387.619369)
			(xy 430.473426 -387.487142) (xy 430.359843 -387.349719) (xy 430.252494 -387.207372) (xy 430.151593 -387.060384)
			(xy 430.05734 -386.909048) (xy 429.969922 -386.753663) (xy 429.889512 -386.594538) (xy 429.816271 -386.431989)
			(xy 429.750344 -386.266339) (xy 429.691861 -386.097917) (xy 429.640939 -385.927056) (xy 429.597679 -385.754097)
			(xy 429.562167 -385.579382) (xy 429.534473 -385.403258) (xy 429.514652 -385.226076) (xy 429.502744 -385.048187)
			(xy 429.498772 -384.869944) (xy 427.286928 -384.869944) (xy 427.286928 -385.338828) (xy 427.286442 -385.366079)
			(xy 427.278686 -385.420027) (xy 427.263331 -385.472322) (xy 427.240689 -385.521899) (xy 427.211223 -385.567749)
			(xy 427.175532 -385.60894) (xy 427.134341 -385.644631) (xy 427.088491 -385.674097) (xy 427.038914 -385.696739)
			(xy 426.986619 -385.712094) (xy 426.932671 -385.71985) (xy 426.878169 -385.71985) (xy 426.824221 -385.712094)
			(xy 426.771926 -385.696739) (xy 426.722349 -385.674097) (xy 426.676499 -385.644631) (xy 426.635308 -385.60894)
			(xy 426.599617 -385.567749) (xy 426.570151 -385.521899) (xy 426.547509 -385.472322) (xy 426.532154 -385.420027)
			(xy 426.524398 -385.366079) (xy 426.523912 -385.338828) (xy 397.418802 -385.338828) (xy 397.416299 -385.347354)
			(xy 397.393657 -385.396931) (xy 397.364191 -385.442781) (xy 397.3285 -385.483972) (xy 397.287309 -385.519663)
			(xy 397.241459 -385.549129) (xy 397.191882 -385.571771) (xy 397.139587 -385.587126) (xy 397.085639 -385.594882)
			(xy 397.031137 -385.594882) (xy 396.977189 -385.587126) (xy 396.924894 -385.571771) (xy 396.875317 -385.549129)
			(xy 396.829467 -385.519663) (xy 396.788276 -385.483972) (xy 396.752585 -385.442781) (xy 396.723119 -385.396931)
			(xy 396.700477 -385.347354) (xy 396.685122 -385.295059) (xy 396.677366 -385.241111) (xy 396.67688 -385.21386)
			(xy 394.75918 -385.21386) (xy 394.75918 -385.338828) (xy 394.758694 -385.366079) (xy 394.750938 -385.420027)
			(xy 394.735583 -385.472322) (xy 394.712941 -385.521899) (xy 394.683475 -385.567749) (xy 394.647784 -385.60894)
			(xy 394.606593 -385.644631) (xy 394.560743 -385.674097) (xy 394.511166 -385.696739) (xy 394.458871 -385.712094)
			(xy 394.404923 -385.71985) (xy 394.350421 -385.71985) (xy 394.296473 -385.712094) (xy 394.244178 -385.696739)
			(xy 394.194601 -385.674097) (xy 394.148751 -385.644631) (xy 394.10756 -385.60894) (xy 394.071869 -385.567749)
			(xy 394.042403 -385.521899) (xy 394.019761 -385.472322) (xy 394.004406 -385.420027) (xy 393.99665 -385.366079)
			(xy 393.996164 -385.338828) (xy 364.891054 -385.338828) (xy 364.888551 -385.347354) (xy 364.865909 -385.396931)
			(xy 364.836443 -385.442781) (xy 364.800752 -385.483972) (xy 364.759561 -385.519663) (xy 364.713711 -385.549129)
			(xy 364.664134 -385.571771) (xy 364.611839 -385.587126) (xy 364.557891 -385.594882) (xy 364.503389 -385.594882)
			(xy 364.449441 -385.587126) (xy 364.397146 -385.571771) (xy 364.347569 -385.549129) (xy 364.301719 -385.519663)
			(xy 364.260528 -385.483972) (xy 364.224837 -385.442781) (xy 364.195371 -385.396931) (xy 364.172729 -385.347354)
			(xy 364.157374 -385.295059) (xy 364.149618 -385.241111) (xy 364.149132 -385.21386) (xy 360.186732 -385.21386)
			(xy 360.186732 -385.338828) (xy 360.186246 -385.366079) (xy 360.17849 -385.420027) (xy 360.163135 -385.472322)
			(xy 360.140493 -385.521899) (xy 360.111027 -385.567749) (xy 360.075336 -385.60894) (xy 360.034145 -385.644631)
			(xy 359.988295 -385.674097) (xy 359.938718 -385.696739) (xy 359.886423 -385.712094) (xy 359.832475 -385.71985)
			(xy 359.777973 -385.71985) (xy 359.724025 -385.712094) (xy 359.67173 -385.696739) (xy 359.622153 -385.674097)
			(xy 359.576303 -385.644631) (xy 359.535112 -385.60894) (xy 359.499421 -385.567749) (xy 359.469955 -385.521899)
			(xy 359.447313 -385.472322) (xy 359.431958 -385.420027) (xy 359.424202 -385.366079) (xy 359.423716 -385.338828)
			(xy 330.318606 -385.338828) (xy 330.316103 -385.347354) (xy 330.293461 -385.396931) (xy 330.263995 -385.442781)
			(xy 330.228304 -385.483972) (xy 330.187113 -385.519663) (xy 330.141263 -385.549129) (xy 330.091686 -385.571771)
			(xy 330.039391 -385.587126) (xy 329.985443 -385.594882) (xy 329.930941 -385.594882) (xy 329.876993 -385.587126)
			(xy 329.824698 -385.571771) (xy 329.775121 -385.549129) (xy 329.729271 -385.519663) (xy 329.68808 -385.483972)
			(xy 329.652389 -385.442781) (xy 329.622923 -385.396931) (xy 329.600281 -385.347354) (xy 329.584926 -385.295059)
			(xy 329.57717 -385.241111) (xy 329.576684 -385.21386) (xy 327.658984 -385.21386) (xy 327.658984 -385.338828)
			(xy 327.658498 -385.366079) (xy 327.650742 -385.420027) (xy 327.635387 -385.472322) (xy 327.612745 -385.521899)
			(xy 327.583279 -385.567749) (xy 327.547588 -385.60894) (xy 327.506397 -385.644631) (xy 327.460547 -385.674097)
			(xy 327.41097 -385.696739) (xy 327.358675 -385.712094) (xy 327.304727 -385.71985) (xy 327.250225 -385.71985)
			(xy 327.196277 -385.712094) (xy 327.143982 -385.696739) (xy 327.094405 -385.674097) (xy 327.048555 -385.644631)
			(xy 327.007364 -385.60894) (xy 326.971673 -385.567749) (xy 326.942207 -385.521899) (xy 326.919565 -385.472322)
			(xy 326.90421 -385.420027) (xy 326.896454 -385.366079) (xy 326.895968 -385.338828) (xy 297.790858 -385.338828)
			(xy 297.788355 -385.347354) (xy 297.765713 -385.396931) (xy 297.736247 -385.442781) (xy 297.700556 -385.483972)
			(xy 297.659365 -385.519663) (xy 297.613515 -385.549129) (xy 297.563938 -385.571771) (xy 297.511643 -385.587126)
			(xy 297.457695 -385.594882) (xy 297.403193 -385.594882) (xy 297.349245 -385.587126) (xy 297.29695 -385.571771)
			(xy 297.247373 -385.549129) (xy 297.201523 -385.519663) (xy 297.160332 -385.483972) (xy 297.124641 -385.442781)
			(xy 297.095175 -385.396931) (xy 297.072533 -385.347354) (xy 297.057178 -385.295059) (xy 297.049422 -385.241111)
			(xy 297.048936 -385.21386) (xy 295.055495 -385.21386) (xy 295.046477 -385.314778) (xy 295.022713 -385.491474)
			(xy 294.991102 -385.666937) (xy 294.951706 -385.840817) (xy 294.904604 -386.01277) (xy 294.849888 -386.182454)
			(xy 294.787667 -386.349531) (xy 294.718066 -386.513672) (xy 294.641221 -386.674548) (xy 294.557287 -386.831842)
			(xy 294.466429 -386.985241) (xy 294.368827 -387.13444) (xy 294.264676 -387.279143) (xy 294.154183 -387.419063)
			(xy 294.037566 -387.553922) (xy 293.915057 -387.683452) (xy 293.7869 -387.807396) (xy 293.653349 -387.925508)
			(xy 293.514669 -388.037553) (xy 293.371135 -388.14331) (xy 293.223032 -388.242567) (xy 293.070655 -388.335129)
			(xy 292.914306 -388.42081) (xy 292.754295 -388.499442) (xy 292.590941 -388.570868) (xy 292.424566 -388.634946)
			(xy 292.255503 -388.691548) (xy 292.084086 -388.740564) (xy 292.076264 -388.742428) (xy 326.895968 -388.742428)
			(xy 326.895968 -387.878828) (xy 326.896454 -387.851577) (xy 326.90421 -387.797629) (xy 326.919565 -387.745334)
			(xy 326.942207 -387.695757) (xy 326.971673 -387.649907) (xy 327.007364 -387.608716) (xy 327.048555 -387.573025)
			(xy 327.094405 -387.543559) (xy 327.143982 -387.520917) (xy 327.196277 -387.505562) (xy 327.250225 -387.497806)
			(xy 327.304727 -387.497806) (xy 327.358675 -387.505562) (xy 327.41097 -387.520917) (xy 327.460547 -387.543559)
			(xy 327.506397 -387.573025) (xy 327.547588 -387.608716) (xy 327.583279 -387.649907) (xy 327.612745 -387.695757)
			(xy 327.635387 -387.745334) (xy 327.650742 -387.797629) (xy 327.658498 -387.851577) (xy 327.658984 -387.878828)
			(xy 327.658984 -388.742428) (xy 359.423716 -388.742428) (xy 359.423716 -387.878828) (xy 359.424202 -387.851577)
			(xy 359.431958 -387.797629) (xy 359.447313 -387.745334) (xy 359.469955 -387.695757) (xy 359.499421 -387.649907)
			(xy 359.535112 -387.608716) (xy 359.576303 -387.573025) (xy 359.622153 -387.543559) (xy 359.67173 -387.520917)
			(xy 359.724025 -387.505562) (xy 359.777973 -387.497806) (xy 359.832475 -387.497806) (xy 359.886423 -387.505562)
			(xy 359.938718 -387.520917) (xy 359.988295 -387.543559) (xy 360.034145 -387.573025) (xy 360.075336 -387.608716)
			(xy 360.111027 -387.649907) (xy 360.140493 -387.695757) (xy 360.163135 -387.745334) (xy 360.17849 -387.797629)
			(xy 360.186246 -387.851577) (xy 360.186732 -387.878828) (xy 360.186732 -388.742428) (xy 393.996164 -388.742428)
			(xy 393.996164 -387.878828) (xy 393.99665 -387.851577) (xy 394.004406 -387.797629) (xy 394.019761 -387.745334)
			(xy 394.042403 -387.695757) (xy 394.071869 -387.649907) (xy 394.10756 -387.608716) (xy 394.148751 -387.573025)
			(xy 394.194601 -387.543559) (xy 394.244178 -387.520917) (xy 394.296473 -387.505562) (xy 394.350421 -387.497806)
			(xy 394.404923 -387.497806) (xy 394.458871 -387.505562) (xy 394.511166 -387.520917) (xy 394.560743 -387.543559)
			(xy 394.606593 -387.573025) (xy 394.647784 -387.608716) (xy 394.683475 -387.649907) (xy 394.712941 -387.695757)
			(xy 394.735583 -387.745334) (xy 394.750938 -387.797629) (xy 394.758694 -387.851577) (xy 394.75918 -387.878828)
			(xy 394.75918 -388.742428) (xy 426.523912 -388.742428) (xy 426.523912 -387.878828) (xy 426.524398 -387.851577)
			(xy 426.532154 -387.797629) (xy 426.547509 -387.745334) (xy 426.570151 -387.695757) (xy 426.599617 -387.649907)
			(xy 426.635308 -387.608716) (xy 426.676499 -387.573025) (xy 426.722349 -387.543559) (xy 426.771926 -387.520917)
			(xy 426.824221 -387.505562) (xy 426.878169 -387.497806) (xy 426.932671 -387.497806) (xy 426.986619 -387.505562)
			(xy 427.038914 -387.520917) (xy 427.088491 -387.543559) (xy 427.134341 -387.573025) (xy 427.175532 -387.608716)
			(xy 427.211223 -387.649907) (xy 427.240689 -387.695757) (xy 427.263331 -387.745334) (xy 427.278686 -387.797629)
			(xy 427.286442 -387.851577) (xy 427.286928 -387.878828) (xy 427.286928 -388.742428) (xy 427.286442 -388.769679)
			(xy 427.278686 -388.823627) (xy 427.263331 -388.875922) (xy 427.240689 -388.925499) (xy 427.211223 -388.971349)
			(xy 427.175532 -389.01254) (xy 427.134341 -389.048231) (xy 427.088491 -389.077697) (xy 427.038914 -389.100339)
			(xy 426.986619 -389.115694) (xy 426.932671 -389.12345) (xy 426.878169 -389.12345) (xy 426.824221 -389.115694)
			(xy 426.771926 -389.100339) (xy 426.722349 -389.077697) (xy 426.676499 -389.048231) (xy 426.635308 -389.01254)
			(xy 426.599617 -388.971349) (xy 426.570151 -388.925499) (xy 426.547509 -388.875922) (xy 426.532154 -388.823627)
			(xy 426.524398 -388.769679) (xy 426.523912 -388.742428) (xy 394.75918 -388.742428) (xy 394.758694 -388.769679)
			(xy 394.750938 -388.823627) (xy 394.735583 -388.875922) (xy 394.712941 -388.925499) (xy 394.683475 -388.971349)
			(xy 394.647784 -389.01254) (xy 394.606593 -389.048231) (xy 394.560743 -389.077697) (xy 394.511166 -389.100339)
			(xy 394.458871 -389.115694) (xy 394.404923 -389.12345) (xy 394.350421 -389.12345) (xy 394.296473 -389.115694)
			(xy 394.244178 -389.100339) (xy 394.194601 -389.077697) (xy 394.148751 -389.048231) (xy 394.10756 -389.01254)
			(xy 394.071869 -388.971349) (xy 394.042403 -388.925499) (xy 394.019761 -388.875922) (xy 394.004406 -388.823627)
			(xy 393.99665 -388.769679) (xy 393.996164 -388.742428) (xy 360.186732 -388.742428) (xy 360.186246 -388.769679)
			(xy 360.17849 -388.823627) (xy 360.163135 -388.875922) (xy 360.140493 -388.925499) (xy 360.111027 -388.971349)
			(xy 360.075336 -389.01254) (xy 360.034145 -389.048231) (xy 359.988295 -389.077697) (xy 359.938718 -389.100339)
			(xy 359.886423 -389.115694) (xy 359.832475 -389.12345) (xy 359.777973 -389.12345) (xy 359.724025 -389.115694)
			(xy 359.67173 -389.100339) (xy 359.622153 -389.077697) (xy 359.576303 -389.048231) (xy 359.535112 -389.01254)
			(xy 359.499421 -388.971349) (xy 359.469955 -388.925499) (xy 359.447313 -388.875922) (xy 359.431958 -388.823627)
			(xy 359.424202 -388.769679) (xy 359.423716 -388.742428) (xy 327.658984 -388.742428) (xy 327.658498 -388.769679)
			(xy 327.650742 -388.823627) (xy 327.635387 -388.875922) (xy 327.612745 -388.925499) (xy 327.583279 -388.971349)
			(xy 327.547588 -389.01254) (xy 327.506397 -389.048231) (xy 327.460547 -389.077697) (xy 327.41097 -389.100339)
			(xy 327.358675 -389.115694) (xy 327.304727 -389.12345) (xy 327.250225 -389.12345) (xy 327.196277 -389.115694)
			(xy 327.143982 -389.100339) (xy 327.094405 -389.077697) (xy 327.048555 -389.048231) (xy 327.007364 -389.01254)
			(xy 326.971673 -388.971349) (xy 326.942207 -388.925499) (xy 326.919565 -388.875922) (xy 326.90421 -388.823627)
			(xy 326.896454 -388.769679) (xy 326.895968 -388.742428) (xy 292.076264 -388.742428) (xy 291.910655 -388.781894)
			(xy 291.735555 -388.815458) (xy 291.559135 -388.841188) (xy 291.381743 -388.859034) (xy 291.203732 -388.86896)
			(xy 291.025455 -388.870946) (xy 290.847268 -388.864989) (xy 290.669522 -388.851099) (xy 290.492572 -388.829306)
			(xy 290.316768 -388.799652) (xy 290.14246 -388.762195) (xy 289.969993 -388.717011) (xy 289.79971 -388.664189)
			(xy 289.631949 -388.603833) (xy 289.467044 -388.536065) (xy 289.305321 -388.461017) (xy 289.147102 -388.37884)
			(xy 288.992701 -388.289697) (xy 288.842424 -388.193763) (xy 288.696569 -388.091231) (xy 288.555427 -387.982303)
			(xy 288.419278 -387.867196) (xy 288.288391 -387.746138) (xy 288.163027 -387.619369) (xy 288.043434 -387.487142)
			(xy 287.929851 -387.349719) (xy 287.822502 -387.207372) (xy 287.721601 -387.060384) (xy 287.627348 -386.909048)
			(xy 287.53993 -386.753663) (xy 287.45952 -386.594538) (xy 287.386279 -386.431989) (xy 287.320352 -386.266339)
			(xy 287.261869 -386.097917) (xy 287.210947 -385.927056) (xy 287.167687 -385.754097) (xy 287.132175 -385.579382)
			(xy 287.104481 -385.403258) (xy 287.08466 -385.226076) (xy 287.072752 -385.048187) (xy 287.06878 -384.869944)
			(xy 281.2288 -384.869944) (xy 281.2288 -387.375146) (xy 281.245056 -387.400292) (xy 281.258772 -387.406388)
			(xy 281.283524 -387.41805) (xy 281.329666 -387.447457) (xy 281.371135 -387.483154) (xy 281.407078 -387.524408)
			(xy 281.43676 -387.570374) (xy 281.45957 -387.620109) (xy 281.475042 -387.672592) (xy 281.482858 -387.726748)
			(xy 281.482857 -387.781464) (xy 281.47504 -387.835619) (xy 281.459566 -387.888102) (xy 281.436754 -387.937836)
			(xy 281.407071 -387.983801) (xy 281.371126 -388.025055) (xy 281.329657 -388.06075) (xy 281.283514 -388.090155)
			(xy 281.258772 -388.10184) (xy 281.245056 -388.107936) (xy 281.2288 -388.133082) (xy 281.2288 -390.75106)
			(xy 297.048936 -390.75106) (xy 297.048936 -389.88746) (xy 297.049422 -389.860209) (xy 297.057178 -389.806261)
			(xy 297.072533 -389.753966) (xy 297.095175 -389.704389) (xy 297.124641 -389.658539) (xy 297.160332 -389.617348)
			(xy 297.201523 -389.581657) (xy 297.247373 -389.552191) (xy 297.29695 -389.529549) (xy 297.349245 -389.514194)
			(xy 297.403193 -389.506438) (xy 297.457695 -389.506438) (xy 297.511643 -389.514194) (xy 297.563938 -389.529549)
			(xy 297.613515 -389.552191) (xy 297.659365 -389.581657) (xy 297.700556 -389.617348) (xy 297.736247 -389.658539)
			(xy 297.765713 -389.704389) (xy 297.788355 -389.753966) (xy 297.80371 -389.806261) (xy 297.811466 -389.860209)
			(xy 297.811952 -389.88746) (xy 297.811952 -390.75106) (xy 329.576684 -390.75106) (xy 329.576684 -389.88746)
			(xy 329.57717 -389.860209) (xy 329.584926 -389.806261) (xy 329.600281 -389.753966) (xy 329.622923 -389.704389)
			(xy 329.652389 -389.658539) (xy 329.68808 -389.617348) (xy 329.729271 -389.581657) (xy 329.775121 -389.552191)
			(xy 329.824698 -389.529549) (xy 329.876993 -389.514194) (xy 329.930941 -389.506438) (xy 329.985443 -389.506438)
			(xy 330.039391 -389.514194) (xy 330.091686 -389.529549) (xy 330.141263 -389.552191) (xy 330.187113 -389.581657)
			(xy 330.228304 -389.617348) (xy 330.263995 -389.658539) (xy 330.293461 -389.704389) (xy 330.316103 -389.753966)
			(xy 330.331458 -389.806261) (xy 330.339214 -389.860209) (xy 330.3397 -389.88746) (xy 330.3397 -390.75106)
			(xy 364.149132 -390.75106) (xy 364.149132 -389.88746) (xy 364.149618 -389.860209) (xy 364.157374 -389.806261)
			(xy 364.172729 -389.753966) (xy 364.195371 -389.704389) (xy 364.224837 -389.658539) (xy 364.260528 -389.617348)
			(xy 364.301719 -389.581657) (xy 364.347569 -389.552191) (xy 364.397146 -389.529549) (xy 364.449441 -389.514194)
			(xy 364.503389 -389.506438) (xy 364.557891 -389.506438) (xy 364.611839 -389.514194) (xy 364.664134 -389.529549)
			(xy 364.713711 -389.552191) (xy 364.759561 -389.581657) (xy 364.800752 -389.617348) (xy 364.836443 -389.658539)
			(xy 364.865909 -389.704389) (xy 364.888551 -389.753966) (xy 364.903906 -389.806261) (xy 364.911662 -389.860209)
			(xy 364.912148 -389.88746) (xy 364.912148 -390.75106) (xy 396.67688 -390.75106) (xy 396.67688 -389.88746)
			(xy 396.677366 -389.860209) (xy 396.685122 -389.806261) (xy 396.700477 -389.753966) (xy 396.723119 -389.704389)
			(xy 396.752585 -389.658539) (xy 396.788276 -389.617348) (xy 396.829467 -389.581657) (xy 396.875317 -389.552191)
			(xy 396.924894 -389.529549) (xy 396.977189 -389.514194) (xy 397.031137 -389.506438) (xy 397.085639 -389.506438)
			(xy 397.139587 -389.514194) (xy 397.191882 -389.529549) (xy 397.241459 -389.552191) (xy 397.287309 -389.581657)
			(xy 397.3285 -389.617348) (xy 397.364191 -389.658539) (xy 397.393657 -389.704389) (xy 397.416299 -389.753966)
			(xy 397.431654 -389.806261) (xy 397.43941 -389.860209) (xy 397.439896 -389.88746) (xy 397.439896 -390.75106)
			(xy 397.43941 -390.778311) (xy 397.431654 -390.832259) (xy 397.416299 -390.884554) (xy 397.393657 -390.934131)
			(xy 397.364191 -390.979981) (xy 397.3285 -391.021172) (xy 397.287309 -391.056863) (xy 397.241459 -391.086329)
			(xy 397.191882 -391.108971) (xy 397.139587 -391.124326) (xy 397.085639 -391.132082) (xy 397.031137 -391.132082)
			(xy 396.977189 -391.124326) (xy 396.924894 -391.108971) (xy 396.875317 -391.086329) (xy 396.829467 -391.056863)
			(xy 396.788276 -391.021172) (xy 396.752585 -390.979981) (xy 396.723119 -390.934131) (xy 396.700477 -390.884554)
			(xy 396.685122 -390.832259) (xy 396.677366 -390.778311) (xy 396.67688 -390.75106) (xy 364.912148 -390.75106)
			(xy 364.911662 -390.778311) (xy 364.903906 -390.832259) (xy 364.888551 -390.884554) (xy 364.865909 -390.934131)
			(xy 364.836443 -390.979981) (xy 364.800752 -391.021172) (xy 364.759561 -391.056863) (xy 364.713711 -391.086329)
			(xy 364.664134 -391.108971) (xy 364.611839 -391.124326) (xy 364.557891 -391.132082) (xy 364.503389 -391.132082)
			(xy 364.449441 -391.124326) (xy 364.397146 -391.108971) (xy 364.347569 -391.086329) (xy 364.301719 -391.056863)
			(xy 364.260528 -391.021172) (xy 364.224837 -390.979981) (xy 364.195371 -390.934131) (xy 364.172729 -390.884554)
			(xy 364.157374 -390.832259) (xy 364.149618 -390.778311) (xy 364.149132 -390.75106) (xy 330.3397 -390.75106)
			(xy 330.339214 -390.778311) (xy 330.331458 -390.832259) (xy 330.316103 -390.884554) (xy 330.293461 -390.934131)
			(xy 330.263995 -390.979981) (xy 330.228304 -391.021172) (xy 330.187113 -391.056863) (xy 330.141263 -391.086329)
			(xy 330.091686 -391.108971) (xy 330.039391 -391.124326) (xy 329.985443 -391.132082) (xy 329.930941 -391.132082)
			(xy 329.876993 -391.124326) (xy 329.824698 -391.108971) (xy 329.775121 -391.086329) (xy 329.729271 -391.056863)
			(xy 329.68808 -391.021172) (xy 329.652389 -390.979981) (xy 329.622923 -390.934131) (xy 329.600281 -390.884554)
			(xy 329.584926 -390.832259) (xy 329.57717 -390.778311) (xy 329.576684 -390.75106) (xy 297.811952 -390.75106)
			(xy 297.811466 -390.778311) (xy 297.80371 -390.832259) (xy 297.788355 -390.884554) (xy 297.765713 -390.934131)
			(xy 297.736247 -390.979981) (xy 297.700556 -391.021172) (xy 297.659365 -391.056863) (xy 297.613515 -391.086329)
			(xy 297.563938 -391.108971) (xy 297.511643 -391.124326) (xy 297.457695 -391.132082) (xy 297.403193 -391.132082)
			(xy 297.349245 -391.124326) (xy 297.29695 -391.108971) (xy 297.247373 -391.086329) (xy 297.201523 -391.056863)
			(xy 297.160332 -391.021172) (xy 297.124641 -390.979981) (xy 297.095175 -390.934131) (xy 297.072533 -390.884554)
			(xy 297.057178 -390.832259) (xy 297.049422 -390.778311) (xy 297.048936 -390.75106) (xy 281.2288 -390.75106)
			(xy 281.2288 -392.180572) (xy 281.228283 -392.20552) (xy 281.220475 -392.254803) (xy 281.205064 -392.30226)
			(xy 281.182426 -392.346726) (xy 281.153119 -392.387109) (xy 281.135836 -392.405108) (xy 280.810462 -392.730482)
			(xy 280.803632 -392.73789) (xy 280.795908 -392.756483) (xy 280.795476 -392.76655) (xy 280.795476 -393.110974)
			(xy 280.794938 -393.135921) (xy 280.787132 -393.185202) (xy 280.771724 -393.232658) (xy 280.749092 -393.277124)
			(xy 280.719792 -393.31751) (xy 280.702512 -393.33551) (xy 280.345134 -393.692888) (xy 303.485804 -393.692888)
			(xy 303.485804 -393.69238) (xy 303.486244 -393.668388) (xy 303.493754 -393.620994) (xy 303.508585 -393.575359)
			(xy 303.530372 -393.532605) (xy 303.558579 -393.493786) (xy 303.592511 -393.459858) (xy 303.631333 -393.431655)
			(xy 303.674088 -393.409872) (xy 303.719725 -393.395046) (xy 303.76712 -393.387542) (xy 303.791112 -393.387072)
			(xy 303.815046 -393.38757) (xy 303.862329 -393.395022) (xy 303.907871 -393.409757) (xy 303.950558 -393.431416)
			(xy 303.989344 -393.459467) (xy 304.02328 -393.493224) (xy 304.051536 -393.531861) (xy 304.062892 -393.552934)
			(xy 304.0634 -393.55395) (xy 304.143706 -393.692888) (xy 304.6857 -393.692888) (xy 304.6857 -393.69238)
			(xy 304.686144 -393.668388) (xy 304.693654 -393.620995) (xy 304.708484 -393.57536) (xy 304.730271 -393.532606)
			(xy 304.758477 -393.493788) (xy 304.792409 -393.459859) (xy 304.83123 -393.431656) (xy 304.873986 -393.409873)
			(xy 304.919622 -393.395047) (xy 304.967016 -393.387542) (xy 304.991008 -393.387072) (xy 305.014941 -393.387573)
			(xy 305.062224 -393.395024) (xy 305.107767 -393.409759) (xy 305.150453 -393.431417) (xy 305.189239 -393.459468)
			(xy 305.223176 -393.493224) (xy 305.251432 -393.531861) (xy 305.262788 -393.552934) (xy 305.263296 -393.55395)
			(xy 305.343602 -393.692888) (xy 305.885596 -393.692888) (xy 305.885596 -393.69238) (xy 305.886043 -393.668401)
			(xy 305.893544 -393.621032) (xy 305.908359 -393.575419) (xy 305.930124 -393.532684) (xy 305.958302 -393.493876)
			(xy 305.992201 -393.459951) (xy 306.030987 -393.431744) (xy 306.073707 -393.409948) (xy 306.119308 -393.395098)
			(xy 306.166671 -393.387561) (xy 306.19065 -393.387072) (xy 306.191158 -393.387072) (xy 306.215093 -393.387532)
			(xy 306.262378 -393.394992) (xy 306.307921 -393.409734) (xy 306.350607 -393.431398) (xy 306.389393 -393.459455)
			(xy 306.423328 -393.493217) (xy 306.451583 -393.531859) (xy 306.462938 -393.552934) (xy 306.463446 -393.55395)
			(xy 306.543752 -393.692888) (xy 307.085492 -393.692888) (xy 307.085492 -393.69238) (xy 307.085943 -393.668401)
			(xy 307.093444 -393.621033) (xy 307.108259 -393.57542) (xy 307.130023 -393.532685) (xy 307.158201 -393.493877)
			(xy 307.192099 -393.459953) (xy 307.230885 -393.431745) (xy 307.273604 -393.409949) (xy 307.319205 -393.395099)
			(xy 307.366567 -393.387562) (xy 307.390546 -393.387072) (xy 307.391054 -393.387072) (xy 307.414989 -393.387536)
			(xy 307.462274 -393.394994) (xy 307.507817 -393.409736) (xy 307.550503 -393.4314) (xy 307.589289 -393.459456)
			(xy 307.623224 -393.493218) (xy 307.651479 -393.531859) (xy 307.662834 -393.552934) (xy 307.663342 -393.55395)
			(xy 307.743648 -393.692888) (xy 308.285388 -393.692888) (xy 308.285388 -393.69238) (xy 308.285843 -393.668401)
			(xy 308.293344 -393.621034) (xy 308.308159 -393.575421) (xy 308.329922 -393.532686) (xy 308.358099 -393.493879)
			(xy 308.391998 -393.459954) (xy 308.430783 -393.431747) (xy 308.473501 -393.40995) (xy 308.519102 -393.3951)
			(xy 308.566463 -393.387562) (xy 308.590442 -393.387072) (xy 308.59095 -393.387072) (xy 308.614885 -393.387539)
			(xy 308.662169 -393.394997) (xy 308.707712 -393.409738) (xy 308.750399 -393.431401) (xy 308.789184 -393.459457)
			(xy 308.82312 -393.493218) (xy 308.851375 -393.531859) (xy 308.86273 -393.552934) (xy 308.863238 -393.55395)
			(xy 308.943544 -393.692888) (xy 309.485792 -393.692888) (xy 309.485792 -393.69238) (xy 309.486244 -393.668388)
			(xy 309.493753 -393.620996) (xy 309.508583 -393.575362) (xy 309.530369 -393.532609) (xy 309.558575 -393.49379)
			(xy 309.592506 -393.459862) (xy 309.631326 -393.431659) (xy 309.67408 -393.409876) (xy 309.719715 -393.395049)
			(xy 309.767108 -393.387543) (xy 309.7911 -393.387072) (xy 309.815033 -393.38758) (xy 309.862316 -393.39503)
			(xy 309.907858 -393.409764) (xy 309.950544 -393.43142) (xy 309.989331 -393.45947) (xy 310.023268 -393.493226)
			(xy 310.051524 -393.531862) (xy 310.06288 -393.552934) (xy 310.063388 -393.55395) (xy 310.143694 -393.692888)
			(xy 310.685688 -393.692888) (xy 310.685688 -393.69238) (xy 310.686144 -393.668388) (xy 310.693653 -393.620996)
			(xy 310.708483 -393.575362) (xy 310.730269 -393.53261) (xy 310.758474 -393.493792) (xy 310.792404 -393.459863)
			(xy 310.831224 -393.43166) (xy 310.873977 -393.409877) (xy 310.919612 -393.395049) (xy 310.967004 -393.387543)
			(xy 310.990996 -393.387072) (xy 311.014932 -393.387502) (xy 311.062218 -393.394966) (xy 311.107762 -393.409714)
			(xy 311.150449 -393.431384) (xy 311.189234 -393.459445) (xy 311.223168 -393.493212) (xy 311.251422 -393.531857)
			(xy 311.262776 -393.552934) (xy 311.263284 -393.55395) (xy 311.34359 -393.692888) (xy 311.885584 -393.692888)
			(xy 311.885584 -393.69238) (xy 311.886043 -393.668401) (xy 311.893544 -393.621034) (xy 311.908358 -393.575422)
			(xy 311.930121 -393.532687) (xy 311.958298 -393.49388) (xy 311.992196 -393.459956) (xy 312.03098 -393.431748)
			(xy 312.073698 -393.409951) (xy 312.119298 -393.395101) (xy 312.16666 -393.387562) (xy 312.190638 -393.387072)
			(xy 312.191146 -393.387072) (xy 312.215081 -393.387542) (xy 312.262365 -393.394999) (xy 312.307908 -393.40974)
			(xy 312.350594 -393.431403) (xy 312.38938 -393.459458) (xy 312.423316 -393.493219) (xy 312.451571 -393.531859)
			(xy 312.462926 -393.552934) (xy 312.463434 -393.55395) (xy 312.54374 -393.692888) (xy 313.08548 -393.692888)
			(xy 313.08548 -393.69238) (xy 313.085943 -393.668402) (xy 313.093444 -393.621035) (xy 313.108258 -393.575423)
			(xy 313.130021 -393.532688) (xy 313.158197 -393.493882) (xy 313.192094 -393.459957) (xy 313.230878 -393.431749)
			(xy 313.273595 -393.409952) (xy 313.319195 -393.395101) (xy 313.366556 -393.387562) (xy 313.390534 -393.387072)
			(xy 313.391042 -393.387072) (xy 313.414976 -393.387545) (xy 313.462261 -393.395002) (xy 313.507803 -393.409742)
			(xy 313.55049 -393.431404) (xy 313.589276 -393.459459) (xy 313.623212 -393.49322) (xy 313.651467 -393.53186)
			(xy 313.662822 -393.552934) (xy 313.66333 -393.55395) (xy 313.743636 -393.692888) (xy 314.285376 -393.692888)
			(xy 314.285376 -393.69238) (xy 314.285821 -393.668374) (xy 314.293338 -393.620955) (xy 314.308183 -393.575297)
			(xy 314.329992 -393.532525) (xy 314.358226 -393.493693) (xy 314.392189 -393.459758) (xy 314.431045 -393.431557)
			(xy 314.473836 -393.409785) (xy 314.519507 -393.394977) (xy 314.566932 -393.3875) (xy 314.590938 -393.387072)
			(xy 314.591446 -393.387072) (xy 314.615381 -393.387542) (xy 314.662665 -393.394999) (xy 314.708208 -393.40974)
			(xy 314.750894 -393.431403) (xy 314.78968 -393.459458) (xy 314.823616 -393.493219) (xy 314.851871 -393.531859)
			(xy 314.863226 -393.552934) (xy 314.863734 -393.55395) (xy 314.94404 -393.692888) (xy 315.48578 -393.692888)
			(xy 315.48578 -393.69238) (xy 315.486244 -393.668389) (xy 315.493753 -393.620998) (xy 315.508582 -393.575364)
			(xy 315.530367 -393.532612) (xy 315.558571 -393.493795) (xy 315.592501 -393.459866) (xy 315.631319 -393.431663)
			(xy 315.674072 -393.409879) (xy 315.719705 -393.395051) (xy 315.767097 -393.387543) (xy 315.791088 -393.387072)
			(xy 315.791342 -393.387072) (xy 315.815276 -393.387545) (xy 315.862561 -393.395002) (xy 315.908103 -393.409742)
			(xy 315.95079 -393.431404) (xy 315.989576 -393.459459) (xy 316.023512 -393.49322) (xy 316.051767 -393.53186)
			(xy 316.063122 -393.552934) (xy 316.06363 -393.55395) (xy 316.143936 -393.692888) (xy 316.685676 -393.692888)
			(xy 316.685676 -393.69238) (xy 316.686144 -393.668389) (xy 316.693653 -393.620998) (xy 316.708482 -393.575365)
			(xy 316.730267 -393.532614) (xy 316.75847 -393.493796) (xy 316.792399 -393.459868) (xy 316.831217 -393.431664)
			(xy 316.873969 -393.40988) (xy 316.919602 -393.395052) (xy 316.966993 -393.387544) (xy 316.990984 -393.387072)
			(xy 316.991492 -393.387072) (xy 317.015428 -393.387505) (xy 317.062714 -393.394969) (xy 317.108258 -393.409716)
			(xy 317.150944 -393.431385) (xy 317.18973 -393.459446) (xy 317.223664 -393.493212) (xy 317.251918 -393.531857)
			(xy 317.263272 -393.552934) (xy 317.26378 -393.55395) (xy 317.344086 -393.692888) (xy 317.885572 -393.692888)
			(xy 317.885572 -393.69238) (xy 317.886021 -393.668375) (xy 317.893538 -393.620956) (xy 317.908383 -393.575298)
			(xy 317.930191 -393.532526) (xy 317.958425 -393.493694) (xy 317.992388 -393.45976) (xy 318.031243 -393.431558)
			(xy 318.074033 -393.409786) (xy 318.119703 -393.394978) (xy 318.167128 -393.387501) (xy 318.191134 -393.387072)
			(xy 318.191388 -393.387072) (xy 318.215324 -393.387508) (xy 318.26261 -393.394972) (xy 318.308153 -393.409718)
			(xy 318.35084 -393.431387) (xy 318.389625 -393.459447) (xy 318.42356 -393.493213) (xy 318.451814 -393.531858)
			(xy 318.463168 -393.552934) (xy 318.463676 -393.55395) (xy 318.543982 -393.692888) (xy 319.085468 -393.692888)
			(xy 319.085468 -393.69238) (xy 319.085921 -393.668375) (xy 319.093437 -393.620957) (xy 319.108283 -393.575299)
			(xy 319.130091 -393.532527) (xy 319.158324 -393.493696) (xy 319.192286 -393.459761) (xy 319.231141 -393.43156)
			(xy 319.27393 -393.409787) (xy 319.3196 -393.394979) (xy 319.367024 -393.387501) (xy 319.39103 -393.387072)
			(xy 319.391284 -393.387072) (xy 319.41522 -393.387511) (xy 319.462506 -393.394974) (xy 319.508049 -393.40972)
			(xy 319.550736 -393.431388) (xy 319.589521 -393.459448) (xy 319.623456 -393.493214) (xy 319.65171 -393.531858)
			(xy 319.663064 -393.552934) (xy 319.663572 -393.55395) (xy 319.743878 -393.692888) (xy 320.285872 -393.692888)
			(xy 320.285872 -393.69238) (xy 320.286344 -393.668389) (xy 320.293853 -393.620999) (xy 320.308681 -393.575366)
			(xy 320.330466 -393.532615) (xy 320.358669 -393.493797) (xy 320.392597 -393.459869) (xy 320.431415 -393.431666)
			(xy 320.474166 -393.409881) (xy 320.519799 -393.395053) (xy 320.567189 -393.387544) (xy 320.59118 -393.387072)
			(xy 320.591434 -393.387072) (xy 320.615368 -393.387552) (xy 320.662652 -393.395007) (xy 320.708195 -393.409746)
			(xy 320.750881 -393.431407) (xy 320.789667 -393.459461) (xy 320.823603 -393.493221) (xy 320.851859 -393.53186)
			(xy 320.863214 -393.552934) (xy 320.863722 -393.55395) (xy 320.944028 -393.692888) (xy 321.485768 -393.692888)
			(xy 321.485768 -393.69238) (xy 321.486244 -393.668389) (xy 321.493752 -393.620999) (xy 321.508581 -393.575367)
			(xy 321.530365 -393.532616) (xy 321.558568 -393.493799) (xy 321.592496 -393.459871) (xy 321.631313 -393.431667)
			(xy 321.674063 -393.409883) (xy 321.719695 -393.395053) (xy 321.767085 -393.387544) (xy 321.791076 -393.387072)
			(xy 321.79133 -393.387072) (xy 321.815264 -393.387555) (xy 321.862548 -393.39501) (xy 321.90809 -393.409748)
			(xy 321.950777 -393.431409) (xy 321.989563 -393.459462) (xy 322.023499 -393.493221) (xy 322.051755 -393.53186)
			(xy 322.06311 -393.552934) (xy 322.063618 -393.55395) (xy 322.143924 -393.692888) (xy 336.013552 -393.692888)
			(xy 336.013552 -393.69238) (xy 336.014044 -393.66839) (xy 336.021552 -393.621002) (xy 336.03638 -393.575371)
			(xy 336.058162 -393.532621) (xy 336.086363 -393.493804) (xy 336.120289 -393.459876) (xy 336.159104 -393.431673)
			(xy 336.201852 -393.409887) (xy 336.247482 -393.395057) (xy 336.29487 -393.387546) (xy 336.31886 -393.387072)
			(xy 336.342795 -393.387531) (xy 336.39008 -393.39499) (xy 336.435623 -393.409733) (xy 336.47831 -393.431398)
			(xy 336.517095 -393.459455) (xy 336.551031 -393.493217) (xy 336.579285 -393.531859) (xy 336.59064 -393.552934)
			(xy 336.591148 -393.55395) (xy 336.671454 -393.692888) (xy 337.213448 -393.692888) (xy 337.213448 -393.69238)
			(xy 337.213944 -393.66839) (xy 337.221452 -393.621002) (xy 337.236279 -393.575372) (xy 337.258061 -393.532622)
			(xy 337.286262 -393.493805) (xy 337.320187 -393.459878) (xy 337.359001 -393.431674) (xy 337.401749 -393.409888)
			(xy 337.447379 -393.395057) (xy 337.494766 -393.387546) (xy 337.518756 -393.387072) (xy 337.542691 -393.387534)
			(xy 337.589976 -393.394993) (xy 337.635519 -393.409735) (xy 337.678205 -393.431399) (xy 337.716991 -393.459456)
			(xy 337.750926 -393.493218) (xy 337.779181 -393.531859) (xy 337.790536 -393.552934) (xy 337.791044 -393.55395)
			(xy 337.87135 -393.692888) (xy 338.413344 -393.692888) (xy 338.413344 -393.69238) (xy 338.413843 -393.668403)
			(xy 338.421343 -393.62104) (xy 338.436154 -393.575431) (xy 338.457914 -393.532699) (xy 338.486087 -393.493894)
			(xy 338.519979 -393.45997) (xy 338.558758 -393.431762) (xy 338.60147 -393.409962) (xy 338.647065 -393.395109)
			(xy 338.694422 -393.387565) (xy 338.718398 -393.387072) (xy 338.718906 -393.387072) (xy 338.742839 -393.387575)
			(xy 338.790122 -393.395026) (xy 338.835664 -393.40976) (xy 338.878351 -393.431418) (xy 338.917137 -393.459468)
			(xy 338.951074 -393.493225) (xy 338.97933 -393.531861) (xy 338.990686 -393.552934) (xy 338.991194 -393.55395)
			(xy 339.0715 -393.692888) (xy 339.61324 -393.692888) (xy 339.61324 -393.69238) (xy 339.613643 -393.668399)
			(xy 339.621146 -393.621026) (xy 339.635964 -393.575409) (xy 339.657732 -393.53267) (xy 339.685915 -393.493861)
			(xy 339.719819 -393.459936) (xy 339.758612 -393.431729) (xy 339.801337 -393.409935) (xy 339.846945 -393.395089)
			(xy 339.894313 -393.387558) (xy 339.918294 -393.387072) (xy 339.918802 -393.387072) (xy 339.942735 -393.387578)
			(xy 339.990018 -393.395028) (xy 340.03556 -393.409763) (xy 340.078247 -393.43142) (xy 340.117033 -393.459469)
			(xy 340.15097 -393.493225) (xy 340.179226 -393.531861) (xy 340.190582 -393.552934) (xy 340.19109 -393.55395)
			(xy 340.271396 -393.692888) (xy 340.813136 -393.692888) (xy 340.813136 -393.69238) (xy 340.813543 -393.668399)
			(xy 340.821046 -393.621027) (xy 340.835863 -393.57541) (xy 340.857631 -393.532672) (xy 340.885813 -393.493862)
			(xy 340.919718 -393.459937) (xy 340.958509 -393.43173) (xy 341.001234 -393.409936) (xy 341.046841 -393.39509)
			(xy 341.094209 -393.387558) (xy 341.11819 -393.387072) (xy 341.118698 -393.387072) (xy 341.142634 -393.3875)
			(xy 341.189921 -393.394965) (xy 341.235464 -393.409713) (xy 341.278151 -393.431383) (xy 341.316936 -393.459445)
			(xy 341.35087 -393.493212) (xy 341.379124 -393.531857) (xy 341.390478 -393.552934) (xy 341.390986 -393.55395)
			(xy 341.471292 -393.692888) (xy 342.01354 -393.692888) (xy 342.01354 -393.69238) (xy 342.01392 -393.668384)
			(xy 342.021431 -393.620983) (xy 342.036265 -393.575341) (xy 342.058057 -393.532582) (xy 342.08627 -393.493758)
			(xy 342.12021 -393.459826) (xy 342.15904 -393.431622) (xy 342.201804 -393.409839) (xy 342.247449 -393.395015)
			(xy 342.294852 -393.387515) (xy 342.318848 -393.387072) (xy 342.342783 -393.387541) (xy 342.390067 -393.394998)
			(xy 342.43561 -393.409739) (xy 342.478297 -393.431402) (xy 342.517082 -393.459458) (xy 342.551018 -393.493219)
			(xy 342.579273 -393.531859) (xy 342.590628 -393.552934) (xy 342.591136 -393.55395) (xy 342.671442 -393.692888)
			(xy 343.213436 -393.692888) (xy 343.213436 -393.69238) (xy 343.21382 -393.668384) (xy 343.221331 -393.620984)
			(xy 343.236165 -393.575342) (xy 343.257957 -393.532583) (xy 343.286169 -393.493759) (xy 343.320108 -393.459828)
			(xy 343.358938 -393.431623) (xy 343.401701 -393.40984) (xy 343.447346 -393.395016) (xy 343.494748 -393.387515)
			(xy 343.518744 -393.387072) (xy 343.542678 -393.387544) (xy 343.589963 -393.395001) (xy 343.635506 -393.409741)
			(xy 343.678192 -393.431404) (xy 343.716978 -393.459459) (xy 343.750914 -393.493219) (xy 343.779169 -393.53186)
			(xy 343.790524 -393.552934) (xy 343.791032 -393.55395) (xy 343.871338 -393.692888) (xy 344.413332 -393.692888)
			(xy 344.413332 -393.69238) (xy 344.413743 -393.668399) (xy 344.421246 -393.621027) (xy 344.436063 -393.575411)
			(xy 344.45783 -393.532673) (xy 344.486012 -393.493864) (xy 344.519916 -393.459939) (xy 344.558707 -393.431732)
			(xy 344.601432 -393.409937) (xy 344.647038 -393.395091) (xy 344.694405 -393.387559) (xy 344.718386 -393.387072)
			(xy 344.718894 -393.387072) (xy 344.74283 -393.387503) (xy 344.790116 -393.394968) (xy 344.83566 -393.409715)
			(xy 344.878347 -393.431385) (xy 344.917132 -393.459446) (xy 344.951066 -393.493212) (xy 344.97932 -393.531857)
			(xy 344.990674 -393.552934) (xy 344.991182 -393.55395) (xy 345.071488 -393.692888) (xy 345.613228 -393.692888)
			(xy 345.613228 -393.69238) (xy 345.613643 -393.668399) (xy 345.621146 -393.621028) (xy 345.635962 -393.575412)
			(xy 345.657729 -393.532674) (xy 345.685911 -393.493865) (xy 345.719814 -393.45994) (xy 345.758605 -393.431733)
			(xy 345.801329 -393.409938) (xy 345.846935 -393.395092) (xy 345.894301 -393.387559) (xy 345.918282 -393.387072)
			(xy 345.91879 -393.387072) (xy 345.942726 -393.387506) (xy 345.990012 -393.39497) (xy 346.035556 -393.409717)
			(xy 346.078242 -393.431386) (xy 346.117027 -393.459447) (xy 346.150962 -393.493213) (xy 346.179216 -393.531857)
			(xy 346.19057 -393.552934) (xy 346.191078 -393.55395) (xy 346.271384 -393.692888) (xy 346.813124 -393.692888)
			(xy 346.813124 -393.69238) (xy 346.813543 -393.668399) (xy 346.821045 -393.621028) (xy 346.835862 -393.575413)
			(xy 346.857629 -393.532675) (xy 346.88581 -393.493866) (xy 346.919713 -393.459941) (xy 346.958503 -393.431734)
			(xy 347.001226 -393.40994) (xy 347.046832 -393.395093) (xy 347.094198 -393.387559) (xy 347.118178 -393.387072)
			(xy 347.118686 -393.387072) (xy 347.142622 -393.38751) (xy 347.189908 -393.394973) (xy 347.235451 -393.409719)
			(xy 347.278138 -393.431388) (xy 347.316923 -393.459448) (xy 347.350858 -393.493213) (xy 347.379112 -393.531858)
			(xy 347.390466 -393.552934) (xy 347.390974 -393.55395) (xy 347.47128 -393.692888) (xy 348.013528 -393.692888)
			(xy 348.013528 -393.69238) (xy 348.01392 -393.668385) (xy 348.021431 -393.620985) (xy 348.036264 -393.575344)
			(xy 348.058055 -393.532585) (xy 348.086267 -393.493762) (xy 348.120205 -393.45983) (xy 348.159033 -393.431626)
			(xy 348.201796 -393.409843) (xy 348.247439 -393.395018) (xy 348.29484 -393.387515) (xy 348.318836 -393.387072)
			(xy 348.34277 -393.38755) (xy 348.390054 -393.395006) (xy 348.435597 -393.409745) (xy 348.478284 -393.431407)
			(xy 348.517069 -393.459461) (xy 348.551005 -393.49322) (xy 348.579261 -393.53186) (xy 348.590616 -393.552934)
			(xy 348.591124 -393.55395) (xy 348.67143 -393.692888) (xy 349.213424 -393.692888) (xy 349.213424 -393.69238)
			(xy 349.21382 -393.668385) (xy 349.221331 -393.620985) (xy 349.236164 -393.575345) (xy 349.257954 -393.532586)
			(xy 349.286166 -393.493764) (xy 349.320103 -393.459832) (xy 349.358931 -393.431627) (xy 349.401693 -393.409844)
			(xy 349.447336 -393.395018) (xy 349.494737 -393.387516) (xy 349.518732 -393.387072) (xy 349.542666 -393.387554)
			(xy 349.58995 -393.395009) (xy 349.635493 -393.409747) (xy 349.678179 -393.431408) (xy 349.716965 -393.459462)
			(xy 349.750901 -393.493221) (xy 349.779157 -393.53186) (xy 349.790512 -393.552934) (xy 349.79102 -393.55395)
			(xy 349.871326 -393.692888) (xy 350.41332 -393.692888) (xy 350.41332 -393.69238) (xy 350.413743 -393.6684)
			(xy 350.421245 -393.621029) (xy 350.436062 -393.575414) (xy 350.457828 -393.532676) (xy 350.486009 -393.493868)
			(xy 350.519911 -393.459943) (xy 350.5587 -393.431736) (xy 350.601423 -393.409941) (xy 350.647028 -393.395093)
			(xy 350.694394 -393.387559) (xy 350.718374 -393.387072) (xy 350.718882 -393.387072) (xy 350.742818 -393.387513)
			(xy 350.790103 -393.394976) (xy 350.835647 -393.409721) (xy 350.878334 -393.431389) (xy 350.917119 -393.459449)
			(xy 350.951054 -393.493214) (xy 350.979308 -393.531858) (xy 350.990662 -393.552934) (xy 350.99117 -393.55395)
			(xy 351.071476 -393.692888) (xy 351.613216 -393.692888) (xy 351.613216 -393.69238) (xy 351.613643 -393.6684)
			(xy 351.621145 -393.621029) (xy 351.635961 -393.575415) (xy 351.657727 -393.532678) (xy 351.685908 -393.493869)
			(xy 351.719809 -393.459944) (xy 351.758598 -393.431737) (xy 351.80132 -393.409942) (xy 351.846925 -393.395094)
			(xy 351.89429 -393.38756) (xy 351.91827 -393.387072) (xy 351.918778 -393.387072) (xy 351.942713 -393.387516)
			(xy 351.989999 -393.394978) (xy 352.035543 -393.409723) (xy 352.078229 -393.431391) (xy 352.117015 -393.45945)
			(xy 352.150949 -393.493214) (xy 352.179204 -393.531858) (xy 352.190558 -393.552934) (xy 352.191066 -393.55395)
			(xy 352.271372 -393.692888) (xy 352.81362 -393.692888) (xy 352.81362 -393.69238) (xy 352.81402 -393.668385)
			(xy 352.82153 -393.620986) (xy 352.836363 -393.575346) (xy 352.858154 -393.532588) (xy 352.886365 -393.493765)
			(xy 352.920301 -393.459833) (xy 352.959129 -393.431629) (xy 353.00189 -393.409845) (xy 353.047533 -393.395019)
			(xy 353.094933 -393.387516) (xy 353.118928 -393.387072) (xy 353.142862 -393.387557) (xy 353.190146 -393.395011)
			(xy 353.235688 -393.409749) (xy 353.278375 -393.43141) (xy 353.317161 -393.459463) (xy 353.351097 -393.493222)
			(xy 353.379353 -393.53186) (xy 353.390708 -393.552934) (xy 353.391216 -393.55395) (xy 353.471522 -393.692888)
			(xy 354.013516 -393.692888) (xy 354.013516 -393.69238) (xy 354.01392 -393.668385) (xy 354.02143 -393.620987)
			(xy 354.036263 -393.575347) (xy 354.058053 -393.532589) (xy 354.086263 -393.493766) (xy 354.1202 -393.459835)
			(xy 354.159026 -393.43163) (xy 354.201787 -393.409846) (xy 354.247429 -393.39502) (xy 354.294829 -393.387516)
			(xy 354.318824 -393.387072) (xy 354.342758 -393.38756) (xy 354.390042 -393.395014) (xy 354.435584 -393.409751)
			(xy 354.478271 -393.431411) (xy 354.517057 -393.459464) (xy 354.550993 -393.493222) (xy 354.579249 -393.53186)
			(xy 354.590604 -393.552934) (xy 354.591112 -393.55395) (xy 354.671418 -393.692888) (xy 370.586 -393.692888)
			(xy 370.586 -393.69238) (xy 370.586444 -393.668388) (xy 370.593954 -393.620995) (xy 370.608784 -393.57536)
			(xy 370.630571 -393.532606) (xy 370.658777 -393.493788) (xy 370.692709 -393.459859) (xy 370.73153 -393.431656)
			(xy 370.774286 -393.409873) (xy 370.819922 -393.395047) (xy 370.867316 -393.387542) (xy 370.891308 -393.387072)
			(xy 370.915241 -393.387573) (xy 370.962524 -393.395024) (xy 371.008067 -393.409759) (xy 371.050753 -393.431417)
			(xy 371.089539 -393.459468) (xy 371.123476 -393.493224) (xy 371.151732 -393.531861) (xy 371.163088 -393.552934)
			(xy 371.163596 -393.55395) (xy 371.243902 -393.692888) (xy 371.785896 -393.692888) (xy 371.785896 -393.69238)
			(xy 371.786344 -393.668388) (xy 371.793853 -393.620995) (xy 371.808684 -393.575361) (xy 371.83047 -393.532608)
			(xy 371.858676 -393.493789) (xy 371.892607 -393.459861) (xy 371.931428 -393.431658) (xy 371.974183 -393.409875)
			(xy 372.019819 -393.395048) (xy 372.067212 -393.387542) (xy 372.091204 -393.387072) (xy 372.115137 -393.387576)
			(xy 372.16242 -393.395027) (xy 372.207962 -393.409762) (xy 372.250649 -393.431419) (xy 372.289435 -393.459469)
			(xy 372.323372 -393.493225) (xy 372.351628 -393.531861) (xy 372.362984 -393.552934) (xy 372.363492 -393.55395)
			(xy 372.443798 -393.692888) (xy 372.985792 -393.692888) (xy 372.985792 -393.69238) (xy 372.986244 -393.668388)
			(xy 372.993753 -393.620996) (xy 373.008583 -393.575362) (xy 373.030369 -393.532609) (xy 373.058575 -393.49379)
			(xy 373.092506 -393.459862) (xy 373.131326 -393.431659) (xy 373.17408 -393.409876) (xy 373.219715 -393.395049)
			(xy 373.267108 -393.387543) (xy 373.2911 -393.387072) (xy 373.315033 -393.38758) (xy 373.362316 -393.39503)
			(xy 373.407858 -393.409764) (xy 373.450544 -393.43142) (xy 373.489331 -393.45947) (xy 373.523268 -393.493226)
			(xy 373.551524 -393.531862) (xy 373.56288 -393.552934) (xy 373.563388 -393.55395) (xy 373.643694 -393.692888)
			(xy 374.185688 -393.692888) (xy 374.185688 -393.69238) (xy 374.186143 -393.668401) (xy 374.193644 -393.621034)
			(xy 374.208459 -393.575421) (xy 374.230222 -393.532686) (xy 374.258399 -393.493879) (xy 374.292298 -393.459954)
			(xy 374.331083 -393.431747) (xy 374.373801 -393.40995) (xy 374.419402 -393.3951) (xy 374.466763 -393.387562)
			(xy 374.490742 -393.387072) (xy 374.49125 -393.387072) (xy 374.515185 -393.387539) (xy 374.562469 -393.394997)
			(xy 374.608012 -393.409738) (xy 374.650699 -393.431401) (xy 374.689484 -393.459457) (xy 374.72342 -393.493218)
			(xy 374.751675 -393.531859) (xy 374.76303 -393.552934) (xy 374.763538 -393.55395) (xy 374.843844 -393.692888)
			(xy 375.385584 -393.692888) (xy 375.385584 -393.69238) (xy 375.386043 -393.668401) (xy 375.393544 -393.621034)
			(xy 375.408358 -393.575422) (xy 375.430121 -393.532687) (xy 375.458298 -393.49388) (xy 375.492196 -393.459956)
			(xy 375.53098 -393.431748) (xy 375.573698 -393.409951) (xy 375.619298 -393.395101) (xy 375.66666 -393.387562)
			(xy 375.690638 -393.387072) (xy 375.691146 -393.387072) (xy 375.715081 -393.387542) (xy 375.762365 -393.394999)
			(xy 375.807908 -393.40974) (xy 375.850594 -393.431403) (xy 375.88938 -393.459458) (xy 375.923316 -393.493219)
			(xy 375.951571 -393.531859) (xy 375.962926 -393.552934) (xy 375.963434 -393.55395) (xy 376.04374 -393.692888)
			(xy 376.585988 -393.692888) (xy 376.585988 -393.69238) (xy 376.586444 -393.668388) (xy 376.593953 -393.620996)
			(xy 376.608783 -393.575362) (xy 376.630569 -393.53261) (xy 376.658774 -393.493792) (xy 376.692704 -393.459863)
			(xy 376.731524 -393.43166) (xy 376.774277 -393.409877) (xy 376.819912 -393.395049) (xy 376.867304 -393.387543)
			(xy 376.891296 -393.387072) (xy 376.915232 -393.387502) (xy 376.962518 -393.394966) (xy 377.008062 -393.409714)
			(xy 377.050749 -393.431384) (xy 377.089534 -393.459445) (xy 377.123468 -393.493212) (xy 377.151722 -393.531857)
			(xy 377.163076 -393.552934) (xy 377.163584 -393.55395) (xy 377.24389 -393.692888) (xy 377.785884 -393.692888)
			(xy 377.785884 -393.69238) (xy 377.786344 -393.668389) (xy 377.793853 -393.620997) (xy 377.808683 -393.575363)
			(xy 377.830468 -393.532611) (xy 377.858673 -393.493793) (xy 377.892602 -393.459865) (xy 377.931421 -393.431662)
			(xy 377.974174 -393.409878) (xy 378.019809 -393.39505) (xy 378.067201 -393.387543) (xy 378.091192 -393.387072)
			(xy 378.115128 -393.387505) (xy 378.162414 -393.394969) (xy 378.207958 -393.409716) (xy 378.250644 -393.431385)
			(xy 378.28943 -393.459446) (xy 378.323364 -393.493212) (xy 378.351618 -393.531857) (xy 378.362972 -393.552934)
			(xy 378.36348 -393.55395) (xy 378.443786 -393.692888) (xy 378.98578 -393.692888) (xy 378.98578 -393.69238)
			(xy 378.986244 -393.668389) (xy 378.993753 -393.620998) (xy 379.008582 -393.575364) (xy 379.030367 -393.532612)
			(xy 379.058571 -393.493795) (xy 379.092501 -393.459866) (xy 379.131319 -393.431663) (xy 379.174072 -393.409879)
			(xy 379.219705 -393.395051) (xy 379.267097 -393.387543) (xy 379.291088 -393.387072) (xy 379.315024 -393.387508)
			(xy 379.36231 -393.394972) (xy 379.407853 -393.409718) (xy 379.45054 -393.431387) (xy 379.489325 -393.459447)
			(xy 379.52326 -393.493213) (xy 379.551514 -393.531858) (xy 379.562868 -393.552934) (xy 379.563376 -393.55395)
			(xy 379.643682 -393.692888) (xy 380.185676 -393.692888) (xy 380.185676 -393.69238) (xy 380.186143 -393.668402)
			(xy 380.193644 -393.621035) (xy 380.208457 -393.575424) (xy 380.23022 -393.532689) (xy 380.258396 -393.493883)
			(xy 380.292292 -393.459959) (xy 380.331076 -393.431751) (xy 380.373793 -393.409953) (xy 380.419392 -393.395102)
			(xy 380.466752 -393.387563) (xy 380.49073 -393.387072) (xy 380.491238 -393.387072) (xy 380.515172 -393.387549)
			(xy 380.562456 -393.395005) (xy 380.607999 -393.409744) (xy 380.650686 -393.431406) (xy 380.689472 -393.45946)
			(xy 380.723407 -393.49322) (xy 380.751663 -393.53186) (xy 380.763018 -393.552934) (xy 380.763526 -393.55395)
			(xy 380.843832 -393.692888) (xy 381.385572 -393.692888) (xy 381.385572 -393.69238) (xy 381.386043 -393.668402)
			(xy 381.393544 -393.621036) (xy 381.408357 -393.575425) (xy 381.430119 -393.532691) (xy 381.458295 -393.493884)
			(xy 381.492191 -393.45996) (xy 381.530974 -393.431752) (xy 381.57369 -393.409954) (xy 381.619289 -393.395103)
			(xy 381.666648 -393.387563) (xy 381.690626 -393.387072) (xy 381.691134 -393.387072) (xy 381.715068 -393.387552)
			(xy 381.762352 -393.395007) (xy 381.807895 -393.409746) (xy 381.850581 -393.431407) (xy 381.889367 -393.459461)
			(xy 381.923303 -393.493221) (xy 381.951559 -393.53186) (xy 381.962914 -393.552934) (xy 381.963422 -393.55395)
			(xy 382.043728 -393.692888) (xy 382.585976 -393.692888) (xy 382.585976 -393.69238) (xy 382.586444 -393.668389)
			(xy 382.593953 -393.620998) (xy 382.608782 -393.575365) (xy 382.630567 -393.532614) (xy 382.65877 -393.493796)
			(xy 382.692699 -393.459868) (xy 382.731517 -393.431664) (xy 382.774269 -393.40988) (xy 382.819902 -393.395052)
			(xy 382.867293 -393.387544) (xy 382.891284 -393.387072) (xy 382.91522 -393.387511) (xy 382.962506 -393.394974)
			(xy 383.008049 -393.40972) (xy 383.050736 -393.431388) (xy 383.089521 -393.459448) (xy 383.123456 -393.493214)
			(xy 383.15171 -393.531858) (xy 383.163064 -393.552934) (xy 383.163572 -393.55395) (xy 383.243878 -393.692888)
			(xy 383.785872 -393.692888) (xy 383.785872 -393.69238) (xy 383.786344 -393.668389) (xy 383.793853 -393.620999)
			(xy 383.808681 -393.575366) (xy 383.830466 -393.532615) (xy 383.858669 -393.493797) (xy 383.892597 -393.459869)
			(xy 383.931415 -393.431666) (xy 383.974166 -393.409881) (xy 384.019799 -393.395053) (xy 384.067189 -393.387544)
			(xy 384.09118 -393.387072) (xy 384.115116 -393.387515) (xy 384.162401 -393.394977) (xy 384.207945 -393.409722)
			(xy 384.250631 -393.43139) (xy 384.289417 -393.459449) (xy 384.323352 -393.493214) (xy 384.351606 -393.531858)
			(xy 384.36296 -393.552934) (xy 384.363468 -393.55395) (xy 384.443774 -393.692888) (xy 384.985768 -393.692888)
			(xy 384.985768 -393.69238) (xy 384.986244 -393.668389) (xy 384.993752 -393.620999) (xy 385.008581 -393.575367)
			(xy 385.030365 -393.532616) (xy 385.058568 -393.493799) (xy 385.092496 -393.459871) (xy 385.131313 -393.431667)
			(xy 385.174063 -393.409883) (xy 385.219695 -393.395053) (xy 385.267085 -393.387544) (xy 385.291076 -393.387072)
			(xy 385.315011 -393.387518) (xy 385.362297 -393.39498) (xy 385.40784 -393.409724) (xy 385.450527 -393.431391)
			(xy 385.489312 -393.45945) (xy 385.523247 -393.493215) (xy 385.551501 -393.531858) (xy 385.562856 -393.552934)
			(xy 385.563364 -393.55395) (xy 385.64367 -393.692888) (xy 386.185664 -393.692888) (xy 386.185664 -393.69238)
			(xy 386.186143 -393.668402) (xy 386.193643 -393.621037) (xy 386.208456 -393.575427) (xy 386.230218 -393.532693)
			(xy 386.258392 -393.493887) (xy 386.292287 -393.459963) (xy 386.331069 -393.431755) (xy 386.373784 -393.409957)
			(xy 386.419382 -393.395105) (xy 386.466741 -393.387564) (xy 386.490718 -393.387072) (xy 386.491226 -393.387072)
			(xy 386.51516 -393.387558) (xy 386.562444 -393.395013) (xy 386.607986 -393.40975) (xy 386.650673 -393.43141)
			(xy 386.689459 -393.459463) (xy 386.723395 -393.493222) (xy 386.751651 -393.53186) (xy 386.763006 -393.552934)
			(xy 386.763514 -393.55395) (xy 386.84382 -393.692888) (xy 387.38556 -393.692888) (xy 387.38556 -393.69238)
			(xy 387.386043 -393.668403) (xy 387.393543 -393.621038) (xy 387.408356 -393.575428) (xy 387.430117 -393.532694)
			(xy 387.458291 -393.493888) (xy 387.492186 -393.459964) (xy 387.530967 -393.431756) (xy 387.573682 -393.409958)
			(xy 387.619279 -393.395105) (xy 387.666637 -393.387564) (xy 387.690614 -393.387072) (xy 387.691122 -393.387072)
			(xy 387.715056 -393.387562) (xy 387.762339 -393.395015) (xy 387.807882 -393.409752) (xy 387.850568 -393.431412)
			(xy 387.889354 -393.459464) (xy 387.923291 -393.493222) (xy 387.951547 -393.531861) (xy 387.962902 -393.552934)
			(xy 387.96341 -393.55395) (xy 388.043716 -393.692888) (xy 388.585964 -393.692888) (xy 388.585964 -393.69238)
			(xy 388.586444 -393.66839) (xy 388.593952 -393.621) (xy 388.608781 -393.575368) (xy 388.630564 -393.532617)
			(xy 388.658767 -393.4938) (xy 388.692694 -393.459872) (xy 388.73151 -393.431668) (xy 388.774261 -393.409884)
			(xy 388.819892 -393.395054) (xy 388.867282 -393.387545) (xy 388.891272 -393.387072) (xy 388.915207 -393.387521)
			(xy 388.962493 -393.394982) (xy 389.008036 -393.409727) (xy 389.050723 -393.431393) (xy 389.089508 -393.459451)
			(xy 389.123443 -393.493215) (xy 389.151697 -393.531858) (xy 389.163052 -393.552934) (xy 389.16356 -393.55395)
			(xy 389.243866 -393.692888) (xy 403.113748 -393.692888) (xy 403.113748 -393.69238) (xy 403.114244 -393.66839)
			(xy 403.121752 -393.621002) (xy 403.136579 -393.575372) (xy 403.158361 -393.532622) (xy 403.186562 -393.493805)
			(xy 403.220487 -393.459878) (xy 403.259301 -393.431674) (xy 403.302049 -393.409888) (xy 403.347679 -393.395057)
			(xy 403.395066 -393.387546) (xy 403.419056 -393.387072) (xy 403.442991 -393.387534) (xy 403.490276 -393.394993)
			(xy 403.535819 -393.409735) (xy 403.578505 -393.431399) (xy 403.617291 -393.459456) (xy 403.651226 -393.493218)
			(xy 403.679481 -393.531859) (xy 403.690836 -393.552934) (xy 403.691344 -393.55395) (xy 403.77165 -393.692888)
			(xy 404.313644 -393.692888) (xy 404.313644 -393.69238) (xy 404.314144 -393.668391) (xy 404.321652 -393.621003)
			(xy 404.336479 -393.575373) (xy 404.358261 -393.532623) (xy 404.386461 -393.493807) (xy 404.420386 -393.459879)
			(xy 404.459199 -393.431675) (xy 404.501947 -393.40989) (xy 404.547576 -393.395058) (xy 404.594963 -393.387546)
			(xy 404.618952 -393.387072) (xy 404.642887 -393.387537) (xy 404.690171 -393.394995) (xy 404.735714 -393.409737)
			(xy 404.778401 -393.431401) (xy 404.817187 -393.459457) (xy 404.851122 -393.493218) (xy 404.879377 -393.531859)
			(xy 404.890732 -393.552934) (xy 404.89124 -393.55395) (xy 404.971546 -393.692888) (xy 405.51354 -393.692888)
			(xy 405.51354 -393.69238) (xy 405.51392 -393.668384) (xy 405.521431 -393.620983) (xy 405.536265 -393.575341)
			(xy 405.558057 -393.532582) (xy 405.58627 -393.493758) (xy 405.62021 -393.459826) (xy 405.65904 -393.431622)
			(xy 405.701804 -393.409839) (xy 405.747449 -393.395015) (xy 405.794852 -393.387515) (xy 405.818848 -393.387072)
			(xy 405.842783 -393.387541) (xy 405.890067 -393.394998) (xy 405.93561 -393.409739) (xy 405.978297 -393.431402)
			(xy 406.017082 -393.459458) (xy 406.051018 -393.493219) (xy 406.079273 -393.531859) (xy 406.090628 -393.552934)
			(xy 406.091136 -393.55395) (xy 406.171442 -393.692888) (xy 406.713436 -393.692888) (xy 406.713436 -393.69238)
			(xy 406.713843 -393.668399) (xy 406.721346 -393.621027) (xy 406.736163 -393.57541) (xy 406.757931 -393.532672)
			(xy 406.786113 -393.493862) (xy 406.820018 -393.459937) (xy 406.858809 -393.43173) (xy 406.901534 -393.409936)
			(xy 406.947141 -393.39509) (xy 406.994509 -393.387558) (xy 407.01849 -393.387072) (xy 407.018998 -393.387072)
			(xy 407.042934 -393.3875) (xy 407.090221 -393.394965) (xy 407.135764 -393.409713) (xy 407.178451 -393.431383)
			(xy 407.217236 -393.459445) (xy 407.25117 -393.493212) (xy 407.279424 -393.531857) (xy 407.290778 -393.552934)
			(xy 407.291286 -393.55395) (xy 407.371592 -393.692888) (xy 407.913332 -393.692888) (xy 407.913332 -393.69238)
			(xy 407.913743 -393.668399) (xy 407.921246 -393.621027) (xy 407.936063 -393.575411) (xy 407.95783 -393.532673)
			(xy 407.986012 -393.493864) (xy 408.019916 -393.459939) (xy 408.058707 -393.431732) (xy 408.101432 -393.409937)
			(xy 408.147038 -393.395091) (xy 408.194405 -393.387559) (xy 408.218386 -393.387072) (xy 408.218894 -393.387072)
			(xy 408.24283 -393.387503) (xy 408.290116 -393.394968) (xy 408.33566 -393.409715) (xy 408.378347 -393.431385)
			(xy 408.417132 -393.459446) (xy 408.451066 -393.493212) (xy 408.47932 -393.531857) (xy 408.490674 -393.552934)
			(xy 408.491182 -393.55395) (xy 408.571488 -393.692888) (xy 409.113736 -393.692888) (xy 409.113736 -393.69238)
			(xy 409.11412 -393.668384) (xy 409.121631 -393.620984) (xy 409.136465 -393.575342) (xy 409.158257 -393.532583)
			(xy 409.186469 -393.493759) (xy 409.220408 -393.459828) (xy 409.259238 -393.431623) (xy 409.302001 -393.40984)
			(xy 409.347646 -393.395016) (xy 409.395048 -393.387515) (xy 409.419044 -393.387072) (xy 409.442978 -393.387544)
			(xy 409.490263 -393.395001) (xy 409.535806 -393.409741) (xy 409.578492 -393.431404) (xy 409.617278 -393.459459)
			(xy 409.651214 -393.493219) (xy 409.679469 -393.53186) (xy 409.690824 -393.552934) (xy 409.691332 -393.55395)
			(xy 409.771638 -393.692888) (xy 410.313632 -393.692888) (xy 410.313632 -393.69238) (xy 410.31402 -393.668384)
			(xy 410.321531 -393.620984) (xy 410.336365 -393.575343) (xy 410.358156 -393.532584) (xy 410.386368 -393.493761)
			(xy 410.420306 -393.459829) (xy 410.459135 -393.431624) (xy 410.501898 -393.409842) (xy 410.547543 -393.395017)
			(xy 410.594944 -393.387515) (xy 410.61894 -393.387072) (xy 410.642874 -393.387547) (xy 410.690159 -393.395003)
			(xy 410.735701 -393.409743) (xy 410.778388 -393.431405) (xy 410.817174 -393.45946) (xy 410.85111 -393.49322)
			(xy 410.879365 -393.53186) (xy 410.89072 -393.552934) (xy 410.891228 -393.55395) (xy 410.971534 -393.692888)
			(xy 411.513528 -393.692888) (xy 411.513528 -393.69238) (xy 411.51392 -393.668385) (xy 411.521431 -393.620985)
			(xy 411.536264 -393.575344) (xy 411.558055 -393.532585) (xy 411.586267 -393.493762) (xy 411.620205 -393.45983)
			(xy 411.659033 -393.431626) (xy 411.701796 -393.409843) (xy 411.747439 -393.395018) (xy 411.79484 -393.387515)
			(xy 411.818836 -393.387072) (xy 411.84277 -393.38755) (xy 411.890054 -393.395006) (xy 411.935597 -393.409745)
			(xy 411.978284 -393.431407) (xy 412.017069 -393.459461) (xy 412.051005 -393.49322) (xy 412.079261 -393.53186)
			(xy 412.090616 -393.552934) (xy 412.091124 -393.55395) (xy 412.17143 -393.692888) (xy 412.713424 -393.692888)
			(xy 412.713424 -393.69238) (xy 412.713843 -393.668399) (xy 412.721345 -393.621028) (xy 412.736162 -393.575413)
			(xy 412.757929 -393.532675) (xy 412.78611 -393.493866) (xy 412.820013 -393.459941) (xy 412.858803 -393.431734)
			(xy 412.901526 -393.40994) (xy 412.947132 -393.395093) (xy 412.994498 -393.387559) (xy 413.018478 -393.387072)
			(xy 413.018986 -393.387072) (xy 413.042922 -393.38751) (xy 413.090208 -393.394973) (xy 413.135751 -393.409719)
			(xy 413.178438 -393.431388) (xy 413.217223 -393.459448) (xy 413.251158 -393.493213) (xy 413.279412 -393.531858)
			(xy 413.290766 -393.552934) (xy 413.291274 -393.55395) (xy 413.37158 -393.692888) (xy 413.91332 -393.692888)
			(xy 413.91332 -393.69238) (xy 413.913743 -393.6684) (xy 413.921245 -393.621029) (xy 413.936062 -393.575414)
			(xy 413.957828 -393.532676) (xy 413.986009 -393.493868) (xy 414.019911 -393.459943) (xy 414.0587 -393.431736)
			(xy 414.101423 -393.409941) (xy 414.147028 -393.395093) (xy 414.194394 -393.387559) (xy 414.218374 -393.387072)
			(xy 414.218882 -393.387072) (xy 414.242818 -393.387513) (xy 414.290103 -393.394976) (xy 414.335647 -393.409721)
			(xy 414.378334 -393.431389) (xy 414.417119 -393.459449) (xy 414.451054 -393.493214) (xy 414.479308 -393.531858)
			(xy 414.490662 -393.552934) (xy 414.49117 -393.55395) (xy 414.571476 -393.692888) (xy 415.113724 -393.692888)
			(xy 415.113724 -393.69238) (xy 415.11412 -393.668385) (xy 415.121631 -393.620985) (xy 415.136464 -393.575345)
			(xy 415.158254 -393.532586) (xy 415.186466 -393.493764) (xy 415.220403 -393.459832) (xy 415.259231 -393.431627)
			(xy 415.301993 -393.409844) (xy 415.347636 -393.395018) (xy 415.395037 -393.387516) (xy 415.419032 -393.387072)
			(xy 415.442966 -393.387554) (xy 415.49025 -393.395009) (xy 415.535793 -393.409747) (xy 415.578479 -393.431408)
			(xy 415.617265 -393.459462) (xy 415.651201 -393.493221) (xy 415.679457 -393.53186) (xy 415.690812 -393.552934)
			(xy 415.69132 -393.55395) (xy 415.771626 -393.692888) (xy 416.31362 -393.692888) (xy 416.31362 -393.69238)
			(xy 416.31402 -393.668385) (xy 416.32153 -393.620986) (xy 416.336363 -393.575346) (xy 416.358154 -393.532588)
			(xy 416.386365 -393.493765) (xy 416.420301 -393.459833) (xy 416.459129 -393.431629) (xy 416.50189 -393.409845)
			(xy 416.547533 -393.395019) (xy 416.594933 -393.387516) (xy 416.618928 -393.387072) (xy 416.642862 -393.387557)
			(xy 416.690146 -393.395011) (xy 416.735688 -393.409749) (xy 416.778375 -393.43141) (xy 416.817161 -393.459463)
			(xy 416.851097 -393.493222) (xy 416.879353 -393.53186) (xy 416.890708 -393.552934) (xy 416.891216 -393.55395)
			(xy 416.971522 -393.692888) (xy 417.513516 -393.692888) (xy 417.513516 -393.69238) (xy 417.51392 -393.668385)
			(xy 417.52143 -393.620987) (xy 417.536263 -393.575347) (xy 417.558053 -393.532589) (xy 417.586263 -393.493766)
			(xy 417.6202 -393.459835) (xy 417.659026 -393.43163) (xy 417.701787 -393.409846) (xy 417.747429 -393.39502)
			(xy 417.794829 -393.387516) (xy 417.818824 -393.387072) (xy 417.842758 -393.38756) (xy 417.890042 -393.395014)
			(xy 417.935584 -393.409751) (xy 417.978271 -393.431411) (xy 418.017057 -393.459464) (xy 418.050993 -393.493222)
			(xy 418.079249 -393.53186) (xy 418.090604 -393.552934) (xy 418.091112 -393.55395) (xy 418.171418 -393.692888)
			(xy 418.713412 -393.692888) (xy 418.713412 -393.69238) (xy 418.713843 -393.6684) (xy 418.721345 -393.62103)
			(xy 418.736161 -393.575416) (xy 418.757927 -393.532679) (xy 418.786106 -393.493871) (xy 418.820008 -393.459946)
			(xy 418.858796 -393.431739) (xy 418.901518 -393.409943) (xy 418.947122 -393.395095) (xy 418.994486 -393.38756)
			(xy 419.018466 -393.387072) (xy 419.018974 -393.387072) (xy 419.042909 -393.387519) (xy 419.090195 -393.394981)
			(xy 419.135738 -393.409726) (xy 419.178425 -393.431392) (xy 419.21721 -393.459451) (xy 419.251145 -393.493215)
			(xy 419.279399 -393.531858) (xy 419.290754 -393.552934) (xy 419.291262 -393.55395) (xy 419.371568 -393.692888)
			(xy 419.913308 -393.692888) (xy 419.913308 -393.69238) (xy 419.913743 -393.6684) (xy 419.921245 -393.621031)
			(xy 419.936061 -393.575417) (xy 419.957826 -393.53268) (xy 419.986005 -393.493872) (xy 420.019906 -393.459947)
			(xy 420.058694 -393.43174) (xy 420.101415 -393.409944) (xy 420.147018 -393.395096) (xy 420.194382 -393.38756)
			(xy 420.218362 -393.387072) (xy 420.21887 -393.387072) (xy 420.242805 -393.387523) (xy 420.290091 -393.394984)
			(xy 420.335634 -393.409728) (xy 420.378321 -393.431394) (xy 420.417106 -393.459452) (xy 420.451041 -393.493216)
			(xy 420.479295 -393.531858) (xy 420.49065 -393.552934) (xy 420.491158 -393.55395) (xy 420.571464 -393.692888)
			(xy 421.113712 -393.692888) (xy 421.113712 -393.69238) (xy 421.114144 -393.668387) (xy 421.121654 -393.620993)
			(xy 421.136485 -393.575357) (xy 421.158273 -393.532603) (xy 421.186481 -393.493784) (xy 421.220414 -393.459855)
			(xy 421.259237 -393.431652) (xy 421.301994 -393.40987) (xy 421.347632 -393.395045) (xy 421.395027 -393.387541)
			(xy 421.41902 -393.387072) (xy 421.442954 -393.387563) (xy 421.490237 -393.395017) (xy 421.53578 -393.409753)
			(xy 421.578466 -393.431413) (xy 421.617252 -393.459465) (xy 421.651189 -393.493223) (xy 421.679444 -393.531861)
			(xy 421.6908 -393.552934) (xy 421.691308 -393.55395) (xy 422.083738 -394.232892) (xy 422.096563 -394.256225)
			(xy 422.114783 -394.306247) (xy 422.124043 -394.358673) (xy 422.124632 -394.385292) (xy 422.124131 -394.409269)
			(xy 422.116635 -394.456634) (xy 422.101826 -394.502244) (xy 422.080067 -394.544978) (xy 422.051895 -394.583784)
			(xy 422.018002 -394.617709) (xy 421.979222 -394.645918) (xy 421.936509 -394.667716) (xy 421.890912 -394.682568)
			(xy 421.843555 -394.690109) (xy 421.819578 -394.6906) (xy 421.81907 -394.6906) (xy 421.795495 -394.69023)
			(xy 421.748906 -394.682984) (xy 421.703987 -394.668654) (xy 421.661808 -394.647582) (xy 421.623376 -394.620268)
			(xy 421.589605 -394.587365) (xy 421.5613 -394.549657) (xy 421.54983 -394.529056) (xy 421.549322 -394.528294)
			(xy 421.151558 -393.839954) (xy 421.139699 -393.817269) (xy 421.122842 -393.76894) (xy 421.114262 -393.71848)
			(xy 421.113712 -393.692888) (xy 420.571464 -393.692888) (xy 420.883588 -394.232892) (xy 420.89632 -394.256211)
			(xy 420.914415 -394.306158) (xy 420.923631 -394.358477) (xy 420.924228 -394.385038) (xy 420.924228 -394.385292)
			(xy 420.92373 -394.409282) (xy 420.916226 -394.456672) (xy 420.901401 -394.502304) (xy 420.87962 -394.545055)
			(xy 420.85142 -394.583873) (xy 420.817494 -394.617801) (xy 420.778679 -394.646005) (xy 420.73593 -394.66779)
			(xy 420.690299 -394.682619) (xy 420.64291 -394.690128) (xy 420.61892 -394.6906) (xy 420.595347 -394.69019)
			(xy 420.548759 -394.682952) (xy 420.503841 -394.668629) (xy 420.461662 -394.647563) (xy 420.423229 -394.620256)
			(xy 420.389457 -394.587358) (xy 420.361151 -394.549655) (xy 420.34968 -394.529056) (xy 420.349172 -394.528294)
			(xy 419.951408 -393.839954) (xy 419.939474 -393.817295) (xy 419.922543 -393.768965) (xy 419.913891 -393.718491)
			(xy 419.913308 -393.692888) (xy 419.371568 -393.692888) (xy 419.683692 -394.232892) (xy 419.696424 -394.25621)
			(xy 419.714519 -394.306158) (xy 419.723735 -394.358477) (xy 419.724332 -394.385038) (xy 419.724332 -394.385292)
			(xy 419.72383 -394.409282) (xy 419.716326 -394.456671) (xy 419.701501 -394.502303) (xy 419.679721 -394.545054)
			(xy 419.651521 -394.583871) (xy 419.617596 -394.6178) (xy 419.578781 -394.646004) (xy 419.536032 -394.667789)
			(xy 419.490402 -394.682618) (xy 419.443014 -394.690128) (xy 419.419024 -394.6906) (xy 419.395451 -394.690187)
			(xy 419.348863 -394.682949) (xy 419.303945 -394.668627) (xy 419.261767 -394.647561) (xy 419.223333 -394.620255)
			(xy 419.189561 -394.587358) (xy 419.161255 -394.549655) (xy 419.149784 -394.529056) (xy 419.149276 -394.528294)
			(xy 418.751512 -393.839954) (xy 418.739579 -393.817295) (xy 418.722647 -393.768965) (xy 418.713995 -393.718491)
			(xy 418.713412 -393.692888) (xy 418.171418 -393.692888) (xy 418.483542 -394.232892) (xy 418.496367 -394.256224)
			(xy 418.514587 -394.306247) (xy 418.523847 -394.358673) (xy 418.524436 -394.385292) (xy 418.523931 -394.409269)
			(xy 418.516435 -394.456633) (xy 418.501626 -394.502243) (xy 418.479868 -394.544977) (xy 418.451696 -394.583783)
			(xy 418.417804 -394.617708) (xy 418.379024 -394.645916) (xy 418.336311 -394.667715) (xy 418.290716 -394.682567)
			(xy 418.243358 -394.690108) (xy 418.219382 -394.6906) (xy 418.218874 -394.6906) (xy 418.195299 -394.690227)
			(xy 418.14871 -394.682982) (xy 418.103791 -394.668652) (xy 418.061613 -394.64758) (xy 418.02318 -394.620267)
			(xy 417.989409 -394.587365) (xy 417.961104 -394.549657) (xy 417.949634 -394.529056) (xy 417.949126 -394.528294)
			(xy 417.551362 -393.839954) (xy 417.539504 -393.817268) (xy 417.522646 -393.76894) (xy 417.514066 -393.71848)
			(xy 417.513516 -393.692888) (xy 416.971522 -393.692888) (xy 417.283646 -394.232892) (xy 417.296471 -394.256224)
			(xy 417.314691 -394.306247) (xy 417.323951 -394.358673) (xy 417.32454 -394.385292) (xy 417.324031 -394.409269)
			(xy 417.316535 -394.456633) (xy 417.301726 -394.502242) (xy 417.279969 -394.544976) (xy 417.251798 -394.583782)
			(xy 417.217906 -394.617706) (xy 417.179127 -394.645915) (xy 417.136414 -394.667714) (xy 417.090819 -394.682566)
			(xy 417.043462 -394.690108) (xy 417.019486 -394.6906) (xy 417.018978 -394.6906) (xy 416.995403 -394.690224)
			(xy 416.948814 -394.682979) (xy 416.903895 -394.66865) (xy 416.861717 -394.647579) (xy 416.823284 -394.620266)
			(xy 416.789513 -394.587364) (xy 416.761208 -394.549657) (xy 416.749738 -394.529056) (xy 416.74923 -394.528294)
			(xy 416.351466 -393.839954) (xy 416.339608 -393.817268) (xy 416.32275 -393.76894) (xy 416.31417 -393.71848)
			(xy 416.31362 -393.692888) (xy 415.771626 -393.692888) (xy 416.08375 -394.232892) (xy 416.096576 -394.256224)
			(xy 416.114795 -394.306247) (xy 416.124055 -394.358673) (xy 416.124644 -394.385292) (xy 416.124131 -394.409269)
			(xy 416.116635 -394.456632) (xy 416.101827 -394.502241) (xy 416.080069 -394.544974) (xy 416.051899 -394.58378)
			(xy 416.018007 -394.617705) (xy 415.979229 -394.645913) (xy 415.936517 -394.667712) (xy 415.890922 -394.682566)
			(xy 415.843566 -394.690108) (xy 415.81959 -394.6906) (xy 415.819082 -394.6906) (xy 415.795507 -394.690221)
			(xy 415.748919 -394.682977) (xy 415.704 -394.668648) (xy 415.661821 -394.647577) (xy 415.623388 -394.620265)
			(xy 415.589617 -394.587364) (xy 415.561312 -394.549657) (xy 415.549842 -394.529056) (xy 415.549334 -394.528294)
			(xy 415.15157 -393.839954) (xy 415.139712 -393.817268) (xy 415.122855 -393.768939) (xy 415.114274 -393.71848)
			(xy 415.113724 -393.692888) (xy 414.571476 -393.692888) (xy 414.8836 -394.232892) (xy 414.896333 -394.25621)
			(xy 414.914427 -394.306158) (xy 414.923643 -394.358477) (xy 414.92424 -394.385038) (xy 414.92424 -394.385292)
			(xy 414.92373 -394.409281) (xy 414.916226 -394.45667) (xy 414.901402 -394.502301) (xy 414.879622 -394.545051)
			(xy 414.851423 -394.583869) (xy 414.817499 -394.617797) (xy 414.778686 -394.646001) (xy 414.735938 -394.667787)
			(xy 414.690309 -394.682617) (xy 414.642921 -394.690127) (xy 414.618932 -394.6906) (xy 414.595359 -394.69018)
			(xy 414.548772 -394.682944) (xy 414.503854 -394.668623) (xy 414.461675 -394.647558) (xy 414.423242 -394.620253)
			(xy 414.38947 -394.587357) (xy 414.361163 -394.549654) (xy 414.349692 -394.529056) (xy 414.349184 -394.528294)
			(xy 413.95142 -393.839954) (xy 413.939487 -393.817294) (xy 413.922556 -393.768965) (xy 413.913903 -393.718491)
			(xy 413.91332 -393.692888) (xy 413.37158 -393.692888) (xy 413.683704 -394.232892) (xy 413.696437 -394.25621)
			(xy 413.714531 -394.306158) (xy 413.723747 -394.358477) (xy 413.724344 -394.385038) (xy 413.724344 -394.385292)
			(xy 413.72383 -394.409281) (xy 413.716326 -394.456669) (xy 413.701502 -394.5023) (xy 413.679723 -394.54505)
			(xy 413.651524 -394.583867) (xy 413.617601 -394.617796) (xy 413.578788 -394.646) (xy 413.536041 -394.667785)
			(xy 413.490412 -394.682616) (xy 413.443025 -394.690127) (xy 413.419036 -394.6906) (xy 413.395463 -394.690177)
			(xy 413.348876 -394.682941) (xy 413.303958 -394.668621) (xy 413.26178 -394.647557) (xy 413.223346 -394.620252)
			(xy 413.189574 -394.587356) (xy 413.161267 -394.549654) (xy 413.149796 -394.529056) (xy 413.149288 -394.528294)
			(xy 412.751524 -393.839954) (xy 412.739592 -393.817294) (xy 412.72266 -393.768965) (xy 412.714007 -393.718491)
			(xy 412.713424 -393.692888) (xy 412.17143 -393.692888) (xy 412.483554 -394.232892) (xy 412.49638 -394.256224)
			(xy 412.514599 -394.306247) (xy 412.523859 -394.358673) (xy 412.524448 -394.385292) (xy 412.523931 -394.409268)
			(xy 412.516436 -394.456632) (xy 412.501627 -394.50224) (xy 412.47987 -394.544973) (xy 412.4517 -394.583779)
			(xy 412.417809 -394.617703) (xy 412.379031 -394.645912) (xy 412.33632 -394.667711) (xy 412.290726 -394.682565)
			(xy 412.24337 -394.690107) (xy 412.219394 -394.6906) (xy 412.218886 -394.6906) (xy 412.195312 -394.690217)
			(xy 412.148723 -394.682974) (xy 412.103804 -394.668646) (xy 412.061626 -394.647576) (xy 412.023193 -394.620264)
			(xy 411.989421 -394.587363) (xy 411.961116 -394.549656) (xy 411.949646 -394.529056) (xy 411.949138 -394.528294)
			(xy 411.551374 -393.839954) (xy 411.539517 -393.817268) (xy 411.522659 -393.768939) (xy 411.514078 -393.718479)
			(xy 411.513528 -393.692888) (xy 410.971534 -393.692888) (xy 411.283658 -394.232892) (xy 411.296484 -394.256224)
			(xy 411.314704 -394.306247) (xy 411.323963 -394.358673) (xy 411.324552 -394.385292) (xy 411.324031 -394.409268)
			(xy 411.316536 -394.456631) (xy 411.301727 -394.502239) (xy 411.279971 -394.544972) (xy 411.251801 -394.583778)
			(xy 411.217911 -394.617702) (xy 411.179133 -394.645911) (xy 411.136423 -394.66771) (xy 411.090829 -394.682564)
			(xy 411.043474 -394.690107) (xy 411.019498 -394.6906) (xy 411.01899 -394.6906) (xy 410.995416 -394.690214)
			(xy 410.948827 -394.682971) (xy 410.903908 -394.668644) (xy 410.86173 -394.647574) (xy 410.823297 -394.620263)
			(xy 410.789526 -394.587363) (xy 410.76122 -394.549656) (xy 410.74975 -394.529056) (xy 410.749242 -394.528294)
			(xy 410.351478 -393.839954) (xy 410.339621 -393.817268) (xy 410.322763 -393.768939) (xy 410.314182 -393.718479)
			(xy 410.313632 -393.692888) (xy 409.771638 -393.692888) (xy 410.083762 -394.232892) (xy 410.096589 -394.256224)
			(xy 410.114808 -394.306247) (xy 410.124067 -394.358673) (xy 410.124656 -394.385292) (xy 410.124131 -394.409268)
			(xy 410.116636 -394.45663) (xy 410.101828 -394.502239) (xy 410.080072 -394.544971) (xy 410.051902 -394.583776)
			(xy 410.018012 -394.617701) (xy 409.979235 -394.645909) (xy 409.936525 -394.667709) (xy 409.890932 -394.682563)
			(xy 409.843577 -394.690107) (xy 409.819602 -394.6906) (xy 409.819094 -394.6906) (xy 409.79552 -394.690211)
			(xy 409.748931 -394.682969) (xy 409.704013 -394.668642) (xy 409.661834 -394.647573) (xy 409.623401 -394.620262)
			(xy 409.58963 -394.587362) (xy 409.561324 -394.549656) (xy 409.549854 -394.529056) (xy 409.549346 -394.528294)
			(xy 409.151582 -393.839954) (xy 409.139725 -393.817268) (xy 409.122867 -393.768939) (xy 409.114286 -393.718479)
			(xy 409.113736 -393.692888) (xy 408.571488 -393.692888) (xy 408.883612 -394.232892) (xy 408.896346 -394.25621)
			(xy 408.914439 -394.306158) (xy 408.923655 -394.358477) (xy 408.924252 -394.385038) (xy 408.924252 -394.385292)
			(xy 408.92373 -394.409281) (xy 408.916227 -394.456668) (xy 408.901403 -394.502298) (xy 408.879624 -394.545048)
			(xy 408.851427 -394.583865) (xy 408.817504 -394.617793) (xy 408.778692 -394.645997) (xy 408.735946 -394.667783)
			(xy 408.690319 -394.682614) (xy 408.642933 -394.690126) (xy 408.618944 -394.6906) (xy 408.595371 -394.690171)
			(xy 408.548785 -394.682936) (xy 408.503867 -394.668616) (xy 408.461689 -394.647554) (xy 408.423255 -394.620249)
			(xy 408.389482 -394.587355) (xy 408.361175 -394.549654) (xy 408.349704 -394.529056) (xy 408.349196 -394.528294)
			(xy 407.951432 -393.839954) (xy 407.9395 -393.817294) (xy 407.922568 -393.768965) (xy 407.913915 -393.718491)
			(xy 407.913332 -393.692888) (xy 407.371592 -393.692888) (xy 407.683716 -394.232892) (xy 407.69645 -394.256209)
			(xy 407.714543 -394.306158) (xy 407.723759 -394.358477) (xy 407.724356 -394.385038) (xy 407.724356 -394.385292)
			(xy 407.72383 -394.409281) (xy 407.716327 -394.456667) (xy 407.701503 -394.502297) (xy 407.679725 -394.545047)
			(xy 407.651528 -394.583863) (xy 407.617606 -394.617791) (xy 407.578794 -394.645996) (xy 407.536049 -394.667782)
			(xy 407.490422 -394.682614) (xy 407.443037 -394.690126) (xy 407.419048 -394.6906) (xy 407.395475 -394.690168)
			(xy 407.348889 -394.682933) (xy 407.303971 -394.668614) (xy 407.261793 -394.647552) (xy 407.223359 -394.620248)
			(xy 407.189586 -394.587354) (xy 407.161279 -394.549654) (xy 407.149808 -394.529056) (xy 407.1493 -394.528294)
			(xy 406.751536 -393.839954) (xy 406.739605 -393.817294) (xy 406.722672 -393.768964) (xy 406.714019 -393.718491)
			(xy 406.713436 -393.692888) (xy 406.171442 -393.692888) (xy 406.483566 -394.232892) (xy 406.496393 -394.256223)
			(xy 406.514612 -394.306247) (xy 406.523871 -394.358673) (xy 406.52446 -394.385292) (xy 406.524031 -394.409273)
			(xy 406.516532 -394.456644) (xy 406.501719 -394.502261) (xy 406.479954 -394.544999) (xy 406.451774 -394.583809)
			(xy 406.417872 -394.617735) (xy 406.379082 -394.645942) (xy 406.336359 -394.667737) (xy 406.290753 -394.682582)
			(xy 406.243386 -394.690114) (xy 406.219406 -394.6906) (xy 406.218898 -394.6906) (xy 406.195324 -394.690208)
			(xy 406.148736 -394.682966) (xy 406.103817 -394.66864) (xy 406.061639 -394.647571) (xy 406.023206 -394.620261)
			(xy 405.989434 -394.587361) (xy 405.961128 -394.549656) (xy 405.949658 -394.529056) (xy 405.94915 -394.528294)
			(xy 405.551386 -393.839954) (xy 405.53953 -393.817267) (xy 405.522671 -393.768939) (xy 405.51409 -393.718479)
			(xy 405.51354 -393.692888) (xy 404.971546 -393.692888) (xy 405.28367 -394.232892) (xy 405.296497 -394.256223)
			(xy 405.314716 -394.306247) (xy 405.323975 -394.358673) (xy 405.324564 -394.385292) (xy 405.324131 -394.409273)
			(xy 405.316633 -394.456644) (xy 405.301819 -394.50226) (xy 405.280055 -394.544998) (xy 405.251875 -394.583808)
			(xy 405.217974 -394.617733) (xy 405.179184 -394.645941) (xy 405.136461 -394.667735) (xy 405.090856 -394.682581)
			(xy 405.04349 -394.690114) (xy 405.01951 -394.6906) (xy 405.019002 -394.6906) (xy 404.995428 -394.690205)
			(xy 404.94884 -394.682963) (xy 404.903921 -394.668638) (xy 404.861743 -394.64757) (xy 404.82331 -394.62026)
			(xy 404.789538 -394.587361) (xy 404.761233 -394.549656) (xy 404.749762 -394.529056) (xy 404.749254 -394.528294)
			(xy 404.35149 -393.839954) (xy 404.339634 -393.817267) (xy 404.322775 -393.768939) (xy 404.314194 -393.718479)
			(xy 404.313644 -393.692888) (xy 403.77165 -393.692888) (xy 404.083774 -394.232892) (xy 404.096601 -394.256223)
			(xy 404.11482 -394.306247) (xy 404.124079 -394.358673) (xy 404.124668 -394.385292) (xy 404.124231 -394.409272)
			(xy 404.116733 -394.456643) (xy 404.101919 -394.502259) (xy 404.080155 -394.544997) (xy 404.051976 -394.583806)
			(xy 404.018075 -394.617732) (xy 403.979287 -394.645939) (xy 403.936564 -394.667734) (xy 403.890959 -394.682581)
			(xy 403.843594 -394.690113) (xy 403.819614 -394.6906) (xy 403.819106 -394.6906) (xy 403.795532 -394.690201)
			(xy 403.748944 -394.682961) (xy 403.704026 -394.668636) (xy 403.661847 -394.647568) (xy 403.623414 -394.620259)
			(xy 403.589642 -394.58736) (xy 403.561337 -394.549655) (xy 403.549866 -394.529056) (xy 403.549358 -394.528294)
			(xy 403.151594 -393.839954) (xy 403.139738 -393.817267) (xy 403.122879 -393.768939) (xy 403.114298 -393.718479)
			(xy 403.113748 -393.692888) (xy 389.243866 -393.692888) (xy 389.55599 -394.232892) (xy 389.568819 -394.256222)
			(xy 389.587037 -394.306246) (xy 389.596295 -394.358673) (xy 389.596884 -394.385292) (xy 389.596431 -394.409272)
			(xy 389.588933 -394.456641) (xy 389.574121 -394.502255) (xy 389.552358 -394.544992) (xy 389.524181 -394.583801)
			(xy 389.490282 -394.617726) (xy 389.451496 -394.645934) (xy 389.408775 -394.66773) (xy 389.363173 -394.682578)
			(xy 389.315809 -394.690112) (xy 389.29183 -394.6906) (xy 389.291322 -394.6906) (xy 389.267749 -394.690188)
			(xy 389.221161 -394.68295) (xy 389.176243 -394.668628) (xy 389.134065 -394.647562) (xy 389.095631 -394.620255)
			(xy 389.061859 -394.587358) (xy 389.033553 -394.549655) (xy 389.022082 -394.529056) (xy 389.021574 -394.528294)
			(xy 388.62381 -393.839954) (xy 388.611948 -393.81727) (xy 388.595093 -393.76894) (xy 388.586513 -393.71848)
			(xy 388.585964 -393.692888) (xy 388.043716 -393.692888) (xy 388.35584 -394.232892) (xy 388.368576 -394.256208)
			(xy 388.386668 -394.306157) (xy 388.395883 -394.358476) (xy 388.39648 -394.385038) (xy 388.39648 -394.385292)
			(xy 388.396054 -394.409286) (xy 388.388548 -394.456684) (xy 388.373719 -394.502324) (xy 388.351932 -394.545082)
			(xy 388.323724 -394.583905) (xy 388.28979 -394.617837) (xy 388.250965 -394.646042) (xy 388.208206 -394.667826)
			(xy 388.162565 -394.682653) (xy 388.115166 -394.690156) (xy 388.091172 -394.6906) (xy 388.067597 -394.690229)
			(xy 388.021008 -394.682983) (xy 387.976089 -394.668653) (xy 387.93391 -394.647581) (xy 387.895478 -394.620268)
			(xy 387.861707 -394.587365) (xy 387.833402 -394.549657) (xy 387.821932 -394.529056) (xy 387.821424 -394.528294)
			(xy 387.42366 -393.839954) (xy 387.41173 -393.817293) (xy 387.394797 -393.768964) (xy 387.386143 -393.718491)
			(xy 387.38556 -393.692888) (xy 386.84382 -393.692888) (xy 387.155944 -394.232892) (xy 387.16868 -394.256208)
			(xy 387.186772 -394.306157) (xy 387.195988 -394.358476) (xy 387.196584 -394.385038) (xy 387.196584 -394.385292)
			(xy 387.196154 -394.409286) (xy 387.188648 -394.456684) (xy 387.173819 -394.502323) (xy 387.152033 -394.545081)
			(xy 387.123825 -394.583904) (xy 387.089892 -394.617836) (xy 387.051067 -394.646041) (xy 387.008308 -394.667825)
			(xy 386.962668 -394.682652) (xy 386.91527 -394.690156) (xy 386.891276 -394.6906) (xy 386.867701 -394.690226)
			(xy 386.821112 -394.68298) (xy 386.776193 -394.668651) (xy 386.734015 -394.647579) (xy 386.695582 -394.620267)
			(xy 386.661811 -394.587365) (xy 386.633506 -394.549657) (xy 386.622036 -394.529056) (xy 386.621528 -394.528294)
			(xy 386.223764 -393.839954) (xy 386.211835 -393.817292) (xy 386.194901 -393.768964) (xy 386.186248 -393.718491)
			(xy 386.185664 -393.692888) (xy 385.64367 -393.692888) (xy 385.955794 -394.232892) (xy 385.968623 -394.256222)
			(xy 385.986841 -394.306246) (xy 385.996099 -394.358673) (xy 385.996688 -394.385292) (xy 385.996231 -394.409271)
			(xy 385.988733 -394.45664) (xy 385.973921 -394.502254) (xy 385.952159 -394.544991) (xy 385.923982 -394.5838)
			(xy 385.890084 -394.617725) (xy 385.851298 -394.645932) (xy 385.808578 -394.667728) (xy 385.762976 -394.682577)
			(xy 385.715613 -394.690112) (xy 385.691634 -394.6906) (xy 385.691126 -394.6906) (xy 385.667553 -394.690185)
			(xy 385.620965 -394.682948) (xy 385.576047 -394.668626) (xy 385.533869 -394.64756) (xy 385.495436 -394.620254)
			(xy 385.461663 -394.587357) (xy 385.433357 -394.549655) (xy 385.421886 -394.529056) (xy 385.421378 -394.528294)
			(xy 385.023614 -393.839954) (xy 385.011752 -393.81727) (xy 384.994897 -393.76894) (xy 384.986317 -393.71848)
			(xy 384.985768 -393.692888) (xy 384.443774 -393.692888) (xy 384.755898 -394.232892) (xy 384.768719 -394.256226)
			(xy 384.786942 -394.306248) (xy 384.796203 -394.358674) (xy 384.796792 -394.385292) (xy 384.796331 -394.409271)
			(xy 384.788834 -394.45664) (xy 384.774022 -394.502253) (xy 384.75226 -394.54499) (xy 384.724083 -394.583798)
			(xy 384.690186 -394.617723) (xy 384.6514 -394.645931) (xy 384.608681 -394.667727) (xy 384.563079 -394.682576)
			(xy 384.515717 -394.690112) (xy 384.491738 -394.6906) (xy 384.49123 -394.6906) (xy 384.467657 -394.690182)
			(xy 384.42107 -394.682945) (xy 384.376152 -394.668624) (xy 384.333973 -394.647559) (xy 384.29554 -394.620253)
			(xy 384.261768 -394.587357) (xy 384.233461 -394.549654) (xy 384.22199 -394.529056) (xy 384.221482 -394.528294)
			(xy 383.823718 -393.839954) (xy 383.811856 -393.81727) (xy 383.795001 -393.76894) (xy 383.786421 -393.71848)
			(xy 383.785872 -393.692888) (xy 383.243878 -393.692888) (xy 383.556002 -394.232892) (xy 383.568824 -394.256226)
			(xy 383.587046 -394.306248) (xy 383.596307 -394.358674) (xy 383.596896 -394.385292) (xy 383.596431 -394.409271)
			(xy 383.588934 -394.456639) (xy 383.574122 -394.502252) (xy 383.552361 -394.544989) (xy 383.524185 -394.583797)
			(xy 383.490287 -394.617722) (xy 383.451502 -394.64593) (xy 383.408784 -394.667726) (xy 383.363183 -394.682575)
			(xy 383.315821 -394.690111) (xy 383.291842 -394.6906) (xy 383.291334 -394.6906) (xy 383.267761 -394.690179)
			(xy 383.221174 -394.682942) (xy 383.176256 -394.668622) (xy 383.134078 -394.647557) (xy 383.095644 -394.620252)
			(xy 383.061872 -394.587356) (xy 383.033565 -394.549654) (xy 383.022094 -394.529056) (xy 383.021586 -394.528294)
			(xy 382.623822 -393.839954) (xy 382.611961 -393.81727) (xy 382.595105 -393.76894) (xy 382.586526 -393.71848)
			(xy 382.585976 -393.692888) (xy 382.043728 -393.692888) (xy 382.355852 -394.232892) (xy 382.368589 -394.256208)
			(xy 382.386681 -394.306157) (xy 382.395896 -394.358476) (xy 382.396492 -394.385038) (xy 382.396492 -394.385292)
			(xy 382.396054 -394.409286) (xy 382.388548 -394.456682) (xy 382.37372 -394.502321) (xy 382.351934 -394.545079)
			(xy 382.323728 -394.583901) (xy 382.289795 -394.617833) (xy 382.250972 -394.646038) (xy 382.208214 -394.667823)
			(xy 382.162575 -394.68265) (xy 382.115178 -394.690155) (xy 382.091184 -394.6906) (xy 382.06761 -394.690219)
			(xy 382.021021 -394.682975) (xy 381.976102 -394.668647) (xy 381.933923 -394.647576) (xy 381.895491 -394.620265)
			(xy 381.861719 -394.587363) (xy 381.833414 -394.549656) (xy 381.821944 -394.529056) (xy 381.821436 -394.528294)
			(xy 381.423672 -393.839954) (xy 381.411736 -393.817296) (xy 381.394806 -393.768965) (xy 381.386155 -393.718492)
			(xy 381.385572 -393.692888) (xy 380.843832 -393.692888) (xy 381.155956 -394.232892) (xy 381.168693 -394.256208)
			(xy 381.186785 -394.306157) (xy 381.196 -394.358476) (xy 381.196596 -394.385038) (xy 381.196596 -394.385292)
			(xy 381.196154 -394.409286) (xy 381.188648 -394.456682) (xy 381.17382 -394.50232) (xy 381.152035 -394.545077)
			(xy 381.123829 -394.5839) (xy 381.089897 -394.617831) (xy 381.051074 -394.646037) (xy 381.008317 -394.667822)
			(xy 380.962678 -394.682649) (xy 380.915282 -394.690155) (xy 380.891288 -394.6906) (xy 380.867714 -394.690216)
			(xy 380.821125 -394.682973) (xy 380.776206 -394.668645) (xy 380.734028 -394.647575) (xy 380.695595 -394.620264)
			(xy 380.661823 -394.587363) (xy 380.633518 -394.549656) (xy 380.622048 -394.529056) (xy 380.62154 -394.528294)
			(xy 380.223776 -393.839954) (xy 380.21184 -393.817296) (xy 380.19491 -393.768965) (xy 380.186259 -393.718492)
			(xy 380.185676 -393.692888) (xy 379.643682 -393.692888) (xy 379.955806 -394.232892) (xy 379.968628 -394.256226)
			(xy 379.98685 -394.306248) (xy 379.996111 -394.358674) (xy 379.9967 -394.385292) (xy 379.996231 -394.409271)
			(xy 379.988734 -394.456639) (xy 379.973922 -394.502251) (xy 379.952161 -394.544988) (xy 379.923986 -394.583795)
			(xy 379.890089 -394.617721) (xy 379.851304 -394.645928) (xy 379.808586 -394.667725) (xy 379.762986 -394.682574)
			(xy 379.715624 -394.690111) (xy 379.691646 -394.6906) (xy 379.691138 -394.6906) (xy 379.667565 -394.690176)
			(xy 379.620978 -394.68294) (xy 379.57606 -394.66862) (xy 379.533882 -394.647556) (xy 379.495448 -394.620251)
			(xy 379.461676 -394.587356) (xy 379.433369 -394.549654) (xy 379.421898 -394.529056) (xy 379.42139 -394.528294)
			(xy 379.023626 -393.839954) (xy 379.011765 -393.81727) (xy 378.994909 -393.76894) (xy 378.98633 -393.71848)
			(xy 378.98578 -393.692888) (xy 378.443786 -393.692888) (xy 378.75591 -394.232892) (xy 378.768732 -394.256226)
			(xy 378.786954 -394.306248) (xy 378.796215 -394.358673) (xy 378.796804 -394.385292) (xy 378.796331 -394.409271)
			(xy 378.788834 -394.456638) (xy 378.774023 -394.502251) (xy 378.752262 -394.544986) (xy 378.724087 -394.583794)
			(xy 378.690191 -394.617719) (xy 378.651407 -394.645927) (xy 378.608689 -394.667724) (xy 378.563089 -394.682574)
			(xy 378.515728 -394.690111) (xy 378.49175 -394.6906) (xy 378.491242 -394.6906) (xy 378.467669 -394.690172)
			(xy 378.421083 -394.682937) (xy 378.376165 -394.668617) (xy 378.333986 -394.647554) (xy 378.295553 -394.62025)
			(xy 378.26178 -394.587355) (xy 378.233473 -394.549654) (xy 378.222002 -394.529056) (xy 378.221494 -394.528294)
			(xy 377.82373 -393.839954) (xy 377.811869 -393.81727) (xy 377.795013 -393.76894) (xy 377.786434 -393.71848)
			(xy 377.785884 -393.692888) (xy 377.24389 -393.692888) (xy 377.556014 -394.232892) (xy 377.568837 -394.256226)
			(xy 377.587058 -394.306248) (xy 377.596319 -394.358673) (xy 377.596908 -394.385292) (xy 377.596431 -394.40927)
			(xy 377.588934 -394.456637) (xy 377.574123 -394.50225) (xy 377.552363 -394.544985) (xy 377.524188 -394.583793)
			(xy 377.490292 -394.617718) (xy 377.451509 -394.645926) (xy 377.408792 -394.667723) (xy 377.363192 -394.682573)
			(xy 377.315832 -394.69011) (xy 377.291854 -394.6906) (xy 377.291346 -394.6906) (xy 377.267773 -394.690169)
			(xy 377.221187 -394.682935) (xy 377.176269 -394.668615) (xy 377.134091 -394.647553) (xy 377.095657 -394.620249)
			(xy 377.061884 -394.587355) (xy 377.033577 -394.549654) (xy 377.022106 -394.529056) (xy 377.021598 -394.528294)
			(xy 376.623834 -393.839954) (xy 376.611974 -393.81727) (xy 376.595118 -393.76894) (xy 376.586538 -393.71848)
			(xy 376.585988 -393.692888) (xy 376.04374 -393.692888) (xy 376.355864 -394.232892) (xy 376.368602 -394.256207)
			(xy 376.386693 -394.306157) (xy 376.395908 -394.358476) (xy 376.396504 -394.385038) (xy 376.396504 -394.385292)
			(xy 376.396054 -394.409285) (xy 376.388549 -394.456681) (xy 376.373721 -394.502319) (xy 376.351936 -394.545075)
			(xy 376.323731 -394.583897) (xy 376.2898 -394.617829) (xy 376.250978 -394.646034) (xy 376.208222 -394.66782)
			(xy 376.162585 -394.682648) (xy 376.115189 -394.690154) (xy 376.091196 -394.6906) (xy 376.067622 -394.690209)
			(xy 376.021033 -394.682967) (xy 375.976115 -394.668641) (xy 375.933936 -394.647572) (xy 375.895503 -394.620262)
			(xy 375.861732 -394.587362) (xy 375.833426 -394.549656) (xy 375.821956 -394.529056) (xy 375.821448 -394.528294)
			(xy 375.423684 -393.839954) (xy 375.411748 -393.817296) (xy 375.394819 -393.768965) (xy 375.386167 -393.718492)
			(xy 375.385584 -393.692888) (xy 374.843844 -393.692888) (xy 375.155968 -394.232892) (xy 375.168706 -394.256207)
			(xy 375.186797 -394.306157) (xy 375.196012 -394.358476) (xy 375.196608 -394.385038) (xy 375.196608 -394.385292)
			(xy 375.196154 -394.409285) (xy 375.188649 -394.45668) (xy 375.173821 -394.502318) (xy 375.152037 -394.545074)
			(xy 375.123832 -394.583896) (xy 375.089902 -394.617827) (xy 375.051081 -394.646033) (xy 375.008325 -394.667818)
			(xy 374.962688 -394.682647) (xy 374.915293 -394.690154) (xy 374.8913 -394.6906) (xy 374.867726 -394.690206)
			(xy 374.821138 -394.682965) (xy 374.776219 -394.668639) (xy 374.734041 -394.64757) (xy 374.695608 -394.620261)
			(xy 374.661836 -394.587361) (xy 374.63353 -394.549656) (xy 374.62206 -394.529056) (xy 374.621552 -394.528294)
			(xy 374.223788 -393.839954) (xy 374.211853 -393.817296) (xy 374.194923 -393.768965) (xy 374.186271 -393.718491)
			(xy 374.185688 -393.692888) (xy 373.643694 -393.692888) (xy 373.955818 -394.232892) (xy 373.968641 -394.256226)
			(xy 373.986862 -394.306248) (xy 373.996123 -394.358673) (xy 373.996712 -394.385292) (xy 373.996231 -394.40927)
			(xy 373.988734 -394.456637) (xy 373.973924 -394.502249) (xy 373.952164 -394.544984) (xy 373.923989 -394.583791)
			(xy 373.890094 -394.617716) (xy 373.851311 -394.645924) (xy 373.808595 -394.667722) (xy 373.762996 -394.682572)
			(xy 373.715636 -394.69011) (xy 373.691658 -394.6906) (xy 373.69115 -394.6906) (xy 373.667577 -394.690166)
			(xy 373.620991 -394.682932) (xy 373.576073 -394.668613) (xy 373.533895 -394.647551) (xy 373.495461 -394.620248)
			(xy 373.461688 -394.587354) (xy 373.433381 -394.549653) (xy 373.42191 -394.529056) (xy 373.421402 -394.528294)
			(xy 373.023638 -393.839954) (xy 373.011778 -393.817269) (xy 372.994922 -393.76894) (xy 372.986342 -393.71848)
			(xy 372.985792 -393.692888) (xy 372.443798 -393.692888) (xy 372.755922 -394.232892) (xy 372.768745 -394.256225)
			(xy 372.786966 -394.306248) (xy 372.796227 -394.358673) (xy 372.796816 -394.385292) (xy 372.796331 -394.40927)
			(xy 372.788834 -394.456636) (xy 372.774024 -394.502248) (xy 372.752264 -394.544983) (xy 372.72409 -394.58379)
			(xy 372.690196 -394.617715) (xy 372.651413 -394.645923) (xy 372.608698 -394.66772) (xy 372.563099 -394.682571)
			(xy 372.51574 -394.69011) (xy 372.491762 -394.6906) (xy 372.491254 -394.6906) (xy 372.467682 -394.690163)
			(xy 372.421095 -394.682929) (xy 372.376178 -394.668611) (xy 372.333999 -394.64755) (xy 372.295566 -394.620247)
			(xy 372.261793 -394.587353) (xy 372.233485 -394.549653) (xy 372.222014 -394.529056) (xy 372.221506 -394.528294)
			(xy 371.823742 -393.839954) (xy 371.811882 -393.817269) (xy 371.795026 -393.76894) (xy 371.786446 -393.71848)
			(xy 371.785896 -393.692888) (xy 371.243902 -393.692888) (xy 371.556026 -394.232892) (xy 371.56885 -394.256225)
			(xy 371.587071 -394.306247) (xy 371.596331 -394.358673) (xy 371.59692 -394.385292) (xy 371.596431 -394.40927)
			(xy 371.588935 -394.456636) (xy 371.574124 -394.502247) (xy 371.552365 -394.544982) (xy 371.524192 -394.583789)
			(xy 371.490297 -394.617713) (xy 371.451516 -394.645922) (xy 371.4088 -394.667719) (xy 371.363202 -394.68257)
			(xy 371.315843 -394.69011) (xy 371.291866 -394.6906) (xy 371.291358 -394.6906) (xy 371.267786 -394.690159)
			(xy 371.2212 -394.682927) (xy 371.176282 -394.668609) (xy 371.134104 -394.647548) (xy 371.09567 -394.620246)
			(xy 371.061897 -394.587353) (xy 371.03359 -394.549653) (xy 371.022118 -394.529056) (xy 371.02161 -394.528294)
			(xy 370.623846 -393.839954) (xy 370.611986 -393.817269) (xy 370.59513 -393.76894) (xy 370.58655 -393.71848)
			(xy 370.586 -393.692888) (xy 354.671418 -393.692888) (xy 354.983542 -394.232892) (xy 354.996367 -394.256224)
			(xy 355.014587 -394.306247) (xy 355.023847 -394.358673) (xy 355.024436 -394.385292) (xy 355.023931 -394.409269)
			(xy 355.016435 -394.456633) (xy 355.001626 -394.502243) (xy 354.979868 -394.544977) (xy 354.951696 -394.583783)
			(xy 354.917804 -394.617708) (xy 354.879024 -394.645916) (xy 354.836311 -394.667715) (xy 354.790716 -394.682567)
			(xy 354.743358 -394.690108) (xy 354.719382 -394.6906) (xy 354.718874 -394.6906) (xy 354.695299 -394.690227)
			(xy 354.64871 -394.682982) (xy 354.603791 -394.668652) (xy 354.561613 -394.64758) (xy 354.52318 -394.620267)
			(xy 354.489409 -394.587365) (xy 354.461104 -394.549657) (xy 354.449634 -394.529056) (xy 354.449126 -394.528294)
			(xy 354.051362 -393.839954) (xy 354.039504 -393.817268) (xy 354.022646 -393.76894) (xy 354.014066 -393.71848)
			(xy 354.013516 -393.692888) (xy 353.471522 -393.692888) (xy 353.783646 -394.232892) (xy 353.796471 -394.256224)
			(xy 353.814691 -394.306247) (xy 353.823951 -394.358673) (xy 353.82454 -394.385292) (xy 353.824031 -394.409269)
			(xy 353.816535 -394.456633) (xy 353.801726 -394.502242) (xy 353.779969 -394.544976) (xy 353.751798 -394.583782)
			(xy 353.717906 -394.617706) (xy 353.679127 -394.645915) (xy 353.636414 -394.667714) (xy 353.590819 -394.682566)
			(xy 353.543462 -394.690108) (xy 353.519486 -394.6906) (xy 353.518978 -394.6906) (xy 353.495403 -394.690224)
			(xy 353.448814 -394.682979) (xy 353.403895 -394.66865) (xy 353.361717 -394.647579) (xy 353.323284 -394.620266)
			(xy 353.289513 -394.587364) (xy 353.261208 -394.549657) (xy 353.249738 -394.529056) (xy 353.24923 -394.528294)
			(xy 352.851466 -393.839954) (xy 352.839608 -393.817268) (xy 352.82275 -393.76894) (xy 352.81417 -393.71848)
			(xy 352.81362 -393.692888) (xy 352.271372 -393.692888) (xy 352.583496 -394.232892) (xy 352.596228 -394.25621)
			(xy 352.614323 -394.306158) (xy 352.623539 -394.358477) (xy 352.624136 -394.385038) (xy 352.624136 -394.385292)
			(xy 352.62363 -394.409282) (xy 352.616126 -394.45667) (xy 352.601301 -394.502302) (xy 352.579521 -394.545053)
			(xy 352.551322 -394.58387) (xy 352.517397 -394.617798) (xy 352.478583 -394.646002) (xy 352.435835 -394.667788)
			(xy 352.390205 -394.682618) (xy 352.342818 -394.690127) (xy 352.318828 -394.6906) (xy 352.295255 -394.690184)
			(xy 352.248668 -394.682946) (xy 352.20375 -394.668625) (xy 352.161571 -394.64756) (xy 352.123138 -394.620254)
			(xy 352.089365 -394.587357) (xy 352.061059 -394.549654) (xy 352.049588 -394.529056) (xy 352.04908 -394.528294)
			(xy 351.651316 -393.839954) (xy 351.639383 -393.817294) (xy 351.622452 -393.768965) (xy 351.613799 -393.718491)
			(xy 351.613216 -393.692888) (xy 351.071476 -393.692888) (xy 351.3836 -394.232892) (xy 351.396333 -394.25621)
			(xy 351.414427 -394.306158) (xy 351.423643 -394.358477) (xy 351.42424 -394.385038) (xy 351.42424 -394.385292)
			(xy 351.42373 -394.409281) (xy 351.416226 -394.45667) (xy 351.401402 -394.502301) (xy 351.379622 -394.545051)
			(xy 351.351423 -394.583869) (xy 351.317499 -394.617797) (xy 351.278686 -394.646001) (xy 351.235938 -394.667787)
			(xy 351.190309 -394.682617) (xy 351.142921 -394.690127) (xy 351.118932 -394.6906) (xy 351.095359 -394.69018)
			(xy 351.048772 -394.682944) (xy 351.003854 -394.668623) (xy 350.961675 -394.647558) (xy 350.923242 -394.620253)
			(xy 350.88947 -394.587357) (xy 350.861163 -394.549654) (xy 350.849692 -394.529056) (xy 350.849184 -394.528294)
			(xy 350.45142 -393.839954) (xy 350.439487 -393.817294) (xy 350.422556 -393.768965) (xy 350.413903 -393.718491)
			(xy 350.41332 -393.692888) (xy 349.871326 -393.692888) (xy 350.18345 -394.232892) (xy 350.196276 -394.256224)
			(xy 350.214495 -394.306247) (xy 350.223755 -394.358673) (xy 350.224344 -394.385292) (xy 350.223831 -394.409269)
			(xy 350.216335 -394.456632) (xy 350.201527 -394.502241) (xy 350.179769 -394.544974) (xy 350.151599 -394.58378)
			(xy 350.117707 -394.617705) (xy 350.078929 -394.645913) (xy 350.036217 -394.667712) (xy 349.990622 -394.682566)
			(xy 349.943266 -394.690108) (xy 349.91929 -394.6906) (xy 349.918782 -394.6906) (xy 349.895207 -394.690221)
			(xy 349.848619 -394.682977) (xy 349.8037 -394.668648) (xy 349.761521 -394.647577) (xy 349.723088 -394.620265)
			(xy 349.689317 -394.587364) (xy 349.661012 -394.549657) (xy 349.649542 -394.529056) (xy 349.649034 -394.528294)
			(xy 349.25127 -393.839954) (xy 349.239412 -393.817268) (xy 349.222555 -393.768939) (xy 349.213974 -393.71848)
			(xy 349.213424 -393.692888) (xy 348.67143 -393.692888) (xy 348.983554 -394.232892) (xy 348.99638 -394.256224)
			(xy 349.014599 -394.306247) (xy 349.023859 -394.358673) (xy 349.024448 -394.385292) (xy 349.023931 -394.409268)
			(xy 349.016436 -394.456632) (xy 349.001627 -394.50224) (xy 348.97987 -394.544973) (xy 348.9517 -394.583779)
			(xy 348.917809 -394.617703) (xy 348.879031 -394.645912) (xy 348.83632 -394.667711) (xy 348.790726 -394.682565)
			(xy 348.74337 -394.690107) (xy 348.719394 -394.6906) (xy 348.718886 -394.6906) (xy 348.695312 -394.690217)
			(xy 348.648723 -394.682974) (xy 348.603804 -394.668646) (xy 348.561626 -394.647576) (xy 348.523193 -394.620264)
			(xy 348.489421 -394.587363) (xy 348.461116 -394.549656) (xy 348.449646 -394.529056) (xy 348.449138 -394.528294)
			(xy 348.051374 -393.839954) (xy 348.039517 -393.817268) (xy 348.022659 -393.768939) (xy 348.014078 -393.718479)
			(xy 348.013528 -393.692888) (xy 347.47128 -393.692888) (xy 347.783404 -394.232892) (xy 347.796137 -394.25621)
			(xy 347.814231 -394.306158) (xy 347.823447 -394.358477) (xy 347.824044 -394.385038) (xy 347.824044 -394.385292)
			(xy 347.82353 -394.409281) (xy 347.816026 -394.456669) (xy 347.801202 -394.5023) (xy 347.779423 -394.54505)
			(xy 347.751224 -394.583867) (xy 347.717301 -394.617796) (xy 347.678488 -394.646) (xy 347.635741 -394.667785)
			(xy 347.590112 -394.682616) (xy 347.542725 -394.690127) (xy 347.518736 -394.6906) (xy 347.495163 -394.690177)
			(xy 347.448576 -394.682941) (xy 347.403658 -394.668621) (xy 347.36148 -394.647557) (xy 347.323046 -394.620252)
			(xy 347.289274 -394.587356) (xy 347.260967 -394.549654) (xy 347.249496 -394.529056) (xy 347.248988 -394.528294)
			(xy 346.851224 -393.839954) (xy 346.839292 -393.817294) (xy 346.82236 -393.768965) (xy 346.813707 -393.718491)
			(xy 346.813124 -393.692888) (xy 346.271384 -393.692888) (xy 346.583508 -394.232892) (xy 346.596241 -394.25621)
			(xy 346.614335 -394.306158) (xy 346.623551 -394.358477) (xy 346.624148 -394.385038) (xy 346.624148 -394.385292)
			(xy 346.62363 -394.409281) (xy 346.616126 -394.456669) (xy 346.601303 -394.502299) (xy 346.579524 -394.545049)
			(xy 346.551325 -394.583866) (xy 346.517403 -394.617794) (xy 346.47859 -394.645998) (xy 346.435843 -394.667784)
			(xy 346.390215 -394.682615) (xy 346.342829 -394.690126) (xy 346.31884 -394.6906) (xy 346.295267 -394.690174)
			(xy 346.24868 -394.682939) (xy 346.203763 -394.668618) (xy 346.161584 -394.647555) (xy 346.123151 -394.620251)
			(xy 346.089378 -394.587355) (xy 346.061071 -394.549654) (xy 346.0496 -394.529056) (xy 346.049092 -394.528294)
			(xy 345.651328 -393.839954) (xy 345.639396 -393.817294) (xy 345.622464 -393.768965) (xy 345.613811 -393.718491)
			(xy 345.613228 -393.692888) (xy 345.071488 -393.692888) (xy 345.383612 -394.232892) (xy 345.396346 -394.25621)
			(xy 345.414439 -394.306158) (xy 345.423655 -394.358477) (xy 345.424252 -394.385038) (xy 345.424252 -394.385292)
			(xy 345.42373 -394.409281) (xy 345.416227 -394.456668) (xy 345.401403 -394.502298) (xy 345.379624 -394.545048)
			(xy 345.351427 -394.583865) (xy 345.317504 -394.617793) (xy 345.278692 -394.645997) (xy 345.235946 -394.667783)
			(xy 345.190319 -394.682614) (xy 345.142933 -394.690126) (xy 345.118944 -394.6906) (xy 345.095371 -394.690171)
			(xy 345.048785 -394.682936) (xy 345.003867 -394.668616) (xy 344.961689 -394.647554) (xy 344.923255 -394.620249)
			(xy 344.889482 -394.587355) (xy 344.861175 -394.549654) (xy 344.849704 -394.529056) (xy 344.849196 -394.528294)
			(xy 344.451432 -393.839954) (xy 344.4395 -393.817294) (xy 344.422568 -393.768965) (xy 344.413915 -393.718491)
			(xy 344.413332 -393.692888) (xy 343.871338 -393.692888) (xy 344.183462 -394.232892) (xy 344.196289 -394.256224)
			(xy 344.214508 -394.306247) (xy 344.223767 -394.358673) (xy 344.224356 -394.385292) (xy 344.223831 -394.409268)
			(xy 344.216336 -394.45663) (xy 344.201528 -394.502239) (xy 344.179772 -394.544971) (xy 344.151602 -394.583776)
			(xy 344.117712 -394.617701) (xy 344.078935 -394.645909) (xy 344.036225 -394.667709) (xy 343.990632 -394.682563)
			(xy 343.943277 -394.690107) (xy 343.919302 -394.6906) (xy 343.918794 -394.6906) (xy 343.89522 -394.690211)
			(xy 343.848631 -394.682969) (xy 343.803713 -394.668642) (xy 343.761534 -394.647573) (xy 343.723101 -394.620262)
			(xy 343.68933 -394.587362) (xy 343.661024 -394.549656) (xy 343.649554 -394.529056) (xy 343.649046 -394.528294)
			(xy 343.251282 -393.839954) (xy 343.239425 -393.817268) (xy 343.222567 -393.768939) (xy 343.213986 -393.718479)
			(xy 343.213436 -393.692888) (xy 342.671442 -393.692888) (xy 342.983566 -394.232892) (xy 342.996393 -394.256223)
			(xy 343.014612 -394.306247) (xy 343.023871 -394.358673) (xy 343.02446 -394.385292) (xy 343.024031 -394.409273)
			(xy 343.016532 -394.456644) (xy 343.001719 -394.502261) (xy 342.979954 -394.544999) (xy 342.951774 -394.583809)
			(xy 342.917872 -394.617735) (xy 342.879082 -394.645942) (xy 342.836359 -394.667737) (xy 342.790753 -394.682582)
			(xy 342.743386 -394.690114) (xy 342.719406 -394.6906) (xy 342.718898 -394.6906) (xy 342.695324 -394.690208)
			(xy 342.648736 -394.682966) (xy 342.603817 -394.66864) (xy 342.561639 -394.647571) (xy 342.523206 -394.620261)
			(xy 342.489434 -394.587361) (xy 342.461128 -394.549656) (xy 342.449658 -394.529056) (xy 342.44915 -394.528294)
			(xy 342.051386 -393.839954) (xy 342.03953 -393.817267) (xy 342.022671 -393.768939) (xy 342.01409 -393.718479)
			(xy 342.01354 -393.692888) (xy 341.471292 -393.692888) (xy 341.783416 -394.232892) (xy 341.79615 -394.256209)
			(xy 341.814243 -394.306158) (xy 341.823459 -394.358477) (xy 341.824056 -394.385038) (xy 341.824056 -394.385292)
			(xy 341.82353 -394.409281) (xy 341.816027 -394.456667) (xy 341.801203 -394.502297) (xy 341.779425 -394.545047)
			(xy 341.751228 -394.583863) (xy 341.717306 -394.617791) (xy 341.678494 -394.645996) (xy 341.635749 -394.667782)
			(xy 341.590122 -394.682614) (xy 341.542737 -394.690126) (xy 341.518748 -394.6906) (xy 341.495175 -394.690168)
			(xy 341.448589 -394.682933) (xy 341.403671 -394.668614) (xy 341.361493 -394.647552) (xy 341.323059 -394.620248)
			(xy 341.289286 -394.587354) (xy 341.260979 -394.549654) (xy 341.249508 -394.529056) (xy 341.249 -394.528294)
			(xy 340.851236 -393.839954) (xy 340.839305 -393.817294) (xy 340.822372 -393.768964) (xy 340.813719 -393.718491)
			(xy 340.813136 -393.692888) (xy 340.271396 -393.692888) (xy 340.58352 -394.232892) (xy 340.596254 -394.256209)
			(xy 340.614348 -394.306158) (xy 340.623563 -394.358476) (xy 340.62416 -394.385038) (xy 340.62416 -394.385292)
			(xy 340.623754 -394.409287) (xy 340.616247 -394.456687) (xy 340.601417 -394.502329) (xy 340.579628 -394.545088)
			(xy 340.551418 -394.583912) (xy 340.517482 -394.617844) (xy 340.478654 -394.646049) (xy 340.435892 -394.667832)
			(xy 340.390248 -394.682657) (xy 340.342847 -394.690157) (xy 340.318852 -394.6906) (xy 340.295279 -394.690164)
			(xy 340.248693 -394.682931) (xy 340.203776 -394.668612) (xy 340.161597 -394.647551) (xy 340.123164 -394.620247)
			(xy 340.089391 -394.587354) (xy 340.061083 -394.549653) (xy 340.049612 -394.529056) (xy 340.049104 -394.528294)
			(xy 339.65134 -393.839954) (xy 339.639409 -393.817293) (xy 339.622476 -393.768964) (xy 339.613823 -393.718491)
			(xy 339.61324 -393.692888) (xy 339.0715 -393.692888) (xy 339.383624 -394.232892) (xy 339.396359 -394.256209)
			(xy 339.414452 -394.306158) (xy 339.423667 -394.358476) (xy 339.424264 -394.385038) (xy 339.424264 -394.385292)
			(xy 339.423854 -394.409287) (xy 339.416347 -394.456687) (xy 339.401517 -394.502328) (xy 339.379729 -394.545087)
			(xy 339.351519 -394.583911) (xy 339.317583 -394.617843) (xy 339.278756 -394.646048) (xy 339.235995 -394.667831)
			(xy 339.190352 -394.682656) (xy 339.142951 -394.690157) (xy 339.118956 -394.6906) (xy 339.095384 -394.690161)
			(xy 339.048797 -394.682928) (xy 339.00388 -394.66861) (xy 338.961702 -394.647549) (xy 338.923268 -394.620246)
			(xy 338.889495 -394.587353) (xy 338.861187 -394.549653) (xy 338.849716 -394.529056) (xy 338.849208 -394.528294)
			(xy 338.451444 -393.839954) (xy 338.439513 -393.817293) (xy 338.42258 -393.768964) (xy 338.413927 -393.718491)
			(xy 338.413344 -393.692888) (xy 337.87135 -393.692888) (xy 338.183474 -394.232892) (xy 338.196301 -394.256223)
			(xy 338.21452 -394.306247) (xy 338.223779 -394.358673) (xy 338.224368 -394.385292) (xy 338.223931 -394.409272)
			(xy 338.216433 -394.456643) (xy 338.201619 -394.502259) (xy 338.179855 -394.544997) (xy 338.151676 -394.583806)
			(xy 338.117775 -394.617732) (xy 338.078987 -394.645939) (xy 338.036264 -394.667734) (xy 337.990659 -394.682581)
			(xy 337.943294 -394.690113) (xy 337.919314 -394.6906) (xy 337.918806 -394.6906) (xy 337.895232 -394.690201)
			(xy 337.848644 -394.682961) (xy 337.803726 -394.668636) (xy 337.761547 -394.647568) (xy 337.723114 -394.620259)
			(xy 337.689342 -394.58736) (xy 337.661037 -394.549655) (xy 337.649566 -394.529056) (xy 337.649058 -394.528294)
			(xy 337.251294 -393.839954) (xy 337.239438 -393.817267) (xy 337.222579 -393.768939) (xy 337.213998 -393.718479)
			(xy 337.213448 -393.692888) (xy 336.671454 -393.692888) (xy 336.983578 -394.232892) (xy 336.996406 -394.256223)
			(xy 337.014624 -394.306247) (xy 337.023883 -394.358673) (xy 337.024472 -394.385292) (xy 337.024031 -394.409272)
			(xy 337.016533 -394.456643) (xy 337.00172 -394.502258) (xy 336.979956 -394.544996) (xy 336.951778 -394.583805)
			(xy 336.917877 -394.617731) (xy 336.879089 -394.645938) (xy 336.836367 -394.667733) (xy 336.790763 -394.68258)
			(xy 336.743398 -394.690113) (xy 336.719418 -394.6906) (xy 336.71891 -394.6906) (xy 336.695336 -394.690198)
			(xy 336.648748 -394.682958) (xy 336.60383 -394.668634) (xy 336.561652 -394.647566) (xy 336.523218 -394.620258)
			(xy 336.489447 -394.58736) (xy 336.461141 -394.549655) (xy 336.44967 -394.529056) (xy 336.449162 -394.528294)
			(xy 336.051398 -393.839954) (xy 336.039542 -393.817267) (xy 336.022683 -393.768939) (xy 336.014102 -393.718479)
			(xy 336.013552 -393.692888) (xy 322.143924 -393.692888) (xy 322.456048 -394.232892) (xy 322.468785 -394.256208)
			(xy 322.486876 -394.306157) (xy 322.496092 -394.358476) (xy 322.496688 -394.385038) (xy 322.496688 -394.385292)
			(xy 322.496254 -394.409286) (xy 322.488748 -394.456683) (xy 322.47392 -394.502322) (xy 322.452133 -394.54508)
			(xy 322.423926 -394.583902) (xy 322.389993 -394.617834) (xy 322.35117 -394.64604) (xy 322.308411 -394.667824)
			(xy 322.262771 -394.682651) (xy 322.215374 -394.690155) (xy 322.19138 -394.6906) (xy 322.191126 -394.6906)
			(xy 322.167553 -394.690185) (xy 322.120965 -394.682948) (xy 322.076047 -394.668626) (xy 322.033869 -394.64756)
			(xy 321.995436 -394.620254) (xy 321.961663 -394.587357) (xy 321.933357 -394.549655) (xy 321.921886 -394.529056)
			(xy 321.921378 -394.528294) (xy 321.523614 -393.839954) (xy 321.511752 -393.81727) (xy 321.494897 -393.76894)
			(xy 321.486317 -393.71848) (xy 321.485768 -393.692888) (xy 320.944028 -393.692888) (xy 321.256152 -394.232892)
			(xy 321.268889 -394.256208) (xy 321.286981 -394.306157) (xy 321.296196 -394.358476) (xy 321.296792 -394.385038)
			(xy 321.296792 -394.385292) (xy 321.296354 -394.409286) (xy 321.288848 -394.456682) (xy 321.27402 -394.502321)
			(xy 321.252234 -394.545079) (xy 321.224028 -394.583901) (xy 321.190095 -394.617833) (xy 321.151272 -394.646038)
			(xy 321.108514 -394.667823) (xy 321.062875 -394.68265) (xy 321.015478 -394.690155) (xy 320.991484 -394.6906)
			(xy 320.99123 -394.6906) (xy 320.967657 -394.690182) (xy 320.92107 -394.682945) (xy 320.876152 -394.668624)
			(xy 320.833973 -394.647559) (xy 320.79554 -394.620253) (xy 320.761768 -394.587357) (xy 320.733461 -394.549654)
			(xy 320.72199 -394.529056) (xy 320.721482 -394.528294) (xy 320.323718 -393.839954) (xy 320.311856 -393.81727)
			(xy 320.295001 -393.76894) (xy 320.286421 -393.71848) (xy 320.285872 -393.692888) (xy 319.743878 -393.692888)
			(xy 320.056002 -394.232892) (xy 320.068824 -394.256226) (xy 320.087046 -394.306248) (xy 320.096307 -394.358674)
			(xy 320.096896 -394.385292) (xy 320.096453 -394.409298) (xy 320.08894 -394.456719) (xy 320.074096 -394.502379)
			(xy 320.052288 -394.545153) (xy 320.024055 -394.583987) (xy 319.99009 -394.617922) (xy 319.951233 -394.646123)
			(xy 319.908441 -394.667895) (xy 319.862768 -394.6827) (xy 319.815341 -394.690174) (xy 319.791334 -394.6906)
			(xy 319.79108 -394.6906) (xy 319.767505 -394.690222) (xy 319.720916 -394.682978) (xy 319.675997 -394.668649)
			(xy 319.633819 -394.647578) (xy 319.595386 -394.620266) (xy 319.561615 -394.587364) (xy 319.53331 -394.549657)
			(xy 319.52184 -394.529056) (xy 319.521332 -394.528294) (xy 319.123568 -393.839954) (xy 319.111639 -393.817292)
			(xy 319.094706 -393.768964) (xy 319.086052 -393.718491) (xy 319.085468 -393.692888) (xy 318.543982 -393.692888)
			(xy 318.856106 -394.232892) (xy 318.868928 -394.256226) (xy 318.88715 -394.306248) (xy 318.896411 -394.358674)
			(xy 318.897 -394.385292) (xy 318.896554 -394.409298) (xy 318.88904 -394.456718) (xy 318.874196 -394.502378)
			(xy 318.852389 -394.545152) (xy 318.824156 -394.583985) (xy 318.790192 -394.617921) (xy 318.751335 -394.646122)
			(xy 318.708543 -394.667894) (xy 318.662871 -394.682699) (xy 318.615444 -394.690173) (xy 318.591438 -394.6906)
			(xy 318.591184 -394.6906) (xy 318.56761 -394.690219) (xy 318.521021 -394.682975) (xy 318.476102 -394.668647)
			(xy 318.433923 -394.647576) (xy 318.395491 -394.620265) (xy 318.361719 -394.587363) (xy 318.333414 -394.549656)
			(xy 318.321944 -394.529056) (xy 318.321436 -394.528294) (xy 317.923672 -393.839954) (xy 317.911736 -393.817296)
			(xy 317.894806 -393.768965) (xy 317.886155 -393.718492) (xy 317.885572 -393.692888) (xy 317.344086 -393.692888)
			(xy 317.65621 -394.232892) (xy 317.669032 -394.256226) (xy 317.687254 -394.306248) (xy 317.696515 -394.358673)
			(xy 317.697104 -394.385292) (xy 317.696654 -394.409298) (xy 317.68914 -394.456718) (xy 317.674297 -394.502377)
			(xy 317.65249 -394.545151) (xy 317.624257 -394.583984) (xy 317.590294 -394.61792) (xy 317.551437 -394.646121)
			(xy 317.508646 -394.667893) (xy 317.462974 -394.682698) (xy 317.415548 -394.690173) (xy 317.391542 -394.6906)
			(xy 317.391034 -394.6906) (xy 317.367461 -394.690179) (xy 317.320874 -394.682942) (xy 317.275956 -394.668622)
			(xy 317.233778 -394.647557) (xy 317.195344 -394.620252) (xy 317.161572 -394.587356) (xy 317.133265 -394.549654)
			(xy 317.121794 -394.529056) (xy 317.121286 -394.528294) (xy 316.723522 -393.839954) (xy 316.711661 -393.81727)
			(xy 316.694805 -393.76894) (xy 316.686226 -393.71848) (xy 316.685676 -393.692888) (xy 316.143936 -393.692888)
			(xy 316.45606 -394.232892) (xy 316.468798 -394.256207) (xy 316.486889 -394.306157) (xy 316.496104 -394.358476)
			(xy 316.4967 -394.385038) (xy 316.4967 -394.385292) (xy 316.496254 -394.409285) (xy 316.488749 -394.456681)
			(xy 316.473921 -394.50232) (xy 316.452136 -394.545076) (xy 316.42393 -394.583898) (xy 316.389998 -394.61783)
			(xy 316.351176 -394.646036) (xy 316.30842 -394.667821) (xy 316.262781 -394.682649) (xy 316.215385 -394.690154)
			(xy 316.191392 -394.6906) (xy 316.191138 -394.6906) (xy 316.167565 -394.690176) (xy 316.120978 -394.68294)
			(xy 316.07606 -394.66862) (xy 316.033882 -394.647556) (xy 315.995448 -394.620251) (xy 315.961676 -394.587356)
			(xy 315.933369 -394.549654) (xy 315.921898 -394.529056) (xy 315.92139 -394.528294) (xy 315.523626 -393.839954)
			(xy 315.511765 -393.81727) (xy 315.494909 -393.76894) (xy 315.48633 -393.71848) (xy 315.48578 -393.692888)
			(xy 314.94404 -393.692888) (xy 315.256164 -394.232892) (xy 315.268902 -394.256207) (xy 315.286993 -394.306157)
			(xy 315.296208 -394.358476) (xy 315.296804 -394.385038) (xy 315.296804 -394.385292) (xy 315.296354 -394.409285)
			(xy 315.288849 -394.456681) (xy 315.274021 -394.502319) (xy 315.252236 -394.545075) (xy 315.224031 -394.583897)
			(xy 315.1901 -394.617829) (xy 315.151278 -394.646034) (xy 315.108522 -394.66782) (xy 315.062885 -394.682648)
			(xy 315.015489 -394.690154) (xy 314.991496 -394.6906) (xy 314.990988 -394.6906) (xy 314.967414 -394.690216)
			(xy 314.920825 -394.682973) (xy 314.875906 -394.668645) (xy 314.833728 -394.647575) (xy 314.795295 -394.620264)
			(xy 314.761523 -394.587363) (xy 314.733218 -394.549656) (xy 314.721748 -394.529056) (xy 314.72124 -394.528294)
			(xy 314.323476 -393.839954) (xy 314.31154 -393.817296) (xy 314.29461 -393.768965) (xy 314.285959 -393.718492)
			(xy 314.285376 -393.692888) (xy 313.743636 -393.692888) (xy 314.05576 -394.232892) (xy 314.068498 -394.256207)
			(xy 314.086589 -394.306157) (xy 314.095804 -394.358476) (xy 314.0964 -394.385038) (xy 314.0964 -394.385292)
			(xy 314.095954 -394.409285) (xy 314.088449 -394.456681) (xy 314.073621 -394.50232) (xy 314.051836 -394.545076)
			(xy 314.02363 -394.583898) (xy 313.989698 -394.61783) (xy 313.950876 -394.646036) (xy 313.90812 -394.667821)
			(xy 313.862481 -394.682649) (xy 313.815085 -394.690154) (xy 313.791092 -394.6906) (xy 313.767518 -394.690213)
			(xy 313.720929 -394.68297) (xy 313.67601 -394.668643) (xy 313.633832 -394.647573) (xy 313.595399 -394.620263)
			(xy 313.561628 -394.587362) (xy 313.533322 -394.549656) (xy 313.521852 -394.529056) (xy 313.521344 -394.528294)
			(xy 313.12358 -393.839954) (xy 313.111644 -393.817296) (xy 313.094715 -393.768965) (xy 313.086063 -393.718492)
			(xy 313.08548 -393.692888) (xy 312.54374 -393.692888) (xy 312.855864 -394.232892) (xy 312.868602 -394.256207)
			(xy 312.886693 -394.306157) (xy 312.895908 -394.358476) (xy 312.896504 -394.385038) (xy 312.896504 -394.385292)
			(xy 312.896054 -394.409285) (xy 312.888549 -394.456681) (xy 312.873721 -394.502319) (xy 312.851936 -394.545075)
			(xy 312.823731 -394.583897) (xy 312.7898 -394.617829) (xy 312.750978 -394.646034) (xy 312.708222 -394.66782)
			(xy 312.662585 -394.682648) (xy 312.615189 -394.690154) (xy 312.591196 -394.6906) (xy 312.567622 -394.690209)
			(xy 312.521033 -394.682967) (xy 312.476115 -394.668641) (xy 312.433936 -394.647572) (xy 312.395503 -394.620262)
			(xy 312.361732 -394.587362) (xy 312.333426 -394.549656) (xy 312.321956 -394.529056) (xy 312.321448 -394.528294)
			(xy 311.923684 -393.839954) (xy 311.911748 -393.817296) (xy 311.894819 -393.768965) (xy 311.886167 -393.718492)
			(xy 311.885584 -393.692888) (xy 311.34359 -393.692888) (xy 311.655714 -394.232892) (xy 311.668537 -394.256226)
			(xy 311.686758 -394.306248) (xy 311.696019 -394.358673) (xy 311.696608 -394.385292) (xy 311.696131 -394.40927)
			(xy 311.688634 -394.456637) (xy 311.673823 -394.50225) (xy 311.652063 -394.544985) (xy 311.623888 -394.583793)
			(xy 311.589992 -394.617718) (xy 311.551209 -394.645926) (xy 311.508492 -394.667723) (xy 311.462892 -394.682573)
			(xy 311.415532 -394.69011) (xy 311.391554 -394.6906) (xy 311.391046 -394.6906) (xy 311.367473 -394.690169)
			(xy 311.320887 -394.682935) (xy 311.275969 -394.668615) (xy 311.233791 -394.647553) (xy 311.195357 -394.620249)
			(xy 311.161584 -394.587355) (xy 311.133277 -394.549654) (xy 311.121806 -394.529056) (xy 311.121298 -394.528294)
			(xy 310.723534 -393.839954) (xy 310.711674 -393.81727) (xy 310.694818 -393.76894) (xy 310.686238 -393.71848)
			(xy 310.685688 -393.692888) (xy 310.143694 -393.692888) (xy 310.455818 -394.232892) (xy 310.468641 -394.256226)
			(xy 310.486862 -394.306248) (xy 310.496123 -394.358673) (xy 310.496712 -394.385292) (xy 310.496231 -394.40927)
			(xy 310.488734 -394.456637) (xy 310.473924 -394.502249) (xy 310.452164 -394.544984) (xy 310.423989 -394.583791)
			(xy 310.390094 -394.617716) (xy 310.351311 -394.645924) (xy 310.308595 -394.667722) (xy 310.262996 -394.682572)
			(xy 310.215636 -394.69011) (xy 310.191658 -394.6906) (xy 310.19115 -394.6906) (xy 310.167577 -394.690166)
			(xy 310.120991 -394.682932) (xy 310.076073 -394.668613) (xy 310.033895 -394.647551) (xy 309.995461 -394.620248)
			(xy 309.961688 -394.587354) (xy 309.933381 -394.549653) (xy 309.92191 -394.529056) (xy 309.921402 -394.528294)
			(xy 309.523638 -393.839954) (xy 309.511778 -393.817269) (xy 309.494922 -393.76894) (xy 309.486342 -393.71848)
			(xy 309.485792 -393.692888) (xy 308.943544 -393.692888) (xy 309.255668 -394.232892) (xy 309.268406 -394.256207)
			(xy 309.286497 -394.306157) (xy 309.295712 -394.358476) (xy 309.296308 -394.385038) (xy 309.296308 -394.385292)
			(xy 309.295854 -394.409285) (xy 309.288349 -394.45668) (xy 309.273521 -394.502318) (xy 309.251737 -394.545074)
			(xy 309.223532 -394.583896) (xy 309.189602 -394.617827) (xy 309.150781 -394.646033) (xy 309.108025 -394.667818)
			(xy 309.062388 -394.682647) (xy 309.014993 -394.690154) (xy 308.991 -394.6906) (xy 308.967426 -394.690206)
			(xy 308.920838 -394.682965) (xy 308.875919 -394.668639) (xy 308.833741 -394.64757) (xy 308.795308 -394.620261)
			(xy 308.761536 -394.587361) (xy 308.73323 -394.549656) (xy 308.72176 -394.529056) (xy 308.721252 -394.528294)
			(xy 308.323488 -393.839954) (xy 308.311553 -393.817296) (xy 308.294623 -393.768965) (xy 308.285971 -393.718491)
			(xy 308.285388 -393.692888) (xy 307.743648 -393.692888) (xy 308.055772 -394.232892) (xy 308.068511 -394.256207)
			(xy 308.086601 -394.306157) (xy 308.095816 -394.358476) (xy 308.096412 -394.385038) (xy 308.096412 -394.385292)
			(xy 308.095954 -394.409285) (xy 308.088449 -394.45668) (xy 308.073622 -394.502317) (xy 308.051838 -394.545073)
			(xy 308.023634 -394.583894) (xy 307.989703 -394.617826) (xy 307.950883 -394.646032) (xy 307.908128 -394.667817)
			(xy 307.862491 -394.682646) (xy 307.815097 -394.690154) (xy 307.791104 -394.6906) (xy 307.76753 -394.690203)
			(xy 307.720942 -394.682962) (xy 307.676023 -394.668637) (xy 307.633845 -394.647569) (xy 307.595412 -394.62026)
			(xy 307.56164 -394.587361) (xy 307.533335 -394.549656) (xy 307.521864 -394.529056) (xy 307.521356 -394.528294)
			(xy 307.123592 -393.839954) (xy 307.111657 -393.817295) (xy 307.094727 -393.768965) (xy 307.086075 -393.718491)
			(xy 307.085492 -393.692888) (xy 306.543752 -393.692888) (xy 306.855876 -394.232892) (xy 306.868615 -394.256207)
			(xy 306.886705 -394.306157) (xy 306.89592 -394.358476) (xy 306.896516 -394.385038) (xy 306.896516 -394.385292)
			(xy 306.89603 -394.409283) (xy 306.888525 -394.456673) (xy 306.8737 -394.502306) (xy 306.851918 -394.545059)
			(xy 306.823716 -394.583877) (xy 306.789789 -394.617806) (xy 306.750972 -394.646009) (xy 306.708221 -394.667793)
			(xy 306.662589 -394.682622) (xy 306.615199 -394.690129) (xy 306.591208 -394.6906) (xy 306.567634 -394.6902)
			(xy 306.521046 -394.68296) (xy 306.476128 -394.668635) (xy 306.433949 -394.647567) (xy 306.395516 -394.620259)
			(xy 306.361744 -394.58736) (xy 306.333439 -394.549655) (xy 306.321968 -394.529056) (xy 306.32146 -394.528294)
			(xy 305.923696 -393.839954) (xy 305.911761 -393.817295) (xy 305.894831 -393.768965) (xy 305.886179 -393.718491)
			(xy 305.885596 -393.692888) (xy 305.343602 -393.692888) (xy 305.655726 -394.232892) (xy 305.66855 -394.256225)
			(xy 305.686771 -394.306247) (xy 305.696031 -394.358673) (xy 305.69662 -394.385292) (xy 305.696131 -394.40927)
			(xy 305.688635 -394.456636) (xy 305.673824 -394.502247) (xy 305.652065 -394.544982) (xy 305.623892 -394.583789)
			(xy 305.589997 -394.617713) (xy 305.551216 -394.645922) (xy 305.5085 -394.667719) (xy 305.462902 -394.68257)
			(xy 305.415543 -394.69011) (xy 305.391566 -394.6906) (xy 305.391058 -394.6906) (xy 305.367486 -394.690159)
			(xy 305.3209 -394.682927) (xy 305.275982 -394.668609) (xy 305.233804 -394.647548) (xy 305.19537 -394.620246)
			(xy 305.161597 -394.587353) (xy 305.13329 -394.549653) (xy 305.121818 -394.529056) (xy 305.12131 -394.528294)
			(xy 304.723546 -393.839954) (xy 304.711686 -393.817269) (xy 304.69483 -393.76894) (xy 304.68625 -393.71848)
			(xy 304.6857 -393.692888) (xy 304.143706 -393.692888) (xy 304.45583 -394.232892) (xy 304.468654 -394.256225)
			(xy 304.486875 -394.306247) (xy 304.496135 -394.358673) (xy 304.496724 -394.385292) (xy 304.496231 -394.40927)
			(xy 304.488735 -394.456635) (xy 304.473925 -394.502246) (xy 304.452166 -394.54498) (xy 304.423993 -394.583787)
			(xy 304.390099 -394.617712) (xy 304.351318 -394.64592) (xy 304.308603 -394.667718) (xy 304.263006 -394.68257)
			(xy 304.215647 -394.690109) (xy 304.19167 -394.6906) (xy 304.191162 -394.6906) (xy 304.16759 -394.690156)
			(xy 304.121004 -394.682924) (xy 304.076086 -394.668607) (xy 304.033908 -394.647547) (xy 303.995474 -394.620245)
			(xy 303.961701 -394.587352) (xy 303.933394 -394.549653) (xy 303.921922 -394.529056) (xy 303.921414 -394.528294)
			(xy 303.52365 -393.839954) (xy 303.511791 -393.817269) (xy 303.494934 -393.76894) (xy 303.486354 -393.71848)
			(xy 303.485804 -393.692888) (xy 280.345134 -393.692888) (xy 280.093674 -393.944348) (xy 280.08686 -393.951769)
			(xy 280.079126 -393.970352) (xy 280.078688 -393.980416) (xy 280.079196 -394.062966) (xy 280.08707 -394.081508)
			(xy 280.094436 -394.08862) (xy 280.100532 -394.094716) (xy 280.483818 -394.478002) (xy 280.510712 -394.505555)
			(xy 280.558798 -394.565692) (xy 280.599841 -394.630839) (xy 280.633323 -394.700176) (xy 280.658823 -394.772829)
			(xy 280.67602 -394.847882) (xy 280.684696 -394.924389) (xy 280.68524 -394.962888) (xy 280.68524 -396.171674)
			(xy 296.901108 -396.171674) (xy 296.901108 -395.308074) (xy 296.901594 -395.280823) (xy 296.90935 -395.226875)
			(xy 296.924705 -395.17458) (xy 296.947347 -395.125003) (xy 296.976813 -395.079153) (xy 297.012504 -395.037962)
			(xy 297.053695 -395.002271) (xy 297.099545 -394.972805) (xy 297.149122 -394.950163) (xy 297.201417 -394.934808)
			(xy 297.255365 -394.927052) (xy 297.309867 -394.927052) (xy 297.363815 -394.934808) (xy 297.41611 -394.950163)
			(xy 297.465687 -394.972805) (xy 297.511537 -395.002271) (xy 297.552728 -395.037962) (xy 297.588419 -395.079153)
			(xy 297.617885 -395.125003) (xy 297.640527 -395.17458) (xy 297.655882 -395.226875) (xy 297.663638 -395.280823)
			(xy 297.664124 -395.308074) (xy 297.664124 -396.171674) (xy 329.428856 -396.171674) (xy 329.428856 -395.308074)
			(xy 329.429342 -395.280823) (xy 329.437098 -395.226875) (xy 329.452453 -395.17458) (xy 329.475095 -395.125003)
			(xy 329.504561 -395.079153) (xy 329.540252 -395.037962) (xy 329.581443 -395.002271) (xy 329.627293 -394.972805)
			(xy 329.67687 -394.950163) (xy 329.729165 -394.934808) (xy 329.783113 -394.927052) (xy 329.837615 -394.927052)
			(xy 329.891563 -394.934808) (xy 329.943858 -394.950163) (xy 329.993435 -394.972805) (xy 330.039285 -395.002271)
			(xy 330.080476 -395.037962) (xy 330.116167 -395.079153) (xy 330.145633 -395.125003) (xy 330.168275 -395.17458)
			(xy 330.18363 -395.226875) (xy 330.191386 -395.280823) (xy 330.191872 -395.308074) (xy 330.191872 -396.171674)
			(xy 364.001304 -396.171674) (xy 364.001304 -395.308074) (xy 364.00179 -395.280823) (xy 364.009546 -395.226875)
			(xy 364.024901 -395.17458) (xy 364.047543 -395.125003) (xy 364.077009 -395.079153) (xy 364.1127 -395.037962)
			(xy 364.153891 -395.002271) (xy 364.199741 -394.972805) (xy 364.249318 -394.950163) (xy 364.301613 -394.934808)
			(xy 364.355561 -394.927052) (xy 364.410063 -394.927052) (xy 364.464011 -394.934808) (xy 364.516306 -394.950163)
			(xy 364.565883 -394.972805) (xy 364.611733 -395.002271) (xy 364.652924 -395.037962) (xy 364.688615 -395.079153)
			(xy 364.718081 -395.125003) (xy 364.740723 -395.17458) (xy 364.756078 -395.226875) (xy 364.763834 -395.280823)
			(xy 364.76432 -395.308074) (xy 364.76432 -396.171674) (xy 396.529052 -396.171674) (xy 396.529052 -395.308074)
			(xy 396.529538 -395.280823) (xy 396.537294 -395.226875) (xy 396.552649 -395.17458) (xy 396.575291 -395.125003)
			(xy 396.604757 -395.079153) (xy 396.640448 -395.037962) (xy 396.681639 -395.002271) (xy 396.727489 -394.972805)
			(xy 396.777066 -394.950163) (xy 396.829361 -394.934808) (xy 396.883309 -394.927052) (xy 396.937811 -394.927052)
			(xy 396.991759 -394.934808) (xy 397.044054 -394.950163) (xy 397.093631 -394.972805) (xy 397.139481 -395.002271)
			(xy 397.180672 -395.037962) (xy 397.216363 -395.079153) (xy 397.245829 -395.125003) (xy 397.268471 -395.17458)
			(xy 397.283826 -395.226875) (xy 397.291582 -395.280823) (xy 397.292068 -395.308074) (xy 397.292068 -396.171674)
			(xy 397.291582 -396.198925) (xy 397.283826 -396.252873) (xy 397.268471 -396.305168) (xy 397.245829 -396.354745)
			(xy 397.216363 -396.400595) (xy 397.180672 -396.441786) (xy 397.139481 -396.477477) (xy 397.093631 -396.506943)
			(xy 397.044054 -396.529585) (xy 396.991759 -396.54494) (xy 396.937811 -396.552696) (xy 396.883309 -396.552696)
			(xy 396.829361 -396.54494) (xy 396.777066 -396.529585) (xy 396.727489 -396.506943) (xy 396.681639 -396.477477)
			(xy 396.640448 -396.441786) (xy 396.604757 -396.400595) (xy 396.575291 -396.354745) (xy 396.552649 -396.305168)
			(xy 396.537294 -396.252873) (xy 396.529538 -396.198925) (xy 396.529052 -396.171674) (xy 364.76432 -396.171674)
			(xy 364.763834 -396.198925) (xy 364.756078 -396.252873) (xy 364.740723 -396.305168) (xy 364.718081 -396.354745)
			(xy 364.688615 -396.400595) (xy 364.652924 -396.441786) (xy 364.611733 -396.477477) (xy 364.565883 -396.506943)
			(xy 364.516306 -396.529585) (xy 364.464011 -396.54494) (xy 364.410063 -396.552696) (xy 364.355561 -396.552696)
			(xy 364.301613 -396.54494) (xy 364.249318 -396.529585) (xy 364.199741 -396.506943) (xy 364.153891 -396.477477)
			(xy 364.1127 -396.441786) (xy 364.077009 -396.400595) (xy 364.047543 -396.354745) (xy 364.024901 -396.305168)
			(xy 364.009546 -396.252873) (xy 364.00179 -396.198925) (xy 364.001304 -396.171674) (xy 330.191872 -396.171674)
			(xy 330.191386 -396.198925) (xy 330.18363 -396.252873) (xy 330.168275 -396.305168) (xy 330.145633 -396.354745)
			(xy 330.116167 -396.400595) (xy 330.080476 -396.441786) (xy 330.039285 -396.477477) (xy 329.993435 -396.506943)
			(xy 329.943858 -396.529585) (xy 329.891563 -396.54494) (xy 329.837615 -396.552696) (xy 329.783113 -396.552696)
			(xy 329.729165 -396.54494) (xy 329.67687 -396.529585) (xy 329.627293 -396.506943) (xy 329.581443 -396.477477)
			(xy 329.540252 -396.441786) (xy 329.504561 -396.400595) (xy 329.475095 -396.354745) (xy 329.452453 -396.305168)
			(xy 329.437098 -396.252873) (xy 329.429342 -396.198925) (xy 329.428856 -396.171674) (xy 297.664124 -396.171674)
			(xy 297.663638 -396.198925) (xy 297.655882 -396.252873) (xy 297.640527 -396.305168) (xy 297.617885 -396.354745)
			(xy 297.588419 -396.400595) (xy 297.552728 -396.441786) (xy 297.511537 -396.477477) (xy 297.465687 -396.506943)
			(xy 297.41611 -396.529585) (xy 297.363815 -396.54494) (xy 297.309867 -396.552696) (xy 297.255365 -396.552696)
			(xy 297.201417 -396.54494) (xy 297.149122 -396.529585) (xy 297.099545 -396.506943) (xy 297.053695 -396.477477)
			(xy 297.012504 -396.441786) (xy 296.976813 -396.400595) (xy 296.947347 -396.354745) (xy 296.924705 -396.305168)
			(xy 296.90935 -396.252873) (xy 296.901594 -396.198925) (xy 296.901108 -396.171674) (xy 280.68524 -396.171674)
			(xy 280.68524 -397.15694) (xy 303.485804 -397.15694) (xy 303.485804 -397.156432) (xy 303.486268 -397.132439)
			(xy 303.49377 -397.085044) (xy 303.508595 -397.039405) (xy 303.530377 -396.996648) (xy 303.558581 -396.957826)
			(xy 303.592511 -396.923894) (xy 303.631331 -396.895688) (xy 303.674087 -396.873903) (xy 303.719724 -396.859075)
			(xy 303.767119 -396.851569) (xy 303.791112 -396.851124) (xy 303.815047 -396.851594) (xy 303.862333 -396.859047)
			(xy 303.907877 -396.873786) (xy 303.950565 -396.895448) (xy 303.989351 -396.923504) (xy 304.023286 -396.957267)
			(xy 304.051539 -396.99591) (xy 304.062892 -397.016986) (xy 304.0634 -397.018002) (xy 304.143706 -397.15694)
			(xy 304.6857 -397.15694) (xy 304.6857 -397.156432) (xy 304.686168 -397.132439) (xy 304.69367 -397.085044)
			(xy 304.708495 -397.039406) (xy 304.730277 -396.99665) (xy 304.75848 -396.957827) (xy 304.792409 -396.923895)
			(xy 304.831229 -396.895689) (xy 304.873984 -396.873904) (xy 304.919621 -396.859076) (xy 304.967015 -396.85157)
			(xy 304.991008 -396.851124) (xy 305.014943 -396.851597) (xy 305.062229 -396.85905) (xy 305.107773 -396.873788)
			(xy 305.150461 -396.89545) (xy 305.189247 -396.923505) (xy 305.223182 -396.957268) (xy 305.251435 -396.99591)
			(xy 305.262788 -397.016986) (xy 305.263296 -397.018002) (xy 305.343602 -397.15694) (xy 305.885596 -397.15694)
			(xy 305.885596 -397.156432) (xy 305.886068 -397.13244) (xy 305.89357 -397.085045) (xy 305.908394 -397.039407)
			(xy 305.930176 -396.996651) (xy 305.958378 -396.957829) (xy 305.992307 -396.923897) (xy 306.031127 -396.895691)
			(xy 306.073881 -396.873905) (xy 306.119517 -396.859076) (xy 306.166912 -396.85157) (xy 306.190904 -396.851124)
			(xy 306.214839 -396.8516) (xy 306.262124 -396.859053) (xy 306.307668 -396.87379) (xy 306.350356 -396.895451)
			(xy 306.389142 -396.923506) (xy 306.423077 -396.957268) (xy 306.451331 -396.99591) (xy 306.462684 -397.016986)
			(xy 306.463192 -397.018002) (xy 306.543498 -397.15694) (xy 307.085492 -397.15694) (xy 307.085492 -397.156432)
			(xy 307.085991 -397.132454) (xy 307.093484 -397.085088) (xy 307.108292 -397.039476) (xy 307.130049 -396.996741)
			(xy 307.158222 -396.957933) (xy 307.192115 -396.924008) (xy 307.230897 -396.895799) (xy 307.273612 -396.874002)
			(xy 307.31921 -396.859151) (xy 307.366569 -396.851614) (xy 307.390546 -396.851124) (xy 307.391054 -396.851124)
			(xy 307.41499 -396.85156) (xy 307.462278 -396.85902) (xy 307.507823 -396.873764) (xy 307.550511 -396.895432)
			(xy 307.589296 -396.923493) (xy 307.62323 -396.957261) (xy 307.651481 -396.995908) (xy 307.662834 -397.016986)
			(xy 307.663342 -397.018002) (xy 307.743648 -397.15694) (xy 308.285388 -397.15694) (xy 308.285388 -397.156432)
			(xy 308.285891 -397.132455) (xy 308.293384 -397.085089) (xy 308.308192 -397.039477) (xy 308.329949 -396.996742)
			(xy 308.35812 -396.957934) (xy 308.392013 -396.924009) (xy 308.430794 -396.895801) (xy 308.473509 -396.874003)
			(xy 308.519106 -396.859152) (xy 308.566465 -396.851614) (xy 308.590442 -396.851124) (xy 308.59095 -396.851124)
			(xy 308.614886 -396.851563) (xy 308.662173 -396.859022) (xy 308.707718 -396.873766) (xy 308.750406 -396.895434)
			(xy 308.789192 -396.923494) (xy 308.823126 -396.957262) (xy 308.851377 -396.995908) (xy 308.86273 -397.016986)
			(xy 308.863238 -397.018002) (xy 308.943544 -397.15694) (xy 309.485792 -397.15694) (xy 309.485792 -397.156432)
			(xy 309.486268 -397.13244) (xy 309.49377 -397.085045) (xy 309.508594 -397.039408) (xy 309.530375 -396.996652)
			(xy 309.558577 -396.95783) (xy 309.592506 -396.923898) (xy 309.631325 -396.895692) (xy 309.674079 -396.873906)
			(xy 309.719714 -396.859077) (xy 309.767108 -396.85157) (xy 309.7911 -396.851124) (xy 309.815035 -396.851603)
			(xy 309.86232 -396.859055) (xy 309.907864 -396.873792) (xy 309.950552 -396.895453) (xy 309.989338 -396.923507)
			(xy 310.023273 -396.957269) (xy 310.051526 -396.995911) (xy 310.06288 -397.016986) (xy 310.063388 -397.018002)
			(xy 310.143694 -397.15694) (xy 310.685688 -397.15694) (xy 310.685688 -397.156432) (xy 310.686168 -397.13244)
			(xy 310.69367 -397.085046) (xy 310.708493 -397.039409) (xy 310.730274 -396.996653) (xy 310.758476 -396.957831)
			(xy 310.792404 -396.9239) (xy 310.831223 -396.895693) (xy 310.873976 -396.873907) (xy 310.919611 -396.859078)
			(xy 310.967004 -396.851571) (xy 310.990996 -396.851124) (xy 311.014933 -396.851526) (xy 311.062223 -396.858992)
			(xy 311.107768 -396.873742) (xy 311.150456 -396.895416) (xy 311.189241 -396.923483) (xy 311.223174 -396.957255)
			(xy 311.251424 -396.995906) (xy 311.262776 -397.016986) (xy 311.263284 -397.018002) (xy 311.34359 -397.15694)
			(xy 311.885584 -397.15694) (xy 311.885584 -397.156432) (xy 311.886068 -397.13244) (xy 311.893569 -397.085046)
			(xy 311.908393 -397.03941) (xy 311.930174 -396.996654) (xy 311.958375 -396.957833) (xy 311.992302 -396.923901)
			(xy 312.03112 -396.895695) (xy 312.073873 -396.873908) (xy 312.119508 -396.859079) (xy 312.1669 -396.851571)
			(xy 312.190892 -396.851124) (xy 312.214829 -396.851529) (xy 312.262118 -396.858995) (xy 312.307664 -396.873745)
			(xy 312.350352 -396.895418) (xy 312.389137 -396.923484) (xy 312.42307 -396.957256) (xy 312.45132 -396.995906)
			(xy 312.462672 -397.016986) (xy 312.46318 -397.018002) (xy 312.543486 -397.15694) (xy 313.08548 -397.15694)
			(xy 313.08548 -397.156432) (xy 313.085991 -397.132455) (xy 313.093484 -397.08509) (xy 313.108291 -397.039479)
			(xy 313.130047 -396.996744) (xy 313.158218 -396.957937) (xy 313.19211 -396.924012) (xy 313.23089 -396.895803)
			(xy 313.273603 -396.874005) (xy 313.3192 -396.859154) (xy 313.366557 -396.851614) (xy 313.390534 -396.851124)
			(xy 313.391042 -396.851124) (xy 313.414978 -396.851569) (xy 313.462265 -396.859028) (xy 313.50781 -396.87377)
			(xy 313.550497 -396.895437) (xy 313.589283 -396.923496) (xy 313.623217 -396.957263) (xy 313.651469 -396.995909)
			(xy 313.662822 -397.016986) (xy 313.66333 -397.018002) (xy 313.743636 -397.15694) (xy 314.285376 -397.15694)
			(xy 314.285376 -397.156432) (xy 314.285891 -397.132455) (xy 314.293384 -397.08509) (xy 314.308191 -397.03948)
			(xy 314.329947 -396.996746) (xy 314.358117 -396.957938) (xy 314.392008 -396.924013) (xy 314.430788 -396.895805)
			(xy 314.473501 -396.874006) (xy 314.519096 -396.859155) (xy 314.566454 -396.851615) (xy 314.59043 -396.851124)
			(xy 314.590938 -396.851124) (xy 314.614874 -396.851573) (xy 314.662161 -396.85903) (xy 314.707705 -396.873772)
			(xy 314.750393 -396.895438) (xy 314.789179 -396.923498) (xy 314.823113 -396.957263) (xy 314.851365 -396.995909)
			(xy 314.862718 -397.016986) (xy 314.863226 -397.018002) (xy 314.943532 -397.15694) (xy 315.48578 -397.15694)
			(xy 315.48578 -397.156432) (xy 315.486268 -397.13244) (xy 315.493769 -397.085047) (xy 315.508593 -397.039411)
			(xy 315.530373 -396.996656) (xy 315.558574 -396.957834) (xy 315.592501 -396.923902) (xy 315.631318 -396.895696)
			(xy 315.67407 -396.87391) (xy 315.719704 -396.85908) (xy 315.767096 -396.851571) (xy 315.791088 -396.851124)
			(xy 315.815025 -396.851532) (xy 315.862314 -396.858997) (xy 315.90786 -396.873747) (xy 315.950547 -396.895419)
			(xy 315.989333 -396.923485) (xy 316.023266 -396.957256) (xy 316.051516 -396.995907) (xy 316.062868 -397.016986)
			(xy 316.063376 -397.018002) (xy 316.143682 -397.15694) (xy 316.685676 -397.15694) (xy 316.685676 -397.156432)
			(xy 316.686168 -397.132441) (xy 316.693669 -397.085048) (xy 316.708492 -397.039412) (xy 316.730272 -396.996657)
			(xy 316.758473 -396.957836) (xy 316.792399 -396.923904) (xy 316.831216 -396.895697) (xy 316.873967 -396.873911)
			(xy 316.919601 -396.85908) (xy 316.966993 -396.851571) (xy 316.990984 -396.851124) (xy 317.014921 -396.851535)
			(xy 317.06221 -396.859) (xy 317.107755 -396.873749) (xy 317.150443 -396.895421) (xy 317.189228 -396.923486)
			(xy 317.223161 -396.957257) (xy 317.251412 -396.995907) (xy 317.262764 -397.016986) (xy 317.263272 -397.018002)
			(xy 317.343578 -397.15694) (xy 317.885572 -397.15694) (xy 317.885572 -397.156432) (xy 317.886068 -397.132441)
			(xy 317.893569 -397.085048) (xy 317.908392 -397.039413) (xy 317.930172 -396.996658) (xy 317.958371 -396.957837)
			(xy 317.992297 -396.923905) (xy 318.031114 -396.895699) (xy 318.073865 -396.873912) (xy 318.119498 -396.859081)
			(xy 318.166889 -396.851572) (xy 318.19088 -396.851124) (xy 318.214817 -396.851539) (xy 318.262105 -396.859002)
			(xy 318.307651 -396.873751) (xy 318.350339 -396.895422) (xy 318.389124 -396.923487) (xy 318.423057 -396.957257)
			(xy 318.451308 -396.995907) (xy 318.46266 -397.016986) (xy 318.463168 -397.018002) (xy 318.543474 -397.15694)
			(xy 319.085468 -397.15694) (xy 319.085468 -397.156432) (xy 319.085991 -397.132456) (xy 319.093484 -397.085092)
			(xy 319.10829 -397.039482) (xy 319.130045 -396.996748) (xy 319.158215 -396.957941) (xy 319.192105 -396.924016)
			(xy 319.230883 -396.895807) (xy 319.273595 -396.874009) (xy 319.31919 -396.859156) (xy 319.366546 -396.851615)
			(xy 319.390522 -396.851124) (xy 319.39103 -396.851124) (xy 319.414965 -396.851579) (xy 319.462252 -396.859035)
			(xy 319.507797 -396.873776) (xy 319.550484 -396.895441) (xy 319.58927 -396.9235) (xy 319.623205 -396.957264)
			(xy 319.651457 -396.995909) (xy 319.66281 -397.016986) (xy 319.663318 -397.018002) (xy 319.743624 -397.15694)
			(xy 320.285364 -397.15694) (xy 320.285364 -397.156432) (xy 320.285891 -397.132456) (xy 320.293383 -397.085092)
			(xy 320.308189 -397.039483) (xy 320.329944 -396.996749) (xy 320.358113 -396.957943) (xy 320.392003 -396.924018)
			(xy 320.430781 -396.895809) (xy 320.473492 -396.87401) (xy 320.519086 -396.859157) (xy 320.566442 -396.851616)
			(xy 320.590418 -396.851124) (xy 320.590926 -396.851124) (xy 320.614861 -396.851582) (xy 320.662148 -396.859038)
			(xy 320.707692 -396.873778) (xy 320.75038 -396.895443) (xy 320.789166 -396.923501) (xy 320.823101 -396.957265)
			(xy 320.851353 -396.995909) (xy 320.862706 -397.016986) (xy 320.863214 -397.018002) (xy 320.94352 -397.15694)
			(xy 321.485768 -397.15694) (xy 321.485768 -397.156432) (xy 321.486268 -397.132441) (xy 321.493769 -397.085049)
			(xy 321.508592 -397.039414) (xy 321.530371 -396.996659) (xy 321.55857 -396.957838) (xy 321.592496 -396.923907)
			(xy 321.631311 -396.8957) (xy 321.674062 -396.873913) (xy 321.719694 -396.859082) (xy 321.767085 -396.851572)
			(xy 321.791076 -396.851124) (xy 321.815013 -396.851542) (xy 321.862301 -396.859005) (xy 321.907847 -396.873753)
			(xy 321.950534 -396.895424) (xy 321.98932 -396.923488) (xy 322.023253 -396.957258) (xy 322.051504 -396.995907)
			(xy 322.062856 -397.016986) (xy 322.063364 -397.018002) (xy 322.14367 -397.15694) (xy 336.013552 -397.15694)
			(xy 336.013552 -397.156432) (xy 336.014092 -397.132444) (xy 336.021592 -397.085057) (xy 336.036413 -397.039427)
			(xy 336.058189 -396.996677) (xy 336.086384 -396.95786) (xy 336.120305 -396.923931) (xy 336.159115 -396.895726)
			(xy 336.20186 -396.87394) (xy 336.247487 -396.859109) (xy 336.294872 -396.851598) (xy 336.31886 -396.851124)
			(xy 336.342796 -396.851555) (xy 336.390084 -396.859016) (xy 336.435629 -396.873761) (xy 336.478317 -396.89543)
			(xy 336.517103 -396.923492) (xy 336.551036 -396.95726) (xy 336.579288 -396.995908) (xy 336.59064 -397.016986)
			(xy 336.591148 -397.018002) (xy 336.671454 -397.15694) (xy 337.213448 -397.15694) (xy 337.213448 -397.156432)
			(xy 337.213992 -397.132444) (xy 337.221492 -397.085057) (xy 337.236312 -397.039428) (xy 337.258088 -396.996678)
			(xy 337.286283 -396.957861) (xy 337.320203 -396.923933) (xy 337.359013 -396.895728) (xy 337.401757 -396.873941)
			(xy 337.447383 -396.85911) (xy 337.494768 -396.851598) (xy 337.518756 -396.851124) (xy 337.542692 -396.851558)
			(xy 337.58998 -396.859018) (xy 337.635525 -396.873763) (xy 337.678213 -396.895431) (xy 337.716998 -396.923493)
			(xy 337.750932 -396.957261) (xy 337.779183 -396.995908) (xy 337.790536 -397.016986) (xy 337.791044 -397.018002)
			(xy 337.87135 -397.15694) (xy 338.413344 -397.15694) (xy 338.413344 -397.156432) (xy 338.413892 -397.132444)
			(xy 338.421392 -397.085058) (xy 338.436212 -397.039429) (xy 338.457987 -396.996679) (xy 338.486182 -396.957862)
			(xy 338.520101 -396.923934) (xy 338.558911 -396.895729) (xy 338.601655 -396.873943) (xy 338.64728 -396.859111)
			(xy 338.694664 -396.851598) (xy 338.718652 -396.851124) (xy 338.742588 -396.851561) (xy 338.789876 -396.859021)
			(xy 338.835421 -396.873765) (xy 338.878108 -396.895433) (xy 338.916894 -396.923494) (xy 338.950828 -396.957261)
			(xy 338.979079 -396.995908) (xy 338.990432 -397.016986) (xy 338.99094 -397.018002) (xy 339.071246 -397.15694)
			(xy 339.61324 -397.15694) (xy 339.61324 -397.156432) (xy 339.613691 -397.132452) (xy 339.621186 -397.085081)
			(xy 339.635997 -397.039465) (xy 339.657758 -396.996726) (xy 339.685936 -396.957917) (xy 339.719835 -396.92399)
			(xy 339.758623 -396.895783) (xy 339.801345 -396.873988) (xy 339.846949 -396.859142) (xy 339.894314 -396.85161)
			(xy 339.918294 -396.851124) (xy 339.918802 -396.851124) (xy 339.942737 -396.851602) (xy 339.990022 -396.859054)
			(xy 340.035566 -396.873791) (xy 340.078254 -396.895452) (xy 340.11704 -396.923507) (xy 340.150975 -396.957268)
			(xy 340.179229 -396.99591) (xy 340.190582 -397.016986) (xy 340.19109 -397.018002) (xy 340.271396 -397.15694)
			(xy 340.813136 -397.15694) (xy 340.813136 -397.156432) (xy 340.813591 -397.132452) (xy 340.821086 -397.085082)
			(xy 340.835896 -397.039466) (xy 340.857658 -396.996728) (xy 340.885834 -396.957918) (xy 340.919734 -396.923992)
			(xy 340.958521 -396.895784) (xy 341.001242 -396.873989) (xy 341.046846 -396.859143) (xy 341.09421 -396.85161)
			(xy 341.11819 -396.851124) (xy 341.118698 -396.851124) (xy 341.142635 -396.851524) (xy 341.189925 -396.858991)
			(xy 341.235471 -396.873741) (xy 341.278158 -396.895415) (xy 341.316943 -396.923482) (xy 341.350876 -396.957255)
			(xy 341.379126 -396.995906) (xy 341.390478 -397.016986) (xy 341.390986 -397.018002) (xy 341.471292 -397.15694)
			(xy 342.01354 -397.15694) (xy 342.01354 -397.156432) (xy 342.013968 -397.132437) (xy 342.021471 -397.085038)
			(xy 342.036298 -397.039397) (xy 342.058084 -396.996638) (xy 342.086291 -396.957814) (xy 342.120226 -396.923881)
			(xy 342.159051 -396.895676) (xy 342.201812 -396.873892) (xy 342.247454 -396.859068) (xy 342.294853 -396.851567)
			(xy 342.318848 -396.851124) (xy 342.342784 -396.851565) (xy 342.390071 -396.859024) (xy 342.435616 -396.873767)
			(xy 342.478304 -396.895434) (xy 342.51709 -396.923495) (xy 342.551024 -396.957262) (xy 342.579275 -396.995908)
			(xy 342.590628 -397.016986) (xy 342.591136 -397.018002) (xy 342.671442 -397.15694) (xy 343.213436 -397.15694)
			(xy 343.213436 -397.156432) (xy 343.213868 -397.132438) (xy 343.221371 -397.085039) (xy 343.236198 -397.039398)
			(xy 343.257983 -396.996639) (xy 343.28619 -396.957815) (xy 343.320124 -396.923882) (xy 343.358949 -396.895677)
			(xy 343.401709 -396.873893) (xy 343.447351 -396.859068) (xy 343.49475 -396.851567) (xy 343.518744 -396.851124)
			(xy 343.54268 -396.851568) (xy 343.589967 -396.859026) (xy 343.635512 -396.873769) (xy 343.6782 -396.895436)
			(xy 343.716985 -396.923496) (xy 343.750919 -396.957262) (xy 343.779171 -396.995909) (xy 343.790524 -397.016986)
			(xy 343.791032 -397.018002) (xy 343.871338 -397.15694) (xy 344.413332 -397.15694) (xy 344.413332 -397.156432)
			(xy 344.413768 -397.132438) (xy 344.421271 -397.085039) (xy 344.436098 -397.039399) (xy 344.457883 -396.99664)
			(xy 344.486089 -396.957816) (xy 344.520022 -396.923884) (xy 344.558847 -396.895678) (xy 344.601606 -396.873895)
			(xy 344.647247 -396.859069) (xy 344.694646 -396.851567) (xy 344.71864 -396.851124) (xy 344.742576 -396.851571)
			(xy 344.789863 -396.859029) (xy 344.835408 -396.873771) (xy 344.878095 -396.895437) (xy 344.916881 -396.923497)
			(xy 344.950815 -396.957263) (xy 344.979067 -396.995909) (xy 344.99042 -397.016986) (xy 344.990928 -397.018002)
			(xy 345.071234 -397.15694) (xy 345.613228 -397.15694) (xy 345.613228 -397.156432) (xy 345.613691 -397.132453)
			(xy 345.621186 -397.085083) (xy 345.635996 -397.039468) (xy 345.657756 -396.99673) (xy 345.685932 -396.957921)
			(xy 345.71983 -396.923995) (xy 345.758617 -396.895787) (xy 345.801337 -396.873991) (xy 345.846939 -396.859144)
			(xy 345.894303 -396.851611) (xy 345.918282 -396.851124) (xy 345.91879 -396.851124) (xy 345.942727 -396.85153)
			(xy 345.990016 -396.858996) (xy 346.035562 -396.873746) (xy 346.07825 -396.895419) (xy 346.117035 -396.923484)
			(xy 346.150968 -396.957256) (xy 346.179218 -396.995907) (xy 346.19057 -397.016986) (xy 346.191078 -397.018002)
			(xy 346.271384 -397.15694) (xy 346.813124 -397.15694) (xy 346.813124 -397.156432) (xy 346.813591 -397.132453)
			(xy 346.821086 -397.085083) (xy 346.835895 -397.039469) (xy 346.857655 -396.996731) (xy 346.885831 -396.957922)
			(xy 346.919729 -396.923996) (xy 346.958514 -396.895788) (xy 347.001234 -396.873993) (xy 347.046836 -396.859145)
			(xy 347.094199 -396.851611) (xy 347.118178 -396.851124) (xy 347.118686 -396.851124) (xy 347.142623 -396.851534)
			(xy 347.189912 -396.858998) (xy 347.235457 -396.873748) (xy 347.278145 -396.89542) (xy 347.31693 -396.923485)
			(xy 347.350864 -396.957256) (xy 347.379114 -396.995907) (xy 347.390466 -397.016986) (xy 347.390974 -397.018002)
			(xy 347.47128 -397.15694) (xy 348.013528 -397.15694) (xy 348.013528 -397.156432) (xy 348.013968 -397.132438)
			(xy 348.021471 -397.08504) (xy 348.036297 -397.0394) (xy 348.058082 -396.996641) (xy 348.086288 -396.957818)
			(xy 348.120221 -396.923885) (xy 348.159045 -396.89568) (xy 348.201804 -396.873896) (xy 348.247444 -396.85907)
			(xy 348.294842 -396.851568) (xy 348.318836 -396.851124) (xy 348.342772 -396.851574) (xy 348.390058 -396.859031)
			(xy 348.435603 -396.873773) (xy 348.478291 -396.895439) (xy 348.517077 -396.923498) (xy 348.551011 -396.957264)
			(xy 348.579263 -396.995909) (xy 348.590616 -397.016986) (xy 348.591124 -397.018002) (xy 348.67143 -397.15694)
			(xy 349.213424 -397.15694) (xy 349.213424 -397.156432) (xy 349.213868 -397.132438) (xy 349.221371 -397.085041)
			(xy 349.236197 -397.039401) (xy 349.257981 -396.996643) (xy 349.286187 -396.957819) (xy 349.320119 -396.923887)
			(xy 349.358943 -396.895681) (xy 349.401701 -396.873897) (xy 349.447341 -396.859071) (xy 349.494738 -396.851568)
			(xy 349.518732 -396.851124) (xy 349.542668 -396.851578) (xy 349.589954 -396.859034) (xy 349.635499 -396.873775)
			(xy 349.678187 -396.89544) (xy 349.716972 -396.923499) (xy 349.750907 -396.957264) (xy 349.779159 -396.995909)
			(xy 349.790512 -397.016986) (xy 349.79102 -397.018002) (xy 349.871326 -397.15694) (xy 350.41332 -397.15694)
			(xy 350.41332 -397.156432) (xy 350.413768 -397.132438) (xy 350.421271 -397.085041) (xy 350.436097 -397.039402)
			(xy 350.45788 -396.996644) (xy 350.486086 -396.95782) (xy 350.520017 -396.923888) (xy 350.55884 -396.895682)
			(xy 350.601598 -396.873898) (xy 350.647237 -396.859072) (xy 350.694634 -396.851568) (xy 350.718628 -396.851124)
			(xy 350.742563 -396.851581) (xy 350.78985 -396.859037) (xy 350.835395 -396.873777) (xy 350.878082 -396.895442)
			(xy 350.916868 -396.9235) (xy 350.950803 -396.957265) (xy 350.979055 -396.995909) (xy 350.990408 -397.016986)
			(xy 350.990916 -397.018002) (xy 351.071222 -397.15694) (xy 351.613216 -397.15694) (xy 351.613216 -397.156432)
			(xy 351.613691 -397.132453) (xy 351.621185 -397.085085) (xy 351.635994 -397.039471) (xy 351.657754 -396.996734)
			(xy 351.685929 -396.957925) (xy 351.719825 -396.923999) (xy 351.75861 -396.895791) (xy 351.801328 -396.873995)
			(xy 351.846929 -396.859147) (xy 351.894292 -396.851612) (xy 351.91827 -396.851124) (xy 351.918778 -396.851124)
			(xy 351.942715 -396.85154) (xy 351.990003 -396.859004) (xy 352.035549 -396.873752) (xy 352.078237 -396.895423)
			(xy 352.117022 -396.923487) (xy 352.150955 -396.957258) (xy 352.179206 -396.995907) (xy 352.190558 -397.016986)
			(xy 352.191066 -397.018002) (xy 352.271372 -397.15694) (xy 352.813112 -397.15694) (xy 352.813112 -397.156432)
			(xy 352.813591 -397.132453) (xy 352.821085 -397.085085) (xy 352.835894 -397.039472) (xy 352.857653 -396.996735)
			(xy 352.885827 -396.957926) (xy 352.919724 -396.924) (xy 352.958508 -396.895792) (xy 353.001225 -396.873996)
			(xy 353.046826 -396.859147) (xy 353.094188 -396.851612) (xy 353.118166 -396.851124) (xy 353.118674 -396.851124)
			(xy 353.142611 -396.851543) (xy 353.189899 -396.859006) (xy 353.235444 -396.873754) (xy 353.278132 -396.895425)
			(xy 353.316918 -396.923488) (xy 353.350851 -396.957258) (xy 353.379102 -396.995907) (xy 353.390454 -397.016986)
			(xy 353.390962 -397.018002) (xy 353.471268 -397.15694) (xy 354.013516 -397.15694) (xy 354.013516 -397.156432)
			(xy 354.013968 -397.132439) (xy 354.021471 -397.085042) (xy 354.036296 -397.039403) (xy 354.05808 -396.996645)
			(xy 354.086284 -396.957822) (xy 354.120216 -396.92389) (xy 354.159038 -396.895684) (xy 354.201795 -396.873899)
			(xy 354.247434 -396.859072) (xy 354.294831 -396.851568) (xy 354.318824 -396.851124) (xy 354.342759 -396.851584)
			(xy 354.390046 -396.859039) (xy 354.43559 -396.873779) (xy 354.478278 -396.895444) (xy 354.517064 -396.923501)
			(xy 354.550998 -396.957265) (xy 354.579251 -396.99591) (xy 354.590604 -397.016986) (xy 354.591112 -397.018002)
			(xy 354.671418 -397.15694) (xy 370.586 -397.15694) (xy 370.586 -397.156432) (xy 370.586468 -397.132439)
			(xy 370.59397 -397.085044) (xy 370.608795 -397.039406) (xy 370.630577 -396.99665) (xy 370.65878 -396.957827)
			(xy 370.692709 -396.923895) (xy 370.731529 -396.895689) (xy 370.774284 -396.873904) (xy 370.819921 -396.859076)
			(xy 370.867315 -396.85157) (xy 370.891308 -396.851124) (xy 370.915243 -396.851597) (xy 370.962529 -396.85905)
			(xy 371.008073 -396.873788) (xy 371.050761 -396.89545) (xy 371.089547 -396.923505) (xy 371.123482 -396.957268)
			(xy 371.151735 -396.99591) (xy 371.163088 -397.016986) (xy 371.163596 -397.018002) (xy 371.243902 -397.15694)
			(xy 371.785896 -397.15694) (xy 371.785896 -397.156432) (xy 371.786368 -397.13244) (xy 371.79387 -397.085045)
			(xy 371.808694 -397.039407) (xy 371.830476 -396.996651) (xy 371.858678 -396.957829) (xy 371.892607 -396.923897)
			(xy 371.931427 -396.895691) (xy 371.974181 -396.873905) (xy 372.019817 -396.859076) (xy 372.067212 -396.85157)
			(xy 372.091204 -396.851124) (xy 372.115139 -396.8516) (xy 372.162424 -396.859053) (xy 372.207968 -396.87379)
			(xy 372.250656 -396.895451) (xy 372.289442 -396.923506) (xy 372.323377 -396.957268) (xy 372.351631 -396.99591)
			(xy 372.362984 -397.016986) (xy 372.363492 -397.018002) (xy 372.443798 -397.15694) (xy 372.985792 -397.15694)
			(xy 372.985792 -397.156432) (xy 372.986268 -397.13244) (xy 372.99377 -397.085045) (xy 373.008594 -397.039408)
			(xy 373.030375 -396.996652) (xy 373.058577 -396.95783) (xy 373.092506 -396.923898) (xy 373.131325 -396.895692)
			(xy 373.174079 -396.873906) (xy 373.219714 -396.859077) (xy 373.267108 -396.85157) (xy 373.2911 -396.851124)
			(xy 373.315035 -396.851603) (xy 373.36232 -396.859055) (xy 373.407864 -396.873792) (xy 373.450552 -396.895453)
			(xy 373.489338 -396.923507) (xy 373.523273 -396.957269) (xy 373.551526 -396.995911) (xy 373.56288 -397.016986)
			(xy 373.563388 -397.018002) (xy 373.643694 -397.15694) (xy 374.185688 -397.15694) (xy 374.185688 -397.156432)
			(xy 374.186191 -397.132455) (xy 374.193684 -397.085089) (xy 374.208492 -397.039477) (xy 374.230249 -396.996742)
			(xy 374.25842 -396.957934) (xy 374.292313 -396.924009) (xy 374.331094 -396.895801) (xy 374.373809 -396.874003)
			(xy 374.419406 -396.859152) (xy 374.466765 -396.851614) (xy 374.490742 -396.851124) (xy 374.49125 -396.851124)
			(xy 374.515186 -396.851563) (xy 374.562473 -396.859022) (xy 374.608018 -396.873766) (xy 374.650706 -396.895434)
			(xy 374.689492 -396.923494) (xy 374.723426 -396.957262) (xy 374.751677 -396.995908) (xy 374.76303 -397.016986)
			(xy 374.763538 -397.018002) (xy 374.843844 -397.15694) (xy 375.385584 -397.15694) (xy 375.385584 -397.156432)
			(xy 375.386091 -397.132455) (xy 375.393584 -397.085089) (xy 375.408391 -397.039478) (xy 375.430148 -396.996743)
			(xy 375.458319 -396.957936) (xy 375.492212 -396.92401) (xy 375.530992 -396.895802) (xy 375.573706 -396.874004)
			(xy 375.619303 -396.859153) (xy 375.666661 -396.851614) (xy 375.690638 -396.851124) (xy 375.691146 -396.851124)
			(xy 375.715082 -396.851566) (xy 375.762369 -396.859025) (xy 375.807914 -396.873768) (xy 375.850602 -396.895435)
			(xy 375.889387 -396.923495) (xy 375.923322 -396.957262) (xy 375.951573 -396.995909) (xy 375.962926 -397.016986)
			(xy 375.963434 -397.018002) (xy 376.04374 -397.15694) (xy 376.585988 -397.15694) (xy 376.585988 -397.156432)
			(xy 376.586468 -397.13244) (xy 376.59397 -397.085046) (xy 376.608793 -397.039409) (xy 376.630574 -396.996653)
			(xy 376.658776 -396.957831) (xy 376.692704 -396.9239) (xy 376.731523 -396.895693) (xy 376.774276 -396.873907)
			(xy 376.819911 -396.859078) (xy 376.867304 -396.851571) (xy 376.891296 -396.851124) (xy 376.915233 -396.851526)
			(xy 376.962523 -396.858992) (xy 377.008068 -396.873742) (xy 377.050756 -396.895416) (xy 377.089541 -396.923483)
			(xy 377.123474 -396.957255) (xy 377.151724 -396.995906) (xy 377.163076 -397.016986) (xy 377.163584 -397.018002)
			(xy 377.24389 -397.15694) (xy 377.785884 -397.15694) (xy 377.785884 -397.156432) (xy 377.786368 -397.13244)
			(xy 377.793869 -397.085046) (xy 377.808693 -397.03941) (xy 377.830474 -396.996654) (xy 377.858675 -396.957833)
			(xy 377.892602 -396.923901) (xy 377.93142 -396.895695) (xy 377.974173 -396.873908) (xy 378.019808 -396.859079)
			(xy 378.0672 -396.851571) (xy 378.091192 -396.851124) (xy 378.115129 -396.851529) (xy 378.162418 -396.858995)
			(xy 378.207964 -396.873745) (xy 378.250652 -396.895418) (xy 378.289437 -396.923484) (xy 378.32337 -396.957256)
			(xy 378.35162 -396.995906) (xy 378.362972 -397.016986) (xy 378.36348 -397.018002) (xy 378.443786 -397.15694)
			(xy 378.98578 -397.15694) (xy 378.98578 -397.156432) (xy 378.986268 -397.13244) (xy 378.993769 -397.085047)
			(xy 379.008593 -397.039411) (xy 379.030373 -396.996656) (xy 379.058574 -396.957834) (xy 379.092501 -396.923902)
			(xy 379.131318 -396.895696) (xy 379.17407 -396.87391) (xy 379.219704 -396.85908) (xy 379.267096 -396.851571)
			(xy 379.291088 -396.851124) (xy 379.315025 -396.851532) (xy 379.362314 -396.858997) (xy 379.40786 -396.873747)
			(xy 379.450547 -396.895419) (xy 379.489333 -396.923485) (xy 379.523266 -396.957256) (xy 379.551516 -396.995907)
			(xy 379.562868 -397.016986) (xy 379.563376 -397.018002) (xy 379.643682 -397.15694) (xy 380.185676 -397.15694)
			(xy 380.185676 -397.156432) (xy 380.186191 -397.132455) (xy 380.193684 -397.08509) (xy 380.208491 -397.03948)
			(xy 380.230247 -396.996746) (xy 380.258417 -396.957938) (xy 380.292308 -396.924013) (xy 380.331088 -396.895805)
			(xy 380.373801 -396.874006) (xy 380.419396 -396.859155) (xy 380.466754 -396.851615) (xy 380.49073 -396.851124)
			(xy 380.491238 -396.851124) (xy 380.515174 -396.851573) (xy 380.562461 -396.85903) (xy 380.608005 -396.873772)
			(xy 380.650693 -396.895438) (xy 380.689479 -396.923498) (xy 380.723413 -396.957263) (xy 380.751665 -396.995909)
			(xy 380.763018 -397.016986) (xy 380.763526 -397.018002) (xy 380.843832 -397.15694) (xy 381.385572 -397.15694)
			(xy 381.385572 -397.156432) (xy 381.386091 -397.132455) (xy 381.393584 -397.085091) (xy 381.40839 -397.039481)
			(xy 381.430146 -396.996747) (xy 381.458316 -396.95794) (xy 381.492207 -396.924015) (xy 381.530985 -396.895806)
			(xy 381.573698 -396.874007) (xy 381.619293 -396.859155) (xy 381.66665 -396.851615) (xy 381.690626 -396.851124)
			(xy 381.691134 -396.851124) (xy 381.71507 -396.851576) (xy 381.762356 -396.859033) (xy 381.807901 -396.873774)
			(xy 381.850589 -396.89544) (xy 381.889375 -396.923499) (xy 381.923309 -396.957264) (xy 381.951561 -396.995909)
			(xy 381.962914 -397.016986) (xy 381.963422 -397.018002) (xy 382.043728 -397.15694) (xy 382.585976 -397.15694)
			(xy 382.585976 -397.156432) (xy 382.586468 -397.132441) (xy 382.593969 -397.085048) (xy 382.608792 -397.039412)
			(xy 382.630572 -396.996657) (xy 382.658773 -396.957836) (xy 382.692699 -396.923904) (xy 382.731516 -396.895697)
			(xy 382.774267 -396.873911) (xy 382.819901 -396.85908) (xy 382.867293 -396.851571) (xy 382.891284 -396.851124)
			(xy 382.915221 -396.851535) (xy 382.96251 -396.859) (xy 383.008055 -396.873749) (xy 383.050743 -396.895421)
			(xy 383.089528 -396.923486) (xy 383.123461 -396.957257) (xy 383.151712 -396.995907) (xy 383.163064 -397.016986)
			(xy 383.163572 -397.018002) (xy 383.243878 -397.15694) (xy 383.785872 -397.15694) (xy 383.785872 -397.156432)
			(xy 383.786368 -397.132441) (xy 383.793869 -397.085048) (xy 383.808692 -397.039413) (xy 383.830472 -396.996658)
			(xy 383.858671 -396.957837) (xy 383.892597 -396.923905) (xy 383.931414 -396.895699) (xy 383.974165 -396.873912)
			(xy 384.019798 -396.859081) (xy 384.067189 -396.851572) (xy 384.09118 -396.851124) (xy 384.115117 -396.851539)
			(xy 384.162405 -396.859002) (xy 384.207951 -396.873751) (xy 384.250639 -396.895422) (xy 384.289424 -396.923487)
			(xy 384.323357 -396.957257) (xy 384.351608 -396.995907) (xy 384.36296 -397.016986) (xy 384.363468 -397.018002)
			(xy 384.443774 -397.15694) (xy 384.985768 -397.15694) (xy 384.985768 -397.156432) (xy 384.986268 -397.132441)
			(xy 384.993769 -397.085049) (xy 385.008592 -397.039414) (xy 385.030371 -396.996659) (xy 385.05857 -396.957838)
			(xy 385.092496 -396.923907) (xy 385.131311 -396.8957) (xy 385.174062 -396.873913) (xy 385.219694 -396.859082)
			(xy 385.267085 -396.851572) (xy 385.291076 -396.851124) (xy 385.315013 -396.851542) (xy 385.362301 -396.859005)
			(xy 385.407847 -396.873753) (xy 385.450534 -396.895424) (xy 385.48932 -396.923488) (xy 385.523253 -396.957258)
			(xy 385.551504 -396.995907) (xy 385.562856 -397.016986) (xy 385.563364 -397.018002) (xy 385.64367 -397.15694)
			(xy 386.185664 -397.15694) (xy 386.185664 -397.156432) (xy 386.186191 -397.132456) (xy 386.193683 -397.085092)
			(xy 386.208489 -397.039483) (xy 386.230244 -396.996749) (xy 386.258413 -396.957943) (xy 386.292303 -396.924018)
			(xy 386.331081 -396.895809) (xy 386.373792 -396.87401) (xy 386.419386 -396.859157) (xy 386.466742 -396.851616)
			(xy 386.490718 -396.851124) (xy 386.491226 -396.851124) (xy 386.515161 -396.851582) (xy 386.562448 -396.859038)
			(xy 386.607992 -396.873778) (xy 386.65068 -396.895443) (xy 386.689466 -396.923501) (xy 386.723401 -396.957265)
			(xy 386.751653 -396.995909) (xy 386.763006 -397.016986) (xy 386.763514 -397.018002) (xy 386.84382 -397.15694)
			(xy 387.38556 -397.15694) (xy 387.38556 -397.156432) (xy 387.386091 -397.132456) (xy 387.393583 -397.085093)
			(xy 387.408389 -397.039484) (xy 387.430144 -396.99675) (xy 387.458312 -396.957944) (xy 387.492202 -396.924019)
			(xy 387.530979 -396.89581) (xy 387.573689 -396.874011) (xy 387.619283 -396.859158) (xy 387.666638 -396.851616)
			(xy 387.690614 -396.851124) (xy 387.691122 -396.851124) (xy 387.715057 -396.851586) (xy 387.762343 -396.859041)
			(xy 387.807888 -396.873781) (xy 387.850576 -396.895444) (xy 387.889362 -396.923502) (xy 387.923296 -396.957266)
			(xy 387.951549 -396.99591) (xy 387.962902 -397.016986) (xy 387.96341 -397.018002) (xy 388.043716 -397.15694)
			(xy 388.585964 -397.15694) (xy 388.585964 -397.156432) (xy 388.586468 -397.132441) (xy 388.593969 -397.085049)
			(xy 388.608791 -397.039415) (xy 388.63057 -396.99666) (xy 388.658769 -396.95784) (xy 388.692694 -396.923908)
			(xy 388.731509 -396.895701) (xy 388.774259 -396.873914) (xy 388.819891 -396.859083) (xy 388.867281 -396.851572)
			(xy 388.891272 -396.851124) (xy 388.915209 -396.851545) (xy 388.962497 -396.859008) (xy 389.008042 -396.873755)
			(xy 389.05073 -396.895425) (xy 389.089515 -396.923489) (xy 389.123449 -396.957258) (xy 389.1517 -396.995907)
			(xy 389.163052 -397.016986) (xy 389.16356 -397.018002) (xy 389.243866 -397.15694) (xy 403.113748 -397.15694)
			(xy 403.113748 -397.156432) (xy 403.114292 -397.132444) (xy 403.121792 -397.085057) (xy 403.136612 -397.039428)
			(xy 403.158388 -396.996678) (xy 403.186583 -396.957861) (xy 403.220503 -396.923933) (xy 403.259313 -396.895728)
			(xy 403.302057 -396.873941) (xy 403.347683 -396.85911) (xy 403.395068 -396.851598) (xy 403.419056 -396.851124)
			(xy 403.442992 -396.851558) (xy 403.49028 -396.859018) (xy 403.535825 -396.873763) (xy 403.578513 -396.895431)
			(xy 403.617298 -396.923493) (xy 403.651232 -396.957261) (xy 403.679483 -396.995908) (xy 403.690836 -397.016986)
			(xy 403.691344 -397.018002) (xy 403.77165 -397.15694) (xy 404.313644 -397.15694) (xy 404.313644 -397.156432)
			(xy 404.314192 -397.132444) (xy 404.321692 -397.085058) (xy 404.336512 -397.039429) (xy 404.358287 -396.996679)
			(xy 404.386482 -396.957862) (xy 404.420401 -396.923934) (xy 404.459211 -396.895729) (xy 404.501955 -396.873943)
			(xy 404.54758 -396.859111) (xy 404.594964 -396.851598) (xy 404.618952 -396.851124) (xy 404.642888 -396.851561)
			(xy 404.690176 -396.859021) (xy 404.735721 -396.873765) (xy 404.778408 -396.895433) (xy 404.817194 -396.923494)
			(xy 404.851128 -396.957261) (xy 404.879379 -396.995908) (xy 404.890732 -397.016986) (xy 404.89124 -397.018002)
			(xy 404.971546 -397.15694) (xy 405.51354 -397.15694) (xy 405.51354 -397.156432) (xy 405.513968 -397.132437)
			(xy 405.521471 -397.085038) (xy 405.536298 -397.039397) (xy 405.558084 -396.996638) (xy 405.586291 -396.957814)
			(xy 405.620226 -396.923881) (xy 405.659051 -396.895676) (xy 405.701812 -396.873892) (xy 405.747454 -396.859068)
			(xy 405.794853 -396.851567) (xy 405.818848 -396.851124) (xy 405.842784 -396.851565) (xy 405.890071 -396.859024)
			(xy 405.935616 -396.873767) (xy 405.978304 -396.895434) (xy 406.01709 -396.923495) (xy 406.051024 -396.957262)
			(xy 406.079275 -396.995908) (xy 406.090628 -397.016986) (xy 406.091136 -397.018002) (xy 406.171442 -397.15694)
			(xy 406.713436 -397.15694) (xy 406.713436 -397.156432) (xy 406.713891 -397.132452) (xy 406.721386 -397.085082)
			(xy 406.736196 -397.039466) (xy 406.757958 -396.996728) (xy 406.786134 -396.957918) (xy 406.820034 -396.923992)
			(xy 406.858821 -396.895784) (xy 406.901542 -396.873989) (xy 406.947146 -396.859143) (xy 406.99451 -396.85161)
			(xy 407.01849 -396.851124) (xy 407.018998 -396.851124) (xy 407.042935 -396.851524) (xy 407.090225 -396.858991)
			(xy 407.135771 -396.873741) (xy 407.178458 -396.895415) (xy 407.217243 -396.923482) (xy 407.251176 -396.957255)
			(xy 407.279426 -396.995906) (xy 407.290778 -397.016986) (xy 407.291286 -397.018002) (xy 407.371592 -397.15694)
			(xy 407.913332 -397.15694) (xy 407.913332 -397.156432) (xy 407.913791 -397.132452) (xy 407.921286 -397.085082)
			(xy 407.936096 -397.039467) (xy 407.957857 -396.996729) (xy 407.986033 -396.957919) (xy 408.019932 -396.923993)
			(xy 408.058719 -396.895786) (xy 408.101439 -396.87399) (xy 408.147043 -396.859143) (xy 408.194407 -396.851611)
			(xy 408.218386 -396.851124) (xy 408.218894 -396.851124) (xy 408.242831 -396.851527) (xy 408.29012 -396.858993)
			(xy 408.335666 -396.873744) (xy 408.378354 -396.895417) (xy 408.417139 -396.923483) (xy 408.451072 -396.957255)
			(xy 408.479322 -396.995906) (xy 408.490674 -397.016986) (xy 408.491182 -397.018002) (xy 408.571488 -397.15694)
			(xy 409.113736 -397.15694) (xy 409.113736 -397.156432) (xy 409.114168 -397.132438) (xy 409.121671 -397.085039)
			(xy 409.136498 -397.039398) (xy 409.158283 -396.996639) (xy 409.18649 -396.957815) (xy 409.220424 -396.923882)
			(xy 409.259249 -396.895677) (xy 409.302009 -396.873893) (xy 409.347651 -396.859068) (xy 409.39505 -396.851567)
			(xy 409.419044 -396.851124) (xy 409.44298 -396.851568) (xy 409.490267 -396.859026) (xy 409.535812 -396.873769)
			(xy 409.5785 -396.895436) (xy 409.617285 -396.923496) (xy 409.651219 -396.957262) (xy 409.679471 -396.995909)
			(xy 409.690824 -397.016986) (xy 409.691332 -397.018002) (xy 409.771638 -397.15694) (xy 410.313632 -397.15694)
			(xy 410.313632 -397.156432) (xy 410.314068 -397.132438) (xy 410.321571 -397.085039) (xy 410.336398 -397.039399)
			(xy 410.358183 -396.99664) (xy 410.386389 -396.957816) (xy 410.420322 -396.923884) (xy 410.459147 -396.895678)
			(xy 410.501906 -396.873895) (xy 410.547547 -396.859069) (xy 410.594946 -396.851567) (xy 410.61894 -396.851124)
			(xy 410.642876 -396.851571) (xy 410.690163 -396.859029) (xy 410.735708 -396.873771) (xy 410.778395 -396.895437)
			(xy 410.817181 -396.923497) (xy 410.851115 -396.957263) (xy 410.879367 -396.995909) (xy 410.89072 -397.016986)
			(xy 410.891228 -397.018002) (xy 410.971534 -397.15694) (xy 411.513528 -397.15694) (xy 411.513528 -397.156432)
			(xy 411.513968 -397.132438) (xy 411.521471 -397.08504) (xy 411.536297 -397.0394) (xy 411.558082 -396.996641)
			(xy 411.586288 -396.957818) (xy 411.620221 -396.923885) (xy 411.659045 -396.89568) (xy 411.701804 -396.873896)
			(xy 411.747444 -396.85907) (xy 411.794842 -396.851568) (xy 411.818836 -396.851124) (xy 411.842772 -396.851574)
			(xy 411.890058 -396.859031) (xy 411.935603 -396.873773) (xy 411.978291 -396.895439) (xy 412.017077 -396.923498)
			(xy 412.051011 -396.957264) (xy 412.079263 -396.995909) (xy 412.090616 -397.016986) (xy 412.091124 -397.018002)
			(xy 412.17143 -397.15694) (xy 412.713424 -397.15694) (xy 412.713424 -397.156432) (xy 412.713891 -397.132453)
			(xy 412.721386 -397.085083) (xy 412.736195 -397.039469) (xy 412.757955 -396.996731) (xy 412.786131 -396.957922)
			(xy 412.820029 -396.923996) (xy 412.858814 -396.895788) (xy 412.901534 -396.873993) (xy 412.947136 -396.859145)
			(xy 412.994499 -396.851611) (xy 413.018478 -396.851124) (xy 413.018986 -396.851124) (xy 413.042923 -396.851534)
			(xy 413.090212 -396.858998) (xy 413.135757 -396.873748) (xy 413.178445 -396.89542) (xy 413.21723 -396.923485)
			(xy 413.251164 -396.957256) (xy 413.279414 -396.995907) (xy 413.290766 -397.016986) (xy 413.291274 -397.018002)
			(xy 413.37158 -397.15694) (xy 413.91332 -397.15694) (xy 413.91332 -397.156432) (xy 413.913791 -397.132453)
			(xy 413.921285 -397.085084) (xy 413.936095 -397.03947) (xy 413.957855 -396.996732) (xy 413.98603 -396.957923)
			(xy 414.019927 -396.923998) (xy 414.058712 -396.89579) (xy 414.101431 -396.873994) (xy 414.147033 -396.859146)
			(xy 414.194395 -396.851612) (xy 414.218374 -396.851124) (xy 414.218882 -396.851124) (xy 414.242819 -396.851537)
			(xy 414.290108 -396.859001) (xy 414.335653 -396.87375) (xy 414.378341 -396.895422) (xy 414.417126 -396.923486)
			(xy 414.451059 -396.957257) (xy 414.47931 -396.995907) (xy 414.490662 -397.016986) (xy 414.49117 -397.018002)
			(xy 414.571476 -397.15694) (xy 415.113724 -397.15694) (xy 415.113724 -397.156432) (xy 415.114168 -397.132438)
			(xy 415.121671 -397.085041) (xy 415.136497 -397.039401) (xy 415.158281 -396.996643) (xy 415.186487 -396.957819)
			(xy 415.220419 -396.923887) (xy 415.259243 -396.895681) (xy 415.302001 -396.873897) (xy 415.347641 -396.859071)
			(xy 415.395038 -396.851568) (xy 415.419032 -396.851124) (xy 415.442968 -396.851578) (xy 415.490254 -396.859034)
			(xy 415.535799 -396.873775) (xy 415.578487 -396.89544) (xy 415.617272 -396.923499) (xy 415.651207 -396.957264)
			(xy 415.679459 -396.995909) (xy 415.690812 -397.016986) (xy 415.69132 -397.018002) (xy 415.771626 -397.15694)
			(xy 416.31362 -397.15694) (xy 416.31362 -397.156432) (xy 416.314068 -397.132438) (xy 416.321571 -397.085041)
			(xy 416.336397 -397.039402) (xy 416.35818 -396.996644) (xy 416.386386 -396.95782) (xy 416.420317 -396.923888)
			(xy 416.45914 -396.895682) (xy 416.501898 -396.873898) (xy 416.547537 -396.859072) (xy 416.594934 -396.851568)
			(xy 416.618928 -396.851124) (xy 416.642863 -396.851581) (xy 416.69015 -396.859037) (xy 416.735695 -396.873777)
			(xy 416.778382 -396.895442) (xy 416.817168 -396.9235) (xy 416.851103 -396.957265) (xy 416.879355 -396.995909)
			(xy 416.890708 -397.016986) (xy 416.891216 -397.018002) (xy 416.971522 -397.15694) (xy 417.513516 -397.15694)
			(xy 417.513516 -397.156432) (xy 417.513968 -397.132439) (xy 417.521471 -397.085042) (xy 417.536296 -397.039403)
			(xy 417.55808 -396.996645) (xy 417.586284 -396.957822) (xy 417.620216 -396.92389) (xy 417.659038 -396.895684)
			(xy 417.701795 -396.873899) (xy 417.747434 -396.859072) (xy 417.794831 -396.851568) (xy 417.818824 -396.851124)
			(xy 417.842759 -396.851584) (xy 417.890046 -396.859039) (xy 417.93559 -396.873779) (xy 417.978278 -396.895444)
			(xy 418.017064 -396.923501) (xy 418.050998 -396.957265) (xy 418.079251 -396.99591) (xy 418.090604 -397.016986)
			(xy 418.091112 -397.018002) (xy 418.171418 -397.15694) (xy 418.713412 -397.15694) (xy 418.713412 -397.156432)
			(xy 418.713891 -397.132453) (xy 418.721385 -397.085085) (xy 418.736194 -397.039472) (xy 418.757953 -396.996735)
			(xy 418.786127 -396.957926) (xy 418.820024 -396.924) (xy 418.858808 -396.895792) (xy 418.901525 -396.873996)
			(xy 418.947126 -396.859147) (xy 418.994488 -396.851612) (xy 419.018466 -396.851124) (xy 419.018974 -396.851124)
			(xy 419.042911 -396.851543) (xy 419.090199 -396.859006) (xy 419.135744 -396.873754) (xy 419.178432 -396.895425)
			(xy 419.217218 -396.923488) (xy 419.251151 -396.957258) (xy 419.279402 -396.995907) (xy 419.290754 -397.016986)
			(xy 419.291262 -397.018002) (xy 419.371568 -397.15694) (xy 419.913308 -397.15694) (xy 419.913308 -397.156432)
			(xy 419.913791 -397.132454) (xy 419.921285 -397.085086) (xy 419.936094 -397.039473) (xy 419.957852 -396.996736)
			(xy 419.986026 -396.957927) (xy 420.019922 -396.924002) (xy 420.058705 -396.895794) (xy 420.101423 -396.873997)
			(xy 420.147023 -396.859148) (xy 420.194384 -396.851612) (xy 420.218362 -396.851124) (xy 420.21887 -396.851124)
			(xy 420.242807 -396.851547) (xy 420.290095 -396.859009) (xy 420.33564 -396.873756) (xy 420.378328 -396.895426)
			(xy 420.417113 -396.923489) (xy 420.451047 -396.957259) (xy 420.479298 -396.995907) (xy 420.49065 -397.016986)
			(xy 420.491158 -397.018002) (xy 420.571464 -397.15694) (xy 421.113712 -397.15694) (xy 421.113712 -397.156432)
			(xy 421.114168 -397.132439) (xy 421.12167 -397.085042) (xy 421.136496 -397.039404) (xy 421.158279 -396.996646)
			(xy 421.186483 -396.957823) (xy 421.220414 -396.923891) (xy 421.259236 -396.895685) (xy 421.301992 -396.8739)
			(xy 421.347631 -396.859073) (xy 421.395027 -396.851569) (xy 421.41902 -396.851124) (xy 421.442955 -396.851587)
			(xy 421.490241 -396.859042) (xy 421.535786 -396.873782) (xy 421.578474 -396.895445) (xy 421.61726 -396.923502)
			(xy 421.651194 -396.957266) (xy 421.679447 -396.99591) (xy 421.6908 -397.016986) (xy 421.691308 -397.018002)
			(xy 422.083738 -397.696944) (xy 422.096544 -397.720286) (xy 422.114771 -397.770304) (xy 422.124039 -397.822727)
			(xy 422.124632 -397.849344) (xy 422.124179 -397.873323) (xy 422.116675 -397.920689) (xy 422.101859 -397.9663)
			(xy 422.080094 -398.009034) (xy 422.051916 -398.04784) (xy 422.018018 -398.081764) (xy 421.979234 -398.109971)
			(xy 421.936517 -398.131769) (xy 421.890917 -398.14662) (xy 421.843556 -398.154161) (xy 421.819578 -398.154652)
			(xy 421.81907 -398.154652) (xy 421.795497 -398.154255) (xy 421.74891 -398.14701) (xy 421.703993 -398.132683)
			(xy 421.661815 -398.111614) (xy 421.623383 -398.084306) (xy 421.58961 -398.051409) (xy 421.561302 -398.013706)
			(xy 421.54983 -397.993108) (xy 421.549322 -397.992346) (xy 421.151558 -397.304006) (xy 421.139682 -397.281329)
			(xy 421.122831 -397.232996) (xy 421.114258 -397.182533) (xy 421.113712 -397.15694) (xy 420.571464 -397.15694)
			(xy 420.883588 -397.696944) (xy 420.896302 -397.720272) (xy 420.914403 -397.770215) (xy 420.923627 -397.82253)
			(xy 420.924228 -397.84909) (xy 420.924228 -397.849344) (xy 420.923778 -397.873335) (xy 420.916266 -397.920727)
			(xy 420.901434 -397.96636) (xy 420.879647 -398.009111) (xy 420.851441 -398.047928) (xy 420.81751 -398.081856)
			(xy 420.778691 -398.110059) (xy 420.735937 -398.131843) (xy 420.690303 -398.146672) (xy 420.642911 -398.15418)
			(xy 420.61892 -398.154652) (xy 420.595348 -398.154215) (xy 420.548763 -398.146978) (xy 420.503847 -398.132658)
			(xy 420.46167 -398.111595) (xy 420.423236 -398.084293) (xy 420.389462 -398.051402) (xy 420.361153 -398.013704)
			(xy 420.34968 -397.993108) (xy 420.349172 -397.992346) (xy 419.951408 -397.304006) (xy 419.939493 -397.281337)
			(xy 419.922555 -397.233012) (xy 419.913896 -397.182542) (xy 419.913308 -397.15694) (xy 419.371568 -397.15694)
			(xy 419.683692 -397.696944) (xy 419.696406 -397.720272) (xy 419.714507 -397.770215) (xy 419.723731 -397.82253)
			(xy 419.724332 -397.84909) (xy 419.724332 -397.849344) (xy 419.723878 -397.873335) (xy 419.716366 -397.920726)
			(xy 419.701534 -397.966359) (xy 419.679747 -398.00911) (xy 419.651542 -398.047927) (xy 419.617612 -398.081855)
			(xy 419.578793 -398.110058) (xy 419.53604 -398.131842) (xy 419.490407 -398.146671) (xy 419.443015 -398.15418)
			(xy 419.419024 -398.154652) (xy 419.395452 -398.154211) (xy 419.348867 -398.146975) (xy 419.303951 -398.132656)
			(xy 419.261774 -398.111594) (xy 419.223341 -398.084292) (xy 419.189567 -398.051401) (xy 419.161257 -398.013704)
			(xy 419.149784 -397.993108) (xy 419.149276 -397.992346) (xy 418.751512 -397.304006) (xy 418.739598 -397.281337)
			(xy 418.72266 -397.233012) (xy 418.714 -397.182542) (xy 418.713412 -397.15694) (xy 418.171418 -397.15694)
			(xy 418.483542 -397.696944) (xy 418.496349 -397.720286) (xy 418.514576 -397.770304) (xy 418.523843 -397.822727)
			(xy 418.524436 -397.849344) (xy 418.523979 -397.873322) (xy 418.516475 -397.920688) (xy 418.501659 -397.966299)
			(xy 418.479895 -398.009033) (xy 418.451717 -398.047839) (xy 418.41782 -398.081762) (xy 418.379036 -398.10997)
			(xy 418.336319 -398.131768) (xy 418.29072 -398.14662) (xy 418.24336 -398.15416) (xy 418.219382 -398.154652)
			(xy 418.218874 -398.154652) (xy 418.195301 -398.154252) (xy 418.148714 -398.147008) (xy 418.103797 -398.132681)
			(xy 418.06162 -398.111613) (xy 418.023187 -398.084305) (xy 417.989414 -398.051408) (xy 417.961106 -398.013706)
			(xy 417.949634 -397.993108) (xy 417.949126 -397.992346) (xy 417.551362 -397.304006) (xy 417.539486 -397.281329)
			(xy 417.522635 -397.232996) (xy 417.514062 -397.182533) (xy 417.513516 -397.15694) (xy 416.971522 -397.15694)
			(xy 417.283646 -397.696944) (xy 417.296453 -397.720286) (xy 417.31468 -397.770304) (xy 417.323947 -397.822727)
			(xy 417.32454 -397.849344) (xy 417.324079 -397.873322) (xy 417.316575 -397.920688) (xy 417.301759 -397.966298)
			(xy 417.279995 -398.009032) (xy 417.251818 -398.047837) (xy 417.217922 -398.081761) (xy 417.179138 -398.109969)
			(xy 417.136422 -398.131767) (xy 417.090824 -398.146619) (xy 417.043464 -398.15416) (xy 417.019486 -398.154652)
			(xy 417.018978 -398.154652) (xy 416.995405 -398.154249) (xy 416.948818 -398.147005) (xy 416.903901 -398.132679)
			(xy 416.861724 -398.111611) (xy 416.823291 -398.084304) (xy 416.789518 -398.051408) (xy 416.76121 -398.013706)
			(xy 416.749738 -397.993108) (xy 416.74923 -397.992346) (xy 416.351466 -397.304006) (xy 416.339591 -397.281329)
			(xy 416.322739 -397.232996) (xy 416.314166 -397.182533) (xy 416.31362 -397.15694) (xy 415.771626 -397.15694)
			(xy 416.08375 -397.696944) (xy 416.096557 -397.720285) (xy 416.114784 -397.770304) (xy 416.124051 -397.822726)
			(xy 416.124644 -397.849344) (xy 416.124179 -397.873322) (xy 416.116676 -397.920687) (xy 416.10186 -397.966297)
			(xy 416.080096 -398.00903) (xy 416.05192 -398.047836) (xy 416.018023 -398.08176) (xy 415.97924 -398.109967)
			(xy 415.936525 -398.131765) (xy 415.890927 -398.146618) (xy 415.843568 -398.15416) (xy 415.81959 -398.154652)
			(xy 415.819082 -398.154652) (xy 415.795509 -398.154245) (xy 415.748922 -398.147003) (xy 415.704006 -398.132677)
			(xy 415.661828 -398.11161) (xy 415.623395 -398.084303) (xy 415.589623 -398.051407) (xy 415.561314 -398.013706)
			(xy 415.549842 -397.993108) (xy 415.549334 -397.992346) (xy 415.15157 -397.304006) (xy 415.139695 -397.281329)
			(xy 415.122843 -397.232996) (xy 415.11427 -397.182533) (xy 415.113724 -397.15694) (xy 414.571476 -397.15694)
			(xy 414.8836 -397.696944) (xy 414.896315 -397.720271) (xy 414.914415 -397.770215) (xy 414.923639 -397.82253)
			(xy 414.92424 -397.84909) (xy 414.92424 -397.849344) (xy 414.923778 -397.873335) (xy 414.916266 -397.920725)
			(xy 414.901435 -397.966357) (xy 414.879649 -398.009107) (xy 414.851444 -398.047924) (xy 414.817515 -398.081852)
			(xy 414.778697 -398.110055) (xy 414.735946 -398.13184) (xy 414.690313 -398.146669) (xy 414.642923 -398.154179)
			(xy 414.618932 -398.154652) (xy 414.59536 -398.154205) (xy 414.548776 -398.14697) (xy 414.50386 -398.132651)
			(xy 414.461683 -398.111591) (xy 414.423249 -398.08429) (xy 414.389475 -398.0514) (xy 414.361165 -398.013703)
			(xy 414.349692 -397.993108) (xy 414.349184 -397.992346) (xy 413.95142 -397.304006) (xy 413.939506 -397.281337)
			(xy 413.922568 -397.233012) (xy 413.913908 -397.182542) (xy 413.91332 -397.15694) (xy 413.37158 -397.15694)
			(xy 413.683704 -397.696944) (xy 413.696419 -397.720271) (xy 413.71452 -397.770214) (xy 413.723743 -397.82253)
			(xy 413.724344 -397.84909) (xy 413.724344 -397.849344) (xy 413.723878 -397.873335) (xy 413.716367 -397.920724)
			(xy 413.701535 -397.966356) (xy 413.679749 -398.009106) (xy 413.651545 -398.047923) (xy 413.617617 -398.08185)
			(xy 413.578799 -398.110054) (xy 413.536049 -398.131838) (xy 413.490417 -398.146668) (xy 413.443027 -398.154179)
			(xy 413.419036 -398.154652) (xy 413.395464 -398.154202) (xy 413.34888 -398.146967) (xy 413.303964 -398.132649)
			(xy 413.261787 -398.111589) (xy 413.223353 -398.084289) (xy 413.189579 -398.051399) (xy 413.161269 -398.013703)
			(xy 413.149796 -397.993108) (xy 413.149288 -397.992346) (xy 412.751524 -397.304006) (xy 412.739611 -397.281337)
			(xy 412.722672 -397.233012) (xy 412.714012 -397.182542) (xy 412.713424 -397.15694) (xy 412.17143 -397.15694)
			(xy 412.483554 -397.696944) (xy 412.496362 -397.720285) (xy 412.514588 -397.770304) (xy 412.523855 -397.822726)
			(xy 412.524448 -397.849344) (xy 412.523979 -397.873322) (xy 412.516476 -397.920687) (xy 412.50166 -397.966296)
			(xy 412.479897 -398.009029) (xy 412.451721 -398.047835) (xy 412.417825 -398.081758) (xy 412.379043 -398.109966)
			(xy 412.336328 -398.131764) (xy 412.29073 -398.146617) (xy 412.243371 -398.154159) (xy 412.219394 -398.154652)
			(xy 412.218886 -398.154652) (xy 412.195313 -398.154242) (xy 412.148727 -398.147) (xy 412.10381 -398.132675)
			(xy 412.061633 -398.111608) (xy 412.0232 -398.084302) (xy 411.989427 -398.051406) (xy 411.961119 -398.013705)
			(xy 411.949646 -397.993108) (xy 411.949138 -397.992346) (xy 411.551374 -397.304006) (xy 411.539499 -397.281329)
			(xy 411.522648 -397.232996) (xy 411.514074 -397.182533) (xy 411.513528 -397.15694) (xy 410.971534 -397.15694)
			(xy 411.283658 -397.696944) (xy 411.296466 -397.720285) (xy 411.314692 -397.770304) (xy 411.323959 -397.822726)
			(xy 411.324552 -397.849344) (xy 411.324079 -397.873322) (xy 411.316576 -397.920686) (xy 411.301761 -397.966295)
			(xy 411.279998 -398.009028) (xy 411.251822 -398.047833) (xy 411.217927 -398.081757) (xy 411.179145 -398.109965)
			(xy 411.13643 -398.131763) (xy 411.090833 -398.146616) (xy 411.043475 -398.154159) (xy 411.019498 -398.154652)
			(xy 411.01899 -398.154652) (xy 410.995417 -398.154239) (xy 410.948831 -398.146997) (xy 410.903914 -398.132673)
			(xy 410.861737 -398.111607) (xy 410.823304 -398.084301) (xy 410.789531 -398.051406) (xy 410.761223 -398.013705)
			(xy 410.74975 -397.993108) (xy 410.749242 -397.992346) (xy 410.351478 -397.304006) (xy 410.339603 -397.281328)
			(xy 410.322752 -397.232996) (xy 410.314178 -397.182533) (xy 410.313632 -397.15694) (xy 409.771638 -397.15694)
			(xy 410.083762 -397.696944) (xy 410.09657 -397.720285) (xy 410.114796 -397.770304) (xy 410.124063 -397.822726)
			(xy 410.124656 -397.849344) (xy 410.124179 -397.873321) (xy 410.116676 -397.920686) (xy 410.101861 -397.966295)
			(xy 410.080098 -398.009027) (xy 410.051923 -398.047832) (xy 410.018028 -398.081755) (xy 409.979247 -398.109963)
			(xy 409.936533 -398.131762) (xy 409.890937 -398.146616) (xy 409.843579 -398.154159) (xy 409.819602 -398.154652)
			(xy 409.819094 -398.154652) (xy 409.795521 -398.154236) (xy 409.748935 -398.146995) (xy 409.704019 -398.132671)
			(xy 409.661841 -398.111605) (xy 409.623408 -398.0843) (xy 409.589635 -398.051405) (xy 409.561327 -398.013705)
			(xy 409.549854 -397.993108) (xy 409.549346 -397.992346) (xy 409.151582 -397.304006) (xy 409.139708 -397.281328)
			(xy 409.122856 -397.232996) (xy 409.114282 -397.182533) (xy 409.113736 -397.15694) (xy 408.571488 -397.15694)
			(xy 408.883612 -397.696944) (xy 408.896328 -397.720271) (xy 408.914428 -397.770214) (xy 408.923651 -397.82253)
			(xy 408.924252 -397.84909) (xy 408.924252 -397.849344) (xy 408.923778 -397.873334) (xy 408.916267 -397.920723)
			(xy 408.901436 -397.966354) (xy 408.879651 -398.009104) (xy 408.851448 -398.04792) (xy 408.81752 -398.081848)
			(xy 408.778704 -398.110051) (xy 408.735954 -398.131836) (xy 408.690323 -398.146667) (xy 408.642934 -398.154178)
			(xy 408.618944 -398.154652) (xy 408.595373 -398.154195) (xy 408.548789 -398.146962) (xy 408.503873 -398.132645)
			(xy 408.461696 -398.111586) (xy 408.423262 -398.084287) (xy 408.389488 -398.051398) (xy 408.361178 -398.013703)
			(xy 408.349704 -397.993108) (xy 408.349196 -397.992346) (xy 407.951432 -397.304006) (xy 407.939519 -397.281336)
			(xy 407.92258 -397.233012) (xy 407.91392 -397.182542) (xy 407.913332 -397.15694) (xy 407.371592 -397.15694)
			(xy 407.683716 -397.696944) (xy 407.696432 -397.720271) (xy 407.714532 -397.770214) (xy 407.723755 -397.82253)
			(xy 407.724356 -397.84909) (xy 407.724356 -397.849344) (xy 407.723878 -397.873334) (xy 407.716367 -397.920723)
			(xy 407.701536 -397.966353) (xy 407.679752 -398.009103) (xy 407.651549 -398.047919) (xy 407.617622 -398.081846)
			(xy 407.578806 -398.11005) (xy 407.536057 -398.131835) (xy 407.490427 -398.146666) (xy 407.443038 -398.154178)
			(xy 407.419048 -398.154652) (xy 407.395477 -398.154192) (xy 407.348893 -398.146959) (xy 407.303977 -398.132643)
			(xy 407.2618 -398.111585) (xy 407.223366 -398.084286) (xy 407.189592 -398.051398) (xy 407.161282 -398.013703)
			(xy 407.149808 -397.993108) (xy 407.1493 -397.992346) (xy 406.751536 -397.304006) (xy 406.739623 -397.281336)
			(xy 406.722684 -397.233012) (xy 406.714024 -397.182542) (xy 406.713436 -397.15694) (xy 406.171442 -397.15694)
			(xy 406.483566 -397.696944) (xy 406.496375 -397.720285) (xy 406.5146 -397.770303) (xy 406.523867 -397.822726)
			(xy 406.52446 -397.849344) (xy 406.524079 -397.873326) (xy 406.516573 -397.9207) (xy 406.501752 -397.966317)
			(xy 406.479981 -398.009055) (xy 406.451795 -398.047865) (xy 406.417888 -398.08179) (xy 406.379094 -398.109996)
			(xy 406.336367 -398.13179) (xy 406.290757 -398.146635) (xy 406.243388 -398.154166) (xy 406.219406 -398.154652)
			(xy 406.218898 -398.154652) (xy 406.195325 -398.154232) (xy 406.14874 -398.146992) (xy 406.103823 -398.132669)
			(xy 406.061646 -398.111604) (xy 406.023213 -398.084299) (xy 405.989439 -398.051405) (xy 405.961131 -398.013705)
			(xy 405.949658 -397.993108) (xy 405.94915 -397.992346) (xy 405.551386 -397.304006) (xy 405.539512 -397.281328)
			(xy 405.52266 -397.232996) (xy 405.514086 -397.182533) (xy 405.51354 -397.15694) (xy 404.971546 -397.15694)
			(xy 405.28367 -397.696944) (xy 405.296479 -397.720285) (xy 405.314704 -397.770303) (xy 405.323971 -397.822726)
			(xy 405.324564 -397.849344) (xy 405.324179 -397.873326) (xy 405.316673 -397.920699) (xy 405.301852 -397.966316)
			(xy 405.280081 -398.009054) (xy 405.251896 -398.047863) (xy 405.21799 -398.081788) (xy 405.179196 -398.109994)
			(xy 405.136469 -398.131788) (xy 405.090861 -398.146634) (xy 405.043492 -398.154166) (xy 405.01951 -398.154652)
			(xy 405.019002 -398.154652) (xy 404.995429 -398.154229) (xy 404.948844 -398.14699) (xy 404.903927 -398.132667)
			(xy 404.86175 -398.111602) (xy 404.823317 -398.084298) (xy 404.789544 -398.051404) (xy 404.761235 -398.013705)
			(xy 404.749762 -397.993108) (xy 404.749254 -397.992346) (xy 404.35149 -397.304006) (xy 404.339616 -397.281328)
			(xy 404.322764 -397.232995) (xy 404.31419 -397.182533) (xy 404.313644 -397.15694) (xy 403.77165 -397.15694)
			(xy 404.083774 -397.696944) (xy 404.096583 -397.720284) (xy 404.114808 -397.770303) (xy 404.124075 -397.822726)
			(xy 404.124668 -397.849344) (xy 404.124279 -397.873326) (xy 404.116773 -397.920698) (xy 404.101952 -397.966315)
			(xy 404.080182 -398.009053) (xy 404.051997 -398.047862) (xy 404.018091 -398.081787) (xy 403.979298 -398.109993)
			(xy 403.936572 -398.131787) (xy 403.890964 -398.146633) (xy 403.843595 -398.154165) (xy 403.819614 -398.154652)
			(xy 403.819106 -398.154652) (xy 403.795534 -398.154226) (xy 403.748948 -398.146987) (xy 403.704032 -398.132665)
			(xy 403.661854 -398.111601) (xy 403.623421 -398.084297) (xy 403.589648 -398.051404) (xy 403.561339 -398.013705)
			(xy 403.549866 -397.993108) (xy 403.549358 -397.992346) (xy 403.151594 -397.304006) (xy 403.139721 -397.281328)
			(xy 403.122868 -397.232995) (xy 403.114294 -397.182532) (xy 403.113748 -397.15694) (xy 389.243866 -397.15694)
			(xy 389.55599 -397.696944) (xy 389.568801 -397.720284) (xy 389.587025 -397.770303) (xy 389.596291 -397.822726)
			(xy 389.596884 -397.849344) (xy 389.596479 -397.873325) (xy 389.588973 -397.920696) (xy 389.574154 -397.966311)
			(xy 389.552385 -398.009048) (xy 389.524202 -398.047856) (xy 389.490298 -398.081781) (xy 389.451507 -398.109988)
			(xy 389.408783 -398.131783) (xy 389.363177 -398.14663) (xy 389.315811 -398.154164) (xy 389.29183 -398.154652)
			(xy 389.291322 -398.154652) (xy 389.26775 -398.154213) (xy 389.221165 -398.146976) (xy 389.176249 -398.132657)
			(xy 389.134072 -398.111595) (xy 389.095638 -398.084293) (xy 389.061865 -398.051401) (xy 389.033555 -398.013704)
			(xy 389.022082 -397.993108) (xy 389.021574 -397.992346) (xy 388.62381 -397.304006) (xy 388.61193 -397.281331)
			(xy 388.595082 -397.232997) (xy 388.58651 -397.182533) (xy 388.585964 -397.15694) (xy 388.043716 -397.15694)
			(xy 388.35584 -397.696944) (xy 388.368558 -397.72027) (xy 388.386657 -397.770214) (xy 388.395879 -397.82253)
			(xy 388.39648 -397.84909) (xy 388.39648 -397.849344) (xy 388.396078 -397.873338) (xy 388.388564 -397.920734)
			(xy 388.373729 -397.966371) (xy 388.351938 -398.009125) (xy 388.323726 -398.047945) (xy 388.28979 -398.081873)
			(xy 388.250964 -398.110075) (xy 388.208204 -398.131857) (xy 388.162564 -398.146681) (xy 388.115166 -398.154184)
			(xy 388.091172 -398.154652) (xy 388.067599 -398.154253) (xy 388.021012 -398.147009) (xy 387.976095 -398.132682)
			(xy 387.933917 -398.111614) (xy 387.895485 -398.084306) (xy 387.861712 -398.051408) (xy 387.833404 -398.013706)
			(xy 387.821932 -397.993108) (xy 387.821424 -397.992346) (xy 387.42366 -397.304006) (xy 387.411749 -397.281335)
			(xy 387.394809 -397.233011) (xy 387.386148 -397.182542) (xy 387.38556 -397.15694) (xy 386.84382 -397.15694)
			(xy 387.155944 -397.696944) (xy 387.168662 -397.720269) (xy 387.186761 -397.770214) (xy 387.195983 -397.82253)
			(xy 387.196584 -397.84909) (xy 387.196584 -397.849344) (xy 387.196178 -397.873338) (xy 387.188664 -397.920733)
			(xy 387.17383 -397.96637) (xy 387.152038 -398.009124) (xy 387.123828 -398.047943) (xy 387.089892 -398.081872)
			(xy 387.051066 -398.110074) (xy 387.008307 -398.131856) (xy 386.962667 -398.14668) (xy 386.91527 -398.154183)
			(xy 386.891276 -398.154652) (xy 386.867703 -398.15425) (xy 386.821116 -398.147007) (xy 386.776199 -398.13268)
			(xy 386.734022 -398.111612) (xy 386.695589 -398.084305) (xy 386.661816 -398.051408) (xy 386.633508 -398.013706)
			(xy 386.622036 -397.993108) (xy 386.621528 -397.992346) (xy 386.223764 -397.304006) (xy 386.211854 -397.281335)
			(xy 386.194914 -397.233011) (xy 386.186252 -397.182542) (xy 386.185664 -397.15694) (xy 385.64367 -397.15694)
			(xy 385.955794 -397.696944) (xy 385.968605 -397.720283) (xy 385.986829 -397.770303) (xy 385.996095 -397.822726)
			(xy 385.996688 -397.849344) (xy 385.996279 -397.873325) (xy 385.988774 -397.920695) (xy 385.973954 -397.96631)
			(xy 385.952186 -398.009047) (xy 385.924003 -398.047855) (xy 385.8901 -398.08178) (xy 385.851309 -398.109986)
			(xy 385.808586 -398.131782) (xy 385.76298 -398.146629) (xy 385.715614 -398.154164) (xy 385.691634 -398.154652)
			(xy 385.691126 -398.154652) (xy 385.667554 -398.15421) (xy 385.620969 -398.146974) (xy 385.576053 -398.132654)
			(xy 385.533876 -398.111593) (xy 385.495443 -398.084292) (xy 385.461669 -398.051401) (xy 385.433359 -398.013704)
			(xy 385.421886 -397.993108) (xy 385.421378 -397.992346) (xy 385.023614 -397.304006) (xy 385.011735 -397.281331)
			(xy 384.994886 -397.232997) (xy 384.986314 -397.182533) (xy 384.985768 -397.15694) (xy 384.443774 -397.15694)
			(xy 384.755898 -397.696944) (xy 384.768701 -397.720288) (xy 384.78693 -397.770305) (xy 384.796199 -397.822727)
			(xy 384.796792 -397.849344) (xy 384.796379 -397.873325) (xy 384.788874 -397.920695) (xy 384.774055 -397.966309)
			(xy 384.752287 -398.009046) (xy 384.724104 -398.047854) (xy 384.690201 -398.081778) (xy 384.651412 -398.109985)
			(xy 384.608689 -398.13178) (xy 384.563084 -398.146628) (xy 384.515718 -398.154164) (xy 384.491738 -398.154652)
			(xy 384.49123 -398.154652) (xy 384.467658 -398.154207) (xy 384.421074 -398.146971) (xy 384.376158 -398.132652)
			(xy 384.33398 -398.111592) (xy 384.295547 -398.084291) (xy 384.261773 -398.0514) (xy 384.233463 -398.013704)
			(xy 384.22199 -397.993108) (xy 384.221482 -397.992346) (xy 383.823718 -397.304006) (xy 383.811839 -397.281331)
			(xy 383.79499 -397.232997) (xy 383.786418 -397.182533) (xy 383.785872 -397.15694) (xy 383.243878 -397.15694)
			(xy 383.556002 -397.696944) (xy 383.568805 -397.720288) (xy 383.587034 -397.770305) (xy 383.596303 -397.822727)
			(xy 383.596896 -397.849344) (xy 383.596479 -397.873324) (xy 383.588974 -397.920694) (xy 383.574155 -397.966308)
			(xy 383.552387 -398.009045) (xy 383.524206 -398.047852) (xy 383.490303 -398.081777) (xy 383.451514 -398.109984)
			(xy 383.408792 -398.131779) (xy 383.363187 -398.146628) (xy 383.315822 -398.154163) (xy 383.291842 -398.154652)
			(xy 383.291334 -398.154652) (xy 383.267762 -398.154203) (xy 383.221178 -398.146969) (xy 383.176262 -398.13265)
			(xy 383.134085 -398.11159) (xy 383.095651 -398.08429) (xy 383.061877 -398.0514) (xy 383.033567 -398.013703)
			(xy 383.022094 -397.993108) (xy 383.021586 -397.992346) (xy 382.623822 -397.304006) (xy 382.611943 -397.281331)
			(xy 382.595094 -397.232996) (xy 382.586522 -397.182533) (xy 382.585976 -397.15694) (xy 382.043728 -397.15694)
			(xy 382.355852 -397.696944) (xy 382.368571 -397.720269) (xy 382.386669 -397.770214) (xy 382.395891 -397.82253)
			(xy 382.396492 -397.84909) (xy 382.396492 -397.849344) (xy 382.396078 -397.873337) (xy 382.388565 -397.920732)
			(xy 382.37373 -397.966368) (xy 382.35194 -398.009122) (xy 382.32373 -398.047941) (xy 382.289795 -398.081869)
			(xy 382.250971 -398.110071) (xy 382.208212 -398.131853) (xy 382.162574 -398.146679) (xy 382.115177 -398.154183)
			(xy 382.091184 -398.154652) (xy 382.067611 -398.154244) (xy 382.021025 -398.147001) (xy 381.976108 -398.132676)
			(xy 381.933931 -398.111609) (xy 381.895498 -398.084302) (xy 381.861725 -398.051407) (xy 381.833416 -398.013706)
			(xy 381.821944 -397.993108) (xy 381.821436 -397.992346) (xy 381.423672 -397.304006) (xy 381.411754 -397.281339)
			(xy 381.394818 -397.233013) (xy 381.386159 -397.182542) (xy 381.385572 -397.15694) (xy 380.843832 -397.15694)
			(xy 381.155956 -397.696944) (xy 381.168675 -397.720269) (xy 381.186773 -397.770214) (xy 381.195995 -397.822529)
			(xy 381.196596 -397.84909) (xy 381.196596 -397.849344) (xy 381.196178 -397.873337) (xy 381.188665 -397.920731)
			(xy 381.173831 -397.966367) (xy 381.152041 -398.009121) (xy 381.123831 -398.047939) (xy 381.089897 -398.081868)
			(xy 381.051073 -398.11007) (xy 381.008315 -398.131852) (xy 380.962677 -398.146678) (xy 380.915281 -398.154182)
			(xy 380.891288 -398.154652) (xy 380.867715 -398.154241) (xy 380.821129 -398.146999) (xy 380.776212 -398.132674)
			(xy 380.734035 -398.111608) (xy 380.695602 -398.084301) (xy 380.661829 -398.051406) (xy 380.633521 -398.013705)
			(xy 380.622048 -397.993108) (xy 380.62154 -397.992346) (xy 380.223776 -397.304006) (xy 380.211859 -397.281339)
			(xy 380.194923 -397.233013) (xy 380.186263 -397.182542) (xy 380.185676 -397.15694) (xy 379.643682 -397.15694)
			(xy 379.955806 -397.696944) (xy 379.96861 -397.720287) (xy 379.986838 -397.770304) (xy 379.996107 -397.822727)
			(xy 379.9967 -397.849344) (xy 379.996279 -397.873324) (xy 379.988774 -397.920694) (xy 379.973956 -397.966307)
			(xy 379.952188 -398.009044) (xy 379.924007 -398.047851) (xy 379.890105 -398.081775) (xy 379.851316 -398.109982)
			(xy 379.808594 -398.131778) (xy 379.76299 -398.146627) (xy 379.715626 -398.154163) (xy 379.691646 -398.154652)
			(xy 379.691138 -398.154652) (xy 379.667566 -398.1542) (xy 379.620982 -398.146966) (xy 379.576066 -398.132648)
			(xy 379.533889 -398.111589) (xy 379.495456 -398.084289) (xy 379.461681 -398.051399) (xy 379.433371 -398.013703)
			(xy 379.421898 -397.993108) (xy 379.42139 -397.992346) (xy 379.023626 -397.304006) (xy 379.011747 -397.28133)
			(xy 378.994898 -397.232996) (xy 378.986326 -397.182533) (xy 378.98578 -397.15694) (xy 378.443786 -397.15694)
			(xy 378.75591 -397.696944) (xy 378.768714 -397.720287) (xy 378.786943 -397.770304) (xy 378.796211 -397.822727)
			(xy 378.796804 -397.849344) (xy 378.796379 -397.873324) (xy 378.788874 -397.920693) (xy 378.774056 -397.966307)
			(xy 378.752289 -398.009042) (xy 378.724108 -398.04785) (xy 378.690206 -398.081774) (xy 378.651418 -398.109981)
			(xy 378.608697 -398.131777) (xy 378.563094 -398.146626) (xy 378.51573 -398.154163) (xy 378.49175 -398.154652)
			(xy 378.491242 -398.154652) (xy 378.467671 -398.154197) (xy 378.421086 -398.146963) (xy 378.376171 -398.132646)
			(xy 378.333993 -398.111587) (xy 378.29556 -398.084288) (xy 378.261786 -398.051398) (xy 378.233476 -398.013703)
			(xy 378.222002 -397.993108) (xy 378.221494 -397.992346) (xy 377.82373 -397.304006) (xy 377.811852 -397.28133)
			(xy 377.795002 -397.232996) (xy 377.78643 -397.182533) (xy 377.785884 -397.15694) (xy 377.24389 -397.15694)
			(xy 377.556014 -397.696944) (xy 377.568818 -397.720287) (xy 377.587047 -397.770304) (xy 377.596315 -397.822727)
			(xy 377.596908 -397.849344) (xy 377.596479 -397.873324) (xy 377.588974 -397.920693) (xy 377.574156 -397.966306)
			(xy 377.552389 -398.009041) (xy 377.524209 -398.047848) (xy 377.490308 -398.081772) (xy 377.45152 -398.10998)
			(xy 377.4088 -398.131776) (xy 377.363197 -398.146625) (xy 377.315833 -398.154162) (xy 377.291854 -398.154652)
			(xy 377.291346 -398.154652) (xy 377.267775 -398.154194) (xy 377.221191 -398.146961) (xy 377.176275 -398.132644)
			(xy 377.134098 -398.111586) (xy 377.095664 -398.084287) (xy 377.06189 -398.051398) (xy 377.03358 -398.013703)
			(xy 377.022106 -397.993108) (xy 377.021598 -397.992346) (xy 376.623834 -397.304006) (xy 376.611956 -397.28133)
			(xy 376.595106 -397.232996) (xy 376.586534 -397.182533) (xy 376.585988 -397.15694) (xy 376.04374 -397.15694)
			(xy 376.355864 -397.696944) (xy 376.368584 -397.720268) (xy 376.386681 -397.770213) (xy 376.395904 -397.822529)
			(xy 376.396504 -397.84909) (xy 376.396504 -397.849344) (xy 376.396078 -397.873337) (xy 376.388565 -397.92073)
			(xy 376.373731 -397.966365) (xy 376.351942 -398.009118) (xy 376.323733 -398.047937) (xy 376.2898 -398.081865)
			(xy 376.250977 -398.110067) (xy 376.208221 -398.13185) (xy 376.162583 -398.146676) (xy 376.115189 -398.154182)
			(xy 376.091196 -398.154652) (xy 376.067623 -398.154234) (xy 376.021037 -398.146993) (xy 375.976121 -398.13267)
			(xy 375.933944 -398.111605) (xy 375.89551 -398.084299) (xy 375.861737 -398.051405) (xy 375.833429 -398.013705)
			(xy 375.821956 -397.993108) (xy 375.821448 -397.992346) (xy 375.423684 -397.304006) (xy 375.411767 -397.281338)
			(xy 375.394831 -397.233013) (xy 375.386171 -397.182542) (xy 375.385584 -397.15694) (xy 374.843844 -397.15694)
			(xy 375.155968 -397.696944) (xy 375.168688 -397.720268) (xy 375.186786 -397.770213) (xy 375.196008 -397.822529)
			(xy 375.196608 -397.84909) (xy 375.196608 -397.849344) (xy 375.196178 -397.873336) (xy 375.188665 -397.92073)
			(xy 375.173832 -397.966364) (xy 375.152043 -398.009117) (xy 375.123835 -398.047935) (xy 375.089902 -398.081863)
			(xy 375.051079 -398.110066) (xy 375.008324 -398.131849) (xy 374.962687 -398.146676) (xy 374.915292 -398.154181)
			(xy 374.8913 -398.154652) (xy 374.867727 -398.154231) (xy 374.821142 -398.146991) (xy 374.776225 -398.132668)
			(xy 374.734048 -398.111603) (xy 374.695615 -398.084298) (xy 374.661842 -398.051404) (xy 374.633533 -398.013705)
			(xy 374.62206 -397.993108) (xy 374.621552 -397.992346) (xy 374.223788 -397.304006) (xy 374.211872 -397.281338)
			(xy 374.194935 -397.233013) (xy 374.186275 -397.182542) (xy 374.185688 -397.15694) (xy 373.643694 -397.15694)
			(xy 373.955818 -397.696944) (xy 373.968623 -397.720287) (xy 373.986851 -397.770304) (xy 373.996119 -397.822727)
			(xy 373.996712 -397.849344) (xy 373.996279 -397.873324) (xy 373.988774 -397.920692) (xy 373.973957 -397.966305)
			(xy 373.95219 -398.00904) (xy 373.92401 -398.047847) (xy 373.89011 -398.081771) (xy 373.851323 -398.109978)
			(xy 373.808603 -398.131775) (xy 373.763 -398.146624) (xy 373.715637 -398.154162) (xy 373.691658 -398.154652)
			(xy 373.69115 -398.154652) (xy 373.667579 -398.154191) (xy 373.620995 -398.146958) (xy 373.576079 -398.132642)
			(xy 373.533902 -398.111584) (xy 373.495468 -398.084286) (xy 373.461694 -398.051397) (xy 373.433384 -398.013703)
			(xy 373.42191 -397.993108) (xy 373.421402 -397.992346) (xy 373.023638 -397.304006) (xy 373.01176 -397.28133)
			(xy 372.994911 -397.232996) (xy 372.986338 -397.182533) (xy 372.985792 -397.15694) (xy 372.443798 -397.15694)
			(xy 372.755922 -397.696944) (xy 372.768727 -397.720287) (xy 372.786955 -397.770304) (xy 372.796223 -397.822727)
			(xy 372.796816 -397.849344) (xy 372.796379 -397.873323) (xy 372.788875 -397.920691) (xy 372.774057 -397.966304)
			(xy 372.752291 -398.009039) (xy 372.724111 -398.047846) (xy 372.690212 -398.08177) (xy 372.651425 -398.109977)
			(xy 372.608705 -398.131773) (xy 372.563104 -398.146624) (xy 372.515741 -398.154162) (xy 372.491762 -398.154652)
			(xy 372.491254 -398.154652) (xy 372.467683 -398.154187) (xy 372.421099 -398.146955) (xy 372.376184 -398.13264)
			(xy 372.334006 -398.111583) (xy 372.295573 -398.084285) (xy 372.261798 -398.051397) (xy 372.233488 -398.013702)
			(xy 372.222014 -397.993108) (xy 372.221506 -397.992346) (xy 371.823742 -397.304006) (xy 371.811865 -397.28133)
			(xy 371.795015 -397.232996) (xy 371.786442 -397.182533) (xy 371.785896 -397.15694) (xy 371.243902 -397.15694)
			(xy 371.556026 -397.696944) (xy 371.568831 -397.720286) (xy 371.587059 -397.770304) (xy 371.596327 -397.822727)
			(xy 371.59692 -397.849344) (xy 371.596479 -397.873323) (xy 371.588975 -397.920691) (xy 371.574157 -397.966303)
			(xy 371.552392 -398.009038) (xy 371.524213 -398.047844) (xy 371.490313 -398.081768) (xy 371.451527 -398.109975)
			(xy 371.408808 -398.131772) (xy 371.363207 -398.146623) (xy 371.315845 -398.154162) (xy 371.291866 -398.154652)
			(xy 371.291358 -398.154652) (xy 371.267787 -398.154184) (xy 371.221204 -398.146953) (xy 371.176288 -398.132638)
			(xy 371.134111 -398.111581) (xy 371.095677 -398.084284) (xy 371.061902 -398.051396) (xy 371.033592 -398.013702)
			(xy 371.022118 -397.993108) (xy 371.02161 -397.992346) (xy 370.623846 -397.304006) (xy 370.611969 -397.28133)
			(xy 370.595119 -397.232996) (xy 370.586546 -397.182533) (xy 370.586 -397.15694) (xy 354.671418 -397.15694)
			(xy 354.983542 -397.696944) (xy 354.996349 -397.720286) (xy 355.014576 -397.770304) (xy 355.023843 -397.822727)
			(xy 355.024436 -397.849344) (xy 355.023979 -397.873322) (xy 355.016475 -397.920688) (xy 355.001659 -397.966299)
			(xy 354.979895 -398.009033) (xy 354.951717 -398.047839) (xy 354.91782 -398.081762) (xy 354.879036 -398.10997)
			(xy 354.836319 -398.131768) (xy 354.79072 -398.14662) (xy 354.74336 -398.15416) (xy 354.719382 -398.154652)
			(xy 354.718874 -398.154652) (xy 354.695301 -398.154252) (xy 354.648714 -398.147008) (xy 354.603797 -398.132681)
			(xy 354.56162 -398.111613) (xy 354.523187 -398.084305) (xy 354.489414 -398.051408) (xy 354.461106 -398.013706)
			(xy 354.449634 -397.993108) (xy 354.449126 -397.992346) (xy 354.051362 -397.304006) (xy 354.039486 -397.281329)
			(xy 354.022635 -397.232996) (xy 354.014062 -397.182533) (xy 354.013516 -397.15694) (xy 353.471268 -397.15694)
			(xy 353.783392 -397.696944) (xy 353.796106 -397.720272) (xy 353.814207 -397.770215) (xy 353.823431 -397.82253)
			(xy 353.824032 -397.84909) (xy 353.824032 -397.849344) (xy 353.823578 -397.873335) (xy 353.816066 -397.920726)
			(xy 353.801234 -397.966359) (xy 353.779447 -398.00911) (xy 353.751242 -398.047927) (xy 353.717312 -398.081855)
			(xy 353.678493 -398.110058) (xy 353.63574 -398.131842) (xy 353.590107 -398.146671) (xy 353.542715 -398.15418)
			(xy 353.518724 -398.154652) (xy 353.495152 -398.154211) (xy 353.448567 -398.146975) (xy 353.403651 -398.132656)
			(xy 353.361474 -398.111594) (xy 353.323041 -398.084292) (xy 353.289267 -398.051401) (xy 353.260957 -398.013704)
			(xy 353.249484 -397.993108) (xy 353.248976 -397.992346) (xy 352.851212 -397.304006) (xy 352.839298 -397.281337)
			(xy 352.82236 -397.233012) (xy 352.8137 -397.182542) (xy 352.813112 -397.15694) (xy 352.271372 -397.15694)
			(xy 352.583496 -397.696944) (xy 352.59621 -397.720271) (xy 352.614311 -397.770215) (xy 352.623535 -397.82253)
			(xy 352.624136 -397.84909) (xy 352.624136 -397.849344) (xy 352.623678 -397.873335) (xy 352.616166 -397.920726)
			(xy 352.601335 -397.966358) (xy 352.579548 -398.009109) (xy 352.551343 -398.047926) (xy 352.517413 -398.081853)
			(xy 352.478595 -398.110056) (xy 352.435843 -398.131841) (xy 352.39021 -398.14667) (xy 352.342819 -398.154179)
			(xy 352.318828 -398.154652) (xy 352.295256 -398.154208) (xy 352.248672 -398.146972) (xy 352.203756 -398.132653)
			(xy 352.161578 -398.111592) (xy 352.123145 -398.084291) (xy 352.089371 -398.0514) (xy 352.061061 -398.013704)
			(xy 352.049588 -397.993108) (xy 352.04908 -397.992346) (xy 351.651316 -397.304006) (xy 351.639402 -397.281337)
			(xy 351.622464 -397.233012) (xy 351.613804 -397.182542) (xy 351.613216 -397.15694) (xy 351.071222 -397.15694)
			(xy 351.383346 -397.696944) (xy 351.396153 -397.720286) (xy 351.41438 -397.770304) (xy 351.423647 -397.822727)
			(xy 351.42424 -397.849344) (xy 351.423779 -397.873322) (xy 351.416275 -397.920688) (xy 351.401459 -397.966298)
			(xy 351.379695 -398.009032) (xy 351.351518 -398.047837) (xy 351.317622 -398.081761) (xy 351.278838 -398.109969)
			(xy 351.236122 -398.131767) (xy 351.190524 -398.146619) (xy 351.143164 -398.15416) (xy 351.119186 -398.154652)
			(xy 351.118678 -398.154652) (xy 351.095105 -398.154249) (xy 351.048518 -398.147005) (xy 351.003601 -398.132679)
			(xy 350.961424 -398.111611) (xy 350.922991 -398.084304) (xy 350.889218 -398.051408) (xy 350.86091 -398.013706)
			(xy 350.849438 -397.993108) (xy 350.84893 -397.992346) (xy 350.451166 -397.304006) (xy 350.439291 -397.281329)
			(xy 350.422439 -397.232996) (xy 350.413866 -397.182533) (xy 350.41332 -397.15694) (xy 349.871326 -397.15694)
			(xy 350.18345 -397.696944) (xy 350.196257 -397.720285) (xy 350.214484 -397.770304) (xy 350.223751 -397.822726)
			(xy 350.224344 -397.849344) (xy 350.223879 -397.873322) (xy 350.216376 -397.920687) (xy 350.20156 -397.966297)
			(xy 350.179796 -398.00903) (xy 350.15162 -398.047836) (xy 350.117723 -398.08176) (xy 350.07894 -398.109967)
			(xy 350.036225 -398.131765) (xy 349.990627 -398.146618) (xy 349.943268 -398.15416) (xy 349.91929 -398.154652)
			(xy 349.918782 -398.154652) (xy 349.895209 -398.154245) (xy 349.848622 -398.147003) (xy 349.803706 -398.132677)
			(xy 349.761528 -398.11161) (xy 349.723095 -398.084303) (xy 349.689323 -398.051407) (xy 349.661014 -398.013706)
			(xy 349.649542 -397.993108) (xy 349.649034 -397.992346) (xy 349.25127 -397.304006) (xy 349.239395 -397.281329)
			(xy 349.222543 -397.232996) (xy 349.21397 -397.182533) (xy 349.213424 -397.15694) (xy 348.67143 -397.15694)
			(xy 348.983554 -397.696944) (xy 348.996362 -397.720285) (xy 349.014588 -397.770304) (xy 349.023855 -397.822726)
			(xy 349.024448 -397.849344) (xy 349.023979 -397.873322) (xy 349.016476 -397.920687) (xy 349.00166 -397.966296)
			(xy 348.979897 -398.009029) (xy 348.951721 -398.047835) (xy 348.917825 -398.081758) (xy 348.879043 -398.109966)
			(xy 348.836328 -398.131764) (xy 348.79073 -398.146617) (xy 348.743371 -398.154159) (xy 348.719394 -398.154652)
			(xy 348.718886 -398.154652) (xy 348.695313 -398.154242) (xy 348.648727 -398.147) (xy 348.60381 -398.132675)
			(xy 348.561633 -398.111608) (xy 348.5232 -398.084302) (xy 348.489427 -398.051406) (xy 348.461119 -398.013705)
			(xy 348.449646 -397.993108) (xy 348.449138 -397.992346) (xy 348.051374 -397.304006) (xy 348.039499 -397.281329)
			(xy 348.022648 -397.232996) (xy 348.014074 -397.182533) (xy 348.013528 -397.15694) (xy 347.47128 -397.15694)
			(xy 347.783404 -397.696944) (xy 347.796119 -397.720271) (xy 347.81422 -397.770214) (xy 347.823443 -397.82253)
			(xy 347.824044 -397.84909) (xy 347.824044 -397.849344) (xy 347.823578 -397.873335) (xy 347.816067 -397.920724)
			(xy 347.801235 -397.966356) (xy 347.779449 -398.009106) (xy 347.751245 -398.047923) (xy 347.717317 -398.08185)
			(xy 347.678499 -398.110054) (xy 347.635749 -398.131838) (xy 347.590117 -398.146668) (xy 347.542727 -398.154179)
			(xy 347.518736 -398.154652) (xy 347.495164 -398.154202) (xy 347.44858 -398.146967) (xy 347.403664 -398.132649)
			(xy 347.361487 -398.111589) (xy 347.323053 -398.084289) (xy 347.289279 -398.051399) (xy 347.260969 -398.013703)
			(xy 347.249496 -397.993108) (xy 347.248988 -397.992346) (xy 346.851224 -397.304006) (xy 346.839311 -397.281337)
			(xy 346.822372 -397.233012) (xy 346.813712 -397.182542) (xy 346.813124 -397.15694) (xy 346.271384 -397.15694)
			(xy 346.583508 -397.696944) (xy 346.596223 -397.720271) (xy 346.614324 -397.770214) (xy 346.623547 -397.82253)
			(xy 346.624148 -397.84909) (xy 346.624148 -397.849344) (xy 346.623678 -397.873334) (xy 346.616167 -397.920724)
			(xy 346.601336 -397.966355) (xy 346.57955 -398.009105) (xy 346.551346 -398.047922) (xy 346.517418 -398.081849)
			(xy 346.478602 -398.110052) (xy 346.435851 -398.131837) (xy 346.39022 -398.146668) (xy 346.34283 -398.154178)
			(xy 346.31884 -398.154652) (xy 346.295269 -398.154199) (xy 346.248684 -398.146965) (xy 346.203769 -398.132647)
			(xy 346.161591 -398.111588) (xy 346.123158 -398.084288) (xy 346.089383 -398.051399) (xy 346.061073 -398.013703)
			(xy 346.0496 -397.993108) (xy 346.049092 -397.992346) (xy 345.651328 -397.304006) (xy 345.639415 -397.281337)
			(xy 345.622476 -397.233012) (xy 345.613816 -397.182542) (xy 345.613228 -397.15694) (xy 345.071234 -397.15694)
			(xy 345.383358 -397.696944) (xy 345.396166 -397.720285) (xy 345.414392 -397.770304) (xy 345.423659 -397.822726)
			(xy 345.424252 -397.849344) (xy 345.423779 -397.873322) (xy 345.416276 -397.920686) (xy 345.401461 -397.966295)
			(xy 345.379698 -398.009028) (xy 345.351522 -398.047833) (xy 345.317627 -398.081757) (xy 345.278845 -398.109965)
			(xy 345.23613 -398.131763) (xy 345.190533 -398.146616) (xy 345.143175 -398.154159) (xy 345.119198 -398.154652)
			(xy 345.11869 -398.154652) (xy 345.095117 -398.154239) (xy 345.048531 -398.146997) (xy 345.003614 -398.132673)
			(xy 344.961437 -398.111607) (xy 344.923004 -398.084301) (xy 344.889231 -398.051406) (xy 344.860923 -398.013705)
			(xy 344.84945 -397.993108) (xy 344.848942 -397.992346) (xy 344.451178 -397.304006) (xy 344.439303 -397.281328)
			(xy 344.422452 -397.232996) (xy 344.413878 -397.182533) (xy 344.413332 -397.15694) (xy 343.871338 -397.15694)
			(xy 344.183462 -397.696944) (xy 344.19627 -397.720285) (xy 344.214496 -397.770304) (xy 344.223763 -397.822726)
			(xy 344.224356 -397.849344) (xy 344.223879 -397.873321) (xy 344.216376 -397.920686) (xy 344.201561 -397.966295)
			(xy 344.179798 -398.009027) (xy 344.151623 -398.047832) (xy 344.117728 -398.081755) (xy 344.078947 -398.109963)
			(xy 344.036233 -398.131762) (xy 343.990637 -398.146616) (xy 343.943279 -398.154159) (xy 343.919302 -398.154652)
			(xy 343.918794 -398.154652) (xy 343.895221 -398.154236) (xy 343.848635 -398.146995) (xy 343.803719 -398.132671)
			(xy 343.761541 -398.111605) (xy 343.723108 -398.0843) (xy 343.689335 -398.051405) (xy 343.661027 -398.013705)
			(xy 343.649554 -397.993108) (xy 343.649046 -397.992346) (xy 343.251282 -397.304006) (xy 343.239408 -397.281328)
			(xy 343.222556 -397.232996) (xy 343.213982 -397.182533) (xy 343.213436 -397.15694) (xy 342.671442 -397.15694)
			(xy 342.983566 -397.696944) (xy 342.996375 -397.720285) (xy 343.0146 -397.770303) (xy 343.023867 -397.822726)
			(xy 343.02446 -397.849344) (xy 343.024079 -397.873326) (xy 343.016573 -397.9207) (xy 343.001752 -397.966317)
			(xy 342.979981 -398.009055) (xy 342.951795 -398.047865) (xy 342.917888 -398.08179) (xy 342.879094 -398.109996)
			(xy 342.836367 -398.13179) (xy 342.790757 -398.146635) (xy 342.743388 -398.154166) (xy 342.719406 -398.154652)
			(xy 342.718898 -398.154652) (xy 342.695325 -398.154232) (xy 342.64874 -398.146992) (xy 342.603823 -398.132669)
			(xy 342.561646 -398.111604) (xy 342.523213 -398.084299) (xy 342.489439 -398.051405) (xy 342.461131 -398.013705)
			(xy 342.449658 -397.993108) (xy 342.44915 -397.992346) (xy 342.051386 -397.304006) (xy 342.039512 -397.281328)
			(xy 342.02266 -397.232996) (xy 342.014086 -397.182533) (xy 342.01354 -397.15694) (xy 341.471292 -397.15694)
			(xy 341.783416 -397.696944) (xy 341.796132 -397.720271) (xy 341.814232 -397.770214) (xy 341.823455 -397.82253)
			(xy 341.824056 -397.84909) (xy 341.824056 -397.849344) (xy 341.823578 -397.873334) (xy 341.816067 -397.920723)
			(xy 341.801236 -397.966353) (xy 341.779452 -398.009103) (xy 341.751249 -398.047919) (xy 341.717322 -398.081846)
			(xy 341.678506 -398.11005) (xy 341.635757 -398.131835) (xy 341.590127 -398.146666) (xy 341.542738 -398.154178)
			(xy 341.518748 -398.154652) (xy 341.495177 -398.154192) (xy 341.448593 -398.146959) (xy 341.403677 -398.132643)
			(xy 341.3615 -398.111585) (xy 341.323066 -398.084286) (xy 341.289292 -398.051398) (xy 341.260982 -398.013703)
			(xy 341.249508 -397.993108) (xy 341.249 -397.992346) (xy 340.851236 -397.304006) (xy 340.839323 -397.281336)
			(xy 340.822384 -397.233012) (xy 340.813724 -397.182542) (xy 340.813136 -397.15694) (xy 340.271396 -397.15694)
			(xy 340.58352 -397.696944) (xy 340.596236 -397.72027) (xy 340.614336 -397.770214) (xy 340.623559 -397.82253)
			(xy 340.62416 -397.84909) (xy 340.62416 -397.849344) (xy 340.623802 -397.873341) (xy 340.616287 -397.920742)
			(xy 340.60145 -397.966385) (xy 340.579655 -398.009144) (xy 340.551439 -398.047968) (xy 340.517498 -398.081899)
			(xy 340.478666 -398.110103) (xy 340.4359 -398.131885) (xy 340.390253 -398.146709) (xy 340.342849 -398.154209)
			(xy 340.318852 -398.154652) (xy 340.295281 -398.154189) (xy 340.248697 -398.146957) (xy 340.203782 -398.132641)
			(xy 340.161604 -398.111583) (xy 340.123171 -398.084285) (xy 340.089396 -398.051397) (xy 340.061086 -398.013703)
			(xy 340.049612 -397.993108) (xy 340.049104 -397.992346) (xy 339.65134 -397.304006) (xy 339.639428 -397.281336)
			(xy 339.622488 -397.233012) (xy 339.613828 -397.182542) (xy 339.61324 -397.15694) (xy 339.071246 -397.15694)
			(xy 339.38337 -397.696944) (xy 339.396179 -397.720285) (xy 339.414404 -397.770303) (xy 339.423671 -397.822726)
			(xy 339.424264 -397.849344) (xy 339.423879 -397.873326) (xy 339.416373 -397.920699) (xy 339.401552 -397.966316)
			(xy 339.379781 -398.009054) (xy 339.351596 -398.047863) (xy 339.31769 -398.081788) (xy 339.278896 -398.109994)
			(xy 339.236169 -398.131788) (xy 339.190561 -398.146634) (xy 339.143192 -398.154166) (xy 339.11921 -398.154652)
			(xy 339.118702 -398.154652) (xy 339.095129 -398.154229) (xy 339.048544 -398.14699) (xy 339.003627 -398.132667)
			(xy 338.96145 -398.111602) (xy 338.923017 -398.084298) (xy 338.889244 -398.051404) (xy 338.860935 -398.013705)
			(xy 338.849462 -397.993108) (xy 338.848954 -397.992346) (xy 338.45119 -397.304006) (xy 338.439316 -397.281328)
			(xy 338.422464 -397.232995) (xy 338.41389 -397.182533) (xy 338.413344 -397.15694) (xy 337.87135 -397.15694)
			(xy 338.183474 -397.696944) (xy 338.196283 -397.720284) (xy 338.214508 -397.770303) (xy 338.223775 -397.822726)
			(xy 338.224368 -397.849344) (xy 338.223979 -397.873326) (xy 338.216473 -397.920698) (xy 338.201652 -397.966315)
			(xy 338.179882 -398.009053) (xy 338.151697 -398.047862) (xy 338.117791 -398.081787) (xy 338.078998 -398.109993)
			(xy 338.036272 -398.131787) (xy 337.990664 -398.146633) (xy 337.943295 -398.154165) (xy 337.919314 -398.154652)
			(xy 337.918806 -398.154652) (xy 337.895234 -398.154226) (xy 337.848648 -398.146987) (xy 337.803732 -398.132665)
			(xy 337.761554 -398.111601) (xy 337.723121 -398.084297) (xy 337.689348 -398.051404) (xy 337.661039 -398.013705)
			(xy 337.649566 -397.993108) (xy 337.649058 -397.992346) (xy 337.251294 -397.304006) (xy 337.239421 -397.281328)
			(xy 337.222568 -397.232995) (xy 337.213994 -397.182532) (xy 337.213448 -397.15694) (xy 336.671454 -397.15694)
			(xy 336.983578 -397.696944) (xy 336.996388 -397.720284) (xy 337.014613 -397.770303) (xy 337.023879 -397.822726)
			(xy 337.024472 -397.849344) (xy 337.024079 -397.873326) (xy 337.016573 -397.920698) (xy 337.001753 -397.966314)
			(xy 336.979983 -398.009052) (xy 336.951799 -398.047861) (xy 336.917893 -398.081785) (xy 336.8791 -398.109992)
			(xy 336.836375 -398.131786) (xy 336.790767 -398.146632) (xy 336.743399 -398.154165) (xy 336.719418 -398.154652)
			(xy 336.71891 -398.154652) (xy 336.695338 -398.154223) (xy 336.648752 -398.146984) (xy 336.603836 -398.132663)
			(xy 336.561659 -398.111599) (xy 336.523225 -398.084296) (xy 336.489452 -398.051403) (xy 336.461143 -398.013704)
			(xy 336.44967 -397.993108) (xy 336.449162 -397.992346) (xy 336.051398 -397.304006) (xy 336.039525 -397.281328)
			(xy 336.022672 -397.232995) (xy 336.014098 -397.182532) (xy 336.013552 -397.15694) (xy 322.14367 -397.15694)
			(xy 322.455794 -397.696944) (xy 322.468605 -397.720283) (xy 322.486829 -397.770303) (xy 322.496095 -397.822726)
			(xy 322.496688 -397.849344) (xy 322.496279 -397.873325) (xy 322.488774 -397.920695) (xy 322.473954 -397.96631)
			(xy 322.452186 -398.009047) (xy 322.424003 -398.047855) (xy 322.3901 -398.08178) (xy 322.351309 -398.109986)
			(xy 322.308586 -398.131782) (xy 322.26298 -398.146629) (xy 322.215614 -398.154164) (xy 322.191634 -398.154652)
			(xy 322.191126 -398.154652) (xy 322.167554 -398.15421) (xy 322.120969 -398.146974) (xy 322.076053 -398.132654)
			(xy 322.033876 -398.111593) (xy 321.995443 -398.084292) (xy 321.961669 -398.051401) (xy 321.933359 -398.013704)
			(xy 321.921886 -397.993108) (xy 321.921378 -397.992346) (xy 321.523614 -397.304006) (xy 321.511735 -397.281331)
			(xy 321.494886 -397.232997) (xy 321.486314 -397.182533) (xy 321.485768 -397.15694) (xy 320.94352 -397.15694)
			(xy 321.255644 -397.696944) (xy 321.268362 -397.720269) (xy 321.286461 -397.770214) (xy 321.295683 -397.82253)
			(xy 321.296284 -397.84909) (xy 321.296284 -397.849344) (xy 321.295878 -397.873338) (xy 321.288364 -397.920733)
			(xy 321.27353 -397.96637) (xy 321.251738 -398.009124) (xy 321.223528 -398.047943) (xy 321.189592 -398.081872)
			(xy 321.150766 -398.110074) (xy 321.108007 -398.131856) (xy 321.062367 -398.14668) (xy 321.01497 -398.154183)
			(xy 320.990976 -398.154652) (xy 320.967403 -398.15425) (xy 320.920816 -398.147007) (xy 320.875899 -398.13268)
			(xy 320.833722 -398.111612) (xy 320.795289 -398.084305) (xy 320.761516 -398.051408) (xy 320.733208 -398.013706)
			(xy 320.721736 -397.993108) (xy 320.721228 -397.992346) (xy 320.323464 -397.304006) (xy 320.311554 -397.281335)
			(xy 320.294614 -397.233011) (xy 320.285952 -397.182542) (xy 320.285364 -397.15694) (xy 319.743624 -397.15694)
			(xy 320.055748 -397.696944) (xy 320.068467 -397.720269) (xy 320.086565 -397.770214) (xy 320.095787 -397.82253)
			(xy 320.096388 -397.84909) (xy 320.096388 -397.849344) (xy 320.095978 -397.873337) (xy 320.088465 -397.920733)
			(xy 320.07363 -397.966369) (xy 320.051839 -398.009123) (xy 320.023629 -398.047942) (xy 319.989693 -398.08187)
			(xy 319.950868 -398.110073) (xy 319.90811 -398.131854) (xy 319.86247 -398.14668) (xy 319.815074 -398.154183)
			(xy 319.79108 -398.154652) (xy 319.767507 -398.154247) (xy 319.72092 -398.147004) (xy 319.676003 -398.132678)
			(xy 319.633826 -398.111611) (xy 319.595393 -398.084304) (xy 319.561621 -398.051407) (xy 319.533312 -398.013706)
			(xy 319.52184 -397.993108) (xy 319.521332 -397.992346) (xy 319.123568 -397.304006) (xy 319.111658 -397.281335)
			(xy 319.094718 -397.233011) (xy 319.086056 -397.182542) (xy 319.085468 -397.15694) (xy 318.543474 -397.15694)
			(xy 318.855598 -397.696944) (xy 318.868401 -397.720288) (xy 318.88663 -397.770305) (xy 318.895899 -397.822727)
			(xy 318.896492 -397.849344) (xy 318.896079 -397.873325) (xy 318.888574 -397.920695) (xy 318.873755 -397.966309)
			(xy 318.851987 -398.009046) (xy 318.823804 -398.047854) (xy 318.789901 -398.081778) (xy 318.751112 -398.109985)
			(xy 318.708389 -398.13178) (xy 318.662784 -398.146628) (xy 318.615418 -398.154164) (xy 318.591438 -398.154652)
			(xy 318.59093 -398.154652) (xy 318.567358 -398.154207) (xy 318.520774 -398.146971) (xy 318.475858 -398.132652)
			(xy 318.43368 -398.111592) (xy 318.395247 -398.084291) (xy 318.361473 -398.0514) (xy 318.333163 -398.013704)
			(xy 318.32169 -397.993108) (xy 318.321182 -397.992346) (xy 317.923418 -397.304006) (xy 317.911539 -397.281331)
			(xy 317.89469 -397.232997) (xy 317.886118 -397.182533) (xy 317.885572 -397.15694) (xy 317.343578 -397.15694)
			(xy 317.655702 -397.696944) (xy 317.668505 -397.720288) (xy 317.686734 -397.770305) (xy 317.696003 -397.822727)
			(xy 317.696596 -397.849344) (xy 317.696179 -397.873324) (xy 317.688674 -397.920694) (xy 317.673855 -397.966308)
			(xy 317.652087 -398.009045) (xy 317.623906 -398.047852) (xy 317.590003 -398.081777) (xy 317.551214 -398.109984)
			(xy 317.508492 -398.131779) (xy 317.462887 -398.146628) (xy 317.415522 -398.154163) (xy 317.391542 -398.154652)
			(xy 317.391034 -398.154652) (xy 317.367462 -398.154203) (xy 317.320878 -398.146969) (xy 317.275962 -398.13265)
			(xy 317.233785 -398.11159) (xy 317.195351 -398.08429) (xy 317.161577 -398.0514) (xy 317.133267 -398.013703)
			(xy 317.121794 -397.993108) (xy 317.121286 -397.992346) (xy 316.723522 -397.304006) (xy 316.711643 -397.281331)
			(xy 316.694794 -397.232996) (xy 316.686222 -397.182533) (xy 316.685676 -397.15694) (xy 316.143682 -397.15694)
			(xy 316.455806 -397.696944) (xy 316.46861 -397.720287) (xy 316.486838 -397.770304) (xy 316.496107 -397.822727)
			(xy 316.4967 -397.849344) (xy 316.496279 -397.873324) (xy 316.488774 -397.920694) (xy 316.473956 -397.966307)
			(xy 316.452188 -398.009044) (xy 316.424007 -398.047851) (xy 316.390105 -398.081775) (xy 316.351316 -398.109982)
			(xy 316.308594 -398.131778) (xy 316.26299 -398.146627) (xy 316.215626 -398.154163) (xy 316.191646 -398.154652)
			(xy 316.191138 -398.154652) (xy 316.167566 -398.1542) (xy 316.120982 -398.146966) (xy 316.076066 -398.132648)
			(xy 316.033889 -398.111589) (xy 315.995456 -398.084289) (xy 315.961681 -398.051399) (xy 315.933371 -398.013703)
			(xy 315.921898 -397.993108) (xy 315.92139 -397.992346) (xy 315.523626 -397.304006) (xy 315.511747 -397.28133)
			(xy 315.494898 -397.232996) (xy 315.486326 -397.182533) (xy 315.48578 -397.15694) (xy 314.943532 -397.15694)
			(xy 315.255656 -397.696944) (xy 315.268375 -397.720269) (xy 315.286473 -397.770214) (xy 315.295695 -397.822529)
			(xy 315.296296 -397.84909) (xy 315.296296 -397.849344) (xy 315.295878 -397.873337) (xy 315.288365 -397.920731)
			(xy 315.273531 -397.966367) (xy 315.251741 -398.009121) (xy 315.223531 -398.047939) (xy 315.189597 -398.081868)
			(xy 315.150773 -398.11007) (xy 315.108015 -398.131852) (xy 315.062377 -398.146678) (xy 315.014981 -398.154182)
			(xy 314.990988 -398.154652) (xy 314.967415 -398.154241) (xy 314.920829 -398.146999) (xy 314.875912 -398.132674)
			(xy 314.833735 -398.111608) (xy 314.795302 -398.084301) (xy 314.761529 -398.051406) (xy 314.733221 -398.013705)
			(xy 314.721748 -397.993108) (xy 314.72124 -397.992346) (xy 314.323476 -397.304006) (xy 314.311559 -397.281339)
			(xy 314.294623 -397.233013) (xy 314.285963 -397.182542) (xy 314.285376 -397.15694) (xy 313.743636 -397.15694)
			(xy 314.05576 -397.696944) (xy 314.06848 -397.720269) (xy 314.086577 -397.770214) (xy 314.095799 -397.822529)
			(xy 314.0964 -397.84909) (xy 314.0964 -397.849344) (xy 314.095978 -397.873337) (xy 314.088465 -397.920731)
			(xy 314.073631 -397.966366) (xy 314.051841 -398.009119) (xy 314.023632 -398.047938) (xy 313.989698 -398.081866)
			(xy 313.950875 -398.110069) (xy 313.908118 -398.131851) (xy 313.86248 -398.146677) (xy 313.815085 -398.154182)
			(xy 313.791092 -398.154652) (xy 313.767519 -398.154237) (xy 313.720933 -398.146996) (xy 313.676016 -398.132672)
			(xy 313.633839 -398.111606) (xy 313.595406 -398.0843) (xy 313.561633 -398.051406) (xy 313.533325 -398.013705)
			(xy 313.521852 -397.993108) (xy 313.521344 -397.992346) (xy 313.12358 -397.304006) (xy 313.111663 -397.281339)
			(xy 313.094727 -397.233013) (xy 313.086067 -397.182542) (xy 313.08548 -397.15694) (xy 312.543486 -397.15694)
			(xy 312.85561 -397.696944) (xy 312.868414 -397.720287) (xy 312.886643 -397.770304) (xy 312.895911 -397.822727)
			(xy 312.896504 -397.849344) (xy 312.896079 -397.873324) (xy 312.888574 -397.920693) (xy 312.873756 -397.966307)
			(xy 312.851989 -398.009042) (xy 312.823808 -398.04785) (xy 312.789906 -398.081774) (xy 312.751118 -398.109981)
			(xy 312.708397 -398.131777) (xy 312.662794 -398.146626) (xy 312.61543 -398.154163) (xy 312.59145 -398.154652)
			(xy 312.590942 -398.154652) (xy 312.567371 -398.154197) (xy 312.520786 -398.146963) (xy 312.475871 -398.132646)
			(xy 312.433693 -398.111587) (xy 312.39526 -398.084288) (xy 312.361486 -398.051398) (xy 312.333176 -398.013703)
			(xy 312.321702 -397.993108) (xy 312.321194 -397.992346) (xy 311.92343 -397.304006) (xy 311.911552 -397.28133)
			(xy 311.894702 -397.232996) (xy 311.88613 -397.182533) (xy 311.885584 -397.15694) (xy 311.34359 -397.15694)
			(xy 311.655714 -397.696944) (xy 311.668518 -397.720287) (xy 311.686747 -397.770304) (xy 311.696015 -397.822727)
			(xy 311.696608 -397.849344) (xy 311.696179 -397.873324) (xy 311.688674 -397.920693) (xy 311.673856 -397.966306)
			(xy 311.652089 -398.009041) (xy 311.623909 -398.047848) (xy 311.590008 -398.081772) (xy 311.55122 -398.10998)
			(xy 311.5085 -398.131776) (xy 311.462897 -398.146625) (xy 311.415533 -398.154162) (xy 311.391554 -398.154652)
			(xy 311.391046 -398.154652) (xy 311.367475 -398.154194) (xy 311.320891 -398.146961) (xy 311.275975 -398.132644)
			(xy 311.233798 -398.111586) (xy 311.195364 -398.084287) (xy 311.16159 -398.051398) (xy 311.13328 -398.013703)
			(xy 311.121806 -397.993108) (xy 311.121298 -397.992346) (xy 310.723534 -397.304006) (xy 310.711656 -397.28133)
			(xy 310.694806 -397.232996) (xy 310.686234 -397.182533) (xy 310.685688 -397.15694) (xy 310.143694 -397.15694)
			(xy 310.455818 -397.696944) (xy 310.468623 -397.720287) (xy 310.486851 -397.770304) (xy 310.496119 -397.822727)
			(xy 310.496712 -397.849344) (xy 310.496279 -397.873324) (xy 310.488774 -397.920692) (xy 310.473957 -397.966305)
			(xy 310.45219 -398.00904) (xy 310.42401 -398.047847) (xy 310.39011 -398.081771) (xy 310.351323 -398.109978)
			(xy 310.308603 -398.131775) (xy 310.263 -398.146624) (xy 310.215637 -398.154162) (xy 310.191658 -398.154652)
			(xy 310.19115 -398.154652) (xy 310.167579 -398.154191) (xy 310.120995 -398.146958) (xy 310.076079 -398.132642)
			(xy 310.033902 -398.111584) (xy 309.995468 -398.084286) (xy 309.961694 -398.051397) (xy 309.933384 -398.013703)
			(xy 309.92191 -397.993108) (xy 309.921402 -397.992346) (xy 309.523638 -397.304006) (xy 309.51176 -397.28133)
			(xy 309.494911 -397.232996) (xy 309.486338 -397.182533) (xy 309.485792 -397.15694) (xy 308.943544 -397.15694)
			(xy 309.255668 -397.696944) (xy 309.268388 -397.720268) (xy 309.286486 -397.770213) (xy 309.295708 -397.822529)
			(xy 309.296308 -397.84909) (xy 309.296308 -397.849344) (xy 309.295878 -397.873336) (xy 309.288365 -397.92073)
			(xy 309.273532 -397.966364) (xy 309.251743 -398.009117) (xy 309.223535 -398.047935) (xy 309.189602 -398.081863)
			(xy 309.150779 -398.110066) (xy 309.108024 -398.131849) (xy 309.062387 -398.146676) (xy 309.014992 -398.154181)
			(xy 308.991 -398.154652) (xy 308.967427 -398.154231) (xy 308.920842 -398.146991) (xy 308.875925 -398.132668)
			(xy 308.833748 -398.111603) (xy 308.795315 -398.084298) (xy 308.761542 -398.051404) (xy 308.733233 -398.013705)
			(xy 308.72176 -397.993108) (xy 308.721252 -397.992346) (xy 308.323488 -397.304006) (xy 308.311572 -397.281338)
			(xy 308.294635 -397.233013) (xy 308.285975 -397.182542) (xy 308.285388 -397.15694) (xy 307.743648 -397.15694)
			(xy 308.055772 -397.696944) (xy 308.068493 -397.720268) (xy 308.08659 -397.770213) (xy 308.095812 -397.822529)
			(xy 308.096412 -397.84909) (xy 308.096412 -397.849344) (xy 308.095978 -397.873336) (xy 308.088465 -397.920729)
			(xy 308.073632 -397.966363) (xy 308.051844 -398.009116) (xy 308.023636 -398.047934) (xy 307.989703 -398.081862)
			(xy 307.950882 -398.110065) (xy 307.908126 -398.131848) (xy 307.86249 -398.146675) (xy 307.815096 -398.154181)
			(xy 307.791104 -398.154652) (xy 307.767532 -398.154228) (xy 307.720946 -398.146988) (xy 307.676029 -398.132666)
			(xy 307.633852 -398.111602) (xy 307.595419 -398.084297) (xy 307.561646 -398.051404) (xy 307.533337 -398.013705)
			(xy 307.521864 -397.993108) (xy 307.521356 -397.992346) (xy 307.123592 -397.304006) (xy 307.111676 -397.281338)
			(xy 307.094739 -397.233012) (xy 307.086079 -397.182542) (xy 307.085492 -397.15694) (xy 306.543498 -397.15694)
			(xy 306.855622 -397.696944) (xy 306.868427 -397.720287) (xy 306.886655 -397.770304) (xy 306.895923 -397.822727)
			(xy 306.896516 -397.849344) (xy 306.896079 -397.873323) (xy 306.888575 -397.920691) (xy 306.873757 -397.966304)
			(xy 306.851991 -398.009039) (xy 306.823811 -398.047846) (xy 306.789912 -398.08177) (xy 306.751125 -398.109977)
			(xy 306.708405 -398.131773) (xy 306.662804 -398.146624) (xy 306.615441 -398.154162) (xy 306.591462 -398.154652)
			(xy 306.590954 -398.154652) (xy 306.567383 -398.154187) (xy 306.520799 -398.146955) (xy 306.475884 -398.13264)
			(xy 306.433706 -398.111583) (xy 306.395273 -398.084285) (xy 306.361498 -398.051397) (xy 306.333188 -398.013702)
			(xy 306.321714 -397.993108) (xy 306.321206 -397.992346) (xy 305.923442 -397.304006) (xy 305.911565 -397.28133)
			(xy 305.894715 -397.232996) (xy 305.886142 -397.182533) (xy 305.885596 -397.15694) (xy 305.343602 -397.15694)
			(xy 305.655726 -397.696944) (xy 305.668531 -397.720286) (xy 305.686759 -397.770304) (xy 305.696027 -397.822727)
			(xy 305.69662 -397.849344) (xy 305.696179 -397.873323) (xy 305.688675 -397.920691) (xy 305.673857 -397.966303)
			(xy 305.652092 -398.009038) (xy 305.623913 -398.047844) (xy 305.590013 -398.081768) (xy 305.551227 -398.109975)
			(xy 305.508508 -398.131772) (xy 305.462907 -398.146623) (xy 305.415545 -398.154162) (xy 305.391566 -398.154652)
			(xy 305.391058 -398.154652) (xy 305.367487 -398.154184) (xy 305.320904 -398.146953) (xy 305.275988 -398.132638)
			(xy 305.233811 -398.111581) (xy 305.195377 -398.084284) (xy 305.161602 -398.051396) (xy 305.133292 -398.013702)
			(xy 305.121818 -397.993108) (xy 305.12131 -397.992346) (xy 304.723546 -397.304006) (xy 304.711669 -397.28133)
			(xy 304.694819 -397.232996) (xy 304.686246 -397.182533) (xy 304.6857 -397.15694) (xy 304.143706 -397.15694)
			(xy 304.45583 -397.696944) (xy 304.468636 -397.720286) (xy 304.486863 -397.770304) (xy 304.496131 -397.822727)
			(xy 304.496724 -397.849344) (xy 304.496279 -397.873323) (xy 304.488775 -397.92069) (xy 304.473958 -397.966302)
			(xy 304.452192 -398.009036) (xy 304.424014 -398.047843) (xy 304.390115 -398.081767) (xy 304.351329 -398.109974)
			(xy 304.308611 -398.131771) (xy 304.26301 -398.146622) (xy 304.215649 -398.154161) (xy 304.19167 -398.154652)
			(xy 304.191162 -398.154652) (xy 304.167591 -398.154181) (xy 304.121008 -398.14695) (xy 304.076092 -398.132636)
			(xy 304.033915 -398.11158) (xy 303.995481 -398.084283) (xy 303.961707 -398.051396) (xy 303.933396 -398.013702)
			(xy 303.921922 -397.993108) (xy 303.921414 -397.992346) (xy 303.52365 -397.304006) (xy 303.511773 -397.281329)
			(xy 303.494923 -397.232996) (xy 303.48635 -397.182533) (xy 303.485804 -397.15694) (xy 280.68524 -397.15694)
			(xy 280.68524 -401.674838) (xy 303.434496 -401.674838) (xy 303.434496 -400.811238) (xy 303.434982 -400.783969)
			(xy 303.442744 -400.729985) (xy 303.458109 -400.677655) (xy 303.480766 -400.628045) (xy 303.510252 -400.582164)
			(xy 303.545967 -400.540947) (xy 303.587184 -400.505232) (xy 303.633065 -400.475746) (xy 303.682675 -400.453089)
			(xy 303.735005 -400.437724) (xy 303.788989 -400.429962) (xy 303.843527 -400.429962) (xy 303.897511 -400.437724)
			(xy 303.949841 -400.453089) (xy 303.999451 -400.475746) (xy 304.045332 -400.505232) (xy 304.086549 -400.540947)
			(xy 304.122264 -400.582164) (xy 304.15175 -400.628045) (xy 304.174407 -400.677655) (xy 304.189772 -400.729985)
			(xy 304.197534 -400.783969) (xy 304.19802 -400.811238) (xy 304.19802 -401.674838) (xy 304.634392 -401.674838)
			(xy 304.634392 -400.811238) (xy 304.634878 -400.783969) (xy 304.64264 -400.729985) (xy 304.658005 -400.677655)
			(xy 304.680662 -400.628045) (xy 304.710148 -400.582164) (xy 304.745863 -400.540947) (xy 304.78708 -400.505232)
			(xy 304.832961 -400.475746) (xy 304.882571 -400.453089) (xy 304.934901 -400.437724) (xy 304.988885 -400.429962)
			(xy 305.043423 -400.429962) (xy 305.097407 -400.437724) (xy 305.149737 -400.453089) (xy 305.199347 -400.475746)
			(xy 305.245228 -400.505232) (xy 305.286445 -400.540947) (xy 305.32216 -400.582164) (xy 305.351646 -400.628045)
			(xy 305.374303 -400.677655) (xy 305.389668 -400.729985) (xy 305.39743 -400.783969) (xy 305.397916 -400.811238)
			(xy 305.397916 -401.674838) (xy 305.834796 -401.674838) (xy 305.834796 -400.811238) (xy 305.835282 -400.783987)
			(xy 305.843038 -400.730039) (xy 305.858393 -400.677744) (xy 305.881035 -400.628167) (xy 305.910501 -400.582317)
			(xy 305.946192 -400.541126) (xy 305.987383 -400.505435) (xy 306.033233 -400.475969) (xy 306.08281 -400.453327)
			(xy 306.135105 -400.437972) (xy 306.189053 -400.430216) (xy 306.243555 -400.430216) (xy 306.297503 -400.437972)
			(xy 306.349798 -400.453327) (xy 306.399375 -400.475969) (xy 306.445225 -400.505435) (xy 306.486416 -400.541126)
			(xy 306.522107 -400.582317) (xy 306.551573 -400.628167) (xy 306.574215 -400.677744) (xy 306.58957 -400.730039)
			(xy 306.597326 -400.783987) (xy 306.597812 -400.811238) (xy 306.597812 -401.674838) (xy 307.034692 -401.674838)
			(xy 307.034692 -400.811238) (xy 307.035178 -400.783987) (xy 307.042934 -400.730039) (xy 307.058289 -400.677744)
			(xy 307.080931 -400.628167) (xy 307.110397 -400.582317) (xy 307.146088 -400.541126) (xy 307.187279 -400.505435)
			(xy 307.233129 -400.475969) (xy 307.282706 -400.453327) (xy 307.335001 -400.437972) (xy 307.388949 -400.430216)
			(xy 307.443451 -400.430216) (xy 307.497399 -400.437972) (xy 307.549694 -400.453327) (xy 307.599271 -400.475969)
			(xy 307.645121 -400.505435) (xy 307.686312 -400.541126) (xy 307.722003 -400.582317) (xy 307.751469 -400.628167)
			(xy 307.774111 -400.677744) (xy 307.789466 -400.730039) (xy 307.797222 -400.783987) (xy 307.797708 -400.811238)
			(xy 307.797708 -401.674838) (xy 308.234588 -401.674838) (xy 308.234588 -400.811238) (xy 308.235074 -400.783969)
			(xy 308.242836 -400.729985) (xy 308.258201 -400.677655) (xy 308.280858 -400.628045) (xy 308.310344 -400.582164)
			(xy 308.346059 -400.540947) (xy 308.387276 -400.505232) (xy 308.433157 -400.475746) (xy 308.482767 -400.453089)
			(xy 308.535097 -400.437724) (xy 308.589081 -400.429962) (xy 308.643619 -400.429962) (xy 308.697603 -400.437724)
			(xy 308.749933 -400.453089) (xy 308.799543 -400.475746) (xy 308.845424 -400.505232) (xy 308.886641 -400.540947)
			(xy 308.922356 -400.582164) (xy 308.951842 -400.628045) (xy 308.974499 -400.677655) (xy 308.989864 -400.729985)
			(xy 308.997626 -400.783969) (xy 308.998112 -400.811238) (xy 308.998112 -401.674838) (xy 309.434484 -401.674838)
			(xy 309.434484 -400.811238) (xy 309.43497 -400.783969) (xy 309.442732 -400.729985) (xy 309.458097 -400.677655)
			(xy 309.480754 -400.628045) (xy 309.51024 -400.582164) (xy 309.545955 -400.540947) (xy 309.587172 -400.505232)
			(xy 309.633053 -400.475746) (xy 309.682663 -400.453089) (xy 309.734993 -400.437724) (xy 309.788977 -400.429962)
			(xy 309.843515 -400.429962) (xy 309.897499 -400.437724) (xy 309.949829 -400.453089) (xy 309.999439 -400.475746)
			(xy 310.04532 -400.505232) (xy 310.086537 -400.540947) (xy 310.122252 -400.582164) (xy 310.151738 -400.628045)
			(xy 310.174395 -400.677655) (xy 310.18976 -400.729985) (xy 310.197522 -400.783969) (xy 310.198008 -400.811238)
			(xy 310.198008 -401.674838) (xy 310.634888 -401.674838) (xy 310.634888 -400.811238) (xy 310.635374 -400.783987)
			(xy 310.64313 -400.730039) (xy 310.658485 -400.677744) (xy 310.681127 -400.628167) (xy 310.710593 -400.582317)
			(xy 310.746284 -400.541126) (xy 310.787475 -400.505435) (xy 310.833325 -400.475969) (xy 310.882902 -400.453327)
			(xy 310.935197 -400.437972) (xy 310.989145 -400.430216) (xy 311.043647 -400.430216) (xy 311.097595 -400.437972)
			(xy 311.14989 -400.453327) (xy 311.199467 -400.475969) (xy 311.245317 -400.505435) (xy 311.286508 -400.541126)
			(xy 311.322199 -400.582317) (xy 311.351665 -400.628167) (xy 311.374307 -400.677744) (xy 311.389662 -400.730039)
			(xy 311.397418 -400.783987) (xy 311.397904 -400.811238) (xy 311.397904 -401.674838) (xy 311.834784 -401.674838)
			(xy 311.834784 -400.811238) (xy 311.83527 -400.783987) (xy 311.843026 -400.730039) (xy 311.858381 -400.677744)
			(xy 311.881023 -400.628167) (xy 311.910489 -400.582317) (xy 311.94618 -400.541126) (xy 311.987371 -400.505435)
			(xy 312.033221 -400.475969) (xy 312.082798 -400.453327) (xy 312.135093 -400.437972) (xy 312.189041 -400.430216)
			(xy 312.243543 -400.430216) (xy 312.297491 -400.437972) (xy 312.349786 -400.453327) (xy 312.399363 -400.475969)
			(xy 312.445213 -400.505435) (xy 312.486404 -400.541126) (xy 312.522095 -400.582317) (xy 312.551561 -400.628167)
			(xy 312.574203 -400.677744) (xy 312.589558 -400.730039) (xy 312.597314 -400.783987) (xy 312.5978 -400.811238)
			(xy 312.5978 -401.674838) (xy 313.03468 -401.674838) (xy 313.03468 -400.811238) (xy 313.035166 -400.783969)
			(xy 313.042928 -400.729985) (xy 313.058293 -400.677655) (xy 313.08095 -400.628045) (xy 313.110436 -400.582164)
			(xy 313.146151 -400.540947) (xy 313.187368 -400.505232) (xy 313.233249 -400.475746) (xy 313.282859 -400.453089)
			(xy 313.335189 -400.437724) (xy 313.389173 -400.429962) (xy 313.443711 -400.429962) (xy 313.497695 -400.437724)
			(xy 313.550025 -400.453089) (xy 313.599635 -400.475746) (xy 313.645516 -400.505232) (xy 313.686733 -400.540947)
			(xy 313.722448 -400.582164) (xy 313.751934 -400.628045) (xy 313.774591 -400.677655) (xy 313.789956 -400.729985)
			(xy 313.797718 -400.783969) (xy 313.798204 -400.811238) (xy 313.798204 -401.674838) (xy 314.234576 -401.674838)
			(xy 314.234576 -400.811238) (xy 314.235062 -400.783969) (xy 314.242824 -400.729985) (xy 314.258189 -400.677655)
			(xy 314.280846 -400.628045) (xy 314.310332 -400.582164) (xy 314.346047 -400.540947) (xy 314.387264 -400.505232)
			(xy 314.433145 -400.475746) (xy 314.482755 -400.453089) (xy 314.535085 -400.437724) (xy 314.589069 -400.429962)
			(xy 314.643607 -400.429962) (xy 314.697591 -400.437724) (xy 314.749921 -400.453089) (xy 314.799531 -400.475746)
			(xy 314.845412 -400.505232) (xy 314.886629 -400.540947) (xy 314.922344 -400.582164) (xy 314.95183 -400.628045)
			(xy 314.974487 -400.677655) (xy 314.989852 -400.729985) (xy 314.997614 -400.783969) (xy 314.9981 -400.811238)
			(xy 314.9981 -401.674838) (xy 315.43498 -401.674838) (xy 315.43498 -400.811238) (xy 315.435466 -400.783987)
			(xy 315.443222 -400.730039) (xy 315.458577 -400.677744) (xy 315.481219 -400.628167) (xy 315.510685 -400.582317)
			(xy 315.546376 -400.541126) (xy 315.587567 -400.505435) (xy 315.633417 -400.475969) (xy 315.682994 -400.453327)
			(xy 315.735289 -400.437972) (xy 315.789237 -400.430216) (xy 315.843739 -400.430216) (xy 315.897687 -400.437972)
			(xy 315.949982 -400.453327) (xy 315.999559 -400.475969) (xy 316.045409 -400.505435) (xy 316.0866 -400.541126)
			(xy 316.122291 -400.582317) (xy 316.151757 -400.628167) (xy 316.174399 -400.677744) (xy 316.189754 -400.730039)
			(xy 316.19751 -400.783987) (xy 316.197996 -400.811238) (xy 316.197996 -401.674838) (xy 316.634876 -401.674838)
			(xy 316.634876 -400.811238) (xy 316.635362 -400.783987) (xy 316.643118 -400.730039) (xy 316.658473 -400.677744)
			(xy 316.681115 -400.628167) (xy 316.710581 -400.582317) (xy 316.746272 -400.541126) (xy 316.787463 -400.505435)
			(xy 316.833313 -400.475969) (xy 316.88289 -400.453327) (xy 316.935185 -400.437972) (xy 316.989133 -400.430216)
			(xy 317.043635 -400.430216) (xy 317.097583 -400.437972) (xy 317.149878 -400.453327) (xy 317.199455 -400.475969)
			(xy 317.245305 -400.505435) (xy 317.286496 -400.541126) (xy 317.322187 -400.582317) (xy 317.351653 -400.628167)
			(xy 317.374295 -400.677744) (xy 317.38965 -400.730039) (xy 317.397406 -400.783987) (xy 317.397892 -400.811238)
			(xy 317.397892 -401.674838) (xy 317.834772 -401.674838) (xy 317.834772 -400.811238) (xy 317.835258 -400.783987)
			(xy 317.843014 -400.730039) (xy 317.858369 -400.677744) (xy 317.881011 -400.628167) (xy 317.910477 -400.582317)
			(xy 317.946168 -400.541126) (xy 317.987359 -400.505435) (xy 318.033209 -400.475969) (xy 318.082786 -400.453327)
			(xy 318.135081 -400.437972) (xy 318.189029 -400.430216) (xy 318.243531 -400.430216) (xy 318.297479 -400.437972)
			(xy 318.349774 -400.453327) (xy 318.399351 -400.475969) (xy 318.445201 -400.505435) (xy 318.486392 -400.541126)
			(xy 318.522083 -400.582317) (xy 318.551549 -400.628167) (xy 318.574191 -400.677744) (xy 318.589546 -400.730039)
			(xy 318.597302 -400.783987) (xy 318.597788 -400.811238) (xy 318.597788 -401.674838) (xy 319.034668 -401.674838)
			(xy 319.034668 -400.811238) (xy 319.035154 -400.783987) (xy 319.04291 -400.730039) (xy 319.058265 -400.677744)
			(xy 319.080907 -400.628167) (xy 319.110373 -400.582317) (xy 319.146064 -400.541126) (xy 319.187255 -400.505435)
			(xy 319.233105 -400.475969) (xy 319.282682 -400.453327) (xy 319.334977 -400.437972) (xy 319.388925 -400.430216)
			(xy 319.443427 -400.430216) (xy 319.497375 -400.437972) (xy 319.54967 -400.453327) (xy 319.599247 -400.475969)
			(xy 319.645097 -400.505435) (xy 319.686288 -400.541126) (xy 319.721979 -400.582317) (xy 319.751445 -400.628167)
			(xy 319.774087 -400.677744) (xy 319.789442 -400.730039) (xy 319.797198 -400.783987) (xy 319.797684 -400.811238)
			(xy 319.797684 -401.674838) (xy 320.234564 -401.674838) (xy 320.234564 -400.811238) (xy 320.23505 -400.783969)
			(xy 320.242812 -400.729985) (xy 320.258177 -400.677655) (xy 320.280834 -400.628045) (xy 320.31032 -400.582164)
			(xy 320.346035 -400.540947) (xy 320.387252 -400.505232) (xy 320.433133 -400.475746) (xy 320.482743 -400.453089)
			(xy 320.535073 -400.437724) (xy 320.589057 -400.429962) (xy 320.643595 -400.429962) (xy 320.697579 -400.437724)
			(xy 320.749909 -400.453089) (xy 320.799519 -400.475746) (xy 320.8454 -400.505232) (xy 320.886617 -400.540947)
			(xy 320.922332 -400.582164) (xy 320.951818 -400.628045) (xy 320.974475 -400.677655) (xy 320.98984 -400.729985)
			(xy 320.997602 -400.783969) (xy 320.998088 -400.811238) (xy 320.998088 -401.674838) (xy 321.43446 -401.674838)
			(xy 321.43446 -400.811238) (xy 321.434946 -400.783969) (xy 321.442708 -400.729985) (xy 321.458073 -400.677655)
			(xy 321.48073 -400.628045) (xy 321.510216 -400.582164) (xy 321.545931 -400.540947) (xy 321.587148 -400.505232)
			(xy 321.633029 -400.475746) (xy 321.682639 -400.453089) (xy 321.734969 -400.437724) (xy 321.788953 -400.429962)
			(xy 321.843491 -400.429962) (xy 321.897475 -400.437724) (xy 321.949805 -400.453089) (xy 321.999415 -400.475746)
			(xy 322.045296 -400.505232) (xy 322.086513 -400.540947) (xy 322.122228 -400.582164) (xy 322.151714 -400.628045)
			(xy 322.174371 -400.677655) (xy 322.189736 -400.729985) (xy 322.197498 -400.783969) (xy 322.197984 -400.811238)
			(xy 322.197984 -401.674838) (xy 335.962244 -401.674838) (xy 335.962244 -400.811238) (xy 335.96273 -400.783969)
			(xy 335.970492 -400.729985) (xy 335.985857 -400.677655) (xy 336.008514 -400.628045) (xy 336.038 -400.582164)
			(xy 336.073715 -400.540947) (xy 336.114932 -400.505232) (xy 336.160813 -400.475746) (xy 336.210423 -400.453089)
			(xy 336.262753 -400.437724) (xy 336.316737 -400.429962) (xy 336.371275 -400.429962) (xy 336.425259 -400.437724)
			(xy 336.477589 -400.453089) (xy 336.527199 -400.475746) (xy 336.57308 -400.505232) (xy 336.614297 -400.540947)
			(xy 336.650012 -400.582164) (xy 336.679498 -400.628045) (xy 336.702155 -400.677655) (xy 336.71752 -400.729985)
			(xy 336.725282 -400.783969) (xy 336.725768 -400.811238) (xy 336.725768 -401.674838) (xy 337.16214 -401.674838)
			(xy 337.16214 -400.811238) (xy 337.162626 -400.783969) (xy 337.170388 -400.729985) (xy 337.185753 -400.677655)
			(xy 337.20841 -400.628045) (xy 337.237896 -400.582164) (xy 337.273611 -400.540947) (xy 337.314828 -400.505232)
			(xy 337.360709 -400.475746) (xy 337.410319 -400.453089) (xy 337.462649 -400.437724) (xy 337.516633 -400.429962)
			(xy 337.571171 -400.429962) (xy 337.625155 -400.437724) (xy 337.677485 -400.453089) (xy 337.727095 -400.475746)
			(xy 337.772976 -400.505232) (xy 337.814193 -400.540947) (xy 337.849908 -400.582164) (xy 337.879394 -400.628045)
			(xy 337.902051 -400.677655) (xy 337.917416 -400.729985) (xy 337.925178 -400.783969) (xy 337.925664 -400.811238)
			(xy 337.925664 -401.674838) (xy 338.362544 -401.674838) (xy 338.362544 -400.811238) (xy 338.36303 -400.783987)
			(xy 338.370786 -400.730039) (xy 338.386141 -400.677744) (xy 338.408783 -400.628167) (xy 338.438249 -400.582317)
			(xy 338.47394 -400.541126) (xy 338.515131 -400.505435) (xy 338.560981 -400.475969) (xy 338.610558 -400.453327)
			(xy 338.662853 -400.437972) (xy 338.716801 -400.430216) (xy 338.771303 -400.430216) (xy 338.825251 -400.437972)
			(xy 338.877546 -400.453327) (xy 338.927123 -400.475969) (xy 338.972973 -400.505435) (xy 339.014164 -400.541126)
			(xy 339.049855 -400.582317) (xy 339.079321 -400.628167) (xy 339.101963 -400.677744) (xy 339.117318 -400.730039)
			(xy 339.125074 -400.783987) (xy 339.12556 -400.811238) (xy 339.12556 -401.674838) (xy 339.56244 -401.674838)
			(xy 339.56244 -400.811238) (xy 339.562926 -400.783987) (xy 339.570682 -400.730039) (xy 339.586037 -400.677744)
			(xy 339.608679 -400.628167) (xy 339.638145 -400.582317) (xy 339.673836 -400.541126) (xy 339.715027 -400.505435)
			(xy 339.760877 -400.475969) (xy 339.810454 -400.453327) (xy 339.862749 -400.437972) (xy 339.916697 -400.430216)
			(xy 339.971199 -400.430216) (xy 340.025147 -400.437972) (xy 340.077442 -400.453327) (xy 340.127019 -400.475969)
			(xy 340.172869 -400.505435) (xy 340.21406 -400.541126) (xy 340.249751 -400.582317) (xy 340.279217 -400.628167)
			(xy 340.301859 -400.677744) (xy 340.317214 -400.730039) (xy 340.32497 -400.783987) (xy 340.325456 -400.811238)
			(xy 340.325456 -401.674838) (xy 340.762336 -401.674838) (xy 340.762336 -400.811238) (xy 340.762822 -400.783969)
			(xy 340.770584 -400.729985) (xy 340.785949 -400.677655) (xy 340.808606 -400.628045) (xy 340.838092 -400.582164)
			(xy 340.873807 -400.540947) (xy 340.915024 -400.505232) (xy 340.960905 -400.475746) (xy 341.010515 -400.453089)
			(xy 341.062845 -400.437724) (xy 341.116829 -400.429962) (xy 341.171367 -400.429962) (xy 341.225351 -400.437724)
			(xy 341.277681 -400.453089) (xy 341.327291 -400.475746) (xy 341.373172 -400.505232) (xy 341.414389 -400.540947)
			(xy 341.450104 -400.582164) (xy 341.47959 -400.628045) (xy 341.502247 -400.677655) (xy 341.517612 -400.729985)
			(xy 341.525374 -400.783969) (xy 341.52586 -400.811238) (xy 341.52586 -401.674838) (xy 341.962232 -401.674838)
			(xy 341.962232 -400.811238) (xy 341.962718 -400.783969) (xy 341.97048 -400.729985) (xy 341.985845 -400.677655)
			(xy 342.008502 -400.628045) (xy 342.037988 -400.582164) (xy 342.073703 -400.540947) (xy 342.11492 -400.505232)
			(xy 342.160801 -400.475746) (xy 342.210411 -400.453089) (xy 342.262741 -400.437724) (xy 342.316725 -400.429962)
			(xy 342.371263 -400.429962) (xy 342.425247 -400.437724) (xy 342.477577 -400.453089) (xy 342.527187 -400.475746)
			(xy 342.573068 -400.505232) (xy 342.614285 -400.540947) (xy 342.65 -400.582164) (xy 342.679486 -400.628045)
			(xy 342.702143 -400.677655) (xy 342.717508 -400.729985) (xy 342.72527 -400.783969) (xy 342.725756 -400.811238)
			(xy 342.725756 -401.674838) (xy 343.162636 -401.674838) (xy 343.162636 -400.811238) (xy 343.163122 -400.783987)
			(xy 343.170878 -400.730039) (xy 343.186233 -400.677744) (xy 343.208875 -400.628167) (xy 343.238341 -400.582317)
			(xy 343.274032 -400.541126) (xy 343.315223 -400.505435) (xy 343.361073 -400.475969) (xy 343.41065 -400.453327)
			(xy 343.462945 -400.437972) (xy 343.516893 -400.430216) (xy 343.571395 -400.430216) (xy 343.625343 -400.437972)
			(xy 343.677638 -400.453327) (xy 343.727215 -400.475969) (xy 343.773065 -400.505435) (xy 343.814256 -400.541126)
			(xy 343.849947 -400.582317) (xy 343.879413 -400.628167) (xy 343.902055 -400.677744) (xy 343.91741 -400.730039)
			(xy 343.925166 -400.783987) (xy 343.925652 -400.811238) (xy 343.925652 -401.674838) (xy 344.362532 -401.674838)
			(xy 344.362532 -400.811238) (xy 344.363018 -400.783987) (xy 344.370774 -400.730039) (xy 344.386129 -400.677744)
			(xy 344.408771 -400.628167) (xy 344.438237 -400.582317) (xy 344.473928 -400.541126) (xy 344.515119 -400.505435)
			(xy 344.560969 -400.475969) (xy 344.610546 -400.453327) (xy 344.662841 -400.437972) (xy 344.716789 -400.430216)
			(xy 344.771291 -400.430216) (xy 344.825239 -400.437972) (xy 344.877534 -400.453327) (xy 344.927111 -400.475969)
			(xy 344.972961 -400.505435) (xy 345.014152 -400.541126) (xy 345.049843 -400.582317) (xy 345.079309 -400.628167)
			(xy 345.101951 -400.677744) (xy 345.117306 -400.730039) (xy 345.125062 -400.783987) (xy 345.125548 -400.811238)
			(xy 345.125548 -401.674838) (xy 345.562428 -401.674838) (xy 345.562428 -400.811238) (xy 345.562914 -400.783969)
			(xy 345.570676 -400.729985) (xy 345.586041 -400.677655) (xy 345.608698 -400.628045) (xy 345.638184 -400.582164)
			(xy 345.673899 -400.540947) (xy 345.715116 -400.505232) (xy 345.760997 -400.475746) (xy 345.810607 -400.453089)
			(xy 345.862937 -400.437724) (xy 345.916921 -400.429962) (xy 345.971459 -400.429962) (xy 346.025443 -400.437724)
			(xy 346.077773 -400.453089) (xy 346.127383 -400.475746) (xy 346.173264 -400.505232) (xy 346.214481 -400.540947)
			(xy 346.250196 -400.582164) (xy 346.279682 -400.628045) (xy 346.302339 -400.677655) (xy 346.317704 -400.729985)
			(xy 346.325466 -400.783969) (xy 346.325952 -400.811238) (xy 346.325952 -401.674838) (xy 346.762324 -401.674838)
			(xy 346.762324 -400.811238) (xy 346.76281 -400.783969) (xy 346.770572 -400.729985) (xy 346.785937 -400.677655)
			(xy 346.808594 -400.628045) (xy 346.83808 -400.582164) (xy 346.873795 -400.540947) (xy 346.915012 -400.505232)
			(xy 346.960893 -400.475746) (xy 347.010503 -400.453089) (xy 347.062833 -400.437724) (xy 347.116817 -400.429962)
			(xy 347.171355 -400.429962) (xy 347.225339 -400.437724) (xy 347.277669 -400.453089) (xy 347.327279 -400.475746)
			(xy 347.37316 -400.505232) (xy 347.414377 -400.540947) (xy 347.450092 -400.582164) (xy 347.479578 -400.628045)
			(xy 347.502235 -400.677655) (xy 347.5176 -400.729985) (xy 347.525362 -400.783969) (xy 347.525848 -400.811238)
			(xy 347.525848 -401.674838) (xy 347.962728 -401.674838) (xy 347.962728 -400.811238) (xy 347.963214 -400.783987)
			(xy 347.97097 -400.730039) (xy 347.986325 -400.677744) (xy 348.008967 -400.628167) (xy 348.038433 -400.582317)
			(xy 348.074124 -400.541126) (xy 348.115315 -400.505435) (xy 348.161165 -400.475969) (xy 348.210742 -400.453327)
			(xy 348.263037 -400.437972) (xy 348.316985 -400.430216) (xy 348.371487 -400.430216) (xy 348.425435 -400.437972)
			(xy 348.47773 -400.453327) (xy 348.527307 -400.475969) (xy 348.573157 -400.505435) (xy 348.614348 -400.541126)
			(xy 348.650039 -400.582317) (xy 348.679505 -400.628167) (xy 348.702147 -400.677744) (xy 348.717502 -400.730039)
			(xy 348.725258 -400.783987) (xy 348.725744 -400.811238) (xy 348.725744 -401.674838) (xy 349.162624 -401.674838)
			(xy 349.162624 -400.811238) (xy 349.16311 -400.783987) (xy 349.170866 -400.730039) (xy 349.186221 -400.677744)
			(xy 349.208863 -400.628167) (xy 349.238329 -400.582317) (xy 349.27402 -400.541126) (xy 349.315211 -400.505435)
			(xy 349.361061 -400.475969) (xy 349.410638 -400.453327) (xy 349.462933 -400.437972) (xy 349.516881 -400.430216)
			(xy 349.571383 -400.430216) (xy 349.625331 -400.437972) (xy 349.677626 -400.453327) (xy 349.727203 -400.475969)
			(xy 349.773053 -400.505435) (xy 349.814244 -400.541126) (xy 349.849935 -400.582317) (xy 349.879401 -400.628167)
			(xy 349.902043 -400.677744) (xy 349.917398 -400.730039) (xy 349.925154 -400.783987) (xy 349.92564 -400.811238)
			(xy 349.92564 -401.674838) (xy 350.36252 -401.674838) (xy 350.36252 -400.811238) (xy 350.363006 -400.783987)
			(xy 350.370762 -400.730039) (xy 350.386117 -400.677744) (xy 350.408759 -400.628167) (xy 350.438225 -400.582317)
			(xy 350.473916 -400.541126) (xy 350.515107 -400.505435) (xy 350.560957 -400.475969) (xy 350.610534 -400.453327)
			(xy 350.662829 -400.437972) (xy 350.716777 -400.430216) (xy 350.771279 -400.430216) (xy 350.825227 -400.437972)
			(xy 350.877522 -400.453327) (xy 350.927099 -400.475969) (xy 350.972949 -400.505435) (xy 351.01414 -400.541126)
			(xy 351.049831 -400.582317) (xy 351.079297 -400.628167) (xy 351.101939 -400.677744) (xy 351.117294 -400.730039)
			(xy 351.12505 -400.783987) (xy 351.125536 -400.811238) (xy 351.125536 -401.674838) (xy 351.562416 -401.674838)
			(xy 351.562416 -400.811238) (xy 351.562902 -400.783987) (xy 351.570658 -400.730039) (xy 351.586013 -400.677744)
			(xy 351.608655 -400.628167) (xy 351.638121 -400.582317) (xy 351.673812 -400.541126) (xy 351.715003 -400.505435)
			(xy 351.760853 -400.475969) (xy 351.81043 -400.453327) (xy 351.862725 -400.437972) (xy 351.916673 -400.430216)
			(xy 351.971175 -400.430216) (xy 352.025123 -400.437972) (xy 352.077418 -400.453327) (xy 352.126995 -400.475969)
			(xy 352.172845 -400.505435) (xy 352.214036 -400.541126) (xy 352.249727 -400.582317) (xy 352.279193 -400.628167)
			(xy 352.301835 -400.677744) (xy 352.31719 -400.730039) (xy 352.324946 -400.783987) (xy 352.325432 -400.811238)
			(xy 352.325432 -401.674838) (xy 352.762312 -401.674838) (xy 352.762312 -400.811238) (xy 352.762798 -400.783969)
			(xy 352.77056 -400.729985) (xy 352.785925 -400.677655) (xy 352.808582 -400.628045) (xy 352.838068 -400.582164)
			(xy 352.873783 -400.540947) (xy 352.915 -400.505232) (xy 352.960881 -400.475746) (xy 353.010491 -400.453089)
			(xy 353.062821 -400.437724) (xy 353.116805 -400.429962) (xy 353.171343 -400.429962) (xy 353.225327 -400.437724)
			(xy 353.277657 -400.453089) (xy 353.327267 -400.475746) (xy 353.373148 -400.505232) (xy 353.414365 -400.540947)
			(xy 353.45008 -400.582164) (xy 353.479566 -400.628045) (xy 353.502223 -400.677655) (xy 353.517588 -400.729985)
			(xy 353.52535 -400.783969) (xy 353.525836 -400.811238) (xy 353.525836 -401.674838) (xy 353.962208 -401.674838)
			(xy 353.962208 -400.811238) (xy 353.962694 -400.783969) (xy 353.970456 -400.729985) (xy 353.985821 -400.677655)
			(xy 354.008478 -400.628045) (xy 354.037964 -400.582164) (xy 354.073679 -400.540947) (xy 354.114896 -400.505232)
			(xy 354.160777 -400.475746) (xy 354.210387 -400.453089) (xy 354.262717 -400.437724) (xy 354.316701 -400.429962)
			(xy 354.371239 -400.429962) (xy 354.425223 -400.437724) (xy 354.477553 -400.453089) (xy 354.527163 -400.475746)
			(xy 354.573044 -400.505232) (xy 354.614261 -400.540947) (xy 354.649976 -400.582164) (xy 354.679462 -400.628045)
			(xy 354.702119 -400.677655) (xy 354.717484 -400.729985) (xy 354.725246 -400.783969) (xy 354.725732 -400.811238)
			(xy 354.725732 -401.674838) (xy 370.534692 -401.674838) (xy 370.534692 -400.811238) (xy 370.535178 -400.783969)
			(xy 370.54294 -400.729985) (xy 370.558305 -400.677655) (xy 370.580962 -400.628045) (xy 370.610448 -400.582164)
			(xy 370.646163 -400.540947) (xy 370.68738 -400.505232) (xy 370.733261 -400.475746) (xy 370.782871 -400.453089)
			(xy 370.835201 -400.437724) (xy 370.889185 -400.429962) (xy 370.943723 -400.429962) (xy 370.997707 -400.437724)
			(xy 371.050037 -400.453089) (xy 371.099647 -400.475746) (xy 371.145528 -400.505232) (xy 371.186745 -400.540947)
			(xy 371.22246 -400.582164) (xy 371.251946 -400.628045) (xy 371.274603 -400.677655) (xy 371.289968 -400.729985)
			(xy 371.29773 -400.783969) (xy 371.298216 -400.811238) (xy 371.298216 -401.674838) (xy 371.734588 -401.674838)
			(xy 371.734588 -400.811238) (xy 371.735074 -400.783969) (xy 371.742836 -400.729985) (xy 371.758201 -400.677655)
			(xy 371.780858 -400.628045) (xy 371.810344 -400.582164) (xy 371.846059 -400.540947) (xy 371.887276 -400.505232)
			(xy 371.933157 -400.475746) (xy 371.982767 -400.453089) (xy 372.035097 -400.437724) (xy 372.089081 -400.429962)
			(xy 372.143619 -400.429962) (xy 372.197603 -400.437724) (xy 372.249933 -400.453089) (xy 372.299543 -400.475746)
			(xy 372.345424 -400.505232) (xy 372.386641 -400.540947) (xy 372.422356 -400.582164) (xy 372.451842 -400.628045)
			(xy 372.474499 -400.677655) (xy 372.489864 -400.729985) (xy 372.497626 -400.783969) (xy 372.498112 -400.811238)
			(xy 372.498112 -401.674838) (xy 372.934992 -401.674838) (xy 372.934992 -400.811238) (xy 372.935478 -400.783987)
			(xy 372.943234 -400.730039) (xy 372.958589 -400.677744) (xy 372.981231 -400.628167) (xy 373.010697 -400.582317)
			(xy 373.046388 -400.541126) (xy 373.087579 -400.505435) (xy 373.133429 -400.475969) (xy 373.183006 -400.453327)
			(xy 373.235301 -400.437972) (xy 373.289249 -400.430216) (xy 373.343751 -400.430216) (xy 373.397699 -400.437972)
			(xy 373.449994 -400.453327) (xy 373.499571 -400.475969) (xy 373.545421 -400.505435) (xy 373.586612 -400.541126)
			(xy 373.622303 -400.582317) (xy 373.651769 -400.628167) (xy 373.674411 -400.677744) (xy 373.689766 -400.730039)
			(xy 373.697522 -400.783987) (xy 373.698008 -400.811238) (xy 373.698008 -401.674838) (xy 374.134888 -401.674838)
			(xy 374.134888 -400.811238) (xy 374.135374 -400.783987) (xy 374.14313 -400.730039) (xy 374.158485 -400.677744)
			(xy 374.181127 -400.628167) (xy 374.210593 -400.582317) (xy 374.246284 -400.541126) (xy 374.287475 -400.505435)
			(xy 374.333325 -400.475969) (xy 374.382902 -400.453327) (xy 374.435197 -400.437972) (xy 374.489145 -400.430216)
			(xy 374.543647 -400.430216) (xy 374.597595 -400.437972) (xy 374.64989 -400.453327) (xy 374.699467 -400.475969)
			(xy 374.745317 -400.505435) (xy 374.786508 -400.541126) (xy 374.822199 -400.582317) (xy 374.851665 -400.628167)
			(xy 374.874307 -400.677744) (xy 374.889662 -400.730039) (xy 374.897418 -400.783987) (xy 374.897904 -400.811238)
			(xy 374.897904 -401.674838) (xy 375.334784 -401.674838) (xy 375.334784 -400.811238) (xy 375.33527 -400.783969)
			(xy 375.343032 -400.729985) (xy 375.358397 -400.677655) (xy 375.381054 -400.628045) (xy 375.41054 -400.582164)
			(xy 375.446255 -400.540947) (xy 375.487472 -400.505232) (xy 375.533353 -400.475746) (xy 375.582963 -400.453089)
			(xy 375.635293 -400.437724) (xy 375.689277 -400.429962) (xy 375.743815 -400.429962) (xy 375.797799 -400.437724)
			(xy 375.850129 -400.453089) (xy 375.899739 -400.475746) (xy 375.94562 -400.505232) (xy 375.986837 -400.540947)
			(xy 376.022552 -400.582164) (xy 376.052038 -400.628045) (xy 376.074695 -400.677655) (xy 376.09006 -400.729985)
			(xy 376.097822 -400.783969) (xy 376.098308 -400.811238) (xy 376.098308 -401.674838) (xy 376.53468 -401.674838)
			(xy 376.53468 -400.811238) (xy 376.535166 -400.783969) (xy 376.542928 -400.729985) (xy 376.558293 -400.677655)
			(xy 376.58095 -400.628045) (xy 376.610436 -400.582164) (xy 376.646151 -400.540947) (xy 376.687368 -400.505232)
			(xy 376.733249 -400.475746) (xy 376.782859 -400.453089) (xy 376.835189 -400.437724) (xy 376.889173 -400.429962)
			(xy 376.943711 -400.429962) (xy 376.997695 -400.437724) (xy 377.050025 -400.453089) (xy 377.099635 -400.475746)
			(xy 377.145516 -400.505232) (xy 377.186733 -400.540947) (xy 377.222448 -400.582164) (xy 377.251934 -400.628045)
			(xy 377.274591 -400.677655) (xy 377.289956 -400.729985) (xy 377.297718 -400.783969) (xy 377.298204 -400.811238)
			(xy 377.298204 -401.674838) (xy 377.735084 -401.674838) (xy 377.735084 -400.811238) (xy 377.73557 -400.783987)
			(xy 377.743326 -400.730039) (xy 377.758681 -400.677744) (xy 377.781323 -400.628167) (xy 377.810789 -400.582317)
			(xy 377.84648 -400.541126) (xy 377.887671 -400.505435) (xy 377.933521 -400.475969) (xy 377.983098 -400.453327)
			(xy 378.035393 -400.437972) (xy 378.089341 -400.430216) (xy 378.143843 -400.430216) (xy 378.197791 -400.437972)
			(xy 378.250086 -400.453327) (xy 378.299663 -400.475969) (xy 378.345513 -400.505435) (xy 378.386704 -400.541126)
			(xy 378.422395 -400.582317) (xy 378.451861 -400.628167) (xy 378.474503 -400.677744) (xy 378.489858 -400.730039)
			(xy 378.497614 -400.783987) (xy 378.4981 -400.811238) (xy 378.4981 -401.674838) (xy 378.93498 -401.674838)
			(xy 378.93498 -400.811238) (xy 378.935466 -400.783987) (xy 378.943222 -400.730039) (xy 378.958577 -400.677744)
			(xy 378.981219 -400.628167) (xy 379.010685 -400.582317) (xy 379.046376 -400.541126) (xy 379.087567 -400.505435)
			(xy 379.133417 -400.475969) (xy 379.182994 -400.453327) (xy 379.235289 -400.437972) (xy 379.289237 -400.430216)
			(xy 379.343739 -400.430216) (xy 379.397687 -400.437972) (xy 379.449982 -400.453327) (xy 379.499559 -400.475969)
			(xy 379.545409 -400.505435) (xy 379.5866 -400.541126) (xy 379.622291 -400.582317) (xy 379.651757 -400.628167)
			(xy 379.674399 -400.677744) (xy 379.689754 -400.730039) (xy 379.69751 -400.783987) (xy 379.697996 -400.811238)
			(xy 379.697996 -401.674838) (xy 380.134876 -401.674838) (xy 380.134876 -400.811238) (xy 380.135362 -400.783969)
			(xy 380.143124 -400.729985) (xy 380.158489 -400.677655) (xy 380.181146 -400.628045) (xy 380.210632 -400.582164)
			(xy 380.246347 -400.540947) (xy 380.287564 -400.505232) (xy 380.333445 -400.475746) (xy 380.383055 -400.453089)
			(xy 380.435385 -400.437724) (xy 380.489369 -400.429962) (xy 380.543907 -400.429962) (xy 380.597891 -400.437724)
			(xy 380.650221 -400.453089) (xy 380.699831 -400.475746) (xy 380.745712 -400.505232) (xy 380.786929 -400.540947)
			(xy 380.822644 -400.582164) (xy 380.85213 -400.628045) (xy 380.874787 -400.677655) (xy 380.890152 -400.729985)
			(xy 380.897914 -400.783969) (xy 380.8984 -400.811238) (xy 380.8984 -401.674838) (xy 381.334772 -401.674838)
			(xy 381.334772 -400.811238) (xy 381.335258 -400.783969) (xy 381.34302 -400.729985) (xy 381.358385 -400.677655)
			(xy 381.381042 -400.628045) (xy 381.410528 -400.582164) (xy 381.446243 -400.540947) (xy 381.48746 -400.505232)
			(xy 381.533341 -400.475746) (xy 381.582951 -400.453089) (xy 381.635281 -400.437724) (xy 381.689265 -400.429962)
			(xy 381.743803 -400.429962) (xy 381.797787 -400.437724) (xy 381.850117 -400.453089) (xy 381.899727 -400.475746)
			(xy 381.945608 -400.505232) (xy 381.986825 -400.540947) (xy 382.02254 -400.582164) (xy 382.052026 -400.628045)
			(xy 382.074683 -400.677655) (xy 382.090048 -400.729985) (xy 382.09781 -400.783969) (xy 382.098296 -400.811238)
			(xy 382.098296 -401.674838) (xy 382.535176 -401.674838) (xy 382.535176 -400.811238) (xy 382.535662 -400.783987)
			(xy 382.543418 -400.730039) (xy 382.558773 -400.677744) (xy 382.581415 -400.628167) (xy 382.610881 -400.582317)
			(xy 382.646572 -400.541126) (xy 382.687763 -400.505435) (xy 382.733613 -400.475969) (xy 382.78319 -400.453327)
			(xy 382.835485 -400.437972) (xy 382.889433 -400.430216) (xy 382.943935 -400.430216) (xy 382.997883 -400.437972)
			(xy 383.050178 -400.453327) (xy 383.099755 -400.475969) (xy 383.145605 -400.505435) (xy 383.186796 -400.541126)
			(xy 383.222487 -400.582317) (xy 383.251953 -400.628167) (xy 383.274595 -400.677744) (xy 383.28995 -400.730039)
			(xy 383.297706 -400.783987) (xy 383.298192 -400.811238) (xy 383.298192 -401.674838) (xy 383.735072 -401.674838)
			(xy 383.735072 -400.811238) (xy 383.735558 -400.783987) (xy 383.743314 -400.730039) (xy 383.758669 -400.677744)
			(xy 383.781311 -400.628167) (xy 383.810777 -400.582317) (xy 383.846468 -400.541126) (xy 383.887659 -400.505435)
			(xy 383.933509 -400.475969) (xy 383.983086 -400.453327) (xy 384.035381 -400.437972) (xy 384.089329 -400.430216)
			(xy 384.143831 -400.430216) (xy 384.197779 -400.437972) (xy 384.250074 -400.453327) (xy 384.299651 -400.475969)
			(xy 384.345501 -400.505435) (xy 384.386692 -400.541126) (xy 384.422383 -400.582317) (xy 384.451849 -400.628167)
			(xy 384.474491 -400.677744) (xy 384.489846 -400.730039) (xy 384.497602 -400.783987) (xy 384.498088 -400.811238)
			(xy 384.498088 -401.674838) (xy 384.934968 -401.674838) (xy 384.934968 -400.811238) (xy 384.935454 -400.783987)
			(xy 384.94321 -400.730039) (xy 384.958565 -400.677744) (xy 384.981207 -400.628167) (xy 385.010673 -400.582317)
			(xy 385.046364 -400.541126) (xy 385.087555 -400.505435) (xy 385.133405 -400.475969) (xy 385.182982 -400.453327)
			(xy 385.235277 -400.437972) (xy 385.289225 -400.430216) (xy 385.343727 -400.430216) (xy 385.397675 -400.437972)
			(xy 385.44997 -400.453327) (xy 385.499547 -400.475969) (xy 385.545397 -400.505435) (xy 385.586588 -400.541126)
			(xy 385.622279 -400.582317) (xy 385.651745 -400.628167) (xy 385.674387 -400.677744) (xy 385.689742 -400.730039)
			(xy 385.697498 -400.783987) (xy 385.697984 -400.811238) (xy 385.697984 -401.674838) (xy 386.134864 -401.674838)
			(xy 386.134864 -400.811238) (xy 386.13535 -400.783987) (xy 386.143106 -400.730039) (xy 386.158461 -400.677744)
			(xy 386.181103 -400.628167) (xy 386.210569 -400.582317) (xy 386.24626 -400.541126) (xy 386.287451 -400.505435)
			(xy 386.333301 -400.475969) (xy 386.382878 -400.453327) (xy 386.435173 -400.437972) (xy 386.489121 -400.430216)
			(xy 386.543623 -400.430216) (xy 386.597571 -400.437972) (xy 386.649866 -400.453327) (xy 386.699443 -400.475969)
			(xy 386.745293 -400.505435) (xy 386.786484 -400.541126) (xy 386.822175 -400.582317) (xy 386.851641 -400.628167)
			(xy 386.874283 -400.677744) (xy 386.889638 -400.730039) (xy 386.897394 -400.783987) (xy 386.89788 -400.811238)
			(xy 386.89788 -401.674838) (xy 387.33476 -401.674838) (xy 387.33476 -400.811238) (xy 387.335246 -400.783969)
			(xy 387.343008 -400.729985) (xy 387.358373 -400.677655) (xy 387.38103 -400.628045) (xy 387.410516 -400.582164)
			(xy 387.446231 -400.540947) (xy 387.487448 -400.505232) (xy 387.533329 -400.475746) (xy 387.582939 -400.453089)
			(xy 387.635269 -400.437724) (xy 387.689253 -400.429962) (xy 387.743791 -400.429962) (xy 387.797775 -400.437724)
			(xy 387.850105 -400.453089) (xy 387.899715 -400.475746) (xy 387.945596 -400.505232) (xy 387.986813 -400.540947)
			(xy 388.022528 -400.582164) (xy 388.052014 -400.628045) (xy 388.074671 -400.677655) (xy 388.090036 -400.729985)
			(xy 388.097798 -400.783969) (xy 388.098284 -400.811238) (xy 388.098284 -401.674838) (xy 388.534656 -401.674838)
			(xy 388.534656 -400.811238) (xy 388.535142 -400.783969) (xy 388.542904 -400.729985) (xy 388.558269 -400.677655)
			(xy 388.580926 -400.628045) (xy 388.610412 -400.582164) (xy 388.646127 -400.540947) (xy 388.687344 -400.505232)
			(xy 388.733225 -400.475746) (xy 388.782835 -400.453089) (xy 388.835165 -400.437724) (xy 388.889149 -400.429962)
			(xy 388.943687 -400.429962) (xy 388.997671 -400.437724) (xy 389.050001 -400.453089) (xy 389.099611 -400.475746)
			(xy 389.145492 -400.505232) (xy 389.186709 -400.540947) (xy 389.222424 -400.582164) (xy 389.25191 -400.628045)
			(xy 389.274567 -400.677655) (xy 389.289932 -400.729985) (xy 389.297694 -400.783969) (xy 389.29818 -400.811238)
			(xy 389.29818 -401.674838) (xy 403.06244 -401.674838) (xy 403.06244 -400.811238) (xy 403.062926 -400.783969)
			(xy 403.070688 -400.729985) (xy 403.086053 -400.677655) (xy 403.10871 -400.628045) (xy 403.138196 -400.582164)
			(xy 403.173911 -400.540947) (xy 403.215128 -400.505232) (xy 403.261009 -400.475746) (xy 403.310619 -400.453089)
			(xy 403.362949 -400.437724) (xy 403.416933 -400.429962) (xy 403.471471 -400.429962) (xy 403.525455 -400.437724)
			(xy 403.577785 -400.453089) (xy 403.627395 -400.475746) (xy 403.673276 -400.505232) (xy 403.714493 -400.540947)
			(xy 403.750208 -400.582164) (xy 403.779694 -400.628045) (xy 403.802351 -400.677655) (xy 403.817716 -400.729985)
			(xy 403.825478 -400.783969) (xy 403.825964 -400.811238) (xy 403.825964 -401.674838) (xy 404.262336 -401.674838)
			(xy 404.262336 -400.811238) (xy 404.262822 -400.783969) (xy 404.270584 -400.729985) (xy 404.285949 -400.677655)
			(xy 404.308606 -400.628045) (xy 404.338092 -400.582164) (xy 404.373807 -400.540947) (xy 404.415024 -400.505232)
			(xy 404.460905 -400.475746) (xy 404.510515 -400.453089) (xy 404.562845 -400.437724) (xy 404.616829 -400.429962)
			(xy 404.671367 -400.429962) (xy 404.725351 -400.437724) (xy 404.777681 -400.453089) (xy 404.827291 -400.475746)
			(xy 404.873172 -400.505232) (xy 404.914389 -400.540947) (xy 404.950104 -400.582164) (xy 404.97959 -400.628045)
			(xy 405.002247 -400.677655) (xy 405.017612 -400.729985) (xy 405.025374 -400.783969) (xy 405.02586 -400.811238)
			(xy 405.02586 -401.674838) (xy 405.46274 -401.674838) (xy 405.46274 -400.811238) (xy 405.463226 -400.783987)
			(xy 405.470982 -400.730039) (xy 405.486337 -400.677744) (xy 405.508979 -400.628167) (xy 405.538445 -400.582317)
			(xy 405.574136 -400.541126) (xy 405.615327 -400.505435) (xy 405.661177 -400.475969) (xy 405.710754 -400.453327)
			(xy 405.763049 -400.437972) (xy 405.816997 -400.430216) (xy 405.871499 -400.430216) (xy 405.925447 -400.437972)
			(xy 405.977742 -400.453327) (xy 406.027319 -400.475969) (xy 406.073169 -400.505435) (xy 406.11436 -400.541126)
			(xy 406.150051 -400.582317) (xy 406.179517 -400.628167) (xy 406.202159 -400.677744) (xy 406.217514 -400.730039)
			(xy 406.22527 -400.783987) (xy 406.225756 -400.811238) (xy 406.225756 -401.674838) (xy 406.662636 -401.674838)
			(xy 406.662636 -400.811238) (xy 406.663122 -400.783987) (xy 406.670878 -400.730039) (xy 406.686233 -400.677744)
			(xy 406.708875 -400.628167) (xy 406.738341 -400.582317) (xy 406.774032 -400.541126) (xy 406.815223 -400.505435)
			(xy 406.861073 -400.475969) (xy 406.91065 -400.453327) (xy 406.962945 -400.437972) (xy 407.016893 -400.430216)
			(xy 407.071395 -400.430216) (xy 407.125343 -400.437972) (xy 407.177638 -400.453327) (xy 407.227215 -400.475969)
			(xy 407.273065 -400.505435) (xy 407.314256 -400.541126) (xy 407.349947 -400.582317) (xy 407.379413 -400.628167)
			(xy 407.402055 -400.677744) (xy 407.41741 -400.730039) (xy 407.425166 -400.783987) (xy 407.425652 -400.811238)
			(xy 407.425652 -401.674838) (xy 407.862532 -401.674838) (xy 407.862532 -400.811238) (xy 407.863018 -400.783969)
			(xy 407.87078 -400.729985) (xy 407.886145 -400.677655) (xy 407.908802 -400.628045) (xy 407.938288 -400.582164)
			(xy 407.974003 -400.540947) (xy 408.01522 -400.505232) (xy 408.061101 -400.475746) (xy 408.110711 -400.453089)
			(xy 408.163041 -400.437724) (xy 408.217025 -400.429962) (xy 408.271563 -400.429962) (xy 408.325547 -400.437724)
			(xy 408.377877 -400.453089) (xy 408.427487 -400.475746) (xy 408.473368 -400.505232) (xy 408.514585 -400.540947)
			(xy 408.5503 -400.582164) (xy 408.579786 -400.628045) (xy 408.602443 -400.677655) (xy 408.617808 -400.729985)
			(xy 408.62557 -400.783969) (xy 408.626056 -400.811238) (xy 408.626056 -401.674838) (xy 409.062428 -401.674838)
			(xy 409.062428 -400.811238) (xy 409.062914 -400.783969) (xy 409.070676 -400.729985) (xy 409.086041 -400.677655)
			(xy 409.108698 -400.628045) (xy 409.138184 -400.582164) (xy 409.173899 -400.540947) (xy 409.215116 -400.505232)
			(xy 409.260997 -400.475746) (xy 409.310607 -400.453089) (xy 409.362937 -400.437724) (xy 409.416921 -400.429962)
			(xy 409.471459 -400.429962) (xy 409.525443 -400.437724) (xy 409.577773 -400.453089) (xy 409.627383 -400.475746)
			(xy 409.673264 -400.505232) (xy 409.714481 -400.540947) (xy 409.750196 -400.582164) (xy 409.779682 -400.628045)
			(xy 409.802339 -400.677655) (xy 409.817704 -400.729985) (xy 409.825466 -400.783969) (xy 409.825952 -400.811238)
			(xy 409.825952 -401.674838) (xy 410.262832 -401.674838) (xy 410.262832 -400.811238) (xy 410.263318 -400.783987)
			(xy 410.271074 -400.730039) (xy 410.286429 -400.677744) (xy 410.309071 -400.628167) (xy 410.338537 -400.582317)
			(xy 410.374228 -400.541126) (xy 410.415419 -400.505435) (xy 410.461269 -400.475969) (xy 410.510846 -400.453327)
			(xy 410.563141 -400.437972) (xy 410.617089 -400.430216) (xy 410.671591 -400.430216) (xy 410.725539 -400.437972)
			(xy 410.777834 -400.453327) (xy 410.827411 -400.475969) (xy 410.873261 -400.505435) (xy 410.914452 -400.541126)
			(xy 410.950143 -400.582317) (xy 410.979609 -400.628167) (xy 411.002251 -400.677744) (xy 411.017606 -400.730039)
			(xy 411.025362 -400.783987) (xy 411.025848 -400.811238) (xy 411.025848 -401.674838) (xy 411.462728 -401.674838)
			(xy 411.462728 -400.811238) (xy 411.463214 -400.783987) (xy 411.47097 -400.730039) (xy 411.486325 -400.677744)
			(xy 411.508967 -400.628167) (xy 411.538433 -400.582317) (xy 411.574124 -400.541126) (xy 411.615315 -400.505435)
			(xy 411.661165 -400.475969) (xy 411.710742 -400.453327) (xy 411.763037 -400.437972) (xy 411.816985 -400.430216)
			(xy 411.871487 -400.430216) (xy 411.925435 -400.437972) (xy 411.97773 -400.453327) (xy 412.027307 -400.475969)
			(xy 412.073157 -400.505435) (xy 412.114348 -400.541126) (xy 412.150039 -400.582317) (xy 412.179505 -400.628167)
			(xy 412.202147 -400.677744) (xy 412.217502 -400.730039) (xy 412.225258 -400.783987) (xy 412.225744 -400.811238)
			(xy 412.225744 -401.674838) (xy 412.662624 -401.674838) (xy 412.662624 -400.811238) (xy 412.66311 -400.783969)
			(xy 412.670872 -400.729985) (xy 412.686237 -400.677655) (xy 412.708894 -400.628045) (xy 412.73838 -400.582164)
			(xy 412.774095 -400.540947) (xy 412.815312 -400.505232) (xy 412.861193 -400.475746) (xy 412.910803 -400.453089)
			(xy 412.963133 -400.437724) (xy 413.017117 -400.429962) (xy 413.071655 -400.429962) (xy 413.125639 -400.437724)
			(xy 413.177969 -400.453089) (xy 413.227579 -400.475746) (xy 413.27346 -400.505232) (xy 413.314677 -400.540947)
			(xy 413.350392 -400.582164) (xy 413.379878 -400.628045) (xy 413.402535 -400.677655) (xy 413.4179 -400.729985)
			(xy 413.425662 -400.783969) (xy 413.426148 -400.811238) (xy 413.426148 -401.674838) (xy 413.86252 -401.674838)
			(xy 413.86252 -400.811238) (xy 413.863006 -400.783969) (xy 413.870768 -400.729985) (xy 413.886133 -400.677655)
			(xy 413.90879 -400.628045) (xy 413.938276 -400.582164) (xy 413.973991 -400.540947) (xy 414.015208 -400.505232)
			(xy 414.061089 -400.475746) (xy 414.110699 -400.453089) (xy 414.163029 -400.437724) (xy 414.217013 -400.429962)
			(xy 414.271551 -400.429962) (xy 414.325535 -400.437724) (xy 414.377865 -400.453089) (xy 414.427475 -400.475746)
			(xy 414.473356 -400.505232) (xy 414.514573 -400.540947) (xy 414.550288 -400.582164) (xy 414.579774 -400.628045)
			(xy 414.602431 -400.677655) (xy 414.617796 -400.729985) (xy 414.625558 -400.783969) (xy 414.626044 -400.811238)
			(xy 414.626044 -401.674838) (xy 415.062924 -401.674838) (xy 415.062924 -400.811238) (xy 415.06341 -400.783987)
			(xy 415.071166 -400.730039) (xy 415.086521 -400.677744) (xy 415.109163 -400.628167) (xy 415.138629 -400.582317)
			(xy 415.17432 -400.541126) (xy 415.215511 -400.505435) (xy 415.261361 -400.475969) (xy 415.310938 -400.453327)
			(xy 415.363233 -400.437972) (xy 415.417181 -400.430216) (xy 415.471683 -400.430216) (xy 415.525631 -400.437972)
			(xy 415.577926 -400.453327) (xy 415.627503 -400.475969) (xy 415.673353 -400.505435) (xy 415.714544 -400.541126)
			(xy 415.750235 -400.582317) (xy 415.779701 -400.628167) (xy 415.802343 -400.677744) (xy 415.817698 -400.730039)
			(xy 415.825454 -400.783987) (xy 415.82594 -400.811238) (xy 415.82594 -401.674838) (xy 416.26282 -401.674838)
			(xy 416.26282 -400.811238) (xy 416.263306 -400.783987) (xy 416.271062 -400.730039) (xy 416.286417 -400.677744)
			(xy 416.309059 -400.628167) (xy 416.338525 -400.582317) (xy 416.374216 -400.541126) (xy 416.415407 -400.505435)
			(xy 416.461257 -400.475969) (xy 416.510834 -400.453327) (xy 416.563129 -400.437972) (xy 416.617077 -400.430216)
			(xy 416.671579 -400.430216) (xy 416.725527 -400.437972) (xy 416.777822 -400.453327) (xy 416.827399 -400.475969)
			(xy 416.873249 -400.505435) (xy 416.91444 -400.541126) (xy 416.950131 -400.582317) (xy 416.979597 -400.628167)
			(xy 417.002239 -400.677744) (xy 417.017594 -400.730039) (xy 417.02535 -400.783987) (xy 417.025836 -400.811238)
			(xy 417.025836 -401.674838) (xy 417.462716 -401.674838) (xy 417.462716 -400.811238) (xy 417.463202 -400.783987)
			(xy 417.470958 -400.730039) (xy 417.486313 -400.677744) (xy 417.508955 -400.628167) (xy 417.538421 -400.582317)
			(xy 417.574112 -400.541126) (xy 417.615303 -400.505435) (xy 417.661153 -400.475969) (xy 417.71073 -400.453327)
			(xy 417.763025 -400.437972) (xy 417.816973 -400.430216) (xy 417.871475 -400.430216) (xy 417.925423 -400.437972)
			(xy 417.977718 -400.453327) (xy 418.027295 -400.475969) (xy 418.073145 -400.505435) (xy 418.114336 -400.541126)
			(xy 418.150027 -400.582317) (xy 418.179493 -400.628167) (xy 418.202135 -400.677744) (xy 418.21749 -400.730039)
			(xy 418.225246 -400.783987) (xy 418.225732 -400.811238) (xy 418.225732 -401.674838) (xy 418.662612 -401.674838)
			(xy 418.662612 -400.811238) (xy 418.663098 -400.783987) (xy 418.670854 -400.730039) (xy 418.686209 -400.677744)
			(xy 418.708851 -400.628167) (xy 418.738317 -400.582317) (xy 418.774008 -400.541126) (xy 418.815199 -400.505435)
			(xy 418.861049 -400.475969) (xy 418.910626 -400.453327) (xy 418.962921 -400.437972) (xy 419.016869 -400.430216)
			(xy 419.071371 -400.430216) (xy 419.125319 -400.437972) (xy 419.177614 -400.453327) (xy 419.227191 -400.475969)
			(xy 419.273041 -400.505435) (xy 419.314232 -400.541126) (xy 419.349923 -400.582317) (xy 419.379389 -400.628167)
			(xy 419.402031 -400.677744) (xy 419.417386 -400.730039) (xy 419.425142 -400.783987) (xy 419.425628 -400.811238)
			(xy 419.425628 -401.674838) (xy 419.862508 -401.674838) (xy 419.862508 -400.811238) (xy 419.862994 -400.783969)
			(xy 419.870756 -400.729985) (xy 419.886121 -400.677655) (xy 419.908778 -400.628045) (xy 419.938264 -400.582164)
			(xy 419.973979 -400.540947) (xy 420.015196 -400.505232) (xy 420.061077 -400.475746) (xy 420.110687 -400.453089)
			(xy 420.163017 -400.437724) (xy 420.217001 -400.429962) (xy 420.271539 -400.429962) (xy 420.325523 -400.437724)
			(xy 420.377853 -400.453089) (xy 420.427463 -400.475746) (xy 420.473344 -400.505232) (xy 420.514561 -400.540947)
			(xy 420.550276 -400.582164) (xy 420.579762 -400.628045) (xy 420.602419 -400.677655) (xy 420.617784 -400.729985)
			(xy 420.625546 -400.783969) (xy 420.626032 -400.811238) (xy 420.626032 -401.674838) (xy 421.062404 -401.674838)
			(xy 421.062404 -400.811238) (xy 421.06289 -400.783969) (xy 421.070652 -400.729985) (xy 421.086017 -400.677655)
			(xy 421.108674 -400.628045) (xy 421.13816 -400.582164) (xy 421.173875 -400.540947) (xy 421.215092 -400.505232)
			(xy 421.260973 -400.475746) (xy 421.310583 -400.453089) (xy 421.362913 -400.437724) (xy 421.416897 -400.429962)
			(xy 421.471435 -400.429962) (xy 421.525419 -400.437724) (xy 421.577749 -400.453089) (xy 421.627359 -400.475746)
			(xy 421.67324 -400.505232) (xy 421.714457 -400.540947) (xy 421.750172 -400.582164) (xy 421.779658 -400.628045)
			(xy 421.802315 -400.677655) (xy 421.81768 -400.729985) (xy 421.825442 -400.783969) (xy 421.825928 -400.811238)
			(xy 421.825928 -401.674838) (xy 421.825442 -401.702107) (xy 421.81768 -401.756091) (xy 421.802315 -401.808421)
			(xy 421.779658 -401.858031) (xy 421.750172 -401.903912) (xy 421.714457 -401.945129) (xy 421.67324 -401.980844)
			(xy 421.627359 -402.01033) (xy 421.577749 -402.032987) (xy 421.525419 -402.048352) (xy 421.471435 -402.056114)
			(xy 421.416897 -402.056114) (xy 421.362913 -402.048352) (xy 421.310583 -402.032987) (xy 421.260973 -402.01033)
			(xy 421.215092 -401.980844) (xy 421.173875 -401.945129) (xy 421.13816 -401.903912) (xy 421.108674 -401.858031)
			(xy 421.086017 -401.808421) (xy 421.070652 -401.756091) (xy 421.06289 -401.702107) (xy 421.062404 -401.674838)
			(xy 420.626032 -401.674838) (xy 420.625546 -401.702107) (xy 420.617784 -401.756091) (xy 420.602419 -401.808421)
			(xy 420.579762 -401.858031) (xy 420.550276 -401.903912) (xy 420.514561 -401.945129) (xy 420.473344 -401.980844)
			(xy 420.427463 -402.01033) (xy 420.377853 -402.032987) (xy 420.325523 -402.048352) (xy 420.271539 -402.056114)
			(xy 420.217001 -402.056114) (xy 420.163017 -402.048352) (xy 420.110687 -402.032987) (xy 420.061077 -402.01033)
			(xy 420.015196 -401.980844) (xy 419.973979 -401.945129) (xy 419.938264 -401.903912) (xy 419.908778 -401.858031)
			(xy 419.886121 -401.808421) (xy 419.870756 -401.756091) (xy 419.862994 -401.702107) (xy 419.862508 -401.674838)
			(xy 419.425628 -401.674838) (xy 419.425142 -401.702089) (xy 419.417386 -401.756037) (xy 419.402031 -401.808332)
			(xy 419.379389 -401.857909) (xy 419.349923 -401.903759) (xy 419.314232 -401.94495) (xy 419.273041 -401.980641)
			(xy 419.227191 -402.010107) (xy 419.177614 -402.032749) (xy 419.125319 -402.048104) (xy 419.071371 -402.05586)
			(xy 419.016869 -402.05586) (xy 418.962921 -402.048104) (xy 418.910626 -402.032749) (xy 418.861049 -402.010107)
			(xy 418.815199 -401.980641) (xy 418.774008 -401.94495) (xy 418.738317 -401.903759) (xy 418.708851 -401.857909)
			(xy 418.686209 -401.808332) (xy 418.670854 -401.756037) (xy 418.663098 -401.702089) (xy 418.662612 -401.674838)
			(xy 418.225732 -401.674838) (xy 418.225246 -401.702089) (xy 418.21749 -401.756037) (xy 418.202135 -401.808332)
			(xy 418.179493 -401.857909) (xy 418.150027 -401.903759) (xy 418.114336 -401.94495) (xy 418.073145 -401.980641)
			(xy 418.027295 -402.010107) (xy 417.977718 -402.032749) (xy 417.925423 -402.048104) (xy 417.871475 -402.05586)
			(xy 417.816973 -402.05586) (xy 417.763025 -402.048104) (xy 417.71073 -402.032749) (xy 417.661153 -402.010107)
			(xy 417.615303 -401.980641) (xy 417.574112 -401.94495) (xy 417.538421 -401.903759) (xy 417.508955 -401.857909)
			(xy 417.486313 -401.808332) (xy 417.470958 -401.756037) (xy 417.463202 -401.702089) (xy 417.462716 -401.674838)
			(xy 417.025836 -401.674838) (xy 417.02535 -401.702089) (xy 417.017594 -401.756037) (xy 417.002239 -401.808332)
			(xy 416.979597 -401.857909) (xy 416.950131 -401.903759) (xy 416.91444 -401.94495) (xy 416.873249 -401.980641)
			(xy 416.827399 -402.010107) (xy 416.777822 -402.032749) (xy 416.725527 -402.048104) (xy 416.671579 -402.05586)
			(xy 416.617077 -402.05586) (xy 416.563129 -402.048104) (xy 416.510834 -402.032749) (xy 416.461257 -402.010107)
			(xy 416.415407 -401.980641) (xy 416.374216 -401.94495) (xy 416.338525 -401.903759) (xy 416.309059 -401.857909)
			(xy 416.286417 -401.808332) (xy 416.271062 -401.756037) (xy 416.263306 -401.702089) (xy 416.26282 -401.674838)
			(xy 415.82594 -401.674838) (xy 415.825454 -401.702089) (xy 415.817698 -401.756037) (xy 415.802343 -401.808332)
			(xy 415.779701 -401.857909) (xy 415.750235 -401.903759) (xy 415.714544 -401.94495) (xy 415.673353 -401.980641)
			(xy 415.627503 -402.010107) (xy 415.577926 -402.032749) (xy 415.525631 -402.048104) (xy 415.471683 -402.05586)
			(xy 415.417181 -402.05586) (xy 415.363233 -402.048104) (xy 415.310938 -402.032749) (xy 415.261361 -402.010107)
			(xy 415.215511 -401.980641) (xy 415.17432 -401.94495) (xy 415.138629 -401.903759) (xy 415.109163 -401.857909)
			(xy 415.086521 -401.808332) (xy 415.071166 -401.756037) (xy 415.06341 -401.702089) (xy 415.062924 -401.674838)
			(xy 414.626044 -401.674838) (xy 414.625558 -401.702107) (xy 414.617796 -401.756091) (xy 414.602431 -401.808421)
			(xy 414.579774 -401.858031) (xy 414.550288 -401.903912) (xy 414.514573 -401.945129) (xy 414.473356 -401.980844)
			(xy 414.427475 -402.01033) (xy 414.377865 -402.032987) (xy 414.325535 -402.048352) (xy 414.271551 -402.056114)
			(xy 414.217013 -402.056114) (xy 414.163029 -402.048352) (xy 414.110699 -402.032987) (xy 414.061089 -402.01033)
			(xy 414.015208 -401.980844) (xy 413.973991 -401.945129) (xy 413.938276 -401.903912) (xy 413.90879 -401.858031)
			(xy 413.886133 -401.808421) (xy 413.870768 -401.756091) (xy 413.863006 -401.702107) (xy 413.86252 -401.674838)
			(xy 413.426148 -401.674838) (xy 413.425662 -401.702107) (xy 413.4179 -401.756091) (xy 413.402535 -401.808421)
			(xy 413.379878 -401.858031) (xy 413.350392 -401.903912) (xy 413.314677 -401.945129) (xy 413.27346 -401.980844)
			(xy 413.227579 -402.01033) (xy 413.177969 -402.032987) (xy 413.125639 -402.048352) (xy 413.071655 -402.056114)
			(xy 413.017117 -402.056114) (xy 412.963133 -402.048352) (xy 412.910803 -402.032987) (xy 412.861193 -402.01033)
			(xy 412.815312 -401.980844) (xy 412.774095 -401.945129) (xy 412.73838 -401.903912) (xy 412.708894 -401.858031)
			(xy 412.686237 -401.808421) (xy 412.670872 -401.756091) (xy 412.66311 -401.702107) (xy 412.662624 -401.674838)
			(xy 412.225744 -401.674838) (xy 412.225258 -401.702089) (xy 412.217502 -401.756037) (xy 412.202147 -401.808332)
			(xy 412.179505 -401.857909) (xy 412.150039 -401.903759) (xy 412.114348 -401.94495) (xy 412.073157 -401.980641)
			(xy 412.027307 -402.010107) (xy 411.97773 -402.032749) (xy 411.925435 -402.048104) (xy 411.871487 -402.05586)
			(xy 411.816985 -402.05586) (xy 411.763037 -402.048104) (xy 411.710742 -402.032749) (xy 411.661165 -402.010107)
			(xy 411.615315 -401.980641) (xy 411.574124 -401.94495) (xy 411.538433 -401.903759) (xy 411.508967 -401.857909)
			(xy 411.486325 -401.808332) (xy 411.47097 -401.756037) (xy 411.463214 -401.702089) (xy 411.462728 -401.674838)
			(xy 411.025848 -401.674838) (xy 411.025362 -401.702089) (xy 411.017606 -401.756037) (xy 411.002251 -401.808332)
			(xy 410.979609 -401.857909) (xy 410.950143 -401.903759) (xy 410.914452 -401.94495) (xy 410.873261 -401.980641)
			(xy 410.827411 -402.010107) (xy 410.777834 -402.032749) (xy 410.725539 -402.048104) (xy 410.671591 -402.05586)
			(xy 410.617089 -402.05586) (xy 410.563141 -402.048104) (xy 410.510846 -402.032749) (xy 410.461269 -402.010107)
			(xy 410.415419 -401.980641) (xy 410.374228 -401.94495) (xy 410.338537 -401.903759) (xy 410.309071 -401.857909)
			(xy 410.286429 -401.808332) (xy 410.271074 -401.756037) (xy 410.263318 -401.702089) (xy 410.262832 -401.674838)
			(xy 409.825952 -401.674838) (xy 409.825466 -401.702107) (xy 409.817704 -401.756091) (xy 409.802339 -401.808421)
			(xy 409.779682 -401.858031) (xy 409.750196 -401.903912) (xy 409.714481 -401.945129) (xy 409.673264 -401.980844)
			(xy 409.627383 -402.01033) (xy 409.577773 -402.032987) (xy 409.525443 -402.048352) (xy 409.471459 -402.056114)
			(xy 409.416921 -402.056114) (xy 409.362937 -402.048352) (xy 409.310607 -402.032987) (xy 409.260997 -402.01033)
			(xy 409.215116 -401.980844) (xy 409.173899 -401.945129) (xy 409.138184 -401.903912) (xy 409.108698 -401.858031)
			(xy 409.086041 -401.808421) (xy 409.070676 -401.756091) (xy 409.062914 -401.702107) (xy 409.062428 -401.674838)
			(xy 408.626056 -401.674838) (xy 408.62557 -401.702107) (xy 408.617808 -401.756091) (xy 408.602443 -401.808421)
			(xy 408.579786 -401.858031) (xy 408.5503 -401.903912) (xy 408.514585 -401.945129) (xy 408.473368 -401.980844)
			(xy 408.427487 -402.01033) (xy 408.377877 -402.032987) (xy 408.325547 -402.048352) (xy 408.271563 -402.056114)
			(xy 408.217025 -402.056114) (xy 408.163041 -402.048352) (xy 408.110711 -402.032987) (xy 408.061101 -402.01033)
			(xy 408.01522 -401.980844) (xy 407.974003 -401.945129) (xy 407.938288 -401.903912) (xy 407.908802 -401.858031)
			(xy 407.886145 -401.808421) (xy 407.87078 -401.756091) (xy 407.863018 -401.702107) (xy 407.862532 -401.674838)
			(xy 407.425652 -401.674838) (xy 407.425166 -401.702089) (xy 407.41741 -401.756037) (xy 407.402055 -401.808332)
			(xy 407.379413 -401.857909) (xy 407.349947 -401.903759) (xy 407.314256 -401.94495) (xy 407.273065 -401.980641)
			(xy 407.227215 -402.010107) (xy 407.177638 -402.032749) (xy 407.125343 -402.048104) (xy 407.071395 -402.05586)
			(xy 407.016893 -402.05586) (xy 406.962945 -402.048104) (xy 406.91065 -402.032749) (xy 406.861073 -402.010107)
			(xy 406.815223 -401.980641) (xy 406.774032 -401.94495) (xy 406.738341 -401.903759) (xy 406.708875 -401.857909)
			(xy 406.686233 -401.808332) (xy 406.670878 -401.756037) (xy 406.663122 -401.702089) (xy 406.662636 -401.674838)
			(xy 406.225756 -401.674838) (xy 406.22527 -401.702089) (xy 406.217514 -401.756037) (xy 406.202159 -401.808332)
			(xy 406.179517 -401.857909) (xy 406.150051 -401.903759) (xy 406.11436 -401.94495) (xy 406.073169 -401.980641)
			(xy 406.027319 -402.010107) (xy 405.977742 -402.032749) (xy 405.925447 -402.048104) (xy 405.871499 -402.05586)
			(xy 405.816997 -402.05586) (xy 405.763049 -402.048104) (xy 405.710754 -402.032749) (xy 405.661177 -402.010107)
			(xy 405.615327 -401.980641) (xy 405.574136 -401.94495) (xy 405.538445 -401.903759) (xy 405.508979 -401.857909)
			(xy 405.486337 -401.808332) (xy 405.470982 -401.756037) (xy 405.463226 -401.702089) (xy 405.46274 -401.674838)
			(xy 405.02586 -401.674838) (xy 405.025374 -401.702107) (xy 405.017612 -401.756091) (xy 405.002247 -401.808421)
			(xy 404.97959 -401.858031) (xy 404.950104 -401.903912) (xy 404.914389 -401.945129) (xy 404.873172 -401.980844)
			(xy 404.827291 -402.01033) (xy 404.777681 -402.032987) (xy 404.725351 -402.048352) (xy 404.671367 -402.056114)
			(xy 404.616829 -402.056114) (xy 404.562845 -402.048352) (xy 404.510515 -402.032987) (xy 404.460905 -402.01033)
			(xy 404.415024 -401.980844) (xy 404.373807 -401.945129) (xy 404.338092 -401.903912) (xy 404.308606 -401.858031)
			(xy 404.285949 -401.808421) (xy 404.270584 -401.756091) (xy 404.262822 -401.702107) (xy 404.262336 -401.674838)
			(xy 403.825964 -401.674838) (xy 403.825478 -401.702107) (xy 403.817716 -401.756091) (xy 403.802351 -401.808421)
			(xy 403.779694 -401.858031) (xy 403.750208 -401.903912) (xy 403.714493 -401.945129) (xy 403.673276 -401.980844)
			(xy 403.627395 -402.01033) (xy 403.577785 -402.032987) (xy 403.525455 -402.048352) (xy 403.471471 -402.056114)
			(xy 403.416933 -402.056114) (xy 403.362949 -402.048352) (xy 403.310619 -402.032987) (xy 403.261009 -402.01033)
			(xy 403.215128 -401.980844) (xy 403.173911 -401.945129) (xy 403.138196 -401.903912) (xy 403.10871 -401.858031)
			(xy 403.086053 -401.808421) (xy 403.070688 -401.756091) (xy 403.062926 -401.702107) (xy 403.06244 -401.674838)
			(xy 389.29818 -401.674838) (xy 389.297694 -401.702107) (xy 389.289932 -401.756091) (xy 389.274567 -401.808421)
			(xy 389.25191 -401.858031) (xy 389.222424 -401.903912) (xy 389.186709 -401.945129) (xy 389.145492 -401.980844)
			(xy 389.099611 -402.01033) (xy 389.050001 -402.032987) (xy 388.997671 -402.048352) (xy 388.943687 -402.056114)
			(xy 388.889149 -402.056114) (xy 388.835165 -402.048352) (xy 388.782835 -402.032987) (xy 388.733225 -402.01033)
			(xy 388.687344 -401.980844) (xy 388.646127 -401.945129) (xy 388.610412 -401.903912) (xy 388.580926 -401.858031)
			(xy 388.558269 -401.808421) (xy 388.542904 -401.756091) (xy 388.535142 -401.702107) (xy 388.534656 -401.674838)
			(xy 388.098284 -401.674838) (xy 388.097798 -401.702107) (xy 388.090036 -401.756091) (xy 388.074671 -401.808421)
			(xy 388.052014 -401.858031) (xy 388.022528 -401.903912) (xy 387.986813 -401.945129) (xy 387.945596 -401.980844)
			(xy 387.899715 -402.01033) (xy 387.850105 -402.032987) (xy 387.797775 -402.048352) (xy 387.743791 -402.056114)
			(xy 387.689253 -402.056114) (xy 387.635269 -402.048352) (xy 387.582939 -402.032987) (xy 387.533329 -402.01033)
			(xy 387.487448 -401.980844) (xy 387.446231 -401.945129) (xy 387.410516 -401.903912) (xy 387.38103 -401.858031)
			(xy 387.358373 -401.808421) (xy 387.343008 -401.756091) (xy 387.335246 -401.702107) (xy 387.33476 -401.674838)
			(xy 386.89788 -401.674838) (xy 386.897394 -401.702089) (xy 386.889638 -401.756037) (xy 386.874283 -401.808332)
			(xy 386.851641 -401.857909) (xy 386.822175 -401.903759) (xy 386.786484 -401.94495) (xy 386.745293 -401.980641)
			(xy 386.699443 -402.010107) (xy 386.649866 -402.032749) (xy 386.597571 -402.048104) (xy 386.543623 -402.05586)
			(xy 386.489121 -402.05586) (xy 386.435173 -402.048104) (xy 386.382878 -402.032749) (xy 386.333301 -402.010107)
			(xy 386.287451 -401.980641) (xy 386.24626 -401.94495) (xy 386.210569 -401.903759) (xy 386.181103 -401.857909)
			(xy 386.158461 -401.808332) (xy 386.143106 -401.756037) (xy 386.13535 -401.702089) (xy 386.134864 -401.674838)
			(xy 385.697984 -401.674838) (xy 385.697498 -401.702089) (xy 385.689742 -401.756037) (xy 385.674387 -401.808332)
			(xy 385.651745 -401.857909) (xy 385.622279 -401.903759) (xy 385.586588 -401.94495) (xy 385.545397 -401.980641)
			(xy 385.499547 -402.010107) (xy 385.44997 -402.032749) (xy 385.397675 -402.048104) (xy 385.343727 -402.05586)
			(xy 385.289225 -402.05586) (xy 385.235277 -402.048104) (xy 385.182982 -402.032749) (xy 385.133405 -402.010107)
			(xy 385.087555 -401.980641) (xy 385.046364 -401.94495) (xy 385.010673 -401.903759) (xy 384.981207 -401.857909)
			(xy 384.958565 -401.808332) (xy 384.94321 -401.756037) (xy 384.935454 -401.702089) (xy 384.934968 -401.674838)
			(xy 384.498088 -401.674838) (xy 384.497602 -401.702089) (xy 384.489846 -401.756037) (xy 384.474491 -401.808332)
			(xy 384.451849 -401.857909) (xy 384.422383 -401.903759) (xy 384.386692 -401.94495) (xy 384.345501 -401.980641)
			(xy 384.299651 -402.010107) (xy 384.250074 -402.032749) (xy 384.197779 -402.048104) (xy 384.143831 -402.05586)
			(xy 384.089329 -402.05586) (xy 384.035381 -402.048104) (xy 383.983086 -402.032749) (xy 383.933509 -402.010107)
			(xy 383.887659 -401.980641) (xy 383.846468 -401.94495) (xy 383.810777 -401.903759) (xy 383.781311 -401.857909)
			(xy 383.758669 -401.808332) (xy 383.743314 -401.756037) (xy 383.735558 -401.702089) (xy 383.735072 -401.674838)
			(xy 383.298192 -401.674838) (xy 383.297706 -401.702089) (xy 383.28995 -401.756037) (xy 383.274595 -401.808332)
			(xy 383.251953 -401.857909) (xy 383.222487 -401.903759) (xy 383.186796 -401.94495) (xy 383.145605 -401.980641)
			(xy 383.099755 -402.010107) (xy 383.050178 -402.032749) (xy 382.997883 -402.048104) (xy 382.943935 -402.05586)
			(xy 382.889433 -402.05586) (xy 382.835485 -402.048104) (xy 382.78319 -402.032749) (xy 382.733613 -402.010107)
			(xy 382.687763 -401.980641) (xy 382.646572 -401.94495) (xy 382.610881 -401.903759) (xy 382.581415 -401.857909)
			(xy 382.558773 -401.808332) (xy 382.543418 -401.756037) (xy 382.535662 -401.702089) (xy 382.535176 -401.674838)
			(xy 382.098296 -401.674838) (xy 382.09781 -401.702107) (xy 382.090048 -401.756091) (xy 382.074683 -401.808421)
			(xy 382.052026 -401.858031) (xy 382.02254 -401.903912) (xy 381.986825 -401.945129) (xy 381.945608 -401.980844)
			(xy 381.899727 -402.01033) (xy 381.850117 -402.032987) (xy 381.797787 -402.048352) (xy 381.743803 -402.056114)
			(xy 381.689265 -402.056114) (xy 381.635281 -402.048352) (xy 381.582951 -402.032987) (xy 381.533341 -402.01033)
			(xy 381.48746 -401.980844) (xy 381.446243 -401.945129) (xy 381.410528 -401.903912) (xy 381.381042 -401.858031)
			(xy 381.358385 -401.808421) (xy 381.34302 -401.756091) (xy 381.335258 -401.702107) (xy 381.334772 -401.674838)
			(xy 380.8984 -401.674838) (xy 380.897914 -401.702107) (xy 380.890152 -401.756091) (xy 380.874787 -401.808421)
			(xy 380.85213 -401.858031) (xy 380.822644 -401.903912) (xy 380.786929 -401.945129) (xy 380.745712 -401.980844)
			(xy 380.699831 -402.01033) (xy 380.650221 -402.032987) (xy 380.597891 -402.048352) (xy 380.543907 -402.056114)
			(xy 380.489369 -402.056114) (xy 380.435385 -402.048352) (xy 380.383055 -402.032987) (xy 380.333445 -402.01033)
			(xy 380.287564 -401.980844) (xy 380.246347 -401.945129) (xy 380.210632 -401.903912) (xy 380.181146 -401.858031)
			(xy 380.158489 -401.808421) (xy 380.143124 -401.756091) (xy 380.135362 -401.702107) (xy 380.134876 -401.674838)
			(xy 379.697996 -401.674838) (xy 379.69751 -401.702089) (xy 379.689754 -401.756037) (xy 379.674399 -401.808332)
			(xy 379.651757 -401.857909) (xy 379.622291 -401.903759) (xy 379.5866 -401.94495) (xy 379.545409 -401.980641)
			(xy 379.499559 -402.010107) (xy 379.449982 -402.032749) (xy 379.397687 -402.048104) (xy 379.343739 -402.05586)
			(xy 379.289237 -402.05586) (xy 379.235289 -402.048104) (xy 379.182994 -402.032749) (xy 379.133417 -402.010107)
			(xy 379.087567 -401.980641) (xy 379.046376 -401.94495) (xy 379.010685 -401.903759) (xy 378.981219 -401.857909)
			(xy 378.958577 -401.808332) (xy 378.943222 -401.756037) (xy 378.935466 -401.702089) (xy 378.93498 -401.674838)
			(xy 378.4981 -401.674838) (xy 378.497614 -401.702089) (xy 378.489858 -401.756037) (xy 378.474503 -401.808332)
			(xy 378.451861 -401.857909) (xy 378.422395 -401.903759) (xy 378.386704 -401.94495) (xy 378.345513 -401.980641)
			(xy 378.299663 -402.010107) (xy 378.250086 -402.032749) (xy 378.197791 -402.048104) (xy 378.143843 -402.05586)
			(xy 378.089341 -402.05586) (xy 378.035393 -402.048104) (xy 377.983098 -402.032749) (xy 377.933521 -402.010107)
			(xy 377.887671 -401.980641) (xy 377.84648 -401.94495) (xy 377.810789 -401.903759) (xy 377.781323 -401.857909)
			(xy 377.758681 -401.808332) (xy 377.743326 -401.756037) (xy 377.73557 -401.702089) (xy 377.735084 -401.674838)
			(xy 377.298204 -401.674838) (xy 377.297718 -401.702107) (xy 377.289956 -401.756091) (xy 377.274591 -401.808421)
			(xy 377.251934 -401.858031) (xy 377.222448 -401.903912) (xy 377.186733 -401.945129) (xy 377.145516 -401.980844)
			(xy 377.099635 -402.01033) (xy 377.050025 -402.032987) (xy 376.997695 -402.048352) (xy 376.943711 -402.056114)
			(xy 376.889173 -402.056114) (xy 376.835189 -402.048352) (xy 376.782859 -402.032987) (xy 376.733249 -402.01033)
			(xy 376.687368 -401.980844) (xy 376.646151 -401.945129) (xy 376.610436 -401.903912) (xy 376.58095 -401.858031)
			(xy 376.558293 -401.808421) (xy 376.542928 -401.756091) (xy 376.535166 -401.702107) (xy 376.53468 -401.674838)
			(xy 376.098308 -401.674838) (xy 376.097822 -401.702107) (xy 376.09006 -401.756091) (xy 376.074695 -401.808421)
			(xy 376.052038 -401.858031) (xy 376.022552 -401.903912) (xy 375.986837 -401.945129) (xy 375.94562 -401.980844)
			(xy 375.899739 -402.01033) (xy 375.850129 -402.032987) (xy 375.797799 -402.048352) (xy 375.743815 -402.056114)
			(xy 375.689277 -402.056114) (xy 375.635293 -402.048352) (xy 375.582963 -402.032987) (xy 375.533353 -402.01033)
			(xy 375.487472 -401.980844) (xy 375.446255 -401.945129) (xy 375.41054 -401.903912) (xy 375.381054 -401.858031)
			(xy 375.358397 -401.808421) (xy 375.343032 -401.756091) (xy 375.33527 -401.702107) (xy 375.334784 -401.674838)
			(xy 374.897904 -401.674838) (xy 374.897418 -401.702089) (xy 374.889662 -401.756037) (xy 374.874307 -401.808332)
			(xy 374.851665 -401.857909) (xy 374.822199 -401.903759) (xy 374.786508 -401.94495) (xy 374.745317 -401.980641)
			(xy 374.699467 -402.010107) (xy 374.64989 -402.032749) (xy 374.597595 -402.048104) (xy 374.543647 -402.05586)
			(xy 374.489145 -402.05586) (xy 374.435197 -402.048104) (xy 374.382902 -402.032749) (xy 374.333325 -402.010107)
			(xy 374.287475 -401.980641) (xy 374.246284 -401.94495) (xy 374.210593 -401.903759) (xy 374.181127 -401.857909)
			(xy 374.158485 -401.808332) (xy 374.14313 -401.756037) (xy 374.135374 -401.702089) (xy 374.134888 -401.674838)
			(xy 373.698008 -401.674838) (xy 373.697522 -401.702089) (xy 373.689766 -401.756037) (xy 373.674411 -401.808332)
			(xy 373.651769 -401.857909) (xy 373.622303 -401.903759) (xy 373.586612 -401.94495) (xy 373.545421 -401.980641)
			(xy 373.499571 -402.010107) (xy 373.449994 -402.032749) (xy 373.397699 -402.048104) (xy 373.343751 -402.05586)
			(xy 373.289249 -402.05586) (xy 373.235301 -402.048104) (xy 373.183006 -402.032749) (xy 373.133429 -402.010107)
			(xy 373.087579 -401.980641) (xy 373.046388 -401.94495) (xy 373.010697 -401.903759) (xy 372.981231 -401.857909)
			(xy 372.958589 -401.808332) (xy 372.943234 -401.756037) (xy 372.935478 -401.702089) (xy 372.934992 -401.674838)
			(xy 372.498112 -401.674838) (xy 372.497626 -401.702107) (xy 372.489864 -401.756091) (xy 372.474499 -401.808421)
			(xy 372.451842 -401.858031) (xy 372.422356 -401.903912) (xy 372.386641 -401.945129) (xy 372.345424 -401.980844)
			(xy 372.299543 -402.01033) (xy 372.249933 -402.032987) (xy 372.197603 -402.048352) (xy 372.143619 -402.056114)
			(xy 372.089081 -402.056114) (xy 372.035097 -402.048352) (xy 371.982767 -402.032987) (xy 371.933157 -402.01033)
			(xy 371.887276 -401.980844) (xy 371.846059 -401.945129) (xy 371.810344 -401.903912) (xy 371.780858 -401.858031)
			(xy 371.758201 -401.808421) (xy 371.742836 -401.756091) (xy 371.735074 -401.702107) (xy 371.734588 -401.674838)
			(xy 371.298216 -401.674838) (xy 371.29773 -401.702107) (xy 371.289968 -401.756091) (xy 371.274603 -401.808421)
			(xy 371.251946 -401.858031) (xy 371.22246 -401.903912) (xy 371.186745 -401.945129) (xy 371.145528 -401.980844)
			(xy 371.099647 -402.01033) (xy 371.050037 -402.032987) (xy 370.997707 -402.048352) (xy 370.943723 -402.056114)
			(xy 370.889185 -402.056114) (xy 370.835201 -402.048352) (xy 370.782871 -402.032987) (xy 370.733261 -402.01033)
			(xy 370.68738 -401.980844) (xy 370.646163 -401.945129) (xy 370.610448 -401.903912) (xy 370.580962 -401.858031)
			(xy 370.558305 -401.808421) (xy 370.54294 -401.756091) (xy 370.535178 -401.702107) (xy 370.534692 -401.674838)
			(xy 354.725732 -401.674838) (xy 354.725246 -401.702107) (xy 354.717484 -401.756091) (xy 354.702119 -401.808421)
			(xy 354.679462 -401.858031) (xy 354.649976 -401.903912) (xy 354.614261 -401.945129) (xy 354.573044 -401.980844)
			(xy 354.527163 -402.01033) (xy 354.477553 -402.032987) (xy 354.425223 -402.048352) (xy 354.371239 -402.056114)
			(xy 354.316701 -402.056114) (xy 354.262717 -402.048352) (xy 354.210387 -402.032987) (xy 354.160777 -402.01033)
			(xy 354.114896 -401.980844) (xy 354.073679 -401.945129) (xy 354.037964 -401.903912) (xy 354.008478 -401.858031)
			(xy 353.985821 -401.808421) (xy 353.970456 -401.756091) (xy 353.962694 -401.702107) (xy 353.962208 -401.674838)
			(xy 353.525836 -401.674838) (xy 353.52535 -401.702107) (xy 353.517588 -401.756091) (xy 353.502223 -401.808421)
			(xy 353.479566 -401.858031) (xy 353.45008 -401.903912) (xy 353.414365 -401.945129) (xy 353.373148 -401.980844)
			(xy 353.327267 -402.01033) (xy 353.277657 -402.032987) (xy 353.225327 -402.048352) (xy 353.171343 -402.056114)
			(xy 353.116805 -402.056114) (xy 353.062821 -402.048352) (xy 353.010491 -402.032987) (xy 352.960881 -402.01033)
			(xy 352.915 -401.980844) (xy 352.873783 -401.945129) (xy 352.838068 -401.903912) (xy 352.808582 -401.858031)
			(xy 352.785925 -401.808421) (xy 352.77056 -401.756091) (xy 352.762798 -401.702107) (xy 352.762312 -401.674838)
			(xy 352.325432 -401.674838) (xy 352.324946 -401.702089) (xy 352.31719 -401.756037) (xy 352.301835 -401.808332)
			(xy 352.279193 -401.857909) (xy 352.249727 -401.903759) (xy 352.214036 -401.94495) (xy 352.172845 -401.980641)
			(xy 352.126995 -402.010107) (xy 352.077418 -402.032749) (xy 352.025123 -402.048104) (xy 351.971175 -402.05586)
			(xy 351.916673 -402.05586) (xy 351.862725 -402.048104) (xy 351.81043 -402.032749) (xy 351.760853 -402.010107)
			(xy 351.715003 -401.980641) (xy 351.673812 -401.94495) (xy 351.638121 -401.903759) (xy 351.608655 -401.857909)
			(xy 351.586013 -401.808332) (xy 351.570658 -401.756037) (xy 351.562902 -401.702089) (xy 351.562416 -401.674838)
			(xy 351.125536 -401.674838) (xy 351.12505 -401.702089) (xy 351.117294 -401.756037) (xy 351.101939 -401.808332)
			(xy 351.079297 -401.857909) (xy 351.049831 -401.903759) (xy 351.01414 -401.94495) (xy 350.972949 -401.980641)
			(xy 350.927099 -402.010107) (xy 350.877522 -402.032749) (xy 350.825227 -402.048104) (xy 350.771279 -402.05586)
			(xy 350.716777 -402.05586) (xy 350.662829 -402.048104) (xy 350.610534 -402.032749) (xy 350.560957 -402.010107)
			(xy 350.515107 -401.980641) (xy 350.473916 -401.94495) (xy 350.438225 -401.903759) (xy 350.408759 -401.857909)
			(xy 350.386117 -401.808332) (xy 350.370762 -401.756037) (xy 350.363006 -401.702089) (xy 350.36252 -401.674838)
			(xy 349.92564 -401.674838) (xy 349.925154 -401.702089) (xy 349.917398 -401.756037) (xy 349.902043 -401.808332)
			(xy 349.879401 -401.857909) (xy 349.849935 -401.903759) (xy 349.814244 -401.94495) (xy 349.773053 -401.980641)
			(xy 349.727203 -402.010107) (xy 349.677626 -402.032749) (xy 349.625331 -402.048104) (xy 349.571383 -402.05586)
			(xy 349.516881 -402.05586) (xy 349.462933 -402.048104) (xy 349.410638 -402.032749) (xy 349.361061 -402.010107)
			(xy 349.315211 -401.980641) (xy 349.27402 -401.94495) (xy 349.238329 -401.903759) (xy 349.208863 -401.857909)
			(xy 349.186221 -401.808332) (xy 349.170866 -401.756037) (xy 349.16311 -401.702089) (xy 349.162624 -401.674838)
			(xy 348.725744 -401.674838) (xy 348.725258 -401.702089) (xy 348.717502 -401.756037) (xy 348.702147 -401.808332)
			(xy 348.679505 -401.857909) (xy 348.650039 -401.903759) (xy 348.614348 -401.94495) (xy 348.573157 -401.980641)
			(xy 348.527307 -402.010107) (xy 348.47773 -402.032749) (xy 348.425435 -402.048104) (xy 348.371487 -402.05586)
			(xy 348.316985 -402.05586) (xy 348.263037 -402.048104) (xy 348.210742 -402.032749) (xy 348.161165 -402.010107)
			(xy 348.115315 -401.980641) (xy 348.074124 -401.94495) (xy 348.038433 -401.903759) (xy 348.008967 -401.857909)
			(xy 347.986325 -401.808332) (xy 347.97097 -401.756037) (xy 347.963214 -401.702089) (xy 347.962728 -401.674838)
			(xy 347.525848 -401.674838) (xy 347.525362 -401.702107) (xy 347.5176 -401.756091) (xy 347.502235 -401.808421)
			(xy 347.479578 -401.858031) (xy 347.450092 -401.903912) (xy 347.414377 -401.945129) (xy 347.37316 -401.980844)
			(xy 347.327279 -402.01033) (xy 347.277669 -402.032987) (xy 347.225339 -402.048352) (xy 347.171355 -402.056114)
			(xy 347.116817 -402.056114) (xy 347.062833 -402.048352) (xy 347.010503 -402.032987) (xy 346.960893 -402.01033)
			(xy 346.915012 -401.980844) (xy 346.873795 -401.945129) (xy 346.83808 -401.903912) (xy 346.808594 -401.858031)
			(xy 346.785937 -401.808421) (xy 346.770572 -401.756091) (xy 346.76281 -401.702107) (xy 346.762324 -401.674838)
			(xy 346.325952 -401.674838) (xy 346.325466 -401.702107) (xy 346.317704 -401.756091) (xy 346.302339 -401.808421)
			(xy 346.279682 -401.858031) (xy 346.250196 -401.903912) (xy 346.214481 -401.945129) (xy 346.173264 -401.980844)
			(xy 346.127383 -402.01033) (xy 346.077773 -402.032987) (xy 346.025443 -402.048352) (xy 345.971459 -402.056114)
			(xy 345.916921 -402.056114) (xy 345.862937 -402.048352) (xy 345.810607 -402.032987) (xy 345.760997 -402.01033)
			(xy 345.715116 -401.980844) (xy 345.673899 -401.945129) (xy 345.638184 -401.903912) (xy 345.608698 -401.858031)
			(xy 345.586041 -401.808421) (xy 345.570676 -401.756091) (xy 345.562914 -401.702107) (xy 345.562428 -401.674838)
			(xy 345.125548 -401.674838) (xy 345.125062 -401.702089) (xy 345.117306 -401.756037) (xy 345.101951 -401.808332)
			(xy 345.079309 -401.857909) (xy 345.049843 -401.903759) (xy 345.014152 -401.94495) (xy 344.972961 -401.980641)
			(xy 344.927111 -402.010107) (xy 344.877534 -402.032749) (xy 344.825239 -402.048104) (xy 344.771291 -402.05586)
			(xy 344.716789 -402.05586) (xy 344.662841 -402.048104) (xy 344.610546 -402.032749) (xy 344.560969 -402.010107)
			(xy 344.515119 -401.980641) (xy 344.473928 -401.94495) (xy 344.438237 -401.903759) (xy 344.408771 -401.857909)
			(xy 344.386129 -401.808332) (xy 344.370774 -401.756037) (xy 344.363018 -401.702089) (xy 344.362532 -401.674838)
			(xy 343.925652 -401.674838) (xy 343.925166 -401.702089) (xy 343.91741 -401.756037) (xy 343.902055 -401.808332)
			(xy 343.879413 -401.857909) (xy 343.849947 -401.903759) (xy 343.814256 -401.94495) (xy 343.773065 -401.980641)
			(xy 343.727215 -402.010107) (xy 343.677638 -402.032749) (xy 343.625343 -402.048104) (xy 343.571395 -402.05586)
			(xy 343.516893 -402.05586) (xy 343.462945 -402.048104) (xy 343.41065 -402.032749) (xy 343.361073 -402.010107)
			(xy 343.315223 -401.980641) (xy 343.274032 -401.94495) (xy 343.238341 -401.903759) (xy 343.208875 -401.857909)
			(xy 343.186233 -401.808332) (xy 343.170878 -401.756037) (xy 343.163122 -401.702089) (xy 343.162636 -401.674838)
			(xy 342.725756 -401.674838) (xy 342.72527 -401.702107) (xy 342.717508 -401.756091) (xy 342.702143 -401.808421)
			(xy 342.679486 -401.858031) (xy 342.65 -401.903912) (xy 342.614285 -401.945129) (xy 342.573068 -401.980844)
			(xy 342.527187 -402.01033) (xy 342.477577 -402.032987) (xy 342.425247 -402.048352) (xy 342.371263 -402.056114)
			(xy 342.316725 -402.056114) (xy 342.262741 -402.048352) (xy 342.210411 -402.032987) (xy 342.160801 -402.01033)
			(xy 342.11492 -401.980844) (xy 342.073703 -401.945129) (xy 342.037988 -401.903912) (xy 342.008502 -401.858031)
			(xy 341.985845 -401.808421) (xy 341.97048 -401.756091) (xy 341.962718 -401.702107) (xy 341.962232 -401.674838)
			(xy 341.52586 -401.674838) (xy 341.525374 -401.702107) (xy 341.517612 -401.756091) (xy 341.502247 -401.808421)
			(xy 341.47959 -401.858031) (xy 341.450104 -401.903912) (xy 341.414389 -401.945129) (xy 341.373172 -401.980844)
			(xy 341.327291 -402.01033) (xy 341.277681 -402.032987) (xy 341.225351 -402.048352) (xy 341.171367 -402.056114)
			(xy 341.116829 -402.056114) (xy 341.062845 -402.048352) (xy 341.010515 -402.032987) (xy 340.960905 -402.01033)
			(xy 340.915024 -401.980844) (xy 340.873807 -401.945129) (xy 340.838092 -401.903912) (xy 340.808606 -401.858031)
			(xy 340.785949 -401.808421) (xy 340.770584 -401.756091) (xy 340.762822 -401.702107) (xy 340.762336 -401.674838)
			(xy 340.325456 -401.674838) (xy 340.32497 -401.702089) (xy 340.317214 -401.756037) (xy 340.301859 -401.808332)
			(xy 340.279217 -401.857909) (xy 340.249751 -401.903759) (xy 340.21406 -401.94495) (xy 340.172869 -401.980641)
			(xy 340.127019 -402.010107) (xy 340.077442 -402.032749) (xy 340.025147 -402.048104) (xy 339.971199 -402.05586)
			(xy 339.916697 -402.05586) (xy 339.862749 -402.048104) (xy 339.810454 -402.032749) (xy 339.760877 -402.010107)
			(xy 339.715027 -401.980641) (xy 339.673836 -401.94495) (xy 339.638145 -401.903759) (xy 339.608679 -401.857909)
			(xy 339.586037 -401.808332) (xy 339.570682 -401.756037) (xy 339.562926 -401.702089) (xy 339.56244 -401.674838)
			(xy 339.12556 -401.674838) (xy 339.125074 -401.702089) (xy 339.117318 -401.756037) (xy 339.101963 -401.808332)
			(xy 339.079321 -401.857909) (xy 339.049855 -401.903759) (xy 339.014164 -401.94495) (xy 338.972973 -401.980641)
			(xy 338.927123 -402.010107) (xy 338.877546 -402.032749) (xy 338.825251 -402.048104) (xy 338.771303 -402.05586)
			(xy 338.716801 -402.05586) (xy 338.662853 -402.048104) (xy 338.610558 -402.032749) (xy 338.560981 -402.010107)
			(xy 338.515131 -401.980641) (xy 338.47394 -401.94495) (xy 338.438249 -401.903759) (xy 338.408783 -401.857909)
			(xy 338.386141 -401.808332) (xy 338.370786 -401.756037) (xy 338.36303 -401.702089) (xy 338.362544 -401.674838)
			(xy 337.925664 -401.674838) (xy 337.925178 -401.702107) (xy 337.917416 -401.756091) (xy 337.902051 -401.808421)
			(xy 337.879394 -401.858031) (xy 337.849908 -401.903912) (xy 337.814193 -401.945129) (xy 337.772976 -401.980844)
			(xy 337.727095 -402.01033) (xy 337.677485 -402.032987) (xy 337.625155 -402.048352) (xy 337.571171 -402.056114)
			(xy 337.516633 -402.056114) (xy 337.462649 -402.048352) (xy 337.410319 -402.032987) (xy 337.360709 -402.01033)
			(xy 337.314828 -401.980844) (xy 337.273611 -401.945129) (xy 337.237896 -401.903912) (xy 337.20841 -401.858031)
			(xy 337.185753 -401.808421) (xy 337.170388 -401.756091) (xy 337.162626 -401.702107) (xy 337.16214 -401.674838)
			(xy 336.725768 -401.674838) (xy 336.725282 -401.702107) (xy 336.71752 -401.756091) (xy 336.702155 -401.808421)
			(xy 336.679498 -401.858031) (xy 336.650012 -401.903912) (xy 336.614297 -401.945129) (xy 336.57308 -401.980844)
			(xy 336.527199 -402.01033) (xy 336.477589 -402.032987) (xy 336.425259 -402.048352) (xy 336.371275 -402.056114)
			(xy 336.316737 -402.056114) (xy 336.262753 -402.048352) (xy 336.210423 -402.032987) (xy 336.160813 -402.01033)
			(xy 336.114932 -401.980844) (xy 336.073715 -401.945129) (xy 336.038 -401.903912) (xy 336.008514 -401.858031)
			(xy 335.985857 -401.808421) (xy 335.970492 -401.756091) (xy 335.96273 -401.702107) (xy 335.962244 -401.674838)
			(xy 322.197984 -401.674838) (xy 322.197498 -401.702107) (xy 322.189736 -401.756091) (xy 322.174371 -401.808421)
			(xy 322.151714 -401.858031) (xy 322.122228 -401.903912) (xy 322.086513 -401.945129) (xy 322.045296 -401.980844)
			(xy 321.999415 -402.01033) (xy 321.949805 -402.032987) (xy 321.897475 -402.048352) (xy 321.843491 -402.056114)
			(xy 321.788953 -402.056114) (xy 321.734969 -402.048352) (xy 321.682639 -402.032987) (xy 321.633029 -402.01033)
			(xy 321.587148 -401.980844) (xy 321.545931 -401.945129) (xy 321.510216 -401.903912) (xy 321.48073 -401.858031)
			(xy 321.458073 -401.808421) (xy 321.442708 -401.756091) (xy 321.434946 -401.702107) (xy 321.43446 -401.674838)
			(xy 320.998088 -401.674838) (xy 320.997602 -401.702107) (xy 320.98984 -401.756091) (xy 320.974475 -401.808421)
			(xy 320.951818 -401.858031) (xy 320.922332 -401.903912) (xy 320.886617 -401.945129) (xy 320.8454 -401.980844)
			(xy 320.799519 -402.01033) (xy 320.749909 -402.032987) (xy 320.697579 -402.048352) (xy 320.643595 -402.056114)
			(xy 320.589057 -402.056114) (xy 320.535073 -402.048352) (xy 320.482743 -402.032987) (xy 320.433133 -402.01033)
			(xy 320.387252 -401.980844) (xy 320.346035 -401.945129) (xy 320.31032 -401.903912) (xy 320.280834 -401.858031)
			(xy 320.258177 -401.808421) (xy 320.242812 -401.756091) (xy 320.23505 -401.702107) (xy 320.234564 -401.674838)
			(xy 319.797684 -401.674838) (xy 319.797198 -401.702089) (xy 319.789442 -401.756037) (xy 319.774087 -401.808332)
			(xy 319.751445 -401.857909) (xy 319.721979 -401.903759) (xy 319.686288 -401.94495) (xy 319.645097 -401.980641)
			(xy 319.599247 -402.010107) (xy 319.54967 -402.032749) (xy 319.497375 -402.048104) (xy 319.443427 -402.05586)
			(xy 319.388925 -402.05586) (xy 319.334977 -402.048104) (xy 319.282682 -402.032749) (xy 319.233105 -402.010107)
			(xy 319.187255 -401.980641) (xy 319.146064 -401.94495) (xy 319.110373 -401.903759) (xy 319.080907 -401.857909)
			(xy 319.058265 -401.808332) (xy 319.04291 -401.756037) (xy 319.035154 -401.702089) (xy 319.034668 -401.674838)
			(xy 318.597788 -401.674838) (xy 318.597302 -401.702089) (xy 318.589546 -401.756037) (xy 318.574191 -401.808332)
			(xy 318.551549 -401.857909) (xy 318.522083 -401.903759) (xy 318.486392 -401.94495) (xy 318.445201 -401.980641)
			(xy 318.399351 -402.010107) (xy 318.349774 -402.032749) (xy 318.297479 -402.048104) (xy 318.243531 -402.05586)
			(xy 318.189029 -402.05586) (xy 318.135081 -402.048104) (xy 318.082786 -402.032749) (xy 318.033209 -402.010107)
			(xy 317.987359 -401.980641) (xy 317.946168 -401.94495) (xy 317.910477 -401.903759) (xy 317.881011 -401.857909)
			(xy 317.858369 -401.808332) (xy 317.843014 -401.756037) (xy 317.835258 -401.702089) (xy 317.834772 -401.674838)
			(xy 317.397892 -401.674838) (xy 317.397406 -401.702089) (xy 317.38965 -401.756037) (xy 317.374295 -401.808332)
			(xy 317.351653 -401.857909) (xy 317.322187 -401.903759) (xy 317.286496 -401.94495) (xy 317.245305 -401.980641)
			(xy 317.199455 -402.010107) (xy 317.149878 -402.032749) (xy 317.097583 -402.048104) (xy 317.043635 -402.05586)
			(xy 316.989133 -402.05586) (xy 316.935185 -402.048104) (xy 316.88289 -402.032749) (xy 316.833313 -402.010107)
			(xy 316.787463 -401.980641) (xy 316.746272 -401.94495) (xy 316.710581 -401.903759) (xy 316.681115 -401.857909)
			(xy 316.658473 -401.808332) (xy 316.643118 -401.756037) (xy 316.635362 -401.702089) (xy 316.634876 -401.674838)
			(xy 316.197996 -401.674838) (xy 316.19751 -401.702089) (xy 316.189754 -401.756037) (xy 316.174399 -401.808332)
			(xy 316.151757 -401.857909) (xy 316.122291 -401.903759) (xy 316.0866 -401.94495) (xy 316.045409 -401.980641)
			(xy 315.999559 -402.010107) (xy 315.949982 -402.032749) (xy 315.897687 -402.048104) (xy 315.843739 -402.05586)
			(xy 315.789237 -402.05586) (xy 315.735289 -402.048104) (xy 315.682994 -402.032749) (xy 315.633417 -402.010107)
			(xy 315.587567 -401.980641) (xy 315.546376 -401.94495) (xy 315.510685 -401.903759) (xy 315.481219 -401.857909)
			(xy 315.458577 -401.808332) (xy 315.443222 -401.756037) (xy 315.435466 -401.702089) (xy 315.43498 -401.674838)
			(xy 314.9981 -401.674838) (xy 314.997614 -401.702107) (xy 314.989852 -401.756091) (xy 314.974487 -401.808421)
			(xy 314.95183 -401.858031) (xy 314.922344 -401.903912) (xy 314.886629 -401.945129) (xy 314.845412 -401.980844)
			(xy 314.799531 -402.01033) (xy 314.749921 -402.032987) (xy 314.697591 -402.048352) (xy 314.643607 -402.056114)
			(xy 314.589069 -402.056114) (xy 314.535085 -402.048352) (xy 314.482755 -402.032987) (xy 314.433145 -402.01033)
			(xy 314.387264 -401.980844) (xy 314.346047 -401.945129) (xy 314.310332 -401.903912) (xy 314.280846 -401.858031)
			(xy 314.258189 -401.808421) (xy 314.242824 -401.756091) (xy 314.235062 -401.702107) (xy 314.234576 -401.674838)
			(xy 313.798204 -401.674838) (xy 313.797718 -401.702107) (xy 313.789956 -401.756091) (xy 313.774591 -401.808421)
			(xy 313.751934 -401.858031) (xy 313.722448 -401.903912) (xy 313.686733 -401.945129) (xy 313.645516 -401.980844)
			(xy 313.599635 -402.01033) (xy 313.550025 -402.032987) (xy 313.497695 -402.048352) (xy 313.443711 -402.056114)
			(xy 313.389173 -402.056114) (xy 313.335189 -402.048352) (xy 313.282859 -402.032987) (xy 313.233249 -402.01033)
			(xy 313.187368 -401.980844) (xy 313.146151 -401.945129) (xy 313.110436 -401.903912) (xy 313.08095 -401.858031)
			(xy 313.058293 -401.808421) (xy 313.042928 -401.756091) (xy 313.035166 -401.702107) (xy 313.03468 -401.674838)
			(xy 312.5978 -401.674838) (xy 312.597314 -401.702089) (xy 312.589558 -401.756037) (xy 312.574203 -401.808332)
			(xy 312.551561 -401.857909) (xy 312.522095 -401.903759) (xy 312.486404 -401.94495) (xy 312.445213 -401.980641)
			(xy 312.399363 -402.010107) (xy 312.349786 -402.032749) (xy 312.297491 -402.048104) (xy 312.243543 -402.05586)
			(xy 312.189041 -402.05586) (xy 312.135093 -402.048104) (xy 312.082798 -402.032749) (xy 312.033221 -402.010107)
			(xy 311.987371 -401.980641) (xy 311.94618 -401.94495) (xy 311.910489 -401.903759) (xy 311.881023 -401.857909)
			(xy 311.858381 -401.808332) (xy 311.843026 -401.756037) (xy 311.83527 -401.702089) (xy 311.834784 -401.674838)
			(xy 311.397904 -401.674838) (xy 311.397418 -401.702089) (xy 311.389662 -401.756037) (xy 311.374307 -401.808332)
			(xy 311.351665 -401.857909) (xy 311.322199 -401.903759) (xy 311.286508 -401.94495) (xy 311.245317 -401.980641)
			(xy 311.199467 -402.010107) (xy 311.14989 -402.032749) (xy 311.097595 -402.048104) (xy 311.043647 -402.05586)
			(xy 310.989145 -402.05586) (xy 310.935197 -402.048104) (xy 310.882902 -402.032749) (xy 310.833325 -402.010107)
			(xy 310.787475 -401.980641) (xy 310.746284 -401.94495) (xy 310.710593 -401.903759) (xy 310.681127 -401.857909)
			(xy 310.658485 -401.808332) (xy 310.64313 -401.756037) (xy 310.635374 -401.702089) (xy 310.634888 -401.674838)
			(xy 310.198008 -401.674838) (xy 310.197522 -401.702107) (xy 310.18976 -401.756091) (xy 310.174395 -401.808421)
			(xy 310.151738 -401.858031) (xy 310.122252 -401.903912) (xy 310.086537 -401.945129) (xy 310.04532 -401.980844)
			(xy 309.999439 -402.01033) (xy 309.949829 -402.032987) (xy 309.897499 -402.048352) (xy 309.843515 -402.056114)
			(xy 309.788977 -402.056114) (xy 309.734993 -402.048352) (xy 309.682663 -402.032987) (xy 309.633053 -402.01033)
			(xy 309.587172 -401.980844) (xy 309.545955 -401.945129) (xy 309.51024 -401.903912) (xy 309.480754 -401.858031)
			(xy 309.458097 -401.808421) (xy 309.442732 -401.756091) (xy 309.43497 -401.702107) (xy 309.434484 -401.674838)
			(xy 308.998112 -401.674838) (xy 308.997626 -401.702107) (xy 308.989864 -401.756091) (xy 308.974499 -401.808421)
			(xy 308.951842 -401.858031) (xy 308.922356 -401.903912) (xy 308.886641 -401.945129) (xy 308.845424 -401.980844)
			(xy 308.799543 -402.01033) (xy 308.749933 -402.032987) (xy 308.697603 -402.048352) (xy 308.643619 -402.056114)
			(xy 308.589081 -402.056114) (xy 308.535097 -402.048352) (xy 308.482767 -402.032987) (xy 308.433157 -402.01033)
			(xy 308.387276 -401.980844) (xy 308.346059 -401.945129) (xy 308.310344 -401.903912) (xy 308.280858 -401.858031)
			(xy 308.258201 -401.808421) (xy 308.242836 -401.756091) (xy 308.235074 -401.702107) (xy 308.234588 -401.674838)
			(xy 307.797708 -401.674838) (xy 307.797222 -401.702089) (xy 307.789466 -401.756037) (xy 307.774111 -401.808332)
			(xy 307.751469 -401.857909) (xy 307.722003 -401.903759) (xy 307.686312 -401.94495) (xy 307.645121 -401.980641)
			(xy 307.599271 -402.010107) (xy 307.549694 -402.032749) (xy 307.497399 -402.048104) (xy 307.443451 -402.05586)
			(xy 307.388949 -402.05586) (xy 307.335001 -402.048104) (xy 307.282706 -402.032749) (xy 307.233129 -402.010107)
			(xy 307.187279 -401.980641) (xy 307.146088 -401.94495) (xy 307.110397 -401.903759) (xy 307.080931 -401.857909)
			(xy 307.058289 -401.808332) (xy 307.042934 -401.756037) (xy 307.035178 -401.702089) (xy 307.034692 -401.674838)
			(xy 306.597812 -401.674838) (xy 306.597326 -401.702089) (xy 306.58957 -401.756037) (xy 306.574215 -401.808332)
			(xy 306.551573 -401.857909) (xy 306.522107 -401.903759) (xy 306.486416 -401.94495) (xy 306.445225 -401.980641)
			(xy 306.399375 -402.010107) (xy 306.349798 -402.032749) (xy 306.297503 -402.048104) (xy 306.243555 -402.05586)
			(xy 306.189053 -402.05586) (xy 306.135105 -402.048104) (xy 306.08281 -402.032749) (xy 306.033233 -402.010107)
			(xy 305.987383 -401.980641) (xy 305.946192 -401.94495) (xy 305.910501 -401.903759) (xy 305.881035 -401.857909)
			(xy 305.858393 -401.808332) (xy 305.843038 -401.756037) (xy 305.835282 -401.702089) (xy 305.834796 -401.674838)
			(xy 305.397916 -401.674838) (xy 305.39743 -401.702107) (xy 305.389668 -401.756091) (xy 305.374303 -401.808421)
			(xy 305.351646 -401.858031) (xy 305.32216 -401.903912) (xy 305.286445 -401.945129) (xy 305.245228 -401.980844)
			(xy 305.199347 -402.01033) (xy 305.149737 -402.032987) (xy 305.097407 -402.048352) (xy 305.043423 -402.056114)
			(xy 304.988885 -402.056114) (xy 304.934901 -402.048352) (xy 304.882571 -402.032987) (xy 304.832961 -402.01033)
			(xy 304.78708 -401.980844) (xy 304.745863 -401.945129) (xy 304.710148 -401.903912) (xy 304.680662 -401.858031)
			(xy 304.658005 -401.808421) (xy 304.64264 -401.756091) (xy 304.634878 -401.702107) (xy 304.634392 -401.674838)
			(xy 304.19802 -401.674838) (xy 304.197534 -401.702107) (xy 304.189772 -401.756091) (xy 304.174407 -401.808421)
			(xy 304.15175 -401.858031) (xy 304.122264 -401.903912) (xy 304.086549 -401.945129) (xy 304.045332 -401.980844)
			(xy 303.999451 -402.01033) (xy 303.949841 -402.032987) (xy 303.897511 -402.048352) (xy 303.843527 -402.056114)
			(xy 303.788989 -402.056114) (xy 303.735005 -402.048352) (xy 303.682675 -402.032987) (xy 303.633065 -402.01033)
			(xy 303.587184 -401.980844) (xy 303.545967 -401.945129) (xy 303.510252 -401.903912) (xy 303.480766 -401.858031)
			(xy 303.458109 -401.808421) (xy 303.442744 -401.756091) (xy 303.434982 -401.702107) (xy 303.434496 -401.674838)
			(xy 280.68524 -401.674838) (xy 280.68524 -404.215092) (xy 283.62402 -404.215092) (xy 283.62402 -403.351492)
			(xy 283.624506 -403.324223) (xy 283.632268 -403.270239) (xy 283.647633 -403.217909) (xy 283.67029 -403.168299)
			(xy 283.699776 -403.122418) (xy 283.735491 -403.081201) (xy 283.776708 -403.045486) (xy 283.822589 -403.016)
			(xy 283.872199 -402.993343) (xy 283.924529 -402.977978) (xy 283.978513 -402.970216) (xy 284.033051 -402.970216)
			(xy 284.087035 -402.977978) (xy 284.139365 -402.993343) (xy 284.188975 -403.016) (xy 284.203533 -403.025356)
			(xy 289.919156 -403.025356) (xy 289.919156 -402.161756) (xy 289.919642 -402.134487) (xy 289.927404 -402.080503)
			(xy 289.942769 -402.028173) (xy 289.965426 -401.978563) (xy 289.994912 -401.932682) (xy 290.030627 -401.891465)
			(xy 290.071844 -401.85575) (xy 290.117725 -401.826264) (xy 290.167335 -401.803607) (xy 290.219665 -401.788242)
			(xy 290.273649 -401.78048) (xy 290.328187 -401.78048) (xy 290.382171 -401.788242) (xy 290.434501 -401.803607)
			(xy 290.484111 -401.826264) (xy 290.529992 -401.85575) (xy 290.571209 -401.891465) (xy 290.606924 -401.932682)
			(xy 290.63641 -401.978563) (xy 290.659067 -402.028173) (xy 290.674432 -402.080503) (xy 290.682194 -402.134487)
			(xy 290.68268 -402.161756) (xy 290.68268 -403.025356) (xy 290.682194 -403.052625) (xy 290.674432 -403.106609)
			(xy 290.659067 -403.158939) (xy 290.63641 -403.208549) (xy 290.606924 -403.25443) (xy 290.571209 -403.295647)
			(xy 290.529992 -403.331362) (xy 290.484111 -403.360848) (xy 290.434501 -403.383505) (xy 290.382171 -403.39887)
			(xy 290.328187 -403.406632) (xy 290.273649 -403.406632) (xy 290.219665 -403.39887) (xy 290.167335 -403.383505)
			(xy 290.117725 -403.360848) (xy 290.071844 -403.331362) (xy 290.030627 -403.295647) (xy 289.994912 -403.25443)
			(xy 289.965426 -403.208549) (xy 289.942769 -403.158939) (xy 289.927404 -403.106609) (xy 289.919642 -403.052625)
			(xy 289.919156 -403.025356) (xy 284.203533 -403.025356) (xy 284.234856 -403.045486) (xy 284.276073 -403.081201)
			(xy 284.311788 -403.122418) (xy 284.341274 -403.168299) (xy 284.363931 -403.217909) (xy 284.379296 -403.270239)
			(xy 284.387058 -403.324223) (xy 284.387544 -403.351492) (xy 284.387544 -404.215092) (xy 284.387058 -404.242361)
			(xy 284.379296 -404.296345) (xy 284.363931 -404.348675) (xy 284.341274 -404.398285) (xy 284.311788 -404.444166)
			(xy 284.276073 -404.485383) (xy 284.234856 -404.521098) (xy 284.188975 -404.550584) (xy 284.139365 -404.573241)
			(xy 284.087035 -404.588606) (xy 284.033051 -404.596368) (xy 283.978513 -404.596368) (xy 283.924529 -404.588606)
			(xy 283.872199 -404.573241) (xy 283.822589 -404.550584) (xy 283.776708 -404.521098) (xy 283.735491 -404.485383)
			(xy 283.699776 -404.444166) (xy 283.67029 -404.398285) (xy 283.647633 -404.348675) (xy 283.632268 -404.296345)
			(xy 283.624506 -404.242361) (xy 283.62402 -404.215092) (xy 280.68524 -404.215092) (xy 280.68524 -407.583953)
			(xy 282.536071 -407.583953) (xy 282.536071 -407.529447) (xy 282.543829 -407.475495) (xy 282.559186 -407.423196)
			(xy 282.581831 -407.373615) (xy 282.611301 -407.327762) (xy 282.646997 -407.28657) (xy 282.688193 -407.250878)
			(xy 282.734049 -407.221412) (xy 282.783632 -407.198773) (xy 282.835932 -407.183421) (xy 282.889885 -407.175669)
			(xy 282.917138 -407.175208) (xy 283.780738 -407.175208) (xy 283.807989 -407.175664) (xy 283.861934 -407.183426)
			(xy 283.914227 -407.198785) (xy 283.963801 -407.221429) (xy 284.009649 -407.250898) (xy 284.050836 -407.286591)
			(xy 284.086525 -407.327782) (xy 284.115989 -407.373632) (xy 284.134525 -407.414222) (xy 287.101788 -407.414222)
			(xy 287.101788 -406.550622) (xy 287.102274 -406.523371) (xy 287.11003 -406.469423) (xy 287.125385 -406.417128)
			(xy 287.148027 -406.367551) (xy 287.177493 -406.321701) (xy 287.213184 -406.28051) (xy 287.254375 -406.244819)
			(xy 287.300225 -406.215353) (xy 287.349802 -406.192711) (xy 287.402097 -406.177356) (xy 287.456045 -406.1696)
			(xy 287.510547 -406.1696) (xy 287.564495 -406.177356) (xy 287.61679 -406.192711) (xy 287.666367 -406.215353)
			(xy 287.712217 -406.244819) (xy 287.753408 -406.28051) (xy 287.789099 -406.321701) (xy 287.818565 -406.367551)
			(xy 287.841207 -406.417128) (xy 287.856562 -406.469423) (xy 287.864318 -406.523371) (xy 287.864804 -406.550622)
			(xy 287.864804 -407.414222) (xy 287.864318 -407.441473) (xy 287.856562 -407.495421) (xy 287.841207 -407.547716)
			(xy 287.818565 -407.597293) (xy 287.789099 -407.643143) (xy 287.753408 -407.684334) (xy 287.712217 -407.720025)
			(xy 287.666367 -407.749491) (xy 287.61679 -407.772133) (xy 287.564495 -407.787488) (xy 287.510547 -407.795244)
			(xy 287.456045 -407.795244) (xy 287.402097 -407.787488) (xy 287.349802 -407.772133) (xy 287.300225 -407.749491)
			(xy 287.254375 -407.720025) (xy 287.213184 -407.684334) (xy 287.177493 -407.643143) (xy 287.148027 -407.597293)
			(xy 287.125385 -407.547716) (xy 287.11003 -407.495421) (xy 287.102274 -407.441473) (xy 287.101788 -407.414222)
			(xy 284.134525 -407.414222) (xy 284.138629 -407.423209) (xy 284.153982 -407.475503) (xy 284.161738 -407.529449)
			(xy 284.161738 -407.583951) (xy 284.153982 -407.637897) (xy 284.138629 -407.690191) (xy 284.115989 -407.739768)
			(xy 284.086525 -407.785619) (xy 284.050836 -407.826809) (xy 284.009649 -407.862502) (xy 283.963801 -407.891971)
			(xy 283.914227 -407.914615) (xy 283.861934 -407.929974) (xy 283.807989 -407.937736) (xy 283.780738 -407.938224)
			(xy 282.917138 -407.938224) (xy 282.889885 -407.937731) (xy 282.835932 -407.929979) (xy 282.783632 -407.914627)
			(xy 282.734049 -407.891988) (xy 282.688193 -407.862522) (xy 282.646997 -407.82683) (xy 282.611301 -407.785638)
			(xy 282.581831 -407.739785) (xy 282.559186 -407.690204) (xy 282.543829 -407.637905) (xy 282.536071 -407.583953)
			(xy 280.68524 -407.583953) (xy 280.68524 -409.10256) (xy 280.684766 -409.12751) (xy 280.676946 -409.176794)
			(xy 280.661524 -409.224251) (xy 280.638877 -409.268716) (xy 280.609563 -409.309098) (xy 280.592276 -409.327096)
			(xy 276.749256 -413.170116) (xy 293.568894 -413.170116) (xy 293.572866 -412.991873) (xy 293.584774 -412.813984)
			(xy 293.604595 -412.636802) (xy 293.632289 -412.460678) (xy 293.667801 -412.285963) (xy 293.711061 -412.113004)
			(xy 293.761983 -411.942143) (xy 293.820466 -411.773721) (xy 293.886393 -411.608071) (xy 293.959634 -411.445522)
			(xy 294.040044 -411.286397) (xy 294.127462 -411.131012) (xy 294.221715 -410.979676) (xy 294.322616 -410.832688)
			(xy 294.429965 -410.690341) (xy 294.543548 -410.552918) (xy 294.663141 -410.420691) (xy 294.788505 -410.293922)
			(xy 294.919392 -410.172864) (xy 295.055541 -410.057757) (xy 295.196683 -409.948829) (xy 295.342538 -409.846297)
			(xy 295.492815 -409.750363) (xy 295.647216 -409.66122) (xy 295.805435 -409.579043) (xy 295.967158 -409.503995)
			(xy 296.132063 -409.436227) (xy 296.299824 -409.375871) (xy 296.470107 -409.323049) (xy 296.642574 -409.277865)
			(xy 296.816882 -409.240408) (xy 296.992686 -409.210754) (xy 297.169636 -409.188961) (xy 297.347382 -409.175071)
			(xy 297.525569 -409.169114) (xy 297.703846 -409.1711) (xy 297.881857 -409.181026) (xy 298.059249 -409.198872)
			(xy 298.235669 -409.224602) (xy 298.410769 -409.258166) (xy 298.5842 -409.299496) (xy 298.755617 -409.348512)
			(xy 298.92468 -409.405114) (xy 299.091055 -409.469192) (xy 299.254409 -409.540618) (xy 299.41442 -409.61925)
			(xy 299.570769 -409.704931) (xy 299.723146 -409.797493) (xy 299.871249 -409.89675) (xy 300.014783 -410.002507)
			(xy 300.153463 -410.114552) (xy 300.287014 -410.232664) (xy 300.415171 -410.356608) (xy 300.53768 -410.486138)
			(xy 300.654297 -410.620997) (xy 300.76479 -410.760917) (xy 300.868941 -410.90562) (xy 300.966543 -411.054819)
			(xy 301.057401 -411.208218) (xy 301.141335 -411.365512) (xy 301.21818 -411.526388) (xy 301.287781 -411.690529)
			(xy 301.350002 -411.857606) (xy 301.404718 -412.02729) (xy 301.45182 -412.199243) (xy 301.491216 -412.373123)
			(xy 301.522827 -412.548586) (xy 301.546591 -412.725282) (xy 301.559858 -412.873752) (xy 303.412875 -412.873752)
			(xy 303.412875 -412.819248) (xy 303.420632 -412.7653) (xy 303.435988 -412.713004) (xy 303.458629 -412.663426)
			(xy 303.488096 -412.617575) (xy 303.523789 -412.576384) (xy 303.56498 -412.540693) (xy 303.610831 -412.511226)
			(xy 303.66041 -412.488585) (xy 303.712706 -412.473231) (xy 303.766654 -412.465475) (xy 303.793906 -412.465012)
			(xy 304.657506 -412.465012) (xy 304.684758 -412.465458) (xy 304.738708 -412.473216) (xy 304.791005 -412.488572)
			(xy 304.840584 -412.511215) (xy 304.886436 -412.540683) (xy 304.927628 -412.576376) (xy 304.963321 -412.617569)
			(xy 304.992788 -412.663421) (xy 305.01543 -412.713001) (xy 305.030785 -412.765298) (xy 305.038542 -412.819248)
			(xy 305.038542 -412.873752) (xy 305.038542 -412.873754) (xy 306.476075 -412.873754) (xy 306.476075 -412.819246)
			(xy 306.483833 -412.765294) (xy 306.499191 -412.712996) (xy 306.521835 -412.663415) (xy 306.551306 -412.617562)
			(xy 306.587003 -412.57637) (xy 306.628199 -412.540679) (xy 306.674055 -412.511213) (xy 306.723639 -412.488575)
			(xy 306.775939 -412.473223) (xy 306.829892 -412.465472) (xy 306.857146 -412.465012) (xy 307.720746 -412.465012)
			(xy 307.747997 -412.465461) (xy 307.801942 -412.473223) (xy 307.854234 -412.488583) (xy 307.903808 -412.511228)
			(xy 307.949655 -412.540697) (xy 307.990842 -412.576391) (xy 308.02653 -412.617582) (xy 308.055994 -412.663432)
			(xy 308.078633 -412.713009) (xy 308.093987 -412.765303) (xy 308.101742 -412.819249) (xy 308.101742 -412.873749)
			(xy 309.539398 -412.873749) (xy 309.539398 -412.819251) (xy 309.547154 -412.765307) (xy 309.562508 -412.713016)
			(xy 309.585146 -412.663443) (xy 309.61461 -412.617596) (xy 309.650298 -412.576408) (xy 309.691484 -412.540718)
			(xy 309.73733 -412.511253) (xy 309.786903 -412.488612) (xy 309.839194 -412.473257) (xy 309.893137 -412.465499)
			(xy 309.920386 -412.465012) (xy 310.783986 -412.465012) (xy 310.811241 -412.465434) (xy 310.865196 -412.47319)
			(xy 310.917499 -412.488545) (xy 310.967083 -412.511188) (xy 311.012941 -412.540657) (xy 311.054137 -412.576353)
			(xy 311.089834 -412.617548) (xy 311.119305 -412.663405) (xy 311.14195 -412.712988) (xy 311.157307 -412.76529)
			(xy 311.165065 -412.819245) (xy 311.165065 -412.873753) (xy 312.602575 -412.873753) (xy 312.602575 -412.819247)
			(xy 312.610333 -412.765297) (xy 312.625689 -412.713) (xy 312.648332 -412.663421) (xy 312.677801 -412.617569)
			(xy 312.713496 -412.576377) (xy 312.754689 -412.540686) (xy 312.800543 -412.51122) (xy 312.850124 -412.48858)
			(xy 312.902422 -412.473227) (xy 312.956373 -412.465474) (xy 312.983626 -412.465012) (xy 313.847226 -412.465012)
			(xy 313.874477 -412.46546) (xy 313.928425 -412.47322) (xy 313.98072 -412.488578) (xy 314.030296 -412.511222)
			(xy 314.076146 -412.54069) (xy 314.117335 -412.576383) (xy 314.153026 -412.617575) (xy 314.182491 -412.663427)
			(xy 314.205131 -412.713005) (xy 314.220486 -412.7653) (xy 314.228242 -412.819249) (xy 314.228242 -412.873748)
			(xy 315.665898 -412.873748) (xy 315.665898 -412.819252) (xy 315.673653 -412.76531) (xy 315.689006 -412.713021)
			(xy 315.711643 -412.663448) (xy 315.741105 -412.617602) (xy 315.776791 -412.576415) (xy 315.817975 -412.540725)
			(xy 315.863818 -412.51126) (xy 315.913389 -412.488618) (xy 315.965677 -412.473261) (xy 316.019618 -412.465501)
			(xy 316.046866 -412.465012) (xy 316.910466 -412.465012) (xy 316.937722 -412.465433) (xy 316.991679 -412.473186)
			(xy 317.043984 -412.48854) (xy 317.093571 -412.511182) (xy 317.139431 -412.54065) (xy 317.18063 -412.576346)
			(xy 317.216329 -412.617542) (xy 317.245802 -412.663399) (xy 317.268448 -412.712984) (xy 317.283807 -412.765287)
			(xy 317.291565 -412.819244) (xy 317.291565 -412.873752) (xy 318.729075 -412.873752) (xy 318.729075 -412.819248)
			(xy 318.736832 -412.7653) (xy 318.752188 -412.713004) (xy 318.774829 -412.663426) (xy 318.804296 -412.617575)
			(xy 318.839989 -412.576384) (xy 318.88118 -412.540693) (xy 318.927031 -412.511226) (xy 318.97661 -412.488585)
			(xy 319.028906 -412.473231) (xy 319.082854 -412.465475) (xy 319.110106 -412.465012) (xy 319.973706 -412.465012)
			(xy 320.000958 -412.465458) (xy 320.054908 -412.473216) (xy 320.107205 -412.488572) (xy 320.156784 -412.511215)
			(xy 320.202636 -412.540683) (xy 320.243828 -412.576376) (xy 320.279521 -412.617569) (xy 320.308988 -412.663421)
			(xy 320.33163 -412.713001) (xy 320.346985 -412.765298) (xy 320.354742 -412.819248) (xy 320.354742 -412.873752)
			(xy 320.354742 -412.873754) (xy 321.792275 -412.873754) (xy 321.792275 -412.819246) (xy 321.800033 -412.765294)
			(xy 321.815391 -412.712996) (xy 321.838035 -412.663415) (xy 321.867506 -412.617562) (xy 321.903203 -412.57637)
			(xy 321.944399 -412.540679) (xy 321.990255 -412.511213) (xy 322.039839 -412.488575) (xy 322.092139 -412.473223)
			(xy 322.146092 -412.465472) (xy 322.173346 -412.465012) (xy 323.036946 -412.465012) (xy 323.064197 -412.465461)
			(xy 323.118142 -412.473223) (xy 323.170434 -412.488583) (xy 323.220008 -412.511228) (xy 323.265855 -412.540697)
			(xy 323.307042 -412.576391) (xy 323.34273 -412.617582) (xy 323.372194 -412.663432) (xy 323.394833 -412.713009)
			(xy 323.410187 -412.765303) (xy 323.417942 -412.819249) (xy 323.417942 -412.873749) (xy 324.855598 -412.873749)
			(xy 324.855598 -412.819251) (xy 324.863354 -412.765307) (xy 324.878708 -412.713016) (xy 324.901346 -412.663443)
			(xy 324.93081 -412.617596) (xy 324.966498 -412.576408) (xy 325.007684 -412.540718) (xy 325.05353 -412.511253)
			(xy 325.103103 -412.488612) (xy 325.155394 -412.473257) (xy 325.209337 -412.465499) (xy 325.236586 -412.465012)
			(xy 326.100186 -412.465012) (xy 326.127441 -412.465434) (xy 326.181396 -412.47319) (xy 326.233699 -412.488545)
			(xy 326.283283 -412.511188) (xy 326.329141 -412.540657) (xy 326.370337 -412.576353) (xy 326.406034 -412.617548)
			(xy 326.435505 -412.663405) (xy 326.45815 -412.712988) (xy 326.473507 -412.76529) (xy 326.481265 -412.819245)
			(xy 326.481265 -412.873753) (xy 327.918775 -412.873753) (xy 327.918775 -412.819247) (xy 327.926533 -412.765297)
			(xy 327.941889 -412.713) (xy 327.964532 -412.663421) (xy 327.994001 -412.617569) (xy 328.029696 -412.576377)
			(xy 328.070889 -412.540686) (xy 328.116743 -412.51122) (xy 328.166324 -412.48858) (xy 328.218622 -412.473227)
			(xy 328.272573 -412.465474) (xy 328.299826 -412.465012) (xy 329.163426 -412.465012) (xy 329.190677 -412.46546)
			(xy 329.244625 -412.47322) (xy 329.29692 -412.488578) (xy 329.346496 -412.511222) (xy 329.392346 -412.54069)
			(xy 329.433535 -412.576383) (xy 329.469226 -412.617575) (xy 329.498691 -412.663427) (xy 329.521331 -412.713005)
			(xy 329.536686 -412.7653) (xy 329.544442 -412.819249) (xy 329.544442 -412.873748) (xy 330.982098 -412.873748)
			(xy 330.982098 -412.819252) (xy 330.989853 -412.76531) (xy 331.005206 -412.713021) (xy 331.027843 -412.663448)
			(xy 331.057305 -412.617602) (xy 331.092991 -412.576415) (xy 331.134175 -412.540725) (xy 331.180018 -412.51126)
			(xy 331.229589 -412.488618) (xy 331.281877 -412.473261) (xy 331.335818 -412.465501) (xy 331.363066 -412.465012)
			(xy 332.226666 -412.465012) (xy 332.253922 -412.465433) (xy 332.307879 -412.473186) (xy 332.360184 -412.48854)
			(xy 332.409771 -412.511182) (xy 332.455631 -412.54065) (xy 332.49683 -412.576346) (xy 332.532529 -412.617542)
			(xy 332.562002 -412.663399) (xy 332.584648 -412.712984) (xy 332.600007 -412.765287) (xy 332.607765 -412.819244)
			(xy 332.607765 -412.873752) (xy 334.045275 -412.873752) (xy 334.045275 -412.819248) (xy 334.053032 -412.7653)
			(xy 334.068388 -412.713004) (xy 334.091029 -412.663426) (xy 334.120496 -412.617575) (xy 334.156189 -412.576384)
			(xy 334.19738 -412.540693) (xy 334.243231 -412.511226) (xy 334.29281 -412.488585) (xy 334.345106 -412.473231)
			(xy 334.399054 -412.465475) (xy 334.426306 -412.465012) (xy 335.289906 -412.465012) (xy 335.317158 -412.465458)
			(xy 335.371108 -412.473216) (xy 335.423405 -412.488572) (xy 335.472984 -412.511215) (xy 335.518836 -412.540683)
			(xy 335.560028 -412.576376) (xy 335.595721 -412.617569) (xy 335.625188 -412.663421) (xy 335.64783 -412.713001)
			(xy 335.663185 -412.765298) (xy 335.670942 -412.819248) (xy 335.670942 -412.873752) (xy 335.670942 -412.873754)
			(xy 337.108475 -412.873754) (xy 337.108475 -412.819246) (xy 337.116233 -412.765294) (xy 337.131591 -412.712996)
			(xy 337.154235 -412.663415) (xy 337.183706 -412.617562) (xy 337.219403 -412.57637) (xy 337.260599 -412.540679)
			(xy 337.306455 -412.511213) (xy 337.356039 -412.488575) (xy 337.408339 -412.473223) (xy 337.462292 -412.465472)
			(xy 337.489546 -412.465012) (xy 338.353146 -412.465012) (xy 338.380397 -412.465461) (xy 338.434342 -412.473223)
			(xy 338.486634 -412.488583) (xy 338.536208 -412.511228) (xy 338.582055 -412.540697) (xy 338.623242 -412.576391)
			(xy 338.65893 -412.617582) (xy 338.688394 -412.663432) (xy 338.711033 -412.713009) (xy 338.726387 -412.765303)
			(xy 338.734142 -412.819249) (xy 338.734142 -412.873749) (xy 340.171798 -412.873749) (xy 340.171798 -412.819251)
			(xy 340.179554 -412.765307) (xy 340.194908 -412.713016) (xy 340.217546 -412.663443) (xy 340.24701 -412.617596)
			(xy 340.282698 -412.576408) (xy 340.323884 -412.540718) (xy 340.36973 -412.511253) (xy 340.419303 -412.488612)
			(xy 340.471594 -412.473257) (xy 340.525537 -412.465499) (xy 340.552786 -412.465012) (xy 341.416386 -412.465012)
			(xy 341.443641 -412.465434) (xy 341.497596 -412.47319) (xy 341.549899 -412.488545) (xy 341.599483 -412.511188)
			(xy 341.645341 -412.540657) (xy 341.686537 -412.576353) (xy 341.722234 -412.617548) (xy 341.751705 -412.663405)
			(xy 341.77435 -412.712988) (xy 341.789707 -412.76529) (xy 341.797465 -412.819245) (xy 341.797465 -412.873753)
			(xy 343.234975 -412.873753) (xy 343.234975 -412.819247) (xy 343.242733 -412.765297) (xy 343.258089 -412.713)
			(xy 343.280732 -412.663421) (xy 343.310201 -412.617569) (xy 343.345896 -412.576377) (xy 343.387089 -412.540686)
			(xy 343.432943 -412.51122) (xy 343.482524 -412.48858) (xy 343.534822 -412.473227) (xy 343.588773 -412.465474)
			(xy 343.616026 -412.465012) (xy 344.479626 -412.465012) (xy 344.506877 -412.46546) (xy 344.560825 -412.47322)
			(xy 344.61312 -412.488578) (xy 344.662696 -412.511222) (xy 344.708546 -412.54069) (xy 344.749735 -412.576383)
			(xy 344.785426 -412.617575) (xy 344.814891 -412.663427) (xy 344.837531 -412.713005) (xy 344.852886 -412.7653)
			(xy 344.860642 -412.819249) (xy 344.860642 -412.873748) (xy 346.298298 -412.873748) (xy 346.298298 -412.819252)
			(xy 346.306053 -412.76531) (xy 346.321406 -412.713021) (xy 346.344043 -412.663448) (xy 346.373505 -412.617602)
			(xy 346.409191 -412.576415) (xy 346.450375 -412.540725) (xy 346.496218 -412.51126) (xy 346.545789 -412.488618)
			(xy 346.598077 -412.473261) (xy 346.652018 -412.465501) (xy 346.679266 -412.465012) (xy 347.542866 -412.465012)
			(xy 347.570122 -412.465433) (xy 347.624079 -412.473186) (xy 347.676384 -412.48854) (xy 347.725971 -412.511182)
			(xy 347.771831 -412.54065) (xy 347.81303 -412.576346) (xy 347.848729 -412.617542) (xy 347.878202 -412.663399)
			(xy 347.900848 -412.712984) (xy 347.916207 -412.765287) (xy 347.923965 -412.819244) (xy 347.923965 -412.873752)
			(xy 349.361475 -412.873752) (xy 349.361475 -412.819248) (xy 349.369232 -412.7653) (xy 349.384588 -412.713004)
			(xy 349.407229 -412.663426) (xy 349.436696 -412.617575) (xy 349.472389 -412.576384) (xy 349.51358 -412.540693)
			(xy 349.559431 -412.511226) (xy 349.60901 -412.488585) (xy 349.661306 -412.473231) (xy 349.715254 -412.465475)
			(xy 349.742506 -412.465012) (xy 350.606106 -412.465012) (xy 350.633358 -412.465458) (xy 350.687308 -412.473216)
			(xy 350.739605 -412.488572) (xy 350.789184 -412.511215) (xy 350.835036 -412.540683) (xy 350.876228 -412.576376)
			(xy 350.911921 -412.617569) (xy 350.941388 -412.663421) (xy 350.96403 -412.713001) (xy 350.979385 -412.765298)
			(xy 350.987142 -412.819248) (xy 350.987142 -412.873752) (xy 370.513075 -412.873752) (xy 370.513075 -412.819248)
			(xy 370.520832 -412.7653) (xy 370.536187 -412.713005) (xy 370.558829 -412.663427) (xy 370.588295 -412.617576)
			(xy 370.623987 -412.576386) (xy 370.665178 -412.540694) (xy 370.711029 -412.511228) (xy 370.760607 -412.488587)
			(xy 370.812902 -412.473231) (xy 370.86685 -412.465475) (xy 370.894102 -412.465012) (xy 371.757702 -412.465012)
			(xy 371.784955 -412.465458) (xy 371.838905 -412.473215) (xy 371.891202 -412.488571) (xy 371.940782 -412.511214)
			(xy 371.986634 -412.540682) (xy 372.027826 -412.576375) (xy 372.06352 -412.617567) (xy 372.092987 -412.66342)
			(xy 372.115629 -412.713) (xy 372.130985 -412.765297) (xy 372.138742 -412.819247) (xy 372.138742 -412.873753)
			(xy 373.576275 -412.873753) (xy 373.576275 -412.819247) (xy 373.584033 -412.765295) (xy 373.59939 -412.712996)
			(xy 373.622035 -412.663416) (xy 373.651505 -412.617563) (xy 373.687201 -412.576372) (xy 373.728397 -412.54068)
			(xy 373.774253 -412.511215) (xy 373.823836 -412.488576) (xy 373.876136 -412.473224) (xy 373.930089 -412.465472)
			(xy 373.957342 -412.465012) (xy 374.820942 -412.465012) (xy 374.848193 -412.465461) (xy 374.902139 -412.473222)
			(xy 374.954431 -412.488582) (xy 375.004006 -412.511227) (xy 375.049853 -412.540696) (xy 375.091041 -412.576389)
			(xy 375.126729 -412.61758) (xy 375.156193 -412.663431) (xy 375.178833 -412.713008) (xy 375.194186 -412.765302)
			(xy 375.201942 -412.819249) (xy 375.201942 -412.873749) (xy 376.639598 -412.873749) (xy 376.639598 -412.819251)
			(xy 376.647354 -412.765308) (xy 376.662707 -412.713017) (xy 376.685346 -412.663444) (xy 376.714809 -412.617597)
			(xy 376.750497 -412.576409) (xy 376.791682 -412.54072) (xy 376.837528 -412.511254) (xy 376.8871 -412.488613)
			(xy 376.93939 -412.473258) (xy 376.993333 -412.465499) (xy 377.020582 -412.465012) (xy 377.884182 -412.465012)
			(xy 377.911437 -412.465434) (xy 377.965393 -412.473189) (xy 378.017696 -412.488544) (xy 378.067281 -412.511187)
			(xy 378.113139 -412.540656) (xy 378.154336 -412.576352) (xy 378.190033 -412.617547) (xy 378.219504 -412.663403)
			(xy 378.242149 -412.712987) (xy 378.257507 -412.765289) (xy 378.265265 -412.819245) (xy 378.265265 -412.873752)
			(xy 379.702775 -412.873752) (xy 379.702775 -412.819248) (xy 379.710532 -412.765298) (xy 379.725889 -412.713001)
			(xy 379.748532 -412.663422) (xy 379.778 -412.61757) (xy 379.813694 -412.576379) (xy 379.854888 -412.540687)
			(xy 379.900741 -412.511221) (xy 379.950321 -412.488581) (xy 380.002619 -412.473228) (xy 380.05657 -412.465474)
			(xy 380.083822 -412.465012) (xy 380.947422 -412.465012) (xy 380.974674 -412.465459) (xy 381.028622 -412.473219)
			(xy 381.080917 -412.488577) (xy 381.130494 -412.51122) (xy 381.176344 -412.540689) (xy 381.217534 -412.576382)
			(xy 381.253225 -412.617574) (xy 381.28269 -412.663426) (xy 381.305331 -412.713004) (xy 381.320686 -412.7653)
			(xy 381.328442 -412.819248) (xy 381.328442 -412.873748) (xy 382.766098 -412.873748) (xy 382.766098 -412.819252)
			(xy 382.773853 -412.76531) (xy 382.789206 -412.713022) (xy 382.811843 -412.663449) (xy 382.841304 -412.617603)
			(xy 382.876989 -412.576416) (xy 382.918173 -412.540727) (xy 382.964016 -412.511261) (xy 383.013586 -412.488619)
			(xy 383.065873 -412.473261) (xy 383.119814 -412.465501) (xy 383.147062 -412.465012) (xy 384.010662 -412.465012)
			(xy 384.037918 -412.465432) (xy 384.091876 -412.473185) (xy 384.144181 -412.488539) (xy 384.193769 -412.51118)
			(xy 384.239629 -412.540649) (xy 384.280829 -412.576345) (xy 384.316528 -412.61754) (xy 384.346001 -412.663398)
			(xy 384.368648 -412.712983) (xy 384.384007 -412.765287) (xy 384.391765 -412.819244) (xy 384.391765 -412.873752)
			(xy 385.829275 -412.873752) (xy 385.829275 -412.819248) (xy 385.837032 -412.7653) (xy 385.852387 -412.713005)
			(xy 385.875029 -412.663427) (xy 385.904495 -412.617576) (xy 385.940187 -412.576386) (xy 385.981378 -412.540694)
			(xy 386.027229 -412.511228) (xy 386.076807 -412.488587) (xy 386.129102 -412.473231) (xy 386.18305 -412.465475)
			(xy 386.210302 -412.465012) (xy 387.073902 -412.465012) (xy 387.101155 -412.465458) (xy 387.155105 -412.473215)
			(xy 387.207402 -412.488571) (xy 387.256982 -412.511214) (xy 387.302834 -412.540682) (xy 387.344026 -412.576375)
			(xy 387.37972 -412.617567) (xy 387.409187 -412.66342) (xy 387.431829 -412.713) (xy 387.447185 -412.765297)
			(xy 387.454942 -412.819247) (xy 387.454942 -412.873753) (xy 388.892475 -412.873753) (xy 388.892475 -412.819247)
			(xy 388.900233 -412.765295) (xy 388.91559 -412.712996) (xy 388.938235 -412.663416) (xy 388.967705 -412.617563)
			(xy 389.003401 -412.576372) (xy 389.044597 -412.54068) (xy 389.090453 -412.511215) (xy 389.140036 -412.488576)
			(xy 389.192336 -412.473224) (xy 389.246289 -412.465472) (xy 389.273542 -412.465012) (xy 390.137142 -412.465012)
			(xy 390.164393 -412.465461) (xy 390.218339 -412.473222) (xy 390.270631 -412.488582) (xy 390.320206 -412.511227)
			(xy 390.366053 -412.540696) (xy 390.407241 -412.576389) (xy 390.442929 -412.61758) (xy 390.472393 -412.663431)
			(xy 390.495033 -412.713008) (xy 390.510386 -412.765302) (xy 390.518142 -412.819249) (xy 390.518142 -412.873749)
			(xy 391.955798 -412.873749) (xy 391.955798 -412.819251) (xy 391.963554 -412.765308) (xy 391.978907 -412.713017)
			(xy 392.001546 -412.663444) (xy 392.031009 -412.617597) (xy 392.066697 -412.576409) (xy 392.107882 -412.54072)
			(xy 392.153728 -412.511254) (xy 392.2033 -412.488613) (xy 392.25559 -412.473258) (xy 392.309533 -412.465499)
			(xy 392.336782 -412.465012) (xy 393.200382 -412.465012) (xy 393.227637 -412.465434) (xy 393.281593 -412.473189)
			(xy 393.333896 -412.488544) (xy 393.383481 -412.511187) (xy 393.429339 -412.540656) (xy 393.470536 -412.576352)
			(xy 393.506233 -412.617547) (xy 393.535704 -412.663403) (xy 393.558349 -412.712987) (xy 393.573707 -412.765289)
			(xy 393.581465 -412.819245) (xy 393.581465 -412.873752) (xy 395.018975 -412.873752) (xy 395.018975 -412.819248)
			(xy 395.026732 -412.765298) (xy 395.042089 -412.713001) (xy 395.064732 -412.663422) (xy 395.0942 -412.61757)
			(xy 395.129894 -412.576379) (xy 395.171088 -412.540687) (xy 395.216941 -412.511221) (xy 395.266521 -412.488581)
			(xy 395.318819 -412.473228) (xy 395.37277 -412.465474) (xy 395.400022 -412.465012) (xy 396.263622 -412.465012)
			(xy 396.290874 -412.465459) (xy 396.344822 -412.473219) (xy 396.397117 -412.488577) (xy 396.446694 -412.51122)
			(xy 396.492544 -412.540689) (xy 396.533734 -412.576382) (xy 396.569425 -412.617574) (xy 396.59889 -412.663426)
			(xy 396.621531 -412.713004) (xy 396.636886 -412.7653) (xy 396.644642 -412.819248) (xy 396.644642 -412.873748)
			(xy 398.082298 -412.873748) (xy 398.082298 -412.819252) (xy 398.090053 -412.76531) (xy 398.105406 -412.713022)
			(xy 398.128043 -412.663449) (xy 398.157504 -412.617603) (xy 398.193189 -412.576416) (xy 398.234373 -412.540727)
			(xy 398.280216 -412.511261) (xy 398.329786 -412.488619) (xy 398.382073 -412.473261) (xy 398.436014 -412.465501)
			(xy 398.463262 -412.465012) (xy 399.326862 -412.465012) (xy 399.354118 -412.465432) (xy 399.408076 -412.473185)
			(xy 399.460381 -412.488539) (xy 399.509969 -412.51118) (xy 399.555829 -412.540649) (xy 399.597029 -412.576345)
			(xy 399.632728 -412.61754) (xy 399.662201 -412.663398) (xy 399.684848 -412.712983) (xy 399.700207 -412.765287)
			(xy 399.707965 -412.819244) (xy 399.707965 -412.873752) (xy 401.145475 -412.873752) (xy 401.145475 -412.819248)
			(xy 401.153232 -412.7653) (xy 401.168587 -412.713005) (xy 401.191229 -412.663427) (xy 401.220695 -412.617576)
			(xy 401.256387 -412.576386) (xy 401.297578 -412.540694) (xy 401.343429 -412.511228) (xy 401.393007 -412.488587)
			(xy 401.445302 -412.473231) (xy 401.49925 -412.465475) (xy 401.526502 -412.465012) (xy 402.390102 -412.465012)
			(xy 402.417355 -412.465458) (xy 402.471305 -412.473215) (xy 402.523602 -412.488571) (xy 402.573182 -412.511214)
			(xy 402.619034 -412.540682) (xy 402.660226 -412.576375) (xy 402.69592 -412.617567) (xy 402.725387 -412.66342)
			(xy 402.748029 -412.713) (xy 402.763385 -412.765297) (xy 402.771142 -412.819247) (xy 402.771142 -412.873753)
			(xy 404.208675 -412.873753) (xy 404.208675 -412.819247) (xy 404.216433 -412.765295) (xy 404.23179 -412.712996)
			(xy 404.254435 -412.663416) (xy 404.283905 -412.617563) (xy 404.319601 -412.576372) (xy 404.360797 -412.54068)
			(xy 404.406653 -412.511215) (xy 404.456236 -412.488576) (xy 404.508536 -412.473224) (xy 404.562489 -412.465472)
			(xy 404.589742 -412.465012) (xy 405.453342 -412.465012) (xy 405.480593 -412.465461) (xy 405.534539 -412.473222)
			(xy 405.586831 -412.488582) (xy 405.636406 -412.511227) (xy 405.682253 -412.540696) (xy 405.723441 -412.576389)
			(xy 405.759129 -412.61758) (xy 405.788593 -412.663431) (xy 405.811233 -412.713008) (xy 405.826586 -412.765302)
			(xy 405.834342 -412.819249) (xy 405.834342 -412.873749) (xy 407.271998 -412.873749) (xy 407.271998 -412.819251)
			(xy 407.279754 -412.765308) (xy 407.295107 -412.713017) (xy 407.317746 -412.663444) (xy 407.347209 -412.617597)
			(xy 407.382897 -412.576409) (xy 407.424082 -412.54072) (xy 407.469928 -412.511254) (xy 407.5195 -412.488613)
			(xy 407.57179 -412.473258) (xy 407.625733 -412.465499) (xy 407.652982 -412.465012) (xy 408.516582 -412.465012)
			(xy 408.543837 -412.465434) (xy 408.597793 -412.473189) (xy 408.650096 -412.488544) (xy 408.699681 -412.511187)
			(xy 408.745539 -412.540656) (xy 408.786736 -412.576352) (xy 408.822433 -412.617547) (xy 408.851904 -412.663403)
			(xy 408.874549 -412.712987) (xy 408.889907 -412.765289) (xy 408.897665 -412.819245) (xy 408.897665 -412.873752)
			(xy 410.335175 -412.873752) (xy 410.335175 -412.819248) (xy 410.342932 -412.765298) (xy 410.358289 -412.713001)
			(xy 410.380932 -412.663422) (xy 410.4104 -412.61757) (xy 410.446094 -412.576379) (xy 410.487288 -412.540687)
			(xy 410.533141 -412.511221) (xy 410.582721 -412.488581) (xy 410.635019 -412.473228) (xy 410.68897 -412.465474)
			(xy 410.716222 -412.465012) (xy 411.579822 -412.465012) (xy 411.607074 -412.465459) (xy 411.661022 -412.473219)
			(xy 411.713317 -412.488577) (xy 411.762894 -412.51122) (xy 411.808744 -412.540689) (xy 411.849934 -412.576382)
			(xy 411.885625 -412.617574) (xy 411.91509 -412.663426) (xy 411.937731 -412.713004) (xy 411.953086 -412.7653)
			(xy 411.960842 -412.819248) (xy 411.960842 -412.873748) (xy 413.398498 -412.873748) (xy 413.398498 -412.819252)
			(xy 413.406253 -412.76531) (xy 413.421606 -412.713022) (xy 413.444243 -412.663449) (xy 413.473704 -412.617603)
			(xy 413.509389 -412.576416) (xy 413.550573 -412.540727) (xy 413.596416 -412.511261) (xy 413.645986 -412.488619)
			(xy 413.698273 -412.473261) (xy 413.752214 -412.465501) (xy 413.779462 -412.465012) (xy 414.643062 -412.465012)
			(xy 414.670318 -412.465432) (xy 414.724276 -412.473185) (xy 414.776581 -412.488539) (xy 414.826169 -412.51118)
			(xy 414.872029 -412.540649) (xy 414.913229 -412.576345) (xy 414.948928 -412.61754) (xy 414.978401 -412.663398)
			(xy 415.001048 -412.712983) (xy 415.016407 -412.765287) (xy 415.024165 -412.819244) (xy 415.024165 -412.873752)
			(xy 416.461675 -412.873752) (xy 416.461675 -412.819248) (xy 416.469432 -412.7653) (xy 416.484787 -412.713005)
			(xy 416.507429 -412.663427) (xy 416.536895 -412.617576) (xy 416.572587 -412.576386) (xy 416.613778 -412.540694)
			(xy 416.659629 -412.511228) (xy 416.709207 -412.488587) (xy 416.761502 -412.473231) (xy 416.81545 -412.465475)
			(xy 416.842702 -412.465012) (xy 417.706302 -412.465012) (xy 417.733555 -412.465458) (xy 417.787505 -412.473215)
			(xy 417.839802 -412.488571) (xy 417.889382 -412.511214) (xy 417.935234 -412.540682) (xy 417.976426 -412.576375)
			(xy 418.01212 -412.617567) (xy 418.041587 -412.66342) (xy 418.064229 -412.713) (xy 418.079585 -412.765297)
			(xy 418.087342 -412.819247) (xy 418.087342 -412.873753) (xy 418.079585 -412.927703) (xy 418.064229 -412.98)
			(xy 418.041587 -413.02958) (xy 418.01212 -413.075433) (xy 417.976426 -413.116625) (xy 417.935234 -413.152318)
			(xy 417.90754 -413.170116) (xy 422.998658 -413.170116) (xy 423.00263 -412.991873) (xy 423.014538 -412.813984)
			(xy 423.034359 -412.636802) (xy 423.062053 -412.460678) (xy 423.097565 -412.285963) (xy 423.140825 -412.113004)
			(xy 423.191747 -411.942143) (xy 423.25023 -411.773721) (xy 423.316157 -411.608071) (xy 423.389398 -411.445522)
			(xy 423.469808 -411.286397) (xy 423.557226 -411.131012) (xy 423.651479 -410.979676) (xy 423.75238 -410.832688)
			(xy 423.859729 -410.690341) (xy 423.973312 -410.552918) (xy 424.092905 -410.420691) (xy 424.218269 -410.293922)
			(xy 424.349156 -410.172864) (xy 424.485305 -410.057757) (xy 424.626447 -409.948829) (xy 424.772302 -409.846297)
			(xy 424.922579 -409.750363) (xy 425.07698 -409.66122) (xy 425.235199 -409.579043) (xy 425.396922 -409.503995)
			(xy 425.561827 -409.436227) (xy 425.729588 -409.375871) (xy 425.899871 -409.323049) (xy 426.072338 -409.277865)
			(xy 426.246646 -409.240408) (xy 426.42245 -409.210754) (xy 426.5994 -409.188961) (xy 426.777146 -409.175071)
			(xy 426.955333 -409.169114) (xy 427.13361 -409.1711) (xy 427.311621 -409.181026) (xy 427.489013 -409.198872)
			(xy 427.665433 -409.224602) (xy 427.840533 -409.258166) (xy 428.013964 -409.299496) (xy 428.185381 -409.348512)
			(xy 428.354444 -409.405114) (xy 428.520819 -409.469192) (xy 428.684173 -409.540618) (xy 428.844184 -409.61925)
			(xy 429.000533 -409.704931) (xy 429.15291 -409.797493) (xy 429.301013 -409.89675) (xy 429.444547 -410.002507)
			(xy 429.583227 -410.114552) (xy 429.716778 -410.232664) (xy 429.844935 -410.356608) (xy 429.967444 -410.486138)
			(xy 430.084061 -410.620997) (xy 430.194554 -410.760917) (xy 430.298705 -410.90562) (xy 430.396307 -411.054819)
			(xy 430.487165 -411.208218) (xy 430.571099 -411.365512) (xy 430.647944 -411.526388) (xy 430.717545 -411.690529)
			(xy 430.779766 -411.857606) (xy 430.834482 -412.02729) (xy 430.881584 -412.199243) (xy 430.92098 -412.373123)
			(xy 430.952591 -412.548586) (xy 430.976355 -412.725282) (xy 430.992223 -412.902862) (xy 431.000165 -413.080972)
			(xy 431.000662 -413.170116) (xy 431.000165 -413.25926) (xy 430.992223 -413.43737) (xy 430.976355 -413.61495)
			(xy 430.952591 -413.791646) (xy 430.92098 -413.967109) (xy 430.881584 -414.140989) (xy 430.834482 -414.312942)
			(xy 430.779766 -414.482626) (xy 430.717545 -414.649703) (xy 430.647944 -414.813844) (xy 430.571099 -414.97472)
			(xy 430.487165 -415.132014) (xy 430.396307 -415.285413) (xy 430.298705 -415.434612) (xy 430.194554 -415.579315)
			(xy 430.084061 -415.719235) (xy 429.967444 -415.854094) (xy 429.844935 -415.983624) (xy 429.716778 -416.107568)
			(xy 429.583227 -416.22568) (xy 429.444547 -416.337725) (xy 429.301013 -416.443482) (xy 429.15291 -416.542739)
			(xy 429.000533 -416.635301) (xy 428.844184 -416.720982) (xy 428.684173 -416.799614) (xy 428.520819 -416.87104)
			(xy 428.354444 -416.935118) (xy 428.185381 -416.99172) (xy 428.013964 -417.040736) (xy 427.840533 -417.082066)
			(xy 427.665433 -417.11563) (xy 427.489013 -417.14136) (xy 427.311621 -417.159206) (xy 427.13361 -417.169132)
			(xy 426.955333 -417.171118) (xy 426.777146 -417.165161) (xy 426.5994 -417.151271) (xy 426.42245 -417.129478)
			(xy 426.246646 -417.099824) (xy 426.072338 -417.062367) (xy 425.899871 -417.017183) (xy 425.729588 -416.964361)
			(xy 425.561827 -416.904005) (xy 425.396922 -416.836237) (xy 425.235199 -416.761189) (xy 425.07698 -416.679012)
			(xy 424.922579 -416.589869) (xy 424.772302 -416.493935) (xy 424.626447 -416.391403) (xy 424.485305 -416.282475)
			(xy 424.349156 -416.167368) (xy 424.218269 -416.04631) (xy 424.092905 -415.919541) (xy 423.973312 -415.787314)
			(xy 423.859729 -415.649891) (xy 423.75238 -415.507544) (xy 423.651479 -415.360556) (xy 423.557226 -415.20922)
			(xy 423.469808 -415.053835) (xy 423.389398 -414.89471) (xy 423.316157 -414.732161) (xy 423.25023 -414.566511)
			(xy 423.191747 -414.398089) (xy 423.140825 -414.227228) (xy 423.097565 -414.054269) (xy 423.062053 -413.879554)
			(xy 423.034359 -413.70343) (xy 423.014538 -413.526248) (xy 423.00263 -413.348359) (xy 422.998658 -413.170116)
			(xy 417.90754 -413.170116) (xy 417.889382 -413.181786) (xy 417.839802 -413.204429) (xy 417.787505 -413.219785)
			(xy 417.733555 -413.227542) (xy 417.706302 -413.228028) (xy 416.842702 -413.228028) (xy 416.81545 -413.227525)
			(xy 416.761502 -413.219769) (xy 416.709207 -413.204413) (xy 416.659629 -413.181772) (xy 416.613778 -413.152306)
			(xy 416.572587 -413.116614) (xy 416.536895 -413.075424) (xy 416.507429 -413.029573) (xy 416.484787 -412.979995)
			(xy 416.469432 -412.9277) (xy 416.461675 -412.873752) (xy 415.024165 -412.873752) (xy 415.024165 -412.873756)
			(xy 415.016407 -412.927713) (xy 415.001048 -412.980017) (xy 414.978401 -413.029602) (xy 414.948928 -413.07546)
			(xy 414.913229 -413.116655) (xy 414.872029 -413.152351) (xy 414.826169 -413.18182) (xy 414.776581 -413.204461)
			(xy 414.724276 -413.219815) (xy 414.670318 -413.227568) (xy 414.643062 -413.228028) (xy 413.779462 -413.228028)
			(xy 413.752214 -413.227499) (xy 413.698273 -413.219739) (xy 413.645986 -413.204381) (xy 413.596416 -413.181739)
			(xy 413.550573 -413.152273) (xy 413.509389 -413.116584) (xy 413.473704 -413.075397) (xy 413.444243 -413.029551)
			(xy 413.421606 -412.979978) (xy 413.406253 -412.92769) (xy 413.398498 -412.873748) (xy 411.960842 -412.873748)
			(xy 411.960842 -412.873752) (xy 411.953086 -412.9277) (xy 411.937731 -412.979996) (xy 411.91509 -413.029574)
			(xy 411.885625 -413.075426) (xy 411.849934 -413.116618) (xy 411.808744 -413.152311) (xy 411.762894 -413.18178)
			(xy 411.713317 -413.204423) (xy 411.661022 -413.219781) (xy 411.607074 -413.227541) (xy 411.579822 -413.228028)
			(xy 410.716222 -413.228028) (xy 410.68897 -413.227526) (xy 410.635019 -413.219772) (xy 410.582721 -413.204419)
			(xy 410.533141 -413.181779) (xy 410.487288 -413.152313) (xy 410.446094 -413.116621) (xy 410.4104 -413.07543)
			(xy 410.380932 -413.029578) (xy 410.358289 -412.979999) (xy 410.342932 -412.927702) (xy 410.335175 -412.873752)
			(xy 408.897665 -412.873752) (xy 408.897665 -412.873755) (xy 408.889907 -412.927711) (xy 408.874549 -412.980013)
			(xy 408.851904 -413.029597) (xy 408.822433 -413.075453) (xy 408.786736 -413.116648) (xy 408.745539 -413.152344)
			(xy 408.699681 -413.181813) (xy 408.650096 -413.204456) (xy 408.597793 -413.219811) (xy 408.543837 -413.227566)
			(xy 408.516582 -413.228028) (xy 407.652982 -413.228028) (xy 407.625733 -413.227501) (xy 407.57179 -413.219742)
			(xy 407.5195 -413.204387) (xy 407.469928 -413.181746) (xy 407.424082 -413.15228) (xy 407.382897 -413.116591)
			(xy 407.347209 -413.075403) (xy 407.317746 -413.029556) (xy 407.295107 -412.979983) (xy 407.279754 -412.927692)
			(xy 407.271998 -412.873749) (xy 405.834342 -412.873749) (xy 405.834342 -412.873751) (xy 405.826586 -412.927698)
			(xy 405.811233 -412.979992) (xy 405.788593 -413.029569) (xy 405.759129 -413.07542) (xy 405.723441 -413.116611)
			(xy 405.682253 -413.152304) (xy 405.636406 -413.181773) (xy 405.586831 -413.204418) (xy 405.534539 -413.219778)
			(xy 405.480593 -413.227539) (xy 405.453342 -413.228028) (xy 404.589742 -413.228028) (xy 404.562489 -413.227528)
			(xy 404.508536 -413.219776) (xy 404.456236 -413.204424) (xy 404.406653 -413.181785) (xy 404.360797 -413.15232)
			(xy 404.319601 -413.116628) (xy 404.283905 -413.075437) (xy 404.254435 -413.029584) (xy 404.23179 -412.980004)
			(xy 404.216433 -412.927705) (xy 404.208675 -412.873753) (xy 402.771142 -412.873753) (xy 402.763385 -412.927703)
			(xy 402.748029 -412.98) (xy 402.725387 -413.02958) (xy 402.69592 -413.075433) (xy 402.660226 -413.116625)
			(xy 402.619034 -413.152318) (xy 402.573182 -413.181786) (xy 402.523602 -413.204429) (xy 402.471305 -413.219785)
			(xy 402.417355 -413.227542) (xy 402.390102 -413.228028) (xy 401.526502 -413.228028) (xy 401.49925 -413.227525)
			(xy 401.445302 -413.219769) (xy 401.393007 -413.204413) (xy 401.343429 -413.181772) (xy 401.297578 -413.152306)
			(xy 401.256387 -413.116614) (xy 401.220695 -413.075424) (xy 401.191229 -413.029573) (xy 401.168587 -412.979995)
			(xy 401.153232 -412.9277) (xy 401.145475 -412.873752) (xy 399.707965 -412.873752) (xy 399.707965 -412.873756)
			(xy 399.700207 -412.927713) (xy 399.684848 -412.980017) (xy 399.662201 -413.029602) (xy 399.632728 -413.07546)
			(xy 399.597029 -413.116655) (xy 399.555829 -413.152351) (xy 399.509969 -413.18182) (xy 399.460381 -413.204461)
			(xy 399.408076 -413.219815) (xy 399.354118 -413.227568) (xy 399.326862 -413.228028) (xy 398.463262 -413.228028)
			(xy 398.436014 -413.227499) (xy 398.382073 -413.219739) (xy 398.329786 -413.204381) (xy 398.280216 -413.181739)
			(xy 398.234373 -413.152273) (xy 398.193189 -413.116584) (xy 398.157504 -413.075397) (xy 398.128043 -413.029551)
			(xy 398.105406 -412.979978) (xy 398.090053 -412.92769) (xy 398.082298 -412.873748) (xy 396.644642 -412.873748)
			(xy 396.644642 -412.873752) (xy 396.636886 -412.9277) (xy 396.621531 -412.979996) (xy 396.59889 -413.029574)
			(xy 396.569425 -413.075426) (xy 396.533734 -413.116618) (xy 396.492544 -413.152311) (xy 396.446694 -413.18178)
			(xy 396.397117 -413.204423) (xy 396.344822 -413.219781) (xy 396.290874 -413.227541) (xy 396.263622 -413.228028)
			(xy 395.400022 -413.228028) (xy 395.37277 -413.227526) (xy 395.318819 -413.219772) (xy 395.266521 -413.204419)
			(xy 395.216941 -413.181779) (xy 395.171088 -413.152313) (xy 395.129894 -413.116621) (xy 395.0942 -413.07543)
			(xy 395.064732 -413.029578) (xy 395.042089 -412.979999) (xy 395.026732 -412.927702) (xy 395.018975 -412.873752)
			(xy 393.581465 -412.873752) (xy 393.581465 -412.873755) (xy 393.573707 -412.927711) (xy 393.558349 -412.980013)
			(xy 393.535704 -413.029597) (xy 393.506233 -413.075453) (xy 393.470536 -413.116648) (xy 393.429339 -413.152344)
			(xy 393.383481 -413.181813) (xy 393.333896 -413.204456) (xy 393.281593 -413.219811) (xy 393.227637 -413.227566)
			(xy 393.200382 -413.228028) (xy 392.336782 -413.228028) (xy 392.309533 -413.227501) (xy 392.25559 -413.219742)
			(xy 392.2033 -413.204387) (xy 392.153728 -413.181746) (xy 392.107882 -413.15228) (xy 392.066697 -413.116591)
			(xy 392.031009 -413.075403) (xy 392.001546 -413.029556) (xy 391.978907 -412.979983) (xy 391.963554 -412.927692)
			(xy 391.955798 -412.873749) (xy 390.518142 -412.873749) (xy 390.518142 -412.873751) (xy 390.510386 -412.927698)
			(xy 390.495033 -412.979992) (xy 390.472393 -413.029569) (xy 390.442929 -413.07542) (xy 390.407241 -413.116611)
			(xy 390.366053 -413.152304) (xy 390.320206 -413.181773) (xy 390.270631 -413.204418) (xy 390.218339 -413.219778)
			(xy 390.164393 -413.227539) (xy 390.137142 -413.228028) (xy 389.273542 -413.228028) (xy 389.246289 -413.227528)
			(xy 389.192336 -413.219776) (xy 389.140036 -413.204424) (xy 389.090453 -413.181785) (xy 389.044597 -413.15232)
			(xy 389.003401 -413.116628) (xy 388.967705 -413.075437) (xy 388.938235 -413.029584) (xy 388.91559 -412.980004)
			(xy 388.900233 -412.927705) (xy 388.892475 -412.873753) (xy 387.454942 -412.873753) (xy 387.447185 -412.927703)
			(xy 387.431829 -412.98) (xy 387.409187 -413.02958) (xy 387.37972 -413.075433) (xy 387.344026 -413.116625)
			(xy 387.302834 -413.152318) (xy 387.256982 -413.181786) (xy 387.207402 -413.204429) (xy 387.155105 -413.219785)
			(xy 387.101155 -413.227542) (xy 387.073902 -413.228028) (xy 386.210302 -413.228028) (xy 386.18305 -413.227525)
			(xy 386.129102 -413.219769) (xy 386.076807 -413.204413) (xy 386.027229 -413.181772) (xy 385.981378 -413.152306)
			(xy 385.940187 -413.116614) (xy 385.904495 -413.075424) (xy 385.875029 -413.029573) (xy 385.852387 -412.979995)
			(xy 385.837032 -412.9277) (xy 385.829275 -412.873752) (xy 384.391765 -412.873752) (xy 384.391765 -412.873756)
			(xy 384.384007 -412.927713) (xy 384.368648 -412.980017) (xy 384.346001 -413.029602) (xy 384.316528 -413.07546)
			(xy 384.280829 -413.116655) (xy 384.239629 -413.152351) (xy 384.193769 -413.18182) (xy 384.144181 -413.204461)
			(xy 384.091876 -413.219815) (xy 384.037918 -413.227568) (xy 384.010662 -413.228028) (xy 383.147062 -413.228028)
			(xy 383.119814 -413.227499) (xy 383.065873 -413.219739) (xy 383.013586 -413.204381) (xy 382.964016 -413.181739)
			(xy 382.918173 -413.152273) (xy 382.876989 -413.116584) (xy 382.841304 -413.075397) (xy 382.811843 -413.029551)
			(xy 382.789206 -412.979978) (xy 382.773853 -412.92769) (xy 382.766098 -412.873748) (xy 381.328442 -412.873748)
			(xy 381.328442 -412.873752) (xy 381.320686 -412.9277) (xy 381.305331 -412.979996) (xy 381.28269 -413.029574)
			(xy 381.253225 -413.075426) (xy 381.217534 -413.116618) (xy 381.176344 -413.152311) (xy 381.130494 -413.18178)
			(xy 381.080917 -413.204423) (xy 381.028622 -413.219781) (xy 380.974674 -413.227541) (xy 380.947422 -413.228028)
			(xy 380.083822 -413.228028) (xy 380.05657 -413.227526) (xy 380.002619 -413.219772) (xy 379.950321 -413.204419)
			(xy 379.900741 -413.181779) (xy 379.854888 -413.152313) (xy 379.813694 -413.116621) (xy 379.778 -413.07543)
			(xy 379.748532 -413.029578) (xy 379.725889 -412.979999) (xy 379.710532 -412.927702) (xy 379.702775 -412.873752)
			(xy 378.265265 -412.873752) (xy 378.265265 -412.873755) (xy 378.257507 -412.927711) (xy 378.242149 -412.980013)
			(xy 378.219504 -413.029597) (xy 378.190033 -413.075453) (xy 378.154336 -413.116648) (xy 378.113139 -413.152344)
			(xy 378.067281 -413.181813) (xy 378.017696 -413.204456) (xy 377.965393 -413.219811) (xy 377.911437 -413.227566)
			(xy 377.884182 -413.228028) (xy 377.020582 -413.228028) (xy 376.993333 -413.227501) (xy 376.93939 -413.219742)
			(xy 376.8871 -413.204387) (xy 376.837528 -413.181746) (xy 376.791682 -413.15228) (xy 376.750497 -413.116591)
			(xy 376.714809 -413.075403) (xy 376.685346 -413.029556) (xy 376.662707 -412.979983) (xy 376.647354 -412.927692)
			(xy 376.639598 -412.873749) (xy 375.201942 -412.873749) (xy 375.201942 -412.873751) (xy 375.194186 -412.927698)
			(xy 375.178833 -412.979992) (xy 375.156193 -413.029569) (xy 375.126729 -413.07542) (xy 375.091041 -413.116611)
			(xy 375.049853 -413.152304) (xy 375.004006 -413.181773) (xy 374.954431 -413.204418) (xy 374.902139 -413.219778)
			(xy 374.848193 -413.227539) (xy 374.820942 -413.228028) (xy 373.957342 -413.228028) (xy 373.930089 -413.227528)
			(xy 373.876136 -413.219776) (xy 373.823836 -413.204424) (xy 373.774253 -413.181785) (xy 373.728397 -413.15232)
			(xy 373.687201 -413.116628) (xy 373.651505 -413.075437) (xy 373.622035 -413.029584) (xy 373.59939 -412.980004)
			(xy 373.584033 -412.927705) (xy 373.576275 -412.873753) (xy 372.138742 -412.873753) (xy 372.130985 -412.927703)
			(xy 372.115629 -412.98) (xy 372.092987 -413.02958) (xy 372.06352 -413.075433) (xy 372.027826 -413.116625)
			(xy 371.986634 -413.152318) (xy 371.940782 -413.181786) (xy 371.891202 -413.204429) (xy 371.838905 -413.219785)
			(xy 371.784955 -413.227542) (xy 371.757702 -413.228028) (xy 370.894102 -413.228028) (xy 370.86685 -413.227525)
			(xy 370.812902 -413.219769) (xy 370.760607 -413.204413) (xy 370.711029 -413.181772) (xy 370.665178 -413.152306)
			(xy 370.623987 -413.116614) (xy 370.588295 -413.075424) (xy 370.558829 -413.029573) (xy 370.536187 -412.979995)
			(xy 370.520832 -412.9277) (xy 370.513075 -412.873752) (xy 350.987142 -412.873752) (xy 350.979385 -412.927702)
			(xy 350.96403 -412.979999) (xy 350.941388 -413.029579) (xy 350.911921 -413.075431) (xy 350.876228 -413.116624)
			(xy 350.835036 -413.152317) (xy 350.789184 -413.181785) (xy 350.739605 -413.204428) (xy 350.687308 -413.219784)
			(xy 350.633358 -413.227542) (xy 350.606106 -413.228028) (xy 349.742506 -413.228028) (xy 349.715254 -413.227525)
			(xy 349.661306 -413.219769) (xy 349.60901 -413.204415) (xy 349.559431 -413.181774) (xy 349.51358 -413.152307)
			(xy 349.472389 -413.116616) (xy 349.436696 -413.075425) (xy 349.407229 -413.029574) (xy 349.384588 -412.979996)
			(xy 349.369232 -412.9277) (xy 349.361475 -412.873752) (xy 347.923965 -412.873752) (xy 347.923965 -412.873756)
			(xy 347.916207 -412.927713) (xy 347.900848 -412.980016) (xy 347.878202 -413.029601) (xy 347.848729 -413.075458)
			(xy 347.81303 -413.116654) (xy 347.771831 -413.15235) (xy 347.725971 -413.181818) (xy 347.676384 -413.20446)
			(xy 347.624079 -413.219814) (xy 347.570122 -413.227567) (xy 347.542866 -413.228028) (xy 346.679266 -413.228028)
			(xy 346.652018 -413.227499) (xy 346.598077 -413.219739) (xy 346.545789 -413.204382) (xy 346.496218 -413.18174)
			(xy 346.450375 -413.152275) (xy 346.409191 -413.116585) (xy 346.373505 -413.075398) (xy 346.344043 -413.029552)
			(xy 346.321406 -412.979979) (xy 346.306053 -412.92769) (xy 346.298298 -412.873748) (xy 344.860642 -412.873748)
			(xy 344.860642 -412.873751) (xy 344.852886 -412.9277) (xy 344.837531 -412.979995) (xy 344.814891 -413.029573)
			(xy 344.785426 -413.075425) (xy 344.749735 -413.116617) (xy 344.708546 -413.15231) (xy 344.662696 -413.181778)
			(xy 344.61312 -413.204422) (xy 344.560825 -413.21978) (xy 344.506877 -413.22754) (xy 344.479626 -413.228028)
			(xy 343.616026 -413.228028) (xy 343.588773 -413.227526) (xy 343.534822 -413.219773) (xy 343.482524 -413.20442)
			(xy 343.432943 -413.18178) (xy 343.387089 -413.152314) (xy 343.345896 -413.116623) (xy 343.310201 -413.075431)
			(xy 343.280732 -413.029579) (xy 343.258089 -412.98) (xy 343.242733 -412.927703) (xy 343.234975 -412.873753)
			(xy 341.797465 -412.873753) (xy 341.797465 -412.873755) (xy 341.789707 -412.92771) (xy 341.77435 -412.980012)
			(xy 341.751705 -413.029595) (xy 341.722234 -413.075452) (xy 341.686537 -413.116647) (xy 341.645341 -413.152343)
			(xy 341.599483 -413.181812) (xy 341.549899 -413.204455) (xy 341.497596 -413.21981) (xy 341.443641 -413.227566)
			(xy 341.416386 -413.228028) (xy 340.552786 -413.228028) (xy 340.525537 -413.227501) (xy 340.471594 -413.219743)
			(xy 340.419303 -413.204388) (xy 340.36973 -413.181747) (xy 340.323884 -413.152282) (xy 340.282698 -413.116592)
			(xy 340.24701 -413.075404) (xy 340.217546 -413.029557) (xy 340.194908 -412.979984) (xy 340.179554 -412.927693)
			(xy 340.171798 -412.873749) (xy 338.734142 -412.873749) (xy 338.734142 -412.873751) (xy 338.726387 -412.927697)
			(xy 338.711033 -412.979991) (xy 338.688394 -413.029568) (xy 338.65893 -413.075418) (xy 338.623242 -413.116609)
			(xy 338.582055 -413.152303) (xy 338.536208 -413.181772) (xy 338.486634 -413.204417) (xy 338.434342 -413.219777)
			(xy 338.380397 -413.227539) (xy 338.353146 -413.228028) (xy 337.489546 -413.228028) (xy 337.462292 -413.227528)
			(xy 337.408339 -413.219777) (xy 337.356039 -413.204425) (xy 337.306455 -413.181787) (xy 337.260599 -413.152321)
			(xy 337.219403 -413.11663) (xy 337.183706 -413.075438) (xy 337.154235 -413.029585) (xy 337.131591 -412.980004)
			(xy 337.116233 -412.927706) (xy 337.108475 -412.873754) (xy 335.670942 -412.873754) (xy 335.663185 -412.927702)
			(xy 335.64783 -412.979999) (xy 335.625188 -413.029579) (xy 335.595721 -413.075431) (xy 335.560028 -413.116624)
			(xy 335.518836 -413.152317) (xy 335.472984 -413.181785) (xy 335.423405 -413.204428) (xy 335.371108 -413.219784)
			(xy 335.317158 -413.227542) (xy 335.289906 -413.228028) (xy 334.426306 -413.228028) (xy 334.399054 -413.227525)
			(xy 334.345106 -413.219769) (xy 334.29281 -413.204415) (xy 334.243231 -413.181774) (xy 334.19738 -413.152307)
			(xy 334.156189 -413.116616) (xy 334.120496 -413.075425) (xy 334.091029 -413.029574) (xy 334.068388 -412.979996)
			(xy 334.053032 -412.9277) (xy 334.045275 -412.873752) (xy 332.607765 -412.873752) (xy 332.607765 -412.873756)
			(xy 332.600007 -412.927713) (xy 332.584648 -412.980016) (xy 332.562002 -413.029601) (xy 332.532529 -413.075458)
			(xy 332.49683 -413.116654) (xy 332.455631 -413.15235) (xy 332.409771 -413.181818) (xy 332.360184 -413.20446)
			(xy 332.307879 -413.219814) (xy 332.253922 -413.227567) (xy 332.226666 -413.228028) (xy 331.363066 -413.228028)
			(xy 331.335818 -413.227499) (xy 331.281877 -413.219739) (xy 331.229589 -413.204382) (xy 331.180018 -413.18174)
			(xy 331.134175 -413.152275) (xy 331.092991 -413.116585) (xy 331.057305 -413.075398) (xy 331.027843 -413.029552)
			(xy 331.005206 -412.979979) (xy 330.989853 -412.92769) (xy 330.982098 -412.873748) (xy 329.544442 -412.873748)
			(xy 329.544442 -412.873751) (xy 329.536686 -412.9277) (xy 329.521331 -412.979995) (xy 329.498691 -413.029573)
			(xy 329.469226 -413.075425) (xy 329.433535 -413.116617) (xy 329.392346 -413.15231) (xy 329.346496 -413.181778)
			(xy 329.29692 -413.204422) (xy 329.244625 -413.21978) (xy 329.190677 -413.22754) (xy 329.163426 -413.228028)
			(xy 328.299826 -413.228028) (xy 328.272573 -413.227526) (xy 328.218622 -413.219773) (xy 328.166324 -413.20442)
			(xy 328.116743 -413.18178) (xy 328.070889 -413.152314) (xy 328.029696 -413.116623) (xy 327.994001 -413.075431)
			(xy 327.964532 -413.029579) (xy 327.941889 -412.98) (xy 327.926533 -412.927703) (xy 327.918775 -412.873753)
			(xy 326.481265 -412.873753) (xy 326.481265 -412.873755) (xy 326.473507 -412.92771) (xy 326.45815 -412.980012)
			(xy 326.435505 -413.029595) (xy 326.406034 -413.075452) (xy 326.370337 -413.116647) (xy 326.329141 -413.152343)
			(xy 326.283283 -413.181812) (xy 326.233699 -413.204455) (xy 326.181396 -413.21981) (xy 326.127441 -413.227566)
			(xy 326.100186 -413.228028) (xy 325.236586 -413.228028) (xy 325.209337 -413.227501) (xy 325.155394 -413.219743)
			(xy 325.103103 -413.204388) (xy 325.05353 -413.181747) (xy 325.007684 -413.152282) (xy 324.966498 -413.116592)
			(xy 324.93081 -413.075404) (xy 324.901346 -413.029557) (xy 324.878708 -412.979984) (xy 324.863354 -412.927693)
			(xy 324.855598 -412.873749) (xy 323.417942 -412.873749) (xy 323.417942 -412.873751) (xy 323.410187 -412.927697)
			(xy 323.394833 -412.979991) (xy 323.372194 -413.029568) (xy 323.34273 -413.075418) (xy 323.307042 -413.116609)
			(xy 323.265855 -413.152303) (xy 323.220008 -413.181772) (xy 323.170434 -413.204417) (xy 323.118142 -413.219777)
			(xy 323.064197 -413.227539) (xy 323.036946 -413.228028) (xy 322.173346 -413.228028) (xy 322.146092 -413.227528)
			(xy 322.092139 -413.219777) (xy 322.039839 -413.204425) (xy 321.990255 -413.181787) (xy 321.944399 -413.152321)
			(xy 321.903203 -413.11663) (xy 321.867506 -413.075438) (xy 321.838035 -413.029585) (xy 321.815391 -412.980004)
			(xy 321.800033 -412.927706) (xy 321.792275 -412.873754) (xy 320.354742 -412.873754) (xy 320.346985 -412.927702)
			(xy 320.33163 -412.979999) (xy 320.308988 -413.029579) (xy 320.279521 -413.075431) (xy 320.243828 -413.116624)
			(xy 320.202636 -413.152317) (xy 320.156784 -413.181785) (xy 320.107205 -413.204428) (xy 320.054908 -413.219784)
			(xy 320.000958 -413.227542) (xy 319.973706 -413.228028) (xy 319.110106 -413.228028) (xy 319.082854 -413.227525)
			(xy 319.028906 -413.219769) (xy 318.97661 -413.204415) (xy 318.927031 -413.181774) (xy 318.88118 -413.152307)
			(xy 318.839989 -413.116616) (xy 318.804296 -413.075425) (xy 318.774829 -413.029574) (xy 318.752188 -412.979996)
			(xy 318.736832 -412.9277) (xy 318.729075 -412.873752) (xy 317.291565 -412.873752) (xy 317.291565 -412.873756)
			(xy 317.283807 -412.927713) (xy 317.268448 -412.980016) (xy 317.245802 -413.029601) (xy 317.216329 -413.075458)
			(xy 317.18063 -413.116654) (xy 317.139431 -413.15235) (xy 317.093571 -413.181818) (xy 317.043984 -413.20446)
			(xy 316.991679 -413.219814) (xy 316.937722 -413.227567) (xy 316.910466 -413.228028) (xy 316.046866 -413.228028)
			(xy 316.019618 -413.227499) (xy 315.965677 -413.219739) (xy 315.913389 -413.204382) (xy 315.863818 -413.18174)
			(xy 315.817975 -413.152275) (xy 315.776791 -413.116585) (xy 315.741105 -413.075398) (xy 315.711643 -413.029552)
			(xy 315.689006 -412.979979) (xy 315.673653 -412.92769) (xy 315.665898 -412.873748) (xy 314.228242 -412.873748)
			(xy 314.228242 -412.873751) (xy 314.220486 -412.9277) (xy 314.205131 -412.979995) (xy 314.182491 -413.029573)
			(xy 314.153026 -413.075425) (xy 314.117335 -413.116617) (xy 314.076146 -413.15231) (xy 314.030296 -413.181778)
			(xy 313.98072 -413.204422) (xy 313.928425 -413.21978) (xy 313.874477 -413.22754) (xy 313.847226 -413.228028)
			(xy 312.983626 -413.228028) (xy 312.956373 -413.227526) (xy 312.902422 -413.219773) (xy 312.850124 -413.20442)
			(xy 312.800543 -413.18178) (xy 312.754689 -413.152314) (xy 312.713496 -413.116623) (xy 312.677801 -413.075431)
			(xy 312.648332 -413.029579) (xy 312.625689 -412.98) (xy 312.610333 -412.927703) (xy 312.602575 -412.873753)
			(xy 311.165065 -412.873753) (xy 311.165065 -412.873755) (xy 311.157307 -412.92771) (xy 311.14195 -412.980012)
			(xy 311.119305 -413.029595) (xy 311.089834 -413.075452) (xy 311.054137 -413.116647) (xy 311.012941 -413.152343)
			(xy 310.967083 -413.181812) (xy 310.917499 -413.204455) (xy 310.865196 -413.21981) (xy 310.811241 -413.227566)
			(xy 310.783986 -413.228028) (xy 309.920386 -413.228028) (xy 309.893137 -413.227501) (xy 309.839194 -413.219743)
			(xy 309.786903 -413.204388) (xy 309.73733 -413.181747) (xy 309.691484 -413.152282) (xy 309.650298 -413.116592)
			(xy 309.61461 -413.075404) (xy 309.585146 -413.029557) (xy 309.562508 -412.979984) (xy 309.547154 -412.927693)
			(xy 309.539398 -412.873749) (xy 308.101742 -412.873749) (xy 308.101742 -412.873751) (xy 308.093987 -412.927697)
			(xy 308.078633 -412.979991) (xy 308.055994 -413.029568) (xy 308.02653 -413.075418) (xy 307.990842 -413.116609)
			(xy 307.949655 -413.152303) (xy 307.903808 -413.181772) (xy 307.854234 -413.204417) (xy 307.801942 -413.219777)
			(xy 307.747997 -413.227539) (xy 307.720746 -413.228028) (xy 306.857146 -413.228028) (xy 306.829892 -413.227528)
			(xy 306.775939 -413.219777) (xy 306.723639 -413.204425) (xy 306.674055 -413.181787) (xy 306.628199 -413.152321)
			(xy 306.587003 -413.11663) (xy 306.551306 -413.075438) (xy 306.521835 -413.029585) (xy 306.499191 -412.980004)
			(xy 306.483833 -412.927706) (xy 306.476075 -412.873754) (xy 305.038542 -412.873754) (xy 305.030785 -412.927702)
			(xy 305.01543 -412.979999) (xy 304.992788 -413.029579) (xy 304.963321 -413.075431) (xy 304.927628 -413.116624)
			(xy 304.886436 -413.152317) (xy 304.840584 -413.181785) (xy 304.791005 -413.204428) (xy 304.738708 -413.219784)
			(xy 304.684758 -413.227542) (xy 304.657506 -413.228028) (xy 303.793906 -413.228028) (xy 303.766654 -413.227525)
			(xy 303.712706 -413.219769) (xy 303.66041 -413.204415) (xy 303.610831 -413.181774) (xy 303.56498 -413.152307)
			(xy 303.523789 -413.116616) (xy 303.488096 -413.075425) (xy 303.458629 -413.029574) (xy 303.435988 -412.979996)
			(xy 303.420632 -412.9277) (xy 303.412875 -412.873752) (xy 301.559858 -412.873752) (xy 301.562459 -412.902862)
			(xy 301.570401 -413.080972) (xy 301.570898 -413.170116) (xy 301.570401 -413.25926) (xy 301.562459 -413.43737)
			(xy 301.546591 -413.61495) (xy 301.522827 -413.791646) (xy 301.491216 -413.967109) (xy 301.45182 -414.140989)
			(xy 301.404718 -414.312942) (xy 301.350002 -414.482626) (xy 301.287781 -414.649703) (xy 301.21818 -414.813844)
			(xy 301.141335 -414.97472) (xy 301.057401 -415.132014) (xy 300.966543 -415.285413) (xy 300.882586 -415.413753)
			(xy 304.944475 -415.413753) (xy 304.944475 -415.359247) (xy 304.952233 -415.305297) (xy 304.967589 -415.253)
			(xy 304.990232 -415.203421) (xy 305.019701 -415.157569) (xy 305.055396 -415.116377) (xy 305.096589 -415.080686)
			(xy 305.142443 -415.05122) (xy 305.192024 -415.02858) (xy 305.244322 -415.013227) (xy 305.298273 -415.005474)
			(xy 305.325526 -415.005012) (xy 306.189126 -415.005012) (xy 306.216377 -415.00546) (xy 306.270325 -415.01322)
			(xy 306.32262 -415.028578) (xy 306.372196 -415.051222) (xy 306.418046 -415.08069) (xy 306.459235 -415.116383)
			(xy 306.494926 -415.157575) (xy 306.524391 -415.203427) (xy 306.547031 -415.253005) (xy 306.562386 -415.3053)
			(xy 306.570142 -415.359249) (xy 306.570142 -415.413748) (xy 308.007798 -415.413748) (xy 308.007798 -415.359252)
			(xy 308.015553 -415.30531) (xy 308.030906 -415.253021) (xy 308.053543 -415.203448) (xy 308.083005 -415.157602)
			(xy 308.118691 -415.116415) (xy 308.159875 -415.080725) (xy 308.205718 -415.05126) (xy 308.255289 -415.028618)
			(xy 308.307577 -415.013261) (xy 308.361518 -415.005501) (xy 308.388766 -415.005012) (xy 309.252366 -415.005012)
			(xy 309.279622 -415.005433) (xy 309.333579 -415.013186) (xy 309.385884 -415.02854) (xy 309.435471 -415.051182)
			(xy 309.481331 -415.08065) (xy 309.52253 -415.116346) (xy 309.558229 -415.157542) (xy 309.587702 -415.203399)
			(xy 309.610348 -415.252984) (xy 309.625707 -415.305287) (xy 309.633465 -415.359244) (xy 309.633465 -415.413752)
			(xy 311.070975 -415.413752) (xy 311.070975 -415.359248) (xy 311.078732 -415.3053) (xy 311.094088 -415.253004)
			(xy 311.116729 -415.203426) (xy 311.146196 -415.157575) (xy 311.181889 -415.116384) (xy 311.22308 -415.080693)
			(xy 311.268931 -415.051226) (xy 311.31851 -415.028585) (xy 311.370806 -415.013231) (xy 311.424754 -415.005475)
			(xy 311.452006 -415.005012) (xy 312.315606 -415.005012) (xy 312.342858 -415.005458) (xy 312.396808 -415.013216)
			(xy 312.449105 -415.028572) (xy 312.498684 -415.051215) (xy 312.544536 -415.080683) (xy 312.585728 -415.116376)
			(xy 312.621421 -415.157569) (xy 312.650888 -415.203421) (xy 312.67353 -415.253001) (xy 312.688885 -415.305298)
			(xy 312.696642 -415.359248) (xy 312.696642 -415.413752) (xy 312.696642 -415.413754) (xy 314.134175 -415.413754)
			(xy 314.134175 -415.359246) (xy 314.141933 -415.305294) (xy 314.157291 -415.252996) (xy 314.179935 -415.203415)
			(xy 314.209406 -415.157562) (xy 314.245103 -415.11637) (xy 314.286299 -415.080679) (xy 314.332155 -415.051213)
			(xy 314.381739 -415.028575) (xy 314.434039 -415.013223) (xy 314.487992 -415.005472) (xy 314.515246 -415.005012)
			(xy 315.378846 -415.005012) (xy 315.406097 -415.005461) (xy 315.460042 -415.013223) (xy 315.512334 -415.028583)
			(xy 315.561908 -415.051228) (xy 315.607755 -415.080697) (xy 315.648942 -415.116391) (xy 315.68463 -415.157582)
			(xy 315.714094 -415.203432) (xy 315.736733 -415.253009) (xy 315.752087 -415.305303) (xy 315.759842 -415.359249)
			(xy 315.759842 -415.413749) (xy 317.197498 -415.413749) (xy 317.197498 -415.359251) (xy 317.205254 -415.305307)
			(xy 317.220608 -415.253016) (xy 317.243246 -415.203443) (xy 317.27271 -415.157596) (xy 317.308398 -415.116408)
			(xy 317.349584 -415.080718) (xy 317.39543 -415.051253) (xy 317.445003 -415.028612) (xy 317.497294 -415.013257)
			(xy 317.551237 -415.005499) (xy 317.578486 -415.005012) (xy 318.442086 -415.005012) (xy 318.469341 -415.005434)
			(xy 318.523296 -415.01319) (xy 318.575599 -415.028545) (xy 318.625183 -415.051188) (xy 318.671041 -415.080657)
			(xy 318.712237 -415.116353) (xy 318.747934 -415.157548) (xy 318.777405 -415.203405) (xy 318.80005 -415.252988)
			(xy 318.815407 -415.30529) (xy 318.823165 -415.359245) (xy 318.823165 -415.413753) (xy 320.260675 -415.413753)
			(xy 320.260675 -415.359247) (xy 320.268433 -415.305297) (xy 320.283789 -415.253) (xy 320.306432 -415.203421)
			(xy 320.335901 -415.157569) (xy 320.371596 -415.116377) (xy 320.412789 -415.080686) (xy 320.458643 -415.05122)
			(xy 320.508224 -415.02858) (xy 320.560522 -415.013227) (xy 320.614473 -415.005474) (xy 320.641726 -415.005012)
			(xy 321.505326 -415.005012) (xy 321.532577 -415.00546) (xy 321.586525 -415.01322) (xy 321.63882 -415.028578)
			(xy 321.688396 -415.051222) (xy 321.734246 -415.08069) (xy 321.775435 -415.116383) (xy 321.811126 -415.157575)
			(xy 321.840591 -415.203427) (xy 321.863231 -415.253005) (xy 321.878586 -415.3053) (xy 321.886342 -415.359249)
			(xy 321.886342 -415.413748) (xy 323.323998 -415.413748) (xy 323.323998 -415.359252) (xy 323.331753 -415.30531)
			(xy 323.347106 -415.253021) (xy 323.369743 -415.203448) (xy 323.399205 -415.157602) (xy 323.434891 -415.116415)
			(xy 323.476075 -415.080725) (xy 323.521918 -415.05126) (xy 323.571489 -415.028618) (xy 323.623777 -415.013261)
			(xy 323.677718 -415.005501) (xy 323.704966 -415.005012) (xy 324.568566 -415.005012) (xy 324.595822 -415.005433)
			(xy 324.649779 -415.013186) (xy 324.702084 -415.02854) (xy 324.751671 -415.051182) (xy 324.797531 -415.08065)
			(xy 324.83873 -415.116346) (xy 324.874429 -415.157542) (xy 324.903902 -415.203399) (xy 324.926548 -415.252984)
			(xy 324.941907 -415.305287) (xy 324.949665 -415.359244) (xy 324.949665 -415.413752) (xy 326.387175 -415.413752)
			(xy 326.387175 -415.359248) (xy 326.394932 -415.3053) (xy 326.410288 -415.253004) (xy 326.432929 -415.203426)
			(xy 326.462396 -415.157575) (xy 326.498089 -415.116384) (xy 326.53928 -415.080693) (xy 326.585131 -415.051226)
			(xy 326.63471 -415.028585) (xy 326.687006 -415.013231) (xy 326.740954 -415.005475) (xy 326.768206 -415.005012)
			(xy 327.631806 -415.005012) (xy 327.659058 -415.005458) (xy 327.713008 -415.013216) (xy 327.765305 -415.028572)
			(xy 327.814884 -415.051215) (xy 327.860736 -415.080683) (xy 327.901928 -415.116376) (xy 327.937621 -415.157569)
			(xy 327.967088 -415.203421) (xy 327.98973 -415.253001) (xy 328.005085 -415.305298) (xy 328.012842 -415.359248)
			(xy 328.012842 -415.413752) (xy 328.012842 -415.413754) (xy 329.450375 -415.413754) (xy 329.450375 -415.359246)
			(xy 329.458133 -415.305294) (xy 329.473491 -415.252996) (xy 329.496135 -415.203415) (xy 329.525606 -415.157562)
			(xy 329.561303 -415.11637) (xy 329.602499 -415.080679) (xy 329.648355 -415.051213) (xy 329.697939 -415.028575)
			(xy 329.750239 -415.013223) (xy 329.804192 -415.005472) (xy 329.831446 -415.005012) (xy 330.695046 -415.005012)
			(xy 330.722297 -415.005461) (xy 330.776242 -415.013223) (xy 330.828534 -415.028583) (xy 330.878108 -415.051228)
			(xy 330.923955 -415.080697) (xy 330.965142 -415.116391) (xy 331.00083 -415.157582) (xy 331.030294 -415.203432)
			(xy 331.052933 -415.253009) (xy 331.068287 -415.305303) (xy 331.076042 -415.359249) (xy 331.076042 -415.413749)
			(xy 332.513698 -415.413749) (xy 332.513698 -415.359251) (xy 332.521454 -415.305307) (xy 332.536808 -415.253016)
			(xy 332.559446 -415.203443) (xy 332.58891 -415.157596) (xy 332.624598 -415.116408) (xy 332.665784 -415.080718)
			(xy 332.71163 -415.051253) (xy 332.761203 -415.028612) (xy 332.813494 -415.013257) (xy 332.867437 -415.005499)
			(xy 332.894686 -415.005012) (xy 333.758286 -415.005012) (xy 333.785541 -415.005434) (xy 333.839496 -415.01319)
			(xy 333.891799 -415.028545) (xy 333.941383 -415.051188) (xy 333.987241 -415.080657) (xy 334.028437 -415.116353)
			(xy 334.064134 -415.157548) (xy 334.093605 -415.203405) (xy 334.11625 -415.252988) (xy 334.131607 -415.30529)
			(xy 334.139365 -415.359245) (xy 334.139365 -415.413753) (xy 335.576875 -415.413753) (xy 335.576875 -415.359247)
			(xy 335.584633 -415.305297) (xy 335.599989 -415.253) (xy 335.622632 -415.203421) (xy 335.652101 -415.157569)
			(xy 335.687796 -415.116377) (xy 335.728989 -415.080686) (xy 335.774843 -415.05122) (xy 335.824424 -415.02858)
			(xy 335.876722 -415.013227) (xy 335.930673 -415.005474) (xy 335.957926 -415.005012) (xy 336.821526 -415.005012)
			(xy 336.848777 -415.00546) (xy 336.902725 -415.01322) (xy 336.95502 -415.028578) (xy 337.004596 -415.051222)
			(xy 337.050446 -415.08069) (xy 337.091635 -415.116383) (xy 337.127326 -415.157575) (xy 337.156791 -415.203427)
			(xy 337.179431 -415.253005) (xy 337.194786 -415.3053) (xy 337.202542 -415.359249) (xy 337.202542 -415.413748)
			(xy 338.640198 -415.413748) (xy 338.640198 -415.359252) (xy 338.647953 -415.30531) (xy 338.663306 -415.253021)
			(xy 338.685943 -415.203448) (xy 338.715405 -415.157602) (xy 338.751091 -415.116415) (xy 338.792275 -415.080725)
			(xy 338.838118 -415.05126) (xy 338.887689 -415.028618) (xy 338.939977 -415.013261) (xy 338.993918 -415.005501)
			(xy 339.021166 -415.005012) (xy 339.884766 -415.005012) (xy 339.912022 -415.005433) (xy 339.965979 -415.013186)
			(xy 340.018284 -415.02854) (xy 340.067871 -415.051182) (xy 340.113731 -415.08065) (xy 340.15493 -415.116346)
			(xy 340.190629 -415.157542) (xy 340.220102 -415.203399) (xy 340.242748 -415.252984) (xy 340.258107 -415.305287)
			(xy 340.265865 -415.359244) (xy 340.265865 -415.413752) (xy 341.703375 -415.413752) (xy 341.703375 -415.359248)
			(xy 341.711132 -415.3053) (xy 341.726488 -415.253004) (xy 341.749129 -415.203426) (xy 341.778596 -415.157575)
			(xy 341.814289 -415.116384) (xy 341.85548 -415.080693) (xy 341.901331 -415.051226) (xy 341.95091 -415.028585)
			(xy 342.003206 -415.013231) (xy 342.057154 -415.005475) (xy 342.084406 -415.005012) (xy 342.948006 -415.005012)
			(xy 342.975258 -415.005458) (xy 343.029208 -415.013216) (xy 343.081505 -415.028572) (xy 343.131084 -415.051215)
			(xy 343.176936 -415.080683) (xy 343.218128 -415.116376) (xy 343.253821 -415.157569) (xy 343.283288 -415.203421)
			(xy 343.30593 -415.253001) (xy 343.321285 -415.305298) (xy 343.329042 -415.359248) (xy 343.329042 -415.413752)
			(xy 343.329042 -415.413754) (xy 344.766575 -415.413754) (xy 344.766575 -415.359246) (xy 344.774333 -415.305294)
			(xy 344.789691 -415.252996) (xy 344.812335 -415.203415) (xy 344.841806 -415.157562) (xy 344.877503 -415.11637)
			(xy 344.918699 -415.080679) (xy 344.964555 -415.051213) (xy 345.014139 -415.028575) (xy 345.066439 -415.013223)
			(xy 345.120392 -415.005472) (xy 345.147646 -415.005012) (xy 346.011246 -415.005012) (xy 346.038497 -415.005461)
			(xy 346.092442 -415.013223) (xy 346.144734 -415.028583) (xy 346.194308 -415.051228) (xy 346.240155 -415.080697)
			(xy 346.281342 -415.116391) (xy 346.31703 -415.157582) (xy 346.346494 -415.203432) (xy 346.369133 -415.253009)
			(xy 346.384487 -415.305303) (xy 346.392242 -415.359249) (xy 346.392242 -415.413749) (xy 347.829898 -415.413749)
			(xy 347.829898 -415.359251) (xy 347.837654 -415.305307) (xy 347.853008 -415.253016) (xy 347.875646 -415.203443)
			(xy 347.90511 -415.157596) (xy 347.940798 -415.116408) (xy 347.981984 -415.080718) (xy 348.02783 -415.051253)
			(xy 348.077403 -415.028612) (xy 348.129694 -415.013257) (xy 348.183637 -415.005499) (xy 348.210886 -415.005012)
			(xy 349.074486 -415.005012) (xy 349.101741 -415.005434) (xy 349.155696 -415.01319) (xy 349.207999 -415.028545)
			(xy 349.257583 -415.051188) (xy 349.303441 -415.080657) (xy 349.344637 -415.116353) (xy 349.380334 -415.157548)
			(xy 349.409805 -415.203405) (xy 349.43245 -415.252988) (xy 349.447807 -415.30529) (xy 349.455565 -415.359245)
			(xy 349.455565 -415.413753) (xy 350.893075 -415.413753) (xy 350.893075 -415.359247) (xy 350.900833 -415.305297)
			(xy 350.916189 -415.253) (xy 350.938832 -415.203421) (xy 350.968301 -415.157569) (xy 351.003996 -415.116377)
			(xy 351.045189 -415.080686) (xy 351.091043 -415.05122) (xy 351.140624 -415.02858) (xy 351.192922 -415.013227)
			(xy 351.246873 -415.005474) (xy 351.274126 -415.005012) (xy 352.137726 -415.005012) (xy 352.164977 -415.00546)
			(xy 352.218925 -415.01322) (xy 352.27122 -415.028578) (xy 352.320796 -415.051222) (xy 352.366646 -415.08069)
			(xy 352.407835 -415.116383) (xy 352.443526 -415.157575) (xy 352.472991 -415.203427) (xy 352.495631 -415.253005)
			(xy 352.510986 -415.3053) (xy 352.518742 -415.359249) (xy 352.518742 -415.413751) (xy 352.518742 -415.413752)
			(xy 372.044675 -415.413752) (xy 372.044675 -415.359248) (xy 372.052432 -415.305298) (xy 372.067789 -415.253001)
			(xy 372.090432 -415.203422) (xy 372.1199 -415.15757) (xy 372.155594 -415.116379) (xy 372.196788 -415.080687)
			(xy 372.242641 -415.051221) (xy 372.292221 -415.028581) (xy 372.344519 -415.013228) (xy 372.39847 -415.005474)
			(xy 372.425722 -415.005012) (xy 373.289322 -415.005012) (xy 373.316574 -415.005459) (xy 373.370522 -415.013219)
			(xy 373.422817 -415.028577) (xy 373.472394 -415.05122) (xy 373.518244 -415.080689) (xy 373.559434 -415.116382)
			(xy 373.595125 -415.157574) (xy 373.62459 -415.203426) (xy 373.647231 -415.253004) (xy 373.662586 -415.3053)
			(xy 373.670342 -415.359248) (xy 373.670342 -415.413748) (xy 375.107998 -415.413748) (xy 375.107998 -415.359252)
			(xy 375.115753 -415.30531) (xy 375.131106 -415.253022) (xy 375.153743 -415.203449) (xy 375.183204 -415.157603)
			(xy 375.218889 -415.116416) (xy 375.260073 -415.080727) (xy 375.305916 -415.051261) (xy 375.355486 -415.028619)
			(xy 375.407773 -415.013261) (xy 375.461714 -415.005501) (xy 375.488962 -415.005012) (xy 376.352562 -415.005012)
			(xy 376.379818 -415.005432) (xy 376.433776 -415.013185) (xy 376.486081 -415.028539) (xy 376.535669 -415.05118)
			(xy 376.581529 -415.080649) (xy 376.622729 -415.116345) (xy 376.658428 -415.15754) (xy 376.687901 -415.203398)
			(xy 376.710548 -415.252983) (xy 376.725907 -415.305287) (xy 376.733665 -415.359244) (xy 376.733665 -415.413752)
			(xy 378.171175 -415.413752) (xy 378.171175 -415.359248) (xy 378.178932 -415.3053) (xy 378.194287 -415.253005)
			(xy 378.216929 -415.203427) (xy 378.246395 -415.157576) (xy 378.282087 -415.116386) (xy 378.323278 -415.080694)
			(xy 378.369129 -415.051228) (xy 378.418707 -415.028587) (xy 378.471002 -415.013231) (xy 378.52495 -415.005475)
			(xy 378.552202 -415.005012) (xy 379.415802 -415.005012) (xy 379.443055 -415.005458) (xy 379.497005 -415.013215)
			(xy 379.549302 -415.028571) (xy 379.598882 -415.051214) (xy 379.644734 -415.080682) (xy 379.685926 -415.116375)
			(xy 379.72162 -415.157567) (xy 379.751087 -415.20342) (xy 379.773729 -415.253) (xy 379.789085 -415.305297)
			(xy 379.796842 -415.359247) (xy 379.796842 -415.413753) (xy 381.234375 -415.413753) (xy 381.234375 -415.359247)
			(xy 381.242133 -415.305295) (xy 381.25749 -415.252996) (xy 381.280135 -415.203416) (xy 381.309605 -415.157563)
			(xy 381.345301 -415.116372) (xy 381.386497 -415.08068) (xy 381.432353 -415.051215) (xy 381.481936 -415.028576)
			(xy 381.534236 -415.013224) (xy 381.588189 -415.005472) (xy 381.615442 -415.005012) (xy 382.479042 -415.005012)
			(xy 382.506293 -415.005461) (xy 382.560239 -415.013222) (xy 382.612531 -415.028582) (xy 382.662106 -415.051227)
			(xy 382.707953 -415.080696) (xy 382.749141 -415.116389) (xy 382.784829 -415.15758) (xy 382.814293 -415.203431)
			(xy 382.836933 -415.253008) (xy 382.852286 -415.305302) (xy 382.860042 -415.359249) (xy 382.860042 -415.413749)
			(xy 384.297698 -415.413749) (xy 384.297698 -415.359251) (xy 384.305454 -415.305308) (xy 384.320807 -415.253017)
			(xy 384.343446 -415.203444) (xy 384.372909 -415.157597) (xy 384.408597 -415.116409) (xy 384.449782 -415.08072)
			(xy 384.495628 -415.051254) (xy 384.5452 -415.028613) (xy 384.59749 -415.013258) (xy 384.651433 -415.005499)
			(xy 384.678682 -415.005012) (xy 385.542282 -415.005012) (xy 385.569537 -415.005434) (xy 385.623493 -415.013189)
			(xy 385.675796 -415.028544) (xy 385.725381 -415.051187) (xy 385.771239 -415.080656) (xy 385.812436 -415.116352)
			(xy 385.848133 -415.157547) (xy 385.877604 -415.203403) (xy 385.900249 -415.252987) (xy 385.915607 -415.305289)
			(xy 385.923365 -415.359245) (xy 385.923365 -415.413752) (xy 387.360875 -415.413752) (xy 387.360875 -415.359248)
			(xy 387.368632 -415.305298) (xy 387.383989 -415.253001) (xy 387.406632 -415.203422) (xy 387.4361 -415.15757)
			(xy 387.471794 -415.116379) (xy 387.512988 -415.080687) (xy 387.558841 -415.051221) (xy 387.608421 -415.028581)
			(xy 387.660719 -415.013228) (xy 387.71467 -415.005474) (xy 387.741922 -415.005012) (xy 388.605522 -415.005012)
			(xy 388.632774 -415.005459) (xy 388.686722 -415.013219) (xy 388.739017 -415.028577) (xy 388.788594 -415.05122)
			(xy 388.834444 -415.080689) (xy 388.875634 -415.116382) (xy 388.911325 -415.157574) (xy 388.94079 -415.203426)
			(xy 388.963431 -415.253004) (xy 388.978786 -415.3053) (xy 388.986542 -415.359248) (xy 388.986542 -415.413748)
			(xy 390.424198 -415.413748) (xy 390.424198 -415.359252) (xy 390.431953 -415.30531) (xy 390.447306 -415.253022)
			(xy 390.469943 -415.203449) (xy 390.499404 -415.157603) (xy 390.535089 -415.116416) (xy 390.576273 -415.080727)
			(xy 390.622116 -415.051261) (xy 390.671686 -415.028619) (xy 390.723973 -415.013261) (xy 390.777914 -415.005501)
			(xy 390.805162 -415.005012) (xy 391.668762 -415.005012) (xy 391.696018 -415.005432) (xy 391.749976 -415.013185)
			(xy 391.802281 -415.028539) (xy 391.851869 -415.05118) (xy 391.897729 -415.080649) (xy 391.938929 -415.116345)
			(xy 391.974628 -415.15754) (xy 392.004101 -415.203398) (xy 392.026748 -415.252983) (xy 392.042107 -415.305287)
			(xy 392.049865 -415.359244) (xy 392.049865 -415.413752) (xy 393.487375 -415.413752) (xy 393.487375 -415.359248)
			(xy 393.495132 -415.3053) (xy 393.510487 -415.253005) (xy 393.533129 -415.203427) (xy 393.562595 -415.157576)
			(xy 393.598287 -415.116386) (xy 393.639478 -415.080694) (xy 393.685329 -415.051228) (xy 393.734907 -415.028587)
			(xy 393.787202 -415.013231) (xy 393.84115 -415.005475) (xy 393.868402 -415.005012) (xy 394.732002 -415.005012)
			(xy 394.759255 -415.005458) (xy 394.813205 -415.013215) (xy 394.865502 -415.028571) (xy 394.915082 -415.051214)
			(xy 394.960934 -415.080682) (xy 395.002126 -415.116375) (xy 395.03782 -415.157567) (xy 395.067287 -415.20342)
			(xy 395.089929 -415.253) (xy 395.105285 -415.305297) (xy 395.113042 -415.359247) (xy 395.113042 -415.413753)
			(xy 396.550575 -415.413753) (xy 396.550575 -415.359247) (xy 396.558333 -415.305295) (xy 396.57369 -415.252996)
			(xy 396.596335 -415.203416) (xy 396.625805 -415.157563) (xy 396.661501 -415.116372) (xy 396.702697 -415.08068)
			(xy 396.748553 -415.051215) (xy 396.798136 -415.028576) (xy 396.850436 -415.013224) (xy 396.904389 -415.005472)
			(xy 396.931642 -415.005012) (xy 397.795242 -415.005012) (xy 397.822493 -415.005461) (xy 397.876439 -415.013222)
			(xy 397.928731 -415.028582) (xy 397.978306 -415.051227) (xy 398.024153 -415.080696) (xy 398.065341 -415.116389)
			(xy 398.101029 -415.15758) (xy 398.130493 -415.203431) (xy 398.153133 -415.253008) (xy 398.168486 -415.305302)
			(xy 398.176242 -415.359249) (xy 398.176242 -415.413749) (xy 399.613898 -415.413749) (xy 399.613898 -415.359251)
			(xy 399.621654 -415.305308) (xy 399.637007 -415.253017) (xy 399.659646 -415.203444) (xy 399.689109 -415.157597)
			(xy 399.724797 -415.116409) (xy 399.765982 -415.08072) (xy 399.811828 -415.051254) (xy 399.8614 -415.028613)
			(xy 399.91369 -415.013258) (xy 399.967633 -415.005499) (xy 399.994882 -415.005012) (xy 400.858482 -415.005012)
			(xy 400.885737 -415.005434) (xy 400.939693 -415.013189) (xy 400.991996 -415.028544) (xy 401.041581 -415.051187)
			(xy 401.087439 -415.080656) (xy 401.128636 -415.116352) (xy 401.164333 -415.157547) (xy 401.193804 -415.203403)
			(xy 401.216449 -415.252987) (xy 401.231807 -415.305289) (xy 401.239565 -415.359245) (xy 401.239565 -415.413752)
			(xy 402.677075 -415.413752) (xy 402.677075 -415.359248) (xy 402.684832 -415.305298) (xy 402.700189 -415.253001)
			(xy 402.722832 -415.203422) (xy 402.7523 -415.15757) (xy 402.787994 -415.116379) (xy 402.829188 -415.080687)
			(xy 402.875041 -415.051221) (xy 402.924621 -415.028581) (xy 402.976919 -415.013228) (xy 403.03087 -415.005474)
			(xy 403.058122 -415.005012) (xy 403.921722 -415.005012) (xy 403.948974 -415.005459) (xy 404.002922 -415.013219)
			(xy 404.055217 -415.028577) (xy 404.104794 -415.05122) (xy 404.150644 -415.080689) (xy 404.191834 -415.116382)
			(xy 404.227525 -415.157574) (xy 404.25699 -415.203426) (xy 404.279631 -415.253004) (xy 404.294986 -415.3053)
			(xy 404.302742 -415.359248) (xy 404.302742 -415.413748) (xy 405.740398 -415.413748) (xy 405.740398 -415.359252)
			(xy 405.748153 -415.30531) (xy 405.763506 -415.253022) (xy 405.786143 -415.203449) (xy 405.815604 -415.157603)
			(xy 405.851289 -415.116416) (xy 405.892473 -415.080727) (xy 405.938316 -415.051261) (xy 405.987886 -415.028619)
			(xy 406.040173 -415.013261) (xy 406.094114 -415.005501) (xy 406.121362 -415.005012) (xy 406.984962 -415.005012)
			(xy 407.012218 -415.005432) (xy 407.066176 -415.013185) (xy 407.118481 -415.028539) (xy 407.168069 -415.05118)
			(xy 407.213929 -415.080649) (xy 407.255129 -415.116345) (xy 407.290828 -415.15754) (xy 407.320301 -415.203398)
			(xy 407.342948 -415.252983) (xy 407.358307 -415.305287) (xy 407.366065 -415.359244) (xy 407.366065 -415.413752)
			(xy 408.803575 -415.413752) (xy 408.803575 -415.359248) (xy 408.811332 -415.3053) (xy 408.826687 -415.253005)
			(xy 408.849329 -415.203427) (xy 408.878795 -415.157576) (xy 408.914487 -415.116386) (xy 408.955678 -415.080694)
			(xy 409.001529 -415.051228) (xy 409.051107 -415.028587) (xy 409.103402 -415.013231) (xy 409.15735 -415.005475)
			(xy 409.184602 -415.005012) (xy 410.048202 -415.005012) (xy 410.075455 -415.005458) (xy 410.129405 -415.013215)
			(xy 410.181702 -415.028571) (xy 410.231282 -415.051214) (xy 410.277134 -415.080682) (xy 410.318326 -415.116375)
			(xy 410.35402 -415.157567) (xy 410.383487 -415.20342) (xy 410.406129 -415.253) (xy 410.421485 -415.305297)
			(xy 410.429242 -415.359247) (xy 410.429242 -415.413753) (xy 411.866775 -415.413753) (xy 411.866775 -415.359247)
			(xy 411.874533 -415.305295) (xy 411.88989 -415.252996) (xy 411.912535 -415.203416) (xy 411.942005 -415.157563)
			(xy 411.977701 -415.116372) (xy 412.018897 -415.08068) (xy 412.064753 -415.051215) (xy 412.114336 -415.028576)
			(xy 412.166636 -415.013224) (xy 412.220589 -415.005472) (xy 412.247842 -415.005012) (xy 413.111442 -415.005012)
			(xy 413.138693 -415.005461) (xy 413.192639 -415.013222) (xy 413.244931 -415.028582) (xy 413.294506 -415.051227)
			(xy 413.340353 -415.080696) (xy 413.381541 -415.116389) (xy 413.417229 -415.15758) (xy 413.446693 -415.203431)
			(xy 413.469333 -415.253008) (xy 413.484686 -415.305302) (xy 413.492442 -415.359249) (xy 413.492442 -415.413749)
			(xy 414.930098 -415.413749) (xy 414.930098 -415.359251) (xy 414.937854 -415.305308) (xy 414.953207 -415.253017)
			(xy 414.975846 -415.203444) (xy 415.005309 -415.157597) (xy 415.040997 -415.116409) (xy 415.082182 -415.08072)
			(xy 415.128028 -415.051254) (xy 415.1776 -415.028613) (xy 415.22989 -415.013258) (xy 415.283833 -415.005499)
			(xy 415.311082 -415.005012) (xy 416.174682 -415.005012) (xy 416.201937 -415.005434) (xy 416.255893 -415.013189)
			(xy 416.308196 -415.028544) (xy 416.357781 -415.051187) (xy 416.403639 -415.080656) (xy 416.444836 -415.116352)
			(xy 416.480533 -415.157547) (xy 416.510004 -415.203403) (xy 416.532649 -415.252987) (xy 416.548007 -415.305289)
			(xy 416.555765 -415.359245) (xy 416.555765 -415.413752) (xy 417.993275 -415.413752) (xy 417.993275 -415.359248)
			(xy 418.001032 -415.305298) (xy 418.016389 -415.253001) (xy 418.039032 -415.203422) (xy 418.0685 -415.15757)
			(xy 418.104194 -415.116379) (xy 418.145388 -415.080687) (xy 418.191241 -415.051221) (xy 418.240821 -415.028581)
			(xy 418.293119 -415.013228) (xy 418.34707 -415.005474) (xy 418.374322 -415.005012) (xy 419.237922 -415.005012)
			(xy 419.265174 -415.005459) (xy 419.319122 -415.013219) (xy 419.371417 -415.028577) (xy 419.420994 -415.05122)
			(xy 419.466844 -415.080689) (xy 419.508034 -415.116382) (xy 419.543725 -415.157574) (xy 419.57319 -415.203426)
			(xy 419.595831 -415.253004) (xy 419.611186 -415.3053) (xy 419.618942 -415.359248) (xy 419.618942 -415.413752)
			(xy 419.611186 -415.4677) (xy 419.595831 -415.519996) (xy 419.57319 -415.569574) (xy 419.543725 -415.615426)
			(xy 419.508034 -415.656618) (xy 419.466844 -415.692311) (xy 419.420994 -415.72178) (xy 419.371417 -415.744423)
			(xy 419.319122 -415.759781) (xy 419.265174 -415.767541) (xy 419.237922 -415.768028) (xy 418.374322 -415.768028)
			(xy 418.34707 -415.767526) (xy 418.293119 -415.759772) (xy 418.240821 -415.744419) (xy 418.191241 -415.721779)
			(xy 418.145388 -415.692313) (xy 418.104194 -415.656621) (xy 418.0685 -415.61543) (xy 418.039032 -415.569578)
			(xy 418.016389 -415.519999) (xy 418.001032 -415.467702) (xy 417.993275 -415.413752) (xy 416.555765 -415.413752)
			(xy 416.555765 -415.413755) (xy 416.548007 -415.467711) (xy 416.532649 -415.520013) (xy 416.510004 -415.569597)
			(xy 416.480533 -415.615453) (xy 416.444836 -415.656648) (xy 416.403639 -415.692344) (xy 416.357781 -415.721813)
			(xy 416.308196 -415.744456) (xy 416.255893 -415.759811) (xy 416.201937 -415.767566) (xy 416.174682 -415.768028)
			(xy 415.311082 -415.768028) (xy 415.283833 -415.767501) (xy 415.22989 -415.759742) (xy 415.1776 -415.744387)
			(xy 415.128028 -415.721746) (xy 415.082182 -415.69228) (xy 415.040997 -415.656591) (xy 415.005309 -415.615403)
			(xy 414.975846 -415.569556) (xy 414.953207 -415.519983) (xy 414.937854 -415.467692) (xy 414.930098 -415.413749)
			(xy 413.492442 -415.413749) (xy 413.492442 -415.413751) (xy 413.484686 -415.467698) (xy 413.469333 -415.519992)
			(xy 413.446693 -415.569569) (xy 413.417229 -415.61542) (xy 413.381541 -415.656611) (xy 413.340353 -415.692304)
			(xy 413.294506 -415.721773) (xy 413.244931 -415.744418) (xy 413.192639 -415.759778) (xy 413.138693 -415.767539)
			(xy 413.111442 -415.768028) (xy 412.247842 -415.768028) (xy 412.220589 -415.767528) (xy 412.166636 -415.759776)
			(xy 412.114336 -415.744424) (xy 412.064753 -415.721785) (xy 412.018897 -415.69232) (xy 411.977701 -415.656628)
			(xy 411.942005 -415.615437) (xy 411.912535 -415.569584) (xy 411.88989 -415.520004) (xy 411.874533 -415.467705)
			(xy 411.866775 -415.413753) (xy 410.429242 -415.413753) (xy 410.421485 -415.467703) (xy 410.406129 -415.52)
			(xy 410.383487 -415.56958) (xy 410.35402 -415.615433) (xy 410.318326 -415.656625) (xy 410.277134 -415.692318)
			(xy 410.231282 -415.721786) (xy 410.181702 -415.744429) (xy 410.129405 -415.759785) (xy 410.075455 -415.767542)
			(xy 410.048202 -415.768028) (xy 409.184602 -415.768028) (xy 409.15735 -415.767525) (xy 409.103402 -415.759769)
			(xy 409.051107 -415.744413) (xy 409.001529 -415.721772) (xy 408.955678 -415.692306) (xy 408.914487 -415.656614)
			(xy 408.878795 -415.615424) (xy 408.849329 -415.569573) (xy 408.826687 -415.519995) (xy 408.811332 -415.4677)
			(xy 408.803575 -415.413752) (xy 407.366065 -415.413752) (xy 407.366065 -415.413756) (xy 407.358307 -415.467713)
			(xy 407.342948 -415.520017) (xy 407.320301 -415.569602) (xy 407.290828 -415.61546) (xy 407.255129 -415.656655)
			(xy 407.213929 -415.692351) (xy 407.168069 -415.72182) (xy 407.118481 -415.744461) (xy 407.066176 -415.759815)
			(xy 407.012218 -415.767568) (xy 406.984962 -415.768028) (xy 406.121362 -415.768028) (xy 406.094114 -415.767499)
			(xy 406.040173 -415.759739) (xy 405.987886 -415.744381) (xy 405.938316 -415.721739) (xy 405.892473 -415.692273)
			(xy 405.851289 -415.656584) (xy 405.815604 -415.615397) (xy 405.786143 -415.569551) (xy 405.763506 -415.519978)
			(xy 405.748153 -415.46769) (xy 405.740398 -415.413748) (xy 404.302742 -415.413748) (xy 404.302742 -415.413752)
			(xy 404.294986 -415.4677) (xy 404.279631 -415.519996) (xy 404.25699 -415.569574) (xy 404.227525 -415.615426)
			(xy 404.191834 -415.656618) (xy 404.150644 -415.692311) (xy 404.104794 -415.72178) (xy 404.055217 -415.744423)
			(xy 404.002922 -415.759781) (xy 403.948974 -415.767541) (xy 403.921722 -415.768028) (xy 403.058122 -415.768028)
			(xy 403.03087 -415.767526) (xy 402.976919 -415.759772) (xy 402.924621 -415.744419) (xy 402.875041 -415.721779)
			(xy 402.829188 -415.692313) (xy 402.787994 -415.656621) (xy 402.7523 -415.61543) (xy 402.722832 -415.569578)
			(xy 402.700189 -415.519999) (xy 402.684832 -415.467702) (xy 402.677075 -415.413752) (xy 401.239565 -415.413752)
			(xy 401.239565 -415.413755) (xy 401.231807 -415.467711) (xy 401.216449 -415.520013) (xy 401.193804 -415.569597)
			(xy 401.164333 -415.615453) (xy 401.128636 -415.656648) (xy 401.087439 -415.692344) (xy 401.041581 -415.721813)
			(xy 400.991996 -415.744456) (xy 400.939693 -415.759811) (xy 400.885737 -415.767566) (xy 400.858482 -415.768028)
			(xy 399.994882 -415.768028) (xy 399.967633 -415.767501) (xy 399.91369 -415.759742) (xy 399.8614 -415.744387)
			(xy 399.811828 -415.721746) (xy 399.765982 -415.69228) (xy 399.724797 -415.656591) (xy 399.689109 -415.615403)
			(xy 399.659646 -415.569556) (xy 399.637007 -415.519983) (xy 399.621654 -415.467692) (xy 399.613898 -415.413749)
			(xy 398.176242 -415.413749) (xy 398.176242 -415.413751) (xy 398.168486 -415.467698) (xy 398.153133 -415.519992)
			(xy 398.130493 -415.569569) (xy 398.101029 -415.61542) (xy 398.065341 -415.656611) (xy 398.024153 -415.692304)
			(xy 397.978306 -415.721773) (xy 397.928731 -415.744418) (xy 397.876439 -415.759778) (xy 397.822493 -415.767539)
			(xy 397.795242 -415.768028) (xy 396.931642 -415.768028) (xy 396.904389 -415.767528) (xy 396.850436 -415.759776)
			(xy 396.798136 -415.744424) (xy 396.748553 -415.721785) (xy 396.702697 -415.69232) (xy 396.661501 -415.656628)
			(xy 396.625805 -415.615437) (xy 396.596335 -415.569584) (xy 396.57369 -415.520004) (xy 396.558333 -415.467705)
			(xy 396.550575 -415.413753) (xy 395.113042 -415.413753) (xy 395.105285 -415.467703) (xy 395.089929 -415.52)
			(xy 395.067287 -415.56958) (xy 395.03782 -415.615433) (xy 395.002126 -415.656625) (xy 394.960934 -415.692318)
			(xy 394.915082 -415.721786) (xy 394.865502 -415.744429) (xy 394.813205 -415.759785) (xy 394.759255 -415.767542)
			(xy 394.732002 -415.768028) (xy 393.868402 -415.768028) (xy 393.84115 -415.767525) (xy 393.787202 -415.759769)
			(xy 393.734907 -415.744413) (xy 393.685329 -415.721772) (xy 393.639478 -415.692306) (xy 393.598287 -415.656614)
			(xy 393.562595 -415.615424) (xy 393.533129 -415.569573) (xy 393.510487 -415.519995) (xy 393.495132 -415.4677)
			(xy 393.487375 -415.413752) (xy 392.049865 -415.413752) (xy 392.049865 -415.413756) (xy 392.042107 -415.467713)
			(xy 392.026748 -415.520017) (xy 392.004101 -415.569602) (xy 391.974628 -415.61546) (xy 391.938929 -415.656655)
			(xy 391.897729 -415.692351) (xy 391.851869 -415.72182) (xy 391.802281 -415.744461) (xy 391.749976 -415.759815)
			(xy 391.696018 -415.767568) (xy 391.668762 -415.768028) (xy 390.805162 -415.768028) (xy 390.777914 -415.767499)
			(xy 390.723973 -415.759739) (xy 390.671686 -415.744381) (xy 390.622116 -415.721739) (xy 390.576273 -415.692273)
			(xy 390.535089 -415.656584) (xy 390.499404 -415.615397) (xy 390.469943 -415.569551) (xy 390.447306 -415.519978)
			(xy 390.431953 -415.46769) (xy 390.424198 -415.413748) (xy 388.986542 -415.413748) (xy 388.986542 -415.413752)
			(xy 388.978786 -415.4677) (xy 388.963431 -415.519996) (xy 388.94079 -415.569574) (xy 388.911325 -415.615426)
			(xy 388.875634 -415.656618) (xy 388.834444 -415.692311) (xy 388.788594 -415.72178) (xy 388.739017 -415.744423)
			(xy 388.686722 -415.759781) (xy 388.632774 -415.767541) (xy 388.605522 -415.768028) (xy 387.741922 -415.768028)
			(xy 387.71467 -415.767526) (xy 387.660719 -415.759772) (xy 387.608421 -415.744419) (xy 387.558841 -415.721779)
			(xy 387.512988 -415.692313) (xy 387.471794 -415.656621) (xy 387.4361 -415.61543) (xy 387.406632 -415.569578)
			(xy 387.383989 -415.519999) (xy 387.368632 -415.467702) (xy 387.360875 -415.413752) (xy 385.923365 -415.413752)
			(xy 385.923365 -415.413755) (xy 385.915607 -415.467711) (xy 385.900249 -415.520013) (xy 385.877604 -415.569597)
			(xy 385.848133 -415.615453) (xy 385.812436 -415.656648) (xy 385.771239 -415.692344) (xy 385.725381 -415.721813)
			(xy 385.675796 -415.744456) (xy 385.623493 -415.759811) (xy 385.569537 -415.767566) (xy 385.542282 -415.768028)
			(xy 384.678682 -415.768028) (xy 384.651433 -415.767501) (xy 384.59749 -415.759742) (xy 384.5452 -415.744387)
			(xy 384.495628 -415.721746) (xy 384.449782 -415.69228) (xy 384.408597 -415.656591) (xy 384.372909 -415.615403)
			(xy 384.343446 -415.569556) (xy 384.320807 -415.519983) (xy 384.305454 -415.467692) (xy 384.297698 -415.413749)
			(xy 382.860042 -415.413749) (xy 382.860042 -415.413751) (xy 382.852286 -415.467698) (xy 382.836933 -415.519992)
			(xy 382.814293 -415.569569) (xy 382.784829 -415.61542) (xy 382.749141 -415.656611) (xy 382.707953 -415.692304)
			(xy 382.662106 -415.721773) (xy 382.612531 -415.744418) (xy 382.560239 -415.759778) (xy 382.506293 -415.767539)
			(xy 382.479042 -415.768028) (xy 381.615442 -415.768028) (xy 381.588189 -415.767528) (xy 381.534236 -415.759776)
			(xy 381.481936 -415.744424) (xy 381.432353 -415.721785) (xy 381.386497 -415.69232) (xy 381.345301 -415.656628)
			(xy 381.309605 -415.615437) (xy 381.280135 -415.569584) (xy 381.25749 -415.520004) (xy 381.242133 -415.467705)
			(xy 381.234375 -415.413753) (xy 379.796842 -415.413753) (xy 379.789085 -415.467703) (xy 379.773729 -415.52)
			(xy 379.751087 -415.56958) (xy 379.72162 -415.615433) (xy 379.685926 -415.656625) (xy 379.644734 -415.692318)
			(xy 379.598882 -415.721786) (xy 379.549302 -415.744429) (xy 379.497005 -415.759785) (xy 379.443055 -415.767542)
			(xy 379.415802 -415.768028) (xy 378.552202 -415.768028) (xy 378.52495 -415.767525) (xy 378.471002 -415.759769)
			(xy 378.418707 -415.744413) (xy 378.369129 -415.721772) (xy 378.323278 -415.692306) (xy 378.282087 -415.656614)
			(xy 378.246395 -415.615424) (xy 378.216929 -415.569573) (xy 378.194287 -415.519995) (xy 378.178932 -415.4677)
			(xy 378.171175 -415.413752) (xy 376.733665 -415.413752) (xy 376.733665 -415.413756) (xy 376.725907 -415.467713)
			(xy 376.710548 -415.520017) (xy 376.687901 -415.569602) (xy 376.658428 -415.61546) (xy 376.622729 -415.656655)
			(xy 376.581529 -415.692351) (xy 376.535669 -415.72182) (xy 376.486081 -415.744461) (xy 376.433776 -415.759815)
			(xy 376.379818 -415.767568) (xy 376.352562 -415.768028) (xy 375.488962 -415.768028) (xy 375.461714 -415.767499)
			(xy 375.407773 -415.759739) (xy 375.355486 -415.744381) (xy 375.305916 -415.721739) (xy 375.260073 -415.692273)
			(xy 375.218889 -415.656584) (xy 375.183204 -415.615397) (xy 375.153743 -415.569551) (xy 375.131106 -415.519978)
			(xy 375.115753 -415.46769) (xy 375.107998 -415.413748) (xy 373.670342 -415.413748) (xy 373.670342 -415.413752)
			(xy 373.662586 -415.4677) (xy 373.647231 -415.519996) (xy 373.62459 -415.569574) (xy 373.595125 -415.615426)
			(xy 373.559434 -415.656618) (xy 373.518244 -415.692311) (xy 373.472394 -415.72178) (xy 373.422817 -415.744423)
			(xy 373.370522 -415.759781) (xy 373.316574 -415.767541) (xy 373.289322 -415.768028) (xy 372.425722 -415.768028)
			(xy 372.39847 -415.767526) (xy 372.344519 -415.759772) (xy 372.292221 -415.744419) (xy 372.242641 -415.721779)
			(xy 372.196788 -415.692313) (xy 372.155594 -415.656621) (xy 372.1199 -415.61543) (xy 372.090432 -415.569578)
			(xy 372.067789 -415.519999) (xy 372.052432 -415.467702) (xy 372.044675 -415.413752) (xy 352.518742 -415.413752)
			(xy 352.510986 -415.4677) (xy 352.495631 -415.519995) (xy 352.472991 -415.569573) (xy 352.443526 -415.615425)
			(xy 352.407835 -415.656617) (xy 352.366646 -415.69231) (xy 352.320796 -415.721778) (xy 352.27122 -415.744422)
			(xy 352.218925 -415.75978) (xy 352.164977 -415.76754) (xy 352.137726 -415.768028) (xy 351.274126 -415.768028)
			(xy 351.246873 -415.767526) (xy 351.192922 -415.759773) (xy 351.140624 -415.74442) (xy 351.091043 -415.72178)
			(xy 351.045189 -415.692314) (xy 351.003996 -415.656623) (xy 350.968301 -415.615431) (xy 350.938832 -415.569579)
			(xy 350.916189 -415.52) (xy 350.900833 -415.467703) (xy 350.893075 -415.413753) (xy 349.455565 -415.413753)
			(xy 349.455565 -415.413755) (xy 349.447807 -415.46771) (xy 349.43245 -415.520012) (xy 349.409805 -415.569595)
			(xy 349.380334 -415.615452) (xy 349.344637 -415.656647) (xy 349.303441 -415.692343) (xy 349.257583 -415.721812)
			(xy 349.207999 -415.744455) (xy 349.155696 -415.75981) (xy 349.101741 -415.767566) (xy 349.074486 -415.768028)
			(xy 348.210886 -415.768028) (xy 348.183637 -415.767501) (xy 348.129694 -415.759743) (xy 348.077403 -415.744388)
			(xy 348.02783 -415.721747) (xy 347.981984 -415.692282) (xy 347.940798 -415.656592) (xy 347.90511 -415.615404)
			(xy 347.875646 -415.569557) (xy 347.853008 -415.519984) (xy 347.837654 -415.467693) (xy 347.829898 -415.413749)
			(xy 346.392242 -415.413749) (xy 346.392242 -415.413751) (xy 346.384487 -415.467697) (xy 346.369133 -415.519991)
			(xy 346.346494 -415.569568) (xy 346.31703 -415.615418) (xy 346.281342 -415.656609) (xy 346.240155 -415.692303)
			(xy 346.194308 -415.721772) (xy 346.144734 -415.744417) (xy 346.092442 -415.759777) (xy 346.038497 -415.767539)
			(xy 346.011246 -415.768028) (xy 345.147646 -415.768028) (xy 345.120392 -415.767528) (xy 345.066439 -415.759777)
			(xy 345.014139 -415.744425) (xy 344.964555 -415.721787) (xy 344.918699 -415.692321) (xy 344.877503 -415.65663)
			(xy 344.841806 -415.615438) (xy 344.812335 -415.569585) (xy 344.789691 -415.520004) (xy 344.774333 -415.467706)
			(xy 344.766575 -415.413754) (xy 343.329042 -415.413754) (xy 343.321285 -415.467702) (xy 343.30593 -415.519999)
			(xy 343.283288 -415.569579) (xy 343.253821 -415.615431) (xy 343.218128 -415.656624) (xy 343.176936 -415.692317)
			(xy 343.131084 -415.721785) (xy 343.081505 -415.744428) (xy 343.029208 -415.759784) (xy 342.975258 -415.767542)
			(xy 342.948006 -415.768028) (xy 342.084406 -415.768028) (xy 342.057154 -415.767525) (xy 342.003206 -415.759769)
			(xy 341.95091 -415.744415) (xy 341.901331 -415.721774) (xy 341.85548 -415.692307) (xy 341.814289 -415.656616)
			(xy 341.778596 -415.615425) (xy 341.749129 -415.569574) (xy 341.726488 -415.519996) (xy 341.711132 -415.4677)
			(xy 341.703375 -415.413752) (xy 340.265865 -415.413752) (xy 340.265865 -415.413756) (xy 340.258107 -415.467713)
			(xy 340.242748 -415.520016) (xy 340.220102 -415.569601) (xy 340.190629 -415.615458) (xy 340.15493 -415.656654)
			(xy 340.113731 -415.69235) (xy 340.067871 -415.721818) (xy 340.018284 -415.74446) (xy 339.965979 -415.759814)
			(xy 339.912022 -415.767567) (xy 339.884766 -415.768028) (xy 339.021166 -415.768028) (xy 338.993918 -415.767499)
			(xy 338.939977 -415.759739) (xy 338.887689 -415.744382) (xy 338.838118 -415.72174) (xy 338.792275 -415.692275)
			(xy 338.751091 -415.656585) (xy 338.715405 -415.615398) (xy 338.685943 -415.569552) (xy 338.663306 -415.519979)
			(xy 338.647953 -415.46769) (xy 338.640198 -415.413748) (xy 337.202542 -415.413748) (xy 337.202542 -415.413751)
			(xy 337.194786 -415.4677) (xy 337.179431 -415.519995) (xy 337.156791 -415.569573) (xy 337.127326 -415.615425)
			(xy 337.091635 -415.656617) (xy 337.050446 -415.69231) (xy 337.004596 -415.721778) (xy 336.95502 -415.744422)
			(xy 336.902725 -415.75978) (xy 336.848777 -415.76754) (xy 336.821526 -415.768028) (xy 335.957926 -415.768028)
			(xy 335.930673 -415.767526) (xy 335.876722 -415.759773) (xy 335.824424 -415.74442) (xy 335.774843 -415.72178)
			(xy 335.728989 -415.692314) (xy 335.687796 -415.656623) (xy 335.652101 -415.615431) (xy 335.622632 -415.569579)
			(xy 335.599989 -415.52) (xy 335.584633 -415.467703) (xy 335.576875 -415.413753) (xy 334.139365 -415.413753)
			(xy 334.139365 -415.413755) (xy 334.131607 -415.46771) (xy 334.11625 -415.520012) (xy 334.093605 -415.569595)
			(xy 334.064134 -415.615452) (xy 334.028437 -415.656647) (xy 333.987241 -415.692343) (xy 333.941383 -415.721812)
			(xy 333.891799 -415.744455) (xy 333.839496 -415.75981) (xy 333.785541 -415.767566) (xy 333.758286 -415.768028)
			(xy 332.894686 -415.768028) (xy 332.867437 -415.767501) (xy 332.813494 -415.759743) (xy 332.761203 -415.744388)
			(xy 332.71163 -415.721747) (xy 332.665784 -415.692282) (xy 332.624598 -415.656592) (xy 332.58891 -415.615404)
			(xy 332.559446 -415.569557) (xy 332.536808 -415.519984) (xy 332.521454 -415.467693) (xy 332.513698 -415.413749)
			(xy 331.076042 -415.413749) (xy 331.076042 -415.413751) (xy 331.068287 -415.467697) (xy 331.052933 -415.519991)
			(xy 331.030294 -415.569568) (xy 331.00083 -415.615418) (xy 330.965142 -415.656609) (xy 330.923955 -415.692303)
			(xy 330.878108 -415.721772) (xy 330.828534 -415.744417) (xy 330.776242 -415.759777) (xy 330.722297 -415.767539)
			(xy 330.695046 -415.768028) (xy 329.831446 -415.768028) (xy 329.804192 -415.767528) (xy 329.750239 -415.759777)
			(xy 329.697939 -415.744425) (xy 329.648355 -415.721787) (xy 329.602499 -415.692321) (xy 329.561303 -415.65663)
			(xy 329.525606 -415.615438) (xy 329.496135 -415.569585) (xy 329.473491 -415.520004) (xy 329.458133 -415.467706)
			(xy 329.450375 -415.413754) (xy 328.012842 -415.413754) (xy 328.005085 -415.467702) (xy 327.98973 -415.519999)
			(xy 327.967088 -415.569579) (xy 327.937621 -415.615431) (xy 327.901928 -415.656624) (xy 327.860736 -415.692317)
			(xy 327.814884 -415.721785) (xy 327.765305 -415.744428) (xy 327.713008 -415.759784) (xy 327.659058 -415.767542)
			(xy 327.631806 -415.768028) (xy 326.768206 -415.768028) (xy 326.740954 -415.767525) (xy 326.687006 -415.759769)
			(xy 326.63471 -415.744415) (xy 326.585131 -415.721774) (xy 326.53928 -415.692307) (xy 326.498089 -415.656616)
			(xy 326.462396 -415.615425) (xy 326.432929 -415.569574) (xy 326.410288 -415.519996) (xy 326.394932 -415.4677)
			(xy 326.387175 -415.413752) (xy 324.949665 -415.413752) (xy 324.949665 -415.413756) (xy 324.941907 -415.467713)
			(xy 324.926548 -415.520016) (xy 324.903902 -415.569601) (xy 324.874429 -415.615458) (xy 324.83873 -415.656654)
			(xy 324.797531 -415.69235) (xy 324.751671 -415.721818) (xy 324.702084 -415.74446) (xy 324.649779 -415.759814)
			(xy 324.595822 -415.767567) (xy 324.568566 -415.768028) (xy 323.704966 -415.768028) (xy 323.677718 -415.767499)
			(xy 323.623777 -415.759739) (xy 323.571489 -415.744382) (xy 323.521918 -415.72174) (xy 323.476075 -415.692275)
			(xy 323.434891 -415.656585) (xy 323.399205 -415.615398) (xy 323.369743 -415.569552) (xy 323.347106 -415.519979)
			(xy 323.331753 -415.46769) (xy 323.323998 -415.413748) (xy 321.886342 -415.413748) (xy 321.886342 -415.413751)
			(xy 321.878586 -415.4677) (xy 321.863231 -415.519995) (xy 321.840591 -415.569573) (xy 321.811126 -415.615425)
			(xy 321.775435 -415.656617) (xy 321.734246 -415.69231) (xy 321.688396 -415.721778) (xy 321.63882 -415.744422)
			(xy 321.586525 -415.75978) (xy 321.532577 -415.76754) (xy 321.505326 -415.768028) (xy 320.641726 -415.768028)
			(xy 320.614473 -415.767526) (xy 320.560522 -415.759773) (xy 320.508224 -415.74442) (xy 320.458643 -415.72178)
			(xy 320.412789 -415.692314) (xy 320.371596 -415.656623) (xy 320.335901 -415.615431) (xy 320.306432 -415.569579)
			(xy 320.283789 -415.52) (xy 320.268433 -415.467703) (xy 320.260675 -415.413753) (xy 318.823165 -415.413753)
			(xy 318.823165 -415.413755) (xy 318.815407 -415.46771) (xy 318.80005 -415.520012) (xy 318.777405 -415.569595)
			(xy 318.747934 -415.615452) (xy 318.712237 -415.656647) (xy 318.671041 -415.692343) (xy 318.625183 -415.721812)
			(xy 318.575599 -415.744455) (xy 318.523296 -415.75981) (xy 318.469341 -415.767566) (xy 318.442086 -415.768028)
			(xy 317.578486 -415.768028) (xy 317.551237 -415.767501) (xy 317.497294 -415.759743) (xy 317.445003 -415.744388)
			(xy 317.39543 -415.721747) (xy 317.349584 -415.692282) (xy 317.308398 -415.656592) (xy 317.27271 -415.615404)
			(xy 317.243246 -415.569557) (xy 317.220608 -415.519984) (xy 317.205254 -415.467693) (xy 317.197498 -415.413749)
			(xy 315.759842 -415.413749) (xy 315.759842 -415.413751) (xy 315.752087 -415.467697) (xy 315.736733 -415.519991)
			(xy 315.714094 -415.569568) (xy 315.68463 -415.615418) (xy 315.648942 -415.656609) (xy 315.607755 -415.692303)
			(xy 315.561908 -415.721772) (xy 315.512334 -415.744417) (xy 315.460042 -415.759777) (xy 315.406097 -415.767539)
			(xy 315.378846 -415.768028) (xy 314.515246 -415.768028) (xy 314.487992 -415.767528) (xy 314.434039 -415.759777)
			(xy 314.381739 -415.744425) (xy 314.332155 -415.721787) (xy 314.286299 -415.692321) (xy 314.245103 -415.65663)
			(xy 314.209406 -415.615438) (xy 314.179935 -415.569585) (xy 314.157291 -415.520004) (xy 314.141933 -415.467706)
			(xy 314.134175 -415.413754) (xy 312.696642 -415.413754) (xy 312.688885 -415.467702) (xy 312.67353 -415.519999)
			(xy 312.650888 -415.569579) (xy 312.621421 -415.615431) (xy 312.585728 -415.656624) (xy 312.544536 -415.692317)
			(xy 312.498684 -415.721785) (xy 312.449105 -415.744428) (xy 312.396808 -415.759784) (xy 312.342858 -415.767542)
			(xy 312.315606 -415.768028) (xy 311.452006 -415.768028) (xy 311.424754 -415.767525) (xy 311.370806 -415.759769)
			(xy 311.31851 -415.744415) (xy 311.268931 -415.721774) (xy 311.22308 -415.692307) (xy 311.181889 -415.656616)
			(xy 311.146196 -415.615425) (xy 311.116729 -415.569574) (xy 311.094088 -415.519996) (xy 311.078732 -415.4677)
			(xy 311.070975 -415.413752) (xy 309.633465 -415.413752) (xy 309.633465 -415.413756) (xy 309.625707 -415.467713)
			(xy 309.610348 -415.520016) (xy 309.587702 -415.569601) (xy 309.558229 -415.615458) (xy 309.52253 -415.656654)
			(xy 309.481331 -415.69235) (xy 309.435471 -415.721818) (xy 309.385884 -415.74446) (xy 309.333579 -415.759814)
			(xy 309.279622 -415.767567) (xy 309.252366 -415.768028) (xy 308.388766 -415.768028) (xy 308.361518 -415.767499)
			(xy 308.307577 -415.759739) (xy 308.255289 -415.744382) (xy 308.205718 -415.72174) (xy 308.159875 -415.692275)
			(xy 308.118691 -415.656585) (xy 308.083005 -415.615398) (xy 308.053543 -415.569552) (xy 308.030906 -415.519979)
			(xy 308.015553 -415.46769) (xy 308.007798 -415.413748) (xy 306.570142 -415.413748) (xy 306.570142 -415.413751)
			(xy 306.562386 -415.4677) (xy 306.547031 -415.519995) (xy 306.524391 -415.569573) (xy 306.494926 -415.615425)
			(xy 306.459235 -415.656617) (xy 306.418046 -415.69231) (xy 306.372196 -415.721778) (xy 306.32262 -415.744422)
			(xy 306.270325 -415.75978) (xy 306.216377 -415.76754) (xy 306.189126 -415.768028) (xy 305.325526 -415.768028)
			(xy 305.298273 -415.767526) (xy 305.244322 -415.759773) (xy 305.192024 -415.74442) (xy 305.142443 -415.72178)
			(xy 305.096589 -415.692314) (xy 305.055396 -415.656623) (xy 305.019701 -415.615431) (xy 304.990232 -415.569579)
			(xy 304.967589 -415.52) (xy 304.952233 -415.467703) (xy 304.944475 -415.413753) (xy 300.882586 -415.413753)
			(xy 300.868941 -415.434612) (xy 300.76479 -415.579315) (xy 300.654297 -415.719235) (xy 300.53768 -415.854094)
			(xy 300.415171 -415.983624) (xy 300.287014 -416.107568) (xy 300.153463 -416.22568) (xy 300.014783 -416.337725)
			(xy 299.871249 -416.443482) (xy 299.723146 -416.542739) (xy 299.570769 -416.635301) (xy 299.41442 -416.720982)
			(xy 299.254409 -416.799614) (xy 299.091055 -416.87104) (xy 298.92468 -416.935118) (xy 298.755617 -416.99172)
			(xy 298.5842 -417.040736) (xy 298.410769 -417.082066) (xy 298.235669 -417.11563) (xy 298.059249 -417.14136)
			(xy 297.881857 -417.159206) (xy 297.703846 -417.169132) (xy 297.525569 -417.171118) (xy 297.347382 -417.165161)
			(xy 297.169636 -417.151271) (xy 296.992686 -417.129478) (xy 296.816882 -417.099824) (xy 296.642574 -417.062367)
			(xy 296.470107 -417.017183) (xy 296.299824 -416.964361) (xy 296.132063 -416.904005) (xy 295.967158 -416.836237)
			(xy 295.805435 -416.761189) (xy 295.647216 -416.679012) (xy 295.492815 -416.589869) (xy 295.342538 -416.493935)
			(xy 295.196683 -416.391403) (xy 295.055541 -416.282475) (xy 294.919392 -416.167368) (xy 294.788505 -416.04631)
			(xy 294.663141 -415.919541) (xy 294.543548 -415.787314) (xy 294.429965 -415.649891) (xy 294.322616 -415.507544)
			(xy 294.221715 -415.360556) (xy 294.127462 -415.20922) (xy 294.040044 -415.053835) (xy 293.959634 -414.89471)
			(xy 293.886393 -414.732161) (xy 293.820466 -414.566511) (xy 293.761983 -414.398089) (xy 293.711061 -414.227228)
			(xy 293.667801 -414.054269) (xy 293.632289 -413.879554) (xy 293.604595 -413.70343) (xy 293.584774 -413.526248)
			(xy 293.572866 -413.348359) (xy 293.568894 -413.170116) (xy 276.749256 -413.170116) (xy 272.414746 -417.504626)
			(xy 272.396783 -417.521953) (xy 272.356401 -417.55128) (xy 272.311928 -417.573928) (xy 272.264459 -417.589339)
			(xy 272.215164 -417.597133) (xy 272.19021 -417.59759) (xy 235.05033 -417.59759) (xy 235.040259 -417.598007)
			(xy 235.02166 -417.605731) (xy 235.014262 -417.612576) (xy 233.545126 -419.081712) (xy 276.721824 -419.081712)
			(xy 276.721824 -418.218112) (xy 276.72231 -418.190861) (xy 276.730066 -418.136913) (xy 276.745421 -418.084618)
			(xy 276.768063 -418.035041) (xy 276.797529 -417.989191) (xy 276.83322 -417.948) (xy 276.874411 -417.912309)
			(xy 276.920261 -417.882843) (xy 276.969838 -417.860201) (xy 277.022133 -417.844846) (xy 277.076081 -417.83709)
			(xy 277.130583 -417.83709) (xy 277.184531 -417.844846) (xy 277.236826 -417.860201) (xy 277.286403 -417.882843)
			(xy 277.332253 -417.912309) (xy 277.373444 -417.948) (xy 277.409135 -417.989191) (xy 277.438601 -418.035041)
			(xy 277.461243 -418.084618) (xy 277.476598 -418.136913) (xy 277.484354 -418.190861) (xy 277.48484 -418.218112)
			(xy 277.48484 -418.254688) (xy 289.453828 -418.254688) (xy 289.453828 -417.391088) (xy 289.454314 -417.363837)
			(xy 289.46207 -417.309889) (xy 289.477425 -417.257594) (xy 289.500067 -417.208017) (xy 289.529533 -417.162167)
			(xy 289.565224 -417.120976) (xy 289.606415 -417.085285) (xy 289.652265 -417.055819) (xy 289.701842 -417.033177)
			(xy 289.754137 -417.017822) (xy 289.808085 -417.010066) (xy 289.862587 -417.010066) (xy 289.916535 -417.017822)
			(xy 289.96883 -417.033177) (xy 290.018407 -417.055819) (xy 290.064257 -417.085285) (xy 290.105448 -417.120976)
			(xy 290.141139 -417.162167) (xy 290.170605 -417.208017) (xy 290.186237 -417.242244) (xy 305.107848 -417.242244)
			(xy 305.107848 -416.556444) (xy 305.108401 -416.544376) (xy 305.115846 -416.521418) (xy 305.130021 -416.501884)
			(xy 305.149539 -416.487686) (xy 305.172489 -416.480215) (xy 305.184556 -416.479736) (xy 305.37912 -416.479736)
			(xy 305.390224 -416.480126) (xy 305.411516 -416.486443) (xy 305.42103 -416.492182) (xy 305.714654 -416.684714)
			(xy 305.724049 -416.690397) (xy 305.745056 -416.696736) (xy 305.766999 -416.696816) (xy 305.788052 -416.690629)
			(xy 305.797458 -416.684968) (xy 306.093622 -416.492182) (xy 306.10314 -416.486448) (xy 306.124427 -416.480114)
			(xy 306.135532 -416.479736) (xy 306.330096 -416.479736) (xy 306.342183 -416.480116) (xy 306.365173 -416.487588)
			(xy 306.384727 -416.501801) (xy 306.39893 -416.521363) (xy 306.40639 -416.544357) (xy 306.406804 -416.556444)
			(xy 306.406804 -417.242244) (xy 308.171088 -417.242244) (xy 308.171088 -416.556444) (xy 308.17155 -416.544364)
			(xy 308.179005 -416.521383) (xy 308.193199 -416.501833) (xy 308.21274 -416.487627) (xy 308.235716 -416.480158)
			(xy 308.247796 -416.479736) (xy 308.44236 -416.479736) (xy 308.453465 -416.48011) (xy 308.474757 -416.486438)
			(xy 308.48427 -416.492182) (xy 308.777894 -416.684714) (xy 308.78727 -416.690431) (xy 308.808286 -416.696763)
			(xy 308.830236 -416.696833) (xy 308.851292 -416.690635) (xy 308.860698 -416.684968) (xy 309.156862 -416.492182)
			(xy 309.166372 -416.486433) (xy 309.187666 -416.480108) (xy 309.198772 -416.479736) (xy 309.393336 -416.479736)
			(xy 309.405425 -416.480083) (xy 309.428416 -416.487565) (xy 309.44797 -416.501787) (xy 309.462171 -416.521355)
			(xy 309.46963 -416.544355) (xy 309.470044 -416.556444) (xy 309.470044 -417.242244) (xy 311.234328 -417.242244)
			(xy 311.234328 -416.556444) (xy 311.234751 -416.54436) (xy 311.24221 -416.521373) (xy 311.256413 -416.501818)
			(xy 311.275965 -416.487614) (xy 311.298952 -416.480152) (xy 311.311036 -416.479736) (xy 311.5056 -416.479736)
			(xy 311.516703 -416.480135) (xy 311.537995 -416.486446) (xy 311.54751 -416.492182) (xy 311.841134 -416.684714)
			(xy 311.850491 -416.690465) (xy 311.871516 -416.69679) (xy 311.893472 -416.69685) (xy 311.914532 -416.69064)
			(xy 311.923938 -416.684968) (xy 312.220102 -416.492182) (xy 312.229604 -416.486418) (xy 312.250904 -416.480103)
			(xy 312.262012 -416.479736) (xy 312.456576 -416.479736) (xy 312.468662 -416.480134) (xy 312.491651 -416.4876)
			(xy 312.511206 -416.501809) (xy 312.525409 -416.521367) (xy 312.532869 -416.544358) (xy 312.533284 -416.556444)
			(xy 312.533284 -417.242244) (xy 314.297568 -417.242244) (xy 314.297568 -416.556444) (xy 314.29805 -416.544366)
			(xy 314.305502 -416.521389) (xy 314.319691 -416.50184) (xy 314.339228 -416.487633) (xy 314.362198 -416.48016)
			(xy 314.374276 -416.479736) (xy 314.56884 -416.479736) (xy 314.579945 -416.480118) (xy 314.601237 -416.486441)
			(xy 314.61075 -416.492182) (xy 314.904374 -416.684714) (xy 314.913759 -416.690414) (xy 314.934771 -416.69675)
			(xy 314.956718 -416.696825) (xy 314.977772 -416.690632) (xy 314.987178 -416.684968) (xy 315.283342 -416.492182)
			(xy 315.292856 -416.48644) (xy 315.314147 -416.480111) (xy 315.325252 -416.479736) (xy 315.519816 -416.479736)
			(xy 315.531904 -416.4801) (xy 315.554895 -416.487577) (xy 315.574449 -416.501794) (xy 315.588651 -416.521359)
			(xy 315.59611 -416.544356) (xy 315.596524 -416.556444) (xy 315.596524 -417.242244) (xy 317.360808 -417.242244)
			(xy 317.360808 -416.556444) (xy 317.36125 -416.544362) (xy 317.368708 -416.521378) (xy 317.382906 -416.501826)
			(xy 317.402453 -416.487621) (xy 317.425434 -416.480155) (xy 317.437516 -416.479736) (xy 317.63208 -416.479736)
			(xy 317.643186 -416.480103) (xy 317.664478 -416.486436) (xy 317.67399 -416.492182) (xy 317.967614 -416.684714)
			(xy 317.97698 -416.690448) (xy 317.998001 -416.696777) (xy 318.019954 -416.696842) (xy 318.041012 -416.690638)
			(xy 318.050418 -416.684968) (xy 318.346582 -416.492182) (xy 318.356088 -416.486426) (xy 318.377385 -416.480105)
			(xy 318.388492 -416.479736) (xy 318.583056 -416.479736) (xy 318.595141 -416.480151) (xy 318.61813 -416.487612)
			(xy 318.637684 -416.501816) (xy 318.651888 -416.52137) (xy 318.659349 -416.544359) (xy 318.659764 -416.556444)
			(xy 318.659764 -417.242244) (xy 320.424048 -417.242244) (xy 320.424048 -416.556444) (xy 320.424601 -416.544376)
			(xy 320.432046 -416.521418) (xy 320.446221 -416.501884) (xy 320.465739 -416.487686) (xy 320.488689 -416.480215)
			(xy 320.500756 -416.479736) (xy 320.69532 -416.479736) (xy 320.706424 -416.480126) (xy 320.727716 -416.486443)
			(xy 320.73723 -416.492182) (xy 321.030854 -416.684714) (xy 321.040249 -416.690397) (xy 321.061256 -416.696736)
			(xy 321.083199 -416.696816) (xy 321.104252 -416.690629) (xy 321.113658 -416.684968) (xy 321.409822 -416.492182)
			(xy 321.41934 -416.486448) (xy 321.440627 -416.480114) (xy 321.451732 -416.479736) (xy 321.646296 -416.479736)
			(xy 321.658383 -416.480116) (xy 321.681373 -416.487588) (xy 321.700927 -416.501801) (xy 321.71513 -416.521363)
			(xy 321.72259 -416.544357) (xy 321.723004 -416.556444) (xy 321.723004 -417.242244) (xy 323.487288 -417.242244)
			(xy 323.487288 -416.556444) (xy 323.48775 -416.544364) (xy 323.495205 -416.521383) (xy 323.509399 -416.501833)
			(xy 323.52894 -416.487627) (xy 323.551916 -416.480158) (xy 323.563996 -416.479736) (xy 323.75856 -416.479736)
			(xy 323.769665 -416.48011) (xy 323.790957 -416.486438) (xy 323.80047 -416.492182) (xy 324.094094 -416.684714)
			(xy 324.10347 -416.690431) (xy 324.124486 -416.696763) (xy 324.146436 -416.696833) (xy 324.167492 -416.690635)
			(xy 324.176898 -416.684968) (xy 324.473062 -416.492182) (xy 324.482572 -416.486433) (xy 324.503866 -416.480108)
			(xy 324.514972 -416.479736) (xy 324.709536 -416.479736) (xy 324.721625 -416.480083) (xy 324.744616 -416.487565)
			(xy 324.76417 -416.501787) (xy 324.778371 -416.521355) (xy 324.78583 -416.544355) (xy 324.786244 -416.556444)
			(xy 324.786244 -417.242244) (xy 326.550528 -417.242244) (xy 326.550528 -416.556444) (xy 326.550951 -416.54436)
			(xy 326.55841 -416.521373) (xy 326.572613 -416.501818) (xy 326.592165 -416.487614) (xy 326.615152 -416.480152)
			(xy 326.627236 -416.479736) (xy 326.8218 -416.479736) (xy 326.832903 -416.480135) (xy 326.854195 -416.486446)
			(xy 326.86371 -416.492182) (xy 327.157334 -416.684714) (xy 327.166691 -416.690465) (xy 327.187716 -416.69679)
			(xy 327.209672 -416.69685) (xy 327.230732 -416.69064) (xy 327.240138 -416.684968) (xy 327.536302 -416.492182)
			(xy 327.545804 -416.486418) (xy 327.567104 -416.480103) (xy 327.578212 -416.479736) (xy 327.772776 -416.479736)
			(xy 327.784862 -416.480134) (xy 327.807851 -416.4876) (xy 327.827406 -416.501809) (xy 327.841609 -416.521367)
			(xy 327.849069 -416.544358) (xy 327.849484 -416.556444) (xy 327.849484 -417.242244) (xy 329.613768 -417.242244)
			(xy 329.613768 -416.556444) (xy 329.61425 -416.544366) (xy 329.621702 -416.521389) (xy 329.635891 -416.50184)
			(xy 329.655428 -416.487633) (xy 329.678398 -416.48016) (xy 329.690476 -416.479736) (xy 329.88504 -416.479736)
			(xy 329.896145 -416.480118) (xy 329.917437 -416.486441) (xy 329.92695 -416.492182) (xy 330.220574 -416.684714)
			(xy 330.229959 -416.690414) (xy 330.250971 -416.69675) (xy 330.272918 -416.696825) (xy 330.293972 -416.690632)
			(xy 330.303378 -416.684968) (xy 330.599542 -416.492182) (xy 330.609056 -416.48644) (xy 330.630347 -416.480111)
			(xy 330.641452 -416.479736) (xy 330.836016 -416.479736) (xy 330.848104 -416.4801) (xy 330.871095 -416.487577)
			(xy 330.890649 -416.501794) (xy 330.904851 -416.521359) (xy 330.91231 -416.544356) (xy 330.912724 -416.556444)
			(xy 330.912724 -417.242244) (xy 332.677008 -417.242244) (xy 332.677008 -416.556444) (xy 332.67745 -416.544362)
			(xy 332.684908 -416.521378) (xy 332.699106 -416.501826) (xy 332.718653 -416.487621) (xy 332.741634 -416.480155)
			(xy 332.753716 -416.479736) (xy 332.94828 -416.479736) (xy 332.959386 -416.480103) (xy 332.980678 -416.486436)
			(xy 332.99019 -416.492182) (xy 333.283814 -416.684714) (xy 333.29318 -416.690448) (xy 333.314201 -416.696777)
			(xy 333.336154 -416.696842) (xy 333.357212 -416.690638) (xy 333.366618 -416.684968) (xy 333.662782 -416.492182)
			(xy 333.672288 -416.486426) (xy 333.693585 -416.480105) (xy 333.704692 -416.479736) (xy 333.899256 -416.479736)
			(xy 333.911341 -416.480151) (xy 333.93433 -416.487612) (xy 333.953884 -416.501816) (xy 333.968088 -416.52137)
			(xy 333.975549 -416.544359) (xy 333.975964 -416.556444) (xy 333.975964 -417.242244) (xy 335.740248 -417.242244)
			(xy 335.740248 -416.556444) (xy 335.740801 -416.544376) (xy 335.748246 -416.521418) (xy 335.762421 -416.501884)
			(xy 335.781939 -416.487686) (xy 335.804889 -416.480215) (xy 335.816956 -416.479736) (xy 336.01152 -416.479736)
			(xy 336.022624 -416.480126) (xy 336.043916 -416.486443) (xy 336.05343 -416.492182) (xy 336.347054 -416.684714)
			(xy 336.356449 -416.690397) (xy 336.377456 -416.696736) (xy 336.399399 -416.696816) (xy 336.420452 -416.690629)
			(xy 336.429858 -416.684968) (xy 336.726022 -416.492182) (xy 336.73554 -416.486448) (xy 336.756827 -416.480114)
			(xy 336.767932 -416.479736) (xy 336.962496 -416.479736) (xy 336.974583 -416.480116) (xy 336.997573 -416.487588)
			(xy 337.017127 -416.501801) (xy 337.03133 -416.521363) (xy 337.03879 -416.544357) (xy 337.039204 -416.556444)
			(xy 337.039204 -417.242244) (xy 338.803488 -417.242244) (xy 338.803488 -416.556444) (xy 338.80395 -416.544364)
			(xy 338.811405 -416.521383) (xy 338.825599 -416.501833) (xy 338.84514 -416.487627) (xy 338.868116 -416.480158)
			(xy 338.880196 -416.479736) (xy 339.07476 -416.479736) (xy 339.085865 -416.48011) (xy 339.107157 -416.486438)
			(xy 339.11667 -416.492182) (xy 339.410294 -416.684714) (xy 339.41967 -416.690431) (xy 339.440686 -416.696763)
			(xy 339.462636 -416.696833) (xy 339.483692 -416.690635) (xy 339.493098 -416.684968) (xy 339.789262 -416.492182)
			(xy 339.798772 -416.486433) (xy 339.820066 -416.480108) (xy 339.831172 -416.479736) (xy 340.025736 -416.479736)
			(xy 340.037825 -416.480083) (xy 340.060816 -416.487565) (xy 340.08037 -416.501787) (xy 340.094571 -416.521355)
			(xy 340.10203 -416.544355) (xy 340.102444 -416.556444) (xy 340.102444 -417.242244) (xy 341.866728 -417.242244)
			(xy 341.866728 -416.556444) (xy 341.867151 -416.54436) (xy 341.87461 -416.521373) (xy 341.888813 -416.501818)
			(xy 341.908365 -416.487614) (xy 341.931352 -416.480152) (xy 341.943436 -416.479736) (xy 342.138 -416.479736)
			(xy 342.149103 -416.480135) (xy 342.170395 -416.486446) (xy 342.17991 -416.492182) (xy 342.473534 -416.684714)
			(xy 342.482891 -416.690465) (xy 342.503916 -416.69679) (xy 342.525872 -416.69685) (xy 342.546932 -416.69064)
			(xy 342.556338 -416.684968) (xy 342.852502 -416.492182) (xy 342.862004 -416.486418) (xy 342.883304 -416.480103)
			(xy 342.894412 -416.479736) (xy 343.088976 -416.479736) (xy 343.101062 -416.480134) (xy 343.124051 -416.4876)
			(xy 343.143606 -416.501809) (xy 343.157809 -416.521367) (xy 343.165269 -416.544358) (xy 343.165684 -416.556444)
			(xy 343.165684 -417.242244) (xy 344.929968 -417.242244) (xy 344.929968 -416.556444) (xy 344.93045 -416.544366)
			(xy 344.937902 -416.521389) (xy 344.952091 -416.50184) (xy 344.971628 -416.487633) (xy 344.994598 -416.48016)
			(xy 345.006676 -416.479736) (xy 345.20124 -416.479736) (xy 345.212345 -416.480118) (xy 345.233637 -416.486441)
			(xy 345.24315 -416.492182) (xy 345.536774 -416.684714) (xy 345.546159 -416.690414) (xy 345.567171 -416.69675)
			(xy 345.589118 -416.696825) (xy 345.610172 -416.690632) (xy 345.619578 -416.684968) (xy 345.915742 -416.492182)
			(xy 345.925256 -416.48644) (xy 345.946547 -416.480111) (xy 345.957652 -416.479736) (xy 346.152216 -416.479736)
			(xy 346.164304 -416.4801) (xy 346.187295 -416.487577) (xy 346.206849 -416.501794) (xy 346.221051 -416.521359)
			(xy 346.22851 -416.544356) (xy 346.228924 -416.556444) (xy 346.228924 -417.242244) (xy 347.993208 -417.242244)
			(xy 347.993208 -416.556444) (xy 347.99365 -416.544362) (xy 348.001108 -416.521378) (xy 348.015306 -416.501826)
			(xy 348.034853 -416.487621) (xy 348.057834 -416.480155) (xy 348.069916 -416.479736) (xy 348.26448 -416.479736)
			(xy 348.275586 -416.480103) (xy 348.296878 -416.486436) (xy 348.30639 -416.492182) (xy 348.600014 -416.684714)
			(xy 348.60938 -416.690448) (xy 348.630401 -416.696777) (xy 348.652354 -416.696842) (xy 348.673412 -416.690638)
			(xy 348.682818 -416.684968) (xy 348.978982 -416.492182) (xy 348.988488 -416.486426) (xy 349.009785 -416.480105)
			(xy 349.020892 -416.479736) (xy 349.215456 -416.479736) (xy 349.227541 -416.480151) (xy 349.25053 -416.487612)
			(xy 349.270084 -416.501816) (xy 349.284288 -416.52137) (xy 349.291749 -416.544359) (xy 349.292164 -416.556444)
			(xy 349.292164 -417.242244) (xy 351.056448 -417.242244) (xy 351.056448 -416.556444) (xy 351.057001 -416.544376)
			(xy 351.064446 -416.521418) (xy 351.078621 -416.501884) (xy 351.098139 -416.487686) (xy 351.121089 -416.480215)
			(xy 351.133156 -416.479736) (xy 351.32772 -416.479736) (xy 351.338824 -416.480126) (xy 351.360116 -416.486443)
			(xy 351.36963 -416.492182) (xy 351.663254 -416.684714) (xy 351.672649 -416.690397) (xy 351.693656 -416.696736)
			(xy 351.715599 -416.696816) (xy 351.736652 -416.690629) (xy 351.746058 -416.684968) (xy 352.042222 -416.492182)
			(xy 352.05174 -416.486448) (xy 352.073027 -416.480114) (xy 352.084132 -416.479736) (xy 352.278696 -416.479736)
			(xy 352.290783 -416.480116) (xy 352.313773 -416.487588) (xy 352.333327 -416.501801) (xy 352.34753 -416.521363)
			(xy 352.35499 -416.544357) (xy 352.355404 -416.556444) (xy 352.355404 -417.242244) (xy 352.354973 -417.254321)
			(xy 352.347498 -417.277291) (xy 352.333293 -417.296827) (xy 352.313748 -417.31102) (xy 352.290774 -417.318481)
			(xy 352.278696 -417.318952) (xy 352.084132 -417.318952) (xy 352.073023 -417.318604) (xy 352.051727 -417.312269)
			(xy 352.042222 -417.306506) (xy 351.747328 -417.113974) (xy 351.737941 -417.108271) (xy 351.716903 -417.101998)
			(xy 351.694949 -417.101998) (xy 351.673911 -417.108271) (xy 351.664524 -417.113974) (xy 351.3709 -417.306506)
			(xy 351.361397 -417.312268) (xy 351.340098 -417.318585) (xy 351.32899 -417.318952) (xy 351.133156 -417.318952)
			(xy 351.121084 -417.318474) (xy 351.098122 -417.311005) (xy 351.07859 -417.29681) (xy 351.064395 -417.277278)
			(xy 351.056926 -417.254316) (xy 351.056448 -417.242244) (xy 349.292164 -417.242244) (xy 349.291773 -417.254325)
			(xy 349.284293 -417.277301) (xy 349.270079 -417.296842) (xy 349.250522 -417.311033) (xy 349.227538 -417.318487)
			(xy 349.215456 -417.318952) (xy 349.020892 -417.318952) (xy 349.009785 -417.31858) (xy 348.988488 -417.312262)
			(xy 348.978982 -417.306506) (xy 348.684088 -417.113974) (xy 348.674701 -417.108271) (xy 348.653663 -417.101998)
			(xy 348.631709 -417.101998) (xy 348.610671 -417.108271) (xy 348.601284 -417.113974) (xy 348.30766 -417.306506)
			(xy 348.298145 -417.312246) (xy 348.276855 -417.318577) (xy 348.26575 -417.318952) (xy 348.069916 -417.318952)
			(xy 348.057847 -417.318423) (xy 348.034887 -417.31097) (xy 348.015354 -417.296789) (xy 348.001157 -417.277266)
			(xy 347.993687 -417.254313) (xy 347.993208 -417.242244) (xy 346.228924 -417.242244) (xy 346.228474 -417.254319)
			(xy 346.221001 -417.277285) (xy 346.2068 -417.29682) (xy 346.18726 -417.311014) (xy 346.164291 -417.318478)
			(xy 346.152216 -417.318952) (xy 345.957652 -417.318952) (xy 345.946543 -417.318596) (xy 345.925247 -417.312267)
			(xy 345.915742 -417.306506) (xy 345.620848 -417.113974) (xy 345.611461 -417.108271) (xy 345.590423 -417.101998)
			(xy 345.568469 -417.101998) (xy 345.547431 -417.108271) (xy 345.538044 -417.113974) (xy 345.24442 -417.306506)
			(xy 345.234913 -417.312261) (xy 345.213617 -417.318582) (xy 345.20251 -417.318952) (xy 345.006676 -417.318952)
			(xy 344.994605 -417.318457) (xy 344.971644 -417.310993) (xy 344.952111 -417.296803) (xy 344.937916 -417.277274)
			(xy 344.930446 -417.254315) (xy 344.929968 -417.242244) (xy 343.165684 -417.242244) (xy 343.165273 -417.254323)
			(xy 343.157796 -417.277296) (xy 343.143586 -417.296834) (xy 343.124035 -417.311027) (xy 343.101056 -417.318484)
			(xy 343.088976 -417.318952) (xy 342.894412 -417.318952) (xy 342.883305 -417.318571) (xy 342.862009 -417.312259)
			(xy 342.852502 -417.306506) (xy 342.557608 -417.113974) (xy 342.548221 -417.108271) (xy 342.527183 -417.101998)
			(xy 342.505229 -417.101998) (xy 342.484191 -417.108271) (xy 342.474804 -417.113974) (xy 342.18118 -417.306506)
			(xy 342.171661 -417.312239) (xy 342.150374 -417.318574) (xy 342.13927 -417.318952) (xy 341.943436 -417.318952)
			(xy 341.931368 -417.318406) (xy 341.908409 -417.310959) (xy 341.888875 -417.296782) (xy 341.874678 -417.277263)
			(xy 341.867207 -417.254312) (xy 341.866728 -417.242244) (xy 340.102444 -417.242244) (xy 340.101974 -417.254317)
			(xy 340.094504 -417.27728) (xy 340.080307 -417.296813) (xy 340.060773 -417.311007) (xy 340.037809 -417.318475)
			(xy 340.025736 -417.318952) (xy 339.831172 -417.318952) (xy 339.820064 -417.318588) (xy 339.798768 -417.312264)
			(xy 339.789262 -417.306506) (xy 339.494368 -417.113974) (xy 339.484981 -417.108271) (xy 339.463943 -417.101998)
			(xy 339.441989 -417.101998) (xy 339.420951 -417.108271) (xy 339.411564 -417.113974) (xy 339.11794 -417.306506)
			(xy 339.108429 -417.312253) (xy 339.087136 -417.318579) (xy 339.07603 -417.318952) (xy 338.880196 -417.318952)
			(xy 338.868126 -417.31844) (xy 338.845166 -417.310982) (xy 338.825633 -417.296796) (xy 338.811437 -417.27727)
			(xy 338.803967 -417.254314) (xy 338.803488 -417.242244) (xy 337.039204 -417.242244) (xy 337.038773 -417.254321)
			(xy 337.031298 -417.277291) (xy 337.017093 -417.296827) (xy 336.997548 -417.31102) (xy 336.974574 -417.318481)
			(xy 336.962496 -417.318952) (xy 336.767932 -417.318952) (xy 336.756823 -417.318604) (xy 336.735527 -417.312269)
			(xy 336.726022 -417.306506) (xy 336.431128 -417.113974) (xy 336.421741 -417.108271) (xy 336.400703 -417.101998)
			(xy 336.378749 -417.101998) (xy 336.357711 -417.108271) (xy 336.348324 -417.113974) (xy 336.0547 -417.306506)
			(xy 336.045197 -417.312268) (xy 336.023898 -417.318585) (xy 336.01279 -417.318952) (xy 335.816956 -417.318952)
			(xy 335.804884 -417.318474) (xy 335.781922 -417.311005) (xy 335.76239 -417.29681) (xy 335.748195 -417.277278)
			(xy 335.740726 -417.254316) (xy 335.740248 -417.242244) (xy 333.975964 -417.242244) (xy 333.975573 -417.254325)
			(xy 333.968093 -417.277301) (xy 333.953879 -417.296842) (xy 333.934322 -417.311033) (xy 333.911338 -417.318487)
			(xy 333.899256 -417.318952) (xy 333.704692 -417.318952) (xy 333.693585 -417.31858) (xy 333.672288 -417.312262)
			(xy 333.662782 -417.306506) (xy 333.367888 -417.113974) (xy 333.358501 -417.108271) (xy 333.337463 -417.101998)
			(xy 333.315509 -417.101998) (xy 333.294471 -417.108271) (xy 333.285084 -417.113974) (xy 332.99146 -417.306506)
			(xy 332.981945 -417.312246) (xy 332.960655 -417.318577) (xy 332.94955 -417.318952) (xy 332.753716 -417.318952)
			(xy 332.741647 -417.318423) (xy 332.718687 -417.31097) (xy 332.699154 -417.296789) (xy 332.684957 -417.277266)
			(xy 332.677487 -417.254313) (xy 332.677008 -417.242244) (xy 330.912724 -417.242244) (xy 330.912274 -417.254319)
			(xy 330.904801 -417.277285) (xy 330.8906 -417.29682) (xy 330.87106 -417.311014) (xy 330.848091 -417.318478)
			(xy 330.836016 -417.318952) (xy 330.641452 -417.318952) (xy 330.630343 -417.318596) (xy 330.609047 -417.312267)
			(xy 330.599542 -417.306506) (xy 330.304648 -417.113974) (xy 330.295261 -417.108271) (xy 330.274223 -417.101998)
			(xy 330.252269 -417.101998) (xy 330.231231 -417.108271) (xy 330.221844 -417.113974) (xy 329.92822 -417.306506)
			(xy 329.918713 -417.312261) (xy 329.897417 -417.318582) (xy 329.88631 -417.318952) (xy 329.690476 -417.318952)
			(xy 329.678405 -417.318457) (xy 329.655444 -417.310993) (xy 329.635911 -417.296803) (xy 329.621716 -417.277274)
			(xy 329.614246 -417.254315) (xy 329.613768 -417.242244) (xy 327.849484 -417.242244) (xy 327.849073 -417.254323)
			(xy 327.841596 -417.277296) (xy 327.827386 -417.296834) (xy 327.807835 -417.311027) (xy 327.784856 -417.318484)
			(xy 327.772776 -417.318952) (xy 327.578212 -417.318952) (xy 327.567105 -417.318571) (xy 327.545809 -417.312259)
			(xy 327.536302 -417.306506) (xy 327.241408 -417.113974) (xy 327.232021 -417.108271) (xy 327.210983 -417.101998)
			(xy 327.189029 -417.101998) (xy 327.167991 -417.108271) (xy 327.158604 -417.113974) (xy 326.86498 -417.306506)
			(xy 326.855461 -417.312239) (xy 326.834174 -417.318574) (xy 326.82307 -417.318952) (xy 326.627236 -417.318952)
			(xy 326.615168 -417.318406) (xy 326.592209 -417.310959) (xy 326.572675 -417.296782) (xy 326.558478 -417.277263)
			(xy 326.551007 -417.254312) (xy 326.550528 -417.242244) (xy 324.786244 -417.242244) (xy 324.785774 -417.254317)
			(xy 324.778304 -417.27728) (xy 324.764107 -417.296813) (xy 324.744573 -417.311007) (xy 324.721609 -417.318475)
			(xy 324.709536 -417.318952) (xy 324.514972 -417.318952) (xy 324.503864 -417.318588) (xy 324.482568 -417.312264)
			(xy 324.473062 -417.306506) (xy 324.178168 -417.113974) (xy 324.168781 -417.108271) (xy 324.147743 -417.101998)
			(xy 324.125789 -417.101998) (xy 324.104751 -417.108271) (xy 324.095364 -417.113974) (xy 323.80174 -417.306506)
			(xy 323.792229 -417.312253) (xy 323.770936 -417.318579) (xy 323.75983 -417.318952) (xy 323.563996 -417.318952)
			(xy 323.551926 -417.31844) (xy 323.528966 -417.310982) (xy 323.509433 -417.296796) (xy 323.495237 -417.27727)
			(xy 323.487767 -417.254314) (xy 323.487288 -417.242244) (xy 321.723004 -417.242244) (xy 321.722573 -417.254321)
			(xy 321.715098 -417.277291) (xy 321.700893 -417.296827) (xy 321.681348 -417.31102) (xy 321.658374 -417.318481)
			(xy 321.646296 -417.318952) (xy 321.451732 -417.318952) (xy 321.440623 -417.318604) (xy 321.419327 -417.312269)
			(xy 321.409822 -417.306506) (xy 321.114928 -417.113974) (xy 321.105541 -417.108271) (xy 321.084503 -417.101998)
			(xy 321.062549 -417.101998) (xy 321.041511 -417.108271) (xy 321.032124 -417.113974) (xy 320.7385 -417.306506)
			(xy 320.728997 -417.312268) (xy 320.707698 -417.318585) (xy 320.69659 -417.318952) (xy 320.500756 -417.318952)
			(xy 320.488684 -417.318474) (xy 320.465722 -417.311005) (xy 320.44619 -417.29681) (xy 320.431995 -417.277278)
			(xy 320.424526 -417.254316) (xy 320.424048 -417.242244) (xy 318.659764 -417.242244) (xy 318.659373 -417.254325)
			(xy 318.651893 -417.277301) (xy 318.637679 -417.296842) (xy 318.618122 -417.311033) (xy 318.595138 -417.318487)
			(xy 318.583056 -417.318952) (xy 318.388492 -417.318952) (xy 318.377385 -417.31858) (xy 318.356088 -417.312262)
			(xy 318.346582 -417.306506) (xy 318.051688 -417.113974) (xy 318.042301 -417.108271) (xy 318.021263 -417.101998)
			(xy 317.999309 -417.101998) (xy 317.978271 -417.108271) (xy 317.968884 -417.113974) (xy 317.67526 -417.306506)
			(xy 317.665745 -417.312246) (xy 317.644455 -417.318577) (xy 317.63335 -417.318952) (xy 317.437516 -417.318952)
			(xy 317.425447 -417.318423) (xy 317.402487 -417.31097) (xy 317.382954 -417.296789) (xy 317.368757 -417.277266)
			(xy 317.361287 -417.254313) (xy 317.360808 -417.242244) (xy 315.596524 -417.242244) (xy 315.596074 -417.254319)
			(xy 315.588601 -417.277285) (xy 315.5744 -417.29682) (xy 315.55486 -417.311014) (xy 315.531891 -417.318478)
			(xy 315.519816 -417.318952) (xy 315.325252 -417.318952) (xy 315.314143 -417.318596) (xy 315.292847 -417.312267)
			(xy 315.283342 -417.306506) (xy 314.988448 -417.113974) (xy 314.979061 -417.108271) (xy 314.958023 -417.101998)
			(xy 314.936069 -417.101998) (xy 314.915031 -417.108271) (xy 314.905644 -417.113974) (xy 314.61202 -417.306506)
			(xy 314.602513 -417.312261) (xy 314.581217 -417.318582) (xy 314.57011 -417.318952) (xy 314.374276 -417.318952)
			(xy 314.362205 -417.318457) (xy 314.339244 -417.310993) (xy 314.319711 -417.296803) (xy 314.305516 -417.277274)
			(xy 314.298046 -417.254315) (xy 314.297568 -417.242244) (xy 312.533284 -417.242244) (xy 312.532873 -417.254323)
			(xy 312.525396 -417.277296) (xy 312.511186 -417.296834) (xy 312.491635 -417.311027) (xy 312.468656 -417.318484)
			(xy 312.456576 -417.318952) (xy 312.262012 -417.318952) (xy 312.250905 -417.318571) (xy 312.229609 -417.312259)
			(xy 312.220102 -417.306506) (xy 311.925208 -417.113974) (xy 311.915821 -417.108271) (xy 311.894783 -417.101998)
			(xy 311.872829 -417.101998) (xy 311.851791 -417.108271) (xy 311.842404 -417.113974) (xy 311.54878 -417.306506)
			(xy 311.539261 -417.312239) (xy 311.517974 -417.318574) (xy 311.50687 -417.318952) (xy 311.311036 -417.318952)
			(xy 311.298968 -417.318406) (xy 311.276009 -417.310959) (xy 311.256475 -417.296782) (xy 311.242278 -417.277263)
			(xy 311.234807 -417.254312) (xy 311.234328 -417.242244) (xy 309.470044 -417.242244) (xy 309.469574 -417.254317)
			(xy 309.462104 -417.27728) (xy 309.447907 -417.296813) (xy 309.428373 -417.311007) (xy 309.405409 -417.318475)
			(xy 309.393336 -417.318952) (xy 309.198772 -417.318952) (xy 309.187664 -417.318588) (xy 309.166368 -417.312264)
			(xy 309.156862 -417.306506) (xy 308.861968 -417.113974) (xy 308.852581 -417.108271) (xy 308.831543 -417.101998)
			(xy 308.809589 -417.101998) (xy 308.788551 -417.108271) (xy 308.779164 -417.113974) (xy 308.48554 -417.306506)
			(xy 308.476029 -417.312253) (xy 308.454736 -417.318579) (xy 308.44363 -417.318952) (xy 308.247796 -417.318952)
			(xy 308.235726 -417.31844) (xy 308.212766 -417.310982) (xy 308.193233 -417.296796) (xy 308.179037 -417.27727)
			(xy 308.171567 -417.254314) (xy 308.171088 -417.242244) (xy 306.406804 -417.242244) (xy 306.406373 -417.254321)
			(xy 306.398898 -417.277291) (xy 306.384693 -417.296827) (xy 306.365148 -417.31102) (xy 306.342174 -417.318481)
			(xy 306.330096 -417.318952) (xy 306.135532 -417.318952) (xy 306.124423 -417.318604) (xy 306.103127 -417.312269)
			(xy 306.093622 -417.306506) (xy 305.798728 -417.113974) (xy 305.789341 -417.108271) (xy 305.768303 -417.101998)
			(xy 305.746349 -417.101998) (xy 305.725311 -417.108271) (xy 305.715924 -417.113974) (xy 305.4223 -417.306506)
			(xy 305.412797 -417.312268) (xy 305.391498 -417.318585) (xy 305.38039 -417.318952) (xy 305.184556 -417.318952)
			(xy 305.172484 -417.318474) (xy 305.149522 -417.311005) (xy 305.12999 -417.29681) (xy 305.115795 -417.277278)
			(xy 305.108326 -417.254316) (xy 305.107848 -417.242244) (xy 290.186237 -417.242244) (xy 290.193247 -417.257594)
			(xy 290.208602 -417.309889) (xy 290.216358 -417.363837) (xy 290.216844 -417.391088) (xy 290.216844 -418.254688)
			(xy 290.216358 -418.281939) (xy 290.208602 -418.335887) (xy 290.193247 -418.388182) (xy 290.170605 -418.437759)
			(xy 290.169514 -418.439456) (xy 304.944423 -418.439456) (xy 304.944423 -418.384944) (xy 304.952181 -418.330986)
			(xy 304.96754 -418.278681) (xy 304.990186 -418.229095) (xy 305.019659 -418.183237) (xy 305.055359 -418.14204)
			(xy 305.096558 -418.106344) (xy 305.142418 -418.076874) (xy 305.192006 -418.054231) (xy 305.244311 -418.038876)
			(xy 305.29827 -418.031121) (xy 305.325526 -418.03066) (xy 306.189126 -418.03066) (xy 306.216374 -418.031212)
			(xy 306.270314 -418.038971) (xy 306.322601 -418.054327) (xy 306.372171 -418.076968) (xy 306.418014 -418.106432)
			(xy 306.459198 -418.142121) (xy 306.494884 -418.183307) (xy 306.524345 -418.229152) (xy 306.546982 -418.278723)
			(xy 306.562335 -418.331011) (xy 306.57009 -418.384952) (xy 306.57009 -418.439448) (xy 306.570089 -418.439452)
			(xy 308.007746 -418.439452) (xy 308.007746 -418.384948) (xy 308.015502 -418.330999) (xy 308.030857 -418.278702)
			(xy 308.053497 -418.229123) (xy 308.082963 -418.183271) (xy 308.118654 -418.142078) (xy 308.159843 -418.106383)
			(xy 308.205693 -418.076914) (xy 308.25527 -418.054269) (xy 308.307565 -418.038909) (xy 308.361514 -418.031148)
			(xy 308.388766 -418.03066) (xy 309.252366 -418.03066) (xy 309.279618 -418.031185) (xy 309.333568 -418.038937)
			(xy 309.385866 -418.054289) (xy 309.435446 -418.076928) (xy 309.4813 -418.106392) (xy 309.522493 -418.142083)
			(xy 309.558187 -418.183273) (xy 309.587656 -418.229124) (xy 309.610299 -418.278702) (xy 309.625655 -418.330999)
			(xy 309.633413 -418.384948) (xy 309.633413 -418.439452) (xy 309.633413 -418.439455) (xy 311.070923 -418.439455)
			(xy 311.070923 -418.384945) (xy 311.078681 -418.330989) (xy 311.094038 -418.278686) (xy 311.116683 -418.229101)
			(xy 311.146154 -418.183244) (xy 311.181852 -418.142047) (xy 311.223049 -418.106351) (xy 311.268906 -418.07688)
			(xy 311.318491 -418.054236) (xy 311.370794 -418.038879) (xy 311.424751 -418.031123) (xy 311.452006 -418.03066)
			(xy 312.315606 -418.03066) (xy 312.342855 -418.031211) (xy 312.396797 -418.038967) (xy 312.449087 -418.054321)
			(xy 312.498659 -418.076961) (xy 312.544505 -418.106425) (xy 312.585691 -418.142113) (xy 312.621379 -418.1833)
			(xy 312.650842 -418.229146) (xy 312.673481 -418.278719) (xy 312.688834 -418.331009) (xy 312.69659 -418.384951)
			(xy 312.69659 -418.439449) (xy 312.696589 -418.439457) (xy 314.134123 -418.439457) (xy 314.134123 -418.384943)
			(xy 314.141882 -418.330983) (xy 314.157242 -418.278677) (xy 314.179889 -418.22909) (xy 314.209364 -418.183231)
			(xy 314.245066 -418.142033) (xy 314.286267 -418.106337) (xy 314.33213 -418.076867) (xy 314.38172 -418.054225)
			(xy 314.434028 -418.038872) (xy 314.487989 -418.03112) (xy 314.515246 -418.03066) (xy 315.378846 -418.03066)
			(xy 315.406093 -418.031213) (xy 315.460031 -418.038975) (xy 315.512316 -418.054332) (xy 315.561883 -418.076974)
			(xy 315.607724 -418.106439) (xy 315.648905 -418.142128) (xy 315.684588 -418.183313) (xy 315.714048 -418.229157)
			(xy 315.736684 -418.278727) (xy 315.752035 -418.331014) (xy 315.75979 -418.384953) (xy 315.75979 -418.439447)
			(xy 315.759789 -418.439453) (xy 317.197446 -418.439453) (xy 317.197446 -418.384947) (xy 317.205203 -418.330996)
			(xy 317.220558 -418.278698) (xy 317.2432 -418.229118) (xy 317.272668 -418.183264) (xy 317.308361 -418.142071)
			(xy 317.349553 -418.106376) (xy 317.395405 -418.076907) (xy 317.444985 -418.054263) (xy 317.497282 -418.038906)
			(xy 317.551233 -418.031147) (xy 317.578486 -418.03066) (xy 318.442086 -418.03066) (xy 318.469337 -418.031186)
			(xy 318.523285 -418.038941) (xy 318.57558 -418.054295) (xy 318.625158 -418.076934) (xy 318.671009 -418.106399)
			(xy 318.7122 -418.14209) (xy 318.747892 -418.18328) (xy 318.777359 -418.22913) (xy 318.800001 -418.278707)
			(xy 318.815356 -418.331001) (xy 318.823113 -418.384949) (xy 318.823113 -418.439451) (xy 318.823112 -418.439456)
			(xy 320.260623 -418.439456) (xy 320.260623 -418.384944) (xy 320.268381 -418.330986) (xy 320.28374 -418.278681)
			(xy 320.306386 -418.229095) (xy 320.335859 -418.183237) (xy 320.371559 -418.14204) (xy 320.412758 -418.106344)
			(xy 320.458618 -418.076874) (xy 320.508206 -418.054231) (xy 320.560511 -418.038876) (xy 320.61447 -418.031121)
			(xy 320.641726 -418.03066) (xy 321.505326 -418.03066) (xy 321.532574 -418.031212) (xy 321.586514 -418.038971)
			(xy 321.638801 -418.054327) (xy 321.688371 -418.076968) (xy 321.734214 -418.106432) (xy 321.775398 -418.142121)
			(xy 321.811084 -418.183307) (xy 321.840545 -418.229152) (xy 321.863182 -418.278723) (xy 321.878535 -418.331011)
			(xy 321.88629 -418.384952) (xy 321.88629 -418.439448) (xy 321.886289 -418.439452) (xy 323.323946 -418.439452)
			(xy 323.323946 -418.384948) (xy 323.331702 -418.330999) (xy 323.347057 -418.278702) (xy 323.369697 -418.229123)
			(xy 323.399163 -418.183271) (xy 323.434854 -418.142078) (xy 323.476043 -418.106383) (xy 323.521893 -418.076914)
			(xy 323.57147 -418.054269) (xy 323.623765 -418.038909) (xy 323.677714 -418.031148) (xy 323.704966 -418.03066)
			(xy 324.568566 -418.03066) (xy 324.595818 -418.031185) (xy 324.649768 -418.038937) (xy 324.702066 -418.054289)
			(xy 324.751646 -418.076928) (xy 324.7975 -418.106392) (xy 324.838693 -418.142083) (xy 324.874387 -418.183273)
			(xy 324.903856 -418.229124) (xy 324.926499 -418.278702) (xy 324.941855 -418.330999) (xy 324.949613 -418.384948)
			(xy 324.949613 -418.439452) (xy 324.949613 -418.439455) (xy 326.387123 -418.439455) (xy 326.387123 -418.384945)
			(xy 326.394881 -418.330989) (xy 326.410238 -418.278686) (xy 326.432883 -418.229101) (xy 326.462354 -418.183244)
			(xy 326.498052 -418.142047) (xy 326.539249 -418.106351) (xy 326.585106 -418.07688) (xy 326.634691 -418.054236)
			(xy 326.686994 -418.038879) (xy 326.740951 -418.031123) (xy 326.768206 -418.03066) (xy 327.631806 -418.03066)
			(xy 327.659055 -418.031211) (xy 327.712997 -418.038967) (xy 327.765287 -418.054321) (xy 327.814859 -418.076961)
			(xy 327.860705 -418.106425) (xy 327.901891 -418.142113) (xy 327.937579 -418.1833) (xy 327.967042 -418.229146)
			(xy 327.989681 -418.278719) (xy 328.005034 -418.331009) (xy 328.01279 -418.384951) (xy 328.01279 -418.439449)
			(xy 328.012789 -418.439457) (xy 329.450323 -418.439457) (xy 329.450323 -418.384943) (xy 329.458082 -418.330983)
			(xy 329.473442 -418.278677) (xy 329.496089 -418.22909) (xy 329.525564 -418.183231) (xy 329.561266 -418.142033)
			(xy 329.602467 -418.106337) (xy 329.64833 -418.076867) (xy 329.69792 -418.054225) (xy 329.750228 -418.038872)
			(xy 329.804189 -418.03112) (xy 329.831446 -418.03066) (xy 330.695046 -418.03066) (xy 330.722293 -418.031213)
			(xy 330.776231 -418.038975) (xy 330.828516 -418.054332) (xy 330.878083 -418.076974) (xy 330.923924 -418.106439)
			(xy 330.965105 -418.142128) (xy 331.000788 -418.183313) (xy 331.030248 -418.229157) (xy 331.052884 -418.278727)
			(xy 331.068235 -418.331014) (xy 331.07599 -418.384953) (xy 331.07599 -418.439447) (xy 331.075989 -418.439453)
			(xy 332.513646 -418.439453) (xy 332.513646 -418.384947) (xy 332.521403 -418.330996) (xy 332.536758 -418.278698)
			(xy 332.5594 -418.229118) (xy 332.588868 -418.183264) (xy 332.624561 -418.142071) (xy 332.665753 -418.106376)
			(xy 332.711605 -418.076907) (xy 332.761185 -418.054263) (xy 332.813482 -418.038906) (xy 332.867433 -418.031147)
			(xy 332.894686 -418.03066) (xy 333.758286 -418.03066) (xy 333.785537 -418.031186) (xy 333.839485 -418.038941)
			(xy 333.89178 -418.054295) (xy 333.941358 -418.076934) (xy 333.987209 -418.106399) (xy 334.0284 -418.14209)
			(xy 334.064092 -418.18328) (xy 334.093559 -418.22913) (xy 334.116201 -418.278707) (xy 334.131556 -418.331001)
			(xy 334.139313 -418.384949) (xy 334.139313 -418.439451) (xy 334.139312 -418.439456) (xy 335.576823 -418.439456)
			(xy 335.576823 -418.384944) (xy 335.584581 -418.330986) (xy 335.59994 -418.278681) (xy 335.622586 -418.229095)
			(xy 335.652059 -418.183237) (xy 335.687759 -418.14204) (xy 335.728958 -418.106344) (xy 335.774818 -418.076874)
			(xy 335.824406 -418.054231) (xy 335.876711 -418.038876) (xy 335.93067 -418.031121) (xy 335.957926 -418.03066)
			(xy 336.821526 -418.03066) (xy 336.848774 -418.031212) (xy 336.902714 -418.038971) (xy 336.955001 -418.054327)
			(xy 337.004571 -418.076968) (xy 337.050414 -418.106432) (xy 337.091598 -418.142121) (xy 337.127284 -418.183307)
			(xy 337.156745 -418.229152) (xy 337.179382 -418.278723) (xy 337.194735 -418.331011) (xy 337.20249 -418.384952)
			(xy 337.20249 -418.439448) (xy 337.202489 -418.439452) (xy 338.640146 -418.439452) (xy 338.640146 -418.384948)
			(xy 338.647902 -418.330999) (xy 338.663257 -418.278702) (xy 338.685897 -418.229123) (xy 338.715363 -418.183271)
			(xy 338.751054 -418.142078) (xy 338.792243 -418.106383) (xy 338.838093 -418.076914) (xy 338.88767 -418.054269)
			(xy 338.939965 -418.038909) (xy 338.993914 -418.031148) (xy 339.021166 -418.03066) (xy 339.884766 -418.03066)
			(xy 339.912018 -418.031185) (xy 339.965968 -418.038937) (xy 340.018266 -418.054289) (xy 340.067846 -418.076928)
			(xy 340.1137 -418.106392) (xy 340.154893 -418.142083) (xy 340.190587 -418.183273) (xy 340.220056 -418.229124)
			(xy 340.242699 -418.278702) (xy 340.258055 -418.330999) (xy 340.265813 -418.384948) (xy 340.265813 -418.439452)
			(xy 340.265813 -418.439455) (xy 341.703323 -418.439455) (xy 341.703323 -418.384945) (xy 341.711081 -418.330989)
			(xy 341.726438 -418.278686) (xy 341.749083 -418.229101) (xy 341.778554 -418.183244) (xy 341.814252 -418.142047)
			(xy 341.855449 -418.106351) (xy 341.901306 -418.07688) (xy 341.950891 -418.054236) (xy 342.003194 -418.038879)
			(xy 342.057151 -418.031123) (xy 342.084406 -418.03066) (xy 342.948006 -418.03066) (xy 342.975255 -418.031211)
			(xy 343.029197 -418.038967) (xy 343.081487 -418.054321) (xy 343.131059 -418.076961) (xy 343.176905 -418.106425)
			(xy 343.218091 -418.142113) (xy 343.253779 -418.1833) (xy 343.283242 -418.229146) (xy 343.305881 -418.278719)
			(xy 343.321234 -418.331009) (xy 343.32899 -418.384951) (xy 343.32899 -418.439449) (xy 343.328989 -418.439457)
			(xy 344.766523 -418.439457) (xy 344.766523 -418.384943) (xy 344.774282 -418.330983) (xy 344.789642 -418.278677)
			(xy 344.812289 -418.22909) (xy 344.841764 -418.183231) (xy 344.877466 -418.142033) (xy 344.918667 -418.106337)
			(xy 344.96453 -418.076867) (xy 345.01412 -418.054225) (xy 345.066428 -418.038872) (xy 345.120389 -418.03112)
			(xy 345.147646 -418.03066) (xy 346.011246 -418.03066) (xy 346.038493 -418.031213) (xy 346.092431 -418.038975)
			(xy 346.144716 -418.054332) (xy 346.194283 -418.076974) (xy 346.240124 -418.106439) (xy 346.281305 -418.142128)
			(xy 346.316988 -418.183313) (xy 346.346448 -418.229157) (xy 346.369084 -418.278727) (xy 346.384435 -418.331014)
			(xy 346.39219 -418.384953) (xy 346.39219 -418.439447) (xy 346.392189 -418.439453) (xy 347.829846 -418.439453)
			(xy 347.829846 -418.384947) (xy 347.837603 -418.330996) (xy 347.852958 -418.278698) (xy 347.8756 -418.229118)
			(xy 347.905068 -418.183264) (xy 347.940761 -418.142071) (xy 347.981953 -418.106376) (xy 348.027805 -418.076907)
			(xy 348.077385 -418.054263) (xy 348.129682 -418.038906) (xy 348.183633 -418.031147) (xy 348.210886 -418.03066)
			(xy 349.074486 -418.03066) (xy 349.101737 -418.031186) (xy 349.155685 -418.038941) (xy 349.20798 -418.054295)
			(xy 349.257558 -418.076934) (xy 349.303409 -418.106399) (xy 349.3446 -418.14209) (xy 349.380292 -418.18328)
			(xy 349.409759 -418.22913) (xy 349.432401 -418.278707) (xy 349.447756 -418.331001) (xy 349.455513 -418.384949)
			(xy 349.455513 -418.439451) (xy 349.455512 -418.439456) (xy 350.893023 -418.439456) (xy 350.893023 -418.384944)
			(xy 350.900781 -418.330986) (xy 350.91614 -418.278681) (xy 350.938786 -418.229095) (xy 350.968259 -418.183237)
			(xy 351.003959 -418.14204) (xy 351.045158 -418.106344) (xy 351.091018 -418.076874) (xy 351.140606 -418.054231)
			(xy 351.192911 -418.038876) (xy 351.24687 -418.031121) (xy 351.274126 -418.03066) (xy 352.137726 -418.03066)
			(xy 352.164974 -418.031212) (xy 352.218914 -418.038971) (xy 352.271201 -418.054327) (xy 352.320771 -418.076968)
			(xy 352.366614 -418.106432) (xy 352.407798 -418.142121) (xy 352.443484 -418.183307) (xy 352.472945 -418.229152)
			(xy 352.495582 -418.278723) (xy 352.510935 -418.331011) (xy 352.51869 -418.384952) (xy 352.51869 -418.439448)
			(xy 352.510935 -418.493389) (xy 352.495582 -418.545677) (xy 352.472945 -418.595248) (xy 352.443484 -418.641093)
			(xy 352.407798 -418.682279) (xy 352.366614 -418.717968) (xy 352.320771 -418.747432) (xy 352.271201 -418.770073)
			(xy 352.218914 -418.785429) (xy 352.164974 -418.793188) (xy 352.137726 -418.793676) (xy 351.274126 -418.793676)
			(xy 351.24687 -418.793279) (xy 351.192911 -418.785524) (xy 351.140606 -418.770169) (xy 351.091018 -418.747526)
			(xy 351.045158 -418.718056) (xy 351.003959 -418.68236) (xy 350.968259 -418.641163) (xy 350.938786 -418.595305)
			(xy 350.91614 -418.545719) (xy 350.900781 -418.493414) (xy 350.893023 -418.439456) (xy 349.455512 -418.439456)
			(xy 349.447756 -418.493399) (xy 349.432401 -418.545693) (xy 349.409759 -418.59527) (xy 349.380292 -418.64112)
			(xy 349.3446 -418.68231) (xy 349.303409 -418.718001) (xy 349.257558 -418.747466) (xy 349.20798 -418.770105)
			(xy 349.155685 -418.785459) (xy 349.101737 -418.793214) (xy 349.074486 -418.793676) (xy 348.210886 -418.793676)
			(xy 348.183633 -418.793253) (xy 348.129682 -418.785494) (xy 348.077385 -418.770137) (xy 348.027805 -418.747493)
			(xy 347.981953 -418.718024) (xy 347.940761 -418.682329) (xy 347.905068 -418.641136) (xy 347.8756 -418.595282)
			(xy 347.852958 -418.545702) (xy 347.837603 -418.493404) (xy 347.829846 -418.439453) (xy 346.392189 -418.439453)
			(xy 346.384435 -418.493386) (xy 346.369084 -418.545673) (xy 346.346448 -418.595243) (xy 346.316988 -418.641087)
			(xy 346.281305 -418.682272) (xy 346.240124 -418.717961) (xy 346.194283 -418.747426) (xy 346.144716 -418.770068)
			(xy 346.092431 -418.785425) (xy 346.038493 -418.793187) (xy 346.011246 -418.793676) (xy 345.147646 -418.793676)
			(xy 345.120389 -418.79328) (xy 345.066428 -418.785528) (xy 345.01412 -418.770175) (xy 344.96453 -418.747533)
			(xy 344.918667 -418.718063) (xy 344.877466 -418.682367) (xy 344.841764 -418.641169) (xy 344.812289 -418.59531)
			(xy 344.789642 -418.545723) (xy 344.774282 -418.493417) (xy 344.766523 -418.439457) (xy 343.328989 -418.439457)
			(xy 343.321234 -418.493391) (xy 343.305881 -418.545681) (xy 343.283242 -418.595254) (xy 343.253779 -418.6411)
			(xy 343.218091 -418.682287) (xy 343.176905 -418.717975) (xy 343.131059 -418.747439) (xy 343.081487 -418.770079)
			(xy 343.029197 -418.785433) (xy 342.975255 -418.793189) (xy 342.948006 -418.793676) (xy 342.084406 -418.793676)
			(xy 342.057151 -418.793277) (xy 342.003194 -418.785521) (xy 341.950891 -418.770164) (xy 341.901306 -418.74752)
			(xy 341.855449 -418.718049) (xy 341.814252 -418.682353) (xy 341.778554 -418.641156) (xy 341.749083 -418.595299)
			(xy 341.726438 -418.545714) (xy 341.711081 -418.493411) (xy 341.703323 -418.439455) (xy 340.265813 -418.439455)
			(xy 340.258055 -418.493402) (xy 340.242699 -418.545698) (xy 340.220056 -418.595276) (xy 340.190587 -418.641127)
			(xy 340.154893 -418.682317) (xy 340.1137 -418.718008) (xy 340.067846 -418.747472) (xy 340.018266 -418.770111)
			(xy 339.965968 -418.785463) (xy 339.912018 -418.793215) (xy 339.884766 -418.793676) (xy 339.021166 -418.793676)
			(xy 338.993914 -418.793252) (xy 338.939965 -418.785491) (xy 338.88767 -418.770131) (xy 338.838093 -418.747486)
			(xy 338.792243 -418.718017) (xy 338.751054 -418.682322) (xy 338.715363 -418.641129) (xy 338.685897 -418.595277)
			(xy 338.663257 -418.545698) (xy 338.647902 -418.493401) (xy 338.640146 -418.439452) (xy 337.202489 -418.439452)
			(xy 337.194735 -418.493389) (xy 337.179382 -418.545677) (xy 337.156745 -418.595248) (xy 337.127284 -418.641093)
			(xy 337.091598 -418.682279) (xy 337.050414 -418.717968) (xy 337.004571 -418.747432) (xy 336.955001 -418.770073)
			(xy 336.902714 -418.785429) (xy 336.848774 -418.793188) (xy 336.821526 -418.793676) (xy 335.957926 -418.793676)
			(xy 335.93067 -418.793279) (xy 335.876711 -418.785524) (xy 335.824406 -418.770169) (xy 335.774818 -418.747526)
			(xy 335.728958 -418.718056) (xy 335.687759 -418.68236) (xy 335.652059 -418.641163) (xy 335.622586 -418.595305)
			(xy 335.59994 -418.545719) (xy 335.584581 -418.493414) (xy 335.576823 -418.439456) (xy 334.139312 -418.439456)
			(xy 334.131556 -418.493399) (xy 334.116201 -418.545693) (xy 334.093559 -418.59527) (xy 334.064092 -418.64112)
			(xy 334.0284 -418.68231) (xy 333.987209 -418.718001) (xy 333.941358 -418.747466) (xy 333.89178 -418.770105)
			(xy 333.839485 -418.785459) (xy 333.785537 -418.793214) (xy 333.758286 -418.793676) (xy 332.894686 -418.793676)
			(xy 332.867433 -418.793253) (xy 332.813482 -418.785494) (xy 332.761185 -418.770137) (xy 332.711605 -418.747493)
			(xy 332.665753 -418.718024) (xy 332.624561 -418.682329) (xy 332.588868 -418.641136) (xy 332.5594 -418.595282)
			(xy 332.536758 -418.545702) (xy 332.521403 -418.493404) (xy 332.513646 -418.439453) (xy 331.075989 -418.439453)
			(xy 331.068235 -418.493386) (xy 331.052884 -418.545673) (xy 331.030248 -418.595243) (xy 331.000788 -418.641087)
			(xy 330.965105 -418.682272) (xy 330.923924 -418.717961) (xy 330.878083 -418.747426) (xy 330.828516 -418.770068)
			(xy 330.776231 -418.785425) (xy 330.722293 -418.793187) (xy 330.695046 -418.793676) (xy 329.831446 -418.793676)
			(xy 329.804189 -418.79328) (xy 329.750228 -418.785528) (xy 329.69792 -418.770175) (xy 329.64833 -418.747533)
			(xy 329.602467 -418.718063) (xy 329.561266 -418.682367) (xy 329.525564 -418.641169) (xy 329.496089 -418.59531)
			(xy 329.473442 -418.545723) (xy 329.458082 -418.493417) (xy 329.450323 -418.439457) (xy 328.012789 -418.439457)
			(xy 328.005034 -418.493391) (xy 327.989681 -418.545681) (xy 327.967042 -418.595254) (xy 327.937579 -418.6411)
			(xy 327.901891 -418.682287) (xy 327.860705 -418.717975) (xy 327.814859 -418.747439) (xy 327.765287 -418.770079)
			(xy 327.712997 -418.785433) (xy 327.659055 -418.793189) (xy 327.631806 -418.793676) (xy 326.768206 -418.793676)
			(xy 326.740951 -418.793277) (xy 326.686994 -418.785521) (xy 326.634691 -418.770164) (xy 326.585106 -418.74752)
			(xy 326.539249 -418.718049) (xy 326.498052 -418.682353) (xy 326.462354 -418.641156) (xy 326.432883 -418.595299)
			(xy 326.410238 -418.545714) (xy 326.394881 -418.493411) (xy 326.387123 -418.439455) (xy 324.949613 -418.439455)
			(xy 324.941855 -418.493402) (xy 324.926499 -418.545698) (xy 324.903856 -418.595276) (xy 324.874387 -418.641127)
			(xy 324.838693 -418.682317) (xy 324.7975 -418.718008) (xy 324.751646 -418.747472) (xy 324.702066 -418.770111)
			(xy 324.649768 -418.785463) (xy 324.595818 -418.793215) (xy 324.568566 -418.793676) (xy 323.704966 -418.793676)
			(xy 323.677714 -418.793252) (xy 323.623765 -418.785491) (xy 323.57147 -418.770131) (xy 323.521893 -418.747486)
			(xy 323.476043 -418.718017) (xy 323.434854 -418.682322) (xy 323.399163 -418.641129) (xy 323.369697 -418.595277)
			(xy 323.347057 -418.545698) (xy 323.331702 -418.493401) (xy 323.323946 -418.439452) (xy 321.886289 -418.439452)
			(xy 321.878535 -418.493389) (xy 321.863182 -418.545677) (xy 321.840545 -418.595248) (xy 321.811084 -418.641093)
			(xy 321.775398 -418.682279) (xy 321.734214 -418.717968) (xy 321.688371 -418.747432) (xy 321.638801 -418.770073)
			(xy 321.586514 -418.785429) (xy 321.532574 -418.793188) (xy 321.505326 -418.793676) (xy 320.641726 -418.793676)
			(xy 320.61447 -418.793279) (xy 320.560511 -418.785524) (xy 320.508206 -418.770169) (xy 320.458618 -418.747526)
			(xy 320.412758 -418.718056) (xy 320.371559 -418.68236) (xy 320.335859 -418.641163) (xy 320.306386 -418.595305)
			(xy 320.28374 -418.545719) (xy 320.268381 -418.493414) (xy 320.260623 -418.439456) (xy 318.823112 -418.439456)
			(xy 318.815356 -418.493399) (xy 318.800001 -418.545693) (xy 318.777359 -418.59527) (xy 318.747892 -418.64112)
			(xy 318.7122 -418.68231) (xy 318.671009 -418.718001) (xy 318.625158 -418.747466) (xy 318.57558 -418.770105)
			(xy 318.523285 -418.785459) (xy 318.469337 -418.793214) (xy 318.442086 -418.793676) (xy 317.578486 -418.793676)
			(xy 317.551233 -418.793253) (xy 317.497282 -418.785494) (xy 317.444985 -418.770137) (xy 317.395405 -418.747493)
			(xy 317.349553 -418.718024) (xy 317.308361 -418.682329) (xy 317.272668 -418.641136) (xy 317.2432 -418.595282)
			(xy 317.220558 -418.545702) (xy 317.205203 -418.493404) (xy 317.197446 -418.439453) (xy 315.759789 -418.439453)
			(xy 315.752035 -418.493386) (xy 315.736684 -418.545673) (xy 315.714048 -418.595243) (xy 315.684588 -418.641087)
			(xy 315.648905 -418.682272) (xy 315.607724 -418.717961) (xy 315.561883 -418.747426) (xy 315.512316 -418.770068)
			(xy 315.460031 -418.785425) (xy 315.406093 -418.793187) (xy 315.378846 -418.793676) (xy 314.515246 -418.793676)
			(xy 314.487989 -418.79328) (xy 314.434028 -418.785528) (xy 314.38172 -418.770175) (xy 314.33213 -418.747533)
			(xy 314.286267 -418.718063) (xy 314.245066 -418.682367) (xy 314.209364 -418.641169) (xy 314.179889 -418.59531)
			(xy 314.157242 -418.545723) (xy 314.141882 -418.493417) (xy 314.134123 -418.439457) (xy 312.696589 -418.439457)
			(xy 312.688834 -418.493391) (xy 312.673481 -418.545681) (xy 312.650842 -418.595254) (xy 312.621379 -418.6411)
			(xy 312.585691 -418.682287) (xy 312.544505 -418.717975) (xy 312.498659 -418.747439) (xy 312.449087 -418.770079)
			(xy 312.396797 -418.785433) (xy 312.342855 -418.793189) (xy 312.315606 -418.793676) (xy 311.452006 -418.793676)
			(xy 311.424751 -418.793277) (xy 311.370794 -418.785521) (xy 311.318491 -418.770164) (xy 311.268906 -418.74752)
			(xy 311.223049 -418.718049) (xy 311.181852 -418.682353) (xy 311.146154 -418.641156) (xy 311.116683 -418.595299)
			(xy 311.094038 -418.545714) (xy 311.078681 -418.493411) (xy 311.070923 -418.439455) (xy 309.633413 -418.439455)
			(xy 309.625655 -418.493402) (xy 309.610299 -418.545698) (xy 309.587656 -418.595276) (xy 309.558187 -418.641127)
			(xy 309.522493 -418.682317) (xy 309.4813 -418.718008) (xy 309.435446 -418.747472) (xy 309.385866 -418.770111)
			(xy 309.333568 -418.785463) (xy 309.279618 -418.793215) (xy 309.252366 -418.793676) (xy 308.388766 -418.793676)
			(xy 308.361514 -418.793252) (xy 308.307565 -418.785491) (xy 308.25527 -418.770131) (xy 308.205693 -418.747486)
			(xy 308.159843 -418.718017) (xy 308.118654 -418.682322) (xy 308.082963 -418.641129) (xy 308.053497 -418.595277)
			(xy 308.030857 -418.545698) (xy 308.015502 -418.493401) (xy 308.007746 -418.439452) (xy 306.570089 -418.439452)
			(xy 306.562335 -418.493389) (xy 306.546982 -418.545677) (xy 306.524345 -418.595248) (xy 306.494884 -418.641093)
			(xy 306.459198 -418.682279) (xy 306.418014 -418.717968) (xy 306.372171 -418.747432) (xy 306.322601 -418.770073)
			(xy 306.270314 -418.785429) (xy 306.216374 -418.793188) (xy 306.189126 -418.793676) (xy 305.325526 -418.793676)
			(xy 305.29827 -418.793279) (xy 305.244311 -418.785524) (xy 305.192006 -418.770169) (xy 305.142418 -418.747526)
			(xy 305.096558 -418.718056) (xy 305.055359 -418.68236) (xy 305.019659 -418.641163) (xy 304.990186 -418.595305)
			(xy 304.96754 -418.545719) (xy 304.952181 -418.493414) (xy 304.944423 -418.439456) (xy 290.169514 -418.439456)
			(xy 290.141139 -418.483609) (xy 290.105448 -418.5248) (xy 290.064257 -418.560491) (xy 290.018407 -418.589957)
			(xy 289.96883 -418.612599) (xy 289.916535 -418.627954) (xy 289.862587 -418.63571) (xy 289.808085 -418.63571)
			(xy 289.754137 -418.627954) (xy 289.701842 -418.612599) (xy 289.652265 -418.589957) (xy 289.606415 -418.560491)
			(xy 289.565224 -418.5248) (xy 289.529533 -418.483609) (xy 289.500067 -418.437759) (xy 289.477425 -418.388182)
			(xy 289.46207 -418.335887) (xy 289.454314 -418.281939) (xy 289.453828 -418.254688) (xy 277.48484 -418.254688)
			(xy 277.48484 -419.081712) (xy 277.484354 -419.108963) (xy 277.476598 -419.162911) (xy 277.461243 -419.215206)
			(xy 277.438601 -419.264783) (xy 277.409135 -419.310633) (xy 277.373444 -419.351824) (xy 277.332253 -419.387515)
			(xy 277.286403 -419.416981) (xy 277.236826 -419.439623) (xy 277.184531 -419.454978) (xy 277.130583 -419.462734)
			(xy 277.076081 -419.462734) (xy 277.022133 -419.454978) (xy 276.969838 -419.439623) (xy 276.920261 -419.416981)
			(xy 276.874411 -419.387515) (xy 276.83322 -419.351824) (xy 276.797529 -419.310633) (xy 276.768063 -419.264783)
			(xy 276.745421 -419.215206) (xy 276.730066 -419.162911) (xy 276.72231 -419.108963) (xy 276.721824 -419.081712)
			(xy 233.545126 -419.081712) (xy 232.102406 -420.524432) (xy 290.829492 -420.524432) (xy 290.829492 -419.660832)
			(xy 290.829978 -419.633563) (xy 290.83774 -419.579579) (xy 290.853105 -419.527249) (xy 290.875762 -419.477639)
			(xy 290.905248 -419.431758) (xy 290.940963 -419.390541) (xy 290.98218 -419.354826) (xy 291.028061 -419.32534)
			(xy 291.077671 -419.302683) (xy 291.130001 -419.287318) (xy 291.183985 -419.279556) (xy 291.238523 -419.279556)
			(xy 291.292507 -419.287318) (xy 291.344837 -419.302683) (xy 291.394447 -419.32534) (xy 291.440328 -419.354826)
			(xy 291.481545 -419.390541) (xy 291.51726 -419.431758) (xy 291.546746 -419.477639) (xy 291.569403 -419.527249)
			(xy 291.584768 -419.579579) (xy 291.59253 -419.633563) (xy 291.593016 -419.660832) (xy 291.593016 -420.524432)
			(xy 291.59253 -420.551701) (xy 291.584768 -420.605685) (xy 291.569403 -420.658015) (xy 291.546746 -420.707625)
			(xy 291.51726 -420.753506) (xy 291.481545 -420.794723) (xy 291.440328 -420.830438) (xy 291.394447 -420.859924)
			(xy 291.344837 -420.882581) (xy 291.292507 -420.897946) (xy 291.238523 -420.905708) (xy 291.183985 -420.905708)
			(xy 291.130001 -420.897946) (xy 291.077671 -420.882581) (xy 291.028061 -420.859924) (xy 290.98218 -420.830438)
			(xy 290.940963 -420.794723) (xy 290.905248 -420.753506) (xy 290.875762 -420.707625) (xy 290.853105 -420.658015)
			(xy 290.83774 -420.605685) (xy 290.829978 -420.551701) (xy 290.829492 -420.524432) (xy 232.102406 -420.524432)
			(xy 231.647383 -420.979455) (xy 303.412823 -420.979455) (xy 303.412823 -420.924945) (xy 303.420581 -420.870989)
			(xy 303.435938 -420.818686) (xy 303.458583 -420.769101) (xy 303.488054 -420.723244) (xy 303.523752 -420.682047)
			(xy 303.564949 -420.646351) (xy 303.610806 -420.61688) (xy 303.660391 -420.594236) (xy 303.712694 -420.578879)
			(xy 303.766651 -420.571123) (xy 303.793906 -420.57066) (xy 304.657506 -420.57066) (xy 304.684755 -420.571211)
			(xy 304.738697 -420.578967) (xy 304.790987 -420.594321) (xy 304.840559 -420.616961) (xy 304.886405 -420.646425)
			(xy 304.927591 -420.682113) (xy 304.963279 -420.7233) (xy 304.992742 -420.769146) (xy 305.015381 -420.818719)
			(xy 305.030734 -420.871009) (xy 305.03849 -420.924951) (xy 305.03849 -420.979449) (xy 305.038489 -420.979457)
			(xy 306.476023 -420.979457) (xy 306.476023 -420.924943) (xy 306.483782 -420.870983) (xy 306.499142 -420.818677)
			(xy 306.521789 -420.76909) (xy 306.551264 -420.723231) (xy 306.586966 -420.682033) (xy 306.628167 -420.646337)
			(xy 306.67403 -420.616867) (xy 306.72362 -420.594225) (xy 306.775928 -420.578872) (xy 306.829889 -420.57112)
			(xy 306.857146 -420.57066) (xy 307.720746 -420.57066) (xy 307.747993 -420.571213) (xy 307.801931 -420.578975)
			(xy 307.854216 -420.594332) (xy 307.903783 -420.616974) (xy 307.949624 -420.646439) (xy 307.990805 -420.682128)
			(xy 308.026488 -420.723313) (xy 308.055948 -420.769157) (xy 308.078584 -420.818727) (xy 308.093935 -420.871014)
			(xy 308.10169 -420.924953) (xy 308.10169 -420.979447) (xy 308.101689 -420.979453) (xy 309.539346 -420.979453)
			(xy 309.539346 -420.924947) (xy 309.547103 -420.870996) (xy 309.562458 -420.818698) (xy 309.5851 -420.769118)
			(xy 309.614568 -420.723264) (xy 309.650261 -420.682071) (xy 309.691453 -420.646376) (xy 309.737305 -420.616907)
			(xy 309.786885 -420.594263) (xy 309.839182 -420.578906) (xy 309.893133 -420.571147) (xy 309.920386 -420.57066)
			(xy 310.783986 -420.57066) (xy 310.811237 -420.571186) (xy 310.865185 -420.578941) (xy 310.91748 -420.594295)
			(xy 310.967058 -420.616934) (xy 311.012909 -420.646399) (xy 311.0541 -420.68209) (xy 311.089792 -420.72328)
			(xy 311.119259 -420.76913) (xy 311.141901 -420.818707) (xy 311.157256 -420.871001) (xy 311.165013 -420.924949)
			(xy 311.165013 -420.979451) (xy 311.165012 -420.979456) (xy 312.602523 -420.979456) (xy 312.602523 -420.924944)
			(xy 312.610281 -420.870986) (xy 312.62564 -420.818681) (xy 312.648286 -420.769095) (xy 312.677759 -420.723237)
			(xy 312.713459 -420.68204) (xy 312.754658 -420.646344) (xy 312.800518 -420.616874) (xy 312.850106 -420.594231)
			(xy 312.902411 -420.578876) (xy 312.95637 -420.571121) (xy 312.983626 -420.57066) (xy 313.847226 -420.57066)
			(xy 313.874474 -420.571212) (xy 313.928414 -420.578971) (xy 313.980701 -420.594327) (xy 314.030271 -420.616968)
			(xy 314.076114 -420.646432) (xy 314.117298 -420.682121) (xy 314.152984 -420.723307) (xy 314.182445 -420.769152)
			(xy 314.205082 -420.818723) (xy 314.220435 -420.871011) (xy 314.22819 -420.924952) (xy 314.22819 -420.979448)
			(xy 314.228189 -420.979452) (xy 315.665846 -420.979452) (xy 315.665846 -420.924948) (xy 315.673602 -420.870999)
			(xy 315.688957 -420.818702) (xy 315.711597 -420.769123) (xy 315.741063 -420.723271) (xy 315.776754 -420.682078)
			(xy 315.817943 -420.646383) (xy 315.863793 -420.616914) (xy 315.91337 -420.594269) (xy 315.965665 -420.578909)
			(xy 316.019614 -420.571148) (xy 316.046866 -420.57066) (xy 316.910466 -420.57066) (xy 316.937718 -420.571185)
			(xy 316.991668 -420.578937) (xy 317.043966 -420.594289) (xy 317.093546 -420.616928) (xy 317.1394 -420.646392)
			(xy 317.180593 -420.682083) (xy 317.216287 -420.723273) (xy 317.245756 -420.769124) (xy 317.268399 -420.818702)
			(xy 317.283755 -420.870999) (xy 317.291513 -420.924948) (xy 317.291513 -420.979452) (xy 317.291513 -420.979455)
			(xy 318.729023 -420.979455) (xy 318.729023 -420.924945) (xy 318.736781 -420.870989) (xy 318.752138 -420.818686)
			(xy 318.774783 -420.769101) (xy 318.804254 -420.723244) (xy 318.839952 -420.682047) (xy 318.881149 -420.646351)
			(xy 318.927006 -420.61688) (xy 318.976591 -420.594236) (xy 319.028894 -420.578879) (xy 319.082851 -420.571123)
			(xy 319.110106 -420.57066) (xy 319.973706 -420.57066) (xy 320.000955 -420.571211) (xy 320.054897 -420.578967)
			(xy 320.107187 -420.594321) (xy 320.156759 -420.616961) (xy 320.202605 -420.646425) (xy 320.243791 -420.682113)
			(xy 320.279479 -420.7233) (xy 320.308942 -420.769146) (xy 320.331581 -420.818719) (xy 320.346934 -420.871009)
			(xy 320.35469 -420.924951) (xy 320.35469 -420.979449) (xy 320.354689 -420.979457) (xy 321.792223 -420.979457)
			(xy 321.792223 -420.924943) (xy 321.799982 -420.870983) (xy 321.815342 -420.818677) (xy 321.837989 -420.76909)
			(xy 321.867464 -420.723231) (xy 321.903166 -420.682033) (xy 321.944367 -420.646337) (xy 321.99023 -420.616867)
			(xy 322.03982 -420.594225) (xy 322.092128 -420.578872) (xy 322.146089 -420.57112) (xy 322.173346 -420.57066)
			(xy 323.036946 -420.57066) (xy 323.064193 -420.571213) (xy 323.118131 -420.578975) (xy 323.170416 -420.594332)
			(xy 323.219983 -420.616974) (xy 323.265824 -420.646439) (xy 323.307005 -420.682128) (xy 323.342688 -420.723313)
			(xy 323.372148 -420.769157) (xy 323.394784 -420.818727) (xy 323.410135 -420.871014) (xy 323.41789 -420.924953)
			(xy 323.41789 -420.979447) (xy 323.417889 -420.979453) (xy 324.855546 -420.979453) (xy 324.855546 -420.924947)
			(xy 324.863303 -420.870996) (xy 324.878658 -420.818698) (xy 324.9013 -420.769118) (xy 324.930768 -420.723264)
			(xy 324.966461 -420.682071) (xy 325.007653 -420.646376) (xy 325.053505 -420.616907) (xy 325.103085 -420.594263)
			(xy 325.155382 -420.578906) (xy 325.209333 -420.571147) (xy 325.236586 -420.57066) (xy 326.100186 -420.57066)
			(xy 326.127437 -420.571186) (xy 326.181385 -420.578941) (xy 326.23368 -420.594295) (xy 326.283258 -420.616934)
			(xy 326.329109 -420.646399) (xy 326.3703 -420.68209) (xy 326.405992 -420.72328) (xy 326.435459 -420.76913)
			(xy 326.458101 -420.818707) (xy 326.473456 -420.871001) (xy 326.481213 -420.924949) (xy 326.481213 -420.979451)
			(xy 326.481212 -420.979456) (xy 327.918723 -420.979456) (xy 327.918723 -420.924944) (xy 327.926481 -420.870986)
			(xy 327.94184 -420.818681) (xy 327.964486 -420.769095) (xy 327.993959 -420.723237) (xy 328.029659 -420.68204)
			(xy 328.070858 -420.646344) (xy 328.116718 -420.616874) (xy 328.166306 -420.594231) (xy 328.218611 -420.578876)
			(xy 328.27257 -420.571121) (xy 328.299826 -420.57066) (xy 329.163426 -420.57066) (xy 329.190674 -420.571212)
			(xy 329.244614 -420.578971) (xy 329.296901 -420.594327) (xy 329.346471 -420.616968) (xy 329.392314 -420.646432)
			(xy 329.433498 -420.682121) (xy 329.469184 -420.723307) (xy 329.498645 -420.769152) (xy 329.521282 -420.818723)
			(xy 329.536635 -420.871011) (xy 329.54439 -420.924952) (xy 329.54439 -420.979448) (xy 329.544389 -420.979452)
			(xy 330.982046 -420.979452) (xy 330.982046 -420.924948) (xy 330.989802 -420.870999) (xy 331.005157 -420.818702)
			(xy 331.027797 -420.769123) (xy 331.057263 -420.723271) (xy 331.092954 -420.682078) (xy 331.134143 -420.646383)
			(xy 331.179993 -420.616914) (xy 331.22957 -420.594269) (xy 331.281865 -420.578909) (xy 331.335814 -420.571148)
			(xy 331.363066 -420.57066) (xy 332.226666 -420.57066) (xy 332.253918 -420.571185) (xy 332.307868 -420.578937)
			(xy 332.360166 -420.594289) (xy 332.409746 -420.616928) (xy 332.4556 -420.646392) (xy 332.496793 -420.682083)
			(xy 332.532487 -420.723273) (xy 332.561956 -420.769124) (xy 332.584599 -420.818702) (xy 332.599955 -420.870999)
			(xy 332.607713 -420.924948) (xy 332.607713 -420.979452) (xy 332.607713 -420.979455) (xy 334.045223 -420.979455)
			(xy 334.045223 -420.924945) (xy 334.052981 -420.870989) (xy 334.068338 -420.818686) (xy 334.090983 -420.769101)
			(xy 334.120454 -420.723244) (xy 334.156152 -420.682047) (xy 334.197349 -420.646351) (xy 334.243206 -420.61688)
			(xy 334.292791 -420.594236) (xy 334.345094 -420.578879) (xy 334.399051 -420.571123) (xy 334.426306 -420.57066)
			(xy 335.289906 -420.57066) (xy 335.317155 -420.571211) (xy 335.371097 -420.578967) (xy 335.423387 -420.594321)
			(xy 335.472959 -420.616961) (xy 335.518805 -420.646425) (xy 335.559991 -420.682113) (xy 335.595679 -420.7233)
			(xy 335.625142 -420.769146) (xy 335.647781 -420.818719) (xy 335.663134 -420.871009) (xy 335.67089 -420.924951)
			(xy 335.67089 -420.979449) (xy 335.670889 -420.979457) (xy 337.108423 -420.979457) (xy 337.108423 -420.924943)
			(xy 337.116182 -420.870983) (xy 337.131542 -420.818677) (xy 337.154189 -420.76909) (xy 337.183664 -420.723231)
			(xy 337.219366 -420.682033) (xy 337.260567 -420.646337) (xy 337.30643 -420.616867) (xy 337.35602 -420.594225)
			(xy 337.408328 -420.578872) (xy 337.462289 -420.57112) (xy 337.489546 -420.57066) (xy 338.353146 -420.57066)
			(xy 338.380393 -420.571213) (xy 338.434331 -420.578975) (xy 338.486616 -420.594332) (xy 338.536183 -420.616974)
			(xy 338.582024 -420.646439) (xy 338.623205 -420.682128) (xy 338.658888 -420.723313) (xy 338.688348 -420.769157)
			(xy 338.710984 -420.818727) (xy 338.726335 -420.871014) (xy 338.73409 -420.924953) (xy 338.73409 -420.979447)
			(xy 338.734089 -420.979453) (xy 340.171746 -420.979453) (xy 340.171746 -420.924947) (xy 340.179503 -420.870996)
			(xy 340.194858 -420.818698) (xy 340.2175 -420.769118) (xy 340.246968 -420.723264) (xy 340.282661 -420.682071)
			(xy 340.323853 -420.646376) (xy 340.369705 -420.616907) (xy 340.419285 -420.594263) (xy 340.471582 -420.578906)
			(xy 340.525533 -420.571147) (xy 340.552786 -420.57066) (xy 341.416386 -420.57066) (xy 341.443637 -420.571186)
			(xy 341.497585 -420.578941) (xy 341.54988 -420.594295) (xy 341.599458 -420.616934) (xy 341.645309 -420.646399)
			(xy 341.6865 -420.68209) (xy 341.722192 -420.72328) (xy 341.751659 -420.76913) (xy 341.774301 -420.818707)
			(xy 341.789656 -420.871001) (xy 341.797413 -420.924949) (xy 341.797413 -420.979451) (xy 341.797412 -420.979456)
			(xy 343.234923 -420.979456) (xy 343.234923 -420.924944) (xy 343.242681 -420.870986) (xy 343.25804 -420.818681)
			(xy 343.280686 -420.769095) (xy 343.310159 -420.723237) (xy 343.345859 -420.68204) (xy 343.387058 -420.646344)
			(xy 343.432918 -420.616874) (xy 343.482506 -420.594231) (xy 343.534811 -420.578876) (xy 343.58877 -420.571121)
			(xy 343.616026 -420.57066) (xy 344.479626 -420.57066) (xy 344.506874 -420.571212) (xy 344.560814 -420.578971)
			(xy 344.613101 -420.594327) (xy 344.662671 -420.616968) (xy 344.708514 -420.646432) (xy 344.749698 -420.682121)
			(xy 344.785384 -420.723307) (xy 344.814845 -420.769152) (xy 344.837482 -420.818723) (xy 344.852835 -420.871011)
			(xy 344.86059 -420.924952) (xy 344.86059 -420.979448) (xy 344.860589 -420.979452) (xy 346.298246 -420.979452)
			(xy 346.298246 -420.924948) (xy 346.306002 -420.870999) (xy 346.321357 -420.818702) (xy 346.343997 -420.769123)
			(xy 346.373463 -420.723271) (xy 346.409154 -420.682078) (xy 346.450343 -420.646383) (xy 346.496193 -420.616914)
			(xy 346.54577 -420.594269) (xy 346.598065 -420.578909) (xy 346.652014 -420.571148) (xy 346.679266 -420.57066)
			(xy 347.542866 -420.57066) (xy 347.570118 -420.571185) (xy 347.624068 -420.578937) (xy 347.676366 -420.594289)
			(xy 347.725946 -420.616928) (xy 347.7718 -420.646392) (xy 347.812993 -420.682083) (xy 347.848687 -420.723273)
			(xy 347.878156 -420.769124) (xy 347.900799 -420.818702) (xy 347.916155 -420.870999) (xy 347.923913 -420.924948)
			(xy 347.923913 -420.979452) (xy 347.923913 -420.979455) (xy 349.361423 -420.979455) (xy 349.361423 -420.924945)
			(xy 349.369181 -420.870989) (xy 349.384538 -420.818686) (xy 349.407183 -420.769101) (xy 349.436654 -420.723244)
			(xy 349.472352 -420.682047) (xy 349.513549 -420.646351) (xy 349.559406 -420.61688) (xy 349.608991 -420.594236)
			(xy 349.661294 -420.578879) (xy 349.715251 -420.571123) (xy 349.742506 -420.57066) (xy 350.606106 -420.57066)
			(xy 350.633355 -420.571211) (xy 350.687297 -420.578967) (xy 350.739587 -420.594321) (xy 350.789159 -420.616961)
			(xy 350.835005 -420.646425) (xy 350.876191 -420.682113) (xy 350.911879 -420.7233) (xy 350.941342 -420.769146)
			(xy 350.963981 -420.818719) (xy 350.979334 -420.871009) (xy 350.98709 -420.924951) (xy 350.98709 -420.979449)
			(xy 350.979334 -421.033391) (xy 350.963981 -421.085681) (xy 350.941342 -421.135254) (xy 350.911879 -421.1811)
			(xy 350.876191 -421.222287) (xy 350.835005 -421.257975) (xy 350.789159 -421.287439) (xy 350.739587 -421.310079)
			(xy 350.687297 -421.325433) (xy 350.633355 -421.333189) (xy 350.606106 -421.333676) (xy 349.742506 -421.333676)
			(xy 349.715251 -421.333277) (xy 349.661294 -421.325521) (xy 349.608991 -421.310164) (xy 349.559406 -421.28752)
			(xy 349.513549 -421.258049) (xy 349.472352 -421.222353) (xy 349.436654 -421.181156) (xy 349.407183 -421.135299)
			(xy 349.384538 -421.085714) (xy 349.369181 -421.033411) (xy 349.361423 -420.979455) (xy 347.923913 -420.979455)
			(xy 347.916155 -421.033402) (xy 347.900799 -421.085698) (xy 347.878156 -421.135276) (xy 347.848687 -421.181127)
			(xy 347.812993 -421.222317) (xy 347.7718 -421.258008) (xy 347.725946 -421.287472) (xy 347.676366 -421.310111)
			(xy 347.624068 -421.325463) (xy 347.570118 -421.333215) (xy 347.542866 -421.333676) (xy 346.679266 -421.333676)
			(xy 346.652014 -421.333252) (xy 346.598065 -421.325491) (xy 346.54577 -421.310131) (xy 346.496193 -421.287486)
			(xy 346.450343 -421.258017) (xy 346.409154 -421.222322) (xy 346.373463 -421.181129) (xy 346.343997 -421.135277)
			(xy 346.321357 -421.085698) (xy 346.306002 -421.033401) (xy 346.298246 -420.979452) (xy 344.860589 -420.979452)
			(xy 344.852835 -421.033389) (xy 344.837482 -421.085677) (xy 344.814845 -421.135248) (xy 344.785384 -421.181093)
			(xy 344.749698 -421.222279) (xy 344.708514 -421.257968) (xy 344.662671 -421.287432) (xy 344.613101 -421.310073)
			(xy 344.560814 -421.325429) (xy 344.506874 -421.333188) (xy 344.479626 -421.333676) (xy 343.616026 -421.333676)
			(xy 343.58877 -421.333279) (xy 343.534811 -421.325524) (xy 343.482506 -421.310169) (xy 343.432918 -421.287526)
			(xy 343.387058 -421.258056) (xy 343.345859 -421.22236) (xy 343.310159 -421.181163) (xy 343.280686 -421.135305)
			(xy 343.25804 -421.085719) (xy 343.242681 -421.033414) (xy 343.234923 -420.979456) (xy 341.797412 -420.979456)
			(xy 341.789656 -421.033399) (xy 341.774301 -421.085693) (xy 341.751659 -421.13527) (xy 341.722192 -421.18112)
			(xy 341.6865 -421.22231) (xy 341.645309 -421.258001) (xy 341.599458 -421.287466) (xy 341.54988 -421.310105)
			(xy 341.497585 -421.325459) (xy 341.443637 -421.333214) (xy 341.416386 -421.333676) (xy 340.552786 -421.333676)
			(xy 340.525533 -421.333253) (xy 340.471582 -421.325494) (xy 340.419285 -421.310137) (xy 340.369705 -421.287493)
			(xy 340.323853 -421.258024) (xy 340.282661 -421.222329) (xy 340.246968 -421.181136) (xy 340.2175 -421.135282)
			(xy 340.194858 -421.085702) (xy 340.179503 -421.033404) (xy 340.171746 -420.979453) (xy 338.734089 -420.979453)
			(xy 338.726335 -421.033386) (xy 338.710984 -421.085673) (xy 338.688348 -421.135243) (xy 338.658888 -421.181087)
			(xy 338.623205 -421.222272) (xy 338.582024 -421.257961) (xy 338.536183 -421.287426) (xy 338.486616 -421.310068)
			(xy 338.434331 -421.325425) (xy 338.380393 -421.333187) (xy 338.353146 -421.333676) (xy 337.489546 -421.333676)
			(xy 337.462289 -421.33328) (xy 337.408328 -421.325528) (xy 337.35602 -421.310175) (xy 337.30643 -421.287533)
			(xy 337.260567 -421.258063) (xy 337.219366 -421.222367) (xy 337.183664 -421.181169) (xy 337.154189 -421.13531)
			(xy 337.131542 -421.085723) (xy 337.116182 -421.033417) (xy 337.108423 -420.979457) (xy 335.670889 -420.979457)
			(xy 335.663134 -421.033391) (xy 335.647781 -421.085681) (xy 335.625142 -421.135254) (xy 335.595679 -421.1811)
			(xy 335.559991 -421.222287) (xy 335.518805 -421.257975) (xy 335.472959 -421.287439) (xy 335.423387 -421.310079)
			(xy 335.371097 -421.325433) (xy 335.317155 -421.333189) (xy 335.289906 -421.333676) (xy 334.426306 -421.333676)
			(xy 334.399051 -421.333277) (xy 334.345094 -421.325521) (xy 334.292791 -421.310164) (xy 334.243206 -421.28752)
			(xy 334.197349 -421.258049) (xy 334.156152 -421.222353) (xy 334.120454 -421.181156) (xy 334.090983 -421.135299)
			(xy 334.068338 -421.085714) (xy 334.052981 -421.033411) (xy 334.045223 -420.979455) (xy 332.607713 -420.979455)
			(xy 332.599955 -421.033402) (xy 332.584599 -421.085698) (xy 332.561956 -421.135276) (xy 332.532487 -421.181127)
			(xy 332.496793 -421.222317) (xy 332.4556 -421.258008) (xy 332.409746 -421.287472) (xy 332.360166 -421.310111)
			(xy 332.307868 -421.325463) (xy 332.253918 -421.333215) (xy 332.226666 -421.333676) (xy 331.363066 -421.333676)
			(xy 331.335814 -421.333252) (xy 331.281865 -421.325491) (xy 331.22957 -421.310131) (xy 331.179993 -421.287486)
			(xy 331.134143 -421.258017) (xy 331.092954 -421.222322) (xy 331.057263 -421.181129) (xy 331.027797 -421.135277)
			(xy 331.005157 -421.085698) (xy 330.989802 -421.033401) (xy 330.982046 -420.979452) (xy 329.544389 -420.979452)
			(xy 329.536635 -421.033389) (xy 329.521282 -421.085677) (xy 329.498645 -421.135248) (xy 329.469184 -421.181093)
			(xy 329.433498 -421.222279) (xy 329.392314 -421.257968) (xy 329.346471 -421.287432) (xy 329.296901 -421.310073)
			(xy 329.244614 -421.325429) (xy 329.190674 -421.333188) (xy 329.163426 -421.333676) (xy 328.299826 -421.333676)
			(xy 328.27257 -421.333279) (xy 328.218611 -421.325524) (xy 328.166306 -421.310169) (xy 328.116718 -421.287526)
			(xy 328.070858 -421.258056) (xy 328.029659 -421.22236) (xy 327.993959 -421.181163) (xy 327.964486 -421.135305)
			(xy 327.94184 -421.085719) (xy 327.926481 -421.033414) (xy 327.918723 -420.979456) (xy 326.481212 -420.979456)
			(xy 326.473456 -421.033399) (xy 326.458101 -421.085693) (xy 326.435459 -421.13527) (xy 326.405992 -421.18112)
			(xy 326.3703 -421.22231) (xy 326.329109 -421.258001) (xy 326.283258 -421.287466) (xy 326.23368 -421.310105)
			(xy 326.181385 -421.325459) (xy 326.127437 -421.333214) (xy 326.100186 -421.333676) (xy 325.236586 -421.333676)
			(xy 325.209333 -421.333253) (xy 325.155382 -421.325494) (xy 325.103085 -421.310137) (xy 325.053505 -421.287493)
			(xy 325.007653 -421.258024) (xy 324.966461 -421.222329) (xy 324.930768 -421.181136) (xy 324.9013 -421.135282)
			(xy 324.878658 -421.085702) (xy 324.863303 -421.033404) (xy 324.855546 -420.979453) (xy 323.417889 -420.979453)
			(xy 323.410135 -421.033386) (xy 323.394784 -421.085673) (xy 323.372148 -421.135243) (xy 323.342688 -421.181087)
			(xy 323.307005 -421.222272) (xy 323.265824 -421.257961) (xy 323.219983 -421.287426) (xy 323.170416 -421.310068)
			(xy 323.118131 -421.325425) (xy 323.064193 -421.333187) (xy 323.036946 -421.333676) (xy 322.173346 -421.333676)
			(xy 322.146089 -421.33328) (xy 322.092128 -421.325528) (xy 322.03982 -421.310175) (xy 321.99023 -421.287533)
			(xy 321.944367 -421.258063) (xy 321.903166 -421.222367) (xy 321.867464 -421.181169) (xy 321.837989 -421.13531)
			(xy 321.815342 -421.085723) (xy 321.799982 -421.033417) (xy 321.792223 -420.979457) (xy 320.354689 -420.979457)
			(xy 320.346934 -421.033391) (xy 320.331581 -421.085681) (xy 320.308942 -421.135254) (xy 320.279479 -421.1811)
			(xy 320.243791 -421.222287) (xy 320.202605 -421.257975) (xy 320.156759 -421.287439) (xy 320.107187 -421.310079)
			(xy 320.054897 -421.325433) (xy 320.000955 -421.333189) (xy 319.973706 -421.333676) (xy 319.110106 -421.333676)
			(xy 319.082851 -421.333277) (xy 319.028894 -421.325521) (xy 318.976591 -421.310164) (xy 318.927006 -421.28752)
			(xy 318.881149 -421.258049) (xy 318.839952 -421.222353) (xy 318.804254 -421.181156) (xy 318.774783 -421.135299)
			(xy 318.752138 -421.085714) (xy 318.736781 -421.033411) (xy 318.729023 -420.979455) (xy 317.291513 -420.979455)
			(xy 317.283755 -421.033402) (xy 317.268399 -421.085698) (xy 317.245756 -421.135276) (xy 317.216287 -421.181127)
			(xy 317.180593 -421.222317) (xy 317.1394 -421.258008) (xy 317.093546 -421.287472) (xy 317.043966 -421.310111)
			(xy 316.991668 -421.325463) (xy 316.937718 -421.333215) (xy 316.910466 -421.333676) (xy 316.046866 -421.333676)
			(xy 316.019614 -421.333252) (xy 315.965665 -421.325491) (xy 315.91337 -421.310131) (xy 315.863793 -421.287486)
			(xy 315.817943 -421.258017) (xy 315.776754 -421.222322) (xy 315.741063 -421.181129) (xy 315.711597 -421.135277)
			(xy 315.688957 -421.085698) (xy 315.673602 -421.033401) (xy 315.665846 -420.979452) (xy 314.228189 -420.979452)
			(xy 314.220435 -421.033389) (xy 314.205082 -421.085677) (xy 314.182445 -421.135248) (xy 314.152984 -421.181093)
			(xy 314.117298 -421.222279) (xy 314.076114 -421.257968) (xy 314.030271 -421.287432) (xy 313.980701 -421.310073)
			(xy 313.928414 -421.325429) (xy 313.874474 -421.333188) (xy 313.847226 -421.333676) (xy 312.983626 -421.333676)
			(xy 312.95637 -421.333279) (xy 312.902411 -421.325524) (xy 312.850106 -421.310169) (xy 312.800518 -421.287526)
			(xy 312.754658 -421.258056) (xy 312.713459 -421.22236) (xy 312.677759 -421.181163) (xy 312.648286 -421.135305)
			(xy 312.62564 -421.085719) (xy 312.610281 -421.033414) (xy 312.602523 -420.979456) (xy 311.165012 -420.979456)
			(xy 311.157256 -421.033399) (xy 311.141901 -421.085693) (xy 311.119259 -421.13527) (xy 311.089792 -421.18112)
			(xy 311.0541 -421.22231) (xy 311.012909 -421.258001) (xy 310.967058 -421.287466) (xy 310.91748 -421.310105)
			(xy 310.865185 -421.325459) (xy 310.811237 -421.333214) (xy 310.783986 -421.333676) (xy 309.920386 -421.333676)
			(xy 309.893133 -421.333253) (xy 309.839182 -421.325494) (xy 309.786885 -421.310137) (xy 309.737305 -421.287493)
			(xy 309.691453 -421.258024) (xy 309.650261 -421.222329) (xy 309.614568 -421.181136) (xy 309.5851 -421.135282)
			(xy 309.562458 -421.085702) (xy 309.547103 -421.033404) (xy 309.539346 -420.979453) (xy 308.101689 -420.979453)
			(xy 308.093935 -421.033386) (xy 308.078584 -421.085673) (xy 308.055948 -421.135243) (xy 308.026488 -421.181087)
			(xy 307.990805 -421.222272) (xy 307.949624 -421.257961) (xy 307.903783 -421.287426) (xy 307.854216 -421.310068)
			(xy 307.801931 -421.325425) (xy 307.747993 -421.333187) (xy 307.720746 -421.333676) (xy 306.857146 -421.333676)
			(xy 306.829889 -421.33328) (xy 306.775928 -421.325528) (xy 306.72362 -421.310175) (xy 306.67403 -421.287533)
			(xy 306.628167 -421.258063) (xy 306.586966 -421.222367) (xy 306.551264 -421.181169) (xy 306.521789 -421.13531)
			(xy 306.499142 -421.085723) (xy 306.483782 -421.033417) (xy 306.476023 -420.979457) (xy 305.038489 -420.979457)
			(xy 305.030734 -421.033391) (xy 305.015381 -421.085681) (xy 304.992742 -421.135254) (xy 304.963279 -421.1811)
			(xy 304.927591 -421.222287) (xy 304.886405 -421.257975) (xy 304.840559 -421.287439) (xy 304.790987 -421.310079)
			(xy 304.738697 -421.325433) (xy 304.684755 -421.333189) (xy 304.657506 -421.333676) (xy 303.793906 -421.333676)
			(xy 303.766651 -421.333277) (xy 303.712694 -421.325521) (xy 303.660391 -421.310164) (xy 303.610806 -421.28752)
			(xy 303.564949 -421.258049) (xy 303.523752 -421.222353) (xy 303.488054 -421.181156) (xy 303.458583 -421.135299)
			(xy 303.435938 -421.085714) (xy 303.420581 -421.033411) (xy 303.412823 -420.979455) (xy 231.647383 -420.979455)
			(xy 230.329486 -422.297352) (xy 230.322673 -422.304773) (xy 230.314938 -422.323356) (xy 230.3145 -422.33342)
			(xy 230.3145 -422.354375) (xy 285.567772 -422.354375) (xy 285.567772 -422.299825) (xy 285.575535 -422.245831)
			(xy 285.590905 -422.193491) (xy 285.613567 -422.143872) (xy 285.64306 -422.097983) (xy 285.678784 -422.056759)
			(xy 285.720012 -422.021038) (xy 285.765903 -421.991549) (xy 285.815525 -421.968892) (xy 285.867866 -421.953528)
			(xy 285.921861 -421.945769) (xy 285.949136 -421.945308) (xy 286.812736 -421.945308) (xy 286.840002 -421.945857)
			(xy 286.893977 -421.953622) (xy 286.946298 -421.968989) (xy 286.9959 -421.991646) (xy 287.041773 -422.02113)
			(xy 287.082983 -422.056843) (xy 287.118691 -422.098056) (xy 287.148172 -422.143932) (xy 287.170823 -422.193536)
			(xy 287.186186 -422.245858) (xy 287.193946 -422.299834) (xy 287.193946 -422.354366) (xy 287.186186 -422.408342)
			(xy 287.170823 -422.460664) (xy 287.148172 -422.510268) (xy 287.118691 -422.556144) (xy 287.082983 -422.597357)
			(xy 287.041773 -422.63307) (xy 286.9959 -422.662554) (xy 286.946298 -422.685211) (xy 286.893977 -422.700578)
			(xy 286.840002 -422.708343) (xy 286.812736 -422.708832) (xy 285.949136 -422.708832) (xy 285.921861 -422.708431)
			(xy 285.867866 -422.700672) (xy 285.815525 -422.685308) (xy 285.765903 -422.662651) (xy 285.720012 -422.633162)
			(xy 285.678784 -422.597441) (xy 285.64306 -422.556217) (xy 285.613567 -422.510328) (xy 285.590905 -422.460709)
			(xy 285.575535 -422.408369) (xy 285.567772 -422.354375) (xy 230.3145 -422.354375) (xy 230.3145 -424.80464)
			(xy 357.679233 -424.80464) (xy 357.679233 -424.6755) (xy 357.687183 -424.546605) (xy 357.703053 -424.418445)
			(xy 357.726782 -424.291504) (xy 357.758281 -424.166265) (xy 357.79743 -424.043202) (xy 357.844081 -423.922783)
			(xy 357.898056 -423.805464) (xy 357.959151 -423.69169) (xy 358.027134 -423.581893) (xy 358.101748 -423.47649)
			(xy 358.182709 -423.37588) (xy 358.269709 -423.280445) (xy 358.36242 -423.190546) (xy 358.46049 -423.106525)
			(xy 358.563545 -423.028701) (xy 358.671196 -422.957369) (xy 358.783035 -422.892799) (xy 358.898636 -422.835237)
			(xy 359.017561 -422.7849) (xy 359.13936 -422.74198) (xy 359.26357 -422.706639) (xy 359.389719 -422.679012)
			(xy 359.517331 -422.659203) (xy 359.64592 -422.647287) (xy 359.774998 -422.643311) (xy 359.904076 -422.647287)
			(xy 360.032665 -422.659203) (xy 360.160277 -422.679012) (xy 360.222212 -422.692576) (xy 365.310928 -422.692576)
			(xy 365.310928 -415.898584) (xy 365.3113 -415.888356) (xy 365.319137 -415.86946) (xy 365.33361 -415.855003)
			(xy 365.352515 -415.847188) (xy 365.362744 -415.846768) (xy 370.261388 -415.846768) (xy 370.271593 -415.847291)
			(xy 370.290451 -415.855097) (xy 370.304887 -415.869525) (xy 370.312703 -415.888379) (xy 370.313204 -415.898584)
			(xy 370.313204 -417.242244) (xy 372.208044 -417.242244) (xy 372.208044 -416.556444) (xy 372.208601 -416.544376)
			(xy 372.216045 -416.521419) (xy 372.23022 -416.501885) (xy 372.249736 -416.487687) (xy 372.272685 -416.480215)
			(xy 372.284752 -416.479736) (xy 372.479316 -416.479736) (xy 372.49042 -416.480128) (xy 372.511712 -416.486444)
			(xy 372.521226 -416.492182) (xy 372.81485 -416.684714) (xy 372.824199 -416.690479) (xy 372.845228 -416.696801)
			(xy 372.867187 -416.696857) (xy 372.888248 -416.690643) (xy 372.897654 -416.684968) (xy 373.193818 -416.492182)
			(xy 373.203317 -416.486412) (xy 373.224619 -416.4801) (xy 373.235728 -416.479736) (xy 373.430292 -416.479736)
			(xy 373.442379 -416.48012) (xy 373.465369 -416.487591) (xy 373.484923 -416.501803) (xy 373.499126 -416.521364)
			(xy 373.506586 -416.544357) (xy 373.507 -416.556444) (xy 373.507 -417.242244) (xy 375.271284 -417.242244)
			(xy 375.271284 -416.556444) (xy 375.27175 -416.544364) (xy 375.279204 -416.521384) (xy 375.293397 -416.501834)
			(xy 375.312938 -416.487628) (xy 375.335913 -416.480158) (xy 375.347992 -416.479736) (xy 375.542556 -416.479736)
			(xy 375.553661 -416.480112) (xy 375.574953 -416.486439) (xy 375.584466 -416.492182) (xy 375.87809 -416.684714)
			(xy 375.887467 -416.690428) (xy 375.908483 -416.696761) (xy 375.930432 -416.696831) (xy 375.951488 -416.690634)
			(xy 375.960894 -416.684968) (xy 376.257058 -416.492182) (xy 376.266569 -416.486434) (xy 376.287862 -416.480109)
			(xy 376.298968 -416.479736) (xy 376.493532 -416.479736) (xy 376.505621 -416.480086) (xy 376.528612 -416.487568)
			(xy 376.548166 -416.501789) (xy 376.562367 -416.521356) (xy 376.569826 -416.544355) (xy 376.57024 -416.556444)
			(xy 376.57024 -417.242244) (xy 378.334524 -417.242244) (xy 378.334524 -416.556444) (xy 378.334951 -416.54436)
			(xy 378.34241 -416.521374) (xy 378.356611 -416.50182) (xy 378.376163 -416.487615) (xy 378.399148 -416.480153)
			(xy 378.411232 -416.479736) (xy 378.605796 -416.479736) (xy 378.616903 -416.480096) (xy 378.638194 -416.486434)
			(xy 378.647706 -416.492182) (xy 378.94133 -416.684714) (xy 378.950689 -416.690462) (xy 378.971713 -416.696787)
			(xy 378.993669 -416.696848) (xy 379.014728 -416.69064) (xy 379.024134 -416.684968) (xy 379.320298 -416.492182)
			(xy 379.329801 -416.48642) (xy 379.3511 -416.480103) (xy 379.362208 -416.479736) (xy 379.556772 -416.479736)
			(xy 379.568858 -416.480137) (xy 379.591847 -416.487602) (xy 379.611401 -416.50181) (xy 379.625605 -416.521367)
			(xy 379.633065 -416.544358) (xy 379.63348 -416.556444) (xy 379.63348 -417.242244) (xy 381.397764 -417.242244)
			(xy 381.397764 -416.556444) (xy 381.39825 -416.544366) (xy 381.405702 -416.52139) (xy 381.41989 -416.501841)
			(xy 381.439425 -416.487635) (xy 381.462395 -416.480161) (xy 381.474472 -416.479736) (xy 381.669036 -416.479736)
			(xy 381.680141 -416.48012) (xy 381.701433 -416.486441) (xy 381.710946 -416.492182) (xy 382.00457 -416.684714)
			(xy 382.013957 -416.690411) (xy 382.034968 -416.696748) (xy 382.056914 -416.696823) (xy 382.077968 -416.690631)
			(xy 382.087374 -416.684968) (xy 382.383538 -416.492182) (xy 382.393053 -416.486442) (xy 382.414343 -416.480111)
			(xy 382.425448 -416.479736) (xy 382.620012 -416.479736) (xy 382.6321 -416.480103) (xy 382.65509 -416.487579)
			(xy 382.674644 -416.501796) (xy 382.688846 -416.52136) (xy 382.696306 -416.544356) (xy 382.69672 -416.556444)
			(xy 382.69672 -417.242244) (xy 384.461004 -417.242244) (xy 384.461004 -416.556444) (xy 384.46145 -416.544362)
			(xy 384.468907 -416.521379) (xy 384.483104 -416.501827) (xy 384.50265 -416.487622) (xy 384.525631 -416.480155)
			(xy 384.537712 -416.479736) (xy 384.732276 -416.479736) (xy 384.743382 -416.480104) (xy 384.764674 -416.486437)
			(xy 384.774186 -416.492182) (xy 385.06781 -416.684714) (xy 385.077178 -416.690445) (xy 385.098198 -416.696774)
			(xy 385.12015 -416.69684) (xy 385.141208 -416.690637) (xy 385.150614 -416.684968) (xy 385.446778 -416.492182)
			(xy 385.456285 -416.486427) (xy 385.477581 -416.480106) (xy 385.488688 -416.479736) (xy 385.683252 -416.479736)
			(xy 385.695337 -416.480154) (xy 385.718325 -416.487614) (xy 385.73788 -416.501817) (xy 385.752084 -416.521371)
			(xy 385.759545 -416.544359) (xy 385.75996 -416.556444) (xy 385.75996 -417.242244) (xy 387.524244 -417.242244)
			(xy 387.524244 -416.556444) (xy 387.524801 -416.544376) (xy 387.532245 -416.521419) (xy 387.54642 -416.501885)
			(xy 387.565936 -416.487687) (xy 387.588885 -416.480215) (xy 387.600952 -416.479736) (xy 387.795516 -416.479736)
			(xy 387.80662 -416.480128) (xy 387.827912 -416.486444) (xy 387.837426 -416.492182) (xy 388.13105 -416.684714)
			(xy 388.140399 -416.690479) (xy 388.161428 -416.696801) (xy 388.183387 -416.696857) (xy 388.204448 -416.690643)
			(xy 388.213854 -416.684968) (xy 388.510018 -416.492182) (xy 388.519517 -416.486412) (xy 388.540819 -416.4801)
			(xy 388.551928 -416.479736) (xy 388.746492 -416.479736) (xy 388.758579 -416.48012) (xy 388.781569 -416.487591)
			(xy 388.801123 -416.501803) (xy 388.815326 -416.521364) (xy 388.822786 -416.544357) (xy 388.8232 -416.556444)
			(xy 388.8232 -417.242244) (xy 390.587484 -417.242244) (xy 390.587484 -416.556444) (xy 390.58795 -416.544364)
			(xy 390.595404 -416.521384) (xy 390.609597 -416.501834) (xy 390.629138 -416.487628) (xy 390.652113 -416.480158)
			(xy 390.664192 -416.479736) (xy 390.858756 -416.479736) (xy 390.869861 -416.480112) (xy 390.891153 -416.486439)
			(xy 390.900666 -416.492182) (xy 391.19429 -416.684714) (xy 391.203667 -416.690428) (xy 391.224683 -416.696761)
			(xy 391.246632 -416.696831) (xy 391.267688 -416.690634) (xy 391.277094 -416.684968) (xy 391.573258 -416.492182)
			(xy 391.582769 -416.486434) (xy 391.604062 -416.480109) (xy 391.615168 -416.479736) (xy 391.809732 -416.479736)
			(xy 391.821821 -416.480086) (xy 391.844812 -416.487568) (xy 391.864366 -416.501789) (xy 391.878567 -416.521356)
			(xy 391.886026 -416.544355) (xy 391.88644 -416.556444) (xy 391.88644 -417.242244) (xy 393.650724 -417.242244)
			(xy 393.650724 -416.556444) (xy 393.651151 -416.54436) (xy 393.65861 -416.521374) (xy 393.672811 -416.50182)
			(xy 393.692363 -416.487615) (xy 393.715348 -416.480153) (xy 393.727432 -416.479736) (xy 393.921996 -416.479736)
			(xy 393.933103 -416.480096) (xy 393.954394 -416.486434) (xy 393.963906 -416.492182) (xy 394.25753 -416.684714)
			(xy 394.266889 -416.690462) (xy 394.287913 -416.696787) (xy 394.309869 -416.696848) (xy 394.330928 -416.69064)
			(xy 394.340334 -416.684968) (xy 394.636498 -416.492182) (xy 394.646001 -416.48642) (xy 394.6673 -416.480103)
			(xy 394.678408 -416.479736) (xy 394.872972 -416.479736) (xy 394.885058 -416.480137) (xy 394.908047 -416.487602)
			(xy 394.927601 -416.50181) (xy 394.941805 -416.521367) (xy 394.949265 -416.544358) (xy 394.94968 -416.556444)
			(xy 394.94968 -417.242244) (xy 396.713964 -417.242244) (xy 396.713964 -416.556444) (xy 396.71445 -416.544366)
			(xy 396.721902 -416.52139) (xy 396.73609 -416.501841) (xy 396.755625 -416.487635) (xy 396.778595 -416.480161)
			(xy 396.790672 -416.479736) (xy 396.985236 -416.479736) (xy 396.996341 -416.48012) (xy 397.017633 -416.486441)
			(xy 397.027146 -416.492182) (xy 397.32077 -416.684714) (xy 397.330157 -416.690411) (xy 397.351168 -416.696748)
			(xy 397.373114 -416.696823) (xy 397.394168 -416.690631) (xy 397.403574 -416.684968) (xy 397.699738 -416.492182)
			(xy 397.709253 -416.486442) (xy 397.730543 -416.480111) (xy 397.741648 -416.479736) (xy 397.936212 -416.479736)
			(xy 397.9483 -416.480103) (xy 397.97129 -416.487579) (xy 397.990844 -416.501796) (xy 398.005046 -416.52136)
			(xy 398.012506 -416.544356) (xy 398.01292 -416.556444) (xy 398.01292 -417.242244) (xy 399.777204 -417.242244)
			(xy 399.777204 -416.556444) (xy 399.77765 -416.544362) (xy 399.785107 -416.521379) (xy 399.799304 -416.501827)
			(xy 399.81885 -416.487622) (xy 399.841831 -416.480155) (xy 399.853912 -416.479736) (xy 400.048476 -416.479736)
			(xy 400.059582 -416.480104) (xy 400.080874 -416.486437) (xy 400.090386 -416.492182) (xy 400.38401 -416.684714)
			(xy 400.393378 -416.690445) (xy 400.414398 -416.696774) (xy 400.43635 -416.69684) (xy 400.457408 -416.690637)
			(xy 400.466814 -416.684968) (xy 400.762978 -416.492182) (xy 400.772485 -416.486427) (xy 400.793781 -416.480106)
			(xy 400.804888 -416.479736) (xy 400.999452 -416.479736) (xy 401.011537 -416.480154) (xy 401.034525 -416.487614)
			(xy 401.05408 -416.501817) (xy 401.068284 -416.521371) (xy 401.075745 -416.544359) (xy 401.07616 -416.556444)
			(xy 401.07616 -417.242244) (xy 402.840444 -417.242244) (xy 402.840444 -416.556444) (xy 402.841001 -416.544376)
			(xy 402.848445 -416.521419) (xy 402.86262 -416.501885) (xy 402.882136 -416.487687) (xy 402.905085 -416.480215)
			(xy 402.917152 -416.479736) (xy 403.111716 -416.479736) (xy 403.12282 -416.480128) (xy 403.144112 -416.486444)
			(xy 403.153626 -416.492182) (xy 403.44725 -416.684714) (xy 403.456599 -416.690479) (xy 403.477628 -416.696801)
			(xy 403.499587 -416.696857) (xy 403.520648 -416.690643) (xy 403.530054 -416.684968) (xy 403.826218 -416.492182)
			(xy 403.835717 -416.486412) (xy 403.857019 -416.4801) (xy 403.868128 -416.479736) (xy 404.062692 -416.479736)
			(xy 404.074779 -416.48012) (xy 404.097769 -416.487591) (xy 404.117323 -416.501803) (xy 404.131526 -416.521364)
			(xy 404.138986 -416.544357) (xy 404.1394 -416.556444) (xy 404.1394 -417.242244) (xy 405.903684 -417.242244)
			(xy 405.903684 -416.556444) (xy 405.90415 -416.544364) (xy 405.911604 -416.521384) (xy 405.925797 -416.501834)
			(xy 405.945338 -416.487628) (xy 405.968313 -416.480158) (xy 405.980392 -416.479736) (xy 406.174956 -416.479736)
			(xy 406.186061 -416.480112) (xy 406.207353 -416.486439) (xy 406.216866 -416.492182) (xy 406.51049 -416.684714)
			(xy 406.519867 -416.690428) (xy 406.540883 -416.696761) (xy 406.562832 -416.696831) (xy 406.583888 -416.690634)
			(xy 406.593294 -416.684968) (xy 406.889458 -416.492182) (xy 406.898969 -416.486434) (xy 406.920262 -416.480109)
			(xy 406.931368 -416.479736) (xy 407.125932 -416.479736) (xy 407.138021 -416.480086) (xy 407.161012 -416.487568)
			(xy 407.180566 -416.501789) (xy 407.194767 -416.521356) (xy 407.202226 -416.544355) (xy 407.20264 -416.556444)
			(xy 407.20264 -417.242244) (xy 408.966924 -417.242244) (xy 408.966924 -416.556444) (xy 408.967351 -416.54436)
			(xy 408.97481 -416.521374) (xy 408.989011 -416.50182) (xy 409.008563 -416.487615) (xy 409.031548 -416.480153)
			(xy 409.043632 -416.479736) (xy 409.238196 -416.479736) (xy 409.249303 -416.480096) (xy 409.270594 -416.486434)
			(xy 409.280106 -416.492182) (xy 409.57373 -416.684714) (xy 409.583089 -416.690462) (xy 409.604113 -416.696787)
			(xy 409.626069 -416.696848) (xy 409.647128 -416.69064) (xy 409.656534 -416.684968) (xy 409.952698 -416.492182)
			(xy 409.962201 -416.48642) (xy 409.9835 -416.480103) (xy 409.994608 -416.479736) (xy 410.189172 -416.479736)
			(xy 410.201258 -416.480137) (xy 410.224247 -416.487602) (xy 410.243801 -416.50181) (xy 410.258005 -416.521367)
			(xy 410.265465 -416.544358) (xy 410.26588 -416.556444) (xy 410.26588 -417.242244) (xy 412.030164 -417.242244)
			(xy 412.030164 -416.556444) (xy 412.03065 -416.544366) (xy 412.038102 -416.52139) (xy 412.05229 -416.501841)
			(xy 412.071825 -416.487635) (xy 412.094795 -416.480161) (xy 412.106872 -416.479736) (xy 412.301436 -416.479736)
			(xy 412.312541 -416.48012) (xy 412.333833 -416.486441) (xy 412.343346 -416.492182) (xy 412.63697 -416.684714)
			(xy 412.646357 -416.690411) (xy 412.667368 -416.696748) (xy 412.689314 -416.696823) (xy 412.710368 -416.690631)
			(xy 412.719774 -416.684968) (xy 413.015938 -416.492182) (xy 413.025453 -416.486442) (xy 413.046743 -416.480111)
			(xy 413.057848 -416.479736) (xy 413.252412 -416.479736) (xy 413.2645 -416.480103) (xy 413.28749 -416.487579)
			(xy 413.307044 -416.501796) (xy 413.321246 -416.52136) (xy 413.328706 -416.544356) (xy 413.32912 -416.556444)
			(xy 413.32912 -417.242244) (xy 415.093404 -417.242244) (xy 415.093404 -416.556444) (xy 415.09385 -416.544362)
			(xy 415.101307 -416.521379) (xy 415.115504 -416.501827) (xy 415.13505 -416.487622) (xy 415.158031 -416.480155)
			(xy 415.170112 -416.479736) (xy 415.364676 -416.479736) (xy 415.375782 -416.480104) (xy 415.397074 -416.486437)
			(xy 415.406586 -416.492182) (xy 415.70021 -416.684714) (xy 415.709578 -416.690445) (xy 415.730598 -416.696774)
			(xy 415.75255 -416.69684) (xy 415.773608 -416.690637) (xy 415.783014 -416.684968) (xy 416.079178 -416.492182)
			(xy 416.088685 -416.486427) (xy 416.109981 -416.480106) (xy 416.121088 -416.479736) (xy 416.315652 -416.479736)
			(xy 416.327737 -416.480154) (xy 416.350725 -416.487614) (xy 416.37028 -416.501817) (xy 416.384484 -416.521371)
			(xy 416.391945 -416.544359) (xy 416.39236 -416.556444) (xy 416.39236 -417.242244) (xy 418.156644 -417.242244)
			(xy 418.156644 -416.556444) (xy 418.157201 -416.544376) (xy 418.164645 -416.521419) (xy 418.17882 -416.501885)
			(xy 418.198336 -416.487687) (xy 418.221285 -416.480215) (xy 418.233352 -416.479736) (xy 418.427916 -416.479736)
			(xy 418.43902 -416.480128) (xy 418.460312 -416.486444) (xy 418.469826 -416.492182) (xy 418.76345 -416.684714)
			(xy 418.772799 -416.690479) (xy 418.793828 -416.696801) (xy 418.815787 -416.696857) (xy 418.836848 -416.690643)
			(xy 418.846254 -416.684968) (xy 419.142418 -416.492182) (xy 419.151917 -416.486412) (xy 419.173219 -416.4801)
			(xy 419.184328 -416.479736) (xy 419.378892 -416.479736) (xy 419.390979 -416.48012) (xy 419.413969 -416.487591)
			(xy 419.433523 -416.501803) (xy 419.447726 -416.521364) (xy 419.455186 -416.544357) (xy 419.4556 -416.556444)
			(xy 419.4556 -417.242244) (xy 419.455173 -417.254322) (xy 419.447698 -417.277292) (xy 419.433492 -417.296829)
			(xy 419.413945 -417.311021) (xy 419.39097 -417.318481) (xy 419.378892 -417.318952) (xy 419.184328 -417.318952)
			(xy 419.173219 -417.318606) (xy 419.151922 -417.31227) (xy 419.142418 -417.306506) (xy 418.847524 -417.113974)
			(xy 418.838137 -417.108271) (xy 418.817099 -417.101998) (xy 418.795145 -417.101998) (xy 418.774107 -417.108271)
			(xy 418.76472 -417.113974) (xy 418.471096 -417.306506) (xy 418.461594 -417.31227) (xy 418.440294 -417.318586)
			(xy 418.429186 -417.318952) (xy 418.233352 -417.318952) (xy 418.221279 -417.318478) (xy 418.198318 -417.311007)
			(xy 418.178786 -417.296812) (xy 418.164591 -417.277278) (xy 418.157122 -417.254317) (xy 418.156644 -417.242244)
			(xy 416.39236 -417.242244) (xy 416.392024 -417.254334) (xy 416.384539 -417.277326) (xy 416.370314 -417.29688)
			(xy 416.350744 -417.311081) (xy 416.327742 -417.318539) (xy 416.315652 -417.318952) (xy 416.121088 -417.318952)
			(xy 416.109981 -417.318582) (xy 416.088684 -417.312262) (xy 416.079178 -417.306506) (xy 415.784284 -417.113974)
			(xy 415.774897 -417.108271) (xy 415.753859 -417.101998) (xy 415.731905 -417.101998) (xy 415.710867 -417.108271)
			(xy 415.70148 -417.113974) (xy 415.407856 -417.306506) (xy 415.398342 -417.312247) (xy 415.377051 -417.318577)
			(xy 415.365946 -417.318952) (xy 415.170112 -417.318952) (xy 415.158042 -417.318426) (xy 415.135083 -417.310972)
			(xy 415.11555 -417.29679) (xy 415.101353 -417.277267) (xy 415.093883 -417.254313) (xy 415.093404 -417.242244)
			(xy 413.32912 -417.242244) (xy 413.328674 -417.25432) (xy 413.3212 -417.277286) (xy 413.306999 -417.296822)
			(xy 413.287458 -417.311015) (xy 413.264488 -417.318479) (xy 413.252412 -417.318952) (xy 413.057848 -417.318952)
			(xy 413.046739 -417.318598) (xy 413.025443 -417.312267) (xy 413.015938 -417.306506) (xy 412.721044 -417.113974)
			(xy 412.711657 -417.108271) (xy 412.690619 -417.101998) (xy 412.668665 -417.101998) (xy 412.647627 -417.108271)
			(xy 412.63824 -417.113974) (xy 412.344616 -417.306506) (xy 412.33511 -417.312262) (xy 412.313813 -417.318583)
			(xy 412.302706 -417.318952) (xy 412.106872 -417.318952) (xy 412.0948 -417.318461) (xy 412.07184 -417.310996)
			(xy 412.052307 -417.296805) (xy 412.038112 -417.277275) (xy 412.030642 -417.254316) (xy 412.030164 -417.242244)
			(xy 410.26588 -417.242244) (xy 410.265473 -417.254324) (xy 410.257995 -417.277297) (xy 410.243785 -417.296836)
			(xy 410.224232 -417.311028) (xy 410.201252 -417.318484) (xy 410.189172 -417.318952) (xy 409.994608 -417.318952)
			(xy 409.983501 -417.318573) (xy 409.962205 -417.312259) (xy 409.952698 -417.306506) (xy 409.657804 -417.113974)
			(xy 409.648417 -417.108271) (xy 409.627379 -417.101998) (xy 409.605425 -417.101998) (xy 409.584387 -417.108271)
			(xy 409.575 -417.113974) (xy 409.281376 -417.306506) (xy 409.271858 -417.31224) (xy 409.250571 -417.318574)
			(xy 409.239466 -417.318952) (xy 409.043632 -417.318952) (xy 409.031563 -417.318409) (xy 409.008605 -417.310961)
			(xy 408.989071 -417.296783) (xy 408.974874 -417.277263) (xy 408.967403 -417.254312) (xy 408.966924 -417.242244)
			(xy 407.20264 -417.242244) (xy 407.202174 -417.254318) (xy 407.194703 -417.277281) (xy 407.180506 -417.296814)
			(xy 407.16097 -417.311009) (xy 407.138006 -417.318476) (xy 407.125932 -417.318952) (xy 406.931368 -417.318952)
			(xy 406.92026 -417.31859) (xy 406.898964 -417.312265) (xy 406.889458 -417.306506) (xy 406.594564 -417.113974)
			(xy 406.585177 -417.108271) (xy 406.564139 -417.101998) (xy 406.542185 -417.101998) (xy 406.521147 -417.108271)
			(xy 406.51176 -417.113974) (xy 406.218136 -417.306506) (xy 406.208626 -417.312255) (xy 406.187332 -417.31858)
			(xy 406.176226 -417.318952) (xy 405.980392 -417.318952) (xy 405.968321 -417.318443) (xy 405.945361 -417.310984)
			(xy 405.925828 -417.296797) (xy 405.911633 -417.277271) (xy 405.904162 -417.254314) (xy 405.903684 -417.242244)
			(xy 404.1394 -417.242244) (xy 404.138973 -417.254322) (xy 404.131498 -417.277292) (xy 404.117292 -417.296829)
			(xy 404.097745 -417.311021) (xy 404.07477 -417.318481) (xy 404.062692 -417.318952) (xy 403.868128 -417.318952)
			(xy 403.857019 -417.318606) (xy 403.835722 -417.31227) (xy 403.826218 -417.306506) (xy 403.531324 -417.113974)
			(xy 403.521937 -417.108271) (xy 403.500899 -417.101998) (xy 403.478945 -417.101998) (xy 403.457907 -417.108271)
			(xy 403.44852 -417.113974) (xy 403.154896 -417.306506) (xy 403.145394 -417.31227) (xy 403.124094 -417.318586)
			(xy 403.112986 -417.318952) (xy 402.917152 -417.318952) (xy 402.905079 -417.318478) (xy 402.882118 -417.311007)
			(xy 402.862586 -417.296812) (xy 402.848391 -417.277278) (xy 402.840922 -417.254317) (xy 402.840444 -417.242244)
			(xy 401.07616 -417.242244) (xy 401.075824 -417.254334) (xy 401.068339 -417.277326) (xy 401.054114 -417.29688)
			(xy 401.034544 -417.311081) (xy 401.011542 -417.318539) (xy 400.999452 -417.318952) (xy 400.804888 -417.318952)
			(xy 400.793781 -417.318582) (xy 400.772484 -417.312262) (xy 400.762978 -417.306506) (xy 400.468084 -417.113974)
			(xy 400.458697 -417.108271) (xy 400.437659 -417.101998) (xy 400.415705 -417.101998) (xy 400.394667 -417.108271)
			(xy 400.38528 -417.113974) (xy 400.091656 -417.306506) (xy 400.082142 -417.312247) (xy 400.060851 -417.318577)
			(xy 400.049746 -417.318952) (xy 399.853912 -417.318952) (xy 399.841842 -417.318426) (xy 399.818883 -417.310972)
			(xy 399.79935 -417.29679) (xy 399.785153 -417.277267) (xy 399.777683 -417.254313) (xy 399.777204 -417.242244)
			(xy 398.01292 -417.242244) (xy 398.012474 -417.25432) (xy 398.005 -417.277286) (xy 397.990799 -417.296822)
			(xy 397.971258 -417.311015) (xy 397.948288 -417.318479) (xy 397.936212 -417.318952) (xy 397.741648 -417.318952)
			(xy 397.730539 -417.318598) (xy 397.709243 -417.312267) (xy 397.699738 -417.306506) (xy 397.404844 -417.113974)
			(xy 397.395457 -417.108271) (xy 397.374419 -417.101998) (xy 397.352465 -417.101998) (xy 397.331427 -417.108271)
			(xy 397.32204 -417.113974) (xy 397.028416 -417.306506) (xy 397.01891 -417.312262) (xy 396.997613 -417.318583)
			(xy 396.986506 -417.318952) (xy 396.790672 -417.318952) (xy 396.7786 -417.318461) (xy 396.75564 -417.310996)
			(xy 396.736107 -417.296805) (xy 396.721912 -417.277275) (xy 396.714442 -417.254316) (xy 396.713964 -417.242244)
			(xy 394.94968 -417.242244) (xy 394.949273 -417.254324) (xy 394.941795 -417.277297) (xy 394.927585 -417.296836)
			(xy 394.908032 -417.311028) (xy 394.885052 -417.318484) (xy 394.872972 -417.318952) (xy 394.678408 -417.318952)
			(xy 394.667301 -417.318573) (xy 394.646005 -417.312259) (xy 394.636498 -417.306506) (xy 394.341604 -417.113974)
			(xy 394.332217 -417.108271) (xy 394.311179 -417.101998) (xy 394.289225 -417.101998) (xy 394.268187 -417.108271)
			(xy 394.2588 -417.113974) (xy 393.965176 -417.306506) (xy 393.955658 -417.31224) (xy 393.934371 -417.318574)
			(xy 393.923266 -417.318952) (xy 393.727432 -417.318952) (xy 393.715363 -417.318409) (xy 393.692405 -417.310961)
			(xy 393.672871 -417.296783) (xy 393.658674 -417.277263) (xy 393.651203 -417.254312) (xy 393.650724 -417.242244)
			(xy 391.88644 -417.242244) (xy 391.885974 -417.254318) (xy 391.878503 -417.277281) (xy 391.864306 -417.296814)
			(xy 391.84477 -417.311009) (xy 391.821806 -417.318476) (xy 391.809732 -417.318952) (xy 391.615168 -417.318952)
			(xy 391.60406 -417.31859) (xy 391.582764 -417.312265) (xy 391.573258 -417.306506) (xy 391.278364 -417.113974)
			(xy 391.268977 -417.108271) (xy 391.247939 -417.101998) (xy 391.225985 -417.101998) (xy 391.204947 -417.108271)
			(xy 391.19556 -417.113974) (xy 390.901936 -417.306506) (xy 390.892426 -417.312255) (xy 390.871132 -417.31858)
			(xy 390.860026 -417.318952) (xy 390.664192 -417.318952) (xy 390.652121 -417.318443) (xy 390.629161 -417.310984)
			(xy 390.609628 -417.296797) (xy 390.595433 -417.277271) (xy 390.587962 -417.254314) (xy 390.587484 -417.242244)
			(xy 388.8232 -417.242244) (xy 388.822773 -417.254322) (xy 388.815298 -417.277292) (xy 388.801092 -417.296829)
			(xy 388.781545 -417.311021) (xy 388.75857 -417.318481) (xy 388.746492 -417.318952) (xy 388.551928 -417.318952)
			(xy 388.540819 -417.318606) (xy 388.519522 -417.31227) (xy 388.510018 -417.306506) (xy 388.215124 -417.113974)
			(xy 388.205737 -417.108271) (xy 388.184699 -417.101998) (xy 388.162745 -417.101998) (xy 388.141707 -417.108271)
			(xy 388.13232 -417.113974) (xy 387.838696 -417.306506) (xy 387.829194 -417.31227) (xy 387.807894 -417.318586)
			(xy 387.796786 -417.318952) (xy 387.600952 -417.318952) (xy 387.588879 -417.318478) (xy 387.565918 -417.311007)
			(xy 387.546386 -417.296812) (xy 387.532191 -417.277278) (xy 387.524722 -417.254317) (xy 387.524244 -417.242244)
			(xy 385.75996 -417.242244) (xy 385.759624 -417.254334) (xy 385.752139 -417.277326) (xy 385.737914 -417.29688)
			(xy 385.718344 -417.311081) (xy 385.695342 -417.318539) (xy 385.683252 -417.318952) (xy 385.488688 -417.318952)
			(xy 385.477581 -417.318582) (xy 385.456284 -417.312262) (xy 385.446778 -417.306506) (xy 385.151884 -417.113974)
			(xy 385.142497 -417.108271) (xy 385.121459 -417.101998) (xy 385.099505 -417.101998) (xy 385.078467 -417.108271)
			(xy 385.06908 -417.113974) (xy 384.775456 -417.306506) (xy 384.765942 -417.312247) (xy 384.744651 -417.318577)
			(xy 384.733546 -417.318952) (xy 384.537712 -417.318952) (xy 384.525642 -417.318426) (xy 384.502683 -417.310972)
			(xy 384.48315 -417.29679) (xy 384.468953 -417.277267) (xy 384.461483 -417.254313) (xy 384.461004 -417.242244)
			(xy 382.69672 -417.242244) (xy 382.696274 -417.25432) (xy 382.6888 -417.277286) (xy 382.674599 -417.296822)
			(xy 382.655058 -417.311015) (xy 382.632088 -417.318479) (xy 382.620012 -417.318952) (xy 382.425448 -417.318952)
			(xy 382.414339 -417.318598) (xy 382.393043 -417.312267) (xy 382.383538 -417.306506) (xy 382.088644 -417.113974)
			(xy 382.079257 -417.108271) (xy 382.058219 -417.101998) (xy 382.036265 -417.101998) (xy 382.015227 -417.108271)
			(xy 382.00584 -417.113974) (xy 381.712216 -417.306506) (xy 381.70271 -417.312262) (xy 381.681413 -417.318583)
			(xy 381.670306 -417.318952) (xy 381.474472 -417.318952) (xy 381.4624 -417.318461) (xy 381.43944 -417.310996)
			(xy 381.419907 -417.296805) (xy 381.405712 -417.277275) (xy 381.398242 -417.254316) (xy 381.397764 -417.242244)
			(xy 379.63348 -417.242244) (xy 379.633073 -417.254324) (xy 379.625595 -417.277297) (xy 379.611385 -417.296836)
			(xy 379.591832 -417.311028) (xy 379.568852 -417.318484) (xy 379.556772 -417.318952) (xy 379.362208 -417.318952)
			(xy 379.351101 -417.318573) (xy 379.329805 -417.312259) (xy 379.320298 -417.306506) (xy 379.025404 -417.113974)
			(xy 379.016017 -417.108271) (xy 378.994979 -417.101998) (xy 378.973025 -417.101998) (xy 378.951987 -417.108271)
			(xy 378.9426 -417.113974) (xy 378.648976 -417.306506) (xy 378.639458 -417.31224) (xy 378.618171 -417.318574)
			(xy 378.607066 -417.318952) (xy 378.411232 -417.318952) (xy 378.399163 -417.318409) (xy 378.376205 -417.310961)
			(xy 378.356671 -417.296783) (xy 378.342474 -417.277263) (xy 378.335003 -417.254312) (xy 378.334524 -417.242244)
			(xy 376.57024 -417.242244) (xy 376.569774 -417.254318) (xy 376.562303 -417.277281) (xy 376.548106 -417.296814)
			(xy 376.52857 -417.311009) (xy 376.505606 -417.318476) (xy 376.493532 -417.318952) (xy 376.298968 -417.318952)
			(xy 376.28786 -417.31859) (xy 376.266564 -417.312265) (xy 376.257058 -417.306506) (xy 375.962164 -417.113974)
			(xy 375.952777 -417.108271) (xy 375.931739 -417.101998) (xy 375.909785 -417.101998) (xy 375.888747 -417.108271)
			(xy 375.87936 -417.113974) (xy 375.585736 -417.306506) (xy 375.576226 -417.312255) (xy 375.554932 -417.31858)
			(xy 375.543826 -417.318952) (xy 375.347992 -417.318952) (xy 375.335921 -417.318443) (xy 375.312961 -417.310984)
			(xy 375.293428 -417.296797) (xy 375.279233 -417.277271) (xy 375.271762 -417.254314) (xy 375.271284 -417.242244)
			(xy 373.507 -417.242244) (xy 373.506573 -417.254322) (xy 373.499098 -417.277292) (xy 373.484892 -417.296829)
			(xy 373.465345 -417.311021) (xy 373.44237 -417.318481) (xy 373.430292 -417.318952) (xy 373.235728 -417.318952)
			(xy 373.224619 -417.318606) (xy 373.203322 -417.31227) (xy 373.193818 -417.306506) (xy 372.898924 -417.113974)
			(xy 372.889537 -417.108271) (xy 372.868499 -417.101998) (xy 372.846545 -417.101998) (xy 372.825507 -417.108271)
			(xy 372.81612 -417.113974) (xy 372.522496 -417.306506) (xy 372.512994 -417.31227) (xy 372.491694 -417.318586)
			(xy 372.480586 -417.318952) (xy 372.284752 -417.318952) (xy 372.272679 -417.318478) (xy 372.249718 -417.311007)
			(xy 372.230186 -417.296812) (xy 372.215991 -417.277278) (xy 372.208522 -417.254317) (xy 372.208044 -417.242244)
			(xy 370.313204 -417.242244) (xy 370.313204 -418.439456) (xy 372.044623 -418.439456) (xy 372.044623 -418.384944)
			(xy 372.052381 -418.330986) (xy 372.06774 -418.278682) (xy 372.090386 -418.229097) (xy 372.119858 -418.183238)
			(xy 372.155557 -418.142042) (xy 372.196756 -418.106345) (xy 372.242616 -418.076875) (xy 372.292203 -418.054232)
			(xy 372.344508 -418.038877) (xy 372.398466 -418.031121) (xy 372.425722 -418.03066) (xy 373.289322 -418.03066)
			(xy 373.31657 -418.031212) (xy 373.370511 -418.03897) (xy 373.422798 -418.054326) (xy 373.472369 -418.076966)
			(xy 373.518212 -418.106431) (xy 373.559396 -418.142119) (xy 373.595083 -418.183305) (xy 373.624544 -418.229151)
			(xy 373.647182 -418.278722) (xy 373.662535 -418.331011) (xy 373.67029 -418.384952) (xy 373.67029 -418.439448)
			(xy 373.670289 -418.439452) (xy 375.107946 -418.439452) (xy 375.107946 -418.384948) (xy 375.115702 -418.330999)
			(xy 375.131056 -418.278703) (xy 375.153697 -418.229124) (xy 375.183162 -418.183272) (xy 375.218852 -418.142079)
			(xy 375.260041 -418.106385) (xy 375.305891 -418.076915) (xy 375.355468 -418.05427) (xy 375.407762 -418.03891)
			(xy 375.46171 -418.031148) (xy 375.488962 -418.03066) (xy 376.352562 -418.03066) (xy 376.379814 -418.031185)
			(xy 376.433765 -418.038937) (xy 376.486063 -418.054288) (xy 376.535644 -418.076926) (xy 376.581498 -418.106391)
			(xy 376.622691 -418.142082) (xy 376.658386 -418.183272) (xy 376.687855 -418.229123) (xy 376.710499 -418.278701)
			(xy 376.725855 -418.330998) (xy 376.733613 -418.384948) (xy 376.733613 -418.439452) (xy 376.733613 -418.439455)
			(xy 378.171123 -418.439455) (xy 378.171123 -418.384945) (xy 378.178881 -418.330989) (xy 378.194238 -418.278687)
			(xy 378.216883 -418.229102) (xy 378.246353 -418.183245) (xy 378.28205 -418.142049) (xy 378.323247 -418.106352)
			(xy 378.369104 -418.076882) (xy 378.418688 -418.054237) (xy 378.470991 -418.03888) (xy 378.524947 -418.031123)
			(xy 378.552202 -418.03066) (xy 379.415802 -418.03066) (xy 379.443051 -418.03121) (xy 379.496994 -418.038966)
			(xy 379.549284 -418.05432) (xy 379.598857 -418.07696) (xy 379.644703 -418.106424) (xy 379.685889 -418.142112)
			(xy 379.721578 -418.183299) (xy 379.751041 -418.229145) (xy 379.77368 -418.278718) (xy 379.789034 -418.331008)
			(xy 379.79679 -418.384951) (xy 379.79679 -418.439449) (xy 379.796789 -418.439457) (xy 381.234323 -418.439457)
			(xy 381.234323 -418.384943) (xy 381.242082 -418.330984) (xy 381.257441 -418.278678) (xy 381.280089 -418.229091)
			(xy 381.309563 -418.183232) (xy 381.345264 -418.142035) (xy 381.386466 -418.106338) (xy 381.432328 -418.076869)
			(xy 381.481917 -418.054227) (xy 381.534225 -418.038873) (xy 381.588185 -418.03112) (xy 381.615442 -418.03066)
			(xy 382.479042 -418.03066) (xy 382.506289 -418.031213) (xy 382.560228 -418.038974) (xy 382.612513 -418.054331)
			(xy 382.662081 -418.076973) (xy 382.707922 -418.106438) (xy 382.749103 -418.142126) (xy 382.784787 -418.183312)
			(xy 382.814247 -418.229156) (xy 382.836883 -418.278727) (xy 382.852235 -418.331014) (xy 382.85999 -418.384953)
			(xy 382.85999 -418.439447) (xy 382.859989 -418.439453) (xy 384.297646 -418.439453) (xy 384.297646 -418.384947)
			(xy 384.305403 -418.330997) (xy 384.320758 -418.278699) (xy 384.3434 -418.229119) (xy 384.372867 -418.183265)
			(xy 384.408559 -418.142072) (xy 384.449751 -418.106378) (xy 384.495603 -418.076908) (xy 384.545182 -418.054264)
			(xy 384.597479 -418.038906) (xy 384.651429 -418.031147) (xy 384.678682 -418.03066) (xy 385.542282 -418.03066)
			(xy 385.569533 -418.031186) (xy 385.623482 -418.03894) (xy 385.675777 -418.054293) (xy 385.725356 -418.076933)
			(xy 385.771207 -418.106398) (xy 385.812399 -418.142089) (xy 385.848091 -418.183278) (xy 385.877558 -418.229129)
			(xy 385.9002 -418.278706) (xy 385.915556 -418.331001) (xy 385.923313 -418.384949) (xy 385.923313 -418.439451)
			(xy 385.923312 -418.439456) (xy 387.360823 -418.439456) (xy 387.360823 -418.384944) (xy 387.368581 -418.330986)
			(xy 387.38394 -418.278682) (xy 387.406586 -418.229097) (xy 387.436058 -418.183238) (xy 387.471757 -418.142042)
			(xy 387.512956 -418.106345) (xy 387.558816 -418.076875) (xy 387.608403 -418.054232) (xy 387.660708 -418.038877)
			(xy 387.714666 -418.031121) (xy 387.741922 -418.03066) (xy 388.605522 -418.03066) (xy 388.63277 -418.031212)
			(xy 388.686711 -418.03897) (xy 388.738998 -418.054326) (xy 388.788569 -418.076966) (xy 388.834412 -418.106431)
			(xy 388.875596 -418.142119) (xy 388.911283 -418.183305) (xy 388.940744 -418.229151) (xy 388.963382 -418.278722)
			(xy 388.978735 -418.331011) (xy 388.98649 -418.384952) (xy 388.98649 -418.439448) (xy 388.986489 -418.439452)
			(xy 390.424146 -418.439452) (xy 390.424146 -418.384948) (xy 390.431902 -418.330999) (xy 390.447256 -418.278703)
			(xy 390.469897 -418.229124) (xy 390.499362 -418.183272) (xy 390.535052 -418.142079) (xy 390.576241 -418.106385)
			(xy 390.622091 -418.076915) (xy 390.671668 -418.05427) (xy 390.723962 -418.03891) (xy 390.77791 -418.031148)
			(xy 390.805162 -418.03066) (xy 391.668762 -418.03066) (xy 391.696014 -418.031185) (xy 391.749965 -418.038937)
			(xy 391.802263 -418.054288) (xy 391.851844 -418.076926) (xy 391.897698 -418.106391) (xy 391.938891 -418.142082)
			(xy 391.974586 -418.183272) (xy 392.004055 -418.229123) (xy 392.026699 -418.278701) (xy 392.042055 -418.330998)
			(xy 392.049813 -418.384948) (xy 392.049813 -418.439452) (xy 392.049813 -418.439455) (xy 393.487323 -418.439455)
			(xy 393.487323 -418.384945) (xy 393.495081 -418.330989) (xy 393.510438 -418.278687) (xy 393.533083 -418.229102)
			(xy 393.562553 -418.183245) (xy 393.59825 -418.142049) (xy 393.639447 -418.106352) (xy 393.685304 -418.076882)
			(xy 393.734888 -418.054237) (xy 393.787191 -418.03888) (xy 393.841147 -418.031123) (xy 393.868402 -418.03066)
			(xy 394.732002 -418.03066) (xy 394.759251 -418.03121) (xy 394.813194 -418.038966) (xy 394.865484 -418.05432)
			(xy 394.915057 -418.07696) (xy 394.960903 -418.106424) (xy 395.002089 -418.142112) (xy 395.037778 -418.183299)
			(xy 395.067241 -418.229145) (xy 395.08988 -418.278718) (xy 395.105234 -418.331008) (xy 395.11299 -418.384951)
			(xy 395.11299 -418.439449) (xy 395.112989 -418.439457) (xy 396.550523 -418.439457) (xy 396.550523 -418.384943)
			(xy 396.558282 -418.330984) (xy 396.573641 -418.278678) (xy 396.596289 -418.229091) (xy 396.625763 -418.183232)
			(xy 396.661464 -418.142035) (xy 396.702666 -418.106338) (xy 396.748528 -418.076869) (xy 396.798117 -418.054227)
			(xy 396.850425 -418.038873) (xy 396.904385 -418.03112) (xy 396.931642 -418.03066) (xy 397.795242 -418.03066)
			(xy 397.822489 -418.031213) (xy 397.876428 -418.038974) (xy 397.928713 -418.054331) (xy 397.978281 -418.076973)
			(xy 398.024122 -418.106438) (xy 398.065303 -418.142126) (xy 398.100987 -418.183312) (xy 398.130447 -418.229156)
			(xy 398.153083 -418.278727) (xy 398.168435 -418.331014) (xy 398.17619 -418.384953) (xy 398.17619 -418.439447)
			(xy 398.176189 -418.439453) (xy 399.613846 -418.439453) (xy 399.613846 -418.384947) (xy 399.621603 -418.330997)
			(xy 399.636958 -418.278699) (xy 399.6596 -418.229119) (xy 399.689067 -418.183265) (xy 399.724759 -418.142072)
			(xy 399.765951 -418.106378) (xy 399.811803 -418.076908) (xy 399.861382 -418.054264) (xy 399.913679 -418.038906)
			(xy 399.967629 -418.031147) (xy 399.994882 -418.03066) (xy 400.858482 -418.03066) (xy 400.885733 -418.031186)
			(xy 400.939682 -418.03894) (xy 400.991977 -418.054293) (xy 401.041556 -418.076933) (xy 401.087407 -418.106398)
			(xy 401.128599 -418.142089) (xy 401.164291 -418.183278) (xy 401.193758 -418.229129) (xy 401.2164 -418.278706)
			(xy 401.231756 -418.331001) (xy 401.239513 -418.384949) (xy 401.239513 -418.439451) (xy 401.239512 -418.439456)
			(xy 402.677023 -418.439456) (xy 402.677023 -418.384944) (xy 402.684781 -418.330986) (xy 402.70014 -418.278682)
			(xy 402.722786 -418.229097) (xy 402.752258 -418.183238) (xy 402.787957 -418.142042) (xy 402.829156 -418.106345)
			(xy 402.875016 -418.076875) (xy 402.924603 -418.054232) (xy 402.976908 -418.038877) (xy 403.030866 -418.031121)
			(xy 403.058122 -418.03066) (xy 403.921722 -418.03066) (xy 403.94897 -418.031212) (xy 404.002911 -418.03897)
			(xy 404.055198 -418.054326) (xy 404.104769 -418.076966) (xy 404.150612 -418.106431) (xy 404.191796 -418.142119)
			(xy 404.227483 -418.183305) (xy 404.256944 -418.229151) (xy 404.279582 -418.278722) (xy 404.294935 -418.331011)
			(xy 404.30269 -418.384952) (xy 404.30269 -418.439448) (xy 404.302689 -418.439452) (xy 405.740346 -418.439452)
			(xy 405.740346 -418.384948) (xy 405.748102 -418.330999) (xy 405.763456 -418.278703) (xy 405.786097 -418.229124)
			(xy 405.815562 -418.183272) (xy 405.851252 -418.142079) (xy 405.892441 -418.106385) (xy 405.938291 -418.076915)
			(xy 405.987868 -418.05427) (xy 406.040162 -418.03891) (xy 406.09411 -418.031148) (xy 406.121362 -418.03066)
			(xy 406.984962 -418.03066) (xy 407.012214 -418.031185) (xy 407.066165 -418.038937) (xy 407.118463 -418.054288)
			(xy 407.168044 -418.076926) (xy 407.213898 -418.106391) (xy 407.255091 -418.142082) (xy 407.290786 -418.183272)
			(xy 407.320255 -418.229123) (xy 407.342899 -418.278701) (xy 407.358255 -418.330998) (xy 407.366013 -418.384948)
			(xy 407.366013 -418.439452) (xy 407.366013 -418.439455) (xy 408.803523 -418.439455) (xy 408.803523 -418.384945)
			(xy 408.811281 -418.330989) (xy 408.826638 -418.278687) (xy 408.849283 -418.229102) (xy 408.878753 -418.183245)
			(xy 408.91445 -418.142049) (xy 408.955647 -418.106352) (xy 409.001504 -418.076882) (xy 409.051088 -418.054237)
			(xy 409.103391 -418.03888) (xy 409.157347 -418.031123) (xy 409.184602 -418.03066) (xy 410.048202 -418.03066)
			(xy 410.075451 -418.03121) (xy 410.129394 -418.038966) (xy 410.181684 -418.05432) (xy 410.231257 -418.07696)
			(xy 410.277103 -418.106424) (xy 410.318289 -418.142112) (xy 410.353978 -418.183299) (xy 410.383441 -418.229145)
			(xy 410.40608 -418.278718) (xy 410.421434 -418.331008) (xy 410.42919 -418.384951) (xy 410.42919 -418.439449)
			(xy 410.429189 -418.439457) (xy 411.866723 -418.439457) (xy 411.866723 -418.384943) (xy 411.874482 -418.330984)
			(xy 411.889841 -418.278678) (xy 411.912489 -418.229091) (xy 411.941963 -418.183232) (xy 411.977664 -418.142035)
			(xy 412.018866 -418.106338) (xy 412.064728 -418.076869) (xy 412.114317 -418.054227) (xy 412.166625 -418.038873)
			(xy 412.220585 -418.03112) (xy 412.247842 -418.03066) (xy 413.111442 -418.03066) (xy 413.138689 -418.031213)
			(xy 413.192628 -418.038974) (xy 413.244913 -418.054331) (xy 413.294481 -418.076973) (xy 413.340322 -418.106438)
			(xy 413.381503 -418.142126) (xy 413.417187 -418.183312) (xy 413.446647 -418.229156) (xy 413.469283 -418.278727)
			(xy 413.484635 -418.331014) (xy 413.49239 -418.384953) (xy 413.49239 -418.439447) (xy 413.492389 -418.439453)
			(xy 414.930046 -418.439453) (xy 414.930046 -418.384947) (xy 414.937803 -418.330997) (xy 414.953158 -418.278699)
			(xy 414.9758 -418.229119) (xy 415.005267 -418.183265) (xy 415.040959 -418.142072) (xy 415.082151 -418.106378)
			(xy 415.128003 -418.076908) (xy 415.177582 -418.054264) (xy 415.229879 -418.038906) (xy 415.283829 -418.031147)
			(xy 415.311082 -418.03066) (xy 416.174682 -418.03066) (xy 416.201933 -418.031186) (xy 416.255882 -418.03894)
			(xy 416.308177 -418.054293) (xy 416.357756 -418.076933) (xy 416.403607 -418.106398) (xy 416.444799 -418.142089)
			(xy 416.480491 -418.183278) (xy 416.509958 -418.229129) (xy 416.5326 -418.278706) (xy 416.547956 -418.331001)
			(xy 416.555713 -418.384949) (xy 416.555713 -418.439451) (xy 416.555712 -418.439456) (xy 417.993223 -418.439456)
			(xy 417.993223 -418.384944) (xy 418.000981 -418.330986) (xy 418.01634 -418.278682) (xy 418.038986 -418.229097)
			(xy 418.068458 -418.183238) (xy 418.104157 -418.142042) (xy 418.145356 -418.106345) (xy 418.191216 -418.076875)
			(xy 418.240803 -418.054232) (xy 418.293108 -418.038877) (xy 418.347066 -418.031121) (xy 418.374322 -418.03066)
			(xy 419.237922 -418.03066) (xy 419.26517 -418.031212) (xy 419.319111 -418.03897) (xy 419.371398 -418.054326)
			(xy 419.420969 -418.076966) (xy 419.466812 -418.106431) (xy 419.507996 -418.142119) (xy 419.543683 -418.183305)
			(xy 419.573144 -418.229151) (xy 419.595782 -418.278722) (xy 419.611135 -418.331011) (xy 419.61889 -418.384952)
			(xy 419.61889 -418.439448) (xy 419.611135 -418.493389) (xy 419.595782 -418.545678) (xy 419.573144 -418.595249)
			(xy 419.543683 -418.641095) (xy 419.507996 -418.682281) (xy 419.466812 -418.717969) (xy 419.420969 -418.747434)
			(xy 419.371398 -418.770074) (xy 419.319111 -418.78543) (xy 419.26517 -418.793188) (xy 419.237922 -418.793676)
			(xy 418.374322 -418.793676) (xy 418.347066 -418.793279) (xy 418.293108 -418.785523) (xy 418.240803 -418.770168)
			(xy 418.191216 -418.747525) (xy 418.145356 -418.718055) (xy 418.104157 -418.682358) (xy 418.068458 -418.641162)
			(xy 418.038986 -418.595303) (xy 418.01634 -418.545718) (xy 418.000981 -418.493414) (xy 417.993223 -418.439456)
			(xy 416.555712 -418.439456) (xy 416.547956 -418.493399) (xy 416.5326 -418.545694) (xy 416.509958 -418.595271)
			(xy 416.480491 -418.641122) (xy 416.444799 -418.682311) (xy 416.403607 -418.718002) (xy 416.357756 -418.747467)
			(xy 416.308177 -418.770107) (xy 416.255882 -418.78546) (xy 416.201933 -418.793214) (xy 416.174682 -418.793676)
			(xy 415.311082 -418.793676) (xy 415.283829 -418.793253) (xy 415.229879 -418.785494) (xy 415.177582 -418.770136)
			(xy 415.128003 -418.747492) (xy 415.082151 -418.718022) (xy 415.040959 -418.682328) (xy 415.005267 -418.641135)
			(xy 414.9758 -418.595281) (xy 414.953158 -418.545701) (xy 414.937803 -418.493403) (xy 414.930046 -418.439453)
			(xy 413.492389 -418.439453) (xy 413.484635 -418.493386) (xy 413.469283 -418.545673) (xy 413.446647 -418.595244)
			(xy 413.417187 -418.641088) (xy 413.381503 -418.682274) (xy 413.340322 -418.717962) (xy 413.294481 -418.747427)
			(xy 413.244913 -418.770069) (xy 413.192628 -418.785426) (xy 413.138689 -418.793187) (xy 413.111442 -418.793676)
			(xy 412.247842 -418.793676) (xy 412.220585 -418.79328) (xy 412.166625 -418.785527) (xy 412.114317 -418.770173)
			(xy 412.064728 -418.747531) (xy 412.018866 -418.718062) (xy 411.977664 -418.682365) (xy 411.941963 -418.641168)
			(xy 411.912489 -418.595309) (xy 411.889841 -418.545722) (xy 411.874482 -418.493416) (xy 411.866723 -418.439457)
			(xy 410.429189 -418.439457) (xy 410.421434 -418.493392) (xy 410.40608 -418.545682) (xy 410.383441 -418.595255)
			(xy 410.353978 -418.641101) (xy 410.318289 -418.682288) (xy 410.277103 -418.717976) (xy 410.231257 -418.74744)
			(xy 410.181684 -418.77008) (xy 410.129394 -418.785434) (xy 410.075451 -418.79319) (xy 410.048202 -418.793676)
			(xy 409.184602 -418.793676) (xy 409.157347 -418.793277) (xy 409.103391 -418.78552) (xy 409.051088 -418.770163)
			(xy 409.001504 -418.747518) (xy 408.955647 -418.718048) (xy 408.91445 -418.682351) (xy 408.878753 -418.641155)
			(xy 408.849283 -418.595298) (xy 408.826638 -418.545713) (xy 408.811281 -418.493411) (xy 408.803523 -418.439455)
			(xy 407.366013 -418.439455) (xy 407.358255 -418.493402) (xy 407.342899 -418.545699) (xy 407.320255 -418.595277)
			(xy 407.290786 -418.641128) (xy 407.255091 -418.682318) (xy 407.213898 -418.718009) (xy 407.168044 -418.747474)
			(xy 407.118463 -418.770112) (xy 407.066165 -418.785463) (xy 407.012214 -418.793215) (xy 406.984962 -418.793676)
			(xy 406.121362 -418.793676) (xy 406.09411 -418.793252) (xy 406.040162 -418.78549) (xy 405.987868 -418.77013)
			(xy 405.938291 -418.747485) (xy 405.892441 -418.718015) (xy 405.851252 -418.682321) (xy 405.815562 -418.641128)
			(xy 405.786097 -418.595276) (xy 405.763456 -418.545697) (xy 405.748102 -418.493401) (xy 405.740346 -418.439452)
			(xy 404.302689 -418.439452) (xy 404.294935 -418.493389) (xy 404.279582 -418.545678) (xy 404.256944 -418.595249)
			(xy 404.227483 -418.641095) (xy 404.191796 -418.682281) (xy 404.150612 -418.717969) (xy 404.104769 -418.747434)
			(xy 404.055198 -418.770074) (xy 404.002911 -418.78543) (xy 403.94897 -418.793188) (xy 403.921722 -418.793676)
			(xy 403.058122 -418.793676) (xy 403.030866 -418.793279) (xy 402.976908 -418.785523) (xy 402.924603 -418.770168)
			(xy 402.875016 -418.747525) (xy 402.829156 -418.718055) (xy 402.787957 -418.682358) (xy 402.752258 -418.641162)
			(xy 402.722786 -418.595303) (xy 402.70014 -418.545718) (xy 402.684781 -418.493414) (xy 402.677023 -418.439456)
			(xy 401.239512 -418.439456) (xy 401.231756 -418.493399) (xy 401.2164 -418.545694) (xy 401.193758 -418.595271)
			(xy 401.164291 -418.641122) (xy 401.128599 -418.682311) (xy 401.087407 -418.718002) (xy 401.041556 -418.747467)
			(xy 400.991977 -418.770107) (xy 400.939682 -418.78546) (xy 400.885733 -418.793214) (xy 400.858482 -418.793676)
			(xy 399.994882 -418.793676) (xy 399.967629 -418.793253) (xy 399.913679 -418.785494) (xy 399.861382 -418.770136)
			(xy 399.811803 -418.747492) (xy 399.765951 -418.718022) (xy 399.724759 -418.682328) (xy 399.689067 -418.641135)
			(xy 399.6596 -418.595281) (xy 399.636958 -418.545701) (xy 399.621603 -418.493403) (xy 399.613846 -418.439453)
			(xy 398.176189 -418.439453) (xy 398.168435 -418.493386) (xy 398.153083 -418.545673) (xy 398.130447 -418.595244)
			(xy 398.100987 -418.641088) (xy 398.065303 -418.682274) (xy 398.024122 -418.717962) (xy 397.978281 -418.747427)
			(xy 397.928713 -418.770069) (xy 397.876428 -418.785426) (xy 397.822489 -418.793187) (xy 397.795242 -418.793676)
			(xy 396.931642 -418.793676) (xy 396.904385 -418.79328) (xy 396.850425 -418.785527) (xy 396.798117 -418.770173)
			(xy 396.748528 -418.747531) (xy 396.702666 -418.718062) (xy 396.661464 -418.682365) (xy 396.625763 -418.641168)
			(xy 396.596289 -418.595309) (xy 396.573641 -418.545722) (xy 396.558282 -418.493416) (xy 396.550523 -418.439457)
			(xy 395.112989 -418.439457) (xy 395.105234 -418.493392) (xy 395.08988 -418.545682) (xy 395.067241 -418.595255)
			(xy 395.037778 -418.641101) (xy 395.002089 -418.682288) (xy 394.960903 -418.717976) (xy 394.915057 -418.74744)
			(xy 394.865484 -418.77008) (xy 394.813194 -418.785434) (xy 394.759251 -418.79319) (xy 394.732002 -418.793676)
			(xy 393.868402 -418.793676) (xy 393.841147 -418.793277) (xy 393.787191 -418.78552) (xy 393.734888 -418.770163)
			(xy 393.685304 -418.747518) (xy 393.639447 -418.718048) (xy 393.59825 -418.682351) (xy 393.562553 -418.641155)
			(xy 393.533083 -418.595298) (xy 393.510438 -418.545713) (xy 393.495081 -418.493411) (xy 393.487323 -418.439455)
			(xy 392.049813 -418.439455) (xy 392.042055 -418.493402) (xy 392.026699 -418.545699) (xy 392.004055 -418.595277)
			(xy 391.974586 -418.641128) (xy 391.938891 -418.682318) (xy 391.897698 -418.718009) (xy 391.851844 -418.747474)
			(xy 391.802263 -418.770112) (xy 391.749965 -418.785463) (xy 391.696014 -418.793215) (xy 391.668762 -418.793676)
			(xy 390.805162 -418.793676) (xy 390.77791 -418.793252) (xy 390.723962 -418.78549) (xy 390.671668 -418.77013)
			(xy 390.622091 -418.747485) (xy 390.576241 -418.718015) (xy 390.535052 -418.682321) (xy 390.499362 -418.641128)
			(xy 390.469897 -418.595276) (xy 390.447256 -418.545697) (xy 390.431902 -418.493401) (xy 390.424146 -418.439452)
			(xy 388.986489 -418.439452) (xy 388.978735 -418.493389) (xy 388.963382 -418.545678) (xy 388.940744 -418.595249)
			(xy 388.911283 -418.641095) (xy 388.875596 -418.682281) (xy 388.834412 -418.717969) (xy 388.788569 -418.747434)
			(xy 388.738998 -418.770074) (xy 388.686711 -418.78543) (xy 388.63277 -418.793188) (xy 388.605522 -418.793676)
			(xy 387.741922 -418.793676) (xy 387.714666 -418.793279) (xy 387.660708 -418.785523) (xy 387.608403 -418.770168)
			(xy 387.558816 -418.747525) (xy 387.512956 -418.718055) (xy 387.471757 -418.682358) (xy 387.436058 -418.641162)
			(xy 387.406586 -418.595303) (xy 387.38394 -418.545718) (xy 387.368581 -418.493414) (xy 387.360823 -418.439456)
			(xy 385.923312 -418.439456) (xy 385.915556 -418.493399) (xy 385.9002 -418.545694) (xy 385.877558 -418.595271)
			(xy 385.848091 -418.641122) (xy 385.812399 -418.682311) (xy 385.771207 -418.718002) (xy 385.725356 -418.747467)
			(xy 385.675777 -418.770107) (xy 385.623482 -418.78546) (xy 385.569533 -418.793214) (xy 385.542282 -418.793676)
			(xy 384.678682 -418.793676) (xy 384.651429 -418.793253) (xy 384.597479 -418.785494) (xy 384.545182 -418.770136)
			(xy 384.495603 -418.747492) (xy 384.449751 -418.718022) (xy 384.408559 -418.682328) (xy 384.372867 -418.641135)
			(xy 384.3434 -418.595281) (xy 384.320758 -418.545701) (xy 384.305403 -418.493403) (xy 384.297646 -418.439453)
			(xy 382.859989 -418.439453) (xy 382.852235 -418.493386) (xy 382.836883 -418.545673) (xy 382.814247 -418.595244)
			(xy 382.784787 -418.641088) (xy 382.749103 -418.682274) (xy 382.707922 -418.717962) (xy 382.662081 -418.747427)
			(xy 382.612513 -418.770069) (xy 382.560228 -418.785426) (xy 382.506289 -418.793187) (xy 382.479042 -418.793676)
			(xy 381.615442 -418.793676) (xy 381.588185 -418.79328) (xy 381.534225 -418.785527) (xy 381.481917 -418.770173)
			(xy 381.432328 -418.747531) (xy 381.386466 -418.718062) (xy 381.345264 -418.682365) (xy 381.309563 -418.641168)
			(xy 381.280089 -418.595309) (xy 381.257441 -418.545722) (xy 381.242082 -418.493416) (xy 381.234323 -418.439457)
			(xy 379.796789 -418.439457) (xy 379.789034 -418.493392) (xy 379.77368 -418.545682) (xy 379.751041 -418.595255)
			(xy 379.721578 -418.641101) (xy 379.685889 -418.682288) (xy 379.644703 -418.717976) (xy 379.598857 -418.74744)
			(xy 379.549284 -418.77008) (xy 379.496994 -418.785434) (xy 379.443051 -418.79319) (xy 379.415802 -418.793676)
			(xy 378.552202 -418.793676) (xy 378.524947 -418.793277) (xy 378.470991 -418.78552) (xy 378.418688 -418.770163)
			(xy 378.369104 -418.747518) (xy 378.323247 -418.718048) (xy 378.28205 -418.682351) (xy 378.246353 -418.641155)
			(xy 378.216883 -418.595298) (xy 378.194238 -418.545713) (xy 378.178881 -418.493411) (xy 378.171123 -418.439455)
			(xy 376.733613 -418.439455) (xy 376.725855 -418.493402) (xy 376.710499 -418.545699) (xy 376.687855 -418.595277)
			(xy 376.658386 -418.641128) (xy 376.622691 -418.682318) (xy 376.581498 -418.718009) (xy 376.535644 -418.747474)
			(xy 376.486063 -418.770112) (xy 376.433765 -418.785463) (xy 376.379814 -418.793215) (xy 376.352562 -418.793676)
			(xy 375.488962 -418.793676) (xy 375.46171 -418.793252) (xy 375.407762 -418.78549) (xy 375.355468 -418.77013)
			(xy 375.305891 -418.747485) (xy 375.260041 -418.718015) (xy 375.218852 -418.682321) (xy 375.183162 -418.641128)
			(xy 375.153697 -418.595276) (xy 375.131056 -418.545697) (xy 375.115702 -418.493401) (xy 375.107946 -418.439452)
			(xy 373.670289 -418.439452) (xy 373.662535 -418.493389) (xy 373.647182 -418.545678) (xy 373.624544 -418.595249)
			(xy 373.595083 -418.641095) (xy 373.559396 -418.682281) (xy 373.518212 -418.717969) (xy 373.472369 -418.747434)
			(xy 373.422798 -418.770074) (xy 373.370511 -418.78543) (xy 373.31657 -418.793188) (xy 373.289322 -418.793676)
			(xy 372.425722 -418.793676) (xy 372.398466 -418.793279) (xy 372.344508 -418.785523) (xy 372.292203 -418.770168)
			(xy 372.242616 -418.747525) (xy 372.196756 -418.718055) (xy 372.155557 -418.682358) (xy 372.119858 -418.641162)
			(xy 372.090386 -418.595303) (xy 372.06774 -418.545718) (xy 372.052381 -418.493414) (xy 372.044623 -418.439456)
			(xy 370.313204 -418.439456) (xy 370.313204 -420.692072) (xy 370.313204 -420.739316) (xy 370.262404 -420.739316)
			(xy 370.16182 -420.739316) (xy 370.150438 -420.74117) (xy 370.131001 -420.753543) (xy 370.118864 -420.773128)
			(xy 370.117116 -420.784528) (xy 370.117116 -420.979455) (xy 370.513023 -420.979455) (xy 370.513023 -420.924945)
			(xy 370.520781 -420.870989) (xy 370.536138 -420.818687) (xy 370.558783 -420.769102) (xy 370.588253 -420.723245)
			(xy 370.62395 -420.682049) (xy 370.665147 -420.646352) (xy 370.711004 -420.616882) (xy 370.760588 -420.594237)
			(xy 370.812891 -420.57888) (xy 370.866847 -420.571123) (xy 370.894102 -420.57066) (xy 371.757702 -420.57066)
			(xy 371.784951 -420.57121) (xy 371.838894 -420.578966) (xy 371.891184 -420.59432) (xy 371.940757 -420.61696)
			(xy 371.986603 -420.646424) (xy 372.027789 -420.682112) (xy 372.063478 -420.723299) (xy 372.092941 -420.769145)
			(xy 372.11558 -420.818718) (xy 372.130934 -420.871008) (xy 372.13869 -420.924951) (xy 372.13869 -420.979449)
			(xy 372.138689 -420.979457) (xy 373.576223 -420.979457) (xy 373.576223 -420.924943) (xy 373.583982 -420.870984)
			(xy 373.599341 -420.818678) (xy 373.621989 -420.769091) (xy 373.651463 -420.723232) (xy 373.687164 -420.682035)
			(xy 373.728366 -420.646338) (xy 373.774228 -420.616869) (xy 373.823817 -420.594227) (xy 373.876125 -420.578873)
			(xy 373.930085 -420.57112) (xy 373.957342 -420.57066) (xy 374.820942 -420.57066) (xy 374.848189 -420.571213)
			(xy 374.902128 -420.578974) (xy 374.954413 -420.594331) (xy 375.003981 -420.616973) (xy 375.049822 -420.646438)
			(xy 375.091003 -420.682126) (xy 375.126687 -420.723312) (xy 375.156147 -420.769156) (xy 375.178783 -420.818727)
			(xy 375.194135 -420.871014) (xy 375.20189 -420.924953) (xy 375.20189 -420.979447) (xy 375.201889 -420.979453)
			(xy 376.639546 -420.979453) (xy 376.639546 -420.924947) (xy 376.647303 -420.870997) (xy 376.662658 -420.818699)
			(xy 376.6853 -420.769119) (xy 376.714767 -420.723265) (xy 376.750459 -420.682072) (xy 376.791651 -420.646378)
			(xy 376.837503 -420.616908) (xy 376.887082 -420.594264) (xy 376.939379 -420.578906) (xy 376.993329 -420.571147)
			(xy 377.020582 -420.57066) (xy 377.884182 -420.57066) (xy 377.911433 -420.571186) (xy 377.965382 -420.57894)
			(xy 378.017677 -420.594293) (xy 378.067256 -420.616933) (xy 378.113107 -420.646398) (xy 378.154299 -420.682089)
			(xy 378.189991 -420.723278) (xy 378.219458 -420.769129) (xy 378.2421 -420.818706) (xy 378.257456 -420.871001)
			(xy 378.265213 -420.924949) (xy 378.265213 -420.979451) (xy 378.265212 -420.979456) (xy 379.702723 -420.979456)
			(xy 379.702723 -420.924944) (xy 379.710481 -420.870986) (xy 379.72584 -420.818682) (xy 379.748486 -420.769097)
			(xy 379.777958 -420.723238) (xy 379.813657 -420.682042) (xy 379.854856 -420.646345) (xy 379.900716 -420.616875)
			(xy 379.950303 -420.594232) (xy 380.002608 -420.578877) (xy 380.056566 -420.571121) (xy 380.083822 -420.57066)
			(xy 380.947422 -420.57066) (xy 380.97467 -420.571212) (xy 381.028611 -420.57897) (xy 381.080898 -420.594326)
			(xy 381.130469 -420.616966) (xy 381.176312 -420.646431) (xy 381.217496 -420.682119) (xy 381.253183 -420.723305)
			(xy 381.282644 -420.769151) (xy 381.305282 -420.818722) (xy 381.320635 -420.871011) (xy 381.32839 -420.924952)
			(xy 381.32839 -420.979448) (xy 381.328389 -420.979452) (xy 382.766046 -420.979452) (xy 382.766046 -420.924948)
			(xy 382.773802 -420.870999) (xy 382.789156 -420.818703) (xy 382.811797 -420.769124) (xy 382.841262 -420.723272)
			(xy 382.876952 -420.682079) (xy 382.918141 -420.646385) (xy 382.963991 -420.616915) (xy 383.013568 -420.59427)
			(xy 383.065862 -420.57891) (xy 383.11981 -420.571148) (xy 383.147062 -420.57066) (xy 384.010662 -420.57066)
			(xy 384.037914 -420.571185) (xy 384.091865 -420.578937) (xy 384.144163 -420.594288) (xy 384.193744 -420.616926)
			(xy 384.239598 -420.646391) (xy 384.280791 -420.682082) (xy 384.316486 -420.723272) (xy 384.345955 -420.769123)
			(xy 384.368599 -420.818701) (xy 384.383955 -420.870998) (xy 384.391713 -420.924948) (xy 384.391713 -420.979452)
			(xy 384.391713 -420.979455) (xy 385.829223 -420.979455) (xy 385.829223 -420.924945) (xy 385.836981 -420.870989)
			(xy 385.852338 -420.818687) (xy 385.874983 -420.769102) (xy 385.904453 -420.723245) (xy 385.94015 -420.682049)
			(xy 385.981347 -420.646352) (xy 386.027204 -420.616882) (xy 386.076788 -420.594237) (xy 386.129091 -420.57888)
			(xy 386.183047 -420.571123) (xy 386.210302 -420.57066) (xy 387.073902 -420.57066) (xy 387.101151 -420.57121)
			(xy 387.155094 -420.578966) (xy 387.207384 -420.59432) (xy 387.256957 -420.61696) (xy 387.302803 -420.646424)
			(xy 387.343989 -420.682112) (xy 387.379678 -420.723299) (xy 387.409141 -420.769145) (xy 387.43178 -420.818718)
			(xy 387.447134 -420.871008) (xy 387.45489 -420.924951) (xy 387.45489 -420.979449) (xy 387.454889 -420.979457)
			(xy 388.892423 -420.979457) (xy 388.892423 -420.924943) (xy 388.900182 -420.870984) (xy 388.915541 -420.818678)
			(xy 388.938189 -420.769091) (xy 388.967663 -420.723232) (xy 389.003364 -420.682035) (xy 389.044566 -420.646338)
			(xy 389.090428 -420.616869) (xy 389.140017 -420.594227) (xy 389.192325 -420.578873) (xy 389.246285 -420.57112)
			(xy 389.273542 -420.57066) (xy 390.137142 -420.57066) (xy 390.164389 -420.571213) (xy 390.218328 -420.578974)
			(xy 390.270613 -420.594331) (xy 390.320181 -420.616973) (xy 390.366022 -420.646438) (xy 390.407203 -420.682126)
			(xy 390.442887 -420.723312) (xy 390.472347 -420.769156) (xy 390.494983 -420.818727) (xy 390.510335 -420.871014)
			(xy 390.51809 -420.924953) (xy 390.51809 -420.979447) (xy 390.518089 -420.979453) (xy 391.955746 -420.979453)
			(xy 391.955746 -420.924947) (xy 391.963503 -420.870997) (xy 391.978858 -420.818699) (xy 392.0015 -420.769119)
			(xy 392.030967 -420.723265) (xy 392.066659 -420.682072) (xy 392.107851 -420.646378) (xy 392.153703 -420.616908)
			(xy 392.203282 -420.594264) (xy 392.255579 -420.578906) (xy 392.309529 -420.571147) (xy 392.336782 -420.57066)
			(xy 393.200382 -420.57066) (xy 393.227633 -420.571186) (xy 393.281582 -420.57894) (xy 393.333877 -420.594293)
			(xy 393.383456 -420.616933) (xy 393.429307 -420.646398) (xy 393.470499 -420.682089) (xy 393.506191 -420.723278)
			(xy 393.535658 -420.769129) (xy 393.5583 -420.818706) (xy 393.573656 -420.871001) (xy 393.581413 -420.924949)
			(xy 393.581413 -420.979451) (xy 393.581412 -420.979456) (xy 395.018923 -420.979456) (xy 395.018923 -420.924944)
			(xy 395.026681 -420.870986) (xy 395.04204 -420.818682) (xy 395.064686 -420.769097) (xy 395.094158 -420.723238)
			(xy 395.129857 -420.682042) (xy 395.171056 -420.646345) (xy 395.216916 -420.616875) (xy 395.266503 -420.594232)
			(xy 395.318808 -420.578877) (xy 395.372766 -420.571121) (xy 395.400022 -420.57066) (xy 396.263622 -420.57066)
			(xy 396.29087 -420.571212) (xy 396.344811 -420.57897) (xy 396.397098 -420.594326) (xy 396.446669 -420.616966)
			(xy 396.492512 -420.646431) (xy 396.533696 -420.682119) (xy 396.569383 -420.723305) (xy 396.598844 -420.769151)
			(xy 396.621482 -420.818722) (xy 396.636835 -420.871011) (xy 396.64459 -420.924952) (xy 396.64459 -420.979448)
			(xy 396.644589 -420.979452) (xy 398.082246 -420.979452) (xy 398.082246 -420.924948) (xy 398.090002 -420.870999)
			(xy 398.105356 -420.818703) (xy 398.127997 -420.769124) (xy 398.157462 -420.723272) (xy 398.193152 -420.682079)
			(xy 398.234341 -420.646385) (xy 398.280191 -420.616915) (xy 398.329768 -420.59427) (xy 398.382062 -420.57891)
			(xy 398.43601 -420.571148) (xy 398.463262 -420.57066) (xy 399.326862 -420.57066) (xy 399.354114 -420.571185)
			(xy 399.408065 -420.578937) (xy 399.460363 -420.594288) (xy 399.509944 -420.616926) (xy 399.555798 -420.646391)
			(xy 399.596991 -420.682082) (xy 399.632686 -420.723272) (xy 399.662155 -420.769123) (xy 399.684799 -420.818701)
			(xy 399.700155 -420.870998) (xy 399.707913 -420.924948) (xy 399.707913 -420.979452) (xy 399.707913 -420.979455)
			(xy 401.145423 -420.979455) (xy 401.145423 -420.924945) (xy 401.153181 -420.870989) (xy 401.168538 -420.818687)
			(xy 401.191183 -420.769102) (xy 401.220653 -420.723245) (xy 401.25635 -420.682049) (xy 401.297547 -420.646352)
			(xy 401.343404 -420.616882) (xy 401.392988 -420.594237) (xy 401.445291 -420.57888) (xy 401.499247 -420.571123)
			(xy 401.526502 -420.57066) (xy 402.390102 -420.57066) (xy 402.417351 -420.57121) (xy 402.471294 -420.578966)
			(xy 402.523584 -420.59432) (xy 402.573157 -420.61696) (xy 402.619003 -420.646424) (xy 402.660189 -420.682112)
			(xy 402.695878 -420.723299) (xy 402.725341 -420.769145) (xy 402.74798 -420.818718) (xy 402.763334 -420.871008)
			(xy 402.77109 -420.924951) (xy 402.77109 -420.979449) (xy 402.771089 -420.979457) (xy 404.208623 -420.979457)
			(xy 404.208623 -420.924943) (xy 404.216382 -420.870984) (xy 404.231741 -420.818678) (xy 404.254389 -420.769091)
			(xy 404.283863 -420.723232) (xy 404.319564 -420.682035) (xy 404.360766 -420.646338) (xy 404.406628 -420.616869)
			(xy 404.456217 -420.594227) (xy 404.508525 -420.578873) (xy 404.562485 -420.57112) (xy 404.589742 -420.57066)
			(xy 405.453342 -420.57066) (xy 405.480589 -420.571213) (xy 405.534528 -420.578974) (xy 405.586813 -420.594331)
			(xy 405.636381 -420.616973) (xy 405.682222 -420.646438) (xy 405.723403 -420.682126) (xy 405.759087 -420.723312)
			(xy 405.788547 -420.769156) (xy 405.811183 -420.818727) (xy 405.826535 -420.871014) (xy 405.83429 -420.924953)
			(xy 405.83429 -420.979447) (xy 405.834289 -420.979453) (xy 407.271946 -420.979453) (xy 407.271946 -420.924947)
			(xy 407.279703 -420.870997) (xy 407.295058 -420.818699) (xy 407.3177 -420.769119) (xy 407.347167 -420.723265)
			(xy 407.382859 -420.682072) (xy 407.424051 -420.646378) (xy 407.469903 -420.616908) (xy 407.519482 -420.594264)
			(xy 407.571779 -420.578906) (xy 407.625729 -420.571147) (xy 407.652982 -420.57066) (xy 408.516582 -420.57066)
			(xy 408.543833 -420.571186) (xy 408.597782 -420.57894) (xy 408.650077 -420.594293) (xy 408.699656 -420.616933)
			(xy 408.745507 -420.646398) (xy 408.786699 -420.682089) (xy 408.822391 -420.723278) (xy 408.851858 -420.769129)
			(xy 408.8745 -420.818706) (xy 408.889856 -420.871001) (xy 408.897613 -420.924949) (xy 408.897613 -420.979451)
			(xy 408.897612 -420.979456) (xy 410.335123 -420.979456) (xy 410.335123 -420.924944) (xy 410.342881 -420.870986)
			(xy 410.35824 -420.818682) (xy 410.380886 -420.769097) (xy 410.410358 -420.723238) (xy 410.446057 -420.682042)
			(xy 410.487256 -420.646345) (xy 410.533116 -420.616875) (xy 410.582703 -420.594232) (xy 410.635008 -420.578877)
			(xy 410.688966 -420.571121) (xy 410.716222 -420.57066) (xy 411.579822 -420.57066) (xy 411.60707 -420.571212)
			(xy 411.661011 -420.57897) (xy 411.713298 -420.594326) (xy 411.762869 -420.616966) (xy 411.808712 -420.646431)
			(xy 411.849896 -420.682119) (xy 411.885583 -420.723305) (xy 411.915044 -420.769151) (xy 411.937682 -420.818722)
			(xy 411.953035 -420.871011) (xy 411.96079 -420.924952) (xy 411.96079 -420.979448) (xy 411.960789 -420.979452)
			(xy 413.398446 -420.979452) (xy 413.398446 -420.924948) (xy 413.406202 -420.870999) (xy 413.421556 -420.818703)
			(xy 413.444197 -420.769124) (xy 413.473662 -420.723272) (xy 413.509352 -420.682079) (xy 413.550541 -420.646385)
			(xy 413.596391 -420.616915) (xy 413.645968 -420.59427) (xy 413.698262 -420.57891) (xy 413.75221 -420.571148)
			(xy 413.779462 -420.57066) (xy 414.643062 -420.57066) (xy 414.670314 -420.571185) (xy 414.724265 -420.578937)
			(xy 414.776563 -420.594288) (xy 414.826144 -420.616926) (xy 414.871998 -420.646391) (xy 414.913191 -420.682082)
			(xy 414.948886 -420.723272) (xy 414.978355 -420.769123) (xy 415.000999 -420.818701) (xy 415.016355 -420.870998)
			(xy 415.024113 -420.924948) (xy 415.024113 -420.979452) (xy 415.024113 -420.979455) (xy 416.461623 -420.979455)
			(xy 416.461623 -420.924945) (xy 416.469381 -420.870989) (xy 416.484738 -420.818687) (xy 416.507383 -420.769102)
			(xy 416.536853 -420.723245) (xy 416.57255 -420.682049) (xy 416.613747 -420.646352) (xy 416.659604 -420.616882)
			(xy 416.709188 -420.594237) (xy 416.761491 -420.57888) (xy 416.815447 -420.571123) (xy 416.842702 -420.57066)
			(xy 417.706302 -420.57066) (xy 417.733551 -420.57121) (xy 417.787494 -420.578966) (xy 417.839784 -420.59432)
			(xy 417.889357 -420.61696) (xy 417.935203 -420.646424) (xy 417.976389 -420.682112) (xy 418.012078 -420.723299)
			(xy 418.041541 -420.769145) (xy 418.06418 -420.818718) (xy 418.079534 -420.871008) (xy 418.08729 -420.924951)
			(xy 418.08729 -420.979449) (xy 418.079534 -421.033392) (xy 418.06418 -421.085682) (xy 418.041541 -421.135255)
			(xy 418.012078 -421.181101) (xy 417.976389 -421.222288) (xy 417.935203 -421.257976) (xy 417.889357 -421.28744)
			(xy 417.839784 -421.31008) (xy 417.787494 -421.325434) (xy 417.733551 -421.33319) (xy 417.706302 -421.333676)
			(xy 416.842702 -421.333676) (xy 416.815447 -421.333277) (xy 416.761491 -421.32552) (xy 416.709188 -421.310163)
			(xy 416.659604 -421.287518) (xy 416.613747 -421.258048) (xy 416.57255 -421.222351) (xy 416.536853 -421.181155)
			(xy 416.507383 -421.135298) (xy 416.484738 -421.085713) (xy 416.469381 -421.033411) (xy 416.461623 -420.979455)
			(xy 415.024113 -420.979455) (xy 415.016355 -421.033402) (xy 415.000999 -421.085699) (xy 414.978355 -421.135277)
			(xy 414.948886 -421.181128) (xy 414.913191 -421.222318) (xy 414.871998 -421.258009) (xy 414.826144 -421.287474)
			(xy 414.776563 -421.310112) (xy 414.724265 -421.325463) (xy 414.670314 -421.333215) (xy 414.643062 -421.333676)
			(xy 413.779462 -421.333676) (xy 413.75221 -421.333252) (xy 413.698262 -421.32549) (xy 413.645968 -421.31013)
			(xy 413.596391 -421.287485) (xy 413.550541 -421.258015) (xy 413.509352 -421.222321) (xy 413.473662 -421.181128)
			(xy 413.444197 -421.135276) (xy 413.421556 -421.085697) (xy 413.406202 -421.033401) (xy 413.398446 -420.979452)
			(xy 411.960789 -420.979452) (xy 411.953035 -421.033389) (xy 411.937682 -421.085678) (xy 411.915044 -421.135249)
			(xy 411.885583 -421.181095) (xy 411.849896 -421.222281) (xy 411.808712 -421.257969) (xy 411.762869 -421.287434)
			(xy 411.713298 -421.310074) (xy 411.661011 -421.32543) (xy 411.60707 -421.333188) (xy 411.579822 -421.333676)
			(xy 410.716222 -421.333676) (xy 410.688966 -421.333279) (xy 410.635008 -421.325523) (xy 410.582703 -421.310168)
			(xy 410.533116 -421.287525) (xy 410.487256 -421.258055) (xy 410.446057 -421.222358) (xy 410.410358 -421.181162)
			(xy 410.380886 -421.135303) (xy 410.35824 -421.085718) (xy 410.342881 -421.033414) (xy 410.335123 -420.979456)
			(xy 408.897612 -420.979456) (xy 408.889856 -421.033399) (xy 408.8745 -421.085694) (xy 408.851858 -421.135271)
			(xy 408.822391 -421.181122) (xy 408.786699 -421.222311) (xy 408.745507 -421.258002) (xy 408.699656 -421.287467)
			(xy 408.650077 -421.310107) (xy 408.597782 -421.32546) (xy 408.543833 -421.333214) (xy 408.516582 -421.333676)
			(xy 407.652982 -421.333676) (xy 407.625729 -421.333253) (xy 407.571779 -421.325494) (xy 407.519482 -421.310136)
			(xy 407.469903 -421.287492) (xy 407.424051 -421.258022) (xy 407.382859 -421.222328) (xy 407.347167 -421.181135)
			(xy 407.3177 -421.135281) (xy 407.295058 -421.085701) (xy 407.279703 -421.033403) (xy 407.271946 -420.979453)
			(xy 405.834289 -420.979453) (xy 405.826535 -421.033386) (xy 405.811183 -421.085673) (xy 405.788547 -421.135244)
			(xy 405.759087 -421.181088) (xy 405.723403 -421.222274) (xy 405.682222 -421.257962) (xy 405.636381 -421.287427)
			(xy 405.586813 -421.310069) (xy 405.534528 -421.325426) (xy 405.480589 -421.333187) (xy 405.453342 -421.333676)
			(xy 404.589742 -421.333676) (xy 404.562485 -421.33328) (xy 404.508525 -421.325527) (xy 404.456217 -421.310173)
			(xy 404.406628 -421.287531) (xy 404.360766 -421.258062) (xy 404.319564 -421.222365) (xy 404.283863 -421.181168)
			(xy 404.254389 -421.135309) (xy 404.231741 -421.085722) (xy 404.216382 -421.033416) (xy 404.208623 -420.979457)
			(xy 402.771089 -420.979457) (xy 402.763334 -421.033392) (xy 402.74798 -421.085682) (xy 402.725341 -421.135255)
			(xy 402.695878 -421.181101) (xy 402.660189 -421.222288) (xy 402.619003 -421.257976) (xy 402.573157 -421.28744)
			(xy 402.523584 -421.31008) (xy 402.471294 -421.325434) (xy 402.417351 -421.33319) (xy 402.390102 -421.333676)
			(xy 401.526502 -421.333676) (xy 401.499247 -421.333277) (xy 401.445291 -421.32552) (xy 401.392988 -421.310163)
			(xy 401.343404 -421.287518) (xy 401.297547 -421.258048) (xy 401.25635 -421.222351) (xy 401.220653 -421.181155)
			(xy 401.191183 -421.135298) (xy 401.168538 -421.085713) (xy 401.153181 -421.033411) (xy 401.145423 -420.979455)
			(xy 399.707913 -420.979455) (xy 399.700155 -421.033402) (xy 399.684799 -421.085699) (xy 399.662155 -421.135277)
			(xy 399.632686 -421.181128) (xy 399.596991 -421.222318) (xy 399.555798 -421.258009) (xy 399.509944 -421.287474)
			(xy 399.460363 -421.310112) (xy 399.408065 -421.325463) (xy 399.354114 -421.333215) (xy 399.326862 -421.333676)
			(xy 398.463262 -421.333676) (xy 398.43601 -421.333252) (xy 398.382062 -421.32549) (xy 398.329768 -421.31013)
			(xy 398.280191 -421.287485) (xy 398.234341 -421.258015) (xy 398.193152 -421.222321) (xy 398.157462 -421.181128)
			(xy 398.127997 -421.135276) (xy 398.105356 -421.085697) (xy 398.090002 -421.033401) (xy 398.082246 -420.979452)
			(xy 396.644589 -420.979452) (xy 396.636835 -421.033389) (xy 396.621482 -421.085678) (xy 396.598844 -421.135249)
			(xy 396.569383 -421.181095) (xy 396.533696 -421.222281) (xy 396.492512 -421.257969) (xy 396.446669 -421.287434)
			(xy 396.397098 -421.310074) (xy 396.344811 -421.32543) (xy 396.29087 -421.333188) (xy 396.263622 -421.333676)
			(xy 395.400022 -421.333676) (xy 395.372766 -421.333279) (xy 395.318808 -421.325523) (xy 395.266503 -421.310168)
			(xy 395.216916 -421.287525) (xy 395.171056 -421.258055) (xy 395.129857 -421.222358) (xy 395.094158 -421.181162)
			(xy 395.064686 -421.135303) (xy 395.04204 -421.085718) (xy 395.026681 -421.033414) (xy 395.018923 -420.979456)
			(xy 393.581412 -420.979456) (xy 393.573656 -421.033399) (xy 393.5583 -421.085694) (xy 393.535658 -421.135271)
			(xy 393.506191 -421.181122) (xy 393.470499 -421.222311) (xy 393.429307 -421.258002) (xy 393.383456 -421.287467)
			(xy 393.333877 -421.310107) (xy 393.281582 -421.32546) (xy 393.227633 -421.333214) (xy 393.200382 -421.333676)
			(xy 392.336782 -421.333676) (xy 392.309529 -421.333253) (xy 392.255579 -421.325494) (xy 392.203282 -421.310136)
			(xy 392.153703 -421.287492) (xy 392.107851 -421.258022) (xy 392.066659 -421.222328) (xy 392.030967 -421.181135)
			(xy 392.0015 -421.135281) (xy 391.978858 -421.085701) (xy 391.963503 -421.033403) (xy 391.955746 -420.979453)
			(xy 390.518089 -420.979453) (xy 390.510335 -421.033386) (xy 390.494983 -421.085673) (xy 390.472347 -421.135244)
			(xy 390.442887 -421.181088) (xy 390.407203 -421.222274) (xy 390.366022 -421.257962) (xy 390.320181 -421.287427)
			(xy 390.270613 -421.310069) (xy 390.218328 -421.325426) (xy 390.164389 -421.333187) (xy 390.137142 -421.333676)
			(xy 389.273542 -421.333676) (xy 389.246285 -421.33328) (xy 389.192325 -421.325527) (xy 389.140017 -421.310173)
			(xy 389.090428 -421.287531) (xy 389.044566 -421.258062) (xy 389.003364 -421.222365) (xy 388.967663 -421.181168)
			(xy 388.938189 -421.135309) (xy 388.915541 -421.085722) (xy 388.900182 -421.033416) (xy 388.892423 -420.979457)
			(xy 387.454889 -420.979457) (xy 387.447134 -421.033392) (xy 387.43178 -421.085682) (xy 387.409141 -421.135255)
			(xy 387.379678 -421.181101) (xy 387.343989 -421.222288) (xy 387.302803 -421.257976) (xy 387.256957 -421.28744)
			(xy 387.207384 -421.31008) (xy 387.155094 -421.325434) (xy 387.101151 -421.33319) (xy 387.073902 -421.333676)
			(xy 386.210302 -421.333676) (xy 386.183047 -421.333277) (xy 386.129091 -421.32552) (xy 386.076788 -421.310163)
			(xy 386.027204 -421.287518) (xy 385.981347 -421.258048) (xy 385.94015 -421.222351) (xy 385.904453 -421.181155)
			(xy 385.874983 -421.135298) (xy 385.852338 -421.085713) (xy 385.836981 -421.033411) (xy 385.829223 -420.979455)
			(xy 384.391713 -420.979455) (xy 384.383955 -421.033402) (xy 384.368599 -421.085699) (xy 384.345955 -421.135277)
			(xy 384.316486 -421.181128) (xy 384.280791 -421.222318) (xy 384.239598 -421.258009) (xy 384.193744 -421.287474)
			(xy 384.144163 -421.310112) (xy 384.091865 -421.325463) (xy 384.037914 -421.333215) (xy 384.010662 -421.333676)
			(xy 383.147062 -421.333676) (xy 383.11981 -421.333252) (xy 383.065862 -421.32549) (xy 383.013568 -421.31013)
			(xy 382.963991 -421.287485) (xy 382.918141 -421.258015) (xy 382.876952 -421.222321) (xy 382.841262 -421.181128)
			(xy 382.811797 -421.135276) (xy 382.789156 -421.085697) (xy 382.773802 -421.033401) (xy 382.766046 -420.979452)
			(xy 381.328389 -420.979452) (xy 381.320635 -421.033389) (xy 381.305282 -421.085678) (xy 381.282644 -421.135249)
			(xy 381.253183 -421.181095) (xy 381.217496 -421.222281) (xy 381.176312 -421.257969) (xy 381.130469 -421.287434)
			(xy 381.080898 -421.310074) (xy 381.028611 -421.32543) (xy 380.97467 -421.333188) (xy 380.947422 -421.333676)
			(xy 380.083822 -421.333676) (xy 380.056566 -421.333279) (xy 380.002608 -421.325523) (xy 379.950303 -421.310168)
			(xy 379.900716 -421.287525) (xy 379.854856 -421.258055) (xy 379.813657 -421.222358) (xy 379.777958 -421.181162)
			(xy 379.748486 -421.135303) (xy 379.72584 -421.085718) (xy 379.710481 -421.033414) (xy 379.702723 -420.979456)
			(xy 378.265212 -420.979456) (xy 378.257456 -421.033399) (xy 378.2421 -421.085694) (xy 378.219458 -421.135271)
			(xy 378.189991 -421.181122) (xy 378.154299 -421.222311) (xy 378.113107 -421.258002) (xy 378.067256 -421.287467)
			(xy 378.017677 -421.310107) (xy 377.965382 -421.32546) (xy 377.911433 -421.333214) (xy 377.884182 -421.333676)
			(xy 377.020582 -421.333676) (xy 376.993329 -421.333253) (xy 376.939379 -421.325494) (xy 376.887082 -421.310136)
			(xy 376.837503 -421.287492) (xy 376.791651 -421.258022) (xy 376.750459 -421.222328) (xy 376.714767 -421.181135)
			(xy 376.6853 -421.135281) (xy 376.662658 -421.085701) (xy 376.647303 -421.033403) (xy 376.639546 -420.979453)
			(xy 375.201889 -420.979453) (xy 375.194135 -421.033386) (xy 375.178783 -421.085673) (xy 375.156147 -421.135244)
			(xy 375.126687 -421.181088) (xy 375.091003 -421.222274) (xy 375.049822 -421.257962) (xy 375.003981 -421.287427)
			(xy 374.954413 -421.310069) (xy 374.902128 -421.325426) (xy 374.848189 -421.333187) (xy 374.820942 -421.333676)
			(xy 373.957342 -421.333676) (xy 373.930085 -421.33328) (xy 373.876125 -421.325527) (xy 373.823817 -421.310173)
			(xy 373.774228 -421.287531) (xy 373.728366 -421.258062) (xy 373.687164 -421.222365) (xy 373.651463 -421.181168)
			(xy 373.621989 -421.135309) (xy 373.599341 -421.085722) (xy 373.583982 -421.033416) (xy 373.576223 -420.979457)
			(xy 372.138689 -420.979457) (xy 372.130934 -421.033392) (xy 372.11558 -421.085682) (xy 372.092941 -421.135255)
			(xy 372.063478 -421.181101) (xy 372.027789 -421.222288) (xy 371.986603 -421.257976) (xy 371.940757 -421.28744)
			(xy 371.891184 -421.31008) (xy 371.838894 -421.325434) (xy 371.784951 -421.33319) (xy 371.757702 -421.333676)
			(xy 370.894102 -421.333676) (xy 370.866847 -421.333277) (xy 370.812891 -421.32552) (xy 370.760588 -421.310163)
			(xy 370.711004 -421.287518) (xy 370.665147 -421.258048) (xy 370.62395 -421.222351) (xy 370.588253 -421.181155)
			(xy 370.558783 -421.135298) (xy 370.536138 -421.085713) (xy 370.520781 -421.033411) (xy 370.513023 -420.979455)
			(xy 370.117116 -420.979455) (xy 370.117116 -421.134032) (xy 370.118827 -421.145443) (xy 370.130963 -421.165042)
			(xy 370.150431 -421.17739) (xy 370.16182 -421.179244) (xy 370.26596 -421.179244) (xy 370.313204 -421.179244)
			(xy 370.313204 -421.230044) (xy 370.313204 -422.692576) (xy 370.312768 -422.702798) (xy 370.30495 -422.721687)
			(xy 370.290497 -422.736144) (xy 370.27161 -422.743966) (xy 370.261388 -422.744392) (xy 365.362744 -422.744392)
			(xy 365.352522 -422.743952) (xy 365.333631 -422.736138) (xy 365.319173 -422.721686) (xy 365.311352 -422.702798)
			(xy 365.310928 -422.692576) (xy 360.222212 -422.692576) (xy 360.286426 -422.706639) (xy 360.410636 -422.74198)
			(xy 360.532435 -422.7849) (xy 360.65136 -422.835237) (xy 360.766961 -422.892799) (xy 360.8788 -422.957369)
			(xy 360.986451 -423.028701) (xy 361.089506 -423.106525) (xy 361.187576 -423.190546) (xy 361.280287 -423.280445)
			(xy 361.367287 -423.37588) (xy 361.448248 -423.47649) (xy 361.505055 -423.556738) (xy 456.285335 -423.556738)
			(xy 456.285335 -423.427598) (xy 456.293285 -423.298703) (xy 456.309155 -423.170543) (xy 456.332884 -423.043602)
			(xy 456.364383 -422.918363) (xy 456.403532 -422.7953) (xy 456.450183 -422.674881) (xy 456.504158 -422.557562)
			(xy 456.565253 -422.443788) (xy 456.633236 -422.333991) (xy 456.70785 -422.228588) (xy 456.788811 -422.127978)
			(xy 456.875811 -422.032543) (xy 456.968522 -421.942644) (xy 457.066592 -421.858623) (xy 457.169647 -421.780799)
			(xy 457.277298 -421.709467) (xy 457.389137 -421.644897) (xy 457.504738 -421.587335) (xy 457.623663 -421.536998)
			(xy 457.745462 -421.494078) (xy 457.869672 -421.458737) (xy 457.995821 -421.43111) (xy 458.123433 -421.411301)
			(xy 458.252022 -421.399385) (xy 458.3811 -421.395409) (xy 458.510178 -421.399385) (xy 458.638767 -421.411301)
			(xy 458.766379 -421.43111) (xy 458.892528 -421.458737) (xy 459.016738 -421.494078) (xy 459.138537 -421.536998)
			(xy 459.257462 -421.587335) (xy 459.373063 -421.644897) (xy 459.484902 -421.709467) (xy 459.592553 -421.780799)
			(xy 459.695608 -421.858623) (xy 459.793678 -421.942644) (xy 459.886389 -422.032543) (xy 459.973389 -422.127978)
			(xy 460.05435 -422.228588) (xy 460.128964 -422.333991) (xy 460.196947 -422.443788) (xy 460.258042 -422.557562)
			(xy 460.312017 -422.674881) (xy 460.358668 -422.7953) (xy 460.397817 -422.918363) (xy 460.429316 -423.043602)
			(xy 460.453045 -423.170543) (xy 460.468915 -423.298703) (xy 460.476865 -423.427598) (xy 460.477362 -423.492168)
			(xy 460.476865 -423.556738) (xy 460.468915 -423.685633) (xy 460.453045 -423.813793) (xy 460.429316 -423.940734)
			(xy 460.397817 -424.065973) (xy 460.358668 -424.189036) (xy 460.312017 -424.309455) (xy 460.258042 -424.426774)
			(xy 460.196947 -424.540548) (xy 460.128964 -424.650345) (xy 460.05435 -424.755748) (xy 459.973389 -424.856358)
			(xy 459.886389 -424.951793) (xy 459.793678 -425.041692) (xy 459.695608 -425.125713) (xy 459.592553 -425.203537)
			(xy 459.484902 -425.274869) (xy 459.373063 -425.339439) (xy 459.257462 -425.397001) (xy 459.138537 -425.447338)
			(xy 459.016738 -425.490258) (xy 458.892528 -425.525599) (xy 458.766379 -425.553226) (xy 458.638767 -425.573035)
			(xy 458.510178 -425.584951) (xy 458.3811 -425.588928) (xy 458.252022 -425.584951) (xy 458.123433 -425.573035)
			(xy 457.995821 -425.553226) (xy 457.869672 -425.525599) (xy 457.745462 -425.490258) (xy 457.623663 -425.447338)
			(xy 457.504738 -425.397001) (xy 457.389137 -425.339439) (xy 457.277298 -425.274869) (xy 457.169647 -425.203537)
			(xy 457.066592 -425.125713) (xy 456.968522 -425.041692) (xy 456.875811 -424.951793) (xy 456.788811 -424.856358)
			(xy 456.70785 -424.755748) (xy 456.633236 -424.650345) (xy 456.565253 -424.540548) (xy 456.504158 -424.426774)
			(xy 456.450183 -424.309455) (xy 456.403532 -424.189036) (xy 456.364383 -424.065973) (xy 456.332884 -423.940734)
			(xy 456.309155 -423.813793) (xy 456.293285 -423.685633) (xy 456.285335 -423.556738) (xy 361.505055 -423.556738)
			(xy 361.522862 -423.581893) (xy 361.590845 -423.69169) (xy 361.65194 -423.805464) (xy 361.705915 -423.922783)
			(xy 361.752566 -424.043202) (xy 361.791715 -424.166265) (xy 361.823214 -424.291504) (xy 361.846943 -424.418445)
			(xy 361.862813 -424.546605) (xy 361.870763 -424.6755) (xy 361.87126 -424.74007) (xy 361.870763 -424.80464)
			(xy 361.862813 -424.933535) (xy 361.846943 -425.061695) (xy 361.823214 -425.188636) (xy 361.791715 -425.313875)
			(xy 361.752566 -425.436938) (xy 361.705915 -425.557357) (xy 361.65194 -425.674676) (xy 361.590845 -425.78845)
			(xy 361.522862 -425.898247) (xy 361.448248 -426.00365) (xy 361.367287 -426.10426) (xy 361.280287 -426.199695)
			(xy 361.187576 -426.289594) (xy 361.089506 -426.373615) (xy 360.986451 -426.451439) (xy 360.8788 -426.522771)
			(xy 360.766961 -426.587341) (xy 360.65136 -426.644903) (xy 360.532435 -426.69524) (xy 360.410636 -426.73816)
			(xy 360.286426 -426.773501) (xy 360.160277 -426.801128) (xy 360.032665 -426.820937) (xy 359.904076 -426.832853)
			(xy 359.774998 -426.83683) (xy 359.64592 -426.832853) (xy 359.517331 -426.820937) (xy 359.389719 -426.801128)
			(xy 359.26357 -426.773501) (xy 359.13936 -426.73816) (xy 359.017561 -426.69524) (xy 358.898636 -426.644903)
			(xy 358.783035 -426.587341) (xy 358.671196 -426.522771) (xy 358.563545 -426.451439) (xy 358.46049 -426.373615)
			(xy 358.36242 -426.289594) (xy 358.269709 -426.199695) (xy 358.182709 -426.10426) (xy 358.101748 -426.00365)
			(xy 358.027134 -425.898247) (xy 357.959151 -425.78845) (xy 357.898056 -425.674676) (xy 357.844081 -425.557357)
			(xy 357.79743 -425.436938) (xy 357.758281 -425.313875) (xy 357.726782 -425.188636) (xy 357.703053 -425.061695)
			(xy 357.687183 -424.933535) (xy 357.679233 -424.80464) (xy 230.3145 -424.80464) (xy 230.3145 -427.289976)
			(xy 314.137548 -427.289976) (xy 314.137665 -427.275593) (xy 314.139315 -427.246874) (xy 314.14085 -427.232572)
			(xy 314.141104 -427.22673) (xy 314.141104 -426.153072) (xy 314.14085 -426.14723) (xy 314.139321 -426.132928)
			(xy 314.13767 -426.104209) (xy 314.137548 -426.089826) (xy 314.137661 -426.075443) (xy 314.139314 -426.046723)
			(xy 314.14085 -426.032422) (xy 314.141104 -426.02658) (xy 314.141104 -425.419012) (xy 314.14157 -425.406962)
			(xy 314.149 -425.384036) (xy 314.163139 -425.36452) (xy 314.182609 -425.350316) (xy 314.20551 -425.342811)
			(xy 314.217558 -425.342304) (xy 315.157866 -425.342304) (xy 315.16995 -425.342836) (xy 315.192944 -425.350279)
			(xy 315.212521 -425.36445) (xy 315.226774 -425.383968) (xy 315.234313 -425.40693) (xy 315.234828 -425.419012)
			(xy 315.234828 -427.960536) (xy 315.234371 -427.972585) (xy 315.226932 -427.995507) (xy 315.21279 -428.01502)
			(xy 315.193321 -428.029223) (xy 315.170422 -428.036734) (xy 315.158374 -428.037244) (xy 314.218066 -428.037244)
			(xy 314.205973 -428.036821) (xy 314.182969 -428.029353) (xy 314.163388 -428.015156) (xy 314.149139 -427.995612)
			(xy 314.141611 -427.972628) (xy 314.141104 -427.960536) (xy 314.141104 -427.353222) (xy 314.14085 -427.34738)
			(xy 314.139325 -427.333078) (xy 314.137672 -427.304359) (xy 314.137548 -427.289976) (xy 230.3145 -427.289976)
			(xy 230.3145 -428.28972) (xy 316.137544 -428.28972) (xy 316.137656 -428.275337) (xy 316.139309 -428.246617)
			(xy 316.140846 -428.232316) (xy 316.1411 -428.226474) (xy 316.1411 -427.15307) (xy 316.140846 -427.147228)
			(xy 316.139317 -427.132926) (xy 316.137666 -427.104207) (xy 316.137544 -427.089824) (xy 316.137656 -427.075441)
			(xy 316.139309 -427.046721) (xy 316.140846 -427.03242) (xy 316.1411 -427.026578) (xy 316.1411 -426.41901)
			(xy 316.14162 -426.4069) (xy 316.1491 -426.383863) (xy 316.163331 -426.364265) (xy 316.18292 -426.350022)
			(xy 316.205952 -426.342527) (xy 316.218062 -426.342048) (xy 317.157862 -426.342048) (xy 317.169984 -426.342492)
			(xy 317.193043 -426.349975) (xy 317.21266 -426.36422) (xy 317.226912 -426.383832) (xy 317.234403 -426.406888)
			(xy 317.234824 -426.41901) (xy 317.234824 -427.289976) (xy 318.13754 -427.289976) (xy 318.137656 -427.275593)
			(xy 318.139307 -427.246874) (xy 318.140842 -427.232572) (xy 318.141096 -427.22673) (xy 318.141096 -426.153072)
			(xy 318.140842 -426.14723) (xy 318.139313 -426.132928) (xy 318.137662 -426.104209) (xy 318.13754 -426.089826)
			(xy 318.137652 -426.075443) (xy 318.139306 -426.046723) (xy 318.140842 -426.032422) (xy 318.141096 -426.02658)
			(xy 318.141096 -425.419012) (xy 318.14157 -425.406963) (xy 318.148999 -425.384038) (xy 318.163136 -425.364523)
			(xy 318.182604 -425.350319) (xy 318.205503 -425.342812) (xy 318.21755 -425.342304) (xy 319.157858 -425.342304)
			(xy 319.169942 -425.342842) (xy 319.192935 -425.350283) (xy 319.212513 -425.364453) (xy 319.226766 -425.383969)
			(xy 319.234305 -425.40693) (xy 319.23482 -425.419012) (xy 319.23482 -427.960536) (xy 319.234371 -427.972586)
			(xy 319.226931 -427.99551) (xy 319.212787 -428.015023) (xy 319.193316 -428.029226) (xy 319.170415 -428.036735)
			(xy 319.158366 -428.037244) (xy 318.218058 -428.037244) (xy 318.205965 -428.036828) (xy 318.18296 -428.029358)
			(xy 318.163379 -428.015159) (xy 318.149131 -427.995614) (xy 318.141603 -427.972628) (xy 318.141096 -427.960536)
			(xy 318.141096 -427.353222) (xy 318.140842 -427.34738) (xy 318.139317 -427.333078) (xy 318.137664 -427.304359)
			(xy 318.13754 -427.289976) (xy 317.234824 -427.289976) (xy 317.234824 -428.28972) (xy 320.137536 -428.28972)
			(xy 320.137648 -428.275337) (xy 320.139301 -428.246617) (xy 320.140838 -428.232316) (xy 320.141092 -428.226474)
			(xy 320.141092 -427.15307) (xy 320.140838 -427.147228) (xy 320.139308 -427.132926) (xy 320.137658 -427.104207)
			(xy 320.137536 -427.089824) (xy 320.137648 -427.075441) (xy 320.139301 -427.046721) (xy 320.140838 -427.03242)
			(xy 320.141092 -427.026578) (xy 320.141092 -426.41901) (xy 320.14162 -426.406901) (xy 320.149099 -426.383865)
			(xy 320.163328 -426.364268) (xy 320.182915 -426.350024) (xy 320.205945 -426.342528) (xy 320.218054 -426.342048)
			(xy 321.157854 -426.342048) (xy 321.169975 -426.342499) (xy 321.193034 -426.34998) (xy 321.212651 -426.364223)
			(xy 321.226904 -426.383833) (xy 321.234395 -426.406889) (xy 321.234816 -426.41901) (xy 321.234816 -427.289976)
			(xy 322.137532 -427.289976) (xy 322.137648 -427.275593) (xy 322.139299 -427.246874) (xy 322.140834 -427.232572)
			(xy 322.141088 -427.22673) (xy 322.141088 -426.153072) (xy 322.140834 -426.14723) (xy 322.139305 -426.132928)
			(xy 322.137654 -426.104209) (xy 322.137532 -426.089826) (xy 322.137644 -426.075443) (xy 322.139298 -426.046723)
			(xy 322.140834 -426.032422) (xy 322.141088 -426.02658) (xy 322.141088 -425.419012) (xy 322.14157 -425.406964)
			(xy 322.148998 -425.38404) (xy 322.163133 -425.364526) (xy 322.182598 -425.350321) (xy 322.205495 -425.342813)
			(xy 322.217542 -425.342304) (xy 323.15785 -425.342304) (xy 323.169933 -425.342849) (xy 323.192926 -425.350288)
			(xy 323.212504 -425.364455) (xy 323.226758 -425.383971) (xy 323.234297 -425.406931) (xy 323.234812 -425.419012)
			(xy 323.234812 -427.960536) (xy 323.234371 -427.972587) (xy 323.22693 -427.995512) (xy 323.212784 -428.015026)
			(xy 323.193311 -428.029228) (xy 323.170407 -428.036736) (xy 323.158358 -428.037244) (xy 322.21805 -428.037244)
			(xy 322.205961 -428.03675) (xy 322.18296 -428.029305) (xy 322.163378 -428.015126) (xy 322.149126 -427.995597)
			(xy 322.141595 -427.972623) (xy 322.141088 -427.960536) (xy 322.141088 -427.353222) (xy 322.140834 -427.34738)
			(xy 322.139309 -427.333078) (xy 322.137656 -427.304359) (xy 322.137532 -427.289976) (xy 321.234816 -427.289976)
			(xy 321.234816 -428.28972) (xy 324.137528 -428.28972) (xy 324.13764 -428.275337) (xy 324.139293 -428.246617)
			(xy 324.14083 -428.232316) (xy 324.141084 -428.226474) (xy 324.141084 -427.15307) (xy 324.14083 -427.147228)
			(xy 324.1393 -427.132926) (xy 324.13765 -427.104207) (xy 324.137528 -427.089824) (xy 324.13764 -427.075441)
			(xy 324.139294 -427.046721) (xy 324.14083 -427.03242) (xy 324.141084 -427.026578) (xy 324.141084 -426.41901)
			(xy 324.141469 -426.406883) (xy 324.148964 -426.383817) (xy 324.163223 -426.364198) (xy 324.182849 -426.349948)
			(xy 324.205919 -426.342464) (xy 324.218046 -426.342048) (xy 325.157846 -426.342048) (xy 325.169964 -426.342473)
			(xy 325.19301 -426.349974) (xy 325.212612 -426.364228) (xy 325.226852 -426.38384) (xy 325.234336 -426.406892)
			(xy 325.234808 -426.41901) (xy 325.234808 -427.289976) (xy 326.137524 -427.289976) (xy 326.137641 -427.275593)
			(xy 326.139291 -427.246874) (xy 326.140826 -427.232572) (xy 326.14108 -427.22673) (xy 326.14108 -426.153072)
			(xy 326.140826 -426.14723) (xy 326.139297 -426.132928) (xy 326.137646 -426.104209) (xy 326.137524 -426.089826)
			(xy 326.137636 -426.075443) (xy 326.13929 -426.046723) (xy 326.140826 -426.032422) (xy 326.14108 -426.02658)
			(xy 326.14108 -425.419012) (xy 326.14157 -425.406964) (xy 326.148997 -425.384043) (xy 326.163131 -425.364528)
			(xy 326.182593 -425.350324) (xy 326.205488 -425.342814) (xy 326.217534 -425.342304) (xy 327.157842 -425.342304)
			(xy 327.16993 -425.342771) (xy 327.192926 -425.350235) (xy 327.212502 -425.364423) (xy 327.226753 -425.383953)
			(xy 327.23429 -425.406925) (xy 327.234804 -425.419012) (xy 327.234804 -427.960536) (xy 327.234371 -427.972588)
			(xy 327.226929 -427.995514) (xy 327.212781 -428.015029) (xy 327.193306 -428.029231) (xy 327.1704 -428.036737)
			(xy 327.15835 -428.037244) (xy 326.218042 -428.037244) (xy 326.205953 -428.036757) (xy 326.182951 -428.029309)
			(xy 326.163369 -428.015129) (xy 326.149118 -427.995598) (xy 326.141587 -427.972623) (xy 326.14108 -427.960536)
			(xy 326.14108 -427.353222) (xy 326.140826 -427.34738) (xy 326.139301 -427.333078) (xy 326.137648 -427.304359)
			(xy 326.137524 -427.289976) (xy 325.234808 -427.289976) (xy 325.234808 -428.28972) (xy 328.13752 -428.28972)
			(xy 328.137632 -428.275337) (xy 328.139285 -428.246617) (xy 328.140822 -428.232316) (xy 328.141076 -428.226474)
			(xy 328.141076 -427.15307) (xy 328.140822 -427.147228) (xy 328.139292 -427.132926) (xy 328.137642 -427.104207)
			(xy 328.13752 -427.089824) (xy 328.137632 -427.075441) (xy 328.139286 -427.046721) (xy 328.140822 -427.03242)
			(xy 328.141076 -427.026578) (xy 328.141076 -426.41901) (xy 328.141469 -426.406884) (xy 328.148963 -426.383819)
			(xy 328.16322 -426.364201) (xy 328.182844 -426.34995) (xy 328.205912 -426.342465) (xy 328.218038 -426.342048)
			(xy 329.157838 -426.342048) (xy 329.169956 -426.342479) (xy 329.193002 -426.349978) (xy 329.212604 -426.36423)
			(xy 329.226844 -426.383841) (xy 329.234328 -426.406892) (xy 329.2348 -426.41901) (xy 329.2348 -427.289976)
			(xy 331.137768 -427.289976) (xy 331.137885 -427.275593) (xy 331.139535 -427.246874) (xy 331.14107 -427.232572)
			(xy 331.141324 -427.22673) (xy 331.141324 -426.153072) (xy 331.14107 -426.14723) (xy 331.13954 -426.132928)
			(xy 331.13789 -426.104209) (xy 331.137768 -426.089826) (xy 331.137881 -426.075443) (xy 331.139534 -426.046723)
			(xy 331.14107 -426.032422) (xy 331.141324 -426.02658) (xy 331.141324 -425.419012) (xy 331.141724 -425.406927)
			(xy 331.149192 -425.383939) (xy 331.1634 -425.364386) (xy 331.182957 -425.350183) (xy 331.205947 -425.34272)
			(xy 331.218032 -425.342304) (xy 332.157832 -425.342304) (xy 332.169909 -425.342737) (xy 332.19288 -425.35021)
			(xy 332.212417 -425.364414) (xy 332.22661 -425.38396) (xy 332.23407 -425.406934) (xy 332.23454 -425.419012)
			(xy 332.23454 -427.960536) (xy 332.234067 -427.972609) (xy 332.226599 -427.995572) (xy 332.212403 -428.015106)
			(xy 332.192869 -428.0293) (xy 332.169905 -428.036768) (xy 332.157832 -428.037244) (xy 331.218032 -428.037244)
			(xy 331.205963 -428.036709) (xy 331.183003 -428.02926) (xy 331.163468 -428.01508) (xy 331.149271 -427.995558)
			(xy 331.141801 -427.972605) (xy 331.141324 -427.960536) (xy 331.141324 -427.353222) (xy 331.14107 -427.34738)
			(xy 331.139545 -427.333078) (xy 331.137892 -427.304359) (xy 331.137768 -427.289976) (xy 329.2348 -427.289976)
			(xy 329.2348 -428.28972) (xy 333.137764 -428.28972) (xy 333.137876 -428.275337) (xy 333.13953 -428.246617)
			(xy 333.141066 -428.232316) (xy 333.14132 -428.226474) (xy 333.14132 -427.15307) (xy 333.141066 -427.147228)
			(xy 333.139536 -427.132926) (xy 333.137886 -427.104207) (xy 333.137764 -427.089824) (xy 333.137877 -427.075441)
			(xy 333.13953 -427.046721) (xy 333.141066 -427.03242) (xy 333.14132 -427.026578) (xy 333.14132 -426.41901)
			(xy 333.141816 -426.406923) (xy 333.149267 -426.383926) (xy 333.163447 -426.364348) (xy 333.182973 -426.350096)
			(xy 333.205943 -426.34256) (xy 333.218028 -426.342048) (xy 334.157828 -426.342048) (xy 334.169933 -426.342492)
			(xy 334.192952 -426.349993) (xy 334.212521 -426.364249) (xy 334.226716 -426.383861) (xy 334.234145 -426.406904)
			(xy 334.234536 -426.41901) (xy 334.234536 -427.289976) (xy 335.13776 -427.289976) (xy 335.137877 -427.275593)
			(xy 335.139527 -427.246874) (xy 335.141062 -427.232572) (xy 335.141316 -427.22673) (xy 335.141316 -426.153072)
			(xy 335.141062 -426.14723) (xy 335.139533 -426.132928) (xy 335.137882 -426.104209) (xy 335.13776 -426.089826)
			(xy 335.137873 -426.075443) (xy 335.139526 -426.046723) (xy 335.141062 -426.032422) (xy 335.141316 -426.02658)
			(xy 335.141316 -425.419012) (xy 335.141723 -425.406928) (xy 335.149191 -425.383941) (xy 335.163397 -425.364389)
			(xy 335.182952 -425.350185) (xy 335.205939 -425.342722) (xy 335.218024 -425.342304) (xy 336.157824 -425.342304)
			(xy 336.169901 -425.342744) (xy 336.192871 -425.350215) (xy 336.212409 -425.364417) (xy 336.226602 -425.383961)
			(xy 336.234061 -425.406935) (xy 336.234532 -425.419012) (xy 336.234532 -427.960536) (xy 336.234067 -427.97261)
			(xy 336.226598 -427.995574) (xy 336.2124 -428.015109) (xy 336.192864 -428.029303) (xy 336.169898 -428.036769)
			(xy 336.157824 -428.037244) (xy 335.218024 -428.037244) (xy 335.205954 -428.036716) (xy 335.182994 -428.029264)
			(xy 335.16346 -428.015083) (xy 335.149263 -427.99556) (xy 335.141793 -427.972605) (xy 335.141316 -427.960536)
			(xy 335.141316 -427.353222) (xy 335.141062 -427.34738) (xy 335.139537 -427.333078) (xy 335.137884 -427.304359)
			(xy 335.13776 -427.289976) (xy 334.234536 -427.289976) (xy 334.234536 -428.28972) (xy 337.137756 -428.28972)
			(xy 337.137868 -428.275337) (xy 337.139522 -428.246617) (xy 337.141058 -428.232316) (xy 337.141312 -428.226474)
			(xy 337.141312 -427.15307) (xy 337.141058 -427.147228) (xy 337.139529 -427.132926) (xy 337.137878 -427.104207)
			(xy 337.137756 -427.089824) (xy 337.137869 -427.075441) (xy 337.139522 -427.046721) (xy 337.141058 -427.03242)
			(xy 337.141312 -427.026578) (xy 337.141312 -426.41901) (xy 337.141815 -426.406924) (xy 337.149266 -426.383928)
			(xy 337.163444 -426.364351) (xy 337.182968 -426.350099) (xy 337.205936 -426.342562) (xy 337.21802 -426.342048)
			(xy 338.15782 -426.342048) (xy 338.169925 -426.342499) (xy 338.192944 -426.349997) (xy 338.212512 -426.364252)
			(xy 338.226708 -426.383863) (xy 338.234137 -426.406904) (xy 338.234528 -426.41901) (xy 338.234528 -427.289976)
			(xy 339.137752 -427.289976) (xy 339.137869 -427.275593) (xy 339.139519 -427.246874) (xy 339.141054 -427.232572)
			(xy 339.141308 -427.22673) (xy 339.141308 -426.153072) (xy 339.141054 -426.14723) (xy 339.139525 -426.132928)
			(xy 339.137874 -426.104209) (xy 339.137752 -426.089826) (xy 339.137865 -426.075443) (xy 339.139518 -426.046723)
			(xy 339.141054 -426.032422) (xy 339.141308 -426.02658) (xy 339.141308 -425.419012) (xy 339.141723 -425.406928)
			(xy 339.149189 -425.383943) (xy 339.163394 -425.364392) (xy 339.182947 -425.350188) (xy 339.205932 -425.342723)
			(xy 339.218016 -425.342304) (xy 340.157816 -425.342304) (xy 340.169893 -425.342751) (xy 340.192862 -425.350219)
			(xy 340.2124 -425.36442) (xy 340.226594 -425.383963) (xy 340.234053 -425.406935) (xy 340.234524 -425.419012)
			(xy 340.234524 -427.960536) (xy 340.234067 -427.972611) (xy 340.226596 -427.995577) (xy 340.212397 -428.015112)
			(xy 340.192859 -428.029306) (xy 340.169891 -428.03677) (xy 340.157816 -428.037244) (xy 339.218016 -428.037244)
			(xy 339.205946 -428.036723) (xy 339.182985 -428.029269) (xy 339.163451 -428.015086) (xy 339.149255 -427.995561)
			(xy 339.141785 -427.972606) (xy 339.141308 -427.960536) (xy 339.141308 -427.353222) (xy 339.141054 -427.34738)
			(xy 339.139529 -427.333078) (xy 339.137876 -427.304359) (xy 339.137752 -427.289976) (xy 338.234528 -427.289976)
			(xy 338.234528 -428.28972) (xy 341.137748 -428.28972) (xy 341.13786 -428.275337) (xy 341.139514 -428.246617)
			(xy 341.14105 -428.232316) (xy 341.141304 -428.226474) (xy 341.141304 -427.15307) (xy 341.14105 -427.147228)
			(xy 341.139521 -427.132926) (xy 341.13787 -427.104207) (xy 341.137748 -427.089824) (xy 341.137861 -427.075441)
			(xy 341.139514 -427.046721) (xy 341.14105 -427.03242) (xy 341.141304 -427.026578) (xy 341.141304 -426.41901)
			(xy 341.141815 -426.406925) (xy 341.149265 -426.38393) (xy 341.163441 -426.364353) (xy 341.182963 -426.350101)
			(xy 341.205928 -426.342563) (xy 341.218012 -426.342048) (xy 342.157812 -426.342048) (xy 342.169916 -426.342505)
			(xy 342.192935 -426.350002) (xy 342.212504 -426.364255) (xy 342.2267 -426.383864) (xy 342.234129 -426.406905)
			(xy 342.23452 -426.41901) (xy 342.23452 -427.289976) (xy 343.137744 -427.289976) (xy 343.13786 -427.275593)
			(xy 343.139511 -427.246874) (xy 343.141046 -427.232572) (xy 343.1413 -427.22673) (xy 343.1413 -426.153072)
			(xy 343.141046 -426.14723) (xy 343.139517 -426.132928) (xy 343.137866 -426.104209) (xy 343.137744 -426.089826)
			(xy 343.137856 -426.075443) (xy 343.13951 -426.046723) (xy 343.141046 -426.032422) (xy 343.1413 -426.02658)
			(xy 343.1413 -425.419012) (xy 343.141723 -425.406929) (xy 343.149188 -425.383946) (xy 343.163392 -425.364394)
			(xy 343.182942 -425.35019) (xy 343.205925 -425.342724) (xy 343.218008 -425.342304) (xy 344.157808 -425.342304)
			(xy 344.169892 -425.342706) (xy 344.192877 -425.350177) (xy 344.212429 -425.364386) (xy 344.226632 -425.383941)
			(xy 344.234097 -425.406928) (xy 344.234516 -425.419012) (xy 344.234516 -427.960536) (xy 344.234067 -427.972612)
			(xy 344.226595 -427.995579) (xy 344.212395 -428.015115) (xy 344.192854 -428.029308) (xy 344.169884 -428.036771)
			(xy 344.157808 -428.037244) (xy 343.218008 -428.037244) (xy 343.205937 -428.03673) (xy 343.182977 -428.029274)
			(xy 343.163443 -428.015089) (xy 343.149247 -427.995563) (xy 343.141777 -427.972606) (xy 343.1413 -427.960536)
			(xy 343.1413 -427.353222) (xy 343.141046 -427.34738) (xy 343.139521 -427.333078) (xy 343.137868 -427.304359)
			(xy 343.137744 -427.289976) (xy 342.23452 -427.289976) (xy 342.23452 -428.28972) (xy 345.13774 -428.28972)
			(xy 345.137852 -428.275337) (xy 345.139505 -428.246617) (xy 345.141042 -428.232316) (xy 345.141296 -428.226474)
			(xy 345.141296 -427.15307) (xy 345.141042 -427.147228) (xy 345.139513 -427.132926) (xy 345.137862 -427.104207)
			(xy 345.13774 -427.089824) (xy 345.137852 -427.075441) (xy 345.139505 -427.046721) (xy 345.141042 -427.03242)
			(xy 345.141296 -427.026578) (xy 345.141296 -426.41901) (xy 345.141815 -426.406925) (xy 345.149264 -426.383932)
			(xy 345.163439 -426.364356) (xy 345.182958 -426.350104) (xy 345.205921 -426.342564) (xy 345.218004 -426.342048)
			(xy 346.157804 -426.342048) (xy 346.169908 -426.342512) (xy 346.192927 -426.350006) (xy 346.212495 -426.364257)
			(xy 346.226691 -426.383866) (xy 346.234121 -426.406905) (xy 346.234512 -426.41901) (xy 346.234512 -427.289976)
			(xy 381.237744 -427.289976) (xy 381.23786 -427.275593) (xy 381.239511 -427.246874) (xy 381.241046 -427.232572)
			(xy 381.2413 -427.22673) (xy 381.2413 -426.153072) (xy 381.241046 -426.14723) (xy 381.239517 -426.132928)
			(xy 381.237866 -426.104209) (xy 381.237744 -426.089826) (xy 381.237856 -426.075443) (xy 381.23951 -426.046723)
			(xy 381.241046 -426.032422) (xy 381.2413 -426.02658) (xy 381.2413 -425.419012) (xy 381.241723 -425.406929)
			(xy 381.249188 -425.383946) (xy 381.263392 -425.364394) (xy 381.282942 -425.35019) (xy 381.305925 -425.342724)
			(xy 381.318008 -425.342304) (xy 382.257808 -425.342304) (xy 382.269892 -425.342706) (xy 382.292877 -425.350177)
			(xy 382.312429 -425.364386) (xy 382.326632 -425.383941) (xy 382.334097 -425.406928) (xy 382.334516 -425.419012)
			(xy 382.334516 -427.960536) (xy 382.334067 -427.972612) (xy 382.326595 -427.995579) (xy 382.312395 -428.015115)
			(xy 382.292854 -428.029308) (xy 382.269884 -428.036771) (xy 382.257808 -428.037244) (xy 381.318008 -428.037244)
			(xy 381.305937 -428.03673) (xy 381.282977 -428.029274) (xy 381.263443 -428.015089) (xy 381.249247 -427.995563)
			(xy 381.241777 -427.972606) (xy 381.2413 -427.960536) (xy 381.2413 -427.353222) (xy 381.241046 -427.34738)
			(xy 381.239521 -427.333078) (xy 381.237868 -427.304359) (xy 381.237744 -427.289976) (xy 346.234512 -427.289976)
			(xy 346.234512 -428.960534) (xy 346.234121 -428.97263) (xy 346.226649 -428.99564) (xy 346.212444 -429.015223)
			(xy 346.192892 -429.029471) (xy 346.169899 -429.036994) (xy 346.157804 -429.037496) (xy 345.218004 -429.037496)
			(xy 345.205895 -429.03708) (xy 345.182867 -429.029582) (xy 345.163293 -429.01532) (xy 345.149099 -428.995698)
			(xy 345.141679 -428.972644) (xy 345.141296 -428.960534) (xy 345.141296 -428.352966) (xy 345.141042 -428.347124)
			(xy 345.139512 -428.332822) (xy 345.137862 -428.304103) (xy 345.13774 -428.28972) (xy 342.23452 -428.28972)
			(xy 342.23452 -428.960534) (xy 342.234121 -428.972629) (xy 342.22665 -428.995638) (xy 342.212447 -429.015221)
			(xy 342.192897 -429.029469) (xy 342.169906 -429.036993) (xy 342.157812 -429.037496) (xy 341.218012 -429.037496)
			(xy 341.205903 -429.037073) (xy 341.182876 -429.029577) (xy 341.163302 -429.015317) (xy 341.149107 -428.995696)
			(xy 341.141687 -428.972644) (xy 341.141304 -428.960534) (xy 341.141304 -428.352966) (xy 341.14105 -428.347124)
			(xy 341.13952 -428.332822) (xy 341.13787 -428.304103) (xy 341.137748 -428.28972) (xy 338.234528 -428.28972)
			(xy 338.234528 -428.960534) (xy 338.234121 -428.972629) (xy 338.226651 -428.995636) (xy 338.21245 -429.015218)
			(xy 338.192902 -429.029466) (xy 338.169913 -429.036992) (xy 338.15782 -429.037496) (xy 337.21802 -429.037496)
			(xy 337.205912 -429.037066) (xy 337.182885 -429.029572) (xy 337.163311 -429.015314) (xy 337.149116 -428.995695)
			(xy 337.141695 -428.972643) (xy 337.141312 -428.960534) (xy 337.141312 -428.352966) (xy 337.141058 -428.347124)
			(xy 337.139528 -428.332822) (xy 337.137878 -428.304103) (xy 337.137756 -428.28972) (xy 334.234536 -428.28972)
			(xy 334.234536 -428.960534) (xy 334.234121 -428.972628) (xy 334.226652 -428.995634) (xy 334.212453 -429.015215)
			(xy 334.192907 -429.029464) (xy 334.16992 -429.03699) (xy 334.157828 -429.037496) (xy 333.218028 -429.037496)
			(xy 333.20592 -429.03706) (xy 333.182893 -429.029567) (xy 333.163319 -429.015311) (xy 333.149124 -428.995693)
			(xy 333.141703 -428.972643) (xy 333.14132 -428.960534) (xy 333.14132 -428.352966) (xy 333.141066 -428.347124)
			(xy 333.139536 -428.332822) (xy 333.137886 -428.304103) (xy 333.137764 -428.28972) (xy 329.2348 -428.28972)
			(xy 329.2348 -428.960534) (xy 329.234318 -428.972647) (xy 329.226826 -428.995684) (xy 329.212585 -429.015282)
			(xy 329.192988 -429.029524) (xy 329.169951 -429.037017) (xy 329.157838 -429.037496) (xy 328.218038 -429.037496)
			(xy 328.205921 -429.037008) (xy 328.182869 -429.029531) (xy 328.163256 -429.015295) (xy 328.149002 -428.995696)
			(xy 328.141503 -428.972651) (xy 328.141076 -428.960534) (xy 328.141076 -428.352966) (xy 328.140822 -428.347124)
			(xy 328.139292 -428.332822) (xy 328.137642 -428.304103) (xy 328.13752 -428.28972) (xy 325.234808 -428.28972)
			(xy 325.234808 -428.960534) (xy 325.234318 -428.972646) (xy 325.226827 -428.995682) (xy 325.212588 -429.01528)
			(xy 325.192993 -429.029522) (xy 325.169958 -429.037016) (xy 325.157846 -429.037496) (xy 324.218046 -429.037496)
			(xy 324.205929 -429.037002) (xy 324.182877 -429.029526) (xy 324.163264 -429.015292) (xy 324.149011 -428.995694)
			(xy 324.141511 -428.972651) (xy 324.141084 -428.960534) (xy 324.141084 -428.352966) (xy 324.14083 -428.347124)
			(xy 324.1393 -428.332822) (xy 324.13765 -428.304103) (xy 324.137528 -428.28972) (xy 321.234816 -428.28972)
			(xy 321.234816 -428.960534) (xy 321.234468 -428.972663) (xy 321.226961 -428.995731) (xy 321.212692 -429.015349)
			(xy 321.193059 -429.029598) (xy 321.169984 -429.037081) (xy 321.157854 -429.037496) (xy 320.218054 -429.037496)
			(xy 320.20594 -429.037028) (xy 320.182901 -429.029532) (xy 320.163303 -429.015288) (xy 320.149062 -428.995688)
			(xy 320.14157 -428.972648) (xy 320.141092 -428.960534) (xy 320.141092 -428.352966) (xy 320.140838 -428.347124)
			(xy 320.139308 -428.332822) (xy 320.137658 -428.304103) (xy 320.137536 -428.28972) (xy 317.234824 -428.28972)
			(xy 317.234824 -428.960534) (xy 317.234469 -428.972662) (xy 317.226962 -428.995729) (xy 317.212695 -429.015347)
			(xy 317.193064 -429.029595) (xy 317.169991 -429.03708) (xy 317.157862 -429.037496) (xy 316.218062 -429.037496)
			(xy 316.205949 -429.037021) (xy 316.18291 -429.029528) (xy 316.163312 -429.015285) (xy 316.14907 -428.995686)
			(xy 316.141578 -428.972647) (xy 316.1411 -428.960534) (xy 316.1411 -428.352966) (xy 316.140846 -428.347124)
			(xy 316.139316 -428.332822) (xy 316.137666 -428.304103) (xy 316.137544 -428.28972) (xy 230.3145 -428.28972)
			(xy 230.3145 -433.130695) (xy 266.885917 -433.130695) (xy 266.885917 -432.953425) (xy 266.89387 -432.776334)
			(xy 266.909761 -432.599778) (xy 266.933556 -432.424113) (xy 266.965209 -432.249692) (xy 267.004655 -432.076867)
			(xy 267.051815 -431.905986) (xy 267.106594 -431.737392) (xy 267.168882 -431.571427) (xy 267.238554 -431.408422)
			(xy 267.315468 -431.248708) (xy 267.399471 -431.092605) (xy 267.490392 -430.940428) (xy 267.588049 -430.792484)
			(xy 267.692246 -430.64907) (xy 267.802772 -430.510475) (xy 267.919404 -430.376978) (xy 268.041909 -430.248849)
			(xy 268.170038 -430.126344) (xy 268.303535 -430.009712) (xy 268.44213 -429.899186) (xy 268.585544 -429.794989)
			(xy 268.733488 -429.697332) (xy 268.885665 -429.606411) (xy 269.041768 -429.522408) (xy 269.201482 -429.445494)
			(xy 269.364487 -429.375822) (xy 269.530452 -429.313534) (xy 269.699046 -429.258755) (xy 269.869927 -429.211595)
			(xy 270.042752 -429.172149) (xy 270.217173 -429.140496) (xy 270.392838 -429.116701) (xy 270.569394 -429.10081)
			(xy 270.746485 -429.092857) (xy 270.923755 -429.092857) (xy 271.100846 -429.10081) (xy 271.277402 -429.116701)
			(xy 271.453067 -429.140496) (xy 271.627488 -429.172149) (xy 271.800313 -429.211595) (xy 271.971194 -429.258755)
			(xy 272.139788 -429.313534) (xy 272.305753 -429.375822) (xy 272.468758 -429.445494) (xy 272.628472 -429.522408)
			(xy 272.784575 -429.606411) (xy 272.936752 -429.697332) (xy 273.084696 -429.794989) (xy 273.22811 -429.899186)
			(xy 273.366705 -430.009712) (xy 273.500202 -430.126344) (xy 273.628331 -430.248849) (xy 273.750836 -430.376978)
			(xy 273.867468 -430.510475) (xy 273.977994 -430.64907) (xy 274.082191 -430.792484) (xy 274.146507 -430.889918)
			(xy 314.137548 -430.889918) (xy 314.13766 -430.875535) (xy 314.139314 -430.846815) (xy 314.14085 -430.832514)
			(xy 314.141104 -430.826672) (xy 314.141104 -429.753014) (xy 314.14085 -429.747172) (xy 314.139324 -429.73287)
			(xy 314.137671 -429.704151) (xy 314.137548 -429.689768) (xy 314.137664 -429.675385) (xy 314.139315 -429.646666)
			(xy 314.14085 -429.632364) (xy 314.141104 -429.626522) (xy 314.141104 -429.018954) (xy 314.141572 -429.00684)
			(xy 314.149068 -428.983801) (xy 314.163312 -428.964203) (xy 314.182912 -428.949962) (xy 314.205952 -428.94247)
			(xy 314.218066 -428.941992) (xy 315.157866 -428.941992) (xy 315.169974 -428.94254) (xy 315.193009 -428.950012)
			(xy 315.212607 -428.964236) (xy 315.226851 -428.98382) (xy 315.234347 -429.006846) (xy 315.234828 -429.018954)
			(xy 315.234828 -431.560478) (xy 315.234421 -431.572603) (xy 315.22693 -431.595667) (xy 315.212677 -431.615285)
			(xy 315.193056 -431.629536) (xy 315.169991 -431.637023) (xy 315.157866 -431.63744) (xy 314.218066 -431.63744)
			(xy 314.205947 -431.637017) (xy 314.182899 -431.629518) (xy 314.163296 -431.615264) (xy 314.149057 -431.59565)
			(xy 314.141574 -431.572597) (xy 314.141104 -431.560478) (xy 314.141104 -430.953164) (xy 314.14085 -430.947322)
			(xy 314.13932 -430.93302) (xy 314.13767 -430.904301) (xy 314.137548 -430.889918) (xy 274.146507 -430.889918)
			(xy 274.179848 -430.940428) (xy 274.270769 -431.092605) (xy 274.354772 -431.248708) (xy 274.431686 -431.408422)
			(xy 274.501358 -431.571427) (xy 274.563646 -431.737392) (xy 274.613204 -431.889916) (xy 316.137544 -431.889916)
			(xy 316.137655 -431.875533) (xy 316.139309 -431.846813) (xy 316.140846 -431.832512) (xy 316.1411 -431.82667)
			(xy 316.1411 -430.753012) (xy 316.140846 -430.74717) (xy 316.13932 -430.732868) (xy 316.137667 -430.704149)
			(xy 316.137544 -430.689766) (xy 316.13766 -430.675383) (xy 316.139311 -430.646664) (xy 316.140846 -430.632362)
			(xy 316.1411 -430.62652) (xy 316.1411 -430.018952) (xy 316.141519 -430.006899) (xy 316.148965 -429.983972)
			(xy 316.163116 -429.964457) (xy 316.182595 -429.950255) (xy 316.205503 -429.94275) (xy 316.217554 -429.942244)
			(xy 317.157862 -429.942244) (xy 317.16995 -429.94274) (xy 317.19295 -429.950187) (xy 317.212531 -429.964366)
			(xy 317.226783 -429.983894) (xy 317.234315 -430.006866) (xy 317.234824 -430.018952) (xy 317.234824 -430.889918)
			(xy 318.13754 -430.889918) (xy 318.137652 -430.875535) (xy 318.139305 -430.846815) (xy 318.140842 -430.832514)
			(xy 318.141096 -430.826672) (xy 318.141096 -429.753014) (xy 318.140842 -429.747172) (xy 318.139316 -429.73287)
			(xy 318.137663 -429.704151) (xy 318.13754 -429.689768) (xy 318.137656 -429.675385) (xy 318.139307 -429.646666)
			(xy 318.140842 -429.632364) (xy 318.141096 -429.626522) (xy 318.141096 -429.018954) (xy 318.141572 -429.006841)
			(xy 318.149067 -428.983804) (xy 318.163309 -428.964206) (xy 318.182907 -428.949965) (xy 318.205945 -428.942471)
			(xy 318.218058 -428.941992) (xy 319.157858 -428.941992) (xy 319.169966 -428.942547) (xy 319.193 -428.950017)
			(xy 319.212598 -428.964239) (xy 319.226843 -428.983821) (xy 319.234339 -429.006847) (xy 319.23482 -429.018954)
			(xy 319.23482 -431.560478) (xy 319.234421 -431.572604) (xy 319.226929 -431.595669) (xy 319.212674 -431.615288)
			(xy 319.193051 -431.629538) (xy 319.169984 -431.637024) (xy 319.157858 -431.63744) (xy 318.218058 -431.63744)
			(xy 318.205939 -431.637024) (xy 318.182891 -431.629522) (xy 318.163288 -431.615267) (xy 318.149048 -431.595652)
			(xy 318.141566 -431.572597) (xy 318.141096 -431.560478) (xy 318.141096 -430.953164) (xy 318.140842 -430.947322)
			(xy 318.139312 -430.93302) (xy 318.137662 -430.904301) (xy 318.13754 -430.889918) (xy 317.234824 -430.889918)
			(xy 317.234824 -431.889916) (xy 320.137536 -431.889916) (xy 320.137647 -431.875533) (xy 320.139301 -431.846813)
			(xy 320.140838 -431.832512) (xy 320.141092 -431.82667) (xy 320.141092 -430.753012) (xy 320.140838 -430.74717)
			(xy 320.139312 -430.732868) (xy 320.137659 -430.704149) (xy 320.137536 -430.689766) (xy 320.137652 -430.675383)
			(xy 320.139303 -430.646664) (xy 320.140838 -430.632362) (xy 320.141092 -430.62652) (xy 320.141092 -430.018952)
			(xy 320.141519 -430.0069) (xy 320.148964 -429.983974) (xy 320.163113 -429.96446) (xy 320.18259 -429.950258)
			(xy 320.205495 -429.942752) (xy 320.217546 -429.942244) (xy 321.157854 -429.942244) (xy 321.169942 -429.942747)
			(xy 321.192941 -429.950191) (xy 321.212522 -429.964368) (xy 321.226774 -429.983895) (xy 321.234307 -430.006866)
			(xy 321.234816 -430.018952) (xy 321.234816 -430.889918) (xy 322.137532 -430.889918) (xy 322.137644 -430.875535)
			(xy 322.139297 -430.846815) (xy 322.140834 -430.832514) (xy 322.141088 -430.826672) (xy 322.141088 -429.753014)
			(xy 322.140834 -429.747172) (xy 322.139308 -429.73287) (xy 322.137655 -429.704151) (xy 322.137532 -429.689768)
			(xy 322.137648 -429.675385) (xy 322.139299 -429.646666) (xy 322.140834 -429.632364) (xy 322.141088 -429.626522)
			(xy 322.141088 -429.018954) (xy 322.141572 -429.006842) (xy 322.149066 -428.983806) (xy 322.163306 -428.964209)
			(xy 322.182902 -428.949967) (xy 322.205938 -428.942472) (xy 322.21805 -428.941992) (xy 323.15785 -428.941992)
			(xy 323.169963 -428.942468) (xy 323.193 -428.949964) (xy 323.212597 -428.964206) (xy 323.226838 -428.983804)
			(xy 323.234332 -429.006841) (xy 323.234812 -429.018954) (xy 323.234812 -431.560478) (xy 323.23427 -431.572586)
			(xy 323.226795 -431.59562) (xy 323.212569 -431.615218) (xy 323.192985 -431.629462) (xy 323.169958 -431.636959)
			(xy 323.15785 -431.63744) (xy 322.21805 -431.63744) (xy 322.205931 -431.63703) (xy 322.182882 -431.629527)
			(xy 322.163279 -431.615269) (xy 322.14904 -431.595653) (xy 322.141558 -431.572598) (xy 322.141088 -431.560478)
			(xy 322.141088 -430.953164) (xy 322.140834 -430.947322) (xy 322.139304 -430.93302) (xy 322.137654 -430.904301)
			(xy 322.137532 -430.889918) (xy 321.234816 -430.889918) (xy 321.234816 -431.889916) (xy 324.137528 -431.889916)
			(xy 324.137639 -431.875533) (xy 324.139293 -431.846813) (xy 324.14083 -431.832512) (xy 324.141084 -431.82667)
			(xy 324.141084 -430.753012) (xy 324.14083 -430.74717) (xy 324.139304 -430.732868) (xy 324.137651 -430.704149)
			(xy 324.137528 -430.689766) (xy 324.137644 -430.675383) (xy 324.139295 -430.646664) (xy 324.14083 -430.632362)
			(xy 324.141084 -430.62652) (xy 324.141084 -430.018952) (xy 324.141519 -430.006901) (xy 324.148963 -429.983976)
			(xy 324.163111 -429.964463) (xy 324.182585 -429.950261) (xy 324.205488 -429.942753) (xy 324.217538 -429.942244)
			(xy 325.157846 -429.942244) (xy 325.169938 -429.942668) (xy 325.192941 -429.950138) (xy 325.212521 -429.964336)
			(xy 325.22677 -429.983878) (xy 325.2343 -430.006861) (xy 325.234808 -430.018952) (xy 325.234808 -430.889918)
			(xy 326.137524 -430.889918) (xy 326.137636 -430.875535) (xy 326.139289 -430.846815) (xy 326.140826 -430.832514)
			(xy 326.14108 -430.826672) (xy 326.14108 -429.753014) (xy 326.140826 -429.747172) (xy 326.1393 -429.73287)
			(xy 326.137647 -429.704151) (xy 326.137524 -429.689768) (xy 326.13764 -429.675385) (xy 326.139291 -429.646666)
			(xy 326.140826 -429.632364) (xy 326.14108 -429.626522) (xy 326.14108 -429.018954) (xy 326.141473 -429.006833)
			(xy 326.148978 -428.983781) (xy 326.163239 -428.964176) (xy 326.18286 -428.949938) (xy 326.20592 -428.942459)
			(xy 326.218042 -428.941992) (xy 327.157842 -428.941992) (xy 327.169954 -428.942475) (xy 327.192991 -428.949968)
			(xy 327.212588 -428.964209) (xy 327.22683 -428.983805) (xy 327.234324 -429.006842) (xy 327.234804 -429.018954)
			(xy 327.234804 -431.560478) (xy 327.23427 -431.572587) (xy 327.226794 -431.595623) (xy 327.212567 -431.615221)
			(xy 327.19298 -431.629465) (xy 327.169951 -431.63696) (xy 327.157842 -431.63744) (xy 326.218042 -431.63744)
			(xy 326.205919 -431.637004) (xy 326.182858 -431.629521) (xy 326.16324 -431.615274) (xy 326.148988 -431.59566)
			(xy 326.141499 -431.572601) (xy 326.14108 -431.560478) (xy 326.14108 -430.953164) (xy 326.140826 -430.947322)
			(xy 326.139296 -430.93302) (xy 326.137646 -430.904301) (xy 326.137524 -430.889918) (xy 325.234808 -430.889918)
			(xy 325.234808 -431.889916) (xy 328.13752 -431.889916) (xy 328.137631 -431.875533) (xy 328.139285 -431.846813)
			(xy 328.140822 -431.832512) (xy 328.141076 -431.82667) (xy 328.141076 -430.753012) (xy 328.140822 -430.74717)
			(xy 328.139296 -430.732868) (xy 328.137643 -430.704149) (xy 328.13752 -430.689766) (xy 328.137636 -430.675383)
			(xy 328.139287 -430.646664) (xy 328.140822 -430.632362) (xy 328.141076 -430.62652) (xy 328.141076 -430.018952)
			(xy 328.141518 -430.006902) (xy 328.148961 -429.983979) (xy 328.163108 -429.964466) (xy 328.18258 -429.950263)
			(xy 328.205481 -429.942754) (xy 328.21753 -429.942244) (xy 329.157838 -429.942244) (xy 329.16993 -429.942675)
			(xy 329.192933 -429.950143) (xy 329.212512 -429.964338) (xy 329.226761 -429.983879) (xy 329.234292 -430.006861)
			(xy 329.2348 -430.018952) (xy 329.2348 -430.889918) (xy 331.137768 -430.889918) (xy 331.13788 -430.875535)
			(xy 331.139534 -430.846815) (xy 331.14107 -430.832514) (xy 331.141324 -430.826672) (xy 331.141324 -429.753014)
			(xy 331.14107 -429.747172) (xy 331.139544 -429.73287) (xy 331.137891 -429.704151) (xy 331.137768 -429.689768)
			(xy 331.137884 -429.675385) (xy 331.139535 -429.646666) (xy 331.14107 -429.632364) (xy 331.141324 -429.626522)
			(xy 331.141324 -429.018954) (xy 331.141768 -429.006864) (xy 331.149235 -428.983864) (xy 331.163428 -428.964286)
			(xy 331.182965 -428.950037) (xy 331.205943 -428.942503) (xy 331.218032 -428.941992) (xy 332.157832 -428.941992)
			(xy 332.169942 -428.942389) (xy 332.192969 -428.949896) (xy 332.212541 -428.964163) (xy 332.226734 -428.983788)
			(xy 332.234156 -429.006843) (xy 332.23454 -429.018954) (xy 332.23454 -431.560478) (xy 332.234073 -431.572568)
			(xy 332.22662 -431.595572) (xy 332.212434 -431.615154) (xy 332.192899 -431.629404) (xy 332.169921 -431.636933)
			(xy 332.157832 -431.63744) (xy 331.218032 -431.63744) (xy 331.205929 -431.636957) (xy 331.182909 -431.629471)
			(xy 331.163339 -431.615225) (xy 331.149142 -431.59562) (xy 331.141713 -431.572582) (xy 331.141324 -431.560478)
			(xy 331.141324 -430.953164) (xy 331.14107 -430.947322) (xy 331.13954 -430.93302) (xy 331.13789 -430.904301)
			(xy 331.137768 -430.889918) (xy 329.2348 -430.889918) (xy 329.2348 -431.889916) (xy 333.137764 -431.889916)
			(xy 333.137876 -431.875533) (xy 333.139529 -431.846813) (xy 333.141066 -431.832512) (xy 333.14132 -431.82667)
			(xy 333.14132 -430.753012) (xy 333.141066 -430.74717) (xy 333.13954 -430.732868) (xy 333.137887 -430.704149)
			(xy 333.137764 -430.689766) (xy 333.13788 -430.675383) (xy 333.139531 -430.646664) (xy 333.141066 -430.632362)
			(xy 333.14132 -430.62652) (xy 333.14132 -430.018952) (xy 333.141724 -430.006872) (xy 333.149203 -429.983899)
			(xy 333.163414 -429.96436) (xy 333.182967 -429.950168) (xy 333.205948 -429.942712) (xy 333.218028 -429.942244)
			(xy 334.157828 -429.942244) (xy 334.169899 -429.942739) (xy 334.192859 -429.950204) (xy 334.212392 -429.964394)
			(xy 334.226587 -429.983923) (xy 334.234058 -430.006881) (xy 334.234536 -430.018952) (xy 334.234536 -430.889918)
			(xy 335.13776 -430.889918) (xy 335.137872 -430.875535) (xy 335.139526 -430.846815) (xy 335.141062 -430.832514)
			(xy 335.141316 -430.826672) (xy 335.141316 -429.753014) (xy 335.141062 -429.747172) (xy 335.139536 -429.73287)
			(xy 335.137883 -429.704151) (xy 335.13776 -429.689768) (xy 335.137876 -429.675385) (xy 335.139527 -429.646666)
			(xy 335.141062 -429.632364) (xy 335.141316 -429.626522) (xy 335.141316 -429.018954) (xy 335.141768 -429.006864)
			(xy 335.149234 -428.983866) (xy 335.163426 -428.964289) (xy 335.18296 -428.950039) (xy 335.205936 -428.942504)
			(xy 335.218024 -428.941992) (xy 336.157824 -428.941992) (xy 336.169933 -428.942396) (xy 336.19296 -428.949901)
			(xy 336.212532 -428.964166) (xy 336.226726 -428.983789) (xy 336.234148 -429.006843) (xy 336.234532 -429.018954)
			(xy 336.234532 -431.560478) (xy 336.234073 -431.572569) (xy 336.226619 -431.595574) (xy 336.212432 -431.615156)
			(xy 336.192894 -431.629407) (xy 336.169914 -431.636934) (xy 336.157824 -431.63744) (xy 335.218024 -431.63744)
			(xy 335.20592 -431.636964) (xy 335.182901 -431.629476) (xy 335.163331 -431.615228) (xy 335.149134 -431.595622)
			(xy 335.141705 -431.572583) (xy 335.141316 -431.560478) (xy 335.141316 -430.953164) (xy 335.141062 -430.947322)
			(xy 335.139532 -430.93302) (xy 335.137882 -430.904301) (xy 335.13776 -430.889918) (xy 334.234536 -430.889918)
			(xy 334.234536 -431.889916) (xy 337.137756 -431.889916) (xy 337.137868 -431.875533) (xy 337.139521 -431.846813)
			(xy 337.141058 -431.832512) (xy 337.141312 -431.82667) (xy 337.141312 -430.753012) (xy 337.141058 -430.74717)
			(xy 337.139532 -430.732868) (xy 337.137879 -430.704149) (xy 337.137756 -430.689766) (xy 337.137872 -430.675383)
			(xy 337.139523 -430.646664) (xy 337.141058 -430.632362) (xy 337.141312 -430.62652) (xy 337.141312 -430.018952)
			(xy 337.141724 -430.006873) (xy 337.149202 -429.983901) (xy 337.163411 -429.964363) (xy 337.182962 -429.950171)
			(xy 337.205941 -429.942713) (xy 337.21802 -429.942244) (xy 338.15782 -429.942244) (xy 338.169891 -429.942747)
			(xy 338.19285 -429.950209) (xy 338.212383 -429.964397) (xy 338.226578 -429.983924) (xy 338.234049 -430.006881)
			(xy 338.234528 -430.018952) (xy 338.234528 -430.889918) (xy 339.137752 -430.889918) (xy 339.137864 -430.875535)
			(xy 339.139518 -430.846815) (xy 339.141054 -430.832514) (xy 339.141308 -430.826672) (xy 339.141308 -429.753014)
			(xy 339.141054 -429.747172) (xy 339.139528 -429.73287) (xy 339.137875 -429.704151) (xy 339.137752 -429.689768)
			(xy 339.137868 -429.675385) (xy 339.139519 -429.646666) (xy 339.141054 -429.632364) (xy 339.141308 -429.626522)
			(xy 339.141308 -429.018954) (xy 339.141768 -429.006865) (xy 339.149233 -428.983868) (xy 339.163423 -428.964292)
			(xy 339.182955 -428.950042) (xy 339.205929 -428.942505) (xy 339.218016 -428.941992) (xy 340.157816 -428.941992)
			(xy 340.169925 -428.942402) (xy 340.192951 -428.949905) (xy 340.212524 -428.964169) (xy 340.226718 -428.983791)
			(xy 340.23414 -429.006844) (xy 340.234524 -429.018954) (xy 340.234524 -431.560478) (xy 340.234073 -431.57257)
			(xy 340.226618 -431.595576) (xy 340.212429 -431.615159) (xy 340.192889 -431.629409) (xy 340.169906 -431.636935)
			(xy 340.157816 -431.63744) (xy 339.218016 -431.63744) (xy 339.205912 -431.63697) (xy 339.182892 -431.62948)
			(xy 339.163322 -431.615231) (xy 339.149126 -431.595623) (xy 339.141697 -431.572583) (xy 339.141308 -431.560478)
			(xy 339.141308 -430.953164) (xy 339.141054 -430.947322) (xy 339.139524 -430.93302) (xy 339.137874 -430.904301)
			(xy 339.137752 -430.889918) (xy 338.234528 -430.889918) (xy 338.234528 -431.889916) (xy 341.137748 -431.889916)
			(xy 341.13786 -431.875533) (xy 341.139514 -431.846813) (xy 341.14105 -431.832512) (xy 341.141304 -431.82667)
			(xy 341.141304 -430.753012) (xy 341.14105 -430.74717) (xy 341.139524 -430.732868) (xy 341.137871 -430.704149)
			(xy 341.137748 -430.689766) (xy 341.137864 -430.675383) (xy 341.139515 -430.646664) (xy 341.14105 -430.632362)
			(xy 341.141304 -430.62652) (xy 341.141304 -430.018952) (xy 341.141723 -430.006874) (xy 341.149201 -429.983903)
			(xy 341.163408 -429.964366) (xy 341.182957 -429.950173) (xy 341.205933 -429.942714) (xy 341.218012 -429.942244)
			(xy 342.157812 -429.942244) (xy 342.169882 -429.942753) (xy 342.192842 -429.950213) (xy 342.212374 -429.9644)
			(xy 342.22657 -429.983926) (xy 342.234041 -430.006882) (xy 342.23452 -430.018952) (xy 342.23452 -430.889918)
			(xy 343.137744 -430.889918) (xy 343.137856 -430.875535) (xy 343.139509 -430.846815) (xy 343.141046 -430.832514)
			(xy 343.1413 -430.826672) (xy 343.1413 -429.753014) (xy 343.141046 -429.747172) (xy 343.13952 -429.73287)
			(xy 343.137867 -429.704151) (xy 343.137744 -429.689768) (xy 343.13786 -429.675385) (xy 343.139511 -429.646666)
			(xy 343.141046 -429.632364) (xy 343.1413 -429.626522) (xy 343.1413 -429.018954) (xy 343.141767 -429.006866)
			(xy 343.149232 -428.983871) (xy 343.16342 -428.964295) (xy 343.18295 -428.950044) (xy 343.205922 -428.942507)
			(xy 343.218008 -428.941992) (xy 344.157808 -428.941992) (xy 344.169917 -428.942409) (xy 344.192943 -428.94991)
			(xy 344.212515 -428.964172) (xy 344.22671 -428.983792) (xy 344.234132 -429.006844) (xy 344.234516 -429.018954)
			(xy 344.234516 -431.560478) (xy 344.234073 -431.572571) (xy 344.226617 -431.595578) (xy 344.212426 -431.615162)
			(xy 344.192884 -431.629412) (xy 344.169899 -431.636937) (xy 344.157808 -431.63744) (xy 343.218008 -431.63744)
			(xy 343.205904 -431.636978) (xy 343.182883 -431.629485) (xy 343.163313 -431.615234) (xy 343.149117 -431.595625)
			(xy 343.141689 -431.572584) (xy 343.1413 -431.560478) (xy 343.1413 -430.953164) (xy 343.141046 -430.947322)
			(xy 343.139516 -430.93302) (xy 343.137866 -430.904301) (xy 343.137744 -430.889918) (xy 342.23452 -430.889918)
			(xy 342.23452 -431.889916) (xy 345.13774 -431.889916) (xy 345.137851 -431.875533) (xy 345.139505 -431.846813)
			(xy 345.141042 -431.832512) (xy 345.141296 -431.82667) (xy 345.141296 -430.753012) (xy 345.141042 -430.74717)
			(xy 345.139516 -430.732868) (xy 345.137863 -430.704149) (xy 345.13774 -430.689766) (xy 345.137856 -430.675383)
			(xy 345.139507 -430.646664) (xy 345.141042 -430.632362) (xy 345.141296 -430.62652) (xy 345.141296 -430.018952)
			(xy 345.141723 -430.006875) (xy 345.149199 -429.983905) (xy 345.163405 -429.964368) (xy 345.182952 -429.950176)
			(xy 345.205926 -429.942715) (xy 345.218004 -429.942244) (xy 346.157804 -429.942244) (xy 346.169874 -429.94276)
			(xy 346.192833 -429.950218) (xy 346.212366 -429.964403) (xy 346.226562 -429.983927) (xy 346.234033 -430.006882)
			(xy 346.234512 -430.018952) (xy 346.234512 -431.360072) (xy 356.154736 -431.360072) (xy 356.155234 -431.275192)
			(xy 356.163191 -431.105619) (xy 356.179087 -430.936605) (xy 356.202888 -430.768522) (xy 356.234542 -430.601739)
			(xy 356.273978 -430.436623) (xy 356.32111 -430.273538) (xy 356.375834 -430.11284) (xy 356.438031 -429.954885)
			(xy 356.507563 -429.800018) (xy 356.584278 -429.648581) (xy 356.668006 -429.500905) (xy 356.758564 -429.357317)
			(xy 356.855753 -429.218131) (xy 356.95936 -429.083654) (xy 357.069155 -428.954181) (xy 357.184899 -428.829996)
			(xy 357.306336 -428.711373) (xy 357.4332 -428.598572) (xy 357.565211 -428.491842) (xy 357.702081 -428.391417)
			(xy 357.843506 -428.297518) (xy 357.989178 -428.21035) (xy 358.138776 -428.130107) (xy 358.29197 -428.056963)
			(xy 358.448424 -427.991081) (xy 358.607794 -427.932604) (xy 358.76973 -427.881662) (xy 358.933876 -427.838366)
			(xy 359.099871 -427.802811) (xy 359.26735 -427.775076) (xy 359.435945 -427.755222) (xy 359.605285 -427.743292)
			(xy 359.774998 -427.739313) (xy 359.944711 -427.743292) (xy 360.114051 -427.755222) (xy 360.282646 -427.775076)
			(xy 360.450125 -427.802811) (xy 360.61612 -427.838366) (xy 360.780266 -427.881662) (xy 360.942202 -427.932604)
			(xy 361.101572 -427.991081) (xy 361.258026 -428.056963) (xy 361.41122 -428.130107) (xy 361.560818 -428.21035)
			(xy 361.693458 -428.28972) (xy 383.23774 -428.28972) (xy 383.237852 -428.275337) (xy 383.239505 -428.246617)
			(xy 383.241042 -428.232316) (xy 383.241296 -428.226474) (xy 383.241296 -427.15307) (xy 383.241042 -427.147228)
			(xy 383.239513 -427.132926) (xy 383.237862 -427.104207) (xy 383.23774 -427.089824) (xy 383.237852 -427.075441)
			(xy 383.239505 -427.046721) (xy 383.241042 -427.03242) (xy 383.241296 -427.026578) (xy 383.241296 -426.41901)
			(xy 383.241815 -426.406925) (xy 383.249264 -426.383932) (xy 383.263439 -426.364356) (xy 383.282958 -426.350104)
			(xy 383.305921 -426.342564) (xy 383.318004 -426.342048) (xy 384.257804 -426.342048) (xy 384.269908 -426.342512)
			(xy 384.292927 -426.350006) (xy 384.312495 -426.364257) (xy 384.326691 -426.383866) (xy 384.334121 -426.406905)
			(xy 384.334512 -426.41901) (xy 384.334512 -427.289976) (xy 385.237736 -427.289976) (xy 385.237852 -427.275593)
			(xy 385.239503 -427.246874) (xy 385.241038 -427.232572) (xy 385.241292 -427.22673) (xy 385.241292 -426.153072)
			(xy 385.241038 -426.14723) (xy 385.239509 -426.132928) (xy 385.237858 -426.104209) (xy 385.237736 -426.089826)
			(xy 385.237848 -426.075443) (xy 385.239502 -426.046723) (xy 385.241038 -426.032422) (xy 385.241292 -426.02658)
			(xy 385.241292 -425.419012) (xy 385.241723 -425.40693) (xy 385.249187 -425.383948) (xy 385.263389 -425.364397)
			(xy 385.282937 -425.350193) (xy 385.305918 -425.342725) (xy 385.318 -425.342304) (xy 386.2578 -425.342304)
			(xy 386.269884 -425.342713) (xy 386.292869 -425.350182) (xy 386.31242 -425.364388) (xy 386.326624 -425.383942)
			(xy 386.334089 -425.406928) (xy 386.334508 -425.419012) (xy 386.334508 -427.960536) (xy 386.334067 -427.972612)
			(xy 386.326594 -427.995581) (xy 386.312392 -428.015117) (xy 386.292849 -428.029311) (xy 386.269877 -428.036772)
			(xy 386.2578 -428.037244) (xy 385.318 -428.037244) (xy 385.305929 -428.036736) (xy 385.282968 -428.029278)
			(xy 385.263434 -428.015092) (xy 385.249238 -427.995564) (xy 385.241769 -427.972607) (xy 385.241292 -427.960536)
			(xy 385.241292 -427.353222) (xy 385.241038 -427.34738) (xy 385.239513 -427.333078) (xy 385.23786 -427.304359)
			(xy 385.237736 -427.289976) (xy 384.334512 -427.289976) (xy 384.334512 -428.28972) (xy 387.237732 -428.28972)
			(xy 387.237844 -428.275337) (xy 387.239497 -428.246617) (xy 387.241034 -428.232316) (xy 387.241288 -428.226474)
			(xy 387.241288 -427.15307) (xy 387.241034 -427.147228) (xy 387.239504 -427.132926) (xy 387.237854 -427.104207)
			(xy 387.237732 -427.089824) (xy 387.237844 -427.075441) (xy 387.239497 -427.046721) (xy 387.241034 -427.03242)
			(xy 387.241288 -427.026578) (xy 387.241288 -426.41901) (xy 387.241717 -426.406916) (xy 387.249177 -426.383908)
			(xy 387.263371 -426.364324) (xy 387.282916 -426.350075) (xy 387.305904 -426.342551) (xy 387.317996 -426.342048)
			(xy 388.257796 -426.342048) (xy 388.269899 -426.342519) (xy 388.292918 -426.350011) (xy 388.312487 -426.36426)
			(xy 388.326683 -426.383867) (xy 388.334113 -426.406905) (xy 388.334504 -426.41901) (xy 388.334504 -427.289976)
			(xy 389.237728 -427.289976) (xy 389.237845 -427.275593) (xy 389.239495 -427.246874) (xy 389.24103 -427.232572)
			(xy 389.241284 -427.22673) (xy 389.241284 -426.153072) (xy 389.24103 -426.14723) (xy 389.239501 -426.132928)
			(xy 389.23785 -426.104209) (xy 389.237728 -426.089826) (xy 389.23784 -426.075443) (xy 389.239494 -426.046723)
			(xy 389.24103 -426.032422) (xy 389.241284 -426.02658) (xy 389.241284 -425.419012) (xy 389.241723 -425.406931)
			(xy 389.249186 -425.38395) (xy 389.263386 -425.3644) (xy 389.282932 -425.350195) (xy 389.305911 -425.342726)
			(xy 389.317992 -425.342304) (xy 390.257792 -425.342304) (xy 390.269876 -425.342719) (xy 390.29286 -425.350186)
			(xy 390.312412 -425.364391) (xy 390.326616 -425.383943) (xy 390.334081 -425.406928) (xy 390.3345 -425.419012)
			(xy 390.3345 -427.960536) (xy 390.334067 -427.972613) (xy 390.326593 -427.995583) (xy 390.312389 -428.01512)
			(xy 390.292844 -428.029313) (xy 390.26987 -428.036773) (xy 390.257792 -428.037244) (xy 389.317992 -428.037244)
			(xy 389.305921 -428.036743) (xy 389.282959 -428.029283) (xy 389.263426 -428.015094) (xy 389.24923 -427.995566)
			(xy 389.241761 -427.972607) (xy 389.241284 -427.960536) (xy 389.241284 -427.353222) (xy 389.24103 -427.34738)
			(xy 389.239505 -427.333078) (xy 389.237852 -427.304359) (xy 389.237728 -427.289976) (xy 388.334504 -427.289976)
			(xy 388.334504 -428.28972) (xy 391.237724 -428.28972) (xy 391.237836 -428.275337) (xy 391.239489 -428.246617)
			(xy 391.241026 -428.232316) (xy 391.24128 -428.226474) (xy 391.24128 -427.15307) (xy 391.241026 -427.147228)
			(xy 391.239496 -427.132926) (xy 391.237846 -427.104207) (xy 391.237724 -427.089824) (xy 391.237836 -427.075441)
			(xy 391.23949 -427.046721) (xy 391.241026 -427.03242) (xy 391.24128 -427.026578) (xy 391.24128 -426.41901)
			(xy 391.241717 -426.406917) (xy 391.249176 -426.38391) (xy 391.263369 -426.364326) (xy 391.282911 -426.350077)
			(xy 391.305896 -426.342552) (xy 391.317988 -426.342048) (xy 392.257788 -426.342048) (xy 392.269891 -426.342526)
			(xy 392.292909 -426.350016) (xy 392.312478 -426.364263) (xy 392.326675 -426.383869) (xy 392.334105 -426.406906)
			(xy 392.334496 -426.41901) (xy 392.334496 -427.289976) (xy 393.23772 -427.289976) (xy 393.237837 -427.275593)
			(xy 393.239487 -427.246874) (xy 393.241022 -427.232572) (xy 393.241276 -427.22673) (xy 393.241276 -426.153072)
			(xy 393.241022 -426.14723) (xy 393.239493 -426.132928) (xy 393.237842 -426.104209) (xy 393.23772 -426.089826)
			(xy 393.237832 -426.075443) (xy 393.239486 -426.046723) (xy 393.241022 -426.032422) (xy 393.241276 -426.02658)
			(xy 393.241276 -425.419012) (xy 393.241774 -425.40694) (xy 393.249231 -425.383976) (xy 393.26342 -425.36444)
			(xy 393.28295 -425.350244) (xy 393.305912 -425.342779) (xy 393.317984 -425.342304) (xy 394.257784 -425.342304)
			(xy 394.269867 -425.342727) (xy 394.292851 -425.350191) (xy 394.312403 -425.364394) (xy 394.326607 -425.383945)
			(xy 394.334073 -425.406929) (xy 394.334492 -425.419012) (xy 394.334492 -427.960536) (xy 394.334066 -427.972614)
			(xy 394.326592 -427.995585) (xy 394.312386 -428.015123) (xy 394.292839 -428.029316) (xy 394.269862 -428.036775)
			(xy 394.257784 -428.037244) (xy 393.317984 -428.037244) (xy 393.305912 -428.03675) (xy 393.282951 -428.029287)
			(xy 393.263417 -428.015097) (xy 393.249222 -427.995567) (xy 393.241753 -427.972608) (xy 393.241276 -427.960536)
			(xy 393.241276 -427.353222) (xy 393.241022 -427.34738) (xy 393.239497 -427.333078) (xy 393.237844 -427.304359)
			(xy 393.23772 -427.289976) (xy 392.334496 -427.289976) (xy 392.334496 -428.28972) (xy 395.237716 -428.28972)
			(xy 395.237828 -428.275337) (xy 395.239481 -428.246617) (xy 395.241018 -428.232316) (xy 395.241272 -428.226474)
			(xy 395.241272 -427.15307) (xy 395.241018 -427.147228) (xy 395.239488 -427.132926) (xy 395.237838 -427.104207)
			(xy 395.237716 -427.089824) (xy 395.237828 -427.075441) (xy 395.239482 -427.046721) (xy 395.241018 -427.03242)
			(xy 395.241272 -427.026578) (xy 395.241272 -426.41901) (xy 395.241717 -426.406918) (xy 395.249174 -426.383912)
			(xy 395.263366 -426.364329) (xy 395.282906 -426.35008) (xy 395.305889 -426.342553) (xy 395.31798 -426.342048)
			(xy 396.25778 -426.342048) (xy 396.269883 -426.342533) (xy 396.2929 -426.35002) (xy 396.312469 -426.364266)
			(xy 396.326666 -426.38387) (xy 396.334097 -426.406906) (xy 396.334488 -426.41901) (xy 396.334488 -427.289976)
			(xy 398.238472 -427.289976) (xy 398.238537 -427.277829) (xy 398.239683 -427.253562) (xy 398.240758 -427.241462)
			(xy 398.241012 -427.236636) (xy 398.241012 -426.143166) (xy 398.240758 -426.13834) (xy 398.239681 -426.12624)
			(xy 398.238537 -426.101973) (xy 398.238472 -426.089826) (xy 398.238541 -426.077679) (xy 398.239684 -426.053412)
			(xy 398.240758 -426.041312) (xy 398.241012 -426.036486) (xy 398.241012 -425.419012) (xy 398.24147 -425.406961)
			(xy 398.248901 -425.384034) (xy 398.263042 -425.364517) (xy 398.282514 -425.350314) (xy 398.305417 -425.342809)
			(xy 398.317466 -425.342304) (xy 399.257774 -425.342304) (xy 399.269859 -425.342829) (xy 399.292852 -425.350274)
			(xy 399.31243 -425.364447) (xy 399.326682 -425.383966) (xy 399.334221 -425.406929) (xy 399.334736 -425.419012)
			(xy 399.334736 -427.960536) (xy 399.334272 -427.972585) (xy 399.326833 -427.995505) (xy 399.312692 -428.015017)
			(xy 399.293226 -428.029221) (xy 399.270329 -428.036732) (xy 399.258282 -428.037244) (xy 398.317974 -428.037244)
			(xy 398.305881 -428.036815) (xy 398.282877 -428.029349) (xy 398.263296 -428.015153) (xy 398.249047 -427.995611)
			(xy 398.241519 -427.972627) (xy 398.241012 -427.960536) (xy 398.241012 -427.343316) (xy 398.240758 -427.33849)
			(xy 398.239677 -427.326391) (xy 398.238535 -427.302123) (xy 398.238472 -427.289976) (xy 396.334488 -427.289976)
			(xy 396.334488 -428.28972) (xy 400.238468 -428.28972) (xy 400.238537 -428.277573) (xy 400.23968 -428.253306)
			(xy 400.240754 -428.241206) (xy 400.241008 -428.23638) (xy 400.241008 -427.143164) (xy 400.240754 -427.138338)
			(xy 400.239677 -427.126239) (xy 400.238533 -427.101971) (xy 400.238468 -427.089824) (xy 400.238537 -427.077677)
			(xy 400.23968 -427.05341) (xy 400.240754 -427.04131) (xy 400.241008 -427.036484) (xy 400.241008 -426.41901)
			(xy 400.24152 -426.406899) (xy 400.249001 -426.383861) (xy 400.263233 -426.364262) (xy 400.282825 -426.350019)
			(xy 400.305859 -426.342526) (xy 400.31797 -426.342048) (xy 401.25777 -426.342048) (xy 401.269892 -426.342486)
			(xy 401.292952 -426.349971) (xy 401.312568 -426.364218) (xy 401.32682 -426.38383) (xy 401.334311 -426.406888)
			(xy 401.334732 -426.41901) (xy 401.334732 -427.289976) (xy 402.238464 -427.289976) (xy 402.238529 -427.277829)
			(xy 402.239675 -427.253562) (xy 402.24075 -427.241462) (xy 402.241004 -427.236636) (xy 402.241004 -426.143166)
			(xy 402.24075 -426.13834) (xy 402.239673 -426.126241) (xy 402.238529 -426.101973) (xy 402.238464 -426.089826)
			(xy 402.238533 -426.077679) (xy 402.239676 -426.053412) (xy 402.24075 -426.041312) (xy 402.241004 -426.036486)
			(xy 402.241004 -425.419012) (xy 402.24147 -425.406962) (xy 402.2489 -425.384036) (xy 402.263039 -425.36452)
			(xy 402.282509 -425.350316) (xy 402.30541 -425.342811) (xy 402.317458 -425.342304) (xy 403.257766 -425.342304)
			(xy 403.26985 -425.342836) (xy 403.292844 -425.350279) (xy 403.312421 -425.36445) (xy 403.326674 -425.383968)
			(xy 403.334213 -425.40693) (xy 403.334728 -425.419012) (xy 403.334728 -427.960536) (xy 403.334271 -427.972585)
			(xy 403.326832 -427.995507) (xy 403.31269 -428.01502) (xy 403.293221 -428.029223) (xy 403.270322 -428.036734)
			(xy 403.258274 -428.037244) (xy 402.317966 -428.037244) (xy 402.305873 -428.036821) (xy 402.282869 -428.029353)
			(xy 402.263288 -428.015156) (xy 402.249039 -427.995612) (xy 402.241511 -427.972628) (xy 402.241004 -427.960536)
			(xy 402.241004 -427.343316) (xy 402.24075 -427.33849) (xy 402.239669 -427.326391) (xy 402.238527 -427.302123)
			(xy 402.238464 -427.289976) (xy 401.334732 -427.289976) (xy 401.334732 -428.28972) (xy 404.23846 -428.28972)
			(xy 404.238529 -428.277573) (xy 404.239672 -428.253306) (xy 404.240746 -428.241206) (xy 404.241 -428.23638)
			(xy 404.241 -427.143164) (xy 404.240746 -427.138338) (xy 404.239669 -427.126239) (xy 404.238525 -427.101971)
			(xy 404.23846 -427.089824) (xy 404.238529 -427.077677) (xy 404.239672 -427.05341) (xy 404.240746 -427.04131)
			(xy 404.241 -427.036484) (xy 404.241 -426.41901) (xy 404.24152 -426.4069) (xy 404.249 -426.383863)
			(xy 404.263231 -426.364265) (xy 404.28282 -426.350022) (xy 404.305852 -426.342527) (xy 404.317962 -426.342048)
			(xy 405.257762 -426.342048) (xy 405.269884 -426.342492) (xy 405.292943 -426.349975) (xy 405.31256 -426.36422)
			(xy 405.326812 -426.383832) (xy 405.334303 -426.406888) (xy 405.334724 -426.41901) (xy 405.334724 -427.289976)
			(xy 406.238456 -427.289976) (xy 406.238522 -427.277829) (xy 406.239667 -427.253562) (xy 406.240742 -427.241462)
			(xy 406.240996 -427.236636) (xy 406.240996 -426.143166) (xy 406.240742 -426.13834) (xy 406.239665 -426.126241)
			(xy 406.238521 -426.101973) (xy 406.238456 -426.089826) (xy 406.238525 -426.077679) (xy 406.239668 -426.053412)
			(xy 406.240742 -426.041312) (xy 406.240996 -426.036486) (xy 406.240996 -425.419012) (xy 406.24147 -425.406963)
			(xy 406.248899 -425.384038) (xy 406.263036 -425.364523) (xy 406.282504 -425.350319) (xy 406.305403 -425.342812)
			(xy 406.31745 -425.342304) (xy 407.257758 -425.342304) (xy 407.269842 -425.342842) (xy 407.292835 -425.350283)
			(xy 407.312413 -425.364453) (xy 407.326666 -425.383969) (xy 407.334205 -425.40693) (xy 407.33472 -425.419012)
			(xy 407.33472 -427.960536) (xy 407.334271 -427.972586) (xy 407.326831 -427.99551) (xy 407.312687 -428.015023)
			(xy 407.293216 -428.029226) (xy 407.270315 -428.036735) (xy 407.258266 -428.037244) (xy 406.317958 -428.037244)
			(xy 406.305865 -428.036828) (xy 406.28286 -428.029358) (xy 406.263279 -428.015159) (xy 406.249031 -427.995614)
			(xy 406.241503 -427.972628) (xy 406.240996 -427.960536) (xy 406.240996 -427.343316) (xy 406.240742 -427.33849)
			(xy 406.239661 -427.326391) (xy 406.238519 -427.302123) (xy 406.238456 -427.289976) (xy 405.334724 -427.289976)
			(xy 405.334724 -428.28972) (xy 408.238452 -428.28972) (xy 408.238521 -428.277573) (xy 408.239664 -428.253306)
			(xy 408.240738 -428.241206) (xy 408.240992 -428.23638) (xy 408.240992 -427.143164) (xy 408.240738 -427.138338)
			(xy 408.239661 -427.126239) (xy 408.238517 -427.101971) (xy 408.238452 -427.089824) (xy 408.238521 -427.077677)
			(xy 408.239664 -427.05341) (xy 408.240738 -427.04131) (xy 408.240992 -427.036484) (xy 408.240992 -426.41901)
			(xy 408.24152 -426.406901) (xy 408.248999 -426.383865) (xy 408.263228 -426.364268) (xy 408.282815 -426.350024)
			(xy 408.305845 -426.342528) (xy 408.317954 -426.342048) (xy 409.257754 -426.342048) (xy 409.269875 -426.342499)
			(xy 409.292934 -426.34998) (xy 409.312551 -426.364223) (xy 409.326804 -426.383833) (xy 409.334295 -426.406889)
			(xy 409.334716 -426.41901) (xy 409.334716 -427.289976) (xy 410.238448 -427.289976) (xy 410.238514 -427.277829)
			(xy 410.239659 -427.253562) (xy 410.240734 -427.241462) (xy 410.240988 -427.236636) (xy 410.240988 -426.143166)
			(xy 410.240734 -426.13834) (xy 410.239657 -426.126241) (xy 410.238513 -426.101973) (xy 410.238448 -426.089826)
			(xy 410.238517 -426.077679) (xy 410.23966 -426.053412) (xy 410.240734 -426.041312) (xy 410.240988 -426.036486)
			(xy 410.240988 -425.419012) (xy 410.24147 -425.406964) (xy 410.248898 -425.38404) (xy 410.263033 -425.364526)
			(xy 410.282498 -425.350321) (xy 410.305395 -425.342813) (xy 410.317442 -425.342304) (xy 411.25775 -425.342304)
			(xy 411.269833 -425.342849) (xy 411.292826 -425.350288) (xy 411.312404 -425.364455) (xy 411.326658 -425.383971)
			(xy 411.334197 -425.406931) (xy 411.334712 -425.419012) (xy 411.334712 -427.960536) (xy 411.334271 -427.972587)
			(xy 411.32683 -427.995512) (xy 411.312684 -428.015026) (xy 411.293211 -428.029228) (xy 411.270307 -428.036736)
			(xy 411.258258 -428.037244) (xy 410.31795 -428.037244) (xy 410.305861 -428.03675) (xy 410.28286 -428.029305)
			(xy 410.263278 -428.015126) (xy 410.249026 -427.995597) (xy 410.241495 -427.972623) (xy 410.240988 -427.960536)
			(xy 410.240988 -427.343316) (xy 410.240734 -427.33849) (xy 410.239653 -427.326391) (xy 410.238511 -427.302123)
			(xy 410.238448 -427.289976) (xy 409.334716 -427.289976) (xy 409.334716 -428.28972) (xy 412.238444 -428.28972)
			(xy 412.238512 -428.277573) (xy 412.239656 -428.253306) (xy 412.24073 -428.241206) (xy 412.240984 -428.23638)
			(xy 412.240984 -427.143164) (xy 412.24073 -427.138338) (xy 412.239653 -427.126239) (xy 412.238509 -427.101971)
			(xy 412.238444 -427.089824) (xy 412.238513 -427.077677) (xy 412.239656 -427.05341) (xy 412.24073 -427.04131)
			(xy 412.240984 -427.036484) (xy 412.240984 -426.41901) (xy 412.241369 -426.406883) (xy 412.248864 -426.383817)
			(xy 412.263123 -426.364198) (xy 412.282749 -426.349948) (xy 412.305819 -426.342464) (xy 412.317946 -426.342048)
			(xy 413.257746 -426.342048) (xy 413.269864 -426.342473) (xy 413.29291 -426.349974) (xy 413.312512 -426.364228)
			(xy 413.326752 -426.38384) (xy 413.334236 -426.406892) (xy 413.334708 -426.41901) (xy 413.334708 -428.960534)
			(xy 413.334218 -428.972646) (xy 413.326727 -428.995682) (xy 413.312488 -429.01528) (xy 413.292893 -429.029522)
			(xy 413.269858 -429.037016) (xy 413.257746 -429.037496) (xy 412.317946 -429.037496) (xy 412.305829 -429.037002)
			(xy 412.282777 -429.029526) (xy 412.263164 -429.015292) (xy 412.248911 -428.995694) (xy 412.241411 -428.972651)
			(xy 412.240984 -428.960534) (xy 412.240984 -428.34306) (xy 412.24073 -428.338234) (xy 412.239652 -428.326135)
			(xy 412.238509 -428.301867) (xy 412.238444 -428.28972) (xy 409.334716 -428.28972) (xy 409.334716 -428.960534)
			(xy 409.334368 -428.972663) (xy 409.326861 -428.995731) (xy 409.312592 -429.015349) (xy 409.292959 -429.029598)
			(xy 409.269884 -429.037081) (xy 409.257754 -429.037496) (xy 408.317954 -429.037496) (xy 408.30584 -429.037028)
			(xy 408.282801 -429.029532) (xy 408.263203 -429.015288) (xy 408.248962 -428.995688) (xy 408.24147 -428.972648)
			(xy 408.240992 -428.960534) (xy 408.240992 -428.34306) (xy 408.240738 -428.338234) (xy 408.23966 -428.326135)
			(xy 408.238517 -428.301867) (xy 408.238452 -428.28972) (xy 405.334724 -428.28972) (xy 405.334724 -428.960534)
			(xy 405.334369 -428.972662) (xy 405.326862 -428.995729) (xy 405.312595 -429.015347) (xy 405.292964 -429.029595)
			(xy 405.269891 -429.03708) (xy 405.257762 -429.037496) (xy 404.317962 -429.037496) (xy 404.305849 -429.037021)
			(xy 404.28281 -429.029528) (xy 404.263212 -429.015285) (xy 404.24897 -428.995686) (xy 404.241478 -428.972647)
			(xy 404.241 -428.960534) (xy 404.241 -428.34306) (xy 404.240746 -428.338234) (xy 404.239668 -428.326135)
			(xy 404.238525 -428.301867) (xy 404.23846 -428.28972) (xy 401.334732 -428.28972) (xy 401.334732 -428.960534)
			(xy 401.334317 -428.972653) (xy 401.326817 -428.995703) (xy 401.312561 -429.015307) (xy 401.292945 -429.029546)
			(xy 401.26989 -429.037027) (xy 401.25777 -429.037496) (xy 400.31797 -429.037496) (xy 400.305857 -429.037014)
			(xy 400.282819 -429.029523) (xy 400.26322 -429.015282) (xy 400.248979 -428.995685) (xy 400.241486 -428.972647)
			(xy 400.241008 -428.960534) (xy 400.241008 -428.34306) (xy 400.240754 -428.338234) (xy 400.239676 -428.326135)
			(xy 400.238533 -428.301867) (xy 400.238468 -428.28972) (xy 396.334488 -428.28972) (xy 396.334488 -428.960534)
			(xy 396.334022 -428.972623) (xy 396.32656 -428.99562) (xy 396.312372 -429.015197) (xy 396.29284 -429.029447)
			(xy 396.269867 -429.036983) (xy 396.25778 -429.037496) (xy 395.31798 -429.037496) (xy 395.30587 -429.037101)
			(xy 395.282841 -429.029595) (xy 395.263268 -429.015328) (xy 395.249074 -428.995702) (xy 395.241655 -428.972646)
			(xy 395.241272 -428.960534) (xy 395.241272 -428.352966) (xy 395.241018 -428.347124) (xy 395.239488 -428.332822)
			(xy 395.237838 -428.304103) (xy 395.237716 -428.28972) (xy 392.334496 -428.28972) (xy 392.334496 -428.960534)
			(xy 392.334022 -428.972622) (xy 392.326561 -428.995617) (xy 392.312374 -429.015194) (xy 392.292845 -429.029444)
			(xy 392.269874 -429.036982) (xy 392.257788 -429.037496) (xy 391.317988 -429.037496) (xy 391.305878 -429.037094)
			(xy 391.28285 -429.029591) (xy 391.263276 -429.015326) (xy 391.249082 -428.995701) (xy 391.241663 -428.972645)
			(xy 391.24128 -428.960534) (xy 391.24128 -428.352966) (xy 391.241026 -428.347124) (xy 391.239496 -428.332822)
			(xy 391.237846 -428.304103) (xy 391.237724 -428.28972) (xy 388.334504 -428.28972) (xy 388.334504 -428.960534)
			(xy 388.334023 -428.972621) (xy 388.326562 -428.995615) (xy 388.312377 -429.015191) (xy 388.29285 -429.029442)
			(xy 388.269881 -429.036981) (xy 388.257796 -429.037496) (xy 387.317996 -429.037496) (xy 387.305887 -429.037087)
			(xy 387.282858 -429.029586) (xy 387.263285 -429.015323) (xy 387.249091 -428.995699) (xy 387.241671 -428.972645)
			(xy 387.241288 -428.960534) (xy 387.241288 -428.352966) (xy 387.241034 -428.347124) (xy 387.239504 -428.332822)
			(xy 387.237854 -428.304103) (xy 387.237732 -428.28972) (xy 384.334512 -428.28972) (xy 384.334512 -428.960534)
			(xy 384.334121 -428.97263) (xy 384.326649 -428.99564) (xy 384.312444 -429.015223) (xy 384.292892 -429.029471)
			(xy 384.269899 -429.036994) (xy 384.257804 -429.037496) (xy 383.318004 -429.037496) (xy 383.305895 -429.03708)
			(xy 383.282867 -429.029582) (xy 383.263293 -429.01532) (xy 383.249099 -428.995698) (xy 383.241679 -428.972644)
			(xy 383.241296 -428.960534) (xy 383.241296 -428.352966) (xy 383.241042 -428.347124) (xy 383.239512 -428.332822)
			(xy 383.237862 -428.304103) (xy 383.23774 -428.28972) (xy 361.693458 -428.28972) (xy 361.70649 -428.297518)
			(xy 361.847915 -428.391417) (xy 361.984785 -428.491842) (xy 362.116796 -428.598572) (xy 362.24366 -428.711373)
			(xy 362.365097 -428.829996) (xy 362.480841 -428.954181) (xy 362.590636 -429.083654) (xy 362.694243 -429.218131)
			(xy 362.791432 -429.357317) (xy 362.88199 -429.500905) (xy 362.965718 -429.648581) (xy 363.042433 -429.800018)
			(xy 363.111965 -429.954885) (xy 363.174162 -430.11284) (xy 363.228886 -430.273538) (xy 363.276018 -430.436623)
			(xy 363.315454 -430.601739) (xy 363.347108 -430.768522) (xy 363.364298 -430.889918) (xy 381.237744 -430.889918)
			(xy 381.237856 -430.875535) (xy 381.239509 -430.846815) (xy 381.241046 -430.832514) (xy 381.2413 -430.826672)
			(xy 381.2413 -429.753014) (xy 381.241046 -429.747172) (xy 381.23952 -429.73287) (xy 381.237867 -429.704151)
			(xy 381.237744 -429.689768) (xy 381.23786 -429.675385) (xy 381.239511 -429.646666) (xy 381.241046 -429.632364)
			(xy 381.2413 -429.626522) (xy 381.2413 -429.018954) (xy 381.241767 -429.006866) (xy 381.249232 -428.983871)
			(xy 381.26342 -428.964295) (xy 381.28295 -428.950044) (xy 381.305922 -428.942507) (xy 381.318008 -428.941992)
			(xy 382.257808 -428.941992) (xy 382.269917 -428.942409) (xy 382.292943 -428.94991) (xy 382.312515 -428.964172)
			(xy 382.32671 -428.983792) (xy 382.334132 -429.006844) (xy 382.334516 -429.018954) (xy 382.334516 -431.560478)
			(xy 382.334073 -431.572571) (xy 382.326617 -431.595578) (xy 382.312426 -431.615162) (xy 382.292884 -431.629412)
			(xy 382.269899 -431.636937) (xy 382.257808 -431.63744) (xy 381.318008 -431.63744) (xy 381.305904 -431.636978)
			(xy 381.282883 -431.629485) (xy 381.263313 -431.615234) (xy 381.249117 -431.595625) (xy 381.241689 -431.572584)
			(xy 381.2413 -431.560478) (xy 381.2413 -430.953164) (xy 381.241046 -430.947322) (xy 381.239516 -430.93302)
			(xy 381.237866 -430.904301) (xy 381.237744 -430.889918) (xy 363.364298 -430.889918) (xy 363.370909 -430.936605)
			(xy 363.386805 -431.105619) (xy 363.394762 -431.275192) (xy 363.39526 -431.360072) (xy 363.394788 -431.445675)
			(xy 363.386701 -431.616689) (xy 363.370537 -431.787129) (xy 363.355859 -431.889916) (xy 383.23774 -431.889916)
			(xy 383.237851 -431.875533) (xy 383.239505 -431.846813) (xy 383.241042 -431.832512) (xy 383.241296 -431.82667)
			(xy 383.241296 -430.753012) (xy 383.241042 -430.74717) (xy 383.239516 -430.732868) (xy 383.237863 -430.704149)
			(xy 383.23774 -430.689766) (xy 383.237856 -430.675383) (xy 383.239507 -430.646664) (xy 383.241042 -430.632362)
			(xy 383.241296 -430.62652) (xy 383.241296 -430.018952) (xy 383.241723 -430.006875) (xy 383.249199 -429.983905)
			(xy 383.263405 -429.964368) (xy 383.282952 -429.950176) (xy 383.305926 -429.942715) (xy 383.318004 -429.942244)
			(xy 384.257804 -429.942244) (xy 384.269874 -429.94276) (xy 384.292833 -429.950218) (xy 384.312366 -429.964403)
			(xy 384.326562 -429.983927) (xy 384.334033 -430.006882) (xy 384.334512 -430.018952) (xy 384.334512 -430.889918)
			(xy 385.237736 -430.889918) (xy 385.237848 -430.875535) (xy 385.239501 -430.846815) (xy 385.241038 -430.832514)
			(xy 385.241292 -430.826672) (xy 385.241292 -429.753014) (xy 385.241038 -429.747172) (xy 385.239512 -429.73287)
			(xy 385.237859 -429.704151) (xy 385.237736 -429.689768) (xy 385.237852 -429.675385) (xy 385.239503 -429.646666)
			(xy 385.241038 -429.632364) (xy 385.241292 -429.626522) (xy 385.241292 -429.018954) (xy 385.241767 -429.006867)
			(xy 385.249231 -428.983873) (xy 385.263417 -428.964298) (xy 385.282945 -428.950047) (xy 385.305914 -428.942508)
			(xy 385.318 -428.941992) (xy 386.2578 -428.941992) (xy 386.269908 -428.942416) (xy 386.292934 -428.949914)
			(xy 386.312507 -428.964174) (xy 386.326701 -428.983794) (xy 386.334124 -429.006845) (xy 386.334508 -429.018954)
			(xy 386.334508 -431.560478) (xy 386.333975 -431.572562) (xy 386.32653 -431.595553) (xy 386.312359 -431.61513)
			(xy 386.292842 -431.629383) (xy 386.269882 -431.636924) (xy 386.2578 -431.63744) (xy 385.318 -431.63744)
			(xy 385.305895 -431.636984) (xy 385.282875 -431.62949) (xy 385.263305 -431.615237) (xy 385.249109 -431.595626)
			(xy 385.241681 -431.572584) (xy 385.241292 -431.560478) (xy 385.241292 -430.953164) (xy 385.241038 -430.947322)
			(xy 385.239508 -430.93302) (xy 385.237858 -430.904301) (xy 385.237736 -430.889918) (xy 384.334512 -430.889918)
			(xy 384.334512 -431.889916) (xy 387.237732 -431.889916) (xy 387.237843 -431.875533) (xy 387.239497 -431.846813)
			(xy 387.241034 -431.832512) (xy 387.241288 -431.82667) (xy 387.241288 -430.753012) (xy 387.241034 -430.74717)
			(xy 387.239508 -430.732868) (xy 387.237855 -430.704149) (xy 387.237732 -430.689766) (xy 387.237848 -430.675383)
			(xy 387.239499 -430.646664) (xy 387.241034 -430.632362) (xy 387.241288 -430.62652) (xy 387.241288 -430.018952)
			(xy 387.241723 -430.006875) (xy 387.249198 -429.983907) (xy 387.263403 -429.964371) (xy 387.282947 -429.950178)
			(xy 387.305919 -429.942716) (xy 387.317996 -429.942244) (xy 388.257796 -429.942244) (xy 388.269866 -429.942767)
			(xy 388.292824 -429.950222) (xy 388.312357 -429.964406) (xy 388.326554 -429.983929) (xy 388.334025 -430.006883)
			(xy 388.334504 -430.018952) (xy 388.334504 -430.889918) (xy 389.237728 -430.889918) (xy 389.23784 -430.875535)
			(xy 389.239493 -430.846815) (xy 389.24103 -430.832514) (xy 389.241284 -430.826672) (xy 389.241284 -429.753014)
			(xy 389.24103 -429.747172) (xy 389.239504 -429.73287) (xy 389.237851 -429.704151) (xy 389.237728 -429.689768)
			(xy 389.237844 -429.675385) (xy 389.239495 -429.646666) (xy 389.24103 -429.632364) (xy 389.241284 -429.626522)
			(xy 389.241284 -429.018954) (xy 389.241669 -429.006858) (xy 389.249144 -428.983848) (xy 389.26335 -428.964265)
			(xy 389.282903 -428.950018) (xy 389.305897 -428.942495) (xy 389.317992 -428.941992) (xy 390.257792 -428.941992)
			(xy 390.2699 -428.942423) (xy 390.292925 -428.949919) (xy 390.312498 -428.964177) (xy 390.326693 -428.983795)
			(xy 390.334116 -429.006845) (xy 390.3345 -429.018954) (xy 390.3345 -431.560478) (xy 390.333975 -431.572562)
			(xy 390.326529 -431.595556) (xy 390.312356 -431.615132) (xy 390.292837 -431.629385) (xy 390.269874 -431.636925)
			(xy 390.257792 -431.63744) (xy 389.317992 -431.63744) (xy 389.305887 -431.636991) (xy 389.282866 -431.629494)
			(xy 389.263296 -431.61524) (xy 389.249101 -431.595628) (xy 389.241673 -431.572585) (xy 389.241284 -431.560478)
			(xy 389.241284 -430.953164) (xy 389.24103 -430.947322) (xy 389.2395 -430.93302) (xy 389.23785 -430.904301)
			(xy 389.237728 -430.889918) (xy 388.334504 -430.889918) (xy 388.334504 -431.889916) (xy 391.237724 -431.889916)
			(xy 391.237835 -431.875533) (xy 391.239489 -431.846813) (xy 391.241026 -431.832512) (xy 391.24128 -431.82667)
			(xy 391.24128 -430.753012) (xy 391.241026 -430.74717) (xy 391.2395 -430.732868) (xy 391.237847 -430.704149)
			(xy 391.237724 -430.689766) (xy 391.23784 -430.675383) (xy 391.239491 -430.646664) (xy 391.241026 -430.632362)
			(xy 391.24128 -430.62652) (xy 391.24128 -430.018952) (xy 391.241723 -430.006876) (xy 391.249197 -429.983909)
			(xy 391.2634 -429.964374) (xy 391.282942 -429.950181) (xy 391.305912 -429.942717) (xy 391.317988 -429.942244)
			(xy 392.257788 -429.942244) (xy 392.269857 -429.942774) (xy 392.292816 -429.950227) (xy 392.312349 -429.964408)
			(xy 392.326546 -429.98393) (xy 392.334017 -430.006883) (xy 392.334496 -430.018952) (xy 392.334496 -430.889918)
			(xy 393.23772 -430.889918) (xy 393.237832 -430.875535) (xy 393.239485 -430.846815) (xy 393.241022 -430.832514)
			(xy 393.241276 -430.826672) (xy 393.241276 -429.753014) (xy 393.241022 -429.747172) (xy 393.239496 -429.73287)
			(xy 393.237843 -429.704151) (xy 393.23772 -429.689768) (xy 393.237836 -429.675385) (xy 393.239487 -429.646666)
			(xy 393.241022 -429.632364) (xy 393.241276 -429.626522) (xy 393.241276 -429.018954) (xy 393.241669 -429.006858)
			(xy 393.249143 -428.98385) (xy 393.263347 -428.964268) (xy 393.282898 -428.95002) (xy 393.30589 -428.942496)
			(xy 393.317984 -428.941992) (xy 394.257784 -428.941992) (xy 394.269891 -428.94243) (xy 394.292917 -428.949924)
			(xy 394.312489 -428.96418) (xy 394.326685 -428.983797) (xy 394.334107 -429.006846) (xy 394.334492 -429.018954)
			(xy 394.334492 -431.560478) (xy 394.333974 -431.572563) (xy 394.326528 -431.595558) (xy 394.312353 -431.615135)
			(xy 394.292832 -431.629388) (xy 394.269867 -431.636926) (xy 394.257784 -431.63744) (xy 393.317984 -431.63744)
			(xy 393.305878 -431.636998) (xy 393.282857 -431.629499) (xy 393.263288 -431.615243) (xy 393.249092 -431.595629)
			(xy 393.241665 -431.572585) (xy 393.241276 -431.560478) (xy 393.241276 -430.953164) (xy 393.241022 -430.947322)
			(xy 393.239492 -430.93302) (xy 393.237842 -430.904301) (xy 393.23772 -430.889918) (xy 392.334496 -430.889918)
			(xy 392.334496 -431.889916) (xy 395.237716 -431.889916) (xy 395.237828 -431.875533) (xy 395.239481 -431.846813)
			(xy 395.241018 -431.832512) (xy 395.241272 -431.82667) (xy 395.241272 -430.753012) (xy 395.241018 -430.74717)
			(xy 395.239492 -430.732868) (xy 395.237839 -430.704149) (xy 395.237716 -430.689766) (xy 395.237832 -430.675383)
			(xy 395.239483 -430.646664) (xy 395.241018 -430.632362) (xy 395.241272 -430.62652) (xy 395.241272 -430.018952)
			(xy 395.241723 -430.006877) (xy 395.249196 -429.983912) (xy 395.263397 -429.964377) (xy 395.282937 -429.950183)
			(xy 395.305905 -429.942718) (xy 395.31798 -429.942244) (xy 396.25778 -429.942244) (xy 396.269849 -429.94278)
			(xy 396.292807 -429.950232) (xy 396.31234 -429.964411) (xy 396.326537 -429.983932) (xy 396.334009 -430.006884)
			(xy 396.334488 -430.018952) (xy 396.334488 -430.889918) (xy 398.238472 -430.889918) (xy 398.23854 -430.877771)
			(xy 398.239684 -430.853504) (xy 398.240758 -430.841404) (xy 398.241012 -430.836578) (xy 398.241012 -429.743108)
			(xy 398.240758 -429.738282) (xy 398.239677 -429.726183) (xy 398.238535 -429.701915) (xy 398.238472 -429.689768)
			(xy 398.238544 -429.677621) (xy 398.239685 -429.653354) (xy 398.240758 -429.641254) (xy 398.241012 -429.636428)
			(xy 398.241012 -429.018954) (xy 398.241472 -429.00684) (xy 398.248969 -428.983799) (xy 398.263215 -428.964201)
			(xy 398.282817 -428.94996) (xy 398.30586 -428.942469) (xy 398.317974 -428.941992) (xy 399.257774 -428.941992)
			(xy 399.269883 -428.942533) (xy 399.292917 -428.950008) (xy 399.312515 -428.964233) (xy 399.326759 -428.983818)
			(xy 399.334255 -429.006846) (xy 399.334736 -429.018954) (xy 399.334736 -431.560478) (xy 399.334321 -431.572602)
			(xy 399.326832 -431.595665) (xy 399.31258 -431.615282) (xy 399.292961 -431.629533) (xy 399.269898 -431.637022)
			(xy 399.257774 -431.63744) (xy 398.317974 -431.63744) (xy 398.305856 -431.63701) (xy 398.282808 -431.629513)
			(xy 398.263205 -431.615261) (xy 398.248965 -431.595649) (xy 398.241482 -431.572596) (xy 398.241012 -431.560478)
			(xy 398.241012 -430.943258) (xy 398.240758 -430.938432) (xy 398.23968 -430.926333) (xy 398.238536 -430.902065)
			(xy 398.238472 -430.889918) (xy 396.334488 -430.889918) (xy 396.334488 -431.889916) (xy 400.238468 -431.889916)
			(xy 400.238536 -431.877769) (xy 400.23968 -431.853502) (xy 400.240754 -431.841402) (xy 400.241008 -431.836576)
			(xy 400.241008 -430.743106) (xy 400.240754 -430.73828) (xy 400.239673 -430.726181) (xy 400.238531 -430.701913)
			(xy 400.238468 -430.689766) (xy 400.23854 -430.677619) (xy 400.239681 -430.653352) (xy 400.240754 -430.641252)
			(xy 400.241008 -430.636426) (xy 400.241008 -430.018952) (xy 400.241419 -430.006898) (xy 400.248866 -429.98397)
			(xy 400.263019 -429.964454) (xy 400.2825 -429.950253) (xy 400.30541 -429.942749) (xy 400.317462 -429.942244)
			(xy 401.25777 -429.942244) (xy 401.269858 -429.942733) (xy 401.292859 -429.950182) (xy 401.312439 -429.964363)
			(xy 401.326691 -429.983892) (xy 401.334223 -430.006865) (xy 401.334732 -430.018952) (xy 401.334732 -430.889918)
			(xy 402.238464 -430.889918) (xy 402.238532 -430.877771) (xy 402.239676 -430.853504) (xy 402.24075 -430.841404)
			(xy 402.241004 -430.836578) (xy 402.241004 -429.743108) (xy 402.24075 -429.738282) (xy 402.239669 -429.726183)
			(xy 402.238527 -429.701915) (xy 402.238464 -429.689768) (xy 402.238536 -429.677621) (xy 402.239677 -429.653354)
			(xy 402.24075 -429.641254) (xy 402.241004 -429.636428) (xy 402.241004 -429.018954) (xy 402.241472 -429.00684)
			(xy 402.248968 -428.983801) (xy 402.263212 -428.964203) (xy 402.282812 -428.949962) (xy 402.305852 -428.94247)
			(xy 402.317966 -428.941992) (xy 403.257766 -428.941992) (xy 403.269874 -428.94254) (xy 403.292909 -428.950012)
			(xy 403.312507 -428.964236) (xy 403.326751 -428.98382) (xy 403.334247 -429.006846) (xy 403.334728 -429.018954)
			(xy 403.334728 -431.560478) (xy 403.334321 -431.572603) (xy 403.32683 -431.595667) (xy 403.312577 -431.615285)
			(xy 403.292956 -431.629536) (xy 403.269891 -431.637023) (xy 403.257766 -431.63744) (xy 402.317966 -431.63744)
			(xy 402.305847 -431.637017) (xy 402.282799 -431.629518) (xy 402.263196 -431.615264) (xy 402.248957 -431.59565)
			(xy 402.241474 -431.572597) (xy 402.241004 -431.560478) (xy 402.241004 -430.943258) (xy 402.24075 -430.938432)
			(xy 402.239672 -430.926333) (xy 402.238528 -430.902065) (xy 402.238464 -430.889918) (xy 401.334732 -430.889918)
			(xy 401.334732 -431.889916) (xy 404.23846 -431.889916) (xy 404.238528 -431.877769) (xy 404.239672 -431.853502)
			(xy 404.240746 -431.841402) (xy 404.241 -431.836576) (xy 404.241 -430.743106) (xy 404.240746 -430.73828)
			(xy 404.239665 -430.726181) (xy 404.238523 -430.701913) (xy 404.23846 -430.689766) (xy 404.238532 -430.677619)
			(xy 404.239673 -430.653352) (xy 404.240746 -430.641252) (xy 404.241 -430.636426) (xy 404.241 -430.018952)
			(xy 404.241419 -430.006899) (xy 404.248865 -429.983972) (xy 404.263016 -429.964457) (xy 404.282495 -429.950255)
			(xy 404.305403 -429.94275) (xy 404.317454 -429.942244) (xy 405.257762 -429.942244) (xy 405.26985 -429.94274)
			(xy 405.29285 -429.950187) (xy 405.312431 -429.964366) (xy 405.326683 -429.983894) (xy 405.334215 -430.006866)
			(xy 405.334724 -430.018952) (xy 405.334724 -430.889918) (xy 406.238456 -430.889918) (xy 406.238524 -430.877771)
			(xy 406.239668 -430.853504) (xy 406.240742 -430.841404) (xy 406.240996 -430.836578) (xy 406.240996 -429.743108)
			(xy 406.240742 -429.738282) (xy 406.239661 -429.726183) (xy 406.238519 -429.701915) (xy 406.238456 -429.689768)
			(xy 406.238528 -429.677621) (xy 406.239669 -429.653354) (xy 406.240742 -429.641254) (xy 406.240996 -429.636428)
			(xy 406.240996 -429.018954) (xy 406.241472 -429.006841) (xy 406.248967 -428.983804) (xy 406.263209 -428.964206)
			(xy 406.282807 -428.949965) (xy 406.305845 -428.942471) (xy 406.317958 -428.941992) (xy 407.257758 -428.941992)
			(xy 407.269866 -428.942547) (xy 407.2929 -428.950017) (xy 407.312498 -428.964239) (xy 407.326743 -428.983821)
			(xy 407.334239 -429.006847) (xy 407.33472 -429.018954) (xy 407.33472 -431.560478) (xy 407.334321 -431.572604)
			(xy 407.326829 -431.595669) (xy 407.312574 -431.615288) (xy 407.292951 -431.629538) (xy 407.269884 -431.637024)
			(xy 407.257758 -431.63744) (xy 406.317958 -431.63744) (xy 406.305839 -431.637024) (xy 406.282791 -431.629522)
			(xy 406.263188 -431.615267) (xy 406.248948 -431.595652) (xy 406.241466 -431.572597) (xy 406.240996 -431.560478)
			(xy 406.240996 -430.943258) (xy 406.240742 -430.938432) (xy 406.239664 -430.926333) (xy 406.23852 -430.902065)
			(xy 406.238456 -430.889918) (xy 405.334724 -430.889918) (xy 405.334724 -431.889916) (xy 408.238452 -431.889916)
			(xy 408.23852 -431.877769) (xy 408.239664 -431.853502) (xy 408.240738 -431.841402) (xy 408.240992 -431.836576)
			(xy 408.240992 -430.743106) (xy 408.240738 -430.73828) (xy 408.239656 -430.726181) (xy 408.238515 -430.701913)
			(xy 408.238452 -430.689766) (xy 408.238524 -430.677619) (xy 408.239665 -430.653352) (xy 408.240738 -430.641252)
			(xy 408.240992 -430.636426) (xy 408.240992 -430.018952) (xy 408.241419 -430.0069) (xy 408.248864 -429.983974)
			(xy 408.263013 -429.96446) (xy 408.28249 -429.950258) (xy 408.305395 -429.942752) (xy 408.317446 -429.942244)
			(xy 409.257754 -429.942244) (xy 409.269842 -429.942747) (xy 409.292841 -429.950191) (xy 409.312422 -429.964368)
			(xy 409.326674 -429.983895) (xy 409.334207 -430.006866) (xy 409.334716 -430.018952) (xy 409.334716 -430.889918)
			(xy 410.238448 -430.889918) (xy 410.238517 -430.877771) (xy 410.23966 -430.853504) (xy 410.240734 -430.841404)
			(xy 410.240988 -430.836578) (xy 410.240988 -429.743108) (xy 410.240734 -429.738282) (xy 410.239653 -429.726183)
			(xy 410.238511 -429.701915) (xy 410.238448 -429.689768) (xy 410.23852 -429.677621) (xy 410.239661 -429.653354)
			(xy 410.240734 -429.641254) (xy 410.240988 -429.636428) (xy 410.240988 -429.018954) (xy 410.241472 -429.006842)
			(xy 410.248966 -428.983806) (xy 410.263206 -428.964209) (xy 410.282802 -428.949967) (xy 410.305838 -428.942472)
			(xy 410.31795 -428.941992) (xy 411.25775 -428.941992) (xy 411.269863 -428.942468) (xy 411.2929 -428.949964)
			(xy 411.312497 -428.964206) (xy 411.326738 -428.983804) (xy 411.334232 -429.006841) (xy 411.334712 -429.018954)
			(xy 411.334712 -431.560478) (xy 411.33417 -431.572586) (xy 411.326695 -431.59562) (xy 411.312469 -431.615218)
			(xy 411.292885 -431.629462) (xy 411.269858 -431.636959) (xy 411.25775 -431.63744) (xy 410.31795 -431.63744)
			(xy 410.305831 -431.63703) (xy 410.282782 -431.629527) (xy 410.263179 -431.615269) (xy 410.24894 -431.595653)
			(xy 410.241458 -431.572598) (xy 410.240988 -431.560478) (xy 410.240988 -430.943258) (xy 410.240734 -430.938432)
			(xy 410.239656 -430.926333) (xy 410.238512 -430.902065) (xy 410.238448 -430.889918) (xy 409.334716 -430.889918)
			(xy 409.334716 -431.889916) (xy 412.238444 -431.889916) (xy 412.238512 -431.877769) (xy 412.239656 -431.853502)
			(xy 412.24073 -431.841402) (xy 412.240984 -431.836576) (xy 412.240984 -430.743106) (xy 412.24073 -430.73828)
			(xy 412.239648 -430.726181) (xy 412.238507 -430.701913) (xy 412.238444 -430.689766) (xy 412.238516 -430.677619)
			(xy 412.239657 -430.653352) (xy 412.24073 -430.641252) (xy 412.240984 -430.636426) (xy 412.240984 -430.018952)
			(xy 412.241419 -430.006901) (xy 412.248863 -429.983976) (xy 412.263011 -429.964463) (xy 412.282485 -429.950261)
			(xy 412.305388 -429.942753) (xy 412.317438 -429.942244) (xy 413.257746 -429.942244) (xy 413.269838 -429.942668)
			(xy 413.292841 -429.950138) (xy 413.312421 -429.964336) (xy 413.32667 -429.983878) (xy 413.3342 -430.006861)
			(xy 413.334708 -430.018952) (xy 413.334708 -432.560476) (xy 413.33422 -432.572524) (xy 413.326795 -432.595448)
			(xy 413.312661 -432.614963) (xy 413.293197 -432.629168) (xy 413.2703 -432.636676) (xy 413.258254 -432.637184)
			(xy 412.317946 -432.637184) (xy 412.305861 -432.636654) (xy 412.282866 -432.629213) (xy 412.263287 -432.615042)
			(xy 412.249034 -432.595522) (xy 412.241497 -432.572559) (xy 412.240984 -432.560476) (xy 412.240984 -431.943256)
			(xy 412.24073 -431.93843) (xy 412.239652 -431.926331) (xy 412.238508 -431.902063) (xy 412.238444 -431.889916)
			(xy 409.334716 -431.889916) (xy 409.334716 -432.560476) (xy 409.33422 -432.572523) (xy 409.326796 -432.595445)
			(xy 409.312664 -432.61496) (xy 409.293202 -432.629165) (xy 409.270308 -432.636675) (xy 409.258262 -432.637184)
			(xy 408.317954 -432.637184) (xy 408.305864 -432.636732) (xy 408.282866 -432.629266) (xy 408.263289 -432.615074)
			(xy 408.249039 -432.59554) (xy 408.241504 -432.572564) (xy 408.240992 -432.560476) (xy 408.240992 -431.943256)
			(xy 408.240738 -431.93843) (xy 408.23966 -431.926331) (xy 408.238516 -431.902063) (xy 408.238452 -431.889916)
			(xy 405.334724 -431.889916) (xy 405.334724 -432.560476) (xy 405.33422 -432.572523) (xy 405.326797 -432.595443)
			(xy 405.312667 -432.614957) (xy 405.293207 -432.629162) (xy 405.270315 -432.636673) (xy 405.25827 -432.637184)
			(xy 404.317962 -432.637184) (xy 404.305873 -432.636726) (xy 404.282875 -432.629261) (xy 404.263298 -432.615072)
			(xy 404.249048 -432.595538) (xy 404.241512 -432.572564) (xy 404.241 -432.560476) (xy 404.241 -431.943256)
			(xy 404.240746 -431.93843) (xy 404.239668 -431.926331) (xy 404.238524 -431.902063) (xy 404.23846 -431.889916)
			(xy 401.334732 -431.889916) (xy 401.334732 -432.560476) (xy 401.33422 -432.572522) (xy 401.326798 -432.595441)
			(xy 401.312669 -432.614955) (xy 401.293212 -432.62916) (xy 401.270322 -432.636672) (xy 401.258278 -432.637184)
			(xy 400.31797 -432.637184) (xy 400.305881 -432.636719) (xy 400.282884 -432.629257) (xy 400.263306 -432.615069)
			(xy 400.249056 -432.595537) (xy 400.24152 -432.572563) (xy 400.241008 -432.560476) (xy 400.241008 -431.943256)
			(xy 400.240754 -431.93843) (xy 400.239676 -431.926331) (xy 400.238532 -431.902063) (xy 400.238468 -431.889916)
			(xy 396.334488 -431.889916) (xy 396.334488 -432.560476) (xy 396.334066 -432.572559) (xy 396.326603 -432.595545)
			(xy 396.3124 -432.615097) (xy 396.292848 -432.629301) (xy 396.269863 -432.636766) (xy 396.25778 -432.637184)
			(xy 395.31798 -432.637184) (xy 395.305894 -432.636804) (xy 395.282906 -432.629328) (xy 395.263354 -432.615114)
			(xy 395.249152 -432.595554) (xy 395.241689 -432.572562) (xy 395.241272 -432.560476) (xy 395.241272 -431.953162)
			(xy 395.241018 -431.94732) (xy 395.239488 -431.933018) (xy 395.237838 -431.904299) (xy 395.237716 -431.889916)
			(xy 392.334496 -431.889916) (xy 392.334496 -432.560476) (xy 392.334067 -432.572559) (xy 392.326604 -432.595543)
			(xy 392.312403 -432.615094) (xy 392.292853 -432.629299) (xy 392.269871 -432.636765) (xy 392.257788 -432.637184)
			(xy 391.317988 -432.637184) (xy 391.305902 -432.636797) (xy 391.282915 -432.629324) (xy 391.263363 -432.615112)
			(xy 391.24916 -432.595553) (xy 391.241697 -432.572562) (xy 391.24128 -432.560476) (xy 391.24128 -431.953162)
			(xy 391.241026 -431.94732) (xy 391.239496 -431.933018) (xy 391.237846 -431.904299) (xy 391.237724 -431.889916)
			(xy 388.334504 -431.889916) (xy 388.334504 -432.560476) (xy 388.334067 -432.572558) (xy 388.326605 -432.59554)
			(xy 388.312406 -432.615091) (xy 388.292858 -432.629296) (xy 388.269878 -432.636764) (xy 388.257796 -432.637184)
			(xy 387.317996 -432.637184) (xy 387.305911 -432.636791) (xy 387.282924 -432.629319) (xy 387.263371 -432.615109)
			(xy 387.249168 -432.595551) (xy 387.241705 -432.572562) (xy 387.241288 -432.560476) (xy 387.241288 -431.953162)
			(xy 387.241034 -431.94732) (xy 387.239504 -431.933018) (xy 387.237854 -431.904299) (xy 387.237732 -431.889916)
			(xy 384.334512 -431.889916) (xy 384.334512 -432.560476) (xy 384.334067 -432.572557) (xy 384.326606 -432.595538)
			(xy 384.312409 -432.615089) (xy 384.292863 -432.629294) (xy 384.269885 -432.636762) (xy 384.257804 -432.637184)
			(xy 383.318004 -432.637184) (xy 383.305919 -432.636784) (xy 383.282932 -432.629314) (xy 383.26338 -432.615106)
			(xy 383.249176 -432.59555) (xy 383.241713 -432.572561) (xy 383.241296 -432.560476) (xy 383.241296 -431.953162)
			(xy 383.241042 -431.94732) (xy 383.239512 -431.933018) (xy 383.237862 -431.904299) (xy 383.23774 -431.889916)
			(xy 363.355859 -431.889916) (xy 363.346334 -431.956615) (xy 363.314145 -432.124767) (xy 363.274043 -432.291209)
			(xy 363.226117 -432.455569) (xy 363.170474 -432.61748) (xy 363.107239 -432.776579) (xy 363.036553 -432.932511)
			(xy 362.958574 -433.084927) (xy 362.873477 -433.233486) (xy 362.781452 -433.377855) (xy 362.682704 -433.517713)
			(xy 362.577455 -433.652746) (xy 362.46594 -433.782652) (xy 362.348408 -433.907141) (xy 362.225123 -434.025934)
			(xy 362.096359 -434.138766) (xy 361.962404 -434.245385) (xy 361.82356 -434.345551) (xy 361.680135 -434.439042)
			(xy 361.593477 -434.48986) (xy 381.237744 -434.48986) (xy 381.237859 -434.475477) (xy 381.23951 -434.446758)
			(xy 381.241046 -434.432456) (xy 381.2413 -434.426614) (xy 381.2413 -433.35321) (xy 381.241046 -433.347368)
			(xy 381.23952 -433.333066) (xy 381.237867 -433.304347) (xy 381.237744 -433.289964) (xy 381.237859 -433.275581)
			(xy 381.239511 -433.246862) (xy 381.241046 -433.23256) (xy 381.2413 -433.226718) (xy 381.2413 -432.618896)
			(xy 381.241709 -432.606812) (xy 381.249179 -432.583828) (xy 381.263386 -432.564277) (xy 381.282939 -432.550073)
			(xy 381.305924 -432.542607) (xy 381.318008 -432.542188) (xy 382.257808 -432.542188) (xy 382.269883 -432.542657)
			(xy 382.292849 -432.550122) (xy 382.312386 -432.564317) (xy 382.32658 -432.583854) (xy 382.334043 -432.606821)
			(xy 382.334516 -432.618896) (xy 382.334516 -435.16042) (xy 382.334053 -435.172495) (xy 382.326586 -435.195461)
			(xy 382.312389 -435.214997) (xy 382.29285 -435.229191) (xy 382.269883 -435.236655) (xy 382.257808 -435.237128)
			(xy 381.318008 -435.237128) (xy 381.305936 -435.236629) (xy 381.282972 -435.229171) (xy 381.263437 -435.214983)
			(xy 381.249241 -435.195453) (xy 381.241775 -435.172492) (xy 381.2413 -435.16042) (xy 381.2413 -434.553106)
			(xy 381.241046 -434.547264) (xy 381.23952 -434.532962) (xy 381.237867 -434.504243) (xy 381.237744 -434.48986)
			(xy 361.593477 -434.48986) (xy 361.53245 -434.525647) (xy 361.380836 -434.605174) (xy 361.225632 -434.677444)
			(xy 361.146598 -434.710332) (xy 361.138713 -434.713995) (xy 361.125816 -434.725637) (xy 361.117551 -434.740919)
			(xy 361.115864 -434.749448) (xy 361.100116 -434.849016) (xy 361.109514 -434.873654) (xy 361.119928 -434.88229)
			(xy 361.169374 -434.924299) (xy 361.263563 -435.013553) (xy 361.352051 -435.108462) (xy 361.434498 -435.208663)
			(xy 361.510589 -435.313772) (xy 361.580032 -435.423387) (xy 361.616588 -435.489858) (xy 383.23774 -435.489858)
			(xy 383.237855 -435.475475) (xy 383.239506 -435.446756) (xy 383.241042 -435.432454) (xy 383.241296 -435.426612)
			(xy 383.241296 -434.353208) (xy 383.241042 -434.347366) (xy 383.239516 -434.333064) (xy 383.237863 -434.304345)
			(xy 383.23774 -434.289962) (xy 383.237855 -434.275579) (xy 383.239507 -434.24686) (xy 383.241042 -434.232558)
			(xy 383.241296 -434.226716) (xy 383.241296 -433.618894) (xy 383.241802 -433.606809) (xy 383.249255 -433.583815)
			(xy 383.263433 -433.564239) (xy 383.282955 -433.549987) (xy 383.30592 -433.542448) (xy 383.318004 -433.541932)
			(xy 384.257804 -433.541932) (xy 384.269916 -433.542313) (xy 384.292949 -433.549818) (xy 384.312525 -433.564087)
			(xy 384.326718 -433.583718) (xy 384.334133 -433.60678) (xy 384.334512 -433.618894) (xy 384.334512 -434.48986)
			(xy 385.237736 -434.48986) (xy 385.237851 -434.475477) (xy 385.239502 -434.446758) (xy 385.241038 -434.432456)
			(xy 385.241292 -434.426614) (xy 385.241292 -433.35321) (xy 385.241038 -433.347368) (xy 385.239512 -433.333066)
			(xy 385.237859 -433.304347) (xy 385.237736 -433.289964) (xy 385.237851 -433.275581) (xy 385.239503 -433.246862)
			(xy 385.241038 -433.23256) (xy 385.241292 -433.226718) (xy 385.241292 -432.618896) (xy 385.241761 -432.606821)
			(xy 385.249224 -432.583854) (xy 385.26342 -432.564317) (xy 385.282958 -432.550123) (xy 385.305925 -432.54266)
			(xy 385.318 -432.542188) (xy 386.2578 -432.542188) (xy 386.269874 -432.542664) (xy 386.292841 -432.550126)
			(xy 386.312377 -432.56432) (xy 386.326572 -432.583856) (xy 386.334035 -432.606822) (xy 386.334508 -432.618896)
			(xy 386.334508 -435.16042) (xy 386.334053 -435.172496) (xy 386.326585 -435.195463) (xy 386.312386 -435.215)
			(xy 386.292845 -435.229194) (xy 386.269876 -435.236656) (xy 386.2578 -435.237128) (xy 385.318 -435.237128)
			(xy 385.305927 -435.236636) (xy 385.282964 -435.229176) (xy 385.263428 -435.214986) (xy 385.249233 -435.195454)
			(xy 385.241767 -435.172492) (xy 385.241292 -435.16042) (xy 385.241292 -434.553106) (xy 385.241038 -434.547264)
			(xy 385.239511 -434.532962) (xy 385.237859 -434.504243) (xy 385.237736 -434.48986) (xy 384.334512 -434.48986)
			(xy 384.334512 -435.489858) (xy 387.237732 -435.489858) (xy 387.237847 -435.475475) (xy 387.239498 -435.446756)
			(xy 387.241034 -435.432454) (xy 387.241288 -435.426612) (xy 387.241288 -434.353208) (xy 387.241034 -434.347366)
			(xy 387.239508 -434.333064) (xy 387.237855 -434.304345) (xy 387.237732 -434.289962) (xy 387.237847 -434.275579)
			(xy 387.239499 -434.24686) (xy 387.241034 -434.232558) (xy 387.241288 -434.226716) (xy 387.241288 -433.618894)
			(xy 387.241703 -433.606799) (xy 387.249168 -433.583791) (xy 387.263366 -433.564207) (xy 387.282913 -433.549958)
			(xy 387.305903 -433.542435) (xy 387.317996 -433.541932) (xy 388.257796 -433.541932) (xy 388.269908 -433.54232)
			(xy 388.292941 -433.549822) (xy 388.312517 -433.56409) (xy 388.32671 -433.58372) (xy 388.334125 -433.606781)
			(xy 388.334504 -433.618894) (xy 388.334504 -434.48986) (xy 389.237728 -434.48986) (xy 389.237843 -434.475477)
			(xy 389.239495 -434.446758) (xy 389.24103 -434.432456) (xy 389.241284 -434.426614) (xy 389.241284 -433.35321)
			(xy 389.24103 -433.347368) (xy 389.239504 -433.333066) (xy 389.237851 -433.304347) (xy 389.237728 -433.289964)
			(xy 389.237844 -433.275581) (xy 389.239495 -433.246862) (xy 389.24103 -433.23256) (xy 389.241284 -433.226718)
			(xy 389.241284 -432.618896) (xy 389.241761 -432.606822) (xy 389.249223 -432.583856) (xy 389.263417 -432.56432)
			(xy 389.282953 -432.550125) (xy 389.305918 -432.542661) (xy 389.317992 -432.542188) (xy 390.257792 -432.542188)
			(xy 390.269874 -432.542619) (xy 390.292856 -432.550084) (xy 390.312406 -432.564286) (xy 390.326611 -432.583833)
			(xy 390.334079 -432.606814) (xy 390.3345 -432.618896) (xy 390.3345 -435.16042) (xy 390.334053 -435.172496)
			(xy 390.326584 -435.195465) (xy 390.312383 -435.215003) (xy 390.29284 -435.229196) (xy 390.269869 -435.236657)
			(xy 390.257792 -435.237128) (xy 389.317992 -435.237128) (xy 389.305919 -435.236643) (xy 389.282955 -435.229181)
			(xy 389.26342 -435.214989) (xy 389.249225 -435.195456) (xy 389.241759 -435.172493) (xy 389.241284 -435.16042)
			(xy 389.241284 -434.553106) (xy 389.24103 -434.547264) (xy 389.239503 -434.532962) (xy 389.237851 -434.504243)
			(xy 389.237728 -434.48986) (xy 388.334504 -434.48986) (xy 388.334504 -435.489858) (xy 391.237724 -435.489858)
			(xy 391.237839 -435.475475) (xy 391.23949 -435.446756) (xy 391.241026 -435.432454) (xy 391.24128 -435.426612)
			(xy 391.24128 -434.353208) (xy 391.241026 -434.347366) (xy 391.2395 -434.333064) (xy 391.237847 -434.304345)
			(xy 391.237724 -434.289962) (xy 391.237839 -434.275579) (xy 391.239491 -434.24686) (xy 391.241026 -434.232558)
			(xy 391.24128 -434.226716) (xy 391.24128 -433.618894) (xy 391.241703 -433.6068) (xy 391.249166 -433.583793)
			(xy 391.263363 -433.564209) (xy 391.282908 -433.549961) (xy 391.305896 -433.542436) (xy 391.317988 -433.541932)
			(xy 392.257788 -433.541932) (xy 392.269899 -433.542327) (xy 392.292932 -433.549827) (xy 392.312508 -433.564093)
			(xy 392.326702 -433.583721) (xy 392.334117 -433.606781) (xy 392.334496 -433.618894) (xy 392.334496 -434.48986)
			(xy 393.23772 -434.48986) (xy 393.237835 -434.475477) (xy 393.239487 -434.446758) (xy 393.241022 -434.432456)
			(xy 393.241276 -434.426614) (xy 393.241276 -433.35321) (xy 393.241022 -433.347368) (xy 393.239496 -433.333066)
			(xy 393.237843 -433.304347) (xy 393.23772 -433.289964) (xy 393.237836 -433.275581) (xy 393.239487 -433.246862)
			(xy 393.241022 -433.23256) (xy 393.241276 -433.226718) (xy 393.241276 -432.618896) (xy 393.241761 -432.606823)
			(xy 393.249222 -432.583858) (xy 393.263414 -432.564323) (xy 393.282948 -432.550128) (xy 393.305911 -432.542663)
			(xy 393.317984 -432.542188) (xy 394.257784 -432.542188) (xy 394.269865 -432.542626) (xy 394.292847 -432.550089)
			(xy 394.312397 -432.564289) (xy 394.326602 -432.583835) (xy 394.33407 -432.606815) (xy 394.334492 -432.618896)
			(xy 394.334492 -435.16042) (xy 394.334052 -435.172497) (xy 394.326582 -435.195468) (xy 394.31238 -435.215006)
			(xy 394.292835 -435.229199) (xy 394.269861 -435.236658) (xy 394.257784 -435.237128) (xy 393.317984 -435.237128)
			(xy 393.305911 -435.23665) (xy 393.282946 -435.229185) (xy 393.263411 -435.214991) (xy 393.249217 -435.195457)
			(xy 393.241751 -435.172493) (xy 393.241276 -435.16042) (xy 393.241276 -434.553106) (xy 393.241022 -434.547264)
			(xy 393.239495 -434.532962) (xy 393.237843 -434.504243) (xy 393.23772 -434.48986) (xy 392.334496 -434.48986)
			(xy 392.334496 -435.489858) (xy 395.237716 -435.489858) (xy 395.237831 -435.475475) (xy 395.239482 -435.446756)
			(xy 395.241018 -435.432454) (xy 395.241272 -435.426612) (xy 395.241272 -434.353208) (xy 395.241018 -434.347366)
			(xy 395.239492 -434.333064) (xy 395.237839 -434.304345) (xy 395.237716 -434.289962) (xy 395.237831 -434.275579)
			(xy 395.239483 -434.24686) (xy 395.241018 -434.232558) (xy 395.241272 -434.226716) (xy 395.241272 -433.618894)
			(xy 395.241703 -433.606801) (xy 395.249165 -433.583795) (xy 395.26336 -433.564212) (xy 395.282903 -433.549963)
			(xy 395.305888 -433.542437) (xy 395.31798 -433.541932) (xy 396.25778 -433.541932) (xy 396.269891 -433.542334)
			(xy 396.292923 -433.549832) (xy 396.312499 -433.564096) (xy 396.326693 -433.583723) (xy 396.334109 -433.606782)
			(xy 396.334488 -433.618894) (xy 396.334488 -434.48986) (xy 398.238472 -434.48986) (xy 398.238543 -434.477713)
			(xy 398.239685 -434.453446) (xy 398.240758 -434.441346) (xy 398.241012 -434.43652) (xy 398.241012 -433.343304)
			(xy 398.240758 -433.338478) (xy 398.239684 -433.326378) (xy 398.238538 -433.302111) (xy 398.238472 -433.289964)
			(xy 398.238544 -433.277817) (xy 398.239685 -433.25355) (xy 398.240758 -433.24145) (xy 398.241012 -433.236624)
			(xy 398.241012 -432.618896) (xy 398.241457 -432.606844) (xy 398.248892 -432.583917) (xy 398.263036 -432.5644)
			(xy 398.282511 -432.550197) (xy 398.305416 -432.542693) (xy 398.317466 -432.542188) (xy 399.257774 -432.542188)
			(xy 399.269867 -432.54263) (xy 399.292875 -432.550086) (xy 399.312459 -432.564277) (xy 399.326709 -432.583819)
			(xy 399.334233 -432.606804) (xy 399.334736 -432.618896) (xy 399.334736 -435.16042) (xy 399.334258 -435.172468)
			(xy 399.326824 -435.195388) (xy 399.312686 -435.2149) (xy 399.293223 -435.229104) (xy 399.270328 -435.236616)
			(xy 399.258282 -435.237128) (xy 398.317974 -435.237128) (xy 398.30588 -435.236714) (xy 398.282873 -435.229247)
			(xy 398.263291 -435.215047) (xy 398.249042 -435.195501) (xy 398.241516 -435.172513) (xy 398.241012 -435.16042)
			(xy 398.241012 -434.5432) (xy 398.240758 -434.538374) (xy 398.239683 -434.526274) (xy 398.238537 -434.502007)
			(xy 398.238472 -434.48986) (xy 396.334488 -434.48986) (xy 396.334488 -435.489858) (xy 400.238468 -435.489858)
			(xy 400.238539 -435.477711) (xy 400.239681 -435.453444) (xy 400.240754 -435.441344) (xy 400.241008 -435.436518)
			(xy 400.241008 -434.343302) (xy 400.240754 -434.338476) (xy 400.239679 -434.326376) (xy 400.238534 -434.302109)
			(xy 400.238468 -434.289962) (xy 400.23854 -434.277815) (xy 400.239681 -434.253548) (xy 400.240754 -434.241448)
			(xy 400.241008 -434.236622) (xy 400.241008 -433.618894) (xy 400.241506 -433.606782) (xy 400.248992 -433.583744)
			(xy 400.263228 -433.564145) (xy 400.282822 -433.549903) (xy 400.305858 -433.54241) (xy 400.31797 -433.541932)
			(xy 401.25777 -433.541932) (xy 401.269891 -433.542385) (xy 401.292947 -433.549869) (xy 401.312563 -433.564112)
			(xy 401.326815 -433.58372) (xy 401.334309 -433.606774) (xy 401.334732 -433.618894) (xy 401.334732 -434.48986)
			(xy 402.238464 -434.48986) (xy 402.238535 -434.477713) (xy 402.239677 -434.453446) (xy 402.24075 -434.441346)
			(xy 402.241004 -434.43652) (xy 402.241004 -433.343304) (xy 402.24075 -433.338478) (xy 402.239675 -433.326378)
			(xy 402.23853 -433.302111) (xy 402.238464 -433.289964) (xy 402.238536 -433.277817) (xy 402.239677 -433.25355)
			(xy 402.24075 -433.24145) (xy 402.241004 -433.236624) (xy 402.241004 -432.618896) (xy 402.241457 -432.606845)
			(xy 402.248891 -432.583919) (xy 402.263034 -432.564403) (xy 402.282506 -432.5502) (xy 402.305409 -432.542694)
			(xy 402.317458 -432.542188) (xy 403.257766 -432.542188) (xy 403.269859 -432.542637) (xy 403.292866 -432.55009)
			(xy 403.312451 -432.56428) (xy 403.326701 -432.583821) (xy 403.334225 -432.606805) (xy 403.334728 -432.618896)
			(xy 403.334728 -435.16042) (xy 403.334257 -435.172468) (xy 403.326823 -435.19539) (xy 403.312684 -435.214903)
			(xy 403.293217 -435.229106) (xy 403.270321 -435.236617) (xy 403.258274 -435.237128) (xy 402.317966 -435.237128)
			(xy 402.305871 -435.236721) (xy 402.282864 -435.229251) (xy 402.263282 -435.21505) (xy 402.249034 -435.195502)
			(xy 402.241508 -435.172513) (xy 402.241004 -435.16042) (xy 402.241004 -434.5432) (xy 402.24075 -434.538374)
			(xy 402.239675 -434.526274) (xy 402.238529 -434.502007) (xy 402.238464 -434.48986) (xy 401.334732 -434.48986)
			(xy 401.334732 -435.489858) (xy 404.23846 -435.489858) (xy 404.238531 -435.477711) (xy 404.239673 -435.453444)
			(xy 404.240746 -435.441344) (xy 404.241 -435.436518) (xy 404.241 -434.343302) (xy 404.240746 -434.338476)
			(xy 404.239671 -434.326376) (xy 404.238526 -434.302109) (xy 404.23846 -434.289962) (xy 404.238532 -434.277815)
			(xy 404.239673 -434.253548) (xy 404.240746 -434.241448) (xy 404.241 -434.236622) (xy 404.241 -433.618894)
			(xy 404.241506 -433.606783) (xy 404.24899 -433.583746) (xy 404.263225 -433.564148) (xy 404.282817 -433.549905)
			(xy 404.305851 -433.542411) (xy 404.317962 -433.541932) (xy 405.257762 -433.541932) (xy 405.269882 -433.542392)
			(xy 405.292939 -433.549873) (xy 405.312554 -433.564115) (xy 405.326807 -433.583722) (xy 405.334301 -433.606774)
			(xy 405.334724 -433.618894) (xy 405.334724 -434.48986) (xy 406.238456 -434.48986) (xy 406.238527 -434.477713)
			(xy 406.239669 -434.453446) (xy 406.240742 -434.441346) (xy 406.240996 -434.43652) (xy 406.240996 -433.343304)
			(xy 406.240742 -433.338478) (xy 406.239667 -433.326378) (xy 406.238522 -433.302111) (xy 406.238456 -433.289964)
			(xy 406.238528 -433.277817) (xy 406.239669 -433.25355) (xy 406.240742 -433.24145) (xy 406.240996 -433.236624)
			(xy 406.240996 -432.618896) (xy 406.241457 -432.606846) (xy 406.24889 -432.583921) (xy 406.263031 -432.564406)
			(xy 406.282501 -432.550202) (xy 406.305402 -432.542696) (xy 406.31745 -432.542188) (xy 407.257758 -432.542188)
			(xy 407.26985 -432.542644) (xy 407.292858 -432.550095) (xy 407.312442 -432.564283) (xy 407.326693 -432.583822)
			(xy 407.334217 -432.606805) (xy 407.33472 -432.618896) (xy 407.33472 -435.16042) (xy 407.334257 -435.172469)
			(xy 407.326821 -435.195392) (xy 407.312681 -435.214906) (xy 407.293212 -435.229109) (xy 407.270314 -435.236618)
			(xy 407.258266 -435.237128) (xy 406.317958 -435.237128) (xy 406.305863 -435.236728) (xy 406.282856 -435.229256)
			(xy 406.263274 -435.215053) (xy 406.249026 -435.195504) (xy 406.2415 -435.172514) (xy 406.240996 -435.16042)
			(xy 406.240996 -434.5432) (xy 406.240742 -434.538374) (xy 406.239667 -434.526274) (xy 406.238521 -434.502007)
			(xy 406.238456 -434.48986) (xy 405.334724 -434.48986) (xy 405.334724 -435.489858) (xy 408.238452 -435.489858)
			(xy 408.238523 -435.477711) (xy 408.239665 -435.453444) (xy 408.240738 -435.441344) (xy 408.240992 -435.436518)
			(xy 408.240992 -434.343302) (xy 408.240738 -434.338476) (xy 408.239663 -434.326376) (xy 408.238518 -434.302109)
			(xy 408.238452 -434.289962) (xy 408.238524 -434.277815) (xy 408.239665 -434.253548) (xy 408.240738 -434.241448)
			(xy 408.240992 -434.236622) (xy 408.240992 -433.618894) (xy 408.241506 -433.606784) (xy 408.248989 -433.583748)
			(xy 408.263222 -433.564151) (xy 408.282812 -433.549908) (xy 408.305844 -433.542412) (xy 408.317954 -433.541932)
			(xy 409.257754 -433.541932) (xy 409.269874 -433.542399) (xy 409.29293 -433.549878) (xy 409.312546 -433.564117)
			(xy 409.326798 -433.583723) (xy 409.334293 -433.606775) (xy 409.334716 -433.618894) (xy 409.334716 -434.48986)
			(xy 410.238448 -434.48986) (xy 410.238519 -434.477713) (xy 410.239661 -434.453446) (xy 410.240734 -434.441346)
			(xy 410.240988 -434.43652) (xy 410.240988 -433.343304) (xy 410.240734 -433.338478) (xy 410.239659 -433.326378)
			(xy 410.238514 -433.302111) (xy 410.238448 -433.289964) (xy 410.23852 -433.277817) (xy 410.239661 -433.25355)
			(xy 410.240734 -433.24145) (xy 410.240988 -433.236624) (xy 410.240988 -432.618896) (xy 410.241456 -432.606847)
			(xy 410.248889 -432.583923) (xy 410.263028 -432.564409) (xy 410.282496 -432.550205) (xy 410.305394 -432.542697)
			(xy 410.317442 -432.542188) (xy 411.25775 -432.542188) (xy 411.269842 -432.542651) (xy 411.292849 -432.5501)
			(xy 411.312434 -432.564285) (xy 411.326684 -432.583823) (xy 411.334209 -432.606806) (xy 411.334712 -432.618896)
			(xy 411.334712 -435.16042) (xy 411.334257 -435.17247) (xy 411.32682 -435.195394) (xy 411.312678 -435.214908)
			(xy 411.293207 -435.229111) (xy 411.270306 -435.236619) (xy 411.258258 -435.237128) (xy 410.31795 -435.237128)
			(xy 410.30586 -435.23665) (xy 410.282855 -435.229203) (xy 410.263272 -435.21502) (xy 410.249021 -435.195487)
			(xy 410.241493 -435.172508) (xy 410.240988 -435.16042) (xy 410.240988 -434.5432) (xy 410.240734 -434.538374)
			(xy 410.239659 -434.526274) (xy 410.238513 -434.502007) (xy 410.238448 -434.48986) (xy 409.334716 -434.48986)
			(xy 409.334716 -435.489858) (xy 412.238444 -435.489858) (xy 412.238515 -435.477711) (xy 412.239657 -435.453444)
			(xy 412.24073 -435.441344) (xy 412.240984 -435.436518) (xy 412.240984 -434.343302) (xy 412.24073 -434.338476)
			(xy 412.239655 -434.326376) (xy 412.23851 -434.302109) (xy 412.238444 -434.289962) (xy 412.238515 -434.277815)
			(xy 412.239657 -434.253548) (xy 412.24073 -434.241448) (xy 412.240984 -434.236622) (xy 412.240984 -433.618894)
			(xy 412.241356 -433.606766) (xy 412.248855 -433.5837) (xy 412.263118 -433.564081) (xy 412.282746 -433.549831)
			(xy 412.305818 -433.542348) (xy 412.317946 -433.541932) (xy 413.257746 -433.541932) (xy 413.269862 -433.542372)
			(xy 413.292906 -433.549872) (xy 413.312507 -433.564122) (xy 413.326747 -433.58373) (xy 413.334234 -433.606777)
			(xy 413.334708 -433.618894) (xy 413.334708 -435.59984) (xy 446.741306 -435.59984) (xy 446.745288 -435.471854)
			(xy 446.75722 -435.344363) (xy 446.777054 -435.21786) (xy 446.804715 -435.092835) (xy 446.840095 -434.969772)
			(xy 446.883057 -434.849146) (xy 446.933435 -434.731425) (xy 446.991035 -434.617063) (xy 447.055633 -434.506504)
			(xy 447.12698 -434.400174) (xy 447.204799 -434.298486) (xy 447.288789 -434.201832) (xy 447.378626 -434.110587)
			(xy 447.473962 -434.025104) (xy 447.574427 -433.945713) (xy 447.679635 -433.872721) (xy 447.789176 -433.806412)
			(xy 447.902628 -433.747041) (xy 448.019552 -433.694837) (xy 448.139495 -433.650004) (xy 448.261993 -433.612715)
			(xy 448.386573 -433.583113) (xy 448.512751 -433.561314) (xy 448.640041 -433.547401) (xy 448.76795 -433.541429)
			(xy 448.895983 -433.54342) (xy 449.023644 -433.553368) (xy 449.15044 -433.571232) (xy 449.275879 -433.596945)
			(xy 449.399478 -433.630407) (xy 449.520757 -433.671488) (xy 449.639248 -433.72003) (xy 449.754492 -433.775844)
			(xy 449.866042 -433.838715) (xy 449.973469 -433.908399) (xy 450.076355 -433.984627) (xy 450.174303 -434.067104)
			(xy 450.266934 -434.155511) (xy 450.35389 -434.249506) (xy 450.434834 -434.348725) (xy 450.509453 -434.452784)
			(xy 450.577458 -434.561281) (xy 450.638586 -434.673796) (xy 450.692601 -434.789894) (xy 450.739294 -434.909125)
			(xy 450.778484 -435.031029) (xy 450.81002 -435.155133) (xy 450.833779 -435.280957) (xy 450.849669 -435.408016)
			(xy 450.85763 -435.535816) (xy 450.858128 -435.59984) (xy 450.85763 -435.663864) (xy 450.849669 -435.791664)
			(xy 450.833779 -435.918723) (xy 450.81002 -436.044547) (xy 450.778484 -436.168651) (xy 450.739294 -436.290555)
			(xy 450.692601 -436.409786) (xy 450.638586 -436.525884) (xy 450.577458 -436.638399) (xy 450.509453 -436.746896)
			(xy 450.434834 -436.850955) (xy 450.35389 -436.950174) (xy 450.266934 -437.044169) (xy 450.174303 -437.132576)
			(xy 450.076355 -437.215053) (xy 449.973469 -437.291281) (xy 449.866042 -437.360965) (xy 449.754492 -437.423836)
			(xy 449.639248 -437.47965) (xy 449.520757 -437.528192) (xy 449.399478 -437.569273) (xy 449.275879 -437.602735)
			(xy 449.15044 -437.628448) (xy 449.023644 -437.646312) (xy 448.895983 -437.65626) (xy 448.76795 -437.658251)
			(xy 448.640041 -437.652279) (xy 448.512751 -437.638366) (xy 448.386573 -437.616567) (xy 448.261993 -437.586965)
			(xy 448.139495 -437.549676) (xy 448.019552 -437.504843) (xy 447.902628 -437.452639) (xy 447.789176 -437.393268)
			(xy 447.679635 -437.326959) (xy 447.574427 -437.253967) (xy 447.473962 -437.174576) (xy 447.378626 -437.089093)
			(xy 447.288789 -436.997848) (xy 447.204799 -436.901194) (xy 447.12698 -436.799506) (xy 447.055633 -436.693176)
			(xy 446.991035 -436.582617) (xy 446.933435 -436.468255) (xy 446.883057 -436.350534) (xy 446.840095 -436.229908)
			(xy 446.804715 -436.106845) (xy 446.777054 -435.98182) (xy 446.75722 -435.855317) (xy 446.745288 -435.727826)
			(xy 446.741306 -435.59984) (xy 413.334708 -435.59984) (xy 413.334708 -436.160418) (xy 413.334205 -436.172529)
			(xy 413.326718 -436.195565) (xy 413.312482 -436.215163) (xy 413.29289 -436.229405) (xy 413.269857 -436.2369)
			(xy 413.257746 -436.23738) (xy 412.317946 -436.23738) (xy 412.305827 -436.236901) (xy 412.282773 -436.229424)
			(xy 412.263159 -436.215187) (xy 412.248905 -436.195584) (xy 412.241409 -436.172536) (xy 412.240984 -436.160418)
			(xy 412.240984 -435.543198) (xy 412.24073 -435.538372) (xy 412.239655 -435.526272) (xy 412.238509 -435.502005)
			(xy 412.238444 -435.489858) (xy 409.334716 -435.489858) (xy 409.334716 -436.160418) (xy 409.334354 -436.172546)
			(xy 409.326852 -436.195613) (xy 409.312586 -436.215232) (xy 409.292956 -436.229481) (xy 409.269883 -436.236965)
			(xy 409.257754 -436.23738) (xy 408.317954 -436.23738) (xy 408.305839 -436.236928) (xy 408.282797 -436.22943)
			(xy 408.263198 -436.215182) (xy 408.248957 -436.195578) (xy 408.241468 -436.172533) (xy 408.240992 -436.160418)
			(xy 408.240992 -435.543198) (xy 408.240738 -435.538372) (xy 408.239663 -435.526272) (xy 408.238517 -435.502005)
			(xy 408.238452 -435.489858) (xy 405.334724 -435.489858) (xy 405.334724 -436.160418) (xy 405.334355 -436.172545)
			(xy 405.326853 -436.195611) (xy 405.312589 -436.215229) (xy 405.292961 -436.229478) (xy 405.26989 -436.236963)
			(xy 405.257762 -436.23738) (xy 404.317962 -436.23738) (xy 404.305847 -436.236921) (xy 404.282806 -436.229425)
			(xy 404.263206 -436.21518) (xy 404.248965 -436.195576) (xy 404.241476 -436.172533) (xy 404.241 -436.160418)
			(xy 404.241 -435.543198) (xy 404.240746 -435.538372) (xy 404.239671 -435.526272) (xy 404.238525 -435.502005)
			(xy 404.23846 -435.489858) (xy 401.334732 -435.489858) (xy 401.334732 -436.160418) (xy 401.334355 -436.172545)
			(xy 401.326854 -436.195609) (xy 401.312592 -436.215226) (xy 401.292966 -436.229476) (xy 401.269897 -436.236962)
			(xy 401.25777 -436.23738) (xy 400.31797 -436.23738) (xy 400.305856 -436.236914) (xy 400.282814 -436.229421)
			(xy 400.263215 -436.215177) (xy 400.248974 -436.195575) (xy 400.241484 -436.172532) (xy 400.241008 -436.160418)
			(xy 400.241008 -435.543198) (xy 400.240754 -435.538372) (xy 400.239679 -435.526272) (xy 400.238533 -435.502005)
			(xy 400.238468 -435.489858) (xy 396.334488 -435.489858) (xy 396.334488 -436.160418) (xy 396.334009 -436.172506)
			(xy 396.32655 -436.195502) (xy 396.312366 -436.21508) (xy 396.292837 -436.229331) (xy 396.269866 -436.236867)
			(xy 396.25778 -436.23738) (xy 395.31798 -436.23738) (xy 395.305868 -436.237001) (xy 395.282837 -436.229493)
			(xy 395.263262 -436.215223) (xy 395.249069 -436.195592) (xy 395.241652 -436.172532) (xy 395.241272 -436.160418)
			(xy 395.241272 -435.553104) (xy 395.241018 -435.547262) (xy 395.239491 -435.53296) (xy 395.237839 -435.504241)
			(xy 395.237716 -435.489858) (xy 392.334496 -435.489858) (xy 392.334496 -436.160418) (xy 392.334009 -436.172505)
			(xy 392.326552 -436.1955) (xy 392.312369 -436.215077) (xy 392.292842 -436.229328) (xy 392.269873 -436.236866)
			(xy 392.257788 -436.23738) (xy 391.317988 -436.23738) (xy 391.305876 -436.236994) (xy 391.282845 -436.229489)
			(xy 391.263271 -436.21522) (xy 391.249077 -436.195591) (xy 391.24166 -436.172531) (xy 391.24128 -436.160418)
			(xy 391.24128 -435.553104) (xy 391.241026 -435.547262) (xy 391.239499 -435.53296) (xy 391.237847 -435.504241)
			(xy 391.237724 -435.489858) (xy 388.334504 -435.489858) (xy 388.334504 -436.160418) (xy 388.334009 -436.172504)
			(xy 388.326553 -436.195498) (xy 388.312372 -436.215074) (xy 388.292847 -436.229325) (xy 388.26988 -436.236865)
			(xy 388.257796 -436.23738) (xy 387.317996 -436.23738) (xy 387.305885 -436.236987) (xy 387.282854 -436.229484)
			(xy 387.263279 -436.215217) (xy 387.249085 -436.195589) (xy 387.241668 -436.172531) (xy 387.241288 -436.160418)
			(xy 387.241288 -435.553104) (xy 387.241034 -435.547262) (xy 387.239507 -435.53296) (xy 387.237855 -435.504241)
			(xy 387.237732 -435.489858) (xy 384.334512 -435.489858) (xy 384.334512 -436.160418) (xy 384.334107 -436.172513)
			(xy 384.32664 -436.195523) (xy 384.312439 -436.215106) (xy 384.292889 -436.229355) (xy 384.269898 -436.236878)
			(xy 384.257804 -436.23738) (xy 383.318004 -436.23738) (xy 383.305893 -436.23698) (xy 383.282863 -436.229479)
			(xy 383.263288 -436.215214) (xy 383.249094 -436.195588) (xy 383.241676 -436.17253) (xy 383.241296 -436.160418)
			(xy 383.241296 -435.553104) (xy 383.241042 -435.547262) (xy 383.239515 -435.53296) (xy 383.237863 -435.504241)
			(xy 383.23774 -435.489858) (xy 361.616588 -435.489858) (xy 361.642562 -435.537087) (xy 361.697938 -435.654438)
			(xy 361.74595 -435.77499) (xy 361.786412 -435.89828) (xy 361.81917 -436.023838) (xy 361.844098 -436.151181)
			(xy 361.861101 -436.279823) (xy 361.870114 -436.40927) (xy 361.871103 -436.539027) (xy 361.864062 -436.668596)
			(xy 361.849021 -436.797482) (xy 361.826035 -436.92519) (xy 361.795194 -437.051232) (xy 361.756614 -437.175125)
			(xy 361.710445 -437.296394) (xy 361.656862 -437.414574) (xy 361.596072 -437.529214) (xy 361.528306 -437.639874)
			(xy 361.453825 -437.74613) (xy 361.372914 -437.847575) (xy 361.285882 -437.943821) (xy 361.193064 -438.034499)
			(xy 361.128961 -438.089802) (xy 381.218186 -438.089802) (xy 381.218618 -438.057912) (xy 381.226256 -437.994592)
			(xy 381.24141 -437.93264) (xy 381.263863 -437.872943) (xy 381.293293 -437.81636) (xy 381.329278 -437.763702)
			(xy 381.371301 -437.715724) (xy 381.394716 -437.69407) (xy 381.398348 -437.690741) (xy 381.404359 -437.682936)
			(xy 381.406654 -437.678576) (xy 381.4826 -437.523382) (xy 381.487302 -437.512866) (xy 381.490792 -437.490107)
			(xy 381.487306 -437.467348) (xy 381.4826 -437.456834) (xy 381.405892 -437.300878) (xy 381.403725 -437.296539)
			(xy 381.397963 -437.28874) (xy 381.394462 -437.285384) (xy 381.371044 -437.263771) (xy 381.329083 -437.215806)
			(xy 381.293156 -437.163169) (xy 381.263778 -437.106615) (xy 381.241371 -437.046955) (xy 381.226256 -436.985044)
			(xy 381.218649 -436.921771) (xy 381.218186 -436.889906) (xy 381.21884 -436.852371) (xy 381.229416 -436.778049)
			(xy 381.239268 -436.741824) (xy 381.240217 -436.738345) (xy 381.241237 -436.731206) (xy 381.2413 -436.7276)
			(xy 381.2413 -436.219092) (xy 381.241758 -436.207016) (xy 381.249223 -436.184047) (xy 381.263421 -436.16451)
			(xy 381.282962 -436.150316) (xy 381.305932 -436.142855) (xy 381.318008 -436.142384) (xy 382.257808 -436.142384)
			(xy 382.269882 -436.142857) (xy 382.292848 -436.150321) (xy 382.312384 -436.164516) (xy 382.326579 -436.184052)
			(xy 382.334043 -436.207018) (xy 382.334516 -436.219092) (xy 382.334516 -438.760616) (xy 382.334049 -438.772691)
			(xy 382.326583 -438.795657) (xy 382.312387 -438.815193) (xy 382.29285 -438.829387) (xy 382.269883 -438.836851)
			(xy 382.257808 -438.837324) (xy 381.318008 -438.837324) (xy 381.305935 -438.836829) (xy 381.282971 -438.829371)
			(xy 381.263435 -438.815182) (xy 381.24924 -438.79565) (xy 381.241775 -438.772688) (xy 381.2413 -438.760616)
			(xy 381.2413 -438.252108) (xy 381.241235 -438.248502) (xy 381.240217 -438.241363) (xy 381.239268 -438.237884)
			(xy 381.229441 -438.201653) (xy 381.218855 -438.127336) (xy 381.218186 -438.089802) (xy 361.128961 -438.089802)
			(xy 361.094814 -438.119261) (xy 360.991508 -438.197784) (xy 360.883543 -438.269766) (xy 360.771333 -438.334931)
			(xy 360.655306 -438.39303) (xy 360.535907 -438.443841) (xy 360.413594 -438.487169) (xy 360.288835 -438.522847)
			(xy 360.162108 -438.550739) (xy 360.033898 -438.570739) (xy 359.904696 -438.58277) (xy 359.774998 -438.586785)
			(xy 359.6453 -438.58277) (xy 359.516098 -438.570739) (xy 359.387888 -438.550739) (xy 359.261161 -438.522847)
			(xy 359.136402 -438.487169) (xy 359.014089 -438.443841) (xy 358.89469 -438.39303) (xy 358.778663 -438.334931)
			(xy 358.666453 -438.269766) (xy 358.558488 -438.197784) (xy 358.455182 -438.119261) (xy 358.356932 -438.034499)
			(xy 358.264114 -437.943821) (xy 358.177082 -437.847575) (xy 358.096171 -437.74613) (xy 358.02169 -437.639874)
			(xy 357.953924 -437.529214) (xy 357.893134 -437.414574) (xy 357.839551 -437.296394) (xy 357.793382 -437.175125)
			(xy 357.754802 -437.051232) (xy 357.723961 -436.92519) (xy 357.700975 -436.797482) (xy 357.685934 -436.668596)
			(xy 357.678893 -436.539027) (xy 357.679882 -436.40927) (xy 357.688895 -436.279823) (xy 357.705898 -436.151181)
			(xy 357.730826 -436.023838) (xy 357.763584 -435.89828) (xy 357.804046 -435.77499) (xy 357.852058 -435.654438)
			(xy 357.907434 -435.537087) (xy 357.969964 -435.423387) (xy 358.039407 -435.313772) (xy 358.115498 -435.208663)
			(xy 358.197945 -435.108462) (xy 358.286433 -435.013553) (xy 358.380622 -434.924299) (xy 358.430068 -434.88229)
			(xy 358.440228 -434.873908) (xy 358.449626 -434.849016) (xy 358.4321 -434.73624) (xy 358.415844 -434.715412)
			(xy 358.403398 -434.710332) (xy 358.325295 -434.677853) (xy 358.1719 -434.606515) (xy 358.022004 -434.52809)
			(xy 357.875935 -434.44275) (xy 357.734012 -434.350681) (xy 357.596544 -434.252083) (xy 357.463831 -434.147172)
			(xy 357.336162 -434.036176) (xy 357.213818 -433.919339) (xy 357.097064 -433.796915) (xy 356.986156 -433.669172)
			(xy 356.881335 -433.536387) (xy 356.782831 -433.398852) (xy 356.690858 -433.256866) (xy 356.605617 -433.110739)
			(xy 356.527295 -432.96079) (xy 356.456061 -432.807346) (xy 356.392073 -432.650743) (xy 356.335468 -432.491322)
			(xy 356.286372 -432.329431) (xy 356.244891 -432.165424) (xy 356.211115 -431.999658) (xy 356.185119 -431.832496)
			(xy 356.166958 -431.664301) (xy 356.156674 -431.495443) (xy 356.15499 -431.410872) (xy 356.155244 -431.410872)
			(xy 356.154736 -431.360072) (xy 346.234512 -431.360072) (xy 346.234512 -432.560476) (xy 346.234067 -432.572557)
			(xy 346.226606 -432.595538) (xy 346.212409 -432.615089) (xy 346.192863 -432.629294) (xy 346.169885 -432.636762)
			(xy 346.157804 -432.637184) (xy 345.218004 -432.637184) (xy 345.205919 -432.636784) (xy 345.182932 -432.629314)
			(xy 345.16338 -432.615106) (xy 345.149176 -432.59555) (xy 345.141713 -432.572561) (xy 345.141296 -432.560476)
			(xy 345.141296 -431.953162) (xy 345.141042 -431.94732) (xy 345.139512 -431.933018) (xy 345.137862 -431.904299)
			(xy 345.13774 -431.889916) (xy 342.23452 -431.889916) (xy 342.23452 -432.560476) (xy 342.234067 -432.572556)
			(xy 342.226607 -432.595536) (xy 342.212411 -432.615086) (xy 342.192868 -432.629291) (xy 342.169892 -432.636761)
			(xy 342.157812 -432.637184) (xy 341.218012 -432.637184) (xy 341.205928 -432.636777) (xy 341.182941 -432.629309)
			(xy 341.163389 -432.615103) (xy 341.149185 -432.595548) (xy 341.141722 -432.572561) (xy 341.141304 -432.560476)
			(xy 341.141304 -431.953162) (xy 341.14105 -431.94732) (xy 341.13952 -431.933018) (xy 341.13787 -431.904299)
			(xy 341.137748 -431.889916) (xy 338.234528 -431.889916) (xy 338.234528 -432.560476) (xy 338.234067 -432.572555)
			(xy 338.226609 -432.595534) (xy 338.212414 -432.615083) (xy 338.192873 -432.629288) (xy 338.169899 -432.63676)
			(xy 338.15782 -432.637184) (xy 337.21802 -432.637184) (xy 337.205936 -432.63677) (xy 337.18295 -432.629305)
			(xy 337.163397 -432.6151) (xy 337.149193 -432.595547) (xy 337.14173 -432.57256) (xy 337.141312 -432.560476)
			(xy 337.141312 -431.953162) (xy 337.141058 -431.94732) (xy 337.139528 -431.933018) (xy 337.137878 -431.904299)
			(xy 337.137756 -431.889916) (xy 334.234536 -431.889916) (xy 334.234536 -432.560476) (xy 334.234016 -432.572547)
			(xy 334.226563 -432.595508) (xy 334.21238 -432.615043) (xy 334.192855 -432.62924) (xy 334.169898 -432.636708)
			(xy 334.157828 -432.637184) (xy 333.218028 -432.637184) (xy 333.205944 -432.636763) (xy 333.182959 -432.6293)
			(xy 333.163406 -432.615097) (xy 333.149202 -432.595545) (xy 333.141738 -432.57256) (xy 333.14132 -432.560476)
			(xy 333.14132 -431.953162) (xy 333.141066 -431.94732) (xy 333.139536 -431.933018) (xy 333.137886 -431.904299)
			(xy 333.137764 -431.889916) (xy 329.2348 -431.889916) (xy 329.2348 -432.560476) (xy 329.23432 -432.572525)
			(xy 329.226894 -432.59545) (xy 329.212758 -432.614966) (xy 329.193292 -432.62917) (xy 329.170393 -432.636677)
			(xy 329.158346 -432.637184) (xy 328.218038 -432.637184) (xy 328.205953 -432.636661) (xy 328.182957 -432.629217)
			(xy 328.163379 -432.615044) (xy 328.149126 -432.595524) (xy 328.141589 -432.572559) (xy 328.141076 -432.560476)
			(xy 328.141076 -431.953162) (xy 328.140822 -431.94732) (xy 328.139292 -431.933018) (xy 328.137642 -431.904299)
			(xy 328.13752 -431.889916) (xy 325.234808 -431.889916) (xy 325.234808 -432.560476) (xy 325.23432 -432.572524)
			(xy 325.226895 -432.595448) (xy 325.212761 -432.614963) (xy 325.193297 -432.629168) (xy 325.1704 -432.636676)
			(xy 325.158354 -432.637184) (xy 324.218046 -432.637184) (xy 324.205961 -432.636654) (xy 324.182966 -432.629213)
			(xy 324.163387 -432.615042) (xy 324.149134 -432.595522) (xy 324.141597 -432.572559) (xy 324.141084 -432.560476)
			(xy 324.141084 -431.953162) (xy 324.14083 -431.94732) (xy 324.1393 -431.933018) (xy 324.13765 -431.904299)
			(xy 324.137528 -431.889916) (xy 321.234816 -431.889916) (xy 321.234816 -432.560476) (xy 321.23432 -432.572523)
			(xy 321.226896 -432.595445) (xy 321.212764 -432.61496) (xy 321.193302 -432.629165) (xy 321.170408 -432.636675)
			(xy 321.158362 -432.637184) (xy 320.218054 -432.637184) (xy 320.205964 -432.636732) (xy 320.182966 -432.629266)
			(xy 320.163389 -432.615074) (xy 320.149139 -432.59554) (xy 320.141604 -432.572564) (xy 320.141092 -432.560476)
			(xy 320.141092 -431.953162) (xy 320.140838 -431.94732) (xy 320.139308 -431.933018) (xy 320.137658 -431.904299)
			(xy 320.137536 -431.889916) (xy 317.234824 -431.889916) (xy 317.234824 -432.560476) (xy 317.23432 -432.572523)
			(xy 317.226897 -432.595443) (xy 317.212767 -432.614957) (xy 317.193307 -432.629162) (xy 317.170415 -432.636673)
			(xy 317.15837 -432.637184) (xy 316.218062 -432.637184) (xy 316.205973 -432.636726) (xy 316.182975 -432.629261)
			(xy 316.163398 -432.615072) (xy 316.149148 -432.595538) (xy 316.141612 -432.572564) (xy 316.1411 -432.560476)
			(xy 316.1411 -431.953162) (xy 316.140846 -431.94732) (xy 316.139316 -431.933018) (xy 316.137666 -431.904299)
			(xy 316.137544 -431.889916) (xy 274.613204 -431.889916) (xy 274.618425 -431.905986) (xy 274.665585 -432.076867)
			(xy 274.705031 -432.249692) (xy 274.736684 -432.424113) (xy 274.760479 -432.599778) (xy 274.77637 -432.776334)
			(xy 274.784323 -432.953425) (xy 274.78482 -433.04206) (xy 274.784323 -433.130695) (xy 274.77637 -433.307786)
			(xy 274.760479 -433.484342) (xy 274.736684 -433.660007) (xy 274.705031 -433.834428) (xy 274.665585 -434.007253)
			(xy 274.618425 -434.178134) (xy 274.563646 -434.346728) (xy 274.509927 -434.48986) (xy 314.137548 -434.48986)
			(xy 314.137664 -434.475477) (xy 314.139315 -434.446758) (xy 314.14085 -434.432456) (xy 314.141104 -434.426614)
			(xy 314.141104 -433.35321) (xy 314.14085 -433.347368) (xy 314.139324 -433.333066) (xy 314.137671 -433.304347)
			(xy 314.137548 -433.289964) (xy 314.137664 -433.275581) (xy 314.139315 -433.246862) (xy 314.14085 -433.23256)
			(xy 314.141104 -433.226718) (xy 314.141104 -432.618896) (xy 314.141557 -432.606845) (xy 314.148991 -432.583919)
			(xy 314.163134 -432.564403) (xy 314.182606 -432.5502) (xy 314.205509 -432.542694) (xy 314.217558 -432.542188)
			(xy 315.157866 -432.542188) (xy 315.169959 -432.542637) (xy 315.192966 -432.55009) (xy 315.212551 -432.56428)
			(xy 315.226801 -432.583821) (xy 315.234325 -432.606805) (xy 315.234828 -432.618896) (xy 315.234828 -435.16042)
			(xy 315.234357 -435.172468) (xy 315.226923 -435.19539) (xy 315.212784 -435.214903) (xy 315.193317 -435.229106)
			(xy 315.170421 -435.236617) (xy 315.158374 -435.237128) (xy 314.218066 -435.237128) (xy 314.205971 -435.236721)
			(xy 314.182964 -435.229251) (xy 314.163382 -435.21505) (xy 314.149134 -435.195502) (xy 314.141608 -435.172513)
			(xy 314.141104 -435.16042) (xy 314.141104 -434.553106) (xy 314.14085 -434.547264) (xy 314.139324 -434.532962)
			(xy 314.137671 -434.504243) (xy 314.137548 -434.48986) (xy 274.509927 -434.48986) (xy 274.501358 -434.512693)
			(xy 274.431686 -434.675698) (xy 274.354772 -434.835412) (xy 274.270769 -434.991515) (xy 274.179848 -435.143692)
			(xy 274.082191 -435.291636) (xy 273.977994 -435.43505) (xy 273.934286 -435.489858) (xy 316.137544 -435.489858)
			(xy 316.137659 -435.475475) (xy 316.13931 -435.446756) (xy 316.140846 -435.432454) (xy 316.1411 -435.426612)
			(xy 316.1411 -434.353208) (xy 316.140846 -434.347366) (xy 316.13932 -434.333064) (xy 316.137667 -434.304345)
			(xy 316.137544 -434.289962) (xy 316.137659 -434.275579) (xy 316.139311 -434.24686) (xy 316.140846 -434.232558)
			(xy 316.1411 -434.226716) (xy 316.1411 -433.618894) (xy 316.141606 -433.606783) (xy 316.14909 -433.583746)
			(xy 316.163325 -433.564148) (xy 316.182917 -433.549905) (xy 316.205951 -433.542411) (xy 316.218062 -433.541932)
			(xy 317.157862 -433.541932) (xy 317.169982 -433.542392) (xy 317.193039 -433.549873) (xy 317.212654 -433.564115)
			(xy 317.226907 -433.583722) (xy 317.234401 -433.606774) (xy 317.234824 -433.618894) (xy 317.234824 -434.48986)
			(xy 318.13754 -434.48986) (xy 318.137655 -434.475477) (xy 318.139306 -434.446758) (xy 318.140842 -434.432456)
			(xy 318.141096 -434.426614) (xy 318.141096 -433.35321) (xy 318.140842 -433.347368) (xy 318.139316 -433.333066)
			(xy 318.137663 -433.304347) (xy 318.13754 -433.289964) (xy 318.137655 -433.275581) (xy 318.139307 -433.246862)
			(xy 318.140842 -433.23256) (xy 318.141096 -433.226718) (xy 318.141096 -432.618896) (xy 318.141557 -432.606846)
			(xy 318.14899 -432.583921) (xy 318.163131 -432.564406) (xy 318.182601 -432.550202) (xy 318.205502 -432.542696)
			(xy 318.21755 -432.542188) (xy 319.157858 -432.542188) (xy 319.16995 -432.542644) (xy 319.192958 -432.550095)
			(xy 319.212542 -432.564283) (xy 319.226793 -432.583822) (xy 319.234317 -432.606805) (xy 319.23482 -432.618896)
			(xy 319.23482 -435.16042) (xy 319.234357 -435.172469) (xy 319.226921 -435.195392) (xy 319.212781 -435.214906)
			(xy 319.193312 -435.229109) (xy 319.170414 -435.236618) (xy 319.158366 -435.237128) (xy 318.218058 -435.237128)
			(xy 318.205963 -435.236728) (xy 318.182956 -435.229256) (xy 318.163374 -435.215053) (xy 318.149126 -435.195504)
			(xy 318.1416 -435.172514) (xy 318.141096 -435.16042) (xy 318.141096 -434.553106) (xy 318.140842 -434.547264)
			(xy 318.139316 -434.532962) (xy 318.137663 -434.504243) (xy 318.13754 -434.48986) (xy 317.234824 -434.48986)
			(xy 317.234824 -435.489858) (xy 320.137536 -435.489858) (xy 320.137651 -435.475475) (xy 320.139302 -435.446756)
			(xy 320.140838 -435.432454) (xy 320.141092 -435.426612) (xy 320.141092 -434.353208) (xy 320.140838 -434.347366)
			(xy 320.139312 -434.333064) (xy 320.137659 -434.304345) (xy 320.137536 -434.289962) (xy 320.137651 -434.275579)
			(xy 320.139303 -434.24686) (xy 320.140838 -434.232558) (xy 320.141092 -434.226716) (xy 320.141092 -433.618894)
			(xy 320.141606 -433.606784) (xy 320.149089 -433.583748) (xy 320.163322 -433.564151) (xy 320.182912 -433.549908)
			(xy 320.205944 -433.542412) (xy 320.218054 -433.541932) (xy 321.157854 -433.541932) (xy 321.169974 -433.542399)
			(xy 321.19303 -433.549878) (xy 321.212646 -433.564117) (xy 321.226898 -433.583723) (xy 321.234393 -433.606775)
			(xy 321.234816 -433.618894) (xy 321.234816 -434.48986) (xy 322.137532 -434.48986) (xy 322.137647 -434.475477)
			(xy 322.139299 -434.446758) (xy 322.140834 -434.432456) (xy 322.141088 -434.426614) (xy 322.141088 -433.35321)
			(xy 322.140834 -433.347368) (xy 322.139308 -433.333066) (xy 322.137655 -433.304347) (xy 322.137532 -433.289964)
			(xy 322.137647 -433.275581) (xy 322.139299 -433.246862) (xy 322.140834 -433.23256) (xy 322.141088 -433.226718)
			(xy 322.141088 -432.618896) (xy 322.141556 -432.606847) (xy 322.148989 -432.583923) (xy 322.163128 -432.564409)
			(xy 322.182596 -432.550205) (xy 322.205494 -432.542697) (xy 322.217542 -432.542188) (xy 323.15785 -432.542188)
			(xy 323.169942 -432.542651) (xy 323.192949 -432.5501) (xy 323.212534 -432.564285) (xy 323.226784 -432.583823)
			(xy 323.234309 -432.606806) (xy 323.234812 -432.618896) (xy 323.234812 -435.16042) (xy 323.234357 -435.17247)
			(xy 323.22692 -435.195394) (xy 323.212778 -435.214908) (xy 323.193307 -435.229111) (xy 323.170406 -435.236619)
			(xy 323.158358 -435.237128) (xy 322.21805 -435.237128) (xy 322.20596 -435.23665) (xy 322.182955 -435.229203)
			(xy 322.163372 -435.21502) (xy 322.149121 -435.195487) (xy 322.141593 -435.172508) (xy 322.141088 -435.16042)
			(xy 322.141088 -434.553106) (xy 322.140834 -434.547264) (xy 322.139307 -434.532962) (xy 322.137655 -434.504243)
			(xy 322.137532 -434.48986) (xy 321.234816 -434.48986) (xy 321.234816 -435.489858) (xy 324.137528 -435.489858)
			(xy 324.137643 -435.475475) (xy 324.139294 -435.446756) (xy 324.14083 -435.432454) (xy 324.141084 -435.426612)
			(xy 324.141084 -434.353208) (xy 324.14083 -434.347366) (xy 324.139304 -434.333064) (xy 324.137651 -434.304345)
			(xy 324.137528 -434.289962) (xy 324.137643 -434.275579) (xy 324.139295 -434.24686) (xy 324.14083 -434.232558)
			(xy 324.141084 -434.226716) (xy 324.141084 -433.618894) (xy 324.141456 -433.606766) (xy 324.148955 -433.5837)
			(xy 324.163218 -433.564081) (xy 324.182846 -433.549831) (xy 324.205918 -433.542348) (xy 324.218046 -433.541932)
			(xy 325.157846 -433.541932) (xy 325.169962 -433.542372) (xy 325.193006 -433.549872) (xy 325.212607 -433.564122)
			(xy 325.226847 -433.58373) (xy 325.234334 -433.606777) (xy 325.234808 -433.618894) (xy 325.234808 -434.48986)
			(xy 326.137524 -434.48986) (xy 326.137639 -434.475477) (xy 326.139291 -434.446758) (xy 326.140826 -434.432456)
			(xy 326.14108 -434.426614) (xy 326.14108 -433.35321) (xy 326.140826 -433.347368) (xy 326.1393 -433.333066)
			(xy 326.137647 -433.304347) (xy 326.137524 -433.289964) (xy 326.13764 -433.275581) (xy 326.139291 -433.246862)
			(xy 326.140826 -433.23256) (xy 326.14108 -433.226718) (xy 326.14108 -432.618896) (xy 326.141556 -432.606848)
			(xy 326.148988 -432.583925) (xy 326.163125 -432.564411) (xy 326.182591 -432.550208) (xy 326.205487 -432.542698)
			(xy 326.217534 -432.542188) (xy 327.157842 -432.542188) (xy 327.169939 -432.542572) (xy 327.192949 -432.550047)
			(xy 327.212532 -432.564253) (xy 327.226779 -432.583806) (xy 327.234302 -432.606801) (xy 327.234804 -432.618896)
			(xy 327.234804 -435.16042) (xy 327.234357 -435.172471) (xy 327.226919 -435.195396) (xy 327.212775 -435.214911)
			(xy 327.193302 -435.229114) (xy 327.170399 -435.23662) (xy 327.15835 -435.237128) (xy 326.218042 -435.237128)
			(xy 326.205951 -435.236656) (xy 326.182947 -435.229207) (xy 326.163363 -435.215023) (xy 326.149113 -435.195488)
			(xy 326.141585 -435.172509) (xy 326.14108 -435.16042) (xy 326.14108 -434.553106) (xy 326.140826 -434.547264)
			(xy 326.139299 -434.532962) (xy 326.137647 -434.504243) (xy 326.137524 -434.48986) (xy 325.234808 -434.48986)
			(xy 325.234808 -435.489858) (xy 328.13752 -435.489858) (xy 328.137635 -435.475475) (xy 328.139286 -435.446756)
			(xy 328.140822 -435.432454) (xy 328.141076 -435.426612) (xy 328.141076 -434.353208) (xy 328.140822 -434.347366)
			(xy 328.139296 -434.333064) (xy 328.137643 -434.304345) (xy 328.13752 -434.289962) (xy 328.137635 -434.275579)
			(xy 328.139287 -434.24686) (xy 328.140822 -434.232558) (xy 328.141076 -434.226716) (xy 328.141076 -433.618894)
			(xy 328.141456 -433.606767) (xy 328.148954 -433.583702) (xy 328.163215 -433.564084) (xy 328.182841 -433.549834)
			(xy 328.205911 -433.542349) (xy 328.218038 -433.541932) (xy 329.157838 -433.541932) (xy 329.169954 -433.542379)
			(xy 329.192997 -433.549876) (xy 329.212598 -433.564125) (xy 329.226838 -433.583731) (xy 329.234326 -433.606778)
			(xy 329.2348 -433.618894) (xy 329.2348 -434.48986) (xy 331.137768 -434.48986) (xy 331.137884 -434.475477)
			(xy 331.139535 -434.446758) (xy 331.14107 -434.432456) (xy 331.141324 -434.426614) (xy 331.141324 -433.35321)
			(xy 331.14107 -433.347368) (xy 331.139544 -433.333066) (xy 331.137891 -433.304347) (xy 331.137768 -433.289964)
			(xy 331.137884 -433.275581) (xy 331.139535 -433.246862) (xy 331.14107 -433.23256) (xy 331.141324 -433.226718)
			(xy 331.141324 -432.618896) (xy 331.14171 -432.60681) (xy 331.149182 -432.583822) (xy 331.163394 -432.564268)
			(xy 331.182954 -432.550066) (xy 331.205946 -432.542604) (xy 331.218032 -432.542188) (xy 332.157832 -432.542188)
			(xy 332.169908 -432.542637) (xy 332.192875 -432.550108) (xy 332.212412 -432.564308) (xy 332.226605 -432.58385)
			(xy 332.234068 -432.60682) (xy 332.23454 -432.618896) (xy 332.23454 -435.16042) (xy 332.234053 -435.172492)
			(xy 332.226589 -435.195455) (xy 332.212397 -435.214989) (xy 332.192865 -435.229184) (xy 332.169904 -435.236651)
			(xy 332.157832 -435.237128) (xy 331.218032 -435.237128) (xy 331.205953 -435.23666) (xy 331.182975 -435.229204)
			(xy 331.163426 -435.215011) (xy 331.14922 -435.195472) (xy 331.141748 -435.172499) (xy 331.141324 -435.16042)
			(xy 331.141324 -434.553106) (xy 331.14107 -434.547264) (xy 331.139543 -434.532962) (xy 331.137891 -434.504243)
			(xy 331.137768 -434.48986) (xy 329.2348 -434.48986) (xy 329.2348 -435.489858) (xy 333.137764 -435.489858)
			(xy 333.137879 -435.475475) (xy 333.139531 -435.446756) (xy 333.141066 -435.432454) (xy 333.14132 -435.426612)
			(xy 333.14132 -434.353208) (xy 333.141066 -434.347366) (xy 333.139539 -434.333064) (xy 333.137887 -434.304345)
			(xy 333.137764 -434.289962) (xy 333.13788 -434.275579) (xy 333.139531 -434.24686) (xy 333.141066 -434.232558)
			(xy 333.14132 -434.226716) (xy 333.14132 -433.618894) (xy 333.141802 -433.606806) (xy 333.149258 -433.583809)
			(xy 333.163441 -433.564231) (xy 333.18297 -433.54998) (xy 333.205942 -433.542444) (xy 333.218028 -433.541932)
			(xy 334.157828 -433.541932) (xy 334.169942 -433.542293) (xy 334.192975 -433.549804) (xy 334.212551 -433.564079)
			(xy 334.226743 -433.583714) (xy 334.234157 -433.606779) (xy 334.234536 -433.618894) (xy 334.234536 -434.48986)
			(xy 335.13776 -434.48986) (xy 335.137876 -434.475477) (xy 335.139527 -434.446758) (xy 335.141062 -434.432456)
			(xy 335.141316 -434.426614) (xy 335.141316 -433.35321) (xy 335.141062 -433.347368) (xy 335.139536 -433.333066)
			(xy 335.137883 -433.304347) (xy 335.13776 -433.289964) (xy 335.137876 -433.275581) (xy 335.139527 -433.246862)
			(xy 335.141062 -433.23256) (xy 335.141316 -433.226718) (xy 335.141316 -432.618896) (xy 335.141709 -432.606811)
			(xy 335.149181 -432.583824) (xy 335.163391 -432.564271) (xy 335.182949 -432.550068) (xy 335.205938 -432.542605)
			(xy 335.218024 -432.542188) (xy 336.157824 -432.542188) (xy 336.169899 -432.542644) (xy 336.192867 -432.550113)
			(xy 336.212403 -432.564311) (xy 336.226597 -432.583851) (xy 336.234059 -432.606821) (xy 336.234532 -432.618896)
			(xy 336.234532 -435.16042) (xy 336.234053 -435.172493) (xy 336.226588 -435.195457) (xy 336.212394 -435.214991)
			(xy 336.19286 -435.229186) (xy 336.169897 -435.236652) (xy 336.157824 -435.237128) (xy 335.218024 -435.237128)
			(xy 335.205945 -435.236667) (xy 335.182966 -435.229209) (xy 335.163417 -435.215014) (xy 335.149212 -435.195473)
			(xy 335.14174 -435.172499) (xy 335.141316 -435.16042) (xy 335.141316 -434.553106) (xy 335.141062 -434.547264)
			(xy 335.139536 -434.532962) (xy 335.137883 -434.504243) (xy 335.13776 -434.48986) (xy 334.234536 -434.48986)
			(xy 334.234536 -435.489858) (xy 337.137756 -435.489858) (xy 337.137871 -435.475475) (xy 337.139523 -435.446756)
			(xy 337.141058 -435.432454) (xy 337.141312 -435.426612) (xy 337.141312 -434.353208) (xy 337.141058 -434.347366)
			(xy 337.139532 -434.333064) (xy 337.137879 -434.304345) (xy 337.137756 -434.289962) (xy 337.137872 -434.275579)
			(xy 337.139523 -434.24686) (xy 337.141058 -434.232558) (xy 337.141312 -434.226716) (xy 337.141312 -433.618894)
			(xy 337.141802 -433.606807) (xy 337.149257 -433.583811) (xy 337.163439 -433.564234) (xy 337.182965 -433.549982)
			(xy 337.205935 -433.542445) (xy 337.21802 -433.541932) (xy 338.15782 -433.541932) (xy 338.169933 -433.5423)
			(xy 338.192967 -433.549808) (xy 338.212542 -433.564081) (xy 338.226735 -433.583715) (xy 338.234149 -433.606779)
			(xy 338.234528 -433.618894) (xy 338.234528 -434.48986) (xy 339.137752 -434.48986) (xy 339.137868 -434.475477)
			(xy 339.139519 -434.446758) (xy 339.141054 -434.432456) (xy 339.141308 -434.426614) (xy 339.141308 -433.35321)
			(xy 339.141054 -433.347368) (xy 339.139528 -433.333066) (xy 339.137875 -433.304347) (xy 339.137752 -433.289964)
			(xy 339.137868 -433.275581) (xy 339.139519 -433.246862) (xy 339.141054 -433.23256) (xy 339.141308 -433.226718)
			(xy 339.141308 -432.618896) (xy 339.141709 -432.606811) (xy 339.14918 -432.583826) (xy 339.163388 -432.564274)
			(xy 339.182944 -432.550071) (xy 339.205931 -432.542606) (xy 339.218016 -432.542188) (xy 340.157816 -432.542188)
			(xy 340.169891 -432.542651) (xy 340.192858 -432.550117) (xy 340.212394 -432.564314) (xy 340.226588 -432.583853)
			(xy 340.234051 -432.606821) (xy 340.234524 -432.618896) (xy 340.234524 -435.16042) (xy 340.234053 -435.172494)
			(xy 340.226587 -435.195459) (xy 340.212391 -435.214994) (xy 340.192855 -435.229189) (xy 340.16989 -435.236654)
			(xy 340.157816 -435.237128) (xy 339.218016 -435.237128) (xy 339.205944 -435.236622) (xy 339.182981 -435.229167)
			(xy 339.163445 -435.21498) (xy 339.14925 -435.195451) (xy 339.141783 -435.172492) (xy 339.141308 -435.16042)
			(xy 339.141308 -434.553106) (xy 339.141054 -434.547264) (xy 339.139528 -434.532962) (xy 339.137875 -434.504243)
			(xy 339.137752 -434.48986) (xy 338.234528 -434.48986) (xy 338.234528 -435.489858) (xy 341.137748 -435.489858)
			(xy 341.137863 -435.475475) (xy 341.139515 -435.446756) (xy 341.14105 -435.432454) (xy 341.141304 -435.426612)
			(xy 341.141304 -434.353208) (xy 341.14105 -434.347366) (xy 341.139524 -434.333064) (xy 341.137871 -434.304345)
			(xy 341.137748 -434.289962) (xy 341.137864 -434.275579) (xy 341.139515 -434.24686) (xy 341.14105 -434.232558)
			(xy 341.141304 -434.226716) (xy 341.141304 -433.618894) (xy 341.141802 -433.606808) (xy 341.149256 -433.583813)
			(xy 341.163436 -433.564236) (xy 341.18296 -433.549985) (xy 341.205928 -433.542447) (xy 341.218012 -433.541932)
			(xy 342.157812 -433.541932) (xy 342.169925 -433.542306) (xy 342.192958 -433.549813) (xy 342.212534 -433.564084)
			(xy 342.226727 -433.583717) (xy 342.234141 -433.60678) (xy 342.23452 -433.618894) (xy 342.23452 -434.48986)
			(xy 343.137744 -434.48986) (xy 343.137859 -434.475477) (xy 343.13951 -434.446758) (xy 343.141046 -434.432456)
			(xy 343.1413 -434.426614) (xy 343.1413 -433.35321) (xy 343.141046 -433.347368) (xy 343.13952 -433.333066)
			(xy 343.137867 -433.304347) (xy 343.137744 -433.289964) (xy 343.137859 -433.275581) (xy 343.139511 -433.246862)
			(xy 343.141046 -433.23256) (xy 343.1413 -433.226718) (xy 343.1413 -432.618896) (xy 343.141709 -432.606812)
			(xy 343.149179 -432.583828) (xy 343.163386 -432.564277) (xy 343.182939 -432.550073) (xy 343.205924 -432.542607)
			(xy 343.218008 -432.542188) (xy 344.157808 -432.542188) (xy 344.169883 -432.542657) (xy 344.192849 -432.550122)
			(xy 344.212386 -432.564317) (xy 344.22658 -432.583854) (xy 344.234043 -432.606821) (xy 344.234516 -432.618896)
			(xy 344.234516 -435.16042) (xy 344.234053 -435.172495) (xy 344.226586 -435.195461) (xy 344.212389 -435.214997)
			(xy 344.19285 -435.229191) (xy 344.169883 -435.236655) (xy 344.157808 -435.237128) (xy 343.218008 -435.237128)
			(xy 343.205936 -435.236629) (xy 343.182972 -435.229171) (xy 343.163437 -435.214983) (xy 343.149241 -435.195453)
			(xy 343.141775 -435.172492) (xy 343.1413 -435.16042) (xy 343.1413 -434.553106) (xy 343.141046 -434.547264)
			(xy 343.13952 -434.532962) (xy 343.137867 -434.504243) (xy 343.137744 -434.48986) (xy 342.23452 -434.48986)
			(xy 342.23452 -435.489858) (xy 345.13774 -435.489858) (xy 345.137855 -435.475475) (xy 345.139506 -435.446756)
			(xy 345.141042 -435.432454) (xy 345.141296 -435.426612) (xy 345.141296 -434.353208) (xy 345.141042 -434.347366)
			(xy 345.139516 -434.333064) (xy 345.137863 -434.304345) (xy 345.13774 -434.289962) (xy 345.137855 -434.275579)
			(xy 345.139507 -434.24686) (xy 345.141042 -434.232558) (xy 345.141296 -434.226716) (xy 345.141296 -433.618894)
			(xy 345.141802 -433.606809) (xy 345.149255 -433.583815) (xy 345.163433 -433.564239) (xy 345.182955 -433.549987)
			(xy 345.20592 -433.542448) (xy 345.218004 -433.541932) (xy 346.157804 -433.541932) (xy 346.169916 -433.542313)
			(xy 346.192949 -433.549818) (xy 346.212525 -433.564087) (xy 346.226718 -433.583718) (xy 346.234133 -433.60678)
			(xy 346.234512 -433.618894) (xy 346.234512 -436.160418) (xy 346.234107 -436.172513) (xy 346.22664 -436.195523)
			(xy 346.212439 -436.215106) (xy 346.192889 -436.229355) (xy 346.169898 -436.236878) (xy 346.157804 -436.23738)
			(xy 345.218004 -436.23738) (xy 345.205893 -436.23698) (xy 345.182863 -436.229479) (xy 345.163288 -436.215214)
			(xy 345.149094 -436.195588) (xy 345.141676 -436.17253) (xy 345.141296 -436.160418) (xy 345.141296 -435.553104)
			(xy 345.141042 -435.547262) (xy 345.139515 -435.53296) (xy 345.137863 -435.504241) (xy 345.13774 -435.489858)
			(xy 342.23452 -435.489858) (xy 342.23452 -436.160418) (xy 342.234107 -436.172513) (xy 342.226641 -436.195521)
			(xy 342.212442 -436.215104) (xy 342.192894 -436.229352) (xy 342.169905 -436.236877) (xy 342.157812 -436.23738)
			(xy 341.218012 -436.23738) (xy 341.205902 -436.236973) (xy 341.182872 -436.229474) (xy 341.163297 -436.215211)
			(xy 341.149102 -436.195586) (xy 341.141685 -436.17253) (xy 341.141304 -436.160418) (xy 341.141304 -435.553104)
			(xy 341.14105 -435.547262) (xy 341.139523 -435.53296) (xy 341.137871 -435.504241) (xy 341.137748 -435.489858)
			(xy 338.234528 -435.489858) (xy 338.234528 -436.160418) (xy 338.234108 -436.172512) (xy 338.226642 -436.195518)
			(xy 338.212445 -436.215101) (xy 338.192899 -436.22935) (xy 338.169912 -436.236876) (xy 338.15782 -436.23738)
			(xy 337.21802 -436.23738) (xy 337.20591 -436.236966) (xy 337.18288 -436.22947) (xy 337.163305 -436.215208)
			(xy 337.149111 -436.195585) (xy 337.141693 -436.172529) (xy 337.141312 -436.160418) (xy 337.141312 -435.553104)
			(xy 337.141058 -435.547262) (xy 337.139531 -435.53296) (xy 337.137879 -435.504241) (xy 337.137756 -435.489858)
			(xy 334.234536 -435.489858) (xy 334.234536 -436.160418) (xy 334.234108 -436.172511) (xy 334.226643 -436.195516)
			(xy 334.212447 -436.215098) (xy 334.192904 -436.229347) (xy 334.16992 -436.236874) (xy 334.157828 -436.23738)
			(xy 333.218028 -436.23738) (xy 333.205919 -436.236959) (xy 333.182889 -436.229465) (xy 333.163314 -436.215206)
			(xy 333.149119 -436.195583) (xy 333.141701 -436.172529) (xy 333.14132 -436.160418) (xy 333.14132 -435.553104)
			(xy 333.141066 -435.547262) (xy 333.139539 -435.53296) (xy 333.137887 -435.504241) (xy 333.137764 -435.489858)
			(xy 329.2348 -435.489858) (xy 329.2348 -436.160418) (xy 329.234304 -436.17253) (xy 329.226817 -436.195567)
			(xy 329.21258 -436.215165) (xy 329.192985 -436.229408) (xy 329.16995 -436.236901) (xy 329.157838 -436.23738)
			(xy 328.218038 -436.23738) (xy 328.205919 -436.236908) (xy 328.182864 -436.229428) (xy 328.16325 -436.21519)
			(xy 328.148997 -436.195586) (xy 328.141501 -436.172537) (xy 328.141076 -436.160418) (xy 328.141076 -435.553104)
			(xy 328.140822 -435.547262) (xy 328.139295 -435.53296) (xy 328.137643 -435.504241) (xy 328.13752 -435.489858)
			(xy 325.234808 -435.489858) (xy 325.234808 -436.160418) (xy 325.234305 -436.172529) (xy 325.226818 -436.195565)
			(xy 325.212582 -436.215163) (xy 325.19299 -436.229405) (xy 325.169957 -436.2369) (xy 325.157846 -436.23738)
			(xy 324.218046 -436.23738) (xy 324.205927 -436.236901) (xy 324.182873 -436.229424) (xy 324.163259 -436.215187)
			(xy 324.149005 -436.195584) (xy 324.141509 -436.172536) (xy 324.141084 -436.160418) (xy 324.141084 -435.553104)
			(xy 324.14083 -435.547262) (xy 324.139303 -435.53296) (xy 324.137651 -435.504241) (xy 324.137528 -435.489858)
			(xy 321.234816 -435.489858) (xy 321.234816 -436.160418) (xy 321.234454 -436.172546) (xy 321.226952 -436.195613)
			(xy 321.212686 -436.215232) (xy 321.193056 -436.229481) (xy 321.169983 -436.236965) (xy 321.157854 -436.23738)
			(xy 320.218054 -436.23738) (xy 320.205939 -436.236928) (xy 320.182897 -436.22943) (xy 320.163298 -436.215182)
			(xy 320.149057 -436.195578) (xy 320.141568 -436.172533) (xy 320.141092 -436.160418) (xy 320.141092 -435.553104)
			(xy 320.140838 -435.547262) (xy 320.139311 -435.53296) (xy 320.137659 -435.504241) (xy 320.137536 -435.489858)
			(xy 317.234824 -435.489858) (xy 317.234824 -436.160418) (xy 317.234455 -436.172545) (xy 317.226953 -436.195611)
			(xy 317.212689 -436.215229) (xy 317.193061 -436.229478) (xy 317.16999 -436.236963) (xy 317.157862 -436.23738)
			(xy 316.218062 -436.23738) (xy 316.205947 -436.236921) (xy 316.182906 -436.229425) (xy 316.163306 -436.21518)
			(xy 316.149065 -436.195576) (xy 316.141576 -436.172533) (xy 316.1411 -436.160418) (xy 316.1411 -435.553104)
			(xy 316.140846 -435.547262) (xy 316.139319 -435.53296) (xy 316.137667 -435.504241) (xy 316.137544 -435.489858)
			(xy 273.934286 -435.489858) (xy 273.867468 -435.573645) (xy 273.750836 -435.707142) (xy 273.628331 -435.835271)
			(xy 273.500202 -435.957776) (xy 273.366705 -436.074408) (xy 273.22811 -436.184934) (xy 273.084696 -436.289131)
			(xy 272.936752 -436.386788) (xy 272.784575 -436.477709) (xy 272.628472 -436.561712) (xy 272.468758 -436.638626)
			(xy 272.305753 -436.708298) (xy 272.139788 -436.770586) (xy 271.971194 -436.825365) (xy 271.800313 -436.872525)
			(xy 271.627488 -436.911971) (xy 271.453067 -436.943624) (xy 271.277402 -436.967419) (xy 271.100846 -436.98331)
			(xy 270.923755 -436.991263) (xy 270.746485 -436.991263) (xy 270.569394 -436.98331) (xy 270.392838 -436.967419)
			(xy 270.217173 -436.943624) (xy 270.042752 -436.911971) (xy 269.869927 -436.872525) (xy 269.699046 -436.825365)
			(xy 269.530452 -436.770586) (xy 269.364487 -436.708298) (xy 269.201482 -436.638626) (xy 269.041768 -436.561712)
			(xy 268.885665 -436.477709) (xy 268.733488 -436.386788) (xy 268.585544 -436.289131) (xy 268.44213 -436.184934)
			(xy 268.303535 -436.074408) (xy 268.170038 -435.957776) (xy 268.041909 -435.835271) (xy 267.919404 -435.707142)
			(xy 267.802772 -435.573645) (xy 267.692246 -435.43505) (xy 267.588049 -435.291636) (xy 267.490392 -435.143692)
			(xy 267.399471 -434.991515) (xy 267.315468 -434.835412) (xy 267.238554 -434.675698) (xy 267.168882 -434.512693)
			(xy 267.106594 -434.346728) (xy 267.051815 -434.178134) (xy 267.004655 -434.007253) (xy 266.965209 -433.834428)
			(xy 266.933556 -433.660007) (xy 266.909761 -433.484342) (xy 266.89387 -433.307786) (xy 266.885917 -433.130695)
			(xy 230.3145 -433.130695) (xy 230.3145 -435.873652) (xy 230.314033 -435.898602) (xy 230.306213 -435.947887)
			(xy 230.29079 -435.995345) (xy 230.268141 -436.03981) (xy 230.238824 -436.080191) (xy 230.221536 -436.098188)
			(xy 229.299008 -437.020716) (xy 229.281016 -437.03801) (xy 229.240639 -437.067332) (xy 229.196172 -437.089979)
			(xy 229.148711 -437.105393) (xy 229.099423 -437.113193) (xy 229.074472 -437.11368) (xy 207.302608 -437.11368)
			(xy 207.27766 -437.113152) (xy 207.22838 -437.105344) (xy 207.180923 -437.089933) (xy 207.136457 -437.067299)
			(xy 207.096072 -437.037997) (xy 207.078072 -437.020716) (xy 205.512924 -435.455568) (xy 205.495618 -435.437587)
			(xy 205.466295 -435.397208) (xy 205.44365 -435.352738) (xy 205.42824 -435.305274) (xy 205.420444 -435.255984)
			(xy 205.41996 -435.231032) (xy 205.41996 -431.16881) (xy 205.41954 -431.15874) (xy 205.411817 -431.140141)
			(xy 205.404974 -431.132742) (xy 196.207888 -421.935656) (xy 196.19057 -421.917686) (xy 196.16125 -421.877303)
			(xy 196.138608 -421.832831) (xy 196.1232 -421.785364) (xy 196.115407 -421.736072) (xy 196.114924 -421.71112)
			(xy 196.114924 -413.329374) (xy 196.114532 -413.319301) (xy 196.10679 -413.300702) (xy 196.099938 -413.293306)
			(xy 195.154296 -412.347664) (xy 195.146896 -412.340825) (xy 195.128296 -412.333106) (xy 195.118228 -412.332678)
			(xy 188.720222 -412.332678) (xy 188.695275 -412.332142) (xy 188.645994 -412.324336) (xy 188.598538 -412.308927)
			(xy 188.554072 -412.286295) (xy 188.513686 -412.256994) (xy 188.495686 -412.239714) (xy 187.848748 -411.592776)
			(xy 187.841328 -411.585961) (xy 187.822744 -411.578227) (xy 187.81268 -411.57779) (xy 184.8104 -411.57779)
			(xy 184.785451 -411.577293) (xy 184.736167 -411.569481) (xy 184.68871 -411.554065) (xy 184.644244 -411.531423)
			(xy 184.603862 -411.502111) (xy 184.585864 -411.484826) (xy 184.033922 -410.932884) (xy 184.016624 -410.914896)
			(xy 183.9873 -410.874519) (xy 183.964653 -410.830051) (xy 183.949241 -410.782588) (xy 183.941443 -410.733299)
			(xy 183.940958 -410.708348) (xy 7.00913 -410.708348) (xy 7.00913 -413.4485) (xy 38.974268 -413.4485)
			(xy 38.974268 -412.5849) (xy 38.974754 -412.557631) (xy 38.982516 -412.503647) (xy 38.997881 -412.451317)
			(xy 39.020538 -412.401707) (xy 39.050024 -412.355826) (xy 39.085739 -412.314609) (xy 39.126956 -412.278894)
			(xy 39.172837 -412.249408) (xy 39.222447 -412.226751) (xy 39.274777 -412.211386) (xy 39.328761 -412.203624)
			(xy 39.383299 -412.203624) (xy 39.437283 -412.211386) (xy 39.489613 -412.226751) (xy 39.539223 -412.249408)
			(xy 39.585104 -412.278894) (xy 39.626321 -412.314609) (xy 39.662036 -412.355826) (xy 39.691522 -412.401707)
			(xy 39.714179 -412.451317) (xy 39.729544 -412.503647) (xy 39.737306 -412.557631) (xy 39.737792 -412.5849)
			(xy 39.737792 -412.597452) (xy 47.413146 -412.597452) (xy 47.413146 -412.542948) (xy 47.420902 -412.488999)
			(xy 47.436257 -412.436703) (xy 47.458897 -412.387124) (xy 47.488362 -412.341271) (xy 47.524053 -412.300079)
			(xy 47.565242 -412.264384) (xy 47.611092 -412.234914) (xy 47.660669 -412.212269) (xy 47.712964 -412.19691)
			(xy 47.766912 -412.189148) (xy 47.794164 -412.18866) (xy 48.657764 -412.18866) (xy 48.685016 -412.189185)
			(xy 48.738967 -412.196937) (xy 48.791264 -412.212289) (xy 48.840845 -412.234927) (xy 48.886699 -412.264392)
			(xy 48.927892 -412.300082) (xy 48.963587 -412.341273) (xy 48.993056 -412.387124) (xy 49.015699 -412.436702)
			(xy 49.031055 -412.488998) (xy 49.038813 -412.542948) (xy 49.038813 -412.597452) (xy 49.038813 -412.597455)
			(xy 50.476323 -412.597455) (xy 50.476323 -412.542945) (xy 50.484081 -412.488989) (xy 50.499438 -412.436686)
			(xy 50.522083 -412.387102) (xy 50.551554 -412.341244) (xy 50.587251 -412.300048) (xy 50.628448 -412.264351)
			(xy 50.674305 -412.234881) (xy 50.72389 -412.212237) (xy 50.776193 -412.19688) (xy 50.830149 -412.189123)
			(xy 50.857404 -412.18866) (xy 51.721004 -412.18866) (xy 51.748253 -412.18921) (xy 51.802195 -412.196967)
			(xy 51.854485 -412.212321) (xy 51.904058 -412.23496) (xy 51.949904 -412.264424) (xy 51.99109 -412.300113)
			(xy 52.026778 -412.341299) (xy 52.056242 -412.387146) (xy 52.07888 -412.436718) (xy 52.094234 -412.489008)
			(xy 52.10199 -412.542951) (xy 52.10199 -412.597449) (xy 52.101989 -412.597457) (xy 53.539523 -412.597457)
			(xy 53.539523 -412.542943) (xy 53.547282 -412.488983) (xy 53.562641 -412.436678) (xy 53.585289 -412.38709)
			(xy 53.614764 -412.341231) (xy 53.650465 -412.300034) (xy 53.691667 -412.264337) (xy 53.737529 -412.234868)
			(xy 53.787119 -412.212226) (xy 53.839427 -412.196872) (xy 53.893387 -412.18912) (xy 53.920644 -412.18866)
			(xy 54.784244 -412.18866) (xy 54.811491 -412.189213) (xy 54.865429 -412.196974) (xy 54.917714 -412.212332)
			(xy 54.967282 -412.234973) (xy 55.013123 -412.264438) (xy 55.054304 -412.300127) (xy 55.089988 -412.341313)
			(xy 55.119448 -412.387157) (xy 55.142084 -412.436727) (xy 55.157435 -412.489014) (xy 55.16519 -412.542953)
			(xy 55.16519 -412.597447) (xy 55.165189 -412.597453) (xy 56.602846 -412.597453) (xy 56.602846 -412.542947)
			(xy 56.610603 -412.488996) (xy 56.625958 -412.436698) (xy 56.6486 -412.387118) (xy 56.678067 -412.341265)
			(xy 56.71376 -412.300071) (xy 56.754952 -412.264377) (xy 56.800804 -412.234908) (xy 56.850383 -412.212264)
			(xy 56.902681 -412.196906) (xy 56.956631 -412.189147) (xy 56.983884 -412.18866) (xy 57.847484 -412.18866)
			(xy 57.874735 -412.189186) (xy 57.928683 -412.196941) (xy 57.980979 -412.212294) (xy 58.030557 -412.234934)
			(xy 58.076408 -412.264399) (xy 58.117599 -412.300089) (xy 58.153292 -412.341279) (xy 58.182759 -412.387129)
			(xy 58.2054 -412.436706) (xy 58.220756 -412.489001) (xy 58.228513 -412.542949) (xy 58.228513 -412.597451)
			(xy 58.228512 -412.597456) (xy 59.666023 -412.597456) (xy 59.666023 -412.542944) (xy 59.673781 -412.488986)
			(xy 59.68914 -412.436682) (xy 59.711786 -412.387096) (xy 59.741259 -412.341238) (xy 59.776958 -412.300041)
			(xy 59.818157 -412.264344) (xy 59.864017 -412.234874) (xy 59.913604 -412.212231) (xy 59.96591 -412.196876)
			(xy 60.019868 -412.189121) (xy 60.047124 -412.18866) (xy 60.910724 -412.18866) (xy 60.937972 -412.189212)
			(xy 60.991912 -412.19697) (xy 61.0442 -412.212326) (xy 61.09377 -412.234967) (xy 61.139613 -412.264431)
			(xy 61.180797 -412.30012) (xy 61.216483 -412.341306) (xy 61.245945 -412.387151) (xy 61.268582 -412.436723)
			(xy 61.283935 -412.489011) (xy 61.29169 -412.542952) (xy 61.29169 -412.597448) (xy 61.291689 -412.597452)
			(xy 62.729346 -412.597452) (xy 62.729346 -412.542948) (xy 62.737102 -412.488999) (xy 62.752457 -412.436703)
			(xy 62.775097 -412.387124) (xy 62.804562 -412.341271) (xy 62.840253 -412.300079) (xy 62.881442 -412.264384)
			(xy 62.927292 -412.234914) (xy 62.976869 -412.212269) (xy 63.029164 -412.19691) (xy 63.083112 -412.189148)
			(xy 63.110364 -412.18866) (xy 63.973964 -412.18866) (xy 64.001216 -412.189185) (xy 64.055167 -412.196937)
			(xy 64.107464 -412.212289) (xy 64.157045 -412.234927) (xy 64.202899 -412.264392) (xy 64.244092 -412.300082)
			(xy 64.279787 -412.341273) (xy 64.309256 -412.387124) (xy 64.331899 -412.436702) (xy 64.347255 -412.488998)
			(xy 64.355013 -412.542948) (xy 64.355013 -412.597452) (xy 64.355013 -412.597455) (xy 65.792523 -412.597455)
			(xy 65.792523 -412.542945) (xy 65.800281 -412.488989) (xy 65.815638 -412.436686) (xy 65.838283 -412.387102)
			(xy 65.867754 -412.341244) (xy 65.903451 -412.300048) (xy 65.944648 -412.264351) (xy 65.990505 -412.234881)
			(xy 66.04009 -412.212237) (xy 66.092393 -412.19688) (xy 66.146349 -412.189123) (xy 66.173604 -412.18866)
			(xy 67.037204 -412.18866) (xy 67.064453 -412.18921) (xy 67.118395 -412.196967) (xy 67.170685 -412.212321)
			(xy 67.220258 -412.23496) (xy 67.266104 -412.264424) (xy 67.30729 -412.300113) (xy 67.342978 -412.341299)
			(xy 67.372442 -412.387146) (xy 67.39508 -412.436718) (xy 67.410434 -412.489008) (xy 67.41819 -412.542951)
			(xy 67.41819 -412.597449) (xy 67.418189 -412.597457) (xy 68.855723 -412.597457) (xy 68.855723 -412.542943)
			(xy 68.863482 -412.488983) (xy 68.878841 -412.436678) (xy 68.901489 -412.38709) (xy 68.930964 -412.341231)
			(xy 68.966665 -412.300034) (xy 69.007867 -412.264337) (xy 69.053729 -412.234868) (xy 69.103319 -412.212226)
			(xy 69.155627 -412.196872) (xy 69.209587 -412.18912) (xy 69.236844 -412.18866) (xy 70.100444 -412.18866)
			(xy 70.127691 -412.189213) (xy 70.181629 -412.196974) (xy 70.233914 -412.212332) (xy 70.283482 -412.234973)
			(xy 70.329323 -412.264438) (xy 70.370504 -412.300127) (xy 70.406188 -412.341313) (xy 70.435648 -412.387157)
			(xy 70.458284 -412.436727) (xy 70.473635 -412.489014) (xy 70.48139 -412.542953) (xy 70.48139 -412.597447)
			(xy 70.481389 -412.597453) (xy 71.919046 -412.597453) (xy 71.919046 -412.542947) (xy 71.926803 -412.488996)
			(xy 71.942158 -412.436698) (xy 71.9648 -412.387118) (xy 71.994267 -412.341265) (xy 72.02996 -412.300071)
			(xy 72.071152 -412.264377) (xy 72.117004 -412.234908) (xy 72.166583 -412.212264) (xy 72.218881 -412.196906)
			(xy 72.272831 -412.189147) (xy 72.300084 -412.18866) (xy 73.163684 -412.18866) (xy 73.190935 -412.189186)
			(xy 73.244883 -412.196941) (xy 73.297179 -412.212294) (xy 73.346757 -412.234934) (xy 73.392608 -412.264399)
			(xy 73.433799 -412.300089) (xy 73.469492 -412.341279) (xy 73.498959 -412.387129) (xy 73.5216 -412.436706)
			(xy 73.536956 -412.489001) (xy 73.544713 -412.542949) (xy 73.544713 -412.597451) (xy 73.544712 -412.597456)
			(xy 74.982223 -412.597456) (xy 74.982223 -412.542944) (xy 74.989981 -412.488986) (xy 75.00534 -412.436682)
			(xy 75.027986 -412.387096) (xy 75.057459 -412.341238) (xy 75.093158 -412.300041) (xy 75.134357 -412.264344)
			(xy 75.180217 -412.234874) (xy 75.229804 -412.212231) (xy 75.28211 -412.196876) (xy 75.336068 -412.189121)
			(xy 75.363324 -412.18866) (xy 76.226924 -412.18866) (xy 76.254172 -412.189212) (xy 76.308112 -412.19697)
			(xy 76.3604 -412.212326) (xy 76.40997 -412.234967) (xy 76.455813 -412.264431) (xy 76.496997 -412.30012)
			(xy 76.532683 -412.341306) (xy 76.562145 -412.387151) (xy 76.584782 -412.436723) (xy 76.600135 -412.489011)
			(xy 76.60789 -412.542952) (xy 76.60789 -412.597448) (xy 76.607889 -412.597452) (xy 78.045546 -412.597452)
			(xy 78.045546 -412.542948) (xy 78.053302 -412.488999) (xy 78.068657 -412.436703) (xy 78.091297 -412.387124)
			(xy 78.120762 -412.341271) (xy 78.156453 -412.300079) (xy 78.197642 -412.264384) (xy 78.243492 -412.234914)
			(xy 78.293069 -412.212269) (xy 78.345364 -412.19691) (xy 78.399312 -412.189148) (xy 78.426564 -412.18866)
			(xy 79.290164 -412.18866) (xy 79.317416 -412.189185) (xy 79.371367 -412.196937) (xy 79.423664 -412.212289)
			(xy 79.473245 -412.234927) (xy 79.519099 -412.264392) (xy 79.560292 -412.300082) (xy 79.595987 -412.341273)
			(xy 79.625456 -412.387124) (xy 79.648099 -412.436702) (xy 79.663455 -412.488998) (xy 79.671213 -412.542948)
			(xy 79.671213 -412.597452) (xy 79.671213 -412.597455) (xy 81.108723 -412.597455) (xy 81.108723 -412.542945)
			(xy 81.116481 -412.488989) (xy 81.131838 -412.436686) (xy 81.154483 -412.387102) (xy 81.183954 -412.341244)
			(xy 81.219651 -412.300048) (xy 81.260848 -412.264351) (xy 81.306705 -412.234881) (xy 81.35629 -412.212237)
			(xy 81.408593 -412.19688) (xy 81.462549 -412.189123) (xy 81.489804 -412.18866) (xy 82.353404 -412.18866)
			(xy 82.380653 -412.18921) (xy 82.434595 -412.196967) (xy 82.486885 -412.212321) (xy 82.536458 -412.23496)
			(xy 82.582304 -412.264424) (xy 82.62349 -412.300113) (xy 82.659178 -412.341299) (xy 82.688642 -412.387146)
			(xy 82.71128 -412.436718) (xy 82.726634 -412.489008) (xy 82.73439 -412.542951) (xy 82.73439 -412.597449)
			(xy 82.734389 -412.597457) (xy 84.171923 -412.597457) (xy 84.171923 -412.542943) (xy 84.179682 -412.488983)
			(xy 84.195041 -412.436678) (xy 84.217689 -412.38709) (xy 84.247164 -412.341231) (xy 84.282865 -412.300034)
			(xy 84.324067 -412.264337) (xy 84.369929 -412.234868) (xy 84.419519 -412.212226) (xy 84.471827 -412.196872)
			(xy 84.525787 -412.18912) (xy 84.553044 -412.18866) (xy 85.416644 -412.18866) (xy 85.443891 -412.189213)
			(xy 85.497829 -412.196974) (xy 85.550114 -412.212332) (xy 85.599682 -412.234973) (xy 85.645523 -412.264438)
			(xy 85.686704 -412.300127) (xy 85.722388 -412.341313) (xy 85.751848 -412.387157) (xy 85.774484 -412.436727)
			(xy 85.789835 -412.489014) (xy 85.79759 -412.542953) (xy 85.79759 -412.597447) (xy 85.797589 -412.597453)
			(xy 87.235246 -412.597453) (xy 87.235246 -412.542947) (xy 87.243003 -412.488996) (xy 87.258358 -412.436698)
			(xy 87.281 -412.387118) (xy 87.310467 -412.341265) (xy 87.34616 -412.300071) (xy 87.387352 -412.264377)
			(xy 87.433204 -412.234908) (xy 87.482783 -412.212264) (xy 87.535081 -412.196906) (xy 87.589031 -412.189147)
			(xy 87.616284 -412.18866) (xy 88.479884 -412.18866) (xy 88.507135 -412.189186) (xy 88.561083 -412.196941)
			(xy 88.613379 -412.212294) (xy 88.662957 -412.234934) (xy 88.708808 -412.264399) (xy 88.749999 -412.300089)
			(xy 88.785692 -412.341279) (xy 88.815159 -412.387129) (xy 88.8378 -412.436706) (xy 88.853156 -412.489001)
			(xy 88.860913 -412.542949) (xy 88.860913 -412.597451) (xy 88.860912 -412.597456) (xy 90.298423 -412.597456)
			(xy 90.298423 -412.542944) (xy 90.306181 -412.488986) (xy 90.32154 -412.436682) (xy 90.344186 -412.387096)
			(xy 90.373659 -412.341238) (xy 90.409358 -412.300041) (xy 90.450557 -412.264344) (xy 90.496417 -412.234874)
			(xy 90.546004 -412.212231) (xy 90.59831 -412.196876) (xy 90.652268 -412.189121) (xy 90.679524 -412.18866)
			(xy 91.543124 -412.18866) (xy 91.570372 -412.189212) (xy 91.624312 -412.19697) (xy 91.6766 -412.212326)
			(xy 91.72617 -412.234967) (xy 91.772013 -412.264431) (xy 91.813197 -412.30012) (xy 91.848883 -412.341306)
			(xy 91.878345 -412.387151) (xy 91.900982 -412.436723) (xy 91.916335 -412.489011) (xy 91.92409 -412.542952)
			(xy 91.92409 -412.597448) (xy 91.924089 -412.597452) (xy 93.361746 -412.597452) (xy 93.361746 -412.542948)
			(xy 93.369502 -412.488999) (xy 93.384857 -412.436703) (xy 93.407497 -412.387124) (xy 93.436962 -412.341271)
			(xy 93.472653 -412.300079) (xy 93.513842 -412.264384) (xy 93.559692 -412.234914) (xy 93.609269 -412.212269)
			(xy 93.661564 -412.19691) (xy 93.715512 -412.189148) (xy 93.742764 -412.18866) (xy 94.606364 -412.18866)
			(xy 94.633616 -412.189185) (xy 94.687567 -412.196937) (xy 94.739864 -412.212289) (xy 94.789445 -412.234927)
			(xy 94.835299 -412.264392) (xy 94.876492 -412.300082) (xy 94.912187 -412.341273) (xy 94.941656 -412.387124)
			(xy 94.964299 -412.436702) (xy 94.979655 -412.488998) (xy 94.987413 -412.542948) (xy 94.987413 -412.597452)
			(xy 94.987413 -412.597455) (xy 114.513023 -412.597455) (xy 114.513023 -412.542945) (xy 114.520781 -412.488989)
			(xy 114.536138 -412.436686) (xy 114.558783 -412.387101) (xy 114.588254 -412.341244) (xy 114.623952 -412.300047)
			(xy 114.665149 -412.264351) (xy 114.711006 -412.23488) (xy 114.760591 -412.212236) (xy 114.812894 -412.196879)
			(xy 114.866851 -412.189123) (xy 114.894106 -412.18866) (xy 115.757706 -412.18866) (xy 115.784955 -412.189211)
			(xy 115.838897 -412.196967) (xy 115.891187 -412.212321) (xy 115.940759 -412.234961) (xy 115.986605 -412.264425)
			(xy 116.027791 -412.300113) (xy 116.063479 -412.3413) (xy 116.092942 -412.387146) (xy 116.115581 -412.436719)
			(xy 116.130934 -412.489009) (xy 116.13869 -412.542951) (xy 116.13869 -412.597449) (xy 116.138689 -412.597457)
			(xy 117.576223 -412.597457) (xy 117.576223 -412.542943) (xy 117.583982 -412.488983) (xy 117.599342 -412.436677)
			(xy 117.621989 -412.38709) (xy 117.651464 -412.341231) (xy 117.687166 -412.300033) (xy 117.728367 -412.264337)
			(xy 117.77423 -412.234867) (xy 117.82382 -412.212225) (xy 117.876128 -412.196872) (xy 117.930089 -412.18912)
			(xy 117.957346 -412.18866) (xy 118.820946 -412.18866) (xy 118.848193 -412.189213) (xy 118.902131 -412.196975)
			(xy 118.954416 -412.212332) (xy 119.003983 -412.234974) (xy 119.049824 -412.264439) (xy 119.091005 -412.300128)
			(xy 119.126688 -412.341313) (xy 119.156148 -412.387157) (xy 119.178784 -412.436727) (xy 119.194135 -412.489014)
			(xy 119.20189 -412.542953) (xy 119.20189 -412.597447) (xy 119.201889 -412.597453) (xy 120.639546 -412.597453)
			(xy 120.639546 -412.542947) (xy 120.647303 -412.488996) (xy 120.662658 -412.436698) (xy 120.6853 -412.387118)
			(xy 120.714768 -412.341264) (xy 120.750461 -412.300071) (xy 120.791653 -412.264376) (xy 120.837505 -412.234907)
			(xy 120.887085 -412.212263) (xy 120.939382 -412.196906) (xy 120.993333 -412.189147) (xy 121.020586 -412.18866)
			(xy 121.884186 -412.18866) (xy 121.911437 -412.189186) (xy 121.965385 -412.196941) (xy 122.01768 -412.212295)
			(xy 122.067258 -412.234934) (xy 122.113109 -412.264399) (xy 122.1543 -412.30009) (xy 122.189992 -412.34128)
			(xy 122.219459 -412.38713) (xy 122.242101 -412.436707) (xy 122.257456 -412.489001) (xy 122.265213 -412.542949)
			(xy 122.265213 -412.597451) (xy 122.265212 -412.597456) (xy 123.702723 -412.597456) (xy 123.702723 -412.542944)
			(xy 123.710481 -412.488986) (xy 123.72584 -412.436681) (xy 123.748486 -412.387095) (xy 123.777959 -412.341237)
			(xy 123.813659 -412.30004) (xy 123.854858 -412.264344) (xy 123.900718 -412.234874) (xy 123.950306 -412.212231)
			(xy 124.002611 -412.196876) (xy 124.05657 -412.189121) (xy 124.083826 -412.18866) (xy 124.947426 -412.18866)
			(xy 124.974674 -412.189212) (xy 125.028614 -412.196971) (xy 125.080901 -412.212327) (xy 125.130471 -412.234968)
			(xy 125.176314 -412.264432) (xy 125.217498 -412.300121) (xy 125.253184 -412.341307) (xy 125.282645 -412.387152)
			(xy 125.305282 -412.436723) (xy 125.320635 -412.489011) (xy 125.32839 -412.542952) (xy 125.32839 -412.597448)
			(xy 125.328389 -412.597452) (xy 126.766046 -412.597452) (xy 126.766046 -412.542948) (xy 126.773802 -412.488999)
			(xy 126.789157 -412.436702) (xy 126.811797 -412.387123) (xy 126.841263 -412.341271) (xy 126.876954 -412.300078)
			(xy 126.918143 -412.264383) (xy 126.963993 -412.234914) (xy 127.01357 -412.212269) (xy 127.065865 -412.196909)
			(xy 127.119814 -412.189148) (xy 127.147066 -412.18866) (xy 128.010666 -412.18866) (xy 128.037918 -412.189185)
			(xy 128.091868 -412.196937) (xy 128.144166 -412.212289) (xy 128.193746 -412.234928) (xy 128.2396 -412.264392)
			(xy 128.280793 -412.300083) (xy 128.316487 -412.341273) (xy 128.345956 -412.387124) (xy 128.368599 -412.436702)
			(xy 128.383955 -412.488999) (xy 128.391713 -412.542948) (xy 128.391713 -412.597452) (xy 128.391713 -412.597455)
			(xy 129.829223 -412.597455) (xy 129.829223 -412.542945) (xy 129.836981 -412.488989) (xy 129.852338 -412.436686)
			(xy 129.874983 -412.387101) (xy 129.904454 -412.341244) (xy 129.940152 -412.300047) (xy 129.981349 -412.264351)
			(xy 130.027206 -412.23488) (xy 130.076791 -412.212236) (xy 130.129094 -412.196879) (xy 130.183051 -412.189123)
			(xy 130.210306 -412.18866) (xy 131.073906 -412.18866) (xy 131.101155 -412.189211) (xy 131.155097 -412.196967)
			(xy 131.207387 -412.212321) (xy 131.256959 -412.234961) (xy 131.302805 -412.264425) (xy 131.343991 -412.300113)
			(xy 131.379679 -412.3413) (xy 131.409142 -412.387146) (xy 131.431781 -412.436719) (xy 131.447134 -412.489009)
			(xy 131.45489 -412.542951) (xy 131.45489 -412.597449) (xy 131.454889 -412.597457) (xy 132.892423 -412.597457)
			(xy 132.892423 -412.542943) (xy 132.900182 -412.488983) (xy 132.915542 -412.436677) (xy 132.938189 -412.38709)
			(xy 132.967664 -412.341231) (xy 133.003366 -412.300033) (xy 133.044567 -412.264337) (xy 133.09043 -412.234867)
			(xy 133.14002 -412.212225) (xy 133.192328 -412.196872) (xy 133.246289 -412.18912) (xy 133.273546 -412.18866)
			(xy 134.137146 -412.18866) (xy 134.164393 -412.189213) (xy 134.218331 -412.196975) (xy 134.270616 -412.212332)
			(xy 134.320183 -412.234974) (xy 134.366024 -412.264439) (xy 134.407205 -412.300128) (xy 134.442888 -412.341313)
			(xy 134.472348 -412.387157) (xy 134.494984 -412.436727) (xy 134.510335 -412.489014) (xy 134.51809 -412.542953)
			(xy 134.51809 -412.597447) (xy 134.518089 -412.597453) (xy 135.955746 -412.597453) (xy 135.955746 -412.542947)
			(xy 135.963503 -412.488996) (xy 135.978858 -412.436698) (xy 136.0015 -412.387118) (xy 136.030968 -412.341264)
			(xy 136.066661 -412.300071) (xy 136.107853 -412.264376) (xy 136.153705 -412.234907) (xy 136.203285 -412.212263)
			(xy 136.255582 -412.196906) (xy 136.309533 -412.189147) (xy 136.336786 -412.18866) (xy 137.200386 -412.18866)
			(xy 137.227637 -412.189186) (xy 137.281585 -412.196941) (xy 137.33388 -412.212295) (xy 137.383458 -412.234934)
			(xy 137.429309 -412.264399) (xy 137.4705 -412.30009) (xy 137.506192 -412.34128) (xy 137.535659 -412.38713)
			(xy 137.558301 -412.436707) (xy 137.573656 -412.489001) (xy 137.581413 -412.542949) (xy 137.581413 -412.597451)
			(xy 137.581412 -412.597456) (xy 139.018923 -412.597456) (xy 139.018923 -412.542944) (xy 139.026681 -412.488986)
			(xy 139.04204 -412.436681) (xy 139.064686 -412.387095) (xy 139.094159 -412.341237) (xy 139.129859 -412.30004)
			(xy 139.171058 -412.264344) (xy 139.216918 -412.234874) (xy 139.266506 -412.212231) (xy 139.318811 -412.196876)
			(xy 139.37277 -412.189121) (xy 139.400026 -412.18866) (xy 140.263626 -412.18866) (xy 140.290874 -412.189212)
			(xy 140.344814 -412.196971) (xy 140.397101 -412.212327) (xy 140.446671 -412.234968) (xy 140.492514 -412.264432)
			(xy 140.533698 -412.300121) (xy 140.569384 -412.341307) (xy 140.598845 -412.387152) (xy 140.621482 -412.436723)
			(xy 140.636835 -412.489011) (xy 140.64459 -412.542952) (xy 140.64459 -412.597448) (xy 140.644589 -412.597452)
			(xy 142.082246 -412.597452) (xy 142.082246 -412.542948) (xy 142.090002 -412.488999) (xy 142.105357 -412.436702)
			(xy 142.127997 -412.387123) (xy 142.157463 -412.341271) (xy 142.193154 -412.300078) (xy 142.234343 -412.264383)
			(xy 142.280193 -412.234914) (xy 142.32977 -412.212269) (xy 142.382065 -412.196909) (xy 142.436014 -412.189148)
			(xy 142.463266 -412.18866) (xy 143.326866 -412.18866) (xy 143.354118 -412.189185) (xy 143.408068 -412.196937)
			(xy 143.460366 -412.212289) (xy 143.509946 -412.234928) (xy 143.5558 -412.264392) (xy 143.596993 -412.300083)
			(xy 143.632687 -412.341273) (xy 143.662156 -412.387124) (xy 143.684799 -412.436702) (xy 143.700155 -412.488999)
			(xy 143.707913 -412.542948) (xy 143.707913 -412.597452) (xy 143.707913 -412.597455) (xy 145.145423 -412.597455)
			(xy 145.145423 -412.542945) (xy 145.153181 -412.488989) (xy 145.168538 -412.436686) (xy 145.191183 -412.387101)
			(xy 145.220654 -412.341244) (xy 145.256352 -412.300047) (xy 145.297549 -412.264351) (xy 145.343406 -412.23488)
			(xy 145.392991 -412.212236) (xy 145.445294 -412.196879) (xy 145.499251 -412.189123) (xy 145.526506 -412.18866)
			(xy 146.390106 -412.18866) (xy 146.417355 -412.189211) (xy 146.471297 -412.196967) (xy 146.523587 -412.212321)
			(xy 146.573159 -412.234961) (xy 146.619005 -412.264425) (xy 146.660191 -412.300113) (xy 146.695879 -412.3413)
			(xy 146.725342 -412.387146) (xy 146.747981 -412.436719) (xy 146.763334 -412.489009) (xy 146.77109 -412.542951)
			(xy 146.77109 -412.597449) (xy 146.771089 -412.597457) (xy 148.208623 -412.597457) (xy 148.208623 -412.542943)
			(xy 148.216382 -412.488983) (xy 148.231742 -412.436677) (xy 148.254389 -412.38709) (xy 148.283864 -412.341231)
			(xy 148.319566 -412.300033) (xy 148.360767 -412.264337) (xy 148.40663 -412.234867) (xy 148.45622 -412.212225)
			(xy 148.508528 -412.196872) (xy 148.562489 -412.18912) (xy 148.589746 -412.18866) (xy 149.453346 -412.18866)
			(xy 149.480593 -412.189213) (xy 149.534531 -412.196975) (xy 149.586816 -412.212332) (xy 149.636383 -412.234974)
			(xy 149.682224 -412.264439) (xy 149.723405 -412.300128) (xy 149.759088 -412.341313) (xy 149.788548 -412.387157)
			(xy 149.811184 -412.436727) (xy 149.826535 -412.489014) (xy 149.83429 -412.542953) (xy 149.83429 -412.597447)
			(xy 149.834289 -412.597453) (xy 151.271946 -412.597453) (xy 151.271946 -412.542947) (xy 151.279703 -412.488996)
			(xy 151.295058 -412.436698) (xy 151.3177 -412.387118) (xy 151.347168 -412.341264) (xy 151.382861 -412.300071)
			(xy 151.424053 -412.264376) (xy 151.469905 -412.234907) (xy 151.519485 -412.212263) (xy 151.571782 -412.196906)
			(xy 151.625733 -412.189147) (xy 151.652986 -412.18866) (xy 152.516586 -412.18866) (xy 152.543837 -412.189186)
			(xy 152.597785 -412.196941) (xy 152.65008 -412.212295) (xy 152.699658 -412.234934) (xy 152.745509 -412.264399)
			(xy 152.7867 -412.30009) (xy 152.822392 -412.34128) (xy 152.851859 -412.38713) (xy 152.874501 -412.436707)
			(xy 152.889856 -412.489001) (xy 152.897613 -412.542949) (xy 152.897613 -412.597451) (xy 152.897612 -412.597456)
			(xy 154.335123 -412.597456) (xy 154.335123 -412.542944) (xy 154.342881 -412.488986) (xy 154.35824 -412.436681)
			(xy 154.380886 -412.387095) (xy 154.410359 -412.341237) (xy 154.446059 -412.30004) (xy 154.487258 -412.264344)
			(xy 154.533118 -412.234874) (xy 154.582706 -412.212231) (xy 154.635011 -412.196876) (xy 154.68897 -412.189121)
			(xy 154.716226 -412.18866) (xy 155.579826 -412.18866) (xy 155.607074 -412.189212) (xy 155.661014 -412.196971)
			(xy 155.713301 -412.212327) (xy 155.762871 -412.234968) (xy 155.808714 -412.264432) (xy 155.849898 -412.300121)
			(xy 155.885584 -412.341307) (xy 155.915045 -412.387152) (xy 155.937682 -412.436723) (xy 155.953035 -412.489011)
			(xy 155.96079 -412.542952) (xy 155.96079 -412.597448) (xy 155.960789 -412.597452) (xy 157.398446 -412.597452)
			(xy 157.398446 -412.542948) (xy 157.406202 -412.488999) (xy 157.421557 -412.436702) (xy 157.444197 -412.387123)
			(xy 157.473663 -412.341271) (xy 157.509354 -412.300078) (xy 157.550543 -412.264383) (xy 157.596393 -412.234914)
			(xy 157.64597 -412.212269) (xy 157.698265 -412.196909) (xy 157.752214 -412.189148) (xy 157.779466 -412.18866)
			(xy 158.643066 -412.18866) (xy 158.670318 -412.189185) (xy 158.724268 -412.196937) (xy 158.776566 -412.212289)
			(xy 158.826146 -412.234928) (xy 158.872 -412.264392) (xy 158.913193 -412.300083) (xy 158.948887 -412.341273)
			(xy 158.978356 -412.387124) (xy 159.000999 -412.436702) (xy 159.016355 -412.488999) (xy 159.024113 -412.542948)
			(xy 159.024113 -412.597452) (xy 159.024113 -412.597455) (xy 160.461623 -412.597455) (xy 160.461623 -412.542945)
			(xy 160.469381 -412.488989) (xy 160.484738 -412.436686) (xy 160.507383 -412.387101) (xy 160.536854 -412.341244)
			(xy 160.572552 -412.300047) (xy 160.613749 -412.264351) (xy 160.659606 -412.23488) (xy 160.709191 -412.212236)
			(xy 160.761494 -412.196879) (xy 160.815451 -412.189123) (xy 160.842706 -412.18866) (xy 161.706306 -412.18866)
			(xy 161.733555 -412.189211) (xy 161.787497 -412.196967) (xy 161.839787 -412.212321) (xy 161.889359 -412.234961)
			(xy 161.935205 -412.264425) (xy 161.976391 -412.300113) (xy 162.012079 -412.3413) (xy 162.041542 -412.387146)
			(xy 162.064181 -412.436719) (xy 162.079534 -412.489009) (xy 162.08729 -412.542951) (xy 162.08729 -412.597449)
			(xy 162.079534 -412.651391) (xy 162.064181 -412.703681) (xy 162.041542 -412.753254) (xy 162.012079 -412.7991)
			(xy 161.976391 -412.840287) (xy 161.935205 -412.875975) (xy 161.889359 -412.905439) (xy 161.839787 -412.928079)
			(xy 161.787497 -412.943433) (xy 161.733555 -412.951189) (xy 161.706306 -412.951676) (xy 160.842706 -412.951676)
			(xy 160.815451 -412.951277) (xy 160.761494 -412.943521) (xy 160.709191 -412.928164) (xy 160.659606 -412.90552)
			(xy 160.613749 -412.876049) (xy 160.572552 -412.840353) (xy 160.536854 -412.799156) (xy 160.507383 -412.753299)
			(xy 160.484738 -412.703714) (xy 160.469381 -412.651411) (xy 160.461623 -412.597455) (xy 159.024113 -412.597455)
			(xy 159.016355 -412.651402) (xy 159.000999 -412.703698) (xy 158.978356 -412.753276) (xy 158.948887 -412.799127)
			(xy 158.913193 -412.840317) (xy 158.872 -412.876008) (xy 158.826146 -412.905472) (xy 158.776566 -412.928111)
			(xy 158.724268 -412.943463) (xy 158.670318 -412.951215) (xy 158.643066 -412.951676) (xy 157.779466 -412.951676)
			(xy 157.752214 -412.951252) (xy 157.698265 -412.943491) (xy 157.64597 -412.928131) (xy 157.596393 -412.905486)
			(xy 157.550543 -412.876017) (xy 157.509354 -412.840322) (xy 157.473663 -412.799129) (xy 157.444197 -412.753277)
			(xy 157.421557 -412.703698) (xy 157.406202 -412.651401) (xy 157.398446 -412.597452) (xy 155.960789 -412.597452)
			(xy 155.953035 -412.651389) (xy 155.937682 -412.703677) (xy 155.915045 -412.753248) (xy 155.885584 -412.799093)
			(xy 155.849898 -412.840279) (xy 155.808714 -412.875968) (xy 155.762871 -412.905432) (xy 155.713301 -412.928073)
			(xy 155.661014 -412.943429) (xy 155.607074 -412.951188) (xy 155.579826 -412.951676) (xy 154.716226 -412.951676)
			(xy 154.68897 -412.951279) (xy 154.635011 -412.943524) (xy 154.582706 -412.928169) (xy 154.533118 -412.905526)
			(xy 154.487258 -412.876056) (xy 154.446059 -412.84036) (xy 154.410359 -412.799163) (xy 154.380886 -412.753305)
			(xy 154.35824 -412.703719) (xy 154.342881 -412.651414) (xy 154.335123 -412.597456) (xy 152.897612 -412.597456)
			(xy 152.889856 -412.651399) (xy 152.874501 -412.703693) (xy 152.851859 -412.75327) (xy 152.822392 -412.79912)
			(xy 152.7867 -412.84031) (xy 152.745509 -412.876001) (xy 152.699658 -412.905466) (xy 152.65008 -412.928105)
			(xy 152.597785 -412.943459) (xy 152.543837 -412.951214) (xy 152.516586 -412.951676) (xy 151.652986 -412.951676)
			(xy 151.625733 -412.951253) (xy 151.571782 -412.943494) (xy 151.519485 -412.928137) (xy 151.469905 -412.905493)
			(xy 151.424053 -412.876024) (xy 151.382861 -412.840329) (xy 151.347168 -412.799136) (xy 151.3177 -412.753282)
			(xy 151.295058 -412.703702) (xy 151.279703 -412.651404) (xy 151.271946 -412.597453) (xy 149.834289 -412.597453)
			(xy 149.826535 -412.651386) (xy 149.811184 -412.703673) (xy 149.788548 -412.753243) (xy 149.759088 -412.799087)
			(xy 149.723405 -412.840272) (xy 149.682224 -412.875961) (xy 149.636383 -412.905426) (xy 149.586816 -412.928068)
			(xy 149.534531 -412.943425) (xy 149.480593 -412.951187) (xy 149.453346 -412.951676) (xy 148.589746 -412.951676)
			(xy 148.562489 -412.95128) (xy 148.508528 -412.943528) (xy 148.45622 -412.928175) (xy 148.40663 -412.905533)
			(xy 148.360767 -412.876063) (xy 148.319566 -412.840367) (xy 148.283864 -412.799169) (xy 148.254389 -412.75331)
			(xy 148.231742 -412.703723) (xy 148.216382 -412.651417) (xy 148.208623 -412.597457) (xy 146.771089 -412.597457)
			(xy 146.763334 -412.651391) (xy 146.747981 -412.703681) (xy 146.725342 -412.753254) (xy 146.695879 -412.7991)
			(xy 146.660191 -412.840287) (xy 146.619005 -412.875975) (xy 146.573159 -412.905439) (xy 146.523587 -412.928079)
			(xy 146.471297 -412.943433) (xy 146.417355 -412.951189) (xy 146.390106 -412.951676) (xy 145.526506 -412.951676)
			(xy 145.499251 -412.951277) (xy 145.445294 -412.943521) (xy 145.392991 -412.928164) (xy 145.343406 -412.90552)
			(xy 145.297549 -412.876049) (xy 145.256352 -412.840353) (xy 145.220654 -412.799156) (xy 145.191183 -412.753299)
			(xy 145.168538 -412.703714) (xy 145.153181 -412.651411) (xy 145.145423 -412.597455) (xy 143.707913 -412.597455)
			(xy 143.700155 -412.651402) (xy 143.684799 -412.703698) (xy 143.662156 -412.753276) (xy 143.632687 -412.799127)
			(xy 143.596993 -412.840317) (xy 143.5558 -412.876008) (xy 143.509946 -412.905472) (xy 143.460366 -412.928111)
			(xy 143.408068 -412.943463) (xy 143.354118 -412.951215) (xy 143.326866 -412.951676) (xy 142.463266 -412.951676)
			(xy 142.436014 -412.951252) (xy 142.382065 -412.943491) (xy 142.32977 -412.928131) (xy 142.280193 -412.905486)
			(xy 142.234343 -412.876017) (xy 142.193154 -412.840322) (xy 142.157463 -412.799129) (xy 142.127997 -412.753277)
			(xy 142.105357 -412.703698) (xy 142.090002 -412.651401) (xy 142.082246 -412.597452) (xy 140.644589 -412.597452)
			(xy 140.636835 -412.651389) (xy 140.621482 -412.703677) (xy 140.598845 -412.753248) (xy 140.569384 -412.799093)
			(xy 140.533698 -412.840279) (xy 140.492514 -412.875968) (xy 140.446671 -412.905432) (xy 140.397101 -412.928073)
			(xy 140.344814 -412.943429) (xy 140.290874 -412.951188) (xy 140.263626 -412.951676) (xy 139.400026 -412.951676)
			(xy 139.37277 -412.951279) (xy 139.318811 -412.943524) (xy 139.266506 -412.928169) (xy 139.216918 -412.905526)
			(xy 139.171058 -412.876056) (xy 139.129859 -412.84036) (xy 139.094159 -412.799163) (xy 139.064686 -412.753305)
			(xy 139.04204 -412.703719) (xy 139.026681 -412.651414) (xy 139.018923 -412.597456) (xy 137.581412 -412.597456)
			(xy 137.573656 -412.651399) (xy 137.558301 -412.703693) (xy 137.535659 -412.75327) (xy 137.506192 -412.79912)
			(xy 137.4705 -412.84031) (xy 137.429309 -412.876001) (xy 137.383458 -412.905466) (xy 137.33388 -412.928105)
			(xy 137.281585 -412.943459) (xy 137.227637 -412.951214) (xy 137.200386 -412.951676) (xy 136.336786 -412.951676)
			(xy 136.309533 -412.951253) (xy 136.255582 -412.943494) (xy 136.203285 -412.928137) (xy 136.153705 -412.905493)
			(xy 136.107853 -412.876024) (xy 136.066661 -412.840329) (xy 136.030968 -412.799136) (xy 136.0015 -412.753282)
			(xy 135.978858 -412.703702) (xy 135.963503 -412.651404) (xy 135.955746 -412.597453) (xy 134.518089 -412.597453)
			(xy 134.510335 -412.651386) (xy 134.494984 -412.703673) (xy 134.472348 -412.753243) (xy 134.442888 -412.799087)
			(xy 134.407205 -412.840272) (xy 134.366024 -412.875961) (xy 134.320183 -412.905426) (xy 134.270616 -412.928068)
			(xy 134.218331 -412.943425) (xy 134.164393 -412.951187) (xy 134.137146 -412.951676) (xy 133.273546 -412.951676)
			(xy 133.246289 -412.95128) (xy 133.192328 -412.943528) (xy 133.14002 -412.928175) (xy 133.09043 -412.905533)
			(xy 133.044567 -412.876063) (xy 133.003366 -412.840367) (xy 132.967664 -412.799169) (xy 132.938189 -412.75331)
			(xy 132.915542 -412.703723) (xy 132.900182 -412.651417) (xy 132.892423 -412.597457) (xy 131.454889 -412.597457)
			(xy 131.447134 -412.651391) (xy 131.431781 -412.703681) (xy 131.409142 -412.753254) (xy 131.379679 -412.7991)
			(xy 131.343991 -412.840287) (xy 131.302805 -412.875975) (xy 131.256959 -412.905439) (xy 131.207387 -412.928079)
			(xy 131.155097 -412.943433) (xy 131.101155 -412.951189) (xy 131.073906 -412.951676) (xy 130.210306 -412.951676)
			(xy 130.183051 -412.951277) (xy 130.129094 -412.943521) (xy 130.076791 -412.928164) (xy 130.027206 -412.90552)
			(xy 129.981349 -412.876049) (xy 129.940152 -412.840353) (xy 129.904454 -412.799156) (xy 129.874983 -412.753299)
			(xy 129.852338 -412.703714) (xy 129.836981 -412.651411) (xy 129.829223 -412.597455) (xy 128.391713 -412.597455)
			(xy 128.383955 -412.651402) (xy 128.368599 -412.703698) (xy 128.345956 -412.753276) (xy 128.316487 -412.799127)
			(xy 128.280793 -412.840317) (xy 128.2396 -412.876008) (xy 128.193746 -412.905472) (xy 128.144166 -412.928111)
			(xy 128.091868 -412.943463) (xy 128.037918 -412.951215) (xy 128.010666 -412.951676) (xy 127.147066 -412.951676)
			(xy 127.119814 -412.951252) (xy 127.065865 -412.943491) (xy 127.01357 -412.928131) (xy 126.963993 -412.905486)
			(xy 126.918143 -412.876017) (xy 126.876954 -412.840322) (xy 126.841263 -412.799129) (xy 126.811797 -412.753277)
			(xy 126.789157 -412.703698) (xy 126.773802 -412.651401) (xy 126.766046 -412.597452) (xy 125.328389 -412.597452)
			(xy 125.320635 -412.651389) (xy 125.305282 -412.703677) (xy 125.282645 -412.753248) (xy 125.253184 -412.799093)
			(xy 125.217498 -412.840279) (xy 125.176314 -412.875968) (xy 125.130471 -412.905432) (xy 125.080901 -412.928073)
			(xy 125.028614 -412.943429) (xy 124.974674 -412.951188) (xy 124.947426 -412.951676) (xy 124.083826 -412.951676)
			(xy 124.05657 -412.951279) (xy 124.002611 -412.943524) (xy 123.950306 -412.928169) (xy 123.900718 -412.905526)
			(xy 123.854858 -412.876056) (xy 123.813659 -412.84036) (xy 123.777959 -412.799163) (xy 123.748486 -412.753305)
			(xy 123.72584 -412.703719) (xy 123.710481 -412.651414) (xy 123.702723 -412.597456) (xy 122.265212 -412.597456)
			(xy 122.257456 -412.651399) (xy 122.242101 -412.703693) (xy 122.219459 -412.75327) (xy 122.189992 -412.79912)
			(xy 122.1543 -412.84031) (xy 122.113109 -412.876001) (xy 122.067258 -412.905466) (xy 122.01768 -412.928105)
			(xy 121.965385 -412.943459) (xy 121.911437 -412.951214) (xy 121.884186 -412.951676) (xy 121.020586 -412.951676)
			(xy 120.993333 -412.951253) (xy 120.939382 -412.943494) (xy 120.887085 -412.928137) (xy 120.837505 -412.905493)
			(xy 120.791653 -412.876024) (xy 120.750461 -412.840329) (xy 120.714768 -412.799136) (xy 120.6853 -412.753282)
			(xy 120.662658 -412.703702) (xy 120.647303 -412.651404) (xy 120.639546 -412.597453) (xy 119.201889 -412.597453)
			(xy 119.194135 -412.651386) (xy 119.178784 -412.703673) (xy 119.156148 -412.753243) (xy 119.126688 -412.799087)
			(xy 119.091005 -412.840272) (xy 119.049824 -412.875961) (xy 119.003983 -412.905426) (xy 118.954416 -412.928068)
			(xy 118.902131 -412.943425) (xy 118.848193 -412.951187) (xy 118.820946 -412.951676) (xy 117.957346 -412.951676)
			(xy 117.930089 -412.95128) (xy 117.876128 -412.943528) (xy 117.82382 -412.928175) (xy 117.77423 -412.905533)
			(xy 117.728367 -412.876063) (xy 117.687166 -412.840367) (xy 117.651464 -412.799169) (xy 117.621989 -412.75331)
			(xy 117.599342 -412.703723) (xy 117.583982 -412.651417) (xy 117.576223 -412.597457) (xy 116.138689 -412.597457)
			(xy 116.130934 -412.651391) (xy 116.115581 -412.703681) (xy 116.092942 -412.753254) (xy 116.063479 -412.7991)
			(xy 116.027791 -412.840287) (xy 115.986605 -412.875975) (xy 115.940759 -412.905439) (xy 115.891187 -412.928079)
			(xy 115.838897 -412.943433) (xy 115.784955 -412.951189) (xy 115.757706 -412.951676) (xy 114.894106 -412.951676)
			(xy 114.866851 -412.951277) (xy 114.812894 -412.943521) (xy 114.760591 -412.928164) (xy 114.711006 -412.90552)
			(xy 114.665149 -412.876049) (xy 114.623952 -412.840353) (xy 114.588254 -412.799156) (xy 114.558783 -412.753299)
			(xy 114.536138 -412.703714) (xy 114.520781 -412.651411) (xy 114.513023 -412.597455) (xy 94.987413 -412.597455)
			(xy 94.979655 -412.651402) (xy 94.964299 -412.703698) (xy 94.941656 -412.753276) (xy 94.912187 -412.799127)
			(xy 94.876492 -412.840318) (xy 94.835299 -412.876008) (xy 94.789445 -412.905473) (xy 94.739864 -412.928111)
			(xy 94.687567 -412.943463) (xy 94.633616 -412.951215) (xy 94.606364 -412.951676) (xy 93.742764 -412.951676)
			(xy 93.715512 -412.951252) (xy 93.661564 -412.94349) (xy 93.609269 -412.928131) (xy 93.559692 -412.905486)
			(xy 93.513842 -412.876016) (xy 93.472653 -412.840321) (xy 93.436962 -412.799129) (xy 93.407497 -412.753276)
			(xy 93.384857 -412.703697) (xy 93.369502 -412.651401) (xy 93.361746 -412.597452) (xy 91.924089 -412.597452)
			(xy 91.916335 -412.651389) (xy 91.900982 -412.703677) (xy 91.878345 -412.753249) (xy 91.848883 -412.799094)
			(xy 91.813197 -412.84028) (xy 91.772013 -412.875969) (xy 91.72617 -412.905433) (xy 91.6766 -412.928074)
			(xy 91.624312 -412.94343) (xy 91.570372 -412.951188) (xy 91.543124 -412.951676) (xy 90.679524 -412.951676)
			(xy 90.652268 -412.951279) (xy 90.59831 -412.943524) (xy 90.546004 -412.928169) (xy 90.496417 -412.905526)
			(xy 90.450557 -412.876056) (xy 90.409358 -412.840359) (xy 90.373659 -412.799162) (xy 90.344186 -412.753304)
			(xy 90.32154 -412.703718) (xy 90.306181 -412.651414) (xy 90.298423 -412.597456) (xy 88.860912 -412.597456)
			(xy 88.853156 -412.651399) (xy 88.8378 -412.703694) (xy 88.815159 -412.753271) (xy 88.785692 -412.799121)
			(xy 88.749999 -412.840311) (xy 88.708808 -412.876001) (xy 88.662957 -412.905466) (xy 88.613379 -412.928106)
			(xy 88.561083 -412.943459) (xy 88.507135 -412.951214) (xy 88.479884 -412.951676) (xy 87.616284 -412.951676)
			(xy 87.589031 -412.951253) (xy 87.535081 -412.943494) (xy 87.482783 -412.928136) (xy 87.433204 -412.905492)
			(xy 87.387352 -412.876023) (xy 87.34616 -412.840329) (xy 87.310467 -412.799135) (xy 87.281 -412.753282)
			(xy 87.258358 -412.703702) (xy 87.243003 -412.651404) (xy 87.235246 -412.597453) (xy 85.797589 -412.597453)
			(xy 85.789835 -412.651386) (xy 85.774484 -412.703673) (xy 85.751848 -412.753243) (xy 85.722388 -412.799087)
			(xy 85.686704 -412.840273) (xy 85.645523 -412.875962) (xy 85.599682 -412.905427) (xy 85.550114 -412.928068)
			(xy 85.497829 -412.943426) (xy 85.443891 -412.951187) (xy 85.416644 -412.951676) (xy 84.553044 -412.951676)
			(xy 84.525787 -412.95128) (xy 84.471827 -412.943528) (xy 84.419519 -412.928174) (xy 84.369929 -412.905532)
			(xy 84.324067 -412.876063) (xy 84.282865 -412.840366) (xy 84.247164 -412.799169) (xy 84.217689 -412.75331)
			(xy 84.195041 -412.703722) (xy 84.179682 -412.651417) (xy 84.171923 -412.597457) (xy 82.734389 -412.597457)
			(xy 82.726634 -412.651392) (xy 82.71128 -412.703682) (xy 82.688642 -412.753254) (xy 82.659178 -412.799101)
			(xy 82.62349 -412.840287) (xy 82.582304 -412.875976) (xy 82.536458 -412.90544) (xy 82.486885 -412.928079)
			(xy 82.434595 -412.943433) (xy 82.380653 -412.95119) (xy 82.353404 -412.951676) (xy 81.489804 -412.951676)
			(xy 81.462549 -412.951277) (xy 81.408593 -412.94352) (xy 81.35629 -412.928163) (xy 81.306705 -412.905519)
			(xy 81.260848 -412.876049) (xy 81.219651 -412.840352) (xy 81.183954 -412.799156) (xy 81.154483 -412.753298)
			(xy 81.131838 -412.703714) (xy 81.116481 -412.651411) (xy 81.108723 -412.597455) (xy 79.671213 -412.597455)
			(xy 79.663455 -412.651402) (xy 79.648099 -412.703698) (xy 79.625456 -412.753276) (xy 79.595987 -412.799127)
			(xy 79.560292 -412.840318) (xy 79.519099 -412.876008) (xy 79.473245 -412.905473) (xy 79.423664 -412.928111)
			(xy 79.371367 -412.943463) (xy 79.317416 -412.951215) (xy 79.290164 -412.951676) (xy 78.426564 -412.951676)
			(xy 78.399312 -412.951252) (xy 78.345364 -412.94349) (xy 78.293069 -412.928131) (xy 78.243492 -412.905486)
			(xy 78.197642 -412.876016) (xy 78.156453 -412.840321) (xy 78.120762 -412.799129) (xy 78.091297 -412.753276)
			(xy 78.068657 -412.703697) (xy 78.053302 -412.651401) (xy 78.045546 -412.597452) (xy 76.607889 -412.597452)
			(xy 76.600135 -412.651389) (xy 76.584782 -412.703677) (xy 76.562145 -412.753249) (xy 76.532683 -412.799094)
			(xy 76.496997 -412.84028) (xy 76.455813 -412.875969) (xy 76.40997 -412.905433) (xy 76.3604 -412.928074)
			(xy 76.308112 -412.94343) (xy 76.254172 -412.951188) (xy 76.226924 -412.951676) (xy 75.363324 -412.951676)
			(xy 75.336068 -412.951279) (xy 75.28211 -412.943524) (xy 75.229804 -412.928169) (xy 75.180217 -412.905526)
			(xy 75.134357 -412.876056) (xy 75.093158 -412.840359) (xy 75.057459 -412.799162) (xy 75.027986 -412.753304)
			(xy 75.00534 -412.703718) (xy 74.989981 -412.651414) (xy 74.982223 -412.597456) (xy 73.544712 -412.597456)
			(xy 73.536956 -412.651399) (xy 73.5216 -412.703694) (xy 73.498959 -412.753271) (xy 73.469492 -412.799121)
			(xy 73.433799 -412.840311) (xy 73.392608 -412.876001) (xy 73.346757 -412.905466) (xy 73.297179 -412.928106)
			(xy 73.244883 -412.943459) (xy 73.190935 -412.951214) (xy 73.163684 -412.951676) (xy 72.300084 -412.951676)
			(xy 72.272831 -412.951253) (xy 72.218881 -412.943494) (xy 72.166583 -412.928136) (xy 72.117004 -412.905492)
			(xy 72.071152 -412.876023) (xy 72.02996 -412.840329) (xy 71.994267 -412.799135) (xy 71.9648 -412.753282)
			(xy 71.942158 -412.703702) (xy 71.926803 -412.651404) (xy 71.919046 -412.597453) (xy 70.481389 -412.597453)
			(xy 70.473635 -412.651386) (xy 70.458284 -412.703673) (xy 70.435648 -412.753243) (xy 70.406188 -412.799087)
			(xy 70.370504 -412.840273) (xy 70.329323 -412.875962) (xy 70.283482 -412.905427) (xy 70.233914 -412.928068)
			(xy 70.181629 -412.943426) (xy 70.127691 -412.951187) (xy 70.100444 -412.951676) (xy 69.236844 -412.951676)
			(xy 69.209587 -412.95128) (xy 69.155627 -412.943528) (xy 69.103319 -412.928174) (xy 69.053729 -412.905532)
			(xy 69.007867 -412.876063) (xy 68.966665 -412.840366) (xy 68.930964 -412.799169) (xy 68.901489 -412.75331)
			(xy 68.878841 -412.703722) (xy 68.863482 -412.651417) (xy 68.855723 -412.597457) (xy 67.418189 -412.597457)
			(xy 67.410434 -412.651392) (xy 67.39508 -412.703682) (xy 67.372442 -412.753254) (xy 67.342978 -412.799101)
			(xy 67.30729 -412.840287) (xy 67.266104 -412.875976) (xy 67.220258 -412.90544) (xy 67.170685 -412.928079)
			(xy 67.118395 -412.943433) (xy 67.064453 -412.95119) (xy 67.037204 -412.951676) (xy 66.173604 -412.951676)
			(xy 66.146349 -412.951277) (xy 66.092393 -412.94352) (xy 66.04009 -412.928163) (xy 65.990505 -412.905519)
			(xy 65.944648 -412.876049) (xy 65.903451 -412.840352) (xy 65.867754 -412.799156) (xy 65.838283 -412.753298)
			(xy 65.815638 -412.703714) (xy 65.800281 -412.651411) (xy 65.792523 -412.597455) (xy 64.355013 -412.597455)
			(xy 64.347255 -412.651402) (xy 64.331899 -412.703698) (xy 64.309256 -412.753276) (xy 64.279787 -412.799127)
			(xy 64.244092 -412.840318) (xy 64.202899 -412.876008) (xy 64.157045 -412.905473) (xy 64.107464 -412.928111)
			(xy 64.055167 -412.943463) (xy 64.001216 -412.951215) (xy 63.973964 -412.951676) (xy 63.110364 -412.951676)
			(xy 63.083112 -412.951252) (xy 63.029164 -412.94349) (xy 62.976869 -412.928131) (xy 62.927292 -412.905486)
			(xy 62.881442 -412.876016) (xy 62.840253 -412.840321) (xy 62.804562 -412.799129) (xy 62.775097 -412.753276)
			(xy 62.752457 -412.703697) (xy 62.737102 -412.651401) (xy 62.729346 -412.597452) (xy 61.291689 -412.597452)
			(xy 61.283935 -412.651389) (xy 61.268582 -412.703677) (xy 61.245945 -412.753249) (xy 61.216483 -412.799094)
			(xy 61.180797 -412.84028) (xy 61.139613 -412.875969) (xy 61.09377 -412.905433) (xy 61.0442 -412.928074)
			(xy 60.991912 -412.94343) (xy 60.937972 -412.951188) (xy 60.910724 -412.951676) (xy 60.047124 -412.951676)
			(xy 60.019868 -412.951279) (xy 59.96591 -412.943524) (xy 59.913604 -412.928169) (xy 59.864017 -412.905526)
			(xy 59.818157 -412.876056) (xy 59.776958 -412.840359) (xy 59.741259 -412.799162) (xy 59.711786 -412.753304)
			(xy 59.68914 -412.703718) (xy 59.673781 -412.651414) (xy 59.666023 -412.597456) (xy 58.228512 -412.597456)
			(xy 58.220756 -412.651399) (xy 58.2054 -412.703694) (xy 58.182759 -412.753271) (xy 58.153292 -412.799121)
			(xy 58.117599 -412.840311) (xy 58.076408 -412.876001) (xy 58.030557 -412.905466) (xy 57.980979 -412.928106)
			(xy 57.928683 -412.943459) (xy 57.874735 -412.951214) (xy 57.847484 -412.951676) (xy 56.983884 -412.951676)
			(xy 56.956631 -412.951253) (xy 56.902681 -412.943494) (xy 56.850383 -412.928136) (xy 56.800804 -412.905492)
			(xy 56.754952 -412.876023) (xy 56.71376 -412.840329) (xy 56.678067 -412.799135) (xy 56.6486 -412.753282)
			(xy 56.625958 -412.703702) (xy 56.610603 -412.651404) (xy 56.602846 -412.597453) (xy 55.165189 -412.597453)
			(xy 55.157435 -412.651386) (xy 55.142084 -412.703673) (xy 55.119448 -412.753243) (xy 55.089988 -412.799087)
			(xy 55.054304 -412.840273) (xy 55.013123 -412.875962) (xy 54.967282 -412.905427) (xy 54.917714 -412.928068)
			(xy 54.865429 -412.943426) (xy 54.811491 -412.951187) (xy 54.784244 -412.951676) (xy 53.920644 -412.951676)
			(xy 53.893387 -412.95128) (xy 53.839427 -412.943528) (xy 53.787119 -412.928174) (xy 53.737529 -412.905532)
			(xy 53.691667 -412.876063) (xy 53.650465 -412.840366) (xy 53.614764 -412.799169) (xy 53.585289 -412.75331)
			(xy 53.562641 -412.703722) (xy 53.547282 -412.651417) (xy 53.539523 -412.597457) (xy 52.101989 -412.597457)
			(xy 52.094234 -412.651392) (xy 52.07888 -412.703682) (xy 52.056242 -412.753254) (xy 52.026778 -412.799101)
			(xy 51.99109 -412.840287) (xy 51.949904 -412.875976) (xy 51.904058 -412.90544) (xy 51.854485 -412.928079)
			(xy 51.802195 -412.943433) (xy 51.748253 -412.95119) (xy 51.721004 -412.951676) (xy 50.857404 -412.951676)
			(xy 50.830149 -412.951277) (xy 50.776193 -412.94352) (xy 50.72389 -412.928163) (xy 50.674305 -412.905519)
			(xy 50.628448 -412.876049) (xy 50.587251 -412.840352) (xy 50.551554 -412.799156) (xy 50.522083 -412.753298)
			(xy 50.499438 -412.703714) (xy 50.484081 -412.651411) (xy 50.476323 -412.597455) (xy 49.038813 -412.597455)
			(xy 49.031055 -412.651402) (xy 49.015699 -412.703698) (xy 48.993056 -412.753276) (xy 48.963587 -412.799127)
			(xy 48.927892 -412.840318) (xy 48.886699 -412.876008) (xy 48.840845 -412.905473) (xy 48.791264 -412.928111)
			(xy 48.738967 -412.943463) (xy 48.685016 -412.951215) (xy 48.657764 -412.951676) (xy 47.794164 -412.951676)
			(xy 47.766912 -412.951252) (xy 47.712964 -412.94349) (xy 47.660669 -412.928131) (xy 47.611092 -412.905486)
			(xy 47.565242 -412.876016) (xy 47.524053 -412.840321) (xy 47.488362 -412.799129) (xy 47.458897 -412.753276)
			(xy 47.436257 -412.703697) (xy 47.420902 -412.651401) (xy 47.413146 -412.597452) (xy 39.737792 -412.597452)
			(xy 39.737792 -413.4485) (xy 39.737306 -413.475769) (xy 39.729544 -413.529753) (xy 39.714179 -413.582083)
			(xy 39.691522 -413.631693) (xy 39.662036 -413.677574) (xy 39.626321 -413.718791) (xy 39.585104 -413.754506)
			(xy 39.539223 -413.783992) (xy 39.489613 -413.806649) (xy 39.437283 -413.822014) (xy 39.383299 -413.829776)
			(xy 39.328761 -413.829776) (xy 39.274777 -413.822014) (xy 39.222447 -413.806649) (xy 39.172837 -413.783992)
			(xy 39.126956 -413.754506) (xy 39.085739 -413.718791) (xy 39.050024 -413.677574) (xy 39.020538 -413.631693)
			(xy 38.997881 -413.582083) (xy 38.982516 -413.529753) (xy 38.974754 -413.475769) (xy 38.974268 -413.4485)
			(xy 7.00913 -413.4485) (xy 7.00913 -413.845248) (xy 43.729148 -413.845248) (xy 43.729148 -413.650684)
			(xy 43.729571 -413.639559) (xy 43.736024 -413.618262) (xy 43.741848 -413.608774) (xy 43.93438 -413.31388)
			(xy 43.940099 -413.304503) (xy 43.946366 -413.28346) (xy 43.946361 -413.261504) (xy 43.940084 -413.240464)
			(xy 43.93438 -413.231076) (xy 43.741848 -412.937452) (xy 43.736036 -412.927959) (xy 43.729589 -412.906664)
			(xy 43.729148 -412.895542) (xy 43.729148 -412.699708) (xy 43.729666 -412.687663) (xy 43.73709 -412.664747)
			(xy 43.751218 -412.645235) (xy 43.770673 -412.63103) (xy 43.793559 -412.623514) (xy 43.805602 -412.623)
			(xy 44.49191 -412.623) (xy 44.503996 -412.623498) (xy 44.52699 -412.630953) (xy 44.546566 -412.645133)
			(xy 44.560818 -412.664657) (xy 44.568357 -412.687624) (xy 44.568872 -412.699708) (xy 44.568872 -412.894272)
			(xy 44.568428 -412.905395) (xy 44.561989 -412.926692) (xy 44.556172 -412.936182) (xy 44.36364 -413.229806)
			(xy 44.357909 -413.239175) (xy 44.351575 -413.260194) (xy 44.351508 -413.282147) (xy 44.357714 -413.303205)
			(xy 44.363386 -413.31261) (xy 44.46048 -413.461769) (xy 105.629431 -413.461769) (xy 105.629431 -413.407231)
			(xy 105.637193 -413.353247) (xy 105.652559 -413.300918) (xy 105.675215 -413.251308) (xy 105.704702 -413.205427)
			(xy 105.740417 -413.16421) (xy 105.781635 -413.128496) (xy 105.827517 -413.099011) (xy 105.877127 -413.076355)
			(xy 105.929457 -413.060991) (xy 105.983441 -413.053231) (xy 106.01071 -413.052768) (xy 106.87431 -413.052768)
			(xy 106.901581 -413.053195) (xy 106.955568 -413.060959) (xy 107.0079 -413.076326) (xy 107.057513 -413.098985)
			(xy 107.103396 -413.128473) (xy 107.144616 -413.164191) (xy 107.180333 -413.205412) (xy 107.20982 -413.251296)
			(xy 107.232477 -413.300909) (xy 107.247844 -413.353242) (xy 107.255606 -413.407229) (xy 107.255606 -413.461771)
			(xy 107.247844 -413.515758) (xy 107.232477 -413.568091) (xy 107.20982 -413.617704) (xy 107.180333 -413.663588)
			(xy 107.144616 -413.704809) (xy 107.103396 -413.740527) (xy 107.057513 -413.770015) (xy 107.0079 -413.792674)
			(xy 106.955568 -413.808041) (xy 106.901581 -413.815805) (xy 106.87431 -413.816292) (xy 106.01071 -413.816292)
			(xy 105.983441 -413.815769) (xy 105.929457 -413.808009) (xy 105.877127 -413.792645) (xy 105.827517 -413.769989)
			(xy 105.781635 -413.740504) (xy 105.740417 -413.70479) (xy 105.704702 -413.663573) (xy 105.675215 -413.617692)
			(xy 105.652559 -413.568082) (xy 105.637193 -413.515753) (xy 105.629431 -413.461769) (xy 44.46048 -413.461769)
			(xy 44.556172 -413.608774) (xy 44.561958 -413.618281) (xy 44.568421 -413.639565) (xy 44.568872 -413.650684)
			(xy 44.568872 -413.845248) (xy 44.568481 -413.857304) (xy 44.561031 -413.880235) (xy 44.546874 -413.899753)
			(xy 44.527388 -413.913953) (xy 44.504472 -413.921454) (xy 44.492418 -413.921956) (xy 43.80611 -413.921956)
			(xy 43.794021 -413.921484) (xy 43.77102 -413.914029) (xy 43.751439 -413.899844) (xy 43.737189 -413.880312)
			(xy 43.729657 -413.857336) (xy 43.729148 -413.845248) (xy 7.00913 -413.845248) (xy 7.00913 -415.383726)
			(xy 41.206928 -415.383726) (xy 41.206928 -414.520126) (xy 41.207414 -414.492857) (xy 41.215176 -414.438873)
			(xy 41.230541 -414.386543) (xy 41.253198 -414.336933) (xy 41.282684 -414.291052) (xy 41.318399 -414.249835)
			(xy 41.359616 -414.21412) (xy 41.405497 -414.184634) (xy 41.455107 -414.161977) (xy 41.507437 -414.146612)
			(xy 41.561421 -414.13885) (xy 41.615959 -414.13885) (xy 41.669943 -414.146612) (xy 41.722273 -414.161977)
			(xy 41.771883 -414.184634) (xy 41.817764 -414.21412) (xy 41.858981 -414.249835) (xy 41.894696 -414.291052)
			(xy 41.924182 -414.336933) (xy 41.946839 -414.386543) (xy 41.962204 -414.438873) (xy 41.969966 -414.492857)
			(xy 41.970452 -414.520126) (xy 41.970452 -415.383726) (xy 41.969966 -415.410995) (xy 41.962204 -415.464979)
			(xy 41.946839 -415.517309) (xy 41.924182 -415.566919) (xy 41.894696 -415.6128) (xy 41.858981 -415.654017)
			(xy 41.817764 -415.689732) (xy 41.771883 -415.719218) (xy 41.722273 -415.741875) (xy 41.669943 -415.75724)
			(xy 41.615959 -415.765002) (xy 41.561421 -415.765002) (xy 41.507437 -415.75724) (xy 41.455107 -415.741875)
			(xy 41.405497 -415.719218) (xy 41.359616 -415.689732) (xy 41.318399 -415.654017) (xy 41.282684 -415.6128)
			(xy 41.253198 -415.566919) (xy 41.230541 -415.517309) (xy 41.215176 -415.464979) (xy 41.207414 -415.410995)
			(xy 41.206928 -415.383726) (xy 7.00913 -415.383726) (xy 7.00913 -417.465002) (xy 35.832796 -417.465002)
			(xy 35.832796 -416.601402) (xy 35.833282 -416.574151) (xy 35.841038 -416.520203) (xy 35.856393 -416.467908)
			(xy 35.879035 -416.418331) (xy 35.908501 -416.372481) (xy 35.944192 -416.33129) (xy 35.985383 -416.295599)
			(xy 36.031233 -416.266133) (xy 36.08081 -416.243491) (xy 36.133105 -416.228136) (xy 36.187053 -416.22038)
			(xy 36.241555 -416.22038) (xy 36.295503 -416.228136) (xy 36.347798 -416.243491) (xy 36.397375 -416.266133)
			(xy 36.443225 -416.295599) (xy 36.484416 -416.33129) (xy 36.520107 -416.372481) (xy 36.549573 -416.418331)
			(xy 36.572215 -416.467908) (xy 36.58757 -416.520203) (xy 36.595326 -416.574151) (xy 36.595812 -416.601402)
			(xy 36.595812 -417.436808) (xy 48.812704 -417.436808) (xy 48.812704 -416.573208) (xy 48.81319 -416.545939)
			(xy 48.820952 -416.491955) (xy 48.836317 -416.439625) (xy 48.858974 -416.390015) (xy 48.88846 -416.344134)
			(xy 48.924175 -416.302917) (xy 48.965392 -416.267202) (xy 49.011273 -416.237716) (xy 49.060883 -416.215059)
			(xy 49.113213 -416.199694) (xy 49.167197 -416.191932) (xy 49.221735 -416.191932) (xy 49.275719 -416.199694)
			(xy 49.328049 -416.215059) (xy 49.377659 -416.237716) (xy 49.42354 -416.267202) (xy 49.464757 -416.302917)
			(xy 49.500472 -416.344134) (xy 49.529958 -416.390015) (xy 49.552615 -416.439625) (xy 49.56798 -416.491955)
			(xy 49.575742 -416.545939) (xy 49.576228 -416.573208) (xy 49.576228 -417.082986) (xy 51.315112 -417.082986)
			(xy 51.315112 -416.888422) (xy 51.315556 -416.877299) (xy 51.321995 -416.856002) (xy 51.327812 -416.846512)
			(xy 51.520344 -416.551618) (xy 51.526033 -416.542224) (xy 51.53231 -416.521189) (xy 51.532314 -416.499238)
			(xy 51.526045 -416.4782) (xy 51.520344 -416.468814) (xy 51.327812 -416.17519) (xy 51.322011 -416.165691)
			(xy 51.315557 -416.144401) (xy 51.315112 -416.13328) (xy 51.315112 -415.937446) (xy 51.315599 -415.925328)
			(xy 51.323075 -415.902275) (xy 51.33731 -415.882662) (xy 51.356911 -415.868408) (xy 51.379957 -415.86091)
			(xy 51.392074 -415.860484) (xy 52.077874 -415.860484) (xy 52.09 -415.860883) (xy 52.113066 -415.868373)
			(xy 52.132685 -415.882629) (xy 52.146936 -415.902252) (xy 52.15442 -415.92532) (xy 52.154836 -415.937446)
			(xy 52.154836 -416.13201) (xy 52.154413 -416.143135) (xy 52.14796 -416.164432) (xy 52.142136 -416.17392)
			(xy 51.949604 -416.467544) (xy 51.943843 -416.476896) (xy 51.937519 -416.497923) (xy 51.937461 -416.519882)
			(xy 51.943675 -416.540942) (xy 51.94935 -416.550348) (xy 52.142136 -416.846512) (xy 52.147942 -416.856008)
			(xy 52.154392 -416.877301) (xy 52.154836 -416.888422) (xy 52.154836 -417.082986) (xy 52.154428 -417.095111)
			(xy 52.146936 -417.118173) (xy 52.132682 -417.137791) (xy 52.113063 -417.152042) (xy 52.089999 -417.15953)
			(xy 52.077874 -417.159948) (xy 51.392074 -417.159948) (xy 51.379957 -417.15951) (xy 51.35691 -417.152014)
			(xy 51.337308 -417.137764) (xy 51.323067 -417.118154) (xy 51.315583 -417.095104) (xy 51.315112 -417.082986)
			(xy 49.576228 -417.082986) (xy 49.576228 -417.436808) (xy 49.575742 -417.464077) (xy 49.56798 -417.518061)
			(xy 49.552615 -417.570391) (xy 49.529958 -417.620001) (xy 49.500472 -417.665882) (xy 49.464757 -417.707099)
			(xy 49.42354 -417.742814) (xy 49.377659 -417.7723) (xy 49.328049 -417.794957) (xy 49.275719 -417.810322)
			(xy 49.221735 -417.818084) (xy 49.167197 -417.818084) (xy 49.113213 -417.810322) (xy 49.060883 -417.794957)
			(xy 49.011273 -417.7723) (xy 48.965392 -417.742814) (xy 48.924175 -417.707099) (xy 48.88846 -417.665882)
			(xy 48.858974 -417.620001) (xy 48.836317 -417.570391) (xy 48.820952 -417.518061) (xy 48.81319 -417.464077)
			(xy 48.812704 -417.436808) (xy 36.595812 -417.436808) (xy 36.595812 -417.465002) (xy 36.595326 -417.492253)
			(xy 36.58757 -417.546201) (xy 36.572215 -417.598496) (xy 36.549573 -417.648073) (xy 36.520107 -417.693923)
			(xy 36.484416 -417.735114) (xy 36.443225 -417.770805) (xy 36.397375 -417.800271) (xy 36.347798 -417.822913)
			(xy 36.295503 -417.838268) (xy 36.241555 -417.846024) (xy 36.187053 -417.846024) (xy 36.133105 -417.838268)
			(xy 36.08081 -417.822913) (xy 36.031233 -417.800271) (xy 35.985383 -417.770805) (xy 35.944192 -417.735114)
			(xy 35.908501 -417.693923) (xy 35.879035 -417.648073) (xy 35.856393 -417.598496) (xy 35.841038 -417.546201)
			(xy 35.833282 -417.492253) (xy 35.832796 -417.465002) (xy 7.00913 -417.465002) (xy 7.00913 -418.963602)
			(xy 50.007012 -418.963602) (xy 50.007012 -418.45357) (xy 50.007486 -418.441456) (xy 50.014978 -418.418417)
			(xy 50.02922 -418.398818) (xy 50.04882 -418.384576) (xy 50.07186 -418.377085) (xy 50.083974 -418.376608)
			(xy 51.353212 -418.376608) (xy 51.365297 -418.377003) (xy 51.388283 -418.384475) (xy 51.407834 -418.398686)
			(xy 51.422037 -418.418242) (xy 51.429502 -418.441231) (xy 51.42992 -418.453316) (xy 51.42992 -418.963602)
			(xy 51.429493 -418.975696) (xy 51.422031 -418.998703) (xy 51.407836 -419.018286) (xy 51.388291 -419.032535)
			(xy 51.365304 -419.04006) (xy 51.353212 -419.040564) (xy 50.083974 -419.040564) (xy 50.071858 -419.040111)
			(xy 50.048814 -419.032616) (xy 50.029213 -419.01837) (xy 50.014973 -418.998764) (xy 50.007486 -418.975718)
			(xy 50.007012 -418.963602) (xy 7.00913 -418.963602) (xy 7.00913 -421.200326) (xy 10.01268 -421.200326)
			(xy 10.01268 -420.336726) (xy 10.013166 -420.309475) (xy 10.020922 -420.255527) (xy 10.036277 -420.203232)
			(xy 10.058919 -420.153655) (xy 10.088385 -420.107805) (xy 10.124076 -420.066614) (xy 10.165267 -420.030923)
			(xy 10.211117 -420.001457) (xy 10.260694 -419.978815) (xy 10.312989 -419.96346) (xy 10.366937 -419.955704)
			(xy 10.421439 -419.955704) (xy 10.475387 -419.96346) (xy 10.527682 -419.978815) (xy 10.529405 -419.979602)
			(xy 50.007012 -419.979602) (xy 50.007012 -419.46957) (xy 50.007486 -419.457456) (xy 50.014978 -419.434417)
			(xy 50.02922 -419.414818) (xy 50.04882 -419.400576) (xy 50.07186 -419.393085) (xy 50.083974 -419.392608)
			(xy 51.353212 -419.392608) (xy 51.365297 -419.393003) (xy 51.388283 -419.400475) (xy 51.407834 -419.414686)
			(xy 51.422037 -419.434242) (xy 51.429502 -419.457231) (xy 51.42992 -419.469316) (xy 51.42992 -419.64102)
			(xy 51.809904 -419.64102) (xy 51.809904 -418.77742) (xy 51.81039 -418.750151) (xy 51.818152 -418.696167)
			(xy 51.833517 -418.643837) (xy 51.856174 -418.594227) (xy 51.88566 -418.548346) (xy 51.921375 -418.507129)
			(xy 51.962592 -418.471414) (xy 52.008473 -418.441928) (xy 52.058083 -418.419271) (xy 52.110413 -418.403906)
			(xy 52.164397 -418.396144) (xy 52.218935 -418.396144) (xy 52.272919 -418.403906) (xy 52.325249 -418.419271)
			(xy 52.374859 -418.441928) (xy 52.42074 -418.471414) (xy 52.461957 -418.507129) (xy 52.497672 -418.548346)
			(xy 52.527158 -418.594227) (xy 52.549815 -418.643837) (xy 52.56518 -418.696167) (xy 52.572942 -418.750151)
			(xy 52.573428 -418.77742) (xy 52.573428 -419.64102) (xy 52.572942 -419.668289) (xy 52.56518 -419.722273)
			(xy 52.549815 -419.774603) (xy 52.527158 -419.824213) (xy 52.497672 -419.870094) (xy 52.461957 -419.911311)
			(xy 52.42074 -419.947026) (xy 52.374859 -419.976512) (xy 52.325249 -419.999169) (xy 52.272919 -420.014534)
			(xy 52.218935 -420.022296) (xy 52.164397 -420.022296) (xy 52.110413 -420.014534) (xy 52.058083 -419.999169)
			(xy 52.008473 -419.976512) (xy 51.962592 -419.947026) (xy 51.921375 -419.911311) (xy 51.88566 -419.870094)
			(xy 51.856174 -419.824213) (xy 51.833517 -419.774603) (xy 51.818152 -419.722273) (xy 51.81039 -419.668289)
			(xy 51.809904 -419.64102) (xy 51.42992 -419.64102) (xy 51.42992 -419.979602) (xy 51.429493 -419.991696)
			(xy 51.422031 -420.014703) (xy 51.407836 -420.034286) (xy 51.388291 -420.048535) (xy 51.365304 -420.05606)
			(xy 51.353212 -420.056564) (xy 50.083974 -420.056564) (xy 50.071858 -420.056111) (xy 50.048814 -420.048616)
			(xy 50.029213 -420.03437) (xy 50.014973 -420.014764) (xy 50.007486 -419.991718) (xy 50.007012 -419.979602)
			(xy 10.529405 -419.979602) (xy 10.577259 -420.001457) (xy 10.623109 -420.030923) (xy 10.6643 -420.066614)
			(xy 10.699991 -420.107805) (xy 10.729457 -420.153655) (xy 10.752099 -420.203232) (xy 10.767454 -420.255527)
			(xy 10.77521 -420.309475) (xy 10.775696 -420.336726) (xy 10.775696 -421.200326) (xy 10.77521 -421.227577)
			(xy 10.769122 -421.269922) (xy 21.420836 -421.269922) (xy 21.420836 -420.406322) (xy 21.421322 -420.379071)
			(xy 21.429078 -420.325123) (xy 21.444433 -420.272828) (xy 21.467075 -420.223251) (xy 21.496541 -420.177401)
			(xy 21.532232 -420.13621) (xy 21.573423 -420.100519) (xy 21.619273 -420.071053) (xy 21.66885 -420.048411)
			(xy 21.721145 -420.033056) (xy 21.775093 -420.0253) (xy 21.829595 -420.0253) (xy 21.883543 -420.033056)
			(xy 21.935838 -420.048411) (xy 21.985415 -420.071053) (xy 22.014645 -420.089838) (xy 58.137806 -420.089838)
			(xy 58.137905 -420.075966) (xy 58.139431 -420.048265) (xy 58.140854 -420.034466) (xy 58.141108 -420.028878)
			(xy 58.141108 -418.950902) (xy 58.140854 -418.945314) (xy 58.139442 -418.931514) (xy 58.137915 -418.903813)
			(xy 58.137806 -418.889942) (xy 58.137905 -418.87607) (xy 58.139431 -418.848369) (xy 58.140854 -418.83457)
			(xy 58.141108 -418.828982) (xy 58.141108 -418.218874) (xy 58.141589 -418.206761) (xy 58.14908 -418.183722)
			(xy 58.16332 -418.164123) (xy 58.182918 -418.149882) (xy 58.205957 -418.14239) (xy 58.21807 -418.141912)
			(xy 59.15787 -418.141912) (xy 59.169989 -418.142385) (xy 59.193042 -418.149866) (xy 59.212655 -418.164105)
			(xy 59.226908 -418.183708) (xy 59.234406 -418.206756) (xy 59.234832 -418.218874) (xy 59.234832 -420.760398)
			(xy 59.234438 -420.772524) (xy 59.226942 -420.795587) (xy 59.212685 -420.815205) (xy 59.193062 -420.829455)
			(xy 59.169996 -420.836942) (xy 59.15787 -420.83736) (xy 58.21807 -420.83736) (xy 58.205954 -420.836914)
			(xy 58.182909 -420.829418) (xy 58.163308 -420.81517) (xy 58.149067 -420.795562) (xy 58.141581 -420.772515)
			(xy 58.141108 -420.760398) (xy 58.141108 -420.150798) (xy 58.140854 -420.14521) (xy 58.139442 -420.13141)
			(xy 58.137915 -420.103709) (xy 58.137806 -420.089838) (xy 22.014645 -420.089838) (xy 22.031265 -420.100519)
			(xy 22.072456 -420.13621) (xy 22.108147 -420.177401) (xy 22.137613 -420.223251) (xy 22.160255 -420.272828)
			(xy 22.17561 -420.325123) (xy 22.183366 -420.379071) (xy 22.183852 -420.406322) (xy 22.183852 -421.269922)
			(xy 22.183366 -421.297173) (xy 22.17561 -421.351121) (xy 22.160255 -421.403416) (xy 22.137613 -421.452993)
			(xy 22.108147 -421.498843) (xy 22.072456 -421.540034) (xy 22.031265 -421.575725) (xy 21.985415 -421.605191)
			(xy 21.935838 -421.627833) (xy 21.883543 -421.643188) (xy 21.829595 -421.650944) (xy 21.775093 -421.650944)
			(xy 21.721145 -421.643188) (xy 21.66885 -421.627833) (xy 21.619273 -421.605191) (xy 21.573423 -421.575725)
			(xy 21.532232 -421.540034) (xy 21.496541 -421.498843) (xy 21.467075 -421.452993) (xy 21.444433 -421.403416)
			(xy 21.429078 -421.351121) (xy 21.421322 -421.297173) (xy 21.420836 -421.269922) (xy 10.769122 -421.269922)
			(xy 10.767454 -421.281525) (xy 10.752099 -421.33382) (xy 10.729457 -421.383397) (xy 10.699991 -421.429247)
			(xy 10.6643 -421.470438) (xy 10.623109 -421.506129) (xy 10.577259 -421.535595) (xy 10.527682 -421.558237)
			(xy 10.475387 -421.573592) (xy 10.421439 -421.581348) (xy 10.366937 -421.581348) (xy 10.312989 -421.573592)
			(xy 10.260694 -421.558237) (xy 10.211117 -421.535595) (xy 10.165267 -421.506129) (xy 10.124076 -421.470438)
			(xy 10.088385 -421.429247) (xy 10.058919 -421.383397) (xy 10.036277 -421.33382) (xy 10.020922 -421.281525)
			(xy 10.013166 -421.227577) (xy 10.01268 -421.200326) (xy 7.00913 -421.200326) (xy 7.00913 -422.130474)
			(xy 24.87676 -422.130474) (xy 24.87676 -421.266874) (xy 24.877246 -421.239605) (xy 24.885008 -421.185621)
			(xy 24.900373 -421.133291) (xy 24.92303 -421.083681) (xy 24.952516 -421.0378) (xy 24.988231 -420.996583)
			(xy 25.029448 -420.960868) (xy 25.075329 -420.931382) (xy 25.124939 -420.908725) (xy 25.177269 -420.89336)
			(xy 25.231253 -420.885598) (xy 25.285791 -420.885598) (xy 25.339775 -420.89336) (xy 25.392105 -420.908725)
			(xy 25.441715 -420.931382) (xy 25.487596 -420.960868) (xy 25.528813 -420.996583) (xy 25.564528 -421.0378)
			(xy 25.594014 -421.083681) (xy 25.596825 -421.089836) (xy 60.137802 -421.089836) (xy 60.1379 -421.075964)
			(xy 60.139427 -421.048263) (xy 60.14085 -421.034464) (xy 60.141104 -421.028876) (xy 60.141104 -419.9509)
			(xy 60.14085 -419.945312) (xy 60.139438 -419.931512) (xy 60.137911 -419.903811) (xy 60.137802 -419.88994)
			(xy 60.137901 -419.876068) (xy 60.139427 -419.848367) (xy 60.14085 -419.834568) (xy 60.141104 -419.82898)
			(xy 60.141104 -419.218872) (xy 60.141536 -419.20682) (xy 60.148977 -419.183893) (xy 60.163125 -419.164377)
			(xy 60.182601 -419.150175) (xy 60.205507 -419.14267) (xy 60.217558 -419.142164) (xy 61.157866 -419.142164)
			(xy 61.169956 -419.142637) (xy 61.19296 -419.150087) (xy 61.212542 -419.164271) (xy 61.226793 -419.183805)
			(xy 61.234322 -419.206783) (xy 61.234828 -419.218872) (xy 61.234828 -421.089836) (xy 68.137786 -421.089836)
			(xy 68.137884 -421.075964) (xy 68.139411 -421.048263) (xy 68.140834 -421.034464) (xy 68.141088 -421.028876)
			(xy 68.141088 -419.9509) (xy 68.140834 -419.945312) (xy 68.139422 -419.931512) (xy 68.137895 -419.903811)
			(xy 68.137786 -419.88994) (xy 68.137885 -419.876068) (xy 68.139411 -419.848367) (xy 68.140834 -419.834568)
			(xy 68.141088 -419.82898) (xy 68.141088 -419.218872) (xy 68.141536 -419.206822) (xy 68.148975 -419.183897)
			(xy 68.163119 -419.164383) (xy 68.182591 -419.15018) (xy 68.205493 -419.142672) (xy 68.217542 -419.142164)
			(xy 69.15785 -419.142164) (xy 69.169939 -419.14265) (xy 69.192942 -419.150096) (xy 69.212525 -419.164277)
			(xy 69.226777 -419.183808) (xy 69.234306 -419.206784) (xy 69.234812 -419.218872) (xy 69.234812 -420.089838)
			(xy 70.137782 -420.089838) (xy 70.137881 -420.075966) (xy 70.139407 -420.048265) (xy 70.14083 -420.034466)
			(xy 70.141084 -420.028878) (xy 70.141084 -418.950902) (xy 70.14083 -418.945314) (xy 70.139418 -418.931514)
			(xy 70.137891 -418.903813) (xy 70.137782 -418.889942) (xy 70.137881 -418.87607) (xy 70.139407 -418.848369)
			(xy 70.14083 -418.83457) (xy 70.141084 -418.828982) (xy 70.141084 -418.218874) (xy 70.141438 -418.206745)
			(xy 70.148943 -418.183678) (xy 70.16321 -418.164059) (xy 70.182842 -418.14981) (xy 70.205917 -418.142327)
			(xy 70.218046 -418.141912) (xy 71.157846 -418.141912) (xy 71.16996 -418.142372) (xy 71.193001 -418.149869)
			(xy 71.212599 -418.164115) (xy 71.22684 -418.183717) (xy 71.234331 -418.20676) (xy 71.234808 -418.218874)
			(xy 71.234808 -418.3761) (xy 77.661008 -418.3761) (xy 77.661008 -417.5125) (xy 77.661494 -417.485231)
			(xy 77.669256 -417.431247) (xy 77.684621 -417.378917) (xy 77.707278 -417.329307) (xy 77.736764 -417.283426)
			(xy 77.772479 -417.242209) (xy 77.813696 -417.206494) (xy 77.859577 -417.177008) (xy 77.909187 -417.154351)
			(xy 77.961517 -417.138986) (xy 78.015501 -417.131224) (xy 78.070039 -417.131224) (xy 78.124023 -417.138986)
			(xy 78.176353 -417.154351) (xy 78.225963 -417.177008) (xy 78.271844 -417.206494) (xy 78.313061 -417.242209)
			(xy 78.348776 -417.283426) (xy 78.378262 -417.329307) (xy 78.400919 -417.378917) (xy 78.416284 -417.431247)
			(xy 78.424046 -417.485231) (xy 78.424532 -417.5125) (xy 78.424532 -418.3761) (xy 78.424046 -418.403369)
			(xy 78.416284 -418.457353) (xy 78.400919 -418.509683) (xy 78.378262 -418.559293) (xy 78.348776 -418.605174)
			(xy 78.313061 -418.646391) (xy 78.271844 -418.682106) (xy 78.225963 -418.711592) (xy 78.176353 -418.734249)
			(xy 78.124023 -418.749614) (xy 78.070039 -418.757376) (xy 78.015501 -418.757376) (xy 77.961517 -418.749614)
			(xy 77.909187 -418.734249) (xy 77.859577 -418.711592) (xy 77.813696 -418.682106) (xy 77.772479 -418.646391)
			(xy 77.736764 -418.605174) (xy 77.707278 -418.559293) (xy 77.684621 -418.509683) (xy 77.669256 -418.457353)
			(xy 77.661494 -418.403369) (xy 77.661008 -418.3761) (xy 71.234808 -418.3761) (xy 71.234808 -420.760398)
			(xy 71.234287 -420.772508) (xy 71.226806 -420.795543) (xy 71.212575 -420.815141) (xy 71.192986 -420.829384)
			(xy 71.169956 -420.83688) (xy 71.157846 -420.83736) (xy 70.218046 -420.83736) (xy 70.205925 -420.836901)
			(xy 70.182868 -420.829421) (xy 70.163252 -420.81518) (xy 70.148999 -420.795572) (xy 70.141506 -420.772518)
			(xy 70.141084 -420.760398) (xy 70.141084 -420.150798) (xy 70.14083 -420.14521) (xy 70.139417 -420.13141)
			(xy 70.137891 -420.103709) (xy 70.137782 -420.089838) (xy 69.234812 -420.089838) (xy 69.234812 -421.089836)
			(xy 72.137778 -421.089836) (xy 72.137877 -421.075964) (xy 72.139403 -421.048263) (xy 72.140826 -421.034464)
			(xy 72.14108 -421.028876) (xy 72.14108 -419.9509) (xy 72.140826 -419.945312) (xy 72.139414 -419.931512)
			(xy 72.137887 -419.903811) (xy 72.137778 -419.88994) (xy 72.137877 -419.876068) (xy 72.139403 -419.848367)
			(xy 72.140826 -419.834568) (xy 72.14108 -419.82898) (xy 72.14108 -419.218872) (xy 72.141535 -419.206822)
			(xy 72.148973 -419.183899) (xy 72.163116 -419.164386) (xy 72.182586 -419.150182) (xy 72.205486 -419.142673)
			(xy 72.217534 -419.142164) (xy 73.157842 -419.142164) (xy 73.169936 -419.142572) (xy 73.192942 -419.150043)
			(xy 73.212524 -419.164244) (xy 73.226772 -419.183791) (xy 73.234298 -419.206779) (xy 73.234804 -419.218872)
			(xy 73.234804 -420.921688) (xy 75.13828 -420.921688) (xy 75.13828 -420.058088) (xy 75.138766 -420.030819)
			(xy 75.146528 -419.976835) (xy 75.161893 -419.924505) (xy 75.18455 -419.874895) (xy 75.214036 -419.829014)
			(xy 75.249751 -419.787797) (xy 75.290968 -419.752082) (xy 75.336849 -419.722596) (xy 75.386459 -419.699939)
			(xy 75.438789 -419.684574) (xy 75.492773 -419.676812) (xy 75.547311 -419.676812) (xy 75.601295 -419.684574)
			(xy 75.653625 -419.699939) (xy 75.703235 -419.722596) (xy 75.749116 -419.752082) (xy 75.790333 -419.787797)
			(xy 75.826048 -419.829014) (xy 75.855534 -419.874895) (xy 75.878191 -419.924505) (xy 75.893556 -419.976835)
			(xy 75.901318 -420.030819) (xy 75.901804 -420.058088) (xy 75.901804 -420.921688) (xy 75.901318 -420.948957)
			(xy 75.893556 -421.002941) (xy 75.878191 -421.055271) (xy 75.855534 -421.104881) (xy 75.844472 -421.122094)
			(xy 97.149412 -421.122094) (xy 97.149412 -414.328102) (xy 97.149934 -414.317948) (xy 97.157703 -414.299183)
			(xy 97.17206 -414.284819) (xy 97.19082 -414.27704) (xy 97.200974 -414.27654) (xy 102.099618 -414.27654)
			(xy 102.109777 -414.277018) (xy 102.128547 -414.284799) (xy 102.142912 -414.29917) (xy 102.150685 -414.317943)
			(xy 102.15118 -414.328102) (xy 102.15118 -421.122094) (xy 102.150662 -421.132249) (xy 102.142893 -421.151015)
			(xy 102.128535 -421.16538) (xy 102.109773 -421.173157) (xy 102.099618 -421.173656) (xy 97.200974 -421.173656)
			(xy 97.190814 -421.173188) (xy 97.172043 -421.165404) (xy 97.157678 -421.15103) (xy 97.149906 -421.132255)
			(xy 97.149412 -421.122094) (xy 75.844472 -421.122094) (xy 75.826048 -421.150762) (xy 75.790333 -421.191979)
			(xy 75.749116 -421.227694) (xy 75.703235 -421.25718) (xy 75.653625 -421.279837) (xy 75.601295 -421.295202)
			(xy 75.547311 -421.302964) (xy 75.492773 -421.302964) (xy 75.438789 -421.295202) (xy 75.386459 -421.279837)
			(xy 75.336849 -421.25718) (xy 75.290968 -421.227694) (xy 75.249751 -421.191979) (xy 75.214036 -421.150762)
			(xy 75.18455 -421.104881) (xy 75.161893 -421.055271) (xy 75.146528 -421.002941) (xy 75.138766 -420.948957)
			(xy 75.13828 -420.921688) (xy 73.234804 -420.921688) (xy 73.234804 -421.760396) (xy 73.234337 -421.772446)
			(xy 73.226906 -421.79537) (xy 73.212766 -421.814886) (xy 73.193298 -421.829089) (xy 73.170398 -421.836596)
			(xy 73.15835 -421.837104) (xy 72.218042 -421.837104) (xy 72.205959 -421.836558) (xy 72.182967 -421.829118)
			(xy 72.16339 -421.81495) (xy 72.149137 -421.795436) (xy 72.141596 -421.772477) (xy 72.14108 -421.760396)
			(xy 72.14108 -421.150796) (xy 72.140826 -421.145208) (xy 72.139413 -421.131408) (xy 72.137887 -421.103707)
			(xy 72.137778 -421.089836) (xy 69.234812 -421.089836) (xy 69.234812 -421.760396) (xy 69.234337 -421.772445)
			(xy 69.226907 -421.795368) (xy 69.212769 -421.814883) (xy 69.193303 -421.829087) (xy 69.170405 -421.836595)
			(xy 69.158358 -421.837104) (xy 68.21805 -421.837104) (xy 68.205967 -421.836551) (xy 68.182976 -421.829113)
			(xy 68.163399 -421.814947) (xy 68.149145 -421.795434) (xy 68.141604 -421.772476) (xy 68.141088 -421.760396)
			(xy 68.141088 -421.150796) (xy 68.140834 -421.145208) (xy 68.139421 -421.131408) (xy 68.137895 -421.103707)
			(xy 68.137786 -421.089836) (xy 61.234828 -421.089836) (xy 61.234828 -421.760396) (xy 61.234337 -421.772443)
			(xy 61.226909 -421.795364) (xy 61.212775 -421.814877) (xy 61.193313 -421.829082) (xy 61.170419 -421.836593)
			(xy 61.158374 -421.837104) (xy 60.218066 -421.837104) (xy 60.205979 -421.836623) (xy 60.182985 -421.829162)
			(xy 60.163409 -421.814977) (xy 60.149158 -421.79545) (xy 60.141619 -421.772481) (xy 60.141104 -421.760396)
			(xy 60.141104 -421.150796) (xy 60.14085 -421.145208) (xy 60.139437 -421.131408) (xy 60.137911 -421.103707)
			(xy 60.137802 -421.089836) (xy 25.596825 -421.089836) (xy 25.616671 -421.133291) (xy 25.632036 -421.185621)
			(xy 25.639798 -421.239605) (xy 25.640284 -421.266874) (xy 25.640284 -421.726974) (xy 27.323192 -421.726974)
			(xy 27.323192 -421.672426) (xy 27.330955 -421.618434) (xy 27.346324 -421.566097) (xy 27.368985 -421.51648)
			(xy 27.398477 -421.470593) (xy 27.4342 -421.429371) (xy 27.475427 -421.393652) (xy 27.521317 -421.364165)
			(xy 27.570936 -421.341509) (xy 27.623276 -421.326146) (xy 27.677268 -421.318389) (xy 27.704542 -421.317928)
			(xy 28.568142 -421.317928) (xy 28.595409 -421.318437) (xy 28.649386 -421.326204) (xy 28.701709 -421.341572)
			(xy 28.751313 -421.36423) (xy 28.797187 -421.393716) (xy 28.838399 -421.429431) (xy 28.874109 -421.470646)
			(xy 28.90359 -421.516524) (xy 28.926243 -421.56613) (xy 28.941605 -421.618455) (xy 28.949366 -421.672433)
			(xy 28.949366 -421.726967) (xy 28.941605 -421.780945) (xy 28.926243 -421.83327) (xy 28.90359 -421.882876)
			(xy 28.874109 -421.928754) (xy 28.838399 -421.969969) (xy 28.797187 -422.005684) (xy 28.751313 -422.03517)
			(xy 28.701709 -422.057828) (xy 28.649386 -422.073196) (xy 28.595409 -422.080963) (xy 28.568142 -422.081452)
			(xy 27.704542 -422.081452) (xy 27.677268 -422.081011) (xy 27.623276 -422.073254) (xy 27.570936 -422.057891)
			(xy 27.521317 -422.035235) (xy 27.475427 -422.005748) (xy 27.4342 -421.970029) (xy 27.398477 -421.928807)
			(xy 27.368985 -421.88292) (xy 27.346324 -421.833303) (xy 27.330955 -421.780966) (xy 27.323192 -421.726974)
			(xy 25.640284 -421.726974) (xy 25.640284 -422.130474) (xy 25.639798 -422.157743) (xy 25.632036 -422.211727)
			(xy 25.616671 -422.264057) (xy 25.594014 -422.313667) (xy 25.564528 -422.359548) (xy 25.528813 -422.400765)
			(xy 25.487596 -422.43648) (xy 25.441715 -422.465966) (xy 25.392105 -422.488623) (xy 25.339775 -422.503988)
			(xy 25.285791 -422.51175) (xy 25.231253 -422.51175) (xy 25.177269 -422.503988) (xy 25.124939 -422.488623)
			(xy 25.075329 -422.465966) (xy 25.029448 -422.43648) (xy 24.988231 -422.400765) (xy 24.952516 -422.359548)
			(xy 24.92303 -422.313667) (xy 24.900373 -422.264057) (xy 24.885008 -422.211727) (xy 24.877246 -422.157743)
			(xy 24.87676 -422.130474) (xy 7.00913 -422.130474) (xy 7.00913 -422.66627) (xy 38.762906 -422.66627)
			(xy 38.762906 -422.61173) (xy 38.770668 -422.557744) (xy 38.786034 -422.505412) (xy 38.808691 -422.4558)
			(xy 38.838178 -422.409918) (xy 38.873894 -422.368698) (xy 38.915113 -422.332981) (xy 38.960995 -422.303494)
			(xy 39.010607 -422.280836) (xy 39.062938 -422.26547) (xy 39.116924 -422.257707) (xy 39.144194 -422.25722)
			(xy 40.007794 -422.25722) (xy 40.035064 -422.257719) (xy 40.089049 -422.26548) (xy 40.14138 -422.280845)
			(xy 40.190991 -422.303501) (xy 40.236874 -422.332987) (xy 40.278093 -422.368703) (xy 40.313809 -422.409921)
			(xy 40.343296 -422.455803) (xy 40.365953 -422.505414) (xy 40.381319 -422.557745) (xy 40.389081 -422.61173)
			(xy 40.389081 -422.66627) (xy 40.381319 -422.720255) (xy 40.365953 -422.772586) (xy 40.343296 -422.822197)
			(xy 40.313809 -422.868079) (xy 40.278093 -422.909297) (xy 40.236874 -422.945013) (xy 40.190991 -422.974499)
			(xy 40.14138 -422.997155) (xy 40.089049 -423.01252) (xy 40.035064 -423.020281) (xy 40.007794 -423.020744)
			(xy 39.144194 -423.020744) (xy 39.116924 -423.020293) (xy 39.062938 -423.01253) (xy 39.010607 -422.997164)
			(xy 38.960995 -422.974506) (xy 38.915113 -422.945019) (xy 38.873894 -422.909302) (xy 38.838178 -422.868082)
			(xy 38.808691 -422.8222) (xy 38.786034 -422.772588) (xy 38.770668 -422.720256) (xy 38.762906 -422.66627)
			(xy 7.00913 -422.66627) (xy 7.00913 -423.057828) (xy 41.652952 -423.057828) (xy 41.652952 -422.194228)
			(xy 41.653438 -422.166959) (xy 41.6612 -422.112975) (xy 41.676565 -422.060645) (xy 41.699222 -422.011035)
			(xy 41.728708 -421.965154) (xy 41.764423 -421.923937) (xy 41.80564 -421.888222) (xy 41.851521 -421.858736)
			(xy 41.901131 -421.836079) (xy 41.953461 -421.820714) (xy 42.007445 -421.812952) (xy 42.061983 -421.812952)
			(xy 42.115967 -421.820714) (xy 42.168297 -421.836079) (xy 42.217907 -421.858736) (xy 42.263788 -421.888222)
			(xy 42.305005 -421.923937) (xy 42.34072 -421.965154) (xy 42.370206 -422.011035) (xy 42.392863 -422.060645)
			(xy 42.408228 -422.112975) (xy 42.41599 -422.166959) (xy 42.416476 -422.194228) (xy 42.416476 -423.057828)
			(xy 42.41599 -423.085097) (xy 42.408228 -423.139081) (xy 42.392863 -423.191411) (xy 42.370206 -423.241021)
			(xy 42.34072 -423.286902) (xy 42.305005 -423.328119) (xy 42.263788 -423.363834) (xy 42.217907 -423.39332)
			(xy 42.168297 -423.415977) (xy 42.115967 -423.431342) (xy 42.061983 -423.439104) (xy 42.007445 -423.439104)
			(xy 41.953461 -423.431342) (xy 41.901131 -423.415977) (xy 41.851521 -423.39332) (xy 41.80564 -423.363834)
			(xy 41.764423 -423.328119) (xy 41.728708 -423.286902) (xy 41.699222 -423.241021) (xy 41.676565 -423.191411)
			(xy 41.6612 -423.139081) (xy 41.653438 -423.085097) (xy 41.652952 -423.057828) (xy 7.00913 -423.057828)
			(xy 7.00913 -423.68978) (xy 58.137806 -423.68978) (xy 58.137908 -423.675908) (xy 58.139432 -423.648207)
			(xy 58.140854 -423.634408) (xy 58.141108 -423.62882) (xy 58.141108 -422.550844) (xy 58.140854 -422.545256)
			(xy 58.139437 -422.531457) (xy 58.137914 -422.503755) (xy 58.137806 -422.489884) (xy 58.137908 -422.476012)
			(xy 58.139432 -422.448311) (xy 58.140854 -422.434512) (xy 58.141108 -422.428924) (xy 58.141108 -421.81907)
			(xy 58.141586 -421.806957) (xy 58.149077 -421.783918) (xy 58.163319 -421.764319) (xy 58.182918 -421.750077)
			(xy 58.205957 -421.742586) (xy 58.21807 -421.742108) (xy 59.15787 -421.742108) (xy 59.16998 -421.742637)
			(xy 59.193017 -421.750112) (xy 59.212617 -421.76434) (xy 59.22686 -421.783929) (xy 59.234354 -421.80696)
			(xy 59.234832 -421.81907) (xy 59.234832 -423.68978) (xy 62.137798 -423.68978) (xy 62.1379 -423.675908)
			(xy 62.139424 -423.648207) (xy 62.140846 -423.634408) (xy 62.1411 -423.62882) (xy 62.1411 -422.550844)
			(xy 62.140846 -422.545256) (xy 62.139429 -422.531457) (xy 62.137906 -422.503755) (xy 62.137798 -422.489884)
			(xy 62.1379 -422.476012) (xy 62.139424 -422.448311) (xy 62.140846 -422.434512) (xy 62.1411 -422.428924)
			(xy 62.1411 -421.81907) (xy 62.141585 -421.806958) (xy 62.149076 -421.78392) (xy 62.163316 -421.764322)
			(xy 62.182913 -421.75008) (xy 62.20595 -421.742587) (xy 62.218062 -421.742108) (xy 63.157862 -421.742108)
			(xy 63.16998 -421.742592) (xy 63.193032 -421.75007) (xy 63.212645 -421.764306) (xy 63.226899 -421.783907)
			(xy 63.234398 -421.806953) (xy 63.234824 -421.81907) (xy 63.234824 -424.360594) (xy 63.234434 -424.37272)
			(xy 63.226939 -424.395785) (xy 63.212681 -424.415404) (xy 63.193057 -424.429654) (xy 63.169988 -424.437139)
			(xy 63.157862 -424.437556) (xy 62.218062 -424.437556) (xy 62.205945 -424.437121) (xy 62.182899 -424.429622)
			(xy 62.163298 -424.415371) (xy 62.149058 -424.395761) (xy 62.141572 -424.372711) (xy 62.1411 -424.360594)
			(xy 62.1411 -423.75074) (xy 62.140846 -423.745152) (xy 62.139429 -423.731353) (xy 62.137906 -423.703651)
			(xy 62.137798 -423.68978) (xy 59.234832 -423.68978) (xy 59.234832 -424.360594) (xy 59.234434 -424.372719)
			(xy 59.22694 -424.395783) (xy 59.212684 -424.415401) (xy 59.193062 -424.429651) (xy 59.169996 -424.437138)
			(xy 59.15787 -424.437556) (xy 58.21807 -424.437556) (xy 58.205953 -424.437114) (xy 58.182908 -424.429618)
			(xy 58.163306 -424.415368) (xy 58.149066 -424.39576) (xy 58.14158 -424.372711) (xy 58.141108 -424.360594)
			(xy 58.141108 -423.75074) (xy 58.140854 -423.745152) (xy 58.139437 -423.731353) (xy 58.137914 -423.703651)
			(xy 58.137806 -423.68978) (xy 7.00913 -423.68978) (xy 7.00913 -425.887642) (xy 10.204704 -425.887642)
			(xy 10.204704 -425.024042) (xy 10.20519 -424.996773) (xy 10.212952 -424.942789) (xy 10.228317 -424.890459)
			(xy 10.250974 -424.840849) (xy 10.28046 -424.794968) (xy 10.316175 -424.753751) (xy 10.357392 -424.718036)
			(xy 10.403273 -424.68855) (xy 10.452883 -424.665893) (xy 10.505213 -424.650528) (xy 10.559197 -424.642766)
			(xy 10.613735 -424.642766) (xy 10.667719 -424.650528) (xy 10.720049 -424.665893) (xy 10.769659 -424.68855)
			(xy 10.81554 -424.718036) (xy 10.856757 -424.753751) (xy 10.892472 -424.794968) (xy 10.921958 -424.840849)
			(xy 10.944615 -424.890459) (xy 10.95998 -424.942789) (xy 10.967742 -424.996773) (xy 10.968228 -425.024042)
			(xy 10.968228 -425.328334) (xy 21.942552 -425.328334) (xy 21.942552 -424.464734) (xy 21.943038 -424.437465)
			(xy 21.9508 -424.383481) (xy 21.966165 -424.331151) (xy 21.988822 -424.281541) (xy 22.018308 -424.23566)
			(xy 22.054023 -424.194443) (xy 22.09524 -424.158728) (xy 22.141121 -424.129242) (xy 22.190731 -424.106585)
			(xy 22.243061 -424.09122) (xy 22.297045 -424.083458) (xy 22.351583 -424.083458) (xy 22.405567 -424.09122)
			(xy 22.457897 -424.106585) (xy 22.507507 -424.129242) (xy 22.553388 -424.158728) (xy 22.594605 -424.194443)
			(xy 22.63032 -424.23566) (xy 22.659806 -424.281541) (xy 22.682463 -424.331151) (xy 22.697828 -424.383481)
			(xy 22.70559 -424.437465) (xy 22.706076 -424.464734) (xy 22.706076 -424.689778) (xy 64.137794 -424.689778)
			(xy 64.137896 -424.675906) (xy 64.13942 -424.648205) (xy 64.140842 -424.634406) (xy 64.141096 -424.628818)
			(xy 64.141096 -423.550842) (xy 64.140842 -423.545254) (xy 64.139425 -423.531455) (xy 64.137902 -423.503753)
			(xy 64.137794 -423.489882) (xy 64.137896 -423.47601) (xy 64.13942 -423.448309) (xy 64.140842 -423.43451)
			(xy 64.141096 -423.428922) (xy 64.141096 -422.819068) (xy 64.141532 -422.807017) (xy 64.148973 -422.784091)
			(xy 64.16312 -422.764576) (xy 64.182595 -422.750373) (xy 64.2055 -422.742867) (xy 64.21755 -422.74236)
			(xy 65.157858 -422.74236) (xy 65.169947 -422.742843) (xy 65.19295 -422.750291) (xy 65.212532 -422.764473)
			(xy 65.226784 -422.784004) (xy 65.234313 -422.80698) (xy 65.23482 -422.819068) (xy 65.23482 -424.689778)
			(xy 68.137786 -424.689778) (xy 68.137888 -424.675906) (xy 68.139412 -424.648205) (xy 68.140834 -424.634406)
			(xy 68.141088 -424.628818) (xy 68.141088 -423.550842) (xy 68.140834 -423.545254) (xy 68.139417 -423.531455)
			(xy 68.137894 -423.503753) (xy 68.137786 -423.489882) (xy 68.137888 -423.47601) (xy 68.139412 -423.448309)
			(xy 68.140834 -423.43451) (xy 68.141088 -423.428922) (xy 68.141088 -422.819068) (xy 68.141532 -422.807017)
			(xy 68.148972 -422.784093) (xy 68.163118 -422.764578) (xy 68.18259 -422.750376) (xy 68.205493 -422.742868)
			(xy 68.217542 -422.74236) (xy 69.15785 -422.74236) (xy 69.169939 -422.74285) (xy 69.192941 -422.750296)
			(xy 69.212524 -422.764475) (xy 69.226775 -422.784006) (xy 69.234305 -422.806981) (xy 69.234812 -422.819068)
			(xy 69.234812 -423.68978) (xy 70.137782 -423.68978) (xy 70.137884 -423.675908) (xy 70.139408 -423.648207)
			(xy 70.14083 -423.634408) (xy 70.141084 -423.62882) (xy 70.141084 -422.550844) (xy 70.14083 -422.545256)
			(xy 70.139413 -422.531457) (xy 70.13789 -422.503755) (xy 70.137782 -422.489884) (xy 70.137884 -422.476012)
			(xy 70.139408 -422.448311) (xy 70.14083 -422.434512) (xy 70.141084 -422.428924) (xy 70.141084 -421.81907)
			(xy 70.141435 -421.806941) (xy 70.148941 -421.783873) (xy 70.163209 -421.764255) (xy 70.182842 -421.750006)
			(xy 70.205917 -421.742523) (xy 70.218046 -421.742108) (xy 71.157846 -421.742108) (xy 71.16996 -421.742572)
			(xy 71.193 -421.750068) (xy 71.212598 -421.764313) (xy 71.226839 -421.783915) (xy 71.23433 -421.806956)
			(xy 71.234808 -421.81907) (xy 71.234808 -424.360594) (xy 71.234284 -424.372704) (xy 71.226804 -424.395739)
			(xy 71.212574 -424.415337) (xy 71.192985 -424.42958) (xy 71.169955 -424.437076) (xy 71.157846 -424.437556)
			(xy 70.218046 -424.437556) (xy 70.205925 -424.437101) (xy 70.182867 -424.429621) (xy 70.16325 -424.415378)
			(xy 70.148998 -424.395769) (xy 70.141505 -424.372715) (xy 70.141084 -424.360594) (xy 70.141084 -423.75074)
			(xy 70.14083 -423.745152) (xy 70.139413 -423.731353) (xy 70.13789 -423.703651) (xy 70.137782 -423.68978)
			(xy 69.234812 -423.68978) (xy 69.234812 -424.689778) (xy 72.137778 -424.689778) (xy 72.13788 -424.675906)
			(xy 72.139404 -424.648205) (xy 72.140826 -424.634406) (xy 72.14108 -424.628818) (xy 72.14108 -423.550842)
			(xy 72.140826 -423.545254) (xy 72.139409 -423.531455) (xy 72.137886 -423.503753) (xy 72.137778 -423.489882)
			(xy 72.13788 -423.47601) (xy 72.139404 -423.448309) (xy 72.140826 -423.43451) (xy 72.14108 -423.428922)
			(xy 72.14108 -422.819068) (xy 72.141532 -422.807018) (xy 72.148971 -422.784095) (xy 72.163115 -422.764581)
			(xy 72.182585 -422.750378) (xy 72.205486 -422.742869) (xy 72.217534 -422.74236) (xy 73.157842 -422.74236)
			(xy 73.169936 -422.742772) (xy 73.192941 -422.750243) (xy 73.212522 -422.764443) (xy 73.226771 -422.783989)
			(xy 73.234298 -422.806975) (xy 73.234804 -422.819068) (xy 73.234804 -424.80464) (xy 109.929157 -424.80464)
			(xy 109.929157 -424.6755) (xy 109.937107 -424.546605) (xy 109.952977 -424.418445) (xy 109.976706 -424.291504)
			(xy 110.008205 -424.166265) (xy 110.047354 -424.043202) (xy 110.094005 -423.922783) (xy 110.14798 -423.805464)
			(xy 110.209075 -423.69169) (xy 110.277058 -423.581893) (xy 110.351672 -423.47649) (xy 110.432633 -423.37588)
			(xy 110.519633 -423.280445) (xy 110.612344 -423.190546) (xy 110.710414 -423.106525) (xy 110.813469 -423.028701)
			(xy 110.92112 -422.957369) (xy 111.032959 -422.892799) (xy 111.14856 -422.835237) (xy 111.267485 -422.7849)
			(xy 111.389284 -422.74198) (xy 111.513494 -422.706639) (xy 111.639643 -422.679012) (xy 111.767255 -422.659203)
			(xy 111.895844 -422.647287) (xy 112.024922 -422.643311) (xy 112.154 -422.647287) (xy 112.282589 -422.659203)
			(xy 112.410201 -422.679012) (xy 112.53635 -422.706639) (xy 112.66056 -422.74198) (xy 112.782359 -422.7849)
			(xy 112.901284 -422.835237) (xy 113.016885 -422.892799) (xy 113.128724 -422.957369) (xy 113.236375 -423.028701)
			(xy 113.33943 -423.106525) (xy 113.4375 -423.190546) (xy 113.530211 -423.280445) (xy 113.617211 -423.37588)
			(xy 113.698172 -423.47649) (xy 113.772786 -423.581893) (xy 113.840769 -423.69169) (xy 113.901864 -423.805464)
			(xy 113.955839 -423.922783) (xy 114.00249 -424.043202) (xy 114.041639 -424.166265) (xy 114.073138 -424.291504)
			(xy 114.096867 -424.418445) (xy 114.112737 -424.546605) (xy 114.120687 -424.6755) (xy 114.121184 -424.74007)
			(xy 114.120687 -424.80464) (xy 114.112737 -424.933535) (xy 114.096867 -425.061695) (xy 114.073138 -425.188636)
			(xy 114.041639 -425.313875) (xy 114.00249 -425.436938) (xy 113.955839 -425.557357) (xy 113.901864 -425.674676)
			(xy 113.840769 -425.78845) (xy 113.772786 -425.898247) (xy 113.698172 -426.00365) (xy 113.617211 -426.10426)
			(xy 113.530211 -426.199695) (xy 113.4375 -426.289594) (xy 113.33943 -426.373615) (xy 113.236375 -426.451439)
			(xy 113.128724 -426.522771) (xy 113.016885 -426.587341) (xy 112.901284 -426.644903) (xy 112.782359 -426.69524)
			(xy 112.66056 -426.73816) (xy 112.53635 -426.773501) (xy 112.410201 -426.801128) (xy 112.282589 -426.820937)
			(xy 112.154 -426.832853) (xy 112.024922 -426.83683) (xy 111.895844 -426.832853) (xy 111.767255 -426.820937)
			(xy 111.639643 -426.801128) (xy 111.513494 -426.773501) (xy 111.389284 -426.73816) (xy 111.267485 -426.69524)
			(xy 111.14856 -426.644903) (xy 111.032959 -426.587341) (xy 110.92112 -426.522771) (xy 110.813469 -426.451439)
			(xy 110.710414 -426.373615) (xy 110.612344 -426.289594) (xy 110.519633 -426.199695) (xy 110.432633 -426.10426)
			(xy 110.351672 -426.00365) (xy 110.277058 -425.898247) (xy 110.209075 -425.78845) (xy 110.14798 -425.674676)
			(xy 110.094005 -425.557357) (xy 110.047354 -425.436938) (xy 110.008205 -425.313875) (xy 109.976706 -425.188636)
			(xy 109.952977 -425.061695) (xy 109.937107 -424.933535) (xy 109.929157 -424.80464) (xy 73.234804 -424.80464)
			(xy 73.234804 -425.360592) (xy 73.234333 -425.372641) (xy 73.226903 -425.395566) (xy 73.212765 -425.415082)
			(xy 73.193297 -425.429285) (xy 73.170398 -425.436792) (xy 73.15835 -425.4373) (xy 72.218042 -425.4373)
			(xy 72.205959 -425.436758) (xy 72.182966 -425.429317) (xy 72.163389 -425.415149) (xy 72.149135 -425.395633)
			(xy 72.141595 -425.372673) (xy 72.14108 -425.360592) (xy 72.14108 -424.750738) (xy 72.140826 -424.74515)
			(xy 72.139409 -424.731351) (xy 72.137886 -424.703649) (xy 72.137778 -424.689778) (xy 69.234812 -424.689778)
			(xy 69.234812 -425.360592) (xy 69.234333 -425.372641) (xy 69.226904 -425.395564) (xy 69.212768 -425.415079)
			(xy 69.193302 -425.429283) (xy 69.170405 -425.436791) (xy 69.158358 -425.4373) (xy 68.21805 -425.4373)
			(xy 68.205967 -425.436751) (xy 68.182975 -425.429313) (xy 68.163397 -425.415146) (xy 68.149144 -425.395632)
			(xy 68.141603 -425.372673) (xy 68.141088 -425.360592) (xy 68.141088 -424.750738) (xy 68.140834 -424.74515)
			(xy 68.139417 -424.731351) (xy 68.137894 -424.703649) (xy 68.137786 -424.689778) (xy 65.23482 -424.689778)
			(xy 65.23482 -425.360592) (xy 65.234334 -425.37264) (xy 65.226905 -425.395562) (xy 65.212771 -425.415076)
			(xy 65.193307 -425.42928) (xy 65.170412 -425.43679) (xy 65.158366 -425.4373) (xy 64.218058 -425.4373)
			(xy 64.20597 -425.436829) (xy 64.182975 -425.429366) (xy 64.163399 -425.415179) (xy 64.149149 -425.395649)
			(xy 64.141611 -425.372678) (xy 64.141096 -425.360592) (xy 64.141096 -424.750738) (xy 64.140842 -424.74515)
			(xy 64.139425 -424.731351) (xy 64.137902 -424.703649) (xy 64.137794 -424.689778) (xy 22.706076 -424.689778)
			(xy 22.706076 -425.328334) (xy 22.70559 -425.355603) (xy 22.697828 -425.409587) (xy 22.682463 -425.461917)
			(xy 22.659806 -425.511527) (xy 22.63032 -425.557408) (xy 22.594605 -425.598625) (xy 22.553388 -425.63434)
			(xy 22.507507 -425.663826) (xy 22.457897 -425.686483) (xy 22.405567 -425.701848) (xy 22.351583 -425.70961)
			(xy 22.297045 -425.70961) (xy 22.243061 -425.701848) (xy 22.190731 -425.686483) (xy 22.141121 -425.663826)
			(xy 22.09524 -425.63434) (xy 22.054023 -425.598625) (xy 22.018308 -425.557408) (xy 21.988822 -425.511527)
			(xy 21.966165 -425.461917) (xy 21.9508 -425.409587) (xy 21.943038 -425.355603) (xy 21.942552 -425.328334)
			(xy 10.968228 -425.328334) (xy 10.968228 -425.887642) (xy 10.967742 -425.914911) (xy 10.964527 -425.937273)
			(xy 38.737196 -425.937273) (xy 38.737196 -425.882727) (xy 38.744959 -425.828736) (xy 38.760327 -425.776399)
			(xy 38.782988 -425.726782) (xy 38.81248 -425.680896) (xy 38.848202 -425.639674) (xy 38.889428 -425.603956)
			(xy 38.935317 -425.574469) (xy 38.984936 -425.551813) (xy 39.037275 -425.53645) (xy 39.091267 -425.528693)
			(xy 39.11854 -425.528232) (xy 39.98214 -425.528232) (xy 40.009407 -425.528733) (xy 40.063385 -425.536499)
			(xy 40.115709 -425.551868) (xy 40.165314 -425.574526) (xy 40.211189 -425.604012) (xy 40.252401 -425.639727)
			(xy 40.288112 -425.680943) (xy 40.317593 -425.726821) (xy 40.340246 -425.776428) (xy 40.355609 -425.828754)
			(xy 40.36337 -425.882733) (xy 40.36337 -425.937267) (xy 40.355609 -425.991246) (xy 40.340246 -426.043572)
			(xy 40.317593 -426.093179) (xy 40.288112 -426.139057) (xy 40.252401 -426.180273) (xy 40.211189 -426.215988)
			(xy 40.165314 -426.245474) (xy 40.115709 -426.268132) (xy 40.063385 -426.283501) (xy 40.009407 -426.291267)
			(xy 39.98214 -426.291756) (xy 39.11854 -426.291756) (xy 39.091267 -426.291307) (xy 39.037275 -426.28355)
			(xy 38.984936 -426.268187) (xy 38.935317 -426.245531) (xy 38.889428 -426.216044) (xy 38.848202 -426.180326)
			(xy 38.81248 -426.139104) (xy 38.782988 -426.093218) (xy 38.760327 -426.043601) (xy 38.744959 -425.991264)
			(xy 38.737196 -425.937273) (xy 10.964527 -425.937273) (xy 10.95998 -425.968895) (xy 10.944615 -426.021225)
			(xy 10.921958 -426.070835) (xy 10.892472 -426.116716) (xy 10.856757 -426.157933) (xy 10.81554 -426.193648)
			(xy 10.769659 -426.223134) (xy 10.720049 -426.245791) (xy 10.667719 -426.261156) (xy 10.613735 -426.268918)
			(xy 10.559197 -426.268918) (xy 10.505213 -426.261156) (xy 10.452883 -426.245791) (xy 10.403273 -426.223134)
			(xy 10.357392 -426.193648) (xy 10.316175 -426.157933) (xy 10.28046 -426.116716) (xy 10.250974 -426.070835)
			(xy 10.228317 -426.021225) (xy 10.212952 -425.968895) (xy 10.20519 -425.914911) (xy 10.204704 -425.887642)
			(xy 7.00913 -425.887642) (xy 7.00913 -426.333158) (xy 41.613836 -426.333158) (xy 41.613836 -425.469558)
			(xy 41.614322 -425.442307) (xy 41.622078 -425.388359) (xy 41.637433 -425.336064) (xy 41.660075 -425.286487)
			(xy 41.689541 -425.240637) (xy 41.725232 -425.199446) (xy 41.766423 -425.163755) (xy 41.812273 -425.134289)
			(xy 41.86185 -425.111647) (xy 41.914145 -425.096292) (xy 41.968093 -425.088536) (xy 42.022595 -425.088536)
			(xy 42.076543 -425.096292) (xy 42.128838 -425.111647) (xy 42.178415 -425.134289) (xy 42.224265 -425.163755)
			(xy 42.265456 -425.199446) (xy 42.301147 -425.240637) (xy 42.330613 -425.286487) (xy 42.353255 -425.336064)
			(xy 42.36861 -425.388359) (xy 42.376366 -425.442307) (xy 42.376852 -425.469558) (xy 42.376852 -426.333158)
			(xy 42.376366 -426.360409) (xy 42.36861 -426.414357) (xy 42.353255 -426.466652) (xy 42.330613 -426.516229)
			(xy 42.301147 -426.562079) (xy 42.265456 -426.60327) (xy 42.224265 -426.638961) (xy 42.178415 -426.668427)
			(xy 42.128838 -426.691069) (xy 42.076543 -426.706424) (xy 42.022595 -426.71418) (xy 41.968093 -426.71418)
			(xy 41.914145 -426.706424) (xy 41.86185 -426.691069) (xy 41.812273 -426.668427) (xy 41.766423 -426.638961)
			(xy 41.725232 -426.60327) (xy 41.689541 -426.562079) (xy 41.660075 -426.516229) (xy 41.637433 -426.466652)
			(xy 41.622078 -426.414357) (xy 41.614322 -426.360409) (xy 41.613836 -426.333158) (xy 7.00913 -426.333158)
			(xy 7.00913 -427.289976) (xy 58.137806 -427.289976) (xy 58.137908 -427.276104) (xy 58.139432 -427.248403)
			(xy 58.140854 -427.234604) (xy 58.141108 -427.229016) (xy 58.141108 -426.150786) (xy 58.140854 -426.145198)
			(xy 58.139441 -426.131398) (xy 58.137915 -426.103697) (xy 58.137806 -426.089826) (xy 58.137904 -426.075954)
			(xy 58.13943 -426.048253) (xy 58.140854 -426.034454) (xy 58.141108 -426.028866) (xy 58.141108 -425.419012)
			(xy 58.14157 -425.406962) (xy 58.149001 -425.384035) (xy 58.163141 -425.364518) (xy 58.182611 -425.350315)
			(xy 58.205513 -425.34281) (xy 58.217562 -425.342304) (xy 59.15787 -425.342304) (xy 59.169954 -425.342832)
			(xy 59.192948 -425.350276) (xy 59.212525 -425.364448) (xy 59.226778 -425.383967) (xy 59.234317 -425.40693)
			(xy 59.234832 -425.419012) (xy 59.234832 -427.960536) (xy 59.234372 -427.972585) (xy 59.226933 -427.995506)
			(xy 59.212791 -428.015019) (xy 59.193323 -428.029222) (xy 59.170425 -428.036733) (xy 59.158378 -428.037244)
			(xy 58.21807 -428.037244) (xy 58.205977 -428.036818) (xy 58.182973 -428.029351) (xy 58.163392 -428.015154)
			(xy 58.149143 -427.995612) (xy 58.141615 -427.972627) (xy 58.141108 -427.960536) (xy 58.141108 -427.350936)
			(xy 58.140854 -427.345348) (xy 58.139437 -427.331549) (xy 58.137914 -427.303847) (xy 58.137806 -427.289976)
			(xy 7.00913 -427.289976) (xy 7.00913 -428.615602) (xy 25.13076 -428.615602) (xy 25.13076 -427.752002)
			(xy 25.131246 -427.724733) (xy 25.139008 -427.670749) (xy 25.154373 -427.618419) (xy 25.17703 -427.568809)
			(xy 25.206516 -427.522928) (xy 25.242231 -427.481711) (xy 25.283448 -427.445996) (xy 25.329329 -427.41651)
			(xy 25.378939 -427.393853) (xy 25.431269 -427.378488) (xy 25.485253 -427.370726) (xy 25.539791 -427.370726)
			(xy 25.593775 -427.378488) (xy 25.646105 -427.393853) (xy 25.695715 -427.41651) (xy 25.741596 -427.445996)
			(xy 25.782813 -427.481711) (xy 25.818528 -427.522928) (xy 25.848014 -427.568809) (xy 25.870671 -427.618419)
			(xy 25.886036 -427.670749) (xy 25.893798 -427.724733) (xy 25.894284 -427.752002) (xy 25.894284 -428.211072)
			(xy 26.941204 -428.211072) (xy 26.941204 -428.156528) (xy 26.948966 -428.102539) (xy 26.964334 -428.050205)
			(xy 26.986993 -428.00059) (xy 27.016483 -427.954705) (xy 27.052203 -427.913485) (xy 27.093426 -427.877767)
			(xy 27.139313 -427.848281) (xy 27.188929 -427.825625) (xy 27.241265 -427.810261) (xy 27.295254 -427.802502)
			(xy 27.322526 -427.80204) (xy 28.186126 -427.80204) (xy 28.213394 -427.802524) (xy 28.267375 -427.810289)
			(xy 28.319702 -427.825657) (xy 28.369309 -427.848314) (xy 28.415187 -427.877801) (xy 28.456402 -427.913517)
			(xy 28.492114 -427.954734) (xy 28.521598 -428.000614) (xy 28.544253 -428.050222) (xy 28.559617 -428.10255)
			(xy 28.567378 -428.156532) (xy 28.567378 -428.211068) (xy 28.559617 -428.26505) (xy 28.552374 -428.28972)
			(xy 60.137802 -428.28972) (xy 60.137899 -428.275848) (xy 60.139426 -428.248147) (xy 60.14085 -428.234348)
			(xy 60.141104 -428.22876) (xy 60.141104 -427.150784) (xy 60.14085 -427.145196) (xy 60.139436 -427.131396)
			(xy 60.137911 -427.103695) (xy 60.137802 -427.089824) (xy 60.137899 -427.075952) (xy 60.139426 -427.048251)
			(xy 60.14085 -427.034452) (xy 60.141104 -427.028864) (xy 60.141104 -426.41901) (xy 60.14162 -426.406899)
			(xy 60.1491 -426.383862) (xy 60.163332 -426.364263) (xy 60.182923 -426.35002) (xy 60.205956 -426.342527)
			(xy 60.218066 -426.342048) (xy 61.157866 -426.342048) (xy 61.169988 -426.342489) (xy 61.193047 -426.349973)
			(xy 61.212664 -426.364219) (xy 61.226916 -426.383831) (xy 61.234407 -426.406888) (xy 61.234828 -426.41901)
			(xy 61.234828 -427.289976) (xy 62.137798 -427.289976) (xy 62.1379 -427.276104) (xy 62.139424 -427.248403)
			(xy 62.140846 -427.234604) (xy 62.1411 -427.229016) (xy 62.1411 -426.150786) (xy 62.140846 -426.145198)
			(xy 62.139433 -426.131398) (xy 62.137907 -426.103697) (xy 62.137798 -426.089826) (xy 62.137896 -426.075954)
			(xy 62.139422 -426.048253) (xy 62.140846 -426.034454) (xy 62.1411 -426.028866) (xy 62.1411 -425.419012)
			(xy 62.14157 -425.406962) (xy 62.149 -425.384037) (xy 62.163138 -425.364521) (xy 62.182606 -425.350318)
			(xy 62.205506 -425.342811) (xy 62.217554 -425.342304) (xy 63.157862 -425.342304) (xy 63.169946 -425.342839)
			(xy 63.192939 -425.350281) (xy 63.212517 -425.364451) (xy 63.22677 -425.383968) (xy 63.234309 -425.40693)
			(xy 63.234824 -425.419012) (xy 63.234824 -427.960536) (xy 63.234371 -427.972586) (xy 63.226932 -427.995508)
			(xy 63.212788 -428.015022) (xy 63.193318 -428.029225) (xy 63.170418 -428.036734) (xy 63.15837 -428.037244)
			(xy 62.218062 -428.037244) (xy 62.205969 -428.036825) (xy 62.182964 -428.029356) (xy 62.163384 -428.015157)
			(xy 62.149135 -427.995613) (xy 62.141607 -427.972628) (xy 62.1411 -427.960536) (xy 62.1411 -427.350936)
			(xy 62.140846 -427.345348) (xy 62.139429 -427.331549) (xy 62.137906 -427.303847) (xy 62.137798 -427.289976)
			(xy 61.234828 -427.289976) (xy 61.234828 -428.28972) (xy 64.137794 -428.28972) (xy 64.137891 -428.275848)
			(xy 64.139418 -428.248147) (xy 64.140842 -428.234348) (xy 64.141096 -428.22876) (xy 64.141096 -427.150784)
			(xy 64.140842 -427.145196) (xy 64.139428 -427.131396) (xy 64.137903 -427.103695) (xy 64.137794 -427.089824)
			(xy 64.137891 -427.075952) (xy 64.139418 -427.048251) (xy 64.140842 -427.034452) (xy 64.141096 -427.028864)
			(xy 64.141096 -426.41901) (xy 64.14162 -426.4069) (xy 64.149099 -426.383864) (xy 64.163329 -426.364266)
			(xy 64.182918 -426.350023) (xy 64.205948 -426.342528) (xy 64.218058 -426.342048) (xy 65.157858 -426.342048)
			(xy 65.16998 -426.342496) (xy 65.193039 -426.349978) (xy 65.212655 -426.364222) (xy 65.226908 -426.383833)
			(xy 65.234399 -426.406889) (xy 65.23482 -426.41901) (xy 65.23482 -427.289976) (xy 66.13779 -427.289976)
			(xy 66.137892 -427.276104) (xy 66.139416 -427.248403) (xy 66.140838 -427.234604) (xy 66.141092 -427.229016)
			(xy 66.141092 -426.150786) (xy 66.140838 -426.145198) (xy 66.139424 -426.131398) (xy 66.137899 -426.103697)
			(xy 66.13779 -426.089826) (xy 66.137888 -426.075954) (xy 66.139414 -426.048253) (xy 66.140838 -426.034454)
			(xy 66.141092 -426.028866) (xy 66.141092 -425.419012) (xy 66.14157 -425.406963) (xy 66.148998 -425.384039)
			(xy 66.163135 -425.364524) (xy 66.182601 -425.35032) (xy 66.205499 -425.342812) (xy 66.217546 -425.342304)
			(xy 67.157854 -425.342304) (xy 67.169938 -425.342846) (xy 67.192931 -425.350286) (xy 67.212508 -425.364454)
			(xy 67.226762 -425.38397) (xy 67.234301 -425.40693) (xy 67.234816 -425.419012) (xy 67.234816 -427.960536)
			(xy 67.234371 -427.972587) (xy 67.226931 -427.995511) (xy 67.212785 -428.015024) (xy 67.193313 -428.029227)
			(xy 67.170411 -428.036735) (xy 67.158362 -428.037244) (xy 66.218054 -428.037244) (xy 66.20596 -428.036832)
			(xy 66.182956 -428.02936) (xy 66.163375 -428.01516) (xy 66.149127 -427.995615) (xy 66.141599 -427.972628)
			(xy 66.141092 -427.960536) (xy 66.141092 -427.350936) (xy 66.140838 -427.345348) (xy 66.13942 -427.331549)
			(xy 66.137898 -427.303847) (xy 66.13779 -427.289976) (xy 65.23482 -427.289976) (xy 65.23482 -428.28972)
			(xy 68.137786 -428.28972) (xy 68.137883 -428.275848) (xy 68.13941 -428.248147) (xy 68.140834 -428.234348)
			(xy 68.141088 -428.22876) (xy 68.141088 -427.150784) (xy 68.140834 -427.145196) (xy 68.13942 -427.131396)
			(xy 68.137895 -427.103695) (xy 68.137786 -427.089824) (xy 68.137884 -427.075952) (xy 68.13941 -427.048251)
			(xy 68.140834 -427.034452) (xy 68.141088 -427.028864) (xy 68.141088 -426.41901) (xy 68.14162 -426.406901)
			(xy 68.149098 -426.383867) (xy 68.163326 -426.364269) (xy 68.182913 -426.350025) (xy 68.205941 -426.342529)
			(xy 68.21805 -426.342048) (xy 69.15785 -426.342048) (xy 69.169968 -426.342469) (xy 69.193015 -426.349972)
			(xy 69.212616 -426.364226) (xy 69.226856 -426.383839) (xy 69.23434 -426.406891) (xy 69.234812 -426.41901)
			(xy 69.234812 -427.289976) (xy 70.137782 -427.289976) (xy 70.137884 -427.276104) (xy 70.139408 -427.248403)
			(xy 70.14083 -427.234604) (xy 70.141084 -427.229016) (xy 70.141084 -426.150786) (xy 70.14083 -426.145198)
			(xy 70.139416 -426.131398) (xy 70.137891 -426.103697) (xy 70.137782 -426.089826) (xy 70.13788 -426.075954)
			(xy 70.139406 -426.048253) (xy 70.14083 -426.034454) (xy 70.141084 -426.028866) (xy 70.141084 -425.419012)
			(xy 70.14157 -425.406964) (xy 70.148997 -425.384042) (xy 70.163132 -425.364527) (xy 70.182596 -425.350323)
			(xy 70.205492 -425.342813) (xy 70.217538 -425.342304) (xy 71.157846 -425.342304) (xy 71.169934 -425.342767)
			(xy 71.19293 -425.350232) (xy 71.212507 -425.364421) (xy 71.226757 -425.383953) (xy 71.234294 -425.406925)
			(xy 71.234808 -425.419012) (xy 71.234808 -427.960536) (xy 71.234371 -427.972587) (xy 71.226929 -427.995513)
			(xy 71.212782 -428.015027) (xy 71.193308 -428.02923) (xy 71.170404 -428.036736) (xy 71.158354 -428.037244)
			(xy 70.218046 -428.037244) (xy 70.205957 -428.036753) (xy 70.182955 -428.029307) (xy 70.163373 -428.015127)
			(xy 70.149122 -427.995597) (xy 70.141591 -427.972623) (xy 70.141084 -427.960536) (xy 70.141084 -427.350936)
			(xy 70.14083 -427.345348) (xy 70.139412 -427.331549) (xy 70.13789 -427.303847) (xy 70.137782 -427.289976)
			(xy 69.234812 -427.289976) (xy 69.234812 -428.28972) (xy 72.137778 -428.28972) (xy 72.137875 -428.275848)
			(xy 72.139402 -428.248147) (xy 72.140826 -428.234348) (xy 72.14108 -428.22876) (xy 72.14108 -427.150784)
			(xy 72.140826 -427.145196) (xy 72.139412 -427.131396) (xy 72.137887 -427.103695) (xy 72.137778 -427.089824)
			(xy 72.137876 -427.075952) (xy 72.139402 -427.048251) (xy 72.140826 -427.034452) (xy 72.14108 -427.028864)
			(xy 72.14108 -426.41901) (xy 72.141469 -426.406884) (xy 72.148964 -426.383818) (xy 72.163222 -426.364199)
			(xy 72.182847 -426.349949) (xy 72.205915 -426.342464) (xy 72.218042 -426.342048) (xy 73.157842 -426.342048)
			(xy 73.16996 -426.342476) (xy 73.193006 -426.349976) (xy 73.212608 -426.364229) (xy 73.226848 -426.383841)
			(xy 73.234332 -426.406892) (xy 73.234804 -426.41901) (xy 73.234804 -427.289976) (xy 75.138026 -427.289976)
			(xy 75.138128 -427.276104) (xy 75.139652 -427.248403) (xy 75.141074 -427.234604) (xy 75.141328 -427.229016)
			(xy 75.141328 -426.150786) (xy 75.141074 -426.145198) (xy 75.139661 -426.131398) (xy 75.138135 -426.103697)
			(xy 75.138026 -426.089826) (xy 75.138123 -426.075954) (xy 75.13965 -426.048253) (xy 75.141074 -426.034454)
			(xy 75.141328 -426.028866) (xy 75.141328 -425.419012) (xy 75.141724 -425.406926) (xy 75.149192 -425.383938)
			(xy 75.163402 -425.364384) (xy 75.18296 -425.350181) (xy 75.20595 -425.34272) (xy 75.218036 -425.342304)
			(xy 76.157836 -425.342304) (xy 76.169914 -425.342734) (xy 76.192884 -425.350207) (xy 76.212422 -425.364413)
			(xy 76.226615 -425.383959) (xy 76.234074 -425.406934) (xy 76.234544 -425.419012) (xy 76.234544 -427.960536)
			(xy 76.234067 -427.972609) (xy 76.226599 -427.995571) (xy 76.212405 -428.015105) (xy 76.192871 -428.029299)
			(xy 76.169909 -428.036767) (xy 76.157836 -428.037244) (xy 75.218036 -428.037244) (xy 75.205967 -428.036706)
			(xy 75.183007 -428.029258) (xy 75.163472 -428.015079) (xy 75.149275 -427.995558) (xy 75.141806 -427.972605)
			(xy 75.141328 -427.960536) (xy 75.141328 -427.350936) (xy 75.141074 -427.345348) (xy 75.139657 -427.331549)
			(xy 75.138134 -427.303847) (xy 75.138026 -427.289976) (xy 73.234804 -427.289976) (xy 73.234804 -428.28972)
			(xy 77.138022 -428.28972) (xy 77.138119 -428.275848) (xy 77.139646 -428.248147) (xy 77.14107 -428.234348)
			(xy 77.141324 -428.22876) (xy 77.141324 -427.150784) (xy 77.14107 -427.145196) (xy 77.139656 -427.131396)
			(xy 77.138131 -427.103695) (xy 77.138022 -427.089824) (xy 77.138119 -427.075952) (xy 77.139646 -427.048251)
			(xy 77.14107 -427.034452) (xy 77.141324 -427.028864) (xy 77.141324 -426.41901) (xy 77.141816 -426.406923)
			(xy 77.149268 -426.383925) (xy 77.163449 -426.364346) (xy 77.182976 -426.350095) (xy 77.205946 -426.34256)
			(xy 77.218032 -426.342048) (xy 78.157832 -426.342048) (xy 78.169937 -426.342488) (xy 78.192957 -426.34999)
			(xy 78.212525 -426.364248) (xy 78.22672 -426.38386) (xy 78.234149 -426.406903) (xy 78.23454 -426.41901)
			(xy 78.23454 -427.289976) (xy 79.138018 -427.289976) (xy 79.13812 -427.276104) (xy 79.139644 -427.248403)
			(xy 79.141066 -427.234604) (xy 79.14132 -427.229016) (xy 79.14132 -426.150786) (xy 79.141066 -426.145198)
			(xy 79.139653 -426.131398) (xy 79.138127 -426.103697) (xy 79.138018 -426.089826) (xy 79.138115 -426.075954)
			(xy 79.139642 -426.048253) (xy 79.141066 -426.034454) (xy 79.14132 -426.028866) (xy 79.14132 -425.419012)
			(xy 79.141724 -425.406927) (xy 79.149191 -425.38394) (xy 79.163399 -425.364387) (xy 79.182954 -425.350184)
			(xy 79.205943 -425.342721) (xy 79.218028 -425.342304) (xy 80.157828 -425.342304) (xy 80.169905 -425.34274)
			(xy 80.192875 -425.350212) (xy 80.212413 -425.364415) (xy 80.226606 -425.38396) (xy 80.234066 -425.406935)
			(xy 80.234536 -425.419012) (xy 80.234536 -427.960536) (xy 80.234067 -427.97261) (xy 80.226598 -427.995573)
			(xy 80.212402 -428.015107) (xy 80.192866 -428.029302) (xy 80.169902 -428.036768) (xy 80.157828 -428.037244)
			(xy 79.218028 -428.037244) (xy 79.205958 -428.036713) (xy 79.182998 -428.029262) (xy 79.163464 -428.015082)
			(xy 79.149267 -427.995559) (xy 79.141797 -427.972605) (xy 79.14132 -427.960536) (xy 79.14132 -427.350936)
			(xy 79.141066 -427.345348) (xy 79.139649 -427.331549) (xy 79.138126 -427.303847) (xy 79.138018 -427.289976)
			(xy 78.23454 -427.289976) (xy 78.23454 -428.28972) (xy 81.138014 -428.28972) (xy 81.138111 -428.275848)
			(xy 81.139638 -428.248147) (xy 81.141062 -428.234348) (xy 81.141316 -428.22876) (xy 81.141316 -427.150784)
			(xy 81.141062 -427.145196) (xy 81.139648 -427.131396) (xy 81.138123 -427.103695) (xy 81.138014 -427.089824)
			(xy 81.138111 -427.075952) (xy 81.139638 -427.048251) (xy 81.141062 -427.034452) (xy 81.141316 -427.028864)
			(xy 81.141316 -426.41901) (xy 81.141816 -426.406923) (xy 81.149267 -426.383927) (xy 81.163446 -426.364349)
			(xy 81.182971 -426.350097) (xy 81.205939 -426.342561) (xy 81.218024 -426.342048) (xy 82.157824 -426.342048)
			(xy 82.169929 -426.342495) (xy 82.192948 -426.349995) (xy 82.212516 -426.36425) (xy 82.226712 -426.383862)
			(xy 82.234141 -426.406904) (xy 82.234532 -426.41901) (xy 82.234532 -427.289976) (xy 83.13801 -427.289976)
			(xy 83.138112 -427.276104) (xy 83.139636 -427.248403) (xy 83.141058 -427.234604) (xy 83.141312 -427.229016)
			(xy 83.141312 -426.150786) (xy 83.141058 -426.145198) (xy 83.139645 -426.131398) (xy 83.138119 -426.103697)
			(xy 83.13801 -426.089826) (xy 83.138108 -426.075954) (xy 83.139634 -426.048253) (xy 83.141058 -426.034454)
			(xy 83.141312 -426.028866) (xy 83.141312 -425.419012) (xy 83.141723 -425.406928) (xy 83.14919 -425.383942)
			(xy 83.163396 -425.36439) (xy 83.182949 -425.350186) (xy 83.205936 -425.342722) (xy 83.21802 -425.342304)
			(xy 84.15782 -425.342304) (xy 84.169897 -425.342748) (xy 84.192867 -425.350217) (xy 84.212404 -425.364419)
			(xy 84.226598 -425.383962) (xy 84.234057 -425.406935) (xy 84.234528 -425.419012) (xy 84.234528 -427.960536)
			(xy 84.234067 -427.97261) (xy 84.226597 -427.995576) (xy 84.212399 -428.01511) (xy 84.192861 -428.029304)
			(xy 84.169895 -428.036769) (xy 84.15782 -428.037244) (xy 83.21802 -428.037244) (xy 83.20595 -428.036719)
			(xy 83.18299 -428.029267) (xy 83.163455 -428.015085) (xy 83.149259 -427.995561) (xy 83.141789 -427.972606)
			(xy 83.141312 -427.960536) (xy 83.141312 -427.350936) (xy 83.141058 -427.345348) (xy 83.139641 -427.331549)
			(xy 83.138118 -427.303847) (xy 83.13801 -427.289976) (xy 82.234532 -427.289976) (xy 82.234532 -428.28972)
			(xy 85.138006 -428.28972) (xy 85.138103 -428.275848) (xy 85.13963 -428.248147) (xy 85.141054 -428.234348)
			(xy 85.141308 -428.22876) (xy 85.141308 -427.150784) (xy 85.141054 -427.145196) (xy 85.13964 -427.131396)
			(xy 85.138115 -427.103695) (xy 85.138006 -427.089824) (xy 85.138103 -427.075952) (xy 85.13963 -427.048251)
			(xy 85.141054 -427.034452) (xy 85.141308 -427.028864) (xy 85.141308 -426.41901) (xy 85.141815 -426.406924)
			(xy 85.149265 -426.383929) (xy 85.163443 -426.364352) (xy 85.182966 -426.3501) (xy 85.205932 -426.342562)
			(xy 85.218016 -426.342048) (xy 86.157816 -426.342048) (xy 86.169921 -426.342502) (xy 86.192939 -426.349999)
			(xy 86.212508 -426.364253) (xy 86.226704 -426.383863) (xy 86.234133 -426.406904) (xy 86.234524 -426.41901)
			(xy 86.234524 -427.289976) (xy 87.138002 -427.289976) (xy 87.138104 -427.276104) (xy 87.139628 -427.248403)
			(xy 87.14105 -427.234604) (xy 87.141304 -427.229016) (xy 87.141304 -426.150786) (xy 87.14105 -426.145198)
			(xy 87.139637 -426.131398) (xy 87.138111 -426.103697) (xy 87.138002 -426.089826) (xy 87.1381 -426.075954)
			(xy 87.139626 -426.048253) (xy 87.14105 -426.034454) (xy 87.141304 -426.028866) (xy 87.141304 -425.419012)
			(xy 87.141723 -425.406929) (xy 87.149189 -425.383944) (xy 87.163393 -425.364393) (xy 87.182944 -425.350189)
			(xy 87.205929 -425.342723) (xy 87.218012 -425.342304) (xy 88.157812 -425.342304) (xy 88.169888 -425.342754)
			(xy 88.192858 -425.350222) (xy 88.212396 -425.364421) (xy 88.226589 -425.383964) (xy 88.234049 -425.406935)
			(xy 88.23452 -425.419012) (xy 88.23452 -427.960536) (xy 88.234067 -427.972611) (xy 88.226596 -427.995578)
			(xy 88.212396 -428.015113) (xy 88.192856 -428.029307) (xy 88.169887 -428.036771) (xy 88.157812 -428.037244)
			(xy 87.218012 -428.037244) (xy 87.205942 -428.036726) (xy 87.182981 -428.029271) (xy 87.163447 -428.015087)
			(xy 87.149251 -427.995562) (xy 87.141781 -427.972606) (xy 87.141304 -427.960536) (xy 87.141304 -427.350936)
			(xy 87.14105 -427.345348) (xy 87.139633 -427.331549) (xy 87.13811 -427.303847) (xy 87.138002 -427.289976)
			(xy 86.234524 -427.289976) (xy 86.234524 -428.28972) (xy 89.137998 -428.28972) (xy 89.138095 -428.275848)
			(xy 89.139622 -428.248147) (xy 89.141046 -428.234348) (xy 89.1413 -428.22876) (xy 89.1413 -427.150784)
			(xy 89.141046 -427.145196) (xy 89.139632 -427.131396) (xy 89.138107 -427.103695) (xy 89.137998 -427.089824)
			(xy 89.138095 -427.075952) (xy 89.139622 -427.048251) (xy 89.141046 -427.034452) (xy 89.1413 -427.028864)
			(xy 89.1413 -426.41901) (xy 89.141815 -426.406925) (xy 89.149264 -426.383931) (xy 89.16344 -426.364355)
			(xy 89.182961 -426.350103) (xy 89.205925 -426.342563) (xy 89.218008 -426.342048) (xy 90.157808 -426.342048)
			(xy 90.169912 -426.342509) (xy 90.192931 -426.350004) (xy 90.212499 -426.364256) (xy 90.226696 -426.383865)
			(xy 90.234125 -426.406905) (xy 90.234516 -426.41901) (xy 90.234516 -427.289976) (xy 125.237748 -427.289976)
			(xy 125.237865 -427.275593) (xy 125.239515 -427.246874) (xy 125.24105 -427.232572) (xy 125.241304 -427.22673)
			(xy 125.241304 -426.153072) (xy 125.24105 -426.14723) (xy 125.239521 -426.132928) (xy 125.23787 -426.104209)
			(xy 125.237748 -426.089826) (xy 125.237861 -426.075443) (xy 125.239514 -426.046723) (xy 125.24105 -426.032422)
			(xy 125.241304 -426.02658) (xy 125.241304 -425.419012) (xy 125.241723 -425.406929) (xy 125.249189 -425.383944)
			(xy 125.263393 -425.364393) (xy 125.282944 -425.350189) (xy 125.305929 -425.342723) (xy 125.318012 -425.342304)
			(xy 126.257812 -425.342304) (xy 126.269888 -425.342754) (xy 126.292858 -425.350222) (xy 126.312396 -425.364421)
			(xy 126.326589 -425.383964) (xy 126.334049 -425.406935) (xy 126.33452 -425.419012) (xy 126.33452 -427.960536)
			(xy 126.334067 -427.972611) (xy 126.326596 -427.995578) (xy 126.312396 -428.015113) (xy 126.292856 -428.029307)
			(xy 126.269887 -428.036771) (xy 126.257812 -428.037244) (xy 125.318012 -428.037244) (xy 125.305942 -428.036726)
			(xy 125.282981 -428.029271) (xy 125.263447 -428.015087) (xy 125.249251 -427.995562) (xy 125.241781 -427.972606)
			(xy 125.241304 -427.960536) (xy 125.241304 -427.353222) (xy 125.24105 -427.34738) (xy 125.239525 -427.333078)
			(xy 125.237872 -427.304359) (xy 125.237748 -427.289976) (xy 90.234516 -427.289976) (xy 90.234516 -428.960534)
			(xy 90.234121 -428.97263) (xy 90.226649 -428.995639) (xy 90.212446 -429.015222) (xy 90.192895 -429.02947)
			(xy 90.169903 -429.036993) (xy 90.157808 -429.037496) (xy 89.218008 -429.037496) (xy 89.205899 -429.037077)
			(xy 89.182871 -429.029579) (xy 89.163298 -429.015319) (xy 89.149103 -428.995697) (xy 89.141683 -428.972644)
			(xy 89.1413 -428.960534) (xy 89.1413 -428.35068) (xy 89.141046 -428.345092) (xy 89.139632 -428.331292)
			(xy 89.138107 -428.303591) (xy 89.137998 -428.28972) (xy 86.234524 -428.28972) (xy 86.234524 -428.960534)
			(xy 86.234121 -428.972629) (xy 86.226651 -428.995637) (xy 86.212449 -429.015219) (xy 86.1929 -429.029467)
			(xy 86.16991 -429.036992) (xy 86.157816 -429.037496) (xy 85.218016 -429.037496) (xy 85.205908 -429.03707)
			(xy 85.18288 -429.029574) (xy 85.163307 -429.015315) (xy 85.149112 -428.995695) (xy 85.141691 -428.972644)
			(xy 85.141308 -428.960534) (xy 85.141308 -428.35068) (xy 85.141054 -428.345092) (xy 85.13964 -428.331292)
			(xy 85.138115 -428.303591) (xy 85.138006 -428.28972) (xy 82.234532 -428.28972) (xy 82.234532 -428.960534)
			(xy 82.234121 -428.972628) (xy 82.226652 -428.995635) (xy 82.212452 -429.015216) (xy 82.192905 -429.029465)
			(xy 82.169917 -429.036991) (xy 82.157824 -429.037496) (xy 81.218024 -429.037496) (xy 81.205916 -429.037063)
			(xy 81.182889 -429.02957) (xy 81.163315 -429.015313) (xy 81.14912 -428.995694) (xy 81.141699 -428.972643)
			(xy 81.141316 -428.960534) (xy 81.141316 -428.35068) (xy 81.141062 -428.345092) (xy 81.139648 -428.331292)
			(xy 81.138123 -428.303591) (xy 81.138014 -428.28972) (xy 78.23454 -428.28972) (xy 78.23454 -428.960534)
			(xy 78.234121 -428.972627) (xy 78.226653 -428.995632) (xy 78.212454 -429.015214) (xy 78.19291 -429.029462)
			(xy 78.169924 -429.03699) (xy 78.157832 -429.037496) (xy 77.218032 -429.037496) (xy 77.205924 -429.037056)
			(xy 77.182898 -429.029565) (xy 77.163324 -429.01531) (xy 77.149128 -428.995692) (xy 77.141707 -428.972643)
			(xy 77.141324 -428.960534) (xy 77.141324 -428.35068) (xy 77.14107 -428.345092) (xy 77.139656 -428.331292)
			(xy 77.138131 -428.303591) (xy 77.138022 -428.28972) (xy 73.234804 -428.28972) (xy 73.234804 -428.960534)
			(xy 73.234318 -428.972646) (xy 73.226827 -428.995683) (xy 73.212587 -429.015281) (xy 73.192991 -429.029523)
			(xy 73.169954 -429.037017) (xy 73.157842 -429.037496) (xy 72.218042 -429.037496) (xy 72.205925 -429.037005)
			(xy 72.182873 -429.029528) (xy 72.16326 -429.015294) (xy 72.149006 -428.995695) (xy 72.141507 -428.972651)
			(xy 72.14108 -428.960534) (xy 72.14108 -428.35068) (xy 72.140826 -428.345092) (xy 72.139412 -428.331292)
			(xy 72.137887 -428.303591) (xy 72.137778 -428.28972) (xy 69.234812 -428.28972) (xy 69.234812 -428.960534)
			(xy 69.234318 -428.972645) (xy 69.226828 -428.995681) (xy 69.21259 -429.015278) (xy 69.192996 -429.02952)
			(xy 69.169961 -429.037016) (xy 69.15785 -429.037496) (xy 68.21805 -429.037496) (xy 68.205936 -429.037031)
			(xy 68.182897 -429.029535) (xy 68.163299 -429.015289) (xy 68.149058 -428.995689) (xy 68.141566 -428.972648)
			(xy 68.141088 -428.960534) (xy 68.141088 -428.35068) (xy 68.140834 -428.345092) (xy 68.13942 -428.331292)
			(xy 68.137895 -428.303591) (xy 68.137786 -428.28972) (xy 65.23482 -428.28972) (xy 65.23482 -428.960534)
			(xy 65.234469 -428.972663) (xy 65.226962 -428.99573) (xy 65.212694 -429.015348) (xy 65.193062 -429.029597)
			(xy 65.169987 -429.03708) (xy 65.157858 -429.037496) (xy 64.218058 -429.037496) (xy 64.205945 -429.037025)
			(xy 64.182906 -429.02953) (xy 64.163308 -429.015287) (xy 64.149066 -428.995687) (xy 64.141574 -428.972647)
			(xy 64.141096 -428.960534) (xy 64.141096 -428.35068) (xy 64.140842 -428.345092) (xy 64.139428 -428.331292)
			(xy 64.137903 -428.303591) (xy 64.137794 -428.28972) (xy 61.234828 -428.28972) (xy 61.234828 -428.960534)
			(xy 61.234417 -428.972654) (xy 61.226916 -428.995704) (xy 61.21266 -429.015308) (xy 61.193043 -429.029547)
			(xy 61.169986 -429.037027) (xy 61.157866 -429.037496) (xy 60.218066 -429.037496) (xy 60.205953 -429.037018)
			(xy 60.182914 -429.029525) (xy 60.163316 -429.015284) (xy 60.149075 -428.995686) (xy 60.141582 -428.972647)
			(xy 60.141104 -428.960534) (xy 60.141104 -428.35068) (xy 60.14085 -428.345092) (xy 60.139436 -428.331292)
			(xy 60.137911 -428.303591) (xy 60.137802 -428.28972) (xy 28.552374 -428.28972) (xy 28.544253 -428.317378)
			(xy 28.521598 -428.366986) (xy 28.492114 -428.412866) (xy 28.456402 -428.454083) (xy 28.415187 -428.489799)
			(xy 28.369309 -428.519286) (xy 28.319702 -428.541943) (xy 28.267375 -428.557311) (xy 28.213394 -428.565076)
			(xy 28.186126 -428.565564) (xy 27.322526 -428.565564) (xy 27.295254 -428.565098) (xy 27.241265 -428.557339)
			(xy 27.188929 -428.541975) (xy 27.139313 -428.519319) (xy 27.093426 -428.489833) (xy 27.052203 -428.454115)
			(xy 27.016483 -428.412895) (xy 26.986993 -428.36701) (xy 26.964334 -428.317395) (xy 26.948966 -428.265061)
			(xy 26.941204 -428.211072) (xy 25.894284 -428.211072) (xy 25.894284 -428.615602) (xy 25.893798 -428.642871)
			(xy 25.886036 -428.696855) (xy 25.870671 -428.749185) (xy 25.848014 -428.798795) (xy 25.818528 -428.844676)
			(xy 25.782813 -428.885893) (xy 25.741596 -428.921608) (xy 25.695715 -428.951094) (xy 25.646105 -428.973751)
			(xy 25.593775 -428.989116) (xy 25.539791 -428.996878) (xy 25.485253 -428.996878) (xy 25.431269 -428.989116)
			(xy 25.378939 -428.973751) (xy 25.329329 -428.951094) (xy 25.283448 -428.921608) (xy 25.242231 -428.885893)
			(xy 25.206516 -428.844676) (xy 25.17703 -428.798795) (xy 25.154373 -428.749185) (xy 25.139008 -428.696855)
			(xy 25.131246 -428.642871) (xy 25.13076 -428.615602) (xy 7.00913 -428.615602) (xy 7.00913 -430.889918)
			(xy 58.137806 -430.889918) (xy 58.137903 -430.876046) (xy 58.13943 -430.848345) (xy 58.140854 -430.834546)
			(xy 58.141108 -430.828958) (xy 58.141108 -429.750728) (xy 58.140854 -429.74514) (xy 58.139436 -429.731341)
			(xy 58.137913 -429.703639) (xy 58.137806 -429.689768) (xy 58.137907 -429.675896) (xy 58.139432 -429.648195)
			(xy 58.140854 -429.634396) (xy 58.141108 -429.628808) (xy 58.141108 -429.018954) (xy 58.141572 -429.00684)
			(xy 58.149068 -428.9838) (xy 58.163313 -428.964202) (xy 58.182915 -428.949961) (xy 58.205956 -428.94247)
			(xy 58.21807 -428.941992) (xy 59.15787 -428.941992) (xy 59.169978 -428.942537) (xy 59.193013 -428.95001)
			(xy 59.212611 -428.964235) (xy 59.226855 -428.983819) (xy 59.234351 -429.006846) (xy 59.234832 -429.018954)
			(xy 59.234832 -431.560478) (xy 59.234421 -431.572603) (xy 59.226931 -431.595666) (xy 59.212678 -431.615284)
			(xy 59.193059 -431.629535) (xy 59.169995 -431.637022) (xy 59.15787 -431.63744) (xy 58.21807 -431.63744)
			(xy 58.205952 -431.637014) (xy 58.182904 -431.629515) (xy 58.163301 -431.615262) (xy 58.149061 -431.59565)
			(xy 58.141578 -431.572597) (xy 58.141108 -431.560478) (xy 58.141108 -430.950878) (xy 58.140854 -430.94529)
			(xy 58.13944 -430.93149) (xy 58.137915 -430.903789) (xy 58.137806 -430.889918) (xy 7.00913 -430.889918)
			(xy 7.00913 -431.889916) (xy 60.137802 -431.889916) (xy 60.137899 -431.876044) (xy 60.139426 -431.848343)
			(xy 60.14085 -431.834544) (xy 60.141104 -431.828956) (xy 60.141104 -430.750726) (xy 60.14085 -430.745138)
			(xy 60.139432 -430.731339) (xy 60.137909 -430.703637) (xy 60.137802 -430.689766) (xy 60.137903 -430.675894)
			(xy 60.139428 -430.648193) (xy 60.14085 -430.634394) (xy 60.141104 -430.628806) (xy 60.141104 -430.018952)
			(xy 60.141519 -430.006899) (xy 60.148965 -429.983971) (xy 60.163118 -429.964456) (xy 60.182597 -429.950254)
			(xy 60.205506 -429.94275) (xy 60.217558 -429.942244) (xy 61.157866 -429.942244) (xy 61.169954 -429.942736)
			(xy 61.192954 -429.950184) (xy 61.212535 -429.964364) (xy 61.226787 -429.983893) (xy 61.234319 -430.006866)
			(xy 61.234828 -430.018952) (xy 61.234828 -430.889918) (xy 62.137798 -430.889918) (xy 62.137895 -430.876046)
			(xy 62.139422 -430.848345) (xy 62.140846 -430.834546) (xy 62.1411 -430.828958) (xy 62.1411 -429.750728)
			(xy 62.140846 -429.74514) (xy 62.139428 -429.731341) (xy 62.137905 -429.703639) (xy 62.137798 -429.689768)
			(xy 62.137899 -429.675896) (xy 62.139424 -429.648195) (xy 62.140846 -429.634396) (xy 62.1411 -429.628808)
			(xy 62.1411 -429.018954) (xy 62.141572 -429.006841) (xy 62.149067 -428.983803) (xy 62.163311 -428.964205)
			(xy 62.18291 -428.949964) (xy 62.205949 -428.942471) (xy 62.218062 -428.941992) (xy 63.157862 -428.941992)
			(xy 63.16997 -428.942543) (xy 63.193004 -428.950015) (xy 63.212603 -428.964238) (xy 63.226847 -428.98382)
			(xy 63.234343 -429.006847) (xy 63.234824 -429.018954) (xy 63.234824 -431.560478) (xy 63.234421 -431.572603)
			(xy 63.22693 -431.595668) (xy 63.212675 -431.615287) (xy 63.193054 -431.629537) (xy 63.169987 -431.637023)
			(xy 63.157862 -431.63744) (xy 62.218062 -431.63744) (xy 62.205943 -431.63702) (xy 62.182895 -431.62952)
			(xy 62.163292 -431.615265) (xy 62.149053 -431.595651) (xy 62.14157 -431.572597) (xy 62.1411 -431.560478)
			(xy 62.1411 -430.950878) (xy 62.140846 -430.94529) (xy 62.139432 -430.93149) (xy 62.137907 -430.903789)
			(xy 62.137798 -430.889918) (xy 61.234828 -430.889918) (xy 61.234828 -431.889916) (xy 64.137794 -431.889916)
			(xy 64.137891 -431.876044) (xy 64.139418 -431.848343) (xy 64.140842 -431.834544) (xy 64.141096 -431.828956)
			(xy 64.141096 -430.750726) (xy 64.140842 -430.745138) (xy 64.139424 -430.731339) (xy 64.137901 -430.703637)
			(xy 64.137794 -430.689766) (xy 64.137895 -430.675894) (xy 64.13942 -430.648193) (xy 64.140842 -430.634394)
			(xy 64.141096 -430.628806) (xy 64.141096 -430.018952) (xy 64.141519 -430.0069) (xy 64.148964 -429.983973)
			(xy 64.163115 -429.964459) (xy 64.182592 -429.950257) (xy 64.205499 -429.942751) (xy 64.21755 -429.942244)
			(xy 65.157858 -429.942244) (xy 65.169946 -429.942743) (xy 65.192946 -429.950189) (xy 65.212527 -429.964367)
			(xy 65.226779 -429.983894) (xy 65.234311 -430.006866) (xy 65.23482 -430.018952) (xy 65.23482 -430.889918)
			(xy 66.13779 -430.889918) (xy 66.137887 -430.876046) (xy 66.139414 -430.848345) (xy 66.140838 -430.834546)
			(xy 66.141092 -430.828958) (xy 66.141092 -429.750728) (xy 66.140838 -429.74514) (xy 66.13942 -429.731341)
			(xy 66.137897 -429.703639) (xy 66.13779 -429.689768) (xy 66.137891 -429.675896) (xy 66.139416 -429.648195)
			(xy 66.140838 -429.634396) (xy 66.141092 -429.628808) (xy 66.141092 -429.018954) (xy 66.141572 -429.006842)
			(xy 66.149066 -428.983805) (xy 66.163308 -428.964208) (xy 66.182905 -428.949966) (xy 66.205942 -428.942472)
			(xy 66.218054 -428.941992) (xy 67.157854 -428.941992) (xy 67.169962 -428.94255) (xy 67.192996 -428.950019)
			(xy 67.212594 -428.96424) (xy 67.226839 -428.983822) (xy 67.234335 -429.006847) (xy 67.234816 -429.018954)
			(xy 67.234816 -431.560478) (xy 67.234421 -431.572604) (xy 67.226929 -431.59567) (xy 67.212672 -431.61529)
			(xy 67.193049 -431.62954) (xy 67.16998 -431.637024) (xy 67.157854 -431.63744) (xy 66.218054 -431.63744)
			(xy 66.205935 -431.637027) (xy 66.182886 -431.629525) (xy 66.163284 -431.615268) (xy 66.149044 -431.595653)
			(xy 66.141562 -431.572598) (xy 66.141092 -431.560478) (xy 66.141092 -430.950878) (xy 66.140838 -430.94529)
			(xy 66.139424 -430.93149) (xy 66.137899 -430.903789) (xy 66.13779 -430.889918) (xy 65.23482 -430.889918)
			(xy 65.23482 -431.889916) (xy 68.137786 -431.889916) (xy 68.137883 -431.876044) (xy 68.13941 -431.848343)
			(xy 68.140834 -431.834544) (xy 68.141088 -431.828956) (xy 68.141088 -430.750726) (xy 68.140834 -430.745138)
			(xy 68.139416 -430.731339) (xy 68.137893 -430.703637) (xy 68.137786 -430.689766) (xy 68.137887 -430.675894)
			(xy 68.139412 -430.648193) (xy 68.140834 -430.634394) (xy 68.141088 -430.628806) (xy 68.141088 -430.018952)
			(xy 68.141519 -430.0069) (xy 68.148963 -429.983975) (xy 68.163112 -429.964461) (xy 68.182587 -429.950259)
			(xy 68.205492 -429.942752) (xy 68.217542 -429.942244) (xy 69.15785 -429.942244) (xy 69.169937 -429.94275)
			(xy 69.192937 -429.950193) (xy 69.212518 -429.96437) (xy 69.22677 -429.983896) (xy 69.234303 -430.006866)
			(xy 69.234812 -430.018952) (xy 69.234812 -430.889918) (xy 70.137782 -430.889918) (xy 70.137879 -430.876046)
			(xy 70.139406 -430.848345) (xy 70.14083 -430.834546) (xy 70.141084 -430.828958) (xy 70.141084 -429.750728)
			(xy 70.14083 -429.74514) (xy 70.139412 -429.731341) (xy 70.137889 -429.703639) (xy 70.137782 -429.689768)
			(xy 70.137883 -429.675896) (xy 70.139408 -429.648195) (xy 70.14083 -429.634396) (xy 70.141084 -429.628808)
			(xy 70.141084 -429.018954) (xy 70.141473 -429.006832) (xy 70.148979 -428.98378) (xy 70.16324 -428.964175)
			(xy 70.182862 -428.949937) (xy 70.205924 -428.942459) (xy 70.218046 -428.941992) (xy 71.157846 -428.941992)
			(xy 71.169958 -428.942472) (xy 71.192995 -428.949966) (xy 71.212592 -428.964208) (xy 71.226834 -428.983805)
			(xy 71.234328 -429.006842) (xy 71.234808 -429.018954) (xy 71.234808 -431.560478) (xy 71.23427 -431.572587)
			(xy 71.226795 -431.595622) (xy 71.212568 -431.61522) (xy 71.192983 -431.629464) (xy 71.169954 -431.636959)
			(xy 71.157846 -431.63744) (xy 70.218046 -431.63744) (xy 70.205923 -431.637001) (xy 70.182862 -431.629518)
			(xy 70.163245 -431.615273) (xy 70.148993 -431.595659) (xy 70.141503 -431.5726) (xy 70.141084 -431.560478)
			(xy 70.141084 -430.950878) (xy 70.14083 -430.94529) (xy 70.139416 -430.93149) (xy 70.137891 -430.903789)
			(xy 70.137782 -430.889918) (xy 69.234812 -430.889918) (xy 69.234812 -431.889916) (xy 72.137778 -431.889916)
			(xy 72.137875 -431.876044) (xy 72.139402 -431.848343) (xy 72.140826 -431.834544) (xy 72.14108 -431.828956)
			(xy 72.14108 -430.750726) (xy 72.140826 -430.745138) (xy 72.139408 -430.731339) (xy 72.137885 -430.703637)
			(xy 72.137778 -430.689766) (xy 72.137879 -430.675894) (xy 72.139404 -430.648193) (xy 72.140826 -430.634394)
			(xy 72.14108 -430.628806) (xy 72.14108 -430.018952) (xy 72.141519 -430.006901) (xy 72.148962 -429.983977)
			(xy 72.163109 -429.964464) (xy 72.182582 -429.950262) (xy 72.205485 -429.942753) (xy 72.217534 -429.942244)
			(xy 73.157842 -429.942244) (xy 73.169934 -429.942672) (xy 73.192937 -429.95014) (xy 73.212516 -429.964337)
			(xy 73.226765 -429.983879) (xy 73.234296 -430.006861) (xy 73.234804 -430.018952) (xy 73.234804 -430.889918)
			(xy 75.138026 -430.889918) (xy 75.138123 -430.876046) (xy 75.13965 -430.848345) (xy 75.141074 -430.834546)
			(xy 75.141328 -430.828958) (xy 75.141328 -429.750728) (xy 75.141074 -429.74514) (xy 75.139656 -429.731341)
			(xy 75.138133 -429.703639) (xy 75.138026 -429.689768) (xy 75.138127 -429.675896) (xy 75.139652 -429.648195)
			(xy 75.141074 -429.634396) (xy 75.141328 -429.628808) (xy 75.141328 -429.018954) (xy 75.141768 -429.006863)
			(xy 75.149236 -428.983863) (xy 75.16343 -428.964285) (xy 75.182968 -428.950036) (xy 75.205947 -428.942503)
			(xy 75.218036 -428.941992) (xy 76.157836 -428.941992) (xy 76.169946 -428.942386) (xy 76.192973 -428.949894)
			(xy 76.212545 -428.964162) (xy 76.226738 -428.983787) (xy 76.23416 -429.006843) (xy 76.234544 -429.018954)
			(xy 76.234544 -431.560478) (xy 76.234074 -431.572568) (xy 76.226621 -431.595571) (xy 76.212436 -431.615152)
			(xy 76.192902 -431.629403) (xy 76.169924 -431.636933) (xy 76.157836 -431.63744) (xy 75.218036 -431.63744)
			(xy 75.205933 -431.636953) (xy 75.182914 -431.629469) (xy 75.163344 -431.615224) (xy 75.149146 -431.595619)
			(xy 75.141718 -431.572582) (xy 75.141328 -431.560478) (xy 75.141328 -430.950878) (xy 75.141074 -430.94529)
			(xy 75.13966 -430.93149) (xy 75.138135 -430.903789) (xy 75.138026 -430.889918) (xy 73.234804 -430.889918)
			(xy 73.234804 -431.889916) (xy 77.138022 -431.889916) (xy 77.138119 -431.876044) (xy 77.139646 -431.848343)
			(xy 77.14107 -431.834544) (xy 77.141324 -431.828956) (xy 77.141324 -430.750726) (xy 77.14107 -430.745138)
			(xy 77.139652 -430.731339) (xy 77.138129 -430.703637) (xy 77.138022 -430.689766) (xy 77.138123 -430.675894)
			(xy 77.139647 -430.648193) (xy 77.14107 -430.634394) (xy 77.141324 -430.628806) (xy 77.141324 -430.018952)
			(xy 77.141724 -430.006872) (xy 77.149203 -429.983898) (xy 77.163415 -429.964358) (xy 77.182969 -429.950167)
			(xy 77.205951 -429.942711) (xy 77.218032 -429.942244) (xy 78.157832 -429.942244) (xy 78.169903 -429.942736)
			(xy 78.192864 -429.950201) (xy 78.212396 -429.964393) (xy 78.226591 -429.983922) (xy 78.234062 -430.006881)
			(xy 78.23454 -430.018952) (xy 78.23454 -430.889918) (xy 79.138018 -430.889918) (xy 79.138115 -430.876046)
			(xy 79.139642 -430.848345) (xy 79.141066 -430.834546) (xy 79.14132 -430.828958) (xy 79.14132 -429.750728)
			(xy 79.141066 -429.74514) (xy 79.139648 -429.731341) (xy 79.138125 -429.703639) (xy 79.138018 -429.689768)
			(xy 79.138119 -429.675896) (xy 79.139644 -429.648195) (xy 79.141066 -429.634396) (xy 79.14132 -429.628808)
			(xy 79.14132 -429.018954) (xy 79.141768 -429.006864) (xy 79.149235 -428.983865) (xy 79.163427 -428.964288)
			(xy 79.182963 -428.950038) (xy 79.205939 -428.942504) (xy 79.218028 -428.941992) (xy 80.157828 -428.941992)
			(xy 80.169938 -428.942392) (xy 80.192964 -428.949899) (xy 80.212536 -428.964165) (xy 80.22673 -428.983789)
			(xy 80.234152 -429.006843) (xy 80.234536 -429.018954) (xy 80.234536 -431.560478) (xy 80.234073 -431.572569)
			(xy 80.22662 -431.595573) (xy 80.212433 -431.615155) (xy 80.192897 -431.629405) (xy 80.169917 -431.636934)
			(xy 80.157828 -431.63744) (xy 79.218028 -431.63744) (xy 79.205925 -431.63696) (xy 79.182905 -431.629473)
			(xy 79.163335 -431.615227) (xy 79.149138 -431.595621) (xy 79.141709 -431.572582) (xy 79.14132 -431.560478)
			(xy 79.14132 -430.950878) (xy 79.141066 -430.94529) (xy 79.139652 -430.93149) (xy 79.138127 -430.903789)
			(xy 79.138018 -430.889918) (xy 78.23454 -430.889918) (xy 78.23454 -431.889916) (xy 81.138014 -431.889916)
			(xy 81.138111 -431.876044) (xy 81.139638 -431.848343) (xy 81.141062 -431.834544) (xy 81.141316 -431.828956)
			(xy 81.141316 -430.750726) (xy 81.141062 -430.745138) (xy 81.139644 -430.731339) (xy 81.138121 -430.703637)
			(xy 81.138014 -430.689766) (xy 81.138115 -430.675894) (xy 81.139639 -430.648193) (xy 81.141062 -430.634394)
			(xy 81.141316 -430.628806) (xy 81.141316 -430.018952) (xy 81.141724 -430.006873) (xy 81.149202 -429.9839)
			(xy 81.163413 -429.964361) (xy 81.182964 -429.950169) (xy 81.205944 -429.942712) (xy 81.218024 -429.942244)
			(xy 82.157824 -429.942244) (xy 82.169895 -429.942743) (xy 82.192855 -429.950206) (xy 82.212387 -429.964396)
			(xy 82.226583 -429.983924) (xy 82.234053 -430.006881) (xy 82.234532 -430.018952) (xy 82.234532 -430.889918)
			(xy 83.13801 -430.889918) (xy 83.138107 -430.876046) (xy 83.139634 -430.848345) (xy 83.141058 -430.834546)
			(xy 83.141312 -430.828958) (xy 83.141312 -429.750728) (xy 83.141058 -429.74514) (xy 83.13964 -429.731341)
			(xy 83.138117 -429.703639) (xy 83.13801 -429.689768) (xy 83.138111 -429.675896) (xy 83.139636 -429.648195)
			(xy 83.141058 -429.634396) (xy 83.141312 -429.628808) (xy 83.141312 -429.018954) (xy 83.141768 -429.006865)
			(xy 83.149234 -428.983867) (xy 83.163424 -428.964291) (xy 83.182958 -428.950041) (xy 83.205932 -428.942505)
			(xy 83.21802 -428.941992) (xy 84.15782 -428.941992) (xy 84.169929 -428.942399) (xy 84.192956 -428.949903)
			(xy 84.212528 -428.964167) (xy 84.226722 -428.98379) (xy 84.234144 -429.006843) (xy 84.234528 -429.018954)
			(xy 84.234528 -431.560478) (xy 84.234073 -431.57257) (xy 84.226619 -431.595575) (xy 84.21243 -431.615158)
			(xy 84.192892 -431.629408) (xy 84.16991 -431.636935) (xy 84.15782 -431.63744) (xy 83.21802 -431.63744)
			(xy 83.205916 -431.636967) (xy 83.182896 -431.629478) (xy 83.163327 -431.61523) (xy 83.14913 -431.595622)
			(xy 83.141701 -431.572583) (xy 83.141312 -431.560478) (xy 83.141312 -430.950878) (xy 83.141058 -430.94529)
			(xy 83.139644 -430.93149) (xy 83.138119 -430.903789) (xy 83.13801 -430.889918) (xy 82.234532 -430.889918)
			(xy 82.234532 -431.889916) (xy 85.138006 -431.889916) (xy 85.138103 -431.876044) (xy 85.13963 -431.848343)
			(xy 85.141054 -431.834544) (xy 85.141308 -431.828956) (xy 85.141308 -430.750726) (xy 85.141054 -430.745138)
			(xy 85.139636 -430.731339) (xy 85.138113 -430.703637) (xy 85.138006 -430.689766) (xy 85.138107 -430.675894)
			(xy 85.139631 -430.648193) (xy 85.141054 -430.634394) (xy 85.141308 -430.628806) (xy 85.141308 -430.018952)
			(xy 85.141723 -430.006873) (xy 85.149201 -429.983902) (xy 85.16341 -429.964364) (xy 85.182959 -429.950172)
			(xy 85.205937 -429.942713) (xy 85.218016 -429.942244) (xy 86.157816 -429.942244) (xy 86.169887 -429.94275)
			(xy 86.192846 -429.950211) (xy 86.212379 -429.964399) (xy 86.226574 -429.983925) (xy 86.234045 -430.006882)
			(xy 86.234524 -430.018952) (xy 86.234524 -430.889918) (xy 87.138002 -430.889918) (xy 87.138099 -430.876046)
			(xy 87.139626 -430.848345) (xy 87.14105 -430.834546) (xy 87.141304 -430.828958) (xy 87.141304 -429.750728)
			(xy 87.14105 -429.74514) (xy 87.139632 -429.731341) (xy 87.138109 -429.703639) (xy 87.138002 -429.689768)
			(xy 87.138103 -429.675896) (xy 87.139628 -429.648195) (xy 87.14105 -429.634396) (xy 87.141304 -429.628808)
			(xy 87.141304 -429.018954) (xy 87.141767 -429.006866) (xy 87.149232 -428.98387) (xy 87.163421 -428.964293)
			(xy 87.182953 -428.950043) (xy 87.205925 -428.942506) (xy 87.218012 -428.941992) (xy 88.157812 -428.941992)
			(xy 88.169921 -428.942406) (xy 88.192947 -428.949908) (xy 88.212519 -428.96417) (xy 88.226714 -428.983792)
			(xy 88.234136 -429.006844) (xy 88.23452 -429.018954) (xy 88.23452 -431.560478) (xy 88.234073 -431.57257)
			(xy 88.226618 -431.595577) (xy 88.212427 -431.615161) (xy 88.192887 -431.629411) (xy 88.169903 -431.636936)
			(xy 88.157812 -431.63744) (xy 87.218012 -431.63744) (xy 87.205908 -431.636974) (xy 87.182888 -431.629483)
			(xy 87.163318 -431.615232) (xy 87.149122 -431.595624) (xy 87.141693 -431.572583) (xy 87.141304 -431.560478)
			(xy 87.141304 -430.950878) (xy 87.14105 -430.94529) (xy 87.139636 -430.93149) (xy 87.138111 -430.903789)
			(xy 87.138002 -430.889918) (xy 86.234524 -430.889918) (xy 86.234524 -431.889916) (xy 89.137998 -431.889916)
			(xy 89.138095 -431.876044) (xy 89.139622 -431.848343) (xy 89.141046 -431.834544) (xy 89.1413 -431.828956)
			(xy 89.1413 -430.750726) (xy 89.141046 -430.745138) (xy 89.139628 -430.731339) (xy 89.138105 -430.703637)
			(xy 89.137998 -430.689766) (xy 89.138099 -430.675894) (xy 89.139624 -430.648193) (xy 89.141046 -430.634394)
			(xy 89.1413 -430.628806) (xy 89.1413 -430.018952) (xy 89.141723 -430.006874) (xy 89.1492 -429.983904)
			(xy 89.163407 -429.964367) (xy 89.182954 -429.950174) (xy 89.20593 -429.942714) (xy 89.218008 -429.942244)
			(xy 90.157808 -429.942244) (xy 90.169878 -429.942757) (xy 90.192837 -429.950216) (xy 90.21237 -429.964401)
			(xy 90.226566 -429.983927) (xy 90.234037 -430.006882) (xy 90.234516 -430.018952) (xy 90.234516 -431.360072)
			(xy 108.40466 -431.360072) (xy 108.405158 -431.275192) (xy 108.413115 -431.105619) (xy 108.429011 -430.936605)
			(xy 108.452812 -430.768522) (xy 108.484466 -430.601739) (xy 108.523902 -430.436623) (xy 108.571034 -430.273538)
			(xy 108.625758 -430.11284) (xy 108.687955 -429.954885) (xy 108.757487 -429.800018) (xy 108.834202 -429.648581)
			(xy 108.91793 -429.500905) (xy 109.008488 -429.357317) (xy 109.105677 -429.218131) (xy 109.209284 -429.083654)
			(xy 109.319079 -428.954181) (xy 109.434823 -428.829996) (xy 109.55626 -428.711373) (xy 109.683124 -428.598572)
			(xy 109.815135 -428.491842) (xy 109.952005 -428.391417) (xy 110.09343 -428.297518) (xy 110.239102 -428.21035)
			(xy 110.3887 -428.130107) (xy 110.541894 -428.056963) (xy 110.698348 -427.991081) (xy 110.857718 -427.932604)
			(xy 111.019654 -427.881662) (xy 111.1838 -427.838366) (xy 111.349795 -427.802811) (xy 111.517274 -427.775076)
			(xy 111.685869 -427.755222) (xy 111.855209 -427.743292) (xy 112.024922 -427.739313) (xy 112.194635 -427.743292)
			(xy 112.363975 -427.755222) (xy 112.53257 -427.775076) (xy 112.700049 -427.802811) (xy 112.866044 -427.838366)
			(xy 113.03019 -427.881662) (xy 113.192126 -427.932604) (xy 113.351496 -427.991081) (xy 113.50795 -428.056963)
			(xy 113.661144 -428.130107) (xy 113.810742 -428.21035) (xy 113.943382 -428.28972) (xy 127.237744 -428.28972)
			(xy 127.237856 -428.275337) (xy 127.239509 -428.246617) (xy 127.241046 -428.232316) (xy 127.2413 -428.226474)
			(xy 127.2413 -427.15307) (xy 127.241046 -427.147228) (xy 127.239517 -427.132926) (xy 127.237866 -427.104207)
			(xy 127.237744 -427.089824) (xy 127.237856 -427.075441) (xy 127.239509 -427.046721) (xy 127.241046 -427.03242)
			(xy 127.2413 -427.026578) (xy 127.2413 -426.41901) (xy 127.241815 -426.406925) (xy 127.249264 -426.383931)
			(xy 127.26344 -426.364355) (xy 127.282961 -426.350103) (xy 127.305925 -426.342563) (xy 127.318008 -426.342048)
			(xy 128.257808 -426.342048) (xy 128.269912 -426.342509) (xy 128.292931 -426.350004) (xy 128.312499 -426.364256)
			(xy 128.326696 -426.383865) (xy 128.334125 -426.406905) (xy 128.334516 -426.41901) (xy 128.334516 -427.289976)
			(xy 129.23774 -427.289976) (xy 129.237856 -427.275593) (xy 129.239507 -427.246874) (xy 129.241042 -427.232572)
			(xy 129.241296 -427.22673) (xy 129.241296 -426.153072) (xy 129.241042 -426.14723) (xy 129.239513 -426.132928)
			(xy 129.237862 -426.104209) (xy 129.23774 -426.089826) (xy 129.237852 -426.075443) (xy 129.239506 -426.046723)
			(xy 129.241042 -426.032422) (xy 129.241296 -426.02658) (xy 129.241296 -425.419012) (xy 129.241723 -425.40693)
			(xy 129.249188 -425.383947) (xy 129.26339 -425.364396) (xy 129.282939 -425.350191) (xy 129.305922 -425.342724)
			(xy 129.318004 -425.342304) (xy 130.257804 -425.342304) (xy 130.269888 -425.342709) (xy 130.292873 -425.350179)
			(xy 130.312424 -425.364387) (xy 130.326628 -425.383941) (xy 130.334093 -425.406928) (xy 130.334512 -425.419012)
			(xy 130.334512 -427.960536) (xy 130.334067 -427.972612) (xy 130.326595 -427.99558) (xy 130.312393 -428.015116)
			(xy 130.292851 -428.029309) (xy 130.26988 -428.036772) (xy 130.257804 -428.037244) (xy 129.318004 -428.037244)
			(xy 129.305933 -428.036733) (xy 129.282972 -428.029276) (xy 129.263438 -428.01509) (xy 129.249242 -427.995564)
			(xy 129.241773 -427.972607) (xy 129.241296 -427.960536) (xy 129.241296 -427.353222) (xy 129.241042 -427.34738)
			(xy 129.239517 -427.333078) (xy 129.237864 -427.304359) (xy 129.23774 -427.289976) (xy 128.334516 -427.289976)
			(xy 128.334516 -428.28972) (xy 131.237736 -428.28972) (xy 131.237848 -428.275337) (xy 131.239501 -428.246617)
			(xy 131.241038 -428.232316) (xy 131.241292 -428.226474) (xy 131.241292 -427.15307) (xy 131.241038 -427.147228)
			(xy 131.239508 -427.132926) (xy 131.237858 -427.104207) (xy 131.237736 -427.089824) (xy 131.237848 -427.075441)
			(xy 131.239501 -427.046721) (xy 131.241038 -427.03242) (xy 131.241292 -427.026578) (xy 131.241292 -426.41901)
			(xy 131.241815 -426.406926) (xy 131.249263 -426.383934) (xy 131.263437 -426.364358) (xy 131.282956 -426.350105)
			(xy 131.305918 -426.342564) (xy 131.318 -426.342048) (xy 132.2578 -426.342048) (xy 132.269904 -426.342515)
			(xy 132.292922 -426.350009) (xy 132.312491 -426.364259) (xy 132.326687 -426.383866) (xy 132.334117 -426.406905)
			(xy 132.334508 -426.41901) (xy 132.334508 -427.289976) (xy 133.237732 -427.289976) (xy 133.237848 -427.275593)
			(xy 133.239499 -427.246874) (xy 133.241034 -427.232572) (xy 133.241288 -427.22673) (xy 133.241288 -426.153072)
			(xy 133.241034 -426.14723) (xy 133.239505 -426.132928) (xy 133.237854 -426.104209) (xy 133.237732 -426.089826)
			(xy 133.237844 -426.075443) (xy 133.239498 -426.046723) (xy 133.241034 -426.032422) (xy 133.241288 -426.02658)
			(xy 133.241288 -425.419012) (xy 133.241723 -425.40693) (xy 133.249187 -425.383949) (xy 133.263387 -425.364399)
			(xy 133.282934 -425.350194) (xy 133.305914 -425.342726) (xy 133.317996 -425.342304) (xy 134.257796 -425.342304)
			(xy 134.26988 -425.342716) (xy 134.292864 -425.350184) (xy 134.312416 -425.36439) (xy 134.32662 -425.383943)
			(xy 134.334085 -425.406928) (xy 134.334504 -425.419012) (xy 134.334504 -427.960536) (xy 134.334067 -427.972613)
			(xy 134.326594 -427.995582) (xy 134.31239 -428.015119) (xy 134.292846 -428.029312) (xy 134.269873 -428.036773)
			(xy 134.257796 -428.037244) (xy 133.317996 -428.037244) (xy 133.305925 -428.03674) (xy 133.282964 -428.02928)
			(xy 133.26343 -428.015093) (xy 133.249234 -427.995565) (xy 133.241765 -427.972607) (xy 133.241288 -427.960536)
			(xy 133.241288 -427.353222) (xy 133.241034 -427.34738) (xy 133.239509 -427.333078) (xy 133.237856 -427.304359)
			(xy 133.237732 -427.289976) (xy 132.334508 -427.289976) (xy 132.334508 -428.28972) (xy 135.237728 -428.28972)
			(xy 135.23784 -428.275337) (xy 135.239493 -428.246617) (xy 135.24103 -428.232316) (xy 135.241284 -428.226474)
			(xy 135.241284 -427.15307) (xy 135.24103 -427.147228) (xy 135.2395 -427.132926) (xy 135.23785 -427.104207)
			(xy 135.237728 -427.089824) (xy 135.23784 -427.075441) (xy 135.239494 -427.046721) (xy 135.24103 -427.03242)
			(xy 135.241284 -427.026578) (xy 135.241284 -426.41901) (xy 135.241717 -426.406917) (xy 135.249176 -426.383909)
			(xy 135.26337 -426.364325) (xy 135.282914 -426.350076) (xy 135.3059 -426.342551) (xy 135.317992 -426.342048)
			(xy 136.257792 -426.342048) (xy 136.269895 -426.342522) (xy 136.292914 -426.350013) (xy 136.312482 -426.364262)
			(xy 136.326679 -426.383868) (xy 136.334109 -426.406906) (xy 136.3345 -426.41901) (xy 136.3345 -427.289976)
			(xy 137.237724 -427.289976) (xy 137.237841 -427.275593) (xy 137.239491 -427.246874) (xy 137.241026 -427.232572)
			(xy 137.24128 -427.22673) (xy 137.24128 -426.153072) (xy 137.241026 -426.14723) (xy 137.239497 -426.132928)
			(xy 137.237846 -426.104209) (xy 137.237724 -426.089826) (xy 137.237836 -426.075443) (xy 137.23949 -426.046723)
			(xy 137.241026 -426.032422) (xy 137.24128 -426.02658) (xy 137.24128 -425.419012) (xy 137.241774 -425.406939)
			(xy 137.249232 -425.383974) (xy 137.263421 -425.364438) (xy 137.282953 -425.350243) (xy 137.305915 -425.342778)
			(xy 137.317988 -425.342304) (xy 138.257788 -425.342304) (xy 138.269871 -425.342723) (xy 138.292856 -425.350189)
			(xy 138.312407 -425.364393) (xy 138.326611 -425.383944) (xy 138.334077 -425.406929) (xy 138.334496 -425.419012)
			(xy 138.334496 -427.960536) (xy 138.334066 -427.972614) (xy 138.326593 -427.995584) (xy 138.312387 -428.015122)
			(xy 138.292841 -428.029315) (xy 138.269866 -428.036774) (xy 138.257788 -428.037244) (xy 137.317988 -428.037244)
			(xy 137.305916 -428.036746) (xy 137.282955 -428.029285) (xy 137.263421 -428.015096) (xy 137.249226 -427.995567)
			(xy 137.241757 -427.972607) (xy 137.24128 -427.960536) (xy 137.24128 -427.353222) (xy 137.241026 -427.34738)
			(xy 137.239501 -427.333078) (xy 137.237848 -427.304359) (xy 137.237724 -427.289976) (xy 136.3345 -427.289976)
			(xy 136.3345 -428.28972) (xy 139.23772 -428.28972) (xy 139.237832 -428.275337) (xy 139.239485 -428.246617)
			(xy 139.241022 -428.232316) (xy 139.241276 -428.226474) (xy 139.241276 -427.15307) (xy 139.241022 -427.147228)
			(xy 139.239492 -427.132926) (xy 139.237842 -427.104207) (xy 139.23772 -427.089824) (xy 139.237832 -427.075441)
			(xy 139.239486 -427.046721) (xy 139.241022 -427.03242) (xy 139.241276 -427.026578) (xy 139.241276 -426.41901)
			(xy 139.241717 -426.406917) (xy 139.249175 -426.383911) (xy 139.263367 -426.364328) (xy 139.282909 -426.350078)
			(xy 139.305893 -426.342553) (xy 139.317984 -426.342048) (xy 140.257784 -426.342048) (xy 140.269887 -426.342529)
			(xy 140.292905 -426.350018) (xy 140.312473 -426.364265) (xy 140.32667 -426.383869) (xy 140.334101 -426.406906)
			(xy 140.334492 -426.41901) (xy 140.334492 -427.289976) (xy 142.238476 -427.289976) (xy 142.238541 -427.277829)
			(xy 142.239687 -427.253562) (xy 142.240762 -427.241462) (xy 142.241016 -427.236636) (xy 142.241016 -426.143166)
			(xy 142.240762 -426.13834) (xy 142.239685 -426.12624) (xy 142.238541 -426.101973) (xy 142.238476 -426.089826)
			(xy 142.238545 -426.077679) (xy 142.239688 -426.053412) (xy 142.240762 -426.041312) (xy 142.241016 -426.036486)
			(xy 142.241016 -425.419012) (xy 142.24147 -425.406961) (xy 142.248902 -425.384033) (xy 142.263043 -425.364516)
			(xy 142.282516 -425.350313) (xy 142.30542 -425.342809) (xy 142.31747 -425.342304) (xy 143.257778 -425.342304)
			(xy 143.269863 -425.342825) (xy 143.292857 -425.350272) (xy 143.312434 -425.364446) (xy 143.326686 -425.383966)
			(xy 143.334225 -425.406929) (xy 143.33474 -425.419012) (xy 143.33474 -427.960536) (xy 143.334272 -427.972584)
			(xy 143.326834 -427.995504) (xy 143.312694 -428.015016) (xy 143.293228 -428.029219) (xy 143.270333 -428.036732)
			(xy 143.258286 -428.037244) (xy 142.317978 -428.037244) (xy 142.305886 -428.036811) (xy 142.282882 -428.029347)
			(xy 142.263301 -428.015152) (xy 142.249051 -427.99561) (xy 142.241523 -427.972627) (xy 142.241016 -427.960536)
			(xy 142.241016 -427.343316) (xy 142.240762 -427.33849) (xy 142.239681 -427.326391) (xy 142.238539 -427.302123)
			(xy 142.238476 -427.289976) (xy 140.334492 -427.289976) (xy 140.334492 -428.28972) (xy 144.238472 -428.28972)
			(xy 144.238541 -428.277573) (xy 144.239684 -428.253306) (xy 144.240758 -428.241206) (xy 144.241012 -428.23638)
			(xy 144.241012 -427.143164) (xy 144.240758 -427.138338) (xy 144.239681 -427.126239) (xy 144.238537 -427.101971)
			(xy 144.238472 -427.089824) (xy 144.238541 -427.077677) (xy 144.239684 -427.05341) (xy 144.240758 -427.04131)
			(xy 144.241012 -427.036484) (xy 144.241012 -426.41901) (xy 144.24152 -426.406899) (xy 144.249001 -426.38386)
			(xy 144.263235 -426.36426) (xy 144.282828 -426.350018) (xy 144.305863 -426.342526) (xy 144.317974 -426.342048)
			(xy 145.257774 -426.342048) (xy 145.269896 -426.342482) (xy 145.292956 -426.349969) (xy 145.312572 -426.364216)
			(xy 145.326824 -426.38383) (xy 145.334315 -426.406888) (xy 145.334736 -426.41901) (xy 145.334736 -427.289976)
			(xy 146.238468 -427.289976) (xy 146.238533 -427.277829) (xy 146.239679 -427.253562) (xy 146.240754 -427.241462)
			(xy 146.241008 -427.236636) (xy 146.241008 -426.143166) (xy 146.240754 -426.13834) (xy 146.239677 -426.12624)
			(xy 146.238533 -426.101973) (xy 146.238468 -426.089826) (xy 146.238537 -426.077679) (xy 146.23968 -426.053412)
			(xy 146.240754 -426.041312) (xy 146.241008 -426.036486) (xy 146.241008 -425.419012) (xy 146.24147 -425.406962)
			(xy 146.248901 -425.384035) (xy 146.263041 -425.364518) (xy 146.282511 -425.350315) (xy 146.305413 -425.34281)
			(xy 146.317462 -425.342304) (xy 147.25777 -425.342304) (xy 147.269854 -425.342832) (xy 147.292848 -425.350276)
			(xy 147.312425 -425.364448) (xy 147.326678 -425.383967) (xy 147.334217 -425.40693) (xy 147.334732 -425.419012)
			(xy 147.334732 -427.960536) (xy 147.334272 -427.972585) (xy 147.326833 -427.995506) (xy 147.312691 -428.015019)
			(xy 147.293223 -428.029222) (xy 147.270325 -428.036733) (xy 147.258278 -428.037244) (xy 146.31797 -428.037244)
			(xy 146.305877 -428.036818) (xy 146.282873 -428.029351) (xy 146.263292 -428.015154) (xy 146.249043 -427.995612)
			(xy 146.241515 -427.972627) (xy 146.241008 -427.960536) (xy 146.241008 -427.343316) (xy 146.240754 -427.33849)
			(xy 146.239673 -427.326391) (xy 146.238531 -427.302123) (xy 146.238468 -427.289976) (xy 145.334736 -427.289976)
			(xy 145.334736 -428.28972) (xy 148.238464 -428.28972) (xy 148.238533 -428.277573) (xy 148.239676 -428.253306)
			(xy 148.24075 -428.241206) (xy 148.241004 -428.23638) (xy 148.241004 -427.143164) (xy 148.24075 -427.138338)
			(xy 148.239673 -427.126239) (xy 148.238529 -427.101971) (xy 148.238464 -427.089824) (xy 148.238533 -427.077677)
			(xy 148.239676 -427.05341) (xy 148.24075 -427.04131) (xy 148.241004 -427.036484) (xy 148.241004 -426.41901)
			(xy 148.24152 -426.406899) (xy 148.249 -426.383862) (xy 148.263232 -426.364263) (xy 148.282823 -426.35002)
			(xy 148.305856 -426.342527) (xy 148.317966 -426.342048) (xy 149.257766 -426.342048) (xy 149.269888 -426.342489)
			(xy 149.292947 -426.349973) (xy 149.312564 -426.364219) (xy 149.326816 -426.383831) (xy 149.334307 -426.406888)
			(xy 149.334728 -426.41901) (xy 149.334728 -427.289976) (xy 150.23846 -427.289976) (xy 150.238525 -427.277829)
			(xy 150.239671 -427.253562) (xy 150.240746 -427.241462) (xy 150.241 -427.236636) (xy 150.241 -426.143166)
			(xy 150.240746 -426.13834) (xy 150.239669 -426.126241) (xy 150.238525 -426.101973) (xy 150.23846 -426.089826)
			(xy 150.238529 -426.077679) (xy 150.239672 -426.053412) (xy 150.240746 -426.041312) (xy 150.241 -426.036486)
			(xy 150.241 -425.419012) (xy 150.24147 -425.406962) (xy 150.2489 -425.384037) (xy 150.263038 -425.364521)
			(xy 150.282506 -425.350318) (xy 150.305406 -425.342811) (xy 150.317454 -425.342304) (xy 151.257762 -425.342304)
			(xy 151.269846 -425.342839) (xy 151.292839 -425.350281) (xy 151.312417 -425.364451) (xy 151.32667 -425.383968)
			(xy 151.334209 -425.40693) (xy 151.334724 -425.419012) (xy 151.334724 -427.960536) (xy 151.334271 -427.972586)
			(xy 151.326832 -427.995508) (xy 151.312688 -428.015022) (xy 151.293218 -428.029225) (xy 151.270318 -428.036734)
			(xy 151.25827 -428.037244) (xy 150.317962 -428.037244) (xy 150.305869 -428.036825) (xy 150.282864 -428.029356)
			(xy 150.263284 -428.015157) (xy 150.249035 -427.995613) (xy 150.241507 -427.972628) (xy 150.241 -427.960536)
			(xy 150.241 -427.343316) (xy 150.240746 -427.33849) (xy 150.239665 -427.326391) (xy 150.238523 -427.302123)
			(xy 150.23846 -427.289976) (xy 149.334728 -427.289976) (xy 149.334728 -428.28972) (xy 152.238456 -428.28972)
			(xy 152.238525 -428.277573) (xy 152.239668 -428.253306) (xy 152.240742 -428.241206) (xy 152.240996 -428.23638)
			(xy 152.240996 -427.143164) (xy 152.240742 -427.138338) (xy 152.239665 -427.126239) (xy 152.238521 -427.101971)
			(xy 152.238456 -427.089824) (xy 152.238525 -427.077677) (xy 152.239668 -427.05341) (xy 152.240742 -427.04131)
			(xy 152.240996 -427.036484) (xy 152.240996 -426.41901) (xy 152.24152 -426.4069) (xy 152.248999 -426.383864)
			(xy 152.263229 -426.364266) (xy 152.282818 -426.350023) (xy 152.305848 -426.342528) (xy 152.317958 -426.342048)
			(xy 153.257758 -426.342048) (xy 153.26988 -426.342496) (xy 153.292939 -426.349978) (xy 153.312555 -426.364222)
			(xy 153.326808 -426.383833) (xy 153.334299 -426.406889) (xy 153.33472 -426.41901) (xy 153.33472 -427.289976)
			(xy 154.238452 -427.289976) (xy 154.238518 -427.277829) (xy 154.239663 -427.253562) (xy 154.240738 -427.241462)
			(xy 154.240992 -427.236636) (xy 154.240992 -426.143166) (xy 154.240738 -426.13834) (xy 154.239661 -426.126241)
			(xy 154.238517 -426.101973) (xy 154.238452 -426.089826) (xy 154.238521 -426.077679) (xy 154.239664 -426.053412)
			(xy 154.240738 -426.041312) (xy 154.240992 -426.036486) (xy 154.240992 -425.419012) (xy 154.24147 -425.406963)
			(xy 154.248898 -425.384039) (xy 154.263035 -425.364524) (xy 154.282501 -425.35032) (xy 154.305399 -425.342812)
			(xy 154.317446 -425.342304) (xy 155.257754 -425.342304) (xy 155.269838 -425.342846) (xy 155.292831 -425.350286)
			(xy 155.312408 -425.364454) (xy 155.326662 -425.38397) (xy 155.334201 -425.40693) (xy 155.334716 -425.419012)
			(xy 155.334716 -427.960536) (xy 155.334271 -427.972587) (xy 155.326831 -427.995511) (xy 155.312685 -428.015024)
			(xy 155.293213 -428.029227) (xy 155.270311 -428.036735) (xy 155.258262 -428.037244) (xy 154.317954 -428.037244)
			(xy 154.30586 -428.036832) (xy 154.282856 -428.02936) (xy 154.263275 -428.01516) (xy 154.249027 -427.995615)
			(xy 154.241499 -427.972628) (xy 154.240992 -427.960536) (xy 154.240992 -427.343316) (xy 154.240738 -427.33849)
			(xy 154.239657 -427.326391) (xy 154.238515 -427.302123) (xy 154.238452 -427.289976) (xy 153.33472 -427.289976)
			(xy 153.33472 -428.28972) (xy 156.238448 -428.28972) (xy 156.238517 -428.277573) (xy 156.23966 -428.253306)
			(xy 156.240734 -428.241206) (xy 156.240988 -428.23638) (xy 156.240988 -427.143164) (xy 156.240734 -427.138338)
			(xy 156.239657 -427.126239) (xy 156.238513 -427.101971) (xy 156.238448 -427.089824) (xy 156.238517 -427.077677)
			(xy 156.23966 -427.05341) (xy 156.240734 -427.04131) (xy 156.240988 -427.036484) (xy 156.240988 -426.41901)
			(xy 156.24152 -426.406901) (xy 156.248998 -426.383867) (xy 156.263226 -426.364269) (xy 156.282813 -426.350025)
			(xy 156.305841 -426.342529) (xy 156.31795 -426.342048) (xy 157.25775 -426.342048) (xy 157.269868 -426.342469)
			(xy 157.292915 -426.349972) (xy 157.312516 -426.364226) (xy 157.326756 -426.383839) (xy 157.33424 -426.406891)
			(xy 157.334712 -426.41901) (xy 157.334712 -428.960534) (xy 157.334218 -428.972645) (xy 157.326728 -428.995681)
			(xy 157.31249 -429.015278) (xy 157.292896 -429.02952) (xy 157.269861 -429.037016) (xy 157.25775 -429.037496)
			(xy 156.31795 -429.037496) (xy 156.305836 -429.037031) (xy 156.282797 -429.029535) (xy 156.263199 -429.015289)
			(xy 156.248958 -428.995689) (xy 156.241466 -428.972648) (xy 156.240988 -428.960534) (xy 156.240988 -428.34306)
			(xy 156.240734 -428.338234) (xy 156.239656 -428.326135) (xy 156.238513 -428.301867) (xy 156.238448 -428.28972)
			(xy 153.33472 -428.28972) (xy 153.33472 -428.960534) (xy 153.334369 -428.972663) (xy 153.326862 -428.99573)
			(xy 153.312594 -429.015348) (xy 153.292962 -429.029597) (xy 153.269887 -429.03708) (xy 153.257758 -429.037496)
			(xy 152.317958 -429.037496) (xy 152.305845 -429.037025) (xy 152.282806 -429.02953) (xy 152.263208 -429.015287)
			(xy 152.248966 -428.995687) (xy 152.241474 -428.972647) (xy 152.240996 -428.960534) (xy 152.240996 -428.34306)
			(xy 152.240742 -428.338234) (xy 152.239664 -428.326135) (xy 152.238521 -428.301867) (xy 152.238456 -428.28972)
			(xy 149.334728 -428.28972) (xy 149.334728 -428.960534) (xy 149.334317 -428.972654) (xy 149.326816 -428.995704)
			(xy 149.31256 -429.015308) (xy 149.292943 -429.029547) (xy 149.269886 -429.037027) (xy 149.257766 -429.037496)
			(xy 148.317966 -429.037496) (xy 148.305853 -429.037018) (xy 148.282814 -429.029525) (xy 148.263216 -429.015284)
			(xy 148.248975 -428.995686) (xy 148.241482 -428.972647) (xy 148.241004 -428.960534) (xy 148.241004 -428.34306)
			(xy 148.24075 -428.338234) (xy 148.239672 -428.326135) (xy 148.238529 -428.301867) (xy 148.238464 -428.28972)
			(xy 145.334736 -428.28972) (xy 145.334736 -428.960534) (xy 145.334317 -428.972653) (xy 145.326817 -428.995702)
			(xy 145.312562 -429.015305) (xy 145.292948 -429.029545) (xy 145.269893 -429.037026) (xy 145.257774 -429.037496)
			(xy 144.317974 -429.037496) (xy 144.305861 -429.037011) (xy 144.282823 -429.029521) (xy 144.263225 -429.015281)
			(xy 144.248983 -428.995684) (xy 144.24149 -428.972646) (xy 144.241012 -428.960534) (xy 144.241012 -428.34306)
			(xy 144.240758 -428.338234) (xy 144.23968 -428.326135) (xy 144.238537 -428.301867) (xy 144.238472 -428.28972)
			(xy 140.334492 -428.28972) (xy 140.334492 -428.960534) (xy 140.334022 -428.972622) (xy 140.32656 -428.995619)
			(xy 140.312373 -429.015195) (xy 140.292843 -429.029446) (xy 140.269871 -429.036983) (xy 140.257784 -429.037496)
			(xy 139.317984 -429.037496) (xy 139.305874 -429.037097) (xy 139.282845 -429.029593) (xy 139.263272 -429.015327)
			(xy 139.249078 -428.995702) (xy 139.241659 -428.972646) (xy 139.241276 -428.960534) (xy 139.241276 -428.352966)
			(xy 139.241022 -428.347124) (xy 139.239492 -428.332822) (xy 139.237842 -428.304103) (xy 139.23772 -428.28972)
			(xy 136.3345 -428.28972) (xy 136.3345 -428.960534) (xy 136.334022 -428.972621) (xy 136.326561 -428.995616)
			(xy 136.312376 -429.015192) (xy 136.292848 -429.029443) (xy 136.269878 -429.036981) (xy 136.257792 -429.037496)
			(xy 135.317992 -429.037496) (xy 135.305882 -429.037091) (xy 135.282854 -429.029588) (xy 135.263281 -429.015324)
			(xy 135.249086 -428.9957) (xy 135.241667 -428.972645) (xy 135.241284 -428.960534) (xy 135.241284 -428.352966)
			(xy 135.24103 -428.347124) (xy 135.2395 -428.332822) (xy 135.23785 -428.304103) (xy 135.237728 -428.28972)
			(xy 132.334508 -428.28972) (xy 132.334508 -428.960534) (xy 132.334023 -428.972621) (xy 132.326562 -428.995614)
			(xy 132.312379 -429.01519) (xy 132.292853 -429.029441) (xy 132.269885 -429.03698) (xy 132.2578 -429.037496)
			(xy 131.318 -429.037496) (xy 131.305891 -429.037084) (xy 131.282863 -429.029584) (xy 131.263289 -429.015321)
			(xy 131.249095 -428.995699) (xy 131.241675 -428.972645) (xy 131.241292 -428.960534) (xy 131.241292 -428.352966)
			(xy 131.241038 -428.347124) (xy 131.239508 -428.332822) (xy 131.237858 -428.304103) (xy 131.237736 -428.28972)
			(xy 128.334516 -428.28972) (xy 128.334516 -428.960534) (xy 128.334121 -428.97263) (xy 128.326649 -428.995639)
			(xy 128.312446 -429.015222) (xy 128.292895 -429.02947) (xy 128.269903 -429.036993) (xy 128.257808 -429.037496)
			(xy 127.318008 -429.037496) (xy 127.305899 -429.037077) (xy 127.282871 -429.029579) (xy 127.263298 -429.015319)
			(xy 127.249103 -428.995697) (xy 127.241683 -428.972644) (xy 127.2413 -428.960534) (xy 127.2413 -428.352966)
			(xy 127.241046 -428.347124) (xy 127.239516 -428.332822) (xy 127.237866 -428.304103) (xy 127.237744 -428.28972)
			(xy 113.943382 -428.28972) (xy 113.956414 -428.297518) (xy 114.097839 -428.391417) (xy 114.234709 -428.491842)
			(xy 114.36672 -428.598572) (xy 114.493584 -428.711373) (xy 114.615021 -428.829996) (xy 114.730765 -428.954181)
			(xy 114.84056 -429.083654) (xy 114.944167 -429.218131) (xy 115.041356 -429.357317) (xy 115.131914 -429.500905)
			(xy 115.215642 -429.648581) (xy 115.292357 -429.800018) (xy 115.361889 -429.954885) (xy 115.424086 -430.11284)
			(xy 115.47881 -430.273538) (xy 115.525942 -430.436623) (xy 115.565378 -430.601739) (xy 115.597032 -430.768522)
			(xy 115.614222 -430.889918) (xy 125.237748 -430.889918) (xy 125.23786 -430.875535) (xy 125.239514 -430.846815)
			(xy 125.24105 -430.832514) (xy 125.241304 -430.826672) (xy 125.241304 -429.753014) (xy 125.24105 -429.747172)
			(xy 125.239524 -429.73287) (xy 125.237871 -429.704151) (xy 125.237748 -429.689768) (xy 125.237864 -429.675385)
			(xy 125.239515 -429.646666) (xy 125.24105 -429.632364) (xy 125.241304 -429.626522) (xy 125.241304 -429.018954)
			(xy 125.241767 -429.006866) (xy 125.249232 -428.98387) (xy 125.263421 -428.964293) (xy 125.282953 -428.950043)
			(xy 125.305925 -428.942506) (xy 125.318012 -428.941992) (xy 126.257812 -428.941992) (xy 126.269921 -428.942406)
			(xy 126.292947 -428.949908) (xy 126.312519 -428.96417) (xy 126.326714 -428.983792) (xy 126.334136 -429.006844)
			(xy 126.33452 -429.018954) (xy 126.33452 -431.560478) (xy 126.334073 -431.57257) (xy 126.326618 -431.595577)
			(xy 126.312427 -431.615161) (xy 126.292887 -431.629411) (xy 126.269903 -431.636936) (xy 126.257812 -431.63744)
			(xy 125.318012 -431.63744) (xy 125.305908 -431.636974) (xy 125.282888 -431.629483) (xy 125.263318 -431.615232)
			(xy 125.249122 -431.595624) (xy 125.241693 -431.572583) (xy 125.241304 -431.560478) (xy 125.241304 -430.953164)
			(xy 125.24105 -430.947322) (xy 125.23952 -430.93302) (xy 125.23787 -430.904301) (xy 125.237748 -430.889918)
			(xy 115.614222 -430.889918) (xy 115.620833 -430.936605) (xy 115.636729 -431.105619) (xy 115.644686 -431.275192)
			(xy 115.645184 -431.360072) (xy 115.644698 -431.445674) (xy 115.63661 -431.616688) (xy 115.620446 -431.787128)
			(xy 115.605768 -431.889916) (xy 127.237744 -431.889916) (xy 127.237855 -431.875533) (xy 127.239509 -431.846813)
			(xy 127.241046 -431.832512) (xy 127.2413 -431.82667) (xy 127.2413 -430.753012) (xy 127.241046 -430.74717)
			(xy 127.23952 -430.732868) (xy 127.237867 -430.704149) (xy 127.237744 -430.689766) (xy 127.23786 -430.675383)
			(xy 127.239511 -430.646664) (xy 127.241046 -430.632362) (xy 127.2413 -430.62652) (xy 127.2413 -430.018952)
			(xy 127.241723 -430.006874) (xy 127.2492 -429.983904) (xy 127.263407 -429.964367) (xy 127.282954 -429.950174)
			(xy 127.30593 -429.942714) (xy 127.318008 -429.942244) (xy 128.257808 -429.942244) (xy 128.269878 -429.942757)
			(xy 128.292837 -429.950216) (xy 128.31237 -429.964401) (xy 128.326566 -429.983927) (xy 128.334037 -430.006882)
			(xy 128.334516 -430.018952) (xy 128.334516 -430.889918) (xy 129.23774 -430.889918) (xy 129.237852 -430.875535)
			(xy 129.239505 -430.846815) (xy 129.241042 -430.832514) (xy 129.241296 -430.826672) (xy 129.241296 -429.753014)
			(xy 129.241042 -429.747172) (xy 129.239516 -429.73287) (xy 129.237863 -429.704151) (xy 129.23774 -429.689768)
			(xy 129.237856 -429.675385) (xy 129.239507 -429.646666) (xy 129.241042 -429.632364) (xy 129.241296 -429.626522)
			(xy 129.241296 -429.018954) (xy 129.241767 -429.006866) (xy 129.249231 -428.983872) (xy 129.263418 -428.964296)
			(xy 129.282948 -428.950046) (xy 129.305918 -428.942507) (xy 129.318004 -428.941992) (xy 130.257804 -428.941992)
			(xy 130.269912 -428.942413) (xy 130.292938 -428.949912) (xy 130.312511 -428.964173) (xy 130.326706 -428.983793)
			(xy 130.334128 -429.006844) (xy 130.334512 -429.018954) (xy 130.334512 -431.560478) (xy 130.334073 -431.572571)
			(xy 130.326616 -431.595579) (xy 130.312424 -431.615164) (xy 130.292882 -431.629413) (xy 130.269896 -431.636937)
			(xy 130.257804 -431.63744) (xy 129.318004 -431.63744) (xy 129.305899 -431.636981) (xy 129.282879 -431.629488)
			(xy 129.263309 -431.615236) (xy 129.249113 -431.595625) (xy 129.241685 -431.572584) (xy 129.241296 -431.560478)
			(xy 129.241296 -430.953164) (xy 129.241042 -430.947322) (xy 129.239512 -430.93302) (xy 129.237862 -430.904301)
			(xy 129.23774 -430.889918) (xy 128.334516 -430.889918) (xy 128.334516 -431.889916) (xy 131.237736 -431.889916)
			(xy 131.237847 -431.875533) (xy 131.239501 -431.846813) (xy 131.241038 -431.832512) (xy 131.241292 -431.82667)
			(xy 131.241292 -430.753012) (xy 131.241038 -430.74717) (xy 131.239512 -430.732868) (xy 131.237859 -430.704149)
			(xy 131.237736 -430.689766) (xy 131.237852 -430.675383) (xy 131.239503 -430.646664) (xy 131.241038 -430.632362)
			(xy 131.241292 -430.62652) (xy 131.241292 -430.018952) (xy 131.241723 -430.006875) (xy 131.249199 -429.983906)
			(xy 131.263404 -429.96437) (xy 131.282949 -429.950177) (xy 131.305923 -429.942716) (xy 131.318 -429.942244)
			(xy 132.2578 -429.942244) (xy 132.26987 -429.942764) (xy 132.292829 -429.95022) (xy 132.312362 -429.964404)
			(xy 132.326558 -429.983928) (xy 132.334029 -430.006883) (xy 132.334508 -430.018952) (xy 132.334508 -430.889918)
			(xy 133.237732 -430.889918) (xy 133.237844 -430.875535) (xy 133.239497 -430.846815) (xy 133.241034 -430.832514)
			(xy 133.241288 -430.826672) (xy 133.241288 -429.753014) (xy 133.241034 -429.747172) (xy 133.239508 -429.73287)
			(xy 133.237855 -429.704151) (xy 133.237732 -429.689768) (xy 133.237848 -429.675385) (xy 133.239499 -429.646666)
			(xy 133.241034 -429.632364) (xy 133.241288 -429.626522) (xy 133.241288 -429.018954) (xy 133.241669 -429.006857)
			(xy 133.249144 -428.983847) (xy 133.263351 -428.964264) (xy 133.282905 -428.950016) (xy 133.3059 -428.942494)
			(xy 133.317996 -428.941992) (xy 134.257796 -428.941992) (xy 134.269904 -428.942419) (xy 134.29293 -428.949917)
			(xy 134.312502 -428.964176) (xy 134.326697 -428.983795) (xy 134.33412 -429.006845) (xy 134.334504 -429.018954)
			(xy 134.334504 -431.560478) (xy 134.333975 -431.572562) (xy 134.326529 -431.595555) (xy 134.312357 -431.615131)
			(xy 134.29284 -431.629384) (xy 134.269878 -431.636924) (xy 134.257796 -431.63744) (xy 133.317996 -431.63744)
			(xy 133.305891 -431.636988) (xy 133.28287 -431.629492) (xy 133.263301 -431.615238) (xy 133.249105 -431.595627)
			(xy 133.241677 -431.572584) (xy 133.241288 -431.560478) (xy 133.241288 -430.953164) (xy 133.241034 -430.947322)
			(xy 133.239504 -430.93302) (xy 133.237854 -430.904301) (xy 133.237732 -430.889918) (xy 132.334508 -430.889918)
			(xy 132.334508 -431.889916) (xy 135.237728 -431.889916) (xy 135.237839 -431.875533) (xy 135.239493 -431.846813)
			(xy 135.24103 -431.832512) (xy 135.241284 -431.82667) (xy 135.241284 -430.753012) (xy 135.24103 -430.74717)
			(xy 135.239504 -430.732868) (xy 135.237851 -430.704149) (xy 135.237728 -430.689766) (xy 135.237844 -430.675383)
			(xy 135.239495 -430.646664) (xy 135.24103 -430.632362) (xy 135.241284 -430.62652) (xy 135.241284 -430.018952)
			(xy 135.241723 -430.006876) (xy 135.249198 -429.983908) (xy 135.263401 -429.964373) (xy 135.282944 -429.95018)
			(xy 135.305915 -429.942717) (xy 135.317992 -429.942244) (xy 136.257792 -429.942244) (xy 136.269861 -429.94277)
			(xy 136.29282 -429.950225) (xy 136.312353 -429.964407) (xy 136.32655 -429.98393) (xy 136.334021 -430.006883)
			(xy 136.3345 -430.018952) (xy 136.3345 -430.889918) (xy 137.237724 -430.889918) (xy 137.237836 -430.875535)
			(xy 137.239489 -430.846815) (xy 137.241026 -430.832514) (xy 137.24128 -430.826672) (xy 137.24128 -429.753014)
			(xy 137.241026 -429.747172) (xy 137.2395 -429.73287) (xy 137.237847 -429.704151) (xy 137.237724 -429.689768)
			(xy 137.23784 -429.675385) (xy 137.239491 -429.646666) (xy 137.241026 -429.632364) (xy 137.24128 -429.626522)
			(xy 137.24128 -429.018954) (xy 137.241669 -429.006858) (xy 137.249143 -428.983849) (xy 137.263348 -428.964267)
			(xy 137.2829 -428.950019) (xy 137.305893 -428.942495) (xy 137.317988 -428.941992) (xy 138.257788 -428.941992)
			(xy 138.269895 -428.942427) (xy 138.292921 -428.949922) (xy 138.312493 -428.964179) (xy 138.326689 -428.983796)
			(xy 138.334111 -429.006845) (xy 138.334496 -429.018954) (xy 138.334496 -431.560478) (xy 138.333975 -431.572563)
			(xy 138.326528 -431.595557) (xy 138.312354 -431.615134) (xy 138.292834 -431.629386) (xy 138.269871 -431.636925)
			(xy 138.257788 -431.63744) (xy 137.317988 -431.63744) (xy 137.305882 -431.636995) (xy 137.282862 -431.629497)
			(xy 137.263292 -431.615241) (xy 137.249096 -431.595628) (xy 137.241669 -431.572585) (xy 137.24128 -431.560478)
			(xy 137.24128 -430.953164) (xy 137.241026 -430.947322) (xy 137.239496 -430.93302) (xy 137.237846 -430.904301)
			(xy 137.237724 -430.889918) (xy 136.3345 -430.889918) (xy 136.3345 -431.889916) (xy 139.23772 -431.889916)
			(xy 139.237831 -431.875533) (xy 139.239485 -431.846813) (xy 139.241022 -431.832512) (xy 139.241276 -431.82667)
			(xy 139.241276 -430.753012) (xy 139.241022 -430.74717) (xy 139.239496 -430.732868) (xy 139.237843 -430.704149)
			(xy 139.23772 -430.689766) (xy 139.237836 -430.675383) (xy 139.239487 -430.646664) (xy 139.241022 -430.632362)
			(xy 139.241276 -430.62652) (xy 139.241276 -430.018952) (xy 139.241723 -430.006877) (xy 139.249197 -429.98391)
			(xy 139.263398 -429.964376) (xy 139.282939 -429.950182) (xy 139.305908 -429.942718) (xy 139.317984 -429.942244)
			(xy 140.257784 -429.942244) (xy 140.269853 -429.942777) (xy 140.292812 -429.950229) (xy 140.312345 -429.96441)
			(xy 140.326541 -429.983931) (xy 140.334013 -430.006883) (xy 140.334492 -430.018952) (xy 140.334492 -430.889918)
			(xy 142.238476 -430.889918) (xy 142.238544 -430.877771) (xy 142.239688 -430.853504) (xy 142.240762 -430.841404)
			(xy 142.241016 -430.836578) (xy 142.241016 -429.743108) (xy 142.240762 -429.738282) (xy 142.239681 -429.726183)
			(xy 142.238539 -429.701915) (xy 142.238476 -429.689768) (xy 142.238548 -429.677621) (xy 142.239689 -429.653354)
			(xy 142.240762 -429.641254) (xy 142.241016 -429.636428) (xy 142.241016 -429.018954) (xy 142.241472 -429.006839)
			(xy 142.248969 -428.983798) (xy 142.263216 -428.964199) (xy 142.28282 -428.949958) (xy 142.305863 -428.942468)
			(xy 142.317978 -428.941992) (xy 143.257778 -428.941992) (xy 143.269887 -428.94253) (xy 143.292922 -428.950005)
			(xy 143.31252 -428.964232) (xy 143.326764 -428.983817) (xy 143.334259 -429.006846) (xy 143.33474 -429.018954)
			(xy 143.33474 -431.560478) (xy 143.334321 -431.572602) (xy 143.326832 -431.595664) (xy 143.312581 -431.615281)
			(xy 143.292964 -431.629532) (xy 143.269902 -431.637021) (xy 143.257778 -431.63744) (xy 142.317978 -431.63744)
			(xy 142.30586 -431.637007) (xy 142.282812 -431.629511) (xy 142.263209 -431.61526) (xy 142.248969 -431.595648)
			(xy 142.241486 -431.572596) (xy 142.241016 -431.560478) (xy 142.241016 -430.943258) (xy 142.240762 -430.938432)
			(xy 142.239684 -430.926333) (xy 142.23854 -430.902065) (xy 142.238476 -430.889918) (xy 140.334492 -430.889918)
			(xy 140.334492 -431.889916) (xy 144.238472 -431.889916) (xy 144.23854 -431.877769) (xy 144.239684 -431.853502)
			(xy 144.240758 -431.841402) (xy 144.241012 -431.836576) (xy 144.241012 -430.743106) (xy 144.240758 -430.73828)
			(xy 144.239677 -430.726181) (xy 144.238535 -430.701913) (xy 144.238472 -430.689766) (xy 144.238544 -430.677619)
			(xy 144.239685 -430.653352) (xy 144.240758 -430.641252) (xy 144.241012 -430.636426) (xy 144.241012 -430.018952)
			(xy 144.241419 -430.006898) (xy 144.248867 -429.983969) (xy 144.263021 -429.964453) (xy 144.282502 -429.950252)
			(xy 144.305413 -429.942749) (xy 144.317466 -429.942244) (xy 145.257774 -429.942244) (xy 145.269863 -429.94273)
			(xy 145.292863 -429.95018) (xy 145.312444 -429.964361) (xy 145.326695 -429.983891) (xy 145.334227 -430.006865)
			(xy 145.334736 -430.018952) (xy 145.334736 -430.889918) (xy 146.238468 -430.889918) (xy 146.238536 -430.877771)
			(xy 146.23968 -430.853504) (xy 146.240754 -430.841404) (xy 146.241008 -430.836578) (xy 146.241008 -429.743108)
			(xy 146.240754 -429.738282) (xy 146.239673 -429.726183) (xy 146.238531 -429.701915) (xy 146.238468 -429.689768)
			(xy 146.23854 -429.677621) (xy 146.239681 -429.653354) (xy 146.240754 -429.641254) (xy 146.241008 -429.636428)
			(xy 146.241008 -429.018954) (xy 146.241472 -429.00684) (xy 146.248968 -428.9838) (xy 146.263213 -428.964202)
			(xy 146.282815 -428.949961) (xy 146.305856 -428.94247) (xy 146.31797 -428.941992) (xy 147.25777 -428.941992)
			(xy 147.269878 -428.942537) (xy 147.292913 -428.95001) (xy 147.312511 -428.964235) (xy 147.326755 -428.983819)
			(xy 147.334251 -429.006846) (xy 147.334732 -429.018954) (xy 147.334732 -431.560478) (xy 147.334321 -431.572603)
			(xy 147.326831 -431.595666) (xy 147.312578 -431.615284) (xy 147.292959 -431.629535) (xy 147.269895 -431.637022)
			(xy 147.25777 -431.63744) (xy 146.31797 -431.63744) (xy 146.305852 -431.637014) (xy 146.282804 -431.629515)
			(xy 146.263201 -431.615262) (xy 146.248961 -431.59565) (xy 146.241478 -431.572597) (xy 146.241008 -431.560478)
			(xy 146.241008 -430.943258) (xy 146.240754 -430.938432) (xy 146.239676 -430.926333) (xy 146.238532 -430.902065)
			(xy 146.238468 -430.889918) (xy 145.334736 -430.889918) (xy 145.334736 -431.889916) (xy 148.238464 -431.889916)
			(xy 148.238532 -431.877769) (xy 148.239676 -431.853502) (xy 148.24075 -431.841402) (xy 148.241004 -431.836576)
			(xy 148.241004 -430.743106) (xy 148.24075 -430.73828) (xy 148.239669 -430.726181) (xy 148.238527 -430.701913)
			(xy 148.238464 -430.689766) (xy 148.238536 -430.677619) (xy 148.239677 -430.653352) (xy 148.24075 -430.641252)
			(xy 148.241004 -430.636426) (xy 148.241004 -430.018952) (xy 148.241419 -430.006899) (xy 148.248865 -429.983971)
			(xy 148.263018 -429.964456) (xy 148.282497 -429.950254) (xy 148.305406 -429.94275) (xy 148.317458 -429.942244)
			(xy 149.257766 -429.942244) (xy 149.269854 -429.942736) (xy 149.292854 -429.950184) (xy 149.312435 -429.964364)
			(xy 149.326687 -429.983893) (xy 149.334219 -430.006866) (xy 149.334728 -430.018952) (xy 149.334728 -430.889918)
			(xy 150.23846 -430.889918) (xy 150.238528 -430.877771) (xy 150.239672 -430.853504) (xy 150.240746 -430.841404)
			(xy 150.241 -430.836578) (xy 150.241 -429.743108) (xy 150.240746 -429.738282) (xy 150.239665 -429.726183)
			(xy 150.238523 -429.701915) (xy 150.23846 -429.689768) (xy 150.238532 -429.677621) (xy 150.239673 -429.653354)
			(xy 150.240746 -429.641254) (xy 150.241 -429.636428) (xy 150.241 -429.018954) (xy 150.241472 -429.006841)
			(xy 150.248967 -428.983803) (xy 150.263211 -428.964205) (xy 150.28281 -428.949964) (xy 150.305849 -428.942471)
			(xy 150.317962 -428.941992) (xy 151.257762 -428.941992) (xy 151.26987 -428.942543) (xy 151.292904 -428.950015)
			(xy 151.312503 -428.964238) (xy 151.326747 -428.98382) (xy 151.334243 -429.006847) (xy 151.334724 -429.018954)
			(xy 151.334724 -431.560478) (xy 151.334321 -431.572603) (xy 151.32683 -431.595668) (xy 151.312575 -431.615287)
			(xy 151.292954 -431.629537) (xy 151.269887 -431.637023) (xy 151.257762 -431.63744) (xy 150.317962 -431.63744)
			(xy 150.305843 -431.63702) (xy 150.282795 -431.62952) (xy 150.263192 -431.615265) (xy 150.248953 -431.595651)
			(xy 150.24147 -431.572597) (xy 150.241 -431.560478) (xy 150.241 -430.943258) (xy 150.240746 -430.938432)
			(xy 150.239668 -430.926333) (xy 150.238524 -430.902065) (xy 150.23846 -430.889918) (xy 149.334728 -430.889918)
			(xy 149.334728 -431.889916) (xy 152.238456 -431.889916) (xy 152.238524 -431.877769) (xy 152.239668 -431.853502)
			(xy 152.240742 -431.841402) (xy 152.240996 -431.836576) (xy 152.240996 -430.743106) (xy 152.240742 -430.73828)
			(xy 152.239661 -430.726181) (xy 152.238519 -430.701913) (xy 152.238456 -430.689766) (xy 152.238528 -430.677619)
			(xy 152.239669 -430.653352) (xy 152.240742 -430.641252) (xy 152.240996 -430.636426) (xy 152.240996 -430.018952)
			(xy 152.241419 -430.0069) (xy 152.248864 -429.983973) (xy 152.263015 -429.964459) (xy 152.282492 -429.950257)
			(xy 152.305399 -429.942751) (xy 152.31745 -429.942244) (xy 153.257758 -429.942244) (xy 153.269846 -429.942743)
			(xy 153.292846 -429.950189) (xy 153.312427 -429.964367) (xy 153.326679 -429.983894) (xy 153.334211 -430.006866)
			(xy 153.33472 -430.018952) (xy 153.33472 -430.889918) (xy 154.238452 -430.889918) (xy 154.23852 -430.877771)
			(xy 154.239664 -430.853504) (xy 154.240738 -430.841404) (xy 154.240992 -430.836578) (xy 154.240992 -429.743108)
			(xy 154.240738 -429.738282) (xy 154.239657 -429.726183) (xy 154.238515 -429.701915) (xy 154.238452 -429.689768)
			(xy 154.238524 -429.677621) (xy 154.239665 -429.653354) (xy 154.240738 -429.641254) (xy 154.240992 -429.636428)
			(xy 154.240992 -429.018954) (xy 154.241472 -429.006842) (xy 154.248966 -428.983805) (xy 154.263208 -428.964208)
			(xy 154.282805 -428.949966) (xy 154.305842 -428.942472) (xy 154.317954 -428.941992) (xy 155.257754 -428.941992)
			(xy 155.269862 -428.94255) (xy 155.292896 -428.950019) (xy 155.312494 -428.96424) (xy 155.326739 -428.983822)
			(xy 155.334235 -429.006847) (xy 155.334716 -429.018954) (xy 155.334716 -431.560478) (xy 155.334321 -431.572604)
			(xy 155.326829 -431.59567) (xy 155.312572 -431.61529) (xy 155.292949 -431.62954) (xy 155.26988 -431.637024)
			(xy 155.257754 -431.63744) (xy 154.317954 -431.63744) (xy 154.305835 -431.637027) (xy 154.282786 -431.629525)
			(xy 154.263184 -431.615268) (xy 154.248944 -431.595653) (xy 154.241462 -431.572598) (xy 154.240992 -431.560478)
			(xy 154.240992 -430.943258) (xy 154.240738 -430.938432) (xy 154.23966 -430.926333) (xy 154.238516 -430.902065)
			(xy 154.238452 -430.889918) (xy 153.33472 -430.889918) (xy 153.33472 -431.889916) (xy 156.238448 -431.889916)
			(xy 156.238516 -431.877769) (xy 156.23966 -431.853502) (xy 156.240734 -431.841402) (xy 156.240988 -431.836576)
			(xy 156.240988 -430.743106) (xy 156.240734 -430.73828) (xy 156.239652 -430.726181) (xy 156.238511 -430.701913)
			(xy 156.238448 -430.689766) (xy 156.23852 -430.677619) (xy 156.239661 -430.653352) (xy 156.240734 -430.641252)
			(xy 156.240988 -430.636426) (xy 156.240988 -430.018952) (xy 156.241419 -430.0069) (xy 156.248863 -429.983975)
			(xy 156.263012 -429.964461) (xy 156.282487 -429.950259) (xy 156.305392 -429.942752) (xy 156.317442 -429.942244)
			(xy 157.25775 -429.942244) (xy 157.269837 -429.94275) (xy 157.292837 -429.950193) (xy 157.312418 -429.96437)
			(xy 157.32667 -429.983896) (xy 157.334203 -430.006866) (xy 157.334712 -430.018952) (xy 157.334712 -432.560476)
			(xy 157.33422 -432.572524) (xy 157.326795 -432.595447) (xy 157.312662 -432.614962) (xy 157.293199 -432.629166)
			(xy 157.270304 -432.636675) (xy 157.258258 -432.637184) (xy 156.31795 -432.637184) (xy 156.305865 -432.636651)
			(xy 156.28287 -432.62921) (xy 156.263292 -432.61504) (xy 156.249039 -432.595522) (xy 156.241501 -432.572559)
			(xy 156.240988 -432.560476) (xy 156.240988 -431.943256) (xy 156.240734 -431.93843) (xy 156.239656 -431.926331)
			(xy 156.238512 -431.902063) (xy 156.238448 -431.889916) (xy 153.33472 -431.889916) (xy 153.33472 -432.560476)
			(xy 153.33422 -432.572523) (xy 153.326796 -432.595444) (xy 153.312665 -432.614959) (xy 153.293204 -432.629164)
			(xy 153.270311 -432.636674) (xy 153.258266 -432.637184) (xy 152.317958 -432.637184) (xy 152.305869 -432.636729)
			(xy 152.282871 -432.629264) (xy 152.263293 -432.615073) (xy 152.249043 -432.595539) (xy 152.241508 -432.572564)
			(xy 152.240996 -432.560476) (xy 152.240996 -431.943256) (xy 152.240742 -431.93843) (xy 152.239664 -431.926331)
			(xy 152.23852 -431.902063) (xy 152.238456 -431.889916) (xy 149.334728 -431.889916) (xy 149.334728 -432.560476)
			(xy 149.33422 -432.572522) (xy 149.326797 -432.595442) (xy 149.312668 -432.614956) (xy 149.293209 -432.629161)
			(xy 149.270318 -432.636673) (xy 149.258274 -432.637184) (xy 148.317966 -432.637184) (xy 148.305877 -432.636722)
			(xy 148.282879 -432.629259) (xy 148.263302 -432.61507) (xy 148.249052 -432.595538) (xy 148.241516 -432.572563)
			(xy 148.241004 -432.560476) (xy 148.241004 -431.943256) (xy 148.24075 -431.93843) (xy 148.239672 -431.926331)
			(xy 148.238528 -431.902063) (xy 148.238464 -431.889916) (xy 145.334736 -431.889916) (xy 145.334736 -432.560476)
			(xy 145.33422 -432.572521) (xy 145.326799 -432.59544) (xy 145.312671 -432.614953) (xy 145.293214 -432.629159)
			(xy 145.270325 -432.636672) (xy 145.258282 -432.637184) (xy 144.317974 -432.637184) (xy 144.305885 -432.636715)
			(xy 144.282888 -432.629254) (xy 144.263311 -432.615067) (xy 144.24906 -432.595536) (xy 144.241524 -432.572563)
			(xy 144.241012 -432.560476) (xy 144.241012 -431.943256) (xy 144.240758 -431.93843) (xy 144.23968 -431.926331)
			(xy 144.238536 -431.902063) (xy 144.238472 -431.889916) (xy 140.334492 -431.889916) (xy 140.334492 -432.560476)
			(xy 140.334067 -432.572559) (xy 140.326604 -432.595544) (xy 140.312401 -432.615096) (xy 140.292851 -432.6293)
			(xy 140.269867 -432.636765) (xy 140.257784 -432.637184) (xy 139.317984 -432.637184) (xy 139.305898 -432.636801)
			(xy 139.282911 -432.629326) (xy 139.263359 -432.615113) (xy 139.249156 -432.595553) (xy 139.241693 -432.572562)
			(xy 139.241276 -432.560476) (xy 139.241276 -431.953162) (xy 139.241022 -431.94732) (xy 139.239492 -431.933018)
			(xy 139.237842 -431.904299) (xy 139.23772 -431.889916) (xy 136.3345 -431.889916) (xy 136.3345 -432.560476)
			(xy 136.334067 -432.572558) (xy 136.326605 -432.595542) (xy 136.312404 -432.615093) (xy 136.292856 -432.629297)
			(xy 136.269874 -432.636764) (xy 136.257792 -432.637184) (xy 135.317992 -432.637184) (xy 135.305906 -432.636794)
			(xy 135.282919 -432.629321) (xy 135.263367 -432.61511) (xy 135.249164 -432.595552) (xy 135.241701 -432.572562)
			(xy 135.241284 -432.560476) (xy 135.241284 -431.953162) (xy 135.24103 -431.94732) (xy 135.2395 -431.933018)
			(xy 135.23785 -431.904299) (xy 135.237728 -431.889916) (xy 132.334508 -431.889916) (xy 132.334508 -432.560476)
			(xy 132.334067 -432.572557) (xy 132.326606 -432.595539) (xy 132.312407 -432.61509) (xy 132.292861 -432.629295)
			(xy 132.269881 -432.636763) (xy 132.2578 -432.637184) (xy 131.318 -432.637184) (xy 131.305915 -432.636787)
			(xy 131.282928 -432.629317) (xy 131.263376 -432.615107) (xy 131.249172 -432.59555) (xy 131.241709 -432.572561)
			(xy 131.241292 -432.560476) (xy 131.241292 -431.953162) (xy 131.241038 -431.94732) (xy 131.239508 -431.933018)
			(xy 131.237858 -431.904299) (xy 131.237736 -431.889916) (xy 128.334516 -431.889916) (xy 128.334516 -432.560476)
			(xy 128.334067 -432.572557) (xy 128.326607 -432.595537) (xy 128.31241 -432.615087) (xy 128.292866 -432.629292)
			(xy 128.269888 -432.636762) (xy 128.257808 -432.637184) (xy 127.318008 -432.637184) (xy 127.305923 -432.63678)
			(xy 127.282937 -432.629312) (xy 127.263384 -432.615105) (xy 127.249181 -432.595549) (xy 127.241717 -432.572561)
			(xy 127.2413 -432.560476) (xy 127.2413 -431.953162) (xy 127.241046 -431.94732) (xy 127.239516 -431.933018)
			(xy 127.237866 -431.904299) (xy 127.237744 -431.889916) (xy 115.605768 -431.889916) (xy 115.596243 -431.956613)
			(xy 115.564055 -432.124765) (xy 115.523953 -432.291207) (xy 115.476027 -432.455567) (xy 115.420385 -432.617477)
			(xy 115.35715 -432.776576) (xy 115.286464 -432.932508) (xy 115.208486 -433.084923) (xy 115.12339 -433.233482)
			(xy 115.031365 -433.377851) (xy 114.932619 -433.517709) (xy 114.82737 -433.652742) (xy 114.715856 -433.782648)
			(xy 114.598325 -433.907137) (xy 114.47504 -434.02593) (xy 114.346277 -434.138763) (xy 114.212324 -434.245381)
			(xy 114.07348 -434.345548) (xy 113.930056 -434.439039) (xy 113.843394 -434.48986) (xy 125.237748 -434.48986)
			(xy 125.237864 -434.475477) (xy 125.239515 -434.446758) (xy 125.24105 -434.432456) (xy 125.241304 -434.426614)
			(xy 125.241304 -433.35321) (xy 125.24105 -433.347368) (xy 125.239524 -433.333066) (xy 125.237871 -433.304347)
			(xy 125.237748 -433.289964) (xy 125.237864 -433.275581) (xy 125.239515 -433.246862) (xy 125.24105 -433.23256)
			(xy 125.241304 -433.226718) (xy 125.241304 -432.618896) (xy 125.241709 -432.606812) (xy 125.249179 -432.583827)
			(xy 125.263387 -432.564276) (xy 125.282941 -432.550072) (xy 125.305928 -432.542607) (xy 125.318012 -432.542188)
			(xy 126.257812 -432.542188) (xy 126.269887 -432.542654) (xy 126.292854 -432.550119) (xy 126.31239 -432.564316)
			(xy 126.326584 -432.583854) (xy 126.334047 -432.606821) (xy 126.33452 -432.618896) (xy 126.33452 -435.16042)
			(xy 126.334053 -435.172494) (xy 126.326586 -435.19546) (xy 126.31239 -435.214996) (xy 126.292853 -435.22919)
			(xy 126.269886 -435.236654) (xy 126.257812 -435.237128) (xy 125.318012 -435.237128) (xy 125.30594 -435.236626)
			(xy 125.282977 -435.229169) (xy 125.263441 -435.214982) (xy 125.249246 -435.195452) (xy 125.241779 -435.172492)
			(xy 125.241304 -435.16042) (xy 125.241304 -434.553106) (xy 125.24105 -434.547264) (xy 125.239524 -434.532962)
			(xy 125.237871 -434.504243) (xy 125.237748 -434.48986) (xy 113.843394 -434.48986) (xy 113.782372 -434.525645)
			(xy 113.630759 -434.605172) (xy 113.475556 -434.677443) (xy 113.396522 -434.710332) (xy 113.388621 -434.713964)
			(xy 113.375731 -434.725623) (xy 113.367472 -434.740915) (xy 113.365788 -434.749448) (xy 113.35004 -434.849016)
			(xy 113.359438 -434.873654) (xy 113.369852 -434.88229) (xy 113.419298 -434.924299) (xy 113.513487 -435.013553)
			(xy 113.601975 -435.108462) (xy 113.684422 -435.208663) (xy 113.760513 -435.313772) (xy 113.829956 -435.423387)
			(xy 113.866512 -435.489858) (xy 127.237744 -435.489858) (xy 127.237859 -435.475475) (xy 127.23951 -435.446756)
			(xy 127.241046 -435.432454) (xy 127.2413 -435.426612) (xy 127.2413 -434.353208) (xy 127.241046 -434.347366)
			(xy 127.23952 -434.333064) (xy 127.237867 -434.304345) (xy 127.237744 -434.289962) (xy 127.237859 -434.275579)
			(xy 127.239511 -434.24686) (xy 127.241046 -434.232558) (xy 127.2413 -434.226716) (xy 127.2413 -433.618894)
			(xy 127.241802 -433.606808) (xy 127.249255 -433.583814) (xy 127.263434 -433.564238) (xy 127.282958 -433.549986)
			(xy 127.305924 -433.542447) (xy 127.318008 -433.541932) (xy 128.257808 -433.541932) (xy 128.269921 -433.54231)
			(xy 128.292954 -433.549815) (xy 128.312529 -433.564086) (xy 128.326723 -433.583717) (xy 128.334137 -433.60678)
			(xy 128.334516 -433.618894) (xy 128.334516 -434.48986) (xy 129.23774 -434.48986) (xy 129.237855 -434.475477)
			(xy 129.239506 -434.446758) (xy 129.241042 -434.432456) (xy 129.241296 -434.426614) (xy 129.241296 -433.35321)
			(xy 129.241042 -433.347368) (xy 129.239516 -433.333066) (xy 129.237863 -433.304347) (xy 129.23774 -433.289964)
			(xy 129.237855 -433.275581) (xy 129.239507 -433.246862) (xy 129.241042 -433.23256) (xy 129.241296 -433.226718)
			(xy 129.241296 -432.618896) (xy 129.241761 -432.606821) (xy 129.249225 -432.583853) (xy 129.263421 -432.564316)
			(xy 129.28296 -432.550121) (xy 129.305929 -432.54266) (xy 129.318004 -432.542188) (xy 130.257804 -432.542188)
			(xy 130.269878 -432.542661) (xy 130.292845 -432.550124) (xy 130.312382 -432.564318) (xy 130.326576 -432.583855)
			(xy 130.334039 -432.606822) (xy 130.334512 -432.618896) (xy 130.334512 -435.16042) (xy 130.334053 -435.172495)
			(xy 130.326585 -435.195462) (xy 130.312387 -435.214999) (xy 130.292848 -435.229193) (xy 130.269879 -435.236655)
			(xy 130.257804 -435.237128) (xy 129.318004 -435.237128) (xy 129.305932 -435.236633) (xy 129.282968 -435.229174)
			(xy 129.263433 -435.214984) (xy 129.249237 -435.195454) (xy 129.241771 -435.172492) (xy 129.241296 -435.16042)
			(xy 129.241296 -434.553106) (xy 129.241042 -434.547264) (xy 129.239516 -434.532962) (xy 129.237863 -434.504243)
			(xy 129.23774 -434.48986) (xy 128.334516 -434.48986) (xy 128.334516 -435.489858) (xy 131.237736 -435.489858)
			(xy 131.237851 -435.475475) (xy 131.239502 -435.446756) (xy 131.241038 -435.432454) (xy 131.241292 -435.426612)
			(xy 131.241292 -434.353208) (xy 131.241038 -434.347366) (xy 131.239512 -434.333064) (xy 131.237859 -434.304345)
			(xy 131.237736 -434.289962) (xy 131.237851 -434.275579) (xy 131.239503 -434.24686) (xy 131.241038 -434.232558)
			(xy 131.241292 -434.226716) (xy 131.241292 -433.618894) (xy 131.241802 -433.606809) (xy 131.249254 -433.583816)
			(xy 131.263431 -433.564241) (xy 131.282953 -433.549989) (xy 131.305917 -433.542448) (xy 131.318 -433.541932)
			(xy 132.2578 -433.541932) (xy 132.269912 -433.542317) (xy 132.292945 -433.54982) (xy 132.312521 -433.564088)
			(xy 132.326714 -433.583719) (xy 132.334129 -433.60678) (xy 132.334508 -433.618894) (xy 132.334508 -434.48986)
			(xy 133.237732 -434.48986) (xy 133.237847 -434.475477) (xy 133.239499 -434.446758) (xy 133.241034 -434.432456)
			(xy 133.241288 -434.426614) (xy 133.241288 -433.35321) (xy 133.241034 -433.347368) (xy 133.239508 -433.333066)
			(xy 133.237855 -433.304347) (xy 133.237732 -433.289964) (xy 133.237847 -433.275581) (xy 133.239499 -433.246862)
			(xy 133.241034 -433.23256) (xy 133.241288 -433.226718) (xy 133.241288 -432.618896) (xy 133.241761 -432.606822)
			(xy 133.249224 -432.583855) (xy 133.263418 -432.564318) (xy 133.282955 -432.550124) (xy 133.305922 -432.542661)
			(xy 133.317996 -432.542188) (xy 134.257796 -432.542188) (xy 134.26987 -432.542668) (xy 134.292836 -432.550129)
			(xy 134.312373 -432.564321) (xy 134.326568 -432.583857) (xy 134.334031 -432.606822) (xy 134.334504 -432.618896)
			(xy 134.334504 -435.16042) (xy 134.334053 -435.172496) (xy 134.326584 -435.195464) (xy 134.312384 -435.215001)
			(xy 134.292843 -435.229195) (xy 134.269872 -435.236656) (xy 134.257796 -435.237128) (xy 133.317996 -435.237128)
			(xy 133.305923 -435.236639) (xy 133.282959 -435.229178) (xy 133.263424 -435.214987) (xy 133.249229 -435.195455)
			(xy 133.241763 -435.172493) (xy 133.241288 -435.16042) (xy 133.241288 -434.553106) (xy 133.241034 -434.547264)
			(xy 133.239507 -434.532962) (xy 133.237855 -434.504243) (xy 133.237732 -434.48986) (xy 132.334508 -434.48986)
			(xy 132.334508 -435.489858) (xy 135.237728 -435.489858) (xy 135.237843 -435.475475) (xy 135.239494 -435.446756)
			(xy 135.24103 -435.432454) (xy 135.241284 -435.426612) (xy 135.241284 -434.353208) (xy 135.24103 -434.347366)
			(xy 135.239504 -434.333064) (xy 135.237851 -434.304345) (xy 135.237728 -434.289962) (xy 135.237843 -434.275579)
			(xy 135.239495 -434.24686) (xy 135.24103 -434.232558) (xy 135.241284 -434.226716) (xy 135.241284 -433.618894)
			(xy 135.241703 -433.6068) (xy 135.249167 -433.583792) (xy 135.263364 -433.564208) (xy 135.282911 -433.549959)
			(xy 135.305899 -433.542435) (xy 135.317992 -433.541932) (xy 136.257792 -433.541932) (xy 136.269904 -433.542323)
			(xy 136.292936 -433.549824) (xy 136.312512 -433.564091) (xy 136.326706 -433.58372) (xy 136.334121 -433.606781)
			(xy 136.3345 -433.618894) (xy 136.3345 -434.48986) (xy 137.237724 -434.48986) (xy 137.237839 -434.475477)
			(xy 137.239491 -434.446758) (xy 137.241026 -434.432456) (xy 137.24128 -434.426614) (xy 137.24128 -433.35321)
			(xy 137.241026 -433.347368) (xy 137.2395 -433.333066) (xy 137.237847 -433.304347) (xy 137.237724 -433.289964)
			(xy 137.23784 -433.275581) (xy 137.239491 -433.246862) (xy 137.241026 -433.23256) (xy 137.24128 -433.226718)
			(xy 137.24128 -432.618896) (xy 137.241761 -432.606822) (xy 137.249223 -432.583857) (xy 137.263416 -432.564321)
			(xy 137.28295 -432.550126) (xy 137.305914 -432.542662) (xy 137.317988 -432.542188) (xy 138.257788 -432.542188)
			(xy 138.26987 -432.542623) (xy 138.292851 -432.550087) (xy 138.312401 -432.564287) (xy 138.326606 -432.583834)
			(xy 138.334074 -432.606814) (xy 138.334496 -432.618896) (xy 138.334496 -435.16042) (xy 138.334052 -435.172497)
			(xy 138.326583 -435.195467) (xy 138.312381 -435.215004) (xy 138.292838 -435.229198) (xy 138.269865 -435.236657)
			(xy 138.257788 -435.237128) (xy 137.317988 -435.237128) (xy 137.305915 -435.236646) (xy 137.282951 -435.229183)
			(xy 137.263416 -435.21499) (xy 137.249221 -435.195456) (xy 137.241755 -435.172493) (xy 137.24128 -435.16042)
			(xy 137.24128 -434.553106) (xy 137.241026 -434.547264) (xy 137.239499 -434.532962) (xy 137.237847 -434.504243)
			(xy 137.237724 -434.48986) (xy 136.3345 -434.48986) (xy 136.3345 -435.489858) (xy 139.23772 -435.489858)
			(xy 139.237835 -435.475475) (xy 139.239486 -435.446756) (xy 139.241022 -435.432454) (xy 139.241276 -435.426612)
			(xy 139.241276 -434.353208) (xy 139.241022 -434.347366) (xy 139.239496 -434.333064) (xy 139.237843 -434.304345)
			(xy 139.23772 -434.289962) (xy 139.237835 -434.275579) (xy 139.239487 -434.24686) (xy 139.241022 -434.232558)
			(xy 139.241276 -434.226716) (xy 139.241276 -433.618894) (xy 139.241703 -433.606801) (xy 139.249166 -433.583794)
			(xy 139.263361 -433.564211) (xy 139.282906 -433.549962) (xy 139.305892 -433.542436) (xy 139.317984 -433.541932)
			(xy 140.257784 -433.541932) (xy 140.269895 -433.542331) (xy 140.292927 -433.549829) (xy 140.312503 -433.564094)
			(xy 140.326697 -433.583722) (xy 140.334113 -433.606781) (xy 140.334492 -433.618894) (xy 140.334492 -434.48986)
			(xy 142.238476 -434.48986) (xy 142.238547 -434.477713) (xy 142.239689 -434.453446) (xy 142.240762 -434.441346)
			(xy 142.241016 -434.43652) (xy 142.241016 -433.343304) (xy 142.240762 -433.338478) (xy 142.239688 -433.326378)
			(xy 142.238542 -433.302111) (xy 142.238476 -433.289964) (xy 142.238548 -433.277817) (xy 142.239689 -433.25355)
			(xy 142.240762 -433.24145) (xy 142.241016 -433.236624) (xy 142.241016 -432.618896) (xy 142.241457 -432.606844)
			(xy 142.248893 -432.583916) (xy 142.263038 -432.564399) (xy 142.282513 -432.550196) (xy 142.305419 -432.542693)
			(xy 142.31747 -432.542188) (xy 143.257778 -432.542188) (xy 143.269871 -432.542627) (xy 143.292879 -432.550084)
			(xy 143.312464 -432.564276) (xy 143.326713 -432.583818) (xy 143.334237 -432.606804) (xy 143.33474 -432.618896)
			(xy 143.33474 -435.16042) (xy 143.334258 -435.172467) (xy 143.326824 -435.195387) (xy 143.312688 -435.214899)
			(xy 143.293225 -435.229103) (xy 143.270332 -435.236615) (xy 143.258286 -435.237128) (xy 142.317978 -435.237128)
			(xy 142.305884 -435.236711) (xy 142.282877 -435.229244) (xy 142.263295 -435.215046) (xy 142.249046 -435.1955)
			(xy 142.24152 -435.172513) (xy 142.241016 -435.16042) (xy 142.241016 -434.5432) (xy 142.240762 -434.538374)
			(xy 142.239687 -434.526274) (xy 142.238541 -434.502007) (xy 142.238476 -434.48986) (xy 140.334492 -434.48986)
			(xy 140.334492 -435.489858) (xy 144.238472 -435.489858) (xy 144.238543 -435.477711) (xy 144.239685 -435.453444)
			(xy 144.240758 -435.441344) (xy 144.241012 -435.436518) (xy 144.241012 -434.343302) (xy 144.240758 -434.338476)
			(xy 144.239683 -434.326376) (xy 144.238538 -434.302109) (xy 144.238472 -434.289962) (xy 144.238544 -434.277815)
			(xy 144.239685 -434.253548) (xy 144.240758 -434.241448) (xy 144.241012 -434.236622) (xy 144.241012 -433.618894)
			(xy 144.241506 -433.606782) (xy 144.248992 -433.583743) (xy 144.263229 -433.564143) (xy 144.282825 -433.549901)
			(xy 144.305862 -433.54241) (xy 144.317974 -433.541932) (xy 145.257774 -433.541932) (xy 145.269895 -433.542382)
			(xy 145.292952 -433.549866) (xy 145.312567 -433.56411) (xy 145.326819 -433.58372) (xy 145.334313 -433.606773)
			(xy 145.334736 -433.618894) (xy 145.334736 -434.48986) (xy 146.238468 -434.48986) (xy 146.238539 -434.477713)
			(xy 146.239681 -434.453446) (xy 146.240754 -434.441346) (xy 146.241008 -434.43652) (xy 146.241008 -433.343304)
			(xy 146.240754 -433.338478) (xy 146.23968 -433.326378) (xy 146.238534 -433.302111) (xy 146.238468 -433.289964)
			(xy 146.23854 -433.277817) (xy 146.239681 -433.25355) (xy 146.240754 -433.24145) (xy 146.241008 -433.236624)
			(xy 146.241008 -432.618896) (xy 146.241457 -432.606845) (xy 146.248892 -432.583918) (xy 146.263035 -432.564401)
			(xy 146.282508 -432.550199) (xy 146.305412 -432.542694) (xy 146.317462 -432.542188) (xy 147.25777 -432.542188)
			(xy 147.269863 -432.542634) (xy 147.29287 -432.550088) (xy 147.312455 -432.564278) (xy 147.326705 -432.58382)
			(xy 147.334229 -432.606805) (xy 147.334732 -432.618896) (xy 147.334732 -435.16042) (xy 147.334258 -435.172468)
			(xy 147.326823 -435.195389) (xy 147.312685 -435.214901) (xy 147.29322 -435.229105) (xy 147.270324 -435.236616)
			(xy 147.258278 -435.237128) (xy 146.31797 -435.237128) (xy 146.305876 -435.236718) (xy 146.282869 -435.229249)
			(xy 146.263286 -435.215049) (xy 146.249038 -435.195502) (xy 146.241512 -435.172513) (xy 146.241008 -435.16042)
			(xy 146.241008 -434.5432) (xy 146.240754 -434.538374) (xy 146.239679 -434.526274) (xy 146.238533 -434.502007)
			(xy 146.238468 -434.48986) (xy 145.334736 -434.48986) (xy 145.334736 -435.489858) (xy 148.238464 -435.489858)
			(xy 148.238535 -435.477711) (xy 148.239677 -435.453444) (xy 148.24075 -435.441344) (xy 148.241004 -435.436518)
			(xy 148.241004 -434.343302) (xy 148.24075 -434.338476) (xy 148.239675 -434.326376) (xy 148.23853 -434.302109)
			(xy 148.238464 -434.289962) (xy 148.238536 -434.277815) (xy 148.239677 -434.253548) (xy 148.24075 -434.241448)
			(xy 148.241004 -434.236622) (xy 148.241004 -433.618894) (xy 148.241506 -433.606783) (xy 148.248991 -433.583745)
			(xy 148.263226 -433.564146) (xy 148.28282 -433.549904) (xy 148.305855 -433.542411) (xy 148.317966 -433.541932)
			(xy 149.257766 -433.541932) (xy 149.269886 -433.542389) (xy 149.292943 -433.549871) (xy 149.312558 -433.564113)
			(xy 149.326811 -433.583721) (xy 149.334305 -433.606774) (xy 149.334728 -433.618894) (xy 149.334728 -434.48986)
			(xy 150.23846 -434.48986) (xy 150.238531 -434.477713) (xy 150.239673 -434.453446) (xy 150.240746 -434.441346)
			(xy 150.241 -434.43652) (xy 150.241 -433.343304) (xy 150.240746 -433.338478) (xy 150.239671 -433.326378)
			(xy 150.238526 -433.302111) (xy 150.23846 -433.289964) (xy 150.238532 -433.277817) (xy 150.239673 -433.25355)
			(xy 150.240746 -433.24145) (xy 150.241 -433.236624) (xy 150.241 -432.618896) (xy 150.241457 -432.606846)
			(xy 150.24889 -432.58392) (xy 150.263032 -432.564404) (xy 150.282503 -432.550201) (xy 150.305405 -432.542695)
			(xy 150.317454 -432.542188) (xy 151.257762 -432.542188) (xy 151.269854 -432.542641) (xy 151.292862 -432.550093)
			(xy 151.312447 -432.564281) (xy 151.326697 -432.583821) (xy 151.334221 -432.606805) (xy 151.334724 -432.618896)
			(xy 151.334724 -435.16042) (xy 151.334257 -435.172469) (xy 151.326822 -435.195391) (xy 151.312682 -435.214904)
			(xy 151.293215 -435.229108) (xy 151.270317 -435.236618) (xy 151.25827 -435.237128) (xy 150.317962 -435.237128)
			(xy 150.305867 -435.236724) (xy 150.28286 -435.229253) (xy 150.263278 -435.215052) (xy 150.24903 -435.195503)
			(xy 150.241504 -435.172514) (xy 150.241 -435.16042) (xy 150.241 -434.5432) (xy 150.240746 -434.538374)
			(xy 150.239671 -434.526274) (xy 150.238525 -434.502007) (xy 150.23846 -434.48986) (xy 149.334728 -434.48986)
			(xy 149.334728 -435.489858) (xy 152.238456 -435.489858) (xy 152.238527 -435.477711) (xy 152.239669 -435.453444)
			(xy 152.240742 -435.441344) (xy 152.240996 -435.436518) (xy 152.240996 -434.343302) (xy 152.240742 -434.338476)
			(xy 152.239667 -434.326376) (xy 152.238522 -434.302109) (xy 152.238456 -434.289962) (xy 152.238528 -434.277815)
			(xy 152.239669 -434.253548) (xy 152.240742 -434.241448) (xy 152.240996 -434.236622) (xy 152.240996 -433.618894)
			(xy 152.241506 -433.606783) (xy 152.24899 -433.583747) (xy 152.263224 -433.564149) (xy 152.282815 -433.549906)
			(xy 152.305848 -433.542412) (xy 152.317958 -433.541932) (xy 153.257758 -433.541932) (xy 153.269878 -433.542396)
			(xy 153.292934 -433.549876) (xy 153.31255 -433.564116) (xy 153.326803 -433.583722) (xy 153.334297 -433.606774)
			(xy 153.33472 -433.618894) (xy 153.33472 -434.48986) (xy 154.238452 -434.48986) (xy 154.238523 -434.477713)
			(xy 154.239665 -434.453446) (xy 154.240738 -434.441346) (xy 154.240992 -434.43652) (xy 154.240992 -433.343304)
			(xy 154.240738 -433.338478) (xy 154.239663 -433.326378) (xy 154.238518 -433.302111) (xy 154.238452 -433.289964)
			(xy 154.238524 -433.277817) (xy 154.239665 -433.25355) (xy 154.240738 -433.24145) (xy 154.240992 -433.236624)
			(xy 154.240992 -432.618896) (xy 154.241456 -432.606846) (xy 154.248889 -432.583922) (xy 154.263029 -432.564407)
			(xy 154.282498 -432.550204) (xy 154.305398 -432.542696) (xy 154.317446 -432.542188) (xy 155.257754 -432.542188)
			(xy 155.269846 -432.542647) (xy 155.292853 -432.550097) (xy 155.312438 -432.564284) (xy 155.326688 -432.583823)
			(xy 155.334213 -432.606806) (xy 155.334716 -432.618896) (xy 155.334716 -433.130695) (xy 197.035917 -433.130695)
			(xy 197.035917 -432.953425) (xy 197.04387 -432.776334) (xy 197.059761 -432.599778) (xy 197.083556 -432.424113)
			(xy 197.115209 -432.249692) (xy 197.154655 -432.076867) (xy 197.201815 -431.905986) (xy 197.256594 -431.737392)
			(xy 197.318882 -431.571427) (xy 197.388554 -431.408422) (xy 197.465468 -431.248708) (xy 197.549471 -431.092605)
			(xy 197.640392 -430.940428) (xy 197.738049 -430.792484) (xy 197.842246 -430.64907) (xy 197.952772 -430.510475)
			(xy 198.069404 -430.376978) (xy 198.191909 -430.248849) (xy 198.320038 -430.126344) (xy 198.453535 -430.009712)
			(xy 198.59213 -429.899186) (xy 198.735544 -429.794989) (xy 198.883488 -429.697332) (xy 199.035665 -429.606411)
			(xy 199.191768 -429.522408) (xy 199.351482 -429.445494) (xy 199.514487 -429.375822) (xy 199.680452 -429.313534)
			(xy 199.849046 -429.258755) (xy 200.019927 -429.211595) (xy 200.192752 -429.172149) (xy 200.367173 -429.140496)
			(xy 200.542838 -429.116701) (xy 200.719394 -429.10081) (xy 200.896485 -429.092857) (xy 201.073755 -429.092857)
			(xy 201.250846 -429.10081) (xy 201.427402 -429.116701) (xy 201.603067 -429.140496) (xy 201.777488 -429.172149)
			(xy 201.950313 -429.211595) (xy 202.121194 -429.258755) (xy 202.289788 -429.313534) (xy 202.455753 -429.375822)
			(xy 202.618758 -429.445494) (xy 202.778472 -429.522408) (xy 202.934575 -429.606411) (xy 203.086752 -429.697332)
			(xy 203.234696 -429.794989) (xy 203.37811 -429.899186) (xy 203.516705 -430.009712) (xy 203.650202 -430.126344)
			(xy 203.778331 -430.248849) (xy 203.900836 -430.376978) (xy 204.017468 -430.510475) (xy 204.127994 -430.64907)
			(xy 204.232191 -430.792484) (xy 204.329848 -430.940428) (xy 204.420769 -431.092605) (xy 204.504772 -431.248708)
			(xy 204.581686 -431.408422) (xy 204.651358 -431.571427) (xy 204.713646 -431.737392) (xy 204.768425 -431.905986)
			(xy 204.815585 -432.076867) (xy 204.855031 -432.249692) (xy 204.886684 -432.424113) (xy 204.910479 -432.599778)
			(xy 204.92637 -432.776334) (xy 204.934323 -432.953425) (xy 204.93482 -433.04206) (xy 204.934323 -433.130695)
			(xy 204.92637 -433.307786) (xy 204.910479 -433.484342) (xy 204.886684 -433.660007) (xy 204.855031 -433.834428)
			(xy 204.815585 -434.007253) (xy 204.768425 -434.178134) (xy 204.713646 -434.346728) (xy 204.651358 -434.512693)
			(xy 204.581686 -434.675698) (xy 204.504772 -434.835412) (xy 204.420769 -434.991515) (xy 204.329848 -435.143692)
			(xy 204.232191 -435.291636) (xy 204.127994 -435.43505) (xy 204.017468 -435.573645) (xy 203.900836 -435.707142)
			(xy 203.778331 -435.835271) (xy 203.650202 -435.957776) (xy 203.516705 -436.074408) (xy 203.37811 -436.184934)
			(xy 203.234696 -436.289131) (xy 203.086752 -436.386788) (xy 202.934575 -436.477709) (xy 202.778472 -436.561712)
			(xy 202.618758 -436.638626) (xy 202.455753 -436.708298) (xy 202.289788 -436.770586) (xy 202.121194 -436.825365)
			(xy 201.950313 -436.872525) (xy 201.777488 -436.911971) (xy 201.603067 -436.943624) (xy 201.427402 -436.967419)
			(xy 201.250846 -436.98331) (xy 201.073755 -436.991263) (xy 200.896485 -436.991263) (xy 200.719394 -436.98331)
			(xy 200.542838 -436.967419) (xy 200.367173 -436.943624) (xy 200.192752 -436.911971) (xy 200.019927 -436.872525)
			(xy 199.849046 -436.825365) (xy 199.680452 -436.770586) (xy 199.514487 -436.708298) (xy 199.351482 -436.638626)
			(xy 199.191768 -436.561712) (xy 199.035665 -436.477709) (xy 198.883488 -436.386788) (xy 198.735544 -436.289131)
			(xy 198.59213 -436.184934) (xy 198.453535 -436.074408) (xy 198.320038 -435.957776) (xy 198.191909 -435.835271)
			(xy 198.069404 -435.707142) (xy 197.952772 -435.573645) (xy 197.842246 -435.43505) (xy 197.738049 -435.291636)
			(xy 197.640392 -435.143692) (xy 197.549471 -434.991515) (xy 197.465468 -434.835412) (xy 197.388554 -434.675698)
			(xy 197.318882 -434.512693) (xy 197.256594 -434.346728) (xy 197.201815 -434.178134) (xy 197.154655 -434.007253)
			(xy 197.115209 -433.834428) (xy 197.083556 -433.660007) (xy 197.059761 -433.484342) (xy 197.04387 -433.307786)
			(xy 197.035917 -433.130695) (xy 155.334716 -433.130695) (xy 155.334716 -435.16042) (xy 155.334257 -435.17247)
			(xy 155.326821 -435.195393) (xy 155.312679 -435.214907) (xy 155.29321 -435.22911) (xy 155.27031 -435.236619)
			(xy 155.258262 -435.237128) (xy 154.317954 -435.237128) (xy 154.305859 -435.236731) (xy 154.282851 -435.229258)
			(xy 154.263269 -435.215054) (xy 154.249022 -435.195505) (xy 154.241496 -435.172514) (xy 154.240992 -435.16042)
			(xy 154.240992 -434.5432) (xy 154.240738 -434.538374) (xy 154.239663 -434.526274) (xy 154.238517 -434.502007)
			(xy 154.238452 -434.48986) (xy 153.33472 -434.48986) (xy 153.33472 -435.489858) (xy 156.238448 -435.489858)
			(xy 156.238519 -435.477711) (xy 156.239661 -435.453444) (xy 156.240734 -435.441344) (xy 156.240988 -435.436518)
			(xy 156.240988 -434.343302) (xy 156.240734 -434.338476) (xy 156.239659 -434.326376) (xy 156.238514 -434.302109)
			(xy 156.238448 -434.289962) (xy 156.23852 -434.277815) (xy 156.239661 -434.253548) (xy 156.240734 -434.241448)
			(xy 156.240988 -434.236622) (xy 156.240988 -433.618894) (xy 156.241506 -433.606784) (xy 156.248989 -433.583749)
			(xy 156.263221 -433.564152) (xy 156.28281 -433.549909) (xy 156.30584 -433.542413) (xy 156.31795 -433.541932)
			(xy 157.25775 -433.541932) (xy 157.269867 -433.542369) (xy 157.29291 -433.549869) (xy 157.312511 -433.564121)
			(xy 157.326751 -433.583729) (xy 157.334238 -433.606777) (xy 157.334712 -433.618894) (xy 157.334712 -436.160418)
			(xy 157.334205 -436.172529) (xy 157.326718 -436.195564) (xy 157.312484 -436.215161) (xy 157.292893 -436.229404)
			(xy 157.26986 -436.2369) (xy 157.25775 -436.23738) (xy 156.31795 -436.23738) (xy 156.305835 -436.236931)
			(xy 156.282793 -436.229432) (xy 156.263193 -436.215184) (xy 156.248953 -436.195578) (xy 156.241464 -436.172534)
			(xy 156.240988 -436.160418) (xy 156.240988 -435.543198) (xy 156.240734 -435.538372) (xy 156.239659 -435.526272)
			(xy 156.238513 -435.502005) (xy 156.238448 -435.489858) (xy 153.33472 -435.489858) (xy 153.33472 -436.160418)
			(xy 153.334354 -436.172546) (xy 153.326852 -436.195612) (xy 153.312588 -436.215231) (xy 153.292958 -436.22948)
			(xy 153.269886 -436.236964) (xy 153.257758 -436.23738) (xy 152.317958 -436.23738) (xy 152.305843 -436.236924)
			(xy 152.282801 -436.229428) (xy 152.263202 -436.215181) (xy 152.248961 -436.195577) (xy 152.241472 -436.172533)
			(xy 152.240996 -436.160418) (xy 152.240996 -435.543198) (xy 152.240742 -435.538372) (xy 152.239667 -435.526272)
			(xy 152.238521 -435.502005) (xy 152.238456 -435.489858) (xy 149.334728 -435.489858) (xy 149.334728 -436.160418)
			(xy 149.334355 -436.172545) (xy 149.326853 -436.19561) (xy 149.312591 -436.215228) (xy 149.292964 -436.229477)
			(xy 149.269893 -436.236963) (xy 149.257766 -436.23738) (xy 148.317966 -436.23738) (xy 148.305851 -436.236918)
			(xy 148.28281 -436.229423) (xy 148.26321 -436.215178) (xy 148.248969 -436.195576) (xy 148.24148 -436.172533)
			(xy 148.241004 -436.160418) (xy 148.241004 -435.543198) (xy 148.24075 -435.538372) (xy 148.239675 -435.526272)
			(xy 148.238529 -435.502005) (xy 148.238464 -435.489858) (xy 145.334736 -435.489858) (xy 145.334736 -436.160418)
			(xy 145.334355 -436.172544) (xy 145.326854 -436.195608) (xy 145.312594 -436.215225) (xy 145.292969 -436.229474)
			(xy 145.2699 -436.236962) (xy 145.257774 -436.23738) (xy 144.317974 -436.23738) (xy 144.30586 -436.236911)
			(xy 144.282819 -436.229419) (xy 144.263219 -436.215175) (xy 144.248978 -436.195574) (xy 144.241488 -436.172532)
			(xy 144.241012 -436.160418) (xy 144.241012 -435.543198) (xy 144.240758 -435.538372) (xy 144.239683 -435.526272)
			(xy 144.238537 -435.502005) (xy 144.238472 -435.489858) (xy 140.334492 -435.489858) (xy 140.334492 -436.160418)
			(xy 140.334009 -436.172505) (xy 140.326551 -436.195501) (xy 140.312367 -436.215078) (xy 140.29284 -436.229329)
			(xy 140.26987 -436.236866) (xy 140.257784 -436.23738) (xy 139.317984 -436.23738) (xy 139.305872 -436.236997)
			(xy 139.282841 -436.229491) (xy 139.263266 -436.215221) (xy 139.249073 -436.195592) (xy 139.241656 -436.172531)
			(xy 139.241276 -436.160418) (xy 139.241276 -435.553104) (xy 139.241022 -435.547262) (xy 139.239495 -435.53296)
			(xy 139.237843 -435.504241) (xy 139.23772 -435.489858) (xy 136.3345 -435.489858) (xy 136.3345 -436.160418)
			(xy 136.334009 -436.172505) (xy 136.326552 -436.195499) (xy 136.31237 -436.215075) (xy 136.292845 -436.229327)
			(xy 136.269877 -436.236865) (xy 136.257792 -436.23738) (xy 135.317992 -436.23738) (xy 135.305881 -436.23699)
			(xy 135.28285 -436.229486) (xy 135.263275 -436.215219) (xy 135.249081 -436.19559) (xy 135.241664 -436.172531)
			(xy 135.241284 -436.160418) (xy 135.241284 -435.553104) (xy 135.24103 -435.547262) (xy 135.239503 -435.53296)
			(xy 135.237851 -435.504241) (xy 135.237728 -435.489858) (xy 132.334508 -435.489858) (xy 132.334508 -436.160418)
			(xy 132.334009 -436.172504) (xy 132.326553 -436.195497) (xy 132.312373 -436.215072) (xy 132.29285 -436.229324)
			(xy 132.269884 -436.236864) (xy 132.2578 -436.23738) (xy 131.318 -436.23738) (xy 131.305889 -436.236984)
			(xy 131.282858 -436.229482) (xy 131.263283 -436.215216) (xy 131.24909 -436.195589) (xy 131.241672 -436.17253)
			(xy 131.241292 -436.160418) (xy 131.241292 -435.553104) (xy 131.241038 -435.547262) (xy 131.239511 -435.53296)
			(xy 131.237859 -435.504241) (xy 131.237736 -435.489858) (xy 128.334516 -435.489858) (xy 128.334516 -436.160418)
			(xy 128.334107 -436.172513) (xy 128.32664 -436.195522) (xy 128.31244 -436.215105) (xy 128.292892 -436.229353)
			(xy 128.269902 -436.236877) (xy 128.257808 -436.23738) (xy 127.318008 -436.23738) (xy 127.305898 -436.236977)
			(xy 127.282867 -436.229477) (xy 127.263292 -436.215213) (xy 127.249098 -436.195587) (xy 127.24168 -436.17253)
			(xy 127.2413 -436.160418) (xy 127.2413 -435.553104) (xy 127.241046 -435.547262) (xy 127.239519 -435.53296)
			(xy 127.237867 -435.504241) (xy 127.237744 -435.489858) (xy 113.866512 -435.489858) (xy 113.892486 -435.537087)
			(xy 113.947862 -435.654438) (xy 113.995874 -435.77499) (xy 114.036336 -435.89828) (xy 114.069094 -436.023838)
			(xy 114.094022 -436.151181) (xy 114.111025 -436.279823) (xy 114.120038 -436.40927) (xy 114.121027 -436.539027)
			(xy 114.113986 -436.668596) (xy 114.098945 -436.797482) (xy 114.075959 -436.92519) (xy 114.045118 -437.051232)
			(xy 114.006538 -437.175125) (xy 113.960369 -437.296394) (xy 113.906786 -437.414574) (xy 113.845996 -437.529214)
			(xy 113.77823 -437.639874) (xy 113.703749 -437.74613) (xy 113.622838 -437.847575) (xy 113.535806 -437.943821)
			(xy 113.442988 -438.034499) (xy 113.378885 -438.089802) (xy 125.21819 -438.089802) (xy 125.218621 -438.057912)
			(xy 125.226258 -437.994592) (xy 125.241413 -437.932639) (xy 125.263866 -437.872943) (xy 125.293297 -437.81636)
			(xy 125.329281 -437.763702) (xy 125.371305 -437.715724) (xy 125.39472 -437.69407) (xy 125.398353 -437.690742)
			(xy 125.404363 -437.682936) (xy 125.406658 -437.678576) (xy 125.482604 -437.523382) (xy 125.487305 -437.512865)
			(xy 125.490795 -437.490107) (xy 125.48731 -437.467348) (xy 125.482604 -437.456834) (xy 125.405896 -437.300878)
			(xy 125.403729 -437.29654) (xy 125.397967 -437.28874) (xy 125.394466 -437.285384) (xy 125.371049 -437.26377)
			(xy 125.329087 -437.215805) (xy 125.29316 -437.163169) (xy 125.263782 -437.106615) (xy 125.241375 -437.046955)
			(xy 125.22626 -436.985044) (xy 125.218653 -436.921771) (xy 125.21819 -436.889906) (xy 125.218844 -436.852371)
			(xy 125.22942 -436.778049) (xy 125.239272 -436.741824) (xy 125.240221 -436.738345) (xy 125.241241 -436.731206)
			(xy 125.241304 -436.7276) (xy 125.241304 -436.219092) (xy 125.241706 -436.207008) (xy 125.249177 -436.184023)
			(xy 125.263386 -436.164471) (xy 125.282941 -436.150268) (xy 125.305928 -436.142803) (xy 125.318012 -436.142384)
			(xy 126.257812 -436.142384) (xy 126.269886 -436.142854) (xy 126.292853 -436.150319) (xy 126.312389 -436.164514)
			(xy 126.326583 -436.184051) (xy 126.334047 -436.207018) (xy 126.33452 -436.219092) (xy 126.33452 -438.760616)
			(xy 126.334049 -438.77269) (xy 126.326584 -438.795656) (xy 126.312389 -438.815191) (xy 126.292852 -438.829386)
			(xy 126.269886 -438.83685) (xy 126.257812 -438.837324) (xy 125.318012 -438.837324) (xy 125.30594 -438.836826)
			(xy 125.282976 -438.829369) (xy 125.26344 -438.81518) (xy 125.249244 -438.79565) (xy 125.241779 -438.772688)
			(xy 125.241304 -438.760616) (xy 125.241304 -438.252108) (xy 125.241239 -438.248502) (xy 125.240221 -438.241363)
			(xy 125.239272 -438.237884) (xy 125.229445 -438.201653) (xy 125.218859 -438.127336) (xy 125.21819 -438.089802)
			(xy 113.378885 -438.089802) (xy 113.344738 -438.119261) (xy 113.241432 -438.197784) (xy 113.133467 -438.269766)
			(xy 113.021257 -438.334931) (xy 112.90523 -438.39303) (xy 112.785831 -438.443841) (xy 112.663518 -438.487169)
			(xy 112.538759 -438.522847) (xy 112.412032 -438.550739) (xy 112.283822 -438.570739) (xy 112.15462 -438.58277)
			(xy 112.024922 -438.586785) (xy 111.895224 -438.58277) (xy 111.766022 -438.570739) (xy 111.637812 -438.550739)
			(xy 111.511085 -438.522847) (xy 111.386326 -438.487169) (xy 111.264013 -438.443841) (xy 111.144614 -438.39303)
			(xy 111.028587 -438.334931) (xy 110.916377 -438.269766) (xy 110.808412 -438.197784) (xy 110.705106 -438.119261)
			(xy 110.606856 -438.034499) (xy 110.514038 -437.943821) (xy 110.427006 -437.847575) (xy 110.346095 -437.74613)
			(xy 110.271614 -437.639874) (xy 110.203848 -437.529214) (xy 110.143058 -437.414574) (xy 110.089475 -437.296394)
			(xy 110.043306 -437.175125) (xy 110.004726 -437.051232) (xy 109.973885 -436.92519) (xy 109.950899 -436.797482)
			(xy 109.935858 -436.668596) (xy 109.928817 -436.539027) (xy 109.929806 -436.40927) (xy 109.938819 -436.279823)
			(xy 109.955822 -436.151181) (xy 109.98075 -436.023838) (xy 110.013508 -435.89828) (xy 110.05397 -435.77499)
			(xy 110.101982 -435.654438) (xy 110.157358 -435.537087) (xy 110.219888 -435.423387) (xy 110.289331 -435.313772)
			(xy 110.365422 -435.208663) (xy 110.447869 -435.108462) (xy 110.536357 -435.013553) (xy 110.630546 -434.924299)
			(xy 110.679992 -434.88229) (xy 110.690406 -434.873654) (xy 110.699804 -434.849016) (xy 110.682024 -434.73624)
			(xy 110.665768 -434.715412) (xy 110.653322 -434.710332) (xy 110.574304 -434.677407) (xy 110.419107 -434.605131)
			(xy 110.267499 -434.5256) (xy 110.119821 -434.438991) (xy 109.976402 -434.345497) (xy 109.837562 -434.245328)
			(xy 109.703613 -434.138709) (xy 109.574854 -434.025876) (xy 109.451573 -433.907083) (xy 109.334045 -433.782595)
			(xy 109.222533 -433.65269) (xy 109.117287 -433.517659) (xy 109.018541 -433.377804) (xy 108.926517 -433.233438)
			(xy 108.84142 -433.084883) (xy 108.763441 -432.932471) (xy 108.692754 -432.776543) (xy 108.629516 -432.617449)
			(xy 108.57387 -432.455542) (xy 108.52594 -432.291187) (xy 108.485833 -432.124749) (xy 108.453638 -431.956601)
			(xy 108.429428 -431.78712) (xy 108.413257 -431.616683) (xy 108.405161 -431.445673) (xy 108.40466 -431.360072)
			(xy 90.234516 -431.360072) (xy 90.234516 -432.560476) (xy 90.234067 -432.572557) (xy 90.226607 -432.595537)
			(xy 90.21241 -432.615087) (xy 90.192866 -432.629292) (xy 90.169888 -432.636762) (xy 90.157808 -432.637184)
			(xy 89.218008 -432.637184) (xy 89.205923 -432.63678) (xy 89.182937 -432.629312) (xy 89.163384 -432.615105)
			(xy 89.149181 -432.595549) (xy 89.141717 -432.572561) (xy 89.1413 -432.560476) (xy 89.1413 -431.950876)
			(xy 89.141046 -431.945288) (xy 89.139632 -431.931488) (xy 89.138107 -431.903787) (xy 89.137998 -431.889916)
			(xy 86.234524 -431.889916) (xy 86.234524 -432.560476) (xy 86.234067 -432.572556) (xy 86.226608 -432.595535)
			(xy 86.212413 -432.615084) (xy 86.192871 -432.62929) (xy 86.169896 -432.636761) (xy 86.157816 -432.637184)
			(xy 85.218016 -432.637184) (xy 85.205932 -432.636773) (xy 85.182946 -432.629307) (xy 85.163393 -432.615101)
			(xy 85.149189 -432.595547) (xy 85.141726 -432.57256) (xy 85.141308 -432.560476) (xy 85.141308 -431.950876)
			(xy 85.141054 -431.945288) (xy 85.13964 -431.931488) (xy 85.138115 -431.903787) (xy 85.138006 -431.889916)
			(xy 82.234532 -431.889916) (xy 82.234532 -432.560476) (xy 82.234016 -432.572547) (xy 82.226563 -432.595509)
			(xy 82.212379 -432.615045) (xy 82.192852 -432.629241) (xy 82.169895 -432.636708) (xy 82.157824 -432.637184)
			(xy 81.218024 -432.637184) (xy 81.20594 -432.636766) (xy 81.182954 -432.629303) (xy 81.163401 -432.615099)
			(xy 81.149197 -432.595546) (xy 81.141734 -432.57256) (xy 81.141316 -432.560476) (xy 81.141316 -431.950876)
			(xy 81.141062 -431.945288) (xy 81.139648 -431.931488) (xy 81.138123 -431.903787) (xy 81.138014 -431.889916)
			(xy 78.23454 -431.889916) (xy 78.23454 -432.560476) (xy 78.234016 -432.572546) (xy 78.226564 -432.595507)
			(xy 78.212382 -432.615042) (xy 78.192857 -432.629238) (xy 78.169902 -432.636707) (xy 78.157832 -432.637184)
			(xy 77.218032 -432.637184) (xy 77.205949 -432.63676) (xy 77.182963 -432.629298) (xy 77.16341 -432.615096)
			(xy 77.149206 -432.595544) (xy 77.141742 -432.572559) (xy 77.141324 -432.560476) (xy 77.141324 -431.950876)
			(xy 77.14107 -431.945288) (xy 77.139656 -431.931488) (xy 77.138131 -431.903787) (xy 77.138022 -431.889916)
			(xy 73.234804 -431.889916) (xy 73.234804 -432.560476) (xy 73.23432 -432.572525) (xy 73.226894 -432.595449)
			(xy 73.212759 -432.614964) (xy 73.193294 -432.629169) (xy 73.170397 -432.636676) (xy 73.15835 -432.637184)
			(xy 72.218042 -432.637184) (xy 72.205957 -432.636657) (xy 72.182962 -432.629215) (xy 72.163383 -432.615043)
			(xy 72.14913 -432.595523) (xy 72.141593 -432.572559) (xy 72.14108 -432.560476) (xy 72.14108 -431.950876)
			(xy 72.140826 -431.945288) (xy 72.139412 -431.931488) (xy 72.137887 -431.903787) (xy 72.137778 -431.889916)
			(xy 69.234812 -431.889916) (xy 69.234812 -432.560476) (xy 69.23432 -432.572524) (xy 69.226895 -432.595447)
			(xy 69.212762 -432.614962) (xy 69.193299 -432.629166) (xy 69.170404 -432.636675) (xy 69.158358 -432.637184)
			(xy 68.21805 -432.637184) (xy 68.205965 -432.636651) (xy 68.18297 -432.62921) (xy 68.163392 -432.61504)
			(xy 68.149139 -432.595522) (xy 68.141601 -432.572559) (xy 68.141088 -432.560476) (xy 68.141088 -431.950876)
			(xy 68.140834 -431.945288) (xy 68.13942 -431.931488) (xy 68.137895 -431.903787) (xy 68.137786 -431.889916)
			(xy 65.23482 -431.889916) (xy 65.23482 -432.560476) (xy 65.23432 -432.572523) (xy 65.226896 -432.595444)
			(xy 65.212765 -432.614959) (xy 65.193304 -432.629164) (xy 65.170411 -432.636674) (xy 65.158366 -432.637184)
			(xy 64.218058 -432.637184) (xy 64.205969 -432.636729) (xy 64.182971 -432.629264) (xy 64.163393 -432.615073)
			(xy 64.149143 -432.595539) (xy 64.141608 -432.572564) (xy 64.141096 -432.560476) (xy 64.141096 -431.950876)
			(xy 64.140842 -431.945288) (xy 64.139428 -431.931488) (xy 64.137903 -431.903787) (xy 64.137794 -431.889916)
			(xy 61.234828 -431.889916) (xy 61.234828 -432.560476) (xy 61.23432 -432.572522) (xy 61.226897 -432.595442)
			(xy 61.212768 -432.614956) (xy 61.193309 -432.629161) (xy 61.170418 -432.636673) (xy 61.158374 -432.637184)
			(xy 60.218066 -432.637184) (xy 60.205977 -432.636722) (xy 60.182979 -432.629259) (xy 60.163402 -432.61507)
			(xy 60.149152 -432.595538) (xy 60.141616 -432.572563) (xy 60.141104 -432.560476) (xy 60.141104 -431.950876)
			(xy 60.14085 -431.945288) (xy 60.139436 -431.931488) (xy 60.137911 -431.903787) (xy 60.137802 -431.889916)
			(xy 7.00913 -431.889916) (xy 7.00913 -434.48986) (xy 58.137806 -434.48986) (xy 58.137906 -434.475988)
			(xy 58.139431 -434.448287) (xy 58.140854 -434.434488) (xy 58.141108 -434.4289) (xy 58.141108 -433.350924)
			(xy 58.140854 -433.345336) (xy 58.139436 -433.331537) (xy 58.137913 -433.303835) (xy 58.137806 -433.289964)
			(xy 58.137907 -433.276092) (xy 58.139431 -433.248391) (xy 58.140854 -433.234592) (xy 58.141108 -433.229004)
			(xy 58.141108 -432.618896) (xy 58.141557 -432.606845) (xy 58.148992 -432.583918) (xy 58.163135 -432.564401)
			(xy 58.182608 -432.550199) (xy 58.205512 -432.542694) (xy 58.217562 -432.542188) (xy 59.15787 -432.542188)
			(xy 59.169963 -432.542634) (xy 59.19297 -432.550088) (xy 59.212555 -432.564278) (xy 59.226805 -432.58382)
			(xy 59.234329 -432.606805) (xy 59.234832 -432.618896) (xy 59.234832 -435.16042) (xy 59.234358 -435.172468)
			(xy 59.226923 -435.195389) (xy 59.212785 -435.214901) (xy 59.19332 -435.229105) (xy 59.170424 -435.236616)
			(xy 59.158378 -435.237128) (xy 58.21807 -435.237128) (xy 58.205976 -435.236718) (xy 58.182969 -435.229249)
			(xy 58.163386 -435.215049) (xy 58.149138 -435.195502) (xy 58.141612 -435.172513) (xy 58.141108 -435.16042)
			(xy 58.141108 -434.55082) (xy 58.140854 -434.545232) (xy 58.139443 -434.531432) (xy 58.137916 -434.503731)
			(xy 58.137806 -434.48986) (xy 7.00913 -434.48986) (xy 7.00913 -435.489858) (xy 60.137802 -435.489858)
			(xy 60.137902 -435.475986) (xy 60.139427 -435.448285) (xy 60.14085 -435.434486) (xy 60.141104 -435.428898)
			(xy 60.141104 -434.350922) (xy 60.14085 -434.345334) (xy 60.139431 -434.331535) (xy 60.137909 -434.303833)
			(xy 60.137802 -434.289962) (xy 60.137903 -434.27609) (xy 60.139427 -434.248389) (xy 60.14085 -434.23459)
			(xy 60.141104 -434.229002) (xy 60.141104 -433.618894) (xy 60.141606 -433.606783) (xy 60.149091 -433.583745)
			(xy 60.163326 -433.564146) (xy 60.18292 -433.549904) (xy 60.205955 -433.542411) (xy 60.218066 -433.541932)
			(xy 61.157866 -433.541932) (xy 61.169986 -433.542389) (xy 61.193043 -433.549871) (xy 61.212658 -433.564113)
			(xy 61.226911 -433.583721) (xy 61.234405 -433.606774) (xy 61.234828 -433.618894) (xy 61.234828 -434.48986)
			(xy 62.137798 -434.48986) (xy 62.137898 -434.475988) (xy 62.139423 -434.448287) (xy 62.140846 -434.434488)
			(xy 62.1411 -434.4289) (xy 62.1411 -433.350924) (xy 62.140846 -433.345336) (xy 62.139428 -433.331537)
			(xy 62.137905 -433.303835) (xy 62.137798 -433.289964) (xy 62.137899 -433.276092) (xy 62.139423 -433.248391)
			(xy 62.140846 -433.234592) (xy 62.1411 -433.229004) (xy 62.1411 -432.618896) (xy 62.141557 -432.606846)
			(xy 62.14899 -432.58392) (xy 62.163132 -432.564404) (xy 62.182603 -432.550201) (xy 62.205505 -432.542695)
			(xy 62.217554 -432.542188) (xy 63.157862 -432.542188) (xy 63.169954 -432.542641) (xy 63.192962 -432.550093)
			(xy 63.212547 -432.564281) (xy 63.226797 -432.583821) (xy 63.234321 -432.606805) (xy 63.234824 -432.618896)
			(xy 63.234824 -435.16042) (xy 63.234357 -435.172469) (xy 63.226922 -435.195391) (xy 63.212782 -435.214904)
			(xy 63.193315 -435.229108) (xy 63.170417 -435.236618) (xy 63.15837 -435.237128) (xy 62.218062 -435.237128)
			(xy 62.205967 -435.236724) (xy 62.18296 -435.229253) (xy 62.163378 -435.215052) (xy 62.14913 -435.195503)
			(xy 62.141604 -435.172514) (xy 62.1411 -435.16042) (xy 62.1411 -434.55082) (xy 62.140846 -434.545232)
			(xy 62.139435 -434.531432) (xy 62.137908 -434.503731) (xy 62.137798 -434.48986) (xy 61.234828 -434.48986)
			(xy 61.234828 -435.489858) (xy 64.137794 -435.489858) (xy 64.137894 -435.475986) (xy 64.139419 -435.448285)
			(xy 64.140842 -435.434486) (xy 64.141096 -435.428898) (xy 64.141096 -434.350922) (xy 64.140842 -434.345334)
			(xy 64.139423 -434.331535) (xy 64.137901 -434.303833) (xy 64.137794 -434.289962) (xy 64.137895 -434.27609)
			(xy 64.139419 -434.248389) (xy 64.140842 -434.23459) (xy 64.141096 -434.229002) (xy 64.141096 -433.618894)
			(xy 64.141606 -433.606783) (xy 64.14909 -433.583747) (xy 64.163324 -433.564149) (xy 64.182915 -433.549906)
			(xy 64.205948 -433.542412) (xy 64.218058 -433.541932) (xy 65.157858 -433.541932) (xy 65.169978 -433.542396)
			(xy 65.193034 -433.549876) (xy 65.21265 -433.564116) (xy 65.226903 -433.583722) (xy 65.234397 -433.606774)
			(xy 65.23482 -433.618894) (xy 65.23482 -434.48986) (xy 66.13779 -434.48986) (xy 66.13789 -434.475988)
			(xy 66.139415 -434.448287) (xy 66.140838 -434.434488) (xy 66.141092 -434.4289) (xy 66.141092 -433.350924)
			(xy 66.140838 -433.345336) (xy 66.13942 -433.331537) (xy 66.137897 -433.303835) (xy 66.13779 -433.289964)
			(xy 66.137891 -433.276092) (xy 66.139415 -433.248391) (xy 66.140838 -433.234592) (xy 66.141092 -433.229004)
			(xy 66.141092 -432.618896) (xy 66.141556 -432.606846) (xy 66.148989 -432.583922) (xy 66.163129 -432.564407)
			(xy 66.182598 -432.550204) (xy 66.205498 -432.542696) (xy 66.217546 -432.542188) (xy 67.157854 -432.542188)
			(xy 67.169946 -432.542647) (xy 67.192953 -432.550097) (xy 67.212538 -432.564284) (xy 67.226788 -432.583823)
			(xy 67.234313 -432.606806) (xy 67.234816 -432.618896) (xy 67.234816 -435.16042) (xy 67.234357 -435.17247)
			(xy 67.226921 -435.195393) (xy 67.212779 -435.214907) (xy 67.19331 -435.22911) (xy 67.17041 -435.236619)
			(xy 67.158362 -435.237128) (xy 66.218054 -435.237128) (xy 66.205959 -435.236731) (xy 66.182951 -435.229258)
			(xy 66.163369 -435.215054) (xy 66.149122 -435.195505) (xy 66.141596 -435.172514) (xy 66.141092 -435.16042)
			(xy 66.141092 -434.55082) (xy 66.140838 -434.545232) (xy 66.139427 -434.531432) (xy 66.1379 -434.503731)
			(xy 66.13779 -434.48986) (xy 65.23482 -434.48986) (xy 65.23482 -435.489858) (xy 68.137786 -435.489858)
			(xy 68.137886 -435.475986) (xy 68.139411 -435.448285) (xy 68.140834 -435.434486) (xy 68.141088 -435.428898)
			(xy 68.141088 -434.350922) (xy 68.140834 -434.345334) (xy 68.139415 -434.331535) (xy 68.137893 -434.303833)
			(xy 68.137786 -434.289962) (xy 68.137887 -434.27609) (xy 68.139411 -434.248389) (xy 68.140834 -434.23459)
			(xy 68.141088 -434.229002) (xy 68.141088 -433.618894) (xy 68.141606 -433.606784) (xy 68.149089 -433.583749)
			(xy 68.163321 -433.564152) (xy 68.18291 -433.549909) (xy 68.20594 -433.542413) (xy 68.21805 -433.541932)
			(xy 69.15785 -433.541932) (xy 69.169967 -433.542369) (xy 69.19301 -433.549869) (xy 69.212611 -433.564121)
			(xy 69.226851 -433.583729) (xy 69.234338 -433.606777) (xy 69.234812 -433.618894) (xy 69.234812 -434.48986)
			(xy 70.137782 -434.48986) (xy 70.137882 -434.475988) (xy 70.139407 -434.448287) (xy 70.14083 -434.434488)
			(xy 70.141084 -434.4289) (xy 70.141084 -433.350924) (xy 70.14083 -433.345336) (xy 70.139411 -433.331537)
			(xy 70.137889 -433.303835) (xy 70.137782 -433.289964) (xy 70.137883 -433.276092) (xy 70.139408 -433.248391)
			(xy 70.14083 -433.234592) (xy 70.141084 -433.229004) (xy 70.141084 -432.618896) (xy 70.141556 -432.606847)
			(xy 70.148988 -432.583924) (xy 70.163126 -432.56441) (xy 70.182593 -432.550206) (xy 70.205491 -432.542697)
			(xy 70.217538 -432.542188) (xy 71.157846 -432.542188) (xy 71.169943 -432.542569) (xy 71.192953 -432.550044)
			(xy 71.212536 -432.564251) (xy 71.226784 -432.583805) (xy 71.234306 -432.6068) (xy 71.234808 -432.618896)
			(xy 71.234808 -435.16042) (xy 71.234357 -435.17247) (xy 71.22692 -435.195395) (xy 71.212776 -435.21491)
			(xy 71.193305 -435.229113) (xy 71.170403 -435.23662) (xy 71.158354 -435.237128) (xy 70.218046 -435.237128)
			(xy 70.205956 -435.236653) (xy 70.182951 -435.229205) (xy 70.163368 -435.215022) (xy 70.149117 -435.195487)
			(xy 70.141589 -435.172509) (xy 70.141084 -435.16042) (xy 70.141084 -434.55082) (xy 70.14083 -434.545232)
			(xy 70.139419 -434.531432) (xy 70.137892 -434.503731) (xy 70.137782 -434.48986) (xy 69.234812 -434.48986)
			(xy 69.234812 -435.489858) (xy 72.137778 -435.489858) (xy 72.137878 -435.475986) (xy 72.139403 -435.448285)
			(xy 72.140826 -435.434486) (xy 72.14108 -435.428898) (xy 72.14108 -434.350922) (xy 72.140826 -434.345334)
			(xy 72.139407 -434.331535) (xy 72.137885 -434.303833) (xy 72.137778 -434.289962) (xy 72.137879 -434.27609)
			(xy 72.139403 -434.248389) (xy 72.140826 -434.23459) (xy 72.14108 -434.229002) (xy 72.14108 -433.618894)
			(xy 72.141456 -433.606767) (xy 72.148955 -433.583701) (xy 72.163216 -433.564082) (xy 72.182844 -433.549833)
			(xy 72.205915 -433.542348) (xy 72.218042 -433.541932) (xy 73.157842 -433.541932) (xy 73.169958 -433.542376)
			(xy 73.193002 -433.549874) (xy 73.212602 -433.564123) (xy 73.226843 -433.583731) (xy 73.23433 -433.606778)
			(xy 73.234804 -433.618894) (xy 73.234804 -434.48986) (xy 75.138026 -434.48986) (xy 75.138126 -434.475988)
			(xy 75.139651 -434.448287) (xy 75.141074 -434.434488) (xy 75.141328 -434.4289) (xy 75.141328 -433.350924)
			(xy 75.141074 -433.345336) (xy 75.139656 -433.331537) (xy 75.138133 -433.303835) (xy 75.138026 -433.289964)
			(xy 75.138127 -433.276092) (xy 75.139651 -433.248391) (xy 75.141074 -433.234592) (xy 75.141328 -433.229004)
			(xy 75.141328 -432.618896) (xy 75.14171 -432.606809) (xy 75.149183 -432.58382) (xy 75.163396 -432.564267)
			(xy 75.182956 -432.550064) (xy 75.205949 -432.542603) (xy 75.218036 -432.542188) (xy 76.157836 -432.542188)
			(xy 76.169912 -432.542633) (xy 76.19288 -432.550105) (xy 76.212416 -432.564307) (xy 76.226609 -432.583849)
			(xy 76.234072 -432.60682) (xy 76.234544 -432.618896) (xy 76.234544 -435.16042) (xy 76.234053 -435.172492)
			(xy 76.22659 -435.195454) (xy 76.212399 -435.214987) (xy 76.192868 -435.229182) (xy 76.169908 -435.236651)
			(xy 76.157836 -435.237128) (xy 75.218036 -435.237128) (xy 75.205957 -435.236657) (xy 75.182979 -435.229202)
			(xy 75.16343 -435.21501) (xy 75.149224 -435.195471) (xy 75.141752 -435.172499) (xy 75.141328 -435.16042)
			(xy 75.141328 -434.55082) (xy 75.141074 -434.545232) (xy 75.139663 -434.531432) (xy 75.138136 -434.503731)
			(xy 75.138026 -434.48986) (xy 73.234804 -434.48986) (xy 73.234804 -435.489858) (xy 77.138022 -435.489858)
			(xy 77.138122 -435.475986) (xy 77.139647 -435.448285) (xy 77.14107 -435.434486) (xy 77.141324 -435.428898)
			(xy 77.141324 -434.350922) (xy 77.14107 -434.345334) (xy 77.139651 -434.331535) (xy 77.138129 -434.303833)
			(xy 77.138022 -434.289962) (xy 77.138122 -434.27609) (xy 77.139647 -434.248389) (xy 77.14107 -434.23459)
			(xy 77.141324 -434.229002) (xy 77.141324 -433.618894) (xy 77.141802 -433.606806) (xy 77.149259 -433.583808)
			(xy 77.163443 -433.564229) (xy 77.182973 -433.549978) (xy 77.205945 -433.542444) (xy 77.218032 -433.541932)
			(xy 78.157832 -433.541932) (xy 78.169946 -433.542289) (xy 78.19298 -433.549802) (xy 78.212555 -433.564077)
			(xy 78.226747 -433.583713) (xy 78.234161 -433.606779) (xy 78.23454 -433.618894) (xy 78.23454 -434.48986)
			(xy 79.138018 -434.48986) (xy 79.138118 -434.475988) (xy 79.139643 -434.448287) (xy 79.141066 -434.434488)
			(xy 79.14132 -434.4289) (xy 79.14132 -433.350924) (xy 79.141066 -433.345336) (xy 79.139648 -433.331537)
			(xy 79.138125 -433.303835) (xy 79.138018 -433.289964) (xy 79.138119 -433.276092) (xy 79.139643 -433.248391)
			(xy 79.141066 -433.234592) (xy 79.14132 -433.229004) (xy 79.14132 -432.618896) (xy 79.141709 -432.60681)
			(xy 79.149182 -432.583823) (xy 79.163393 -432.56427) (xy 79.182951 -432.550067) (xy 79.205942 -432.542604)
			(xy 79.218028 -432.542188) (xy 80.157828 -432.542188) (xy 80.169904 -432.54264) (xy 80.192871 -432.55011)
			(xy 80.212407 -432.56431) (xy 80.226601 -432.58385) (xy 80.234064 -432.60682) (xy 80.234536 -432.618896)
			(xy 80.234536 -435.16042) (xy 80.234053 -435.172493) (xy 80.226588 -435.195456) (xy 80.212396 -435.21499)
			(xy 80.192863 -435.229185) (xy 80.169901 -435.236652) (xy 80.157828 -435.237128) (xy 79.218028 -435.237128)
			(xy 79.205949 -435.236664) (xy 79.18297 -435.229206) (xy 79.163421 -435.215013) (xy 79.149216 -435.195473)
			(xy 79.141744 -435.172499) (xy 79.14132 -435.16042) (xy 79.14132 -434.55082) (xy 79.141066 -434.545232)
			(xy 79.139655 -434.531432) (xy 79.138128 -434.503731) (xy 79.138018 -434.48986) (xy 78.23454 -434.48986)
			(xy 78.23454 -435.489858) (xy 81.138014 -435.489858) (xy 81.138114 -435.475986) (xy 81.139639 -435.448285)
			(xy 81.141062 -435.434486) (xy 81.141316 -435.428898) (xy 81.141316 -434.350922) (xy 81.141062 -434.345334)
			(xy 81.139643 -434.331535) (xy 81.138121 -434.303833) (xy 81.138014 -434.289962) (xy 81.138114 -434.27609)
			(xy 81.139639 -434.248389) (xy 81.141062 -434.23459) (xy 81.141316 -434.229002) (xy 81.141316 -433.618894)
			(xy 81.141802 -433.606807) (xy 81.149257 -433.58381) (xy 81.16344 -433.564232) (xy 81.182968 -433.549981)
			(xy 81.205938 -433.542445) (xy 81.218024 -433.541932) (xy 82.157824 -433.541932) (xy 82.169937 -433.542296)
			(xy 82.192971 -433.549806) (xy 82.212546 -433.56408) (xy 82.226739 -433.583715) (xy 82.234153 -433.606779)
			(xy 82.234532 -433.618894) (xy 82.234532 -434.48986) (xy 83.13801 -434.48986) (xy 83.13811 -434.475988)
			(xy 83.139635 -434.448287) (xy 83.141058 -434.434488) (xy 83.141312 -434.4289) (xy 83.141312 -433.350924)
			(xy 83.141058 -433.345336) (xy 83.13964 -433.331537) (xy 83.138117 -433.303835) (xy 83.13801 -433.289964)
			(xy 83.138111 -433.276092) (xy 83.139635 -433.248391) (xy 83.141058 -433.234592) (xy 83.141312 -433.229004)
			(xy 83.141312 -432.618896) (xy 83.141709 -432.606811) (xy 83.14918 -432.583825) (xy 83.16339 -432.564273)
			(xy 83.182946 -432.550069) (xy 83.205935 -432.542606) (xy 83.21802 -432.542188) (xy 84.15782 -432.542188)
			(xy 84.169895 -432.542647) (xy 84.192862 -432.550115) (xy 84.212399 -432.564313) (xy 84.226593 -432.583852)
			(xy 84.234055 -432.606821) (xy 84.234528 -432.618896) (xy 84.234528 -435.16042) (xy 84.234053 -435.172494)
			(xy 84.226587 -435.195458) (xy 84.212393 -435.214993) (xy 84.192858 -435.229187) (xy 84.169894 -435.236653)
			(xy 84.15782 -435.237128) (xy 83.21802 -435.237128) (xy 83.205948 -435.236619) (xy 83.182985 -435.229165)
			(xy 83.16345 -435.214979) (xy 83.149254 -435.195451) (xy 83.141787 -435.172491) (xy 83.141312 -435.16042)
			(xy 83.141312 -434.55082) (xy 83.141058 -434.545232) (xy 83.139647 -434.531432) (xy 83.13812 -434.503731)
			(xy 83.13801 -434.48986) (xy 82.234532 -434.48986) (xy 82.234532 -435.489858) (xy 85.138006 -435.489858)
			(xy 85.138106 -435.475986) (xy 85.139631 -435.448285) (xy 85.141054 -435.434486) (xy 85.141308 -435.428898)
			(xy 85.141308 -434.350922) (xy 85.141054 -434.345334) (xy 85.139635 -434.331535) (xy 85.138113 -434.303833)
			(xy 85.138006 -434.289962) (xy 85.138106 -434.27609) (xy 85.139631 -434.248389) (xy 85.141054 -434.23459)
			(xy 85.141308 -434.229002) (xy 85.141308 -433.618894) (xy 85.141802 -433.606807) (xy 85.149256 -433.583812)
			(xy 85.163437 -433.564235) (xy 85.182963 -433.549984) (xy 85.205931 -433.542446) (xy 85.218016 -433.541932)
			(xy 86.157816 -433.541932) (xy 86.169929 -433.542303) (xy 86.192962 -433.549811) (xy 86.212538 -433.564083)
			(xy 86.226731 -433.583716) (xy 86.234145 -433.606779) (xy 86.234524 -433.618894) (xy 86.234524 -434.48986)
			(xy 87.138002 -434.48986) (xy 87.138102 -434.475988) (xy 87.139627 -434.448287) (xy 87.14105 -434.434488)
			(xy 87.141304 -434.4289) (xy 87.141304 -433.350924) (xy 87.14105 -433.345336) (xy 87.139632 -433.331537)
			(xy 87.138109 -433.303835) (xy 87.138002 -433.289964) (xy 87.138103 -433.276092) (xy 87.139627 -433.248391)
			(xy 87.14105 -433.234592) (xy 87.141304 -433.229004) (xy 87.141304 -432.618896) (xy 87.141709 -432.606812)
			(xy 87.149179 -432.583827) (xy 87.163387 -432.564276) (xy 87.182941 -432.550072) (xy 87.205928 -432.542607)
			(xy 87.218012 -432.542188) (xy 88.157812 -432.542188) (xy 88.169887 -432.542654) (xy 88.192854 -432.550119)
			(xy 88.21239 -432.564316) (xy 88.226584 -432.583854) (xy 88.234047 -432.606821) (xy 88.23452 -432.618896)
			(xy 88.23452 -435.16042) (xy 88.234053 -435.172494) (xy 88.226586 -435.19546) (xy 88.21239 -435.214996)
			(xy 88.192853 -435.22919) (xy 88.169886 -435.236654) (xy 88.157812 -435.237128) (xy 87.218012 -435.237128)
			(xy 87.20594 -435.236626) (xy 87.182977 -435.229169) (xy 87.163441 -435.214982) (xy 87.149246 -435.195452)
			(xy 87.141779 -435.172492) (xy 87.141304 -435.16042) (xy 87.141304 -434.55082) (xy 87.14105 -434.545232)
			(xy 87.139639 -434.531432) (xy 87.138112 -434.503731) (xy 87.138002 -434.48986) (xy 86.234524 -434.48986)
			(xy 86.234524 -435.489858) (xy 89.137998 -435.489858) (xy 89.138098 -435.475986) (xy 89.139623 -435.448285)
			(xy 89.141046 -435.434486) (xy 89.1413 -435.428898) (xy 89.1413 -434.350922) (xy 89.141046 -434.345334)
			(xy 89.139627 -434.331535) (xy 89.138105 -434.303833) (xy 89.137998 -434.289962) (xy 89.138099 -434.27609)
			(xy 89.139623 -434.248389) (xy 89.141046 -434.23459) (xy 89.1413 -434.229002) (xy 89.1413 -433.618894)
			(xy 89.141802 -433.606808) (xy 89.149255 -433.583814) (xy 89.163434 -433.564238) (xy 89.182958 -433.549986)
			(xy 89.205924 -433.542447) (xy 89.218008 -433.541932) (xy 90.157808 -433.541932) (xy 90.169921 -433.54231)
			(xy 90.192954 -433.549815) (xy 90.212529 -433.564086) (xy 90.226723 -433.583717) (xy 90.234137 -433.60678)
			(xy 90.234516 -433.618894) (xy 90.234516 -436.160418) (xy 90.234107 -436.172513) (xy 90.22664 -436.195522)
			(xy 90.21244 -436.215105) (xy 90.192892 -436.229353) (xy 90.169902 -436.236877) (xy 90.157808 -436.23738)
			(xy 89.218008 -436.23738) (xy 89.205898 -436.236977) (xy 89.182867 -436.229477) (xy 89.163292 -436.215213)
			(xy 89.149098 -436.195587) (xy 89.14168 -436.17253) (xy 89.1413 -436.160418) (xy 89.1413 -435.550818)
			(xy 89.141046 -435.54523) (xy 89.139635 -435.53143) (xy 89.138108 -435.503729) (xy 89.137998 -435.489858)
			(xy 86.234524 -435.489858) (xy 86.234524 -436.160418) (xy 86.234107 -436.172512) (xy 86.226641 -436.195519)
			(xy 86.212443 -436.215102) (xy 86.192897 -436.229351) (xy 86.169909 -436.236876) (xy 86.157816 -436.23738)
			(xy 85.218016 -436.23738) (xy 85.205906 -436.23697) (xy 85.182876 -436.229472) (xy 85.163301 -436.21521)
			(xy 85.149106 -436.195585) (xy 85.141689 -436.172529) (xy 85.141308 -436.160418) (xy 85.141308 -435.550818)
			(xy 85.141054 -435.54523) (xy 85.139643 -435.53143) (xy 85.138116 -435.503729) (xy 85.138006 -435.489858)
			(xy 82.234532 -435.489858) (xy 82.234532 -436.160418) (xy 82.234108 -436.172511) (xy 82.226643 -436.195517)
			(xy 82.212446 -436.215099) (xy 82.192902 -436.229348) (xy 82.169916 -436.236875) (xy 82.157824 -436.23738)
			(xy 81.218024 -436.23738) (xy 81.205914 -436.236963) (xy 81.182885 -436.229468) (xy 81.163309 -436.215207)
			(xy 81.149115 -436.195584) (xy 81.141697 -436.172529) (xy 81.141316 -436.160418) (xy 81.141316 -435.550818)
			(xy 81.141062 -435.54523) (xy 81.139651 -435.53143) (xy 81.138124 -435.503729) (xy 81.138014 -435.489858)
			(xy 78.23454 -435.489858) (xy 78.23454 -436.160418) (xy 78.234108 -436.172511) (xy 78.226644 -436.195515)
			(xy 78.212449 -436.215097) (xy 78.192907 -436.229346) (xy 78.169923 -436.236874) (xy 78.157832 -436.23738)
			(xy 77.218032 -436.23738) (xy 77.205923 -436.236956) (xy 77.182893 -436.229463) (xy 77.163318 -436.215204)
			(xy 77.149123 -436.195582) (xy 77.141705 -436.172528) (xy 77.141324 -436.160418) (xy 77.141324 -435.550818)
			(xy 77.14107 -435.54523) (xy 77.139659 -435.53143) (xy 77.138132 -435.503729) (xy 77.138022 -435.489858)
			(xy 73.234804 -435.489858) (xy 73.234804 -436.160418) (xy 73.234304 -436.172529) (xy 73.226817 -436.195566)
			(xy 73.212581 -436.215164) (xy 73.192988 -436.229406) (xy 73.169953 -436.236901) (xy 73.157842 -436.23738)
			(xy 72.218042 -436.23738) (xy 72.205923 -436.236905) (xy 72.182869 -436.229426) (xy 72.163255 -436.215188)
			(xy 72.149001 -436.195585) (xy 72.141505 -436.172536) (xy 72.14108 -436.160418) (xy 72.14108 -435.550818)
			(xy 72.140826 -435.54523) (xy 72.139415 -435.53143) (xy 72.137888 -435.503729) (xy 72.137778 -435.489858)
			(xy 69.234812 -435.489858) (xy 69.234812 -436.160418) (xy 69.234305 -436.172529) (xy 69.226818 -436.195564)
			(xy 69.212584 -436.215161) (xy 69.192993 -436.229404) (xy 69.16996 -436.2369) (xy 69.15785 -436.23738)
			(xy 68.21805 -436.23738) (xy 68.205935 -436.236931) (xy 68.182893 -436.229432) (xy 68.163293 -436.215184)
			(xy 68.149053 -436.195578) (xy 68.141564 -436.172534) (xy 68.141088 -436.160418) (xy 68.141088 -435.550818)
			(xy 68.140834 -435.54523) (xy 68.139423 -435.53143) (xy 68.137896 -435.503729) (xy 68.137786 -435.489858)
			(xy 65.23482 -435.489858) (xy 65.23482 -436.160418) (xy 65.234454 -436.172546) (xy 65.226952 -436.195612)
			(xy 65.212688 -436.215231) (xy 65.193058 -436.22948) (xy 65.169986 -436.236964) (xy 65.157858 -436.23738)
			(xy 64.218058 -436.23738) (xy 64.205943 -436.236924) (xy 64.182901 -436.229428) (xy 64.163302 -436.215181)
			(xy 64.149061 -436.195577) (xy 64.141572 -436.172533) (xy 64.141096 -436.160418) (xy 64.141096 -435.550818)
			(xy 64.140842 -435.54523) (xy 64.139431 -435.53143) (xy 64.137904 -435.503729) (xy 64.137794 -435.489858)
			(xy 61.234828 -435.489858) (xy 61.234828 -436.160418) (xy 61.234455 -436.172545) (xy 61.226953 -436.19561)
			(xy 61.212691 -436.215228) (xy 61.193064 -436.229477) (xy 61.169993 -436.236963) (xy 61.157866 -436.23738)
			(xy 60.218066 -436.23738) (xy 60.205951 -436.236918) (xy 60.18291 -436.229423) (xy 60.16331 -436.215178)
			(xy 60.149069 -436.195576) (xy 60.14158 -436.172533) (xy 60.141104 -436.160418) (xy 60.141104 -435.550818)
			(xy 60.14085 -435.54523) (xy 60.139439 -435.53143) (xy 60.137912 -435.503729) (xy 60.137802 -435.489858)
			(xy 7.00913 -435.489858) (xy 7.00913 -438.089802) (xy 58.118248 -438.089802) (xy 58.118692 -438.057913)
			(xy 58.12633 -437.994594) (xy 58.141483 -437.932642) (xy 58.163934 -437.872946) (xy 58.193362 -437.816363)
			(xy 58.229344 -437.763704) (xy 58.271364 -437.715725) (xy 58.294778 -437.69407) (xy 58.298406 -437.690737)
			(xy 58.30442 -437.682935) (xy 58.306716 -437.678576) (xy 58.382662 -437.523382) (xy 58.387361 -437.512865)
			(xy 58.390848 -437.490107) (xy 58.387365 -437.467349) (xy 58.382662 -437.456834) (xy 58.305954 -437.300878)
			(xy 58.303777 -437.296545) (xy 58.298022 -437.288743) (xy 58.294524 -437.285384) (xy 58.271118 -437.263758)
			(xy 58.229154 -437.215797) (xy 58.193224 -437.163163) (xy 58.163844 -437.106611) (xy 58.141435 -437.046952)
			(xy 58.126318 -436.985043) (xy 58.118711 -436.92177) (xy 58.118248 -436.889906) (xy 58.118876 -436.85257)
			(xy 58.129332 -436.778634) (xy 58.139076 -436.742586) (xy 58.140033 -436.739109) (xy 58.141048 -436.731968)
			(xy 58.141108 -436.728362) (xy 58.141108 -436.219092) (xy 58.141553 -436.207041) (xy 58.148989 -436.184113)
			(xy 58.163134 -436.164597) (xy 58.182607 -436.150394) (xy 58.205512 -436.14289) (xy 58.217562 -436.142384)
			(xy 59.15787 -436.142384) (xy 59.169962 -436.142834) (xy 59.192969 -436.150288) (xy 59.212554 -436.164477)
			(xy 59.226804 -436.184017) (xy 59.234329 -436.207001) (xy 59.234832 -436.219092) (xy 59.234832 -438.760616)
			(xy 59.234354 -438.772664) (xy 59.226921 -438.795584) (xy 59.212784 -438.815097) (xy 59.193319 -438.829301)
			(xy 59.170424 -438.836812) (xy 59.158378 -438.837324) (xy 58.21807 -438.837324) (xy 58.205975 -438.836918)
			(xy 58.182968 -438.829448) (xy 58.163385 -438.815247) (xy 58.149137 -438.795699) (xy 58.141612 -438.77271)
			(xy 58.141108 -438.760616) (xy 58.141108 -438.251346) (xy 58.141056 -438.24774) (xy 58.140029 -438.240601)
			(xy 58.139076 -438.237122) (xy 58.129333 -438.201074) (xy 58.118881 -438.127138) (xy 58.118248 -438.089802)
			(xy 7.00913 -438.089802) (xy 7.00913 -439.0898) (xy 60.118244 -439.0898) (xy 60.118688 -439.057911)
			(xy 60.126326 -438.994592) (xy 60.141479 -438.93264) (xy 60.16393 -438.872944) (xy 60.193358 -438.816361)
			(xy 60.22934 -438.763702) (xy 60.27136 -438.715723) (xy 60.294774 -438.694068) (xy 60.298402 -438.690734)
			(xy 60.304416 -438.682933) (xy 60.306712 -438.678574) (xy 60.382658 -438.52338) (xy 60.387358 -438.512863)
			(xy 60.390845 -438.490105) (xy 60.387362 -438.467347) (xy 60.382658 -438.456832) (xy 60.30595 -438.300876)
			(xy 60.303774 -438.296542) (xy 60.298018 -438.28874) (xy 60.29452 -438.285382) (xy 60.271161 -438.263707)
			(xy 60.229194 -438.215755) (xy 60.193259 -438.163129) (xy 60.163873 -438.106586) (xy 60.141456 -438.046935)
			(xy 60.126331 -437.985033) (xy 60.118713 -437.921766) (xy 60.118244 -437.889904) (xy 60.118872 -437.852568)
			(xy 60.129327 -437.778632) (xy 60.139072 -437.742584) (xy 60.140029 -437.739107) (xy 60.141044 -437.731966)
			(xy 60.141104 -437.72836) (xy 60.141104 -437.21909) (xy 60.141603 -437.206978) (xy 60.149089 -437.183941)
			(xy 60.163325 -437.164342) (xy 60.182919 -437.1501) (xy 60.205954 -437.142607) (xy 60.218066 -437.142128)
			(xy 61.157866 -437.142128) (xy 61.169986 -437.142589) (xy 61.193042 -437.15007) (xy 61.212657 -437.164312)
			(xy 61.22691 -437.183918) (xy 61.234404 -437.20697) (xy 61.234828 -437.21909) (xy 61.234828 -438.089802)
			(xy 62.11824 -438.089802) (xy 62.118687 -438.057913) (xy 62.126324 -437.994594) (xy 62.141477 -437.932642)
			(xy 62.163928 -437.872946) (xy 62.193356 -437.816363) (xy 62.229337 -437.763704) (xy 62.271357 -437.715725)
			(xy 62.29477 -437.69407) (xy 62.298397 -437.690736) (xy 62.304412 -437.682935) (xy 62.306708 -437.678576)
			(xy 62.382654 -437.523382) (xy 62.387353 -437.512865) (xy 62.390841 -437.490107) (xy 62.387357 -437.467349)
			(xy 62.382654 -437.456834) (xy 62.305946 -437.300878) (xy 62.303771 -437.296544) (xy 62.298014 -437.288742)
			(xy 62.294516 -437.285384) (xy 62.271109 -437.26376) (xy 62.229145 -437.215798) (xy 62.193215 -437.163163)
			(xy 62.163835 -437.106611) (xy 62.141427 -437.046953) (xy 62.12631 -436.985043) (xy 62.118703 -436.92177)
			(xy 62.11824 -436.889906) (xy 62.118868 -436.85257) (xy 62.129324 -436.778634) (xy 62.139068 -436.742586)
			(xy 62.140025 -436.739109) (xy 62.14104 -436.731968) (xy 62.1411 -436.728362) (xy 62.1411 -436.219092)
			(xy 62.141553 -436.207041) (xy 62.148988 -436.184116) (xy 62.163131 -436.1646) (xy 62.182602 -436.150397)
			(xy 62.205505 -436.142891) (xy 62.217554 -436.142384) (xy 63.157862 -436.142384) (xy 63.169954 -436.142841)
			(xy 63.192961 -436.150292) (xy 63.212545 -436.16448) (xy 63.226795 -436.184019) (xy 63.234321 -436.207002)
			(xy 63.234824 -436.219092) (xy 63.234824 -438.760616) (xy 63.234354 -438.772665) (xy 63.22692 -438.795587)
			(xy 63.212781 -438.8151) (xy 63.193314 -438.829304) (xy 63.170417 -438.836814) (xy 63.15837 -438.837324)
			(xy 62.218062 -438.837324) (xy 62.205967 -438.836924) (xy 62.182959 -438.829453) (xy 62.163377 -438.81525)
			(xy 62.149129 -438.795701) (xy 62.141604 -438.77271) (xy 62.1411 -438.760616) (xy 62.1411 -438.251346)
			(xy 62.141048 -438.24774) (xy 62.140021 -438.240601) (xy 62.139068 -438.237122) (xy 62.129325 -438.201074)
			(xy 62.118873 -438.127138) (xy 62.11824 -438.089802) (xy 61.234828 -438.089802) (xy 61.234828 -439.0898)
			(xy 64.118236 -439.0898) (xy 64.118683 -439.057911) (xy 64.12632 -438.994592) (xy 64.141473 -438.93264)
			(xy 64.163924 -438.872945) (xy 64.193352 -438.816361) (xy 64.229333 -438.763702) (xy 64.271353 -438.715723)
			(xy 64.294766 -438.694068) (xy 64.298398 -438.690739) (xy 64.304414 -438.682937) (xy 64.306704 -438.678574)
			(xy 64.38265 -438.52338) (xy 64.387351 -438.512864) (xy 64.390838 -438.490105) (xy 64.387354 -438.467347)
			(xy 64.38265 -438.456832) (xy 64.305942 -438.300876) (xy 64.303768 -438.296542) (xy 64.29801 -438.28874)
			(xy 64.294512 -438.285382) (xy 64.271151 -438.263709) (xy 64.229184 -438.215756) (xy 64.19325 -438.16313)
			(xy 64.163864 -438.106586) (xy 64.141448 -438.046936) (xy 64.126323 -437.985033) (xy 64.118705 -437.921766)
			(xy 64.118236 -437.889904) (xy 64.118864 -437.852568) (xy 64.12932 -437.778632) (xy 64.139064 -437.742584)
			(xy 64.140021 -437.739107) (xy 64.141036 -437.731966) (xy 64.141096 -437.72836) (xy 64.141096 -437.21909)
			(xy 64.141603 -437.206979) (xy 64.149088 -437.183943) (xy 64.163322 -437.164345) (xy 64.182914 -437.150102)
			(xy 64.205947 -437.142608) (xy 64.218058 -437.142128) (xy 65.157858 -437.142128) (xy 65.169978 -437.142595)
			(xy 65.193033 -437.150075) (xy 65.212648 -437.164315) (xy 65.226901 -437.18392) (xy 65.234396 -437.206971)
			(xy 65.23482 -437.21909) (xy 65.23482 -438.089802) (xy 66.118232 -438.089802) (xy 66.118682 -438.057913)
			(xy 66.126319 -437.994594) (xy 66.141471 -437.932643) (xy 66.163922 -437.872947) (xy 66.193349 -437.816364)
			(xy 66.22933 -437.763705) (xy 66.271349 -437.715725) (xy 66.294762 -437.69407) (xy 66.298393 -437.69074)
			(xy 66.30441 -437.682938) (xy 66.3067 -437.678576) (xy 66.382646 -437.523382) (xy 66.387346 -437.512865)
			(xy 66.390834 -437.490107) (xy 66.38735 -437.467349) (xy 66.382646 -437.456834) (xy 66.305938 -437.300878)
			(xy 66.303764 -437.296543) (xy 66.298006 -437.288742) (xy 66.294508 -437.285384) (xy 66.271099 -437.263761)
			(xy 66.229135 -437.215799) (xy 66.193206 -437.163164) (xy 66.163827 -437.106612) (xy 66.141418 -437.046953)
			(xy 66.126302 -436.985043) (xy 66.118695 -436.92177) (xy 66.118232 -436.889906) (xy 66.118861 -436.85257)
			(xy 66.129316 -436.778634) (xy 66.13906 -436.742586) (xy 66.140019 -436.739109) (xy 66.141032 -436.731968)
			(xy 66.141092 -436.728362) (xy 66.141092 -436.219092) (xy 66.141553 -436.207042) (xy 66.148987 -436.184118)
			(xy 66.163128 -436.164603) (xy 66.182597 -436.1504) (xy 66.205498 -436.142892) (xy 66.217546 -436.142384)
			(xy 67.157854 -436.142384) (xy 67.169946 -436.142847) (xy 67.192952 -436.150297) (xy 67.212537 -436.164483)
			(xy 67.226787 -436.18402) (xy 67.234312 -436.207002) (xy 67.234816 -436.219092) (xy 67.234816 -438.760616)
			(xy 67.234354 -438.772665) (xy 67.226919 -438.795589) (xy 67.212778 -438.815103) (xy 67.193309 -438.829306)
			(xy 67.17041 -438.836815) (xy 67.158362 -438.837324) (xy 66.218054 -438.837324) (xy 66.205958 -438.836931)
			(xy 66.18295 -438.829457) (xy 66.163368 -438.815253) (xy 66.14912 -438.795702) (xy 66.141596 -438.77271)
			(xy 66.141092 -438.760616) (xy 66.141092 -438.251346) (xy 66.141037 -438.24774) (xy 66.140011 -438.240601)
			(xy 66.13906 -438.237122) (xy 66.129317 -438.201074) (xy 66.118865 -438.127138) (xy 66.118232 -438.089802)
			(xy 65.23482 -438.089802) (xy 65.23482 -439.0898) (xy 68.118228 -439.0898) (xy 68.118678 -439.057911)
			(xy 68.126315 -438.994592) (xy 68.141467 -438.932641) (xy 68.163918 -438.872945) (xy 68.193345 -438.816362)
			(xy 68.229326 -438.763703) (xy 68.271345 -438.715723) (xy 68.294758 -438.694068) (xy 68.298389 -438.690738)
			(xy 68.304406 -438.682936) (xy 68.306696 -438.678574) (xy 68.382642 -438.52338) (xy 68.387343 -438.512864)
			(xy 68.390831 -438.490105) (xy 68.387346 -438.467347) (xy 68.382642 -438.456832) (xy 68.305934 -438.300876)
			(xy 68.303761 -438.296541) (xy 68.298003 -438.28874) (xy 68.294504 -438.285382) (xy 68.271142 -438.263711)
			(xy 68.229175 -438.215757) (xy 68.193242 -438.163131) (xy 68.163856 -438.106587) (xy 68.14144 -438.046936)
			(xy 68.126314 -437.985033) (xy 68.118697 -437.921766) (xy 68.118228 -437.889904) (xy 68.118856 -437.852568)
			(xy 68.129312 -437.778632) (xy 68.139056 -437.742584) (xy 68.140015 -437.739107) (xy 68.141028 -437.731966)
			(xy 68.141088 -437.72836) (xy 68.141088 -437.21909) (xy 68.141603 -437.20698) (xy 68.149087 -437.183945)
			(xy 68.163319 -437.164348) (xy 68.182909 -437.150105) (xy 68.20594 -437.142609) (xy 68.21805 -437.142128)
			(xy 69.15785 -437.142128) (xy 69.169966 -437.142569) (xy 69.193009 -437.150069) (xy 69.212609 -437.164319)
			(xy 69.22685 -437.183927) (xy 69.234337 -437.206974) (xy 69.234812 -437.21909) (xy 69.234812 -438.089802)
			(xy 70.118224 -438.089802) (xy 70.118676 -438.057913) (xy 70.126313 -437.994595) (xy 70.141465 -437.932643)
			(xy 70.163916 -437.872947) (xy 70.193342 -437.816364) (xy 70.229323 -437.763705) (xy 70.271341 -437.715725)
			(xy 70.294754 -437.69407) (xy 70.298385 -437.690739) (xy 70.304401 -437.682938) (xy 70.306692 -437.678576)
			(xy 70.382638 -437.523382) (xy 70.387338 -437.512865) (xy 70.390826 -437.490107) (xy 70.387342 -437.467349)
			(xy 70.382638 -437.456834) (xy 70.30593 -437.300878) (xy 70.303757 -437.296543) (xy 70.297999 -437.288742)
			(xy 70.2945 -437.285384) (xy 70.271089 -437.263763) (xy 70.229126 -437.2158) (xy 70.193197 -437.163165)
			(xy 70.163818 -437.106612) (xy 70.14141 -437.046953) (xy 70.126294 -436.985043) (xy 70.118687 -436.92177)
			(xy 70.118224 -436.889906) (xy 70.118853 -436.85257) (xy 70.129308 -436.778634) (xy 70.139052 -436.742586)
			(xy 70.140011 -436.739109) (xy 70.141024 -436.731968) (xy 70.141084 -436.728362) (xy 70.141084 -436.219092)
			(xy 70.141553 -436.207043) (xy 70.148986 -436.18412) (xy 70.163125 -436.164606) (xy 70.182592 -436.150402)
			(xy 70.205491 -436.142893) (xy 70.217538 -436.142384) (xy 71.157846 -436.142384) (xy 71.169942 -436.142769)
			(xy 71.192952 -436.150244) (xy 71.212535 -436.16445) (xy 71.226782 -436.184003) (xy 71.234305 -436.206997)
			(xy 71.234808 -436.219092) (xy 71.234808 -438.760616) (xy 71.234354 -438.772666) (xy 71.226918 -438.795591)
			(xy 71.212775 -438.815106) (xy 71.193304 -438.829309) (xy 71.170403 -438.836816) (xy 71.158354 -438.837324)
			(xy 70.218046 -438.837324) (xy 70.205955 -438.836853) (xy 70.18295 -438.829404) (xy 70.163366 -438.81522)
			(xy 70.149115 -438.795685) (xy 70.141589 -438.772705) (xy 70.141084 -438.760616) (xy 70.141084 -438.251346)
			(xy 70.141029 -438.24774) (xy 70.140003 -438.240601) (xy 70.139052 -438.237122) (xy 70.129309 -438.201074)
			(xy 70.118856 -438.127138) (xy 70.118224 -438.089802) (xy 69.234812 -438.089802) (xy 69.234812 -439.0898)
			(xy 72.11822 -439.0898) (xy 72.118672 -439.057911) (xy 72.126309 -438.994593) (xy 72.141462 -438.932641)
			(xy 72.163912 -438.872946) (xy 72.193339 -438.816362) (xy 72.229319 -438.763703) (xy 72.271337 -438.715723)
			(xy 72.29475 -438.694068) (xy 72.29838 -438.690737) (xy 72.304397 -438.682936) (xy 72.306688 -438.678574)
			(xy 72.382634 -438.52338) (xy 72.387336 -438.512864) (xy 72.390824 -438.490105) (xy 72.387339 -438.467347)
			(xy 72.382634 -438.456832) (xy 72.305926 -438.300876) (xy 72.303754 -438.29654) (xy 72.297995 -438.28874)
			(xy 72.294496 -438.285382) (xy 72.271132 -438.263712) (xy 72.229166 -438.215758) (xy 72.193233 -438.163132)
			(xy 72.163847 -438.106587) (xy 72.141431 -438.046936) (xy 72.126306 -437.985033) (xy 72.118689 -437.921766)
			(xy 72.11822 -437.889904) (xy 72.118849 -437.852568) (xy 72.129304 -437.778632) (xy 72.139048 -437.742584)
			(xy 72.140007 -437.739107) (xy 72.14102 -437.731966) (xy 72.14108 -437.72836) (xy 72.14108 -437.21909)
			(xy 72.141452 -437.206963) (xy 72.148952 -437.183896) (xy 72.163215 -437.164278) (xy 72.182843 -437.150029)
			(xy 72.205914 -437.142544) (xy 72.218042 -437.142128) (xy 73.157842 -437.142128) (xy 73.169958 -437.142576)
			(xy 73.193001 -437.150073) (xy 73.212601 -437.164322) (xy 73.226841 -437.183928) (xy 73.234329 -437.206974)
			(xy 73.234804 -437.21909) (xy 73.234804 -438.089802) (xy 75.118468 -438.089802) (xy 75.118906 -438.057913)
			(xy 75.126543 -437.994593) (xy 75.141697 -437.932641) (xy 75.164149 -437.872945) (xy 75.193579 -437.816361)
			(xy 75.229562 -437.763703) (xy 75.271584 -437.715724) (xy 75.294998 -437.69407) (xy 75.298628 -437.690739)
			(xy 75.304641 -437.682936) (xy 75.306936 -437.678576) (xy 75.382882 -437.523382) (xy 75.387585 -437.512866)
			(xy 75.391076 -437.490107) (xy 75.387589 -437.467348) (xy 75.382882 -437.456834) (xy 75.306174 -437.300878)
			(xy 75.303994 -437.296547) (xy 75.29824 -437.288744) (xy 75.294744 -437.285384) (xy 75.271342 -437.263754)
			(xy 75.229377 -437.215794) (xy 75.193446 -437.163161) (xy 75.164065 -437.10661) (xy 75.141656 -437.046952)
			(xy 75.126539 -436.985042) (xy 75.118931 -436.92177) (xy 75.118468 -436.889906) (xy 75.119095 -436.85257)
			(xy 75.129551 -436.778633) (xy 75.139296 -436.742586) (xy 75.140254 -436.739109) (xy 75.141268 -436.731968)
			(xy 75.141328 -436.728362) (xy 75.141328 -436.219092) (xy 75.141754 -436.207039) (xy 75.149192 -436.184108)
			(xy 75.163341 -436.16459) (xy 75.18282 -436.150388) (xy 75.20573 -436.142887) (xy 75.217782 -436.142384)
			(xy 76.15809 -436.142384) (xy 76.170183 -436.142817) (xy 76.193191 -436.150276) (xy 76.212775 -436.16447)
			(xy 76.227024 -436.184014) (xy 76.234549 -436.207) (xy 76.235052 -436.219092) (xy 76.235052 -438.760616)
			(xy 76.234555 -438.772662) (xy 76.227124 -438.795579) (xy 76.212991 -438.81509) (xy 76.193532 -438.829295)
			(xy 76.170642 -438.83681) (xy 76.158598 -438.837324) (xy 75.21829 -438.837324) (xy 75.206196 -438.8369)
			(xy 75.183189 -438.829436) (xy 75.163607 -438.81524) (xy 75.149358 -438.795695) (xy 75.141832 -438.772708)
			(xy 75.141328 -438.760616) (xy 75.141328 -438.251346) (xy 75.141275 -438.24774) (xy 75.140248 -438.240601)
			(xy 75.139296 -438.237122) (xy 75.129554 -438.201074) (xy 75.119101 -438.127138) (xy 75.118468 -438.089802)
			(xy 73.234804 -438.089802) (xy 73.234804 -439.0898) (xy 77.118464 -439.0898) (xy 77.118902 -439.057911)
			(xy 77.126539 -438.994591) (xy 77.141693 -438.932639) (xy 77.164146 -438.872943) (xy 77.193575 -438.816359)
			(xy 77.229558 -438.763701) (xy 77.27158 -438.715722) (xy 77.294994 -438.694068) (xy 77.298624 -438.690737)
			(xy 77.304637 -438.682934) (xy 77.306932 -438.678574) (xy 77.382878 -438.52338) (xy 77.387582 -438.512864)
			(xy 77.391073 -438.490105) (xy 77.387585 -438.467346) (xy 77.382878 -438.456832) (xy 77.30617 -438.300876)
			(xy 77.303991 -438.296544) (xy 77.298237 -438.288741) (xy 77.29474 -438.285382) (xy 77.271385 -438.263703)
			(xy 77.229417 -438.215752) (xy 77.193481 -438.163127) (xy 77.164094 -438.106585) (xy 77.141677 -438.046934)
			(xy 77.126551 -437.985032) (xy 77.118933 -437.921766) (xy 77.118464 -437.889904) (xy 77.119091 -437.852568)
			(xy 77.129547 -437.778631) (xy 77.139292 -437.742584) (xy 77.14025 -437.739107) (xy 77.141264 -437.731966)
			(xy 77.141324 -437.72836) (xy 77.141324 -437.21909) (xy 77.141803 -437.206976) (xy 77.149291 -437.183935)
			(xy 77.163532 -437.164335) (xy 77.183132 -437.150093) (xy 77.206172 -437.142604) (xy 77.218286 -437.142128)
			(xy 78.158086 -437.142128) (xy 78.170207 -437.142572) (xy 78.193264 -437.150059) (xy 78.212878 -437.164305)
			(xy 78.22713 -437.183915) (xy 78.234624 -437.206969) (xy 78.235048 -437.21909) (xy 78.235048 -438.089802)
			(xy 79.11846 -438.089802) (xy 79.1189 -438.057913) (xy 79.126538 -437.994593) (xy 79.141691 -437.932641)
			(xy 79.164143 -437.872945) (xy 79.193572 -437.816362) (xy 79.229555 -437.763703) (xy 79.271576 -437.715725)
			(xy 79.29499 -437.69407) (xy 79.298619 -437.690738) (xy 79.304632 -437.682935) (xy 79.306928 -437.678576)
			(xy 79.382874 -437.523382) (xy 79.387577 -437.512866) (xy 79.391068 -437.490107) (xy 79.387581 -437.467348)
			(xy 79.382874 -437.456834) (xy 79.306166 -437.300878) (xy 79.303987 -437.296546) (xy 79.298233 -437.288743)
			(xy 79.294736 -437.285384) (xy 79.271332 -437.263756) (xy 79.229368 -437.215795) (xy 79.193437 -437.163161)
			(xy 79.164057 -437.10661) (xy 79.141647 -437.046952) (xy 79.126531 -436.985043) (xy 79.118923 -436.92177)
			(xy 79.11846 -436.889906) (xy 79.119087 -436.85257) (xy 79.129543 -436.778634) (xy 79.139288 -436.742586)
			(xy 79.140245 -436.739109) (xy 79.14126 -436.731968) (xy 79.14132 -436.728362) (xy 79.14132 -436.219092)
			(xy 79.141754 -436.207039) (xy 79.149191 -436.18411) (xy 79.163338 -436.164593) (xy 79.182815 -436.150391)
			(xy 79.205723 -436.142888) (xy 79.217774 -436.142384) (xy 80.158082 -436.142384) (xy 80.170175 -436.142824)
			(xy 80.193182 -436.150281) (xy 80.212766 -436.164473) (xy 80.227016 -436.184015) (xy 80.234541 -436.207)
			(xy 80.235044 -436.219092) (xy 80.235044 -438.760616) (xy 80.234554 -438.772663) (xy 80.227123 -438.795581)
			(xy 80.212988 -438.815093) (xy 80.193527 -438.829297) (xy 80.170635 -438.836811) (xy 80.15859 -438.837324)
			(xy 79.218282 -438.837324) (xy 79.206188 -438.836907) (xy 79.183181 -438.829441) (xy 79.163598 -438.815243)
			(xy 79.149349 -438.795697) (xy 79.141824 -438.772709) (xy 79.14132 -438.760616) (xy 79.14132 -438.251346)
			(xy 79.141268 -438.24774) (xy 79.140241 -438.240601) (xy 79.139288 -438.237122) (xy 79.129546 -438.201074)
			(xy 79.119093 -438.127138) (xy 79.11846 -438.089802) (xy 78.235048 -438.089802) (xy 78.235048 -439.0898)
			(xy 81.118456 -439.0898) (xy 81.118896 -439.057911) (xy 81.126534 -438.994591) (xy 81.141687 -438.932639)
			(xy 81.16414 -438.872943) (xy 81.193568 -438.81636) (xy 81.229551 -438.763701) (xy 81.271572 -438.715723)
			(xy 81.294986 -438.694068) (xy 81.298615 -438.690736) (xy 81.304628 -438.682933) (xy 81.306924 -438.678574)
			(xy 81.38287 -438.52338) (xy 81.387575 -438.512864) (xy 81.391066 -438.490105) (xy 81.387578 -438.467346)
			(xy 81.38287 -438.456832) (xy 81.306162 -438.300876) (xy 81.303984 -438.296543) (xy 81.298229 -438.288741)
			(xy 81.294732 -438.285382) (xy 81.271375 -438.263705) (xy 81.229407 -438.215753) (xy 81.193472 -438.163128)
			(xy 81.164086 -438.106585) (xy 81.141669 -438.046935) (xy 81.126543 -437.985032) (xy 81.118925 -437.921766)
			(xy 81.118456 -437.889904) (xy 81.119083 -437.852568) (xy 81.129539 -437.778632) (xy 81.139284 -437.742584)
			(xy 81.140242 -437.739107) (xy 81.141256 -437.731966) (xy 81.141316 -437.72836) (xy 81.141316 -437.21909)
			(xy 81.141803 -437.206977) (xy 81.14929 -437.183937) (xy 81.163529 -437.164338) (xy 81.183127 -437.150096)
			(xy 81.206165 -437.142605) (xy 81.218278 -437.142128) (xy 82.158078 -437.142128) (xy 82.170199 -437.142579)
			(xy 82.193255 -437.150064) (xy 82.21287 -437.164308) (xy 82.227122 -437.183916) (xy 82.234616 -437.20697)
			(xy 82.23504 -437.21909) (xy 82.23504 -438.089802) (xy 83.118452 -438.089802) (xy 83.118895 -438.057913)
			(xy 83.126532 -437.994593) (xy 83.141686 -437.932641) (xy 83.164137 -437.872946) (xy 83.193565 -437.816362)
			(xy 83.229548 -437.763704) (xy 83.271568 -437.715725) (xy 83.294982 -437.69407) (xy 83.29861 -437.690737)
			(xy 83.304624 -437.682935) (xy 83.30692 -437.678576) (xy 83.382866 -437.523382) (xy 83.387564 -437.512865)
			(xy 83.391052 -437.490107) (xy 83.387569 -437.467349) (xy 83.382866 -437.456834) (xy 83.306158 -437.300878)
			(xy 83.303981 -437.296545) (xy 83.298225 -437.288743) (xy 83.294728 -437.285384) (xy 83.271323 -437.263757)
			(xy 83.229358 -437.215796) (xy 83.193428 -437.163162) (xy 83.164048 -437.106611) (xy 83.141639 -437.046952)
			(xy 83.126522 -436.985043) (xy 83.118915 -436.92177) (xy 83.118452 -436.889906) (xy 83.11908 -436.85257)
			(xy 83.129535 -436.778634) (xy 83.13928 -436.742586) (xy 83.140237 -436.739109) (xy 83.141252 -436.731968)
			(xy 83.141312 -436.728362) (xy 83.141312 -436.219092) (xy 83.141753 -436.20704) (xy 83.14919 -436.184112)
			(xy 83.163335 -436.164596) (xy 83.18281 -436.150393) (xy 83.205716 -436.142889) (xy 83.217766 -436.142384)
			(xy 84.158074 -436.142384) (xy 84.170167 -436.14283) (xy 84.193174 -436.150285) (xy 84.212758 -436.164476)
			(xy 84.227008 -436.184017) (xy 84.234533 -436.207001) (xy 84.235036 -436.219092) (xy 84.235036 -438.760616)
			(xy 84.234554 -438.772663) (xy 84.227121 -438.795583) (xy 84.212985 -438.815096) (xy 84.193522 -438.8293)
			(xy 84.170628 -438.836812) (xy 84.158582 -438.837324) (xy 83.218274 -438.837324) (xy 83.206179 -438.836914)
			(xy 83.183172 -438.829446) (xy 83.163589 -438.815246) (xy 83.149341 -438.795698) (xy 83.141816 -438.772709)
			(xy 83.141312 -438.760616) (xy 83.141312 -438.251346) (xy 83.14126 -438.24774) (xy 83.140233 -438.240601)
			(xy 83.13928 -438.237122) (xy 83.129537 -438.201074) (xy 83.119085 -438.127138) (xy 83.118452 -438.089802)
			(xy 82.23504 -438.089802) (xy 82.23504 -439.0898) (xy 85.118448 -439.0898) (xy 85.118891 -439.057911)
			(xy 85.126528 -438.994592) (xy 85.141682 -438.93264) (xy 85.164134 -438.872944) (xy 85.193562 -438.816361)
			(xy 85.229544 -438.763702) (xy 85.271564 -438.715723) (xy 85.294978 -438.694068) (xy 85.298606 -438.690735)
			(xy 85.30462 -438.682933) (xy 85.306916 -438.678574) (xy 85.382862 -438.52338) (xy 85.387562 -438.512863)
			(xy 85.391049 -438.490105) (xy 85.387565 -438.467347) (xy 85.382862 -438.456832) (xy 85.306154 -438.300876)
			(xy 85.303978 -438.296543) (xy 85.298222 -438.288741) (xy 85.294724 -438.285382) (xy 85.271366 -438.263706)
			(xy 85.229398 -438.215754) (xy 85.193464 -438.163129) (xy 85.164077 -438.106586) (xy 85.14166 -438.046935)
			(xy 85.126535 -437.985033) (xy 85.118917 -437.921766) (xy 85.118448 -437.889904) (xy 85.119076 -437.852568)
			(xy 85.129531 -437.778632) (xy 85.139276 -437.742584) (xy 85.140234 -437.739107) (xy 85.141248 -437.731966)
			(xy 85.141308 -437.72836) (xy 85.141308 -437.21909) (xy 85.141803 -437.206978) (xy 85.149289 -437.18394)
			(xy 85.163526 -437.164341) (xy 85.183122 -437.150098) (xy 85.206158 -437.142606) (xy 85.21827 -437.142128)
			(xy 86.15807 -437.142128) (xy 86.17019 -437.142585) (xy 86.193246 -437.150068) (xy 86.212861 -437.16431)
			(xy 86.227114 -437.183918) (xy 86.234608 -437.20697) (xy 86.235032 -437.21909) (xy 86.235032 -438.089802)
			(xy 87.118444 -438.089802) (xy 87.11889 -438.057913) (xy 87.126527 -437.994594) (xy 87.14168 -437.932642)
			(xy 87.164131 -437.872946) (xy 87.193559 -437.816363) (xy 87.229541 -437.763704) (xy 87.27156 -437.715725)
			(xy 87.294974 -437.69407) (xy 87.298601 -437.690736) (xy 87.304616 -437.682935) (xy 87.306912 -437.678576)
			(xy 87.382858 -437.523382) (xy 87.387557 -437.512865) (xy 87.391044 -437.490107) (xy 87.387561 -437.467349)
			(xy 87.382858 -437.456834) (xy 87.30615 -437.300878) (xy 87.303974 -437.296545) (xy 87.298218 -437.288743)
			(xy 87.29472 -437.285384) (xy 87.271313 -437.263759) (xy 87.229349 -437.215797) (xy 87.19342 -437.163163)
			(xy 87.16404 -437.106611) (xy 87.141631 -437.046953) (xy 87.126514 -436.985043) (xy 87.118907 -436.92177)
			(xy 87.118444 -436.889906) (xy 87.119072 -436.85257) (xy 87.129528 -436.778634) (xy 87.139272 -436.742586)
			(xy 87.140229 -436.739109) (xy 87.141244 -436.731968) (xy 87.141304 -436.728362) (xy 87.141304 -436.219092)
			(xy 87.141753 -436.207041) (xy 87.149189 -436.184115) (xy 87.163332 -436.164599) (xy 87.182805 -436.150396)
			(xy 87.205709 -436.14289) (xy 87.217758 -436.142384) (xy 88.158066 -436.142384) (xy 88.170158 -436.142837)
			(xy 88.193165 -436.15029) (xy 88.212749 -436.164478) (xy 88.227 -436.184018) (xy 88.234525 -436.207001)
			(xy 88.235028 -436.219092) (xy 88.235028 -438.760616) (xy 88.234554 -438.772664) (xy 88.22712 -438.795586)
			(xy 88.212982 -438.815099) (xy 88.193517 -438.829302) (xy 88.170621 -438.836813) (xy 88.158574 -438.837324)
			(xy 87.218266 -438.837324) (xy 87.206171 -438.836921) (xy 87.183163 -438.829451) (xy 87.163581 -438.815249)
			(xy 87.149333 -438.7957) (xy 87.141808 -438.77271) (xy 87.141304 -438.760616) (xy 87.141304 -438.251346)
			(xy 87.141252 -438.24774) (xy 87.140225 -438.240601) (xy 87.139272 -438.237122) (xy 87.129529 -438.201074)
			(xy 87.119077 -438.127138) (xy 87.118444 -438.089802) (xy 86.235032 -438.089802) (xy 86.235032 -439.0898)
			(xy 89.11844 -439.0898) (xy 89.118886 -439.057911) (xy 89.126523 -438.994592) (xy 89.141676 -438.93264)
			(xy 89.164127 -438.872944) (xy 89.193555 -438.816361) (xy 89.229537 -438.763702) (xy 89.271557 -438.715723)
			(xy 89.29497 -438.694068) (xy 89.298597 -438.690734) (xy 89.304612 -438.682933) (xy 89.306908 -438.678574)
			(xy 89.382854 -438.52338) (xy 89.387555 -438.512864) (xy 89.391042 -438.490105) (xy 89.387558 -438.467347)
			(xy 89.382854 -438.456832) (xy 89.306146 -438.300876) (xy 89.303971 -438.296542) (xy 89.298214 -438.28874)
			(xy 89.294716 -438.285382) (xy 89.271356 -438.263708) (xy 89.229389 -438.215755) (xy 89.193455 -438.16313)
			(xy 89.164069 -438.106586) (xy 89.141652 -438.046935) (xy 89.126527 -437.985033) (xy 89.118909 -437.921766)
			(xy 89.11844 -437.889904) (xy 89.119068 -437.852568) (xy 89.129524 -437.778632) (xy 89.139268 -437.742584)
			(xy 89.140225 -437.739107) (xy 89.14124 -437.731966) (xy 89.1413 -437.72836) (xy 89.1413 -437.21909)
			(xy 89.141803 -437.206979) (xy 89.149288 -437.183942) (xy 89.163524 -437.164343) (xy 89.183117 -437.150101)
			(xy 89.206151 -437.142607) (xy 89.218262 -437.142128) (xy 90.158062 -437.142128) (xy 90.170182 -437.142592)
			(xy 90.193238 -437.150073) (xy 90.212853 -437.164313) (xy 90.227105 -437.183919) (xy 90.2346 -437.20697)
			(xy 90.235024 -437.21909) (xy 90.235024 -439.0898) (xy 127.218186 -439.0898) (xy 127.218616 -439.05791)
			(xy 127.226255 -438.99459) (xy 127.241409 -438.932637) (xy 127.263862 -438.872941) (xy 127.293293 -438.816358)
			(xy 127.329278 -438.7637) (xy 127.371301 -438.715722) (xy 127.394716 -438.694068) (xy 127.398349 -438.690739)
			(xy 127.404359 -438.682934) (xy 127.406654 -438.678574) (xy 127.4826 -438.52338) (xy 127.487303 -438.512864)
			(xy 127.490793 -438.490105) (xy 127.487306 -438.467346) (xy 127.4826 -438.456832) (xy 127.405892 -438.300876)
			(xy 127.403726 -438.296537) (xy 127.397963 -438.288738) (xy 127.394462 -438.285382) (xy 127.371092 -438.263719)
			(xy 127.329127 -438.215763) (xy 127.293195 -438.163135) (xy 127.263811 -438.10659) (xy 127.241396 -438.046938)
			(xy 127.226272 -437.985034) (xy 127.218655 -437.921766) (xy 127.218186 -437.889904) (xy 127.21884 -437.852369)
			(xy 127.229416 -437.778047) (xy 127.239268 -437.741822) (xy 127.240218 -437.738343) (xy 127.241237 -437.731204)
			(xy 127.2413 -437.727598) (xy 127.2413 -437.21909) (xy 127.241798 -437.207004) (xy 127.249253 -437.18401)
			(xy 127.263433 -437.164434) (xy 127.282957 -437.150182) (xy 127.305924 -437.142643) (xy 127.318008 -437.142128)
			(xy 128.257808 -437.142128) (xy 128.26992 -437.14251) (xy 128.292952 -437.150015) (xy 128.312528 -437.164284)
			(xy 128.326721 -437.183915) (xy 128.334137 -437.206976) (xy 128.334516 -437.21909) (xy 128.334516 -438.089802)
			(xy 129.218182 -438.089802) (xy 129.218615 -438.057913) (xy 129.226253 -437.994592) (xy 129.241407 -437.93264)
			(xy 129.26386 -437.872944) (xy 129.29329 -437.81636) (xy 129.329274 -437.763702) (xy 129.371297 -437.715724)
			(xy 129.394712 -437.69407) (xy 129.398344 -437.690741) (xy 129.404355 -437.682936) (xy 129.40665 -437.678576)
			(xy 129.482596 -437.523382) (xy 129.487298 -437.512866) (xy 129.490788 -437.490107) (xy 129.487302 -437.467348)
			(xy 129.482596 -437.456834) (xy 129.405888 -437.300878) (xy 129.403722 -437.296539) (xy 129.397959 -437.28874)
			(xy 129.394458 -437.285384) (xy 129.371059 -437.263751) (xy 129.329093 -437.215792) (xy 129.293161 -437.163159)
			(xy 129.26378 -437.106609) (xy 129.24137 -437.046951) (xy 129.226253 -436.985042) (xy 129.218645 -436.92177)
			(xy 129.218182 -436.889906) (xy 129.218836 -436.852371) (xy 129.229412 -436.778049) (xy 129.239264 -436.741824)
			(xy 129.240213 -436.738345) (xy 129.241233 -436.731206) (xy 129.241296 -436.7276) (xy 129.241296 -436.219092)
			(xy 129.241758 -436.207017) (xy 129.249223 -436.184049) (xy 129.26342 -436.164511) (xy 129.282959 -436.150317)
			(xy 129.305929 -436.142856) (xy 129.318004 -436.142384) (xy 130.257804 -436.142384) (xy 130.269878 -436.142861)
			(xy 130.292844 -436.150323) (xy 130.31238 -436.164517) (xy 130.326575 -436.184053) (xy 130.334039 -436.207018)
			(xy 130.334512 -436.219092) (xy 130.334512 -438.760616) (xy 130.334049 -438.772691) (xy 130.326583 -438.795658)
			(xy 130.312386 -438.815194) (xy 130.292847 -438.829388) (xy 130.269879 -438.836851) (xy 130.257804 -438.837324)
			(xy 129.318004 -438.837324) (xy 129.305931 -438.836833) (xy 129.282967 -438.829373) (xy 129.263431 -438.815183)
			(xy 129.249236 -438.795651) (xy 129.241771 -438.772689) (xy 129.241296 -438.760616) (xy 129.241296 -438.252108)
			(xy 129.241232 -438.248502) (xy 129.240213 -438.241363) (xy 129.239264 -438.237884) (xy 129.229437 -438.201653)
			(xy 129.218851 -438.127336) (xy 129.218182 -438.089802) (xy 128.334516 -438.089802) (xy 128.334516 -439.0898)
			(xy 131.218178 -439.0898) (xy 131.218611 -439.057911) (xy 131.226249 -438.99459) (xy 131.241403 -438.932638)
			(xy 131.263856 -438.872942) (xy 131.293286 -438.816359) (xy 131.329271 -438.7637) (xy 131.371293 -438.715722)
			(xy 131.394708 -438.694068) (xy 131.39834 -438.690738) (xy 131.404351 -438.682934) (xy 131.406646 -438.678574)
			(xy 131.482592 -438.52338) (xy 131.487295 -438.512864) (xy 131.490785 -438.490105) (xy 131.487299 -438.467346)
			(xy 131.482592 -438.456832) (xy 131.405884 -438.300876) (xy 131.403719 -438.296536) (xy 131.397956 -438.288738)
			(xy 131.394454 -438.285382) (xy 131.371102 -438.2637) (xy 131.329133 -438.21575) (xy 131.293197 -438.163126)
			(xy 131.263809 -438.106584) (xy 131.241391 -438.046934) (xy 131.226265 -437.985032) (xy 131.218647 -437.921766)
			(xy 131.218178 -437.889904) (xy 131.218832 -437.852369) (xy 131.229408 -437.778047) (xy 131.23926 -437.741822)
			(xy 131.240212 -437.738343) (xy 131.241229 -437.731204) (xy 131.241292 -437.727598) (xy 131.241292 -437.21909)
			(xy 131.241798 -437.207005) (xy 131.249252 -437.184012) (xy 131.26343 -437.164436) (xy 131.282952 -437.150184)
			(xy 131.305917 -437.142644) (xy 131.318 -437.142128) (xy 132.2578 -437.142128) (xy 132.269912 -437.142516)
			(xy 132.292944 -437.150019) (xy 132.312519 -437.164287) (xy 132.326713 -437.183916) (xy 132.334129 -437.206977)
			(xy 132.334508 -437.21909) (xy 132.334508 -438.089802) (xy 133.218174 -438.089802) (xy 133.21861 -438.057913)
			(xy 133.226247 -437.994593) (xy 133.241401 -437.93264) (xy 133.263854 -437.872944) (xy 133.293283 -437.816361)
			(xy 133.329267 -437.763702) (xy 133.371289 -437.715724) (xy 133.394704 -437.69407) (xy 133.398335 -437.69074)
			(xy 133.404347 -437.682936) (xy 133.406642 -437.678576) (xy 133.482588 -437.523382) (xy 133.48729 -437.512866)
			(xy 133.490781 -437.490107) (xy 133.487295 -437.467348) (xy 133.482588 -437.456834) (xy 133.40588 -437.300878)
			(xy 133.403715 -437.296538) (xy 133.397952 -437.28874) (xy 133.39445 -437.285384) (xy 133.371049 -437.263753)
			(xy 133.329084 -437.215793) (xy 133.293153 -437.16316) (xy 133.263772 -437.106609) (xy 133.241362 -437.046951)
			(xy 133.226245 -436.985042) (xy 133.218637 -436.92177) (xy 133.218174 -436.889906) (xy 133.218829 -436.852371)
			(xy 133.229404 -436.778049) (xy 133.239256 -436.741824) (xy 133.240207 -436.738345) (xy 133.241225 -436.731206)
			(xy 133.241288 -436.7276) (xy 133.241288 -436.219092) (xy 133.241757 -436.207017) (xy 133.249222 -436.184051)
			(xy 133.263417 -436.164514) (xy 133.282954 -436.15032) (xy 133.305921 -436.142857) (xy 133.317996 -436.142384)
			(xy 134.257796 -436.142384) (xy 134.26987 -436.142868) (xy 134.292835 -436.150328) (xy 134.312372 -436.16452)
			(xy 134.326567 -436.184054) (xy 134.334031 -436.207019) (xy 134.334504 -436.219092) (xy 134.334504 -438.760616)
			(xy 134.334049 -438.772692) (xy 134.326582 -438.79566) (xy 134.312383 -438.815197) (xy 134.292842 -438.829391)
			(xy 134.269872 -438.836852) (xy 134.257796 -438.837324) (xy 133.317996 -438.837324) (xy 133.305923 -438.836839)
			(xy 133.282958 -438.829378) (xy 133.263423 -438.815186) (xy 133.249228 -438.795652) (xy 133.241763 -438.772689)
			(xy 133.241288 -438.760616) (xy 133.241288 -438.252108) (xy 133.24122 -438.248502) (xy 133.240203 -438.241363)
			(xy 133.239256 -438.237884) (xy 133.229429 -438.201653) (xy 133.218843 -438.127336) (xy 133.218174 -438.089802)
			(xy 132.334508 -438.089802) (xy 132.334508 -439.0898) (xy 135.21817 -439.0898) (xy 135.218606 -439.057911)
			(xy 135.226244 -438.994591) (xy 135.241398 -438.932638) (xy 135.26385 -438.872942) (xy 135.29328 -438.816359)
			(xy 135.329263 -438.763701) (xy 135.371285 -438.715722) (xy 135.3947 -438.694068) (xy 135.398331 -438.690738)
			(xy 135.404343 -438.682934) (xy 135.406638 -438.678574) (xy 135.482584 -438.52338) (xy 135.487288 -438.512864)
			(xy 135.490778 -438.490105) (xy 135.487291 -438.467346) (xy 135.482584 -438.456832) (xy 135.405876 -438.300876)
			(xy 135.403696 -438.296545) (xy 135.397942 -438.288742) (xy 135.394446 -438.285382) (xy 135.371092 -438.263702)
			(xy 135.329123 -438.215751) (xy 135.293188 -438.163127) (xy 135.263801 -438.106584) (xy 135.241383 -438.046934)
			(xy 135.226257 -437.985032) (xy 135.218639 -437.921766) (xy 135.21817 -437.889904) (xy 135.218824 -437.852369)
			(xy 135.2294 -437.778047) (xy 135.239252 -437.741822) (xy 135.240203 -437.738343) (xy 135.241221 -437.731204)
			(xy 135.241284 -437.727598) (xy 135.241284 -437.21909) (xy 135.2417 -437.206996) (xy 135.249165 -437.183987)
			(xy 135.263363 -437.164404) (xy 135.28291 -437.150155) (xy 135.305899 -437.142631) (xy 135.317992 -437.142128)
			(xy 136.257792 -437.142128) (xy 136.269903 -437.142523) (xy 136.292935 -437.150024) (xy 136.312511 -437.16429)
			(xy 136.326705 -437.183918) (xy 136.334121 -437.206977) (xy 136.3345 -437.21909) (xy 136.3345 -438.089802)
			(xy 137.218166 -438.089802) (xy 137.218604 -438.057913) (xy 137.226242 -437.994593) (xy 137.241396 -437.932641)
			(xy 137.263848 -437.872945) (xy 137.293277 -437.816361) (xy 137.32926 -437.763703) (xy 137.371282 -437.715724)
			(xy 137.394696 -437.69407) (xy 137.398326 -437.690739) (xy 137.404338 -437.682935) (xy 137.406634 -437.678576)
			(xy 137.48258 -437.523382) (xy 137.487283 -437.512866) (xy 137.490774 -437.490107) (xy 137.487287 -437.467348)
			(xy 137.48258 -437.456834) (xy 137.405872 -437.300878) (xy 137.403692 -437.296546) (xy 137.397939 -437.288743)
			(xy 137.394442 -437.285384) (xy 137.37104 -437.263754) (xy 137.329074 -437.215794) (xy 137.293144 -437.163161)
			(xy 137.263763 -437.10661) (xy 137.241353 -437.046952) (xy 137.226237 -436.985042) (xy 137.218629 -436.92177)
			(xy 137.218166 -436.889906) (xy 137.218821 -436.852371) (xy 137.229397 -436.778049) (xy 137.239248 -436.741824)
			(xy 137.240199 -436.738345) (xy 137.241217 -436.731206) (xy 137.24128 -436.7276) (xy 137.24128 -436.219092)
			(xy 137.241757 -436.207018) (xy 137.249221 -436.184053) (xy 137.263414 -436.164517) (xy 137.282949 -436.150322)
			(xy 137.305914 -436.142858) (xy 137.317988 -436.142384) (xy 138.257788 -436.142384) (xy 138.269869 -436.142823)
			(xy 138.29285 -436.150286) (xy 138.3124 -436.164486) (xy 138.326605 -436.184032) (xy 138.334074 -436.207011)
			(xy 138.334496 -436.219092) (xy 138.334496 -438.760616) (xy 138.334049 -438.772693) (xy 138.326581 -438.795662)
			(xy 138.31238 -438.8152) (xy 138.292837 -438.829394) (xy 138.269865 -438.836853) (xy 138.257788 -438.837324)
			(xy 137.317988 -438.837324) (xy 137.305914 -438.836846) (xy 137.28295 -438.829382) (xy 137.263414 -438.815189)
			(xy 137.24922 -438.795654) (xy 137.241755 -438.77269) (xy 137.24128 -438.760616) (xy 137.24128 -438.252108)
			(xy 137.241212 -438.248502) (xy 137.240195 -438.241363) (xy 137.239248 -438.237884) (xy 137.229421 -438.201653)
			(xy 137.218834 -438.127336) (xy 137.218166 -438.089802) (xy 136.3345 -438.089802) (xy 136.3345 -439.0898)
			(xy 139.218162 -439.0898) (xy 139.2186 -439.057911) (xy 139.226238 -438.994591) (xy 139.241392 -438.932639)
			(xy 139.263844 -438.872943) (xy 139.293273 -438.81636) (xy 139.329256 -438.763701) (xy 139.371278 -438.715723)
			(xy 139.394692 -438.694068) (xy 139.398322 -438.690737) (xy 139.404334 -438.682933) (xy 139.40663 -438.678574)
			(xy 139.482576 -438.52338) (xy 139.48728 -438.512864) (xy 139.490771 -438.490105) (xy 139.487284 -438.467346)
			(xy 139.482576 -438.456832) (xy 139.405868 -438.300876) (xy 139.40369 -438.296544) (xy 139.397935 -438.288741)
			(xy 139.394438 -438.285382) (xy 139.371083 -438.263703) (xy 139.329114 -438.215752) (xy 139.293179 -438.163127)
			(xy 139.263792 -438.106585) (xy 139.241375 -438.046934) (xy 139.226249 -437.985032) (xy 139.218631 -437.921766)
			(xy 139.218162 -437.889904) (xy 139.218817 -437.852369) (xy 139.229392 -437.778047) (xy 139.239244 -437.741822)
			(xy 139.240195 -437.738343) (xy 139.241213 -437.731204) (xy 139.241276 -437.727598) (xy 139.241276 -437.21909)
			(xy 139.2417 -437.206996) (xy 139.249164 -437.183989) (xy 139.26336 -437.164407) (xy 139.282905 -437.150158)
			(xy 139.305892 -437.142632) (xy 139.317984 -437.142128) (xy 140.257784 -437.142128) (xy 140.269895 -437.14253)
			(xy 140.292926 -437.150029) (xy 140.312502 -437.164293) (xy 140.326696 -437.18392) (xy 140.334112 -437.206978)
			(xy 140.334492 -437.21909) (xy 140.334492 -438.089802) (xy 142.21841 -438.089802) (xy 142.218867 -438.057913)
			(xy 142.226504 -437.994595) (xy 142.241655 -437.932644) (xy 142.264105 -437.872948) (xy 142.293531 -437.816365)
			(xy 142.329511 -437.763706) (xy 142.371528 -437.715726) (xy 142.39494 -437.69407) (xy 142.398569 -437.690737)
			(xy 142.404587 -437.682938) (xy 142.406878 -437.678576) (xy 142.482824 -437.523382) (xy 142.487525 -437.512865)
			(xy 142.491014 -437.490107) (xy 142.487529 -437.467348) (xy 142.482824 -437.456834) (xy 142.406116 -437.300878)
			(xy 142.403945 -437.296542) (xy 142.398186 -437.288741) (xy 142.394686 -437.285384) (xy 142.371273 -437.263766)
			(xy 142.32931 -437.215802) (xy 142.293382 -437.163167) (xy 142.264003 -437.106613) (xy 142.241596 -437.046954)
			(xy 142.22648 -436.985044) (xy 142.218873 -436.92177) (xy 142.21841 -436.889906) (xy 142.219063 -436.852371)
			(xy 142.22964 -436.778049) (xy 142.239492 -436.741824) (xy 142.240442 -436.738345) (xy 142.241461 -436.731206)
			(xy 142.241524 -436.7276) (xy 142.241524 -436.219092) (xy 142.241906 -436.207006) (xy 142.24938 -436.184017)
			(xy 142.263593 -436.164464) (xy 142.283153 -436.150262) (xy 142.306145 -436.1428) (xy 142.318232 -436.142384)
			(xy 143.258032 -436.142384) (xy 143.270107 -436.142837) (xy 143.293074 -436.150307) (xy 143.31261 -436.164507)
			(xy 143.326804 -436.184047) (xy 143.334267 -436.207016) (xy 143.33474 -436.219092) (xy 143.33474 -438.760616)
			(xy 143.33425 -438.772688) (xy 143.326787 -438.79565) (xy 143.312596 -438.815184) (xy 143.293065 -438.829379)
			(xy 143.270104 -438.836847) (xy 143.258032 -438.837324) (xy 142.318232 -438.837324) (xy 142.306153 -438.83686)
			(xy 142.283174 -438.829403) (xy 142.263624 -438.81521) (xy 142.249418 -438.795669) (xy 142.241947 -438.772695)
			(xy 142.241524 -438.760616) (xy 142.241524 -438.252108) (xy 142.241458 -438.248502) (xy 142.24044 -438.241363)
			(xy 142.239492 -438.237884) (xy 142.229664 -438.201654) (xy 142.219078 -438.127336) (xy 142.21841 -438.089802)
			(xy 140.334492 -438.089802) (xy 140.334492 -439.0898) (xy 144.218406 -439.0898) (xy 144.218863 -439.057911)
			(xy 144.2265 -438.994593) (xy 144.241652 -438.932642) (xy 144.264102 -438.872947) (xy 144.293527 -438.816363)
			(xy 144.329507 -438.763704) (xy 144.371524 -438.715724) (xy 144.394936 -438.694068) (xy 144.398565 -438.690735)
			(xy 144.404583 -438.682936) (xy 144.406874 -438.678574) (xy 144.48282 -438.52338) (xy 144.487522 -438.512864)
			(xy 144.491011 -438.490105) (xy 144.487526 -438.467346) (xy 144.48282 -438.456832) (xy 144.406112 -438.300876)
			(xy 144.403942 -438.296539) (xy 144.398182 -438.288739) (xy 144.394682 -438.285382) (xy 144.371315 -438.263715)
			(xy 144.32935 -438.21576) (xy 144.293417 -438.163133) (xy 144.264032 -438.106588) (xy 144.241617 -438.046937)
			(xy 144.226492 -437.985033) (xy 144.218875 -437.921766) (xy 144.218406 -437.889904) (xy 144.219059 -437.852369)
			(xy 144.229636 -437.778047) (xy 144.239488 -437.741822) (xy 144.240438 -437.738343) (xy 144.241457 -437.731204)
			(xy 144.24152 -437.727598) (xy 144.24152 -437.21909) (xy 144.241999 -437.207002) (xy 144.249456 -437.184004)
			(xy 144.26364 -437.164426) (xy 144.28317 -437.150176) (xy 144.306142 -437.14264) (xy 144.318228 -437.142128)
			(xy 145.258028 -437.142128) (xy 145.270141 -437.142493) (xy 145.293174 -437.150003) (xy 145.312749 -437.164277)
			(xy 145.326942 -437.183911) (xy 145.334357 -437.206975) (xy 145.334736 -437.21909) (xy 145.334736 -438.089802)
			(xy 146.218402 -438.089802) (xy 146.218862 -438.057914) (xy 146.226498 -437.994595) (xy 146.24165 -437.932644)
			(xy 146.264099 -437.872949) (xy 146.293524 -437.816366) (xy 146.329503 -437.763706) (xy 146.37152 -437.715726)
			(xy 146.394932 -437.69407) (xy 146.398566 -437.690743) (xy 146.404576 -437.682937) (xy 146.40687 -437.678576)
			(xy 146.482816 -437.523382) (xy 146.487517 -437.512865) (xy 146.491007 -437.490107) (xy 146.487522 -437.467348)
			(xy 146.482816 -437.456834) (xy 146.406108 -437.300878) (xy 146.403939 -437.296541) (xy 146.398178 -437.288741)
			(xy 146.394678 -437.285384) (xy 146.371263 -437.263768) (xy 146.329301 -437.215804) (xy 146.293373 -437.163167)
			(xy 146.263995 -437.106614) (xy 146.241587 -437.046954) (xy 146.226472 -436.985044) (xy 146.218865 -436.921771)
			(xy 146.218402 -436.889906) (xy 146.219056 -436.852371) (xy 146.229632 -436.778049) (xy 146.239484 -436.741824)
			(xy 146.240434 -436.738345) (xy 146.241453 -436.731206) (xy 146.241516 -436.7276) (xy 146.241516 -436.219092)
			(xy 146.241906 -436.207006) (xy 146.249379 -436.184019) (xy 146.26359 -436.164467) (xy 146.283148 -436.150264)
			(xy 146.306138 -436.142801) (xy 146.318224 -436.142384) (xy 147.258024 -436.142384) (xy 147.270099 -436.142844)
			(xy 147.293066 -436.150312) (xy 147.312601 -436.16451) (xy 147.326795 -436.184049) (xy 147.334259 -436.207017)
			(xy 147.334732 -436.219092) (xy 147.334732 -438.760616) (xy 147.33425 -438.772689) (xy 147.326786 -438.795653)
			(xy 147.312593 -438.815187) (xy 147.29306 -438.829382) (xy 147.270097 -438.836848) (xy 147.258024 -438.837324)
			(xy 146.318224 -438.837324) (xy 146.306144 -438.836867) (xy 146.283165 -438.829408) (xy 146.263616 -438.815213)
			(xy 146.24941 -438.795671) (xy 146.241939 -438.772696) (xy 146.241516 -438.760616) (xy 146.241516 -438.252108)
			(xy 146.241451 -438.248502) (xy 146.240432 -438.241363) (xy 146.239484 -438.237884) (xy 146.229656 -438.201654)
			(xy 146.21907 -438.127336) (xy 146.218402 -438.089802) (xy 145.334736 -438.089802) (xy 145.334736 -439.0898)
			(xy 148.218398 -439.0898) (xy 148.218825 -439.05791) (xy 148.226463 -438.99459) (xy 148.241618 -438.932637)
			(xy 148.264072 -438.87294) (xy 148.293503 -438.816357) (xy 148.329488 -438.763699) (xy 148.371512 -438.715722)
			(xy 148.394928 -438.694068) (xy 148.398562 -438.690741) (xy 148.404572 -438.682935) (xy 148.406866 -438.678574)
			(xy 148.482812 -438.52338) (xy 148.487515 -438.512864) (xy 148.491004 -438.490105) (xy 148.487518 -438.467346)
			(xy 148.482812 -438.456832) (xy 148.406104 -438.300876) (xy 148.403936 -438.296538) (xy 148.398174 -438.288739)
			(xy 148.394674 -438.285382) (xy 148.371306 -438.263717) (xy 148.329341 -438.215762) (xy 148.293408 -438.163134)
			(xy 148.264024 -438.106589) (xy 148.241609 -438.046937) (xy 148.226484 -437.985034) (xy 148.218867 -437.921766)
			(xy 148.218398 -437.889904) (xy 148.219051 -437.852369) (xy 148.229628 -437.778047) (xy 148.23948 -437.741822)
			(xy 148.24043 -437.738343) (xy 148.241449 -437.731204) (xy 148.241512 -437.727598) (xy 148.241512 -437.21909)
			(xy 148.241999 -437.207003) (xy 148.249455 -437.184007) (xy 148.263637 -437.164429) (xy 148.283165 -437.150178)
			(xy 148.306134 -437.142641) (xy 148.31822 -437.142128) (xy 149.25802 -437.142128) (xy 149.270133 -437.1425)
			(xy 149.293165 -437.150008) (xy 149.312741 -437.16428) (xy 149.326934 -437.183913) (xy 149.334349 -437.206976)
			(xy 149.334728 -437.21909) (xy 149.334728 -438.089802) (xy 150.218394 -438.089802) (xy 150.218823 -438.057912)
			(xy 150.226461 -437.994592) (xy 150.241616 -437.932639) (xy 150.264069 -437.872943) (xy 150.2935 -437.81636)
			(xy 150.329485 -437.763701) (xy 150.371509 -437.715724) (xy 150.394924 -437.69407) (xy 150.398557 -437.690742)
			(xy 150.404567 -437.682936) (xy 150.406862 -437.678576) (xy 150.482808 -437.523382) (xy 150.487509 -437.512865)
			(xy 150.490999 -437.490107) (xy 150.487514 -437.467348) (xy 150.482808 -437.456834) (xy 150.4061 -437.300878)
			(xy 150.403932 -437.29654) (xy 150.398171 -437.288741) (xy 150.39467 -437.285384) (xy 150.371253 -437.263769)
			(xy 150.329292 -437.215805) (xy 150.293364 -437.163168) (xy 150.263986 -437.106615) (xy 150.241579 -437.046955)
			(xy 150.226464 -436.985044) (xy 150.218857 -436.921771) (xy 150.218394 -436.889906) (xy 150.219048 -436.852371)
			(xy 150.229624 -436.778049) (xy 150.239476 -436.741824) (xy 150.240425 -436.738345) (xy 150.241445 -436.731206)
			(xy 150.241508 -436.7276) (xy 150.241508 -436.219092) (xy 150.241906 -436.207007) (xy 150.249378 -436.184021)
			(xy 150.263587 -436.16447) (xy 150.283143 -436.150267) (xy 150.306131 -436.142802) (xy 150.318216 -436.142384)
			(xy 151.258016 -436.142384) (xy 151.270091 -436.142851) (xy 151.293057 -436.150317) (xy 151.312593 -436.164513)
			(xy 151.326787 -436.18405) (xy 151.334251 -436.207017) (xy 151.334724 -436.219092) (xy 151.334724 -438.760616)
			(xy 151.33425 -438.77269) (xy 151.326785 -438.795655) (xy 151.31259 -438.81519) (xy 151.293055 -438.829385)
			(xy 151.27009 -438.83685) (xy 151.258016 -438.837324) (xy 150.318216 -438.837324) (xy 150.306144 -438.836822)
			(xy 150.28318 -438.829366) (xy 150.263644 -438.815179) (xy 150.249448 -438.795649) (xy 150.241983 -438.772688)
			(xy 150.241508 -438.760616) (xy 150.241508 -438.252108) (xy 150.241443 -438.248502) (xy 150.240424 -438.241363)
			(xy 150.239476 -438.237884) (xy 150.22965 -438.201653) (xy 150.219063 -438.127336) (xy 150.218394 -438.089802)
			(xy 149.334728 -438.089802) (xy 149.334728 -439.0898) (xy 152.21839 -439.0898) (xy 152.218819 -439.05791)
			(xy 152.226457 -438.99459) (xy 152.241612 -438.932637) (xy 152.264066 -438.872941) (xy 152.293496 -438.816358)
			(xy 152.329481 -438.7637) (xy 152.371505 -438.715722) (xy 152.39492 -438.694068) (xy 152.398553 -438.69074)
			(xy 152.404563 -438.682934) (xy 152.406858 -438.678574) (xy 152.482804 -438.52338) (xy 152.487507 -438.512864)
			(xy 152.490996 -438.490105) (xy 152.48751 -438.467346) (xy 152.482804 -438.456832) (xy 152.406096 -438.300876)
			(xy 152.403929 -438.296538) (xy 152.398167 -438.288738) (xy 152.394666 -438.285382) (xy 152.371296 -438.263719)
			(xy 152.329332 -438.215763) (xy 152.2934 -438.163135) (xy 152.264015 -438.10659) (xy 152.2416 -438.046937)
			(xy 152.226476 -437.985034) (xy 152.218859 -437.921766) (xy 152.21839 -437.889904) (xy 152.219044 -437.852369)
			(xy 152.22962 -437.778047) (xy 152.239472 -437.741822) (xy 152.240422 -437.738343) (xy 152.241441 -437.731204)
			(xy 152.241504 -437.727598) (xy 152.241504 -437.21909) (xy 152.241998 -437.207004) (xy 152.249453 -437.184009)
			(xy 152.263634 -437.164432) (xy 152.28316 -437.150181) (xy 152.306127 -437.142643) (xy 152.318212 -437.142128)
			(xy 153.258012 -437.142128) (xy 153.270124 -437.142506) (xy 153.293157 -437.150012) (xy 153.312732 -437.164283)
			(xy 153.326925 -437.183914) (xy 153.334341 -437.206976) (xy 153.33472 -437.21909) (xy 153.33472 -438.089802)
			(xy 154.218386 -438.089802) (xy 154.218818 -438.057912) (xy 154.226456 -437.994592) (xy 154.24161 -437.93264)
			(xy 154.264063 -437.872943) (xy 154.293493 -437.81636) (xy 154.329478 -437.763702) (xy 154.371501 -437.715724)
			(xy 154.394916 -437.69407) (xy 154.398548 -437.690741) (xy 154.404559 -437.682936) (xy 154.406854 -437.678576)
			(xy 154.4828 -437.523382) (xy 154.487502 -437.512866) (xy 154.490992 -437.490107) (xy 154.487506 -437.467348)
			(xy 154.4828 -437.456834) (xy 154.406092 -437.300878) (xy 154.403925 -437.296539) (xy 154.398163 -437.28874)
			(xy 154.394662 -437.285384) (xy 154.371244 -437.263771) (xy 154.329283 -437.215806) (xy 154.293356 -437.163169)
			(xy 154.263978 -437.106615) (xy 154.241571 -437.046955) (xy 154.226456 -436.985044) (xy 154.218849 -436.921771)
			(xy 154.218386 -436.889906) (xy 154.21904 -436.852371) (xy 154.229616 -436.778049) (xy 154.239468 -436.741824)
			(xy 154.240417 -436.738345) (xy 154.241437 -436.731206) (xy 154.2415 -436.7276) (xy 154.2415 -436.219092)
			(xy 154.241958 -436.207016) (xy 154.249423 -436.184047) (xy 154.263621 -436.16451) (xy 154.283162 -436.150316)
			(xy 154.306132 -436.142855) (xy 154.318208 -436.142384) (xy 155.258008 -436.142384) (xy 155.270082 -436.142857)
			(xy 155.293048 -436.150321) (xy 155.312584 -436.164516) (xy 155.326779 -436.184052) (xy 155.334243 -436.207018)
			(xy 155.334716 -436.219092) (xy 155.334716 -438.760616) (xy 155.334249 -438.772691) (xy 155.326783 -438.795657)
			(xy 155.312587 -438.815193) (xy 155.29305 -438.829387) (xy 155.270083 -438.836851) (xy 155.258008 -438.837324)
			(xy 154.318208 -438.837324) (xy 154.306135 -438.836829) (xy 154.283171 -438.829371) (xy 154.263635 -438.815182)
			(xy 154.24944 -438.79565) (xy 154.241975 -438.772688) (xy 154.2415 -438.760616) (xy 154.2415 -438.252108)
			(xy 154.241435 -438.248502) (xy 154.240417 -438.241363) (xy 154.239468 -438.237884) (xy 154.229641 -438.201653)
			(xy 154.219055 -438.127336) (xy 154.218386 -438.089802) (xy 153.33472 -438.089802) (xy 153.33472 -439.0898)
			(xy 156.218382 -439.0898) (xy 156.218814 -439.05791) (xy 156.226452 -438.99459) (xy 156.241606 -438.932638)
			(xy 156.264059 -438.872941) (xy 156.29349 -438.816358) (xy 156.329474 -438.7637) (xy 156.371497 -438.715722)
			(xy 156.394912 -438.694068) (xy 156.398544 -438.690739) (xy 156.404555 -438.682934) (xy 156.40685 -438.678574)
			(xy 156.482796 -438.52338) (xy 156.487499 -438.512864) (xy 156.490989 -438.490105) (xy 156.487502 -438.467346)
			(xy 156.482796 -438.456832) (xy 156.406088 -438.300876) (xy 156.403922 -438.296537) (xy 156.398159 -438.288738)
			(xy 156.394658 -438.285382) (xy 156.371306 -438.263699) (xy 156.329337 -438.215749) (xy 156.293401 -438.163125)
			(xy 156.264013 -438.106583) (xy 156.241596 -438.046934) (xy 156.226469 -437.985032) (xy 156.218851 -437.921766)
			(xy 156.218382 -437.889904) (xy 156.219036 -437.852369) (xy 156.229612 -437.778047) (xy 156.239464 -437.741822)
			(xy 156.240413 -437.738343) (xy 156.241433 -437.731204) (xy 156.241496 -437.727598) (xy 156.241496 -437.21909)
			(xy 156.241998 -437.207004) (xy 156.249452 -437.184011) (xy 156.263631 -437.164435) (xy 156.283155 -437.150183)
			(xy 156.30612 -437.142644) (xy 156.318204 -437.142128) (xy 157.258004 -437.142128) (xy 157.270116 -437.142513)
			(xy 157.293148 -437.150017) (xy 157.312724 -437.164286) (xy 157.326917 -437.183916) (xy 157.334333 -437.206977)
			(xy 157.334712 -437.21909) (xy 157.334712 -438.089802) (xy 314.11799 -438.089802) (xy 314.118421 -438.057912)
			(xy 314.126058 -437.994592) (xy 314.141213 -437.932639) (xy 314.163666 -437.872943) (xy 314.193097 -437.81636)
			(xy 314.229081 -437.763702) (xy 314.271105 -437.715724) (xy 314.29452 -437.69407) (xy 314.298153 -437.690742)
			(xy 314.304163 -437.682936) (xy 314.306458 -437.678576) (xy 314.382404 -437.523382) (xy 314.387105 -437.512865)
			(xy 314.390595 -437.490107) (xy 314.38711 -437.467348) (xy 314.382404 -437.456834) (xy 314.305696 -437.300878)
			(xy 314.303529 -437.29654) (xy 314.297767 -437.28874) (xy 314.294266 -437.285384) (xy 314.270849 -437.26377)
			(xy 314.228887 -437.215805) (xy 314.19296 -437.163169) (xy 314.163582 -437.106615) (xy 314.141175 -437.046955)
			(xy 314.12606 -436.985044) (xy 314.118453 -436.921771) (xy 314.11799 -436.889906) (xy 314.118644 -436.852371)
			(xy 314.12922 -436.778049) (xy 314.139072 -436.741824) (xy 314.140021 -436.738345) (xy 314.141041 -436.731206)
			(xy 314.141104 -436.7276) (xy 314.141104 -436.219092) (xy 314.141506 -436.207008) (xy 314.148977 -436.184023)
			(xy 314.163186 -436.164471) (xy 314.182741 -436.150268) (xy 314.205728 -436.142803) (xy 314.217812 -436.142384)
			(xy 315.157612 -436.142384) (xy 315.169686 -436.142854) (xy 315.192653 -436.150319) (xy 315.212189 -436.164514)
			(xy 315.226383 -436.184051) (xy 315.233847 -436.207018) (xy 315.23432 -436.219092) (xy 315.23432 -438.760616)
			(xy 315.233849 -438.77269) (xy 315.226384 -438.795656) (xy 315.212189 -438.815191) (xy 315.192652 -438.829386)
			(xy 315.169686 -438.83685) (xy 315.157612 -438.837324) (xy 314.217812 -438.837324) (xy 314.20574 -438.836826)
			(xy 314.182776 -438.829369) (xy 314.16324 -438.81518) (xy 314.149044 -438.79565) (xy 314.141579 -438.772688)
			(xy 314.141104 -438.760616) (xy 314.141104 -438.252108) (xy 314.141039 -438.248502) (xy 314.140021 -438.241363)
			(xy 314.139072 -438.237884) (xy 314.129245 -438.201653) (xy 314.118659 -438.127336) (xy 314.11799 -438.089802)
			(xy 157.334712 -438.089802) (xy 157.334712 -439.0898) (xy 316.117986 -439.0898) (xy 316.118416 -439.05791)
			(xy 316.126055 -438.99459) (xy 316.141209 -438.932637) (xy 316.163662 -438.872941) (xy 316.193093 -438.816358)
			(xy 316.229078 -438.7637) (xy 316.271101 -438.715722) (xy 316.294516 -438.694068) (xy 316.298149 -438.690739)
			(xy 316.304159 -438.682934) (xy 316.306454 -438.678574) (xy 316.3824 -438.52338) (xy 316.387103 -438.512864)
			(xy 316.390593 -438.490105) (xy 316.387106 -438.467346) (xy 316.3824 -438.456832) (xy 316.305692 -438.300876)
			(xy 316.303526 -438.296537) (xy 316.297763 -438.288738) (xy 316.294262 -438.285382) (xy 316.270892 -438.263719)
			(xy 316.228927 -438.215763) (xy 316.192995 -438.163135) (xy 316.163611 -438.10659) (xy 316.141196 -438.046938)
			(xy 316.126072 -437.985034) (xy 316.118455 -437.921766) (xy 316.117986 -437.889904) (xy 316.11864 -437.852369)
			(xy 316.129216 -437.778047) (xy 316.139068 -437.741822) (xy 316.140018 -437.738343) (xy 316.141037 -437.731204)
			(xy 316.1411 -437.727598) (xy 316.1411 -437.21909) (xy 316.141598 -437.207004) (xy 316.149053 -437.18401)
			(xy 316.163233 -437.164434) (xy 316.182757 -437.150182) (xy 316.205724 -437.142643) (xy 316.217808 -437.142128)
			(xy 317.157608 -437.142128) (xy 317.16972 -437.14251) (xy 317.192752 -437.150015) (xy 317.212328 -437.164284)
			(xy 317.226521 -437.183915) (xy 317.233937 -437.206976) (xy 317.234316 -437.21909) (xy 317.234316 -438.089802)
			(xy 318.117982 -438.089802) (xy 318.118415 -438.057913) (xy 318.126053 -437.994592) (xy 318.141207 -437.93264)
			(xy 318.16366 -437.872944) (xy 318.19309 -437.81636) (xy 318.229074 -437.763702) (xy 318.271097 -437.715724)
			(xy 318.294512 -437.69407) (xy 318.298144 -437.690741) (xy 318.304155 -437.682936) (xy 318.30645 -437.678576)
			(xy 318.382396 -437.523382) (xy 318.387098 -437.512866) (xy 318.390588 -437.490107) (xy 318.387102 -437.467348)
			(xy 318.382396 -437.456834) (xy 318.305688 -437.300878) (xy 318.303522 -437.296539) (xy 318.297759 -437.28874)
			(xy 318.294258 -437.285384) (xy 318.270859 -437.263751) (xy 318.228893 -437.215792) (xy 318.192961 -437.163159)
			(xy 318.16358 -437.106609) (xy 318.14117 -437.046951) (xy 318.126053 -436.985042) (xy 318.118445 -436.92177)
			(xy 318.117982 -436.889906) (xy 318.118636 -436.852371) (xy 318.129212 -436.778049) (xy 318.139064 -436.741824)
			(xy 318.140013 -436.738345) (xy 318.141033 -436.731206) (xy 318.141096 -436.7276) (xy 318.141096 -436.219092)
			(xy 318.141558 -436.207017) (xy 318.149023 -436.184049) (xy 318.16322 -436.164511) (xy 318.182759 -436.150317)
			(xy 318.205729 -436.142856) (xy 318.217804 -436.142384) (xy 319.157604 -436.142384) (xy 319.169678 -436.142861)
			(xy 319.192644 -436.150323) (xy 319.21218 -436.164517) (xy 319.226375 -436.184053) (xy 319.233839 -436.207018)
			(xy 319.234312 -436.219092) (xy 319.234312 -438.760616) (xy 319.233849 -438.772691) (xy 319.226383 -438.795658)
			(xy 319.212186 -438.815194) (xy 319.192647 -438.829388) (xy 319.169679 -438.836851) (xy 319.157604 -438.837324)
			(xy 318.217804 -438.837324) (xy 318.205731 -438.836833) (xy 318.182767 -438.829373) (xy 318.163231 -438.815183)
			(xy 318.149036 -438.795651) (xy 318.141571 -438.772689) (xy 318.141096 -438.760616) (xy 318.141096 -438.252108)
			(xy 318.141032 -438.248502) (xy 318.140013 -438.241363) (xy 318.139064 -438.237884) (xy 318.129237 -438.201653)
			(xy 318.118651 -438.127336) (xy 318.117982 -438.089802) (xy 317.234316 -438.089802) (xy 317.234316 -439.0898)
			(xy 320.117978 -439.0898) (xy 320.118411 -439.057911) (xy 320.126049 -438.99459) (xy 320.141203 -438.932638)
			(xy 320.163656 -438.872942) (xy 320.193086 -438.816359) (xy 320.229071 -438.7637) (xy 320.271093 -438.715722)
			(xy 320.294508 -438.694068) (xy 320.29814 -438.690738) (xy 320.304151 -438.682934) (xy 320.306446 -438.678574)
			(xy 320.382392 -438.52338) (xy 320.387095 -438.512864) (xy 320.390585 -438.490105) (xy 320.387099 -438.467346)
			(xy 320.382392 -438.456832) (xy 320.305684 -438.300876) (xy 320.303519 -438.296536) (xy 320.297756 -438.288738)
			(xy 320.294254 -438.285382) (xy 320.270902 -438.2637) (xy 320.228933 -438.21575) (xy 320.192997 -438.163126)
			(xy 320.163609 -438.106584) (xy 320.141191 -438.046934) (xy 320.126065 -437.985032) (xy 320.118447 -437.921766)
			(xy 320.117978 -437.889904) (xy 320.118632 -437.852369) (xy 320.129208 -437.778047) (xy 320.13906 -437.741822)
			(xy 320.140012 -437.738343) (xy 320.141029 -437.731204) (xy 320.141092 -437.727598) (xy 320.141092 -437.21909)
			(xy 320.141598 -437.207005) (xy 320.149052 -437.184012) (xy 320.16323 -437.164436) (xy 320.182752 -437.150184)
			(xy 320.205717 -437.142644) (xy 320.2178 -437.142128) (xy 321.1576 -437.142128) (xy 321.169712 -437.142516)
			(xy 321.192744 -437.150019) (xy 321.212319 -437.164287) (xy 321.226513 -437.183916) (xy 321.233929 -437.206977)
			(xy 321.234308 -437.21909) (xy 321.234308 -438.089802) (xy 322.117974 -438.089802) (xy 322.11841 -438.057913)
			(xy 322.126047 -437.994593) (xy 322.141201 -437.93264) (xy 322.163654 -437.872944) (xy 322.193083 -437.816361)
			(xy 322.229067 -437.763702) (xy 322.271089 -437.715724) (xy 322.294504 -437.69407) (xy 322.298135 -437.69074)
			(xy 322.304147 -437.682936) (xy 322.306442 -437.678576) (xy 322.382388 -437.523382) (xy 322.38709 -437.512866)
			(xy 322.390581 -437.490107) (xy 322.387095 -437.467348) (xy 322.382388 -437.456834) (xy 322.30568 -437.300878)
			(xy 322.303515 -437.296538) (xy 322.297752 -437.28874) (xy 322.29425 -437.285384) (xy 322.270849 -437.263753)
			(xy 322.228884 -437.215793) (xy 322.192953 -437.16316) (xy 322.163572 -437.106609) (xy 322.141162 -437.046951)
			(xy 322.126045 -436.985042) (xy 322.118437 -436.92177) (xy 322.117974 -436.889906) (xy 322.118629 -436.852371)
			(xy 322.129204 -436.778049) (xy 322.139056 -436.741824) (xy 322.140007 -436.738345) (xy 322.141025 -436.731206)
			(xy 322.141088 -436.7276) (xy 322.141088 -436.219092) (xy 322.141557 -436.207017) (xy 322.149022 -436.184051)
			(xy 322.163217 -436.164514) (xy 322.182754 -436.15032) (xy 322.205721 -436.142857) (xy 322.217796 -436.142384)
			(xy 323.157596 -436.142384) (xy 323.16967 -436.142868) (xy 323.192635 -436.150328) (xy 323.212172 -436.16452)
			(xy 323.226367 -436.184054) (xy 323.233831 -436.207019) (xy 323.234304 -436.219092) (xy 323.234304 -438.760616)
			(xy 323.233849 -438.772692) (xy 323.226382 -438.79566) (xy 323.212183 -438.815197) (xy 323.192642 -438.829391)
			(xy 323.169672 -438.836852) (xy 323.157596 -438.837324) (xy 322.217796 -438.837324) (xy 322.205723 -438.836839)
			(xy 322.182758 -438.829378) (xy 322.163223 -438.815186) (xy 322.149028 -438.795652) (xy 322.141563 -438.772689)
			(xy 322.141088 -438.760616) (xy 322.141088 -438.252108) (xy 322.14102 -438.248502) (xy 322.140003 -438.241363)
			(xy 322.139056 -438.237884) (xy 322.129229 -438.201653) (xy 322.118643 -438.127336) (xy 322.117974 -438.089802)
			(xy 321.234308 -438.089802) (xy 321.234308 -439.0898) (xy 324.11797 -439.0898) (xy 324.118406 -439.057911)
			(xy 324.126044 -438.994591) (xy 324.141198 -438.932638) (xy 324.16365 -438.872942) (xy 324.19308 -438.816359)
			(xy 324.229063 -438.763701) (xy 324.271085 -438.715722) (xy 324.2945 -438.694068) (xy 324.298131 -438.690738)
			(xy 324.304143 -438.682934) (xy 324.306438 -438.678574) (xy 324.382384 -438.52338) (xy 324.387088 -438.512864)
			(xy 324.390578 -438.490105) (xy 324.387091 -438.467346) (xy 324.382384 -438.456832) (xy 324.305676 -438.300876)
			(xy 324.303496 -438.296545) (xy 324.297742 -438.288742) (xy 324.294246 -438.285382) (xy 324.270892 -438.263702)
			(xy 324.228923 -438.215751) (xy 324.192988 -438.163127) (xy 324.163601 -438.106584) (xy 324.141183 -438.046934)
			(xy 324.126057 -437.985032) (xy 324.118439 -437.921766) (xy 324.11797 -437.889904) (xy 324.118624 -437.852369)
			(xy 324.1292 -437.778047) (xy 324.139052 -437.741822) (xy 324.140003 -437.738343) (xy 324.141021 -437.731204)
			(xy 324.141084 -437.727598) (xy 324.141084 -437.21909) (xy 324.1415 -437.206996) (xy 324.148965 -437.183987)
			(xy 324.163163 -437.164404) (xy 324.18271 -437.150155) (xy 324.205699 -437.142631) (xy 324.217792 -437.142128)
			(xy 325.157592 -437.142128) (xy 325.169703 -437.142523) (xy 325.192735 -437.150024) (xy 325.212311 -437.16429)
			(xy 325.226505 -437.183918) (xy 325.233921 -437.206977) (xy 325.2343 -437.21909) (xy 325.2343 -438.089802)
			(xy 326.117966 -438.089802) (xy 326.118404 -438.057913) (xy 326.126042 -437.994593) (xy 326.141196 -437.932641)
			(xy 326.163648 -437.872945) (xy 326.193077 -437.816361) (xy 326.22906 -437.763703) (xy 326.271082 -437.715724)
			(xy 326.294496 -437.69407) (xy 326.298126 -437.690739) (xy 326.304138 -437.682935) (xy 326.306434 -437.678576)
			(xy 326.38238 -437.523382) (xy 326.387083 -437.512866) (xy 326.390574 -437.490107) (xy 326.387087 -437.467348)
			(xy 326.38238 -437.456834) (xy 326.305672 -437.300878) (xy 326.303492 -437.296546) (xy 326.297739 -437.288743)
			(xy 326.294242 -437.285384) (xy 326.27084 -437.263754) (xy 326.228874 -437.215794) (xy 326.192944 -437.163161)
			(xy 326.163563 -437.10661) (xy 326.141153 -437.046952) (xy 326.126037 -436.985042) (xy 326.118429 -436.92177)
			(xy 326.117966 -436.889906) (xy 326.118621 -436.852371) (xy 326.129197 -436.778049) (xy 326.139048 -436.741824)
			(xy 326.139999 -436.738345) (xy 326.141017 -436.731206) (xy 326.14108 -436.7276) (xy 326.14108 -436.219092)
			(xy 326.141557 -436.207018) (xy 326.149021 -436.184053) (xy 326.163214 -436.164517) (xy 326.182749 -436.150322)
			(xy 326.205714 -436.142858) (xy 326.217788 -436.142384) (xy 327.157588 -436.142384) (xy 327.169669 -436.142823)
			(xy 327.19265 -436.150286) (xy 327.2122 -436.164486) (xy 327.226405 -436.184032) (xy 327.233874 -436.207011)
			(xy 327.234296 -436.219092) (xy 327.234296 -438.760616) (xy 327.233849 -438.772693) (xy 327.226381 -438.795662)
			(xy 327.21218 -438.8152) (xy 327.192637 -438.829394) (xy 327.169665 -438.836853) (xy 327.157588 -438.837324)
			(xy 326.217788 -438.837324) (xy 326.205714 -438.836846) (xy 326.18275 -438.829382) (xy 326.163214 -438.815189)
			(xy 326.14902 -438.795654) (xy 326.141555 -438.77269) (xy 326.14108 -438.760616) (xy 326.14108 -438.252108)
			(xy 326.141012 -438.248502) (xy 326.139995 -438.241363) (xy 326.139048 -438.237884) (xy 326.129221 -438.201653)
			(xy 326.118634 -438.127336) (xy 326.117966 -438.089802) (xy 325.2343 -438.089802) (xy 325.2343 -439.0898)
			(xy 328.117962 -439.0898) (xy 328.1184 -439.057911) (xy 328.126038 -438.994591) (xy 328.141192 -438.932639)
			(xy 328.163644 -438.872943) (xy 328.193073 -438.81636) (xy 328.229056 -438.763701) (xy 328.271078 -438.715723)
			(xy 328.294492 -438.694068) (xy 328.298122 -438.690737) (xy 328.304134 -438.682933) (xy 328.30643 -438.678574)
			(xy 328.382376 -438.52338) (xy 328.38708 -438.512864) (xy 328.390571 -438.490105) (xy 328.387084 -438.467346)
			(xy 328.382376 -438.456832) (xy 328.305668 -438.300876) (xy 328.30349 -438.296544) (xy 328.297735 -438.288741)
			(xy 328.294238 -438.285382) (xy 328.270883 -438.263703) (xy 328.228914 -438.215752) (xy 328.192979 -438.163127)
			(xy 328.163592 -438.106585) (xy 328.141175 -438.046934) (xy 328.126049 -437.985032) (xy 328.118431 -437.921766)
			(xy 328.117962 -437.889904) (xy 328.118617 -437.852369) (xy 328.129192 -437.778047) (xy 328.139044 -437.741822)
			(xy 328.139995 -437.738343) (xy 328.141013 -437.731204) (xy 328.141076 -437.727598) (xy 328.141076 -437.21909)
			(xy 328.1415 -437.206996) (xy 328.148964 -437.183989) (xy 328.16316 -437.164407) (xy 328.182705 -437.150158)
			(xy 328.205692 -437.142632) (xy 328.217784 -437.142128) (xy 329.157584 -437.142128) (xy 329.169695 -437.14253)
			(xy 329.192726 -437.150029) (xy 329.212302 -437.164293) (xy 329.226496 -437.18392) (xy 329.233912 -437.206978)
			(xy 329.234292 -437.21909) (xy 329.234292 -438.089802) (xy 331.11821 -438.089802) (xy 331.118667 -438.057913)
			(xy 331.126304 -437.994595) (xy 331.141455 -437.932644) (xy 331.163905 -437.872948) (xy 331.193331 -437.816365)
			(xy 331.229311 -437.763706) (xy 331.271328 -437.715726) (xy 331.29474 -437.69407) (xy 331.298369 -437.690737)
			(xy 331.304387 -437.682938) (xy 331.306678 -437.678576) (xy 331.382624 -437.523382) (xy 331.387325 -437.512865)
			(xy 331.390814 -437.490107) (xy 331.387329 -437.467348) (xy 331.382624 -437.456834) (xy 331.305916 -437.300878)
			(xy 331.303745 -437.296542) (xy 331.297986 -437.288741) (xy 331.294486 -437.285384) (xy 331.271073 -437.263766)
			(xy 331.22911 -437.215802) (xy 331.193182 -437.163167) (xy 331.163803 -437.106613) (xy 331.141396 -437.046954)
			(xy 331.12628 -436.985044) (xy 331.118673 -436.92177) (xy 331.11821 -436.889906) (xy 331.118863 -436.852371)
			(xy 331.12944 -436.778049) (xy 331.139292 -436.741824) (xy 331.140242 -436.738345) (xy 331.141261 -436.731206)
			(xy 331.141324 -436.7276) (xy 331.141324 -436.219092) (xy 331.141706 -436.207006) (xy 331.14918 -436.184017)
			(xy 331.163393 -436.164464) (xy 331.182953 -436.150262) (xy 331.205945 -436.1428) (xy 331.218032 -436.142384)
			(xy 332.157832 -436.142384) (xy 332.169907 -436.142837) (xy 332.192874 -436.150307) (xy 332.21241 -436.164507)
			(xy 332.226604 -436.184047) (xy 332.234067 -436.207016) (xy 332.23454 -436.219092) (xy 332.23454 -438.760616)
			(xy 332.23405 -438.772688) (xy 332.226587 -438.79565) (xy 332.212396 -438.815184) (xy 332.192865 -438.829379)
			(xy 332.169904 -438.836847) (xy 332.157832 -438.837324) (xy 331.218032 -438.837324) (xy 331.205953 -438.83686)
			(xy 331.182974 -438.829403) (xy 331.163424 -438.81521) (xy 331.149218 -438.795669) (xy 331.141747 -438.772695)
			(xy 331.141324 -438.760616) (xy 331.141324 -438.252108) (xy 331.141258 -438.248502) (xy 331.14024 -438.241363)
			(xy 331.139292 -438.237884) (xy 331.129464 -438.201654) (xy 331.118878 -438.127336) (xy 331.11821 -438.089802)
			(xy 329.234292 -438.089802) (xy 329.234292 -439.0898) (xy 333.118206 -439.0898) (xy 333.118663 -439.057911)
			(xy 333.1263 -438.994593) (xy 333.141452 -438.932642) (xy 333.163902 -438.872947) (xy 333.193327 -438.816363)
			(xy 333.229307 -438.763704) (xy 333.271324 -438.715724) (xy 333.294736 -438.694068) (xy 333.298365 -438.690735)
			(xy 333.304383 -438.682936) (xy 333.306674 -438.678574) (xy 333.38262 -438.52338) (xy 333.387322 -438.512864)
			(xy 333.390811 -438.490105) (xy 333.387326 -438.467346) (xy 333.38262 -438.456832) (xy 333.305912 -438.300876)
			(xy 333.303742 -438.296539) (xy 333.297982 -438.288739) (xy 333.294482 -438.285382) (xy 333.271115 -438.263715)
			(xy 333.22915 -438.21576) (xy 333.193217 -438.163133) (xy 333.163832 -438.106588) (xy 333.141417 -438.046937)
			(xy 333.126292 -437.985033) (xy 333.118675 -437.921766) (xy 333.118206 -437.889904) (xy 333.118859 -437.852369)
			(xy 333.129436 -437.778047) (xy 333.139288 -437.741822) (xy 333.140238 -437.738343) (xy 333.141257 -437.731204)
			(xy 333.14132 -437.727598) (xy 333.14132 -437.21909) (xy 333.141799 -437.207002) (xy 333.149256 -437.184004)
			(xy 333.16344 -437.164426) (xy 333.18297 -437.150176) (xy 333.205942 -437.14264) (xy 333.218028 -437.142128)
			(xy 334.157828 -437.142128) (xy 334.169941 -437.142493) (xy 334.192974 -437.150003) (xy 334.212549 -437.164277)
			(xy 334.226742 -437.183911) (xy 334.234157 -437.206975) (xy 334.234536 -437.21909) (xy 334.234536 -438.089802)
			(xy 335.118202 -438.089802) (xy 335.118662 -438.057914) (xy 335.126298 -437.994595) (xy 335.14145 -437.932644)
			(xy 335.163899 -437.872949) (xy 335.193324 -437.816366) (xy 335.229303 -437.763706) (xy 335.27132 -437.715726)
			(xy 335.294732 -437.69407) (xy 335.298366 -437.690743) (xy 335.304376 -437.682937) (xy 335.30667 -437.678576)
			(xy 335.382616 -437.523382) (xy 335.387317 -437.512865) (xy 335.390807 -437.490107) (xy 335.387322 -437.467348)
			(xy 335.382616 -437.456834) (xy 335.305908 -437.300878) (xy 335.303739 -437.296541) (xy 335.297978 -437.288741)
			(xy 335.294478 -437.285384) (xy 335.271063 -437.263768) (xy 335.229101 -437.215804) (xy 335.193173 -437.163167)
			(xy 335.163795 -437.106614) (xy 335.141387 -437.046954) (xy 335.126272 -436.985044) (xy 335.118665 -436.921771)
			(xy 335.118202 -436.889906) (xy 335.118856 -436.852371) (xy 335.129432 -436.778049) (xy 335.139284 -436.741824)
			(xy 335.140234 -436.738345) (xy 335.141253 -436.731206) (xy 335.141316 -436.7276) (xy 335.141316 -436.219092)
			(xy 335.141706 -436.207006) (xy 335.149179 -436.184019) (xy 335.16339 -436.164467) (xy 335.182948 -436.150264)
			(xy 335.205938 -436.142801) (xy 335.218024 -436.142384) (xy 336.157824 -436.142384) (xy 336.169899 -436.142844)
			(xy 336.192866 -436.150312) (xy 336.212401 -436.16451) (xy 336.226595 -436.184049) (xy 336.234059 -436.207017)
			(xy 336.234532 -436.219092) (xy 336.234532 -438.760616) (xy 336.23405 -438.772689) (xy 336.226586 -438.795653)
			(xy 336.212393 -438.815187) (xy 336.19286 -438.829382) (xy 336.169897 -438.836848) (xy 336.157824 -438.837324)
			(xy 335.218024 -438.837324) (xy 335.205944 -438.836867) (xy 335.182965 -438.829408) (xy 335.163416 -438.815213)
			(xy 335.14921 -438.795671) (xy 335.141739 -438.772696) (xy 335.141316 -438.760616) (xy 335.141316 -438.252108)
			(xy 335.141251 -438.248502) (xy 335.140232 -438.241363) (xy 335.139284 -438.237884) (xy 335.129456 -438.201654)
			(xy 335.11887 -438.127336) (xy 335.118202 -438.089802) (xy 334.234536 -438.089802) (xy 334.234536 -439.0898)
			(xy 337.118198 -439.0898) (xy 337.118625 -439.05791) (xy 337.126263 -438.99459) (xy 337.141418 -438.932637)
			(xy 337.163872 -438.87294) (xy 337.193303 -438.816357) (xy 337.229288 -438.763699) (xy 337.271312 -438.715722)
			(xy 337.294728 -438.694068) (xy 337.298362 -438.690741) (xy 337.304372 -438.682935) (xy 337.306666 -438.678574)
			(xy 337.382612 -438.52338) (xy 337.387315 -438.512864) (xy 337.390804 -438.490105) (xy 337.387318 -438.467346)
			(xy 337.382612 -438.456832) (xy 337.305904 -438.300876) (xy 337.303736 -438.296538) (xy 337.297974 -438.288739)
			(xy 337.294474 -438.285382) (xy 337.271106 -438.263717) (xy 337.229141 -438.215762) (xy 337.193208 -438.163134)
			(xy 337.163824 -438.106589) (xy 337.141409 -438.046937) (xy 337.126284 -437.985034) (xy 337.118667 -437.921766)
			(xy 337.118198 -437.889904) (xy 337.118851 -437.852369) (xy 337.129428 -437.778047) (xy 337.13928 -437.741822)
			(xy 337.14023 -437.738343) (xy 337.141249 -437.731204) (xy 337.141312 -437.727598) (xy 337.141312 -437.21909)
			(xy 337.141799 -437.207003) (xy 337.149255 -437.184007) (xy 337.163437 -437.164429) (xy 337.182965 -437.150178)
			(xy 337.205934 -437.142641) (xy 337.21802 -437.142128) (xy 338.15782 -437.142128) (xy 338.169933 -437.1425)
			(xy 338.192965 -437.150008) (xy 338.212541 -437.16428) (xy 338.226734 -437.183913) (xy 338.234149 -437.206976)
			(xy 338.234528 -437.21909) (xy 338.234528 -438.089802) (xy 339.118194 -438.089802) (xy 339.118623 -438.057912)
			(xy 339.126261 -437.994592) (xy 339.141416 -437.932639) (xy 339.163869 -437.872943) (xy 339.1933 -437.81636)
			(xy 339.229285 -437.763701) (xy 339.271309 -437.715724) (xy 339.294724 -437.69407) (xy 339.298357 -437.690742)
			(xy 339.304367 -437.682936) (xy 339.306662 -437.678576) (xy 339.382608 -437.523382) (xy 339.387309 -437.512865)
			(xy 339.390799 -437.490107) (xy 339.387314 -437.467348) (xy 339.382608 -437.456834) (xy 339.3059 -437.300878)
			(xy 339.303732 -437.29654) (xy 339.297971 -437.288741) (xy 339.29447 -437.285384) (xy 339.271053 -437.263769)
			(xy 339.229092 -437.215805) (xy 339.193164 -437.163168) (xy 339.163786 -437.106615) (xy 339.141379 -437.046955)
			(xy 339.126264 -436.985044) (xy 339.118657 -436.921771) (xy 339.118194 -436.889906) (xy 339.118848 -436.852371)
			(xy 339.129424 -436.778049) (xy 339.139276 -436.741824) (xy 339.140225 -436.738345) (xy 339.141245 -436.731206)
			(xy 339.141308 -436.7276) (xy 339.141308 -436.219092) (xy 339.141706 -436.207007) (xy 339.149178 -436.184021)
			(xy 339.163387 -436.16447) (xy 339.182943 -436.150267) (xy 339.205931 -436.142802) (xy 339.218016 -436.142384)
			(xy 340.157816 -436.142384) (xy 340.169891 -436.142851) (xy 340.192857 -436.150317) (xy 340.212393 -436.164513)
			(xy 340.226587 -436.18405) (xy 340.234051 -436.207017) (xy 340.234524 -436.219092) (xy 340.234524 -438.760616)
			(xy 340.23405 -438.77269) (xy 340.226585 -438.795655) (xy 340.21239 -438.81519) (xy 340.192855 -438.829385)
			(xy 340.16989 -438.83685) (xy 340.157816 -438.837324) (xy 339.218016 -438.837324) (xy 339.205944 -438.836822)
			(xy 339.18298 -438.829366) (xy 339.163444 -438.815179) (xy 339.149248 -438.795649) (xy 339.141783 -438.772688)
			(xy 339.141308 -438.760616) (xy 339.141308 -438.252108) (xy 339.141243 -438.248502) (xy 339.140224 -438.241363)
			(xy 339.139276 -438.237884) (xy 339.12945 -438.201653) (xy 339.118863 -438.127336) (xy 339.118194 -438.089802)
			(xy 338.234528 -438.089802) (xy 338.234528 -439.0898) (xy 341.11819 -439.0898) (xy 341.118619 -439.05791)
			(xy 341.126257 -438.99459) (xy 341.141412 -438.932637) (xy 341.163866 -438.872941) (xy 341.193296 -438.816358)
			(xy 341.229281 -438.7637) (xy 341.271305 -438.715722) (xy 341.29472 -438.694068) (xy 341.298353 -438.69074)
			(xy 341.304363 -438.682934) (xy 341.306658 -438.678574) (xy 341.382604 -438.52338) (xy 341.387307 -438.512864)
			(xy 341.390796 -438.490105) (xy 341.38731 -438.467346) (xy 341.382604 -438.456832) (xy 341.305896 -438.300876)
			(xy 341.303729 -438.296538) (xy 341.297967 -438.288738) (xy 341.294466 -438.285382) (xy 341.271096 -438.263719)
			(xy 341.229132 -438.215763) (xy 341.1932 -438.163135) (xy 341.163815 -438.10659) (xy 341.1414 -438.046937)
			(xy 341.126276 -437.985034) (xy 341.118659 -437.921766) (xy 341.11819 -437.889904) (xy 341.118844 -437.852369)
			(xy 341.12942 -437.778047) (xy 341.139272 -437.741822) (xy 341.140222 -437.738343) (xy 341.141241 -437.731204)
			(xy 341.141304 -437.727598) (xy 341.141304 -437.21909) (xy 341.141798 -437.207004) (xy 341.149253 -437.184009)
			(xy 341.163434 -437.164432) (xy 341.18296 -437.150181) (xy 341.205927 -437.142643) (xy 341.218012 -437.142128)
			(xy 342.157812 -437.142128) (xy 342.169924 -437.142506) (xy 342.192957 -437.150012) (xy 342.212532 -437.164283)
			(xy 342.226725 -437.183914) (xy 342.234141 -437.206976) (xy 342.23452 -437.21909) (xy 342.23452 -438.089802)
			(xy 343.118186 -438.089802) (xy 343.118618 -438.057912) (xy 343.126256 -437.994592) (xy 343.14141 -437.93264)
			(xy 343.163863 -437.872943) (xy 343.193293 -437.81636) (xy 343.229278 -437.763702) (xy 343.271301 -437.715724)
			(xy 343.294716 -437.69407) (xy 343.298348 -437.690741) (xy 343.304359 -437.682936) (xy 343.306654 -437.678576)
			(xy 343.3826 -437.523382) (xy 343.387302 -437.512866) (xy 343.390792 -437.490107) (xy 343.387306 -437.467348)
			(xy 343.3826 -437.456834) (xy 343.305892 -437.300878) (xy 343.303725 -437.296539) (xy 343.297963 -437.28874)
			(xy 343.294462 -437.285384) (xy 343.271044 -437.263771) (xy 343.229083 -437.215806) (xy 343.193156 -437.163169)
			(xy 343.163778 -437.106615) (xy 343.141371 -437.046955) (xy 343.126256 -436.985044) (xy 343.118649 -436.921771)
			(xy 343.118186 -436.889906) (xy 343.11884 -436.852371) (xy 343.129416 -436.778049) (xy 343.139268 -436.741824)
			(xy 343.140217 -436.738345) (xy 343.141237 -436.731206) (xy 343.1413 -436.7276) (xy 343.1413 -436.219092)
			(xy 343.141758 -436.207016) (xy 343.149223 -436.184047) (xy 343.163421 -436.16451) (xy 343.182962 -436.150316)
			(xy 343.205932 -436.142855) (xy 343.218008 -436.142384) (xy 344.157808 -436.142384) (xy 344.169882 -436.142857)
			(xy 344.192848 -436.150321) (xy 344.212384 -436.164516) (xy 344.226579 -436.184052) (xy 344.234043 -436.207018)
			(xy 344.234516 -436.219092) (xy 344.234516 -438.760616) (xy 344.234049 -438.772691) (xy 344.226583 -438.795657)
			(xy 344.212387 -438.815193) (xy 344.19285 -438.829387) (xy 344.169883 -438.836851) (xy 344.157808 -438.837324)
			(xy 343.218008 -438.837324) (xy 343.205935 -438.836829) (xy 343.182971 -438.829371) (xy 343.163435 -438.815182)
			(xy 343.14924 -438.79565) (xy 343.141775 -438.772688) (xy 343.1413 -438.760616) (xy 343.1413 -438.252108)
			(xy 343.141235 -438.248502) (xy 343.140217 -438.241363) (xy 343.139268 -438.237884) (xy 343.129441 -438.201653)
			(xy 343.118855 -438.127336) (xy 343.118186 -438.089802) (xy 342.23452 -438.089802) (xy 342.23452 -439.0898)
			(xy 345.118182 -439.0898) (xy 345.118614 -439.05791) (xy 345.126252 -438.99459) (xy 345.141406 -438.932638)
			(xy 345.163859 -438.872941) (xy 345.19329 -438.816358) (xy 345.229274 -438.7637) (xy 345.271297 -438.715722)
			(xy 345.294712 -438.694068) (xy 345.298344 -438.690739) (xy 345.304355 -438.682934) (xy 345.30665 -438.678574)
			(xy 345.382596 -438.52338) (xy 345.387299 -438.512864) (xy 345.390789 -438.490105) (xy 345.387302 -438.467346)
			(xy 345.382596 -438.456832) (xy 345.305888 -438.300876) (xy 345.303722 -438.296537) (xy 345.297959 -438.288738)
			(xy 345.294458 -438.285382) (xy 345.271106 -438.263699) (xy 345.229137 -438.215749) (xy 345.193201 -438.163125)
			(xy 345.163813 -438.106583) (xy 345.141396 -438.046934) (xy 345.126269 -437.985032) (xy 345.118651 -437.921766)
			(xy 345.118182 -437.889904) (xy 345.118836 -437.852369) (xy 345.129412 -437.778047) (xy 345.139264 -437.741822)
			(xy 345.140213 -437.738343) (xy 345.141233 -437.731204) (xy 345.141296 -437.727598) (xy 345.141296 -437.21909)
			(xy 345.141798 -437.207004) (xy 345.149252 -437.184011) (xy 345.163431 -437.164435) (xy 345.182955 -437.150183)
			(xy 345.20592 -437.142644) (xy 345.218004 -437.142128) (xy 346.157804 -437.142128) (xy 346.169916 -437.142513)
			(xy 346.192948 -437.150017) (xy 346.212524 -437.164286) (xy 346.226717 -437.183916) (xy 346.234133 -437.206977)
			(xy 346.234512 -437.21909) (xy 346.234512 -439.0898) (xy 383.218182 -439.0898) (xy 383.218614 -439.05791)
			(xy 383.226252 -438.99459) (xy 383.241406 -438.932638) (xy 383.263859 -438.872941) (xy 383.29329 -438.816358)
			(xy 383.329274 -438.7637) (xy 383.371297 -438.715722) (xy 383.394712 -438.694068) (xy 383.398344 -438.690739)
			(xy 383.404355 -438.682934) (xy 383.40665 -438.678574) (xy 383.482596 -438.52338) (xy 383.487299 -438.512864)
			(xy 383.490789 -438.490105) (xy 383.487302 -438.467346) (xy 383.482596 -438.456832) (xy 383.405888 -438.300876)
			(xy 383.403722 -438.296537) (xy 383.397959 -438.288738) (xy 383.394458 -438.285382) (xy 383.371106 -438.263699)
			(xy 383.329137 -438.215749) (xy 383.293201 -438.163125) (xy 383.263813 -438.106583) (xy 383.241396 -438.046934)
			(xy 383.226269 -437.985032) (xy 383.218651 -437.921766) (xy 383.218182 -437.889904) (xy 383.218836 -437.852369)
			(xy 383.229412 -437.778047) (xy 383.239264 -437.741822) (xy 383.240213 -437.738343) (xy 383.241233 -437.731204)
			(xy 383.241296 -437.727598) (xy 383.241296 -437.21909) (xy 383.241798 -437.207004) (xy 383.249252 -437.184011)
			(xy 383.263431 -437.164435) (xy 383.282955 -437.150183) (xy 383.30592 -437.142644) (xy 383.318004 -437.142128)
			(xy 384.257804 -437.142128) (xy 384.269916 -437.142513) (xy 384.292948 -437.150017) (xy 384.312524 -437.164286)
			(xy 384.326717 -437.183916) (xy 384.334133 -437.206977) (xy 384.334512 -437.21909) (xy 384.334512 -438.089802)
			(xy 385.218178 -438.089802) (xy 385.218612 -438.057913) (xy 385.22625 -437.994593) (xy 385.241404 -437.93264)
			(xy 385.263857 -437.872944) (xy 385.293287 -437.816361) (xy 385.329271 -437.763702) (xy 385.371293 -437.715724)
			(xy 385.394708 -437.69407) (xy 385.398339 -437.69074) (xy 385.404351 -437.682936) (xy 385.406646 -437.678576)
			(xy 385.482592 -437.523382) (xy 385.487294 -437.512866) (xy 385.490785 -437.490107) (xy 385.487298 -437.467348)
			(xy 385.482592 -437.456834) (xy 385.405884 -437.300878) (xy 385.403719 -437.296539) (xy 385.397955 -437.28874)
			(xy 385.394454 -437.285384) (xy 385.371054 -437.263752) (xy 385.329088 -437.215792) (xy 385.293157 -437.16316)
			(xy 385.263776 -437.106609) (xy 385.241366 -437.046951) (xy 385.226249 -436.985042) (xy 385.218641 -436.92177)
			(xy 385.218178 -436.889906) (xy 385.218832 -436.852371) (xy 385.229408 -436.778049) (xy 385.23926 -436.741824)
			(xy 385.240211 -436.738345) (xy 385.241229 -436.731206) (xy 385.241292 -436.7276) (xy 385.241292 -436.219092)
			(xy 385.241758 -436.207017) (xy 385.249222 -436.18405) (xy 385.263418 -436.164513) (xy 385.282957 -436.150319)
			(xy 385.305925 -436.142856) (xy 385.318 -436.142384) (xy 386.2578 -436.142384) (xy 386.269874 -436.142864)
			(xy 386.29284 -436.150326) (xy 386.312376 -436.164518) (xy 386.326571 -436.184053) (xy 386.334035 -436.207018)
			(xy 386.334508 -436.219092) (xy 386.334508 -438.760616) (xy 386.334049 -438.772691) (xy 386.326582 -438.795659)
			(xy 386.312384 -438.815196) (xy 386.292845 -438.82939) (xy 386.269875 -438.836852) (xy 386.2578 -438.837324)
			(xy 385.318 -438.837324) (xy 385.305927 -438.836836) (xy 385.282963 -438.829375) (xy 385.263427 -438.815184)
			(xy 385.249232 -438.795652) (xy 385.241767 -438.772689) (xy 385.241292 -438.760616) (xy 385.241292 -438.252108)
			(xy 385.241224 -438.248502) (xy 385.240207 -438.241363) (xy 385.23926 -438.237884) (xy 385.229433 -438.201653)
			(xy 385.218847 -438.127336) (xy 385.218178 -438.089802) (xy 384.334512 -438.089802) (xy 384.334512 -439.0898)
			(xy 387.218174 -439.0898) (xy 387.218608 -439.057911) (xy 387.226246 -438.994591) (xy 387.2414 -438.932638)
			(xy 387.263853 -438.872942) (xy 387.293283 -438.816359) (xy 387.329267 -438.7637) (xy 387.371289 -438.715722)
			(xy 387.394704 -438.694068) (xy 387.398335 -438.690738) (xy 387.404347 -438.682934) (xy 387.406642 -438.678574)
			(xy 387.482588 -438.52338) (xy 387.487292 -438.512864) (xy 387.490782 -438.490105) (xy 387.487295 -438.467346)
			(xy 387.482588 -438.456832) (xy 387.40588 -438.300876) (xy 387.403716 -438.296536) (xy 387.397952 -438.288738)
			(xy 387.39445 -438.285382) (xy 387.371097 -438.263701) (xy 387.329128 -438.21575) (xy 387.293192 -438.163126)
			(xy 387.263805 -438.106584) (xy 387.241387 -438.046934) (xy 387.226261 -437.985032) (xy 387.218643 -437.921766)
			(xy 387.218174 -437.889904) (xy 387.218828 -437.852369) (xy 387.229404 -437.778047) (xy 387.239256 -437.741822)
			(xy 387.240207 -437.738343) (xy 387.241225 -437.731204) (xy 387.241288 -437.727598) (xy 387.241288 -437.21909)
			(xy 387.2417 -437.206995) (xy 387.249165 -437.183986) (xy 387.263364 -437.164402) (xy 387.282912 -437.150154)
			(xy 387.305902 -437.142631) (xy 387.317996 -437.142128) (xy 388.257796 -437.142128) (xy 388.269907 -437.14252)
			(xy 388.292939 -437.150022) (xy 388.312515 -437.164288) (xy 388.326709 -437.183917) (xy 388.334125 -437.206977)
			(xy 388.334504 -437.21909) (xy 388.334504 -438.089802) (xy 389.21817 -438.089802) (xy 389.218607 -438.057913)
			(xy 389.226245 -437.994593) (xy 389.241398 -437.93264) (xy 389.263851 -437.872944) (xy 389.29328 -437.816361)
			(xy 389.329264 -437.763703) (xy 389.371285 -437.715724) (xy 389.3947 -437.69407) (xy 389.39833 -437.690739)
			(xy 389.404343 -437.682936) (xy 389.406638 -437.678576) (xy 389.482584 -437.523382) (xy 389.487286 -437.512866)
			(xy 389.490777 -437.490107) (xy 389.487291 -437.467348) (xy 389.482584 -437.456834) (xy 389.405876 -437.300878)
			(xy 389.403696 -437.296547) (xy 389.397942 -437.288744) (xy 389.394446 -437.285384) (xy 389.371044 -437.263753)
			(xy 389.329079 -437.215793) (xy 389.293148 -437.16316) (xy 389.263767 -437.106609) (xy 389.241358 -437.046951)
			(xy 389.226241 -436.985042) (xy 389.218633 -436.92177) (xy 389.21817 -436.889906) (xy 389.218825 -436.852371)
			(xy 389.2294 -436.778049) (xy 389.239252 -436.741824) (xy 389.240203 -436.738345) (xy 389.241221 -436.731206)
			(xy 389.241284 -436.7276) (xy 389.241284 -436.219092) (xy 389.241757 -436.207018) (xy 389.249221 -436.184052)
			(xy 389.263416 -436.164516) (xy 389.282952 -436.150321) (xy 389.305918 -436.142857) (xy 389.317992 -436.142384)
			(xy 390.257792 -436.142384) (xy 390.269865 -436.142871) (xy 390.292831 -436.15033) (xy 390.312367 -436.164521)
			(xy 390.326562 -436.184055) (xy 390.334027 -436.207019) (xy 390.3345 -436.219092) (xy 390.3345 -438.760616)
			(xy 390.334049 -438.772692) (xy 390.326581 -438.795661) (xy 390.312382 -438.815199) (xy 390.29284 -438.829392)
			(xy 390.269868 -438.836853) (xy 390.257792 -438.837324) (xy 389.317992 -438.837324) (xy 389.305919 -438.836843)
			(xy 389.282954 -438.82938) (xy 389.263418 -438.815187) (xy 389.249224 -438.795653) (xy 389.241759 -438.772689)
			(xy 389.241284 -438.760616) (xy 389.241284 -438.252108) (xy 389.241216 -438.248502) (xy 389.240199 -438.241363)
			(xy 389.239252 -438.237884) (xy 389.229425 -438.201653) (xy 389.218839 -438.127336) (xy 389.21817 -438.089802)
			(xy 388.334504 -438.089802) (xy 388.334504 -439.0898) (xy 391.218166 -439.0898) (xy 391.218603 -439.057911)
			(xy 391.226241 -438.994591) (xy 391.241395 -438.932639) (xy 391.263847 -438.872943) (xy 391.293276 -438.816359)
			(xy 391.32926 -438.763701) (xy 391.371282 -438.715722) (xy 391.394696 -438.694068) (xy 391.398326 -438.690737)
			(xy 391.404339 -438.682934) (xy 391.406634 -438.678574) (xy 391.48258 -438.52338) (xy 391.487284 -438.512864)
			(xy 391.490775 -438.490105) (xy 391.487287 -438.467346) (xy 391.48258 -438.456832) (xy 391.405872 -438.300876)
			(xy 391.403693 -438.296544) (xy 391.397939 -438.288741) (xy 391.394442 -438.285382) (xy 391.371087 -438.263703)
			(xy 391.329119 -438.215751) (xy 391.293183 -438.163127) (xy 391.263796 -438.106584) (xy 391.241379 -438.046934)
			(xy 391.226253 -437.985032) (xy 391.218635 -437.921766) (xy 391.218166 -437.889904) (xy 391.21882 -437.852369)
			(xy 391.229396 -437.778047) (xy 391.239248 -437.741822) (xy 391.240199 -437.738343) (xy 391.241217 -437.731204)
			(xy 391.24128 -437.727598) (xy 391.24128 -437.21909) (xy 391.2417 -437.206996) (xy 391.249164 -437.183988)
			(xy 391.263361 -437.164405) (xy 391.282907 -437.150156) (xy 391.305895 -437.142632) (xy 391.317988 -437.142128)
			(xy 392.257788 -437.142128) (xy 392.269899 -437.142527) (xy 392.292931 -437.150027) (xy 392.312506 -437.164292)
			(xy 392.3267 -437.183919) (xy 392.334116 -437.206978) (xy 392.334496 -437.21909) (xy 392.334496 -438.089802)
			(xy 393.218162 -438.089802) (xy 393.218602 -438.057913) (xy 393.226239 -437.994593) (xy 393.241393 -437.932641)
			(xy 393.263845 -437.872945) (xy 393.293274 -437.816362) (xy 393.329257 -437.763703) (xy 393.371278 -437.715725)
			(xy 393.394692 -437.69407) (xy 393.398322 -437.690738) (xy 393.404334 -437.682935) (xy 393.40663 -437.678576)
			(xy 393.482576 -437.523382) (xy 393.487279 -437.512866) (xy 393.49077 -437.490107) (xy 393.487283 -437.467348)
			(xy 393.482576 -437.456834) (xy 393.405868 -437.300878) (xy 393.403689 -437.296546) (xy 393.397935 -437.288743)
			(xy 393.394438 -437.285384) (xy 393.371035 -437.263755) (xy 393.32907 -437.215795) (xy 393.293139 -437.163161)
			(xy 393.263759 -437.10661) (xy 393.241349 -437.046952) (xy 393.226233 -436.985043) (xy 393.218625 -436.92177)
			(xy 393.218162 -436.889906) (xy 393.218817 -436.852371) (xy 393.229393 -436.778049) (xy 393.239244 -436.741824)
			(xy 393.240195 -436.738345) (xy 393.241213 -436.731206) (xy 393.241276 -436.7276) (xy 393.241276 -436.219092)
			(xy 393.241757 -436.207019) (xy 393.24922 -436.184054) (xy 393.263413 -436.164518) (xy 393.282947 -436.150324)
			(xy 393.305911 -436.142859) (xy 393.317984 -436.142384) (xy 394.257784 -436.142384) (xy 394.269865 -436.142826)
			(xy 394.292846 -436.150288) (xy 394.312396 -436.164487) (xy 394.326601 -436.184033) (xy 394.33407 -436.207011)
			(xy 394.334492 -436.219092) (xy 394.334492 -438.760616) (xy 394.334049 -438.772693) (xy 394.32658 -438.795663)
			(xy 394.312379 -438.815201) (xy 394.292835 -438.829395) (xy 394.269861 -438.836854) (xy 394.257784 -438.837324)
			(xy 393.317984 -438.837324) (xy 393.30591 -438.83685) (xy 393.282945 -438.829385) (xy 393.26341 -438.81519)
			(xy 393.249215 -438.795655) (xy 393.24175 -438.77269) (xy 393.241276 -438.760616) (xy 393.241276 -438.252108)
			(xy 393.241209 -438.248502) (xy 393.240191 -438.241363) (xy 393.239244 -438.237884) (xy 393.229417 -438.201653)
			(xy 393.21883 -438.127336) (xy 393.218162 -438.089802) (xy 392.334496 -438.089802) (xy 392.334496 -439.0898)
			(xy 395.218158 -439.0898) (xy 395.218598 -439.057911) (xy 395.226235 -438.994591) (xy 395.241389 -438.932639)
			(xy 395.263841 -438.872943) (xy 395.29327 -438.81636) (xy 395.329253 -438.763701) (xy 395.371274 -438.715723)
			(xy 395.394688 -438.694068) (xy 395.398317 -438.690736) (xy 395.40433 -438.682933) (xy 395.406626 -438.678574)
			(xy 395.482572 -438.52338) (xy 395.487277 -438.512864) (xy 395.490768 -438.490105) (xy 395.48728 -438.467346)
			(xy 395.482572 -438.456832) (xy 395.405864 -438.300876) (xy 395.403686 -438.296544) (xy 395.397931 -438.288741)
			(xy 395.394434 -438.285382) (xy 395.371078 -438.263704) (xy 395.32911 -438.215753) (xy 395.293175 -438.163128)
			(xy 395.263788 -438.106585) (xy 395.241371 -438.046935) (xy 395.226245 -437.985032) (xy 395.218627 -437.921766)
			(xy 395.218158 -437.889904) (xy 395.218813 -437.852369) (xy 395.229389 -437.778047) (xy 395.23924 -437.741822)
			(xy 395.240191 -437.738343) (xy 395.241209 -437.731204) (xy 395.241272 -437.727598) (xy 395.241272 -437.21909)
			(xy 395.2417 -437.206997) (xy 395.249163 -437.183991) (xy 395.263359 -437.164408) (xy 395.282902 -437.150159)
			(xy 395.305888 -437.142633) (xy 395.31798 -437.142128) (xy 396.25778 -437.142128) (xy 396.269891 -437.142534)
			(xy 396.292922 -437.150031) (xy 396.312498 -437.164294) (xy 396.326692 -437.18392) (xy 396.334108 -437.206978)
			(xy 396.334488 -437.21909) (xy 396.334488 -438.089802) (xy 398.218406 -438.089802) (xy 398.218864 -438.057914)
			(xy 398.226501 -437.994595) (xy 398.241653 -437.932644) (xy 398.264102 -437.872949) (xy 398.293528 -437.816365)
			(xy 398.329507 -437.763706) (xy 398.371524 -437.715726) (xy 398.394936 -437.69407) (xy 398.398564 -437.690737)
			(xy 398.404583 -437.682938) (xy 398.406874 -437.678576) (xy 398.48282 -437.523382) (xy 398.487521 -437.512865)
			(xy 398.49101 -437.490107) (xy 398.487525 -437.467348) (xy 398.48282 -437.456834) (xy 398.406112 -437.300878)
			(xy 398.403942 -437.296541) (xy 398.398182 -437.288741) (xy 398.394682 -437.285384) (xy 398.371268 -437.263767)
			(xy 398.329306 -437.215803) (xy 398.293378 -437.163167) (xy 398.263999 -437.106614) (xy 398.241591 -437.046954)
			(xy 398.226476 -436.985044) (xy 398.218869 -436.921771) (xy 398.218406 -436.889906) (xy 398.219059 -436.852371)
			(xy 398.229636 -436.778049) (xy 398.239488 -436.741824) (xy 398.240438 -436.738345) (xy 398.241457 -436.731206)
			(xy 398.24152 -436.7276) (xy 398.24152 -436.219092) (xy 398.241906 -436.207006) (xy 398.249379 -436.184018)
			(xy 398.263591 -436.164466) (xy 398.283151 -436.150263) (xy 398.306142 -436.1428) (xy 398.318228 -436.142384)
			(xy 399.258028 -436.142384) (xy 399.270103 -436.14284) (xy 399.29307 -436.150309) (xy 399.312606 -436.164508)
			(xy 399.3268 -436.184048) (xy 399.334263 -436.207017) (xy 399.334736 -436.219092) (xy 399.334736 -438.760616)
			(xy 399.33425 -438.772689) (xy 399.326786 -438.795651) (xy 399.312594 -438.815186) (xy 399.293062 -438.829381)
			(xy 399.270101 -438.836848) (xy 399.258028 -438.837324) (xy 398.318228 -438.837324) (xy 398.306148 -438.836864)
			(xy 398.283169 -438.829406) (xy 398.26362 -438.815211) (xy 398.249414 -438.79567) (xy 398.241943 -438.772695)
			(xy 398.24152 -438.760616) (xy 398.24152 -438.252108) (xy 398.241455 -438.248502) (xy 398.240436 -438.241363)
			(xy 398.239488 -438.237884) (xy 398.22966 -438.201654) (xy 398.219074 -438.127336) (xy 398.218406 -438.089802)
			(xy 396.334488 -438.089802) (xy 396.334488 -439.0898) (xy 400.218402 -439.0898) (xy 400.21886 -439.057912)
			(xy 400.226497 -438.994593) (xy 400.241649 -438.932642) (xy 400.264098 -438.872947) (xy 400.293524 -438.816364)
			(xy 400.329503 -438.763704) (xy 400.37152 -438.715724) (xy 400.394932 -438.694068) (xy 400.398567 -438.690741)
			(xy 400.404576 -438.682935) (xy 400.40687 -438.678574) (xy 400.482816 -438.52338) (xy 400.487519 -438.512864)
			(xy 400.491008 -438.490105) (xy 400.487522 -438.467346) (xy 400.482816 -438.456832) (xy 400.406108 -438.300876)
			(xy 400.403939 -438.296539) (xy 400.398178 -438.288739) (xy 400.394678 -438.285382) (xy 400.371311 -438.263716)
			(xy 400.329345 -438.215761) (xy 400.293413 -438.163134) (xy 400.264028 -438.106589) (xy 400.241613 -438.046937)
			(xy 400.226488 -437.985034) (xy 400.218871 -437.921766) (xy 400.218402 -437.889904) (xy 400.219055 -437.852369)
			(xy 400.229632 -437.778047) (xy 400.239484 -437.741822) (xy 400.240434 -437.738343) (xy 400.241453 -437.731204)
			(xy 400.241516 -437.727598) (xy 400.241516 -437.21909) (xy 400.241999 -437.207002) (xy 400.249455 -437.184006)
			(xy 400.263639 -437.164428) (xy 400.283167 -437.150177) (xy 400.306138 -437.142641) (xy 400.318224 -437.142128)
			(xy 401.258024 -437.142128) (xy 401.270137 -437.142496) (xy 401.29317 -437.150006) (xy 401.312745 -437.164279)
			(xy 401.326938 -437.183912) (xy 401.334353 -437.206975) (xy 401.334732 -437.21909) (xy 401.334732 -438.089802)
			(xy 402.218398 -438.089802) (xy 402.218826 -438.057912) (xy 402.226464 -437.994592) (xy 402.241619 -437.932639)
			(xy 402.264072 -437.872942) (xy 402.293503 -437.816359) (xy 402.329489 -437.763701) (xy 402.371512 -437.715724)
			(xy 402.394928 -437.69407) (xy 402.398562 -437.690743) (xy 402.404572 -437.682936) (xy 402.406866 -437.678576)
			(xy 402.482812 -437.523382) (xy 402.487513 -437.512866) (xy 402.491003 -437.490107) (xy 402.487518 -437.467348)
			(xy 402.482812 -437.456834) (xy 402.406104 -437.300878) (xy 402.403935 -437.29654) (xy 402.398174 -437.288741)
			(xy 402.394674 -437.285384) (xy 402.371258 -437.263769) (xy 402.329296 -437.215804) (xy 402.293369 -437.163168)
			(xy 402.263991 -437.106614) (xy 402.241583 -437.046954) (xy 402.226468 -436.985044) (xy 402.218861 -436.921771)
			(xy 402.218398 -436.889906) (xy 402.219052 -436.852371) (xy 402.229628 -436.778049) (xy 402.23948 -436.741824)
			(xy 402.240429 -436.738345) (xy 402.241449 -436.731206) (xy 402.241512 -436.7276) (xy 402.241512 -436.219092)
			(xy 402.241906 -436.207007) (xy 402.249378 -436.18402) (xy 402.263588 -436.164469) (xy 402.283146 -436.150265)
			(xy 402.306135 -436.142802) (xy 402.31822 -436.142384) (xy 403.25802 -436.142384) (xy 403.270095 -436.142847)
			(xy 403.293061 -436.150314) (xy 403.312597 -436.164511) (xy 403.326791 -436.18405) (xy 403.334255 -436.207017)
			(xy 403.334728 -436.219092) (xy 403.334728 -438.760616) (xy 403.33425 -438.772689) (xy 403.326785 -438.795654)
			(xy 403.312591 -438.815189) (xy 403.293057 -438.829383) (xy 403.270093 -438.836849) (xy 403.25802 -438.837324)
			(xy 402.31822 -438.837324) (xy 402.30614 -438.83687) (xy 402.283161 -438.82941) (xy 402.263611 -438.815214)
			(xy 402.249406 -438.795672) (xy 402.241935 -438.772696) (xy 402.241512 -438.760616) (xy 402.241512 -438.252108)
			(xy 402.241447 -438.248502) (xy 402.240428 -438.241363) (xy 402.23948 -438.237884) (xy 402.229654 -438.201653)
			(xy 402.219067 -438.127336) (xy 402.218398 -438.089802) (xy 401.334732 -438.089802) (xy 401.334732 -439.0898)
			(xy 404.218394 -439.0898) (xy 404.218822 -439.05791) (xy 404.22646 -438.99459) (xy 404.241615 -438.932637)
			(xy 404.264069 -438.872941) (xy 404.293499 -438.816357) (xy 404.329485 -438.763699) (xy 404.371508 -438.715722)
			(xy 404.394924 -438.694068) (xy 404.398558 -438.69074) (xy 404.404568 -438.682934) (xy 404.406862 -438.678574)
			(xy 404.482808 -438.52338) (xy 404.487511 -438.512864) (xy 404.491 -438.490105) (xy 404.487514 -438.467346)
			(xy 404.482808 -438.456832) (xy 404.4061 -438.300876) (xy 404.403932 -438.296538) (xy 404.398171 -438.288738)
			(xy 404.39467 -438.285382) (xy 404.371301 -438.263718) (xy 404.329336 -438.215762) (xy 404.293404 -438.163134)
			(xy 404.26402 -438.106589) (xy 404.241605 -438.046937) (xy 404.22648 -437.985034) (xy 404.218863 -437.921766)
			(xy 404.218394 -437.889904) (xy 404.219047 -437.852369) (xy 404.229624 -437.778047) (xy 404.239476 -437.741822)
			(xy 404.240426 -437.738343) (xy 404.241445 -437.731204) (xy 404.241508 -437.727598) (xy 404.241508 -437.21909)
			(xy 404.241998 -437.207003) (xy 404.249454 -437.184008) (xy 404.263636 -437.164431) (xy 404.283162 -437.150179)
			(xy 404.306131 -437.142642) (xy 404.318216 -437.142128) (xy 405.258016 -437.142128) (xy 405.270129 -437.142503)
			(xy 405.293161 -437.15001) (xy 405.312736 -437.164281) (xy 405.326929 -437.183914) (xy 405.334345 -437.206976)
			(xy 405.334724 -437.21909) (xy 405.334724 -438.089802) (xy 406.21839 -438.089802) (xy 406.218821 -438.057912)
			(xy 406.226458 -437.994592) (xy 406.241613 -437.932639) (xy 406.264066 -437.872943) (xy 406.293497 -437.81636)
			(xy 406.329481 -437.763702) (xy 406.371505 -437.715724) (xy 406.39492 -437.69407) (xy 406.398553 -437.690742)
			(xy 406.404563 -437.682936) (xy 406.406858 -437.678576) (xy 406.482804 -437.523382) (xy 406.487505 -437.512865)
			(xy 406.490995 -437.490107) (xy 406.48751 -437.467348) (xy 406.482804 -437.456834) (xy 406.406096 -437.300878)
			(xy 406.403929 -437.29654) (xy 406.398167 -437.28874) (xy 406.394666 -437.285384) (xy 406.371249 -437.26377)
			(xy 406.329287 -437.215805) (xy 406.29336 -437.163169) (xy 406.263982 -437.106615) (xy 406.241575 -437.046955)
			(xy 406.22646 -436.985044) (xy 406.218853 -436.921771) (xy 406.21839 -436.889906) (xy 406.219044 -436.852371)
			(xy 406.22962 -436.778049) (xy 406.239472 -436.741824) (xy 406.240421 -436.738345) (xy 406.241441 -436.731206)
			(xy 406.241504 -436.7276) (xy 406.241504 -436.219092) (xy 406.241906 -436.207008) (xy 406.249377 -436.184023)
			(xy 406.263586 -436.164471) (xy 406.283141 -436.150268) (xy 406.306128 -436.142803) (xy 406.318212 -436.142384)
			(xy 407.258012 -436.142384) (xy 407.270086 -436.142854) (xy 407.293053 -436.150319) (xy 407.312589 -436.164514)
			(xy 407.326783 -436.184051) (xy 407.334247 -436.207018) (xy 407.33472 -436.219092) (xy 407.33472 -438.760616)
			(xy 407.334249 -438.77269) (xy 407.326784 -438.795656) (xy 407.312589 -438.815191) (xy 407.293052 -438.829386)
			(xy 407.270086 -438.83685) (xy 407.258012 -438.837324) (xy 406.318212 -438.837324) (xy 406.30614 -438.836826)
			(xy 406.283176 -438.829369) (xy 406.26364 -438.81518) (xy 406.249444 -438.79565) (xy 406.241979 -438.772688)
			(xy 406.241504 -438.760616) (xy 406.241504 -438.252108) (xy 406.241439 -438.248502) (xy 406.240421 -438.241363)
			(xy 406.239472 -438.237884) (xy 406.229645 -438.201653) (xy 406.219059 -438.127336) (xy 406.21839 -438.089802)
			(xy 405.334724 -438.089802) (xy 405.334724 -439.0898) (xy 408.218386 -439.0898) (xy 408.218816 -439.05791)
			(xy 408.226455 -438.99459) (xy 408.241609 -438.932637) (xy 408.264062 -438.872941) (xy 408.293493 -438.816358)
			(xy 408.329478 -438.7637) (xy 408.371501 -438.715722) (xy 408.394916 -438.694068) (xy 408.398549 -438.690739)
			(xy 408.404559 -438.682934) (xy 408.406854 -438.678574) (xy 408.4828 -438.52338) (xy 408.487503 -438.512864)
			(xy 408.490993 -438.490105) (xy 408.487506 -438.467346) (xy 408.4828 -438.456832) (xy 408.406092 -438.300876)
			(xy 408.403926 -438.296537) (xy 408.398163 -438.288738) (xy 408.394662 -438.285382) (xy 408.371292 -438.263719)
			(xy 408.329327 -438.215763) (xy 408.293395 -438.163135) (xy 408.264011 -438.10659) (xy 408.241596 -438.046938)
			(xy 408.226472 -437.985034) (xy 408.218855 -437.921766) (xy 408.218386 -437.889904) (xy 408.21904 -437.852369)
			(xy 408.229616 -437.778047) (xy 408.239468 -437.741822) (xy 408.240418 -437.738343) (xy 408.241437 -437.731204)
			(xy 408.2415 -437.727598) (xy 408.2415 -437.21909) (xy 408.241998 -437.207004) (xy 408.249453 -437.18401)
			(xy 408.263633 -437.164434) (xy 408.283157 -437.150182) (xy 408.306124 -437.142643) (xy 408.318208 -437.142128)
			(xy 409.258008 -437.142128) (xy 409.27012 -437.14251) (xy 409.293152 -437.150015) (xy 409.312728 -437.164284)
			(xy 409.326921 -437.183915) (xy 409.334337 -437.206976) (xy 409.334716 -437.21909) (xy 409.334716 -438.089802)
			(xy 410.218382 -438.089802) (xy 410.218815 -438.057913) (xy 410.226453 -437.994592) (xy 410.241607 -437.93264)
			(xy 410.26406 -437.872944) (xy 410.29349 -437.81636) (xy 410.329474 -437.763702) (xy 410.371497 -437.715724)
			(xy 410.394912 -437.69407) (xy 410.398544 -437.690741) (xy 410.404555 -437.682936) (xy 410.40685 -437.678576)
			(xy 410.482796 -437.523382) (xy 410.487498 -437.512866) (xy 410.490988 -437.490107) (xy 410.487502 -437.467348)
			(xy 410.482796 -437.456834) (xy 410.406088 -437.300878) (xy 410.403922 -437.296539) (xy 410.398159 -437.28874)
			(xy 410.394658 -437.285384) (xy 410.371259 -437.263751) (xy 410.329293 -437.215792) (xy 410.293361 -437.163159)
			(xy 410.26398 -437.106609) (xy 410.24157 -437.046951) (xy 410.226453 -436.985042) (xy 410.218845 -436.92177)
			(xy 410.218382 -436.889906) (xy 410.219036 -436.852371) (xy 410.229612 -436.778049) (xy 410.239464 -436.741824)
			(xy 410.240413 -436.738345) (xy 410.241433 -436.731206) (xy 410.241496 -436.7276) (xy 410.241496 -436.219092)
			(xy 410.241958 -436.207017) (xy 410.249423 -436.184049) (xy 410.26362 -436.164511) (xy 410.283159 -436.150317)
			(xy 410.306129 -436.142856) (xy 410.318204 -436.142384) (xy 411.258004 -436.142384) (xy 411.270078 -436.142861)
			(xy 411.293044 -436.150323) (xy 411.31258 -436.164517) (xy 411.326775 -436.184053) (xy 411.334239 -436.207018)
			(xy 411.334712 -436.219092) (xy 411.334712 -438.760616) (xy 411.334249 -438.772691) (xy 411.326783 -438.795658)
			(xy 411.312586 -438.815194) (xy 411.293047 -438.829388) (xy 411.270079 -438.836851) (xy 411.258004 -438.837324)
			(xy 410.318204 -438.837324) (xy 410.306131 -438.836833) (xy 410.283167 -438.829373) (xy 410.263631 -438.815183)
			(xy 410.249436 -438.795651) (xy 410.241971 -438.772689) (xy 410.241496 -438.760616) (xy 410.241496 -438.252108)
			(xy 410.241432 -438.248502) (xy 410.240413 -438.241363) (xy 410.239464 -438.237884) (xy 410.229637 -438.201653)
			(xy 410.219051 -438.127336) (xy 410.218382 -438.089802) (xy 409.334716 -438.089802) (xy 409.334716 -439.0898)
			(xy 412.218378 -439.0898) (xy 412.218811 -439.057911) (xy 412.226449 -438.99459) (xy 412.241603 -438.932638)
			(xy 412.264056 -438.872942) (xy 412.293486 -438.816359) (xy 412.329471 -438.7637) (xy 412.371493 -438.715722)
			(xy 412.394908 -438.694068) (xy 412.39854 -438.690738) (xy 412.404551 -438.682934) (xy 412.406846 -438.678574)
			(xy 412.482792 -438.52338) (xy 412.487495 -438.512864) (xy 412.490985 -438.490105) (xy 412.487499 -438.467346)
			(xy 412.482792 -438.456832) (xy 412.406084 -438.300876) (xy 412.403919 -438.296536) (xy 412.398156 -438.288738)
			(xy 412.394654 -438.285382) (xy 412.371302 -438.2637) (xy 412.329333 -438.21575) (xy 412.293397 -438.163126)
			(xy 412.264009 -438.106584) (xy 412.241591 -438.046934) (xy 412.226465 -437.985032) (xy 412.218847 -437.921766)
			(xy 412.218378 -437.889904) (xy 412.219032 -437.852369) (xy 412.229608 -437.778047) (xy 412.23946 -437.741822)
			(xy 412.240412 -437.738343) (xy 412.241429 -437.731204) (xy 412.241492 -437.727598) (xy 412.241492 -437.21909)
			(xy 412.241998 -437.207005) (xy 412.249452 -437.184012) (xy 412.26363 -437.164436) (xy 412.283152 -437.150184)
			(xy 412.306117 -437.142644) (xy 412.3182 -437.142128) (xy 413.258 -437.142128) (xy 413.270112 -437.142516)
			(xy 413.293144 -437.150019) (xy 413.312719 -437.164287) (xy 413.326913 -437.183916) (xy 413.334329 -437.206977)
			(xy 413.334708 -437.21909) (xy 413.334708 -439.760614) (xy 413.334206 -439.7727) (xy 413.326751 -439.795693)
			(xy 413.312572 -439.815268) (xy 413.293049 -439.82952) (xy 413.270084 -439.83706) (xy 413.258 -439.837576)
			(xy 412.3182 -439.837576) (xy 412.306089 -439.837184) (xy 412.283057 -439.829681) (xy 412.263482 -439.815414)
			(xy 412.249288 -439.795786) (xy 412.241872 -439.772727) (xy 412.241492 -439.760614) (xy 412.241492 -439.252106)
			(xy 412.241424 -439.2485) (xy 412.240407 -439.241361) (xy 412.23946 -439.237882) (xy 412.229633 -439.201651)
			(xy 412.219046 -439.127334) (xy 412.218378 -439.0898) (xy 409.334716 -439.0898) (xy 409.334716 -439.760614)
			(xy 409.334304 -439.772709) (xy 409.326838 -439.795717) (xy 409.312639 -439.815301) (xy 409.293091 -439.829549)
			(xy 409.270101 -439.837073) (xy 409.258008 -439.837576) (xy 408.318208 -439.837576) (xy 408.306097 -439.837177)
			(xy 408.283066 -439.829677) (xy 408.263491 -439.815412) (xy 408.249296 -439.795785) (xy 408.24188 -439.772726)
			(xy 408.2415 -439.760614) (xy 408.2415 -439.252106) (xy 408.241436 -439.2485) (xy 408.240417 -439.241361)
			(xy 408.239468 -439.237882) (xy 408.229641 -439.201651) (xy 408.219054 -439.127334) (xy 408.218386 -439.0898)
			(xy 405.334724 -439.0898) (xy 405.334724 -439.760614) (xy 405.334304 -439.772708) (xy 405.326839 -439.795715)
			(xy 405.312642 -439.815298) (xy 405.293096 -439.829547) (xy 405.270109 -439.837072) (xy 405.258016 -439.837576)
			(xy 404.318216 -439.837576) (xy 404.306106 -439.83717) (xy 404.283075 -439.829672) (xy 404.263499 -439.815408)
			(xy 404.249305 -439.795783) (xy 404.241888 -439.772726) (xy 404.241508 -439.760614) (xy 404.241508 -439.252106)
			(xy 404.241443 -439.2485) (xy 404.240425 -439.241361) (xy 404.239476 -439.237882) (xy 404.229649 -439.201651)
			(xy 404.219062 -439.127334) (xy 404.218394 -439.0898) (xy 401.334732 -439.0898) (xy 401.334732 -439.760614)
			(xy 401.334304 -439.772707) (xy 401.32684 -439.795713) (xy 401.312645 -439.815295) (xy 401.293101 -439.829544)
			(xy 401.270116 -439.837071) (xy 401.258024 -439.837576) (xy 400.318224 -439.837576) (xy 400.306114 -439.837163)
			(xy 400.283083 -439.829667) (xy 400.263508 -439.815406) (xy 400.249313 -439.795781) (xy 400.241896 -439.772725)
			(xy 400.241516 -439.760614) (xy 400.241516 -439.252106) (xy 400.241451 -439.2485) (xy 400.240432 -439.241361)
			(xy 400.239484 -439.237882) (xy 400.229655 -439.201652) (xy 400.21907 -439.127334) (xy 400.218402 -439.0898)
			(xy 396.334488 -439.0898) (xy 396.334488 -439.760614) (xy 396.334005 -439.772702) (xy 396.326548 -439.795698)
			(xy 396.312365 -439.815275) (xy 396.292836 -439.829526) (xy 396.269866 -439.837063) (xy 396.25778 -439.837576)
			(xy 395.31798 -439.837576) (xy 395.305868 -439.8372) (xy 395.282836 -439.829693) (xy 395.263261 -439.815421)
			(xy 395.249068 -439.79579) (xy 395.241652 -439.772728) (xy 395.241272 -439.760614) (xy 395.241272 -439.252106)
			(xy 395.241205 -439.2485) (xy 395.240188 -439.241361) (xy 395.23924 -439.237882) (xy 395.229412 -439.201652)
			(xy 395.218826 -439.127334) (xy 395.218158 -439.0898) (xy 392.334496 -439.0898) (xy 392.334496 -439.760614)
			(xy 392.334005 -439.772701) (xy 392.326549 -439.795696) (xy 392.312367 -439.815272) (xy 392.292841 -439.829524)
			(xy 392.269873 -439.837062) (xy 392.257788 -439.837576) (xy 391.317988 -439.837576) (xy 391.305876 -439.837194)
			(xy 391.282844 -439.829688) (xy 391.263269 -439.815419) (xy 391.249076 -439.795788) (xy 391.24166 -439.772727)
			(xy 391.24128 -439.760614) (xy 391.24128 -439.252106) (xy 391.241213 -439.2485) (xy 391.240195 -439.241361)
			(xy 391.239248 -439.237882) (xy 391.22942 -439.201651) (xy 391.218834 -439.127334) (xy 391.218166 -439.0898)
			(xy 388.334504 -439.0898) (xy 388.334504 -439.760614) (xy 388.334006 -439.7727) (xy 388.32655 -439.795694)
			(xy 388.31237 -439.81527) (xy 388.292846 -439.829521) (xy 388.26988 -439.837061) (xy 388.257796 -439.837576)
			(xy 387.317996 -439.837576) (xy 387.305885 -439.837187) (xy 387.282853 -439.829683) (xy 387.263278 -439.815416)
			(xy 387.249084 -439.795787) (xy 387.241668 -439.772727) (xy 387.241288 -439.760614) (xy 387.241288 -439.252106)
			(xy 387.24122 -439.2485) (xy 387.240203 -439.241361) (xy 387.239256 -439.237882) (xy 387.229429 -439.201651)
			(xy 387.218842 -439.127334) (xy 387.218174 -439.0898) (xy 384.334512 -439.0898) (xy 384.334512 -439.760614)
			(xy 384.334104 -439.772709) (xy 384.326638 -439.795718) (xy 384.312437 -439.815302) (xy 384.292889 -439.829551)
			(xy 384.269898 -439.837074) (xy 384.257804 -439.837576) (xy 383.318004 -439.837576) (xy 383.305893 -439.83718)
			(xy 383.282862 -439.829679) (xy 383.263286 -439.815413) (xy 383.249092 -439.795785) (xy 383.241676 -439.772727)
			(xy 383.241296 -439.760614) (xy 383.241296 -439.252106) (xy 383.241232 -439.2485) (xy 383.240213 -439.241361)
			(xy 383.239264 -439.237882) (xy 383.229437 -439.201651) (xy 383.21885 -439.127334) (xy 383.218182 -439.0898)
			(xy 346.234512 -439.0898) (xy 346.234512 -439.760614) (xy 346.234104 -439.772709) (xy 346.226638 -439.795718)
			(xy 346.212437 -439.815302) (xy 346.192889 -439.829551) (xy 346.169898 -439.837074) (xy 346.157804 -439.837576)
			(xy 345.218004 -439.837576) (xy 345.205893 -439.83718) (xy 345.182862 -439.829679) (xy 345.163286 -439.815413)
			(xy 345.149092 -439.795785) (xy 345.141676 -439.772727) (xy 345.141296 -439.760614) (xy 345.141296 -439.252106)
			(xy 345.141232 -439.2485) (xy 345.140213 -439.241361) (xy 345.139264 -439.237882) (xy 345.129437 -439.201651)
			(xy 345.11885 -439.127334) (xy 345.118182 -439.0898) (xy 342.23452 -439.0898) (xy 342.23452 -439.760614)
			(xy 342.234104 -439.772708) (xy 342.226639 -439.795716) (xy 342.21244 -439.815299) (xy 342.192894 -439.829548)
			(xy 342.169905 -439.837073) (xy 342.157812 -439.837576) (xy 341.218012 -439.837576) (xy 341.205901 -439.837173)
			(xy 341.18287 -439.829674) (xy 341.163295 -439.81541) (xy 341.149101 -439.795784) (xy 341.141684 -439.772726)
			(xy 341.141304 -439.760614) (xy 341.141304 -439.252106) (xy 341.14124 -439.2485) (xy 341.140221 -439.241361)
			(xy 341.139272 -439.237882) (xy 341.129445 -439.201651) (xy 341.118858 -439.127334) (xy 341.11819 -439.0898)
			(xy 338.234528 -439.0898) (xy 338.234528 -439.760614) (xy 338.234104 -439.772708) (xy 338.22664 -439.795714)
			(xy 338.212443 -439.815297) (xy 338.192899 -439.829546) (xy 338.169912 -439.837072) (xy 338.15782 -439.837576)
			(xy 337.21802 -439.837576) (xy 337.20591 -439.837166) (xy 337.182879 -439.829669) (xy 337.163304 -439.815407)
			(xy 337.149109 -439.795782) (xy 337.141692 -439.772726) (xy 337.141312 -439.760614) (xy 337.141312 -439.252106)
			(xy 337.141247 -439.2485) (xy 337.140229 -439.241361) (xy 337.13928 -439.237882) (xy 337.129453 -439.201651)
			(xy 337.118866 -439.127334) (xy 337.118198 -439.0898) (xy 334.234536 -439.0898) (xy 334.234536 -439.760614)
			(xy 334.234104 -439.772707) (xy 334.226641 -439.795712) (xy 334.212446 -439.815294) (xy 334.192904 -439.829543)
			(xy 334.169919 -439.83707) (xy 334.157828 -439.837576) (xy 333.218028 -439.837576) (xy 333.205918 -439.837159)
			(xy 333.182888 -439.829665) (xy 333.163312 -439.815404) (xy 333.149117 -439.795781) (xy 333.1417 -439.772725)
			(xy 333.14132 -439.760614) (xy 333.14132 -439.252106) (xy 333.141255 -439.2485) (xy 333.140236 -439.241361)
			(xy 333.139288 -439.237882) (xy 333.129459 -439.201652) (xy 333.118874 -439.127334) (xy 333.118206 -439.0898)
			(xy 329.234292 -439.0898) (xy 329.234292 -439.760614) (xy 329.233805 -439.772701) (xy 329.226349 -439.795697)
			(xy 329.212166 -439.815274) (xy 329.192639 -439.829525) (xy 329.169669 -439.837062) (xy 329.157584 -439.837576)
			(xy 328.217784 -439.837576) (xy 328.205672 -439.837197) (xy 328.18264 -439.82969) (xy 328.163065 -439.81542)
			(xy 328.148872 -439.795789) (xy 328.141456 -439.772728) (xy 328.141076 -439.760614) (xy 328.141076 -439.252106)
			(xy 328.141009 -439.2485) (xy 328.139991 -439.241361) (xy 328.139044 -439.237882) (xy 328.129216 -439.201652)
			(xy 328.11863 -439.127334) (xy 328.117962 -439.0898) (xy 325.2343 -439.0898) (xy 325.2343 -439.760614)
			(xy 325.233806 -439.7727) (xy 325.22635 -439.795695) (xy 325.212169 -439.815271) (xy 325.192644 -439.829523)
			(xy 325.169677 -439.837061) (xy 325.157592 -439.837576) (xy 324.217792 -439.837576) (xy 324.20568 -439.83719)
			(xy 324.182649 -439.829686) (xy 324.163074 -439.815417) (xy 324.14888 -439.795788) (xy 324.141464 -439.772727)
			(xy 324.141084 -439.760614) (xy 324.141084 -439.252106) (xy 324.141017 -439.2485) (xy 324.139999 -439.241361)
			(xy 324.139052 -439.237882) (xy 324.129225 -439.201651) (xy 324.118638 -439.127334) (xy 324.11797 -439.0898)
			(xy 321.234308 -439.0898) (xy 321.234308 -439.760614) (xy 321.233806 -439.7727) (xy 321.226351 -439.795693)
			(xy 321.212172 -439.815268) (xy 321.192649 -439.82952) (xy 321.169684 -439.83706) (xy 321.1576 -439.837576)
			(xy 320.2178 -439.837576) (xy 320.205689 -439.837184) (xy 320.182657 -439.829681) (xy 320.163082 -439.815414)
			(xy 320.148888 -439.795786) (xy 320.141472 -439.772727) (xy 320.141092 -439.760614) (xy 320.141092 -439.252106)
			(xy 320.141024 -439.2485) (xy 320.140007 -439.241361) (xy 320.13906 -439.237882) (xy 320.129233 -439.201651)
			(xy 320.118646 -439.127334) (xy 320.117978 -439.0898) (xy 317.234316 -439.0898) (xy 317.234316 -439.760614)
			(xy 317.233904 -439.772709) (xy 317.226438 -439.795717) (xy 317.212239 -439.815301) (xy 317.192691 -439.829549)
			(xy 317.169701 -439.837073) (xy 317.157608 -439.837576) (xy 316.217808 -439.837576) (xy 316.205697 -439.837177)
			(xy 316.182666 -439.829677) (xy 316.163091 -439.815412) (xy 316.148896 -439.795785) (xy 316.14148 -439.772726)
			(xy 316.1411 -439.760614) (xy 316.1411 -439.252106) (xy 316.141036 -439.2485) (xy 316.140017 -439.241361)
			(xy 316.139068 -439.237882) (xy 316.129241 -439.201651) (xy 316.118654 -439.127334) (xy 316.117986 -439.0898)
			(xy 157.334712 -439.0898) (xy 157.334712 -439.760614) (xy 157.334304 -439.772709) (xy 157.326838 -439.795718)
			(xy 157.312637 -439.815302) (xy 157.293089 -439.829551) (xy 157.270098 -439.837074) (xy 157.258004 -439.837576)
			(xy 156.318204 -439.837576) (xy 156.306093 -439.83718) (xy 156.283062 -439.829679) (xy 156.263486 -439.815413)
			(xy 156.249292 -439.795785) (xy 156.241876 -439.772727) (xy 156.241496 -439.760614) (xy 156.241496 -439.252106)
			(xy 156.241432 -439.2485) (xy 156.240413 -439.241361) (xy 156.239464 -439.237882) (xy 156.229637 -439.201651)
			(xy 156.21905 -439.127334) (xy 156.218382 -439.0898) (xy 153.33472 -439.0898) (xy 153.33472 -439.760614)
			(xy 153.334304 -439.772708) (xy 153.326839 -439.795716) (xy 153.31264 -439.815299) (xy 153.293094 -439.829548)
			(xy 153.270105 -439.837073) (xy 153.258012 -439.837576) (xy 152.318212 -439.837576) (xy 152.306101 -439.837173)
			(xy 152.28307 -439.829674) (xy 152.263495 -439.81541) (xy 152.249301 -439.795784) (xy 152.241884 -439.772726)
			(xy 152.241504 -439.760614) (xy 152.241504 -439.252106) (xy 152.24144 -439.2485) (xy 152.240421 -439.241361)
			(xy 152.239472 -439.237882) (xy 152.229645 -439.201651) (xy 152.219058 -439.127334) (xy 152.21839 -439.0898)
			(xy 149.334728 -439.0898) (xy 149.334728 -439.760614) (xy 149.334304 -439.772708) (xy 149.32684 -439.795714)
			(xy 149.312643 -439.815297) (xy 149.293099 -439.829546) (xy 149.270112 -439.837072) (xy 149.25802 -439.837576)
			(xy 148.31822 -439.837576) (xy 148.30611 -439.837166) (xy 148.283079 -439.829669) (xy 148.263504 -439.815407)
			(xy 148.249309 -439.795782) (xy 148.241892 -439.772726) (xy 148.241512 -439.760614) (xy 148.241512 -439.252106)
			(xy 148.241447 -439.2485) (xy 148.240429 -439.241361) (xy 148.23948 -439.237882) (xy 148.229653 -439.201651)
			(xy 148.219066 -439.127334) (xy 148.218398 -439.0898) (xy 145.334736 -439.0898) (xy 145.334736 -439.760614)
			(xy 145.334304 -439.772707) (xy 145.326841 -439.795712) (xy 145.312646 -439.815294) (xy 145.293104 -439.829543)
			(xy 145.270119 -439.83707) (xy 145.258028 -439.837576) (xy 144.318228 -439.837576) (xy 144.306118 -439.837159)
			(xy 144.283088 -439.829665) (xy 144.263512 -439.815404) (xy 144.249317 -439.795781) (xy 144.2419 -439.772725)
			(xy 144.24152 -439.760614) (xy 144.24152 -439.252106) (xy 144.241455 -439.2485) (xy 144.240436 -439.241361)
			(xy 144.239488 -439.237882) (xy 144.229659 -439.201652) (xy 144.219074 -439.127334) (xy 144.218406 -439.0898)
			(xy 140.334492 -439.0898) (xy 140.334492 -439.760614) (xy 140.334005 -439.772701) (xy 140.326549 -439.795697)
			(xy 140.312366 -439.815274) (xy 140.292839 -439.829525) (xy 140.269869 -439.837062) (xy 140.257784 -439.837576)
			(xy 139.317984 -439.837576) (xy 139.305872 -439.837197) (xy 139.28284 -439.82969) (xy 139.263265 -439.81542)
			(xy 139.249072 -439.795789) (xy 139.241656 -439.772728) (xy 139.241276 -439.760614) (xy 139.241276 -439.252106)
			(xy 139.241209 -439.2485) (xy 139.240191 -439.241361) (xy 139.239244 -439.237882) (xy 139.229416 -439.201652)
			(xy 139.21883 -439.127334) (xy 139.218162 -439.0898) (xy 136.3345 -439.0898) (xy 136.3345 -439.760614)
			(xy 136.334006 -439.7727) (xy 136.32655 -439.795695) (xy 136.312369 -439.815271) (xy 136.292844 -439.829523)
			(xy 136.269877 -439.837061) (xy 136.257792 -439.837576) (xy 135.317992 -439.837576) (xy 135.30588 -439.83719)
			(xy 135.282849 -439.829686) (xy 135.263274 -439.815417) (xy 135.24908 -439.795788) (xy 135.241664 -439.772727)
			(xy 135.241284 -439.760614) (xy 135.241284 -439.252106) (xy 135.241217 -439.2485) (xy 135.240199 -439.241361)
			(xy 135.239252 -439.237882) (xy 135.229425 -439.201651) (xy 135.218838 -439.127334) (xy 135.21817 -439.0898)
			(xy 132.334508 -439.0898) (xy 132.334508 -439.760614) (xy 132.334006 -439.7727) (xy 132.326551 -439.795693)
			(xy 132.312372 -439.815268) (xy 132.292849 -439.82952) (xy 132.269884 -439.83706) (xy 132.2578 -439.837576)
			(xy 131.318 -439.837576) (xy 131.305889 -439.837184) (xy 131.282857 -439.829681) (xy 131.263282 -439.815414)
			(xy 131.249088 -439.795786) (xy 131.241672 -439.772727) (xy 131.241292 -439.760614) (xy 131.241292 -439.252106)
			(xy 131.241224 -439.2485) (xy 131.240207 -439.241361) (xy 131.23926 -439.237882) (xy 131.229433 -439.201651)
			(xy 131.218846 -439.127334) (xy 131.218178 -439.0898) (xy 128.334516 -439.0898) (xy 128.334516 -439.760614)
			(xy 128.334104 -439.772709) (xy 128.326638 -439.795717) (xy 128.312439 -439.815301) (xy 128.292891 -439.829549)
			(xy 128.269901 -439.837073) (xy 128.257808 -439.837576) (xy 127.318008 -439.837576) (xy 127.305897 -439.837177)
			(xy 127.282866 -439.829677) (xy 127.263291 -439.815412) (xy 127.249096 -439.795785) (xy 127.24168 -439.772726)
			(xy 127.2413 -439.760614) (xy 127.2413 -439.252106) (xy 127.241236 -439.2485) (xy 127.240217 -439.241361)
			(xy 127.239268 -439.237882) (xy 127.229441 -439.201651) (xy 127.218854 -439.127334) (xy 127.218186 -439.0898)
			(xy 90.235024 -439.0898) (xy 90.235024 -439.760614) (xy 90.234651 -439.772741) (xy 90.22715 -439.795807)
			(xy 90.212888 -439.815425) (xy 90.19326 -439.829674) (xy 90.17019 -439.837159) (xy 90.158062 -439.837576)
			(xy 89.218262 -439.837576) (xy 89.206147 -439.837121) (xy 89.183105 -439.829625) (xy 89.163505 -439.815378)
			(xy 89.149264 -439.795774) (xy 89.141775 -439.772729) (xy 89.1413 -439.760614) (xy 89.1413 -439.251344)
			(xy 89.141249 -439.247738) (xy 89.140221 -439.240599) (xy 89.139268 -439.23712) (xy 89.129525 -439.201072)
			(xy 89.119072 -439.127136) (xy 89.11844 -439.0898) (xy 86.235032 -439.0898) (xy 86.235032 -439.760614)
			(xy 86.234651 -439.77274) (xy 86.227152 -439.795805) (xy 86.212891 -439.815422) (xy 86.193265 -439.829672)
			(xy 86.170197 -439.837158) (xy 86.15807 -439.837576) (xy 85.21827 -439.837576) (xy 85.206155 -439.837114)
			(xy 85.183113 -439.82962) (xy 85.163513 -439.815375) (xy 85.149272 -439.795772) (xy 85.141783 -439.772729)
			(xy 85.141308 -439.760614) (xy 85.141308 -439.251344) (xy 85.141256 -439.247738) (xy 85.140229 -439.240599)
			(xy 85.139276 -439.23712) (xy 85.129533 -439.201072) (xy 85.11908 -439.127136) (xy 85.118448 -439.0898)
			(xy 82.23504 -439.0898) (xy 82.23504 -439.760614) (xy 82.234651 -439.77274) (xy 82.227153 -439.795803)
			(xy 82.212894 -439.815419) (xy 82.19327 -439.829669) (xy 82.170204 -439.837157) (xy 82.158078 -439.837576)
			(xy 81.218278 -439.837576) (xy 81.206164 -439.837107) (xy 81.183122 -439.829616) (xy 81.163522 -439.815372)
			(xy 81.149281 -439.795771) (xy 81.141791 -439.772728) (xy 81.141316 -439.760614) (xy 81.141316 -439.251344)
			(xy 81.141264 -439.247738) (xy 81.140237 -439.240599) (xy 81.139284 -439.23712) (xy 81.129541 -439.201072)
			(xy 81.119088 -439.127136) (xy 81.118456 -439.0898) (xy 78.235048 -439.0898) (xy 78.235048 -439.760614)
			(xy 78.2346 -439.772731) (xy 78.227107 -439.795777) (xy 78.21286 -439.81538) (xy 78.193252 -439.82962)
			(xy 78.170203 -439.837105) (xy 78.158086 -439.837576) (xy 77.218286 -439.837576) (xy 77.206172 -439.837101)
			(xy 77.183131 -439.829611) (xy 77.16353 -439.81537) (xy 77.149289 -439.795769) (xy 77.141799 -439.772728)
			(xy 77.141324 -439.760614) (xy 77.141324 -439.251344) (xy 77.141272 -439.247738) (xy 77.140245 -439.240599)
			(xy 77.139292 -439.23712) (xy 77.12955 -439.201072) (xy 77.119097 -439.127136) (xy 77.118464 -439.0898)
			(xy 73.234804 -439.0898) (xy 73.234804 -439.760614) (xy 73.234301 -439.772725) (xy 73.226815 -439.795762)
			(xy 73.21258 -439.81536) (xy 73.192987 -439.829602) (xy 73.169953 -439.837097) (xy 73.157842 -439.837576)
			(xy 72.218042 -439.837576) (xy 72.205923 -439.837105) (xy 72.182868 -439.829626) (xy 72.163253 -439.815387)
			(xy 72.149 -439.795783) (xy 72.141504 -439.772733) (xy 72.14108 -439.760614) (xy 72.14108 -439.251344)
			(xy 72.141026 -439.247738) (xy 72.14 -439.240599) (xy 72.139048 -439.23712) (xy 72.129304 -439.201072)
			(xy 72.118852 -439.127136) (xy 72.11822 -439.0898) (xy 69.234812 -439.0898) (xy 69.234812 -439.760614)
			(xy 69.234301 -439.772724) (xy 69.226816 -439.79576) (xy 69.212582 -439.815357) (xy 69.192992 -439.8296)
			(xy 69.16996 -439.837096) (xy 69.15785 -439.837576) (xy 68.21805 -439.837576) (xy 68.205934 -439.837131)
			(xy 68.182892 -439.829632) (xy 68.163292 -439.815382) (xy 68.149052 -439.795776) (xy 68.141563 -439.77273)
			(xy 68.141088 -439.760614) (xy 68.141088 -439.251344) (xy 68.141033 -439.247738) (xy 68.140007 -439.240599)
			(xy 68.139056 -439.23712) (xy 68.129313 -439.201072) (xy 68.11886 -439.127136) (xy 68.118228 -439.0898)
			(xy 65.23482 -439.0898) (xy 65.23482 -439.760614) (xy 65.234451 -439.772742) (xy 65.22695 -439.795808)
			(xy 65.212686 -439.815426) (xy 65.193058 -439.829675) (xy 65.169986 -439.83716) (xy 65.157858 -439.837576)
			(xy 64.218058 -439.837576) (xy 64.205943 -439.837124) (xy 64.1829 -439.829627) (xy 64.163301 -439.815379)
			(xy 64.14906 -439.795774) (xy 64.141571 -439.77273) (xy 64.141096 -439.760614) (xy 64.141096 -439.251344)
			(xy 64.141045 -439.247738) (xy 64.140017 -439.240599) (xy 64.139064 -439.23712) (xy 64.129321 -439.201072)
			(xy 64.118868 -439.127136) (xy 64.118236 -439.0898) (xy 61.234828 -439.0898) (xy 61.234828 -439.760614)
			(xy 61.234451 -439.772741) (xy 61.226951 -439.795806) (xy 61.212689 -439.815424) (xy 61.193063 -439.829673)
			(xy 61.169993 -439.837159) (xy 61.157866 -439.837576) (xy 60.218066 -439.837576) (xy 60.205951 -439.837118)
			(xy 60.182909 -439.829623) (xy 60.163309 -439.815377) (xy 60.149068 -439.795773) (xy 60.141579 -439.772729)
			(xy 60.141104 -439.760614) (xy 60.141104 -439.251344) (xy 60.141053 -439.247738) (xy 60.140025 -439.240599)
			(xy 60.139072 -439.23712) (xy 60.129329 -439.201072) (xy 60.118876 -439.127136) (xy 60.118244 -439.0898)
			(xy 7.00913 -439.0898) (xy 7.00913 -439.989976) (xy 7.009638 -440.045746) (xy 7.017973 -440.156973)
			(xy 7.034597 -440.267266) (xy 7.059417 -440.376009) (xy 7.092293 -440.482593) (xy 7.133043 -440.586422)
			(xy 7.181438 -440.686915) (xy 7.237207 -440.783511) (xy 7.300039 -440.87567) (xy 7.369583 -440.962874)
			(xy 7.445449 -441.044639) (xy 7.527212 -441.120505) (xy 7.614417 -441.190048) (xy 7.706575 -441.252881)
			(xy 7.803171 -441.30865) (xy 7.903664 -441.357045) (xy 8.007493 -441.397795) (xy 8.114077 -441.430672)
			(xy 8.22282 -441.455492) (xy 8.333113 -441.472116) (xy 8.44434 -441.480451) (xy 8.50011 -441.480956)
		)
		(stroke
			(width 0)
			(type solid)
		)
		(fill yes)
		(layer "In16.Cu")
		(net "GND")
	)
	(gr_arc
		(start 0.508 -77.67193)
		(mid 0.621601 -78.242658)
		(end 0.94488 -78.726538)
		(stroke
			(width 0.2)
			(type default)
		)
		(layer "In16.Cu")
	)
	(gr_line
		(start 0.508 -13.780008)
		(end 0.508 -77.67193)
		(stroke
			(width 0.2)
			(type default)
		)
		(layer "In16.Cu")
	)
	(gr_line
		(start 0.94488 -78.726538)
		(end 1.773428 -79.555086)
		(stroke
			(width 0.2)
			(type default)
		)
		(layer "In16.Cu")
	)
	(gr_line
		(start 1.414272 -79.914242)
		(end 0.585724 -79.085694)
		(stroke
			(width 1.016)
			(type default)
		)
		(layer "In16.Cu")
	)
	(gr_line
		(start 1.999996 -403.371558)
		(end 1.999996 -81.328514)
		(stroke
			(width 1.016)
			(type default)
		)
		(layer "In16.Cu")
	)
	(gr_arc
		(start 1.999996 -403.371558)
		(mid 2.152159 -404.136965)
		(end 2.58572 -404.78583)
		(stroke
			(width 1.016)
			(type default)
		)
		(layer "In16.Cu")
	)
	(gr_arc
		(start 1.999996 -81.328514)
		(mid 1.847755 -80.563149)
		(end 1.414272 -79.914242)
		(stroke
			(width 1.016)
			(type default)
		)
		(layer "In16.Cu")
	)
	(gr_arc
		(start 1.999996 -12.288012)
		(mid 0.944996 -12.725008)
		(end 0.508 -13.780008)
		(stroke
			(width 0.2)
			(type default)
		)
		(layer "In16.Cu")
	)
	(gr_arc
		(start 1.999996 -11.780012)
		(mid 0.585785 -12.365797)
		(end 0 -13.780008)
		(stroke
			(width 1.016)
			(type default)
		)
		(layer "In16.Cu")
	)
	(gr_line
		(start 1.999996 -11.780012)
		(end 11.102086 -11.780012)
		(stroke
			(width 1.016)
			(type default)
		)
		(layer "In16.Cu")
	)
	(gr_arc
		(start 2.507996 -403.371812)
		(mid 2.621533 -403.942691)
		(end 2.944876 -404.426674)
		(stroke
			(width 0.2)
			(type default)
		)
		(layer "In16.Cu")
	)
	(gr_arc
		(start 2.507996 -81.32826)
		(mid 2.317045 -80.368624)
		(end 1.773428 -79.555086)
		(stroke
			(width 0.2)
			(type default)
		)
		(layer "In16.Cu")
	)
	(gr_line
		(start 2.507996 -81.32826)
		(end 2.507996 -403.371812)
		(stroke
			(width 0.2)
			(type default)
		)
		(layer "In16.Cu")
	)
	(gr_line
		(start 2.944876 -404.426674)
		(end 6.273292 -407.75509)
		(stroke
			(width 0.2)
			(type default)
		)
		(layer "In16.Cu")
	)
	(gr_line
		(start 5.914136 -408.114246)
		(end 2.58572 -404.78583)
		(stroke
			(width 1.016)
			(type default)
		)
		(layer "In16.Cu")
	)
	(gr_line
		(start 6.500114 -439.989976)
		(end 6.500114 -409.528518)
		(stroke
			(width 1.016)
			(type default)
		)
		(layer "In16.Cu")
	)
	(gr_arc
		(start 6.500114 -439.989976)
		(mid 7.085891 -441.404199)
		(end 8.50011 -441.989972)
		(stroke
			(width 1.016)
			(type default)
		)
		(layer "In16.Cu")
	)
	(gr_arc
		(start 6.500114 -409.528518)
		(mid 6.347771 -408.763109)
		(end 5.914136 -408.114246)
		(stroke
			(width 1.016)
			(type default)
		)
		(layer "In16.Cu")
	)
	(gr_arc
		(start 7.008114 -439.989976)
		(mid 7.44511 -441.044976)
		(end 8.50011 -441.481972)
		(stroke
			(width 0.2)
			(type default)
		)
		(layer "In16.Cu")
	)
	(gr_arc
		(start 7.008114 -409.528518)
		(mid 6.817049 -408.568734)
		(end 6.273292 -407.75509)
		(stroke
			(width 0.2)
			(type default)
		)
		(layer "In16.Cu")
	)
	(gr_line
		(start 7.008114 -409.528518)
		(end 7.008114 -439.989976)
		(stroke
			(width 0.2)
			(type default)
		)
		(layer "In16.Cu")
	)
	(gr_line
		(start 8.50011 -441.481972)
		(end 194.496944 -441.481972)
		(stroke
			(width 0.2)
			(type default)
		)
		(layer "In16.Cu")
	)
	(gr_line
		(start 11.102086 -12.288012)
		(end 1.999996 -12.288012)
		(stroke
			(width 0.2)
			(type default)
		)
		(layer "In16.Cu")
	)
	(gr_arc
		(start 11.102086 -12.288012)
		(mid 12.875508 -11.553438)
		(end 13.610082 -9.780016)
		(stroke
			(width 0.2)
			(type default)
		)
		(layer "In16.Cu")
	)
	(gr_arc
		(start 11.102086 -11.780012)
		(mid 12.516297 -11.194227)
		(end 13.102082 -9.780016)
		(stroke
			(width 1.016)
			(type default)
		)
		(layer "In16.Cu")
	)
	(gr_line
		(start 13.102082 -9.780016)
		(end 13.102082 -0.500126)
		(stroke
			(width 1.016)
			(type default)
		)
		(layer "In16.Cu")
	)
	(gr_arc
		(start 13.601954 0)
		(mid 13.24848 -0.146572)
		(end 13.102082 -0.500126)
		(stroke
			(width 1.016)
			(type default)
		)
		(layer "In16.Cu")
	)
	(gr_line
		(start 13.601954 0)
		(end 81.202022 0)
		(stroke
			(width 1.016)
			(type default)
		)
		(layer "In16.Cu")
	)
	(gr_line
		(start 13.610082 -0.508)
		(end 13.610082 -9.780016)
		(stroke
			(width 0.2)
			(type default)
		)
		(layer "In16.Cu")
	)
	(gr_circle
		(center 25.82545 -40.816276)
		(end 26.71445 -40.816276)
		(stroke
			(width 0.2)
			(type default)
		)
		(fill no)
		(layer "In16.Cu")
	)
	(gr_circle
		(center 29.291534 -348.709488)
		(end 30.171644 -348.709488)
		(stroke
			(width 0.2)
			(type default)
		)
		(fill no)
		(layer "In16.Cu")
	)
	(gr_circle
		(center 29.908754 -348.709488)
		(end 30.788864 -348.709488)
		(stroke
			(width 0.2)
			(type default)
		)
		(fill no)
		(layer "In16.Cu")
	)
	(gr_circle
		(center 30.525974 -348.709488)
		(end 31.406084 -348.709488)
		(stroke
			(width 0.2)
			(type default)
		)
		(fill no)
		(layer "In16.Cu")
	)
	(gr_circle
		(center 30.795214 -347.966538)
		(end 31.684214 -347.966538)
		(stroke
			(width 0.2)
			(type default)
		)
		(fill no)
		(layer "In16.Cu")
	)
	(gr_circle
		(center 30.795214 -347.229938)
		(end 31.684214 -347.229938)
		(stroke
			(width 0.2)
			(type default)
		)
		(fill no)
		(layer "In16.Cu")
	)
	(gr_circle
		(center 31.22803 -350.318578)
		(end 32.11703 -350.318578)
		(stroke
			(width 0.2)
			(type default)
		)
		(fill no)
		(layer "In16.Cu")
	)
	(gr_circle
		(center 31.22803 -349.581978)
		(end 32.11703 -349.581978)
		(stroke
			(width 0.2)
			(type default)
		)
		(fill no)
		(layer "In16.Cu")
	)
	(gr_circle
		(center 31.752794 -349.142558)
		(end 32.641794 -349.142558)
		(stroke
			(width 0.2)
			(type default)
		)
		(fill no)
		(layer "In16.Cu")
	)
	(gr_circle
		(center 31.778194 -349.904558)
		(end 32.667194 -349.904558)
		(stroke
			(width 0.2)
			(type default)
		)
		(fill no)
		(layer "In16.Cu")
	)
	(gr_circle
		(center 32.311594 -350.260158)
		(end 33.200594 -350.260158)
		(stroke
			(width 0.2)
			(type default)
		)
		(fill no)
		(layer "In16.Cu")
	)
	(gr_circle
		(center 32.311594 -349.523558)
		(end 33.200594 -349.523558)
		(stroke
			(width 0.2)
			(type default)
		)
		(fill no)
		(layer "In16.Cu")
	)
	(gr_circle
		(center 32.311594 -348.786958)
		(end 33.200594 -348.786958)
		(stroke
			(width 0.2)
			(type default)
		)
		(fill no)
		(layer "In16.Cu")
	)
	(gr_circle
		(center 37.571934 -348.709488)
		(end 38.452044 -348.709488)
		(stroke
			(width 0.2)
			(type default)
		)
		(fill no)
		(layer "In16.Cu")
	)
	(gr_circle
		(center 38.189154 -348.709488)
		(end 39.069264 -348.709488)
		(stroke
			(width 0.2)
			(type default)
		)
		(fill no)
		(layer "In16.Cu")
	)
	(gr_circle
		(center 38.806374 -348.709488)
		(end 39.686484 -348.709488)
		(stroke
			(width 0.2)
			(type default)
		)
		(fill no)
		(layer "In16.Cu")
	)
	(gr_circle
		(center 39.050214 -347.974158)
		(end 39.939214 -347.974158)
		(stroke
			(width 0.2)
			(type default)
		)
		(fill no)
		(layer "In16.Cu")
	)
	(gr_circle
		(center 39.050214 -347.237558)
		(end 39.939214 -347.237558)
		(stroke
			(width 0.2)
			(type default)
		)
		(fill no)
		(layer "In16.Cu")
	)
	(gr_circle
		(center 39.50843 -350.318578)
		(end 40.39743 -350.318578)
		(stroke
			(width 0.2)
			(type default)
		)
		(fill no)
		(layer "In16.Cu")
	)
	(gr_circle
		(center 39.50843 -349.581978)
		(end 40.39743 -349.581978)
		(stroke
			(width 0.2)
			(type default)
		)
		(fill no)
		(layer "In16.Cu")
	)
	(gr_circle
		(center 40.033194 -349.142558)
		(end 40.922194 -349.142558)
		(stroke
			(width 0.2)
			(type default)
		)
		(fill no)
		(layer "In16.Cu")
	)
	(gr_circle
		(center 40.058594 -349.904558)
		(end 40.947594 -349.904558)
		(stroke
			(width 0.2)
			(type default)
		)
		(fill no)
		(layer "In16.Cu")
	)
	(gr_circle
		(center 40.591994 -350.260158)
		(end 41.480994 -350.260158)
		(stroke
			(width 0.2)
			(type default)
		)
		(fill no)
		(layer "In16.Cu")
	)
	(gr_circle
		(center 40.591994 -349.523558)
		(end 41.480994 -349.523558)
		(stroke
			(width 0.2)
			(type default)
		)
		(fill no)
		(layer "In16.Cu")
	)
	(gr_circle
		(center 40.591994 -348.786958)
		(end 41.480994 -348.786958)
		(stroke
			(width 0.2)
			(type default)
		)
		(fill no)
		(layer "In16.Cu")
	)
	(gr_circle
		(center 41.369742 -358.549194)
		(end 42.258742 -358.549194)
		(stroke
			(width 0.2)
			(type default)
		)
		(fill no)
		(layer "In16.Cu")
	)
	(gr_circle
		(center 41.417494 -357.898192)
		(end 42.306494 -357.898192)
		(stroke
			(width 0.2)
			(type default)
		)
		(fill no)
		(layer "In16.Cu")
	)
	(gr_circle
		(center 41.417494 -357.263192)
		(end 42.306494 -357.263192)
		(stroke
			(width 0.2)
			(type default)
		)
		(fill no)
		(layer "In16.Cu")
	)
	(gr_circle
		(center 41.427146 -359.2576)
		(end 42.316146 -359.2576)
		(stroke
			(width 0.2)
			(type default)
		)
		(fill no)
		(layer "In16.Cu")
	)
	(gr_circle
		(center 43.935904 -358.51084)
		(end 44.824904 -358.51084)
		(stroke
			(width 0.2)
			(type default)
		)
		(fill no)
		(layer "In16.Cu")
	)
	(gr_circle
		(center 43.983656 -357.859838)
		(end 44.872656 -357.859838)
		(stroke
			(width 0.2)
			(type default)
		)
		(fill no)
		(layer "In16.Cu")
	)
	(gr_circle
		(center 43.983656 -357.224838)
		(end 44.872656 -357.224838)
		(stroke
			(width 0.2)
			(type default)
		)
		(fill no)
		(layer "In16.Cu")
	)
	(gr_circle
		(center 43.993308 -359.219246)
		(end 44.882308 -359.219246)
		(stroke
			(width 0.2)
			(type default)
		)
		(fill no)
		(layer "In16.Cu")
	)
	(gr_circle
		(center 45.877734 -348.709488)
		(end 46.757844 -348.709488)
		(stroke
			(width 0.2)
			(type default)
		)
		(fill no)
		(layer "In16.Cu")
	)
	(gr_circle
		(center 46.494954 -348.709488)
		(end 47.375064 -348.709488)
		(stroke
			(width 0.2)
			(type default)
		)
		(fill no)
		(layer "In16.Cu")
	)
	(gr_circle
		(center 47.112174 -348.709488)
		(end 47.992284 -348.709488)
		(stroke
			(width 0.2)
			(type default)
		)
		(fill no)
		(layer "In16.Cu")
	)
	(gr_circle
		(center 47.366174 -348.017338)
		(end 48.255174 -348.017338)
		(stroke
			(width 0.2)
			(type default)
		)
		(fill no)
		(layer "In16.Cu")
	)
	(gr_circle
		(center 47.366174 -347.280738)
		(end 48.255174 -347.280738)
		(stroke
			(width 0.2)
			(type default)
		)
		(fill no)
		(layer "In16.Cu")
	)
	(gr_circle
		(center 47.81423 -350.318578)
		(end 48.70323 -350.318578)
		(stroke
			(width 0.2)
			(type default)
		)
		(fill no)
		(layer "In16.Cu")
	)
	(gr_circle
		(center 47.81423 -349.581978)
		(end 48.70323 -349.581978)
		(stroke
			(width 0.2)
			(type default)
		)
		(fill no)
		(layer "In16.Cu")
	)
	(gr_circle
		(center 47.880778 -358.108504)
		(end 48.769778 -358.108504)
		(stroke
			(width 0.2)
			(type default)
		)
		(fill no)
		(layer "In16.Cu")
	)
	(gr_circle
		(center 47.92853 -357.457502)
		(end 48.81753 -357.457502)
		(stroke
			(width 0.2)
			(type default)
		)
		(fill no)
		(layer "In16.Cu")
	)
	(gr_circle
		(center 47.92853 -356.822502)
		(end 48.81753 -356.822502)
		(stroke
			(width 0.2)
			(type default)
		)
		(fill no)
		(layer "In16.Cu")
	)
	(gr_circle
		(center 48.338994 -349.142558)
		(end 49.227994 -349.142558)
		(stroke
			(width 0.2)
			(type default)
		)
		(fill no)
		(layer "In16.Cu")
	)
	(gr_circle
		(center 48.364394 -349.904558)
		(end 49.253394 -349.904558)
		(stroke
			(width 0.2)
			(type default)
		)
		(fill no)
		(layer "In16.Cu")
	)
	(gr_circle
		(center 48.718978 -358.108504)
		(end 49.607978 -358.108504)
		(stroke
			(width 0.2)
			(type default)
		)
		(fill no)
		(layer "In16.Cu")
	)
	(gr_circle
		(center 48.76673 -357.457502)
		(end 49.65573 -357.457502)
		(stroke
			(width 0.2)
			(type default)
		)
		(fill no)
		(layer "In16.Cu")
	)
	(gr_circle
		(center 48.76673 -356.822502)
		(end 49.65573 -356.822502)
		(stroke
			(width 0.2)
			(type default)
		)
		(fill no)
		(layer "In16.Cu")
	)
	(gr_circle
		(center 48.897794 -350.260158)
		(end 49.786794 -350.260158)
		(stroke
			(width 0.2)
			(type default)
		)
		(fill no)
		(layer "In16.Cu")
	)
	(gr_circle
		(center 48.897794 -349.523558)
		(end 49.786794 -349.523558)
		(stroke
			(width 0.2)
			(type default)
		)
		(fill no)
		(layer "In16.Cu")
	)
	(gr_circle
		(center 48.897794 -348.786958)
		(end 49.786794 -348.786958)
		(stroke
			(width 0.2)
			(type default)
		)
		(fill no)
		(layer "In16.Cu")
	)
	(gr_circle
		(center 49.353978 -358.108504)
		(end 50.242978 -358.108504)
		(stroke
			(width 0.2)
			(type default)
		)
		(fill no)
		(layer "In16.Cu")
	)
	(gr_circle
		(center 49.40173 -357.457502)
		(end 50.29073 -357.457502)
		(stroke
			(width 0.2)
			(type default)
		)
		(fill no)
		(layer "In16.Cu")
	)
	(gr_circle
		(center 49.40173 -356.822502)
		(end 50.29073 -356.822502)
		(stroke
			(width 0.2)
			(type default)
		)
		(fill no)
		(layer "In16.Cu")
	)
	(gr_circle
		(center 49.988978 -358.108504)
		(end 50.877978 -358.108504)
		(stroke
			(width 0.2)
			(type default)
		)
		(fill no)
		(layer "In16.Cu")
	)
	(gr_circle
		(center 50.03673 -357.457502)
		(end 50.92573 -357.457502)
		(stroke
			(width 0.2)
			(type default)
		)
		(fill no)
		(layer "In16.Cu")
	)
	(gr_circle
		(center 50.03673 -356.822502)
		(end 50.92573 -356.822502)
		(stroke
			(width 0.2)
			(type default)
		)
		(fill no)
		(layer "In16.Cu")
	)
	(gr_circle
		(center 50.623978 -358.108504)
		(end 51.512978 -358.108504)
		(stroke
			(width 0.2)
			(type default)
		)
		(fill no)
		(layer "In16.Cu")
	)
	(gr_circle
		(center 50.67173 -357.457502)
		(end 51.56073 -357.457502)
		(stroke
			(width 0.2)
			(type default)
		)
		(fill no)
		(layer "In16.Cu")
	)
	(gr_circle
		(center 50.67173 -356.822502)
		(end 51.56073 -356.822502)
		(stroke
			(width 0.2)
			(type default)
		)
		(fill no)
		(layer "In16.Cu")
	)
	(gr_circle
		(center 54.234334 -348.709488)
		(end 55.114444 -348.709488)
		(stroke
			(width 0.2)
			(type default)
		)
		(fill no)
		(layer "In16.Cu")
	)
	(gr_circle
		(center 54.851554 -348.709488)
		(end 55.731664 -348.709488)
		(stroke
			(width 0.2)
			(type default)
		)
		(fill no)
		(layer "In16.Cu")
	)
	(gr_circle
		(center 55.468774 -348.709488)
		(end 56.348884 -348.709488)
		(stroke
			(width 0.2)
			(type default)
		)
		(fill no)
		(layer "In16.Cu")
	)
	(gr_circle
		(center 55.727854 -347.997018)
		(end 56.616854 -347.997018)
		(stroke
			(width 0.2)
			(type default)
		)
		(fill no)
		(layer "In16.Cu")
	)
	(gr_circle
		(center 55.727854 -347.260418)
		(end 56.616854 -347.260418)
		(stroke
			(width 0.2)
			(type default)
		)
		(fill no)
		(layer "In16.Cu")
	)
	(gr_circle
		(center 56.17083 -350.318578)
		(end 57.05983 -350.318578)
		(stroke
			(width 0.2)
			(type default)
		)
		(fill no)
		(layer "In16.Cu")
	)
	(gr_circle
		(center 56.17083 -349.581978)
		(end 57.05983 -349.581978)
		(stroke
			(width 0.2)
			(type default)
		)
		(fill no)
		(layer "In16.Cu")
	)
	(gr_circle
		(center 56.695594 -349.142558)
		(end 57.584594 -349.142558)
		(stroke
			(width 0.2)
			(type default)
		)
		(fill no)
		(layer "In16.Cu")
	)
	(gr_circle
		(center 56.720994 -349.904558)
		(end 57.609994 -349.904558)
		(stroke
			(width 0.2)
			(type default)
		)
		(fill no)
		(layer "In16.Cu")
	)
	(gr_circle
		(center 57.254394 -350.260158)
		(end 58.143394 -350.260158)
		(stroke
			(width 0.2)
			(type default)
		)
		(fill no)
		(layer "In16.Cu")
	)
	(gr_circle
		(center 57.254394 -349.523558)
		(end 58.143394 -349.523558)
		(stroke
			(width 0.2)
			(type default)
		)
		(fill no)
		(layer "In16.Cu")
	)
	(gr_circle
		(center 57.254394 -348.786958)
		(end 58.143394 -348.786958)
		(stroke
			(width 0.2)
			(type default)
		)
		(fill no)
		(layer "In16.Cu")
	)
	(gr_circle
		(center 61.93663 -166.86276)
		(end 62.82563 -166.86276)
		(stroke
			(width 0.2)
			(type default)
		)
		(fill no)
		(layer "In16.Cu")
	)
	(gr_circle
		(center 61.93663 -166.12616)
		(end 62.82563 -166.12616)
		(stroke
			(width 0.2)
			(type default)
		)
		(fill no)
		(layer "In16.Cu")
	)
	(gr_circle
		(center 61.93663 -165.38956)
		(end 62.82563 -165.38956)
		(stroke
			(width 0.2)
			(type default)
		)
		(fill no)
		(layer "In16.Cu")
	)
	(gr_circle
		(center 62.47003 -165.74516)
		(end 63.35903 -165.74516)
		(stroke
			(width 0.2)
			(type default)
		)
		(fill no)
		(layer "In16.Cu")
	)
	(gr_circle
		(center 62.49543 -166.50716)
		(end 63.38443 -166.50716)
		(stroke
			(width 0.2)
			(type default)
		)
		(fill no)
		(layer "In16.Cu")
	)
	(gr_circle
		(center 62.565534 -348.709488)
		(end 63.445644 -348.709488)
		(stroke
			(width 0.2)
			(type default)
		)
		(fill no)
		(layer "In16.Cu")
	)
	(gr_circle
		(center 63.020194 -166.06774)
		(end 63.909194 -166.06774)
		(stroke
			(width 0.2)
			(type default)
		)
		(fill no)
		(layer "In16.Cu")
	)
	(gr_circle
		(center 63.020194 -165.33114)
		(end 63.909194 -165.33114)
		(stroke
			(width 0.2)
			(type default)
		)
		(fill no)
		(layer "In16.Cu")
	)
	(gr_circle
		(center 63.182754 -348.709488)
		(end 64.062864 -348.709488)
		(stroke
			(width 0.2)
			(type default)
		)
		(fill no)
		(layer "In16.Cu")
	)
	(gr_circle
		(center 63.199264 -12.43711)
		(end 64.088264 -12.43711)
		(stroke
			(width 0.2)
			(type default)
		)
		(fill no)
		(layer "In16.Cu")
	)
	(gr_circle
		(center 63.579248 -168.42232)
		(end 64.468248 -168.42232)
		(stroke
			(width 0.2)
			(type default)
		)
		(fill no)
		(layer "In16.Cu")
	)
	(gr_circle
		(center 63.579248 -167.68572)
		(end 64.468248 -167.68572)
		(stroke
			(width 0.2)
			(type default)
		)
		(fill no)
		(layer "In16.Cu")
	)
	(gr_circle
		(center 63.631064 -13.09751)
		(end 64.520064 -13.09751)
		(stroke
			(width 0.2)
			(type default)
		)
		(fill no)
		(layer "In16.Cu")
	)
	(gr_circle
		(center 63.72225 -166.94023)
		(end 64.60236 -166.94023)
		(stroke
			(width 0.2)
			(type default)
		)
		(fill no)
		(layer "In16.Cu")
	)
	(gr_circle
		(center 63.799974 -348.709488)
		(end 64.680084 -348.709488)
		(stroke
			(width 0.2)
			(type default)
		)
		(fill no)
		(layer "In16.Cu")
	)
	(gr_circle
		(center 64.061594 -348.038928)
		(end 64.941704 -348.038928)
		(stroke
			(width 0.2)
			(type default)
		)
		(fill no)
		(layer "In16.Cu")
	)
	(gr_circle
		(center 64.061594 -347.302328)
		(end 64.941704 -347.302328)
		(stroke
			(width 0.2)
			(type default)
		)
		(fill no)
		(layer "In16.Cu")
	)
	(gr_circle
		(center 64.088264 -12.43711)
		(end 64.977264 -12.43711)
		(stroke
			(width 0.2)
			(type default)
		)
		(fill no)
		(layer "In16.Cu")
	)
	(gr_circle
		(center 64.33947 -166.94023)
		(end 65.21958 -166.94023)
		(stroke
			(width 0.2)
			(type default)
		)
		(fill no)
		(layer "In16.Cu")
	)
	(gr_circle
		(center 64.50203 -350.318578)
		(end 65.39103 -350.318578)
		(stroke
			(width 0.2)
			(type default)
		)
		(fill no)
		(layer "In16.Cu")
	)
	(gr_circle
		(center 64.50203 -349.581978)
		(end 65.39103 -349.581978)
		(stroke
			(width 0.2)
			(type default)
		)
		(fill no)
		(layer "In16.Cu")
	)
	(gr_circle
		(center 64.520064 -13.09751)
		(end 65.409064 -13.09751)
		(stroke
			(width 0.2)
			(type default)
		)
		(fill no)
		(layer "In16.Cu")
	)
	(gr_circle
		(center 64.95669 -166.94023)
		(end 65.8368 -166.94023)
		(stroke
			(width 0.2)
			(type default)
		)
		(fill no)
		(layer "In16.Cu")
	)
	(gr_circle
		(center 64.977264 -12.43711)
		(end 65.866264 -12.43711)
		(stroke
			(width 0.2)
			(type default)
		)
		(fill no)
		(layer "In16.Cu")
	)
	(gr_circle
		(center 65.026794 -349.142558)
		(end 65.915794 -349.142558)
		(stroke
			(width 0.2)
			(type default)
		)
		(fill no)
		(layer "In16.Cu")
	)
	(gr_circle
		(center 65.052194 -349.904558)
		(end 65.941194 -349.904558)
		(stroke
			(width 0.2)
			(type default)
		)
		(fill no)
		(layer "In16.Cu")
	)
	(gr_circle
		(center 65.409064 -13.09751)
		(end 66.298064 -13.09751)
		(stroke
			(width 0.2)
			(type default)
		)
		(fill no)
		(layer "In16.Cu")
	)
	(gr_circle
		(center 65.585594 -350.260158)
		(end 66.474594 -350.260158)
		(stroke
			(width 0.2)
			(type default)
		)
		(fill no)
		(layer "In16.Cu")
	)
	(gr_circle
		(center 65.585594 -349.523558)
		(end 66.474594 -349.523558)
		(stroke
			(width 0.2)
			(type default)
		)
		(fill no)
		(layer "In16.Cu")
	)
	(gr_circle
		(center 65.585594 -348.786958)
		(end 66.474594 -348.786958)
		(stroke
			(width 0.2)
			(type default)
		)
		(fill no)
		(layer "In16.Cu")
	)
	(gr_circle
		(center 65.866264 -12.43711)
		(end 66.755264 -12.43711)
		(stroke
			(width 0.2)
			(type default)
		)
		(fill no)
		(layer "In16.Cu")
	)
	(gr_circle
		(center 66.298064 -13.09751)
		(end 67.187064 -13.09751)
		(stroke
			(width 0.2)
			(type default)
		)
		(fill no)
		(layer "In16.Cu")
	)
	(gr_circle
		(center 66.399664 -25.56891)
		(end 67.288664 -25.56891)
		(stroke
			(width 0.2)
			(type default)
		)
		(fill no)
		(layer "In16.Cu")
	)
	(gr_circle
		(center 66.501264 -12.43711)
		(end 67.390264 -12.43711)
		(stroke
			(width 0.2)
			(type default)
		)
		(fill no)
		(layer "In16.Cu")
	)
	(gr_circle
		(center 66.774822 -20.327366)
		(end 67.663822 -20.327366)
		(stroke
			(width 0.2)
			(type default)
		)
		(fill no)
		(layer "In16.Cu")
	)
	(gr_circle
		(center 66.774822 -19.692366)
		(end 67.663822 -19.692366)
		(stroke
			(width 0.2)
			(type default)
		)
		(fill no)
		(layer "In16.Cu")
	)
	(gr_circle
		(center 66.780664 -24.88311)
		(end 67.669664 -24.88311)
		(stroke
			(width 0.2)
			(type default)
		)
		(fill no)
		(layer "In16.Cu")
	)
	(gr_circle
		(center 66.848228 -18.642584)
		(end 67.737228 -18.642584)
		(stroke
			(width 0.2)
			(type default)
		)
		(fill no)
		(layer "In16.Cu")
	)
	(gr_circle
		(center 66.882264 -22.26691)
		(end 67.771264 -22.26691)
		(stroke
			(width 0.2)
			(type default)
		)
		(fill no)
		(layer "In16.Cu")
	)
	(gr_circle
		(center 66.933064 -13.09751)
		(end 67.822064 -13.09751)
		(stroke
			(width 0.2)
			(type default)
		)
		(fill no)
		(layer "In16.Cu")
	)
	(gr_circle
		(center 67.288664 -25.56891)
		(end 68.177664 -25.56891)
		(stroke
			(width 0.2)
			(type default)
		)
		(fill no)
		(layer "In16.Cu")
	)
	(gr_circle
		(center 67.40271 -12.489434)
		(end 68.29171 -12.489434)
		(stroke
			(width 0.2)
			(type default)
		)
		(fill no)
		(layer "In16.Cu")
	)
	(gr_circle
		(center 67.669664 -24.88311)
		(end 68.558664 -24.88311)
		(stroke
			(width 0.2)
			(type default)
		)
		(fill no)
		(layer "In16.Cu")
	)
	(gr_circle
		(center 68.177664 -25.56891)
		(end 69.066664 -25.56891)
		(stroke
			(width 0.2)
			(type default)
		)
		(fill no)
		(layer "In16.Cu")
	)
	(gr_circle
		(center 68.54444 -18.476214)
		(end 69.43344 -18.476214)
		(stroke
			(width 0.2)
			(type default)
		)
		(fill no)
		(layer "In16.Cu")
	)
	(gr_circle
		(center 68.558664 -24.88311)
		(end 69.447664 -24.88311)
		(stroke
			(width 0.2)
			(type default)
		)
		(fill no)
		(layer "In16.Cu")
	)
	(gr_circle
		(center 69.498464 -24.55291)
		(end 70.387464 -24.55291)
		(stroke
			(width 0.2)
			(type default)
		)
		(fill no)
		(layer "In16.Cu")
	)
	(gr_circle
		(center 70.25005 -175.559974)
		(end 71.13905 -175.559974)
		(stroke
			(width 0.2)
			(type default)
		)
		(fill no)
		(layer "In16.Cu")
	)
	(gr_circle
		(center 70.25005 -174.823374)
		(end 71.13905 -174.823374)
		(stroke
			(width 0.2)
			(type default)
		)
		(fill no)
		(layer "In16.Cu")
	)
	(gr_circle
		(center 70.25005 -174.086774)
		(end 71.13905 -174.086774)
		(stroke
			(width 0.2)
			(type default)
		)
		(fill no)
		(layer "In16.Cu")
	)
	(gr_circle
		(center 70.78345 -174.442374)
		(end 71.67245 -174.442374)
		(stroke
			(width 0.2)
			(type default)
		)
		(fill no)
		(layer "In16.Cu")
	)
	(gr_circle
		(center 70.80885 -175.204374)
		(end 71.69785 -175.204374)
		(stroke
			(width 0.2)
			(type default)
		)
		(fill no)
		(layer "In16.Cu")
	)
	(gr_circle
		(center 71.099934 -336.988404)
		(end 71.980044 -336.988404)
		(stroke
			(width 0.2)
			(type default)
		)
		(fill no)
		(layer "In16.Cu")
	)
	(gr_circle
		(center 71.333614 -174.764954)
		(end 72.222614 -174.764954)
		(stroke
			(width 0.2)
			(type default)
		)
		(fill no)
		(layer "In16.Cu")
	)
	(gr_circle
		(center 71.333614 -174.028354)
		(end 72.222614 -174.028354)
		(stroke
			(width 0.2)
			(type default)
		)
		(fill no)
		(layer "In16.Cu")
	)
	(gr_circle
		(center 71.717154 -336.988404)
		(end 72.597264 -336.988404)
		(stroke
			(width 0.2)
			(type default)
		)
		(fill no)
		(layer "In16.Cu")
	)
	(gr_circle
		(center 71.892668 -177.10912)
		(end 72.781668 -177.10912)
		(stroke
			(width 0.2)
			(type default)
		)
		(fill no)
		(layer "In16.Cu")
	)
	(gr_circle
		(center 71.892668 -176.37252)
		(end 72.781668 -176.37252)
		(stroke
			(width 0.2)
			(type default)
		)
		(fill no)
		(layer "In16.Cu")
	)
	(gr_circle
		(center 72.03567 -175.639222)
		(end 72.91578 -175.639222)
		(stroke
			(width 0.2)
			(type default)
		)
		(fill no)
		(layer "In16.Cu")
	)
	(gr_circle
		(center 72.334374 -336.988404)
		(end 73.214484 -336.988404)
		(stroke
			(width 0.2)
			(type default)
		)
		(fill no)
		(layer "In16.Cu")
	)
	(gr_circle
		(center 72.616314 -336.255868)
		(end 73.496424 -336.255868)
		(stroke
			(width 0.2)
			(type default)
		)
		(fill no)
		(layer "In16.Cu")
	)
	(gr_circle
		(center 72.616314 -335.519268)
		(end 73.496424 -335.519268)
		(stroke
			(width 0.2)
			(type default)
		)
		(fill no)
		(layer "In16.Cu")
	)
	(gr_circle
		(center 72.65289 -175.639222)
		(end 73.533 -175.639222)
		(stroke
			(width 0.2)
			(type default)
		)
		(fill no)
		(layer "In16.Cu")
	)
	(gr_circle
		(center 73.03643 -338.597494)
		(end 73.92543 -338.597494)
		(stroke
			(width 0.2)
			(type default)
		)
		(fill no)
		(layer "In16.Cu")
	)
	(gr_circle
		(center 73.03643 -337.860894)
		(end 73.92543 -337.860894)
		(stroke
			(width 0.2)
			(type default)
		)
		(fill no)
		(layer "In16.Cu")
	)
	(gr_circle
		(center 73.27011 -175.639222)
		(end 74.15022 -175.639222)
		(stroke
			(width 0.2)
			(type default)
		)
		(fill no)
		(layer "In16.Cu")
	)
	(gr_circle
		(center 73.561194 -337.421474)
		(end 74.450194 -337.421474)
		(stroke
			(width 0.2)
			(type default)
		)
		(fill no)
		(layer "In16.Cu")
	)
	(gr_circle
		(center 73.586594 -338.183474)
		(end 74.475594 -338.183474)
		(stroke
			(width 0.2)
			(type default)
		)
		(fill no)
		(layer "In16.Cu")
	)
	(gr_circle
		(center 74.119994 -338.539074)
		(end 75.008994 -338.539074)
		(stroke
			(width 0.2)
			(type default)
		)
		(fill no)
		(layer "In16.Cu")
	)
	(gr_circle
		(center 74.119994 -337.802474)
		(end 75.008994 -337.802474)
		(stroke
			(width 0.2)
			(type default)
		)
		(fill no)
		(layer "In16.Cu")
	)
	(gr_circle
		(center 74.119994 -337.065874)
		(end 75.008994 -337.065874)
		(stroke
			(width 0.2)
			(type default)
		)
		(fill no)
		(layer "In16.Cu")
	)
	(gr_circle
		(center 74.811382 -351.637854)
		(end 75.700382 -351.637854)
		(stroke
			(width 0.2)
			(type default)
		)
		(fill no)
		(layer "In16.Cu")
	)
	(gr_circle
		(center 74.849482 -353.131374)
		(end 75.738482 -353.131374)
		(stroke
			(width 0.2)
			(type default)
		)
		(fill no)
		(layer "In16.Cu")
	)
	(gr_circle
		(center 74.849736 -352.30816)
		(end 75.738736 -352.30816)
		(stroke
			(width 0.2)
			(type default)
		)
		(fill no)
		(layer "In16.Cu")
	)
	(gr_circle
		(center 74.86015 -350.929448)
		(end 75.74915 -350.929448)
		(stroke
			(width 0.2)
			(type default)
		)
		(fill no)
		(layer "In16.Cu")
	)
	(gr_circle
		(center 77.178408 -16.520668)
		(end 78.067408 -16.520668)
		(stroke
			(width 0.2)
			(type default)
		)
		(fill no)
		(layer "In16.Cu")
	)
	(gr_circle
		(center 77.473048 -351.5995)
		(end 78.362048 -351.5995)
		(stroke
			(width 0.2)
			(type default)
		)
		(fill no)
		(layer "In16.Cu")
	)
	(gr_circle
		(center 77.511402 -352.978212)
		(end 78.400402 -352.978212)
		(stroke
			(width 0.2)
			(type default)
		)
		(fill no)
		(layer "In16.Cu")
	)
	(gr_circle
		(center 77.511402 -352.269806)
		(end 78.400402 -352.269806)
		(stroke
			(width 0.2)
			(type default)
		)
		(fill no)
		(layer "In16.Cu")
	)
	(gr_circle
		(center 77.521816 -350.891094)
		(end 78.410816 -350.891094)
		(stroke
			(width 0.2)
			(type default)
		)
		(fill no)
		(layer "In16.Cu")
	)
	(gr_circle
		(center 77.84338 -16.55064)
		(end 78.73238 -16.55064)
		(stroke
			(width 0.2)
			(type default)
		)
		(fill no)
		(layer "In16.Cu")
	)
	(gr_circle
		(center 78.85303 -178.798474)
		(end 79.74203 -178.798474)
		(stroke
			(width 0.2)
			(type default)
		)
		(fill no)
		(layer "In16.Cu")
	)
	(gr_circle
		(center 78.85303 -178.036474)
		(end 79.74203 -178.036474)
		(stroke
			(width 0.2)
			(type default)
		)
		(fill no)
		(layer "In16.Cu")
	)
	(gr_circle
		(center 79.10703 -179.560474)
		(end 79.99603 -179.560474)
		(stroke
			(width 0.2)
			(type default)
		)
		(fill no)
		(layer "In16.Cu")
	)
	(gr_circle
		(center 79.13243 -180.322474)
		(end 80.02143 -180.322474)
		(stroke
			(width 0.2)
			(type default)
		)
		(fill no)
		(layer "In16.Cu")
	)
	(gr_circle
		(center 79.403194 -178.384454)
		(end 80.292194 -178.384454)
		(stroke
			(width 0.2)
			(type default)
		)
		(fill no)
		(layer "In16.Cu")
	)
	(gr_circle
		(center 79.455518 -336.981292)
		(end 80.335628 -336.981292)
		(stroke
			(width 0.2)
			(type default)
		)
		(fill no)
		(layer "In16.Cu")
	)
	(gr_circle
		(center 79.657194 -179.883054)
		(end 80.546194 -179.883054)
		(stroke
			(width 0.2)
			(type default)
		)
		(fill no)
		(layer "In16.Cu")
	)
	(gr_circle
		(center 79.657194 -179.146454)
		(end 80.546194 -179.146454)
		(stroke
			(width 0.2)
			(type default)
		)
		(fill no)
		(layer "In16.Cu")
	)
	(gr_circle
		(center 79.921862 -18.238724)
		(end 80.810862 -18.238724)
		(stroke
			(width 0.2)
			(type default)
		)
		(fill no)
		(layer "In16.Cu")
	)
	(gr_circle
		(center 79.921862 -17.502124)
		(end 80.810862 -17.502124)
		(stroke
			(width 0.2)
			(type default)
		)
		(fill no)
		(layer "In16.Cu")
	)
	(gr_circle
		(center 80.072738 -336.981292)
		(end 80.952848 -336.981292)
		(stroke
			(width 0.2)
			(type default)
		)
		(fill no)
		(layer "In16.Cu")
	)
	(gr_circle
		(center 80.241648 -182.2196)
		(end 81.130648 -182.2196)
		(stroke
			(width 0.2)
			(type default)
		)
		(fill no)
		(layer "In16.Cu")
	)
	(gr_circle
		(center 80.241648 -181.483)
		(end 81.130648 -181.483)
		(stroke
			(width 0.2)
			(type default)
		)
		(fill no)
		(layer "In16.Cu")
	)
	(gr_circle
		(center 80.35925 -180.755544)
		(end 81.23936 -180.755544)
		(stroke
			(width 0.2)
			(type default)
		)
		(fill no)
		(layer "In16.Cu")
	)
	(gr_circle
		(center 80.689958 -336.981292)
		(end 81.570068 -336.981292)
		(stroke
			(width 0.2)
			(type default)
		)
		(fill no)
		(layer "In16.Cu")
	)
	(gr_circle
		(center 80.97647 -180.755544)
		(end 81.85658 -180.755544)
		(stroke
			(width 0.2)
			(type default)
		)
		(fill no)
		(layer "In16.Cu")
	)
	(gr_circle
		(center 80.977994 -336.245708)
		(end 81.858104 -336.245708)
		(stroke
			(width 0.2)
			(type default)
		)
		(fill no)
		(layer "In16.Cu")
	)
	(gr_circle
		(center 80.977994 -335.509108)
		(end 81.858104 -335.509108)
		(stroke
			(width 0.2)
			(type default)
		)
		(fill no)
		(layer "In16.Cu")
	)
	(gr_line
		(start 81.193894 -9.780016)
		(end 81.193894 -0.508)
		(stroke
			(width 0.2)
			(type default)
		)
		(layer "In16.Cu")
	)
	(gr_arc
		(start 81.193894 -9.780016)
		(mid 81.928474 -11.55343)
		(end 83.70189 -12.288012)
		(stroke
			(width 0.2)
			(type default)
		)
		(layer "In16.Cu")
	)
	(gr_line
		(start 81.193894 -0.508)
		(end 13.610082 -0.508)
		(stroke
			(width 0.2)
			(type default)
		)
		(layer "In16.Cu")
	)
	(gr_circle
		(center 81.392014 -338.590382)
		(end 82.281014 -338.590382)
		(stroke
			(width 0.2)
			(type default)
		)
		(fill no)
		(layer "In16.Cu")
	)
	(gr_circle
		(center 81.392014 -337.853782)
		(end 82.281014 -337.853782)
		(stroke
			(width 0.2)
			(type default)
		)
		(fill no)
		(layer "In16.Cu")
	)
	(gr_circle
		(center 81.59369 -180.755544)
		(end 82.4738 -180.755544)
		(stroke
			(width 0.2)
			(type default)
		)
		(fill no)
		(layer "In16.Cu")
	)
	(gr_arc
		(start 81.701894 -9.780016)
		(mid 82.287679 -11.194227)
		(end 83.70189 -11.780012)
		(stroke
			(width 1.016)
			(type default)
		)
		(layer "In16.Cu")
	)
	(gr_arc
		(start 81.701894 -0.500126)
		(mid 81.555625 -0.146451)
		(end 81.202022 0)
		(stroke
			(width 1.016)
			(type default)
		)
		(layer "In16.Cu")
	)
	(gr_line
		(start 81.701894 -0.500126)
		(end 81.701894 -9.780016)
		(stroke
			(width 1.016)
			(type default)
		)
		(layer "In16.Cu")
	)
	(gr_circle
		(center 81.916778 -337.414362)
		(end 82.805778 -337.414362)
		(stroke
			(width 0.2)
			(type default)
		)
		(fill no)
		(layer "In16.Cu")
	)
	(gr_circle
		(center 81.942178 -338.176362)
		(end 82.831178 -338.176362)
		(stroke
			(width 0.2)
			(type default)
		)
		(fill no)
		(layer "In16.Cu")
	)
	(gr_circle
		(center 82.183986 -348.89948)
		(end 83.072986 -348.89948)
		(stroke
			(width 0.2)
			(type default)
		)
		(fill no)
		(layer "In16.Cu")
	)
	(gr_circle
		(center 82.222086 -350.393)
		(end 83.111086 -350.393)
		(stroke
			(width 0.2)
			(type default)
		)
		(fill no)
		(layer "In16.Cu")
	)
	(gr_circle
		(center 82.22234 -349.569786)
		(end 83.11134 -349.569786)
		(stroke
			(width 0.2)
			(type default)
		)
		(fill no)
		(layer "In16.Cu")
	)
	(gr_circle
		(center 82.232754 -348.191074)
		(end 83.121754 -348.191074)
		(stroke
			(width 0.2)
			(type default)
		)
		(fill no)
		(layer "In16.Cu")
	)
	(gr_circle
		(center 82.475578 -338.531962)
		(end 83.364578 -338.531962)
		(stroke
			(width 0.2)
			(type default)
		)
		(fill no)
		(layer "In16.Cu")
	)
	(gr_circle
		(center 82.475578 -337.795362)
		(end 83.364578 -337.795362)
		(stroke
			(width 0.2)
			(type default)
		)
		(fill no)
		(layer "In16.Cu")
	)
	(gr_circle
		(center 82.475578 -337.058762)
		(end 83.364578 -337.058762)
		(stroke
			(width 0.2)
			(type default)
		)
		(fill no)
		(layer "In16.Cu")
	)
	(gr_circle
		(center 82.989674 -165.962076)
		(end 84.386674 -165.962076)
		(stroke
			(width 0.2)
			(type default)
		)
		(fill no)
		(layer "In16.Cu")
	)
	(gr_line
		(start 83.70189 -11.780012)
		(end 124.102114 -11.780012)
		(stroke
			(width 1.016)
			(type default)
		)
		(layer "In16.Cu")
	)
	(gr_circle
		(center 84.845652 -348.861126)
		(end 85.734652 -348.861126)
		(stroke
			(width 0.2)
			(type default)
		)
		(fill no)
		(layer "In16.Cu")
	)
	(gr_circle
		(center 84.884006 -350.239838)
		(end 85.773006 -350.239838)
		(stroke
			(width 0.2)
			(type default)
		)
		(fill no)
		(layer "In16.Cu")
	)
	(gr_circle
		(center 84.884006 -349.531432)
		(end 85.773006 -349.531432)
		(stroke
			(width 0.2)
			(type default)
		)
		(fill no)
		(layer "In16.Cu")
	)
	(gr_circle
		(center 84.89442 -348.15272)
		(end 85.78342 -348.15272)
		(stroke
			(width 0.2)
			(type default)
		)
		(fill no)
		(layer "In16.Cu")
	)
	(gr_circle
		(center 86.97087 -180.610002)
		(end 87.85987 -180.610002)
		(stroke
			(width 0.2)
			(type default)
		)
		(fill no)
		(layer "In16.Cu")
	)
	(gr_circle
		(center 86.97087 -179.873402)
		(end 87.85987 -179.873402)
		(stroke
			(width 0.2)
			(type default)
		)
		(fill no)
		(layer "In16.Cu")
	)
	(gr_circle
		(center 86.97087 -179.136802)
		(end 87.85987 -179.136802)
		(stroke
			(width 0.2)
			(type default)
		)
		(fill no)
		(layer "In16.Cu")
	)
	(gr_circle
		(center 87.01913 -164.097716)
		(end 87.90813 -164.097716)
		(stroke
			(width 0.2)
			(type default)
		)
		(fill no)
		(layer "In16.Cu")
	)
	(gr_circle
		(center 87.03945 -163.447476)
		(end 87.92845 -163.447476)
		(stroke
			(width 0.2)
			(type default)
		)
		(fill no)
		(layer "In16.Cu")
	)
	(gr_circle
		(center 87.03945 -162.812476)
		(end 87.92845 -162.812476)
		(stroke
			(width 0.2)
			(type default)
		)
		(fill no)
		(layer "In16.Cu")
	)
	(gr_circle
		(center 87.50427 -179.492402)
		(end 88.39327 -179.492402)
		(stroke
			(width 0.2)
			(type default)
		)
		(fill no)
		(layer "In16.Cu")
	)
	(gr_circle
		(center 87.52967 -180.254402)
		(end 88.41867 -180.254402)
		(stroke
			(width 0.2)
			(type default)
		)
		(fill no)
		(layer "In16.Cu")
	)
	(gr_circle
		(center 87.65413 -164.097716)
		(end 88.54313 -164.097716)
		(stroke
			(width 0.2)
			(type default)
		)
		(fill no)
		(layer "In16.Cu")
	)
	(gr_circle
		(center 87.67445 -163.447476)
		(end 88.56345 -163.447476)
		(stroke
			(width 0.2)
			(type default)
		)
		(fill no)
		(layer "In16.Cu")
	)
	(gr_circle
		(center 87.67445 -162.812476)
		(end 88.56345 -162.812476)
		(stroke
			(width 0.2)
			(type default)
		)
		(fill no)
		(layer "In16.Cu")
	)
	(gr_circle
		(center 87.813134 -336.966814)
		(end 88.693244 -336.966814)
		(stroke
			(width 0.2)
			(type default)
		)
		(fill no)
		(layer "In16.Cu")
	)
	(gr_circle
		(center 88.054434 -179.814982)
		(end 88.943434 -179.814982)
		(stroke
			(width 0.2)
			(type default)
		)
		(fill no)
		(layer "In16.Cu")
	)
	(gr_circle
		(center 88.054434 -179.078382)
		(end 88.943434 -179.078382)
		(stroke
			(width 0.2)
			(type default)
		)
		(fill no)
		(layer "In16.Cu")
	)
	(gr_circle
		(center 88.28913 -164.097716)
		(end 89.17813 -164.097716)
		(stroke
			(width 0.2)
			(type default)
		)
		(fill no)
		(layer "In16.Cu")
	)
	(gr_circle
		(center 88.30945 -163.447476)
		(end 89.19845 -163.447476)
		(stroke
			(width 0.2)
			(type default)
		)
		(fill no)
		(layer "In16.Cu")
	)
	(gr_circle
		(center 88.30945 -162.812476)
		(end 89.19845 -162.812476)
		(stroke
			(width 0.2)
			(type default)
		)
		(fill no)
		(layer "In16.Cu")
	)
	(gr_circle
		(center 88.430354 -336.966814)
		(end 89.310464 -336.966814)
		(stroke
			(width 0.2)
			(type default)
		)
		(fill no)
		(layer "In16.Cu")
	)
	(gr_circle
		(center 88.49233 -182.13324)
		(end 89.38133 -182.13324)
		(stroke
			(width 0.2)
			(type default)
		)
		(fill no)
		(layer "In16.Cu")
	)
	(gr_circle
		(center 88.49233 -181.39664)
		(end 89.38133 -181.39664)
		(stroke
			(width 0.2)
			(type default)
		)
		(fill no)
		(layer "In16.Cu")
	)
	(gr_circle
		(center 88.75649 -180.687472)
		(end 89.6366 -180.687472)
		(stroke
			(width 0.2)
			(type default)
		)
		(fill no)
		(layer "In16.Cu")
	)
	(gr_circle
		(center 88.92413 -164.097716)
		(end 89.81313 -164.097716)
		(stroke
			(width 0.2)
			(type default)
		)
		(fill no)
		(layer "In16.Cu")
	)
	(gr_circle
		(center 88.94445 -163.447476)
		(end 89.83345 -163.447476)
		(stroke
			(width 0.2)
			(type default)
		)
		(fill no)
		(layer "In16.Cu")
	)
	(gr_circle
		(center 88.94445 -162.812476)
		(end 89.83345 -162.812476)
		(stroke
			(width 0.2)
			(type default)
		)
		(fill no)
		(layer "In16.Cu")
	)
	(gr_circle
		(center 89.047574 -336.966814)
		(end 89.927684 -336.966814)
		(stroke
			(width 0.2)
			(type default)
		)
		(fill no)
		(layer "In16.Cu")
	)
	(gr_circle
		(center 89.314528 -345.237562)
		(end 90.203528 -345.237562)
		(stroke
			(width 0.2)
			(type default)
		)
		(fill no)
		(layer "In16.Cu")
	)
	(gr_circle
		(center 89.319354 -336.255868)
		(end 90.199464 -336.255868)
		(stroke
			(width 0.2)
			(type default)
		)
		(fill no)
		(layer "In16.Cu")
	)
	(gr_circle
		(center 89.319354 -335.519268)
		(end 90.199464 -335.519268)
		(stroke
			(width 0.2)
			(type default)
		)
		(fill no)
		(layer "In16.Cu")
	)
	(gr_circle
		(center 89.350088 -345.96959)
		(end 90.239088 -345.96959)
		(stroke
			(width 0.2)
			(type default)
		)
		(fill no)
		(layer "In16.Cu")
	)
	(gr_circle
		(center 89.37371 -180.687472)
		(end 90.25382 -180.687472)
		(stroke
			(width 0.2)
			(type default)
		)
		(fill no)
		(layer "In16.Cu")
	)
	(gr_circle
		(center 89.388442 -346.639896)
		(end 90.277442 -346.639896)
		(stroke
			(width 0.2)
			(type default)
		)
		(fill no)
		(layer "In16.Cu")
	)
	(gr_circle
		(center 89.55913 -164.097716)
		(end 90.44813 -164.097716)
		(stroke
			(width 0.2)
			(type default)
		)
		(fill no)
		(layer "In16.Cu")
	)
	(gr_circle
		(center 89.57945 -163.447476)
		(end 90.46845 -163.447476)
		(stroke
			(width 0.2)
			(type default)
		)
		(fill no)
		(layer "In16.Cu")
	)
	(gr_circle
		(center 89.57945 -162.812476)
		(end 90.46845 -162.812476)
		(stroke
			(width 0.2)
			(type default)
		)
		(fill no)
		(layer "In16.Cu")
	)
	(gr_circle
		(center 89.74963 -338.575904)
		(end 90.63863 -338.575904)
		(stroke
			(width 0.2)
			(type default)
		)
		(fill no)
		(layer "In16.Cu")
	)
	(gr_circle
		(center 89.74963 -337.839304)
		(end 90.63863 -337.839304)
		(stroke
			(width 0.2)
			(type default)
		)
		(fill no)
		(layer "In16.Cu")
	)
	(gr_circle
		(center 89.983056 -345.261184)
		(end 90.872056 -345.261184)
		(stroke
			(width 0.2)
			(type default)
		)
		(fill no)
		(layer "In16.Cu")
	)
	(gr_circle
		(center 89.985088 -345.96959)
		(end 90.874088 -345.96959)
		(stroke
			(width 0.2)
			(type default)
		)
		(fill no)
		(layer "In16.Cu")
	)
	(gr_circle
		(center 89.99093 -180.687472)
		(end 90.87104 -180.687472)
		(stroke
			(width 0.2)
			(type default)
		)
		(fill no)
		(layer "In16.Cu")
	)
	(gr_circle
		(center 90.023442 -346.639896)
		(end 90.912442 -346.639896)
		(stroke
			(width 0.2)
			(type default)
		)
		(fill no)
		(layer "In16.Cu")
	)
	(gr_circle
		(center 90.21953 -164.107876)
		(end 91.10853 -164.107876)
		(stroke
			(width 0.2)
			(type default)
		)
		(fill no)
		(layer "In16.Cu")
	)
	(gr_circle
		(center 90.23985 -163.457636)
		(end 91.12885 -163.457636)
		(stroke
			(width 0.2)
			(type default)
		)
		(fill no)
		(layer "In16.Cu")
	)
	(gr_circle
		(center 90.23985 -162.822636)
		(end 91.12885 -162.822636)
		(stroke
			(width 0.2)
			(type default)
		)
		(fill no)
		(layer "In16.Cu")
	)
	(gr_circle
		(center 90.274394 -337.399884)
		(end 91.163394 -337.399884)
		(stroke
			(width 0.2)
			(type default)
		)
		(fill no)
		(layer "In16.Cu")
	)
	(gr_circle
		(center 90.299794 -338.161884)
		(end 91.188794 -338.161884)
		(stroke
			(width 0.2)
			(type default)
		)
		(fill no)
		(layer "In16.Cu")
	)
	(gr_circle
		(center 90.618056 -345.261184)
		(end 91.507056 -345.261184)
		(stroke
			(width 0.2)
			(type default)
		)
		(fill no)
		(layer "In16.Cu")
	)
	(gr_circle
		(center 90.620088 -345.96959)
		(end 91.509088 -345.96959)
		(stroke
			(width 0.2)
			(type default)
		)
		(fill no)
		(layer "In16.Cu")
	)
	(gr_circle
		(center 90.658442 -346.639896)
		(end 91.547442 -346.639896)
		(stroke
			(width 0.2)
			(type default)
		)
		(fill no)
		(layer "In16.Cu")
	)
	(gr_circle
		(center 90.833194 -338.517484)
		(end 91.722194 -338.517484)
		(stroke
			(width 0.2)
			(type default)
		)
		(fill no)
		(layer "In16.Cu")
	)
	(gr_circle
		(center 90.833194 -337.780884)
		(end 91.722194 -337.780884)
		(stroke
			(width 0.2)
			(type default)
		)
		(fill no)
		(layer "In16.Cu")
	)
	(gr_circle
		(center 90.833194 -337.044284)
		(end 91.722194 -337.044284)
		(stroke
			(width 0.2)
			(type default)
		)
		(fill no)
		(layer "In16.Cu")
	)
	(gr_circle
		(center 91.255088 -345.96959)
		(end 92.144088 -345.96959)
		(stroke
			(width 0.2)
			(type default)
		)
		(fill no)
		(layer "In16.Cu")
	)
	(gr_circle
		(center 91.293442 -346.639896)
		(end 92.182442 -346.639896)
		(stroke
			(width 0.2)
			(type default)
		)
		(fill no)
		(layer "In16.Cu")
	)
	(gr_circle
		(center 91.380056 -345.261184)
		(end 92.269056 -345.261184)
		(stroke
			(width 0.2)
			(type default)
		)
		(fill no)
		(layer "In16.Cu")
	)
	(gr_circle
		(center 91.966288 -345.96959)
		(end 92.855288 -345.96959)
		(stroke
			(width 0.2)
			(type default)
		)
		(fill no)
		(layer "In16.Cu")
	)
	(gr_circle
		(center 92.004642 -346.639896)
		(end 92.893642 -346.639896)
		(stroke
			(width 0.2)
			(type default)
		)
		(fill no)
		(layer "In16.Cu")
	)
	(gr_circle
		(center 92.015056 -345.261184)
		(end 92.904056 -345.261184)
		(stroke
			(width 0.2)
			(type default)
		)
		(fill no)
		(layer "In16.Cu")
	)
	(gr_circle
		(center 92.387674 -165.962076)
		(end 93.784674 -165.962076)
		(stroke
			(width 0.2)
			(type default)
		)
		(fill no)
		(layer "In16.Cu")
	)
	(gr_circle
		(center 92.601288 -345.96959)
		(end 93.490288 -345.96959)
		(stroke
			(width 0.2)
			(type default)
		)
		(fill no)
		(layer "In16.Cu")
	)
	(gr_circle
		(center 92.639642 -346.639896)
		(end 93.528642 -346.639896)
		(stroke
			(width 0.2)
			(type default)
		)
		(fill no)
		(layer "In16.Cu")
	)
	(gr_circle
		(center 92.650056 -345.261184)
		(end 93.539056 -345.261184)
		(stroke
			(width 0.2)
			(type default)
		)
		(fill no)
		(layer "In16.Cu")
	)
	(gr_circle
		(center 95.36303 -180.627274)
		(end 96.25203 -180.627274)
		(stroke
			(width 0.2)
			(type default)
		)
		(fill no)
		(layer "In16.Cu")
	)
	(gr_circle
		(center 95.36303 -179.890674)
		(end 96.25203 -179.890674)
		(stroke
			(width 0.2)
			(type default)
		)
		(fill no)
		(layer "In16.Cu")
	)
	(gr_circle
		(center 95.36303 -179.154074)
		(end 96.25203 -179.154074)
		(stroke
			(width 0.2)
			(type default)
		)
		(fill no)
		(layer "In16.Cu")
	)
	(gr_circle
		(center 95.89643 -179.509674)
		(end 96.78543 -179.509674)
		(stroke
			(width 0.2)
			(type default)
		)
		(fill no)
		(layer "In16.Cu")
	)
	(gr_circle
		(center 95.92183 -180.271674)
		(end 96.81083 -180.271674)
		(stroke
			(width 0.2)
			(type default)
		)
		(fill no)
		(layer "In16.Cu")
	)
	(gr_circle
		(center 96.144334 -337.017614)
		(end 97.024444 -337.017614)
		(stroke
			(width 0.2)
			(type default)
		)
		(fill no)
		(layer "In16.Cu")
	)
	(gr_circle
		(center 96.446594 -179.832254)
		(end 97.335594 -179.832254)
		(stroke
			(width 0.2)
			(type default)
		)
		(fill no)
		(layer "In16.Cu")
	)
	(gr_circle
		(center 96.446594 -179.095654)
		(end 97.335594 -179.095654)
		(stroke
			(width 0.2)
			(type default)
		)
		(fill no)
		(layer "In16.Cu")
	)
	(gr_circle
		(center 96.761554 -337.017614)
		(end 97.641664 -337.017614)
		(stroke
			(width 0.2)
			(type default)
		)
		(fill no)
		(layer "In16.Cu")
	)
	(gr_circle
		(center 96.980248 -182.13324)
		(end 97.869248 -182.13324)
		(stroke
			(width 0.2)
			(type default)
		)
		(fill no)
		(layer "In16.Cu")
	)
	(gr_circle
		(center 96.980248 -181.39664)
		(end 97.869248 -181.39664)
		(stroke
			(width 0.2)
			(type default)
		)
		(fill no)
		(layer "In16.Cu")
	)
	(gr_circle
		(center 97.14865 -180.704744)
		(end 98.02876 -180.704744)
		(stroke
			(width 0.2)
			(type default)
		)
		(fill no)
		(layer "In16.Cu")
	)
	(gr_circle
		(center 97.378774 -337.017614)
		(end 98.258884 -337.017614)
		(stroke
			(width 0.2)
			(type default)
		)
		(fill no)
		(layer "In16.Cu")
	)
	(gr_circle
		(center 97.658174 -336.319368)
		(end 98.538284 -336.319368)
		(stroke
			(width 0.2)
			(type default)
		)
		(fill no)
		(layer "In16.Cu")
	)
	(gr_circle
		(center 97.658174 -335.582768)
		(end 98.538284 -335.582768)
		(stroke
			(width 0.2)
			(type default)
		)
		(fill no)
		(layer "In16.Cu")
	)
	(gr_circle
		(center 97.76587 -180.704744)
		(end 98.64598 -180.704744)
		(stroke
			(width 0.2)
			(type default)
		)
		(fill no)
		(layer "In16.Cu")
	)
	(gr_circle
		(center 98.08083 -338.626704)
		(end 98.96983 -338.626704)
		(stroke
			(width 0.2)
			(type default)
		)
		(fill no)
		(layer "In16.Cu")
	)
	(gr_circle
		(center 98.08083 -337.890104)
		(end 98.96983 -337.890104)
		(stroke
			(width 0.2)
			(type default)
		)
		(fill no)
		(layer "In16.Cu")
	)
	(gr_circle
		(center 98.199194 -339.358224)
		(end 99.088194 -339.358224)
		(stroke
			(width 0.2)
			(type default)
		)
		(fill no)
		(layer "In16.Cu")
	)
	(gr_circle
		(center 98.38309 -180.704744)
		(end 99.2632 -180.704744)
		(stroke
			(width 0.2)
			(type default)
		)
		(fill no)
		(layer "In16.Cu")
	)
	(gr_circle
		(center 98.605594 -337.450684)
		(end 99.494594 -337.450684)
		(stroke
			(width 0.2)
			(type default)
		)
		(fill no)
		(layer "In16.Cu")
	)
	(gr_circle
		(center 98.630994 -338.212684)
		(end 99.519994 -338.212684)
		(stroke
			(width 0.2)
			(type default)
		)
		(fill no)
		(layer "In16.Cu")
	)
	(gr_circle
		(center 98.747834 -339.736684)
		(end 99.636834 -339.736684)
		(stroke
			(width 0.2)
			(type default)
		)
		(fill no)
		(layer "In16.Cu")
	)
	(gr_circle
		(center 98.747834 -338.974684)
		(end 99.636834 -338.974684)
		(stroke
			(width 0.2)
			(type default)
		)
		(fill no)
		(layer "In16.Cu")
	)
	(gr_circle
		(center 103.74503 -176.106074)
		(end 104.63403 -176.106074)
		(stroke
			(width 0.2)
			(type default)
		)
		(fill no)
		(layer "In16.Cu")
	)
	(gr_circle
		(center 103.74503 -175.369474)
		(end 104.63403 -175.369474)
		(stroke
			(width 0.2)
			(type default)
		)
		(fill no)
		(layer "In16.Cu")
	)
	(gr_circle
		(center 103.74503 -174.632874)
		(end 104.63403 -174.632874)
		(stroke
			(width 0.2)
			(type default)
		)
		(fill no)
		(layer "In16.Cu")
	)
	(gr_circle
		(center 104.27843 -174.988474)
		(end 105.16743 -174.988474)
		(stroke
			(width 0.2)
			(type default)
		)
		(fill no)
		(layer "In16.Cu")
	)
	(gr_circle
		(center 104.30383 -175.750474)
		(end 105.19283 -175.750474)
		(stroke
			(width 0.2)
			(type default)
		)
		(fill no)
		(layer "In16.Cu")
	)
	(gr_circle
		(center 104.420162 -341.927688)
		(end 105.300272 -341.927688)
		(stroke
			(width 0.2)
			(type default)
		)
		(fill no)
		(layer "In16.Cu")
	)
	(gr_circle
		(center 104.828594 -175.311054)
		(end 105.717594 -175.311054)
		(stroke
			(width 0.2)
			(type default)
		)
		(fill no)
		(layer "In16.Cu")
	)
	(gr_circle
		(center 104.828594 -174.574454)
		(end 105.717594 -174.574454)
		(stroke
			(width 0.2)
			(type default)
		)
		(fill no)
		(layer "In16.Cu")
	)
	(gr_circle
		(center 105.037382 -341.927688)
		(end 105.917492 -341.927688)
		(stroke
			(width 0.2)
			(type default)
		)
		(fill no)
		(layer "In16.Cu")
	)
	(gr_circle
		(center 105.336848 -177.65776)
		(end 106.225848 -177.65776)
		(stroke
			(width 0.2)
			(type default)
		)
		(fill no)
		(layer "In16.Cu")
	)
	(gr_circle
		(center 105.336848 -176.92116)
		(end 106.225848 -176.92116)
		(stroke
			(width 0.2)
			(type default)
		)
		(fill no)
		(layer "In16.Cu")
	)
	(gr_circle
		(center 105.53065 -176.183544)
		(end 106.41076 -176.183544)
		(stroke
			(width 0.2)
			(type default)
		)
		(fill no)
		(layer "In16.Cu")
	)
	(gr_circle
		(center 105.654602 -341.927688)
		(end 106.534712 -341.927688)
		(stroke
			(width 0.2)
			(type default)
		)
		(fill no)
		(layer "In16.Cu")
	)
	(gr_circle
		(center 105.934002 -341.229442)
		(end 106.814112 -341.229442)
		(stroke
			(width 0.2)
			(type default)
		)
		(fill no)
		(layer "In16.Cu")
	)
	(gr_circle
		(center 105.934002 -340.492842)
		(end 106.814112 -340.492842)
		(stroke
			(width 0.2)
			(type default)
		)
		(fill no)
		(layer "In16.Cu")
	)
	(gr_circle
		(center 106.14787 -176.183544)
		(end 107.02798 -176.183544)
		(stroke
			(width 0.2)
			(type default)
		)
		(fill no)
		(layer "In16.Cu")
	)
	(gr_circle
		(center 106.34345 -343.450164)
		(end 107.23245 -343.450164)
		(stroke
			(width 0.2)
			(type default)
		)
		(fill no)
		(layer "In16.Cu")
	)
	(gr_circle
		(center 106.34345 -342.713564)
		(end 107.23245 -342.713564)
		(stroke
			(width 0.2)
			(type default)
		)
		(fill no)
		(layer "In16.Cu")
	)
	(gr_circle
		(center 106.76509 -176.183544)
		(end 107.6452 -176.183544)
		(stroke
			(width 0.2)
			(type default)
		)
		(fill no)
		(layer "In16.Cu")
	)
	(gr_circle
		(center 106.98607 -342.540844)
		(end 107.87507 -342.540844)
		(stroke
			(width 0.2)
			(type default)
		)
		(fill no)
		(layer "In16.Cu")
	)
	(gr_circle
		(center 106.98607 -341.804244)
		(end 107.87507 -341.804244)
		(stroke
			(width 0.2)
			(type default)
		)
		(fill no)
		(layer "In16.Cu")
	)
	(gr_circle
		(center 107.01401 -343.986104)
		(end 107.90301 -343.986104)
		(stroke
			(width 0.2)
			(type default)
		)
		(fill no)
		(layer "In16.Cu")
	)
	(gr_circle
		(center 107.01401 -343.249504)
		(end 107.90301 -343.249504)
		(stroke
			(width 0.2)
			(type default)
		)
		(fill no)
		(layer "In16.Cu")
	)
	(gr_circle
		(center 110.140496 -150.941786)
		(end 111.537496 -150.941786)
		(stroke
			(width 0.2)
			(type default)
		)
		(fill no)
		(layer "In16.Cu")
	)
	(gr_circle
		(center 111.97463 -169.857674)
		(end 112.86363 -169.857674)
		(stroke
			(width 0.2)
			(type default)
		)
		(fill no)
		(layer "In16.Cu")
	)
	(gr_circle
		(center 111.97463 -169.121074)
		(end 112.86363 -169.121074)
		(stroke
			(width 0.2)
			(type default)
		)
		(fill no)
		(layer "In16.Cu")
	)
	(gr_circle
		(center 111.97463 -168.384474)
		(end 112.86363 -168.384474)
		(stroke
			(width 0.2)
			(type default)
		)
		(fill no)
		(layer "In16.Cu")
	)
	(gr_circle
		(center 112.50803 -168.740074)
		(end 113.39703 -168.740074)
		(stroke
			(width 0.2)
			(type default)
		)
		(fill no)
		(layer "In16.Cu")
	)
	(gr_circle
		(center 112.53343 -169.502074)
		(end 113.42243 -169.502074)
		(stroke
			(width 0.2)
			(type default)
		)
		(fill no)
		(layer "In16.Cu")
	)
	(gr_circle
		(center 113.058194 -169.062654)
		(end 113.947194 -169.062654)
		(stroke
			(width 0.2)
			(type default)
		)
		(fill no)
		(layer "In16.Cu")
	)
	(gr_circle
		(center 113.058194 -168.326054)
		(end 113.947194 -168.326054)
		(stroke
			(width 0.2)
			(type default)
		)
		(fill no)
		(layer "In16.Cu")
	)
	(gr_circle
		(center 113.591848 -171.33316)
		(end 114.480848 -171.33316)
		(stroke
			(width 0.2)
			(type default)
		)
		(fill no)
		(layer "In16.Cu")
	)
	(gr_circle
		(center 113.591848 -170.59656)
		(end 114.480848 -170.59656)
		(stroke
			(width 0.2)
			(type default)
		)
		(fill no)
		(layer "In16.Cu")
	)
	(gr_circle
		(center 113.76025 -169.935144)
		(end 114.64036 -169.935144)
		(stroke
			(width 0.2)
			(type default)
		)
		(fill no)
		(layer "In16.Cu")
	)
	(gr_circle
		(center 114.37747 -169.935144)
		(end 115.25758 -169.935144)
		(stroke
			(width 0.2)
			(type default)
		)
		(fill no)
		(layer "In16.Cu")
	)
	(gr_circle
		(center 114.99469 -169.935144)
		(end 115.8748 -169.935144)
		(stroke
			(width 0.2)
			(type default)
		)
		(fill no)
		(layer "In16.Cu")
	)
	(gr_circle
		(center 116.258594 -152.657556)
		(end 117.147594 -152.657556)
		(stroke
			(width 0.2)
			(type default)
		)
		(fill no)
		(layer "In16.Cu")
	)
	(gr_circle
		(center 116.258594 -152.022556)
		(end 117.147594 -152.022556)
		(stroke
			(width 0.2)
			(type default)
		)
		(fill no)
		(layer "In16.Cu")
	)
	(gr_circle
		(center 116.893594 -152.657556)
		(end 117.782594 -152.657556)
		(stroke
			(width 0.2)
			(type default)
		)
		(fill no)
		(layer "In16.Cu")
	)
	(gr_circle
		(center 116.893594 -152.022556)
		(end 117.782594 -152.022556)
		(stroke
			(width 0.2)
			(type default)
		)
		(fill no)
		(layer "In16.Cu")
	)
	(gr_circle
		(center 117.559074 -152.657556)
		(end 118.448074 -152.657556)
		(stroke
			(width 0.2)
			(type default)
		)
		(fill no)
		(layer "In16.Cu")
	)
	(gr_circle
		(center 117.559074 -152.022556)
		(end 118.448074 -152.022556)
		(stroke
			(width 0.2)
			(type default)
		)
		(fill no)
		(layer "In16.Cu")
	)
	(gr_circle
		(center 118.194074 -152.657556)
		(end 119.083074 -152.657556)
		(stroke
			(width 0.2)
			(type default)
		)
		(fill no)
		(layer "In16.Cu")
	)
	(gr_circle
		(center 118.194074 -152.022556)
		(end 119.083074 -152.022556)
		(stroke
			(width 0.2)
			(type default)
		)
		(fill no)
		(layer "In16.Cu")
	)
	(gr_circle
		(center 118.829074 -152.657556)
		(end 119.718074 -152.657556)
		(stroke
			(width 0.2)
			(type default)
		)
		(fill no)
		(layer "In16.Cu")
	)
	(gr_circle
		(center 118.829074 -152.022556)
		(end 119.718074 -152.022556)
		(stroke
			(width 0.2)
			(type default)
		)
		(fill no)
		(layer "In16.Cu")
	)
	(gr_circle
		(center 119.464074 -152.657556)
		(end 120.353074 -152.657556)
		(stroke
			(width 0.2)
			(type default)
		)
		(fill no)
		(layer "In16.Cu")
	)
	(gr_circle
		(center 119.464074 -152.022556)
		(end 120.353074 -152.022556)
		(stroke
			(width 0.2)
			(type default)
		)
		(fill no)
		(layer "In16.Cu")
	)
	(gr_circle
		(center 120.25503 -163.126674)
		(end 121.14403 -163.126674)
		(stroke
			(width 0.2)
			(type default)
		)
		(fill no)
		(layer "In16.Cu")
	)
	(gr_circle
		(center 120.25503 -162.390074)
		(end 121.14403 -162.390074)
		(stroke
			(width 0.2)
			(type default)
		)
		(fill no)
		(layer "In16.Cu")
	)
	(gr_circle
		(center 120.25503 -161.653474)
		(end 121.14403 -161.653474)
		(stroke
			(width 0.2)
			(type default)
		)
		(fill no)
		(layer "In16.Cu")
	)
	(gr_circle
		(center 120.78843 -162.009074)
		(end 121.67743 -162.009074)
		(stroke
			(width 0.2)
			(type default)
		)
		(fill no)
		(layer "In16.Cu")
	)
	(gr_circle
		(center 120.81383 -162.771074)
		(end 121.70283 -162.771074)
		(stroke
			(width 0.2)
			(type default)
		)
		(fill no)
		(layer "In16.Cu")
	)
	(gr_circle
		(center 121.338594 -162.331654)
		(end 122.227594 -162.331654)
		(stroke
			(width 0.2)
			(type default)
		)
		(fill no)
		(layer "In16.Cu")
	)
	(gr_circle
		(center 121.338594 -161.595054)
		(end 122.227594 -161.595054)
		(stroke
			(width 0.2)
			(type default)
		)
		(fill no)
		(layer "In16.Cu")
	)
	(gr_circle
		(center 121.872248 -164.62756)
		(end 122.761248 -164.62756)
		(stroke
			(width 0.2)
			(type default)
		)
		(fill no)
		(layer "In16.Cu")
	)
	(gr_circle
		(center 121.872248 -163.89096)
		(end 122.761248 -163.89096)
		(stroke
			(width 0.2)
			(type default)
		)
		(fill no)
		(layer "In16.Cu")
	)
	(gr_circle
		(center 122.04065 -163.204144)
		(end 122.92076 -163.204144)
		(stroke
			(width 0.2)
			(type default)
		)
		(fill no)
		(layer "In16.Cu")
	)
	(gr_circle
		(center 122.65787 -163.204144)
		(end 123.53798 -163.204144)
		(stroke
			(width 0.2)
			(type default)
		)
		(fill no)
		(layer "In16.Cu")
	)
	(gr_circle
		(center 123.27509 -163.204144)
		(end 124.1552 -163.204144)
		(stroke
			(width 0.2)
			(type default)
		)
		(fill no)
		(layer "In16.Cu")
	)
	(gr_line
		(start 124.102114 -12.288012)
		(end 83.70189 -12.288012)
		(stroke
			(width 0.2)
			(type default)
		)
		(layer "In16.Cu")
	)
	(gr_arc
		(start 124.102114 -12.288012)
		(mid 125.875532 -11.553433)
		(end 126.61011 -9.780016)
		(stroke
			(width 0.2)
			(type default)
		)
		(layer "In16.Cu")
	)
	(gr_arc
		(start 124.102114 -11.780012)
		(mid 125.516325 -11.194227)
		(end 126.10211 -9.780016)
		(stroke
			(width 1.016)
			(type default)
		)
		(layer "In16.Cu")
	)
	(gr_line
		(start 126.10211 -9.780016)
		(end 126.10211 -5.780024)
		(stroke
			(width 1.016)
			(type default)
		)
		(layer "In16.Cu")
	)
	(gr_arc
		(start 126.601982 -5.279898)
		(mid 126.248489 -5.42646)
		(end 126.10211 -5.780024)
		(stroke
			(width 1.016)
			(type default)
		)
		(layer "In16.Cu")
	)
	(gr_line
		(start 126.601982 -5.279898)
		(end 194.20205 -5.279898)
		(stroke
			(width 1.016)
			(type default)
		)
		(layer "In16.Cu")
	)
	(gr_line
		(start 126.61011 -5.787898)
		(end 126.61011 -9.780016)
		(stroke
			(width 0.2)
			(type default)
		)
		(layer "In16.Cu")
	)
	(gr_circle
		(center 128.71323 -154.465274)
		(end 129.60223 -154.465274)
		(stroke
			(width 0.2)
			(type default)
		)
		(fill no)
		(layer "In16.Cu")
	)
	(gr_circle
		(center 128.71323 -153.728674)
		(end 129.60223 -153.728674)
		(stroke
			(width 0.2)
			(type default)
		)
		(fill no)
		(layer "In16.Cu")
	)
	(gr_circle
		(center 128.71323 -152.992074)
		(end 129.60223 -152.992074)
		(stroke
			(width 0.2)
			(type default)
		)
		(fill no)
		(layer "In16.Cu")
	)
	(gr_circle
		(center 129.24663 -153.347674)
		(end 130.13563 -153.347674)
		(stroke
			(width 0.2)
			(type default)
		)
		(fill no)
		(layer "In16.Cu")
	)
	(gr_circle
		(center 129.27203 -154.109674)
		(end 130.16103 -154.109674)
		(stroke
			(width 0.2)
			(type default)
		)
		(fill no)
		(layer "In16.Cu")
	)
	(gr_circle
		(center 129.796794 -153.670254)
		(end 130.685794 -153.670254)
		(stroke
			(width 0.2)
			(type default)
		)
		(fill no)
		(layer "In16.Cu")
	)
	(gr_circle
		(center 129.796794 -152.933654)
		(end 130.685794 -152.933654)
		(stroke
			(width 0.2)
			(type default)
		)
		(fill no)
		(layer "In16.Cu")
	)
	(gr_circle
		(center 130.305048 -155.94076)
		(end 131.194048 -155.94076)
		(stroke
			(width 0.2)
			(type default)
		)
		(fill no)
		(layer "In16.Cu")
	)
	(gr_circle
		(center 130.305048 -155.20416)
		(end 131.194048 -155.20416)
		(stroke
			(width 0.2)
			(type default)
		)
		(fill no)
		(layer "In16.Cu")
	)
	(gr_circle
		(center 130.49885 -154.542744)
		(end 131.37896 -154.542744)
		(stroke
			(width 0.2)
			(type default)
		)
		(fill no)
		(layer "In16.Cu")
	)
	(gr_circle
		(center 131.11607 -154.542744)
		(end 131.99618 -154.542744)
		(stroke
			(width 0.2)
			(type default)
		)
		(fill no)
		(layer "In16.Cu")
	)
	(gr_circle
		(center 131.73329 -154.542744)
		(end 132.6134 -154.542744)
		(stroke
			(width 0.2)
			(type default)
		)
		(fill no)
		(layer "In16.Cu")
	)
	(gr_circle
		(center 176.332134 -26.634948)
		(end 177.221134 -26.634948)
		(stroke
			(width 0.2)
			(type default)
		)
		(fill no)
		(layer "In16.Cu")
	)
	(gr_circle
		(center 176.713134 -25.949148)
		(end 177.602134 -25.949148)
		(stroke
			(width 0.2)
			(type default)
		)
		(fill no)
		(layer "In16.Cu")
	)
	(gr_circle
		(center 176.878234 -19.942048)
		(end 177.767234 -19.942048)
		(stroke
			(width 0.2)
			(type default)
		)
		(fill no)
		(layer "In16.Cu")
	)
	(gr_circle
		(center 176.968912 -21.349208)
		(end 177.857912 -21.349208)
		(stroke
			(width 0.2)
			(type default)
		)
		(fill no)
		(layer "In16.Cu")
	)
	(gr_circle
		(center 176.968912 -20.714208)
		(end 177.857912 -20.714208)
		(stroke
			(width 0.2)
			(type default)
		)
		(fill no)
		(layer "In16.Cu")
	)
	(gr_circle
		(center 177.221134 -26.634948)
		(end 178.110134 -26.634948)
		(stroke
			(width 0.2)
			(type default)
		)
		(fill no)
		(layer "In16.Cu")
	)
	(gr_circle
		(center 177.472594 -21.85289)
		(end 178.361594 -21.85289)
		(stroke
			(width 0.2)
			(type default)
		)
		(fill no)
		(layer "In16.Cu")
	)
	(gr_circle
		(center 177.602134 -25.949148)
		(end 178.491134 -25.949148)
		(stroke
			(width 0.2)
			(type default)
		)
		(fill no)
		(layer "In16.Cu")
	)
	(gr_circle
		(center 178.110134 -26.634948)
		(end 178.999134 -26.634948)
		(stroke
			(width 0.2)
			(type default)
		)
		(fill no)
		(layer "In16.Cu")
	)
	(gr_circle
		(center 178.491134 -25.949148)
		(end 179.380134 -25.949148)
		(stroke
			(width 0.2)
			(type default)
		)
		(fill no)
		(layer "In16.Cu")
	)
	(gr_circle
		(center 179.507134 -25.517348)
		(end 180.396134 -25.517348)
		(stroke
			(width 0.2)
			(type default)
		)
		(fill no)
		(layer "In16.Cu")
	)
	(gr_circle
		(center 180.921914 -27.107388)
		(end 181.810914 -27.107388)
		(stroke
			(width 0.2)
			(type default)
		)
		(fill no)
		(layer "In16.Cu")
	)
	(gr_circle
		(center 183.610758 -353.283774)
		(end 184.490868 -353.283774)
		(stroke
			(width 0.2)
			(type default)
		)
		(fill no)
		(layer "In16.Cu")
	)
	(gr_circle
		(center 184.227978 -353.283774)
		(end 185.108088 -353.283774)
		(stroke
			(width 0.2)
			(type default)
		)
		(fill no)
		(layer "In16.Cu")
	)
	(gr_line
		(start 184.258458 -410.708348)
		(end 184.258458 -400.09572)
		(stroke
			(width 0.635)
			(type default)
		)
		(layer "In16.Cu")
	)
	(gr_line
		(start 184.258458 -400.09572)
		(end 184.463944 -399.890234)
		(stroke
			(width 0.635)
			(type default)
		)
		(layer "In16.Cu")
	)
	(gr_line
		(start 184.463944 -399.890234)
		(end 188.119004 -399.890234)
		(stroke
			(width 0.635)
			(type default)
		)
		(layer "In16.Cu")
	)
	(gr_line
		(start 184.8104 -411.26029)
		(end 184.258458 -410.708348)
		(stroke
			(width 0.635)
			(type default)
		)
		(layer "In16.Cu")
	)
	(gr_circle
		(center 184.845198 -353.283774)
		(end 185.725308 -353.283774)
		(stroke
			(width 0.2)
			(type default)
		)
		(fill no)
		(layer "In16.Cu")
	)
	(gr_circle
		(center 184.962292 -352.558604)
		(end 185.851292 -352.558604)
		(stroke
			(width 0.2)
			(type default)
		)
		(fill no)
		(layer "In16.Cu")
	)
	(gr_circle
		(center 184.962292 -351.822004)
		(end 185.851292 -351.822004)
		(stroke
			(width 0.2)
			(type default)
		)
		(fill no)
		(layer "In16.Cu")
	)
	(gr_circle
		(center 185.547254 -354.892864)
		(end 186.436254 -354.892864)
		(stroke
			(width 0.2)
			(type default)
		)
		(fill no)
		(layer "In16.Cu")
	)
	(gr_circle
		(center 185.547254 -354.156264)
		(end 186.436254 -354.156264)
		(stroke
			(width 0.2)
			(type default)
		)
		(fill no)
		(layer "In16.Cu")
	)
	(gr_circle
		(center 186.034172 -362.234988)
		(end 186.923172 -362.234988)
		(stroke
			(width 0.2)
			(type default)
		)
		(fill no)
		(layer "In16.Cu")
	)
	(gr_circle
		(center 186.034172 -361.472988)
		(end 186.923172 -361.472988)
		(stroke
			(width 0.2)
			(type default)
		)
		(fill no)
		(layer "In16.Cu")
	)
	(gr_circle
		(center 186.034172 -360.710988)
		(end 186.923172 -360.710988)
		(stroke
			(width 0.2)
			(type default)
		)
		(fill no)
		(layer "In16.Cu")
	)
	(gr_circle
		(center 186.072018 -353.716844)
		(end 186.961018 -353.716844)
		(stroke
			(width 0.2)
			(type default)
		)
		(fill no)
		(layer "In16.Cu")
	)
	(gr_circle
		(center 186.097418 -354.478844)
		(end 186.986418 -354.478844)
		(stroke
			(width 0.2)
			(type default)
		)
		(fill no)
		(layer "In16.Cu")
	)
	(gr_circle
		(center 186.630818 -354.834444)
		(end 187.519818 -354.834444)
		(stroke
			(width 0.2)
			(type default)
		)
		(fill no)
		(layer "In16.Cu")
	)
	(gr_circle
		(center 186.630818 -354.097844)
		(end 187.519818 -354.097844)
		(stroke
			(width 0.2)
			(type default)
		)
		(fill no)
		(layer "In16.Cu")
	)
	(gr_circle
		(center 186.630818 -353.361244)
		(end 187.519818 -353.361244)
		(stroke
			(width 0.2)
			(type default)
		)
		(fill no)
		(layer "In16.Cu")
	)
	(gr_circle
		(center 186.796172 -362.234988)
		(end 187.685172 -362.234988)
		(stroke
			(width 0.2)
			(type default)
		)
		(fill no)
		(layer "In16.Cu")
	)
	(gr_circle
		(center 186.796172 -361.472988)
		(end 187.685172 -361.472988)
		(stroke
			(width 0.2)
			(type default)
		)
		(fill no)
		(layer "In16.Cu")
	)
	(gr_circle
		(center 186.796172 -360.710988)
		(end 187.685172 -360.710988)
		(stroke
			(width 0.2)
			(type default)
		)
		(fill no)
		(layer "In16.Cu")
	)
	(gr_line
		(start 187.965334 -411.26029)
		(end 184.8104 -411.26029)
		(stroke
			(width 0.635)
			(type default)
		)
		(layer "In16.Cu")
	)
	(gr_line
		(start 188.119004 -399.890234)
		(end 188.303916 -400.075146)
		(stroke
			(width 0.635)
			(type default)
		)
		(layer "In16.Cu")
	)
	(gr_line
		(start 188.303916 -402.905976)
		(end 191.073786 -405.675846)
		(stroke
			(width 0.635)
			(type default)
		)
		(layer "In16.Cu")
	)
	(gr_line
		(start 188.303916 -400.075146)
		(end 188.303916 -402.905976)
		(stroke
			(width 0.635)
			(type default)
		)
		(layer "In16.Cu")
	)
	(gr_line
		(start 188.720222 -412.015178)
		(end 187.965334 -411.26029)
		(stroke
			(width 0.635)
			(type default)
		)
		(layer "In16.Cu")
	)
	(gr_circle
		(center 190.508636 -23.593552)
		(end 191.397636 -23.593552)
		(stroke
			(width 0.2)
			(type default)
		)
		(fill no)
		(layer "In16.Cu")
	)
	(gr_circle
		(center 190.508636 -22.856952)
		(end 191.397636 -22.856952)
		(stroke
			(width 0.2)
			(type default)
		)
		(fill no)
		(layer "In16.Cu")
	)
	(gr_line
		(start 191.073786 -405.675846)
		(end 195.418964 -405.675846)
		(stroke
			(width 0.635)
			(type default)
		)
		(layer "In16.Cu")
	)
	(gr_circle
		(center 191.67983 -362.430568)
		(end 193.07683 -362.430568)
		(stroke
			(width 0.2)
			(type default)
		)
		(fill no)
		(layer "In16.Cu")
	)
	(gr_circle
		(center 191.927734 -13.106908)
		(end 192.816734 -13.106908)
		(stroke
			(width 0.2)
			(type default)
		)
		(fill no)
		(layer "In16.Cu")
	)
	(gr_circle
		(center 191.937386 -353.309174)
		(end 192.817496 -353.309174)
		(stroke
			(width 0.2)
			(type default)
		)
		(fill no)
		(layer "In16.Cu")
	)
	(gr_circle
		(center 192.461134 -16.416528)
		(end 193.350134 -16.416528)
		(stroke
			(width 0.2)
			(type default)
		)
		(fill no)
		(layer "In16.Cu")
	)
	(gr_circle
		(center 192.461134 -15.781528)
		(end 193.350134 -15.781528)
		(stroke
			(width 0.2)
			(type default)
		)
		(fill no)
		(layer "In16.Cu")
	)
	(gr_circle
		(center 192.554606 -353.309174)
		(end 193.434716 -353.309174)
		(stroke
			(width 0.2)
			(type default)
		)
		(fill no)
		(layer "In16.Cu")
	)
	(gr_circle
		(center 192.689734 -13.106908)
		(end 193.578734 -13.106908)
		(stroke
			(width 0.2)
			(type default)
		)
		(fill no)
		(layer "In16.Cu")
	)
	(gr_circle
		(center 193.096134 -16.416528)
		(end 193.985134 -16.416528)
		(stroke
			(width 0.2)
			(type default)
		)
		(fill no)
		(layer "In16.Cu")
	)
	(gr_circle
		(center 193.096134 -15.781528)
		(end 193.985134 -15.781528)
		(stroke
			(width 0.2)
			(type default)
		)
		(fill no)
		(layer "In16.Cu")
	)
	(gr_circle
		(center 193.171826 -353.309174)
		(end 194.051936 -353.309174)
		(stroke
			(width 0.2)
			(type default)
		)
		(fill no)
		(layer "In16.Cu")
	)
	(gr_circle
		(center 193.28892 -352.563684)
		(end 194.17792 -352.563684)
		(stroke
			(width 0.2)
			(type default)
		)
		(fill no)
		(layer "In16.Cu")
	)
	(gr_circle
		(center 193.28892 -351.827084)
		(end 194.17792 -351.827084)
		(stroke
			(width 0.2)
			(type default)
		)
		(fill no)
		(layer "In16.Cu")
	)
	(gr_circle
		(center 193.731134 -15.781528)
		(end 194.620134 -15.781528)
		(stroke
			(width 0.2)
			(type default)
		)
		(fill no)
		(layer "In16.Cu")
	)
	(gr_circle
		(center 193.858134 -16.543528)
		(end 194.747134 -16.543528)
		(stroke
			(width 0.2)
			(type default)
		)
		(fill no)
		(layer "In16.Cu")
	)
	(gr_circle
		(center 193.873882 -354.918264)
		(end 194.762882 -354.918264)
		(stroke
			(width 0.2)
			(type default)
		)
		(fill no)
		(layer "In16.Cu")
	)
	(gr_circle
		(center 193.873882 -354.181664)
		(end 194.762882 -354.181664)
		(stroke
			(width 0.2)
			(type default)
		)
		(fill no)
		(layer "In16.Cu")
	)
	(gr_line
		(start 194.193922 -9.780016)
		(end 194.193922 -5.787898)
		(stroke
			(width 0.2)
			(type default)
		)
		(layer "In16.Cu")
	)
	(gr_arc
		(start 194.193922 -9.780016)
		(mid 194.928504 -11.55342)
		(end 196.701918 -12.288012)
		(stroke
			(width 0.2)
			(type default)
		)
		(layer "In16.Cu")
	)
	(gr_line
		(start 194.193922 -5.787898)
		(end 126.61011 -5.787898)
		(stroke
			(width 0.2)
			(type default)
		)
		(layer "In16.Cu")
	)
	(gr_circle
		(center 194.398646 -353.742244)
		(end 195.287646 -353.742244)
		(stroke
			(width 0.2)
			(type default)
		)
		(fill no)
		(layer "In16.Cu")
	)
	(gr_circle
		(center 194.424046 -354.504244)
		(end 195.313046 -354.504244)
		(stroke
			(width 0.2)
			(type default)
		)
		(fill no)
		(layer "In16.Cu")
	)
	(gr_line
		(start 194.496944 -441.481972)
		(end 194.496944 -441.17006)
		(stroke
			(width 0.2)
			(type default)
		)
		(layer "In16.Cu")
	)
	(gr_line
		(start 194.505072 -441.989972)
		(end 8.50011 -441.989972)
		(stroke
			(width 1.016)
			(type default)
		)
		(layer "In16.Cu")
	)
	(gr_arc
		(start 194.505072 -441.989972)
		(mid 194.858553 -441.843573)
		(end 195.004944 -441.4901)
		(stroke
			(width 1.016)
			(type default)
		)
		(layer "In16.Cu")
	)
	(gr_arc
		(start 194.701922 -9.780016)
		(mid 195.287707 -11.194227)
		(end 196.701918 -11.780012)
		(stroke
			(width 1.016)
			(type default)
		)
		(layer "In16.Cu")
	)
	(gr_arc
		(start 194.701922 -5.780024)
		(mid 194.555654 -5.42634)
		(end 194.20205 -5.279898)
		(stroke
			(width 1.016)
			(type default)
		)
		(layer "In16.Cu")
	)
	(gr_line
		(start 194.701922 -5.780024)
		(end 194.701922 -9.780016)
		(stroke
			(width 1.016)
			(type default)
		)
		(layer "In16.Cu")
	)
	(gr_circle
		(center 194.957446 -354.859844)
		(end 195.846446 -354.859844)
		(stroke
			(width 0.2)
			(type default)
		)
		(fill no)
		(layer "In16.Cu")
	)
	(gr_circle
		(center 194.957446 -354.123244)
		(end 195.846446 -354.123244)
		(stroke
			(width 0.2)
			(type default)
		)
		(fill no)
		(layer "In16.Cu")
	)
	(gr_circle
		(center 194.957446 -353.386644)
		(end 195.846446 -353.386644)
		(stroke
			(width 0.2)
			(type default)
		)
		(fill no)
		(layer "In16.Cu")
	)
	(gr_line
		(start 195.004944 -441.17006)
		(end 195.004944 -441.4901)
		(stroke
			(width 1.016)
			(type default)
		)
		(layer "In16.Cu")
	)
	(gr_line
		(start 195.270882 -412.015178)
		(end 188.720222 -412.015178)
		(stroke
			(width 0.635)
			(type default)
		)
		(layer "In16.Cu")
	)
	(gr_line
		(start 195.418964 -405.675846)
		(end 197.51167 -403.58314)
		(stroke
			(width 0.635)
			(type default)
		)
		(layer "In16.Cu")
	)
	(gr_arc
		(start 195.50507 -440.669934)
		(mid 195.151428 -440.816418)
		(end 195.004944 -441.17006)
		(stroke
			(width 1.016)
			(type default)
		)
		(layer "In16.Cu")
	)
	(gr_arc
		(start 195.50507 -440.161934)
		(mid 194.792223 -440.457215)
		(end 194.496944 -441.17006)
		(stroke
			(width 0.2)
			(type default)
		)
		(layer "In16.Cu")
	)
	(gr_line
		(start 195.50507 -440.161934)
		(end 276.314916 -440.161934)
		(stroke
			(width 0.2)
			(type default)
		)
		(layer "In16.Cu")
	)
	(gr_line
		(start 196.432424 -421.71112)
		(end 196.432424 -413.17672)
		(stroke
			(width 0.635)
			(type default)
		)
		(layer "In16.Cu")
	)
	(gr_line
		(start 196.432424 -421.71112)
		(end 205.73746 -431.016156)
		(stroke
			(width 0.635)
			(type default)
		)
		(layer "In16.Cu")
	)
	(gr_line
		(start 196.432424 -413.17672)
		(end 195.270882 -412.015178)
		(stroke
			(width 0.635)
			(type default)
		)
		(layer "In16.Cu")
	)
	(gr_line
		(start 196.701918 -11.780012)
		(end 221.30004 -11.780012)
		(stroke
			(width 1.016)
			(type default)
		)
		(layer "In16.Cu")
	)
	(gr_line
		(start 197.51167 -403.58314)
		(end 197.51167 -400.104356)
		(stroke
			(width 0.635)
			(type default)
		)
		(layer "In16.Cu")
	)
	(gr_line
		(start 197.51167 -400.104356)
		(end 197.764146 -399.85188)
		(stroke
			(width 0.635)
			(type default)
		)
		(layer "In16.Cu")
	)
	(gr_line
		(start 197.764146 -399.85188)
		(end 201.33818 -399.85188)
		(stroke
			(width 0.635)
			(type default)
		)
		(layer "In16.Cu")
	)
	(gr_circle
		(center 198.160386 -37.328094)
		(end 199.049386 -37.328094)
		(stroke
			(width 0.2)
			(type default)
		)
		(fill no)
		(layer "In16.Cu")
	)
	(gr_circle
		(center 198.486014 -30.133798)
		(end 199.375014 -30.133798)
		(stroke
			(width 0.2)
			(type default)
		)
		(fill no)
		(layer "In16.Cu")
	)
	(gr_circle
		(center 198.836026 -37.965634)
		(end 199.725026 -37.965634)
		(stroke
			(width 0.2)
			(type default)
		)
		(fill no)
		(layer "In16.Cu")
	)
	(gr_circle
		(center 199.121014 -30.133798)
		(end 200.010014 -30.133798)
		(stroke
			(width 0.2)
			(type default)
		)
		(fill no)
		(layer "In16.Cu")
	)
	(gr_circle
		(center 199.435974 -30.720538)
		(end 200.324974 -30.720538)
		(stroke
			(width 0.2)
			(type default)
		)
		(fill no)
		(layer "In16.Cu")
	)
	(gr_circle
		(center 199.756014 -30.133798)
		(end 200.645014 -30.133798)
		(stroke
			(width 0.2)
			(type default)
		)
		(fill no)
		(layer "In16.Cu")
	)
	(gr_circle
		(center 200.070974 -30.720538)
		(end 200.959974 -30.720538)
		(stroke
			(width 0.2)
			(type default)
		)
		(fill no)
		(layer "In16.Cu")
	)
	(gr_circle
		(center 200.33234 -378.160534)
		(end 201.22134 -378.160534)
		(stroke
			(width 0.2)
			(type default)
		)
		(fill no)
		(layer "In16.Cu")
	)
	(gr_circle
		(center 200.391014 -30.133798)
		(end 201.280014 -30.133798)
		(stroke
			(width 0.2)
			(type default)
		)
		(fill no)
		(layer "In16.Cu")
	)
	(gr_circle
		(center 200.705974 -30.720538)
		(end 201.594974 -30.720538)
		(stroke
			(width 0.2)
			(type default)
		)
		(fill no)
		(layer "In16.Cu")
	)
	(gr_line
		(start 201.33818 -399.85188)
		(end 201.59853 -400.11223)
		(stroke
			(width 0.635)
			(type default)
		)
		(layer "In16.Cu")
	)
	(gr_circle
		(center 201.340974 -30.720538)
		(end 202.229974 -30.720538)
		(stroke
			(width 0.2)
			(type default)
		)
		(fill no)
		(layer "In16.Cu")
	)
	(gr_line
		(start 201.59853 -403.575266)
		(end 201.811636 -403.788372)
		(stroke
			(width 0.635)
			(type default)
		)
		(layer "In16.Cu")
	)
	(gr_line
		(start 201.59853 -400.11223)
		(end 201.59853 -403.575266)
		(stroke
			(width 0.635)
			(type default)
		)
		(layer "In16.Cu")
	)
	(gr_circle
		(center 201.745342 -346.583)
		(end 202.634342 -346.583)
		(stroke
			(width 0.2)
			(type default)
		)
		(fill no)
		(layer "In16.Cu")
	)
	(gr_circle
		(center 201.745342 -345.821)
		(end 202.634342 -345.821)
		(stroke
			(width 0.2)
			(type default)
		)
		(fill no)
		(layer "In16.Cu")
	)
	(gr_circle
		(center 201.745342 -344.8304)
		(end 202.634342 -344.8304)
		(stroke
			(width 0.2)
			(type default)
		)
		(fill no)
		(layer "In16.Cu")
	)
	(gr_circle
		(center 201.745342 -344.0684)
		(end 202.634342 -344.0684)
		(stroke
			(width 0.2)
			(type default)
		)
		(fill no)
		(layer "In16.Cu")
	)
	(gr_line
		(start 201.811636 -406.668732)
		(end 203.461112 -408.318208)
		(stroke
			(width 0.635)
			(type default)
		)
		(layer "In16.Cu")
	)
	(gr_line
		(start 201.811636 -403.788372)
		(end 201.811636 -406.668732)
		(stroke
			(width 0.635)
			(type default)
		)
		(layer "In16.Cu")
	)
	(gr_line
		(start 203.461112 -408.318208)
		(end 205.948026 -408.318208)
		(stroke
			(width 0.635)
			(type default)
		)
		(layer "In16.Cu")
	)
	(gr_line
		(start 205.73746 -435.231032)
		(end 207.302608 -436.79618)
		(stroke
			(width 0.635)
			(type default)
		)
		(layer "In16.Cu")
	)
	(gr_line
		(start 205.73746 -431.016156)
		(end 205.73746 -435.231032)
		(stroke
			(width 0.635)
			(type default)
		)
		(layer "In16.Cu")
	)
	(gr_line
		(start 205.948026 -408.318208)
		(end 207.991202 -406.275032)
		(stroke
			(width 0.635)
			(type default)
		)
		(layer "In16.Cu")
	)
	(gr_line
		(start 207.302608 -436.79618)
		(end 229.074472 -436.79618)
		(stroke
			(width 0.635)
			(type default)
		)
		(layer "In16.Cu")
	)
	(gr_line
		(start 207.991202 -406.275032)
		(end 207.991202 -403.722586)
		(stroke
			(width 0.635)
			(type default)
		)
		(layer "In16.Cu")
	)
	(gr_line
		(start 207.991202 -403.722586)
		(end 208.17967 -403.534118)
		(stroke
			(width 0.635)
			(type default)
		)
		(layer "In16.Cu")
	)
	(gr_line
		(start 208.17967 -403.534118)
		(end 208.17967 -400.079464)
		(stroke
			(width 0.635)
			(type default)
		)
		(layer "In16.Cu")
	)
	(gr_line
		(start 208.17967 -400.079464)
		(end 208.42605 -399.833084)
		(stroke
			(width 0.635)
			(type default)
		)
		(layer "In16.Cu")
	)
	(gr_line
		(start 208.42605 -399.833084)
		(end 211.971128 -399.833084)
		(stroke
			(width 0.635)
			(type default)
		)
		(layer "In16.Cu")
	)
	(gr_circle
		(center 208.508854 -37.366448)
		(end 209.397854 -37.366448)
		(stroke
			(width 0.2)
			(type default)
		)
		(fill no)
		(layer "In16.Cu")
	)
	(gr_line
		(start 211.971128 -399.833084)
		(end 212.28304 -400.144996)
		(stroke
			(width 0.635)
			(type default)
		)
		(layer "In16.Cu")
	)
	(gr_line
		(start 212.28304 -403.63267)
		(end 212.414358 -403.763988)
		(stroke
			(width 0.635)
			(type default)
		)
		(layer "In16.Cu")
	)
	(gr_line
		(start 212.28304 -400.144996)
		(end 212.28304 -403.63267)
		(stroke
			(width 0.635)
			(type default)
		)
		(layer "In16.Cu")
	)
	(gr_line
		(start 212.414358 -406.410668)
		(end 214.347044 -408.343354)
		(stroke
			(width 0.635)
			(type default)
		)
		(layer "In16.Cu")
	)
	(gr_line
		(start 212.414358 -403.763988)
		(end 212.414358 -406.410668)
		(stroke
			(width 0.635)
			(type default)
		)
		(layer "In16.Cu")
	)
	(gr_line
		(start 214.347044 -408.343354)
		(end 216.541604 -408.343354)
		(stroke
			(width 0.635)
			(type default)
		)
		(layer "In16.Cu")
	)
	(gr_line
		(start 216.541604 -408.343354)
		(end 218.667584 -406.217374)
		(stroke
			(width 0.635)
			(type default)
		)
		(layer "In16.Cu")
	)
	(gr_line
		(start 218.667584 -406.217374)
		(end 218.667584 -403.755606)
		(stroke
			(width 0.635)
			(type default)
		)
		(layer "In16.Cu")
	)
	(gr_line
		(start 218.667584 -403.755606)
		(end 218.839796 -403.583394)
		(stroke
			(width 0.635)
			(type default)
		)
		(layer "In16.Cu")
	)
	(gr_line
		(start 218.839796 -403.583394)
		(end 218.839796 -400.095974)
		(stroke
			(width 0.635)
			(type default)
		)
		(layer "In16.Cu")
	)
	(gr_line
		(start 218.839796 -400.095974)
		(end 219.045282 -399.890488)
		(stroke
			(width 0.635)
			(type default)
		)
		(layer "In16.Cu")
	)
	(gr_line
		(start 219.045282 -399.890488)
		(end 222.709232 -399.890488)
		(stroke
			(width 0.635)
			(type default)
		)
		(layer "In16.Cu")
	)
	(gr_line
		(start 221.30004 -12.288012)
		(end 196.701918 -12.288012)
		(stroke
			(width 0.2)
			(type default)
		)
		(layer "In16.Cu")
	)
	(gr_line
		(start 222.709232 -399.890488)
		(end 222.906082 -400.087338)
		(stroke
			(width 0.635)
			(type default)
		)
		(layer "In16.Cu")
	)
	(gr_line
		(start 222.792036 -34.120074)
		(end 222.792036 -13.780008)
		(stroke
			(width 0.2)
			(type default)
		)
		(layer "In16.Cu")
	)
	(gr_arc
		(start 222.792036 -34.120074)
		(mid 223.526604 -35.8935)
		(end 225.300032 -36.62807)
		(stroke
			(width 0.2)
			(type default)
		)
		(layer "In16.Cu")
	)
	(gr_arc
		(start 222.792036 -13.780008)
		(mid 222.35504 -12.725008)
		(end 221.30004 -12.288012)
		(stroke
			(width 0.2)
			(type default)
		)
		(layer "In16.Cu")
	)
	(gr_line
		(start 222.906082 -403.607778)
		(end 223.099122 -403.800818)
		(stroke
			(width 0.635)
			(type default)
		)
		(layer "In16.Cu")
	)
	(gr_line
		(start 222.906082 -400.087338)
		(end 222.906082 -403.607778)
		(stroke
			(width 0.635)
			(type default)
		)
		(layer "In16.Cu")
	)
	(gr_line
		(start 223.099122 -406.414732)
		(end 224.990406 -408.306016)
		(stroke
			(width 0.635)
			(type default)
		)
		(layer "In16.Cu")
	)
	(gr_line
		(start 223.099122 -403.800818)
		(end 223.099122 -406.414732)
		(stroke
			(width 0.635)
			(type default)
		)
		(layer "In16.Cu")
	)
	(gr_arc
		(start 223.300036 -34.120074)
		(mid 223.885821 -35.534285)
		(end 225.300032 -36.12007)
		(stroke
			(width 1.016)
			(type default)
		)
		(layer "In16.Cu")
	)
	(gr_arc
		(start 223.300036 -13.780008)
		(mid 222.714256 -12.365778)
		(end 221.30004 -11.780012)
		(stroke
			(width 1.016)
			(type default)
		)
		(layer "In16.Cu")
	)
	(gr_line
		(start 223.300036 -13.780008)
		(end 223.300036 -34.120074)
		(stroke
			(width 1.016)
			(type default)
		)
		(layer "In16.Cu")
	)
	(gr_line
		(start 224.990406 -408.306016)
		(end 227.218748 -408.306016)
		(stroke
			(width 0.635)
			(type default)
		)
		(layer "In16.Cu")
	)
	(gr_line
		(start 225.300032 -36.12007)
		(end 256.800096 -36.12007)
		(stroke
			(width 1.016)
			(type default)
		)
		(layer "In16.Cu")
	)
	(gr_line
		(start 227.218748 -408.306016)
		(end 229.331774 -406.19299)
		(stroke
			(width 0.635)
			(type default)
		)
		(layer "In16.Cu")
	)
	(gr_line
		(start 229.074472 -436.79618)
		(end 229.997 -435.873652)
		(stroke
			(width 0.635)
			(type default)
		)
		(layer "In16.Cu")
	)
	(gr_line
		(start 229.331774 -406.19299)
		(end 229.331774 -403.768052)
		(stroke
			(width 0.635)
			(type default)
		)
		(layer "In16.Cu")
	)
	(gr_line
		(start 229.331774 -403.768052)
		(end 229.516178 -403.583648)
		(stroke
			(width 0.635)
			(type default)
		)
		(layer "In16.Cu")
	)
	(gr_line
		(start 229.516178 -403.583648)
		(end 229.516178 -400.11223)
		(stroke
			(width 0.635)
			(type default)
		)
		(layer "In16.Cu")
	)
	(gr_line
		(start 229.516178 -400.11223)
		(end 229.746302 -399.882106)
		(stroke
			(width 0.635)
			(type default)
		)
		(layer "In16.Cu")
	)
	(gr_line
		(start 229.746302 -399.882106)
		(end 233.352594 -399.882106)
		(stroke
			(width 0.635)
			(type default)
		)
		(layer "In16.Cu")
	)
	(gr_line
		(start 229.997 -422.180766)
		(end 229.997 -435.873652)
		(stroke
			(width 0.635)
			(type default)
		)
		(layer "In16.Cu")
	)
	(gr_line
		(start 233.352594 -399.882106)
		(end 233.574336 -400.103848)
		(stroke
			(width 0.635)
			(type default)
		)
		(layer "In16.Cu")
	)
	(gr_line
		(start 233.574336 -403.673564)
		(end 233.820462 -403.91969)
		(stroke
			(width 0.635)
			(type default)
		)
		(layer "In16.Cu")
	)
	(gr_line
		(start 233.574336 -400.103848)
		(end 233.574336 -403.673564)
		(stroke
			(width 0.635)
			(type default)
		)
		(layer "In16.Cu")
	)
	(gr_line
		(start 233.820462 -404.855172)
		(end 234.522264 -405.556974)
		(stroke
			(width 0.635)
			(type default)
		)
		(layer "In16.Cu")
	)
	(gr_line
		(start 233.820462 -403.91969)
		(end 233.820462 -404.855172)
		(stroke
			(width 0.635)
			(type default)
		)
		(layer "In16.Cu")
	)
	(gr_line
		(start 234.522264 -405.556974)
		(end 238.715804 -405.556974)
		(stroke
			(width 0.635)
			(type default)
		)
		(layer "In16.Cu")
	)
	(gr_line
		(start 234.897676 -417.28009)
		(end 229.997 -422.180766)
		(stroke
			(width 0.635)
			(type default)
		)
		(layer "In16.Cu")
	)
	(gr_circle
		(center 237.629954 -44.025566)
		(end 238.518954 -44.025566)
		(stroke
			(width 0.2)
			(type default)
		)
		(fill no)
		(layer "In16.Cu")
	)
	(gr_circle
		(center 237.640114 -44.716446)
		(end 238.529114 -44.716446)
		(stroke
			(width 0.2)
			(type default)
		)
		(fill no)
		(layer "In16.Cu")
	)
	(gr_circle
		(center 238.292894 -44.802806)
		(end 239.181894 -44.802806)
		(stroke
			(width 0.2)
			(type default)
		)
		(fill no)
		(layer "In16.Cu")
	)
	(gr_circle
		(center 238.292894 -44.040806)
		(end 239.181894 -44.040806)
		(stroke
			(width 0.2)
			(type default)
		)
		(fill no)
		(layer "In16.Cu")
	)
	(gr_arc
		(start 238.695992 -393.003532)
		(mid 238.724179 -393.144586)
		(end 238.804196 -393.264136)
		(stroke
			(width 0.635)
			(type default)
		)
		(layer "In16.Cu")
	)
	(gr_line
		(start 238.695992 -384.337306)
		(end 238.695992 -393.003532)
		(stroke
			(width 0.635)
			(type default)
		)
		(layer "In16.Cu")
	)
	(gr_line
		(start 238.715804 -405.556974)
		(end 238.882682 -405.390096)
		(stroke
			(width 0.635)
			(type default)
		)
		(layer "In16.Cu")
	)
	(gr_line
		(start 238.752126 -384.198876)
		(end 238.695992 -384.337306)
		(stroke
			(width 0.635)
			(type default)
		)
		(layer "In16.Cu")
	)
	(gr_line
		(start 238.804196 -393.264136)
		(end 239.027716 -393.487656)
		(stroke
			(width 0.635)
			(type default)
		)
		(layer "In16.Cu")
	)
	(gr_line
		(start 238.805974 -384.146806)
		(end 238.752126 -384.198876)
		(stroke
			(width 0.635)
			(type default)
		)
		(layer "In16.Cu")
	)
	(gr_line
		(start 238.882682 -405.390096)
		(end 238.882682 -394.210794)
		(stroke
			(width 0.635)
			(type default)
		)
		(layer "In16.Cu")
	)
	(gr_line
		(start 238.882682 -394.210794)
		(end 238.882682 -394.001498)
		(stroke
			(width 0.635)
			(type default)
		)
		(layer "In16.Cu")
	)
	(gr_line
		(start 238.882682 -394.210794)
		(end 279.615392 -394.210794)
		(stroke
			(width 0.635)
			(type default)
		)
		(layer "In16.Cu")
	)
	(gr_line
		(start 238.882682 -394.001498)
		(end 239.28832 -393.59586)
		(stroke
			(width 0.635)
			(type default)
		)
		(layer "In16.Cu")
	)
	(gr_circle
		(center 238.943134 -44.802806)
		(end 239.832134 -44.802806)
		(stroke
			(width 0.2)
			(type default)
		)
		(fill no)
		(layer "In16.Cu")
	)
	(gr_circle
		(center 238.943134 -44.040806)
		(end 239.832134 -44.040806)
		(stroke
			(width 0.2)
			(type default)
		)
		(fill no)
		(layer "In16.Cu")
	)
	(gr_arc
		(start 239.027716 -393.487656)
		(mid 239.147257 -393.567682)
		(end 239.28832 -393.59586)
		(stroke
			(width 0.635)
			(type default)
		)
		(layer "In16.Cu")
	)
	(gr_line
		(start 239.281716 -383.671064)
		(end 238.805974 -384.146806)
		(stroke
			(width 0.635)
			(type default)
		)
		(layer "In16.Cu")
	)
	(gr_line
		(start 239.28832 -393.59586)
		(end 273.155664 -393.59586)
		(stroke
			(width 0.635)
			(type default)
		)
		(layer "In16.Cu")
	)
	(gr_arc
		(start 239.54232 -383.56286)
		(mid 239.401266 -383.591047)
		(end 239.281716 -383.671064)
		(stroke
			(width 0.635)
			(type default)
		)
		(layer "In16.Cu")
	)
	(gr_circle
		(center 239.578134 -44.802806)
		(end 240.467134 -44.802806)
		(stroke
			(width 0.2)
			(type default)
		)
		(fill no)
		(layer "In16.Cu")
	)
	(gr_circle
		(center 239.578134 -44.040806)
		(end 240.467134 -44.040806)
		(stroke
			(width 0.2)
			(type default)
		)
		(fill no)
		(layer "In16.Cu")
	)
	(gr_circle
		(center 240.213134 -44.802806)
		(end 241.102134 -44.802806)
		(stroke
			(width 0.2)
			(type default)
		)
		(fill no)
		(layer "In16.Cu")
	)
	(gr_circle
		(center 240.213134 -44.040806)
		(end 241.102134 -44.040806)
		(stroke
			(width 0.2)
			(type default)
		)
		(fill no)
		(layer "In16.Cu")
	)
	(gr_circle
		(center 240.893854 -44.830746)
		(end 241.782854 -44.830746)
		(stroke
			(width 0.2)
			(type default)
		)
		(fill no)
		(layer "In16.Cu")
	)
	(gr_circle
		(center 244.518942 -43.246802)
		(end 245.407942 -43.246802)
		(stroke
			(width 0.2)
			(type default)
		)
		(fill no)
		(layer "In16.Cu")
	)
	(gr_circle
		(center 244.518942 -42.611802)
		(end 245.407942 -42.611802)
		(stroke
			(width 0.2)
			(type default)
		)
		(fill no)
		(layer "In16.Cu")
	)
	(gr_circle
		(center 245.857522 -52.022502)
		(end 246.746522 -52.022502)
		(stroke
			(width 0.2)
			(type default)
		)
		(fill no)
		(layer "In16.Cu")
	)
	(gr_circle
		(center 246.873522 -52.022502)
		(end 247.762522 -52.022502)
		(stroke
			(width 0.2)
			(type default)
		)
		(fill no)
		(layer "In16.Cu")
	)
	(gr_circle
		(center 247.825514 -40.94988)
		(end 248.714514 -40.94988)
		(stroke
			(width 0.2)
			(type default)
		)
		(fill no)
		(layer "In16.Cu")
	)
	(gr_circle
		(center 247.840246 -51.320446)
		(end 248.729246 -51.320446)
		(stroke
			(width 0.2)
			(type default)
		)
		(fill no)
		(layer "In16.Cu")
	)
	(gr_circle
		(center 248.214134 -52.171346)
		(end 249.103134 -52.171346)
		(stroke
			(width 0.2)
			(type default)
		)
		(fill no)
		(layer "In16.Cu")
	)
	(gr_circle
		(center 248.881646 -51.320446)
		(end 249.770646 -51.320446)
		(stroke
			(width 0.2)
			(type default)
		)
		(fill no)
		(layer "In16.Cu")
	)
	(gr_circle
		(center 249.202448 -40.945816)
		(end 250.091448 -40.945816)
		(stroke
			(width 0.2)
			(type default)
		)
		(fill no)
		(layer "In16.Cu")
	)
	(gr_circle
		(center 249.905266 -51.349148)
		(end 250.794266 -51.349148)
		(stroke
			(width 0.2)
			(type default)
		)
		(fill no)
		(layer "In16.Cu")
	)
	(gr_circle
		(center 250.449334 -49.555146)
		(end 251.338334 -49.555146)
		(stroke
			(width 0.2)
			(type default)
		)
		(fill no)
		(layer "In16.Cu")
	)
	(gr_circle
		(center 250.779534 -52.222146)
		(end 251.668534 -52.222146)
		(stroke
			(width 0.2)
			(type default)
		)
		(fill no)
		(layer "In16.Cu")
	)
	(gr_circle
		(center 250.779534 -51.333146)
		(end 251.668534 -51.333146)
		(stroke
			(width 0.2)
			(type default)
		)
		(fill no)
		(layer "In16.Cu")
	)
	(gr_circle
		(center 250.779534 -50.444146)
		(end 251.668534 -50.444146)
		(stroke
			(width 0.2)
			(type default)
		)
		(fill no)
		(layer "In16.Cu")
	)
	(gr_circle
		(center 251.516134 -52.501546)
		(end 252.405134 -52.501546)
		(stroke
			(width 0.2)
			(type default)
		)
		(fill no)
		(layer "In16.Cu")
	)
	(gr_circle
		(center 251.516134 -51.612546)
		(end 252.405134 -51.612546)
		(stroke
			(width 0.2)
			(type default)
		)
		(fill no)
		(layer "In16.Cu")
	)
	(gr_circle
		(center 251.516134 -50.723546)
		(end 252.405134 -50.723546)
		(stroke
			(width 0.2)
			(type default)
		)
		(fill no)
		(layer "In16.Cu")
	)
	(gr_circle
		(center 255.347978 -39.380922)
		(end 256.236978 -39.380922)
		(stroke
			(width 0.2)
			(type default)
		)
		(fill no)
		(layer "In16.Cu")
	)
	(gr_line
		(start 256.800096 -36.62807)
		(end 225.300032 -36.62807)
		(stroke
			(width 0.2)
			(type default)
		)
		(layer "In16.Cu")
	)
	(gr_arc
		(start 256.800096 -36.62807)
		(mid 258.57351 -35.893495)
		(end 259.308092 -34.120074)
		(stroke
			(width 0.2)
			(type default)
		)
		(layer "In16.Cu")
	)
	(gr_arc
		(start 256.800096 -36.12007)
		(mid 258.214307 -35.534285)
		(end 258.800092 -34.120074)
		(stroke
			(width 1.016)
			(type default)
		)
		(layer "In16.Cu")
	)
	(gr_line
		(start 258.800092 -34.120074)
		(end 258.800092 -13.780008)
		(stroke
			(width 1.016)
			(type default)
		)
		(layer "In16.Cu")
	)
	(gr_line
		(start 259.308092 -13.780008)
		(end 259.308092 -34.120074)
		(stroke
			(width 0.2)
			(type default)
		)
		(layer "In16.Cu")
	)
	(gr_arc
		(start 260.800088 -12.288012)
		(mid 259.745088 -12.725008)
		(end 259.308092 -13.780008)
		(stroke
			(width 0.2)
			(type default)
		)
		(layer "In16.Cu")
	)
	(gr_arc
		(start 260.800088 -11.780012)
		(mid 259.385888 -12.365802)
		(end 258.800092 -13.780008)
		(stroke
			(width 1.016)
			(type default)
		)
		(layer "In16.Cu")
	)
	(gr_line
		(start 260.800088 -11.780012)
		(end 385.601972 -11.780012)
		(stroke
			(width 1.016)
			(type default)
		)
		(layer "In16.Cu")
	)
	(gr_line
		(start 272.19021 -417.28009)
		(end 234.897676 -417.28009)
		(stroke
			(width 0.635)
			(type default)
		)
		(layer "In16.Cu")
	)
	(gr_arc
		(start 273.155664 -393.59586)
		(mid 273.296718 -393.567673)
		(end 273.416268 -393.487656)
		(stroke
			(width 0.635)
			(type default)
		)
		(layer "In16.Cu")
	)
	(gr_line
		(start 273.33067 -394.041884)
		(end 279.547066 -394.041884)
		(stroke
			(width 0.635)
			(type default)
		)
		(layer "In16.Cu")
	)
	(gr_line
		(start 273.416268 -393.487656)
		(end 273.893788 -393.010136)
		(stroke
			(width 0.635)
			(type default)
		)
		(layer "In16.Cu")
	)
	(gr_line
		(start 273.481546 -383.56286)
		(end 239.54232 -383.56286)
		(stroke
			(width 0.635)
			(type default)
		)
		(layer "In16.Cu")
	)
	(gr_line
		(start 273.619976 -383.618994)
		(end 273.481546 -383.56286)
		(stroke
			(width 0.635)
			(type default)
		)
		(layer "In16.Cu")
	)
	(gr_line
		(start 273.672046 -383.672842)
		(end 273.619976 -383.618994)
		(stroke
			(width 0.635)
			(type default)
		)
		(layer "In16.Cu")
	)
	(gr_arc
		(start 273.893788 -393.010136)
		(mid 273.97387 -392.890613)
		(end 274.001992 -392.749532)
		(stroke
			(width 0.635)
			(type default)
		)
		(layer "In16.Cu")
	)
	(gr_line
		(start 273.893788 -383.894584)
		(end 273.672046 -383.672842)
		(stroke
			(width 0.635)
			(type default)
		)
		(layer "In16.Cu")
	)
	(gr_line
		(start 274.001992 -392.749532)
		(end 274.001992 -384.155188)
		(stroke
			(width 0.635)
			(type default)
		)
		(layer "In16.Cu")
	)
	(gr_arc
		(start 274.001992 -384.155188)
		(mid 273.973805 -384.014134)
		(end 273.893788 -383.894584)
		(stroke
			(width 0.635)
			(type default)
		)
		(layer "In16.Cu")
	)
	(gr_line
		(start 274.123404 -393.697206)
		(end 279.133554 -393.697206)
		(stroke
			(width 0.635)
			(type default)
		)
		(layer "In16.Cu")
	)
	(gr_line
		(start 274.433792 -392.938762)
		(end 273.33067 -394.041884)
		(stroke
			(width 0.635)
			(type default)
		)
		(layer "In16.Cu")
	)
	(gr_line
		(start 274.433792 -392.938762)
		(end 274.50288 -392.869674)
		(stroke
			(width 0.635)
			(type default)
		)
		(layer "In16.Cu")
	)
	(gr_line
		(start 274.433792 -392.317732)
		(end 274.67052 -392.55446)
		(stroke
			(width 0.635)
			(type default)
		)
		(layer "In16.Cu")
	)
	(gr_line
		(start 274.433792 -384.002788)
		(end 274.433792 -392.938762)
		(stroke
			(width 0.635)
			(type default)
		)
		(layer "In16.Cu")
	)
	(gr_line
		(start 274.433792 -384.002788)
		(end 274.433792 -392.317732)
		(stroke
			(width 0.635)
			(type default)
		)
		(layer "In16.Cu")
	)
	(gr_line
		(start 274.50288 -392.869674)
		(end 279.110694 -392.869674)
		(stroke
			(width 0.635)
			(type default)
		)
		(layer "In16.Cu")
	)
	(gr_line
		(start 274.732496 -393.237466)
		(end 274.433792 -392.938762)
		(stroke
			(width 0.635)
			(type default)
		)
		(layer "In16.Cu")
	)
	(gr_line
		(start 274.778724 -392.605514)
		(end 274.192746 -392.019536)
		(stroke
			(width 0.635)
			(type default)
		)
		(layer "In16.Cu")
	)
	(gr_line
		(start 274.87372 -383.56286)
		(end 274.433792 -384.002788)
		(stroke
			(width 0.635)
			(type default)
		)
		(layer "In16.Cu")
	)
	(gr_circle
		(center 276.112986 -348.704662)
		(end 276.993096 -348.704662)
		(stroke
			(width 0.2)
			(type default)
		)
		(fill no)
		(layer "In16.Cu")
	)
	(gr_line
		(start 276.314916 -440.669934)
		(end 195.50507 -440.669934)
		(stroke
			(width 1.016)
			(type default)
		)
		(layer "In16.Cu")
	)
	(gr_circle
		(center 276.730206 -348.704662)
		(end 277.610316 -348.704662)
		(stroke
			(width 0.2)
			(type default)
		)
		(fill no)
		(layer "In16.Cu")
	)
	(gr_line
		(start 276.815042 -441.4901)
		(end 276.815042 -441.17006)
		(stroke
			(width 1.016)
			(type default)
		)
		(layer "In16.Cu")
	)
	(gr_arc
		(start 276.815042 -441.4901)
		(mid 276.961452 -441.843558)
		(end 277.314914 -441.989972)
		(stroke
			(width 1.016)
			(type default)
		)
		(layer "In16.Cu")
	)
	(gr_arc
		(start 276.815042 -441.17006)
		(mid 276.668558 -440.816418)
		(end 276.314916 -440.669934)
		(stroke
			(width 1.016)
			(type default)
		)
		(layer "In16.Cu")
	)
	(gr_line
		(start 277.323042 -441.481972)
		(end 463.300064 -441.481972)
		(stroke
			(width 0.2)
			(type default)
		)
		(layer "In16.Cu")
	)
	(gr_arc
		(start 277.323042 -441.17006)
		(mid 277.027756 -440.457227)
		(end 276.314916 -440.161934)
		(stroke
			(width 0.2)
			(type default)
		)
		(layer "In16.Cu")
	)
	(gr_line
		(start 277.323042 -441.17006)
		(end 277.323042 -441.481972)
		(stroke
			(width 0.2)
			(type default)
		)
		(layer "In16.Cu")
	)
	(gr_circle
		(center 277.347426 -348.704662)
		(end 278.227536 -348.704662)
		(stroke
			(width 0.2)
			(type default)
		)
		(fill no)
		(layer "In16.Cu")
	)
	(gr_circle
		(center 277.593806 -348.025212)
		(end 278.482806 -348.025212)
		(stroke
			(width 0.2)
			(type default)
		)
		(fill no)
		(layer "In16.Cu")
	)
	(gr_circle
		(center 277.593806 -347.288612)
		(end 278.482806 -347.288612)
		(stroke
			(width 0.2)
			(type default)
		)
		(fill no)
		(layer "In16.Cu")
	)
	(gr_circle
		(center 278.049482 -350.313752)
		(end 278.938482 -350.313752)
		(stroke
			(width 0.2)
			(type default)
		)
		(fill no)
		(layer "In16.Cu")
	)
	(gr_circle
		(center 278.049482 -349.577152)
		(end 278.938482 -349.577152)
		(stroke
			(width 0.2)
			(type default)
		)
		(fill no)
		(layer "In16.Cu")
	)
	(gr_circle
		(center 278.574246 -349.137732)
		(end 279.463246 -349.137732)
		(stroke
			(width 0.2)
			(type default)
		)
		(fill no)
		(layer "In16.Cu")
	)
	(gr_circle
		(center 278.599646 -349.899732)
		(end 279.488646 -349.899732)
		(stroke
			(width 0.2)
			(type default)
		)
		(fill no)
		(layer "In16.Cu")
	)
	(gr_line
		(start 278.892508 -393.237466)
		(end 274.732496 -393.237466)
		(stroke
			(width 0.635)
			(type default)
		)
		(layer "In16.Cu")
	)
	(gr_line
		(start 279.110694 -392.869674)
		(end 279.351994 -392.628374)
		(stroke
			(width 0.635)
			(type default)
		)
		(layer "In16.Cu")
	)
	(gr_circle
		(center 279.133046 -350.255332)
		(end 280.022046 -350.255332)
		(stroke
			(width 0.2)
			(type default)
		)
		(fill no)
		(layer "In16.Cu")
	)
	(gr_circle
		(center 279.133046 -349.518732)
		(end 280.022046 -349.518732)
		(stroke
			(width 0.2)
			(type default)
		)
		(fill no)
		(layer "In16.Cu")
	)
	(gr_circle
		(center 279.133046 -348.782132)
		(end 280.022046 -348.782132)
		(stroke
			(width 0.2)
			(type default)
		)
		(fill no)
		(layer "In16.Cu")
	)
	(gr_line
		(start 279.133554 -393.697206)
		(end 279.983946 -392.846814)
		(stroke
			(width 0.635)
			(type default)
		)
		(layer "In16.Cu")
	)
	(gr_line
		(start 279.329134 -392.605514)
		(end 274.778724 -392.605514)
		(stroke
			(width 0.635)
			(type default)
		)
		(layer "In16.Cu")
	)
	(gr_line
		(start 279.351994 -392.628374)
		(end 279.329134 -392.605514)
		(stroke
			(width 0.635)
			(type default)
		)
		(layer "In16.Cu")
	)
	(gr_line
		(start 279.547066 -394.041884)
		(end 280.477976 -393.110974)
		(stroke
			(width 0.635)
			(type default)
		)
		(layer "In16.Cu")
	)
	(gr_line
		(start 279.616408 -392.513566)
		(end 278.892508 -393.237466)
		(stroke
			(width 0.635)
			(type default)
		)
		(layer "In16.Cu")
	)
	(gr_line
		(start 279.616408 -383.780538)
		(end 279.616408 -392.513566)
		(stroke
			(width 0.635)
			(type default)
		)
		(layer "In16.Cu")
	)
	(gr_line
		(start 279.834086 -383.56286)
		(end 279.616408 -383.780538)
		(stroke
			(width 0.635)
			(type default)
		)
		(layer "In16.Cu")
	)
	(gr_arc
		(start 279.875996 -394.318998)
		(mid 279.756473 -394.238916)
		(end 279.615392 -394.210794)
		(stroke
			(width 0.635)
			(type default)
		)
		(layer "In16.Cu")
	)
	(gr_line
		(start 279.983946 -392.846814)
		(end 279.983946 -383.781046)
		(stroke
			(width 0.635)
			(type default)
		)
		(layer "In16.Cu")
	)
	(gr_line
		(start 279.983946 -383.781046)
		(end 280.202132 -383.56286)
		(stroke
			(width 0.635)
			(type default)
		)
		(layer "In16.Cu")
	)
	(gr_line
		(start 280.202132 -383.56286)
		(end 274.87372 -383.56286)
		(stroke
			(width 0.635)
			(type default)
		)
		(layer "In16.Cu")
	)
	(gr_line
		(start 280.202132 -383.56286)
		(end 279.834086 -383.56286)
		(stroke
			(width 0.635)
			(type default)
		)
		(layer "In16.Cu")
	)
	(gr_line
		(start 280.259536 -394.702538)
		(end 279.875996 -394.318998)
		(stroke
			(width 0.635)
			(type default)
		)
		(layer "In16.Cu")
	)
	(gr_line
		(start 280.36774 -409.10256)
		(end 272.19021 -417.28009)
		(stroke
			(width 0.635)
			(type default)
		)
		(layer "In16.Cu")
	)
	(gr_arc
		(start 280.36774 -394.963142)
		(mid 280.339553 -394.822088)
		(end 280.259536 -394.702538)
		(stroke
			(width 0.635)
			(type default)
		)
		(layer "In16.Cu")
	)
	(gr_line
		(start 280.36774 -394.963142)
		(end 280.36774 -409.10256)
		(stroke
			(width 0.635)
			(type default)
		)
		(layer "In16.Cu")
	)
	(gr_line
		(start 280.477976 -393.110974)
		(end 280.477976 -383.838704)
		(stroke
			(width 0.635)
			(type default)
		)
		(layer "In16.Cu")
	)
	(gr_line
		(start 280.477976 -383.838704)
		(end 280.202132 -383.56286)
		(stroke
			(width 0.635)
			(type default)
		)
		(layer "In16.Cu")
	)
	(gr_line
		(start 280.537412 -392.55446)
		(end 274.67052 -392.55446)
		(stroke
			(width 0.635)
			(type default)
		)
		(layer "In16.Cu")
	)
	(gr_line
		(start 280.537412 -392.55446)
		(end 280.9113 -392.180572)
		(stroke
			(width 0.635)
			(type default)
		)
		(layer "In16.Cu")
	)
	(gr_line
		(start 280.9113 -392.180572)
		(end 280.9113 -384.272028)
		(stroke
			(width 0.635)
			(type default)
		)
		(layer "In16.Cu")
	)
	(gr_line
		(start 280.9113 -384.272028)
		(end 280.202132 -383.56286)
		(stroke
			(width 0.635)
			(type default)
		)
		(layer "In16.Cu")
	)
	(gr_circle
		(center 284.393386 -348.704662)
		(end 285.273496 -348.704662)
		(stroke
			(width 0.2)
			(type default)
		)
		(fill no)
		(layer "In16.Cu")
	)
	(gr_circle
		(center 285.010606 -348.704662)
		(end 285.890716 -348.704662)
		(stroke
			(width 0.2)
			(type default)
		)
		(fill no)
		(layer "In16.Cu")
	)
	(gr_circle
		(center 285.627826 -348.704662)
		(end 286.507936 -348.704662)
		(stroke
			(width 0.2)
			(type default)
		)
		(fill no)
		(layer "In16.Cu")
	)
	(gr_circle
		(center 285.869126 -347.982032)
		(end 286.758126 -347.982032)
		(stroke
			(width 0.2)
			(type default)
		)
		(fill no)
		(layer "In16.Cu")
	)
	(gr_circle
		(center 285.869126 -347.245432)
		(end 286.758126 -347.245432)
		(stroke
			(width 0.2)
			(type default)
		)
		(fill no)
		(layer "In16.Cu")
	)
	(gr_circle
		(center 286.329882 -350.313752)
		(end 287.218882 -350.313752)
		(stroke
			(width 0.2)
			(type default)
		)
		(fill no)
		(layer "In16.Cu")
	)
	(gr_circle
		(center 286.329882 -349.577152)
		(end 287.218882 -349.577152)
		(stroke
			(width 0.2)
			(type default)
		)
		(fill no)
		(layer "In16.Cu")
	)
	(gr_circle
		(center 286.36595 -355.279198)
		(end 287.25495 -355.279198)
		(stroke
			(width 0.2)
			(type default)
		)
		(fill no)
		(layer "In16.Cu")
	)
	(gr_circle
		(center 286.37611 -356.584758)
		(end 287.26511 -356.584758)
		(stroke
			(width 0.2)
			(type default)
		)
		(fill no)
		(layer "In16.Cu")
	)
	(gr_circle
		(center 286.37611 -355.949758)
		(end 287.26511 -355.949758)
		(stroke
			(width 0.2)
			(type default)
		)
		(fill no)
		(layer "In16.Cu")
	)
	(gr_circle
		(center 286.854646 -349.137732)
		(end 287.743646 -349.137732)
		(stroke
			(width 0.2)
			(type default)
		)
		(fill no)
		(layer "In16.Cu")
	)
	(gr_circle
		(center 286.880046 -349.899732)
		(end 287.769046 -349.899732)
		(stroke
			(width 0.2)
			(type default)
		)
		(fill no)
		(layer "In16.Cu")
	)
	(gr_circle
		(center 287.00095 -355.279198)
		(end 287.88995 -355.279198)
		(stroke
			(width 0.2)
			(type default)
		)
		(fill no)
		(layer "In16.Cu")
	)
	(gr_circle
		(center 287.01111 -356.584758)
		(end 287.90011 -356.584758)
		(stroke
			(width 0.2)
			(type default)
		)
		(fill no)
		(layer "In16.Cu")
	)
	(gr_circle
		(center 287.01111 -355.949758)
		(end 287.90011 -355.949758)
		(stroke
			(width 0.2)
			(type default)
		)
		(fill no)
		(layer "In16.Cu")
	)
	(gr_circle
		(center 287.413446 -350.255332)
		(end 288.302446 -350.255332)
		(stroke
			(width 0.2)
			(type default)
		)
		(fill no)
		(layer "In16.Cu")
	)
	(gr_circle
		(center 287.413446 -349.518732)
		(end 288.302446 -349.518732)
		(stroke
			(width 0.2)
			(type default)
		)
		(fill no)
		(layer "In16.Cu")
	)
	(gr_circle
		(center 287.413446 -348.782132)
		(end 288.302446 -348.782132)
		(stroke
			(width 0.2)
			(type default)
		)
		(fill no)
		(layer "In16.Cu")
	)
	(gr_circle
		(center 287.63595 -355.279198)
		(end 288.52495 -355.279198)
		(stroke
			(width 0.2)
			(type default)
		)
		(fill no)
		(layer "In16.Cu")
	)
	(gr_circle
		(center 287.64611 -356.584758)
		(end 288.53511 -356.584758)
		(stroke
			(width 0.2)
			(type default)
		)
		(fill no)
		(layer "In16.Cu")
	)
	(gr_circle
		(center 287.64611 -355.949758)
		(end 288.53511 -355.949758)
		(stroke
			(width 0.2)
			(type default)
		)
		(fill no)
		(layer "In16.Cu")
	)
	(gr_circle
		(center 288.27095 -355.279198)
		(end 289.15995 -355.279198)
		(stroke
			(width 0.2)
			(type default)
		)
		(fill no)
		(layer "In16.Cu")
	)
	(gr_circle
		(center 288.28111 -356.584758)
		(end 289.17011 -356.584758)
		(stroke
			(width 0.2)
			(type default)
		)
		(fill no)
		(layer "In16.Cu")
	)
	(gr_circle
		(center 288.28111 -355.949758)
		(end 289.17011 -355.949758)
		(stroke
			(width 0.2)
			(type default)
		)
		(fill no)
		(layer "In16.Cu")
	)
	(gr_circle
		(center 288.90595 -355.279198)
		(end 289.79495 -355.279198)
		(stroke
			(width 0.2)
			(type default)
		)
		(fill no)
		(layer "In16.Cu")
	)
	(gr_circle
		(center 288.91611 -356.584758)
		(end 289.80511 -356.584758)
		(stroke
			(width 0.2)
			(type default)
		)
		(fill no)
		(layer "In16.Cu")
	)
	(gr_circle
		(center 288.91611 -355.949758)
		(end 289.80511 -355.949758)
		(stroke
			(width 0.2)
			(type default)
		)
		(fill no)
		(layer "In16.Cu")
	)
	(gr_circle
		(center 292.699186 -348.704662)
		(end 293.579296 -348.704662)
		(stroke
			(width 0.2)
			(type default)
		)
		(fill no)
		(layer "In16.Cu")
	)
	(gr_circle
		(center 293.316406 -348.704662)
		(end 294.196516 -348.704662)
		(stroke
			(width 0.2)
			(type default)
		)
		(fill no)
		(layer "In16.Cu")
	)
	(gr_circle
		(center 293.933626 -348.704662)
		(end 294.813736 -348.704662)
		(stroke
			(width 0.2)
			(type default)
		)
		(fill no)
		(layer "In16.Cu")
	)
	(gr_circle
		(center 294.146986 -347.959172)
		(end 295.035986 -347.959172)
		(stroke
			(width 0.2)
			(type default)
		)
		(fill no)
		(layer "In16.Cu")
	)
	(gr_circle
		(center 294.146986 -347.222572)
		(end 295.035986 -347.222572)
		(stroke
			(width 0.2)
			(type default)
		)
		(fill no)
		(layer "In16.Cu")
	)
	(gr_circle
		(center 294.635682 -350.313752)
		(end 295.524682 -350.313752)
		(stroke
			(width 0.2)
			(type default)
		)
		(fill no)
		(layer "In16.Cu")
	)
	(gr_circle
		(center 294.635682 -349.577152)
		(end 295.524682 -349.577152)
		(stroke
			(width 0.2)
			(type default)
		)
		(fill no)
		(layer "In16.Cu")
	)
	(gr_circle
		(center 295.160446 -349.137732)
		(end 296.049446 -349.137732)
		(stroke
			(width 0.2)
			(type default)
		)
		(fill no)
		(layer "In16.Cu")
	)
	(gr_circle
		(center 295.185846 -349.899732)
		(end 296.074846 -349.899732)
		(stroke
			(width 0.2)
			(type default)
		)
		(fill no)
		(layer "In16.Cu")
	)
	(gr_circle
		(center 295.719246 -350.255332)
		(end 296.608246 -350.255332)
		(stroke
			(width 0.2)
			(type default)
		)
		(fill no)
		(layer "In16.Cu")
	)
	(gr_circle
		(center 295.719246 -349.518732)
		(end 296.608246 -349.518732)
		(stroke
			(width 0.2)
			(type default)
		)
		(fill no)
		(layer "In16.Cu")
	)
	(gr_circle
		(center 295.719246 -348.782132)
		(end 296.608246 -348.782132)
		(stroke
			(width 0.2)
			(type default)
		)
		(fill no)
		(layer "In16.Cu")
	)
	(gr_circle
		(center 296.29989 -358.769666)
		(end 297.69689 -358.769666)
		(stroke
			(width 0.2)
			(type default)
		)
		(fill no)
		(layer "In16.Cu")
	)
	(gr_circle
		(center 301.055786 -348.704662)
		(end 301.935896 -348.704662)
		(stroke
			(width 0.2)
			(type default)
		)
		(fill no)
		(layer "In16.Cu")
	)
	(gr_circle
		(center 301.673006 -348.704662)
		(end 302.553116 -348.704662)
		(stroke
			(width 0.2)
			(type default)
		)
		(fill no)
		(layer "In16.Cu")
	)
	(gr_circle
		(center 302.290226 -348.704662)
		(end 303.170336 -348.704662)
		(stroke
			(width 0.2)
			(type default)
		)
		(fill no)
		(layer "In16.Cu")
	)
	(gr_circle
		(center 302.526446 -348.002352)
		(end 303.415446 -348.002352)
		(stroke
			(width 0.2)
			(type default)
		)
		(fill no)
		(layer "In16.Cu")
	)
	(gr_circle
		(center 302.526446 -347.265752)
		(end 303.415446 -347.265752)
		(stroke
			(width 0.2)
			(type default)
		)
		(fill no)
		(layer "In16.Cu")
	)
	(gr_circle
		(center 302.992282 -350.313752)
		(end 303.881282 -350.313752)
		(stroke
			(width 0.2)
			(type default)
		)
		(fill no)
		(layer "In16.Cu")
	)
	(gr_circle
		(center 302.992282 -349.577152)
		(end 303.881282 -349.577152)
		(stroke
			(width 0.2)
			(type default)
		)
		(fill no)
		(layer "In16.Cu")
	)
	(gr_circle
		(center 303.517046 -349.137732)
		(end 304.406046 -349.137732)
		(stroke
			(width 0.2)
			(type default)
		)
		(fill no)
		(layer "In16.Cu")
	)
	(gr_circle
		(center 303.542446 -349.899732)
		(end 304.431446 -349.899732)
		(stroke
			(width 0.2)
			(type default)
		)
		(fill no)
		(layer "In16.Cu")
	)
	(gr_circle
		(center 304.075846 -350.255332)
		(end 304.964846 -350.255332)
		(stroke
			(width 0.2)
			(type default)
		)
		(fill no)
		(layer "In16.Cu")
	)
	(gr_circle
		(center 304.075846 -349.518732)
		(end 304.964846 -349.518732)
		(stroke
			(width 0.2)
			(type default)
		)
		(fill no)
		(layer "In16.Cu")
	)
	(gr_circle
		(center 304.075846 -348.782132)
		(end 304.964846 -348.782132)
		(stroke
			(width 0.2)
			(type default)
		)
		(fill no)
		(layer "In16.Cu")
	)
	(gr_circle
		(center 309.386986 -348.704662)
		(end 310.267096 -348.704662)
		(stroke
			(width 0.2)
			(type default)
		)
		(fill no)
		(layer "In16.Cu")
	)
	(gr_circle
		(center 310.004206 -348.704662)
		(end 310.884316 -348.704662)
		(stroke
			(width 0.2)
			(type default)
		)
		(fill no)
		(layer "In16.Cu")
	)
	(gr_circle
		(center 310.621426 -348.704662)
		(end 311.501536 -348.704662)
		(stroke
			(width 0.2)
			(type default)
		)
		(fill no)
		(layer "In16.Cu")
	)
	(gr_circle
		(center 310.867806 -348.002352)
		(end 311.756806 -348.002352)
		(stroke
			(width 0.2)
			(type default)
		)
		(fill no)
		(layer "In16.Cu")
	)
	(gr_circle
		(center 310.867806 -347.265752)
		(end 311.756806 -347.265752)
		(stroke
			(width 0.2)
			(type default)
		)
		(fill no)
		(layer "In16.Cu")
	)
	(gr_circle
		(center 311.323482 -350.313752)
		(end 312.212482 -350.313752)
		(stroke
			(width 0.2)
			(type default)
		)
		(fill no)
		(layer "In16.Cu")
	)
	(gr_circle
		(center 311.323482 -349.577152)
		(end 312.212482 -349.577152)
		(stroke
			(width 0.2)
			(type default)
		)
		(fill no)
		(layer "In16.Cu")
	)
	(gr_circle
		(center 311.848246 -349.137732)
		(end 312.737246 -349.137732)
		(stroke
			(width 0.2)
			(type default)
		)
		(fill no)
		(layer "In16.Cu")
	)
	(gr_circle
		(center 311.873646 -349.899732)
		(end 312.762646 -349.899732)
		(stroke
			(width 0.2)
			(type default)
		)
		(fill no)
		(layer "In16.Cu")
	)
	(gr_circle
		(center 312.407046 -350.255332)
		(end 313.296046 -350.255332)
		(stroke
			(width 0.2)
			(type default)
		)
		(fill no)
		(layer "In16.Cu")
	)
	(gr_circle
		(center 312.407046 -349.518732)
		(end 313.296046 -349.518732)
		(stroke
			(width 0.2)
			(type default)
		)
		(fill no)
		(layer "In16.Cu")
	)
	(gr_circle
		(center 312.407046 -348.782132)
		(end 313.296046 -348.782132)
		(stroke
			(width 0.2)
			(type default)
		)
		(fill no)
		(layer "In16.Cu")
	)
	(gr_circle
		(center 319.0367 -336.983578)
		(end 319.91681 -336.983578)
		(stroke
			(width 0.2)
			(type default)
		)
		(fill no)
		(layer "In16.Cu")
	)
	(gr_circle
		(center 319.65392 -336.983578)
		(end 320.53403 -336.983578)
		(stroke
			(width 0.2)
			(type default)
		)
		(fill no)
		(layer "In16.Cu")
	)
	(gr_circle
		(center 320.27114 -336.983578)
		(end 321.15125 -336.983578)
		(stroke
			(width 0.2)
			(type default)
		)
		(fill no)
		(layer "In16.Cu")
	)
	(gr_circle
		(center 320.5607 -336.239612)
		(end 321.4497 -336.239612)
		(stroke
			(width 0.2)
			(type default)
		)
		(fill no)
		(layer "In16.Cu")
	)
	(gr_circle
		(center 320.5607 -335.503012)
		(end 321.4497 -335.503012)
		(stroke
			(width 0.2)
			(type default)
		)
		(fill no)
		(layer "In16.Cu")
	)
	(gr_circle
		(center 320.973196 -338.592668)
		(end 321.862196 -338.592668)
		(stroke
			(width 0.2)
			(type default)
		)
		(fill no)
		(layer "In16.Cu")
	)
	(gr_circle
		(center 320.973196 -337.856068)
		(end 321.862196 -337.856068)
		(stroke
			(width 0.2)
			(type default)
		)
		(fill no)
		(layer "In16.Cu")
	)
	(gr_circle
		(center 321.49796 -337.416648)
		(end 322.38696 -337.416648)
		(stroke
			(width 0.2)
			(type default)
		)
		(fill no)
		(layer "In16.Cu")
	)
	(gr_circle
		(center 321.52336 -338.178648)
		(end 322.41236 -338.178648)
		(stroke
			(width 0.2)
			(type default)
		)
		(fill no)
		(layer "In16.Cu")
	)
	(gr_circle
		(center 322.05676 -338.534248)
		(end 322.94576 -338.534248)
		(stroke
			(width 0.2)
			(type default)
		)
		(fill no)
		(layer "In16.Cu")
	)
	(gr_circle
		(center 322.05676 -337.797648)
		(end 322.94576 -337.797648)
		(stroke
			(width 0.2)
			(type default)
		)
		(fill no)
		(layer "In16.Cu")
	)
	(gr_circle
		(center 322.05676 -337.061048)
		(end 322.94576 -337.061048)
		(stroke
			(width 0.2)
			(type default)
		)
		(fill no)
		(layer "In16.Cu")
	)
	(gr_circle
		(center 327.392284 -336.976466)
		(end 328.272394 -336.976466)
		(stroke
			(width 0.2)
			(type default)
		)
		(fill no)
		(layer "In16.Cu")
	)
	(gr_circle
		(center 327.692258 -104.30129)
		(end 328.581258 -104.30129)
		(stroke
			(width 0.2)
			(type default)
		)
		(fill no)
		(layer "In16.Cu")
	)
	(gr_circle
		(center 327.951084 -349.43161)
		(end 329.348084 -349.43161)
		(stroke
			(width 0.2)
			(type default)
		)
		(fill no)
		(layer "In16.Cu")
	)
	(gr_circle
		(center 328.009504 -336.976466)
		(end 328.889614 -336.976466)
		(stroke
			(width 0.2)
			(type default)
		)
		(fill no)
		(layer "In16.Cu")
	)
	(gr_circle
		(center 328.626724 -336.976466)
		(end 329.506834 -336.976466)
		(stroke
			(width 0.2)
			(type default)
		)
		(fill no)
		(layer "In16.Cu")
	)
	(gr_circle
		(center 328.918824 -336.253836)
		(end 329.807824 -336.253836)
		(stroke
			(width 0.2)
			(type default)
		)
		(fill no)
		(layer "In16.Cu")
	)
	(gr_circle
		(center 328.918824 -335.517236)
		(end 329.807824 -335.517236)
		(stroke
			(width 0.2)
			(type default)
		)
		(fill no)
		(layer "In16.Cu")
	)
	(gr_circle
		(center 329.32878 -338.585556)
		(end 330.21778 -338.585556)
		(stroke
			(width 0.2)
			(type default)
		)
		(fill no)
		(layer "In16.Cu")
	)
	(gr_circle
		(center 329.32878 -337.848956)
		(end 330.21778 -337.848956)
		(stroke
			(width 0.2)
			(type default)
		)
		(fill no)
		(layer "In16.Cu")
	)
	(gr_circle
		(center 329.853544 -337.409536)
		(end 330.742544 -337.409536)
		(stroke
			(width 0.2)
			(type default)
		)
		(fill no)
		(layer "In16.Cu")
	)
	(gr_circle
		(center 329.878944 -338.171536)
		(end 330.767944 -338.171536)
		(stroke
			(width 0.2)
			(type default)
		)
		(fill no)
		(layer "In16.Cu")
	)
	(gr_circle
		(center 330.412344 -338.527136)
		(end 331.301344 -338.527136)
		(stroke
			(width 0.2)
			(type default)
		)
		(fill no)
		(layer "In16.Cu")
	)
	(gr_circle
		(center 330.412344 -337.790536)
		(end 331.301344 -337.790536)
		(stroke
			(width 0.2)
			(type default)
		)
		(fill no)
		(layer "In16.Cu")
	)
	(gr_circle
		(center 330.412344 -337.053936)
		(end 331.301344 -337.053936)
		(stroke
			(width 0.2)
			(type default)
		)
		(fill no)
		(layer "In16.Cu")
	)
	(gr_circle
		(center 335.411064 -349.43161)
		(end 336.808064 -349.43161)
		(stroke
			(width 0.2)
			(type default)
		)
		(fill no)
		(layer "In16.Cu")
	)
	(gr_circle
		(center 335.7499 -336.961988)
		(end 336.63001 -336.961988)
		(stroke
			(width 0.2)
			(type default)
		)
		(fill no)
		(layer "In16.Cu")
	)
	(gr_circle
		(center 336.36712 -336.961988)
		(end 337.24723 -336.961988)
		(stroke
			(width 0.2)
			(type default)
		)
		(fill no)
		(layer "In16.Cu")
	)
	(gr_circle
		(center 336.98434 -336.961988)
		(end 337.86445 -336.961988)
		(stroke
			(width 0.2)
			(type default)
		)
		(fill no)
		(layer "In16.Cu")
	)
	(gr_circle
		(center 337.280504 -336.253836)
		(end 338.169504 -336.253836)
		(stroke
			(width 0.2)
			(type default)
		)
		(fill no)
		(layer "In16.Cu")
	)
	(gr_circle
		(center 337.280504 -335.517236)
		(end 338.169504 -335.517236)
		(stroke
			(width 0.2)
			(type default)
		)
		(fill no)
		(layer "In16.Cu")
	)
	(gr_circle
		(center 337.686396 -338.571078)
		(end 338.575396 -338.571078)
		(stroke
			(width 0.2)
			(type default)
		)
		(fill no)
		(layer "In16.Cu")
	)
	(gr_circle
		(center 337.686396 -337.834478)
		(end 338.575396 -337.834478)
		(stroke
			(width 0.2)
			(type default)
		)
		(fill no)
		(layer "In16.Cu")
	)
	(gr_circle
		(center 338.21116 -337.395058)
		(end 339.10016 -337.395058)
		(stroke
			(width 0.2)
			(type default)
		)
		(fill no)
		(layer "In16.Cu")
	)
	(gr_circle
		(center 338.23656 -338.157058)
		(end 339.12556 -338.157058)
		(stroke
			(width 0.2)
			(type default)
		)
		(fill no)
		(layer "In16.Cu")
	)
	(gr_circle
		(center 338.76996 -338.512658)
		(end 339.65896 -338.512658)
		(stroke
			(width 0.2)
			(type default)
		)
		(fill no)
		(layer "In16.Cu")
	)
	(gr_circle
		(center 338.76996 -337.776058)
		(end 339.65896 -337.776058)
		(stroke
			(width 0.2)
			(type default)
		)
		(fill no)
		(layer "In16.Cu")
	)
	(gr_circle
		(center 338.76996 -337.039458)
		(end 339.65896 -337.039458)
		(stroke
			(width 0.2)
			(type default)
		)
		(fill no)
		(layer "In16.Cu")
	)
	(gr_circle
		(center 339.73897 -352.973132)
		(end 340.62797 -352.973132)
		(stroke
			(width 0.2)
			(type default)
		)
		(fill no)
		(layer "In16.Cu")
	)
	(gr_circle
		(center 339.739224 -352.215196)
		(end 340.628224 -352.215196)
		(stroke
			(width 0.2)
			(type default)
		)
		(fill no)
		(layer "In16.Cu")
	)
	(gr_circle
		(center 339.739224 -351.453196)
		(end 340.628224 -351.453196)
		(stroke
			(width 0.2)
			(type default)
		)
		(fill no)
		(layer "In16.Cu")
	)
	(gr_circle
		(center 340.501224 -352.215196)
		(end 341.390224 -352.215196)
		(stroke
			(width 0.2)
			(type default)
		)
		(fill no)
		(layer "In16.Cu")
	)
	(gr_circle
		(center 340.501224 -351.453196)
		(end 341.390224 -351.453196)
		(stroke
			(width 0.2)
			(type default)
		)
		(fill no)
		(layer "In16.Cu")
	)
	(gr_circle
		(center 340.667848 -353.010216)
		(end 341.556848 -353.010216)
		(stroke
			(width 0.2)
			(type default)
		)
		(fill no)
		(layer "In16.Cu")
	)
	(gr_circle
		(center 341.263224 -352.215196)
		(end 342.152224 -352.215196)
		(stroke
			(width 0.2)
			(type default)
		)
		(fill no)
		(layer "In16.Cu")
	)
	(gr_circle
		(center 341.263224 -351.453196)
		(end 342.152224 -351.453196)
		(stroke
			(width 0.2)
			(type default)
		)
		(fill no)
		(layer "In16.Cu")
	)
	(gr_circle
		(center 341.302848 -353.010216)
		(end 342.191848 -353.010216)
		(stroke
			(width 0.2)
			(type default)
		)
		(fill no)
		(layer "In16.Cu")
	)
	(gr_circle
		(center 341.937848 -353.010216)
		(end 342.826848 -353.010216)
		(stroke
			(width 0.2)
			(type default)
		)
		(fill no)
		(layer "In16.Cu")
	)
	(gr_circle
		(center 342.025224 -352.215196)
		(end 342.914224 -352.215196)
		(stroke
			(width 0.2)
			(type default)
		)
		(fill no)
		(layer "In16.Cu")
	)
	(gr_circle
		(center 342.025224 -351.453196)
		(end 342.914224 -351.453196)
		(stroke
			(width 0.2)
			(type default)
		)
		(fill no)
		(layer "In16.Cu")
	)
	(gr_circle
		(center 342.572848 -353.010216)
		(end 343.461848 -353.010216)
		(stroke
			(width 0.2)
			(type default)
		)
		(fill no)
		(layer "In16.Cu")
	)
	(gr_circle
		(center 342.787224 -352.215196)
		(end 343.676224 -352.215196)
		(stroke
			(width 0.2)
			(type default)
		)
		(fill no)
		(layer "In16.Cu")
	)
	(gr_circle
		(center 342.787224 -351.453196)
		(end 343.676224 -351.453196)
		(stroke
			(width 0.2)
			(type default)
		)
		(fill no)
		(layer "In16.Cu")
	)
	(gr_circle
		(center 343.46515 -353.006152)
		(end 344.35415 -353.006152)
		(stroke
			(width 0.2)
			(type default)
		)
		(fill no)
		(layer "In16.Cu")
	)
	(gr_circle
		(center 343.465404 -352.248216)
		(end 344.354404 -352.248216)
		(stroke
			(width 0.2)
			(type default)
		)
		(fill no)
		(layer "In16.Cu")
	)
	(gr_circle
		(center 343.465404 -351.486216)
		(end 344.354404 -351.486216)
		(stroke
			(width 0.2)
			(type default)
		)
		(fill no)
		(layer "In16.Cu")
	)
	(gr_circle
		(center 344.016838 -159.073596)
		(end 344.905838 -159.073596)
		(stroke
			(width 0.2)
			(type default)
		)
		(fill no)
		(layer "In16.Cu")
	)
	(gr_circle
		(center 344.016838 -158.336996)
		(end 344.905838 -158.336996)
		(stroke
			(width 0.2)
			(type default)
		)
		(fill no)
		(layer "In16.Cu")
	)
	(gr_circle
		(center 344.016838 -157.600396)
		(end 344.905838 -157.600396)
		(stroke
			(width 0.2)
			(type default)
		)
		(fill no)
		(layer "In16.Cu")
	)
	(gr_circle
		(center 344.0811 -337.012788)
		(end 344.96121 -337.012788)
		(stroke
			(width 0.2)
			(type default)
		)
		(fill no)
		(layer "In16.Cu")
	)
	(gr_circle
		(center 344.550238 -157.955996)
		(end 345.439238 -157.955996)
		(stroke
			(width 0.2)
			(type default)
		)
		(fill no)
		(layer "In16.Cu")
	)
	(gr_circle
		(center 344.575638 -158.717996)
		(end 345.464638 -158.717996)
		(stroke
			(width 0.2)
			(type default)
		)
		(fill no)
		(layer "In16.Cu")
	)
	(gr_circle
		(center 344.69832 -337.012788)
		(end 345.57843 -337.012788)
		(stroke
			(width 0.2)
			(type default)
		)
		(fill no)
		(layer "In16.Cu")
	)
	(gr_circle
		(center 345.100402 -158.278576)
		(end 345.989402 -158.278576)
		(stroke
			(width 0.2)
			(type default)
		)
		(fill no)
		(layer "In16.Cu")
	)
	(gr_circle
		(center 345.100402 -157.541976)
		(end 345.989402 -157.541976)
		(stroke
			(width 0.2)
			(type default)
		)
		(fill no)
		(layer "In16.Cu")
	)
	(gr_circle
		(center 345.31554 -337.012788)
		(end 346.19565 -337.012788)
		(stroke
			(width 0.2)
			(type default)
		)
		(fill no)
		(layer "In16.Cu")
	)
	(gr_circle
		(center 345.623896 -336.317336)
		(end 346.512896 -336.317336)
		(stroke
			(width 0.2)
			(type default)
		)
		(fill no)
		(layer "In16.Cu")
	)
	(gr_circle
		(center 345.623896 -335.580736)
		(end 346.512896 -335.580736)
		(stroke
			(width 0.2)
			(type default)
		)
		(fill no)
		(layer "In16.Cu")
	)
	(gr_circle
		(center 345.684856 -160.633156)
		(end 346.573856 -160.633156)
		(stroke
			(width 0.2)
			(type default)
		)
		(fill no)
		(layer "In16.Cu")
	)
	(gr_circle
		(center 345.684856 -159.896556)
		(end 346.573856 -159.896556)
		(stroke
			(width 0.2)
			(type default)
		)
		(fill no)
		(layer "In16.Cu")
	)
	(gr_circle
		(center 345.802458 -159.151066)
		(end 346.682568 -159.151066)
		(stroke
			(width 0.2)
			(type default)
		)
		(fill no)
		(layer "In16.Cu")
	)
	(gr_circle
		(center 346.017596 -339.358478)
		(end 346.906596 -339.358478)
		(stroke
			(width 0.2)
			(type default)
		)
		(fill no)
		(layer "In16.Cu")
	)
	(gr_circle
		(center 346.017596 -338.621878)
		(end 346.906596 -338.621878)
		(stroke
			(width 0.2)
			(type default)
		)
		(fill no)
		(layer "In16.Cu")
	)
	(gr_circle
		(center 346.017596 -337.885278)
		(end 346.906596 -337.885278)
		(stroke
			(width 0.2)
			(type default)
		)
		(fill no)
		(layer "In16.Cu")
	)
	(gr_circle
		(center 346.419678 -159.151066)
		(end 347.299788 -159.151066)
		(stroke
			(width 0.2)
			(type default)
		)
		(fill no)
		(layer "In16.Cu")
	)
	(gr_circle
		(center 346.54236 -337.445858)
		(end 347.43136 -337.445858)
		(stroke
			(width 0.2)
			(type default)
		)
		(fill no)
		(layer "In16.Cu")
	)
	(gr_circle
		(center 346.56776 -339.731858)
		(end 347.45676 -339.731858)
		(stroke
			(width 0.2)
			(type default)
		)
		(fill no)
		(layer "In16.Cu")
	)
	(gr_circle
		(center 346.56776 -338.969858)
		(end 347.45676 -338.969858)
		(stroke
			(width 0.2)
			(type default)
		)
		(fill no)
		(layer "In16.Cu")
	)
	(gr_circle
		(center 346.56776 -338.207858)
		(end 347.45676 -338.207858)
		(stroke
			(width 0.2)
			(type default)
		)
		(fill no)
		(layer "In16.Cu")
	)
	(gr_circle
		(center 347.036898 -159.151066)
		(end 347.917008 -159.151066)
		(stroke
			(width 0.2)
			(type default)
		)
		(fill no)
		(layer "In16.Cu")
	)
	(gr_circle
		(center 352.322638 -167.430196)
		(end 353.211638 -167.430196)
		(stroke
			(width 0.2)
			(type default)
		)
		(fill no)
		(layer "In16.Cu")
	)
	(gr_circle
		(center 352.322638 -166.693596)
		(end 353.211638 -166.693596)
		(stroke
			(width 0.2)
			(type default)
		)
		(fill no)
		(layer "In16.Cu")
	)
	(gr_circle
		(center 352.322638 -165.956996)
		(end 353.211638 -165.956996)
		(stroke
			(width 0.2)
			(type default)
		)
		(fill no)
		(layer "In16.Cu")
	)
	(gr_circle
		(center 352.356928 -341.922862)
		(end 353.237038 -341.922862)
		(stroke
			(width 0.2)
			(type default)
		)
		(fill no)
		(layer "In16.Cu")
	)
	(gr_circle
		(center 352.856038 -166.312596)
		(end 353.745038 -166.312596)
		(stroke
			(width 0.2)
			(type default)
		)
		(fill no)
		(layer "In16.Cu")
	)
	(gr_circle
		(center 352.881438 -167.074596)
		(end 353.770438 -167.074596)
		(stroke
			(width 0.2)
			(type default)
		)
		(fill no)
		(layer "In16.Cu")
	)
	(gr_circle
		(center 352.974148 -341.922862)
		(end 353.854258 -341.922862)
		(stroke
			(width 0.2)
			(type default)
		)
		(fill no)
		(layer "In16.Cu")
	)
	(gr_circle
		(center 353.406202 -166.635176)
		(end 354.295202 -166.635176)
		(stroke
			(width 0.2)
			(type default)
		)
		(fill no)
		(layer "In16.Cu")
	)
	(gr_circle
		(center 353.406202 -165.898576)
		(end 354.295202 -165.898576)
		(stroke
			(width 0.2)
			(type default)
		)
		(fill no)
		(layer "In16.Cu")
	)
	(gr_circle
		(center 353.591368 -341.922862)
		(end 354.471478 -341.922862)
		(stroke
			(width 0.2)
			(type default)
		)
		(fill no)
		(layer "In16.Cu")
	)
	(gr_circle
		(center 353.899724 -341.22741)
		(end 354.788724 -341.22741)
		(stroke
			(width 0.2)
			(type default)
		)
		(fill no)
		(layer "In16.Cu")
	)
	(gr_circle
		(center 353.899724 -340.49081)
		(end 354.788724 -340.49081)
		(stroke
			(width 0.2)
			(type default)
		)
		(fill no)
		(layer "In16.Cu")
	)
	(gr_circle
		(center 353.990656 -168.982136)
		(end 354.879656 -168.982136)
		(stroke
			(width 0.2)
			(type default)
		)
		(fill no)
		(layer "In16.Cu")
	)
	(gr_circle
		(center 353.990656 -168.245536)
		(end 354.879656 -168.245536)
		(stroke
			(width 0.2)
			(type default)
		)
		(fill no)
		(layer "In16.Cu")
	)
	(gr_circle
		(center 354.108258 -167.507666)
		(end 354.988368 -167.507666)
		(stroke
			(width 0.2)
			(type default)
		)
		(fill no)
		(layer "In16.Cu")
	)
	(gr_circle
		(center 354.293424 -343.531952)
		(end 355.182424 -343.531952)
		(stroke
			(width 0.2)
			(type default)
		)
		(fill no)
		(layer "In16.Cu")
	)
	(gr_circle
		(center 354.293424 -342.795352)
		(end 355.182424 -342.795352)
		(stroke
			(width 0.2)
			(type default)
		)
		(fill no)
		(layer "In16.Cu")
	)
	(gr_circle
		(center 354.725478 -167.507666)
		(end 355.605588 -167.507666)
		(stroke
			(width 0.2)
			(type default)
		)
		(fill no)
		(layer "In16.Cu")
	)
	(gr_circle
		(center 354.818188 -342.355932)
		(end 355.707188 -342.355932)
		(stroke
			(width 0.2)
			(type default)
		)
		(fill no)
		(layer "In16.Cu")
	)
	(gr_circle
		(center 354.843588 -343.117932)
		(end 355.732588 -343.117932)
		(stroke
			(width 0.2)
			(type default)
		)
		(fill no)
		(layer "In16.Cu")
	)
	(gr_circle
		(center 355.342698 -167.507666)
		(end 356.222808 -167.507666)
		(stroke
			(width 0.2)
			(type default)
		)
		(fill no)
		(layer "In16.Cu")
	)
	(gr_circle
		(center 355.376988 -343.473532)
		(end 356.265988 -343.473532)
		(stroke
			(width 0.2)
			(type default)
		)
		(fill no)
		(layer "In16.Cu")
	)
	(gr_circle
		(center 355.376988 -342.736932)
		(end 356.265988 -342.736932)
		(stroke
			(width 0.2)
			(type default)
		)
		(fill no)
		(layer "In16.Cu")
	)
	(gr_circle
		(center 355.376988 -342.000332)
		(end 356.265988 -342.000332)
		(stroke
			(width 0.2)
			(type default)
		)
		(fill no)
		(layer "In16.Cu")
	)
	(gr_circle
		(center 359.58526 -152.71242)
		(end 360.98226 -152.71242)
		(stroke
			(width 0.2)
			(type default)
		)
		(fill no)
		(layer "In16.Cu")
	)
	(gr_circle
		(center 360.603038 -175.705516)
		(end 361.492038 -175.705516)
		(stroke
			(width 0.2)
			(type default)
		)
		(fill no)
		(layer "In16.Cu")
	)
	(gr_circle
		(center 360.603038 -174.968916)
		(end 361.492038 -174.968916)
		(stroke
			(width 0.2)
			(type default)
		)
		(fill no)
		(layer "In16.Cu")
	)
	(gr_circle
		(center 360.603038 -174.232316)
		(end 361.492038 -174.232316)
		(stroke
			(width 0.2)
			(type default)
		)
		(fill no)
		(layer "In16.Cu")
	)
	(gr_circle
		(center 361.136438 -174.587916)
		(end 362.025438 -174.587916)
		(stroke
			(width 0.2)
			(type default)
		)
		(fill no)
		(layer "In16.Cu")
	)
	(gr_circle
		(center 361.161838 -175.349916)
		(end 362.050838 -175.349916)
		(stroke
			(width 0.2)
			(type default)
		)
		(fill no)
		(layer "In16.Cu")
	)
	(gr_circle
		(center 361.686602 -174.910496)
		(end 362.575602 -174.910496)
		(stroke
			(width 0.2)
			(type default)
		)
		(fill no)
		(layer "In16.Cu")
	)
	(gr_circle
		(center 361.686602 -174.173896)
		(end 362.575602 -174.173896)
		(stroke
			(width 0.2)
			(type default)
		)
		(fill no)
		(layer "In16.Cu")
	)
	(gr_circle
		(center 362.271056 -177.254916)
		(end 363.160056 -177.254916)
		(stroke
			(width 0.2)
			(type default)
		)
		(fill no)
		(layer "In16.Cu")
	)
	(gr_circle
		(center 362.271056 -176.518316)
		(end 363.160056 -176.518316)
		(stroke
			(width 0.2)
			(type default)
		)
		(fill no)
		(layer "In16.Cu")
	)
	(gr_circle
		(center 362.396278 -175.859186)
		(end 363.276388 -175.859186)
		(stroke
			(width 0.2)
			(type default)
		)
		(fill no)
		(layer "In16.Cu")
	)
	(gr_circle
		(center 363.013498 -175.859186)
		(end 363.893608 -175.859186)
		(stroke
			(width 0.2)
			(type default)
		)
		(fill no)
		(layer "In16.Cu")
	)
	(gr_circle
		(center 363.630718 -175.859186)
		(end 364.510828 -175.859186)
		(stroke
			(width 0.2)
			(type default)
		)
		(fill no)
		(layer "In16.Cu")
	)
	(gr_circle
		(center 366.744504 -164.53358)
		(end 367.633504 -164.53358)
		(stroke
			(width 0.2)
			(type default)
		)
		(fill no)
		(layer "In16.Cu")
	)
	(gr_circle
		(center 366.744504 -163.89858)
		(end 367.633504 -163.89858)
		(stroke
			(width 0.2)
			(type default)
		)
		(fill no)
		(layer "In16.Cu")
	)
	(gr_circle
		(center 366.757204 -165.19398)
		(end 367.646204 -165.19398)
		(stroke
			(width 0.2)
			(type default)
		)
		(fill no)
		(layer "In16.Cu")
	)
	(gr_circle
		(center 367.379504 -164.53358)
		(end 368.268504 -164.53358)
		(stroke
			(width 0.2)
			(type default)
		)
		(fill no)
		(layer "In16.Cu")
	)
	(gr_circle
		(center 367.379504 -163.89858)
		(end 368.268504 -163.89858)
		(stroke
			(width 0.2)
			(type default)
		)
		(fill no)
		(layer "In16.Cu")
	)
	(gr_circle
		(center 367.392204 -165.19398)
		(end 368.281204 -165.19398)
		(stroke
			(width 0.2)
			(type default)
		)
		(fill no)
		(layer "In16.Cu")
	)
	(gr_circle
		(center 368.044984 -164.53358)
		(end 368.933984 -164.53358)
		(stroke
			(width 0.2)
			(type default)
		)
		(fill no)
		(layer "In16.Cu")
	)
	(gr_circle
		(center 368.044984 -163.89858)
		(end 368.933984 -163.89858)
		(stroke
			(width 0.2)
			(type default)
		)
		(fill no)
		(layer "In16.Cu")
	)
	(gr_circle
		(center 368.057684 -165.19398)
		(end 368.946684 -165.19398)
		(stroke
			(width 0.2)
			(type default)
		)
		(fill no)
		(layer "In16.Cu")
	)
	(gr_circle
		(center 368.679984 -164.53358)
		(end 369.568984 -164.53358)
		(stroke
			(width 0.2)
			(type default)
		)
		(fill no)
		(layer "In16.Cu")
	)
	(gr_circle
		(center 368.679984 -163.89858)
		(end 369.568984 -163.89858)
		(stroke
			(width 0.2)
			(type default)
		)
		(fill no)
		(layer "In16.Cu")
	)
	(gr_circle
		(center 368.692684 -165.19398)
		(end 369.581684 -165.19398)
		(stroke
			(width 0.2)
			(type default)
		)
		(fill no)
		(layer "In16.Cu")
	)
	(gr_circle
		(center 368.96421 -179.204874)
		(end 369.85321 -179.204874)
		(stroke
			(width 0.2)
			(type default)
		)
		(fill no)
		(layer "In16.Cu")
	)
	(gr_circle
		(center 369.314984 -164.53358)
		(end 370.203984 -164.53358)
		(stroke
			(width 0.2)
			(type default)
		)
		(fill no)
		(layer "In16.Cu")
	)
	(gr_circle
		(center 369.314984 -163.89858)
		(end 370.203984 -163.89858)
		(stroke
			(width 0.2)
			(type default)
		)
		(fill no)
		(layer "In16.Cu")
	)
	(gr_circle
		(center 369.327684 -165.19398)
		(end 370.216684 -165.19398)
		(stroke
			(width 0.2)
			(type default)
		)
		(fill no)
		(layer "In16.Cu")
	)
	(gr_circle
		(center 369.49761 -179.560474)
		(end 370.38661 -179.560474)
		(stroke
			(width 0.2)
			(type default)
		)
		(fill no)
		(layer "In16.Cu")
	)
	(gr_circle
		(center 369.49761 -178.798474)
		(end 370.38661 -178.798474)
		(stroke
			(width 0.2)
			(type default)
		)
		(fill no)
		(layer "In16.Cu")
	)
	(gr_circle
		(center 369.49761 -178.036474)
		(end 370.38661 -178.036474)
		(stroke
			(width 0.2)
			(type default)
		)
		(fill no)
		(layer "In16.Cu")
	)
	(gr_circle
		(center 369.52301 -180.322474)
		(end 370.41201 -180.322474)
		(stroke
			(width 0.2)
			(type default)
		)
		(fill no)
		(layer "In16.Cu")
	)
	(gr_circle
		(center 369.949984 -164.53358)
		(end 370.838984 -164.53358)
		(stroke
			(width 0.2)
			(type default)
		)
		(fill no)
		(layer "In16.Cu")
	)
	(gr_circle
		(center 369.949984 -163.89858)
		(end 370.838984 -163.89858)
		(stroke
			(width 0.2)
			(type default)
		)
		(fill no)
		(layer "In16.Cu")
	)
	(gr_circle
		(center 369.962684 -165.19398)
		(end 370.851684 -165.19398)
		(stroke
			(width 0.2)
			(type default)
		)
		(fill no)
		(layer "In16.Cu")
	)
	(gr_circle
		(center 370.047774 -179.883054)
		(end 370.936774 -179.883054)
		(stroke
			(width 0.2)
			(type default)
		)
		(fill no)
		(layer "In16.Cu")
	)
	(gr_circle
		(center 370.047774 -179.146454)
		(end 370.936774 -179.146454)
		(stroke
			(width 0.2)
			(type default)
		)
		(fill no)
		(layer "In16.Cu")
	)
	(gr_circle
		(center 370.529358 -182.141876)
		(end 371.418358 -182.141876)
		(stroke
			(width 0.2)
			(type default)
		)
		(fill no)
		(layer "In16.Cu")
	)
	(gr_circle
		(center 370.529358 -181.405276)
		(end 371.418358 -181.405276)
		(stroke
			(width 0.2)
			(type default)
		)
		(fill no)
		(layer "In16.Cu")
	)
	(gr_circle
		(center 370.686584 -164.53358)
		(end 371.575584 -164.53358)
		(stroke
			(width 0.2)
			(type default)
		)
		(fill no)
		(layer "In16.Cu")
	)
	(gr_circle
		(center 370.686584 -163.89858)
		(end 371.575584 -163.89858)
		(stroke
			(width 0.2)
			(type default)
		)
		(fill no)
		(layer "In16.Cu")
	)
	(gr_circle
		(center 370.699284 -165.19398)
		(end 371.588284 -165.19398)
		(stroke
			(width 0.2)
			(type default)
		)
		(fill no)
		(layer "In16.Cu")
	)
	(gr_circle
		(center 370.74221 -180.803804)
		(end 371.62232 -180.803804)
		(stroke
			(width 0.2)
			(type default)
		)
		(fill no)
		(layer "In16.Cu")
	)
	(gr_circle
		(center 371.35943 -180.803804)
		(end 372.23954 -180.803804)
		(stroke
			(width 0.2)
			(type default)
		)
		(fill no)
		(layer "In16.Cu")
	)
	(gr_circle
		(center 371.97665 -180.803804)
		(end 372.85676 -180.803804)
		(stroke
			(width 0.2)
			(type default)
		)
		(fill no)
		(layer "In16.Cu")
	)
	(gr_circle
		(center 377.367038 -180.678074)
		(end 378.256038 -180.678074)
		(stroke
			(width 0.2)
			(type default)
		)
		(fill no)
		(layer "In16.Cu")
	)
	(gr_circle
		(center 377.367038 -179.941474)
		(end 378.256038 -179.941474)
		(stroke
			(width 0.2)
			(type default)
		)
		(fill no)
		(layer "In16.Cu")
	)
	(gr_circle
		(center 377.367038 -179.204874)
		(end 378.256038 -179.204874)
		(stroke
			(width 0.2)
			(type default)
		)
		(fill no)
		(layer "In16.Cu")
	)
	(gr_circle
		(center 377.869958 -162.59683)
		(end 379.266958 -162.59683)
		(stroke
			(width 0.2)
			(type default)
		)
		(fill no)
		(layer "In16.Cu")
	)
	(gr_circle
		(center 377.900438 -179.560474)
		(end 378.789438 -179.560474)
		(stroke
			(width 0.2)
			(type default)
		)
		(fill no)
		(layer "In16.Cu")
	)
	(gr_circle
		(center 377.925838 -180.322474)
		(end 378.814838 -180.322474)
		(stroke
			(width 0.2)
			(type default)
		)
		(fill no)
		(layer "In16.Cu")
	)
	(gr_circle
		(center 378.450602 -179.883054)
		(end 379.339602 -179.883054)
		(stroke
			(width 0.2)
			(type default)
		)
		(fill no)
		(layer "In16.Cu")
	)
	(gr_circle
		(center 378.450602 -179.146454)
		(end 379.339602 -179.146454)
		(stroke
			(width 0.2)
			(type default)
		)
		(fill no)
		(layer "In16.Cu")
	)
	(gr_circle
		(center 379.035056 -182.230776)
		(end 379.924056 -182.230776)
		(stroke
			(width 0.2)
			(type default)
		)
		(fill no)
		(layer "In16.Cu")
	)
	(gr_circle
		(center 379.035056 -181.494176)
		(end 379.924056 -181.494176)
		(stroke
			(width 0.2)
			(type default)
		)
		(fill no)
		(layer "In16.Cu")
	)
	(gr_circle
		(center 379.152658 -180.755544)
		(end 380.032768 -180.755544)
		(stroke
			(width 0.2)
			(type default)
		)
		(fill no)
		(layer "In16.Cu")
	)
	(gr_circle
		(center 379.769878 -180.755544)
		(end 380.649988 -180.755544)
		(stroke
			(width 0.2)
			(type default)
		)
		(fill no)
		(layer "In16.Cu")
	)
	(gr_circle
		(center 380.387098 -180.755544)
		(end 381.267208 -180.755544)
		(stroke
			(width 0.2)
			(type default)
		)
		(fill no)
		(layer "In16.Cu")
	)
	(gr_line
		(start 385.601972 -12.288012)
		(end 260.800088 -12.288012)
		(stroke
			(width 0.2)
			(type default)
		)
		(layer "In16.Cu")
	)
	(gr_arc
		(start 385.601972 -12.288012)
		(mid 387.375417 -11.553448)
		(end 388.109968 -9.780016)
		(stroke
			(width 0.2)
			(type default)
		)
		(layer "In16.Cu")
	)
	(gr_arc
		(start 385.601972 -11.780012)
		(mid 387.016183 -11.194227)
		(end 387.601968 -9.780016)
		(stroke
			(width 1.016)
			(type default)
		)
		(layer "In16.Cu")
	)
	(gr_circle
		(center 385.698238 -180.678074)
		(end 386.587238 -180.678074)
		(stroke
			(width 0.2)
			(type default)
		)
		(fill no)
		(layer "In16.Cu")
	)
	(gr_circle
		(center 385.698238 -179.941474)
		(end 386.587238 -179.941474)
		(stroke
			(width 0.2)
			(type default)
		)
		(fill no)
		(layer "In16.Cu")
	)
	(gr_circle
		(center 385.698238 -179.204874)
		(end 386.587238 -179.204874)
		(stroke
			(width 0.2)
			(type default)
		)
		(fill no)
		(layer "In16.Cu")
	)
	(gr_circle
		(center 386.231638 -179.560474)
		(end 387.120638 -179.560474)
		(stroke
			(width 0.2)
			(type default)
		)
		(fill no)
		(layer "In16.Cu")
	)
	(gr_circle
		(center 386.257038 -180.322474)
		(end 387.146038 -180.322474)
		(stroke
			(width 0.2)
			(type default)
		)
		(fill no)
		(layer "In16.Cu")
	)
	(gr_circle
		(center 386.781802 -179.883054)
		(end 387.670802 -179.883054)
		(stroke
			(width 0.2)
			(type default)
		)
		(fill no)
		(layer "In16.Cu")
	)
	(gr_circle
		(center 386.781802 -179.146454)
		(end 387.670802 -179.146454)
		(stroke
			(width 0.2)
			(type default)
		)
		(fill no)
		(layer "In16.Cu")
	)
	(gr_circle
		(center 387.206998 -162.65271)
		(end 388.603998 -162.65271)
		(stroke
			(width 0.2)
			(type default)
		)
		(fill no)
		(layer "In16.Cu")
	)
	(gr_circle
		(center 387.293358 -157.001972)
		(end 388.182358 -157.001972)
		(stroke
			(width 0.2)
			(type default)
		)
		(fill no)
		(layer "In16.Cu")
	)
	(gr_circle
		(center 387.293358 -156.366972)
		(end 388.182358 -156.366972)
		(stroke
			(width 0.2)
			(type default)
		)
		(fill no)
		(layer "In16.Cu")
	)
	(gr_circle
		(center 387.293358 -155.724352)
		(end 388.182358 -155.724352)
		(stroke
			(width 0.2)
			(type default)
		)
		(fill no)
		(layer "In16.Cu")
	)
	(gr_circle
		(center 387.293358 -155.089352)
		(end 388.182358 -155.089352)
		(stroke
			(width 0.2)
			(type default)
		)
		(fill no)
		(layer "In16.Cu")
	)
	(gr_circle
		(center 387.293358 -154.428952)
		(end 388.182358 -154.428952)
		(stroke
			(width 0.2)
			(type default)
		)
		(fill no)
		(layer "In16.Cu")
	)
	(gr_circle
		(center 387.293358 -153.793952)
		(end 388.182358 -153.793952)
		(stroke
			(width 0.2)
			(type default)
		)
		(fill no)
		(layer "In16.Cu")
	)
	(gr_circle
		(center 387.366256 -182.230776)
		(end 388.255256 -182.230776)
		(stroke
			(width 0.2)
			(type default)
		)
		(fill no)
		(layer "In16.Cu")
	)
	(gr_circle
		(center 387.366256 -181.494176)
		(end 388.255256 -181.494176)
		(stroke
			(width 0.2)
			(type default)
		)
		(fill no)
		(layer "In16.Cu")
	)
	(gr_circle
		(center 387.483858 -180.755544)
		(end 388.363968 -180.755544)
		(stroke
			(width 0.2)
			(type default)
		)
		(fill no)
		(layer "In16.Cu")
	)
	(gr_line
		(start 387.601968 -9.780016)
		(end 387.601968 -0.500126)
		(stroke
			(width 1.016)
			(type default)
		)
		(layer "In16.Cu")
	)
	(gr_circle
		(center 387.928358 -157.001972)
		(end 388.817358 -157.001972)
		(stroke
			(width 0.2)
			(type default)
		)
		(fill no)
		(layer "In16.Cu")
	)
	(gr_circle
		(center 387.928358 -156.366972)
		(end 388.817358 -156.366972)
		(stroke
			(width 0.2)
			(type default)
		)
		(fill no)
		(layer "In16.Cu")
	)
	(gr_circle
		(center 387.928358 -155.724352)
		(end 388.817358 -155.724352)
		(stroke
			(width 0.2)
			(type default)
		)
		(fill no)
		(layer "In16.Cu")
	)
	(gr_circle
		(center 387.928358 -155.089352)
		(end 388.817358 -155.089352)
		(stroke
			(width 0.2)
			(type default)
		)
		(fill no)
		(layer "In16.Cu")
	)
	(gr_circle
		(center 387.928358 -154.428952)
		(end 388.817358 -154.428952)
		(stroke
			(width 0.2)
			(type default)
		)
		(fill no)
		(layer "In16.Cu")
	)
	(gr_circle
		(center 387.928358 -153.793952)
		(end 388.817358 -153.793952)
		(stroke
			(width 0.2)
			(type default)
		)
		(fill no)
		(layer "In16.Cu")
	)
	(gr_circle
		(center 388.101078 -180.755544)
		(end 388.981188 -180.755544)
		(stroke
			(width 0.2)
			(type default)
		)
		(fill no)
		(layer "In16.Cu")
	)
	(gr_arc
		(start 388.102094 0)
		(mid 387.748465 -0.146487)
		(end 387.601968 -0.500126)
		(stroke
			(width 1.016)
			(type default)
		)
		(layer "In16.Cu")
	)
	(gr_line
		(start 388.102094 0)
		(end 455.701908 0)
		(stroke
			(width 1.016)
			(type default)
		)
		(layer "In16.Cu")
	)
	(gr_line
		(start 388.109968 -0.508)
		(end 388.109968 -9.780016)
		(stroke
			(width 0.2)
			(type default)
		)
		(layer "In16.Cu")
	)
	(gr_circle
		(center 388.718298 -180.755544)
		(end 389.598408 -180.755544)
		(stroke
			(width 0.2)
			(type default)
		)
		(fill no)
		(layer "In16.Cu")
	)
	(gr_circle
		(center 394.628878 -173.21911)
		(end 395.517878 -173.21911)
		(stroke
			(width 0.2)
			(type default)
		)
		(fill no)
		(layer "In16.Cu")
	)
	(gr_circle
		(center 394.628878 -172.45711)
		(end 395.517878 -172.45711)
		(stroke
			(width 0.2)
			(type default)
		)
		(fill no)
		(layer "In16.Cu")
	)
	(gr_circle
		(center 394.646658 -173.987714)
		(end 395.535658 -173.987714)
		(stroke
			(width 0.2)
			(type default)
		)
		(fill no)
		(layer "In16.Cu")
	)
	(gr_circle
		(center 394.672058 -174.749714)
		(end 395.561058 -174.749714)
		(stroke
			(width 0.2)
			(type default)
		)
		(fill no)
		(layer "In16.Cu")
	)
	(gr_circle
		(center 395.196822 -174.310294)
		(end 396.085822 -174.310294)
		(stroke
			(width 0.2)
			(type default)
		)
		(fill no)
		(layer "In16.Cu")
	)
	(gr_circle
		(center 395.196822 -173.573694)
		(end 396.085822 -173.573694)
		(stroke
			(width 0.2)
			(type default)
		)
		(fill no)
		(layer "In16.Cu")
	)
	(gr_circle
		(center 395.230858 -172.819314)
		(end 396.119858 -172.819314)
		(stroke
			(width 0.2)
			(type default)
		)
		(fill no)
		(layer "In16.Cu")
	)
	(gr_circle
		(center 395.781276 -176.657254)
		(end 396.670276 -176.657254)
		(stroke
			(width 0.2)
			(type default)
		)
		(fill no)
		(layer "In16.Cu")
	)
	(gr_circle
		(center 395.781276 -175.895254)
		(end 396.670276 -175.895254)
		(stroke
			(width 0.2)
			(type default)
		)
		(fill no)
		(layer "In16.Cu")
	)
	(gr_circle
		(center 395.898878 -175.182784)
		(end 396.778988 -175.182784)
		(stroke
			(width 0.2)
			(type default)
		)
		(fill no)
		(layer "In16.Cu")
	)
	(gr_circle
		(center 396.516098 -175.182784)
		(end 397.396208 -175.182784)
		(stroke
			(width 0.2)
			(type default)
		)
		(fill no)
		(layer "In16.Cu")
	)
	(gr_circle
		(center 397.133318 -175.182784)
		(end 398.013428 -175.182784)
		(stroke
			(width 0.2)
			(type default)
		)
		(fill no)
		(layer "In16.Cu")
	)
	(gr_circle
		(center 399.165064 -81.051146)
		(end 400.054064 -81.051146)
		(stroke
			(width 0.2)
			(type default)
		)
		(fill no)
		(layer "In16.Cu")
	)
	(gr_circle
		(center 402.436838 -166.527988)
		(end 403.325838 -166.527988)
		(stroke
			(width 0.2)
			(type default)
		)
		(fill no)
		(layer "In16.Cu")
	)
	(gr_circle
		(center 402.436838 -165.791388)
		(end 403.325838 -165.791388)
		(stroke
			(width 0.2)
			(type default)
		)
		(fill no)
		(layer "In16.Cu")
	)
	(gr_circle
		(center 402.436838 -165.054788)
		(end 403.325838 -165.054788)
		(stroke
			(width 0.2)
			(type default)
		)
		(fill no)
		(layer "In16.Cu")
	)
	(gr_circle
		(center 402.970238 -165.410388)
		(end 403.859238 -165.410388)
		(stroke
			(width 0.2)
			(type default)
		)
		(fill no)
		(layer "In16.Cu")
	)
	(gr_circle
		(center 402.995638 -166.172388)
		(end 403.884638 -166.172388)
		(stroke
			(width 0.2)
			(type default)
		)
		(fill no)
		(layer "In16.Cu")
	)
	(gr_circle
		(center 403.520402 -165.732968)
		(end 404.409402 -165.732968)
		(stroke
			(width 0.2)
			(type default)
		)
		(fill no)
		(layer "In16.Cu")
	)
	(gr_circle
		(center 403.520402 -164.996368)
		(end 404.409402 -164.996368)
		(stroke
			(width 0.2)
			(type default)
		)
		(fill no)
		(layer "In16.Cu")
	)
	(gr_circle
		(center 404.104856 -168.082214)
		(end 404.993856 -168.082214)
		(stroke
			(width 0.2)
			(type default)
		)
		(fill no)
		(layer "In16.Cu")
	)
	(gr_circle
		(center 404.104856 -167.320214)
		(end 404.993856 -167.320214)
		(stroke
			(width 0.2)
			(type default)
		)
		(fill no)
		(layer "In16.Cu")
	)
	(gr_circle
		(center 404.222458 -166.605458)
		(end 405.102568 -166.605458)
		(stroke
			(width 0.2)
			(type default)
		)
		(fill no)
		(layer "In16.Cu")
	)
	(gr_circle
		(center 404.839678 -166.605458)
		(end 405.719788 -166.605458)
		(stroke
			(width 0.2)
			(type default)
		)
		(fill no)
		(layer "In16.Cu")
	)
	(gr_circle
		(center 405.456898 -166.605458)
		(end 406.337008 -166.605458)
		(stroke
			(width 0.2)
			(type default)
		)
		(fill no)
		(layer "In16.Cu")
	)
	(gr_circle
		(center 410.818838 -161.701988)
		(end 411.707838 -161.701988)
		(stroke
			(width 0.2)
			(type default)
		)
		(fill no)
		(layer "In16.Cu")
	)
	(gr_circle
		(center 410.818838 -160.965388)
		(end 411.707838 -160.965388)
		(stroke
			(width 0.2)
			(type default)
		)
		(fill no)
		(layer "In16.Cu")
	)
	(gr_circle
		(center 410.818838 -160.228788)
		(end 411.707838 -160.228788)
		(stroke
			(width 0.2)
			(type default)
		)
		(fill no)
		(layer "In16.Cu")
	)
	(gr_circle
		(center 411.352238 -160.584388)
		(end 412.241238 -160.584388)
		(stroke
			(width 0.2)
			(type default)
		)
		(fill no)
		(layer "In16.Cu")
	)
	(gr_circle
		(center 411.377638 -161.346388)
		(end 412.266638 -161.346388)
		(stroke
			(width 0.2)
			(type default)
		)
		(fill no)
		(layer "In16.Cu")
	)
	(gr_circle
		(center 411.902402 -160.906968)
		(end 412.791402 -160.906968)
		(stroke
			(width 0.2)
			(type default)
		)
		(fill no)
		(layer "In16.Cu")
	)
	(gr_circle
		(center 411.902402 -160.170368)
		(end 412.791402 -160.170368)
		(stroke
			(width 0.2)
			(type default)
		)
		(fill no)
		(layer "In16.Cu")
	)
	(gr_circle
		(center 412.486856 -163.256214)
		(end 413.375856 -163.256214)
		(stroke
			(width 0.2)
			(type default)
		)
		(fill no)
		(layer "In16.Cu")
	)
	(gr_circle
		(center 412.486856 -162.494214)
		(end 413.375856 -162.494214)
		(stroke
			(width 0.2)
			(type default)
		)
		(fill no)
		(layer "In16.Cu")
	)
	(gr_circle
		(center 412.604458 -161.779458)
		(end 413.484568 -161.779458)
		(stroke
			(width 0.2)
			(type default)
		)
		(fill no)
		(layer "In16.Cu")
	)
	(gr_circle
		(center 413.221678 -161.779458)
		(end 414.101788 -161.779458)
		(stroke
			(width 0.2)
			(type default)
		)
		(fill no)
		(layer "In16.Cu")
	)
	(gr_circle
		(center 413.838898 -161.779458)
		(end 414.719008 -161.779458)
		(stroke
			(width 0.2)
			(type default)
		)
		(fill no)
		(layer "In16.Cu")
	)
	(gr_circle
		(center 424.33494 -353.10318)
		(end 425.21505 -353.10318)
		(stroke
			(width 0.2)
			(type default)
		)
		(fill no)
		(layer "In16.Cu")
	)
	(gr_circle
		(center 424.95216 -353.10318)
		(end 425.83227 -353.10318)
		(stroke
			(width 0.2)
			(type default)
		)
		(fill no)
		(layer "In16.Cu")
	)
	(gr_circle
		(center 425.56938 -353.10318)
		(end 426.44949 -353.10318)
		(stroke
			(width 0.2)
			(type default)
		)
		(fill no)
		(layer "In16.Cu")
	)
	(gr_circle
		(center 425.686474 -352.35769)
		(end 426.575474 -352.35769)
		(stroke
			(width 0.2)
			(type default)
		)
		(fill no)
		(layer "In16.Cu")
	)
	(gr_circle
		(center 425.686474 -351.62109)
		(end 426.575474 -351.62109)
		(stroke
			(width 0.2)
			(type default)
		)
		(fill no)
		(layer "In16.Cu")
	)
	(gr_circle
		(center 426.271436 -354.71227)
		(end 427.160436 -354.71227)
		(stroke
			(width 0.2)
			(type default)
		)
		(fill no)
		(layer "In16.Cu")
	)
	(gr_circle
		(center 426.271436 -353.97567)
		(end 427.160436 -353.97567)
		(stroke
			(width 0.2)
			(type default)
		)
		(fill no)
		(layer "In16.Cu")
	)
	(gr_circle
		(center 426.7962 -353.53625)
		(end 427.6852 -353.53625)
		(stroke
			(width 0.2)
			(type default)
		)
		(fill no)
		(layer "In16.Cu")
	)
	(gr_circle
		(center 426.8216 -354.29825)
		(end 427.7106 -354.29825)
		(stroke
			(width 0.2)
			(type default)
		)
		(fill no)
		(layer "In16.Cu")
	)
	(gr_circle
		(center 427.355 -354.65385)
		(end 428.244 -354.65385)
		(stroke
			(width 0.2)
			(type default)
		)
		(fill no)
		(layer "In16.Cu")
	)
	(gr_circle
		(center 427.355 -353.91725)
		(end 428.244 -353.91725)
		(stroke
			(width 0.2)
			(type default)
		)
		(fill no)
		(layer "In16.Cu")
	)
	(gr_circle
		(center 427.355 -353.18065)
		(end 428.244 -353.18065)
		(stroke
			(width 0.2)
			(type default)
		)
		(fill no)
		(layer "In16.Cu")
	)
	(gr_circle
		(center 432.01336 -361.827826)
		(end 433.41036 -361.827826)
		(stroke
			(width 0.2)
			(type default)
		)
		(fill no)
		(layer "In16.Cu")
	)
	(gr_circle
		(center 432.661568 -353.12858)
		(end 433.541678 -353.12858)
		(stroke
			(width 0.2)
			(type default)
		)
		(fill no)
		(layer "In16.Cu")
	)
	(gr_circle
		(center 433.278788 -353.12858)
		(end 434.158898 -353.12858)
		(stroke
			(width 0.2)
			(type default)
		)
		(fill no)
		(layer "In16.Cu")
	)
	(gr_circle
		(center 433.896008 -353.12858)
		(end 434.776118 -353.12858)
		(stroke
			(width 0.2)
			(type default)
		)
		(fill no)
		(layer "In16.Cu")
	)
	(gr_circle
		(center 434.013102 -352.38309)
		(end 434.902102 -352.38309)
		(stroke
			(width 0.2)
			(type default)
		)
		(fill no)
		(layer "In16.Cu")
	)
	(gr_circle
		(center 434.013102 -351.64649)
		(end 434.902102 -351.64649)
		(stroke
			(width 0.2)
			(type default)
		)
		(fill no)
		(layer "In16.Cu")
	)
	(gr_circle
		(center 434.598064 -354.73767)
		(end 435.487064 -354.73767)
		(stroke
			(width 0.2)
			(type default)
		)
		(fill no)
		(layer "In16.Cu")
	)
	(gr_circle
		(center 434.598064 -354.00107)
		(end 435.487064 -354.00107)
		(stroke
			(width 0.2)
			(type default)
		)
		(fill no)
		(layer "In16.Cu")
	)
	(gr_circle
		(center 435.122828 -353.56165)
		(end 436.011828 -353.56165)
		(stroke
			(width 0.2)
			(type default)
		)
		(fill no)
		(layer "In16.Cu")
	)
	(gr_circle
		(center 435.148228 -354.32365)
		(end 436.037228 -354.32365)
		(stroke
			(width 0.2)
			(type default)
		)
		(fill no)
		(layer "In16.Cu")
	)
	(gr_circle
		(center 435.469538 -361.496102)
		(end 436.358538 -361.496102)
		(stroke
			(width 0.2)
			(type default)
		)
		(fill no)
		(layer "In16.Cu")
	)
	(gr_circle
		(center 435.469538 -360.734102)
		(end 436.358538 -360.734102)
		(stroke
			(width 0.2)
			(type default)
		)
		(fill no)
		(layer "In16.Cu")
	)
	(gr_circle
		(center 435.469538 -359.972102)
		(end 436.358538 -359.972102)
		(stroke
			(width 0.2)
			(type default)
		)
		(fill no)
		(layer "In16.Cu")
	)
	(gr_circle
		(center 435.681628 -354.67925)
		(end 436.570628 -354.67925)
		(stroke
			(width 0.2)
			(type default)
		)
		(fill no)
		(layer "In16.Cu")
	)
	(gr_circle
		(center 435.681628 -353.94265)
		(end 436.570628 -353.94265)
		(stroke
			(width 0.2)
			(type default)
		)
		(fill no)
		(layer "In16.Cu")
	)
	(gr_circle
		(center 435.681628 -353.20605)
		(end 436.570628 -353.20605)
		(stroke
			(width 0.2)
			(type default)
		)
		(fill no)
		(layer "In16.Cu")
	)
	(gr_circle
		(center 436.231538 -361.496102)
		(end 437.120538 -361.496102)
		(stroke
			(width 0.2)
			(type default)
		)
		(fill no)
		(layer "In16.Cu")
	)
	(gr_circle
		(center 436.231538 -360.734102)
		(end 437.120538 -360.734102)
		(stroke
			(width 0.2)
			(type default)
		)
		(fill no)
		(layer "In16.Cu")
	)
	(gr_circle
		(center 436.231538 -359.972102)
		(end 437.120538 -359.972102)
		(stroke
			(width 0.2)
			(type default)
		)
		(fill no)
		(layer "In16.Cu")
	)
	(gr_circle
		(center 437.703214 -12.400788)
		(end 438.592214 -12.400788)
		(stroke
			(width 0.2)
			(type default)
		)
		(fill no)
		(layer "In16.Cu")
	)
	(gr_circle
		(center 438.06999 -13.069316)
		(end 438.95899 -13.069316)
		(stroke
			(width 0.2)
			(type default)
		)
		(fill no)
		(layer "In16.Cu")
	)
	(gr_circle
		(center 438.592214 -12.400788)
		(end 439.481214 -12.400788)
		(stroke
			(width 0.2)
			(type default)
		)
		(fill no)
		(layer "In16.Cu")
	)
	(gr_circle
		(center 438.71515 -13.061696)
		(end 439.60415 -13.061696)
		(stroke
			(width 0.2)
			(type default)
		)
		(fill no)
		(layer "In16.Cu")
	)
	(gr_circle
		(center 439.39333 -13.043916)
		(end 440.28233 -13.043916)
		(stroke
			(width 0.2)
			(type default)
		)
		(fill no)
		(layer "In16.Cu")
	)
	(gr_circle
		(center 439.481214 -12.400788)
		(end 440.370214 -12.400788)
		(stroke
			(width 0.2)
			(type default)
		)
		(fill no)
		(layer "In16.Cu")
	)
	(gr_circle
		(center 440.945524 -11.261852)
		(end 441.834524 -11.261852)
		(stroke
			(width 0.2)
			(type default)
		)
		(fill no)
		(layer "In16.Cu")
	)
	(gr_circle
		(center 440.945524 -10.626852)
		(end 441.834524 -10.626852)
		(stroke
			(width 0.2)
			(type default)
		)
		(fill no)
		(layer "In16.Cu")
	)
	(gr_circle
		(center 441.129674 -25.982422)
		(end 442.018674 -25.982422)
		(stroke
			(width 0.2)
			(type default)
		)
		(fill no)
		(layer "In16.Cu")
	)
	(gr_circle
		(center 441.354718 -20.73656)
		(end 442.243718 -20.73656)
		(stroke
			(width 0.2)
			(type default)
		)
		(fill no)
		(layer "In16.Cu")
	)
	(gr_circle
		(center 441.354718 -20.10156)
		(end 442.243718 -20.10156)
		(stroke
			(width 0.2)
			(type default)
		)
		(fill no)
		(layer "In16.Cu")
	)
	(gr_circle
		(center 441.354718 -19.21256)
		(end 442.243718 -19.21256)
		(stroke
			(width 0.2)
			(type default)
		)
		(fill no)
		(layer "In16.Cu")
	)
	(gr_circle
		(center 441.354718 -18.57756)
		(end 442.243718 -18.57756)
		(stroke
			(width 0.2)
			(type default)
		)
		(fill no)
		(layer "In16.Cu")
	)
	(gr_circle
		(center 441.475622 -14.123162)
		(end 442.364622 -14.123162)
		(stroke
			(width 0.2)
			(type default)
		)
		(fill no)
		(layer "In16.Cu")
	)
	(gr_circle
		(center 441.475622 -13.488162)
		(end 442.364622 -13.488162)
		(stroke
			(width 0.2)
			(type default)
		)
		(fill no)
		(layer "In16.Cu")
	)
	(gr_circle
		(center 441.56249 -25.461976)
		(end 442.45149 -25.461976)
		(stroke
			(width 0.2)
			(type default)
		)
		(fill no)
		(layer "In16.Cu")
	)
	(gr_circle
		(center 442.018674 -25.982422)
		(end 442.907674 -25.982422)
		(stroke
			(width 0.2)
			(type default)
		)
		(fill no)
		(layer "In16.Cu")
	)
	(gr_circle
		(center 442.371734 -20.983702)
		(end 443.260734 -20.983702)
		(stroke
			(width 0.2)
			(type default)
		)
		(fill no)
		(layer "In16.Cu")
	)
	(gr_circle
		(center 442.371734 -20.348702)
		(end 443.260734 -20.348702)
		(stroke
			(width 0.2)
			(type default)
		)
		(fill no)
		(layer "In16.Cu")
	)
	(gr_circle
		(center 442.371734 -19.459702)
		(end 443.260734 -19.459702)
		(stroke
			(width 0.2)
			(type default)
		)
		(fill no)
		(layer "In16.Cu")
	)
	(gr_circle
		(center 442.371734 -18.824702)
		(end 443.260734 -18.824702)
		(stroke
			(width 0.2)
			(type default)
		)
		(fill no)
		(layer "In16.Cu")
	)
	(gr_circle
		(center 442.45149 -25.461976)
		(end 443.34049 -25.461976)
		(stroke
			(width 0.2)
			(type default)
		)
		(fill no)
		(layer "In16.Cu")
	)
	(gr_circle
		(center 442.907674 -25.982422)
		(end 443.796674 -25.982422)
		(stroke
			(width 0.2)
			(type default)
		)
		(fill no)
		(layer "In16.Cu")
	)
	(gr_circle
		(center 443.34049 -25.461976)
		(end 444.22949 -25.461976)
		(stroke
			(width 0.2)
			(type default)
		)
		(fill no)
		(layer "In16.Cu")
	)
	(gr_circle
		(center 444.166244 -24.741632)
		(end 445.055244 -24.741632)
		(stroke
			(width 0.2)
			(type default)
		)
		(fill no)
		(layer "In16.Cu")
	)
	(gr_circle
		(center 450.669914 -14.526514)
		(end 451.558914 -14.526514)
		(stroke
			(width 0.2)
			(type default)
		)
		(fill no)
		(layer "In16.Cu")
	)
	(gr_circle
		(center 450.670676 -16.010382)
		(end 451.559676 -16.010382)
		(stroke
			(width 0.2)
			(type default)
		)
		(fill no)
		(layer "In16.Cu")
	)
	(gr_circle
		(center 450.670676 -15.273782)
		(end 451.559676 -15.273782)
		(stroke
			(width 0.2)
			(type default)
		)
		(fill no)
		(layer "In16.Cu")
	)
	(gr_circle
		(center 452.054976 -18.535142)
		(end 452.943976 -18.535142)
		(stroke
			(width 0.2)
			(type default)
		)
		(fill no)
		(layer "In16.Cu")
	)
	(gr_circle
		(center 452.054976 -17.798542)
		(end 452.943976 -17.798542)
		(stroke
			(width 0.2)
			(type default)
		)
		(fill no)
		(layer "In16.Cu")
	)
	(gr_line
		(start 455.694034 -9.780016)
		(end 455.694034 -0.508)
		(stroke
			(width 0.2)
			(type default)
		)
		(layer "In16.Cu")
	)
	(gr_arc
		(start 455.694034 -9.780016)
		(mid 456.428616 -11.553416)
		(end 458.20203 -12.288012)
		(stroke
			(width 0.2)
			(type default)
		)
		(layer "In16.Cu")
	)
	(gr_line
		(start 455.694034 -0.508)
		(end 388.109968 -0.508)
		(stroke
			(width 0.2)
			(type default)
		)
		(layer "In16.Cu")
	)
	(gr_arc
		(start 456.202034 -9.780016)
		(mid 456.787819 -11.194227)
		(end 458.20203 -11.780012)
		(stroke
			(width 1.016)
			(type default)
		)
		(layer "In16.Cu")
	)
	(gr_arc
		(start 456.202034 -0.500126)
		(mid 456.05556 -0.146464)
		(end 455.701908 0)
		(stroke
			(width 1.016)
			(type default)
		)
		(layer "In16.Cu")
	)
	(gr_line
		(start 456.202034 -0.500126)
		(end 456.202034 -9.780016)
		(stroke
			(width 1.016)
			(type default)
		)
		(layer "In16.Cu")
	)
	(gr_line
		(start 458.20203 -11.780012)
		(end 469.799924 -11.780012)
		(stroke
			(width 1.016)
			(type default)
		)
		(layer "In16.Cu")
	)
	(gr_line
		(start 463.300064 -441.989972)
		(end 277.314914 -441.989972)
		(stroke
			(width 1.016)
			(type default)
		)
		(layer "In16.Cu")
	)
	(gr_arc
		(start 463.300064 -441.989972)
		(mid 464.71429 -441.404198)
		(end 465.30006 -439.989976)
		(stroke
			(width 1.016)
			(type default)
		)
		(layer "In16.Cu")
	)
	(gr_arc
		(start 463.300064 -441.481972)
		(mid 464.355064 -441.044976)
		(end 464.79206 -439.989976)
		(stroke
			(width 0.2)
			(type default)
		)
		(layer "In16.Cu")
	)
	(gr_line
		(start 464.79206 -439.989976)
		(end 464.79206 -409.528264)
		(stroke
			(width 0.2)
			(type default)
		)
		(layer "In16.Cu")
	)
	(gr_line
		(start 465.30006 -409.528518)
		(end 465.30006 -439.989976)
		(stroke
			(width 1.016)
			(type default)
		)
		(layer "In16.Cu")
	)
	(gr_arc
		(start 465.526628 -407.75509)
		(mid 464.983024 -408.568632)
		(end 464.79206 -409.528264)
		(stroke
			(width 0.2)
			(type default)
		)
		(layer "In16.Cu")
	)
	(gr_line
		(start 465.526628 -407.75509)
		(end 467.355174 -405.926544)
		(stroke
			(width 0.2)
			(type default)
		)
		(layer "In16.Cu")
	)
	(gr_arc
		(start 465.885784 -408.114246)
		(mid 465.452221 -408.76312)
		(end 465.30006 -409.528518)
		(stroke
			(width 1.016)
			(type default)
		)
		(layer "In16.Cu")
	)
	(gr_arc
		(start 467.355174 -405.926544)
		(mid 467.678507 -405.442687)
		(end 467.792054 -404.871936)
		(stroke
			(width 0.2)
			(type default)
		)
		(layer "In16.Cu")
	)
	(gr_line
		(start 467.71433 -406.2857)
		(end 465.885784 -408.114246)
		(stroke
			(width 1.016)
			(type default)
		)
		(layer "In16.Cu")
	)
	(gr_arc
		(start 467.71433 -406.2857)
		(mid 468.147828 -405.636947)
		(end 468.300054 -404.871682)
		(stroke
			(width 1.016)
			(type default)
		)
		(layer "In16.Cu")
	)
	(gr_line
		(start 467.792054 -404.871936)
		(end 467.792054 -82.82813)
		(stroke
			(width 0.2)
			(type default)
		)
		(layer "In16.Cu")
	)
	(gr_line
		(start 468.300054 -82.828384)
		(end 468.300054 -404.871682)
		(stroke
			(width 1.016)
			(type default)
		)
		(layer "In16.Cu")
	)
	(gr_arc
		(start 468.526622 -81.054956)
		(mid 467.983009 -81.868496)
		(end 467.792054 -82.82813)
		(stroke
			(width 0.2)
			(type default)
		)
		(layer "In16.Cu")
	)
	(gr_line
		(start 468.526622 -81.054956)
		(end 470.85504 -78.726538)
		(stroke
			(width 0.2)
			(type default)
		)
		(layer "In16.Cu")
	)
	(gr_arc
		(start 468.885778 -81.414112)
		(mid 468.452215 -82.062986)
		(end 468.300054 -82.828384)
		(stroke
			(width 1.016)
			(type default)
		)
		(layer "In16.Cu")
	)
	(gr_line
		(start 469.799924 -12.288012)
		(end 458.20203 -12.288012)
		(stroke
			(width 0.2)
			(type default)
		)
		(layer "In16.Cu")
	)
	(gr_arc
		(start 470.85504 -78.726538)
		(mid 471.178373 -78.242681)
		(end 471.29192 -77.67193)
		(stroke
			(width 0.2)
			(type default)
		)
		(layer "In16.Cu")
	)
	(gr_line
		(start 471.214196 -79.085694)
		(end 468.885778 -81.414112)
		(stroke
			(width 1.016)
			(type default)
		)
		(layer "In16.Cu")
	)
	(gr_arc
		(start 471.214196 -79.085694)
		(mid 471.6477 -78.436942)
		(end 471.79992 -77.671676)
		(stroke
			(width 1.016)
			(type default)
		)
		(layer "In16.Cu")
	)
	(gr_line
		(start 471.29192 -77.67193)
		(end 471.29192 -13.780008)
		(stroke
			(width 0.2)
			(type default)
		)
		(layer "In16.Cu")
	)
	(gr_arc
		(start 471.29192 -13.780008)
		(mid 470.854924 -12.725008)
		(end 469.799924 -12.288012)
		(stroke
			(width 0.2)
			(type default)
		)
		(layer "In16.Cu")
	)
	(gr_arc
		(start 471.79992 -13.780008)
		(mid 471.214139 -12.365784)
		(end 469.799924 -11.780012)
		(stroke
			(width 1.016)
			(type default)
		)
		(layer "In16.Cu")
	)
	(gr_line
		(start 471.79992 -13.780008)
		(end 471.79992 -77.671676)
		(stroke
			(width 1.016)
			(type default)
		)
		(layer "In16.Cu")
	)
	(segment
		(start 265.276076 -420.404798)
		(end 265.56843 -420.112444)
		(width 0.10668)
		(layer "F.Cu")
		(net "PDB_PRSNT_R_N")
	)
	(segment
		(start 269.431516 -420.65194)
		(end 270.125444 -420.65194)
		(width 0.10668)
		(layer "F.Cu")
		(net "PDB_PRSNT_R_N")
	)
	(segment
		(start 267.53566 -419.628828)
		(end 265.56843 -419.628828)
		(width 0.10668)
		(layer "F.Cu")
		(net "PDB_PRSNT_R_N")
	)
	(segment
		(start 271.328134 -420.83863)
		(end 270.312134 -420.83863)
		(width 0.10668)
		(layer "F.Cu")
		(net "PDB_PRSNT_R_N")
	)
	(segment
		(start 267.800328 -419.628828)
		(end 267.53566 -419.628828)
		(width 0.10668)
		(layer "F.Cu")
		(net "PDB_PRSNT_R_N")
	)
	(segment
		(start 265.56843 -420.112444)
		(end 265.56843 -419.628828)
		(width 0.10668)
		(layer "F.Cu")
		(net "PDB_PRSNT_R_N")
	)
	(segment
		(start 270.125444 -420.65194)
		(end 270.312134 -420.83863)
		(width 0.10668)
		(layer "F.Cu")
		(net "PDB_PRSNT_R_N")
	)
	(segment
		(start 266.333478 -422.226486)
		(end 265.276076 -421.169084)
		(width 0.10668)
		(layer "F.Cu")
		(net "PDB_PRSNT_R_N")
	)
	(segment
		(start 269.42796 -420.648384)
		(end 269.431516 -420.65194)
		(width 0.10668)
		(layer "F.Cu")
		(net "PDB_PRSNT_R_N")
	)
	(segment
		(start 265.276076 -421.169084)
		(end 265.276076 -420.404798)
		(width 0.10668)
		(layer "F.Cu")
		(net "PDB_PRSNT_R_N")
	)
	(segment
		(start 266.726416 -422.226486)
		(end 266.333478 -422.226486)
		(width 0.10668)
		(layer "F.Cu")
		(net "PDB_PRSNT_R_N")
	)
	(segment
		(start 268.819884 -420.648384)
		(end 269.42796 -420.648384)
		(width 0.10668)
		(layer "F.Cu")
		(net "PDB_PRSNT_R_N")
	)
	(segment
		(start 268.819884 -420.648384)
		(end 267.800328 -419.628828)
		(width 0.10668)
		(layer "F.Cu")
		(net "PDB_PRSNT_R_N")
	)
	(segment
		(start 274.56638 -419.343332)
		(end 273.409918 -419.343332)
		(width 0.10668)
		(layer "F.Cu")
		(net "PDB_PRSNT_R_N")
	)
	(segment
		(start 271.91462 -420.83863)
		(end 271.328134 -420.83863)
		(width 0.10668)
		(layer "F.Cu")
		(net "PDB_PRSNT_R_N")
	)
	(segment
		(start 273.409918 -419.343332)
		(end 271.91462 -420.83863)
		(width 0.10668)
		(layer "F.Cu")
		(net "PDB_PRSNT_R_N")
	)
	(via
		(at 267.53566 -419.628828)
		(size 0.508)
		(drill 0.254)
		(layers "F.Cu" "B.Cu")
		(net "PDB_PRSNT_R_N")
	)
	(segment
		(start 63.65621 -56.98998)
		(end 63.18504 -56.51881)
		(width 0.10668)
		(layer "F.Cu")
		(net "OCP_V3_2_P3V3_R3_PWRGD")
	)
	(segment
		(start 65.88379 -51.75504)
		(end 66.87439 -52.74564)
		(width 0.10668)
		(layer "F.Cu")
		(net "OCP_V3_2_P3V3_R3_PWRGD")
	)
	(segment
		(start 62.3824 -52.86248)
		(end 63.48984 -51.75504)
		(width 0.10668)
		(layer "F.Cu")
		(net "OCP_V3_2_P3V3_R3_PWRGD")
	)
	(segment
		(start 68.56095 -54.61)
		(end 68.56095 -55.2958)
		(width 0.10668)
		(layer "F.Cu")
		(net "OCP_V3_2_P3V3_R3_PWRGD")
	)
	(segment
		(start 63.65621 -56.98998)
		(end 66.00571 -59.33948)
		(width 0.10668)
		(layer "F.Cu")
		(net "OCP_V3_2_P3V3_R3_PWRGD")
	)
	(segment
		(start 63.18504 -55.45836)
		(end 62.3824 -54.65572)
		(width 0.10668)
		(layer "F.Cu")
		(net "OCP_V3_2_P3V3_R3_PWRGD")
	)
	(segment
		(start 62.3824 -54.65572)
		(end 62.3824 -52.86248)
		(width 0.10668)
		(layer "F.Cu")
		(net "OCP_V3_2_P3V3_R3_PWRGD")
	)
	(segment
		(start 71.685404 -63.369444)
		(end 73.393046 -63.369444)
		(width 0.10668)
		(layer "F.Cu")
		(net "OCP_V3_2_P3V3_R3_PWRGD")
	)
	(segment
		(start 63.18504 -56.51881)
		(end 63.18504 -55.45836)
		(width 0.10668)
		(layer "F.Cu")
		(net "OCP_V3_2_P3V3_R3_PWRGD")
	)
	(segment
		(start 67.65544 -51.57978)
		(end 67.65544 -51.96459)
		(width 0.10668)
		(layer "F.Cu")
		(net "OCP_V3_2_P3V3_R3_PWRGD")
	)
	(segment
		(start 67.65544 -59.33948)
		(end 71.685404 -63.369444)
		(width 0.10668)
		(layer "F.Cu")
		(net "OCP_V3_2_P3V3_R3_PWRGD")
	)
	(segment
		(start 63.48984 -51.75504)
		(end 65.88379 -51.75504)
		(width 0.10668)
		(layer "F.Cu")
		(net "OCP_V3_2_P3V3_R3_PWRGD")
	)
	(segment
		(start 67.65544 -51.96459)
		(end 66.87439 -52.74564)
		(width 0.10668)
		(layer "F.Cu")
		(net "OCP_V3_2_P3V3_R3_PWRGD")
	)
	(segment
		(start 66.00571 -59.33948)
		(end 67.65544 -59.33948)
		(width 0.10668)
		(layer "F.Cu")
		(net "OCP_V3_2_P3V3_R3_PWRGD")
	)
	(via
		(at 68.56095 -55.2958)
		(size 0.508)
		(drill 0.254)
		(layers "F.Cu" "B.Cu")
		(net "OCP_V3_2_P3V3_R3_PWRGD")
	)
	(via
		(at 67.65544 -51.57978)
		(size 0.508)
		(drill 0.254)
		(layers "F.Cu" "B.Cu")
		(net "OCP_V3_2_P3V3_R3_PWRGD")
	)
	(segment
		(start 67.65544 -52.5018)
		(end 67.65544 -51.57978)
		(width 0.11684)
		(layer "In6.Cu")
		(net "OCP_V3_2_P3V3_R3_PWRGD")
	)
	(segment
		(start 68.56095 -55.2958)
		(end 68.56095 -53.40731)
		(width 0.11684)
		(layer "In6.Cu")
		(net "OCP_V3_2_P3V3_R3_PWRGD")
	)
	(segment
		(start 68.56095 -53.40731)
		(end 67.65544 -52.5018)
		(width 0.11684)
		(layer "In6.Cu")
		(net "OCP_V3_2_P3V3_R3_PWRGD")
	)
	(segment
		(start 219.665804 -104.535478)
		(end 221.38513 -106.254804)
		(width 0.10668)
		(layer "F.Cu")
		(net "OCP_V3_1_P3V3_R3_PWRGD")
	)
	(segment
		(start 219.665804 -104.535478)
		(end 219.802964 -104.398318)
		(width 0.10668)
		(layer "F.Cu")
		(net "OCP_V3_1_P3V3_R3_PWRGD")
	)
	(segment
		(start 219.802964 -99.783138)
		(end 219.460826 -99.441)
		(width 0.10668)
		(layer "F.Cu")
		(net "OCP_V3_1_P3V3_R3_PWRGD")
	)
	(segment
		(start 219.39631 -97.70999)
		(end 220.26626 -97.70999)
		(width 0.10668)
		(layer "F.Cu")
		(net "OCP_V3_1_P3V3_R3_PWRGD")
	)
	(segment
		(start 219.460826 -99.441)
		(end 218.96705 -99.441)
		(width 0.10668)
		(layer "F.Cu")
		(net "OCP_V3_1_P3V3_R3_PWRGD")
	)
	(segment
		(start 218.96705 -98.13925)
		(end 219.39631 -97.70999)
		(width 0.10668)
		(layer "F.Cu")
		(net "OCP_V3_1_P3V3_R3_PWRGD")
	)
	(segment
		(start 219.802964 -104.398318)
		(end 219.802964 -100.00234)
		(width 0.10668)
		(layer "F.Cu")
		(net "OCP_V3_1_P3V3_R3_PWRGD")
	)
	(segment
		(start 221.38513 -106.254804)
		(end 221.38513 -106.35488)
		(width 0.10668)
		(layer "F.Cu")
		(net "OCP_V3_1_P3V3_R3_PWRGD")
	)
	(segment
		(start 215.519 -115.55095)
		(end 215.519 -114.840512)
		(width 0.10668)
		(layer "F.Cu")
		(net "OCP_V3_1_P3V3_R3_PWRGD")
	)
	(segment
		(start 218.96705 -99.441)
		(end 218.96705 -98.13925)
		(width 0.10668)
		(layer "F.Cu")
		(net "OCP_V3_1_P3V3_R3_PWRGD")
	)
	(segment
		(start 219.802964 -100.00234)
		(end 219.802964 -99.783138)
		(width 0.10668)
		(layer "F.Cu")
		(net "OCP_V3_1_P3V3_R3_PWRGD")
	)
	(via
		(at 219.802964 -100.00234)
		(size 0.762)
		(drill 0.381)
		(layers "F.Cu" "B.Cu")
		(net "OCP_V3_1_P3V3_R3_PWRGD")
	)
	(via
		(at 215.519 -114.840512)
		(size 0.508)
		(drill 0.254)
		(layers "F.Cu" "B.Cu")
		(net "OCP_V3_1_P3V3_R3_PWRGD")
	)
	(via
		(at 219.665804 -104.535478)
		(size 0.508)
		(drill 0.254)
		(layers "F.Cu" "B.Cu")
		(net "OCP_V3_1_P3V3_R3_PWRGD")
	)
	(segment
		(start 219.665804 -104.535478)
		(end 219.665804 -106.961178)
		(width 0.11684)
		(layer "In4.Cu")
		(net "OCP_V3_1_P3V3_R3_PWRGD")
	)
	(segment
		(start 219.665804 -106.961178)
		(end 219.87891 -107.174284)
		(width 0.11684)
		(layer "In4.Cu")
		(net "OCP_V3_1_P3V3_R3_PWRGD")
	)
	(segment
		(start 219.87891 -107.174284)
		(end 219.87891 -113.554002)
		(width 0.11684)
		(layer "In4.Cu")
		(net "OCP_V3_1_P3V3_R3_PWRGD")
	)
	(segment
		(start 219.87891 -113.554002)
		(end 218.5924 -114.840512)
		(width 0.11684)
		(layer "In4.Cu")
		(net "OCP_V3_1_P3V3_R3_PWRGD")
	)
	(segment
		(start 218.5924 -114.840512)
		(end 215.519 -114.840512)
		(width 0.11684)
		(layer "In4.Cu")
		(net "OCP_V3_1_P3V3_R3_PWRGD")
	)
	(segment
		(start 64.106806 -52.743354)
		(end 63.539624 -52.743354)
		(width 0.10668)
		(layer "F.Cu")
		(net "HP_LVC3_OCP_V3_2_PWRGD_R2")
	)
	(segment
		(start 64.389 -52.46116)
		(end 64.106806 -52.743354)
		(width 0.10668)
		(layer "F.Cu")
		(net "HP_LVC3_OCP_V3_2_PWRGD_R2")
	)
	(segment
		(start 65.04686 -52.46116)
		(end 64.389 -52.46116)
		(width 0.10668)
		(layer "F.Cu")
		(net "HP_LVC3_OCP_V3_2_PWRGD_R2")
	)
	(segment
		(start 66.07429 -52.74564)
		(end 65.78981 -52.46116)
		(width 0.10668)
		(layer "F.Cu")
		(net "HP_LVC3_OCP_V3_2_PWRGD_R2")
	)
	(segment
		(start 65.78981 -52.46116)
		(end 65.04686 -52.46116)
		(width 0.10668)
		(layer "F.Cu")
		(net "HP_LVC3_OCP_V3_2_PWRGD_R2")
	)
	(via
		(at 65.04686 -52.46116)
		(size 0.762)
		(drill 0.381)
		(layers "F.Cu" "B.Cu")
		(net "HP_LVC3_OCP_V3_2_PWRGD_R2")
	)
	(segment
		(start 59.38139 -53.06949)
		(end 60.005214 -53.693314)
		(width 0.10668)
		(layer "F.Cu")
		(net "HP_LVC3_OCP_V3_2_P12V_PWRGD_R2")
	)
	(segment
		(start 60.005214 -53.693314)
		(end 61.139832 -53.693314)
		(width 0.10668)
		(layer "F.Cu")
		(net "HP_LVC3_OCP_V3_2_P12V_PWRGD_R2")
	)
	(segment
		(start 57.80913 -52.53228)
		(end 58.84418 -52.53228)
		(width 0.10668)
		(layer "F.Cu")
		(net "HP_LVC3_OCP_V3_2_P12V_PWRGD_R2")
	)
	(segment
		(start 58.84418 -52.53228)
		(end 59.38139 -53.06949)
		(width 0.10668)
		(layer "F.Cu")
		(net "HP_LVC3_OCP_V3_2_P12V_PWRGD_R2")
	)
	(via
		(at 59.38139 -53.06949)
		(size 0.762)
		(drill 0.381)
		(layers "F.Cu" "B.Cu")
		(net "HP_LVC3_OCP_V3_2_P12V_PWRGD_R2")
	)
	(segment
		(start 218.868244 -104.12222)
		(end 218.799664 -104.12222)
		(width 0.10668)
		(layer "F.Cu")
		(net "HP_LVC3_OCP_V3_1_PWRGD_R2")
	)
	(segment
		(start 220.58503 -106.35488)
		(end 219.94368 -106.35488)
		(width 0.10668)
		(layer "F.Cu")
		(net "HP_LVC3_OCP_V3_1_PWRGD_R2")
	)
	(segment
		(start 219.554044 -105.965244)
		(end 219.17406 -105.58526)
		(width 0.10668)
		(layer "F.Cu")
		(net "HP_LVC3_OCP_V3_1_PWRGD_R2")
	)
	(segment
		(start 219.94368 -106.35488)
		(end 219.554044 -105.965244)
		(width 0.10668)
		(layer "F.Cu")
		(net "HP_LVC3_OCP_V3_1_PWRGD_R2")
	)
	(segment
		(start 219.17406 -104.428036)
		(end 218.868244 -104.12222)
		(width 0.10668)
		(layer "F.Cu")
		(net "HP_LVC3_OCP_V3_1_PWRGD_R2")
	)
	(segment
		(start 219.17406 -105.58526)
		(end 219.17406 -104.428036)
		(width 0.10668)
		(layer "F.Cu")
		(net "HP_LVC3_OCP_V3_1_PWRGD_R2")
	)
	(via
		(at 219.554044 -105.965244)
		(size 0.762)
		(drill 0.381)
		(layers "F.Cu" "B.Cu")
		(net "HP_LVC3_OCP_V3_1_PWRGD_R2")
	)
	(segment
		(start 221.81058 -100.527866)
		(end 221.81058 -103.04526)
		(width 0.10668)
		(layer "F.Cu")
		(net "HP_LVC3_OCP_V3_1_P12V_R2_PWRGD")
	)
	(segment
		(start 221.68358 -103.17226)
		(end 221.199456 -103.17226)
		(width 0.10668)
		(layer "F.Cu")
		(net "HP_LVC3_OCP_V3_1_P12V_R2_PWRGD")
	)
	(segment
		(start 221.28226 -98.51009)
		(end 221.28226 -99.50704)
		(width 0.10668)
		(layer "F.Cu")
		(net "HP_LVC3_OCP_V3_1_P12V_R2_PWRGD")
	)
	(segment
		(start 221.28226 -99.50704)
		(end 221.28226 -99.999546)
		(width 0.10668)
		(layer "F.Cu")
		(net "HP_LVC3_OCP_V3_1_P12V_R2_PWRGD")
	)
	(segment
		(start 221.28226 -99.999546)
		(end 221.81058 -100.527866)
		(width 0.10668)
		(layer "F.Cu")
		(net "HP_LVC3_OCP_V3_1_P12V_R2_PWRGD")
	)
	(segment
		(start 221.81058 -103.04526)
		(end 221.68358 -103.17226)
		(width 0.10668)
		(layer "F.Cu")
		(net "HP_LVC3_OCP_V3_1_P12V_R2_PWRGD")
	)
	(via
		(at 221.28226 -99.50704)
		(size 0.762)
		(drill 0.381)
		(layers "F.Cu" "B.Cu")
		(net "HP_LVC3_OCP_V3_1_P12V_R2_PWRGD")
	)
	(via
		(at 48.07966 -100.76942)
		(size 0.508)
		(drill 0.254)
		(layers "F.Cu" "B.Cu")
		(net "P3V3_AUX_DSC_VOL")
	)
	(via
		(at 47.03064 -106.48188)
		(size 0.508)
		(drill 0.254)
		(layers "F.Cu" "B.Cu")
		(net "P3V3_AUX_DSC_S1")
	)
	(via
		(at 46.1137 -112.08766)
		(size 0.508)
		(drill 0.254)
		(layers "F.Cu" "B.Cu")
		(net "P3V3_AUX_DSC_G2")
	)
	(via
		(at 45.12945 -106.49204)
		(size 0.508)
		(drill 0.254)
		(layers "F.Cu" "B.Cu")
		(net "P3V3_AUX_DSC_G1")
	)
	(via
		(at 43.69054 -120.6246)
		(size 0.508)
		(drill 0.254)
		(layers "F.Cu" "B.Cu")
		(net "P3V3_AUX_DSC")
	)
	(via
		(at 41.35882 -100.82022)
		(size 0.508)
		(drill 0.254)
		(layers "F.Cu" "B.Cu")
		(net "P12V_AUX_DSC_VOL")
	)
	(via
		(at 40.22852 -106.61904)
		(size 0.508)
		(drill 0.254)
		(layers "F.Cu" "B.Cu")
		(net "P12V_AUX_DSC_S1")
	)
	(via
		(at 39.31158 -112.22482)
		(size 0.508)
		(drill 0.254)
		(layers "F.Cu" "B.Cu")
		(net "P12V_AUX_DSC_G2")
	)
	(via
		(at 37.4523 -107.66044)
		(size 0.508)
		(drill 0.254)
		(layers "F.Cu" "B.Cu")
		(net "P12V_AUX_DSC_G1")
	)
	(via
		(at 37.54374 -120.83034)
		(size 0.508)
		(drill 0.254)
		(layers "F.Cu" "B.Cu")
		(net "P12V_AUX_DSC")
	)
	(segment
		(start 189.92215 -115.452906)
		(end 190.31204 -115.842796)
		(width 0.10668)
		(layer "F.Cu")
		(net "Net_19")
	)
	(via
		(at 190.31204 -115.842796)
		(size 0.4572)
		(drill 0.254)
		(layers "F.Cu" "B.Cu")
		(net "Net_19")
	)
	(segment
		(start 205.198218 -195.635372)
		(end 205.010258 -195.823332)
		(width 0.10668)
		(layer "F.Cu")
		(net "I3C_SPD_DDRL_CPU1_SDA")
	)
	(segment
		(start 206.248 -195.635372)
		(end 205.198218 -195.635372)
		(width 0.10668)
		(layer "F.Cu")
		(net "I3C_SPD_DDRL_CPU1_SDA")
	)
	(via
		(at 205.010258 -195.823332)
		(size 0.508)
		(drill 0.254)
		(layers "F.Cu" "B.Cu")
		(net "I3C_SPD_DDRL_CPU1_SDA")
	)
	(segment
		(start 205.82128 -195.95211)
		(end 205.139036 -195.95211)
		(width 0.10668)
		(layer "B.Cu")
		(net "I3C_SPD_DDRL_CPU1_SDA")
	)
	(segment
		(start 205.139036 -195.95211)
		(end 205.010258 -195.823332)
		(width 0.10668)
		(layer "B.Cu")
		(net "I3C_SPD_DDRL_CPU1_SDA")
	)
	(segment
		(start 454.188068 -195.635118)
		(end 455.343768 -195.635118)
		(width 0.10668)
		(layer "F.Cu")
		(net "I3C_SPD_DDRL_CPU0_SDA")
	)
	(via
		(at 455.343768 -195.635118)
		(size 0.4826)
		(drill 0.254)
		(layers "F.Cu" "B.Cu")
		(net "I3C_SPD_DDRL_CPU0_SDA")
	)
	(segment
		(start 455.052176 -195.92671)
		(end 455.343768 -195.635118)
		(width 0.10668)
		(layer "B.Cu")
		(net "I3C_SPD_DDRL_CPU0_SDA")
	)
	(segment
		(start 453.832468 -195.92671)
		(end 455.052176 -195.92671)
		(width 0.10668)
		(layer "B.Cu")
		(net "I3C_SPD_DDRL_CPU0_SDA")
	)
	(segment
		(start 199.8599 -195.635372)
		(end 198.7042 -195.635372)
		(width 0.10668)
		(layer "F.Cu")
		(net "I3C_SPD_DDRK_CPU1_SDA")
	)
	(via
		(at 199.8599 -195.635372)
		(size 0.4826)
		(drill 0.254)
		(layers "F.Cu" "B.Cu")
		(net "I3C_SPD_DDRK_CPU1_SDA")
	)
	(segment
		(start 199.635872 -195.8594)
		(end 199.8599 -195.635372)
		(width 0.10668)
		(layer "B.Cu")
		(net "I3C_SPD_DDRK_CPU1_SDA")
	)
	(segment
		(start 198.3486 -195.8594)
		(end 199.635872 -195.8594)
		(width 0.10668)
		(layer "B.Cu")
		(net "I3C_SPD_DDRK_CPU1_SDA")
	)
	(segment
		(start 446.644268 -195.635118)
		(end 447.799968 -195.635118)
		(width 0.10668)
		(layer "F.Cu")
		(net "I3C_SPD_DDRK_CPU0_SDA")
	)
	(via
		(at 447.799968 -195.635118)
		(size 0.4826)
		(drill 0.254)
		(layers "F.Cu" "B.Cu")
		(net "I3C_SPD_DDRK_CPU0_SDA")
	)
	(segment
		(start 447.574416 -195.86067)
		(end 447.799968 -195.635118)
		(width 0.10668)
		(layer "B.Cu")
		(net "I3C_SPD_DDRK_CPU0_SDA")
	)
	(segment
		(start 446.288414 -195.86067)
		(end 447.574416 -195.86067)
		(width 0.10668)
		(layer "B.Cu")
		(net "I3C_SPD_DDRK_CPU0_SDA")
	)
	(segment
		(start 191.160146 -195.635372)
		(end 192.315846 -195.635372)
		(width 0.10668)
		(layer "F.Cu")
		(net "I3C_SPD_DDRJ_CPU1_SDA")
	)
	(via
		(at 192.315846 -195.635372)
		(size 0.4826)
		(drill 0.254)
		(layers "F.Cu" "B.Cu")
		(net "I3C_SPD_DDRJ_CPU1_SDA")
	)
	(segment
		(start 192.091818 -195.8594)
		(end 192.315846 -195.635372)
		(width 0.10668)
		(layer "B.Cu")
		(net "I3C_SPD_DDRJ_CPU1_SDA")
	)
	(segment
		(start 190.804546 -195.8594)
		(end 192.091818 -195.8594)
		(width 0.10668)
		(layer "B.Cu")
		(net "I3C_SPD_DDRJ_CPU1_SDA")
	)
	(segment
		(start 439.100214 -195.635118)
		(end 440.255914 -195.635118)
		(width 0.10668)
		(layer "F.Cu")
		(net "I3C_SPD_DDRJ_CPU0_SDA")
	)
	(via
		(at 440.255914 -195.635118)
		(size 0.4826)
		(drill 0.254)
		(layers "F.Cu" "B.Cu")
		(net "I3C_SPD_DDRJ_CPU0_SDA")
	)
	(segment
		(start 440.031886 -195.859146)
		(end 440.255914 -195.635118)
		(width 0.10668)
		(layer "B.Cu")
		(net "I3C_SPD_DDRJ_CPU0_SDA")
	)
	(segment
		(start 438.744614 -195.859146)
		(end 440.031886 -195.859146)
		(width 0.10668)
		(layer "B.Cu")
		(net "I3C_SPD_DDRJ_CPU0_SDA")
	)
	(segment
		(start 183.616092 -195.635372)
		(end 184.771792 -195.635372)
		(width 0.10668)
		(layer "F.Cu")
		(net "I3C_SPD_DDRI_CPU1_SDA")
	)
	(via
		(at 184.771792 -195.635372)
		(size 0.4826)
		(drill 0.254)
		(layers "F.Cu" "B.Cu")
		(net "I3C_SPD_DDRI_CPU1_SDA")
	)
	(segment
		(start 184.547764 -195.8594)
		(end 184.771792 -195.635372)
		(width 0.10668)
		(layer "B.Cu")
		(net "I3C_SPD_DDRI_CPU1_SDA")
	)
	(segment
		(start 183.260746 -195.8594)
		(end 184.547764 -195.8594)
		(width 0.10668)
		(layer "B.Cu")
		(net "I3C_SPD_DDRI_CPU1_SDA")
	)
	(segment
		(start 431.55616 -195.635118)
		(end 432.71186 -195.635118)
		(width 0.10668)
		(layer "F.Cu")
		(net "I3C_SPD_DDRI_CPU0_SDA")
	)
	(via
		(at 432.71186 -195.635118)
		(size 0.4826)
		(drill 0.254)
		(layers "F.Cu" "B.Cu")
		(net "I3C_SPD_DDRI_CPU0_SDA")
	)
	(segment
		(start 432.496468 -195.85051)
		(end 432.71186 -195.635118)
		(width 0.10668)
		(layer "B.Cu")
		(net "I3C_SPD_DDRI_CPU0_SDA")
	)
	(segment
		(start 431.20056 -195.85051)
		(end 432.496468 -195.85051)
		(width 0.10668)
		(layer "B.Cu")
		(net "I3C_SPD_DDRI_CPU0_SDA")
	)
	(segment
		(start 176.072038 -195.635372)
		(end 177.227738 -195.635372)
		(width 0.10668)
		(layer "F.Cu")
		(net "I3C_SPD_DDRH_CPU1_SDA")
	)
	(via
		(at 177.227738 -195.635372)
		(size 0.4826)
		(drill 0.254)
		(layers "F.Cu" "B.Cu")
		(net "I3C_SPD_DDRH_CPU1_SDA")
	)
	(segment
		(start 177.00371 -195.8594)
		(end 177.227738 -195.635372)
		(width 0.10668)
		(layer "B.Cu")
		(net "I3C_SPD_DDRH_CPU1_SDA")
	)
	(segment
		(start 175.716692 -195.8594)
		(end 177.00371 -195.8594)
		(width 0.10668)
		(layer "B.Cu")
		(net "I3C_SPD_DDRH_CPU1_SDA")
	)
	(segment
		(start 424.012106 -195.635118)
		(end 425.167806 -195.635118)
		(width 0.10668)
		(layer "F.Cu")
		(net "I3C_SPD_DDRH_CPU0_SDA")
	)
	(via
		(at 425.167806 -195.635118)
		(size 0.4826)
		(drill 0.254)
		(layers "F.Cu" "B.Cu")
		(net "I3C_SPD_DDRH_CPU0_SDA")
	)
	(segment
		(start 424.952414 -195.85051)
		(end 425.167806 -195.635118)
		(width 0.10668)
		(layer "B.Cu")
		(net "I3C_SPD_DDRH_CPU0_SDA")
	)
	(segment
		(start 423.656506 -195.85051)
		(end 424.952414 -195.85051)
		(width 0.10668)
		(layer "B.Cu")
		(net "I3C_SPD_DDRH_CPU0_SDA")
	)
	(segment
		(start 168.527984 -195.635372)
		(end 169.683684 -195.635372)
		(width 0.10668)
		(layer "F.Cu")
		(net "I3C_SPD_DDRG_CPU1_SDA")
	)
	(via
		(at 169.683684 -195.635372)
		(size 0.4826)
		(drill 0.254)
		(layers "F.Cu" "B.Cu")
		(net "I3C_SPD_DDRG_CPU1_SDA")
	)
	(segment
		(start 169.459656 -195.8594)
		(end 169.683684 -195.635372)
		(width 0.10668)
		(layer "B.Cu")
		(net "I3C_SPD_DDRG_CPU1_SDA")
	)
	(segment
		(start 168.172638 -195.8594)
		(end 169.459656 -195.8594)
		(width 0.10668)
		(layer "B.Cu")
		(net "I3C_SPD_DDRG_CPU1_SDA")
	)
	(segment
		(start 416.468052 -195.635118)
		(end 417.623752 -195.635118)
		(width 0.10668)
		(layer "F.Cu")
		(net "I3C_SPD_DDRG_CPU0_SDA")
	)
	(via
		(at 417.623752 -195.635118)
		(size 0.4826)
		(drill 0.254)
		(layers "F.Cu" "B.Cu")
		(net "I3C_SPD_DDRG_CPU0_SDA")
	)
	(segment
		(start 417.40836 -195.85051)
		(end 417.623752 -195.635118)
		(width 0.10668)
		(layer "B.Cu")
		(net "I3C_SPD_DDRG_CPU0_SDA")
	)
	(segment
		(start 416.112452 -195.85051)
		(end 417.40836 -195.85051)
		(width 0.10668)
		(layer "B.Cu")
		(net "I3C_SPD_DDRG_CPU0_SDA")
	)
	(segment
		(start 21.70811 -195.635372)
		(end 22.86381 -195.635372)
		(width 0.10668)
		(layer "F.Cu")
		(net "I3C_SPD_DDRF_CPU1_SDA")
	)
	(via
		(at 22.86381 -195.635372)
		(size 0.4826)
		(drill 0.254)
		(layers "F.Cu" "B.Cu")
		(net "I3C_SPD_DDRF_CPU1_SDA")
	)
	(segment
		(start 22.572218 -195.926964)
		(end 22.86381 -195.635372)
		(width 0.10668)
		(layer "B.Cu")
		(net "I3C_SPD_DDRF_CPU1_SDA")
	)
	(segment
		(start 21.319236 -195.926964)
		(end 22.572218 -195.926964)
		(width 0.10668)
		(layer "B.Cu")
		(net "I3C_SPD_DDRF_CPU1_SDA")
	)
	(segment
		(start 269.648178 -195.635118)
		(end 270.803878 -195.635118)
		(width 0.10668)
		(layer "F.Cu")
		(net "I3C_SPD_DDRF_CPU0_SDA")
	)
	(via
		(at 270.803878 -195.635118)
		(size 0.4826)
		(drill 0.254)
		(layers "F.Cu" "B.Cu")
		(net "I3C_SPD_DDRF_CPU0_SDA")
	)
	(segment
		(start 270.57985 -195.859146)
		(end 270.803878 -195.635118)
		(width 0.10668)
		(layer "B.Cu")
		(net "I3C_SPD_DDRF_CPU0_SDA")
	)
	(segment
		(start 269.292578 -195.859146)
		(end 270.57985 -195.859146)
		(width 0.10668)
		(layer "B.Cu")
		(net "I3C_SPD_DDRF_CPU0_SDA")
	)
	(segment
		(start 29.252164 -195.635372)
		(end 30.407864 -195.635372)
		(width 0.10668)
		(layer "F.Cu")
		(net "I3C_SPD_DDRE_CPU1_SDA")
	)
	(via
		(at 30.407864 -195.635372)
		(size 0.4826)
		(drill 0.254)
		(layers "F.Cu" "B.Cu")
		(net "I3C_SPD_DDRE_CPU1_SDA")
	)
	(segment
		(start 30.116272 -195.926964)
		(end 30.407864 -195.635372)
		(width 0.10668)
		(layer "B.Cu")
		(net "I3C_SPD_DDRE_CPU1_SDA")
	)
	(segment
		(start 28.86329 -195.926964)
		(end 30.116272 -195.926964)
		(width 0.10668)
		(layer "B.Cu")
		(net "I3C_SPD_DDRE_CPU1_SDA")
	)
	(segment
		(start 277.192232 -195.635118)
		(end 278.347932 -195.635118)
		(width 0.10668)
		(layer "F.Cu")
		(net "I3C_SPD_DDRE_CPU0_SDA")
	)
	(via
		(at 278.347932 -195.635118)
		(size 0.4826)
		(drill 0.254)
		(layers "F.Cu" "B.Cu")
		(net "I3C_SPD_DDRE_CPU0_SDA")
	)
	(segment
		(start 278.123904 -195.859146)
		(end 278.347932 -195.635118)
		(width 0.10668)
		(layer "B.Cu")
		(net "I3C_SPD_DDRE_CPU0_SDA")
	)
	(segment
		(start 276.836632 -195.859146)
		(end 278.123904 -195.859146)
		(width 0.10668)
		(layer "B.Cu")
		(net "I3C_SPD_DDRE_CPU0_SDA")
	)
	(segment
		(start 36.795964 -195.635372)
		(end 37.951664 -195.635372)
		(width 0.10668)
		(layer "F.Cu")
		(net "I3C_SPD_DDRD_CPU1_SDA")
	)
	(via
		(at 37.951664 -195.635372)
		(size 0.4826)
		(drill 0.254)
		(layers "F.Cu" "B.Cu")
		(net "I3C_SPD_DDRD_CPU1_SDA")
	)
	(segment
		(start 36.440618 -195.8848)
		(end 37.702236 -195.8848)
		(width 0.10668)
		(layer "B.Cu")
		(net "I3C_SPD_DDRD_CPU1_SDA")
	)
	(segment
		(start 37.702236 -195.8848)
		(end 37.951664 -195.635372)
		(width 0.10668)
		(layer "B.Cu")
		(net "I3C_SPD_DDRD_CPU1_SDA")
	)
	(segment
		(start 284.736032 -195.635118)
		(end 285.891732 -195.635118)
		(width 0.10668)
		(layer "F.Cu")
		(net "I3C_SPD_DDRD_CPU0_SDA")
	)
	(via
		(at 285.891732 -195.635118)
		(size 0.4826)
		(drill 0.254)
		(layers "F.Cu" "B.Cu")
		(net "I3C_SPD_DDRD_CPU0_SDA")
	)
	(segment
		(start 285.667704 -195.859146)
		(end 285.891732 -195.635118)
		(width 0.10668)
		(layer "B.Cu")
		(net "I3C_SPD_DDRD_CPU0_SDA")
	)
	(segment
		(start 284.380686 -195.859146)
		(end 285.667704 -195.859146)
		(width 0.10668)
		(layer "B.Cu")
		(net "I3C_SPD_DDRD_CPU0_SDA")
	)
	(segment
		(start 44.340018 -195.635372)
		(end 45.495718 -195.635372)
		(width 0.10668)
		(layer "F.Cu")
		(net "I3C_SPD_DDRC_CPU1_SDA")
	)
	(via
		(at 45.495718 -195.635372)
		(size 0.4826)
		(drill 0.254)
		(layers "F.Cu" "B.Cu")
		(net "I3C_SPD_DDRC_CPU1_SDA")
	)
	(segment
		(start 43.976798 -195.901564)
		(end 45.229526 -195.901564)
		(width 0.10668)
		(layer "B.Cu")
		(net "I3C_SPD_DDRC_CPU1_SDA")
	)
	(segment
		(start 45.229526 -195.901564)
		(end 45.495718 -195.635372)
		(width 0.10668)
		(layer "B.Cu")
		(net "I3C_SPD_DDRC_CPU1_SDA")
	)
	(segment
		(start 292.280086 -195.635118)
		(end 293.435786 -195.635118)
		(width 0.10668)
		(layer "F.Cu")
		(net "I3C_SPD_DDRC_CPU0_SDA")
	)
	(via
		(at 293.435786 -195.635118)
		(size 0.4826)
		(drill 0.254)
		(layers "F.Cu" "B.Cu")
		(net "I3C_SPD_DDRC_CPU0_SDA")
	)
	(segment
		(start 291.92474 -195.859146)
		(end 293.211758 -195.859146)
		(width 0.10668)
		(layer "B.Cu")
		(net "I3C_SPD_DDRC_CPU0_SDA")
	)
	(segment
		(start 293.211758 -195.859146)
		(end 293.435786 -195.635118)
		(width 0.10668)
		(layer "B.Cu")
		(net "I3C_SPD_DDRC_CPU0_SDA")
	)
	(segment
		(start 51.884072 -195.635372)
		(end 53.039772 -195.635372)
		(width 0.10668)
		(layer "F.Cu")
		(net "I3C_SPD_DDRB_CPU1_SDA")
	)
	(via
		(at 53.039772 -195.635372)
		(size 0.4826)
		(drill 0.254)
		(layers "F.Cu" "B.Cu")
		(net "I3C_SPD_DDRB_CPU1_SDA")
	)
	(segment
		(start 51.520598 -195.926964)
		(end 52.74818 -195.926964)
		(width 0.10668)
		(layer "B.Cu")
		(net "I3C_SPD_DDRB_CPU1_SDA")
	)
	(segment
		(start 52.74818 -195.926964)
		(end 53.039772 -195.635372)
		(width 0.10668)
		(layer "B.Cu")
		(net "I3C_SPD_DDRB_CPU1_SDA")
	)
	(segment
		(start 299.82414 -195.635118)
		(end 300.97984 -195.635118)
		(width 0.10668)
		(layer "F.Cu")
		(net "I3C_SPD_DDRB_CPU0_SDA")
	)
	(via
		(at 300.97984 -195.635118)
		(size 0.4826)
		(drill 0.254)
		(layers "F.Cu" "B.Cu")
		(net "I3C_SPD_DDRB_CPU0_SDA")
	)
	(segment
		(start 300.755812 -195.859146)
		(end 300.97984 -195.635118)
		(width 0.10668)
		(layer "B.Cu")
		(net "I3C_SPD_DDRB_CPU0_SDA")
	)
	(segment
		(start 299.46854 -195.859146)
		(end 300.755812 -195.859146)
		(width 0.10668)
		(layer "B.Cu")
		(net "I3C_SPD_DDRB_CPU0_SDA")
	)
	(segment
		(start 59.428126 -195.635372)
		(end 60.583826 -195.635372)
		(width 0.10668)
		(layer "F.Cu")
		(net "I3C_SPD_DDRA_CPU1_SDA")
	)
	(via
		(at 60.583826 -195.635372)
		(size 0.4826)
		(drill 0.254)
		(layers "F.Cu" "B.Cu")
		(net "I3C_SPD_DDRA_CPU1_SDA")
	)
	(segment
		(start 60.292234 -195.926964)
		(end 60.583826 -195.635372)
		(width 0.10668)
		(layer "B.Cu")
		(net "I3C_SPD_DDRA_CPU1_SDA")
	)
	(segment
		(start 59.801252 -195.926964)
		(end 60.292234 -195.926964)
		(width 0.10668)
		(layer "B.Cu")
		(net "I3C_SPD_DDRA_CPU1_SDA")
	)
	(segment
		(start 308.569614 -196.158358)
		(end 308.569614 -196.152262)
		(width 0.10668)
		(layer "F.Cu")
		(net "I3C_SPD_DDRA_CPU0_SDA")
	)
	(segment
		(start 308.569614 -196.152262)
		(end 308.05247 -195.635118)
		(width 0.10668)
		(layer "F.Cu")
		(net "I3C_SPD_DDRA_CPU0_SDA")
	)
	(segment
		(start 308.05247 -195.635118)
		(end 307.368194 -195.635118)
		(width 0.10668)
		(layer "F.Cu")
		(net "I3C_SPD_DDRA_CPU0_SDA")
	)
	(via
		(at 308.569614 -196.158358)
		(size 0.4826)
		(drill 0.254)
		(layers "F.Cu" "B.Cu")
		(net "I3C_SPD_DDRA_CPU0_SDA")
	)
	(segment
		(start 307.74132 -195.95211)
		(end 307.947568 -196.158358)
		(width 0.10668)
		(layer "B.Cu")
		(net "I3C_SPD_DDRA_CPU0_SDA")
	)
	(segment
		(start 307.947568 -196.158358)
		(end 308.569614 -196.158358)
		(width 0.10668)
		(layer "B.Cu")
		(net "I3C_SPD_DDRA_CPU0_SDA")
	)
	(segment
		(start 261.645146 -331.494892)
		(end 261.645146 -351.50044)
		(width 0.10668)
		(layer "B.Cu")
		(net "SMB_MUX_RT_R2_SDA")
	)
	(segment
		(start 246.8372 -331.124814)
		(end 251.451872 -331.124814)
		(width 0.10668)
		(layer "B.Cu")
		(net "SMB_MUX_RT_R2_SDA")
	)
	(segment
		(start 251.451872 -331.124814)
		(end 253.265686 -329.311)
		(width 0.10668)
		(layer "B.Cu")
		(net "SMB_MUX_RT_R2_SDA")
	)
	(segment
		(start 261.645146 -351.50044)
		(end 270.61541 -360.470704)
		(width 0.10668)
		(layer "B.Cu")
		(net "SMB_MUX_RT_R2_SDA")
	)
	(segment
		(start 253.265686 -329.311)
		(end 259.461254 -329.311)
		(width 0.10668)
		(layer "B.Cu")
		(net "SMB_MUX_RT_R2_SDA")
	)
	(segment
		(start 246.695214 -331.2668)
		(end 246.8372 -331.124814)
		(width 0.10668)
		(layer "B.Cu")
		(net "SMB_MUX_RT_R2_SDA")
	)
	(segment
		(start 246.0371 -331.2668)
		(end 246.695214 -331.2668)
		(width 0.10668)
		(layer "B.Cu")
		(net "SMB_MUX_RT_R2_SDA")
	)
	(segment
		(start 270.61541 -360.470704)
		(end 272.507202 -360.470704)
		(width 0.10668)
		(layer "B.Cu")
		(net "SMB_MUX_RT_R2_SDA")
	)
	(segment
		(start 259.461254 -329.311)
		(end 261.645146 -331.494892)
		(width 0.10668)
		(layer "B.Cu")
		(net "SMB_MUX_RT_R2_SDA")
	)
	(segment
		(start 253.619 -329.565)
		(end 258.444746 -329.565)
		(width 0.10668)
		(layer "B.Cu")
		(net "SMB_MUX_RT_R2_SCL")
	)
	(segment
		(start 251.678186 -331.505814)
		(end 253.619 -329.565)
		(width 0.10668)
		(layer "B.Cu")
		(net "SMB_MUX_RT_R2_SCL")
	)
	(segment
		(start 261.264654 -332.384908)
		(end 261.264654 -351.768156)
		(width 0.10668)
		(layer "B.Cu")
		(net "SMB_MUX_RT_R2_SCL")
	)
	(segment
		(start 246.822214 -332.0796)
		(end 247.396 -331.505814)
		(width 0.10668)
		(layer "B.Cu")
		(net "SMB_MUX_RT_R2_SCL")
	)
	(segment
		(start 247.396 -331.505814)
		(end 251.678186 -331.505814)
		(width 0.10668)
		(layer "B.Cu")
		(net "SMB_MUX_RT_R2_SCL")
	)
	(segment
		(start 261.264654 -351.768156)
		(end 272.507202 -363.010704)
		(width 0.10668)
		(layer "B.Cu")
		(net "SMB_MUX_RT_R2_SCL")
	)
	(segment
		(start 246.0371 -332.0796)
		(end 246.822214 -332.0796)
		(width 0.10668)
		(layer "B.Cu")
		(net "SMB_MUX_RT_R2_SCL")
	)
	(segment
		(start 258.444746 -329.565)
		(end 261.264654 -332.384908)
		(width 0.10668)
		(layer "B.Cu")
		(net "SMB_MUX_RT_R2_SCL")
	)
	(segment
		(start 278.751792 -415.1376)
		(end 278.579072 -415.31032)
		(width 0.10668)
		(layer "F.Cu")
		(net "SMB_HOST_CLK_3V3AUX_SDA_R1")
	)
	(segment
		(start 102.725474 -415.012886)
		(end 102.783894 -415.071306)
		(width 0.10668)
		(layer "F.Cu")
		(net "SMB_HOST_CLK_3V3AUX_SDA_R1")
	)
	(segment
		(start 102.725474 -414.329626)
		(end 102.725474 -415.012886)
		(width 0.10668)
		(layer "F.Cu")
		(net "SMB_HOST_CLK_3V3AUX_SDA_R1")
	)
	(segment
		(start 278.325072 -415.31032)
		(end 277.981156 -414.966404)
		(width 0.10668)
		(layer "F.Cu")
		(net "SMB_HOST_CLK_3V3AUX_SDA_R1")
	)
	(segment
		(start 279.259792 -415.1376)
		(end 278.751792 -415.1376)
		(width 0.10668)
		(layer "F.Cu")
		(net "SMB_HOST_CLK_3V3AUX_SDA_R1")
	)
	(segment
		(start 278.579072 -415.31032)
		(end 278.325072 -415.31032)
		(width 0.10668)
		(layer "F.Cu")
		(net "SMB_HOST_CLK_3V3AUX_SDA_R1")
	)
	(via
		(at 278.579072 -415.31032)
		(size 0.508)
		(drill 0.254)
		(layers "F.Cu" "B.Cu")
		(net "SMB_HOST_CLK_3V3AUX_SDA_R1")
	)
	(via
		(at 102.783894 -415.071306)
		(size 0.508)
		(drill 0.254)
		(layers "F.Cu" "B.Cu")
		(net "SMB_HOST_CLK_3V3AUX_SDA_R1")
	)
	(segment
		(start 103.525574 -414.329626)
		(end 102.783894 -415.071306)
		(width 0.10668)
		(layer "B.Cu")
		(net "SMB_HOST_CLK_3V3AUX_SDA_R1")
	)
	(segment
		(start 276.375114 -417.298886)
		(end 278.36368 -415.31032)
		(width 0.11684)
		(layer "In2.Cu")
		(net "SMB_HOST_CLK_3V3AUX_SDA_R1")
	)
	(segment
		(start 275.138896 -423.265092)
		(end 276.375114 -422.028874)
		(width 0.11684)
		(layer "In2.Cu")
		(net "SMB_HOST_CLK_3V3AUX_SDA_R1")
	)
	(segment
		(start 199.284844 -437.86806)
		(end 229.356158 -437.86806)
		(width 0.11684)
		(layer "In2.Cu")
		(net "SMB_HOST_CLK_3V3AUX_SDA_R1")
	)
	(segment
		(start 177.235612 -412.054294)
		(end 179.498498 -412.054294)
		(width 0.11684)
		(layer "In2.Cu")
		(net "SMB_HOST_CLK_3V3AUX_SDA_R1")
	)
	(segment
		(start 105.489248 -412.75254)
		(end 107.168696 -412.75254)
		(width 0.11684)
		(layer "In2.Cu")
		(net "SMB_HOST_CLK_3V3AUX_SDA_R1")
	)
	(segment
		(start 196.26199 -428.83328)
		(end 196.26199 -434.845206)
		(width 0.11684)
		(layer "In2.Cu")
		(net "SMB_HOST_CLK_3V3AUX_SDA_R1")
	)
	(segment
		(start 104.934258 -414.887918)
		(end 104.934258 -413.30753)
		(width 0.11684)
		(layer "In2.Cu")
		(net "SMB_HOST_CLK_3V3AUX_SDA_R1")
	)
	(segment
		(start 152.938226 -414.068514)
		(end 164.251386 -414.068514)
		(width 0.11684)
		(layer "In2.Cu")
		(net "SMB_HOST_CLK_3V3AUX_SDA_R1")
	)
	(segment
		(start 171.826682 -412.119064)
		(end 174.605696 -412.119064)
		(width 0.11684)
		(layer "In2.Cu")
		(net "SMB_HOST_CLK_3V3AUX_SDA_R1")
	)
	(segment
		(start 196.26199 -434.845206)
		(end 199.284844 -437.86806)
		(width 0.11684)
		(layer "In2.Cu")
		(net "SMB_HOST_CLK_3V3AUX_SDA_R1")
	)
	(segment
		(start 113.876836 -414.288478)
		(end 114.570256 -414.981898)
		(width 0.11684)
		(layer "In2.Cu")
		(net "SMB_HOST_CLK_3V3AUX_SDA_R1")
	)
	(segment
		(start 176.44491 -411.827726)
		(end 177.009044 -411.827726)
		(width 0.11684)
		(layer "In2.Cu")
		(net "SMB_HOST_CLK_3V3AUX_SDA_R1")
	)
	(segment
		(start 152.024842 -414.981898)
		(end 152.938226 -414.068514)
		(width 0.11684)
		(layer "In2.Cu")
		(net "SMB_HOST_CLK_3V3AUX_SDA_R1")
	)
	(segment
		(start 276.375114 -422.028874)
		(end 276.375114 -417.298886)
		(width 0.11684)
		(layer "In2.Cu")
		(net "SMB_HOST_CLK_3V3AUX_SDA_R1")
	)
	(segment
		(start 278.36368 -415.31032)
		(end 278.579072 -415.31032)
		(width 0.11684)
		(layer "In2.Cu")
		(net "SMB_HOST_CLK_3V3AUX_SDA_R1")
	)
	(segment
		(start 235.33862 -419.89121)
		(end 266.074652 -419.89121)
		(width 0.11684)
		(layer "In2.Cu")
		(net "SMB_HOST_CLK_3V3AUX_SDA_R1")
	)
	(segment
		(start 175.950372 -412.322264)
		(end 176.44491 -411.827726)
		(width 0.11684)
		(layer "In2.Cu")
		(net "SMB_HOST_CLK_3V3AUX_SDA_R1")
	)
	(segment
		(start 175.412908 -412.451804)
		(end 175.542448 -412.322264)
		(width 0.11684)
		(layer "In2.Cu")
		(net "SMB_HOST_CLK_3V3AUX_SDA_R1")
	)
	(segment
		(start 174.605696 -412.119064)
		(end 174.938436 -412.451804)
		(width 0.11684)
		(layer "In2.Cu")
		(net "SMB_HOST_CLK_3V3AUX_SDA_R1")
	)
	(segment
		(start 175.542448 -412.322264)
		(end 175.950372 -412.322264)
		(width 0.11684)
		(layer "In2.Cu")
		(net "SMB_HOST_CLK_3V3AUX_SDA_R1")
	)
	(segment
		(start 164.760656 -414.577784)
		(end 167.315134 -414.577784)
		(width 0.11684)
		(layer "In2.Cu")
		(net "SMB_HOST_CLK_3V3AUX_SDA_R1")
	)
	(segment
		(start 193.0654 -421.080692)
		(end 193.0654 -425.63669)
		(width 0.11684)
		(layer "In2.Cu")
		(net "SMB_HOST_CLK_3V3AUX_SDA_R1")
	)
	(segment
		(start 167.315134 -414.577784)
		(end 167.771064 -414.121854)
		(width 0.11684)
		(layer "In2.Cu")
		(net "SMB_HOST_CLK_3V3AUX_SDA_R1")
	)
	(segment
		(start 164.251386 -414.068514)
		(end 164.760656 -414.577784)
		(width 0.11684)
		(layer "In2.Cu")
		(net "SMB_HOST_CLK_3V3AUX_SDA_R1")
	)
	(segment
		(start 104.244902 -415.577274)
		(end 104.934258 -414.887918)
		(width 0.11684)
		(layer "In2.Cu")
		(net "SMB_HOST_CLK_3V3AUX_SDA_R1")
	)
	(segment
		(start 193.0654 -425.63669)
		(end 196.26199 -428.83328)
		(width 0.11684)
		(layer "In2.Cu")
		(net "SMB_HOST_CLK_3V3AUX_SDA_R1")
	)
	(segment
		(start 102.783894 -415.071306)
		(end 103.289862 -415.577274)
		(width 0.11684)
		(layer "In2.Cu")
		(net "SMB_HOST_CLK_3V3AUX_SDA_R1")
	)
	(segment
		(start 181.916324 -414.47212)
		(end 186.456828 -414.47212)
		(width 0.11684)
		(layer "In2.Cu")
		(net "SMB_HOST_CLK_3V3AUX_SDA_R1")
	)
	(segment
		(start 169.823892 -414.121854)
		(end 171.826682 -412.119064)
		(width 0.11684)
		(layer "In2.Cu")
		(net "SMB_HOST_CLK_3V3AUX_SDA_R1")
	)
	(segment
		(start 269.448534 -423.265092)
		(end 275.138896 -423.265092)
		(width 0.11684)
		(layer "In2.Cu")
		(net "SMB_HOST_CLK_3V3AUX_SDA_R1")
	)
	(segment
		(start 179.498498 -412.054294)
		(end 181.916324 -414.47212)
		(width 0.11684)
		(layer "In2.Cu")
		(net "SMB_HOST_CLK_3V3AUX_SDA_R1")
	)
	(segment
		(start 103.289862 -415.577274)
		(end 104.244902 -415.577274)
		(width 0.11684)
		(layer "In2.Cu")
		(net "SMB_HOST_CLK_3V3AUX_SDA_R1")
	)
	(segment
		(start 231.45877 -435.765448)
		(end 231.45877 -423.77106)
		(width 0.11684)
		(layer "In2.Cu")
		(net "SMB_HOST_CLK_3V3AUX_SDA_R1")
	)
	(segment
		(start 186.456828 -414.47212)
		(end 193.0654 -421.080692)
		(width 0.11684)
		(layer "In2.Cu")
		(net "SMB_HOST_CLK_3V3AUX_SDA_R1")
	)
	(segment
		(start 107.168696 -412.75254)
		(end 108.704634 -414.288478)
		(width 0.11684)
		(layer "In2.Cu")
		(net "SMB_HOST_CLK_3V3AUX_SDA_R1")
	)
	(segment
		(start 167.771064 -414.121854)
		(end 169.823892 -414.121854)
		(width 0.11684)
		(layer "In2.Cu")
		(net "SMB_HOST_CLK_3V3AUX_SDA_R1")
	)
	(segment
		(start 174.938436 -412.451804)
		(end 175.412908 -412.451804)
		(width 0.11684)
		(layer "In2.Cu")
		(net "SMB_HOST_CLK_3V3AUX_SDA_R1")
	)
	(segment
		(start 231.45877 -423.77106)
		(end 235.33862 -419.89121)
		(width 0.11684)
		(layer "In2.Cu")
		(net "SMB_HOST_CLK_3V3AUX_SDA_R1")
	)
	(segment
		(start 114.570256 -414.981898)
		(end 152.024842 -414.981898)
		(width 0.11684)
		(layer "In2.Cu")
		(net "SMB_HOST_CLK_3V3AUX_SDA_R1")
	)
	(segment
		(start 229.356158 -437.86806)
		(end 231.45877 -435.765448)
		(width 0.11684)
		(layer "In2.Cu")
		(net "SMB_HOST_CLK_3V3AUX_SDA_R1")
	)
	(segment
		(start 104.934258 -413.30753)
		(end 105.489248 -412.75254)
		(width 0.11684)
		(layer "In2.Cu")
		(net "SMB_HOST_CLK_3V3AUX_SDA_R1")
	)
	(segment
		(start 108.704634 -414.288478)
		(end 113.876836 -414.288478)
		(width 0.11684)
		(layer "In2.Cu")
		(net "SMB_HOST_CLK_3V3AUX_SDA_R1")
	)
	(segment
		(start 177.009044 -411.827726)
		(end 177.235612 -412.054294)
		(width 0.11684)
		(layer "In2.Cu")
		(net "SMB_HOST_CLK_3V3AUX_SDA_R1")
	)
	(segment
		(start 266.074652 -419.89121)
		(end 269.448534 -423.265092)
		(width 0.11684)
		(layer "In2.Cu")
		(net "SMB_HOST_CLK_3V3AUX_SDA_R1")
	)
	(segment
		(start 102.354126 -412.178246)
		(end 102.907084 -412.178246)
		(width 0.10668)
		(layer "F.Cu")
		(net "SMB_HOST_CLK_3V3AUX_SCL_R1")
	)
	(segment
		(start 278.796242 -414.051242)
		(end 279.308814 -414.051242)
		(width 0.10668)
		(layer "F.Cu")
		(net "SMB_HOST_CLK_3V3AUX_SCL_R1")
	)
	(segment
		(start 102.907084 -412.178246)
		(end 103.059738 -412.3309)
		(width 0.10668)
		(layer "F.Cu")
		(net "SMB_HOST_CLK_3V3AUX_SCL_R1")
	)
	(segment
		(start 278.638 -413.893)
		(end 278.796242 -414.051242)
		(width 0.10668)
		(layer "F.Cu")
		(net "SMB_HOST_CLK_3V3AUX_SCL_R1")
	)
	(segment
		(start 278.104854 -413.893)
		(end 278.638 -413.893)
		(width 0.10668)
		(layer "F.Cu")
		(net "SMB_HOST_CLK_3V3AUX_SCL_R1")
	)
	(segment
		(start 277.991824 -414.00603)
		(end 278.104854 -413.893)
		(width 0.10668)
		(layer "F.Cu")
		(net "SMB_HOST_CLK_3V3AUX_SCL_R1")
	)
	(via
		(at 278.638 -413.893)
		(size 0.508)
		(drill 0.254)
		(layers "F.Cu" "B.Cu")
		(net "SMB_HOST_CLK_3V3AUX_SCL_R1")
	)
	(via
		(at 103.059738 -412.3309)
		(size 0.508)
		(drill 0.254)
		(layers "F.Cu" "B.Cu")
		(net "SMB_HOST_CLK_3V3AUX_SCL_R1")
	)
	(segment
		(start 103.059738 -412.733236)
		(end 103.059738 -412.3309)
		(width 0.10668)
		(layer "B.Cu")
		(net "SMB_HOST_CLK_3V3AUX_SCL_R1")
	)
	(segment
		(start 102.25405 -413.2072)
		(end 102.585774 -413.2072)
		(width 0.10668)
		(layer "B.Cu")
		(net "SMB_HOST_CLK_3V3AUX_SCL_R1")
	)
	(segment
		(start 102.585774 -413.2072)
		(end 103.059738 -412.733236)
		(width 0.10668)
		(layer "B.Cu")
		(net "SMB_HOST_CLK_3V3AUX_SCL_R1")
	)
	(segment
		(start 103.598218 -411.79242)
		(end 104.3813 -411.79242)
		(width 0.11684)
		(layer "In2.Cu")
		(net "SMB_HOST_CLK_3V3AUX_SCL_R1")
	)
	(segment
		(start 176.561242 -410.728414)
		(end 177.40249 -411.569662)
		(width 0.11684)
		(layer "In2.Cu")
		(net "SMB_HOST_CLK_3V3AUX_SCL_R1")
	)
	(segment
		(start 108.874052 -413.84982)
		(end 114.141758 -413.84982)
		(width 0.11684)
		(layer "In2.Cu")
		(net "SMB_HOST_CLK_3V3AUX_SCL_R1")
	)
	(segment
		(start 196.74078 -434.611272)
		(end 199.481948 -437.35244)
		(width 0.11684)
		(layer "In2.Cu")
		(net "SMB_HOST_CLK_3V3AUX_SCL_R1")
	)
	(segment
		(start 107.355132 -412.3309)
		(end 108.874052 -413.84982)
		(width 0.11684)
		(layer "In2.Cu")
		(net "SMB_HOST_CLK_3V3AUX_SCL_R1")
	)
	(segment
		(start 193.50736 -422.639744)
		(end 194.21475 -423.347134)
		(width 0.11684)
		(layer "In2.Cu")
		(net "SMB_HOST_CLK_3V3AUX_SCL_R1")
	)
	(segment
		(start 164.932614 -413.585406)
		(end 166.044372 -413.585406)
		(width 0.11684)
		(layer "In2.Cu")
		(net "SMB_HOST_CLK_3V3AUX_SCL_R1")
	)
	(segment
		(start 230.961438 -423.672)
		(end 235.163868 -419.46957)
		(width 0.11684)
		(layer "In2.Cu")
		(net "SMB_HOST_CLK_3V3AUX_SCL_R1")
	)
	(segment
		(start 194.21475 -425.932346)
		(end 196.74078 -428.458376)
		(width 0.11684)
		(layer "In2.Cu")
		(net "SMB_HOST_CLK_3V3AUX_SCL_R1")
	)
	(segment
		(start 275.924772 -416.987482)
		(end 278.638 -414.274254)
		(width 0.11684)
		(layer "In2.Cu")
		(net "SMB_HOST_CLK_3V3AUX_SCL_R1")
	)
	(segment
		(start 193.50736 -420.92626)
		(end 193.50736 -422.639744)
		(width 0.11684)
		(layer "In2.Cu")
		(net "SMB_HOST_CLK_3V3AUX_SCL_R1")
	)
	(segment
		(start 114.141758 -413.84982)
		(end 114.852196 -414.560258)
		(width 0.11684)
		(layer "In2.Cu")
		(net "SMB_HOST_CLK_3V3AUX_SCL_R1")
	)
	(segment
		(start 275.924772 -421.882824)
		(end 275.924772 -416.987482)
		(width 0.11684)
		(layer "In2.Cu")
		(net "SMB_HOST_CLK_3V3AUX_SCL_R1")
	)
	(segment
		(start 194.21475 -423.347134)
		(end 194.21475 -425.932346)
		(width 0.11684)
		(layer "In2.Cu")
		(net "SMB_HOST_CLK_3V3AUX_SCL_R1")
	)
	(segment
		(start 179.697634 -411.569662)
		(end 182.10276 -413.974788)
		(width 0.11684)
		(layer "In2.Cu")
		(net "SMB_HOST_CLK_3V3AUX_SCL_R1")
	)
	(segment
		(start 169.648886 -413.700214)
		(end 172.620686 -410.728414)
		(width 0.11684)
		(layer "In2.Cu")
		(net "SMB_HOST_CLK_3V3AUX_SCL_R1")
	)
	(segment
		(start 196.74078 -428.458376)
		(end 196.74078 -434.611272)
		(width 0.11684)
		(layer "In2.Cu")
		(net "SMB_HOST_CLK_3V3AUX_SCL_R1")
	)
	(segment
		(start 182.10276 -413.974788)
		(end 186.555888 -413.974788)
		(width 0.11684)
		(layer "In2.Cu")
		(net "SMB_HOST_CLK_3V3AUX_SCL_R1")
	)
	(segment
		(start 104.91978 -412.3309)
		(end 107.355132 -412.3309)
		(width 0.11684)
		(layer "In2.Cu")
		(net "SMB_HOST_CLK_3V3AUX_SCL_R1")
	)
	(segment
		(start 274.964144 -422.843452)
		(end 275.924772 -421.882824)
		(width 0.11684)
		(layer "In2.Cu")
		(net "SMB_HOST_CLK_3V3AUX_SCL_R1")
	)
	(segment
		(start 186.555888 -413.974788)
		(end 193.50736 -420.92626)
		(width 0.11684)
		(layer "In2.Cu")
		(net "SMB_HOST_CLK_3V3AUX_SCL_R1")
	)
	(segment
		(start 268.599412 -421.698166)
		(end 271.909794 -421.698166)
		(width 0.11684)
		(layer "In2.Cu")
		(net "SMB_HOST_CLK_3V3AUX_SCL_R1")
	)
	(segment
		(start 273.05508 -422.843452)
		(end 274.964144 -422.843452)
		(width 0.11684)
		(layer "In2.Cu")
		(net "SMB_HOST_CLK_3V3AUX_SCL_R1")
	)
	(segment
		(start 199.481948 -437.35244)
		(end 229.227126 -437.35244)
		(width 0.11684)
		(layer "In2.Cu")
		(net "SMB_HOST_CLK_3V3AUX_SCL_R1")
	)
	(segment
		(start 278.638 -414.274254)
		(end 278.638 -413.893)
		(width 0.11684)
		(layer "In2.Cu")
		(net "SMB_HOST_CLK_3V3AUX_SCL_R1")
	)
	(segment
		(start 177.40249 -411.569662)
		(end 179.697634 -411.569662)
		(width 0.11684)
		(layer "In2.Cu")
		(net "SMB_HOST_CLK_3V3AUX_SCL_R1")
	)
	(segment
		(start 271.909794 -421.698166)
		(end 273.05508 -422.843452)
		(width 0.11684)
		(layer "In2.Cu")
		(net "SMB_HOST_CLK_3V3AUX_SCL_R1")
	)
	(segment
		(start 103.059738 -412.3309)
		(end 103.598218 -411.79242)
		(width 0.11684)
		(layer "In2.Cu")
		(net "SMB_HOST_CLK_3V3AUX_SCL_R1")
	)
	(segment
		(start 152.719278 -413.643572)
		(end 164.874448 -413.643572)
		(width 0.11684)
		(layer "In2.Cu")
		(net "SMB_HOST_CLK_3V3AUX_SCL_R1")
	)
	(segment
		(start 167.284908 -414.011618)
		(end 167.596312 -413.700214)
		(width 0.11684)
		(layer "In2.Cu")
		(net "SMB_HOST_CLK_3V3AUX_SCL_R1")
	)
	(segment
		(start 166.470584 -414.011618)
		(end 167.284908 -414.011618)
		(width 0.11684)
		(layer "In2.Cu")
		(net "SMB_HOST_CLK_3V3AUX_SCL_R1")
	)
	(segment
		(start 172.620686 -410.728414)
		(end 176.561242 -410.728414)
		(width 0.11684)
		(layer "In2.Cu")
		(net "SMB_HOST_CLK_3V3AUX_SCL_R1")
	)
	(segment
		(start 229.227126 -437.35244)
		(end 230.961438 -435.618128)
		(width 0.11684)
		(layer "In2.Cu")
		(net "SMB_HOST_CLK_3V3AUX_SCL_R1")
	)
	(segment
		(start 230.961438 -435.618128)
		(end 230.961438 -423.672)
		(width 0.11684)
		(layer "In2.Cu")
		(net "SMB_HOST_CLK_3V3AUX_SCL_R1")
	)
	(segment
		(start 104.3813 -411.79242)
		(end 104.91978 -412.3309)
		(width 0.11684)
		(layer "In2.Cu")
		(net "SMB_HOST_CLK_3V3AUX_SCL_R1")
	)
	(segment
		(start 151.802592 -414.560258)
		(end 152.719278 -413.643572)
		(width 0.11684)
		(layer "In2.Cu")
		(net "SMB_HOST_CLK_3V3AUX_SCL_R1")
	)
	(segment
		(start 166.044372 -413.585406)
		(end 166.470584 -414.011618)
		(width 0.11684)
		(layer "In2.Cu")
		(net "SMB_HOST_CLK_3V3AUX_SCL_R1")
	)
	(segment
		(start 235.163868 -419.46957)
		(end 266.370816 -419.46957)
		(width 0.11684)
		(layer "In2.Cu")
		(net "SMB_HOST_CLK_3V3AUX_SCL_R1")
	)
	(segment
		(start 167.596312 -413.700214)
		(end 169.648886 -413.700214)
		(width 0.11684)
		(layer "In2.Cu")
		(net "SMB_HOST_CLK_3V3AUX_SCL_R1")
	)
	(segment
		(start 114.852196 -414.560258)
		(end 151.802592 -414.560258)
		(width 0.11684)
		(layer "In2.Cu")
		(net "SMB_HOST_CLK_3V3AUX_SCL_R1")
	)
	(segment
		(start 164.874448 -413.643572)
		(end 164.932614 -413.585406)
		(width 0.11684)
		(layer "In2.Cu")
		(net "SMB_HOST_CLK_3V3AUX_SCL_R1")
	)
	(segment
		(start 266.370816 -419.46957)
		(end 268.599412 -421.698166)
		(width 0.11684)
		(layer "In2.Cu")
		(net "SMB_HOST_CLK_3V3AUX_SCL_R1")
	)
	(segment
		(start 134.729982 -388.660132)
		(end 134.659116 -388.730998)
		(width 0.10668)
		(layer "F.Cu")
		(net "RXDET_BYP_RT_CPU1_P3")
	)
	(segment
		(start 137.557002 -389.360918)
		(end 135.754618 -389.360918)
		(width 0.10668)
		(layer "F.Cu")
		(net "RXDET_BYP_RT_CPU1_P3")
	)
	(segment
		(start 135.472932 -388.925308)
		(end 135.207756 -388.660132)
		(width 0.10668)
		(layer "F.Cu")
		(net "RXDET_BYP_RT_CPU1_P3")
	)
	(segment
		(start 141.653006 -389.494268)
		(end 140.816584 -389.494268)
		(width 0.10668)
		(layer "F.Cu")
		(net "RXDET_BYP_RT_CPU1_P3")
	)
	(segment
		(start 140.816584 -389.494268)
		(end 140.19403 -389.236458)
		(width 0.10668)
		(layer "F.Cu")
		(net "RXDET_BYP_RT_CPU1_P3")
	)
	(segment
		(start 140.19403 -389.236458)
		(end 138.840718 -389.236458)
		(width 0.10668)
		(layer "F.Cu")
		(net "RXDET_BYP_RT_CPU1_P3")
	)
	(segment
		(start 135.207756 -388.660132)
		(end 134.729982 -388.660132)
		(width 0.10668)
		(layer "F.Cu")
		(net "RXDET_BYP_RT_CPU1_P3")
	)
	(segment
		(start 138.61542 -389.01116)
		(end 138.2014 -389.01116)
		(width 0.10668)
		(layer "F.Cu")
		(net "RXDET_BYP_RT_CPU1_P3")
	)
	(segment
		(start 135.754618 -389.360918)
		(end 135.472932 -389.079232)
		(width 0.10668)
		(layer "F.Cu")
		(net "RXDET_BYP_RT_CPU1_P3")
	)
	(segment
		(start 138.2014 -389.01116)
		(end 137.90676 -389.01116)
		(width 0.10668)
		(layer "F.Cu")
		(net "RXDET_BYP_RT_CPU1_P3")
	)
	(segment
		(start 138.840718 -389.236458)
		(end 138.61542 -389.01116)
		(width 0.10668)
		(layer "F.Cu")
		(net "RXDET_BYP_RT_CPU1_P3")
	)
	(segment
		(start 135.472932 -389.079232)
		(end 135.472932 -388.925308)
		(width 0.10668)
		(layer "F.Cu")
		(net "RXDET_BYP_RT_CPU1_P3")
	)
	(segment
		(start 137.90676 -389.01116)
		(end 137.557002 -389.360918)
		(width 0.10668)
		(layer "F.Cu")
		(net "RXDET_BYP_RT_CPU1_P3")
	)
	(segment
		(start 134.659116 -388.730998)
		(end 133.934454 -388.730998)
		(width 0.10668)
		(layer "F.Cu")
		(net "RXDET_BYP_RT_CPU1_P3")
	)
	(segment
		(start 141.80312 -389.344154)
		(end 141.653006 -389.494268)
		(width 0.10668)
		(layer "F.Cu")
		(net "RXDET_BYP_RT_CPU1_P3")
	)
	(segment
		(start 167.186864 -388.730998)
		(end 167.25773 -388.660132)
		(width 0.10668)
		(layer "F.Cu")
		(net "RXDET_BYP_RT_CPU1_P2")
	)
	(segment
		(start 167.25773 -388.660132)
		(end 167.862758 -388.660132)
		(width 0.10668)
		(layer "F.Cu")
		(net "RXDET_BYP_RT_CPU1_P2")
	)
	(segment
		(start 178.07686 -390.2075)
		(end 180.1241 -390.2075)
		(width 0.10668)
		(layer "F.Cu")
		(net "RXDET_BYP_RT_CPU1_P2")
	)
	(segment
		(start 180.1241 -390.779)
		(end 180.1241 -390.2075)
		(width 0.10668)
		(layer "F.Cu")
		(net "RXDET_BYP_RT_CPU1_P2")
	)
	(segment
		(start 166.462202 -388.730998)
		(end 167.186864 -388.730998)
		(width 0.10668)
		(layer "F.Cu")
		(net "RXDET_BYP_RT_CPU1_P2")
	)
	(via
		(at 167.862758 -388.660132)
		(size 0.4064)
		(drill 0.2032)
		(layers "F.Cu" "B.Cu")
		(net "RXDET_BYP_RT_CPU1_P2")
	)
	(via
		(at 180.1241 -390.2075)
		(size 0.508)
		(drill 0.254)
		(layers "F.Cu" "B.Cu")
		(net "RXDET_BYP_RT_CPU1_P2")
	)
	(segment
		(start 179.942998 -390.339834)
		(end 180.075332 -390.2075)
		(width 0.10668)
		(layer "B.Cu")
		(net "RXDET_BYP_RT_CPU1_P2")
	)
	(segment
		(start 168.284398 -388.660132)
		(end 168.856406 -389.23214)
		(width 0.10668)
		(layer "B.Cu")
		(net "RXDET_BYP_RT_CPU1_P2")
	)
	(segment
		(start 167.862758 -388.660132)
		(end 168.284398 -388.660132)
		(width 0.10668)
		(layer "B.Cu")
		(net "RXDET_BYP_RT_CPU1_P2")
	)
	(segment
		(start 171.752006 -389.23214)
		(end 172.8597 -390.339834)
		(width 0.10668)
		(layer "B.Cu")
		(net "RXDET_BYP_RT_CPU1_P2")
	)
	(segment
		(start 180.075332 -390.2075)
		(end 180.1241 -390.2075)
		(width 0.10668)
		(layer "B.Cu")
		(net "RXDET_BYP_RT_CPU1_P2")
	)
	(segment
		(start 172.8597 -390.339834)
		(end 179.942998 -390.339834)
		(width 0.10668)
		(layer "B.Cu")
		(net "RXDET_BYP_RT_CPU1_P2")
	)
	(segment
		(start 168.856406 -389.23214)
		(end 171.752006 -389.23214)
		(width 0.10668)
		(layer "B.Cu")
		(net "RXDET_BYP_RT_CPU1_P2")
	)
	(segment
		(start 102.81285 -390.137904)
		(end 101.797104 -390.137904)
		(width 0.10668)
		(layer "F.Cu")
		(net "RXDET_BYP_RT_CPU1_P1")
	)
	(segment
		(start 100.157788 -388.660132)
		(end 100.086922 -388.730998)
		(width 0.10668)
		(layer "F.Cu")
		(net "RXDET_BYP_RT_CPU1_P1")
	)
	(segment
		(start 101.797104 -390.137904)
		(end 100.82276 -389.16356)
		(width 0.10668)
		(layer "F.Cu")
		(net "RXDET_BYP_RT_CPU1_P1")
	)
	(segment
		(start 100.635562 -388.660132)
		(end 100.157788 -388.660132)
		(width 0.10668)
		(layer "F.Cu")
		(net "RXDET_BYP_RT_CPU1_P1")
	)
	(segment
		(start 100.82276 -388.84733)
		(end 100.635562 -388.660132)
		(width 0.10668)
		(layer "F.Cu")
		(net "RXDET_BYP_RT_CPU1_P1")
	)
	(segment
		(start 104.4956 -389.49376)
		(end 104.4956 -389.578088)
		(width 0.10668)
		(layer "F.Cu")
		(net "RXDET_BYP_RT_CPU1_P1")
	)
	(segment
		(start 104.728772 -389.81126)
		(end 104.728772 -390.380728)
		(width 0.10668)
		(layer "F.Cu")
		(net "RXDET_BYP_RT_CPU1_P1")
	)
	(segment
		(start 104.728772 -390.380728)
		(end 104.4575 -390.652)
		(width 0.10668)
		(layer "F.Cu")
		(net "RXDET_BYP_RT_CPU1_P1")
	)
	(segment
		(start 102.81285 -390.137904)
		(end 103.456994 -389.49376)
		(width 0.10668)
		(layer "F.Cu")
		(net "RXDET_BYP_RT_CPU1_P1")
	)
	(segment
		(start 100.82276 -389.16356)
		(end 100.82276 -388.84733)
		(width 0.10668)
		(layer "F.Cu")
		(net "RXDET_BYP_RT_CPU1_P1")
	)
	(segment
		(start 100.086922 -388.730998)
		(end 99.36226 -388.730998)
		(width 0.10668)
		(layer "F.Cu")
		(net "RXDET_BYP_RT_CPU1_P1")
	)
	(segment
		(start 103.456994 -389.49376)
		(end 104.4956 -389.49376)
		(width 0.10668)
		(layer "F.Cu")
		(net "RXDET_BYP_RT_CPU1_P1")
	)
	(segment
		(start 104.4956 -389.578088)
		(end 104.728772 -389.81126)
		(width 0.10668)
		(layer "F.Cu")
		(net "RXDET_BYP_RT_CPU1_P1")
	)
	(via
		(at 102.81285 -390.137904)
		(size 0.762)
		(drill 0.381)
		(layers "F.Cu" "B.Cu")
		(net "RXDET_BYP_RT_CPU1_P1")
	)
	(segment
		(start 69.591174 -389.405876)
		(end 73.26884 -389.405876)
		(width 0.10668)
		(layer "F.Cu")
		(net "RXDET_BYP_RT_CPU1_P0")
	)
	(segment
		(start 68.295012 -389.16356)
		(end 69.090032 -389.95858)
		(width 0.10668)
		(layer "F.Cu")
		(net "RXDET_BYP_RT_CPU1_P0")
	)
	(segment
		(start 73.26884 -389.405876)
		(end 73.446894 -389.58393)
		(width 0.10668)
		(layer "F.Cu")
		(net "RXDET_BYP_RT_CPU1_P0")
	)
	(segment
		(start 74.463402 -389.58393)
		(end 74.703178 -389.344154)
		(width 0.10668)
		(layer "F.Cu")
		(net "RXDET_BYP_RT_CPU1_P0")
	)
	(segment
		(start 68.295012 -388.84733)
		(end 68.295012 -389.16356)
		(width 0.10668)
		(layer "F.Cu")
		(net "RXDET_BYP_RT_CPU1_P0")
	)
	(segment
		(start 73.446894 -389.58393)
		(end 74.463402 -389.58393)
		(width 0.10668)
		(layer "F.Cu")
		(net "RXDET_BYP_RT_CPU1_P0")
	)
	(segment
		(start 68.107814 -388.660132)
		(end 68.295012 -388.84733)
		(width 0.10668)
		(layer "F.Cu")
		(net "RXDET_BYP_RT_CPU1_P0")
	)
	(segment
		(start 69.4309 -389.95858)
		(end 69.4309 -389.56615)
		(width 0.10668)
		(layer "F.Cu")
		(net "RXDET_BYP_RT_CPU1_P0")
	)
	(segment
		(start 67.63004 -388.660132)
		(end 68.107814 -388.660132)
		(width 0.10668)
		(layer "F.Cu")
		(net "RXDET_BYP_RT_CPU1_P0")
	)
	(segment
		(start 66.834512 -388.730998)
		(end 67.559174 -388.730998)
		(width 0.10668)
		(layer "F.Cu")
		(net "RXDET_BYP_RT_CPU1_P0")
	)
	(segment
		(start 69.090032 -389.95858)
		(end 69.4309 -389.95858)
		(width 0.10668)
		(layer "F.Cu")
		(net "RXDET_BYP_RT_CPU1_P0")
	)
	(segment
		(start 67.559174 -388.730998)
		(end 67.63004 -388.660132)
		(width 0.10668)
		(layer "F.Cu")
		(net "RXDET_BYP_RT_CPU1_P0")
	)
	(segment
		(start 69.4309 -389.56615)
		(end 69.591174 -389.405876)
		(width 0.10668)
		(layer "F.Cu")
		(net "RXDET_BYP_RT_CPU1_P0")
	)
	(segment
		(start 392.530838 -398.34058)
		(end 392.530838 -397.94815)
		(width 0.10668)
		(layer "F.Cu")
		(net "RXDET_BYP_RT_CPU0_P3")
	)
	(segment
		(start 391.207752 -397.042132)
		(end 391.39495 -397.22933)
		(width 0.10668)
		(layer "F.Cu")
		(net "RXDET_BYP_RT_CPU0_P3")
	)
	(segment
		(start 390.659112 -397.112998)
		(end 390.729978 -397.042132)
		(width 0.10668)
		(layer "F.Cu")
		(net "RXDET_BYP_RT_CPU0_P3")
	)
	(segment
		(start 391.39495 -397.54556)
		(end 392.18997 -398.34058)
		(width 0.10668)
		(layer "F.Cu")
		(net "RXDET_BYP_RT_CPU0_P3")
	)
	(segment
		(start 390.729978 -397.042132)
		(end 391.207752 -397.042132)
		(width 0.10668)
		(layer "F.Cu")
		(net "RXDET_BYP_RT_CPU0_P3")
	)
	(segment
		(start 397.563086 -397.96593)
		(end 397.802862 -397.726154)
		(width 0.10668)
		(layer "F.Cu")
		(net "RXDET_BYP_RT_CPU0_P3")
	)
	(segment
		(start 396.546832 -397.96593)
		(end 397.563086 -397.96593)
		(width 0.10668)
		(layer "F.Cu")
		(net "RXDET_BYP_RT_CPU0_P3")
	)
	(segment
		(start 392.691112 -397.787876)
		(end 396.368778 -397.787876)
		(width 0.10668)
		(layer "F.Cu")
		(net "RXDET_BYP_RT_CPU0_P3")
	)
	(segment
		(start 392.530838 -397.94815)
		(end 392.691112 -397.787876)
		(width 0.10668)
		(layer "F.Cu")
		(net "RXDET_BYP_RT_CPU0_P3")
	)
	(segment
		(start 391.39495 -397.22933)
		(end 391.39495 -397.54556)
		(width 0.10668)
		(layer "F.Cu")
		(net "RXDET_BYP_RT_CPU0_P3")
	)
	(segment
		(start 396.368778 -397.787876)
		(end 396.546832 -397.96593)
		(width 0.10668)
		(layer "F.Cu")
		(net "RXDET_BYP_RT_CPU0_P3")
	)
	(segment
		(start 389.93445 -397.112998)
		(end 390.659112 -397.112998)
		(width 0.10668)
		(layer "F.Cu")
		(net "RXDET_BYP_RT_CPU0_P3")
	)
	(segment
		(start 392.18997 -398.34058)
		(end 392.530838 -398.34058)
		(width 0.10668)
		(layer "F.Cu")
		(net "RXDET_BYP_RT_CPU0_P3")
	)
	(segment
		(start 434.330856 -405.76246)
		(end 433.661566 -405.76246)
		(width 0.10668)
		(layer "F.Cu")
		(net "RXDET_BYP_RT_CPU0_P2")
	)
	(segment
		(start 422.462198 -397.112998)
		(end 423.186606 -397.112998)
		(width 0.10668)
		(layer "F.Cu")
		(net "RXDET_BYP_RT_CPU0_P2")
	)
	(segment
		(start 433.506626 -405.9174)
		(end 432.5747 -405.9174)
		(width 0.10668)
		(layer "F.Cu")
		(net "RXDET_BYP_RT_CPU0_P2")
	)
	(segment
		(start 423.186606 -397.112998)
		(end 423.257472 -397.042132)
		(width 0.10668)
		(layer "F.Cu")
		(net "RXDET_BYP_RT_CPU0_P2")
	)
	(segment
		(start 423.257472 -397.042132)
		(end 423.8625 -397.042132)
		(width 0.10668)
		(layer "F.Cu")
		(net "RXDET_BYP_RT_CPU0_P2")
	)
	(segment
		(start 434.902356 -406.33396)
		(end 434.330856 -405.76246)
		(width 0.10668)
		(layer "F.Cu")
		(net "RXDET_BYP_RT_CPU0_P2")
	)
	(segment
		(start 435.786022 -406.33396)
		(end 434.902356 -406.33396)
		(width 0.10668)
		(layer "F.Cu")
		(net "RXDET_BYP_RT_CPU0_P2")
	)
	(segment
		(start 433.661566 -405.76246)
		(end 433.506626 -405.9174)
		(width 0.10668)
		(layer "F.Cu")
		(net "RXDET_BYP_RT_CPU0_P2")
	)
	(via
		(at 434.330856 -405.76246)
		(size 0.508)
		(drill 0.254)
		(layers "F.Cu" "B.Cu")
		(net "RXDET_BYP_RT_CPU0_P2")
	)
	(via
		(at 423.8625 -397.042132)
		(size 0.4064)
		(drill 0.2032)
		(layers "F.Cu" "B.Cu")
		(net "RXDET_BYP_RT_CPU0_P2")
	)
	(segment
		(start 424.856148 -397.61414)
		(end 427.312836 -397.61414)
		(width 0.10668)
		(layer "B.Cu")
		(net "RXDET_BYP_RT_CPU0_P2")
	)
	(segment
		(start 428.204376 -399.63598)
		(end 434.330856 -405.76246)
		(width 0.10668)
		(layer "B.Cu")
		(net "RXDET_BYP_RT_CPU0_P2")
	)
	(segment
		(start 423.8625 -397.042132)
		(end 424.28414 -397.042132)
		(width 0.10668)
		(layer "B.Cu")
		(net "RXDET_BYP_RT_CPU0_P2")
	)
	(segment
		(start 424.28414 -397.042132)
		(end 424.856148 -397.61414)
		(width 0.10668)
		(layer "B.Cu")
		(net "RXDET_BYP_RT_CPU0_P2")
	)
	(segment
		(start 427.312836 -397.61414)
		(end 428.204376 -398.50568)
		(width 0.10668)
		(layer "B.Cu")
		(net "RXDET_BYP_RT_CPU0_P2")
	)
	(segment
		(start 428.204376 -398.50568)
		(end 428.204376 -399.63598)
		(width 0.10668)
		(layer "B.Cu")
		(net "RXDET_BYP_RT_CPU0_P2")
	)
	(segment
		(start 356.635304 -397.042132)
		(end 356.822502 -397.22933)
		(width 0.10668)
		(layer "F.Cu")
		(net "RXDET_BYP_RT_CPU0_P1")
	)
	(segment
		(start 360.730546 -398.760696)
		(end 360.730546 -398.195292)
		(width 0.10668)
		(layer "F.Cu")
		(net "RXDET_BYP_RT_CPU0_P1")
	)
	(segment
		(start 358.812592 -398.519904)
		(end 359.456736 -397.87576)
		(width 0.10668)
		(layer "F.Cu")
		(net "RXDET_BYP_RT_CPU0_P1")
	)
	(segment
		(start 356.086664 -397.112998)
		(end 356.15753 -397.042132)
		(width 0.10668)
		(layer "F.Cu")
		(net "RXDET_BYP_RT_CPU0_P1")
	)
	(segment
		(start 356.15753 -397.042132)
		(end 356.635304 -397.042132)
		(width 0.10668)
		(layer "F.Cu")
		(net "RXDET_BYP_RT_CPU0_P1")
	)
	(segment
		(start 357.796846 -398.519904)
		(end 358.812592 -398.519904)
		(width 0.10668)
		(layer "F.Cu")
		(net "RXDET_BYP_RT_CPU0_P1")
	)
	(segment
		(start 359.456736 -397.87576)
		(end 360.495342 -397.87576)
		(width 0.10668)
		(layer "F.Cu")
		(net "RXDET_BYP_RT_CPU0_P1")
	)
	(segment
		(start 355.362002 -397.112998)
		(end 356.086664 -397.112998)
		(width 0.10668)
		(layer "F.Cu")
		(net "RXDET_BYP_RT_CPU0_P1")
	)
	(segment
		(start 356.822502 -397.22933)
		(end 356.822502 -397.54556)
		(width 0.10668)
		(layer "F.Cu")
		(net "RXDET_BYP_RT_CPU0_P1")
	)
	(segment
		(start 360.457242 -399.034)
		(end 360.730546 -398.760696)
		(width 0.10668)
		(layer "F.Cu")
		(net "RXDET_BYP_RT_CPU0_P1")
	)
	(segment
		(start 360.730546 -398.195292)
		(end 360.495342 -397.960088)
		(width 0.10668)
		(layer "F.Cu")
		(net "RXDET_BYP_RT_CPU0_P1")
	)
	(segment
		(start 360.495342 -397.960088)
		(end 360.495342 -397.87576)
		(width 0.10668)
		(layer "F.Cu")
		(net "RXDET_BYP_RT_CPU0_P1")
	)
	(segment
		(start 356.822502 -397.54556)
		(end 357.796846 -398.519904)
		(width 0.10668)
		(layer "F.Cu")
		(net "RXDET_BYP_RT_CPU0_P1")
	)
	(via
		(at 358.812592 -398.519904)
		(size 0.762)
		(drill 0.381)
		(layers "F.Cu" "B.Cu")
		(net "RXDET_BYP_RT_CPU0_P1")
	)
	(segment
		(start 329.268582 -397.787876)
		(end 329.446636 -397.96593)
		(width 0.10668)
		(layer "F.Cu")
		(net "RXDET_BYP_RT_CPU0_P0")
	)
	(segment
		(start 325.430642 -398.34058)
		(end 325.430642 -397.94815)
		(width 0.10668)
		(layer "F.Cu")
		(net "RXDET_BYP_RT_CPU0_P0")
	)
	(segment
		(start 325.089774 -398.34058)
		(end 325.430642 -398.34058)
		(width 0.10668)
		(layer "F.Cu")
		(net "RXDET_BYP_RT_CPU0_P0")
	)
	(segment
		(start 325.590916 -397.787876)
		(end 329.268582 -397.787876)
		(width 0.10668)
		(layer "F.Cu")
		(net "RXDET_BYP_RT_CPU0_P0")
	)
	(segment
		(start 330.463144 -397.96593)
		(end 330.70292 -397.726154)
		(width 0.10668)
		(layer "F.Cu")
		(net "RXDET_BYP_RT_CPU0_P0")
	)
	(segment
		(start 324.294754 -397.54556)
		(end 325.089774 -398.34058)
		(width 0.10668)
		(layer "F.Cu")
		(net "RXDET_BYP_RT_CPU0_P0")
	)
	(segment
		(start 324.294754 -397.22933)
		(end 324.294754 -397.54556)
		(width 0.10668)
		(layer "F.Cu")
		(net "RXDET_BYP_RT_CPU0_P0")
	)
	(segment
		(start 324.107556 -397.042132)
		(end 324.294754 -397.22933)
		(width 0.10668)
		(layer "F.Cu")
		(net "RXDET_BYP_RT_CPU0_P0")
	)
	(segment
		(start 323.558916 -397.112998)
		(end 323.629782 -397.042132)
		(width 0.10668)
		(layer "F.Cu")
		(net "RXDET_BYP_RT_CPU0_P0")
	)
	(segment
		(start 325.430642 -397.94815)
		(end 325.590916 -397.787876)
		(width 0.10668)
		(layer "F.Cu")
		(net "RXDET_BYP_RT_CPU0_P0")
	)
	(segment
		(start 323.629782 -397.042132)
		(end 324.107556 -397.042132)
		(width 0.10668)
		(layer "F.Cu")
		(net "RXDET_BYP_RT_CPU0_P0")
	)
	(segment
		(start 329.446636 -397.96593)
		(end 330.463144 -397.96593)
		(width 0.10668)
		(layer "F.Cu")
		(net "RXDET_BYP_RT_CPU0_P0")
	)
	(segment
		(start 322.834254 -397.112998)
		(end 323.558916 -397.112998)
		(width 0.10668)
		(layer "F.Cu")
		(net "RXDET_BYP_RT_CPU0_P0")
	)
	(via
		(at 214.913718 -325.674228)
		(size 0.6604)
		(drill 0.3302)
		(layers "F.Cu" "B.Cu")
		(net "P3V3_ADC128_2_VCC")
	)
	(segment
		(start 135.763254 -389.816086)
		(end 135.349488 -389.40232)
		(width 0.10668)
		(layer "F.Cu")
		(net "JTAG_TRST_RT_CPU1_P3_N")
	)
	(segment
		(start 134.737602 -389.40232)
		(end 134.666228 -389.330946)
		(width 0.10668)
		(layer "F.Cu")
		(net "JTAG_TRST_RT_CPU1_P3_N")
	)
	(segment
		(start 136.536938 -389.816086)
		(end 135.763254 -389.816086)
		(width 0.10668)
		(layer "F.Cu")
		(net "JTAG_TRST_RT_CPU1_P3_N")
	)
	(segment
		(start 134.666228 -389.330946)
		(end 133.934454 -389.330946)
		(width 0.10668)
		(layer "F.Cu")
		(net "JTAG_TRST_RT_CPU1_P3_N")
	)
	(segment
		(start 135.349488 -389.40232)
		(end 134.737602 -389.40232)
		(width 0.10668)
		(layer "F.Cu")
		(net "JTAG_TRST_RT_CPU1_P3_N")
	)
	(segment
		(start 166.462202 -389.330946)
		(end 167.193976 -389.330946)
		(width 0.10668)
		(layer "F.Cu")
		(net "JTAG_TRST_RT_CPU1_P2_N")
	)
	(segment
		(start 167.26535 -389.40232)
		(end 167.89908 -389.40232)
		(width 0.10668)
		(layer "F.Cu")
		(net "JTAG_TRST_RT_CPU1_P2_N")
	)
	(segment
		(start 180.1241 -392.4554)
		(end 178.63566 -392.4554)
		(width 0.10668)
		(layer "F.Cu")
		(net "JTAG_TRST_RT_CPU1_P2_N")
	)
	(segment
		(start 167.89908 -389.40232)
		(end 168.237662 -389.740902)
		(width 0.10668)
		(layer "F.Cu")
		(net "JTAG_TRST_RT_CPU1_P2_N")
	)
	(segment
		(start 167.193976 -389.330946)
		(end 167.26535 -389.40232)
		(width 0.10668)
		(layer "F.Cu")
		(net "JTAG_TRST_RT_CPU1_P2_N")
	)
	(via
		(at 168.237662 -389.740902)
		(size 0.4064)
		(drill 0.2032)
		(layers "F.Cu" "B.Cu")
		(net "JTAG_TRST_RT_CPU1_P2_N")
	)
	(via
		(at 178.63566 -392.4554)
		(size 0.508)
		(drill 0.254)
		(layers "F.Cu" "B.Cu")
		(net "JTAG_TRST_RT_CPU1_P2_N")
	)
	(segment
		(start 168.237662 -389.740902)
		(end 168.3131 -389.81634)
		(width 0.10668)
		(layer "B.Cu")
		(net "JTAG_TRST_RT_CPU1_P2_N")
	)
	(segment
		(start 169.239692 -389.81634)
		(end 169.897552 -390.4742)
		(width 0.10668)
		(layer "B.Cu")
		(net "JTAG_TRST_RT_CPU1_P2_N")
	)
	(segment
		(start 170.601894 -393.0015)
		(end 171.15282 -393.0015)
		(width 0.10668)
		(layer "B.Cu")
		(net "JTAG_TRST_RT_CPU1_P2_N")
	)
	(segment
		(start 172.14596 -392.00836)
		(end 178.18862 -392.00836)
		(width 0.10668)
		(layer "B.Cu")
		(net "JTAG_TRST_RT_CPU1_P2_N")
	)
	(segment
		(start 178.18862 -392.00836)
		(end 178.63566 -392.4554)
		(width 0.10668)
		(layer "B.Cu")
		(net "JTAG_TRST_RT_CPU1_P2_N")
	)
	(segment
		(start 168.3131 -389.81634)
		(end 169.239692 -389.81634)
		(width 0.10668)
		(layer "B.Cu")
		(net "JTAG_TRST_RT_CPU1_P2_N")
	)
	(segment
		(start 169.897552 -392.297158)
		(end 170.601894 -393.0015)
		(width 0.10668)
		(layer "B.Cu")
		(net "JTAG_TRST_RT_CPU1_P2_N")
	)
	(segment
		(start 171.15282 -393.0015)
		(end 172.14596 -392.00836)
		(width 0.10668)
		(layer "B.Cu")
		(net "JTAG_TRST_RT_CPU1_P2_N")
	)
	(segment
		(start 169.897552 -390.4742)
		(end 169.897552 -392.297158)
		(width 0.10668)
		(layer "B.Cu")
		(net "JTAG_TRST_RT_CPU1_P2_N")
	)
	(segment
		(start 102.81285 -391.407904)
		(end 102.628954 -391.407904)
		(width 0.10668)
		(layer "F.Cu")
		(net "JTAG_TRST_RT_CPU1_P1_N")
	)
	(segment
		(start 100.62337 -389.40232)
		(end 100.165408 -389.40232)
		(width 0.10668)
		(layer "F.Cu")
		(net "JTAG_TRST_RT_CPU1_P1_N")
	)
	(segment
		(start 100.094034 -389.330946)
		(end 99.36226 -389.330946)
		(width 0.10668)
		(layer "F.Cu")
		(net "JTAG_TRST_RT_CPU1_P1_N")
	)
	(segment
		(start 103.9241 -392.2268)
		(end 103.631746 -392.2268)
		(width 0.10668)
		(layer "F.Cu")
		(net "JTAG_TRST_RT_CPU1_P1_N")
	)
	(segment
		(start 100.165408 -389.40232)
		(end 100.094034 -389.330946)
		(width 0.10668)
		(layer "F.Cu")
		(net "JTAG_TRST_RT_CPU1_P1_N")
	)
	(segment
		(start 102.628954 -391.407904)
		(end 100.62337 -389.40232)
		(width 0.10668)
		(layer "F.Cu")
		(net "JTAG_TRST_RT_CPU1_P1_N")
	)
	(segment
		(start 103.631746 -392.2268)
		(end 102.81285 -391.407904)
		(width 0.10668)
		(layer "F.Cu")
		(net "JTAG_TRST_RT_CPU1_P1_N")
	)
	(via
		(at 102.81285 -391.407904)
		(size 0.762)
		(drill 0.381)
		(layers "F.Cu" "B.Cu")
		(net "JTAG_TRST_RT_CPU1_P1_N")
	)
	(segment
		(start 69.4309 -390.74598)
		(end 69.175376 -390.74598)
		(width 0.10668)
		(layer "F.Cu")
		(net "JTAG_TRST_RT_CPU1_P0_N")
	)
	(segment
		(start 68.72986 -390.036558)
		(end 68.095622 -389.40232)
		(width 0.10668)
		(layer "F.Cu")
		(net "JTAG_TRST_RT_CPU1_P0_N")
	)
	(segment
		(start 67.63766 -389.40232)
		(end 67.566286 -389.330946)
		(width 0.10668)
		(layer "F.Cu")
		(net "JTAG_TRST_RT_CPU1_P0_N")
	)
	(segment
		(start 67.566286 -389.330946)
		(end 66.834512 -389.330946)
		(width 0.10668)
		(layer "F.Cu")
		(net "JTAG_TRST_RT_CPU1_P0_N")
	)
	(segment
		(start 69.175376 -390.74598)
		(end 68.72986 -390.300464)
		(width 0.10668)
		(layer "F.Cu")
		(net "JTAG_TRST_RT_CPU1_P0_N")
	)
	(segment
		(start 68.095622 -389.40232)
		(end 67.63766 -389.40232)
		(width 0.10668)
		(layer "F.Cu")
		(net "JTAG_TRST_RT_CPU1_P0_N")
	)
	(segment
		(start 68.72986 -390.300464)
		(end 68.72986 -390.036558)
		(width 0.10668)
		(layer "F.Cu")
		(net "JTAG_TRST_RT_CPU1_P0_N")
	)
	(segment
		(start 390.737598 -397.78432)
		(end 390.666224 -397.712946)
		(width 0.10668)
		(layer "F.Cu")
		(net "JTAG_TRST_RT_CPU0_P3_N")
	)
	(segment
		(start 391.829798 -398.418558)
		(end 391.19556 -397.78432)
		(width 0.10668)
		(layer "F.Cu")
		(net "JTAG_TRST_RT_CPU0_P3_N")
	)
	(segment
		(start 391.19556 -397.78432)
		(end 390.737598 -397.78432)
		(width 0.10668)
		(layer "F.Cu")
		(net "JTAG_TRST_RT_CPU0_P3_N")
	)
	(segment
		(start 392.530584 -399.12798)
		(end 392.275314 -399.12798)
		(width 0.10668)
		(layer "F.Cu")
		(net "JTAG_TRST_RT_CPU0_P3_N")
	)
	(segment
		(start 390.666224 -397.712946)
		(end 389.93445 -397.712946)
		(width 0.10668)
		(layer "F.Cu")
		(net "JTAG_TRST_RT_CPU0_P3_N")
	)
	(segment
		(start 392.275314 -399.12798)
		(end 391.829798 -398.682464)
		(width 0.10668)
		(layer "F.Cu")
		(net "JTAG_TRST_RT_CPU0_P3_N")
	)
	(segment
		(start 391.829798 -398.682464)
		(end 391.829798 -398.418558)
		(width 0.10668)
		(layer "F.Cu")
		(net "JTAG_TRST_RT_CPU0_P3_N")
	)
	(segment
		(start 423.265346 -397.78432)
		(end 423.899076 -397.78432)
		(width 0.10668)
		(layer "F.Cu")
		(net "JTAG_TRST_RT_CPU0_P2_N")
	)
	(segment
		(start 422.462198 -397.712946)
		(end 423.193972 -397.712946)
		(width 0.10668)
		(layer "F.Cu")
		(net "JTAG_TRST_RT_CPU0_P2_N")
	)
	(segment
		(start 423.193972 -397.712946)
		(end 423.265346 -397.78432)
		(width 0.10668)
		(layer "F.Cu")
		(net "JTAG_TRST_RT_CPU0_P2_N")
	)
	(segment
		(start 435.786022 -408.01036)
		(end 434.297582 -408.01036)
		(width 0.10668)
		(layer "F.Cu")
		(net "JTAG_TRST_RT_CPU0_P2_N")
	)
	(segment
		(start 423.899076 -397.78432)
		(end 424.237658 -398.122902)
		(width 0.10668)
		(layer "F.Cu")
		(net "JTAG_TRST_RT_CPU0_P2_N")
	)
	(via
		(at 424.237658 -398.122902)
		(size 0.4064)
		(drill 0.2032)
		(layers "F.Cu" "B.Cu")
		(net "JTAG_TRST_RT_CPU0_P2_N")
	)
	(via
		(at 434.297582 -408.01036)
		(size 0.508)
		(drill 0.254)
		(layers "F.Cu" "B.Cu")
		(net "JTAG_TRST_RT_CPU0_P2_N")
	)
	(segment
		(start 427.205648 -402.291042)
		(end 426.01388 -401.099274)
		(width 0.10668)
		(layer "B.Cu")
		(net "JTAG_TRST_RT_CPU0_P2_N")
	)
	(segment
		(start 426.01388 -399.18132)
		(end 424.955462 -398.122902)
		(width 0.10668)
		(layer "B.Cu")
		(net "JTAG_TRST_RT_CPU0_P2_N")
	)
	(segment
		(start 426.01388 -401.099274)
		(end 426.01388 -399.18132)
		(width 0.10668)
		(layer "B.Cu")
		(net "JTAG_TRST_RT_CPU0_P2_N")
	)
	(segment
		(start 428.578264 -402.291042)
		(end 427.205648 -402.291042)
		(width 0.10668)
		(layer "B.Cu")
		(net "JTAG_TRST_RT_CPU0_P2_N")
	)
	(segment
		(start 424.955462 -398.122902)
		(end 424.237658 -398.122902)
		(width 0.10668)
		(layer "B.Cu")
		(net "JTAG_TRST_RT_CPU0_P2_N")
	)
	(segment
		(start 434.297582 -408.01036)
		(end 428.578264 -402.291042)
		(width 0.10668)
		(layer "B.Cu")
		(net "JTAG_TRST_RT_CPU0_P2_N")
	)
	(segment
		(start 356.093776 -397.712946)
		(end 355.362002 -397.712946)
		(width 0.10668)
		(layer "F.Cu")
		(net "JTAG_TRST_RT_CPU0_P1_N")
	)
	(segment
		(start 358.628696 -399.789904)
		(end 356.623112 -397.78432)
		(width 0.10668)
		(layer "F.Cu")
		(net "JTAG_TRST_RT_CPU0_P1_N")
	)
	(segment
		(start 356.16515 -397.78432)
		(end 356.093776 -397.712946)
		(width 0.10668)
		(layer "F.Cu")
		(net "JTAG_TRST_RT_CPU0_P1_N")
	)
	(segment
		(start 358.812592 -399.789904)
		(end 358.628696 -399.789904)
		(width 0.10668)
		(layer "F.Cu")
		(net "JTAG_TRST_RT_CPU0_P1_N")
	)
	(segment
		(start 356.623112 -397.78432)
		(end 356.16515 -397.78432)
		(width 0.10668)
		(layer "F.Cu")
		(net "JTAG_TRST_RT_CPU0_P1_N")
	)
	(segment
		(start 359.104946 -399.789904)
		(end 358.812592 -399.789904)
		(width 0.10668)
		(layer "F.Cu")
		(net "JTAG_TRST_RT_CPU0_P1_N")
	)
	(segment
		(start 359.923842 -400.6088)
		(end 359.104946 -399.789904)
		(width 0.10668)
		(layer "F.Cu")
		(net "JTAG_TRST_RT_CPU0_P1_N")
	)
	(via
		(at 358.812592 -399.789904)
		(size 0.762)
		(drill 0.381)
		(layers "F.Cu" "B.Cu")
		(net "JTAG_TRST_RT_CPU0_P1_N")
	)
	(segment
		(start 323.637402 -397.78432)
		(end 323.566028 -397.712946)
		(width 0.10668)
		(layer "F.Cu")
		(net "JTAG_TRST_RT_CPU0_P0_N")
	)
	(segment
		(start 324.729602 -398.682464)
		(end 324.729602 -398.418558)
		(width 0.10668)
		(layer "F.Cu")
		(net "JTAG_TRST_RT_CPU0_P0_N")
	)
	(segment
		(start 324.095364 -397.78432)
		(end 323.637402 -397.78432)
		(width 0.10668)
		(layer "F.Cu")
		(net "JTAG_TRST_RT_CPU0_P0_N")
	)
	(segment
		(start 324.729602 -398.418558)
		(end 324.095364 -397.78432)
		(width 0.10668)
		(layer "F.Cu")
		(net "JTAG_TRST_RT_CPU0_P0_N")
	)
	(segment
		(start 325.430642 -399.12798)
		(end 325.175118 -399.12798)
		(width 0.10668)
		(layer "F.Cu")
		(net "JTAG_TRST_RT_CPU0_P0_N")
	)
	(segment
		(start 323.566028 -397.712946)
		(end 322.834254 -397.712946)
		(width 0.10668)
		(layer "F.Cu")
		(net "JTAG_TRST_RT_CPU0_P0_N")
	)
	(segment
		(start 325.175118 -399.12798)
		(end 324.729602 -398.682464)
		(width 0.10668)
		(layer "F.Cu")
		(net "JTAG_TRST_RT_CPU0_P0_N")
	)
	(segment
		(start 134.595616 -388.289292)
		(end 134.926832 -388.289292)
		(width 0.10668)
		(layer "F.Cu")
		(net "JTAG_TMS_RT_CPU1_P3")
	)
	(segment
		(start 134.453884 -388.431024)
		(end 134.595616 -388.289292)
		(width 0.10668)
		(layer "F.Cu")
		(net "JTAG_TMS_RT_CPU1_P3")
	)
	(via
		(at 163.3982 -426.133006)
		(size 0.6604)
		(drill 0.3302)
		(layers "F.Cu" "B.Cu")
		(net "JTAG_TMS_RT_CPU1_P3")
	)
	(via
		(at 134.926832 -388.289292)
		(size 0.4064)
		(drill 0.2032)
		(layers "F.Cu" "B.Cu")
		(net "JTAG_TMS_RT_CPU1_P3")
	)
	(via
		(at 163.3982 -425.40047)
		(size 0.508)
		(drill 0.254)
		(layers "F.Cu" "B.Cu")
		(net "JTAG_TMS_RT_CPU1_P3")
	)
	(segment
		(start 163.5252 -425.27347)
		(end 163.3982 -425.40047)
		(width 0.10668)
		(layer "B.Cu")
		(net "JTAG_TMS_RT_CPU1_P3")
	)
	(segment
		(start 163.5252 -424.86707)
		(end 163.5252 -425.27347)
		(width 0.10668)
		(layer "B.Cu")
		(net "JTAG_TMS_RT_CPU1_P3")
	)
	(segment
		(start 163.3982 -425.40047)
		(end 163.3982 -426.133006)
		(width 0.10668)
		(layer "B.Cu")
		(net "JTAG_TMS_RT_CPU1_P3")
	)
	(segment
		(start 147.343622 -394.35151)
		(end 142.498572 -389.50646)
		(width 0.11684)
		(layer "In11.Cu")
		(net "JTAG_TMS_RT_CPU1_P3")
	)
	(segment
		(start 164.42563 -420.935404)
		(end 164.42563 -417.748212)
		(width 0.11684)
		(layer "In11.Cu")
		(net "JTAG_TMS_RT_CPU1_P3")
	)
	(segment
		(start 164.663374 -411.378146)
		(end 164.663374 -404.604474)
		(width 0.11684)
		(layer "In11.Cu")
		(net "JTAG_TMS_RT_CPU1_P3")
	)
	(segment
		(start 163.856416 -424.942254)
		(end 163.856416 -421.504618)
		(width 0.11684)
		(layer "In11.Cu")
		(net "JTAG_TMS_RT_CPU1_P3")
	)
	(segment
		(start 137.486644 -388.289292)
		(end 134.926832 -388.289292)
		(width 0.11684)
		(layer "In11.Cu")
		(net "JTAG_TMS_RT_CPU1_P3")
	)
	(segment
		(start 165.01364 -417.160202)
		(end 165.01364 -416.732974)
		(width 0.11684)
		(layer "In11.Cu")
		(net "JTAG_TMS_RT_CPU1_P3")
	)
	(segment
		(start 140.385038 -389.309356)
		(end 138.506708 -389.309356)
		(width 0.11684)
		(layer "In11.Cu")
		(net "JTAG_TMS_RT_CPU1_P3")
	)
	(segment
		(start 163.3982 -425.40047)
		(end 163.856416 -424.942254)
		(width 0.11684)
		(layer "In11.Cu")
		(net "JTAG_TMS_RT_CPU1_P3")
	)
	(segment
		(start 164.663374 -404.604474)
		(end 159.407352 -399.348452)
		(width 0.11684)
		(layer "In11.Cu")
		(net "JTAG_TMS_RT_CPU1_P3")
	)
	(segment
		(start 142.498572 -389.50646)
		(end 140.582142 -389.50646)
		(width 0.11684)
		(layer "In11.Cu")
		(net "JTAG_TMS_RT_CPU1_P3")
	)
	(segment
		(start 159.407352 -399.348452)
		(end 147.343622 -394.35151)
		(width 0.11684)
		(layer "In11.Cu")
		(net "JTAG_TMS_RT_CPU1_P3")
	)
	(segment
		(start 165.01364 -416.732974)
		(end 164.420042 -416.139376)
		(width 0.11684)
		(layer "In11.Cu")
		(net "JTAG_TMS_RT_CPU1_P3")
	)
	(segment
		(start 138.506708 -389.309356)
		(end 137.486644 -388.289292)
		(width 0.11684)
		(layer "In11.Cu")
		(net "JTAG_TMS_RT_CPU1_P3")
	)
	(segment
		(start 164.530786 -411.712918)
		(end 164.530786 -411.510734)
		(width 0.11684)
		(layer "In11.Cu")
		(net "JTAG_TMS_RT_CPU1_P3")
	)
	(segment
		(start 140.582142 -389.50646)
		(end 140.385038 -389.309356)
		(width 0.11684)
		(layer "In11.Cu")
		(net "JTAG_TMS_RT_CPU1_P3")
	)
	(segment
		(start 164.530786 -411.510734)
		(end 164.663374 -411.378146)
		(width 0.11684)
		(layer "In11.Cu")
		(net "JTAG_TMS_RT_CPU1_P3")
	)
	(segment
		(start 164.420042 -411.823662)
		(end 164.530786 -411.712918)
		(width 0.11684)
		(layer "In11.Cu")
		(net "JTAG_TMS_RT_CPU1_P3")
	)
	(segment
		(start 163.856416 -421.504618)
		(end 164.42563 -420.935404)
		(width 0.11684)
		(layer "In11.Cu")
		(net "JTAG_TMS_RT_CPU1_P3")
	)
	(segment
		(start 164.420042 -416.139376)
		(end 164.420042 -411.823662)
		(width 0.11684)
		(layer "In11.Cu")
		(net "JTAG_TMS_RT_CPU1_P3")
	)
	(segment
		(start 164.42563 -417.748212)
		(end 165.01364 -417.160202)
		(width 0.11684)
		(layer "In11.Cu")
		(net "JTAG_TMS_RT_CPU1_P3")
	)
	(segment
		(start 166.981632 -388.431024)
		(end 167.123364 -388.289292)
		(width 0.10668)
		(layer "F.Cu")
		(net "JTAG_TMS_RT_CPU1_P2")
	)
	(segment
		(start 167.123364 -388.289292)
		(end 167.45458 -388.289292)
		(width 0.10668)
		(layer "F.Cu")
		(net "JTAG_TMS_RT_CPU1_P2")
	)
	(segment
		(start 178.07686 -389.0518)
		(end 179.5907 -389.0518)
		(width 0.10668)
		(layer "F.Cu")
		(net "JTAG_TMS_RT_CPU1_P2")
	)
	(via
		(at 167.45458 -388.289292)
		(size 0.4064)
		(drill 0.2032)
		(layers "F.Cu" "B.Cu")
		(net "JTAG_TMS_RT_CPU1_P2")
	)
	(via
		(at 179.5907 -389.0518)
		(size 0.508)
		(drill 0.254)
		(layers "F.Cu" "B.Cu")
		(net "JTAG_TMS_RT_CPU1_P2")
	)
	(segment
		(start 172.519594 -389.387588)
		(end 171.639484 -388.507478)
		(width 0.10668)
		(layer "B.Cu")
		(net "JTAG_TMS_RT_CPU1_P2")
	)
	(segment
		(start 171.639484 -388.507478)
		(end 171.639484 -387.679692)
		(width 0.10668)
		(layer "B.Cu")
		(net "JTAG_TMS_RT_CPU1_P2")
	)
	(segment
		(start 179.5907 -389.0518)
		(end 174.804578 -389.0518)
		(width 0.10668)
		(layer "B.Cu")
		(net "JTAG_TMS_RT_CPU1_P2")
	)
	(segment
		(start 174.804578 -389.0518)
		(end 174.46879 -389.387588)
		(width 0.10668)
		(layer "B.Cu")
		(net "JTAG_TMS_RT_CPU1_P2")
	)
	(segment
		(start 168.517062 -387.903974)
		(end 167.839898 -387.903974)
		(width 0.10668)
		(layer "B.Cu")
		(net "JTAG_TMS_RT_CPU1_P2")
	)
	(segment
		(start 171.225718 -387.265926)
		(end 169.15511 -387.265926)
		(width 0.10668)
		(layer "B.Cu")
		(net "JTAG_TMS_RT_CPU1_P2")
	)
	(segment
		(start 171.639484 -387.679692)
		(end 171.225718 -387.265926)
		(width 0.10668)
		(layer "B.Cu")
		(net "JTAG_TMS_RT_CPU1_P2")
	)
	(segment
		(start 167.839898 -387.903974)
		(end 167.45458 -388.289292)
		(width 0.10668)
		(layer "B.Cu")
		(net "JTAG_TMS_RT_CPU1_P2")
	)
	(segment
		(start 169.15511 -387.265926)
		(end 168.517062 -387.903974)
		(width 0.10668)
		(layer "B.Cu")
		(net "JTAG_TMS_RT_CPU1_P2")
	)
	(segment
		(start 174.46879 -389.387588)
		(end 172.519594 -389.387588)
		(width 0.10668)
		(layer "B.Cu")
		(net "JTAG_TMS_RT_CPU1_P2")
	)
	(segment
		(start 99.88169 -388.431024)
		(end 100.023422 -388.289292)
		(width 0.10668)
		(layer "F.Cu")
		(net "JTAG_TMS_RT_CPU1_P1")
	)
	(segment
		(start 100.023422 -388.289292)
		(end 100.354638 -388.289292)
		(width 0.10668)
		(layer "F.Cu")
		(net "JTAG_TMS_RT_CPU1_P1")
	)
	(segment
		(start 95.7961 -418.846)
		(end 94.730062 -419.912038)
		(width 0.10668)
		(layer "F.Cu")
		(net "JTAG_TMS_RT_CPU1_P1")
	)
	(via
		(at 100.354638 -388.289292)
		(size 0.4064)
		(drill 0.2032)
		(layers "F.Cu" "B.Cu")
		(net "JTAG_TMS_RT_CPU1_P1")
	)
	(via
		(at 94.730062 -419.912038)
		(size 0.508)
		(drill 0.254)
		(layers "F.Cu" "B.Cu")
		(net "JTAG_TMS_RT_CPU1_P1")
	)
	(segment
		(start 95.72371 -418.91839)
		(end 94.730062 -419.912038)
		(width 0.11684)
		(layer "In11.Cu")
		(net "JTAG_TMS_RT_CPU1_P1")
	)
	(segment
		(start 101.843332 -399.292572)
		(end 101.843332 -403.392894)
		(width 0.11684)
		(layer "In11.Cu")
		(net "JTAG_TMS_RT_CPU1_P1")
	)
	(segment
		(start 100.816156 -388.75081)
		(end 100.816156 -389.119364)
		(width 0.11684)
		(layer "In11.Cu")
		(net "JTAG_TMS_RT_CPU1_P1")
	)
	(segment
		(start 97.03308 -416.355276)
		(end 95.72371 -417.664646)
		(width 0.11684)
		(layer "In11.Cu")
		(net "JTAG_TMS_RT_CPU1_P1")
	)
	(segment
		(start 98.527108 -411.349952)
		(end 97.03308 -412.84398)
		(width 0.11684)
		(layer "In11.Cu")
		(net "JTAG_TMS_RT_CPU1_P1")
	)
	(segment
		(start 102.16896 -390.472168)
		(end 102.16896 -394.424154)
		(width 0.11684)
		(layer "In11.Cu")
		(net "JTAG_TMS_RT_CPU1_P1")
	)
	(segment
		(start 99.179126 -410.86405)
		(end 98.693224 -411.349952)
		(width 0.11684)
		(layer "In11.Cu")
		(net "JTAG_TMS_RT_CPU1_P1")
	)
	(segment
		(start 97.03308 -412.84398)
		(end 97.03308 -416.355276)
		(width 0.11684)
		(layer "In11.Cu")
		(net "JTAG_TMS_RT_CPU1_P1")
	)
	(segment
		(start 101.843332 -403.392894)
		(end 100.285042 -404.951184)
		(width 0.11684)
		(layer "In11.Cu")
		(net "JTAG_TMS_RT_CPU1_P1")
	)
	(segment
		(start 99.179126 -407.621232)
		(end 99.179126 -410.86405)
		(width 0.11684)
		(layer "In11.Cu")
		(net "JTAG_TMS_RT_CPU1_P1")
	)
	(segment
		(start 101.3333 -395.259814)
		(end 101.3333 -398.78254)
		(width 0.11684)
		(layer "In11.Cu")
		(net "JTAG_TMS_RT_CPU1_P1")
	)
	(segment
		(start 102.16896 -394.424154)
		(end 101.3333 -395.259814)
		(width 0.11684)
		(layer "In11.Cu")
		(net "JTAG_TMS_RT_CPU1_P1")
	)
	(segment
		(start 101.3333 -398.78254)
		(end 101.843332 -399.292572)
		(width 0.11684)
		(layer "In11.Cu")
		(net "JTAG_TMS_RT_CPU1_P1")
	)
	(segment
		(start 98.693224 -411.349952)
		(end 98.527108 -411.349952)
		(width 0.11684)
		(layer "In11.Cu")
		(net "JTAG_TMS_RT_CPU1_P1")
	)
	(segment
		(start 100.285042 -404.951184)
		(end 99.179126 -407.621232)
		(width 0.11684)
		(layer "In11.Cu")
		(net "JTAG_TMS_RT_CPU1_P1")
	)
	(segment
		(start 100.816156 -389.119364)
		(end 102.16896 -390.472168)
		(width 0.11684)
		(layer "In11.Cu")
		(net "JTAG_TMS_RT_CPU1_P1")
	)
	(segment
		(start 100.354638 -388.289292)
		(end 100.816156 -388.75081)
		(width 0.11684)
		(layer "In11.Cu")
		(net "JTAG_TMS_RT_CPU1_P1")
	)
	(segment
		(start 95.72371 -417.664646)
		(end 95.72371 -418.91839)
		(width 0.11684)
		(layer "In11.Cu")
		(net "JTAG_TMS_RT_CPU1_P1")
	)
	(segment
		(start 67.495674 -388.289292)
		(end 67.82689 -388.289292)
		(width 0.10668)
		(layer "F.Cu")
		(net "JTAG_TMS_RT_CPU1_P0")
	)
	(segment
		(start 67.353942 -388.431024)
		(end 67.495674 -388.289292)
		(width 0.10668)
		(layer "F.Cu")
		(net "JTAG_TMS_RT_CPU1_P0")
	)
	(segment
		(start 46.283118 -418.888164)
		(end 46.771306 -419.376352)
		(width 0.10668)
		(layer "F.Cu")
		(net "JTAG_TMS_RT_CPU1_P0")
	)
	(segment
		(start 46.199044 -418.888164)
		(end 46.283118 -418.888164)
		(width 0.10668)
		(layer "F.Cu")
		(net "JTAG_TMS_RT_CPU1_P0")
	)
	(via
		(at 46.771306 -419.376352)
		(size 0.508)
		(drill 0.254)
		(layers "F.Cu" "B.Cu")
		(net "JTAG_TMS_RT_CPU1_P0")
	)
	(via
		(at 67.82689 -388.289292)
		(size 0.4064)
		(drill 0.2032)
		(layers "F.Cu" "B.Cu")
		(net "JTAG_TMS_RT_CPU1_P0")
	)
	(segment
		(start 49.149254 -400.680682)
		(end 53.864256 -395.96568)
		(width 0.11684)
		(layer "In13.Cu")
		(net "JTAG_TMS_RT_CPU1_P0")
	)
	(segment
		(start 69.133974 -393.832334)
		(end 69.133974 -389.93064)
		(width 0.11684)
		(layer "In13.Cu")
		(net "JTAG_TMS_RT_CPU1_P0")
	)
	(segment
		(start 46.771306 -419.376352)
		(end 46.771306 -407.717752)
		(width 0.11684)
		(layer "In13.Cu")
		(net "JTAG_TMS_RT_CPU1_P0")
	)
	(segment
		(start 48.724566 -406.118568)
		(end 49.79289 -405.050244)
		(width 0.11684)
		(layer "In13.Cu")
		(net "JTAG_TMS_RT_CPU1_P0")
	)
	(segment
		(start 53.864256 -395.96568)
		(end 67.000628 -395.96568)
		(width 0.11684)
		(layer "In13.Cu")
		(net "JTAG_TMS_RT_CPU1_P0")
	)
	(segment
		(start 67.000628 -395.96568)
		(end 69.133974 -393.832334)
		(width 0.11684)
		(layer "In13.Cu")
		(net "JTAG_TMS_RT_CPU1_P0")
	)
	(segment
		(start 69.133974 -389.93064)
		(end 68.2752 -389.071866)
		(width 0.11684)
		(layer "In13.Cu")
		(net "JTAG_TMS_RT_CPU1_P0")
	)
	(segment
		(start 68.2752 -389.071866)
		(end 68.2752 -388.722616)
		(width 0.11684)
		(layer "In13.Cu")
		(net "JTAG_TMS_RT_CPU1_P0")
	)
	(segment
		(start 67.841876 -388.289292)
		(end 67.82689 -388.289292)
		(width 0.11684)
		(layer "In13.Cu")
		(net "JTAG_TMS_RT_CPU1_P0")
	)
	(segment
		(start 49.149254 -403.173692)
		(end 49.149254 -400.680682)
		(width 0.11684)
		(layer "In13.Cu")
		(net "JTAG_TMS_RT_CPU1_P0")
	)
	(segment
		(start 49.79289 -405.050244)
		(end 49.79289 -403.817328)
		(width 0.11684)
		(layer "In13.Cu")
		(net "JTAG_TMS_RT_CPU1_P0")
	)
	(segment
		(start 47.847758 -406.118568)
		(end 48.724566 -406.118568)
		(width 0.11684)
		(layer "In13.Cu")
		(net "JTAG_TMS_RT_CPU1_P0")
	)
	(segment
		(start 46.771306 -407.717752)
		(end 47.140876 -406.82545)
		(width 0.11684)
		(layer "In13.Cu")
		(net "JTAG_TMS_RT_CPU1_P0")
	)
	(segment
		(start 49.79289 -403.817328)
		(end 49.149254 -403.173692)
		(width 0.11684)
		(layer "In13.Cu")
		(net "JTAG_TMS_RT_CPU1_P0")
	)
	(segment
		(start 68.2752 -388.722616)
		(end 67.841876 -388.289292)
		(width 0.11684)
		(layer "In13.Cu")
		(net "JTAG_TMS_RT_CPU1_P0")
	)
	(segment
		(start 47.140876 -406.82545)
		(end 47.847758 -406.118568)
		(width 0.11684)
		(layer "In13.Cu")
		(net "JTAG_TMS_RT_CPU1_P0")
	)
	(segment
		(start 427.967648 -421.9067)
		(end 428.41545 -421.458898)
		(width 0.10668)
		(layer "F.Cu")
		(net "JTAG_TMS_RT_CPU0_P3")
	)
	(segment
		(start 390.595612 -396.671292)
		(end 390.926828 -396.671292)
		(width 0.10668)
		(layer "F.Cu")
		(net "JTAG_TMS_RT_CPU0_P3")
	)
	(segment
		(start 390.45388 -396.813024)
		(end 390.595612 -396.671292)
		(width 0.10668)
		(layer "F.Cu")
		(net "JTAG_TMS_RT_CPU0_P3")
	)
	(segment
		(start 426.974 -421.9067)
		(end 427.967648 -421.9067)
		(width 0.10668)
		(layer "F.Cu")
		(net "JTAG_TMS_RT_CPU0_P3")
	)
	(via
		(at 428.41545 -421.458898)
		(size 0.508)
		(drill 0.254)
		(layers "F.Cu" "B.Cu")
		(net "JTAG_TMS_RT_CPU0_P3")
	)
	(via
		(at 390.926828 -396.671292)
		(size 0.4064)
		(drill 0.2032)
		(layers "F.Cu" "B.Cu")
		(net "JTAG_TMS_RT_CPU0_P3")
	)
	(segment
		(start 428.19955 -421.242998)
		(end 428.41545 -421.458898)
		(width 0.11684)
		(layer "In6.Cu")
		(net "JTAG_TMS_RT_CPU0_P3")
	)
	(segment
		(start 398.343374 -393.7254)
		(end 400.502374 -395.8844)
		(width 0.11684)
		(layer "In6.Cu")
		(net "JTAG_TMS_RT_CPU0_P3")
	)
	(segment
		(start 423.135552 -421.242998)
		(end 428.19955 -421.242998)
		(width 0.11684)
		(layer "In6.Cu")
		(net "JTAG_TMS_RT_CPU0_P3")
	)
	(segment
		(start 405.250142 -398.976342)
		(end 406.45588 -400.18208)
		(width 0.11684)
		(layer "In6.Cu")
		(net "JTAG_TMS_RT_CPU0_P3")
	)
	(segment
		(start 422.208706 -420.316152)
		(end 423.135552 -421.242998)
		(width 0.11684)
		(layer "In6.Cu")
		(net "JTAG_TMS_RT_CPU0_P3")
	)
	(segment
		(start 396.212314 -393.7254)
		(end 398.343374 -393.7254)
		(width 0.11684)
		(layer "In6.Cu")
		(net "JTAG_TMS_RT_CPU0_P3")
	)
	(segment
		(start 406.978104 -402.751544)
		(end 420.384224 -408.304238)
		(width 0.11684)
		(layer "In6.Cu")
		(net "JTAG_TMS_RT_CPU0_P3")
	)
	(segment
		(start 406.45588 -402.22932)
		(end 406.978104 -402.751544)
		(width 0.11684)
		(layer "In6.Cu")
		(net "JTAG_TMS_RT_CPU0_P3")
	)
	(segment
		(start 402.907246 -398.976342)
		(end 405.250142 -398.976342)
		(width 0.11684)
		(layer "In6.Cu")
		(net "JTAG_TMS_RT_CPU0_P3")
	)
	(segment
		(start 401.013168 -395.8844)
		(end 402.148548 -397.01978)
		(width 0.11684)
		(layer "In6.Cu")
		(net "JTAG_TMS_RT_CPU0_P3")
	)
	(segment
		(start 422.208706 -410.12872)
		(end 422.208706 -420.316152)
		(width 0.11684)
		(layer "In6.Cu")
		(net "JTAG_TMS_RT_CPU0_P3")
	)
	(segment
		(start 402.148548 -397.01978)
		(end 402.148548 -398.217644)
		(width 0.11684)
		(layer "In6.Cu")
		(net "JTAG_TMS_RT_CPU0_P3")
	)
	(segment
		(start 406.45588 -400.18208)
		(end 406.45588 -402.22932)
		(width 0.11684)
		(layer "In6.Cu")
		(net "JTAG_TMS_RT_CPU0_P3")
	)
	(segment
		(start 400.502374 -395.8844)
		(end 401.013168 -395.8844)
		(width 0.11684)
		(layer "In6.Cu")
		(net "JTAG_TMS_RT_CPU0_P3")
	)
	(segment
		(start 390.926828 -396.671292)
		(end 391.6299 -395.96822)
		(width 0.11684)
		(layer "In6.Cu")
		(net "JTAG_TMS_RT_CPU0_P3")
	)
	(segment
		(start 402.148548 -398.217644)
		(end 402.907246 -398.976342)
		(width 0.11684)
		(layer "In6.Cu")
		(net "JTAG_TMS_RT_CPU0_P3")
	)
	(segment
		(start 393.969494 -395.96822)
		(end 396.212314 -393.7254)
		(width 0.11684)
		(layer "In6.Cu")
		(net "JTAG_TMS_RT_CPU0_P3")
	)
	(segment
		(start 420.384224 -408.304238)
		(end 422.208706 -410.12872)
		(width 0.11684)
		(layer "In6.Cu")
		(net "JTAG_TMS_RT_CPU0_P3")
	)
	(segment
		(start 391.6299 -395.96822)
		(end 393.969494 -395.96822)
		(width 0.11684)
		(layer "In6.Cu")
		(net "JTAG_TMS_RT_CPU0_P3")
	)
	(segment
		(start 422.981628 -396.813024)
		(end 423.12336 -396.671292)
		(width 0.10668)
		(layer "F.Cu")
		(net "JTAG_TMS_RT_CPU0_P2")
	)
	(segment
		(start 432.5747 -405.13)
		(end 435.229762 -405.13)
		(width 0.10668)
		(layer "F.Cu")
		(net "JTAG_TMS_RT_CPU0_P2")
	)
	(segment
		(start 423.12336 -396.671292)
		(end 423.454322 -396.671292)
		(width 0.10668)
		(layer "F.Cu")
		(net "JTAG_TMS_RT_CPU0_P2")
	)
	(segment
		(start 435.229762 -405.13)
		(end 435.786022 -405.68626)
		(width 0.10668)
		(layer "F.Cu")
		(net "JTAG_TMS_RT_CPU0_P2")
	)
	(via
		(at 423.454322 -396.671292)
		(size 0.4064)
		(drill 0.2032)
		(layers "F.Cu" "B.Cu")
		(net "JTAG_TMS_RT_CPU0_P2")
	)
	(via
		(at 435.786022 -405.68626)
		(size 0.508)
		(drill 0.254)
		(layers "F.Cu" "B.Cu")
		(net "JTAG_TMS_RT_CPU0_P2")
	)
	(segment
		(start 428.7393 -399.4658)
		(end 434.41112 -405.13762)
		(width 0.10668)
		(layer "B.Cu")
		(net "JTAG_TMS_RT_CPU0_P2")
	)
	(segment
		(start 427.22546 -395.647926)
		(end 427.639226 -396.061692)
		(width 0.10668)
		(layer "B.Cu")
		(net "JTAG_TMS_RT_CPU0_P2")
	)
	(segment
		(start 423.454322 -396.671292)
		(end 423.83964 -396.285974)
		(width 0.10668)
		(layer "B.Cu")
		(net "JTAG_TMS_RT_CPU0_P2")
	)
	(segment
		(start 428.7393 -398.580356)
		(end 428.7393 -399.4658)
		(width 0.10668)
		(layer "B.Cu")
		(net "JTAG_TMS_RT_CPU0_P2")
	)
	(segment
		(start 425.154852 -395.647926)
		(end 427.22546 -395.647926)
		(width 0.10668)
		(layer "B.Cu")
		(net "JTAG_TMS_RT_CPU0_P2")
	)
	(segment
		(start 423.83964 -396.285974)
		(end 424.516804 -396.285974)
		(width 0.10668)
		(layer "B.Cu")
		(net "JTAG_TMS_RT_CPU0_P2")
	)
	(segment
		(start 424.516804 -396.285974)
		(end 425.154852 -395.647926)
		(width 0.10668)
		(layer "B.Cu")
		(net "JTAG_TMS_RT_CPU0_P2")
	)
	(segment
		(start 427.639226 -396.061692)
		(end 427.639226 -397.480282)
		(width 0.10668)
		(layer "B.Cu")
		(net "JTAG_TMS_RT_CPU0_P2")
	)
	(segment
		(start 435.237382 -405.13762)
		(end 435.786022 -405.68626)
		(width 0.10668)
		(layer "B.Cu")
		(net "JTAG_TMS_RT_CPU0_P2")
	)
	(segment
		(start 434.41112 -405.13762)
		(end 435.237382 -405.13762)
		(width 0.10668)
		(layer "B.Cu")
		(net "JTAG_TMS_RT_CPU0_P2")
	)
	(segment
		(start 427.639226 -397.480282)
		(end 428.7393 -398.580356)
		(width 0.10668)
		(layer "B.Cu")
		(net "JTAG_TMS_RT_CPU0_P2")
	)
	(segment
		(start 356.023164 -396.671292)
		(end 356.35438 -396.671292)
		(width 0.10668)
		(layer "F.Cu")
		(net "JTAG_TMS_RT_CPU0_P1")
	)
	(segment
		(start 355.287326 -409.03906)
		(end 353.19716 -409.03906)
		(width 0.10668)
		(layer "F.Cu")
		(net "JTAG_TMS_RT_CPU0_P1")
	)
	(segment
		(start 359.882948 -402.049234)
		(end 359.882948 -403.064218)
		(width 0.10668)
		(layer "F.Cu")
		(net "JTAG_TMS_RT_CPU0_P1")
	)
	(segment
		(start 359.882948 -403.064218)
		(end 359.29824 -403.648926)
		(width 0.10668)
		(layer "F.Cu")
		(net "JTAG_TMS_RT_CPU0_P1")
	)
	(segment
		(start 355.881432 -396.813024)
		(end 356.023164 -396.671292)
		(width 0.10668)
		(layer "F.Cu")
		(net "JTAG_TMS_RT_CPU0_P1")
	)
	(segment
		(start 359.29824 -403.648926)
		(end 359.29824 -405.028146)
		(width 0.10668)
		(layer "F.Cu")
		(net "JTAG_TMS_RT_CPU0_P1")
	)
	(segment
		(start 359.29824 -405.028146)
		(end 355.287326 -409.03906)
		(width 0.10668)
		(layer "F.Cu")
		(net "JTAG_TMS_RT_CPU0_P1")
	)
	(segment
		(start 353.19716 -409.03906)
		(end 352.298 -408.1399)
		(width 0.10668)
		(layer "F.Cu")
		(net "JTAG_TMS_RT_CPU0_P1")
	)
	(via
		(at 356.35438 -396.671292)
		(size 0.4064)
		(drill 0.2032)
		(layers "F.Cu" "B.Cu")
		(net "JTAG_TMS_RT_CPU0_P1")
	)
	(via
		(at 359.882948 -402.049234)
		(size 0.508)
		(drill 0.254)
		(layers "F.Cu" "B.Cu")
		(net "JTAG_TMS_RT_CPU0_P1")
	)
	(segment
		(start 357.24846 -398.492726)
		(end 358.85628 -400.100546)
		(width 0.11684)
		(layer "In15.Cu")
		(net "JTAG_TMS_RT_CPU0_P1")
	)
	(segment
		(start 356.791006 -397.241268)
		(end 356.791006 -397.531082)
		(width 0.11684)
		(layer "In15.Cu")
		(net "JTAG_TMS_RT_CPU0_P1")
	)
	(segment
		(start 356.35438 -396.671292)
		(end 356.35438 -396.804642)
		(width 0.11684)
		(layer "In15.Cu")
		(net "JTAG_TMS_RT_CPU0_P1")
	)
	(segment
		(start 357.24846 -397.988536)
		(end 357.24846 -398.492726)
		(width 0.11684)
		(layer "In15.Cu")
		(net "JTAG_TMS_RT_CPU0_P1")
	)
	(segment
		(start 356.35438 -396.804642)
		(end 356.791006 -397.241268)
		(width 0.11684)
		(layer "In15.Cu")
		(net "JTAG_TMS_RT_CPU0_P1")
	)
	(segment
		(start 356.791006 -397.531082)
		(end 357.24846 -397.988536)
		(width 0.11684)
		(layer "In15.Cu")
		(net "JTAG_TMS_RT_CPU0_P1")
	)
	(segment
		(start 358.85628 -400.100546)
		(end 358.85628 -401.022566)
		(width 0.11684)
		(layer "In15.Cu")
		(net "JTAG_TMS_RT_CPU0_P1")
	)
	(segment
		(start 358.85628 -401.022566)
		(end 359.882948 -402.049234)
		(width 0.11684)
		(layer "In15.Cu")
		(net "JTAG_TMS_RT_CPU0_P1")
	)
	(segment
		(start 323.353684 -396.813024)
		(end 323.495416 -396.671292)
		(width 0.10668)
		(layer "F.Cu")
		(net "JTAG_TMS_RT_CPU0_P0")
	)
	(segment
		(start 323.495416 -396.671292)
		(end 323.826632 -396.671292)
		(width 0.10668)
		(layer "F.Cu")
		(net "JTAG_TMS_RT_CPU0_P0")
	)
	(via
		(at 306.787042 -425.089574)
		(size 0.6604)
		(drill 0.3302)
		(layers "F.Cu" "B.Cu")
		(net "JTAG_TMS_RT_CPU0_P0")
	)
	(via
		(at 306.223416 -425.6532)
		(size 0.508)
		(drill 0.254)
		(layers "F.Cu" "B.Cu")
		(net "JTAG_TMS_RT_CPU0_P0")
	)
	(via
		(at 323.826632 -396.671292)
		(size 0.4064)
		(drill 0.2032)
		(layers "F.Cu" "B.Cu")
		(net "JTAG_TMS_RT_CPU0_P0")
	)
	(segment
		(start 305.690016 -425.6532)
		(end 306.223416 -425.6532)
		(width 0.10668)
		(layer "B.Cu")
		(net "JTAG_TMS_RT_CPU0_P0")
	)
	(segment
		(start 306.223416 -425.6532)
		(end 306.787042 -425.089574)
		(width 0.10668)
		(layer "B.Cu")
		(net "JTAG_TMS_RT_CPU0_P0")
	)
	(segment
		(start 305.426618 -425.6532)
		(end 303.91989 -424.146472)
		(width 0.11684)
		(layer "In13.Cu")
		(net "JTAG_TMS_RT_CPU0_P0")
	)
	(segment
		(start 293.1541 -414.885886)
		(end 293.1541 -408.79776)
		(width 0.11684)
		(layer "In13.Cu")
		(net "JTAG_TMS_RT_CPU0_P0")
	)
	(segment
		(start 303.91989 -424.146472)
		(end 303.91989 -422.662604)
		(width 0.11684)
		(layer "In13.Cu")
		(net "JTAG_TMS_RT_CPU0_P0")
	)
	(segment
		(start 323.23278 -402.1709)
		(end 323.23278 -401.159726)
		(width 0.11684)
		(layer "In13.Cu")
		(net "JTAG_TMS_RT_CPU0_P0")
	)
	(segment
		(start 303.91989 -422.662604)
		(end 300.627034 -419.369748)
		(width 0.11684)
		(layer "In13.Cu")
		(net "JTAG_TMS_RT_CPU0_P0")
	)
	(segment
		(start 297.637962 -419.369748)
		(end 293.1541 -414.885886)
		(width 0.11684)
		(layer "In13.Cu")
		(net "JTAG_TMS_RT_CPU0_P0")
	)
	(segment
		(start 300.627034 -419.369748)
		(end 297.637962 -419.369748)
		(width 0.11684)
		(layer "In13.Cu")
		(net "JTAG_TMS_RT_CPU0_P0")
	)
	(segment
		(start 295.92016 -402.109686)
		(end 296.399966 -401.62988)
		(width 0.11684)
		(layer "In13.Cu")
		(net "JTAG_TMS_RT_CPU0_P0")
	)
	(segment
		(start 296.399966 -401.62988)
		(end 300.9646 -401.62988)
		(width 0.11684)
		(layer "In13.Cu")
		(net "JTAG_TMS_RT_CPU0_P0")
	)
	(segment
		(start 322.41744 -402.98624)
		(end 323.23278 -402.1709)
		(width 0.11684)
		(layer "In13.Cu")
		(net "JTAG_TMS_RT_CPU0_P0")
	)
	(segment
		(start 324.903084 -399.489422)
		(end 324.903084 -398.170908)
		(width 0.11684)
		(layer "In13.Cu")
		(net "JTAG_TMS_RT_CPU0_P0")
	)
	(segment
		(start 295.92016 -406.0317)
		(end 295.92016 -402.109686)
		(width 0.11684)
		(layer "In13.Cu")
		(net "JTAG_TMS_RT_CPU0_P0")
	)
	(segment
		(start 306.223416 -425.6532)
		(end 305.426618 -425.6532)
		(width 0.11684)
		(layer "In13.Cu")
		(net "JTAG_TMS_RT_CPU0_P0")
	)
	(segment
		(start 302.32096 -402.98624)
		(end 322.41744 -402.98624)
		(width 0.11684)
		(layer "In13.Cu")
		(net "JTAG_TMS_RT_CPU0_P0")
	)
	(segment
		(start 324.263258 -397.531082)
		(end 324.263258 -397.107918)
		(width 0.11684)
		(layer "In13.Cu")
		(net "JTAG_TMS_RT_CPU0_P0")
	)
	(segment
		(start 300.9646 -401.62988)
		(end 302.32096 -402.98624)
		(width 0.11684)
		(layer "In13.Cu")
		(net "JTAG_TMS_RT_CPU0_P0")
	)
	(segment
		(start 293.1541 -408.79776)
		(end 295.92016 -406.0317)
		(width 0.11684)
		(layer "In13.Cu")
		(net "JTAG_TMS_RT_CPU0_P0")
	)
	(segment
		(start 323.23278 -401.159726)
		(end 324.903084 -399.489422)
		(width 0.11684)
		(layer "In13.Cu")
		(net "JTAG_TMS_RT_CPU0_P0")
	)
	(segment
		(start 324.263258 -397.107918)
		(end 323.826632 -396.671292)
		(width 0.11684)
		(layer "In13.Cu")
		(net "JTAG_TMS_RT_CPU0_P0")
	)
	(segment
		(start 324.903084 -398.170908)
		(end 324.263258 -397.531082)
		(width 0.11684)
		(layer "In13.Cu")
		(net "JTAG_TMS_RT_CPU0_P0")
	)
	(segment
		(start 134.453884 -389.030972)
		(end 135.010398 -389.030972)
		(width 0.10668)
		(layer "F.Cu")
		(net "JTAG_TDO_RT_CPU1_P3")
	)
	(via
		(at 135.010398 -389.030972)
		(size 0.4064)
		(drill 0.2032)
		(layers "F.Cu" "B.Cu")
		(net "JTAG_TDO_RT_CPU1_P3")
	)
	(via
		(at 162.7124 -425.40047)
		(size 0.508)
		(drill 0.254)
		(layers "F.Cu" "B.Cu")
		(net "JTAG_TDO_RT_CPU1_P3")
	)
	(via
		(at 161.850324 -425.906946)
		(size 0.6604)
		(drill 0.3302)
		(layers "F.Cu" "B.Cu")
		(net "JTAG_TDO_RT_CPU1_P3")
	)
	(segment
		(start 162.3568 -425.40047)
		(end 161.850324 -425.906946)
		(width 0.10668)
		(layer "B.Cu")
		(net "JTAG_TDO_RT_CPU1_P3")
	)
	(segment
		(start 162.7124 -425.40047)
		(end 162.3568 -425.40047)
		(width 0.10668)
		(layer "B.Cu")
		(net "JTAG_TDO_RT_CPU1_P3")
	)
	(segment
		(start 162.7124 -424.86707)
		(end 162.7124 -425.40047)
		(width 0.10668)
		(layer "B.Cu")
		(net "JTAG_TDO_RT_CPU1_P3")
	)
	(segment
		(start 138.07186 -389.492236)
		(end 138.254994 -389.67537)
		(width 0.11684)
		(layer "In11.Cu")
		(net "JTAG_TDO_RT_CPU1_P3")
	)
	(segment
		(start 135.397494 -389.030972)
		(end 135.858758 -389.492236)
		(width 0.11684)
		(layer "In11.Cu")
		(net "JTAG_TDO_RT_CPU1_P3")
	)
	(segment
		(start 140.291566 -389.67537)
		(end 140.455396 -389.8392)
		(width 0.11684)
		(layer "In11.Cu")
		(net "JTAG_TDO_RT_CPU1_P3")
	)
	(segment
		(start 135.858758 -389.492236)
		(end 138.07186 -389.492236)
		(width 0.11684)
		(layer "In11.Cu")
		(net "JTAG_TDO_RT_CPU1_P3")
	)
	(segment
		(start 163.714684 -419.040818)
		(end 163.714684 -420.708582)
		(width 0.11684)
		(layer "In11.Cu")
		(net "JTAG_TDO_RT_CPU1_P3")
	)
	(segment
		(start 159.662622 -400.058382)
		(end 162.98418 -403.37994)
		(width 0.11684)
		(layer "In11.Cu")
		(net "JTAG_TDO_RT_CPU1_P3")
	)
	(segment
		(start 140.455396 -389.8392)
		(end 142.377922 -389.8392)
		(width 0.11684)
		(layer "In11.Cu")
		(net "JTAG_TDO_RT_CPU1_P3")
	)
	(segment
		(start 163.8427 -416.83813)
		(end 163.34105 -417.33978)
		(width 0.11684)
		(layer "In11.Cu")
		(net "JTAG_TDO_RT_CPU1_P3")
	)
	(segment
		(start 163.8427 -411.74416)
		(end 163.8427 -416.83813)
		(width 0.11684)
		(layer "In11.Cu")
		(net "JTAG_TDO_RT_CPU1_P3")
	)
	(segment
		(start 162.986212 -403.37994)
		(end 164.34308 -404.736808)
		(width 0.11684)
		(layer "In11.Cu")
		(net "JTAG_TDO_RT_CPU1_P3")
	)
	(segment
		(start 163.714684 -420.708582)
		(end 162.310064 -422.113202)
		(width 0.11684)
		(layer "In11.Cu")
		(net "JTAG_TDO_RT_CPU1_P3")
	)
	(segment
		(start 162.310064 -422.113202)
		(end 162.310064 -424.998134)
		(width 0.11684)
		(layer "In11.Cu")
		(net "JTAG_TDO_RT_CPU1_P3")
	)
	(segment
		(start 163.34105 -417.33978)
		(end 163.34105 -418.667184)
		(width 0.11684)
		(layer "In11.Cu")
		(net "JTAG_TDO_RT_CPU1_P3")
	)
	(segment
		(start 164.34308 -404.736808)
		(end 164.34308 -411.24378)
		(width 0.11684)
		(layer "In11.Cu")
		(net "JTAG_TDO_RT_CPU1_P3")
	)
	(segment
		(start 163.34105 -418.667184)
		(end 163.714684 -419.040818)
		(width 0.11684)
		(layer "In11.Cu")
		(net "JTAG_TDO_RT_CPU1_P3")
	)
	(segment
		(start 138.254994 -389.67537)
		(end 140.291566 -389.67537)
		(width 0.11684)
		(layer "In11.Cu")
		(net "JTAG_TDO_RT_CPU1_P3")
	)
	(segment
		(start 162.310064 -424.998134)
		(end 162.7124 -425.40047)
		(width 0.11684)
		(layer "In11.Cu")
		(net "JTAG_TDO_RT_CPU1_P3")
	)
	(segment
		(start 135.010398 -389.030972)
		(end 135.397494 -389.030972)
		(width 0.11684)
		(layer "In11.Cu")
		(net "JTAG_TDO_RT_CPU1_P3")
	)
	(segment
		(start 164.34308 -411.24378)
		(end 163.8427 -411.74416)
		(width 0.11684)
		(layer "In11.Cu")
		(net "JTAG_TDO_RT_CPU1_P3")
	)
	(segment
		(start 162.98418 -403.37994)
		(end 162.986212 -403.37994)
		(width 0.11684)
		(layer "In11.Cu")
		(net "JTAG_TDO_RT_CPU1_P3")
	)
	(segment
		(start 142.377922 -389.8392)
		(end 147.602448 -395.063726)
		(width 0.11684)
		(layer "In11.Cu")
		(net "JTAG_TDO_RT_CPU1_P3")
	)
	(segment
		(start 147.602448 -395.063726)
		(end 159.662622 -400.058382)
		(width 0.11684)
		(layer "In11.Cu")
		(net "JTAG_TDO_RT_CPU1_P3")
	)
	(segment
		(start 178.07686 -391.6172)
		(end 179.5907 -391.6172)
		(width 0.10668)
		(layer "F.Cu")
		(net "JTAG_TDO_RT_CPU1_P2")
	)
	(segment
		(start 166.981632 -389.030972)
		(end 167.477186 -389.030972)
		(width 0.10668)
		(layer "F.Cu")
		(net "JTAG_TDO_RT_CPU1_P2")
	)
	(via
		(at 167.477186 -389.030972)
		(size 0.4064)
		(drill 0.2032)
		(layers "F.Cu" "B.Cu")
		(net "JTAG_TDO_RT_CPU1_P2")
	)
	(via
		(at 179.5907 -391.6172)
		(size 0.508)
		(drill 0.254)
		(layers "F.Cu" "B.Cu")
		(net "JTAG_TDO_RT_CPU1_P2")
	)
	(segment
		(start 168.44264 -389.146288)
		(end 167.592502 -389.146288)
		(width 0.10668)
		(layer "B.Cu")
		(net "JTAG_TDO_RT_CPU1_P2")
	)
	(segment
		(start 172.638974 -391.6172)
		(end 172.227494 -391.20572)
		(width 0.10668)
		(layer "B.Cu")
		(net "JTAG_TDO_RT_CPU1_P2")
	)
	(segment
		(start 167.592502 -389.146288)
		(end 167.477186 -389.030972)
		(width 0.10668)
		(layer "B.Cu")
		(net "JTAG_TDO_RT_CPU1_P2")
	)
	(segment
		(start 170.59656 -391.20572)
		(end 170.27144 -390.8806)
		(width 0.10668)
		(layer "B.Cu")
		(net "JTAG_TDO_RT_CPU1_P2")
	)
	(segment
		(start 170.27144 -390.28751)
		(end 169.483532 -389.499602)
		(width 0.10668)
		(layer "B.Cu")
		(net "JTAG_TDO_RT_CPU1_P2")
	)
	(segment
		(start 169.483532 -389.499602)
		(end 168.795954 -389.499602)
		(width 0.10668)
		(layer "B.Cu")
		(net "JTAG_TDO_RT_CPU1_P2")
	)
	(segment
		(start 168.795954 -389.499602)
		(end 168.44264 -389.146288)
		(width 0.10668)
		(layer "B.Cu")
		(net "JTAG_TDO_RT_CPU1_P2")
	)
	(segment
		(start 170.27144 -390.8806)
		(end 170.27144 -390.28751)
		(width 0.10668)
		(layer "B.Cu")
		(net "JTAG_TDO_RT_CPU1_P2")
	)
	(segment
		(start 179.5907 -391.6172)
		(end 172.638974 -391.6172)
		(width 0.10668)
		(layer "B.Cu")
		(net "JTAG_TDO_RT_CPU1_P2")
	)
	(segment
		(start 172.227494 -391.20572)
		(end 170.59656 -391.20572)
		(width 0.10668)
		(layer "B.Cu")
		(net "JTAG_TDO_RT_CPU1_P2")
	)
	(segment
		(start 99.88169 -389.030972)
		(end 100.377244 -389.030972)
		(width 0.10668)
		(layer "F.Cu")
		(net "JTAG_TDO_RT_CPU1_P1")
	)
	(segment
		(start 95.7961 -418.166042)
		(end 95.240348 -418.721794)
		(width 0.10668)
		(layer "F.Cu")
		(net "JTAG_TDO_RT_CPU1_P1")
	)
	(segment
		(start 95.7961 -418.0332)
		(end 95.7961 -418.166042)
		(width 0.10668)
		(layer "F.Cu")
		(net "JTAG_TDO_RT_CPU1_P1")
	)
	(via
		(at 100.377244 -389.030972)
		(size 0.4064)
		(drill 0.2032)
		(layers "F.Cu" "B.Cu")
		(net "JTAG_TDO_RT_CPU1_P1")
	)
	(via
		(at 95.240348 -418.721794)
		(size 0.508)
		(drill 0.254)
		(layers "F.Cu" "B.Cu")
		(net "JTAG_TDO_RT_CPU1_P1")
	)
	(segment
		(start 100.86213 -394.958316)
		(end 100.86213 -399.015458)
		(width 0.11684)
		(layer "In11.Cu")
		(net "JTAG_TDO_RT_CPU1_P1")
	)
	(segment
		(start 101.25456 -399.407888)
		(end 101.25456 -402.117814)
		(width 0.11684)
		(layer "In11.Cu")
		(net "JTAG_TDO_RT_CPU1_P1")
	)
	(segment
		(start 95.240348 -417.69538)
		(end 95.240348 -418.721794)
		(width 0.11684)
		(layer "In11.Cu")
		(net "JTAG_TDO_RT_CPU1_P1")
	)
	(segment
		(start 96.496378 -412.768542)
		(end 96.496378 -416.43935)
		(width 0.11684)
		(layer "In11.Cu")
		(net "JTAG_TDO_RT_CPU1_P1")
	)
	(segment
		(start 101.68763 -394.132816)
		(end 100.86213 -394.958316)
		(width 0.11684)
		(layer "In11.Cu")
		(net "JTAG_TDO_RT_CPU1_P1")
	)
	(segment
		(start 96.496378 -416.43935)
		(end 95.240348 -417.69538)
		(width 0.11684)
		(layer "In11.Cu")
		(net "JTAG_TDO_RT_CPU1_P1")
	)
	(segment
		(start 99.111308 -404.261066)
		(end 97.96018 -407.04008)
		(width 0.11684)
		(layer "In11.Cu")
		(net "JTAG_TDO_RT_CPU1_P1")
	)
	(segment
		(start 101.68763 -390.443466)
		(end 101.68763 -394.132816)
		(width 0.11684)
		(layer "In11.Cu")
		(net "JTAG_TDO_RT_CPU1_P1")
	)
	(segment
		(start 100.377244 -389.030972)
		(end 100.377244 -389.13308)
		(width 0.11684)
		(layer "In11.Cu")
		(net "JTAG_TDO_RT_CPU1_P1")
	)
	(segment
		(start 97.96018 -411.30474)
		(end 96.496378 -412.768542)
		(width 0.11684)
		(layer "In11.Cu")
		(net "JTAG_TDO_RT_CPU1_P1")
	)
	(segment
		(start 100.377244 -389.13308)
		(end 101.68763 -390.443466)
		(width 0.11684)
		(layer "In11.Cu")
		(net "JTAG_TDO_RT_CPU1_P1")
	)
	(segment
		(start 101.25456 -402.117814)
		(end 99.111308 -404.261066)
		(width 0.11684)
		(layer "In11.Cu")
		(net "JTAG_TDO_RT_CPU1_P1")
	)
	(segment
		(start 97.96018 -407.04008)
		(end 97.96018 -411.30474)
		(width 0.11684)
		(layer "In11.Cu")
		(net "JTAG_TDO_RT_CPU1_P1")
	)
	(segment
		(start 100.86213 -399.015458)
		(end 101.25456 -399.407888)
		(width 0.11684)
		(layer "In11.Cu")
		(net "JTAG_TDO_RT_CPU1_P1")
	)
	(segment
		(start 46.307502 -419.700964)
		(end 46.71568 -420.109142)
		(width 0.10668)
		(layer "F.Cu")
		(net "JTAG_TDO_RT_CPU1_P0")
	)
	(segment
		(start 46.199044 -419.700964)
		(end 46.307502 -419.700964)
		(width 0.10668)
		(layer "F.Cu")
		(net "JTAG_TDO_RT_CPU1_P0")
	)
	(segment
		(start 67.353942 -389.030972)
		(end 67.849496 -389.030972)
		(width 0.10668)
		(layer "F.Cu")
		(net "JTAG_TDO_RT_CPU1_P0")
	)
	(via
		(at 67.849496 -389.030972)
		(size 0.4064)
		(drill 0.2032)
		(layers "F.Cu" "B.Cu")
		(net "JTAG_TDO_RT_CPU1_P0")
	)
	(via
		(at 44.685458 -419.482524)
		(size 0.6604)
		(drill 0.3302)
		(layers "F.Cu" "B.Cu")
		(net "JTAG_TDO_RT_CPU1_P0")
	)
	(via
		(at 46.71568 -420.109142)
		(size 0.508)
		(drill 0.254)
		(layers "F.Cu" "B.Cu")
		(net "JTAG_TDO_RT_CPU1_P0")
	)
	(segment
		(start 46.054518 -420.109142)
		(end 45.4279 -419.482524)
		(width 0.10668)
		(layer "B.Cu")
		(net "JTAG_TDO_RT_CPU1_P0")
	)
	(segment
		(start 46.71568 -420.109142)
		(end 46.054518 -420.109142)
		(width 0.10668)
		(layer "B.Cu")
		(net "JTAG_TDO_RT_CPU1_P0")
	)
	(segment
		(start 45.4279 -419.482524)
		(end 44.685458 -419.482524)
		(width 0.10668)
		(layer "B.Cu")
		(net "JTAG_TDO_RT_CPU1_P0")
	)
	(segment
		(start 66.786506 -395.478)
		(end 68.12026 -394.144246)
		(width 0.11684)
		(layer "In13.Cu")
		(net "JTAG_TDO_RT_CPU1_P0")
	)
	(segment
		(start 46.71568 -420.109142)
		(end 46.284388 -419.67785)
		(width 0.11684)
		(layer "In13.Cu")
		(net "JTAG_TDO_RT_CPU1_P0")
	)
	(segment
		(start 68.12026 -394.144246)
		(end 68.12026 -393.147042)
		(width 0.11684)
		(layer "In13.Cu")
		(net "JTAG_TDO_RT_CPU1_P0")
	)
	(segment
		(start 67.849496 -389.116316)
		(end 67.849496 -389.030972)
		(width 0.11684)
		(layer "In13.Cu")
		(net "JTAG_TDO_RT_CPU1_P0")
	)
	(segment
		(start 47.83582 -401.30984)
		(end 53.66766 -395.478)
		(width 0.11684)
		(layer "In13.Cu")
		(net "JTAG_TDO_RT_CPU1_P0")
	)
	(segment
		(start 53.66766 -395.478)
		(end 66.786506 -395.478)
		(width 0.11684)
		(layer "In13.Cu")
		(net "JTAG_TDO_RT_CPU1_P0")
	)
	(segment
		(start 46.820836 -403.760178)
		(end 47.83582 -401.30984)
		(width 0.11684)
		(layer "In13.Cu")
		(net "JTAG_TDO_RT_CPU1_P0")
	)
	(segment
		(start 68.12026 -393.147042)
		(end 68.64096 -392.626342)
		(width 0.11684)
		(layer "In13.Cu")
		(net "JTAG_TDO_RT_CPU1_P0")
	)
	(segment
		(start 68.64096 -389.90778)
		(end 67.849496 -389.116316)
		(width 0.11684)
		(layer "In13.Cu")
		(net "JTAG_TDO_RT_CPU1_P0")
	)
	(segment
		(start 46.820836 -406.399492)
		(end 46.820836 -403.760178)
		(width 0.11684)
		(layer "In13.Cu")
		(net "JTAG_TDO_RT_CPU1_P0")
	)
	(segment
		(start 46.284388 -407.694638)
		(end 46.820836 -406.399492)
		(width 0.11684)
		(layer "In13.Cu")
		(net "JTAG_TDO_RT_CPU1_P0")
	)
	(segment
		(start 46.284388 -419.67785)
		(end 46.284388 -407.694638)
		(width 0.11684)
		(layer "In13.Cu")
		(net "JTAG_TDO_RT_CPU1_P0")
	)
	(segment
		(start 68.64096 -392.626342)
		(end 68.64096 -389.90778)
		(width 0.11684)
		(layer "In13.Cu")
		(net "JTAG_TDO_RT_CPU1_P0")
	)
	(segment
		(start 426.1612 -421.9067)
		(end 426.749718 -422.495218)
		(width 0.10668)
		(layer "F.Cu")
		(net "JTAG_TDO_RT_CPU0_P3")
	)
	(segment
		(start 390.45388 -397.412972)
		(end 390.949434 -397.412972)
		(width 0.10668)
		(layer "F.Cu")
		(net "JTAG_TDO_RT_CPU0_P3")
	)
	(segment
		(start 426.749718 -422.495218)
		(end 426.813218 -422.495218)
		(width 0.10668)
		(layer "F.Cu")
		(net "JTAG_TDO_RT_CPU0_P3")
	)
	(via
		(at 390.949434 -397.412972)
		(size 0.4064)
		(drill 0.2032)
		(layers "F.Cu" "B.Cu")
		(net "JTAG_TDO_RT_CPU0_P3")
	)
	(via
		(at 426.813218 -422.495218)
		(size 0.508)
		(drill 0.254)
		(layers "F.Cu" "B.Cu")
		(net "JTAG_TDO_RT_CPU0_P3")
	)
	(segment
		(start 402.774658 -399.296382)
		(end 401.828508 -398.350232)
		(width 0.11684)
		(layer "In6.Cu")
		(net "JTAG_TDO_RT_CPU0_P3")
	)
	(segment
		(start 404.368508 -399.296382)
		(end 402.774658 -399.296382)
		(width 0.11684)
		(layer "In6.Cu")
		(net "JTAG_TDO_RT_CPU0_P3")
	)
	(segment
		(start 421.85336 -410.446474)
		(end 420.15029 -408.743404)
		(width 0.11684)
		(layer "In6.Cu")
		(net "JTAG_TDO_RT_CPU0_P3")
	)
	(segment
		(start 405.725376 -402.768816)
		(end 405.24938 -402.29282)
		(width 0.11684)
		(layer "In6.Cu")
		(net "JTAG_TDO_RT_CPU0_P3")
	)
	(segment
		(start 422.893236 -421.635682)
		(end 421.85336 -420.595806)
		(width 0.11684)
		(layer "In6.Cu")
		(net "JTAG_TDO_RT_CPU0_P3")
	)
	(segment
		(start 401.828508 -398.350232)
		(end 401.828508 -397.152368)
		(width 0.11684)
		(layer "In6.Cu")
		(net "JTAG_TDO_RT_CPU0_P3")
	)
	(segment
		(start 400.114262 -396.253716)
		(end 398.062196 -394.20165)
		(width 0.11684)
		(layer "In6.Cu")
		(net "JTAG_TDO_RT_CPU0_P3")
	)
	(segment
		(start 421.85336 -420.595806)
		(end 421.85336 -410.446474)
		(width 0.11684)
		(layer "In6.Cu")
		(net "JTAG_TDO_RT_CPU0_P3")
	)
	(segment
		(start 405.24938 -402.29282)
		(end 405.24938 -400.177254)
		(width 0.11684)
		(layer "In6.Cu")
		(net "JTAG_TDO_RT_CPU0_P3")
	)
	(segment
		(start 400.929856 -396.253716)
		(end 400.114262 -396.253716)
		(width 0.11684)
		(layer "In6.Cu")
		(net "JTAG_TDO_RT_CPU0_P3")
	)
	(segment
		(start 398.062196 -394.20165)
		(end 396.424404 -394.20165)
		(width 0.11684)
		(layer "In6.Cu")
		(net "JTAG_TDO_RT_CPU0_P3")
	)
	(segment
		(start 420.15029 -408.743404)
		(end 405.725376 -402.768816)
		(width 0.11684)
		(layer "In6.Cu")
		(net "JTAG_TDO_RT_CPU0_P3")
	)
	(segment
		(start 396.424404 -394.20165)
		(end 394.243814 -396.38224)
		(width 0.11684)
		(layer "In6.Cu")
		(net "JTAG_TDO_RT_CPU0_P3")
	)
	(segment
		(start 426.813218 -422.495218)
		(end 426.813218 -422.190418)
		(width 0.11684)
		(layer "In6.Cu")
		(net "JTAG_TDO_RT_CPU0_P3")
	)
	(segment
		(start 391.801604 -396.38224)
		(end 390.949434 -397.23441)
		(width 0.11684)
		(layer "In6.Cu")
		(net "JTAG_TDO_RT_CPU0_P3")
	)
	(segment
		(start 394.243814 -396.38224)
		(end 391.801604 -396.38224)
		(width 0.11684)
		(layer "In6.Cu")
		(net "JTAG_TDO_RT_CPU0_P3")
	)
	(segment
		(start 390.949434 -397.23441)
		(end 390.949434 -397.412972)
		(width 0.11684)
		(layer "In6.Cu")
		(net "JTAG_TDO_RT_CPU0_P3")
	)
	(segment
		(start 426.813218 -422.190418)
		(end 426.258482 -421.635682)
		(width 0.11684)
		(layer "In6.Cu")
		(net "JTAG_TDO_RT_CPU0_P3")
	)
	(segment
		(start 426.258482 -421.635682)
		(end 422.893236 -421.635682)
		(width 0.11684)
		(layer "In6.Cu")
		(net "JTAG_TDO_RT_CPU0_P3")
	)
	(segment
		(start 401.828508 -397.152368)
		(end 400.929856 -396.253716)
		(width 0.11684)
		(layer "In6.Cu")
		(net "JTAG_TDO_RT_CPU0_P3")
	)
	(segment
		(start 405.24938 -400.177254)
		(end 404.368508 -399.296382)
		(width 0.11684)
		(layer "In6.Cu")
		(net "JTAG_TDO_RT_CPU0_P3")
	)
	(segment
		(start 422.981628 -397.412972)
		(end 423.476928 -397.412972)
		(width 0.10668)
		(layer "F.Cu")
		(net "JTAG_TDO_RT_CPU0_P2")
	)
	(segment
		(start 432.5747 -406.7048)
		(end 434.785262 -406.7048)
		(width 0.10668)
		(layer "F.Cu")
		(net "JTAG_TDO_RT_CPU0_P2")
	)
	(segment
		(start 434.785262 -406.7048)
		(end 435.252622 -407.17216)
		(width 0.10668)
		(layer "F.Cu")
		(net "JTAG_TDO_RT_CPU0_P2")
	)
	(via
		(at 435.252622 -407.17216)
		(size 0.508)
		(drill 0.254)
		(layers "F.Cu" "B.Cu")
		(net "JTAG_TDO_RT_CPU0_P2")
	)
	(via
		(at 423.476928 -397.412972)
		(size 0.4064)
		(drill 0.2032)
		(layers "F.Cu" "B.Cu")
		(net "JTAG_TDO_RT_CPU0_P2")
	)
	(segment
		(start 423.592244 -397.528288)
		(end 423.476928 -397.412972)
		(width 0.10668)
		(layer "B.Cu")
		(net "JTAG_TDO_RT_CPU0_P2")
	)
	(segment
		(start 429.438054 -401.980654)
		(end 427.327568 -401.980654)
		(width 0.10668)
		(layer "B.Cu")
		(net "JTAG_TDO_RT_CPU0_P2")
	)
	(segment
		(start 435.252622 -407.17216)
		(end 434.62956 -407.17216)
		(width 0.10668)
		(layer "B.Cu")
		(net "JTAG_TDO_RT_CPU0_P2")
	)
	(segment
		(start 426.33392 -399.034)
		(end 425.181522 -397.881602)
		(width 0.10668)
		(layer "B.Cu")
		(net "JTAG_TDO_RT_CPU0_P2")
	)
	(segment
		(start 426.33392 -400.987006)
		(end 426.33392 -399.034)
		(width 0.10668)
		(layer "B.Cu")
		(net "JTAG_TDO_RT_CPU0_P2")
	)
	(segment
		(start 427.327568 -401.980654)
		(end 426.33392 -400.987006)
		(width 0.10668)
		(layer "B.Cu")
		(net "JTAG_TDO_RT_CPU0_P2")
	)
	(segment
		(start 425.181522 -397.881602)
		(end 424.795696 -397.881602)
		(width 0.10668)
		(layer "B.Cu")
		(net "JTAG_TDO_RT_CPU0_P2")
	)
	(segment
		(start 424.795696 -397.881602)
		(end 424.442382 -397.528288)
		(width 0.10668)
		(layer "B.Cu")
		(net "JTAG_TDO_RT_CPU0_P2")
	)
	(segment
		(start 424.442382 -397.528288)
		(end 423.592244 -397.528288)
		(width 0.10668)
		(layer "B.Cu")
		(net "JTAG_TDO_RT_CPU0_P2")
	)
	(segment
		(start 434.62956 -407.17216)
		(end 429.438054 -401.980654)
		(width 0.10668)
		(layer "B.Cu")
		(net "JTAG_TDO_RT_CPU0_P2")
	)
	(segment
		(start 358.80294 -403.39518)
		(end 358.80294 -404.877524)
		(width 0.10668)
		(layer "F.Cu")
		(net "JTAG_TDO_RT_CPU0_P1")
	)
	(segment
		(start 355.881432 -397.412972)
		(end 356.376986 -397.412972)
		(width 0.10668)
		(layer "F.Cu")
		(net "JTAG_TDO_RT_CPU0_P1")
	)
	(segment
		(start 359.114344 -403.083776)
		(end 358.80294 -403.39518)
		(width 0.10668)
		(layer "F.Cu")
		(net "JTAG_TDO_RT_CPU0_P1")
	)
	(segment
		(start 353.606862 -408.635962)
		(end 353.1108 -408.1399)
		(width 0.10668)
		(layer "F.Cu")
		(net "JTAG_TDO_RT_CPU0_P1")
	)
	(segment
		(start 358.80294 -404.877524)
		(end 355.044502 -408.635962)
		(width 0.10668)
		(layer "F.Cu")
		(net "JTAG_TDO_RT_CPU0_P1")
	)
	(segment
		(start 355.044502 -408.635962)
		(end 353.606862 -408.635962)
		(width 0.10668)
		(layer "F.Cu")
		(net "JTAG_TDO_RT_CPU0_P1")
	)
	(via
		(at 356.376986 -397.412972)
		(size 0.4064)
		(drill 0.2032)
		(layers "F.Cu" "B.Cu")
		(net "JTAG_TDO_RT_CPU0_P1")
	)
	(via
		(at 359.114344 -403.083776)
		(size 0.508)
		(drill 0.254)
		(layers "F.Cu" "B.Cu")
		(net "JTAG_TDO_RT_CPU0_P1")
	)
	(segment
		(start 356.376986 -397.56969)
		(end 356.376986 -397.412972)
		(width 0.11684)
		(layer "In15.Cu")
		(net "JTAG_TDO_RT_CPU0_P1")
	)
	(segment
		(start 358.28478 -400.237706)
		(end 356.790752 -398.743678)
		(width 0.11684)
		(layer "In15.Cu")
		(net "JTAG_TDO_RT_CPU0_P1")
	)
	(segment
		(start 356.790752 -398.743678)
		(end 356.790752 -397.983456)
		(width 0.11684)
		(layer "In15.Cu")
		(net "JTAG_TDO_RT_CPU0_P1")
	)
	(segment
		(start 358.28478 -402.254212)
		(end 358.28478 -400.237706)
		(width 0.11684)
		(layer "In15.Cu")
		(net "JTAG_TDO_RT_CPU0_P1")
	)
	(segment
		(start 359.114344 -403.083776)
		(end 358.28478 -402.254212)
		(width 0.11684)
		(layer "In15.Cu")
		(net "JTAG_TDO_RT_CPU0_P1")
	)
	(segment
		(start 356.790752 -397.983456)
		(end 356.376986 -397.56969)
		(width 0.11684)
		(layer "In15.Cu")
		(net "JTAG_TDO_RT_CPU0_P1")
	)
	(segment
		(start 323.353684 -397.412972)
		(end 323.849238 -397.412972)
		(width 0.10668)
		(layer "F.Cu")
		(net "JTAG_TDO_RT_CPU0_P0")
	)
	(via
		(at 307.986938 -425.678092)
		(size 0.6604)
		(drill 0.3302)
		(layers "F.Cu" "B.Cu")
		(net "JTAG_TDO_RT_CPU0_P0")
	)
	(via
		(at 306.223416 -426.466)
		(size 0.508)
		(drill 0.254)
		(layers "F.Cu" "B.Cu")
		(net "JTAG_TDO_RT_CPU0_P0")
	)
	(via
		(at 323.849238 -397.412972)
		(size 0.4064)
		(drill 0.2032)
		(layers "F.Cu" "B.Cu")
		(net "JTAG_TDO_RT_CPU0_P0")
	)
	(segment
		(start 305.690016 -426.466)
		(end 306.223416 -426.466)
		(width 0.10668)
		(layer "B.Cu")
		(net "JTAG_TDO_RT_CPU0_P0")
	)
	(segment
		(start 307.400452 -426.264578)
		(end 307.986938 -425.678092)
		(width 0.10668)
		(layer "B.Cu")
		(net "JTAG_TDO_RT_CPU0_P0")
	)
	(segment
		(start 306.424838 -426.264578)
		(end 307.400452 -426.264578)
		(width 0.10668)
		(layer "B.Cu")
		(net "JTAG_TDO_RT_CPU0_P0")
	)
	(segment
		(start 306.223416 -426.466)
		(end 306.424838 -426.264578)
		(width 0.10668)
		(layer "B.Cu")
		(net "JTAG_TDO_RT_CPU0_P0")
	)
	(segment
		(start 302.2727 -399.64614)
		(end 301.81296 -400.10588)
		(width 0.11684)
		(layer "In13.Cu")
		(net "JTAG_TDO_RT_CPU0_P0")
	)
	(segment
		(start 296.293794 -400.10588)
		(end 295.5544 -400.845274)
		(width 0.11684)
		(layer "In13.Cu")
		(net "JTAG_TDO_RT_CPU0_P0")
	)
	(segment
		(start 305.868324 -426.098462)
		(end 306.223416 -426.453554)
		(width 0.11684)
		(layer "In13.Cu")
		(net "JTAG_TDO_RT_CPU0_P0")
	)
	(segment
		(start 303.11217 -424.290744)
		(end 303.11217 -425.075858)
		(width 0.11684)
		(layer "In13.Cu")
		(net "JTAG_TDO_RT_CPU0_P0")
	)
	(segment
		(start 303.11217 -425.075858)
		(end 304.134774 -426.098462)
		(width 0.11684)
		(layer "In13.Cu")
		(net "JTAG_TDO_RT_CPU0_P0")
	)
	(segment
		(start 297.347894 -419.689788)
		(end 298.511214 -419.689788)
		(width 0.11684)
		(layer "In13.Cu")
		(net "JTAG_TDO_RT_CPU0_P0")
	)
	(segment
		(start 292.70452 -408.54376)
		(end 292.70452 -415.046414)
		(width 0.11684)
		(layer "In13.Cu")
		(net "JTAG_TDO_RT_CPU0_P0")
	)
	(segment
		(start 298.511214 -419.689788)
		(end 303.11217 -424.290744)
		(width 0.11684)
		(layer "In13.Cu")
		(net "JTAG_TDO_RT_CPU0_P0")
	)
	(segment
		(start 322.892674 -399.64614)
		(end 302.2727 -399.64614)
		(width 0.11684)
		(layer "In13.Cu")
		(net "JTAG_TDO_RT_CPU0_P0")
	)
	(segment
		(start 306.223416 -426.453554)
		(end 306.223416 -426.466)
		(width 0.11684)
		(layer "In13.Cu")
		(net "JTAG_TDO_RT_CPU0_P0")
	)
	(segment
		(start 324.004686 -399.935192)
		(end 323.181726 -399.935192)
		(width 0.11684)
		(layer "In13.Cu")
		(net "JTAG_TDO_RT_CPU0_P0")
	)
	(segment
		(start 324.583044 -399.356834)
		(end 324.004686 -399.935192)
		(width 0.11684)
		(layer "In13.Cu")
		(net "JTAG_TDO_RT_CPU0_P0")
	)
	(segment
		(start 292.70452 -415.046414)
		(end 297.347894 -419.689788)
		(width 0.11684)
		(layer "In13.Cu")
		(net "JTAG_TDO_RT_CPU0_P0")
	)
	(segment
		(start 301.81296 -400.10588)
		(end 296.293794 -400.10588)
		(width 0.11684)
		(layer "In13.Cu")
		(net "JTAG_TDO_RT_CPU0_P0")
	)
	(segment
		(start 295.5544 -400.845274)
		(end 295.5544 -405.69388)
		(width 0.11684)
		(layer "In13.Cu")
		(net "JTAG_TDO_RT_CPU0_P0")
	)
	(segment
		(start 323.181726 -399.935192)
		(end 322.892674 -399.64614)
		(width 0.11684)
		(layer "In13.Cu")
		(net "JTAG_TDO_RT_CPU0_P0")
	)
	(segment
		(start 304.134774 -426.098462)
		(end 305.868324 -426.098462)
		(width 0.11684)
		(layer "In13.Cu")
		(net "JTAG_TDO_RT_CPU0_P0")
	)
	(segment
		(start 323.849238 -397.412972)
		(end 323.849238 -397.56969)
		(width 0.11684)
		(layer "In13.Cu")
		(net "JTAG_TDO_RT_CPU0_P0")
	)
	(segment
		(start 323.849238 -397.56969)
		(end 324.583044 -398.303496)
		(width 0.11684)
		(layer "In13.Cu")
		(net "JTAG_TDO_RT_CPU0_P0")
	)
	(segment
		(start 324.583044 -398.303496)
		(end 324.583044 -399.356834)
		(width 0.11684)
		(layer "In13.Cu")
		(net "JTAG_TDO_RT_CPU0_P0")
	)
	(segment
		(start 295.5544 -405.69388)
		(end 292.70452 -408.54376)
		(width 0.11684)
		(layer "In13.Cu")
		(net "JTAG_TDO_RT_CPU0_P0")
	)
	(segment
		(start 135.109204 -389.77316)
		(end 134.596124 -389.77316)
		(width 0.10668)
		(layer "F.Cu")
		(net "JTAG_TDI_RT_CPU1_P3")
	)
	(segment
		(start 134.596124 -389.77316)
		(end 134.453884 -389.63092)
		(width 0.10668)
		(layer "F.Cu")
		(net "JTAG_TDI_RT_CPU1_P3")
	)
	(via
		(at 165.704266 -425.953936)
		(size 0.6604)
		(drill 0.3302)
		(layers "F.Cu" "B.Cu")
		(net "JTAG_TDI_RT_CPU1_P3")
	)
	(via
		(at 163.87826 -405.1427)
		(size 0.508)
		(drill 0.254)
		(layers "F.Cu" "B.Cu")
		(net "JTAG_TDI_RT_CPU1_P3")
	)
	(via
		(at 135.109204 -389.77316)
		(size 0.4064)
		(drill 0.2032)
		(layers "F.Cu" "B.Cu")
		(net "JTAG_TDI_RT_CPU1_P3")
	)
	(via
		(at 165.1508 -425.40047)
		(size 0.508)
		(drill 0.254)
		(layers "F.Cu" "B.Cu")
		(net "JTAG_TDI_RT_CPU1_P3")
	)
	(segment
		(start 165.1508 -424.86707)
		(end 165.1508 -425.40047)
		(width 0.10668)
		(layer "B.Cu")
		(net "JTAG_TDI_RT_CPU1_P3")
	)
	(segment
		(start 165.1508 -425.40047)
		(end 165.704266 -425.953936)
		(width 0.10668)
		(layer "B.Cu")
		(net "JTAG_TDI_RT_CPU1_P3")
	)
	(segment
		(start 136.16178 -394.57122)
		(end 136.16178 -390.6012)
		(width 0.11684)
		(layer "In11.Cu")
		(net "JTAG_TDI_RT_CPU1_P3")
	)
	(segment
		(start 143.72844 -402.13788)
		(end 136.16178 -394.57122)
		(width 0.11684)
		(layer "In11.Cu")
		(net "JTAG_TDI_RT_CPU1_P3")
	)
	(segment
		(start 135.33374 -389.77316)
		(end 135.109204 -389.77316)
		(width 0.11684)
		(layer "In11.Cu")
		(net "JTAG_TDI_RT_CPU1_P3")
	)
	(segment
		(start 163.87826 -405.1427)
		(end 163.24072 -404.50516)
		(width 0.11684)
		(layer "In11.Cu")
		(net "JTAG_TDI_RT_CPU1_P3")
	)
	(segment
		(start 163.24072 -404.50516)
		(end 163.24072 -404.09114)
		(width 0.11684)
		(layer "In11.Cu")
		(net "JTAG_TDI_RT_CPU1_P3")
	)
	(segment
		(start 136.16178 -390.6012)
		(end 135.33374 -389.77316)
		(width 0.11684)
		(layer "In11.Cu")
		(net "JTAG_TDI_RT_CPU1_P3")
	)
	(segment
		(start 161.28746 -402.13788)
		(end 143.72844 -402.13788)
		(width 0.11684)
		(layer "In11.Cu")
		(net "JTAG_TDI_RT_CPU1_P3")
	)
	(segment
		(start 163.24072 -404.09114)
		(end 161.28746 -402.13788)
		(width 0.11684)
		(layer "In11.Cu")
		(net "JTAG_TDI_RT_CPU1_P3")
	)
	(segment
		(start 164.16655 -424.41622)
		(end 162.72002 -424.41622)
		(width 0.11684)
		(layer "In13.Cu")
		(net "JTAG_TDI_RT_CPU1_P3")
	)
	(segment
		(start 165.46322 -417.82746)
		(end 165.46322 -416.2806)
		(width 0.11684)
		(layer "In13.Cu")
		(net "JTAG_TDI_RT_CPU1_P3")
	)
	(segment
		(start 165.46322 -412.02356)
		(end 164.55644 -411.11678)
		(width 0.11684)
		(layer "In13.Cu")
		(net "JTAG_TDI_RT_CPU1_P3")
	)
	(segment
		(start 162.06978 -422.6433)
		(end 164.29736 -420.41572)
		(width 0.11684)
		(layer "In13.Cu")
		(net "JTAG_TDI_RT_CPU1_P3")
	)
	(segment
		(start 165.46322 -413.1437)
		(end 165.46322 -412.02356)
		(width 0.11684)
		(layer "In13.Cu")
		(net "JTAG_TDI_RT_CPU1_P3")
	)
	(segment
		(start 164.29736 -418.99332)
		(end 165.46322 -417.82746)
		(width 0.11684)
		(layer "In13.Cu")
		(net "JTAG_TDI_RT_CPU1_P3")
	)
	(segment
		(start 164.55644 -405.82088)
		(end 163.87826 -405.1427)
		(width 0.11684)
		(layer "In13.Cu")
		(net "JTAG_TDI_RT_CPU1_P3")
	)
	(segment
		(start 162.06978 -423.76598)
		(end 162.06978 -422.6433)
		(width 0.11684)
		(layer "In13.Cu")
		(net "JTAG_TDI_RT_CPU1_P3")
	)
	(segment
		(start 164.29736 -420.41572)
		(end 164.29736 -418.99332)
		(width 0.11684)
		(layer "In13.Cu")
		(net "JTAG_TDI_RT_CPU1_P3")
	)
	(segment
		(start 165.01364 -415.83102)
		(end 165.01364 -413.59328)
		(width 0.11684)
		(layer "In13.Cu")
		(net "JTAG_TDI_RT_CPU1_P3")
	)
	(segment
		(start 165.1508 -425.40047)
		(end 164.16655 -424.41622)
		(width 0.11684)
		(layer "In13.Cu")
		(net "JTAG_TDI_RT_CPU1_P3")
	)
	(segment
		(start 162.72002 -424.41622)
		(end 162.06978 -423.76598)
		(width 0.11684)
		(layer "In13.Cu")
		(net "JTAG_TDI_RT_CPU1_P3")
	)
	(segment
		(start 164.55644 -411.11678)
		(end 164.55644 -405.82088)
		(width 0.11684)
		(layer "In13.Cu")
		(net "JTAG_TDI_RT_CPU1_P3")
	)
	(segment
		(start 165.01364 -413.59328)
		(end 165.46322 -413.1437)
		(width 0.11684)
		(layer "In13.Cu")
		(net "JTAG_TDI_RT_CPU1_P3")
	)
	(segment
		(start 165.46322 -416.2806)
		(end 165.01364 -415.83102)
		(width 0.11684)
		(layer "In13.Cu")
		(net "JTAG_TDI_RT_CPU1_P3")
	)
	(segment
		(start 178.07686 -393.2936)
		(end 179.5907 -393.2936)
		(width 0.10668)
		(layer "F.Cu")
		(net "JTAG_TDI_RT_CPU1_P2")
	)
	(segment
		(start 167.123872 -389.77316)
		(end 167.476932 -389.77316)
		(width 0.10668)
		(layer "F.Cu")
		(net "JTAG_TDI_RT_CPU1_P2")
	)
	(segment
		(start 166.981632 -389.63092)
		(end 167.123872 -389.77316)
		(width 0.10668)
		(layer "F.Cu")
		(net "JTAG_TDI_RT_CPU1_P2")
	)
	(via
		(at 179.5907 -393.2936)
		(size 0.508)
		(drill 0.254)
		(layers "F.Cu" "B.Cu")
		(net "JTAG_TDI_RT_CPU1_P2")
	)
	(via
		(at 167.476932 -389.77316)
		(size 0.4064)
		(drill 0.2032)
		(layers "F.Cu" "B.Cu")
		(net "JTAG_TDI_RT_CPU1_P2")
	)
	(segment
		(start 179.5907 -393.2936)
		(end 178.43754 -393.2936)
		(width 0.10668)
		(layer "B.Cu")
		(net "JTAG_TDI_RT_CPU1_P2")
	)
	(segment
		(start 170.40225 -393.42441)
		(end 169.569638 -392.591798)
		(width 0.10668)
		(layer "B.Cu")
		(net "JTAG_TDI_RT_CPU1_P2")
	)
	(segment
		(start 169.05478 -390.157716)
		(end 167.974772 -390.157716)
		(width 0.10668)
		(layer "B.Cu")
		(net "JTAG_TDI_RT_CPU1_P2")
	)
	(segment
		(start 178.43754 -393.2936)
		(end 177.5587 -392.41476)
		(width 0.10668)
		(layer "B.Cu")
		(net "JTAG_TDI_RT_CPU1_P2")
	)
	(segment
		(start 172.28058 -392.41476)
		(end 171.27093 -393.42441)
		(width 0.10668)
		(layer "B.Cu")
		(net "JTAG_TDI_RT_CPU1_P2")
	)
	(segment
		(start 171.27093 -393.42441)
		(end 170.40225 -393.42441)
		(width 0.10668)
		(layer "B.Cu")
		(net "JTAG_TDI_RT_CPU1_P2")
	)
	(segment
		(start 167.590216 -389.77316)
		(end 167.476932 -389.77316)
		(width 0.10668)
		(layer "B.Cu")
		(net "JTAG_TDI_RT_CPU1_P2")
	)
	(segment
		(start 169.569638 -390.672574)
		(end 169.05478 -390.157716)
		(width 0.10668)
		(layer "B.Cu")
		(net "JTAG_TDI_RT_CPU1_P2")
	)
	(segment
		(start 169.569638 -392.591798)
		(end 169.569638 -390.672574)
		(width 0.10668)
		(layer "B.Cu")
		(net "JTAG_TDI_RT_CPU1_P2")
	)
	(segment
		(start 177.5587 -392.41476)
		(end 172.28058 -392.41476)
		(width 0.10668)
		(layer "B.Cu")
		(net "JTAG_TDI_RT_CPU1_P2")
	)
	(segment
		(start 167.974772 -390.157716)
		(end 167.590216 -389.77316)
		(width 0.10668)
		(layer "B.Cu")
		(net "JTAG_TDI_RT_CPU1_P2")
	)
	(segment
		(start 99.88169 -389.63092)
		(end 100.02393 -389.77316)
		(width 0.10668)
		(layer "F.Cu")
		(net "JTAG_TDI_RT_CPU1_P1")
	)
	(segment
		(start 95.358712 -417.2204)
		(end 94.872048 -417.707064)
		(width 0.10668)
		(layer "F.Cu")
		(net "JTAG_TDI_RT_CPU1_P1")
	)
	(segment
		(start 95.7961 -417.2204)
		(end 95.358712 -417.2204)
		(width 0.10668)
		(layer "F.Cu")
		(net "JTAG_TDI_RT_CPU1_P1")
	)
	(segment
		(start 100.02393 -389.77316)
		(end 100.37699 -389.77316)
		(width 0.10668)
		(layer "F.Cu")
		(net "JTAG_TDI_RT_CPU1_P1")
	)
	(segment
		(start 94.872048 -417.707064)
		(end 94.443042 -417.707064)
		(width 0.10668)
		(layer "F.Cu")
		(net "JTAG_TDI_RT_CPU1_P1")
	)
	(via
		(at 100.37699 -389.77316)
		(size 0.4064)
		(drill 0.2032)
		(layers "F.Cu" "B.Cu")
		(net "JTAG_TDI_RT_CPU1_P1")
	)
	(via
		(at 94.443042 -417.707064)
		(size 0.508)
		(drill 0.254)
		(layers "F.Cu" "B.Cu")
		(net "JTAG_TDI_RT_CPU1_P1")
	)
	(segment
		(start 101.039422 -390.371076)
		(end 101.039422 -391.416794)
		(width 0.11684)
		(layer "In11.Cu")
		(net "JTAG_TDI_RT_CPU1_P1")
	)
	(segment
		(start 94.713044 -417.707064)
		(end 94.443042 -417.707064)
		(width 0.11684)
		(layer "In11.Cu")
		(net "JTAG_TDI_RT_CPU1_P1")
	)
	(segment
		(start 100.37699 -389.77316)
		(end 100.441506 -389.77316)
		(width 0.11684)
		(layer "In11.Cu")
		(net "JTAG_TDI_RT_CPU1_P1")
	)
	(segment
		(start 99.438968 -399.428462)
		(end 99.438968 -400.713956)
		(width 0.11684)
		(layer "In11.Cu")
		(net "JTAG_TDI_RT_CPU1_P1")
	)
	(segment
		(start 96.04756 -416.372548)
		(end 94.713044 -417.707064)
		(width 0.11684)
		(layer "In11.Cu")
		(net "JTAG_TDI_RT_CPU1_P1")
	)
	(segment
		(start 101.039422 -391.416794)
		(end 99.88296 -392.573256)
		(width 0.11684)
		(layer "In11.Cu")
		(net "JTAG_TDI_RT_CPU1_P1")
	)
	(segment
		(start 99.438968 -400.713956)
		(end 100.00742 -401.282408)
		(width 0.11684)
		(layer "In11.Cu")
		(net "JTAG_TDI_RT_CPU1_P1")
	)
	(segment
		(start 100.076 -398.79143)
		(end 99.438968 -399.428462)
		(width 0.11684)
		(layer "In11.Cu")
		(net "JTAG_TDI_RT_CPU1_P1")
	)
	(segment
		(start 100.00742 -401.282408)
		(end 100.00742 -402.500846)
		(width 0.11684)
		(layer "In11.Cu")
		(net "JTAG_TDI_RT_CPU1_P1")
	)
	(segment
		(start 98.81743 -403.690836)
		(end 97.55886 -406.729692)
		(width 0.11684)
		(layer "In11.Cu")
		(net "JTAG_TDI_RT_CPU1_P1")
	)
	(segment
		(start 100.00742 -402.500846)
		(end 98.81743 -403.690836)
		(width 0.11684)
		(layer "In11.Cu")
		(net "JTAG_TDI_RT_CPU1_P1")
	)
	(segment
		(start 97.55886 -411.031944)
		(end 96.04756 -412.543244)
		(width 0.11684)
		(layer "In11.Cu")
		(net "JTAG_TDI_RT_CPU1_P1")
	)
	(segment
		(start 96.04756 -412.543244)
		(end 96.04756 -416.372548)
		(width 0.11684)
		(layer "In11.Cu")
		(net "JTAG_TDI_RT_CPU1_P1")
	)
	(segment
		(start 100.441506 -389.77316)
		(end 101.039422 -390.371076)
		(width 0.11684)
		(layer "In11.Cu")
		(net "JTAG_TDI_RT_CPU1_P1")
	)
	(segment
		(start 99.88296 -393.0777)
		(end 100.076 -393.27074)
		(width 0.11684)
		(layer "In11.Cu")
		(net "JTAG_TDI_RT_CPU1_P1")
	)
	(segment
		(start 99.88296 -392.573256)
		(end 99.88296 -393.0777)
		(width 0.11684)
		(layer "In11.Cu")
		(net "JTAG_TDI_RT_CPU1_P1")
	)
	(segment
		(start 100.076 -393.27074)
		(end 100.076 -398.79143)
		(width 0.11684)
		(layer "In11.Cu")
		(net "JTAG_TDI_RT_CPU1_P1")
	)
	(segment
		(start 97.55886 -406.729692)
		(end 97.55886 -411.031944)
		(width 0.11684)
		(layer "In11.Cu")
		(net "JTAG_TDI_RT_CPU1_P1")
	)
	(segment
		(start 46.414944 -420.513764)
		(end 46.729396 -420.828216)
		(width 0.10668)
		(layer "F.Cu")
		(net "JTAG_TDI_RT_CPU1_P0")
	)
	(segment
		(start 67.496182 -389.77316)
		(end 67.849242 -389.77316)
		(width 0.10668)
		(layer "F.Cu")
		(net "JTAG_TDI_RT_CPU1_P0")
	)
	(segment
		(start 46.199044 -420.513764)
		(end 46.414944 -420.513764)
		(width 0.10668)
		(layer "F.Cu")
		(net "JTAG_TDI_RT_CPU1_P0")
	)
	(segment
		(start 67.353942 -389.63092)
		(end 67.496182 -389.77316)
		(width 0.10668)
		(layer "F.Cu")
		(net "JTAG_TDI_RT_CPU1_P0")
	)
	(via
		(at 46.729396 -420.828216)
		(size 0.508)
		(drill 0.254)
		(layers "F.Cu" "B.Cu")
		(net "JTAG_TDI_RT_CPU1_P0")
	)
	(via
		(at 67.849242 -389.77316)
		(size 0.4064)
		(drill 0.2032)
		(layers "F.Cu" "B.Cu")
		(net "JTAG_TDI_RT_CPU1_P0")
	)
	(via
		(at 45.999146 -420.828216)
		(size 0.6604)
		(drill 0.3302)
		(layers "F.Cu" "B.Cu")
		(net "JTAG_TDI_RT_CPU1_P0")
	)
	(segment
		(start 46.729396 -420.828216)
		(end 45.999146 -420.828216)
		(width 0.10668)
		(layer "B.Cu")
		(net "JTAG_TDI_RT_CPU1_P0")
	)
	(segment
		(start 46.729396 -420.828216)
		(end 45.964348 -420.063168)
		(width 0.11684)
		(layer "In13.Cu")
		(net "JTAG_TDI_RT_CPU1_P0")
	)
	(segment
		(start 68.00469 -389.77316)
		(end 67.849242 -389.77316)
		(width 0.11684)
		(layer "In13.Cu")
		(net "JTAG_TDI_RT_CPU1_P0")
	)
	(segment
		(start 67.392042 -392.262106)
		(end 68.269358 -391.38479)
		(width 0.11684)
		(layer "In13.Cu")
		(net "JTAG_TDI_RT_CPU1_P0")
	)
	(segment
		(start 45.71238 -417.292028)
		(end 45.71238 -407.676604)
		(width 0.11684)
		(layer "In13.Cu")
		(net "JTAG_TDI_RT_CPU1_P0")
	)
	(segment
		(start 46.34992 -403.560788)
		(end 47.409862 -401.001738)
		(width 0.11684)
		(layer "In13.Cu")
		(net "JTAG_TDI_RT_CPU1_P0")
	)
	(segment
		(start 46.34992 -406.137364)
		(end 46.34992 -403.560788)
		(width 0.11684)
		(layer "In13.Cu")
		(net "JTAG_TDI_RT_CPU1_P0")
	)
	(segment
		(start 68.269358 -390.037828)
		(end 68.00469 -389.77316)
		(width 0.11684)
		(layer "In13.Cu")
		(net "JTAG_TDI_RT_CPU1_P0")
	)
	(segment
		(start 47.409862 -401.001738)
		(end 53.39334 -395.01826)
		(width 0.11684)
		(layer "In13.Cu")
		(net "JTAG_TDI_RT_CPU1_P0")
	)
	(segment
		(start 53.39334 -395.01826)
		(end 66.611754 -395.01826)
		(width 0.11684)
		(layer "In13.Cu")
		(net "JTAG_TDI_RT_CPU1_P0")
	)
	(segment
		(start 45.964348 -420.063168)
		(end 45.964348 -417.543996)
		(width 0.11684)
		(layer "In13.Cu")
		(net "JTAG_TDI_RT_CPU1_P0")
	)
	(segment
		(start 66.611754 -395.01826)
		(end 67.392042 -394.237972)
		(width 0.11684)
		(layer "In13.Cu")
		(net "JTAG_TDI_RT_CPU1_P0")
	)
	(segment
		(start 45.964348 -417.543996)
		(end 45.71238 -417.292028)
		(width 0.11684)
		(layer "In13.Cu")
		(net "JTAG_TDI_RT_CPU1_P0")
	)
	(segment
		(start 67.392042 -394.237972)
		(end 67.392042 -392.262106)
		(width 0.11684)
		(layer "In13.Cu")
		(net "JTAG_TDI_RT_CPU1_P0")
	)
	(segment
		(start 45.71238 -407.676604)
		(end 46.34992 -406.137364)
		(width 0.11684)
		(layer "In13.Cu")
		(net "JTAG_TDI_RT_CPU1_P0")
	)
	(segment
		(start 68.269358 -391.38479)
		(end 68.269358 -390.037828)
		(width 0.11684)
		(layer "In13.Cu")
		(net "JTAG_TDI_RT_CPU1_P0")
	)
	(segment
		(start 425.3484 -422.266618)
		(end 425.52366 -422.441878)
		(width 0.10668)
		(layer "F.Cu")
		(net "JTAG_TDI_RT_CPU0_P3")
	)
	(segment
		(start 425.3484 -421.9067)
		(end 425.3484 -422.266618)
		(width 0.10668)
		(layer "F.Cu")
		(net "JTAG_TDI_RT_CPU0_P3")
	)
	(segment
		(start 390.59612 -398.15516)
		(end 390.94918 -398.15516)
		(width 0.10668)
		(layer "F.Cu")
		(net "JTAG_TDI_RT_CPU0_P3")
	)
	(segment
		(start 390.45388 -398.01292)
		(end 390.59612 -398.15516)
		(width 0.10668)
		(layer "F.Cu")
		(net "JTAG_TDI_RT_CPU0_P3")
	)
	(via
		(at 425.52366 -422.441878)
		(size 0.508)
		(drill 0.254)
		(layers "F.Cu" "B.Cu")
		(net "JTAG_TDI_RT_CPU0_P3")
	)
	(via
		(at 390.94918 -398.15516)
		(size 0.4064)
		(drill 0.2032)
		(layers "F.Cu" "B.Cu")
		(net "JTAG_TDI_RT_CPU0_P3")
	)
	(segment
		(start 401.480528 -398.006062)
		(end 401.480528 -398.471644)
		(width 0.11684)
		(layer "In6.Cu")
		(net "JTAG_TDI_RT_CPU0_P3")
	)
	(segment
		(start 402.710904 -399.70202)
		(end 403.62124 -399.70202)
		(width 0.11684)
		(layer "In6.Cu")
		(net "JTAG_TDI_RT_CPU0_P3")
	)
	(segment
		(start 392.912346 -398.15516)
		(end 393.137136 -397.93037)
		(width 0.11684)
		(layer "In6.Cu")
		(net "JTAG_TDI_RT_CPU0_P3")
	)
	(segment
		(start 421.495728 -410.774134)
		(end 421.495728 -420.898574)
		(width 0.11684)
		(layer "In6.Cu")
		(net "JTAG_TDI_RT_CPU0_P3")
	)
	(segment
		(start 390.94918 -398.15516)
		(end 392.912346 -398.15516)
		(width 0.11684)
		(layer "In6.Cu")
		(net "JTAG_TDI_RT_CPU0_P3")
	)
	(segment
		(start 404.05812 -402.410422)
		(end 404.36292 -402.715222)
		(width 0.11684)
		(layer "In6.Cu")
		(net "JTAG_TDI_RT_CPU0_P3")
	)
	(segment
		(start 421.495728 -420.898574)
		(end 422.552876 -421.955722)
		(width 0.11684)
		(layer "In6.Cu")
		(net "JTAG_TDI_RT_CPU0_P3")
	)
	(segment
		(start 419.85311 -409.131516)
		(end 421.495728 -410.774134)
		(width 0.11684)
		(layer "In6.Cu")
		(net "JTAG_TDI_RT_CPU0_P3")
	)
	(segment
		(start 399.571464 -397.93037)
		(end 399.942304 -397.55953)
		(width 0.11684)
		(layer "In6.Cu")
		(net "JTAG_TDI_RT_CPU0_P3")
	)
	(segment
		(start 403.62124 -399.70202)
		(end 404.05812 -400.1389)
		(width 0.11684)
		(layer "In6.Cu")
		(net "JTAG_TDI_RT_CPU0_P3")
	)
	(segment
		(start 422.552876 -421.955722)
		(end 425.037504 -421.955722)
		(width 0.11684)
		(layer "In6.Cu")
		(net "JTAG_TDI_RT_CPU0_P3")
	)
	(segment
		(start 401.480528 -398.471644)
		(end 402.710904 -399.70202)
		(width 0.11684)
		(layer "In6.Cu")
		(net "JTAG_TDI_RT_CPU0_P3")
	)
	(segment
		(start 425.037504 -421.955722)
		(end 425.52366 -422.441878)
		(width 0.11684)
		(layer "In6.Cu")
		(net "JTAG_TDI_RT_CPU0_P3")
	)
	(segment
		(start 393.137136 -397.93037)
		(end 399.571464 -397.93037)
		(width 0.11684)
		(layer "In6.Cu")
		(net "JTAG_TDI_RT_CPU0_P3")
	)
	(segment
		(start 404.36292 -402.715222)
		(end 419.85311 -409.131516)
		(width 0.11684)
		(layer "In6.Cu")
		(net "JTAG_TDI_RT_CPU0_P3")
	)
	(segment
		(start 401.033996 -397.55953)
		(end 401.480528 -398.006062)
		(width 0.11684)
		(layer "In6.Cu")
		(net "JTAG_TDI_RT_CPU0_P3")
	)
	(segment
		(start 399.942304 -397.55953)
		(end 401.033996 -397.55953)
		(width 0.11684)
		(layer "In6.Cu")
		(net "JTAG_TDI_RT_CPU0_P3")
	)
	(segment
		(start 404.05812 -400.1389)
		(end 404.05812 -402.410422)
		(width 0.11684)
		(layer "In6.Cu")
		(net "JTAG_TDI_RT_CPU0_P3")
	)
	(segment
		(start 432.943254 -407.4922)
		(end 434.299614 -408.84856)
		(width 0.10668)
		(layer "F.Cu")
		(net "JTAG_TDI_RT_CPU0_P2")
	)
	(segment
		(start 434.299614 -408.84856)
		(end 435.252622 -408.84856)
		(width 0.10668)
		(layer "F.Cu")
		(net "JTAG_TDI_RT_CPU0_P2")
	)
	(segment
		(start 422.981628 -398.01292)
		(end 422.981374 -398.01292)
		(width 0.10668)
		(layer "F.Cu")
		(net "JTAG_TDI_RT_CPU0_P2")
	)
	(segment
		(start 423.123614 -398.15516)
		(end 423.476674 -398.15516)
		(width 0.10668)
		(layer "F.Cu")
		(net "JTAG_TDI_RT_CPU0_P2")
	)
	(segment
		(start 432.5747 -407.4922)
		(end 432.943254 -407.4922)
		(width 0.10668)
		(layer "F.Cu")
		(net "JTAG_TDI_RT_CPU0_P2")
	)
	(segment
		(start 422.981374 -398.01292)
		(end 423.123614 -398.15516)
		(width 0.10668)
		(layer "F.Cu")
		(net "JTAG_TDI_RT_CPU0_P2")
	)
	(via
		(at 435.252622 -408.84856)
		(size 0.508)
		(drill 0.254)
		(layers "F.Cu" "B.Cu")
		(net "JTAG_TDI_RT_CPU0_P2")
	)
	(via
		(at 423.476674 -398.15516)
		(size 0.4064)
		(drill 0.2032)
		(layers "F.Cu" "B.Cu")
		(net "JTAG_TDI_RT_CPU0_P2")
	)
	(segment
		(start 424.969178 -402.317458)
		(end 425.71924 -403.06752)
		(width 0.10668)
		(layer "B.Cu")
		(net "JTAG_TDI_RT_CPU0_P2")
	)
	(segment
		(start 427.45152 -403.06752)
		(end 433.23256 -408.84856)
		(width 0.10668)
		(layer "B.Cu")
		(net "JTAG_TDI_RT_CPU0_P2")
	)
	(segment
		(start 423.589958 -398.15516)
		(end 423.970958 -398.53616)
		(width 0.10668)
		(layer "B.Cu")
		(net "JTAG_TDI_RT_CPU0_P2")
	)
	(segment
		(start 425.71924 -403.06752)
		(end 427.45152 -403.06752)
		(width 0.10668)
		(layer "B.Cu")
		(net "JTAG_TDI_RT_CPU0_P2")
	)
	(segment
		(start 425.67098 -399.283174)
		(end 425.67098 -400.872198)
		(width 0.10668)
		(layer "B.Cu")
		(net "JTAG_TDI_RT_CPU0_P2")
	)
	(segment
		(start 433.23256 -408.84856)
		(end 435.252622 -408.84856)
		(width 0.10668)
		(layer "B.Cu")
		(net "JTAG_TDI_RT_CPU0_P2")
	)
	(segment
		(start 423.476674 -398.15516)
		(end 423.589958 -398.15516)
		(width 0.10668)
		(layer "B.Cu")
		(net "JTAG_TDI_RT_CPU0_P2")
	)
	(segment
		(start 423.970958 -398.53616)
		(end 424.923966 -398.53616)
		(width 0.10668)
		(layer "B.Cu")
		(net "JTAG_TDI_RT_CPU0_P2")
	)
	(segment
		(start 425.67098 -400.872198)
		(end 424.969178 -401.574)
		(width 0.10668)
		(layer "B.Cu")
		(net "JTAG_TDI_RT_CPU0_P2")
	)
	(segment
		(start 424.923966 -398.53616)
		(end 425.67098 -399.283174)
		(width 0.10668)
		(layer "B.Cu")
		(net "JTAG_TDI_RT_CPU0_P2")
	)
	(segment
		(start 424.969178 -401.574)
		(end 424.969178 -402.317458)
		(width 0.10668)
		(layer "B.Cu")
		(net "JTAG_TDI_RT_CPU0_P2")
	)
	(segment
		(start 351.4852 -408.1399)
		(end 352.714814 -409.369514)
		(width 0.10668)
		(layer "F.Cu")
		(net "JTAG_TDI_RT_CPU0_P1")
	)
	(segment
		(start 352.714814 -409.369514)
		(end 355.493066 -409.369514)
		(width 0.10668)
		(layer "F.Cu")
		(net "JTAG_TDI_RT_CPU0_P1")
	)
	(segment
		(start 355.881432 -398.01292)
		(end 356.023672 -398.15516)
		(width 0.10668)
		(layer "F.Cu")
		(net "JTAG_TDI_RT_CPU0_P1")
	)
	(segment
		(start 355.493066 -409.369514)
		(end 359.844086 -405.018494)
		(width 0.10668)
		(layer "F.Cu")
		(net "JTAG_TDI_RT_CPU0_P1")
	)
	(segment
		(start 359.844086 -405.018494)
		(end 359.844086 -404.576026)
		(width 0.10668)
		(layer "F.Cu")
		(net "JTAG_TDI_RT_CPU0_P1")
	)
	(segment
		(start 356.023672 -398.15516)
		(end 356.376732 -398.15516)
		(width 0.10668)
		(layer "F.Cu")
		(net "JTAG_TDI_RT_CPU0_P1")
	)
	(via
		(at 356.376732 -398.15516)
		(size 0.4064)
		(drill 0.2032)
		(layers "F.Cu" "B.Cu")
		(net "JTAG_TDI_RT_CPU0_P1")
	)
	(via
		(at 359.844086 -404.576026)
		(size 0.508)
		(drill 0.254)
		(layers "F.Cu" "B.Cu")
		(net "JTAG_TDI_RT_CPU0_P1")
	)
	(segment
		(start 359.844086 -404.576026)
		(end 359.66527 -404.576026)
		(width 0.11684)
		(layer "In15.Cu")
		(net "JTAG_TDI_RT_CPU0_P1")
	)
	(segment
		(start 355.78796 -398.7546)
		(end 356.376732 -398.165828)
		(width 0.11684)
		(layer "In15.Cu")
		(net "JTAG_TDI_RT_CPU0_P1")
	)
	(segment
		(start 359.66527 -404.576026)
		(end 357.427784 -402.33854)
		(width 0.11684)
		(layer "In15.Cu")
		(net "JTAG_TDI_RT_CPU0_P1")
	)
	(segment
		(start 355.78796 -401.55876)
		(end 355.78796 -398.7546)
		(width 0.11684)
		(layer "In15.Cu")
		(net "JTAG_TDI_RT_CPU0_P1")
	)
	(segment
		(start 356.376732 -398.165828)
		(end 356.376732 -398.15516)
		(width 0.11684)
		(layer "In15.Cu")
		(net "JTAG_TDI_RT_CPU0_P1")
	)
	(segment
		(start 357.427784 -402.33854)
		(end 356.56774 -402.33854)
		(width 0.11684)
		(layer "In15.Cu")
		(net "JTAG_TDI_RT_CPU0_P1")
	)
	(segment
		(start 356.56774 -402.33854)
		(end 355.78796 -401.55876)
		(width 0.11684)
		(layer "In15.Cu")
		(net "JTAG_TDI_RT_CPU0_P1")
	)
	(segment
		(start 323.495924 -398.15516)
		(end 323.848984 -398.15516)
		(width 0.10668)
		(layer "F.Cu")
		(net "JTAG_TDI_RT_CPU0_P0")
	)
	(segment
		(start 323.353684 -398.01292)
		(end 323.495924 -398.15516)
		(width 0.10668)
		(layer "F.Cu")
		(net "JTAG_TDI_RT_CPU0_P0")
	)
	(via
		(at 306.223416 -427.2788)
		(size 0.508)
		(drill 0.254)
		(layers "F.Cu" "B.Cu")
		(net "JTAG_TDI_RT_CPU0_P0")
	)
	(via
		(at 307.62829 -426.934884)
		(size 0.6604)
		(drill 0.3302)
		(layers "F.Cu" "B.Cu")
		(net "JTAG_TDI_RT_CPU0_P0")
	)
	(via
		(at 323.848984 -398.15516)
		(size 0.4064)
		(drill 0.2032)
		(layers "F.Cu" "B.Cu")
		(net "JTAG_TDI_RT_CPU0_P0")
	)
	(segment
		(start 306.223416 -427.2788)
		(end 306.255928 -427.311312)
		(width 0.10668)
		(layer "B.Cu")
		(net "JTAG_TDI_RT_CPU0_P0")
	)
	(segment
		(start 306.255928 -427.311312)
		(end 307.251862 -427.311312)
		(width 0.10668)
		(layer "B.Cu")
		(net "JTAG_TDI_RT_CPU0_P0")
	)
	(segment
		(start 305.690016 -427.2788)
		(end 306.223416 -427.2788)
		(width 0.10668)
		(layer "B.Cu")
		(net "JTAG_TDI_RT_CPU0_P0")
	)
	(segment
		(start 307.251862 -427.311312)
		(end 307.62829 -426.934884)
		(width 0.10668)
		(layer "B.Cu")
		(net "JTAG_TDI_RT_CPU0_P0")
	)
	(segment
		(start 301.25162 -397.94434)
		(end 302.583342 -399.276062)
		(width 0.11684)
		(layer "In13.Cu")
		(net "JTAG_TDI_RT_CPU0_P0")
	)
	(segment
		(start 301.753524 -424.800522)
		(end 301.753524 -423.790364)
		(width 0.11684)
		(layer "In13.Cu")
		(net "JTAG_TDI_RT_CPU0_P0")
	)
	(segment
		(start 292.27272 -408.32024)
		(end 295.13276 -405.4602)
		(width 0.11684)
		(layer "In13.Cu")
		(net "JTAG_TDI_RT_CPU0_P0")
	)
	(segment
		(start 301.753524 -423.790364)
		(end 297.972988 -420.009828)
		(width 0.11684)
		(layer "In13.Cu")
		(net "JTAG_TDI_RT_CPU0_P0")
	)
	(segment
		(start 297.972988 -420.009828)
		(end 297.058842 -420.009828)
		(width 0.11684)
		(layer "In13.Cu")
		(net "JTAG_TDI_RT_CPU0_P0")
	)
	(segment
		(start 297.058842 -420.009828)
		(end 292.27272 -415.223706)
		(width 0.11684)
		(layer "In13.Cu")
		(net "JTAG_TDI_RT_CPU0_P0")
	)
	(segment
		(start 295.13276 -400.16684)
		(end 297.35526 -397.94434)
		(width 0.11684)
		(layer "In13.Cu")
		(net "JTAG_TDI_RT_CPU0_P0")
	)
	(segment
		(start 302.583342 -399.276062)
		(end 323.005958 -399.276062)
		(width 0.11684)
		(layer "In13.Cu")
		(net "JTAG_TDI_RT_CPU0_P0")
	)
	(segment
		(start 323.901308 -398.15516)
		(end 323.848984 -398.15516)
		(width 0.11684)
		(layer "In13.Cu")
		(net "JTAG_TDI_RT_CPU0_P0")
	)
	(segment
		(start 306.223416 -427.2788)
		(end 305.363118 -426.418502)
		(width 0.11684)
		(layer "In13.Cu")
		(net "JTAG_TDI_RT_CPU0_P0")
	)
	(segment
		(start 323.345048 -399.615152)
		(end 323.872098 -399.615152)
		(width 0.11684)
		(layer "In13.Cu")
		(net "JTAG_TDI_RT_CPU0_P0")
	)
	(segment
		(start 302.572166 -425.044616)
		(end 301.997618 -425.044616)
		(width 0.11684)
		(layer "In13.Cu")
		(net "JTAG_TDI_RT_CPU0_P0")
	)
	(segment
		(start 324.263004 -398.516856)
		(end 323.901308 -398.15516)
		(width 0.11684)
		(layer "In13.Cu")
		(net "JTAG_TDI_RT_CPU0_P0")
	)
	(segment
		(start 292.27272 -415.223706)
		(end 292.27272 -408.32024)
		(width 0.11684)
		(layer "In13.Cu")
		(net "JTAG_TDI_RT_CPU0_P0")
	)
	(segment
		(start 301.997618 -425.044616)
		(end 301.753524 -424.800522)
		(width 0.11684)
		(layer "In13.Cu")
		(net "JTAG_TDI_RT_CPU0_P0")
	)
	(segment
		(start 303.946052 -426.418502)
		(end 302.572166 -425.044616)
		(width 0.11684)
		(layer "In13.Cu")
		(net "JTAG_TDI_RT_CPU0_P0")
	)
	(segment
		(start 305.363118 -426.418502)
		(end 303.946052 -426.418502)
		(width 0.11684)
		(layer "In13.Cu")
		(net "JTAG_TDI_RT_CPU0_P0")
	)
	(segment
		(start 295.13276 -405.4602)
		(end 295.13276 -400.16684)
		(width 0.11684)
		(layer "In13.Cu")
		(net "JTAG_TDI_RT_CPU0_P0")
	)
	(segment
		(start 323.005958 -399.276062)
		(end 323.345048 -399.615152)
		(width 0.11684)
		(layer "In13.Cu")
		(net "JTAG_TDI_RT_CPU0_P0")
	)
	(segment
		(start 324.263004 -399.224246)
		(end 324.263004 -398.516856)
		(width 0.11684)
		(layer "In13.Cu")
		(net "JTAG_TDI_RT_CPU0_P0")
	)
	(segment
		(start 323.872098 -399.615152)
		(end 324.263004 -399.224246)
		(width 0.11684)
		(layer "In13.Cu")
		(net "JTAG_TDI_RT_CPU0_P0")
	)
	(segment
		(start 297.35526 -397.94434)
		(end 301.25162 -397.94434)
		(width 0.11684)
		(layer "In13.Cu")
		(net "JTAG_TDI_RT_CPU0_P0")
	)
	(segment
		(start 135.025384 -390.30656)
		(end 134.949946 -390.231122)
		(width 0.10668)
		(layer "F.Cu")
		(net "JTAG_TCK_RT_CPU1_P3")
	)
	(segment
		(start 134.949946 -390.231122)
		(end 134.453884 -390.231122)
		(width 0.10668)
		(layer "F.Cu")
		(net "JTAG_TCK_RT_CPU1_P3")
	)
	(segment
		(start 135.20674 -390.30656)
		(end 135.025384 -390.30656)
		(width 0.10668)
		(layer "F.Cu")
		(net "JTAG_TCK_RT_CPU1_P3")
	)
	(via
		(at 164.465 -425.40047)
		(size 0.508)
		(drill 0.254)
		(layers "F.Cu" "B.Cu")
		(net "JTAG_TCK_RT_CPU1_P3")
	)
	(via
		(at 135.20674 -390.30656)
		(size 0.4064)
		(drill 0.2032)
		(layers "F.Cu" "B.Cu")
		(net "JTAG_TCK_RT_CPU1_P3")
	)
	(via
		(at 163.87572 -405.8412)
		(size 0.508)
		(drill 0.254)
		(layers "F.Cu" "B.Cu")
		(net "JTAG_TCK_RT_CPU1_P3")
	)
	(via
		(at 165.22827 -427.222412)
		(size 0.6604)
		(drill 0.3302)
		(layers "F.Cu" "B.Cu")
		(net "JTAG_TCK_RT_CPU1_P3")
	)
	(segment
		(start 164.543994 -426.1485)
		(end 165.22827 -426.832776)
		(width 0.10668)
		(layer "B.Cu")
		(net "JTAG_TCK_RT_CPU1_P3")
	)
	(segment
		(start 164.465 -426.1485)
		(end 164.465 -425.40047)
		(width 0.10668)
		(layer "B.Cu")
		(net "JTAG_TCK_RT_CPU1_P3")
	)
	(segment
		(start 164.465 -426.1485)
		(end 164.543994 -426.1485)
		(width 0.10668)
		(layer "B.Cu")
		(net "JTAG_TCK_RT_CPU1_P3")
	)
	(segment
		(start 164.338 -424.86707)
		(end 164.338 -425.27347)
		(width 0.10668)
		(layer "B.Cu")
		(net "JTAG_TCK_RT_CPU1_P3")
	)
	(segment
		(start 165.22827 -426.832776)
		(end 165.22827 -427.222412)
		(width 0.10668)
		(layer "B.Cu")
		(net "JTAG_TCK_RT_CPU1_P3")
	)
	(segment
		(start 164.338 -425.27347)
		(end 164.465 -425.40047)
		(width 0.10668)
		(layer "B.Cu")
		(net "JTAG_TCK_RT_CPU1_P3")
	)
	(segment
		(start 162.3441 -403.64918)
		(end 161.374836 -402.679916)
		(width 0.11684)
		(layer "In11.Cu")
		(net "JTAG_TCK_RT_CPU1_P3")
	)
	(segment
		(start 143.503904 -402.679916)
		(end 135.619744 -394.795756)
		(width 0.11684)
		(layer "In11.Cu")
		(net "JTAG_TCK_RT_CPU1_P3")
	)
	(segment
		(start 135.619744 -394.795756)
		(end 135.619744 -390.825736)
		(width 0.11684)
		(layer "In11.Cu")
		(net "JTAG_TCK_RT_CPU1_P3")
	)
	(segment
		(start 163.87572 -405.8412)
		(end 162.92068 -404.88616)
		(width 0.11684)
		(layer "In11.Cu")
		(net "JTAG_TCK_RT_CPU1_P3")
	)
	(segment
		(start 162.346132 -403.64918)
		(end 162.3441 -403.64918)
		(width 0.11684)
		(layer "In11.Cu")
		(net "JTAG_TCK_RT_CPU1_P3")
	)
	(segment
		(start 162.92068 -404.88616)
		(end 162.92068 -404.223728)
		(width 0.11684)
		(layer "In11.Cu")
		(net "JTAG_TCK_RT_CPU1_P3")
	)
	(segment
		(start 161.374836 -402.679916)
		(end 143.503904 -402.679916)
		(width 0.11684)
		(layer "In11.Cu")
		(net "JTAG_TCK_RT_CPU1_P3")
	)
	(segment
		(start 135.20674 -390.412732)
		(end 135.20674 -390.30656)
		(width 0.11684)
		(layer "In11.Cu")
		(net "JTAG_TCK_RT_CPU1_P3")
	)
	(segment
		(start 135.619744 -390.825736)
		(end 135.20674 -390.412732)
		(width 0.11684)
		(layer "In11.Cu")
		(net "JTAG_TCK_RT_CPU1_P3")
	)
	(segment
		(start 162.92068 -404.223728)
		(end 162.346132 -403.64918)
		(width 0.11684)
		(layer "In11.Cu")
		(net "JTAG_TCK_RT_CPU1_P3")
	)
	(segment
		(start 161.57956 -423.99966)
		(end 162.43808 -424.85818)
		(width 0.11684)
		(layer "In13.Cu")
		(net "JTAG_TCK_RT_CPU1_P3")
	)
	(segment
		(start 165.04412 -417.6395)
		(end 163.82746 -418.85616)
		(width 0.11684)
		(layer "In13.Cu")
		(net "JTAG_TCK_RT_CPU1_P3")
	)
	(segment
		(start 164.21354 -406.17902)
		(end 164.21354 -415.801048)
		(width 0.11684)
		(layer "In13.Cu")
		(net "JTAG_TCK_RT_CPU1_P3")
	)
	(segment
		(start 164.21354 -415.801048)
		(end 165.04412 -416.631628)
		(width 0.11684)
		(layer "In13.Cu")
		(net "JTAG_TCK_RT_CPU1_P3")
	)
	(segment
		(start 163.92271 -424.85818)
		(end 164.465 -425.40047)
		(width 0.11684)
		(layer "In13.Cu")
		(net "JTAG_TCK_RT_CPU1_P3")
	)
	(segment
		(start 161.57956 -422.53662)
		(end 161.57956 -423.99966)
		(width 0.11684)
		(layer "In13.Cu")
		(net "JTAG_TCK_RT_CPU1_P3")
	)
	(segment
		(start 163.82746 -420.28872)
		(end 161.57956 -422.53662)
		(width 0.11684)
		(layer "In13.Cu")
		(net "JTAG_TCK_RT_CPU1_P3")
	)
	(segment
		(start 162.43808 -424.85818)
		(end 163.92271 -424.85818)
		(width 0.11684)
		(layer "In13.Cu")
		(net "JTAG_TCK_RT_CPU1_P3")
	)
	(segment
		(start 165.04412 -416.631628)
		(end 165.04412 -417.6395)
		(width 0.11684)
		(layer "In13.Cu")
		(net "JTAG_TCK_RT_CPU1_P3")
	)
	(segment
		(start 163.82746 -418.85616)
		(end 163.82746 -420.28872)
		(width 0.11684)
		(layer "In13.Cu")
		(net "JTAG_TCK_RT_CPU1_P3")
	)
	(segment
		(start 163.87572 -405.8412)
		(end 164.21354 -406.17902)
		(width 0.11684)
		(layer "In13.Cu")
		(net "JTAG_TCK_RT_CPU1_P3")
	)
	(segment
		(start 179.929536 -394.1318)
		(end 179.553362 -393.755626)
		(width 0.10668)
		(layer "F.Cu")
		(net "JTAG_TCK_RT_CPU1_P2")
	)
	(segment
		(start 178.07686 -394.1318)
		(end 178.63566 -394.1318)
		(width 0.10668)
		(layer "F.Cu")
		(net "JTAG_TCK_RT_CPU1_P2")
	)
	(segment
		(start 167.401494 -390.231122)
		(end 167.476932 -390.30656)
		(width 0.10668)
		(layer "F.Cu")
		(net "JTAG_TCK_RT_CPU1_P2")
	)
	(segment
		(start 179.553362 -393.755626)
		(end 179.011834 -393.755626)
		(width 0.10668)
		(layer "F.Cu")
		(net "JTAG_TCK_RT_CPU1_P2")
	)
	(segment
		(start 179.011834 -393.755626)
		(end 178.63566 -394.1318)
		(width 0.10668)
		(layer "F.Cu")
		(net "JTAG_TCK_RT_CPU1_P2")
	)
	(segment
		(start 166.981632 -390.231122)
		(end 167.401494 -390.231122)
		(width 0.10668)
		(layer "F.Cu")
		(net "JTAG_TCK_RT_CPU1_P2")
	)
	(segment
		(start 180.1241 -394.1318)
		(end 179.929536 -394.1318)
		(width 0.10668)
		(layer "F.Cu")
		(net "JTAG_TCK_RT_CPU1_P2")
	)
	(via
		(at 178.63566 -394.1318)
		(size 0.508)
		(drill 0.254)
		(layers "F.Cu" "B.Cu")
		(net "JTAG_TCK_RT_CPU1_P2")
	)
	(via
		(at 167.476932 -390.30656)
		(size 0.4064)
		(drill 0.2032)
		(layers "F.Cu" "B.Cu")
		(net "JTAG_TCK_RT_CPU1_P2")
	)
	(segment
		(start 171.424854 -393.83716)
		(end 172.407326 -392.854688)
		(width 0.10668)
		(layer "B.Cu")
		(net "JTAG_TCK_RT_CPU1_P2")
	)
	(segment
		(start 167.551608 -390.381236)
		(end 168.726358 -390.381236)
		(width 0.10668)
		(layer "B.Cu")
		(net "JTAG_TCK_RT_CPU1_P2")
	)
	(segment
		(start 170.22318 -393.83716)
		(end 171.424854 -393.83716)
		(width 0.10668)
		(layer "B.Cu")
		(net "JTAG_TCK_RT_CPU1_P2")
	)
	(segment
		(start 168.726358 -390.381236)
		(end 169.198798 -390.853676)
		(width 0.10668)
		(layer "B.Cu")
		(net "JTAG_TCK_RT_CPU1_P2")
	)
	(segment
		(start 169.198798 -390.853676)
		(end 169.198798 -392.812778)
		(width 0.10668)
		(layer "B.Cu")
		(net "JTAG_TCK_RT_CPU1_P2")
	)
	(segment
		(start 169.198798 -392.812778)
		(end 170.22318 -393.83716)
		(width 0.10668)
		(layer "B.Cu")
		(net "JTAG_TCK_RT_CPU1_P2")
	)
	(segment
		(start 177.358548 -392.854688)
		(end 178.63566 -394.1318)
		(width 0.10668)
		(layer "B.Cu")
		(net "JTAG_TCK_RT_CPU1_P2")
	)
	(segment
		(start 172.407326 -392.854688)
		(end 177.358548 -392.854688)
		(width 0.10668)
		(layer "B.Cu")
		(net "JTAG_TCK_RT_CPU1_P2")
	)
	(segment
		(start 167.476932 -390.30656)
		(end 167.551608 -390.381236)
		(width 0.10668)
		(layer "B.Cu")
		(net "JTAG_TCK_RT_CPU1_P2")
	)
	(segment
		(start 94.7293 -416.4076)
		(end 95.2627 -416.4076)
		(width 0.10668)
		(layer "F.Cu")
		(net "JTAG_TCK_RT_CPU1_P1")
	)
	(segment
		(start 95.2627 -416.4076)
		(end 95.7961 -416.4076)
		(width 0.10668)
		(layer "F.Cu")
		(net "JTAG_TCK_RT_CPU1_P1")
	)
	(segment
		(start 100.301552 -390.231122)
		(end 100.37699 -390.30656)
		(width 0.10668)
		(layer "F.Cu")
		(net "JTAG_TCK_RT_CPU1_P1")
	)
	(segment
		(start 99.88169 -390.231122)
		(end 100.301552 -390.231122)
		(width 0.10668)
		(layer "F.Cu")
		(net "JTAG_TCK_RT_CPU1_P1")
	)
	(via
		(at 95.2627 -416.4076)
		(size 0.508)
		(drill 0.254)
		(layers "F.Cu" "B.Cu")
		(net "JTAG_TCK_RT_CPU1_P1")
	)
	(via
		(at 100.37699 -390.30656)
		(size 0.4064)
		(drill 0.2032)
		(layers "F.Cu" "B.Cu")
		(net "JTAG_TCK_RT_CPU1_P1")
	)
	(segment
		(start 95.2627 -416.4076)
		(end 95.59798 -416.07232)
		(width 0.11684)
		(layer "In11.Cu")
		(net "JTAG_TCK_RT_CPU1_P1")
	)
	(segment
		(start 98.914966 -399.36166)
		(end 99.56292 -398.713706)
		(width 0.11684)
		(layer "In11.Cu")
		(net "JTAG_TCK_RT_CPU1_P1")
	)
	(segment
		(start 99.56292 -398.713706)
		(end 99.56292 -392.14298)
		(width 0.11684)
		(layer "In11.Cu")
		(net "JTAG_TCK_RT_CPU1_P1")
	)
	(segment
		(start 100.655882 -390.585452)
		(end 100.37699 -390.30656)
		(width 0.11684)
		(layer "In11.Cu")
		(net "JTAG_TCK_RT_CPU1_P1")
	)
	(segment
		(start 99.56292 -392.14298)
		(end 100.655882 -391.050018)
		(width 0.11684)
		(layer "In11.Cu")
		(net "JTAG_TCK_RT_CPU1_P1")
	)
	(segment
		(start 98.346768 -400.732498)
		(end 98.914966 -399.36166)
		(width 0.11684)
		(layer "In11.Cu")
		(net "JTAG_TCK_RT_CPU1_P1")
	)
	(segment
		(start 97.130108 -410.831792)
		(end 97.130108 -405.662384)
		(width 0.11684)
		(layer "In11.Cu")
		(net "JTAG_TCK_RT_CPU1_P1")
	)
	(segment
		(start 97.130108 -405.662384)
		(end 97.58426 -404.56612)
		(width 0.11684)
		(layer "In11.Cu")
		(net "JTAG_TCK_RT_CPU1_P1")
	)
	(segment
		(start 97.58426 -404.56612)
		(end 98.346768 -400.732498)
		(width 0.11684)
		(layer "In11.Cu")
		(net "JTAG_TCK_RT_CPU1_P1")
	)
	(segment
		(start 95.59798 -412.36392)
		(end 97.130108 -410.831792)
		(width 0.11684)
		(layer "In11.Cu")
		(net "JTAG_TCK_RT_CPU1_P1")
	)
	(segment
		(start 95.59798 -416.07232)
		(end 95.59798 -412.36392)
		(width 0.11684)
		(layer "In11.Cu")
		(net "JTAG_TCK_RT_CPU1_P1")
	)
	(segment
		(start 100.655882 -391.050018)
		(end 100.655882 -390.585452)
		(width 0.11684)
		(layer "In11.Cu")
		(net "JTAG_TCK_RT_CPU1_P1")
	)
	(segment
		(start 46.732444 -421.525192)
		(end 47.143416 -421.525192)
		(width 0.10668)
		(layer "F.Cu")
		(net "JTAG_TCK_RT_CPU1_P0")
	)
	(segment
		(start 46.199044 -421.326564)
		(end 46.397672 -421.525192)
		(width 0.10668)
		(layer "F.Cu")
		(net "JTAG_TCK_RT_CPU1_P0")
	)
	(segment
		(start 47.143416 -421.525192)
		(end 47.342044 -421.326564)
		(width 0.10668)
		(layer "F.Cu")
		(net "JTAG_TCK_RT_CPU1_P0")
	)
	(segment
		(start 46.397672 -421.525192)
		(end 46.732444 -421.525192)
		(width 0.10668)
		(layer "F.Cu")
		(net "JTAG_TCK_RT_CPU1_P0")
	)
	(segment
		(start 67.773804 -390.231122)
		(end 67.849242 -390.30656)
		(width 0.10668)
		(layer "F.Cu")
		(net "JTAG_TCK_RT_CPU1_P0")
	)
	(segment
		(start 67.353942 -390.231122)
		(end 67.773804 -390.231122)
		(width 0.10668)
		(layer "F.Cu")
		(net "JTAG_TCK_RT_CPU1_P0")
	)
	(via
		(at 45.578522 -422.041574)
		(size 0.6604)
		(drill 0.3302)
		(layers "F.Cu" "B.Cu")
		(net "JTAG_TCK_RT_CPU1_P0")
	)
	(via
		(at 46.732444 -421.525192)
		(size 0.508)
		(drill 0.254)
		(layers "F.Cu" "B.Cu")
		(net "JTAG_TCK_RT_CPU1_P0")
	)
	(via
		(at 67.849242 -390.30656)
		(size 0.4064)
		(drill 0.2032)
		(layers "F.Cu" "B.Cu")
		(net "JTAG_TCK_RT_CPU1_P0")
	)
	(segment
		(start 46.094904 -421.525192)
		(end 45.578522 -422.041574)
		(width 0.10668)
		(layer "B.Cu")
		(net "JTAG_TCK_RT_CPU1_P0")
	)
	(segment
		(start 46.732444 -421.525192)
		(end 46.094904 -421.525192)
		(width 0.10668)
		(layer "B.Cu")
		(net "JTAG_TCK_RT_CPU1_P0")
	)
	(segment
		(start 45.644308 -420.437056)
		(end 46.732444 -421.525192)
		(width 0.11684)
		(layer "In13.Cu")
		(net "JTAG_TCK_RT_CPU1_P0")
	)
	(segment
		(start 45.91812 -403.348444)
		(end 45.91812 -405.946356)
		(width 0.11684)
		(layer "In13.Cu")
		(net "JTAG_TCK_RT_CPU1_P0")
	)
	(segment
		(start 47.040038 -400.640042)
		(end 45.91812 -403.348444)
		(width 0.11684)
		(layer "In13.Cu")
		(net "JTAG_TCK_RT_CPU1_P0")
	)
	(segment
		(start 67.849242 -390.30656)
		(end 67.625722 -390.30656)
		(width 0.11684)
		(layer "In13.Cu")
		(net "JTAG_TCK_RT_CPU1_P0")
	)
	(segment
		(start 67.625722 -390.30656)
		(end 67.056 -390.876282)
		(width 0.11684)
		(layer "In13.Cu")
		(net "JTAG_TCK_RT_CPU1_P0")
	)
	(segment
		(start 45.16882 -407.755598)
		(end 45.16882 -417.69538)
		(width 0.11684)
		(layer "In13.Cu")
		(net "JTAG_TCK_RT_CPU1_P0")
	)
	(segment
		(start 45.644308 -418.170868)
		(end 45.644308 -420.437056)
		(width 0.11684)
		(layer "In13.Cu")
		(net "JTAG_TCK_RT_CPU1_P0")
	)
	(segment
		(start 45.16882 -417.69538)
		(end 45.644308 -418.170868)
		(width 0.11684)
		(layer "In13.Cu")
		(net "JTAG_TCK_RT_CPU1_P0")
	)
	(segment
		(start 67.056 -390.876282)
		(end 67.056 -393.93749)
		(width 0.11684)
		(layer "In13.Cu")
		(net "JTAG_TCK_RT_CPU1_P0")
	)
	(segment
		(start 53.14188 -394.5382)
		(end 47.040038 -400.640042)
		(width 0.11684)
		(layer "In13.Cu")
		(net "JTAG_TCK_RT_CPU1_P0")
	)
	(segment
		(start 67.056 -393.93749)
		(end 66.45529 -394.5382)
		(width 0.11684)
		(layer "In13.Cu")
		(net "JTAG_TCK_RT_CPU1_P0")
	)
	(segment
		(start 45.91812 -405.946356)
		(end 45.16882 -407.755598)
		(width 0.11684)
		(layer "In13.Cu")
		(net "JTAG_TCK_RT_CPU1_P0")
	)
	(segment
		(start 66.45529 -394.5382)
		(end 53.14188 -394.5382)
		(width 0.11684)
		(layer "In13.Cu")
		(net "JTAG_TCK_RT_CPU1_P0")
	)
	(segment
		(start 390.873742 -398.613122)
		(end 390.94918 -398.68856)
		(width 0.10668)
		(layer "F.Cu")
		(net "JTAG_TCK_RT_CPU0_P3")
	)
	(segment
		(start 424.5356 -422.744392)
		(end 424.5356 -422.9735)
		(width 0.10668)
		(layer "F.Cu")
		(net "JTAG_TCK_RT_CPU0_P3")
	)
	(segment
		(start 424.5356 -422.135808)
		(end 424.231308 -422.4401)
		(width 0.10668)
		(layer "F.Cu")
		(net "JTAG_TCK_RT_CPU0_P3")
	)
	(segment
		(start 390.45388 -398.613122)
		(end 390.873742 -398.613122)
		(width 0.10668)
		(layer "F.Cu")
		(net "JTAG_TCK_RT_CPU0_P3")
	)
	(segment
		(start 424.5356 -421.9067)
		(end 424.5356 -422.135808)
		(width 0.10668)
		(layer "F.Cu")
		(net "JTAG_TCK_RT_CPU0_P3")
	)
	(segment
		(start 424.231308 -422.4401)
		(end 424.5356 -422.744392)
		(width 0.10668)
		(layer "F.Cu")
		(net "JTAG_TCK_RT_CPU0_P3")
	)
	(via
		(at 390.94918 -398.68856)
		(size 0.4064)
		(drill 0.2032)
		(layers "F.Cu" "B.Cu")
		(net "JTAG_TCK_RT_CPU0_P3")
	)
	(via
		(at 424.231308 -422.4401)
		(size 0.508)
		(drill 0.254)
		(layers "F.Cu" "B.Cu")
		(net "JTAG_TCK_RT_CPU0_P3")
	)
	(segment
		(start 402.587206 -400.03095)
		(end 402.587206 -402.439124)
		(width 0.11684)
		(layer "In6.Cu")
		(net "JTAG_TCK_RT_CPU0_P3")
	)
	(segment
		(start 390.94918 -398.68856)
		(end 392.831574 -398.68856)
		(width 0.11684)
		(layer "In6.Cu")
		(net "JTAG_TCK_RT_CPU0_P3")
	)
	(segment
		(start 400.074892 -397.87957)
		(end 400.901408 -397.87957)
		(width 0.11684)
		(layer "In6.Cu")
		(net "JTAG_TCK_RT_CPU0_P3")
	)
	(segment
		(start 421.09644 -411.030674)
		(end 421.09644 -421.177974)
		(width 0.11684)
		(layer "In6.Cu")
		(net "JTAG_TCK_RT_CPU0_P3")
	)
	(segment
		(start 393.269724 -398.25041)
		(end 399.704052 -398.25041)
		(width 0.11684)
		(layer "In6.Cu")
		(net "JTAG_TCK_RT_CPU0_P3")
	)
	(segment
		(start 392.831574 -398.68856)
		(end 393.269724 -398.25041)
		(width 0.11684)
		(layer "In6.Cu")
		(net "JTAG_TCK_RT_CPU0_P3")
	)
	(segment
		(start 400.901408 -397.87957)
		(end 401.160488 -398.13865)
		(width 0.11684)
		(layer "In6.Cu")
		(net "JTAG_TCK_RT_CPU0_P3")
	)
	(segment
		(start 421.09644 -421.177974)
		(end 422.358566 -422.4401)
		(width 0.11684)
		(layer "In6.Cu")
		(net "JTAG_TCK_RT_CPU0_P3")
	)
	(segment
		(start 422.358566 -422.4401)
		(end 424.231308 -422.4401)
		(width 0.11684)
		(layer "In6.Cu")
		(net "JTAG_TCK_RT_CPU0_P3")
	)
	(segment
		(start 403.183344 -403.035262)
		(end 403.911308 -403.035262)
		(width 0.11684)
		(layer "In6.Cu")
		(net "JTAG_TCK_RT_CPU0_P3")
	)
	(segment
		(start 402.587206 -402.439124)
		(end 403.183344 -403.035262)
		(width 0.11684)
		(layer "In6.Cu")
		(net "JTAG_TCK_RT_CPU0_P3")
	)
	(segment
		(start 401.160488 -398.13865)
		(end 401.160488 -398.604232)
		(width 0.11684)
		(layer "In6.Cu")
		(net "JTAG_TCK_RT_CPU0_P3")
	)
	(segment
		(start 401.160488 -398.604232)
		(end 402.587206 -400.03095)
		(width 0.11684)
		(layer "In6.Cu")
		(net "JTAG_TCK_RT_CPU0_P3")
	)
	(segment
		(start 403.911308 -403.035262)
		(end 419.598602 -409.532836)
		(width 0.11684)
		(layer "In6.Cu")
		(net "JTAG_TCK_RT_CPU0_P3")
	)
	(segment
		(start 399.704052 -398.25041)
		(end 400.074892 -397.87957)
		(width 0.11684)
		(layer "In6.Cu")
		(net "JTAG_TCK_RT_CPU0_P3")
	)
	(segment
		(start 419.598602 -409.532836)
		(end 421.09644 -411.030674)
		(width 0.11684)
		(layer "In6.Cu")
		(net "JTAG_TCK_RT_CPU0_P3")
	)
	(segment
		(start 435.786022 -409.68676)
		(end 434.297582 -409.68676)
		(width 0.10668)
		(layer "F.Cu")
		(net "JTAG_TCK_RT_CPU0_P2")
	)
	(segment
		(start 423.401236 -398.613122)
		(end 423.476674 -398.68856)
		(width 0.10668)
		(layer "F.Cu")
		(net "JTAG_TCK_RT_CPU0_P2")
	)
	(segment
		(start 422.981628 -398.613122)
		(end 423.401236 -398.613122)
		(width 0.10668)
		(layer "F.Cu")
		(net "JTAG_TCK_RT_CPU0_P2")
	)
	(segment
		(start 432.5747 -408.2796)
		(end 432.890422 -408.2796)
		(width 0.10668)
		(layer "F.Cu")
		(net "JTAG_TCK_RT_CPU0_P2")
	)
	(segment
		(start 432.890422 -408.2796)
		(end 434.297582 -409.68676)
		(width 0.10668)
		(layer "F.Cu")
		(net "JTAG_TCK_RT_CPU0_P2")
	)
	(via
		(at 423.476674 -398.68856)
		(size 0.4064)
		(drill 0.2032)
		(layers "F.Cu" "B.Cu")
		(net "JTAG_TCK_RT_CPU0_P2")
	)
	(via
		(at 434.297582 -409.68676)
		(size 0.508)
		(drill 0.254)
		(layers "F.Cu" "B.Cu")
		(net "JTAG_TCK_RT_CPU0_P2")
	)
	(segment
		(start 425.332398 -399.369534)
		(end 424.725084 -398.76222)
		(width 0.10668)
		(layer "B.Cu")
		(net "JTAG_TCK_RT_CPU0_P2")
	)
	(segment
		(start 424.70578 -402.55317)
		(end 424.70578 -401.424394)
		(width 0.10668)
		(layer "B.Cu")
		(net "JTAG_TCK_RT_CPU0_P2")
	)
	(segment
		(start 424.725084 -398.76222)
		(end 423.550334 -398.76222)
		(width 0.10668)
		(layer "B.Cu")
		(net "JTAG_TCK_RT_CPU0_P2")
	)
	(segment
		(start 423.550334 -398.76222)
		(end 423.476674 -398.68856)
		(width 0.10668)
		(layer "B.Cu")
		(net "JTAG_TCK_RT_CPU0_P2")
	)
	(segment
		(start 434.297582 -409.68676)
		(end 433.340256 -409.68676)
		(width 0.10668)
		(layer "B.Cu")
		(net "JTAG_TCK_RT_CPU0_P2")
	)
	(segment
		(start 425.67733 -403.52472)
		(end 424.70578 -402.55317)
		(width 0.10668)
		(layer "B.Cu")
		(net "JTAG_TCK_RT_CPU0_P2")
	)
	(segment
		(start 427.178216 -403.52472)
		(end 425.67733 -403.52472)
		(width 0.10668)
		(layer "B.Cu")
		(net "JTAG_TCK_RT_CPU0_P2")
	)
	(segment
		(start 425.332398 -400.797776)
		(end 425.332398 -399.369534)
		(width 0.10668)
		(layer "B.Cu")
		(net "JTAG_TCK_RT_CPU0_P2")
	)
	(segment
		(start 424.70578 -401.424394)
		(end 425.332398 -400.797776)
		(width 0.10668)
		(layer "B.Cu")
		(net "JTAG_TCK_RT_CPU0_P2")
	)
	(segment
		(start 433.340256 -409.68676)
		(end 427.178216 -403.52472)
		(width 0.10668)
		(layer "B.Cu")
		(net "JTAG_TCK_RT_CPU0_P2")
	)
	(segment
		(start 358.417876 -400.672046)
		(end 356.358952 -398.613122)
		(width 0.10668)
		(layer "F.Cu")
		(net "JTAG_TCK_RT_CPU0_P1")
	)
	(segment
		(start 359.400348 -401.615148)
		(end 358.21112 -402.804376)
		(width 0.10668)
		(layer "F.Cu")
		(net "JTAG_TCK_RT_CPU0_P1")
	)
	(segment
		(start 358.21112 -404.632668)
		(end 355.096572 -407.747216)
		(width 0.10668)
		(layer "F.Cu")
		(net "JTAG_TCK_RT_CPU0_P1")
	)
	(segment
		(start 358.21112 -402.804376)
		(end 358.21112 -404.632668)
		(width 0.10668)
		(layer "F.Cu")
		(net "JTAG_TCK_RT_CPU0_P1")
	)
	(segment
		(start 354.703888 -408.1399)
		(end 353.9236 -408.1399)
		(width 0.10668)
		(layer "F.Cu")
		(net "JTAG_TCK_RT_CPU0_P1")
	)
	(segment
		(start 355.096572 -407.747216)
		(end 354.703888 -408.1399)
		(width 0.10668)
		(layer "F.Cu")
		(net "JTAG_TCK_RT_CPU0_P1")
	)
	(segment
		(start 356.358952 -398.613122)
		(end 355.881432 -398.613122)
		(width 0.10668)
		(layer "F.Cu")
		(net "JTAG_TCK_RT_CPU0_P1")
	)
	(segment
		(start 359.9053 -401.4216)
		(end 359.711752 -401.615148)
		(width 0.10668)
		(layer "F.Cu")
		(net "JTAG_TCK_RT_CPU0_P1")
	)
	(segment
		(start 359.711752 -401.615148)
		(end 359.400348 -401.615148)
		(width 0.10668)
		(layer "F.Cu")
		(net "JTAG_TCK_RT_CPU0_P1")
	)
	(segment
		(start 359.9053 -401.4216)
		(end 359.155746 -400.672046)
		(width 0.10668)
		(layer "F.Cu")
		(net "JTAG_TCK_RT_CPU0_P1")
	)
	(segment
		(start 359.155746 -400.672046)
		(end 358.417876 -400.672046)
		(width 0.10668)
		(layer "F.Cu")
		(net "JTAG_TCK_RT_CPU0_P1")
	)
	(via
		(at 355.096572 -407.747216)
		(size 0.762)
		(drill 0.381)
		(layers "F.Cu" "B.Cu")
		(net "JTAG_TCK_RT_CPU0_P1")
	)
	(segment
		(start 323.353684 -398.613122)
		(end 323.773546 -398.613122)
		(width 0.10668)
		(layer "F.Cu")
		(net "JTAG_TCK_RT_CPU0_P0")
	)
	(segment
		(start 323.773546 -398.613122)
		(end 323.848984 -398.68856)
		(width 0.10668)
		(layer "F.Cu")
		(net "JTAG_TCK_RT_CPU0_P0")
	)
	(via
		(at 306.7685 -428.882556)
		(size 0.6604)
		(drill 0.3302)
		(layers "F.Cu" "B.Cu")
		(net "JTAG_TCK_RT_CPU0_P0")
	)
	(via
		(at 323.848984 -398.68856)
		(size 0.4064)
		(drill 0.2032)
		(layers "F.Cu" "B.Cu")
		(net "JTAG_TCK_RT_CPU0_P0")
	)
	(via
		(at 306.223416 -428.0916)
		(size 0.508)
		(drill 0.254)
		(layers "F.Cu" "B.Cu")
		(net "JTAG_TCK_RT_CPU0_P0")
	)
	(segment
		(start 305.690016 -428.0916)
		(end 306.223416 -428.0916)
		(width 0.10668)
		(layer "B.Cu")
		(net "JTAG_TCK_RT_CPU0_P0")
	)
	(segment
		(start 306.7685 -428.0916)
		(end 306.223416 -428.0916)
		(width 0.10668)
		(layer "B.Cu")
		(net "JTAG_TCK_RT_CPU0_P0")
	)
	(segment
		(start 306.7685 -428.0916)
		(end 306.7685 -428.882556)
		(width 0.10668)
		(layer "B.Cu")
		(net "JTAG_TCK_RT_CPU0_P0")
	)
	(segment
		(start 293.9034 -400.6088)
		(end 293.9034 -406.05964)
		(width 0.11684)
		(layer "In13.Cu")
		(net "JTAG_TCK_RT_CPU0_P0")
	)
	(segment
		(start 303.181004 -427.779434)
		(end 304.176938 -427.779434)
		(width 0.11684)
		(layer "In13.Cu")
		(net "JTAG_TCK_RT_CPU0_P0")
	)
	(segment
		(start 291.82314 -415.384234)
		(end 296.768774 -420.329868)
		(width 0.11684)
		(layer "In13.Cu")
		(net "JTAG_TCK_RT_CPU0_P0")
	)
	(segment
		(start 301.296578 -425.895008)
		(end 303.181004 -427.779434)
		(width 0.11684)
		(layer "In13.Cu")
		(net "JTAG_TCK_RT_CPU0_P0")
	)
	(segment
		(start 293.9034 -406.05964)
		(end 291.82314 -408.1399)
		(width 0.11684)
		(layer "In13.Cu")
		(net "JTAG_TCK_RT_CPU0_P0")
	)
	(segment
		(start 323.184266 -398.68856)
		(end 322.916804 -398.956022)
		(width 0.11684)
		(layer "In13.Cu")
		(net "JTAG_TCK_RT_CPU0_P0")
	)
	(segment
		(start 301.296578 -423.961052)
		(end 301.296578 -425.895008)
		(width 0.11684)
		(layer "In13.Cu")
		(net "JTAG_TCK_RT_CPU0_P0")
	)
	(segment
		(start 304.176938 -427.779434)
		(end 304.489104 -428.0916)
		(width 0.11684)
		(layer "In13.Cu")
		(net "JTAG_TCK_RT_CPU0_P0")
	)
	(segment
		(start 296.768774 -420.329868)
		(end 297.665394 -420.329868)
		(width 0.11684)
		(layer "In13.Cu")
		(net "JTAG_TCK_RT_CPU0_P0")
	)
	(segment
		(start 304.489104 -428.0916)
		(end 306.223416 -428.0916)
		(width 0.11684)
		(layer "In13.Cu")
		(net "JTAG_TCK_RT_CPU0_P0")
	)
	(segment
		(start 291.82314 -408.1399)
		(end 291.82314 -415.384234)
		(width 0.11684)
		(layer "In13.Cu")
		(net "JTAG_TCK_RT_CPU0_P0")
	)
	(segment
		(start 297.665394 -420.329868)
		(end 301.296578 -423.961052)
		(width 0.11684)
		(layer "In13.Cu")
		(net "JTAG_TCK_RT_CPU0_P0")
	)
	(segment
		(start 297.14698 -397.36522)
		(end 293.9034 -400.6088)
		(width 0.11684)
		(layer "In13.Cu")
		(net "JTAG_TCK_RT_CPU0_P0")
	)
	(segment
		(start 303.187862 -398.956022)
		(end 301.59706 -397.36522)
		(width 0.11684)
		(layer "In13.Cu")
		(net "JTAG_TCK_RT_CPU0_P0")
	)
	(segment
		(start 323.848984 -398.68856)
		(end 323.184266 -398.68856)
		(width 0.11684)
		(layer "In13.Cu")
		(net "JTAG_TCK_RT_CPU0_P0")
	)
	(segment
		(start 322.916804 -398.956022)
		(end 303.187862 -398.956022)
		(width 0.11684)
		(layer "In13.Cu")
		(net "JTAG_TCK_RT_CPU0_P0")
	)
	(segment
		(start 301.59706 -397.36522)
		(end 297.14698 -397.36522)
		(width 0.11684)
		(layer "In13.Cu")
		(net "JTAG_TCK_RT_CPU0_P0")
	)
	(segment
		(start 133.418072 -382.85166)
		(end 133.418072 -383.402586)
		(width 0.10668)
		(layer "F.Cu")
		(net "CLKREQ_RT_CPU1_P3_N")
	)
	(segment
		(start 136.302496 -383.199386)
		(end 135.508492 -383.199386)
		(width 0.10668)
		(layer "F.Cu")
		(net "CLKREQ_RT_CPU1_P3_N")
	)
	(segment
		(start 134.735824 -382.426718)
		(end 133.843014 -382.426718)
		(width 0.10668)
		(layer "F.Cu")
		(net "CLKREQ_RT_CPU1_P3_N")
	)
	(segment
		(start 137.714482 -381.7874)
		(end 136.302496 -383.199386)
		(width 0.10668)
		(layer "F.Cu")
		(net "CLKREQ_RT_CPU1_P3_N")
	)
	(segment
		(start 133.843014 -382.426718)
		(end 133.418072 -382.85166)
		(width 0.10668)
		(layer "F.Cu")
		(net "CLKREQ_RT_CPU1_P3_N")
	)
	(segment
		(start 137.800842 -381.7874)
		(end 137.714482 -381.7874)
		(width 0.10668)
		(layer "F.Cu")
		(net "CLKREQ_RT_CPU1_P3_N")
	)
	(segment
		(start 135.508492 -383.199386)
		(end 134.735824 -382.426718)
		(width 0.10668)
		(layer "F.Cu")
		(net "CLKREQ_RT_CPU1_P3_N")
	)
	(segment
		(start 166.370762 -382.426718)
		(end 165.94582 -382.85166)
		(width 0.10668)
		(layer "F.Cu")
		(net "CLKREQ_RT_CPU1_P2_N")
	)
	(segment
		(start 167.263572 -382.426718)
		(end 166.370762 -382.426718)
		(width 0.10668)
		(layer "F.Cu")
		(net "CLKREQ_RT_CPU1_P2_N")
	)
	(segment
		(start 165.94582 -382.85166)
		(end 165.94582 -383.402586)
		(width 0.10668)
		(layer "F.Cu")
		(net "CLKREQ_RT_CPU1_P2_N")
	)
	(segment
		(start 169.724324 -382.305306)
		(end 168.830244 -383.199386)
		(width 0.10668)
		(layer "F.Cu")
		(net "CLKREQ_RT_CPU1_P2_N")
	)
	(segment
		(start 168.03624 -383.199386)
		(end 167.263572 -382.426718)
		(width 0.10668)
		(layer "F.Cu")
		(net "CLKREQ_RT_CPU1_P2_N")
	)
	(segment
		(start 168.830244 -383.199386)
		(end 168.03624 -383.199386)
		(width 0.10668)
		(layer "F.Cu")
		(net "CLKREQ_RT_CPU1_P2_N")
	)
	(segment
		(start 100.936298 -383.199386)
		(end 100.16363 -382.426718)
		(width 0.10668)
		(layer "F.Cu")
		(net "CLKREQ_RT_CPU1_P1_N")
	)
	(segment
		(start 99.27082 -382.426718)
		(end 98.845878 -382.85166)
		(width 0.10668)
		(layer "F.Cu")
		(net "CLKREQ_RT_CPU1_P1_N")
	)
	(segment
		(start 104.928924 -381.7874)
		(end 105.261664 -381.45466)
		(width 0.10668)
		(layer "F.Cu")
		(net "CLKREQ_RT_CPU1_P1_N")
	)
	(segment
		(start 105.261664 -381.45466)
		(end 105.891584 -381.45466)
		(width 0.10668)
		(layer "F.Cu")
		(net "CLKREQ_RT_CPU1_P1_N")
	)
	(segment
		(start 102.729792 -382.383792)
		(end 102.545896 -382.383792)
		(width 0.10668)
		(layer "F.Cu")
		(net "CLKREQ_RT_CPU1_P1_N")
	)
	(segment
		(start 103.228648 -381.884936)
		(end 102.729792 -382.383792)
		(width 0.10668)
		(layer "F.Cu")
		(net "CLKREQ_RT_CPU1_P1_N")
	)
	(segment
		(start 106.663236 -382.226312)
		(end 106.663236 -383.281174)
		(width 0.10668)
		(layer "F.Cu")
		(net "CLKREQ_RT_CPU1_P1_N")
	)
	(segment
		(start 100.16363 -382.426718)
		(end 99.27082 -382.426718)
		(width 0.10668)
		(layer "F.Cu")
		(net "CLKREQ_RT_CPU1_P1_N")
	)
	(segment
		(start 98.845878 -382.85166)
		(end 98.845878 -383.402586)
		(width 0.10668)
		(layer "F.Cu")
		(net "CLKREQ_RT_CPU1_P1_N")
	)
	(segment
		(start 103.228648 -381.7874)
		(end 103.228648 -381.884936)
		(width 0.10668)
		(layer "F.Cu")
		(net "CLKREQ_RT_CPU1_P1_N")
	)
	(segment
		(start 105.891584 -381.45466)
		(end 106.663236 -382.226312)
		(width 0.10668)
		(layer "F.Cu")
		(net "CLKREQ_RT_CPU1_P1_N")
	)
	(segment
		(start 102.545896 -382.383792)
		(end 101.730302 -383.199386)
		(width 0.10668)
		(layer "F.Cu")
		(net "CLKREQ_RT_CPU1_P1_N")
	)
	(segment
		(start 103.228648 -381.7874)
		(end 104.928924 -381.7874)
		(width 0.10668)
		(layer "F.Cu")
		(net "CLKREQ_RT_CPU1_P1_N")
	)
	(segment
		(start 101.730302 -383.199386)
		(end 100.936298 -383.199386)
		(width 0.10668)
		(layer "F.Cu")
		(net "CLKREQ_RT_CPU1_P1_N")
	)
	(via
		(at 106.663236 -383.281174)
		(size 0.762)
		(drill 0.381)
		(layers "F.Cu" "B.Cu")
		(net "CLKREQ_RT_CPU1_P1_N")
	)
	(segment
		(start 66.743072 -382.426718)
		(end 66.31813 -382.85166)
		(width 0.10668)
		(layer "F.Cu")
		(net "CLKREQ_RT_CPU1_P0_N")
	)
	(segment
		(start 66.31813 -382.85166)
		(end 66.31813 -383.402586)
		(width 0.10668)
		(layer "F.Cu")
		(net "CLKREQ_RT_CPU1_P0_N")
	)
	(segment
		(start 70.7009 -381.7874)
		(end 70.61454 -381.7874)
		(width 0.10668)
		(layer "F.Cu")
		(net "CLKREQ_RT_CPU1_P0_N")
	)
	(segment
		(start 69.202554 -383.199386)
		(end 68.40855 -383.199386)
		(width 0.10668)
		(layer "F.Cu")
		(net "CLKREQ_RT_CPU1_P0_N")
	)
	(segment
		(start 67.635882 -382.426718)
		(end 66.743072 -382.426718)
		(width 0.10668)
		(layer "F.Cu")
		(net "CLKREQ_RT_CPU1_P0_N")
	)
	(segment
		(start 68.40855 -383.199386)
		(end 67.635882 -382.426718)
		(width 0.10668)
		(layer "F.Cu")
		(net "CLKREQ_RT_CPU1_P0_N")
	)
	(segment
		(start 70.61454 -381.7874)
		(end 69.202554 -383.199386)
		(width 0.10668)
		(layer "F.Cu")
		(net "CLKREQ_RT_CPU1_P0_N")
	)
	(segment
		(start 392.302492 -391.581386)
		(end 391.508488 -391.581386)
		(width 0.10668)
		(layer "F.Cu")
		(net "CLKREQ_RT_CPU0_P3_N")
	)
	(segment
		(start 393.714478 -390.1694)
		(end 392.302492 -391.581386)
		(width 0.10668)
		(layer "F.Cu")
		(net "CLKREQ_RT_CPU0_P3_N")
	)
	(segment
		(start 390.73582 -390.808718)
		(end 389.84301 -390.808718)
		(width 0.10668)
		(layer "F.Cu")
		(net "CLKREQ_RT_CPU0_P3_N")
	)
	(segment
		(start 389.418068 -391.23366)
		(end 389.418068 -391.784586)
		(width 0.10668)
		(layer "F.Cu")
		(net "CLKREQ_RT_CPU0_P3_N")
	)
	(segment
		(start 389.84301 -390.808718)
		(end 389.418068 -391.23366)
		(width 0.10668)
		(layer "F.Cu")
		(net "CLKREQ_RT_CPU0_P3_N")
	)
	(segment
		(start 391.508488 -391.581386)
		(end 390.73582 -390.808718)
		(width 0.10668)
		(layer "F.Cu")
		(net "CLKREQ_RT_CPU0_P3_N")
	)
	(segment
		(start 393.800584 -390.1694)
		(end 393.714478 -390.1694)
		(width 0.10668)
		(layer "F.Cu")
		(net "CLKREQ_RT_CPU0_P3_N")
	)
	(segment
		(start 422.370758 -390.808718)
		(end 421.945816 -391.23366)
		(width 0.10668)
		(layer "F.Cu")
		(net "CLKREQ_RT_CPU0_P2_N")
	)
	(segment
		(start 425.79163 -390.538462)
		(end 425.79163 -390.068816)
		(width 0.10668)
		(layer "F.Cu")
		(net "CLKREQ_RT_CPU0_P2_N")
	)
	(segment
		(start 421.945816 -391.23366)
		(end 421.945816 -391.784586)
		(width 0.10668)
		(layer "F.Cu")
		(net "CLKREQ_RT_CPU0_P2_N")
	)
	(segment
		(start 424.921426 -391.581386)
		(end 424.036236 -391.581386)
		(width 0.10668)
		(layer "F.Cu")
		(net "CLKREQ_RT_CPU0_P2_N")
	)
	(segment
		(start 424.036236 -391.581386)
		(end 423.263568 -390.808718)
		(width 0.10668)
		(layer "F.Cu")
		(net "CLKREQ_RT_CPU0_P2_N")
	)
	(segment
		(start 425.87799 -390.624822)
		(end 425.79163 -390.538462)
		(width 0.10668)
		(layer "F.Cu")
		(net "CLKREQ_RT_CPU0_P2_N")
	)
	(segment
		(start 425.87799 -390.624822)
		(end 424.921426 -391.581386)
		(width 0.10668)
		(layer "F.Cu")
		(net "CLKREQ_RT_CPU0_P2_N")
	)
	(segment
		(start 423.263568 -390.808718)
		(end 422.370758 -390.808718)
		(width 0.10668)
		(layer "F.Cu")
		(net "CLKREQ_RT_CPU0_P2_N")
	)
	(via
		(at 425.87799 -390.624822)
		(size 0.508)
		(drill 0.254)
		(layers "F.Cu" "B.Cu")
		(net "CLKREQ_RT_CPU0_P2_N")
	)
	(segment
		(start 355.270562 -390.808718)
		(end 354.84562 -391.23366)
		(width 0.10668)
		(layer "F.Cu")
		(net "CLKREQ_RT_CPU0_P1_N")
	)
	(segment
		(start 358.814624 -390.687814)
		(end 358.709976 -390.687814)
		(width 0.10668)
		(layer "F.Cu")
		(net "CLKREQ_RT_CPU0_P1_N")
	)
	(segment
		(start 359.22839 -390.274048)
		(end 358.814624 -390.687814)
		(width 0.10668)
		(layer "F.Cu")
		(net "CLKREQ_RT_CPU0_P1_N")
	)
	(segment
		(start 359.22839 -390.1694)
		(end 359.22839 -390.274048)
		(width 0.10668)
		(layer "F.Cu")
		(net "CLKREQ_RT_CPU0_P1_N")
	)
	(segment
		(start 356.163372 -390.808718)
		(end 355.270562 -390.808718)
		(width 0.10668)
		(layer "F.Cu")
		(net "CLKREQ_RT_CPU0_P1_N")
	)
	(segment
		(start 356.93604 -391.581386)
		(end 356.163372 -390.808718)
		(width 0.10668)
		(layer "F.Cu")
		(net "CLKREQ_RT_CPU0_P1_N")
	)
	(segment
		(start 361.891326 -389.83666)
		(end 362.662978 -390.608312)
		(width 0.10668)
		(layer "F.Cu")
		(net "CLKREQ_RT_CPU0_P1_N")
	)
	(segment
		(start 358.709976 -390.687814)
		(end 357.816404 -391.581386)
		(width 0.10668)
		(layer "F.Cu")
		(net "CLKREQ_RT_CPU0_P1_N")
	)
	(segment
		(start 357.816404 -391.581386)
		(end 356.93604 -391.581386)
		(width 0.10668)
		(layer "F.Cu")
		(net "CLKREQ_RT_CPU0_P1_N")
	)
	(segment
		(start 354.84562 -391.23366)
		(end 354.84562 -391.784586)
		(width 0.10668)
		(layer "F.Cu")
		(net "CLKREQ_RT_CPU0_P1_N")
	)
	(segment
		(start 359.22839 -390.1694)
		(end 360.928666 -390.1694)
		(width 0.10668)
		(layer "F.Cu")
		(net "CLKREQ_RT_CPU0_P1_N")
	)
	(segment
		(start 360.928666 -390.1694)
		(end 361.261406 -389.83666)
		(width 0.10668)
		(layer "F.Cu")
		(net "CLKREQ_RT_CPU0_P1_N")
	)
	(segment
		(start 362.662978 -390.608312)
		(end 362.662978 -391.663174)
		(width 0.10668)
		(layer "F.Cu")
		(net "CLKREQ_RT_CPU0_P1_N")
	)
	(segment
		(start 361.261406 -389.83666)
		(end 361.891326 -389.83666)
		(width 0.10668)
		(layer "F.Cu")
		(net "CLKREQ_RT_CPU0_P1_N")
	)
	(via
		(at 362.662978 -391.663174)
		(size 0.762)
		(drill 0.381)
		(layers "F.Cu" "B.Cu")
		(net "CLKREQ_RT_CPU0_P1_N")
	)
	(segment
		(start 322.317872 -391.23366)
		(end 322.317872 -391.784586)
		(width 0.10668)
		(layer "F.Cu")
		(net "CLKREQ_RT_CPU0_P0_N")
	)
	(segment
		(start 322.742814 -390.808718)
		(end 322.317872 -391.23366)
		(width 0.10668)
		(layer "F.Cu")
		(net "CLKREQ_RT_CPU0_P0_N")
	)
	(segment
		(start 326.614282 -390.1694)
		(end 325.202296 -391.581386)
		(width 0.10668)
		(layer "F.Cu")
		(net "CLKREQ_RT_CPU0_P0_N")
	)
	(segment
		(start 324.408292 -391.581386)
		(end 323.635624 -390.808718)
		(width 0.10668)
		(layer "F.Cu")
		(net "CLKREQ_RT_CPU0_P0_N")
	)
	(segment
		(start 325.202296 -391.581386)
		(end 324.408292 -391.581386)
		(width 0.10668)
		(layer "F.Cu")
		(net "CLKREQ_RT_CPU0_P0_N")
	)
	(segment
		(start 326.700642 -390.1694)
		(end 326.614282 -390.1694)
		(width 0.10668)
		(layer "F.Cu")
		(net "CLKREQ_RT_CPU0_P0_N")
	)
	(segment
		(start 323.635624 -390.808718)
		(end 322.742814 -390.808718)
		(width 0.10668)
		(layer "F.Cu")
		(net "CLKREQ_RT_CPU0_P0_N")
	)
	(segment
		(start 245.95582 -213.894924)
		(end 245.95582 -190.138812)
		(width 0.10668)
		(layer "F.Cu")
		(net "SMB_ADC_SDA_R")
	)
	(segment
		(start 243.16182 -326.30618)
		(end 251.203206 -326.30618)
		(width 0.10668)
		(layer "F.Cu")
		(net "SMB_ADC_SDA_R")
	)
	(segment
		(start 258.832096 -318.67729)
		(end 258.832096 -226.7712)
		(width 0.10668)
		(layer "F.Cu")
		(net "SMB_ADC_SDA_R")
	)
	(segment
		(start 272.203418 -118.618)
		(end 272.978626 -118.618)
		(width 0.10668)
		(layer "F.Cu")
		(net "SMB_ADC_SDA_R")
	)
	(segment
		(start 242.88369 -161.08172)
		(end 242.88369 -160.511236)
		(width 0.10668)
		(layer "F.Cu")
		(net "SMB_ADC_SDA_R")
	)
	(segment
		(start 240.721134 -171.561506)
		(end 241.555778 -170.726862)
		(width 0.10668)
		(layer "F.Cu")
		(net "SMB_ADC_SDA_R")
	)
	(segment
		(start 241.555778 -162.409632)
		(end 242.88369 -161.08172)
		(width 0.10668)
		(layer "F.Cu")
		(net "SMB_ADC_SDA_R")
	)
	(segment
		(start 271.492726 -118.618)
		(end 272.203418 -118.618)
		(width 0.10668)
		(layer "F.Cu")
		(net "SMB_ADC_SDA_R")
	)
	(segment
		(start 245.95582 -190.138812)
		(end 240.721134 -177.501042)
		(width 0.10668)
		(layer "F.Cu")
		(net "SMB_ADC_SDA_R")
	)
	(segment
		(start 240.721134 -177.501042)
		(end 240.721134 -171.561506)
		(width 0.10668)
		(layer "F.Cu")
		(net "SMB_ADC_SDA_R")
	)
	(segment
		(start 242.88369 -160.511236)
		(end 242.407948 -160.035494)
		(width 0.10668)
		(layer "F.Cu")
		(net "SMB_ADC_SDA_R")
	)
	(segment
		(start 251.203206 -326.30618)
		(end 258.832096 -318.67729)
		(width 0.10668)
		(layer "F.Cu")
		(net "SMB_ADC_SDA_R")
	)
	(segment
		(start 258.832096 -226.7712)
		(end 245.95582 -213.894924)
		(width 0.10668)
		(layer "F.Cu")
		(net "SMB_ADC_SDA_R")
	)
	(segment
		(start 242.57 -326.898)
		(end 243.16182 -326.30618)
		(width 0.10668)
		(layer "F.Cu")
		(net "SMB_ADC_SDA_R")
	)
	(segment
		(start 241.555778 -170.726862)
		(end 241.555778 -162.409632)
		(width 0.10668)
		(layer "F.Cu")
		(net "SMB_ADC_SDA_R")
	)
	(via
		(at 272.203418 -118.618)
		(size 0.508)
		(drill 0.254)
		(layers "F.Cu" "B.Cu")
		(net "SMB_ADC_SDA_R")
	)
	(via
		(at 242.57 -326.898)
		(size 0.508)
		(drill 0.254)
		(layers "F.Cu" "B.Cu")
		(net "SMB_ADC_SDA_R")
	)
	(via
		(at 242.407948 -160.035494)
		(size 0.508)
		(drill 0.254)
		(layers "F.Cu" "B.Cu")
		(net "SMB_ADC_SDA_R")
	)
	(via
		(at 240.551716 -322.13804)
		(size 0.6604)
		(drill 0.3302)
		(layers "F.Cu" "B.Cu")
		(net "SMB_ADC_SDA_R")
	)
	(segment
		(start 215.014302 -323.588634)
		(end 215.723724 -323.588634)
		(width 0.10668)
		(layer "B.Cu")
		(net "SMB_ADC_SDA_R")
	)
	(segment
		(start 242.57 -326.898)
		(end 241.427 -325.755)
		(width 0.10668)
		(layer "B.Cu")
		(net "SMB_ADC_SDA_R")
	)
	(segment
		(start 213.722712 -322.297044)
		(end 215.014302 -323.588634)
		(width 0.10668)
		(layer "B.Cu")
		(net "SMB_ADC_SDA_R")
	)
	(segment
		(start 241.427 -323.013324)
		(end 240.551716 -322.13804)
		(width 0.10668)
		(layer "B.Cu")
		(net "SMB_ADC_SDA_R")
	)
	(segment
		(start 239.222788 -320.809112)
		(end 214.076534 -320.809112)
		(width 0.10668)
		(layer "B.Cu")
		(net "SMB_ADC_SDA_R")
	)
	(segment
		(start 243.31295 -326.898)
		(end 242.57 -326.898)
		(width 0.10668)
		(layer "B.Cu")
		(net "SMB_ADC_SDA_R")
	)
	(segment
		(start 240.551716 -322.13804)
		(end 239.222788 -320.809112)
		(width 0.10668)
		(layer "B.Cu")
		(net "SMB_ADC_SDA_R")
	)
	(segment
		(start 241.427 -325.755)
		(end 241.427 -323.013324)
		(width 0.10668)
		(layer "B.Cu")
		(net "SMB_ADC_SDA_R")
	)
	(segment
		(start 214.076534 -320.809112)
		(end 213.722712 -321.162934)
		(width 0.10668)
		(layer "B.Cu")
		(net "SMB_ADC_SDA_R")
	)
	(segment
		(start 213.722712 -321.162934)
		(end 213.722712 -322.297044)
		(width 0.10668)
		(layer "B.Cu")
		(net "SMB_ADC_SDA_R")
	)
	(segment
		(start 272.203418 -118.618)
		(end 272.203418 -118.639082)
		(width 0.11684)
		(layer "In4.Cu")
		(net "SMB_ADC_SDA_R")
	)
	(segment
		(start 270.575024 -120.267476)
		(end 270.575024 -127.771144)
		(width 0.11684)
		(layer "In4.Cu")
		(net "SMB_ADC_SDA_R")
	)
	(segment
		(start 270.575024 -127.771144)
		(end 271.277842 -128.473962)
		(width 0.11684)
		(layer "In4.Cu")
		(net "SMB_ADC_SDA_R")
	)
	(segment
		(start 262.658098 -155.562554)
		(end 248.0818 -155.562554)
		(width 0.11684)
		(layer "In4.Cu")
		(net "SMB_ADC_SDA_R")
	)
	(segment
		(start 271.277842 -128.473962)
		(end 271.277842 -146.94281)
		(width 0.11684)
		(layer "In4.Cu")
		(net "SMB_ADC_SDA_R")
	)
	(segment
		(start 243.60886 -160.035494)
		(end 242.407948 -160.035494)
		(width 0.11684)
		(layer "In4.Cu")
		(net "SMB_ADC_SDA_R")
	)
	(segment
		(start 272.203418 -118.639082)
		(end 270.575024 -120.267476)
		(width 0.11684)
		(layer "In4.Cu")
		(net "SMB_ADC_SDA_R")
	)
	(segment
		(start 271.277842 -146.94281)
		(end 262.658098 -155.562554)
		(width 0.11684)
		(layer "In4.Cu")
		(net "SMB_ADC_SDA_R")
	)
	(segment
		(start 248.0818 -155.562554)
		(end 243.60886 -160.035494)
		(width 0.11684)
		(layer "In4.Cu")
		(net "SMB_ADC_SDA_R")
	)
	(segment
		(start 268.054582 -118.23192)
		(end 266.975082 -118.23192)
		(width 0.10668)
		(layer "F.Cu")
		(net "SMB_ADC_SDA")
	)
	(segment
		(start 270.4592 -118.851426)
		(end 269.813532 -118.851426)
		(width 0.10668)
		(layer "F.Cu")
		(net "SMB_ADC_SDA")
	)
	(segment
		(start 270.692626 -118.618)
		(end 270.4592 -118.851426)
		(width 0.10668)
		(layer "F.Cu")
		(net "SMB_ADC_SDA")
	)
	(segment
		(start 269.813532 -118.851426)
		(end 268.674088 -118.851426)
		(width 0.10668)
		(layer "F.Cu")
		(net "SMB_ADC_SDA")
	)
	(segment
		(start 268.674088 -118.851426)
		(end 268.054582 -118.23192)
		(width 0.10668)
		(layer "F.Cu")
		(net "SMB_ADC_SDA")
	)
	(via
		(at 269.813532 -118.851426)
		(size 0.762)
		(drill 0.381)
		(layers "F.Cu" "B.Cu")
		(net "SMB_ADC_SDA")
	)
	(segment
		(start 271.492726 -119.761)
		(end 272.203418 -119.761)
		(width 0.10668)
		(layer "F.Cu")
		(net "SMB_ADC_SCL_R")
	)
	(segment
		(start 250.92152 -325.882)
		(end 258.437888 -318.365632)
		(width 0.10668)
		(layer "F.Cu")
		(net "SMB_ADC_SCL_R")
	)
	(segment
		(start 241.212878 -162.056826)
		(end 242.407948 -160.861756)
		(width 0.10668)
		(layer "F.Cu")
		(net "SMB_ADC_SCL_R")
	)
	(segment
		(start 272.203418 -119.761)
		(end 272.978626 -119.761)
		(width 0.10668)
		(layer "F.Cu")
		(net "SMB_ADC_SCL_R")
	)
	(segment
		(start 258.437888 -226.900994)
		(end 245.61546 -214.078566)
		(width 0.10668)
		(layer "F.Cu")
		(net "SMB_ADC_SCL_R")
	)
	(segment
		(start 241.212878 -170.395392)
		(end 241.212878 -162.056826)
		(width 0.10668)
		(layer "F.Cu")
		(net "SMB_ADC_SCL_R")
	)
	(segment
		(start 240.357914 -171.250356)
		(end 241.212878 -170.395392)
		(width 0.10668)
		(layer "F.Cu")
		(net "SMB_ADC_SCL_R")
	)
	(segment
		(start 258.437888 -318.365632)
		(end 258.437888 -226.900994)
		(width 0.10668)
		(layer "F.Cu")
		(net "SMB_ADC_SCL_R")
	)
	(segment
		(start 242.57 -325.882)
		(end 250.92152 -325.882)
		(width 0.10668)
		(layer "F.Cu")
		(net "SMB_ADC_SCL_R")
	)
	(segment
		(start 245.61546 -214.078566)
		(end 245.61546 -190.207138)
		(width 0.10668)
		(layer "F.Cu")
		(net "SMB_ADC_SCL_R")
	)
	(segment
		(start 245.61546 -190.207138)
		(end 240.357914 -177.51425)
		(width 0.10668)
		(layer "F.Cu")
		(net "SMB_ADC_SCL_R")
	)
	(segment
		(start 240.357914 -177.51425)
		(end 240.357914 -171.250356)
		(width 0.10668)
		(layer "F.Cu")
		(net "SMB_ADC_SCL_R")
	)
	(via
		(at 212.924644 -321.38747)
		(size 0.6604)
		(drill 0.3302)
		(layers "F.Cu" "B.Cu")
		(net "SMB_ADC_SCL_R")
	)
	(via
		(at 242.407948 -160.861756)
		(size 0.508)
		(drill 0.254)
		(layers "F.Cu" "B.Cu")
		(net "SMB_ADC_SCL_R")
	)
	(via
		(at 272.203418 -119.761)
		(size 0.508)
		(drill 0.254)
		(layers "F.Cu" "B.Cu")
		(net "SMB_ADC_SCL_R")
	)
	(via
		(at 242.57 -325.882)
		(size 0.508)
		(drill 0.254)
		(layers "F.Cu" "B.Cu")
		(net "SMB_ADC_SCL_R")
	)
	(segment
		(start 241.935 -325.247)
		(end 242.57 -325.882)
		(width 0.10668)
		(layer "B.Cu")
		(net "SMB_ADC_SCL_R")
	)
	(segment
		(start 239.671606 -320.383662)
		(end 241.935 -322.647056)
		(width 0.10668)
		(layer "B.Cu")
		(net "SMB_ADC_SCL_R")
	)
	(segment
		(start 212.924644 -320.835528)
		(end 213.37651 -320.383662)
		(width 0.10668)
		(layer "B.Cu")
		(net "SMB_ADC_SCL_R")
	)
	(segment
		(start 215.70188 -324.647306)
		(end 215.373204 -324.647306)
		(width 0.10668)
		(layer "B.Cu")
		(net "SMB_ADC_SCL_R")
	)
	(segment
		(start 215.373204 -324.647306)
		(end 212.924644 -322.198746)
		(width 0.10668)
		(layer "B.Cu")
		(net "SMB_ADC_SCL_R")
	)
	(segment
		(start 243.31295 -325.882)
		(end 242.57 -325.882)
		(width 0.10668)
		(layer "B.Cu")
		(net "SMB_ADC_SCL_R")
	)
	(segment
		(start 212.924644 -321.38747)
		(end 212.924644 -320.835528)
		(width 0.10668)
		(layer "B.Cu")
		(net "SMB_ADC_SCL_R")
	)
	(segment
		(start 212.924644 -322.198746)
		(end 212.924644 -321.38747)
		(width 0.10668)
		(layer "B.Cu")
		(net "SMB_ADC_SCL_R")
	)
	(segment
		(start 241.935 -322.647056)
		(end 241.935 -325.247)
		(width 0.10668)
		(layer "B.Cu")
		(net "SMB_ADC_SCL_R")
	)
	(segment
		(start 213.37651 -320.383662)
		(end 239.671606 -320.383662)
		(width 0.10668)
		(layer "B.Cu")
		(net "SMB_ADC_SCL_R")
	)
	(segment
		(start 271.102836 -120.861582)
		(end 271.102836 -127.606298)
		(width 0.11684)
		(layer "In4.Cu")
		(net "SMB_ADC_SCL_R")
	)
	(segment
		(start 271.102836 -127.606298)
		(end 271.717008 -128.22047)
		(width 0.11684)
		(layer "In4.Cu")
		(net "SMB_ADC_SCL_R")
	)
	(segment
		(start 271.717008 -128.22047)
		(end 271.717008 -147.277074)
		(width 0.11684)
		(layer "In4.Cu")
		(net "SMB_ADC_SCL_R")
	)
	(segment
		(start 272.203418 -119.761)
		(end 271.102836 -120.861582)
		(width 0.11684)
		(layer "In4.Cu")
		(net "SMB_ADC_SCL_R")
	)
	(segment
		(start 243.777516 -160.861756)
		(end 242.407948 -160.861756)
		(width 0.11684)
		(layer "In4.Cu")
		(net "SMB_ADC_SCL_R")
	)
	(segment
		(start 248.478802 -156.16047)
		(end 243.777516 -160.861756)
		(width 0.11684)
		(layer "In4.Cu")
		(net "SMB_ADC_SCL_R")
	)
	(segment
		(start 271.717008 -147.277074)
		(end 262.833612 -156.16047)
		(width 0.11684)
		(layer "In4.Cu")
		(net "SMB_ADC_SCL_R")
	)
	(segment
		(start 262.833612 -156.16047)
		(end 248.478802 -156.16047)
		(width 0.11684)
		(layer "In4.Cu")
		(net "SMB_ADC_SCL_R")
	)
	(segment
		(start 267.904976 -118.881906)
		(end 266.975082 -118.881906)
		(width 0.10668)
		(layer "F.Cu")
		(net "SMB_ADC_SCL")
	)
	(segment
		(start 270.692626 -119.761)
		(end 268.78407 -119.761)
		(width 0.10668)
		(layer "F.Cu")
		(net "SMB_ADC_SCL")
	)
	(segment
		(start 268.78407 -119.761)
		(end 267.904976 -118.881906)
		(width 0.10668)
		(layer "F.Cu")
		(net "SMB_ADC_SCL")
	)
	(via
		(at 268.78407 -119.761)
		(size 0.762)
		(drill 0.381)
		(layers "F.Cu" "B.Cu")
		(net "SMB_ADC_SCL")
	)
	(segment
		(start 187.325 -100.92182)
		(end 186.817 -101.42982)
		(width 0.10668)
		(layer "F.Cu")
		(net "OCP_V3_2_P3V3_P12V_ADC_R_ALERT")
	)
	(segment
		(start 187.871608 -99.890326)
		(end 187.452 -99.890326)
		(width 0.10668)
		(layer "F.Cu")
		(net "OCP_V3_2_P3V3_P12V_ADC_R_ALERT")
	)
	(segment
		(start 187.452 -99.890326)
		(end 187.325 -100.017326)
		(width 0.10668)
		(layer "F.Cu")
		(net "OCP_V3_2_P3V3_P12V_ADC_R_ALERT")
	)
	(segment
		(start 187.325 -100.017326)
		(end 187.325 -100.92182)
		(width 0.10668)
		(layer "F.Cu")
		(net "OCP_V3_2_P3V3_P12V_ADC_R_ALERT")
	)
	(segment
		(start 67.277234 -37.92474)
		(end 66.637154 -37.92474)
		(width 0.10668)
		(layer "F.Cu")
		(net "OCP_V3_2_P3V3_P12V_ADC_R_ALERT")
	)
	(segment
		(start 67.812412 -37.389562)
		(end 67.277234 -37.92474)
		(width 0.10668)
		(layer "F.Cu")
		(net "OCP_V3_2_P3V3_P12V_ADC_R_ALERT")
	)
	(segment
		(start 18.841466 -37.894514)
		(end 18.201386 -37.894514)
		(width 0.10668)
		(layer "F.Cu")
		(net "OCP_V3_2_P3V3_P12V_ADC_R_ALERT")
	)
	(segment
		(start 66.637154 -37.92474)
		(end 66.191384 -38.37051)
		(width 0.10668)
		(layer "F.Cu")
		(net "OCP_V3_2_P3V3_P12V_ADC_R_ALERT")
	)
	(segment
		(start 18.840704 -36.878514)
		(end 18.840704 -37.893752)
		(width 0.10668)
		(layer "F.Cu")
		(net "OCP_V3_2_P3V3_P12V_ADC_R_ALERT")
	)
	(segment
		(start 18.840704 -37.893752)
		(end 18.841466 -37.894514)
		(width 0.10668)
		(layer "F.Cu")
		(net "OCP_V3_2_P3V3_P12V_ADC_R_ALERT")
	)
	(via
		(at 18.201386 -37.894514)
		(size 0.508)
		(drill 0.254)
		(layers "F.Cu" "B.Cu")
		(net "OCP_V3_2_P3V3_P12V_ADC_R_ALERT")
	)
	(via
		(at 66.191384 -38.37051)
		(size 0.508)
		(drill 0.254)
		(layers "F.Cu" "B.Cu")
		(net "OCP_V3_2_P3V3_P12V_ADC_R_ALERT")
	)
	(via
		(at 172.47489 -51.861974)
		(size 0.508)
		(drill 0.254)
		(layers "F.Cu" "B.Cu")
		(net "OCP_V3_2_P3V3_P12V_ADC_R_ALERT")
	)
	(via
		(at 186.817 -101.42982)
		(size 0.508)
		(drill 0.254)
		(layers "F.Cu" "B.Cu")
		(net "OCP_V3_2_P3V3_P12V_ADC_R_ALERT")
	)
	(segment
		(start 126.8984 -51.4604)
		(end 125.939296 -51.4604)
		(width 0.11684)
		(layer "In6.Cu")
		(net "OCP_V3_2_P3V3_P12V_ADC_R_ALERT")
	)
	(segment
		(start 57.925462 -36.68903)
		(end 57.45099 -36.214558)
		(width 0.11684)
		(layer "In6.Cu")
		(net "OCP_V3_2_P3V3_P12V_ADC_R_ALERT")
	)
	(segment
		(start 57.89549 -24.379174)
		(end 53.797962 -28.476702)
		(width 0.11684)
		(layer "In6.Cu")
		(net "OCP_V3_2_P3V3_P12V_ADC_R_ALERT")
	)
	(segment
		(start 66.191384 -38.37051)
		(end 63.836804 -38.37051)
		(width 0.11684)
		(layer "In6.Cu")
		(net "OCP_V3_2_P3V3_P12V_ADC_R_ALERT")
	)
	(segment
		(start 161.268918 -50.43043)
		(end 149.41169 -50.43043)
		(width 0.11684)
		(layer "In6.Cu")
		(net "OCP_V3_2_P3V3_P12V_ADC_R_ALERT")
	)
	(segment
		(start 50.332386 -38.677342)
		(end 49.135792 -39.873936)
		(width 0.11684)
		(layer "In6.Cu")
		(net "OCP_V3_2_P3V3_P12V_ADC_R_ALERT")
	)
	(segment
		(start 53.797962 -30.125416)
		(end 50.332386 -33.590992)
		(width 0.11684)
		(layer "In6.Cu")
		(net "OCP_V3_2_P3V3_P12V_ADC_R_ALERT")
	)
	(segment
		(start 125.050296 -52.3494)
		(end 103.714296 -52.3494)
		(width 0.11684)
		(layer "In6.Cu")
		(net "OCP_V3_2_P3V3_P12V_ADC_R_ALERT")
	)
	(segment
		(start 127.6858 -52.2478)
		(end 126.8984 -51.4604)
		(width 0.11684)
		(layer "In6.Cu")
		(net "OCP_V3_2_P3V3_P12V_ADC_R_ALERT")
	)
	(segment
		(start 49.135792 -39.873936)
		(end 43.249088 -39.873936)
		(width 0.11684)
		(layer "In6.Cu")
		(net "OCP_V3_2_P3V3_P12V_ADC_R_ALERT")
	)
	(segment
		(start 60.06338 -26.891488)
		(end 60.2869 -26.667968)
		(width 0.11684)
		(layer "In6.Cu")
		(net "OCP_V3_2_P3V3_P12V_ADC_R_ALERT")
	)
	(segment
		(start 53.797962 -28.476702)
		(end 53.797962 -30.125416)
		(width 0.11684)
		(layer "In6.Cu")
		(net "OCP_V3_2_P3V3_P12V_ADC_R_ALERT")
	)
	(segment
		(start 59.08294 -26.891488)
		(end 60.06338 -26.891488)
		(width 0.11684)
		(layer "In6.Cu")
		(net "OCP_V3_2_P3V3_P12V_ADC_R_ALERT")
	)
	(segment
		(start 60.2869 -26.667968)
		(end 60.2869 -24.582882)
		(width 0.11684)
		(layer "In6.Cu")
		(net "OCP_V3_2_P3V3_P12V_ADC_R_ALERT")
	)
	(segment
		(start 66.734182 -38.913308)
		(end 66.191384 -38.37051)
		(width 0.11684)
		(layer "In6.Cu")
		(net "OCP_V3_2_P3V3_P12V_ADC_R_ALERT")
	)
	(segment
		(start 80.872584 -44.931584)
		(end 76.751688 -40.810688)
		(width 0.11684)
		(layer "In6.Cu")
		(net "OCP_V3_2_P3V3_P12V_ADC_R_ALERT")
	)
	(segment
		(start 71.07428 -38.913308)
		(end 66.734182 -38.913308)
		(width 0.11684)
		(layer "In6.Cu")
		(net "OCP_V3_2_P3V3_P12V_ADC_R_ALERT")
	)
	(segment
		(start 63.432944 -37.96665)
		(end 60.800488 -37.96665)
		(width 0.11684)
		(layer "In6.Cu")
		(net "OCP_V3_2_P3V3_P12V_ADC_R_ALERT")
	)
	(segment
		(start 76.751688 -40.810688)
		(end 72.97166 -40.810688)
		(width 0.11684)
		(layer "In6.Cu")
		(net "OCP_V3_2_P3V3_P12V_ADC_R_ALERT")
	)
	(segment
		(start 149.41169 -50.43043)
		(end 148.29536 -51.54676)
		(width 0.11684)
		(layer "In6.Cu")
		(net "OCP_V3_2_P3V3_P12V_ADC_R_ALERT")
	)
	(segment
		(start 72.97166 -40.810688)
		(end 71.07428 -38.913308)
		(width 0.11684)
		(layer "In6.Cu")
		(net "OCP_V3_2_P3V3_P12V_ADC_R_ALERT")
	)
	(segment
		(start 103.714296 -52.3494)
		(end 102.72649 -51.361594)
		(width 0.11684)
		(layer "In6.Cu")
		(net "OCP_V3_2_P3V3_P12V_ADC_R_ALERT")
	)
	(segment
		(start 60.800488 -37.96665)
		(end 59.522868 -36.68903)
		(width 0.11684)
		(layer "In6.Cu")
		(net "OCP_V3_2_P3V3_P12V_ADC_R_ALERT")
	)
	(segment
		(start 20.158202 -39.85133)
		(end 18.201386 -37.894514)
		(width 0.11684)
		(layer "In6.Cu")
		(net "OCP_V3_2_P3V3_P12V_ADC_R_ALERT")
	)
	(segment
		(start 23.576534 -45.838872)
		(end 20.158202 -42.42054)
		(width 0.11684)
		(layer "In6.Cu")
		(net "OCP_V3_2_P3V3_P12V_ADC_R_ALERT")
	)
	(segment
		(start 162.082988 -49.61636)
		(end 161.268918 -50.43043)
		(width 0.11684)
		(layer "In6.Cu")
		(net "OCP_V3_2_P3V3_P12V_ADC_R_ALERT")
	)
	(segment
		(start 57.45099 -28.523438)
		(end 59.08294 -26.891488)
		(width 0.11684)
		(layer "In6.Cu")
		(net "OCP_V3_2_P3V3_P12V_ADC_R_ALERT")
	)
	(segment
		(start 60.083192 -24.379174)
		(end 57.89549 -24.379174)
		(width 0.11684)
		(layer "In6.Cu")
		(net "OCP_V3_2_P3V3_P12V_ADC_R_ALERT")
	)
	(segment
		(start 168.825164 -49.61636)
		(end 162.082988 -49.61636)
		(width 0.11684)
		(layer "In6.Cu")
		(net "OCP_V3_2_P3V3_P12V_ADC_R_ALERT")
	)
	(segment
		(start 59.522868 -36.68903)
		(end 57.925462 -36.68903)
		(width 0.11684)
		(layer "In6.Cu")
		(net "OCP_V3_2_P3V3_P12V_ADC_R_ALERT")
	)
	(segment
		(start 43.249088 -39.873936)
		(end 37.284152 -45.838872)
		(width 0.11684)
		(layer "In6.Cu")
		(net "OCP_V3_2_P3V3_P12V_ADC_R_ALERT")
	)
	(segment
		(start 148.29536 -51.54676)
		(end 129.50444 -51.54676)
		(width 0.11684)
		(layer "In6.Cu")
		(net "OCP_V3_2_P3V3_P12V_ADC_R_ALERT")
	)
	(segment
		(start 172.411136 -51.925728)
		(end 171.134532 -51.925728)
		(width 0.11684)
		(layer "In6.Cu")
		(net "OCP_V3_2_P3V3_P12V_ADC_R_ALERT")
	)
	(segment
		(start 91.457526 -51.361594)
		(end 85.027516 -44.931584)
		(width 0.11684)
		(layer "In6.Cu")
		(net "OCP_V3_2_P3V3_P12V_ADC_R_ALERT")
	)
	(segment
		(start 57.45099 -36.214558)
		(end 57.45099 -28.523438)
		(width 0.11684)
		(layer "In6.Cu")
		(net "OCP_V3_2_P3V3_P12V_ADC_R_ALERT")
	)
	(segment
		(start 50.332386 -33.590992)
		(end 50.332386 -38.677342)
		(width 0.11684)
		(layer "In6.Cu")
		(net "OCP_V3_2_P3V3_P12V_ADC_R_ALERT")
	)
	(segment
		(start 102.72649 -51.361594)
		(end 91.457526 -51.361594)
		(width 0.11684)
		(layer "In6.Cu")
		(net "OCP_V3_2_P3V3_P12V_ADC_R_ALERT")
	)
	(segment
		(start 172.47489 -51.861974)
		(end 172.411136 -51.925728)
		(width 0.11684)
		(layer "In6.Cu")
		(net "OCP_V3_2_P3V3_P12V_ADC_R_ALERT")
	)
	(segment
		(start 60.2869 -24.582882)
		(end 60.083192 -24.379174)
		(width 0.11684)
		(layer "In6.Cu")
		(net "OCP_V3_2_P3V3_P12V_ADC_R_ALERT")
	)
	(segment
		(start 125.939296 -51.4604)
		(end 125.050296 -52.3494)
		(width 0.11684)
		(layer "In6.Cu")
		(net "OCP_V3_2_P3V3_P12V_ADC_R_ALERT")
	)
	(segment
		(start 171.134532 -51.925728)
		(end 168.825164 -49.61636)
		(width 0.11684)
		(layer "In6.Cu")
		(net "OCP_V3_2_P3V3_P12V_ADC_R_ALERT")
	)
	(segment
		(start 37.284152 -45.838872)
		(end 23.576534 -45.838872)
		(width 0.11684)
		(layer "In6.Cu")
		(net "OCP_V3_2_P3V3_P12V_ADC_R_ALERT")
	)
	(segment
		(start 129.50444 -51.54676)
		(end 128.8034 -52.2478)
		(width 0.11684)
		(layer "In6.Cu")
		(net "OCP_V3_2_P3V3_P12V_ADC_R_ALERT")
	)
	(segment
		(start 63.836804 -38.37051)
		(end 63.432944 -37.96665)
		(width 0.11684)
		(layer "In6.Cu")
		(net "OCP_V3_2_P3V3_P12V_ADC_R_ALERT")
	)
	(segment
		(start 85.027516 -44.931584)
		(end 80.872584 -44.931584)
		(width 0.11684)
		(layer "In6.Cu")
		(net "OCP_V3_2_P3V3_P12V_ADC_R_ALERT")
	)
	(segment
		(start 128.8034 -52.2478)
		(end 127.6858 -52.2478)
		(width 0.11684)
		(layer "In6.Cu")
		(net "OCP_V3_2_P3V3_P12V_ADC_R_ALERT")
	)
	(segment
		(start 20.158202 -42.42054)
		(end 20.158202 -39.85133)
		(width 0.11684)
		(layer "In6.Cu")
		(net "OCP_V3_2_P3V3_P12V_ADC_R_ALERT")
	)
	(segment
		(start 188.33338 -92.830396)
		(end 188.33338 -97.848928)
		(width 0.11684)
		(layer "In11.Cu")
		(net "OCP_V3_2_P3V3_P12V_ADC_R_ALERT")
	)
	(segment
		(start 188.37402 -99.8728)
		(end 186.817 -101.42982)
		(width 0.11684)
		(layer "In11.Cu")
		(net "OCP_V3_2_P3V3_P12V_ADC_R_ALERT")
	)
	(segment
		(start 182.411624 -90.096594)
		(end 185.599578 -90.096594)
		(width 0.11684)
		(layer "In11.Cu")
		(net "OCP_V3_2_P3V3_P12V_ADC_R_ALERT")
	)
	(segment
		(start 188.37402 -97.889568)
		(end 188.37402 -99.8728)
		(width 0.11684)
		(layer "In11.Cu")
		(net "OCP_V3_2_P3V3_P12V_ADC_R_ALERT")
	)
	(segment
		(start 172.06214 -52.274724)
		(end 172.06214 -53.920898)
		(width 0.11684)
		(layer "In11.Cu")
		(net "OCP_V3_2_P3V3_P12V_ADC_R_ALERT")
	)
	(segment
		(start 185.599578 -90.096594)
		(end 188.33338 -92.830396)
		(width 0.11684)
		(layer "In11.Cu")
		(net "OCP_V3_2_P3V3_P12V_ADC_R_ALERT")
	)
	(segment
		(start 174.397162 -56.25592)
		(end 174.397162 -57.53481)
		(width 0.11684)
		(layer "In11.Cu")
		(net "OCP_V3_2_P3V3_P12V_ADC_R_ALERT")
	)
	(segment
		(start 176.61255 -82.433414)
		(end 180.784246 -86.60511)
		(width 0.11684)
		(layer "In11.Cu")
		(net "OCP_V3_2_P3V3_P12V_ADC_R_ALERT")
	)
	(segment
		(start 171.303442 -77.680566)
		(end 176.05629 -82.433414)
		(width 0.11684)
		(layer "In11.Cu")
		(net "OCP_V3_2_P3V3_P12V_ADC_R_ALERT")
	)
	(segment
		(start 176.05629 -82.433414)
		(end 176.61255 -82.433414)
		(width 0.11684)
		(layer "In11.Cu")
		(net "OCP_V3_2_P3V3_P12V_ADC_R_ALERT")
	)
	(segment
		(start 180.784246 -86.60511)
		(end 180.784246 -88.469216)
		(width 0.11684)
		(layer "In11.Cu")
		(net "OCP_V3_2_P3V3_P12V_ADC_R_ALERT")
	)
	(segment
		(start 174.397162 -57.53481)
		(end 171.303442 -60.62853)
		(width 0.11684)
		(layer "In11.Cu")
		(net "OCP_V3_2_P3V3_P12V_ADC_R_ALERT")
	)
	(segment
		(start 180.784246 -88.469216)
		(end 182.411624 -90.096594)
		(width 0.11684)
		(layer "In11.Cu")
		(net "OCP_V3_2_P3V3_P12V_ADC_R_ALERT")
	)
	(segment
		(start 171.303442 -60.62853)
		(end 171.303442 -77.680566)
		(width 0.11684)
		(layer "In11.Cu")
		(net "OCP_V3_2_P3V3_P12V_ADC_R_ALERT")
	)
	(segment
		(start 172.47489 -51.861974)
		(end 172.06214 -52.274724)
		(width 0.11684)
		(layer "In11.Cu")
		(net "OCP_V3_2_P3V3_P12V_ADC_R_ALERT")
	)
	(segment
		(start 172.06214 -53.920898)
		(end 174.397162 -56.25592)
		(width 0.11684)
		(layer "In11.Cu")
		(net "OCP_V3_2_P3V3_P12V_ADC_R_ALERT")
	)
	(segment
		(start 188.33338 -97.848928)
		(end 188.37402 -97.889568)
		(width 0.11684)
		(layer "In11.Cu")
		(net "OCP_V3_2_P3V3_P12V_ADC_R_ALERT")
	)
	(segment
		(start 187.30595 -103.01605)
		(end 187.30595 -102.108)
		(width 0.10668)
		(layer "F.Cu")
		(net "OCP_V3_2_P3V3_P12V_ADC_ALERT")
	)
	(segment
		(start 187.871608 -100.690426)
		(end 187.871608 -101.542342)
		(width 0.10668)
		(layer "F.Cu")
		(net "OCP_V3_2_P3V3_P12V_ADC_ALERT")
	)
	(segment
		(start 187.871608 -101.542342)
		(end 187.30595 -102.108)
		(width 0.10668)
		(layer "F.Cu")
		(net "OCP_V3_2_P3V3_P12V_ADC_ALERT")
	)
	(segment
		(start 187.522104 -106.652822)
		(end 187.522104 -103.232204)
		(width 0.10668)
		(layer "F.Cu")
		(net "OCP_V3_2_P3V3_P12V_ADC_ALERT")
	)
	(segment
		(start 187.522104 -103.232204)
		(end 187.30595 -103.01605)
		(width 0.10668)
		(layer "F.Cu")
		(net "OCP_V3_2_P3V3_P12V_ADC_ALERT")
	)
	(via
		(at 187.30595 -102.108)
		(size 0.762)
		(drill 0.381)
		(layers "F.Cu" "B.Cu")
		(net "OCP_V3_2_P3V3_P12V_ADC_ALERT")
	)
	(segment
		(start 210.885532 -102.958138)
		(end 212.813138 -102.958138)
		(width 0.10668)
		(layer "F.Cu")
		(net "OCP_SFF_P3V3_P12V_ADC_R_ALERT")
	)
	(segment
		(start 445.59093 -94.602808)
		(end 446.260982 -94.602808)
		(width 0.10668)
		(layer "F.Cu")
		(net "OCP_SFF_P3V3_P12V_ADC_R_ALERT")
	)
	(segment
		(start 390.891268 -74.375264)
		(end 390.251188 -74.375264)
		(width 0.10668)
		(layer "F.Cu")
		(net "OCP_SFF_P3V3_P12V_ADC_R_ALERT")
	)
	(segment
		(start 390.890506 -73.359264)
		(end 390.890506 -74.374502)
		(width 0.10668)
		(layer "F.Cu")
		(net "OCP_SFF_P3V3_P12V_ADC_R_ALERT")
	)
	(segment
		(start 390.890506 -74.374502)
		(end 390.891268 -74.375264)
		(width 0.10668)
		(layer "F.Cu")
		(net "OCP_SFF_P3V3_P12V_ADC_R_ALERT")
	)
	(via
		(at 212.813138 -102.958138)
		(size 0.508)
		(drill 0.254)
		(layers "F.Cu" "B.Cu")
		(net "OCP_SFF_P3V3_P12V_ADC_R_ALERT")
	)
	(via
		(at 256.604008 -92.31376)
		(size 0.508)
		(drill 0.254)
		(layers "F.Cu" "B.Cu")
		(net "OCP_SFF_P3V3_P12V_ADC_R_ALERT")
	)
	(via
		(at 446.260982 -94.602808)
		(size 0.508)
		(drill 0.254)
		(layers "F.Cu" "B.Cu")
		(net "OCP_SFF_P3V3_P12V_ADC_R_ALERT")
	)
	(via
		(at 255.717802 -100.636324)
		(size 0.508)
		(drill 0.254)
		(layers "F.Cu" "B.Cu")
		(net "OCP_SFF_P3V3_P12V_ADC_R_ALERT")
	)
	(via
		(at 390.251188 -74.375264)
		(size 0.508)
		(drill 0.254)
		(layers "F.Cu" "B.Cu")
		(net "OCP_SFF_P3V3_P12V_ADC_R_ALERT")
	)
	(segment
		(start 256.604008 -99.750118)
		(end 255.717802 -100.636324)
		(width 0.11684)
		(layer "In4.Cu")
		(net "OCP_SFF_P3V3_P12V_ADC_R_ALERT")
	)
	(segment
		(start 256.604008 -92.31376)
		(end 256.604008 -99.750118)
		(width 0.11684)
		(layer "In4.Cu")
		(net "OCP_SFF_P3V3_P12V_ADC_R_ALERT")
	)
	(segment
		(start 213.271862 -102.958138)
		(end 212.813138 -102.958138)
		(width 0.11684)
		(layer "In6.Cu")
		(net "OCP_SFF_P3V3_P12V_ADC_R_ALERT")
	)
	(segment
		(start 263.338818 -91.187016)
		(end 273.85518 -91.187016)
		(width 0.11684)
		(layer "In6.Cu")
		(net "OCP_SFF_P3V3_P12V_ADC_R_ALERT")
	)
	(segment
		(start 262.840216 -91.685618)
		(end 263.338818 -91.187016)
		(width 0.11684)
		(layer "In6.Cu")
		(net "OCP_SFF_P3V3_P12V_ADC_R_ALERT")
	)
	(segment
		(start 216.59342 -101.73843)
		(end 216.26957 -101.41458)
		(width 0.11684)
		(layer "In6.Cu")
		(net "OCP_SFF_P3V3_P12V_ADC_R_ALERT")
	)
	(segment
		(start 217.98788 -101.778562)
		(end 217.947748 -101.73843)
		(width 0.11684)
		(layer "In6.Cu")
		(net "OCP_SFF_P3V3_P12V_ADC_R_ALERT")
	)
	(segment
		(start 279.00249 -91.685618)
		(end 281.27452 -93.957648)
		(width 0.11684)
		(layer "In6.Cu")
		(net "OCP_SFF_P3V3_P12V_ADC_R_ALERT")
	)
	(segment
		(start 255.717802 -100.636324)
		(end 254.575564 -101.778562)
		(width 0.11684)
		(layer "In6.Cu")
		(net "OCP_SFF_P3V3_P12V_ADC_R_ALERT")
	)
	(segment
		(start 417.45662 -92.51696)
		(end 443.561724 -92.51696)
		(width 0.11684)
		(layer "In6.Cu")
		(net "OCP_SFF_P3V3_P12V_ADC_R_ALERT")
	)
	(segment
		(start 316.236604 -93.957648)
		(end 317.646304 -95.367348)
		(width 0.11684)
		(layer "In6.Cu")
		(net "OCP_SFF_P3V3_P12V_ADC_R_ALERT")
	)
	(segment
		(start 215.51519 -101.41458)
		(end 215.19134 -101.73843)
		(width 0.11684)
		(layer "In6.Cu")
		(net "OCP_SFF_P3V3_P12V_ADC_R_ALERT")
	)
	(segment
		(start 256.604008 -92.31376)
		(end 257.23215 -91.685618)
		(width 0.11684)
		(layer "In6.Cu")
		(net "OCP_SFF_P3V3_P12V_ADC_R_ALERT")
	)
	(segment
		(start 214.49157 -101.73843)
		(end 213.271862 -102.958138)
		(width 0.11684)
		(layer "In6.Cu")
		(net "OCP_SFF_P3V3_P12V_ADC_R_ALERT")
	)
	(segment
		(start 281.27452 -93.957648)
		(end 316.236604 -93.957648)
		(width 0.11684)
		(layer "In6.Cu")
		(net "OCP_SFF_P3V3_P12V_ADC_R_ALERT")
	)
	(segment
		(start 215.19134 -101.73843)
		(end 214.49157 -101.73843)
		(width 0.11684)
		(layer "In6.Cu")
		(net "OCP_SFF_P3V3_P12V_ADC_R_ALERT")
	)
	(segment
		(start 443.561724 -92.51696)
		(end 445.647572 -94.602808)
		(width 0.11684)
		(layer "In6.Cu")
		(net "OCP_SFF_P3V3_P12V_ADC_R_ALERT")
	)
	(segment
		(start 445.647572 -94.602808)
		(end 446.260982 -94.602808)
		(width 0.11684)
		(layer "In6.Cu")
		(net "OCP_SFF_P3V3_P12V_ADC_R_ALERT")
	)
	(segment
		(start 274.353782 -91.685618)
		(end 279.00249 -91.685618)
		(width 0.11684)
		(layer "In6.Cu")
		(net "OCP_SFF_P3V3_P12V_ADC_R_ALERT")
	)
	(segment
		(start 414.606232 -95.367348)
		(end 417.45662 -92.51696)
		(width 0.11684)
		(layer "In6.Cu")
		(net "OCP_SFF_P3V3_P12V_ADC_R_ALERT")
	)
	(segment
		(start 216.26957 -101.41458)
		(end 215.51519 -101.41458)
		(width 0.11684)
		(layer "In6.Cu")
		(net "OCP_SFF_P3V3_P12V_ADC_R_ALERT")
	)
	(segment
		(start 273.85518 -91.187016)
		(end 274.353782 -91.685618)
		(width 0.11684)
		(layer "In6.Cu")
		(net "OCP_SFF_P3V3_P12V_ADC_R_ALERT")
	)
	(segment
		(start 317.646304 -95.367348)
		(end 414.606232 -95.367348)
		(width 0.11684)
		(layer "In6.Cu")
		(net "OCP_SFF_P3V3_P12V_ADC_R_ALERT")
	)
	(segment
		(start 257.23215 -91.685618)
		(end 262.840216 -91.685618)
		(width 0.11684)
		(layer "In6.Cu")
		(net "OCP_SFF_P3V3_P12V_ADC_R_ALERT")
	)
	(segment
		(start 217.947748 -101.73843)
		(end 216.59342 -101.73843)
		(width 0.11684)
		(layer "In6.Cu")
		(net "OCP_SFF_P3V3_P12V_ADC_R_ALERT")
	)
	(segment
		(start 254.575564 -101.778562)
		(end 217.98788 -101.778562)
		(width 0.11684)
		(layer "In6.Cu")
		(net "OCP_SFF_P3V3_P12V_ADC_R_ALERT")
	)
	(segment
		(start 443.05347 -89.601294)
		(end 419.056058 -89.601294)
		(width 0.11684)
		(layer "In15.Cu")
		(net "OCP_SFF_P3V3_P12V_ADC_R_ALERT")
	)
	(segment
		(start 445.863218 -94.602808)
		(end 444.63081 -93.3704)
		(width 0.11684)
		(layer "In15.Cu")
		(net "OCP_SFF_P3V3_P12V_ADC_R_ALERT")
	)
	(segment
		(start 444.63081 -93.3704)
		(end 444.63081 -91.178634)
		(width 0.11684)
		(layer "In15.Cu")
		(net "OCP_SFF_P3V3_P12V_ADC_R_ALERT")
	)
	(segment
		(start 396.50416 -74.064622)
		(end 395.73073 -74.838052)
		(width 0.11684)
		(layer "In15.Cu")
		(net "OCP_SFF_P3V3_P12V_ADC_R_ALERT")
	)
	(segment
		(start 444.63081 -91.178634)
		(end 443.05347 -89.601294)
		(width 0.11684)
		(layer "In15.Cu")
		(net "OCP_SFF_P3V3_P12V_ADC_R_ALERT")
	)
	(segment
		(start 395.73073 -74.838052)
		(end 390.713976 -74.838052)
		(width 0.11684)
		(layer "In15.Cu")
		(net "OCP_SFF_P3V3_P12V_ADC_R_ALERT")
	)
	(segment
		(start 419.056058 -89.601294)
		(end 403.519386 -74.064622)
		(width 0.11684)
		(layer "In15.Cu")
		(net "OCP_SFF_P3V3_P12V_ADC_R_ALERT")
	)
	(segment
		(start 446.260982 -94.602808)
		(end 445.863218 -94.602808)
		(width 0.11684)
		(layer "In15.Cu")
		(net "OCP_SFF_P3V3_P12V_ADC_R_ALERT")
	)
	(segment
		(start 390.713976 -74.838052)
		(end 390.251188 -74.375264)
		(width 0.11684)
		(layer "In15.Cu")
		(net "OCP_SFF_P3V3_P12V_ADC_R_ALERT")
	)
	(segment
		(start 403.519386 -74.064622)
		(end 396.50416 -74.064622)
		(width 0.11684)
		(layer "In15.Cu")
		(net "OCP_SFF_P3V3_P12V_ADC_R_ALERT")
	)
	(segment
		(start 210.085432 -102.958138)
		(end 209.461862 -102.958138)
		(width 0.10668)
		(layer "F.Cu")
		(net "OCP_SFF_P3V3_P12V_ADC_ALERT")
	)
	(segment
		(start 193.511932 -106.262932)
		(end 193.122042 -106.652822)
		(width 0.10668)
		(layer "F.Cu")
		(net "OCP_SFF_P3V3_P12V_ADC_ALERT")
	)
	(via
		(at 193.511932 -106.262932)
		(size 0.4572)
		(drill 0.254)
		(layers "F.Cu" "B.Cu")
		(net "OCP_SFF_P3V3_P12V_ADC_ALERT")
	)
	(via
		(at 209.461862 -102.958138)
		(size 0.508)
		(drill 0.254)
		(layers "F.Cu" "B.Cu")
		(net "OCP_SFF_P3V3_P12V_ADC_ALERT")
	)
	(segment
		(start 201.550524 -102.974648)
		(end 198.738236 -102.974648)
		(width 0.11684)
		(layer "In6.Cu")
		(net "OCP_SFF_P3V3_P12V_ADC_ALERT")
	)
	(segment
		(start 198.29907 -103.413814)
		(end 195.701158 -103.413814)
		(width 0.11684)
		(layer "In6.Cu")
		(net "OCP_SFF_P3V3_P12V_ADC_ALERT")
	)
	(segment
		(start 209.461862 -102.958138)
		(end 208.926176 -103.493824)
		(width 0.11684)
		(layer "In6.Cu")
		(net "OCP_SFF_P3V3_P12V_ADC_ALERT")
	)
	(segment
		(start 208.926176 -103.493824)
		(end 202.0697 -103.493824)
		(width 0.11684)
		(layer "In6.Cu")
		(net "OCP_SFF_P3V3_P12V_ADC_ALERT")
	)
	(segment
		(start 195.701158 -103.413814)
		(end 193.511932 -105.60304)
		(width 0.11684)
		(layer "In6.Cu")
		(net "OCP_SFF_P3V3_P12V_ADC_ALERT")
	)
	(segment
		(start 198.738236 -102.974648)
		(end 198.29907 -103.413814)
		(width 0.11684)
		(layer "In6.Cu")
		(net "OCP_SFF_P3V3_P12V_ADC_ALERT")
	)
	(segment
		(start 193.511932 -105.60304)
		(end 193.511932 -106.262932)
		(width 0.11684)
		(layer "In6.Cu")
		(net "OCP_SFF_P3V3_P12V_ADC_ALERT")
	)
	(segment
		(start 202.0697 -103.493824)
		(end 201.550524 -102.974648)
		(width 0.11684)
		(layer "In6.Cu")
		(net "OCP_SFF_P3V3_P12V_ADC_ALERT")
	)
	(segment
		(start 320.707258 -101.37775)
		(end 320.067178 -101.37775)
		(width 0.10668)
		(layer "F.Cu")
		(net "E1S_0_P3V3_P12V_ADC_R_ALERT")
	)
	(segment
		(start 320.706496 -100.36175)
		(end 320.706496 -101.376988)
		(width 0.10668)
		(layer "F.Cu")
		(net "E1S_0_P3V3_P12V_ADC_R_ALERT")
	)
	(segment
		(start 320.706496 -101.376988)
		(end 320.707258 -101.37775)
		(width 0.10668)
		(layer "F.Cu")
		(net "E1S_0_P3V3_P12V_ADC_R_ALERT")
	)
	(via
		(at 279.273 -80.772)
		(size 0.508)
		(drill 0.254)
		(layers "F.Cu" "B.Cu")
		(net "E1S_0_P3V3_P12V_ADC_R_ALERT")
	)
	(via
		(at 170.944794 -42.931334)
		(size 0.508)
		(drill 0.254)
		(layers "F.Cu" "B.Cu")
		(net "E1S_0_P3V3_P12V_ADC_R_ALERT")
	)
	(via
		(at 215.285574 -58.984388)
		(size 0.508)
		(drill 0.254)
		(layers "F.Cu" "B.Cu")
		(net "E1S_0_P3V3_P12V_ADC_R_ALERT")
	)
	(via
		(at 178.683158 -93.829886)
		(size 0.508)
		(drill 0.254)
		(layers "F.Cu" "B.Cu")
		(net "E1S_0_P3V3_P12V_ADC_R_ALERT")
	)
	(via
		(at 320.067178 -101.37775)
		(size 0.508)
		(drill 0.254)
		(layers "F.Cu" "B.Cu")
		(net "E1S_0_P3V3_P12V_ADC_R_ALERT")
	)
	(segment
		(start 177.180748 -96.775778)
		(end 175.973232 -95.568262)
		(width 0.10668)
		(layer "B.Cu")
		(net "E1S_0_P3V3_P12V_ADC_R_ALERT")
	)
	(segment
		(start 177.180748 -99.402646)
		(end 177.180748 -96.775778)
		(width 0.10668)
		(layer "B.Cu")
		(net "E1S_0_P3V3_P12V_ADC_R_ALERT")
	)
	(segment
		(start 175.973232 -94.501716)
		(end 176.252378 -94.22257)
		(width 0.10668)
		(layer "B.Cu")
		(net "E1S_0_P3V3_P12V_ADC_R_ALERT")
	)
	(segment
		(start 212.542374 -58.984388)
		(end 215.285574 -58.984388)
		(width 0.10668)
		(layer "B.Cu")
		(net "E1S_0_P3V3_P12V_ADC_R_ALERT")
	)
	(segment
		(start 211.69503 -57.478422)
		(end 211.69503 -58.137044)
		(width 0.10668)
		(layer "B.Cu")
		(net "E1S_0_P3V3_P12V_ADC_R_ALERT")
	)
	(segment
		(start 177.81143 -93.829886)
		(end 178.683158 -93.829886)
		(width 0.10668)
		(layer "B.Cu")
		(net "E1S_0_P3V3_P12V_ADC_R_ALERT")
	)
	(segment
		(start 211.69503 -58.137044)
		(end 212.542374 -58.984388)
		(width 0.10668)
		(layer "B.Cu")
		(net "E1S_0_P3V3_P12V_ADC_R_ALERT")
	)
	(segment
		(start 177.418746 -94.22257)
		(end 177.81143 -93.829886)
		(width 0.10668)
		(layer "B.Cu")
		(net "E1S_0_P3V3_P12V_ADC_R_ALERT")
	)
	(segment
		(start 177.673 -99.894898)
		(end 177.180748 -99.402646)
		(width 0.10668)
		(layer "B.Cu")
		(net "E1S_0_P3V3_P12V_ADC_R_ALERT")
	)
	(segment
		(start 175.973232 -95.568262)
		(end 175.973232 -94.501716)
		(width 0.10668)
		(layer "B.Cu")
		(net "E1S_0_P3V3_P12V_ADC_R_ALERT")
	)
	(segment
		(start 176.252378 -94.22257)
		(end 177.418746 -94.22257)
		(width 0.10668)
		(layer "B.Cu")
		(net "E1S_0_P3V3_P12V_ADC_R_ALERT")
	)
	(segment
		(start 279.273 -80.772)
		(end 279.273 -84.836)
		(width 0.11684)
		(layer "In2.Cu")
		(net "E1S_0_P3V3_P12V_ADC_R_ALERT")
	)
	(segment
		(start 279.273 -84.836)
		(end 298.323 -103.886)
		(width 0.11684)
		(layer "In2.Cu")
		(net "E1S_0_P3V3_P12V_ADC_R_ALERT")
	)
	(segment
		(start 311.24525 -101.37775)
		(end 320.067178 -101.37775)
		(width 0.11684)
		(layer "In2.Cu")
		(net "E1S_0_P3V3_P12V_ADC_R_ALERT")
	)
	(segment
		(start 308.737 -103.886)
		(end 311.24525 -101.37775)
		(width 0.11684)
		(layer "In2.Cu")
		(net "E1S_0_P3V3_P12V_ADC_R_ALERT")
	)
	(segment
		(start 298.323 -103.886)
		(end 308.737 -103.886)
		(width 0.11684)
		(layer "In2.Cu")
		(net "E1S_0_P3V3_P12V_ADC_R_ALERT")
	)
	(segment
		(start 279.273 -72.332088)
		(end 272.10766 -65.166748)
		(width 0.11684)
		(layer "In4.Cu")
		(net "E1S_0_P3V3_P12V_ADC_R_ALERT")
	)
	(segment
		(start 247.825768 -70.588378)
		(end 247.094248 -69.856858)
		(width 0.11684)
		(layer "In4.Cu")
		(net "E1S_0_P3V3_P12V_ADC_R_ALERT")
	)
	(segment
		(start 262.298434 -70.336156)
		(end 256.172716 -70.336156)
		(width 0.11684)
		(layer "In4.Cu")
		(net "E1S_0_P3V3_P12V_ADC_R_ALERT")
	)
	(segment
		(start 279.273 -80.772)
		(end 279.273 -72.332088)
		(width 0.11684)
		(layer "In4.Cu")
		(net "E1S_0_P3V3_P12V_ADC_R_ALERT")
	)
	(segment
		(start 228.005386 -63.930784)
		(end 221.323662 -57.24906)
		(width 0.11684)
		(layer "In4.Cu")
		(net "E1S_0_P3V3_P12V_ADC_R_ALERT")
	)
	(segment
		(start 215.285574 -57.613296)
		(end 215.285574 -58.984388)
		(width 0.11684)
		(layer "In4.Cu")
		(net "E1S_0_P3V3_P12V_ADC_R_ALERT")
	)
	(segment
		(start 256.172716 -70.336156)
		(end 255.920494 -70.588378)
		(width 0.11684)
		(layer "In4.Cu")
		(net "E1S_0_P3V3_P12V_ADC_R_ALERT")
	)
	(segment
		(start 267.467842 -65.166748)
		(end 262.298434 -70.336156)
		(width 0.11684)
		(layer "In4.Cu")
		(net "E1S_0_P3V3_P12V_ADC_R_ALERT")
	)
	(segment
		(start 221.323662 -57.24906)
		(end 215.64981 -57.24906)
		(width 0.11684)
		(layer "In4.Cu")
		(net "E1S_0_P3V3_P12V_ADC_R_ALERT")
	)
	(segment
		(start 272.10766 -65.166748)
		(end 267.467842 -65.166748)
		(width 0.11684)
		(layer "In4.Cu")
		(net "E1S_0_P3V3_P12V_ADC_R_ALERT")
	)
	(segment
		(start 238.94923 -69.503798)
		(end 231.661462 -69.503798)
		(width 0.11684)
		(layer "In4.Cu")
		(net "E1S_0_P3V3_P12V_ADC_R_ALERT")
	)
	(segment
		(start 215.64981 -57.24906)
		(end 215.285574 -57.613296)
		(width 0.11684)
		(layer "In4.Cu")
		(net "E1S_0_P3V3_P12V_ADC_R_ALERT")
	)
	(segment
		(start 231.661462 -69.503798)
		(end 228.005386 -65.847722)
		(width 0.11684)
		(layer "In4.Cu")
		(net "E1S_0_P3V3_P12V_ADC_R_ALERT")
	)
	(segment
		(start 228.005386 -65.847722)
		(end 228.005386 -63.930784)
		(width 0.11684)
		(layer "In4.Cu")
		(net "E1S_0_P3V3_P12V_ADC_R_ALERT")
	)
	(segment
		(start 239.30229 -69.856858)
		(end 238.94923 -69.503798)
		(width 0.11684)
		(layer "In4.Cu")
		(net "E1S_0_P3V3_P12V_ADC_R_ALERT")
	)
	(segment
		(start 247.094248 -69.856858)
		(end 239.30229 -69.856858)
		(width 0.11684)
		(layer "In4.Cu")
		(net "E1S_0_P3V3_P12V_ADC_R_ALERT")
	)
	(segment
		(start 255.920494 -70.588378)
		(end 247.825768 -70.588378)
		(width 0.11684)
		(layer "In4.Cu")
		(net "E1S_0_P3V3_P12V_ADC_R_ALERT")
	)
	(segment
		(start 187.963048 -48.5394)
		(end 192.35166 -48.5394)
		(width 0.11684)
		(layer "In6.Cu")
		(net "E1S_0_P3V3_P12V_ADC_R_ALERT")
	)
	(segment
		(start 170.944794 -42.931334)
		(end 170.944794 -42.878248)
		(width 0.11684)
		(layer "In6.Cu")
		(net "E1S_0_P3V3_P12V_ADC_R_ALERT")
	)
	(segment
		(start 192.35166 -48.5394)
		(end 194.371976 -46.519084)
		(width 0.11684)
		(layer "In6.Cu")
		(net "E1S_0_P3V3_P12V_ADC_R_ALERT")
	)
	(segment
		(start 182.043832 -42.620184)
		(end 187.963048 -48.5394)
		(width 0.11684)
		(layer "In6.Cu")
		(net "E1S_0_P3V3_P12V_ADC_R_ALERT")
	)
	(segment
		(start 172.00753 -41.815512)
		(end 179.082192 -41.815512)
		(width 0.11684)
		(layer "In6.Cu")
		(net "E1S_0_P3V3_P12V_ADC_R_ALERT")
	)
	(segment
		(start 215.248998 -48.217074)
		(end 215.248998 -58.947812)
		(width 0.11684)
		(layer "In6.Cu")
		(net "E1S_0_P3V3_P12V_ADC_R_ALERT")
	)
	(segment
		(start 179.886864 -42.620184)
		(end 182.043832 -42.620184)
		(width 0.11684)
		(layer "In6.Cu")
		(net "E1S_0_P3V3_P12V_ADC_R_ALERT")
	)
	(segment
		(start 179.082192 -41.815512)
		(end 179.886864 -42.620184)
		(width 0.11684)
		(layer "In6.Cu")
		(net "E1S_0_P3V3_P12V_ADC_R_ALERT")
	)
	(segment
		(start 194.371976 -46.519084)
		(end 213.551008 -46.519084)
		(width 0.11684)
		(layer "In6.Cu")
		(net "E1S_0_P3V3_P12V_ADC_R_ALERT")
	)
	(segment
		(start 215.248998 -58.947812)
		(end 215.285574 -58.984388)
		(width 0.11684)
		(layer "In6.Cu")
		(net "E1S_0_P3V3_P12V_ADC_R_ALERT")
	)
	(segment
		(start 213.551008 -46.519084)
		(end 215.248998 -48.217074)
		(width 0.11684)
		(layer "In6.Cu")
		(net "E1S_0_P3V3_P12V_ADC_R_ALERT")
	)
	(segment
		(start 170.944794 -42.878248)
		(end 172.00753 -41.815512)
		(width 0.11684)
		(layer "In6.Cu")
		(net "E1S_0_P3V3_P12V_ADC_R_ALERT")
	)
	(segment
		(start 171.35094 -49.390808)
		(end 169.9895 -50.752248)
		(width 0.11684)
		(layer "In11.Cu")
		(net "E1S_0_P3V3_P12V_ADC_R_ALERT")
	)
	(segment
		(start 169.9895 -78.177136)
		(end 178.219862 -86.407498)
		(width 0.11684)
		(layer "In11.Cu")
		(net "E1S_0_P3V3_P12V_ADC_R_ALERT")
	)
	(segment
		(start 169.9895 -50.752248)
		(end 169.9895 -78.177136)
		(width 0.11684)
		(layer "In11.Cu")
		(net "E1S_0_P3V3_P12V_ADC_R_ALERT")
	)
	(segment
		(start 178.219862 -93.36659)
		(end 178.683158 -93.829886)
		(width 0.11684)
		(layer "In11.Cu")
		(net "E1S_0_P3V3_P12V_ADC_R_ALERT")
	)
	(segment
		(start 178.219862 -86.407498)
		(end 178.219862 -93.36659)
		(width 0.11684)
		(layer "In11.Cu")
		(net "E1S_0_P3V3_P12V_ADC_R_ALERT")
	)
	(segment
		(start 170.944794 -42.931334)
		(end 171.35094 -43.33748)
		(width 0.11684)
		(layer "In11.Cu")
		(net "E1S_0_P3V3_P12V_ADC_R_ALERT")
	)
	(segment
		(start 171.35094 -43.33748)
		(end 171.35094 -49.390808)
		(width 0.11684)
		(layer "In11.Cu")
		(net "E1S_0_P3V3_P12V_ADC_R_ALERT")
	)
	(segment
		(start 184.322212 -108.252768)
		(end 183.932322 -107.862878)
		(width 0.10668)
		(layer "F.Cu")
		(net "E1S_0_P3V3_P12V_ADC_ALERT")
	)
	(via
		(at 183.932322 -107.862878)
		(size 0.4572)
		(drill 0.254)
		(layers "F.Cu" "B.Cu")
		(net "E1S_0_P3V3_P12V_ADC_ALERT")
	)
	(via
		(at 179.980336 -102.836472)
		(size 0.508)
		(drill 0.254)
		(layers "F.Cu" "B.Cu")
		(net "E1S_0_P3V3_P12V_ADC_ALERT")
	)
	(segment
		(start 177.673 -101.854)
		(end 178.655472 -102.836472)
		(width 0.10668)
		(layer "B.Cu")
		(net "E1S_0_P3V3_P12V_ADC_ALERT")
	)
	(segment
		(start 178.655472 -102.836472)
		(end 179.980336 -102.836472)
		(width 0.10668)
		(layer "B.Cu")
		(net "E1S_0_P3V3_P12V_ADC_ALERT")
	)
	(segment
		(start 177.673 -100.694998)
		(end 177.673 -101.854)
		(width 0.10668)
		(layer "B.Cu")
		(net "E1S_0_P3V3_P12V_ADC_ALERT")
	)
	(segment
		(start 183.534304 -107.46486)
		(end 183.534304 -106.895392)
		(width 0.11684)
		(layer "In11.Cu")
		(net "E1S_0_P3V3_P12V_ADC_ALERT")
	)
	(segment
		(start 183.932322 -107.862878)
		(end 183.534304 -107.46486)
		(width 0.11684)
		(layer "In11.Cu")
		(net "E1S_0_P3V3_P12V_ADC_ALERT")
	)
	(segment
		(start 183.534304 -106.895392)
		(end 183.29402 -106.655108)
		(width 0.11684)
		(layer "In11.Cu")
		(net "E1S_0_P3V3_P12V_ADC_ALERT")
	)
	(segment
		(start 179.980336 -104.703372)
		(end 179.980336 -102.836472)
		(width 0.11684)
		(layer "In11.Cu")
		(net "E1S_0_P3V3_P12V_ADC_ALERT")
	)
	(segment
		(start 183.29402 -106.655108)
		(end 181.932072 -106.655108)
		(width 0.11684)
		(layer "In11.Cu")
		(net "E1S_0_P3V3_P12V_ADC_ALERT")
	)
	(segment
		(start 181.932072 -106.655108)
		(end 179.980336 -104.703372)
		(width 0.11684)
		(layer "In11.Cu")
		(net "E1S_0_P3V3_P12V_ADC_ALERT")
	)
	(segment
		(start 244.819678 -51.86045)
		(end 245.060978 -52.10175)
		(width 0.254)
		(layer "F.Cu")
		(net "VSENSE_P12V_INA230_8_INP")
	)
	(segment
		(start 325.84517 -105.63479)
		(end 325.84517 -104.708198)
		(width 0.254)
		(layer "F.Cu")
		(net "VSENSE_P12V_INA230_8_INP")
	)
	(segment
		(start 244.819678 -51.546506)
		(end 244.819678 -51.86045)
		(width 0.254)
		(layer "F.Cu")
		(net "VSENSE_P12V_INA230_8_INP")
	)
	(segment
		(start 245.0338 -51.332384)
		(end 244.819678 -51.546506)
		(width 0.254)
		(layer "F.Cu")
		(net "VSENSE_P12V_INA230_8_INP")
	)
	(segment
		(start 244.851174 -50.60696)
		(end 244.851174 -51.149758)
		(width 0.254)
		(layer "F.Cu")
		(net "VSENSE_P12V_INA230_8_INP")
	)
	(segment
		(start 245.1227 -50.335434)
		(end 244.851174 -50.60696)
		(width 0.254)
		(layer "F.Cu")
		(net "VSENSE_P12V_INA230_8_INP")
	)
	(segment
		(start 244.851174 -51.149758)
		(end 245.0338 -51.332384)
		(width 0.254)
		(layer "F.Cu")
		(net "VSENSE_P12V_INA230_8_INP")
	)
	(segment
		(start 327.38568 -107.1753)
		(end 325.84517 -105.63479)
		(width 0.254)
		(layer "F.Cu")
		(net "VSENSE_P12V_INA230_8_INP")
	)
	(segment
		(start 327.495408 -107.1753)
		(end 327.38568 -107.1753)
		(width 0.254)
		(layer "F.Cu")
		(net "VSENSE_P12V_INA230_8_INP")
	)
	(via
		(at 327.495408 -107.1753)
		(size 0.508)
		(drill 0.254)
		(layers "F.Cu" "B.Cu")
		(net "VSENSE_P12V_INA230_8_INP")
	)
	(via
		(at 245.060978 -52.10175)
		(size 0.508)
		(drill 0.254)
		(layers "F.Cu" "B.Cu")
		(net "VSENSE_P12V_INA230_8_INP")
	)
	(segment
		(start 333.265018 -104.836214)
		(end 331.167232 -106.934)
		(width 0.254)
		(layer "B.Cu")
		(net "VSENSE_P12V_INA230_8_INP")
	)
	(segment
		(start 257.859784 -80.734154)
		(end 261.285482 -84.159852)
		(width 0.254)
		(layer "B.Cu")
		(net "VSENSE_P12V_INA230_8_INP")
	)
	(segment
		(start 333.265018 -95.10522)
		(end 333.265018 -104.836214)
		(width 0.254)
		(layer "B.Cu")
		(net "VSENSE_P12V_INA230_8_INP")
	)
	(segment
		(start 245.060978 -52.10175)
		(end 244.856 -52.306728)
		(width 0.254)
		(layer "B.Cu")
		(net "VSENSE_P12V_INA230_8_INP")
	)
	(segment
		(start 254.744474 -69.903848)
		(end 254.744474 -73.644252)
		(width 0.254)
		(layer "B.Cu")
		(net "VSENSE_P12V_INA230_8_INP")
	)
	(segment
		(start 261.285482 -84.159852)
		(end 295.589452 -84.159852)
		(width 0.254)
		(layer "B.Cu")
		(net "VSENSE_P12V_INA230_8_INP")
	)
	(segment
		(start 327.736708 -106.934)
		(end 327.495408 -107.1753)
		(width 0.254)
		(layer "B.Cu")
		(net "VSENSE_P12V_INA230_8_INP")
	)
	(segment
		(start 331.11694 -92.957142)
		(end 333.265018 -95.10522)
		(width 0.254)
		(layer "B.Cu")
		(net "VSENSE_P12V_INA230_8_INP")
	)
	(segment
		(start 254.744474 -73.644252)
		(end 257.859784 -76.759562)
		(width 0.254)
		(layer "B.Cu")
		(net "VSENSE_P12V_INA230_8_INP")
	)
	(segment
		(start 331.167232 -106.934)
		(end 327.736708 -106.934)
		(width 0.254)
		(layer "B.Cu")
		(net "VSENSE_P12V_INA230_8_INP")
	)
	(segment
		(start 244.856 -52.306728)
		(end 244.856 -53.440584)
		(width 0.254)
		(layer "B.Cu")
		(net "VSENSE_P12V_INA230_8_INP")
	)
	(segment
		(start 243.998496 -56.937402)
		(end 251.309378 -64.248284)
		(width 0.254)
		(layer "B.Cu")
		(net "VSENSE_P12V_INA230_8_INP")
	)
	(segment
		(start 257.859784 -76.759562)
		(end 257.859784 -80.734154)
		(width 0.254)
		(layer "B.Cu")
		(net "VSENSE_P12V_INA230_8_INP")
	)
	(segment
		(start 251.309378 -64.248284)
		(end 251.309378 -66.468752)
		(width 0.254)
		(layer "B.Cu")
		(net "VSENSE_P12V_INA230_8_INP")
	)
	(segment
		(start 243.998496 -54.298088)
		(end 243.998496 -56.937402)
		(width 0.254)
		(layer "B.Cu")
		(net "VSENSE_P12V_INA230_8_INP")
	)
	(segment
		(start 251.309378 -66.468752)
		(end 254.744474 -69.903848)
		(width 0.254)
		(layer "B.Cu")
		(net "VSENSE_P12V_INA230_8_INP")
	)
	(segment
		(start 295.589452 -84.159852)
		(end 304.386742 -92.957142)
		(width 0.254)
		(layer "B.Cu")
		(net "VSENSE_P12V_INA230_8_INP")
	)
	(segment
		(start 244.856 -53.440584)
		(end 243.998496 -54.298088)
		(width 0.254)
		(layer "B.Cu")
		(net "VSENSE_P12V_INA230_8_INP")
	)
	(segment
		(start 304.386742 -92.957142)
		(end 331.11694 -92.957142)
		(width 0.254)
		(layer "B.Cu")
		(net "VSENSE_P12V_INA230_8_INP")
	)
	(segment
		(start 326.495156 -105.703116)
		(end 327.10374 -106.3117)
		(width 0.254)
		(layer "F.Cu")
		(net "VSENSE_P12V_INA230_8_INN")
	)
	(segment
		(start 244.470174 -51.09591)
		(end 244.2337 -51.332384)
		(width 0.254)
		(layer "F.Cu")
		(net "VSENSE_P12V_INA230_8_INN")
	)
	(segment
		(start 244.438678 -51.537362)
		(end 244.438678 -51.86045)
		(width 0.254)
		(layer "F.Cu")
		(net "VSENSE_P12V_INA230_8_INN")
	)
	(segment
		(start 326.495156 -104.058212)
		(end 326.495156 -105.703116)
		(width 0.254)
		(layer "F.Cu")
		(net "VSENSE_P12V_INA230_8_INN")
	)
	(segment
		(start 244.438678 -51.86045)
		(end 244.197378 -52.10175)
		(width 0.254)
		(layer "F.Cu")
		(net "VSENSE_P12V_INA230_8_INN")
	)
	(segment
		(start 327.10374 -106.3117)
		(end 327.495408 -106.3117)
		(width 0.254)
		(layer "F.Cu")
		(net "VSENSE_P12V_INA230_8_INN")
	)
	(segment
		(start 244.1448 -50.335434)
		(end 244.470174 -50.660808)
		(width 0.254)
		(layer "F.Cu")
		(net "VSENSE_P12V_INA230_8_INN")
	)
	(segment
		(start 244.470174 -50.660808)
		(end 244.470174 -51.09591)
		(width 0.254)
		(layer "F.Cu")
		(net "VSENSE_P12V_INA230_8_INN")
	)
	(segment
		(start 244.2337 -51.332384)
		(end 244.438678 -51.537362)
		(width 0.254)
		(layer "F.Cu")
		(net "VSENSE_P12V_INA230_8_INN")
	)
	(via
		(at 244.197378 -52.10175)
		(size 0.508)
		(drill 0.254)
		(layers "F.Cu" "B.Cu")
		(net "VSENSE_P12V_INA230_8_INN")
	)
	(via
		(at 327.495408 -106.3117)
		(size 0.508)
		(drill 0.254)
		(layers "F.Cu" "B.Cu")
		(net "VSENSE_P12V_INA230_8_INN")
	)
	(segment
		(start 243.617496 -54.1401)
		(end 243.617496 -57.09539)
		(width 0.254)
		(layer "B.Cu")
		(net "VSENSE_P12V_INA230_8_INN")
	)
	(segment
		(start 261.127494 -84.540852)
		(end 295.431464 -84.540852)
		(width 0.254)
		(layer "B.Cu")
		(net "VSENSE_P12V_INA230_8_INN")
	)
	(segment
		(start 332.884018 -95.263208)
		(end 332.884018 -104.678226)
		(width 0.254)
		(layer "B.Cu")
		(net "VSENSE_P12V_INA230_8_INN")
	)
	(segment
		(start 250.928378 -64.406272)
		(end 250.928378 -66.62674)
		(width 0.254)
		(layer "B.Cu")
		(net "VSENSE_P12V_INA230_8_INN")
	)
	(segment
		(start 330.958952 -93.338142)
		(end 332.884018 -95.263208)
		(width 0.254)
		(layer "B.Cu")
		(net "VSENSE_P12V_INA230_8_INN")
	)
	(segment
		(start 257.478784 -80.892142)
		(end 261.127494 -84.540852)
		(width 0.254)
		(layer "B.Cu")
		(net "VSENSE_P12V_INA230_8_INN")
	)
	(segment
		(start 327.736708 -106.553)
		(end 327.495408 -106.3117)
		(width 0.254)
		(layer "B.Cu")
		(net "VSENSE_P12V_INA230_8_INN")
	)
	(segment
		(start 257.478784 -76.91755)
		(end 257.478784 -80.892142)
		(width 0.254)
		(layer "B.Cu")
		(net "VSENSE_P12V_INA230_8_INN")
	)
	(segment
		(start 331.009244 -106.553)
		(end 327.736708 -106.553)
		(width 0.254)
		(layer "B.Cu")
		(net "VSENSE_P12V_INA230_8_INN")
	)
	(segment
		(start 254.363474 -73.80224)
		(end 257.478784 -76.91755)
		(width 0.254)
		(layer "B.Cu")
		(net "VSENSE_P12V_INA230_8_INN")
	)
	(segment
		(start 332.884018 -104.678226)
		(end 331.009244 -106.553)
		(width 0.254)
		(layer "B.Cu")
		(net "VSENSE_P12V_INA230_8_INN")
	)
	(segment
		(start 243.617496 -57.09539)
		(end 250.928378 -64.406272)
		(width 0.254)
		(layer "B.Cu")
		(net "VSENSE_P12V_INA230_8_INN")
	)
	(segment
		(start 295.431464 -84.540852)
		(end 304.228754 -93.338142)
		(width 0.254)
		(layer "B.Cu")
		(net "VSENSE_P12V_INA230_8_INN")
	)
	(segment
		(start 304.228754 -93.338142)
		(end 330.958952 -93.338142)
		(width 0.254)
		(layer "B.Cu")
		(net "VSENSE_P12V_INA230_8_INN")
	)
	(segment
		(start 254.363474 -70.061836)
		(end 254.363474 -73.80224)
		(width 0.254)
		(layer "B.Cu")
		(net "VSENSE_P12V_INA230_8_INN")
	)
	(segment
		(start 244.475 -53.282596)
		(end 243.617496 -54.1401)
		(width 0.254)
		(layer "B.Cu")
		(net "VSENSE_P12V_INA230_8_INN")
	)
	(segment
		(start 244.197378 -52.10175)
		(end 244.475 -52.379372)
		(width 0.254)
		(layer "B.Cu")
		(net "VSENSE_P12V_INA230_8_INN")
	)
	(segment
		(start 244.475 -52.379372)
		(end 244.475 -53.282596)
		(width 0.254)
		(layer "B.Cu")
		(net "VSENSE_P12V_INA230_8_INN")
	)
	(segment
		(start 250.928378 -66.62674)
		(end 254.363474 -70.061836)
		(width 0.254)
		(layer "B.Cu")
		(net "VSENSE_P12V_INA230_8_INN")
	)
	(segment
		(start 23.979378 -41.488106)
		(end 23.979378 -41.224962)
		(width 0.254)
		(layer "F.Cu")
		(net "VSENSE_P12V_INA230_7_INP")
	)
	(segment
		(start 70.564248 -19.20367)
		(end 70.564248 -19.746468)
		(width 0.254)
		(layer "F.Cu")
		(net "VSENSE_P12V_INA230_7_INP")
	)
	(segment
		(start 70.532752 -20.143216)
		(end 70.532752 -20.846796)
		(width 0.254)
		(layer "F.Cu")
		(net "VSENSE_P12V_INA230_7_INP")
	)
	(segment
		(start 70.746874 -19.929094)
		(end 70.532752 -20.143216)
		(width 0.254)
		(layer "F.Cu")
		(net "VSENSE_P12V_INA230_7_INP")
	)
	(segment
		(start 70.532752 -20.846796)
		(end 70.774052 -21.088096)
		(width 0.254)
		(layer "F.Cu")
		(net "VSENSE_P12V_INA230_7_INP")
	)
	(segment
		(start 70.564248 -19.746468)
		(end 70.746874 -19.929094)
		(width 0.254)
		(layer "F.Cu")
		(net "VSENSE_P12V_INA230_7_INP")
	)
	(segment
		(start 70.835774 -18.932144)
		(end 70.564248 -19.20367)
		(width 0.254)
		(layer "F.Cu")
		(net "VSENSE_P12V_INA230_7_INP")
	)
	(segment
		(start 25.607772 -42.902124)
		(end 25.393396 -42.902124)
		(width 0.254)
		(layer "F.Cu")
		(net "VSENSE_P12V_INA230_7_INP")
	)
	(segment
		(start 25.393396 -42.902124)
		(end 23.979378 -41.488106)
		(width 0.254)
		(layer "F.Cu")
		(net "VSENSE_P12V_INA230_7_INP")
	)
	(via
		(at 70.774052 -21.088096)
		(size 0.508)
		(drill 0.254)
		(layers "F.Cu" "B.Cu")
		(net "VSENSE_P12V_INA230_7_INP")
	)
	(via
		(at 25.607772 -42.902124)
		(size 0.508)
		(drill 0.254)
		(layers "F.Cu" "B.Cu")
		(net "VSENSE_P12V_INA230_7_INP")
	)
	(segment
		(start 33.373822 -42.660824)
		(end 53.672994 -22.361652)
		(width 0.254)
		(layer "In6.Cu")
		(net "VSENSE_P12V_INA230_7_INP")
	)
	(segment
		(start 53.672994 -22.361652)
		(end 64.260984 -22.361652)
		(width 0.254)
		(layer "In6.Cu")
		(net "VSENSE_P12V_INA230_7_INP")
	)
	(segment
		(start 70.532752 -22.459188)
		(end 70.532752 -21.329396)
		(width 0.254)
		(layer "In6.Cu")
		(net "VSENSE_P12V_INA230_7_INP")
	)
	(segment
		(start 25.849072 -42.660824)
		(end 33.373822 -42.660824)
		(width 0.254)
		(layer "In6.Cu")
		(net "VSENSE_P12V_INA230_7_INP")
	)
	(segment
		(start 70.05574 -22.9362)
		(end 70.532752 -22.459188)
		(width 0.254)
		(layer "In6.Cu")
		(net "VSENSE_P12V_INA230_7_INP")
	)
	(segment
		(start 70.532752 -21.329396)
		(end 70.774052 -21.088096)
		(width 0.254)
		(layer "In6.Cu")
		(net "VSENSE_P12V_INA230_7_INP")
	)
	(segment
		(start 65.578482 -23.67915)
		(end 68.154042 -23.67915)
		(width 0.254)
		(layer "In6.Cu")
		(net "VSENSE_P12V_INA230_7_INP")
	)
	(segment
		(start 64.260984 -22.361652)
		(end 65.578482 -23.67915)
		(width 0.254)
		(layer "In6.Cu")
		(net "VSENSE_P12V_INA230_7_INP")
	)
	(segment
		(start 68.154042 -23.67915)
		(end 68.896992 -22.9362)
		(width 0.254)
		(layer "In6.Cu")
		(net "VSENSE_P12V_INA230_7_INP")
	)
	(segment
		(start 25.607772 -42.902124)
		(end 25.849072 -42.660824)
		(width 0.254)
		(layer "In6.Cu")
		(net "VSENSE_P12V_INA230_7_INP")
	)
	(segment
		(start 68.896992 -22.9362)
		(end 70.05574 -22.9362)
		(width 0.254)
		(layer "In6.Cu")
		(net "VSENSE_P12V_INA230_7_INP")
	)
	(segment
		(start 70.151752 -20.134072)
		(end 70.151752 -20.846796)
		(width 0.254)
		(layer "F.Cu")
		(net "VSENSE_P12V_INA230_7_INN")
	)
	(segment
		(start 25.110948 -42.038524)
		(end 25.607772 -42.038524)
		(width 0.254)
		(layer "F.Cu")
		(net "VSENSE_P12V_INA230_7_INN")
	)
	(segment
		(start 70.151752 -20.846796)
		(end 69.910452 -21.088096)
		(width 0.254)
		(layer "F.Cu")
		(net "VSENSE_P12V_INA230_7_INN")
	)
	(segment
		(start 70.183248 -19.257518)
		(end 70.183248 -19.69262)
		(width 0.254)
		(layer "F.Cu")
		(net "VSENSE_P12V_INA230_7_INN")
	)
	(segment
		(start 69.946774 -19.929094)
		(end 70.151752 -20.134072)
		(width 0.254)
		(layer "F.Cu")
		(net "VSENSE_P12V_INA230_7_INN")
	)
	(segment
		(start 70.183248 -19.69262)
		(end 69.946774 -19.929094)
		(width 0.254)
		(layer "F.Cu")
		(net "VSENSE_P12V_INA230_7_INN")
	)
	(segment
		(start 24.629364 -40.574976)
		(end 24.629364 -41.55694)
		(width 0.254)
		(layer "F.Cu")
		(net "VSENSE_P12V_INA230_7_INN")
	)
	(segment
		(start 69.857874 -18.932144)
		(end 70.183248 -19.257518)
		(width 0.254)
		(layer "F.Cu")
		(net "VSENSE_P12V_INA230_7_INN")
	)
	(segment
		(start 24.629364 -41.55694)
		(end 25.110948 -42.038524)
		(width 0.254)
		(layer "F.Cu")
		(net "VSENSE_P12V_INA230_7_INN")
	)
	(via
		(at 69.910452 -21.088096)
		(size 0.508)
		(drill 0.254)
		(layers "F.Cu" "B.Cu")
		(net "VSENSE_P12V_INA230_7_INN")
	)
	(via
		(at 25.607772 -42.038524)
		(size 0.762)
		(drill 0.254)
		(layers "F.Cu" "B.Cu")
		(net "VSENSE_P12V_INA230_7_INN")
	)
	(segment
		(start 25.849072 -42.279824)
		(end 33.215834 -42.279824)
		(width 0.254)
		(layer "In6.Cu")
		(net "VSENSE_P12V_INA230_7_INN")
	)
	(segment
		(start 67.996054 -23.29815)
		(end 68.739004 -22.5552)
		(width 0.254)
		(layer "In6.Cu")
		(net "VSENSE_P12V_INA230_7_INN")
	)
	(segment
		(start 70.151752 -22.3012)
		(end 70.151752 -21.329396)
		(width 0.254)
		(layer "In6.Cu")
		(net "VSENSE_P12V_INA230_7_INN")
	)
	(segment
		(start 25.607772 -42.038524)
		(end 25.849072 -42.279824)
		(width 0.254)
		(layer "In6.Cu")
		(net "VSENSE_P12V_INA230_7_INN")
	)
	(segment
		(start 64.418972 -21.980652)
		(end 65.73647 -23.29815)
		(width 0.254)
		(layer "In6.Cu")
		(net "VSENSE_P12V_INA230_7_INN")
	)
	(segment
		(start 70.151752 -21.329396)
		(end 69.910452 -21.088096)
		(width 0.254)
		(layer "In6.Cu")
		(net "VSENSE_P12V_INA230_7_INN")
	)
	(segment
		(start 68.739004 -22.5552)
		(end 69.897752 -22.5552)
		(width 0.254)
		(layer "In6.Cu")
		(net "VSENSE_P12V_INA230_7_INN")
	)
	(segment
		(start 53.515006 -21.980652)
		(end 64.418972 -21.980652)
		(width 0.254)
		(layer "In6.Cu")
		(net "VSENSE_P12V_INA230_7_INN")
	)
	(segment
		(start 33.215834 -42.279824)
		(end 53.515006 -21.980652)
		(width 0.254)
		(layer "In6.Cu")
		(net "VSENSE_P12V_INA230_7_INN")
	)
	(segment
		(start 65.73647 -23.29815)
		(end 67.996054 -23.29815)
		(width 0.254)
		(layer "In6.Cu")
		(net "VSENSE_P12V_INA230_7_INN")
	)
	(segment
		(start 69.897752 -22.5552)
		(end 70.151752 -22.3012)
		(width 0.254)
		(layer "In6.Cu")
		(net "VSENSE_P12V_INA230_7_INN")
	)
	(segment
		(start 442.605414 -22.887178)
		(end 442.605414 -23.336758)
		(width 0.254)
		(layer "F.Cu")
		(net "VSENSE_P12V_INA230_6_INP")
	)
	(segment
		(start 396.02918 -77.999844)
		(end 396.02918 -77.705712)
		(width 0.254)
		(layer "F.Cu")
		(net "VSENSE_P12V_INA230_6_INP")
	)
	(segment
		(start 396.695168 -78.665832)
		(end 396.02918 -77.999844)
		(width 0.254)
		(layer "F.Cu")
		(net "VSENSE_P12V_INA230_6_INP")
	)
	(segment
		(start 442.63691 -22.49043)
		(end 442.819536 -22.673056)
		(width 0.254)
		(layer "F.Cu")
		(net "VSENSE_P12V_INA230_6_INP")
	)
	(segment
		(start 442.819536 -22.673056)
		(end 442.605414 -22.887178)
		(width 0.254)
		(layer "F.Cu")
		(net "VSENSE_P12V_INA230_6_INP")
	)
	(segment
		(start 396.695168 -78.99908)
		(end 396.695168 -78.665832)
		(width 0.254)
		(layer "F.Cu")
		(net "VSENSE_P12V_INA230_6_INP")
	)
	(segment
		(start 442.605414 -23.336758)
		(end 442.846714 -23.578058)
		(width 0.254)
		(layer "F.Cu")
		(net "VSENSE_P12V_INA230_6_INP")
	)
	(segment
		(start 397.384524 -79.688436)
		(end 396.695168 -78.99908)
		(width 0.254)
		(layer "F.Cu")
		(net "VSENSE_P12V_INA230_6_INP")
	)
	(segment
		(start 442.63691 -21.947632)
		(end 442.63691 -22.49043)
		(width 0.254)
		(layer "F.Cu")
		(net "VSENSE_P12V_INA230_6_INP")
	)
	(segment
		(start 442.908436 -21.676106)
		(end 442.63691 -21.947632)
		(width 0.254)
		(layer "F.Cu")
		(net "VSENSE_P12V_INA230_6_INP")
	)
	(via
		(at 397.384524 -79.688436)
		(size 0.508)
		(drill 0.254)
		(layers "F.Cu" "B.Cu")
		(net "VSENSE_P12V_INA230_6_INP")
	)
	(via
		(at 442.846714 -23.578058)
		(size 0.508)
		(drill 0.254)
		(layers "F.Cu" "B.Cu")
		(net "VSENSE_P12V_INA230_6_INP")
	)
	(segment
		(start 409.598368 -61.9506)
		(end 400.849084 -70.699884)
		(width 0.254)
		(layer "B.Cu")
		(net "VSENSE_P12V_INA230_6_INP")
	)
	(segment
		(start 439.600848 -25.037034)
		(end 426.080682 -25.037034)
		(width 0.254)
		(layer "B.Cu")
		(net "VSENSE_P12V_INA230_6_INP")
	)
	(segment
		(start 400.849084 -77.445362)
		(end 398.853406 -79.44104)
		(width 0.254)
		(layer "B.Cu")
		(net "VSENSE_P12V_INA230_6_INP")
	)
	(segment
		(start 397.63192 -79.44104)
		(end 397.384524 -79.688436)
		(width 0.254)
		(layer "B.Cu")
		(net "VSENSE_P12V_INA230_6_INP")
	)
	(segment
		(start 442.846714 -23.578058)
		(end 442.608716 -23.816056)
		(width 0.254)
		(layer "B.Cu")
		(net "VSENSE_P12V_INA230_6_INP")
	)
	(segment
		(start 439.873136 -24.764746)
		(end 439.600848 -25.037034)
		(width 0.254)
		(layer "B.Cu")
		(net "VSENSE_P12V_INA230_6_INP")
	)
	(segment
		(start 426.080682 -25.037034)
		(end 421.37076 -29.746956)
		(width 0.254)
		(layer "B.Cu")
		(net "VSENSE_P12V_INA230_6_INP")
	)
	(segment
		(start 442.608716 -23.816056)
		(end 442.608716 -24.274526)
		(width 0.254)
		(layer "B.Cu")
		(net "VSENSE_P12V_INA230_6_INP")
	)
	(segment
		(start 421.37076 -29.746956)
		(end 421.37076 -43.649138)
		(width 0.254)
		(layer "B.Cu")
		(net "VSENSE_P12V_INA230_6_INP")
	)
	(segment
		(start 442.118496 -24.764746)
		(end 439.873136 -24.764746)
		(width 0.254)
		(layer "B.Cu")
		(net "VSENSE_P12V_INA230_6_INP")
	)
	(segment
		(start 398.853406 -79.44104)
		(end 397.63192 -79.44104)
		(width 0.254)
		(layer "B.Cu")
		(net "VSENSE_P12V_INA230_6_INP")
	)
	(segment
		(start 442.608716 -24.274526)
		(end 442.118496 -24.764746)
		(width 0.254)
		(layer "B.Cu")
		(net "VSENSE_P12V_INA230_6_INP")
	)
	(segment
		(start 409.598368 -55.42153)
		(end 409.598368 -61.9506)
		(width 0.254)
		(layer "B.Cu")
		(net "VSENSE_P12V_INA230_6_INP")
	)
	(segment
		(start 400.849084 -70.699884)
		(end 400.849084 -77.445362)
		(width 0.254)
		(layer "B.Cu")
		(net "VSENSE_P12V_INA230_6_INP")
	)
	(segment
		(start 421.37076 -43.649138)
		(end 409.598368 -55.42153)
		(width 0.254)
		(layer "B.Cu")
		(net "VSENSE_P12V_INA230_6_INP")
	)
	(segment
		(start 397.384524 -78.824836)
		(end 397.384524 -78.8162)
		(width 0.254)
		(layer "F.Cu")
		(net "VSENSE_P12V_INA230_6_INN")
	)
	(segment
		(start 396.957804 -78.38948)
		(end 396.957804 -77.182726)
		(width 0.254)
		(layer "F.Cu")
		(net "VSENSE_P12V_INA230_6_INN")
	)
	(segment
		(start 396.830804 -77.055726)
		(end 396.679166 -77.055726)
		(width 0.254)
		(layer "F.Cu")
		(net "VSENSE_P12V_INA230_6_INN")
	)
	(segment
		(start 396.957804 -77.182726)
		(end 396.830804 -77.055726)
		(width 0.254)
		(layer "F.Cu")
		(net "VSENSE_P12V_INA230_6_INN")
	)
	(segment
		(start 442.224414 -22.878034)
		(end 442.019436 -22.673056)
		(width 0.254)
		(layer "F.Cu")
		(net "VSENSE_P12V_INA230_6_INN")
	)
	(segment
		(start 442.224414 -23.336758)
		(end 442.224414 -22.878034)
		(width 0.254)
		(layer "F.Cu")
		(net "VSENSE_P12V_INA230_6_INN")
	)
	(segment
		(start 397.384524 -78.8162)
		(end 396.957804 -78.38948)
		(width 0.254)
		(layer "F.Cu")
		(net "VSENSE_P12V_INA230_6_INN")
	)
	(segment
		(start 442.25591 -22.00148)
		(end 442.25591 -22.436582)
		(width 0.254)
		(layer "F.Cu")
		(net "VSENSE_P12V_INA230_6_INN")
	)
	(segment
		(start 441.930536 -21.676106)
		(end 442.25591 -22.00148)
		(width 0.254)
		(layer "F.Cu")
		(net "VSENSE_P12V_INA230_6_INN")
	)
	(segment
		(start 442.25591 -22.436582)
		(end 442.019436 -22.673056)
		(width 0.254)
		(layer "F.Cu")
		(net "VSENSE_P12V_INA230_6_INN")
	)
	(segment
		(start 441.983114 -23.578058)
		(end 442.224414 -23.336758)
		(width 0.254)
		(layer "F.Cu")
		(net "VSENSE_P12V_INA230_6_INN")
	)
	(via
		(at 441.983114 -23.578058)
		(size 0.508)
		(drill 0.254)
		(layers "F.Cu" "B.Cu")
		(net "VSENSE_P12V_INA230_6_INN")
	)
	(via
		(at 397.384524 -78.824836)
		(size 0.508)
		(drill 0.254)
		(layers "F.Cu" "B.Cu")
		(net "VSENSE_P12V_INA230_6_INN")
	)
	(segment
		(start 439.44286 -24.656034)
		(end 425.922694 -24.656034)
		(width 0.254)
		(layer "B.Cu")
		(net "VSENSE_P12V_INA230_6_INN")
	)
	(segment
		(start 442.227716 -24.116538)
		(end 441.960508 -24.383746)
		(width 0.254)
		(layer "B.Cu")
		(net "VSENSE_P12V_INA230_6_INN")
	)
	(segment
		(start 439.715148 -24.383746)
		(end 439.44286 -24.656034)
		(width 0.254)
		(layer "B.Cu")
		(net "VSENSE_P12V_INA230_6_INN")
	)
	(segment
		(start 441.983114 -23.578058)
		(end 442.227716 -23.82266)
		(width 0.254)
		(layer "B.Cu")
		(net "VSENSE_P12V_INA230_6_INN")
	)
	(segment
		(start 420.98976 -43.49115)
		(end 409.217368 -55.263542)
		(width 0.254)
		(layer "B.Cu")
		(net "VSENSE_P12V_INA230_6_INN")
	)
	(segment
		(start 425.922694 -24.656034)
		(end 420.98976 -29.588968)
		(width 0.254)
		(layer "B.Cu")
		(net "VSENSE_P12V_INA230_6_INN")
	)
	(segment
		(start 398.695418 -79.06004)
		(end 397.619728 -79.06004)
		(width 0.254)
		(layer "B.Cu")
		(net "VSENSE_P12V_INA230_6_INN")
	)
	(segment
		(start 397.619728 -79.06004)
		(end 397.384524 -78.824836)
		(width 0.254)
		(layer "B.Cu")
		(net "VSENSE_P12V_INA230_6_INN")
	)
	(segment
		(start 409.217368 -55.263542)
		(end 409.217368 -61.792612)
		(width 0.254)
		(layer "B.Cu")
		(net "VSENSE_P12V_INA230_6_INN")
	)
	(segment
		(start 420.98976 -29.588968)
		(end 420.98976 -43.49115)
		(width 0.254)
		(layer "B.Cu")
		(net "VSENSE_P12V_INA230_6_INN")
	)
	(segment
		(start 400.468084 -70.541896)
		(end 400.468084 -77.287374)
		(width 0.254)
		(layer "B.Cu")
		(net "VSENSE_P12V_INA230_6_INN")
	)
	(segment
		(start 409.217368 -61.792612)
		(end 400.468084 -70.541896)
		(width 0.254)
		(layer "B.Cu")
		(net "VSENSE_P12V_INA230_6_INN")
	)
	(segment
		(start 441.960508 -24.383746)
		(end 439.715148 -24.383746)
		(width 0.254)
		(layer "B.Cu")
		(net "VSENSE_P12V_INA230_6_INN")
	)
	(segment
		(start 442.227716 -23.82266)
		(end 442.227716 -24.116538)
		(width 0.254)
		(layer "B.Cu")
		(net "VSENSE_P12V_INA230_6_INN")
	)
	(segment
		(start 400.468084 -77.287374)
		(end 398.695418 -79.06004)
		(width 0.254)
		(layer "B.Cu")
		(net "VSENSE_P12V_INA230_6_INN")
	)
	(via
		(at 220.888052 -329.957176)
		(size 0.6604)
		(drill 0.3302)
		(layers "F.Cu" "B.Cu")
		(net "TP_ADC128_2_INT")
	)
	(segment
		(start 219.608146 -327.509378)
		(end 220.761052 -327.509378)
		(width 0.10668)
		(layer "B.Cu")
		(net "TP_ADC128_2_INT")
	)
	(segment
		(start 220.761052 -327.509378)
		(end 220.888052 -327.636378)
		(width 0.10668)
		(layer "B.Cu")
		(net "TP_ADC128_2_INT")
	)
	(segment
		(start 220.888052 -327.636378)
		(end 220.888052 -329.957176)
		(width 0.10668)
		(layer "B.Cu")
		(net "TP_ADC128_2_INT")
	)
	(via
		(at 217.506042 -323.98462)
		(size 0.6604)
		(drill 0.3302)
		(layers "F.Cu" "B.Cu")
		(net "SMB_SEN_TIC_2_3V3AUX_SDA")
	)
	(segment
		(start 217.110056 -323.588634)
		(end 217.506042 -323.98462)
		(width 0.10668)
		(layer "B.Cu")
		(net "SMB_SEN_TIC_2_3V3AUX_SDA")
	)
	(segment
		(start 217.506042 -323.98462)
		(end 218.430602 -324.90918)
		(width 0.10668)
		(layer "B.Cu")
		(net "SMB_SEN_TIC_2_3V3AUX_SDA")
	)
	(segment
		(start 216.523824 -323.588634)
		(end 217.110056 -323.588634)
		(width 0.10668)
		(layer "B.Cu")
		(net "SMB_SEN_TIC_2_3V3AUX_SDA")
	)
	(segment
		(start 218.430602 -324.90918)
		(end 219.608146 -324.90918)
		(width 0.10668)
		(layer "B.Cu")
		(net "SMB_SEN_TIC_2_3V3AUX_SDA")
	)
	(via
		(at 217.298016 -325.559166)
		(size 0.6604)
		(drill 0.3302)
		(layers "F.Cu" "B.Cu")
		(net "SMB_SEN_TIC_2_3V3AUX_SCL")
	)
	(segment
		(start 216.629234 -325.559166)
		(end 217.298016 -325.559166)
		(width 0.10668)
		(layer "B.Cu")
		(net "SMB_SEN_TIC_2_3V3AUX_SCL")
	)
	(segment
		(start 216.50198 -325.431912)
		(end 216.629234 -325.559166)
		(width 0.10668)
		(layer "B.Cu")
		(net "SMB_SEN_TIC_2_3V3AUX_SCL")
	)
	(segment
		(start 216.50198 -324.647306)
		(end 216.50198 -325.431912)
		(width 0.10668)
		(layer "B.Cu")
		(net "SMB_SEN_TIC_2_3V3AUX_SCL")
	)
	(segment
		(start 217.298016 -325.559166)
		(end 219.608146 -325.559166)
		(width 0.10668)
		(layer "B.Cu")
		(net "SMB_SEN_TIC_2_3V3AUX_SCL")
	)
	(via
		(at 244.971316 -326.998584)
		(size 0.6604)
		(drill 0.3302)
		(layers "F.Cu" "B.Cu")
		(net "SMB_SEN_MAM_2_3V3AUX_SDA")
	)
	(segment
		(start 245.041928 -327.069196)
		(end 245.378224 -327.069196)
		(width 0.10668)
		(layer "B.Cu")
		(net "SMB_SEN_MAM_2_3V3AUX_SDA")
	)
	(segment
		(start 245.378224 -327.069196)
		(end 245.881398 -326.566022)
		(width 0.10668)
		(layer "B.Cu")
		(net "SMB_SEN_MAM_2_3V3AUX_SDA")
	)
	(segment
		(start 244.870732 -326.898)
		(end 244.971316 -326.998584)
		(width 0.10668)
		(layer "B.Cu")
		(net "SMB_SEN_MAM_2_3V3AUX_SDA")
	)
	(segment
		(start 244.971316 -326.998584)
		(end 245.041928 -327.069196)
		(width 0.10668)
		(layer "B.Cu")
		(net "SMB_SEN_MAM_2_3V3AUX_SDA")
	)
	(segment
		(start 244.11305 -326.898)
		(end 244.870732 -326.898)
		(width 0.10668)
		(layer "B.Cu")
		(net "SMB_SEN_MAM_2_3V3AUX_SDA")
	)
	(segment
		(start 245.881398 -326.566022)
		(end 247.249442 -326.566022)
		(width 0.10668)
		(layer "B.Cu")
		(net "SMB_SEN_MAM_2_3V3AUX_SDA")
	)
	(via
		(at 245.508526 -325.674228)
		(size 0.6604)
		(drill 0.3302)
		(layers "F.Cu" "B.Cu")
		(net "SMB_SEN_MAM_2_3V3AUX_SCL")
	)
	(segment
		(start 244.922294 -325.674228)
		(end 244.714522 -325.882)
		(width 0.10668)
		(layer "B.Cu")
		(net "SMB_SEN_MAM_2_3V3AUX_SCL")
	)
	(segment
		(start 246.30761 -325.931022)
		(end 246.050816 -325.674228)
		(width 0.10668)
		(layer "B.Cu")
		(net "SMB_SEN_MAM_2_3V3AUX_SCL")
	)
	(segment
		(start 244.714522 -325.882)
		(end 244.11305 -325.882)
		(width 0.10668)
		(layer "B.Cu")
		(net "SMB_SEN_MAM_2_3V3AUX_SCL")
	)
	(segment
		(start 245.508526 -325.674228)
		(end 244.922294 -325.674228)
		(width 0.10668)
		(layer "B.Cu")
		(net "SMB_SEN_MAM_2_3V3AUX_SCL")
	)
	(segment
		(start 247.249442 -325.931022)
		(end 246.30761 -325.931022)
		(width 0.10668)
		(layer "B.Cu")
		(net "SMB_SEN_MAM_2_3V3AUX_SCL")
	)
	(segment
		(start 246.050816 -325.674228)
		(end 245.508526 -325.674228)
		(width 0.10668)
		(layer "B.Cu")
		(net "SMB_SEN_MAM_2_3V3AUX_SCL")
	)
	(via
		(at 222.259906 -357.440484)
		(size 0.508)
		(drill 0.254)
		(layers "F.Cu" "B.Cu")
		(net "SMB_RT_CPU1_P3_ROM_MUX_2D_SDA")
	)
	(via
		(at 166.543482 -422.709848)
		(size 0.508)
		(drill 0.254)
		(layers "F.Cu" "B.Cu")
		(net "SMB_RT_CPU1_P3_ROM_MUX_2D_SDA")
	)
	(via
		(at 175.142652 -362.576618)
		(size 0.508)
		(drill 0.254)
		(layers "F.Cu" "B.Cu")
		(net "SMB_RT_CPU1_P3_ROM_MUX_2D_SDA")
	)
	(via
		(at 168.079674 -396.515082)
		(size 0.508)
		(drill 0.254)
		(layers "F.Cu" "B.Cu")
		(net "SMB_RT_CPU1_P3_ROM_MUX_2D_SDA")
	)
	(via
		(at 236.324394 -342.242394)
		(size 0.6604)
		(drill 0.3302)
		(layers "F.Cu" "B.Cu")
		(net "SMB_RT_CPU1_P3_ROM_MUX_2D_SDA")
	)
	(segment
		(start 167.696388 -423.405554)
		(end 167.452548 -423.161714)
		(width 0.10668)
		(layer "B.Cu")
		(net "SMB_RT_CPU1_P3_ROM_MUX_2D_SDA")
	)
	(segment
		(start 236.324394 -339.024976)
		(end 236.324394 -342.242394)
		(width 0.10668)
		(layer "B.Cu")
		(net "SMB_RT_CPU1_P3_ROM_MUX_2D_SDA")
	)
	(segment
		(start 236.89437 -338.455)
		(end 236.324394 -339.024976)
		(width 0.10668)
		(layer "B.Cu")
		(net "SMB_RT_CPU1_P3_ROM_MUX_2D_SDA")
	)
	(segment
		(start 222.259906 -356.306882)
		(end 222.259906 -357.440484)
		(width 0.10668)
		(layer "B.Cu")
		(net "SMB_RT_CPU1_P3_ROM_MUX_2D_SDA")
	)
	(segment
		(start 238.3663 -338.455)
		(end 236.89437 -338.455)
		(width 0.10668)
		(layer "B.Cu")
		(net "SMB_RT_CPU1_P3_ROM_MUX_2D_SDA")
	)
	(segment
		(start 166.995348 -423.161714)
		(end 166.543482 -422.709848)
		(width 0.10668)
		(layer "B.Cu")
		(net "SMB_RT_CPU1_P3_ROM_MUX_2D_SDA")
	)
	(segment
		(start 167.452548 -423.161714)
		(end 166.995348 -423.161714)
		(width 0.10668)
		(layer "B.Cu")
		(net "SMB_RT_CPU1_P3_ROM_MUX_2D_SDA")
	)
	(segment
		(start 167.696388 -423.477182)
		(end 167.696388 -423.405554)
		(width 0.10668)
		(layer "B.Cu")
		(net "SMB_RT_CPU1_P3_ROM_MUX_2D_SDA")
	)
	(segment
		(start 236.324394 -342.242394)
		(end 222.259906 -356.306882)
		(width 0.10668)
		(layer "B.Cu")
		(net "SMB_RT_CPU1_P3_ROM_MUX_2D_SDA")
	)
	(segment
		(start 182.871364 -367.317782)
		(end 215.512904 -367.317782)
		(width 0.11684)
		(layer "In6.Cu")
		(net "SMB_RT_CPU1_P3_ROM_MUX_2D_SDA")
	)
	(segment
		(start 175.142652 -362.576618)
		(end 176.22012 -362.576618)
		(width 0.11684)
		(layer "In6.Cu")
		(net "SMB_RT_CPU1_P3_ROM_MUX_2D_SDA")
	)
	(segment
		(start 180.299106 -366.655604)
		(end 182.209186 -366.655604)
		(width 0.11684)
		(layer "In6.Cu")
		(net "SMB_RT_CPU1_P3_ROM_MUX_2D_SDA")
	)
	(segment
		(start 219.879164 -359.821226)
		(end 222.259906 -357.440484)
		(width 0.11684)
		(layer "In6.Cu")
		(net "SMB_RT_CPU1_P3_ROM_MUX_2D_SDA")
	)
	(segment
		(start 182.209186 -366.655604)
		(end 182.871364 -367.317782)
		(width 0.11684)
		(layer "In6.Cu")
		(net "SMB_RT_CPU1_P3_ROM_MUX_2D_SDA")
	)
	(segment
		(start 215.512904 -367.317782)
		(end 219.879164 -362.951522)
		(width 0.11684)
		(layer "In6.Cu")
		(net "SMB_RT_CPU1_P3_ROM_MUX_2D_SDA")
	)
	(segment
		(start 176.22012 -362.576618)
		(end 180.299106 -366.655604)
		(width 0.11684)
		(layer "In6.Cu")
		(net "SMB_RT_CPU1_P3_ROM_MUX_2D_SDA")
	)
	(segment
		(start 219.879164 -362.951522)
		(end 219.879164 -359.821226)
		(width 0.11684)
		(layer "In6.Cu")
		(net "SMB_RT_CPU1_P3_ROM_MUX_2D_SDA")
	)
	(segment
		(start 168.834562 -412.006034)
		(end 168.834562 -408.869388)
		(width 0.11684)
		(layer "In11.Cu")
		(net "SMB_RT_CPU1_P3_ROM_MUX_2D_SDA")
	)
	(segment
		(start 168.465754 -414.480248)
		(end 168.465754 -412.374842)
		(width 0.11684)
		(layer "In11.Cu")
		(net "SMB_RT_CPU1_P3_ROM_MUX_2D_SDA")
	)
	(segment
		(start 166.669974 -402.707856)
		(end 167.5511 -401.82673)
		(width 0.11684)
		(layer "In11.Cu")
		(net "SMB_RT_CPU1_P3_ROM_MUX_2D_SDA")
	)
	(segment
		(start 165.68801 -419.892734)
		(end 166.688008 -418.892736)
		(width 0.11684)
		(layer "In11.Cu")
		(net "SMB_RT_CPU1_P3_ROM_MUX_2D_SDA")
	)
	(segment
		(start 166.669974 -406.7048)
		(end 166.669974 -402.707856)
		(width 0.11684)
		(layer "In11.Cu")
		(net "SMB_RT_CPU1_P3_ROM_MUX_2D_SDA")
	)
	(segment
		(start 165.68801 -421.854376)
		(end 165.68801 -419.892734)
		(width 0.11684)
		(layer "In11.Cu")
		(net "SMB_RT_CPU1_P3_ROM_MUX_2D_SDA")
	)
	(segment
		(start 166.688008 -418.892736)
		(end 166.688008 -416.257994)
		(width 0.11684)
		(layer "In11.Cu")
		(net "SMB_RT_CPU1_P3_ROM_MUX_2D_SDA")
	)
	(segment
		(start 167.5511 -401.82673)
		(end 167.5511 -397.659098)
		(width 0.11684)
		(layer "In11.Cu")
		(net "SMB_RT_CPU1_P3_ROM_MUX_2D_SDA")
	)
	(segment
		(start 168.079674 -397.130524)
		(end 168.079674 -396.515082)
		(width 0.11684)
		(layer "In11.Cu")
		(net "SMB_RT_CPU1_P3_ROM_MUX_2D_SDA")
	)
	(segment
		(start 168.465754 -412.374842)
		(end 168.834562 -412.006034)
		(width 0.11684)
		(layer "In11.Cu")
		(net "SMB_RT_CPU1_P3_ROM_MUX_2D_SDA")
	)
	(segment
		(start 166.543482 -422.709848)
		(end 165.68801 -421.854376)
		(width 0.11684)
		(layer "In11.Cu")
		(net "SMB_RT_CPU1_P3_ROM_MUX_2D_SDA")
	)
	(segment
		(start 166.688008 -416.257994)
		(end 168.465754 -414.480248)
		(width 0.11684)
		(layer "In11.Cu")
		(net "SMB_RT_CPU1_P3_ROM_MUX_2D_SDA")
	)
	(segment
		(start 168.834562 -408.869388)
		(end 166.669974 -406.7048)
		(width 0.11684)
		(layer "In11.Cu")
		(net "SMB_RT_CPU1_P3_ROM_MUX_2D_SDA")
	)
	(segment
		(start 167.5511 -397.659098)
		(end 168.079674 -397.130524)
		(width 0.11684)
		(layer "In11.Cu")
		(net "SMB_RT_CPU1_P3_ROM_MUX_2D_SDA")
	)
	(segment
		(start 184.948068 -379.864874)
		(end 184.948068 -372.067328)
		(width 0.11684)
		(layer "In15.Cu")
		(net "SMB_RT_CPU1_P3_ROM_MUX_2D_SDA")
	)
	(segment
		(start 184.948068 -372.067328)
		(end 178.66995 -365.78921)
		(width 0.11684)
		(layer "In15.Cu")
		(net "SMB_RT_CPU1_P3_ROM_MUX_2D_SDA")
	)
	(segment
		(start 168.079674 -396.515082)
		(end 169.02303 -397.458438)
		(width 0.11684)
		(layer "In15.Cu")
		(net "SMB_RT_CPU1_P3_ROM_MUX_2D_SDA")
	)
	(segment
		(start 171.313094 -397.458438)
		(end 172.079666 -396.691866)
		(width 0.11684)
		(layer "In15.Cu")
		(net "SMB_RT_CPU1_P3_ROM_MUX_2D_SDA")
	)
	(segment
		(start 178.66995 -365.78921)
		(end 178.66995 -365.446056)
		(width 0.11684)
		(layer "In15.Cu")
		(net "SMB_RT_CPU1_P3_ROM_MUX_2D_SDA")
	)
	(segment
		(start 175.800512 -362.576618)
		(end 175.142652 -362.576618)
		(width 0.11684)
		(layer "In15.Cu")
		(net "SMB_RT_CPU1_P3_ROM_MUX_2D_SDA")
	)
	(segment
		(start 172.079666 -392.733276)
		(end 184.948068 -379.864874)
		(width 0.11684)
		(layer "In15.Cu")
		(net "SMB_RT_CPU1_P3_ROM_MUX_2D_SDA")
	)
	(segment
		(start 169.02303 -397.458438)
		(end 171.313094 -397.458438)
		(width 0.11684)
		(layer "In15.Cu")
		(net "SMB_RT_CPU1_P3_ROM_MUX_2D_SDA")
	)
	(segment
		(start 172.079666 -396.691866)
		(end 172.079666 -392.733276)
		(width 0.11684)
		(layer "In15.Cu")
		(net "SMB_RT_CPU1_P3_ROM_MUX_2D_SDA")
	)
	(segment
		(start 178.66995 -365.446056)
		(end 175.800512 -362.576618)
		(width 0.11684)
		(layer "In15.Cu")
		(net "SMB_RT_CPU1_P3_ROM_MUX_2D_SDA")
	)
	(via
		(at 167.296592 -422.698926)
		(size 0.508)
		(drill 0.254)
		(layers "F.Cu" "B.Cu")
		(net "SMB_RT_CPU1_P3_ROM_MUX_2D_SCL")
	)
	(via
		(at 168.718484 -396.496286)
		(size 0.508)
		(drill 0.254)
		(layers "F.Cu" "B.Cu")
		(net "SMB_RT_CPU1_P3_ROM_MUX_2D_SCL")
	)
	(via
		(at 222.247206 -358.252014)
		(size 0.508)
		(drill 0.254)
		(layers "F.Cu" "B.Cu")
		(net "SMB_RT_CPU1_P3_ROM_MUX_2D_SCL")
	)
	(via
		(at 175.663098 -363.09681)
		(size 0.508)
		(drill 0.254)
		(layers "F.Cu" "B.Cu")
		(net "SMB_RT_CPU1_P3_ROM_MUX_2D_SCL")
	)
	(segment
		(start 167.69461 -422.698926)
		(end 167.296592 -422.698926)
		(width 0.10668)
		(layer "B.Cu")
		(net "SMB_RT_CPU1_P3_ROM_MUX_2D_SCL")
	)
	(segment
		(start 237.396782 -339.598)
		(end 236.978444 -340.016338)
		(width 0.10668)
		(layer "B.Cu")
		(net "SMB_RT_CPU1_P3_ROM_MUX_2D_SCL")
	)
	(segment
		(start 236.978444 -340.016338)
		(end 236.978444 -342.604344)
		(width 0.10668)
		(layer "B.Cu")
		(net "SMB_RT_CPU1_P3_ROM_MUX_2D_SCL")
	)
	(segment
		(start 222.848424 -356.734364)
		(end 222.848424 -357.650796)
		(width 0.10668)
		(layer "B.Cu")
		(net "SMB_RT_CPU1_P3_ROM_MUX_2D_SCL")
	)
	(segment
		(start 236.978444 -342.604344)
		(end 222.848424 -356.734364)
		(width 0.10668)
		(layer "B.Cu")
		(net "SMB_RT_CPU1_P3_ROM_MUX_2D_SCL")
	)
	(segment
		(start 238.3663 -339.598)
		(end 237.396782 -339.598)
		(width 0.10668)
		(layer "B.Cu")
		(net "SMB_RT_CPU1_P3_ROM_MUX_2D_SCL")
	)
	(segment
		(start 222.848424 -357.650796)
		(end 222.247206 -358.252014)
		(width 0.10668)
		(layer "B.Cu")
		(net "SMB_RT_CPU1_P3_ROM_MUX_2D_SCL")
	)
	(segment
		(start 168.196514 -423.20083)
		(end 167.69461 -422.698926)
		(width 0.10668)
		(layer "B.Cu")
		(net "SMB_RT_CPU1_P3_ROM_MUX_2D_SCL")
	)
	(segment
		(start 168.196514 -423.477182)
		(end 168.196514 -423.20083)
		(width 0.10668)
		(layer "B.Cu")
		(net "SMB_RT_CPU1_P3_ROM_MUX_2D_SCL")
	)
	(segment
		(start 180.202332 -367.155222)
		(end 176.14392 -363.09681)
		(width 0.11684)
		(layer "In6.Cu")
		(net "SMB_RT_CPU1_P3_ROM_MUX_2D_SCL")
	)
	(segment
		(start 176.14392 -363.09681)
		(end 175.663098 -363.09681)
		(width 0.11684)
		(layer "In6.Cu")
		(net "SMB_RT_CPU1_P3_ROM_MUX_2D_SCL")
	)
	(segment
		(start 215.617298 -367.817146)
		(end 182.383684 -367.817146)
		(width 0.11684)
		(layer "In6.Cu")
		(net "SMB_RT_CPU1_P3_ROM_MUX_2D_SCL")
	)
	(segment
		(start 181.72176 -367.155222)
		(end 180.202332 -367.155222)
		(width 0.11684)
		(layer "In6.Cu")
		(net "SMB_RT_CPU1_P3_ROM_MUX_2D_SCL")
	)
	(segment
		(start 220.366844 -363.0676)
		(end 215.617298 -367.817146)
		(width 0.11684)
		(layer "In6.Cu")
		(net "SMB_RT_CPU1_P3_ROM_MUX_2D_SCL")
	)
	(segment
		(start 220.366844 -360.132376)
		(end 220.366844 -363.0676)
		(width 0.11684)
		(layer "In6.Cu")
		(net "SMB_RT_CPU1_P3_ROM_MUX_2D_SCL")
	)
	(segment
		(start 182.383684 -367.817146)
		(end 181.72176 -367.155222)
		(width 0.11684)
		(layer "In6.Cu")
		(net "SMB_RT_CPU1_P3_ROM_MUX_2D_SCL")
	)
	(segment
		(start 222.247206 -358.252014)
		(end 220.366844 -360.132376)
		(width 0.11684)
		(layer "In6.Cu")
		(net "SMB_RT_CPU1_P3_ROM_MUX_2D_SCL")
	)
	(segment
		(start 167.296592 -422.698926)
		(end 167.12946 -422.531794)
		(width 0.11684)
		(layer "In11.Cu")
		(net "SMB_RT_CPU1_P3_ROM_MUX_2D_SCL")
	)
	(segment
		(start 167.12946 -422.531794)
		(end 167.12946 -418.241988)
		(width 0.11684)
		(layer "In11.Cu")
		(net "SMB_RT_CPU1_P3_ROM_MUX_2D_SCL")
	)
	(segment
		(start 175.46066 -408.00274)
		(end 175.46066 -403.008338)
		(width 0.11684)
		(layer "In11.Cu")
		(net "SMB_RT_CPU1_P3_ROM_MUX_2D_SCL")
	)
	(segment
		(start 170.725338 -398.50314)
		(end 168.718484 -396.496286)
		(width 0.11684)
		(layer "In11.Cu")
		(net "SMB_RT_CPU1_P3_ROM_MUX_2D_SCL")
	)
	(segment
		(start 167.12946 -418.241988)
		(end 169.131488 -416.23996)
		(width 0.11684)
		(layer "In11.Cu")
		(net "SMB_RT_CPU1_P3_ROM_MUX_2D_SCL")
	)
	(segment
		(start 169.131488 -415.487866)
		(end 170.28541 -414.333944)
		(width 0.11684)
		(layer "In11.Cu")
		(net "SMB_RT_CPU1_P3_ROM_MUX_2D_SCL")
	)
	(segment
		(start 169.131488 -416.23996)
		(end 169.131488 -415.487866)
		(width 0.11684)
		(layer "In11.Cu")
		(net "SMB_RT_CPU1_P3_ROM_MUX_2D_SCL")
	)
	(segment
		(start 170.28541 -413.17799)
		(end 175.46066 -408.00274)
		(width 0.11684)
		(layer "In11.Cu")
		(net "SMB_RT_CPU1_P3_ROM_MUX_2D_SCL")
	)
	(segment
		(start 175.46066 -403.008338)
		(end 170.955462 -398.50314)
		(width 0.11684)
		(layer "In11.Cu")
		(net "SMB_RT_CPU1_P3_ROM_MUX_2D_SCL")
	)
	(segment
		(start 170.955462 -398.50314)
		(end 170.725338 -398.50314)
		(width 0.11684)
		(layer "In11.Cu")
		(net "SMB_RT_CPU1_P3_ROM_MUX_2D_SCL")
	)
	(segment
		(start 170.28541 -414.333944)
		(end 170.28541 -413.17799)
		(width 0.11684)
		(layer "In11.Cu")
		(net "SMB_RT_CPU1_P3_ROM_MUX_2D_SCL")
	)
	(segment
		(start 184.526428 -379.5141)
		(end 184.526428 -372.381526)
		(width 0.11684)
		(layer "In15.Cu")
		(net "SMB_RT_CPU1_P3_ROM_MUX_2D_SCL")
	)
	(segment
		(start 178.149758 -365.58347)
		(end 175.663098 -363.09681)
		(width 0.11684)
		(layer "In15.Cu")
		(net "SMB_RT_CPU1_P3_ROM_MUX_2D_SCL")
	)
	(segment
		(start 168.718484 -396.496286)
		(end 169.220642 -396.998444)
		(width 0.11684)
		(layer "In15.Cu")
		(net "SMB_RT_CPU1_P3_ROM_MUX_2D_SCL")
	)
	(segment
		(start 184.526428 -372.381526)
		(end 178.149758 -366.004856)
		(width 0.11684)
		(layer "In15.Cu")
		(net "SMB_RT_CPU1_P3_ROM_MUX_2D_SCL")
	)
	(segment
		(start 172.380656 -391.48131)
		(end 172.380656 -390.975596)
		(width 0.11684)
		(layer "In15.Cu")
		(net "SMB_RT_CPU1_P3_ROM_MUX_2D_SCL")
	)
	(segment
		(start 173.04131 -390.314942)
		(end 173.725586 -390.314942)
		(width 0.11684)
		(layer "In15.Cu")
		(net "SMB_RT_CPU1_P3_ROM_MUX_2D_SCL")
	)
	(segment
		(start 171.619672 -396.501112)
		(end 171.619672 -392.242294)
		(width 0.11684)
		(layer "In15.Cu")
		(net "SMB_RT_CPU1_P3_ROM_MUX_2D_SCL")
	)
	(segment
		(start 178.149758 -366.004856)
		(end 178.149758 -365.58347)
		(width 0.11684)
		(layer "In15.Cu")
		(net "SMB_RT_CPU1_P3_ROM_MUX_2D_SCL")
	)
	(segment
		(start 172.380656 -390.975596)
		(end 173.04131 -390.314942)
		(width 0.11684)
		(layer "In15.Cu")
		(net "SMB_RT_CPU1_P3_ROM_MUX_2D_SCL")
	)
	(segment
		(start 173.725586 -390.314942)
		(end 184.526428 -379.5141)
		(width 0.11684)
		(layer "In15.Cu")
		(net "SMB_RT_CPU1_P3_ROM_MUX_2D_SCL")
	)
	(segment
		(start 171.12234 -396.998444)
		(end 171.619672 -396.501112)
		(width 0.11684)
		(layer "In15.Cu")
		(net "SMB_RT_CPU1_P3_ROM_MUX_2D_SCL")
	)
	(segment
		(start 169.220642 -396.998444)
		(end 171.12234 -396.998444)
		(width 0.11684)
		(layer "In15.Cu")
		(net "SMB_RT_CPU1_P3_ROM_MUX_2D_SCL")
	)
	(segment
		(start 171.619672 -392.242294)
		(end 172.380656 -391.48131)
		(width 0.11684)
		(layer "In15.Cu")
		(net "SMB_RT_CPU1_P3_ROM_MUX_2D_SCL")
	)
	(via
		(at 114.34572 -410.1973)
		(size 0.508)
		(drill 0.254)
		(layers "F.Cu" "B.Cu")
		(net "SMB_RT_CPU1_P3_ROM_MUX_1D_SDA")
	)
	(via
		(at 162.774884 -422.958006)
		(size 0.508)
		(drill 0.254)
		(layers "F.Cu" "B.Cu")
		(net "SMB_RT_CPU1_P3_ROM_MUX_1D_SDA")
	)
	(segment
		(start 168.696386 -423.071798)
		(end 168.696386 -423.477182)
		(width 0.10668)
		(layer "B.Cu")
		(net "SMB_RT_CPU1_P3_ROM_MUX_1D_SDA")
	)
	(segment
		(start 112.35436 -409.44546)
		(end 112.35436 -408.918156)
		(width 0.10668)
		(layer "B.Cu")
		(net "SMB_RT_CPU1_P3_ROM_MUX_1D_SDA")
	)
	(segment
		(start 113.90122 -409.7528)
		(end 112.6617 -409.7528)
		(width 0.10668)
		(layer "B.Cu")
		(net "SMB_RT_CPU1_P3_ROM_MUX_1D_SDA")
	)
	(segment
		(start 168.3004 -421.544496)
		(end 168.3004 -422.675812)
		(width 0.10668)
		(layer "B.Cu")
		(net "SMB_RT_CPU1_P3_ROM_MUX_1D_SDA")
	)
	(segment
		(start 168.3004 -422.675812)
		(end 168.696386 -423.071798)
		(width 0.10668)
		(layer "B.Cu")
		(net "SMB_RT_CPU1_P3_ROM_MUX_1D_SDA")
	)
	(segment
		(start 112.6617 -409.7528)
		(end 112.35436 -409.44546)
		(width 0.10668)
		(layer "B.Cu")
		(net "SMB_RT_CPU1_P3_ROM_MUX_1D_SDA")
	)
	(segment
		(start 168.3004 -421.544496)
		(end 166.102284 -421.544496)
		(width 0.10668)
		(layer "B.Cu")
		(net "SMB_RT_CPU1_P3_ROM_MUX_1D_SDA")
	)
	(segment
		(start 166.102284 -421.544496)
		(end 164.688774 -422.958006)
		(width 0.10668)
		(layer "B.Cu")
		(net "SMB_RT_CPU1_P3_ROM_MUX_1D_SDA")
	)
	(segment
		(start 164.688774 -422.958006)
		(end 162.774884 -422.958006)
		(width 0.10668)
		(layer "B.Cu")
		(net "SMB_RT_CPU1_P3_ROM_MUX_1D_SDA")
	)
	(segment
		(start 114.34572 -410.1973)
		(end 113.90122 -409.7528)
		(width 0.10668)
		(layer "B.Cu")
		(net "SMB_RT_CPU1_P3_ROM_MUX_1D_SDA")
	)
	(segment
		(start 164.420042 -411.90418)
		(end 164.420042 -414.231328)
		(width 0.11684)
		(layer "In6.Cu")
		(net "SMB_RT_CPU1_P3_ROM_MUX_1D_SDA")
	)
	(segment
		(start 162.599878 -420.95674)
		(end 162.483038 -421.07358)
		(width 0.11684)
		(layer "In6.Cu")
		(net "SMB_RT_CPU1_P3_ROM_MUX_1D_SDA")
	)
	(segment
		(start 160.71596 -421.19042)
		(end 160.71596 -421.38092)
		(width 0.11684)
		(layer "In6.Cu")
		(net "SMB_RT_CPU1_P3_ROM_MUX_1D_SDA")
	)
	(segment
		(start 162.976306 -417.78428)
		(end 162.316414 -417.78428)
		(width 0.11684)
		(layer "In6.Cu")
		(net "SMB_RT_CPU1_P3_ROM_MUX_1D_SDA")
	)
	(segment
		(start 114.34572 -410.1973)
		(end 114.685826 -410.1973)
		(width 0.11684)
		(layer "In6.Cu")
		(net "SMB_RT_CPU1_P3_ROM_MUX_1D_SDA")
	)
	(segment
		(start 162.483038 -421.07358)
		(end 160.8328 -421.07358)
		(width 0.11684)
		(layer "In6.Cu")
		(net "SMB_RT_CPU1_P3_ROM_MUX_1D_SDA")
	)
	(segment
		(start 114.685826 -410.1973)
		(end 116.17198 -408.711146)
		(width 0.11684)
		(layer "In6.Cu")
		(net "SMB_RT_CPU1_P3_ROM_MUX_1D_SDA")
	)
	(segment
		(start 164.420042 -414.231328)
		(end 163.950396 -414.700974)
		(width 0.11684)
		(layer "In6.Cu")
		(net "SMB_RT_CPU1_P3_ROM_MUX_1D_SDA")
	)
	(segment
		(start 160.71596 -421.38092)
		(end 160.8328 -421.49776)
		(width 0.11684)
		(layer "In6.Cu")
		(net "SMB_RT_CPU1_P3_ROM_MUX_1D_SDA")
	)
	(segment
		(start 164.596826 -411.727396)
		(end 164.420042 -411.90418)
		(width 0.11684)
		(layer "In6.Cu")
		(net "SMB_RT_CPU1_P3_ROM_MUX_1D_SDA")
	)
	(segment
		(start 164.596826 -409.544266)
		(end 164.596826 -411.727396)
		(width 0.11684)
		(layer "In6.Cu")
		(net "SMB_RT_CPU1_P3_ROM_MUX_1D_SDA")
	)
	(segment
		(start 116.17198 -408.711146)
		(end 163.763706 -408.711146)
		(width 0.11684)
		(layer "In6.Cu")
		(net "SMB_RT_CPU1_P3_ROM_MUX_1D_SDA")
	)
	(segment
		(start 160.8328 -421.07358)
		(end 160.71596 -421.19042)
		(width 0.11684)
		(layer "In6.Cu")
		(net "SMB_RT_CPU1_P3_ROM_MUX_1D_SDA")
	)
	(segment
		(start 163.950396 -416.81019)
		(end 162.976306 -417.78428)
		(width 0.11684)
		(layer "In6.Cu")
		(net "SMB_RT_CPU1_P3_ROM_MUX_1D_SDA")
	)
	(segment
		(start 162.483038 -421.49776)
		(end 162.774884 -421.789606)
		(width 0.11684)
		(layer "In6.Cu")
		(net "SMB_RT_CPU1_P3_ROM_MUX_1D_SDA")
	)
	(segment
		(start 163.950396 -414.700974)
		(end 163.950396 -416.81019)
		(width 0.11684)
		(layer "In6.Cu")
		(net "SMB_RT_CPU1_P3_ROM_MUX_1D_SDA")
	)
	(segment
		(start 163.763706 -408.711146)
		(end 164.596826 -409.544266)
		(width 0.11684)
		(layer "In6.Cu")
		(net "SMB_RT_CPU1_P3_ROM_MUX_1D_SDA")
	)
	(segment
		(start 162.774884 -421.789606)
		(end 162.774884 -422.958006)
		(width 0.11684)
		(layer "In6.Cu")
		(net "SMB_RT_CPU1_P3_ROM_MUX_1D_SDA")
	)
	(segment
		(start 162.316414 -417.78428)
		(end 162.04438 -418.056314)
		(width 0.11684)
		(layer "In6.Cu")
		(net "SMB_RT_CPU1_P3_ROM_MUX_1D_SDA")
	)
	(segment
		(start 162.599878 -418.997384)
		(end 162.599878 -420.95674)
		(width 0.11684)
		(layer "In6.Cu")
		(net "SMB_RT_CPU1_P3_ROM_MUX_1D_SDA")
	)
	(segment
		(start 162.04438 -418.441886)
		(end 162.599878 -418.997384)
		(width 0.11684)
		(layer "In6.Cu")
		(net "SMB_RT_CPU1_P3_ROM_MUX_1D_SDA")
	)
	(segment
		(start 160.8328 -421.49776)
		(end 162.483038 -421.49776)
		(width 0.11684)
		(layer "In6.Cu")
		(net "SMB_RT_CPU1_P3_ROM_MUX_1D_SDA")
	)
	(segment
		(start 162.04438 -418.056314)
		(end 162.04438 -418.441886)
		(width 0.11684)
		(layer "In6.Cu")
		(net "SMB_RT_CPU1_P3_ROM_MUX_1D_SDA")
	)
	(via
		(at 114.427 -409.5623)
		(size 0.508)
		(drill 0.254)
		(layers "F.Cu" "B.Cu")
		(net "SMB_RT_CPU1_P3_ROM_MUX_1D_SCL")
	)
	(via
		(at 164.45484 -422.389808)
		(size 0.508)
		(drill 0.254)
		(layers "F.Cu" "B.Cu")
		(net "SMB_RT_CPU1_P3_ROM_MUX_1D_SCL")
	)
	(segment
		(start 169.2148 -422.129712)
		(end 169.36974 -422.284652)
		(width 0.10668)
		(layer "B.Cu")
		(net "SMB_RT_CPU1_P3_ROM_MUX_1D_SCL")
	)
	(segment
		(start 167.80002 -419.405816)
		(end 166.572438 -420.633398)
		(width 0.10668)
		(layer "B.Cu")
		(net "SMB_RT_CPU1_P3_ROM_MUX_1D_SCL")
	)
	(segment
		(start 170.855132 -420.086028)
		(end 170.53814 -419.769036)
		(width 0.10668)
		(layer "B.Cu")
		(net "SMB_RT_CPU1_P3_ROM_MUX_1D_SCL")
	)
	(segment
		(start 169.2148 -421.544496)
		(end 169.823892 -421.544496)
		(width 0.10668)
		(layer "B.Cu")
		(net "SMB_RT_CPU1_P3_ROM_MUX_1D_SCL")
	)
	(segment
		(start 170.855132 -420.513256)
		(end 170.855132 -420.086028)
		(width 0.10668)
		(layer "B.Cu")
		(net "SMB_RT_CPU1_P3_ROM_MUX_1D_SCL")
	)
	(segment
		(start 169.574972 -419.198298)
		(end 168.773602 -419.198298)
		(width 0.10668)
		(layer "B.Cu")
		(net "SMB_RT_CPU1_P3_ROM_MUX_1D_SCL")
	)
	(segment
		(start 169.196512 -423.225214)
		(end 169.196512 -423.477182)
		(width 0.10668)
		(layer "B.Cu")
		(net "SMB_RT_CPU1_P3_ROM_MUX_1D_SCL")
	)
	(segment
		(start 113.749836 -408.885136)
		(end 113.17478 -408.885136)
		(width 0.10668)
		(layer "B.Cu")
		(net "SMB_RT_CPU1_P3_ROM_MUX_1D_SCL")
	)
	(segment
		(start 166.21125 -420.633398)
		(end 164.45484 -422.389808)
		(width 0.10668)
		(layer "B.Cu")
		(net "SMB_RT_CPU1_P3_ROM_MUX_1D_SCL")
	)
	(segment
		(start 169.36974 -423.051986)
		(end 169.196512 -423.225214)
		(width 0.10668)
		(layer "B.Cu")
		(net "SMB_RT_CPU1_P3_ROM_MUX_1D_SCL")
	)
	(segment
		(start 169.36974 -422.284652)
		(end 169.36974 -423.051986)
		(width 0.10668)
		(layer "B.Cu")
		(net "SMB_RT_CPU1_P3_ROM_MUX_1D_SCL")
	)
	(segment
		(start 169.2148 -421.544496)
		(end 169.2148 -422.129712)
		(width 0.10668)
		(layer "B.Cu")
		(net "SMB_RT_CPU1_P3_ROM_MUX_1D_SCL")
	)
	(segment
		(start 168.566084 -419.405816)
		(end 167.80002 -419.405816)
		(width 0.10668)
		(layer "B.Cu")
		(net "SMB_RT_CPU1_P3_ROM_MUX_1D_SCL")
	)
	(segment
		(start 114.427 -409.5623)
		(end 113.749836 -408.885136)
		(width 0.10668)
		(layer "B.Cu")
		(net "SMB_RT_CPU1_P3_ROM_MUX_1D_SCL")
	)
	(segment
		(start 169.823892 -421.544496)
		(end 170.855132 -420.513256)
		(width 0.10668)
		(layer "B.Cu")
		(net "SMB_RT_CPU1_P3_ROM_MUX_1D_SCL")
	)
	(segment
		(start 170.53814 -419.769036)
		(end 170.14571 -419.769036)
		(width 0.10668)
		(layer "B.Cu")
		(net "SMB_RT_CPU1_P3_ROM_MUX_1D_SCL")
	)
	(segment
		(start 168.773602 -419.198298)
		(end 168.566084 -419.405816)
		(width 0.10668)
		(layer "B.Cu")
		(net "SMB_RT_CPU1_P3_ROM_MUX_1D_SCL")
	)
	(segment
		(start 166.572438 -420.633398)
		(end 166.21125 -420.633398)
		(width 0.10668)
		(layer "B.Cu")
		(net "SMB_RT_CPU1_P3_ROM_MUX_1D_SCL")
	)
	(segment
		(start 170.14571 -419.769036)
		(end 169.574972 -419.198298)
		(width 0.10668)
		(layer "B.Cu")
		(net "SMB_RT_CPU1_P3_ROM_MUX_1D_SCL")
	)
	(segment
		(start 163.85032 -421.785288)
		(end 164.45484 -422.389808)
		(width 0.11684)
		(layer "In6.Cu")
		(net "SMB_RT_CPU1_P3_ROM_MUX_1D_SCL")
	)
	(segment
		(start 115.76431 -408.22499)
		(end 164.759132 -408.22499)
		(width 0.11684)
		(layer "In6.Cu")
		(net "SMB_RT_CPU1_P3_ROM_MUX_1D_SCL")
	)
	(segment
		(start 164.759132 -408.22499)
		(end 166.08298 -409.548838)
		(width 0.11684)
		(layer "In6.Cu")
		(net "SMB_RT_CPU1_P3_ROM_MUX_1D_SCL")
	)
	(segment
		(start 166.08298 -412.686246)
		(end 165.212776 -413.55645)
		(width 0.11684)
		(layer "In6.Cu")
		(net "SMB_RT_CPU1_P3_ROM_MUX_1D_SCL")
	)
	(segment
		(start 163.707064 -418.767514)
		(end 163.707064 -419.710108)
		(width 0.11684)
		(layer "In6.Cu")
		(net "SMB_RT_CPU1_P3_ROM_MUX_1D_SCL")
	)
	(segment
		(start 165.48481 -414.577784)
		(end 165.48481 -417.109656)
		(width 0.11684)
		(layer "In6.Cu")
		(net "SMB_RT_CPU1_P3_ROM_MUX_1D_SCL")
	)
	(segment
		(start 163.34105 -418.015928)
		(end 163.34105 -418.4015)
		(width 0.11684)
		(layer "In6.Cu")
		(net "SMB_RT_CPU1_P3_ROM_MUX_1D_SCL")
	)
	(segment
		(start 164.827204 -417.41471)
		(end 164.49802 -417.743894)
		(width 0.11684)
		(layer "In6.Cu")
		(net "SMB_RT_CPU1_P3_ROM_MUX_1D_SCL")
	)
	(segment
		(start 165.48481 -417.109656)
		(end 165.179756 -417.41471)
		(width 0.11684)
		(layer "In6.Cu")
		(net "SMB_RT_CPU1_P3_ROM_MUX_1D_SCL")
	)
	(segment
		(start 114.427 -409.5623)
		(end 115.76431 -408.22499)
		(width 0.11684)
		(layer "In6.Cu")
		(net "SMB_RT_CPU1_P3_ROM_MUX_1D_SCL")
	)
	(segment
		(start 163.613084 -417.743894)
		(end 163.34105 -418.015928)
		(width 0.11684)
		(layer "In6.Cu")
		(net "SMB_RT_CPU1_P3_ROM_MUX_1D_SCL")
	)
	(segment
		(start 163.85032 -419.853364)
		(end 163.85032 -421.785288)
		(width 0.11684)
		(layer "In6.Cu")
		(net "SMB_RT_CPU1_P3_ROM_MUX_1D_SCL")
	)
	(segment
		(start 166.08298 -409.548838)
		(end 166.08298 -412.686246)
		(width 0.11684)
		(layer "In6.Cu")
		(net "SMB_RT_CPU1_P3_ROM_MUX_1D_SCL")
	)
	(segment
		(start 165.212776 -413.55645)
		(end 165.212776 -414.30575)
		(width 0.11684)
		(layer "In6.Cu")
		(net "SMB_RT_CPU1_P3_ROM_MUX_1D_SCL")
	)
	(segment
		(start 165.212776 -414.30575)
		(end 165.48481 -414.577784)
		(width 0.11684)
		(layer "In6.Cu")
		(net "SMB_RT_CPU1_P3_ROM_MUX_1D_SCL")
	)
	(segment
		(start 164.49802 -417.743894)
		(end 163.613084 -417.743894)
		(width 0.11684)
		(layer "In6.Cu")
		(net "SMB_RT_CPU1_P3_ROM_MUX_1D_SCL")
	)
	(segment
		(start 163.707064 -419.710108)
		(end 163.85032 -419.853364)
		(width 0.11684)
		(layer "In6.Cu")
		(net "SMB_RT_CPU1_P3_ROM_MUX_1D_SCL")
	)
	(segment
		(start 165.179756 -417.41471)
		(end 164.827204 -417.41471)
		(width 0.11684)
		(layer "In6.Cu")
		(net "SMB_RT_CPU1_P3_ROM_MUX_1D_SCL")
	)
	(segment
		(start 163.34105 -418.4015)
		(end 163.707064 -418.767514)
		(width 0.11684)
		(layer "In6.Cu")
		(net "SMB_RT_CPU1_P3_ROM_MUX_1D_SCL")
	)
	(via
		(at 224.378266 -360.141774)
		(size 0.508)
		(drill 0.254)
		(layers "F.Cu" "B.Cu")
		(net "SMB_RT_CPU1_P2_ROM_MUX_2D_SDA")
	)
	(via
		(at 160.437322 -424.420284)
		(size 0.508)
		(drill 0.254)
		(layers "F.Cu" "B.Cu")
		(net "SMB_RT_CPU1_P2_ROM_MUX_2D_SDA")
	)
	(segment
		(start 158.582614 -420.738046)
		(end 160.437322 -422.592754)
		(width 0.10668)
		(layer "B.Cu")
		(net "SMB_RT_CPU1_P2_ROM_MUX_2D_SDA")
	)
	(segment
		(start 159.463232 -418.254942)
		(end 159.094424 -418.254942)
		(width 0.10668)
		(layer "B.Cu")
		(net "SMB_RT_CPU1_P2_ROM_MUX_2D_SDA")
	)
	(segment
		(start 159.094424 -418.254942)
		(end 158.582614 -418.766752)
		(width 0.10668)
		(layer "B.Cu")
		(net "SMB_RT_CPU1_P2_ROM_MUX_2D_SDA")
	)
	(segment
		(start 237.434882 -341.136478)
		(end 237.434882 -342.696546)
		(width 0.10668)
		(layer "B.Cu")
		(net "SMB_RT_CPU1_P2_ROM_MUX_2D_SDA")
	)
	(segment
		(start 224.378266 -355.753162)
		(end 224.378266 -360.141774)
		(width 0.10668)
		(layer "B.Cu")
		(net "SMB_RT_CPU1_P2_ROM_MUX_2D_SDA")
	)
	(segment
		(start 160.437322 -422.592754)
		(end 160.437322 -424.420284)
		(width 0.10668)
		(layer "B.Cu")
		(net "SMB_RT_CPU1_P2_ROM_MUX_2D_SDA")
	)
	(segment
		(start 237.83036 -340.741)
		(end 237.434882 -341.136478)
		(width 0.10668)
		(layer "B.Cu")
		(net "SMB_RT_CPU1_P2_ROM_MUX_2D_SDA")
	)
	(segment
		(start 237.434882 -342.696546)
		(end 224.378266 -355.753162)
		(width 0.10668)
		(layer "B.Cu")
		(net "SMB_RT_CPU1_P2_ROM_MUX_2D_SDA")
	)
	(segment
		(start 238.3663 -340.741)
		(end 237.83036 -340.741)
		(width 0.10668)
		(layer "B.Cu")
		(net "SMB_RT_CPU1_P2_ROM_MUX_2D_SDA")
	)
	(segment
		(start 158.582614 -418.766752)
		(end 158.582614 -420.738046)
		(width 0.10668)
		(layer "B.Cu")
		(net "SMB_RT_CPU1_P2_ROM_MUX_2D_SDA")
	)
	(segment
		(start 166.539418 -417.90366)
		(end 167.210994 -417.232084)
		(width 0.11684)
		(layer "In6.Cu")
		(net "SMB_RT_CPU1_P2_ROM_MUX_2D_SDA")
	)
	(segment
		(start 167.468804 -413.331914)
		(end 167.468804 -412.946342)
		(width 0.11684)
		(layer "In6.Cu")
		(net "SMB_RT_CPU1_P2_ROM_MUX_2D_SDA")
	)
	(segment
		(start 222.554546 -361.965494)
		(end 224.378266 -360.141774)
		(width 0.11684)
		(layer "In6.Cu")
		(net "SMB_RT_CPU1_P2_ROM_MUX_2D_SDA")
	)
	(segment
		(start 160.437322 -424.420284)
		(end 160.936178 -424.420284)
		(width 0.11684)
		(layer "In6.Cu")
		(net "SMB_RT_CPU1_P2_ROM_MUX_2D_SDA")
	)
	(segment
		(start 221.207076 -365.350552)
		(end 222.554546 -364.003082)
		(width 0.11684)
		(layer "In6.Cu")
		(net "SMB_RT_CPU1_P2_ROM_MUX_2D_SDA")
	)
	(segment
		(start 222.554546 -364.003082)
		(end 222.554546 -361.965494)
		(width 0.11684)
		(layer "In6.Cu")
		(net "SMB_RT_CPU1_P2_ROM_MUX_2D_SDA")
	)
	(segment
		(start 167.740838 -414.877758)
		(end 167.740838 -413.603948)
		(width 0.11684)
		(layer "In6.Cu")
		(net "SMB_RT_CPU1_P2_ROM_MUX_2D_SDA")
	)
	(segment
		(start 172.010578 -392.535156)
		(end 172.010578 -390.543288)
		(width 0.11684)
		(layer "In6.Cu")
		(net "SMB_RT_CPU1_P2_ROM_MUX_2D_SDA")
	)
	(segment
		(start 166.891208 -415.727388)
		(end 167.740838 -414.877758)
		(width 0.11684)
		(layer "In6.Cu")
		(net "SMB_RT_CPU1_P2_ROM_MUX_2D_SDA")
	)
	(segment
		(start 166.056056 -424.926506)
		(end 166.056056 -421.508936)
		(width 0.11684)
		(layer "In6.Cu")
		(net "SMB_RT_CPU1_P2_ROM_MUX_2D_SDA")
	)
	(segment
		(start 191.100456 -369.57508)
		(end 219.278708 -369.57508)
		(width 0.11684)
		(layer "In6.Cu")
		(net "SMB_RT_CPU1_P2_ROM_MUX_2D_SDA")
	)
	(segment
		(start 221.207076 -367.646712)
		(end 221.207076 -365.350552)
		(width 0.11684)
		(layer "In6.Cu")
		(net "SMB_RT_CPU1_P2_ROM_MUX_2D_SDA")
	)
	(segment
		(start 219.278708 -369.57508)
		(end 221.207076 -367.646712)
		(width 0.11684)
		(layer "In6.Cu")
		(net "SMB_RT_CPU1_P2_ROM_MUX_2D_SDA")
	)
	(segment
		(start 165.860222 -425.12234)
		(end 166.056056 -424.926506)
		(width 0.11684)
		(layer "In6.Cu")
		(net "SMB_RT_CPU1_P2_ROM_MUX_2D_SDA")
	)
	(segment
		(start 167.210994 -416.78225)
		(end 166.891208 -416.462464)
		(width 0.11684)
		(layer "In6.Cu")
		(net "SMB_RT_CPU1_P2_ROM_MUX_2D_SDA")
	)
	(segment
		(start 164.216334 -401.56511)
		(end 164.216334 -397.677132)
		(width 0.11684)
		(layer "In6.Cu")
		(net "SMB_RT_CPU1_P2_ROM_MUX_2D_SDA")
	)
	(segment
		(start 162.594544 -426.07865)
		(end 165.553644 -426.07865)
		(width 0.11684)
		(layer "In6.Cu")
		(net "SMB_RT_CPU1_P2_ROM_MUX_2D_SDA")
	)
	(segment
		(start 167.468804 -412.946342)
		(end 168.077642 -412.337504)
		(width 0.11684)
		(layer "In6.Cu")
		(net "SMB_RT_CPU1_P2_ROM_MUX_2D_SDA")
	)
	(segment
		(start 178.253898 -384.77952)
		(end 178.253898 -382.421638)
		(width 0.11684)
		(layer "In6.Cu")
		(net "SMB_RT_CPU1_P2_ROM_MUX_2D_SDA")
	)
	(segment
		(start 167.740838 -413.603948)
		(end 167.468804 -413.331914)
		(width 0.11684)
		(layer "In6.Cu")
		(net "SMB_RT_CPU1_P2_ROM_MUX_2D_SDA")
	)
	(segment
		(start 167.210994 -417.232084)
		(end 167.210994 -416.78225)
		(width 0.11684)
		(layer "In6.Cu")
		(net "SMB_RT_CPU1_P2_ROM_MUX_2D_SDA")
	)
	(segment
		(start 172.010578 -390.543288)
		(end 173.174914 -389.378952)
		(width 0.11684)
		(layer "In6.Cu")
		(net "SMB_RT_CPU1_P2_ROM_MUX_2D_SDA")
	)
	(segment
		(start 164.216334 -397.677132)
		(end 166.299896 -395.59357)
		(width 0.11684)
		(layer "In6.Cu")
		(net "SMB_RT_CPU1_P2_ROM_MUX_2D_SDA")
	)
	(segment
		(start 173.654466 -389.378952)
		(end 178.253898 -384.77952)
		(width 0.11684)
		(layer "In6.Cu")
		(net "SMB_RT_CPU1_P2_ROM_MUX_2D_SDA")
	)
	(segment
		(start 165.860222 -425.772072)
		(end 165.860222 -425.12234)
		(width 0.11684)
		(layer "In6.Cu")
		(net "SMB_RT_CPU1_P2_ROM_MUX_2D_SDA")
	)
	(segment
		(start 168.952164 -395.59357)
		(end 172.010578 -392.535156)
		(width 0.11684)
		(layer "In6.Cu")
		(net "SMB_RT_CPU1_P2_ROM_MUX_2D_SDA")
	)
	(segment
		(start 165.716966 -421.169846)
		(end 165.716966 -419.801294)
		(width 0.11684)
		(layer "In6.Cu")
		(net "SMB_RT_CPU1_P2_ROM_MUX_2D_SDA")
	)
	(segment
		(start 168.077642 -409.898088)
		(end 165.506654 -407.3271)
		(width 0.11684)
		(layer "In6.Cu")
		(net "SMB_RT_CPU1_P2_ROM_MUX_2D_SDA")
	)
	(segment
		(start 165.506654 -407.3271)
		(end 165.506654 -402.85543)
		(width 0.11684)
		(layer "In6.Cu")
		(net "SMB_RT_CPU1_P2_ROM_MUX_2D_SDA")
	)
	(segment
		(start 168.077642 -412.337504)
		(end 168.077642 -409.898088)
		(width 0.11684)
		(layer "In6.Cu")
		(net "SMB_RT_CPU1_P2_ROM_MUX_2D_SDA")
	)
	(segment
		(start 166.539418 -418.978842)
		(end 166.539418 -417.90366)
		(width 0.11684)
		(layer "In6.Cu")
		(net "SMB_RT_CPU1_P2_ROM_MUX_2D_SDA")
	)
	(segment
		(start 165.553644 -426.07865)
		(end 165.860222 -425.772072)
		(width 0.11684)
		(layer "In6.Cu")
		(net "SMB_RT_CPU1_P2_ROM_MUX_2D_SDA")
	)
	(segment
		(start 166.891208 -416.462464)
		(end 166.891208 -415.727388)
		(width 0.11684)
		(layer "In6.Cu")
		(net "SMB_RT_CPU1_P2_ROM_MUX_2D_SDA")
	)
	(segment
		(start 165.506654 -402.85543)
		(end 164.216334 -401.56511)
		(width 0.11684)
		(layer "In6.Cu")
		(net "SMB_RT_CPU1_P2_ROM_MUX_2D_SDA")
	)
	(segment
		(start 178.253898 -382.421638)
		(end 191.100456 -369.57508)
		(width 0.11684)
		(layer "In6.Cu")
		(net "SMB_RT_CPU1_P2_ROM_MUX_2D_SDA")
	)
	(segment
		(start 166.056056 -421.508936)
		(end 165.716966 -421.169846)
		(width 0.11684)
		(layer "In6.Cu")
		(net "SMB_RT_CPU1_P2_ROM_MUX_2D_SDA")
	)
	(segment
		(start 165.716966 -419.801294)
		(end 166.539418 -418.978842)
		(width 0.11684)
		(layer "In6.Cu")
		(net "SMB_RT_CPU1_P2_ROM_MUX_2D_SDA")
	)
	(segment
		(start 160.936178 -424.420284)
		(end 162.594544 -426.07865)
		(width 0.11684)
		(layer "In6.Cu")
		(net "SMB_RT_CPU1_P2_ROM_MUX_2D_SDA")
	)
	(segment
		(start 173.174914 -389.378952)
		(end 173.654466 -389.378952)
		(width 0.11684)
		(layer "In6.Cu")
		(net "SMB_RT_CPU1_P2_ROM_MUX_2D_SDA")
	)
	(segment
		(start 166.299896 -395.59357)
		(end 168.952164 -395.59357)
		(width 0.11684)
		(layer "In6.Cu")
		(net "SMB_RT_CPU1_P2_ROM_MUX_2D_SDA")
	)
	(via
		(at 160.889188 -425.065952)
		(size 0.508)
		(drill 0.254)
		(layers "F.Cu" "B.Cu")
		(net "SMB_RT_CPU1_P2_ROM_MUX_2D_SCL")
	)
	(via
		(at 224.352866 -361.118404)
		(size 0.508)
		(drill 0.254)
		(layers "F.Cu" "B.Cu")
		(net "SMB_RT_CPU1_P2_ROM_MUX_2D_SCL")
	)
	(segment
		(start 160.340802 -425.065952)
		(end 159.446722 -424.171872)
		(width 0.10668)
		(layer "B.Cu")
		(net "SMB_RT_CPU1_P2_ROM_MUX_2D_SCL")
	)
	(segment
		(start 159.446722 -424.171872)
		(end 159.446722 -422.09085)
		(width 0.10668)
		(layer "B.Cu")
		(net "SMB_RT_CPU1_P2_ROM_MUX_2D_SCL")
	)
	(segment
		(start 159.031178 -417.754816)
		(end 159.463232 -417.754816)
		(width 0.10668)
		(layer "B.Cu")
		(net "SMB_RT_CPU1_P2_ROM_MUX_2D_SCL")
	)
	(segment
		(start 159.446722 -422.09085)
		(end 158.232602 -420.87673)
		(width 0.10668)
		(layer "B.Cu")
		(net "SMB_RT_CPU1_P2_ROM_MUX_2D_SCL")
	)
	(segment
		(start 158.232602 -420.87673)
		(end 158.232602 -418.553392)
		(width 0.10668)
		(layer "B.Cu")
		(net "SMB_RT_CPU1_P2_ROM_MUX_2D_SCL")
	)
	(segment
		(start 225.000312 -360.470958)
		(end 224.352866 -361.118404)
		(width 0.10668)
		(layer "B.Cu")
		(net "SMB_RT_CPU1_P2_ROM_MUX_2D_SCL")
	)
	(segment
		(start 238.3663 -342.35136)
		(end 225.000312 -355.717348)
		(width 0.10668)
		(layer "B.Cu")
		(net "SMB_RT_CPU1_P2_ROM_MUX_2D_SCL")
	)
	(segment
		(start 158.232602 -418.553392)
		(end 159.031178 -417.754816)
		(width 0.10668)
		(layer "B.Cu")
		(net "SMB_RT_CPU1_P2_ROM_MUX_2D_SCL")
	)
	(segment
		(start 160.889188 -425.065952)
		(end 160.340802 -425.065952)
		(width 0.10668)
		(layer "B.Cu")
		(net "SMB_RT_CPU1_P2_ROM_MUX_2D_SCL")
	)
	(segment
		(start 238.3663 -341.884)
		(end 238.3663 -342.35136)
		(width 0.10668)
		(layer "B.Cu")
		(net "SMB_RT_CPU1_P2_ROM_MUX_2D_SCL")
	)
	(segment
		(start 225.000312 -355.717348)
		(end 225.000312 -360.470958)
		(width 0.10668)
		(layer "B.Cu")
		(net "SMB_RT_CPU1_P2_ROM_MUX_2D_SCL")
	)
	(segment
		(start 166.961058 -418.078412)
		(end 167.632634 -417.406836)
		(width 0.11684)
		(layer "In6.Cu")
		(net "SMB_RT_CPU1_P2_ROM_MUX_2D_SCL")
	)
	(segment
		(start 167.312848 -415.90214)
		(end 167.584882 -415.630106)
		(width 0.11684)
		(layer "In6.Cu")
		(net "SMB_RT_CPU1_P2_ROM_MUX_2D_SCL")
	)
	(segment
		(start 168.234614 -415.3662)
		(end 168.234614 -414.63722)
		(width 0.11684)
		(layer "In6.Cu")
		(net "SMB_RT_CPU1_P2_ROM_MUX_2D_SCL")
	)
	(segment
		(start 167.312848 -416.287712)
		(end 167.312848 -415.90214)
		(width 0.11684)
		(layer "In6.Cu")
		(net "SMB_RT_CPU1_P2_ROM_MUX_2D_SCL")
	)
	(segment
		(start 167.584882 -415.630106)
		(end 167.970708 -415.630106)
		(width 0.11684)
		(layer "In6.Cu")
		(net "SMB_RT_CPU1_P2_ROM_MUX_2D_SCL")
	)
	(segment
		(start 160.889188 -425.065952)
		(end 162.323526 -426.50029)
		(width 0.11684)
		(layer "In6.Cu")
		(net "SMB_RT_CPU1_P2_ROM_MUX_2D_SCL")
	)
	(segment
		(start 224.352866 -361.783884)
		(end 224.352866 -361.118404)
		(width 0.11684)
		(layer "In6.Cu")
		(net "SMB_RT_CPU1_P2_ROM_MUX_2D_SCL")
	)
	(segment
		(start 168.234614 -414.63722)
		(end 168.499282 -414.372552)
		(width 0.11684)
		(layer "In6.Cu")
		(net "SMB_RT_CPU1_P2_ROM_MUX_2D_SCL")
	)
	(segment
		(start 165.928294 -407.152348)
		(end 165.928294 -402.680678)
		(width 0.11684)
		(layer "In6.Cu")
		(net "SMB_RT_CPU1_P2_ROM_MUX_2D_SCL")
	)
	(segment
		(start 165.728396 -426.50029)
		(end 166.281862 -425.946824)
		(width 0.11684)
		(layer "In6.Cu")
		(net "SMB_RT_CPU1_P2_ROM_MUX_2D_SCL")
	)
	(segment
		(start 221.628716 -365.525304)
		(end 222.976186 -364.177834)
		(width 0.11684)
		(layer "In6.Cu")
		(net "SMB_RT_CPU1_P2_ROM_MUX_2D_SCL")
	)
	(segment
		(start 168.499282 -412.460186)
		(end 168.75252 -412.206948)
		(width 0.11684)
		(layer "In6.Cu")
		(net "SMB_RT_CPU1_P2_ROM_MUX_2D_SCL")
	)
	(segment
		(start 166.474648 -396.01521)
		(end 169.212768 -396.01521)
		(width 0.11684)
		(layer "In6.Cu")
		(net "SMB_RT_CPU1_P2_ROM_MUX_2D_SCL")
	)
	(segment
		(start 166.281862 -425.946824)
		(end 166.281862 -425.297092)
		(width 0.11684)
		(layer "In6.Cu")
		(net "SMB_RT_CPU1_P2_ROM_MUX_2D_SCL")
	)
	(segment
		(start 166.852346 -419.520116)
		(end 166.961058 -419.411404)
		(width 0.11684)
		(layer "In6.Cu")
		(net "SMB_RT_CPU1_P2_ROM_MUX_2D_SCL")
	)
	(segment
		(start 172.631862 -390.518396)
		(end 173.349666 -389.800592)
		(width 0.11684)
		(layer "In6.Cu")
		(net "SMB_RT_CPU1_P2_ROM_MUX_2D_SCL")
	)
	(segment
		(start 165.928294 -402.680678)
		(end 164.637974 -401.390358)
		(width 0.11684)
		(layer "In6.Cu")
		(net "SMB_RT_CPU1_P2_ROM_MUX_2D_SCL")
	)
	(segment
		(start 167.632634 -416.607498)
		(end 167.312848 -416.287712)
		(width 0.11684)
		(layer "In6.Cu")
		(net "SMB_RT_CPU1_P2_ROM_MUX_2D_SCL")
	)
	(segment
		(start 191.275208 -369.99672)
		(end 219.504768 -369.99672)
		(width 0.11684)
		(layer "In6.Cu")
		(net "SMB_RT_CPU1_P2_ROM_MUX_2D_SCL")
	)
	(segment
		(start 178.675538 -382.59639)
		(end 191.275208 -369.99672)
		(width 0.11684)
		(layer "In6.Cu")
		(net "SMB_RT_CPU1_P2_ROM_MUX_2D_SCL")
	)
	(segment
		(start 167.83558 -423.743374)
		(end 167.83558 -422.223438)
		(width 0.11684)
		(layer "In6.Cu")
		(net "SMB_RT_CPU1_P2_ROM_MUX_2D_SCL")
	)
	(segment
		(start 162.323526 -426.50029)
		(end 165.728396 -426.50029)
		(width 0.11684)
		(layer "In6.Cu")
		(net "SMB_RT_CPU1_P2_ROM_MUX_2D_SCL")
	)
	(segment
		(start 172.631862 -392.596116)
		(end 172.631862 -390.518396)
		(width 0.11684)
		(layer "In6.Cu")
		(net "SMB_RT_CPU1_P2_ROM_MUX_2D_SCL")
	)
	(segment
		(start 221.628716 -367.872772)
		(end 221.628716 -365.525304)
		(width 0.11684)
		(layer "In6.Cu")
		(net "SMB_RT_CPU1_P2_ROM_MUX_2D_SCL")
	)
	(segment
		(start 166.852346 -421.240204)
		(end 166.852346 -419.520116)
		(width 0.11684)
		(layer "In6.Cu")
		(net "SMB_RT_CPU1_P2_ROM_MUX_2D_SCL")
	)
	(segment
		(start 169.212768 -396.01521)
		(end 172.631862 -392.596116)
		(width 0.11684)
		(layer "In6.Cu")
		(net "SMB_RT_CPU1_P2_ROM_MUX_2D_SCL")
	)
	(segment
		(start 178.675538 -384.954272)
		(end 178.675538 -382.59639)
		(width 0.11684)
		(layer "In6.Cu")
		(net "SMB_RT_CPU1_P2_ROM_MUX_2D_SCL")
	)
	(segment
		(start 173.349666 -389.800592)
		(end 173.829218 -389.800592)
		(width 0.11684)
		(layer "In6.Cu")
		(net "SMB_RT_CPU1_P2_ROM_MUX_2D_SCL")
	)
	(segment
		(start 167.632634 -417.406836)
		(end 167.632634 -416.607498)
		(width 0.11684)
		(layer "In6.Cu")
		(net "SMB_RT_CPU1_P2_ROM_MUX_2D_SCL")
	)
	(segment
		(start 219.504768 -369.99672)
		(end 221.628716 -367.872772)
		(width 0.11684)
		(layer "In6.Cu")
		(net "SMB_RT_CPU1_P2_ROM_MUX_2D_SCL")
	)
	(segment
		(start 168.75252 -409.976574)
		(end 165.928294 -407.152348)
		(width 0.11684)
		(layer "In6.Cu")
		(net "SMB_RT_CPU1_P2_ROM_MUX_2D_SCL")
	)
	(segment
		(start 168.499282 -414.372552)
		(end 168.499282 -412.460186)
		(width 0.11684)
		(layer "In6.Cu")
		(net "SMB_RT_CPU1_P2_ROM_MUX_2D_SCL")
	)
	(segment
		(start 167.970708 -415.630106)
		(end 168.234614 -415.3662)
		(width 0.11684)
		(layer "In6.Cu")
		(net "SMB_RT_CPU1_P2_ROM_MUX_2D_SCL")
	)
	(segment
		(start 173.829218 -389.800592)
		(end 178.675538 -384.954272)
		(width 0.11684)
		(layer "In6.Cu")
		(net "SMB_RT_CPU1_P2_ROM_MUX_2D_SCL")
	)
	(segment
		(start 168.75252 -412.206948)
		(end 168.75252 -409.976574)
		(width 0.11684)
		(layer "In6.Cu")
		(net "SMB_RT_CPU1_P2_ROM_MUX_2D_SCL")
	)
	(segment
		(start 166.281862 -425.297092)
		(end 167.83558 -423.743374)
		(width 0.11684)
		(layer "In6.Cu")
		(net "SMB_RT_CPU1_P2_ROM_MUX_2D_SCL")
	)
	(segment
		(start 167.83558 -422.223438)
		(end 166.852346 -421.240204)
		(width 0.11684)
		(layer "In6.Cu")
		(net "SMB_RT_CPU1_P2_ROM_MUX_2D_SCL")
	)
	(segment
		(start 222.976186 -363.160564)
		(end 224.352866 -361.783884)
		(width 0.11684)
		(layer "In6.Cu")
		(net "SMB_RT_CPU1_P2_ROM_MUX_2D_SCL")
	)
	(segment
		(start 164.637974 -401.390358)
		(end 164.637974 -397.851884)
		(width 0.11684)
		(layer "In6.Cu")
		(net "SMB_RT_CPU1_P2_ROM_MUX_2D_SCL")
	)
	(segment
		(start 222.976186 -364.177834)
		(end 222.976186 -363.160564)
		(width 0.11684)
		(layer "In6.Cu")
		(net "SMB_RT_CPU1_P2_ROM_MUX_2D_SCL")
	)
	(segment
		(start 164.637974 -397.851884)
		(end 166.474648 -396.01521)
		(width 0.11684)
		(layer "In6.Cu")
		(net "SMB_RT_CPU1_P2_ROM_MUX_2D_SCL")
	)
	(segment
		(start 166.961058 -419.411404)
		(end 166.961058 -418.078412)
		(width 0.11684)
		(layer "In6.Cu")
		(net "SMB_RT_CPU1_P2_ROM_MUX_2D_SCL")
	)
	(via
		(at 158.28645 -417.633658)
		(size 0.6604)
		(drill 0.3302)
		(layers "F.Cu" "B.Cu")
		(net "SMB_RT_CPU1_P2_ROM_MUX_1D_SDA")
	)
	(segment
		(start 157.65272 -414.38322)
		(end 155.33624 -416.6997)
		(width 0.10668)
		(layer "B.Cu")
		(net "SMB_RT_CPU1_P2_ROM_MUX_1D_SDA")
	)
	(segment
		(start 158.8897 -414.38322)
		(end 157.65272 -414.38322)
		(width 0.10668)
		(layer "B.Cu")
		(net "SMB_RT_CPU1_P2_ROM_MUX_1D_SDA")
	)
	(segment
		(start 157.619192 -416.9664)
		(end 157.4927 -416.9664)
		(width 0.10668)
		(layer "B.Cu")
		(net "SMB_RT_CPU1_P2_ROM_MUX_1D_SDA")
	)
	(segment
		(start 158.665164 -417.254944)
		(end 158.28645 -417.633658)
		(width 0.10668)
		(layer "B.Cu")
		(net "SMB_RT_CPU1_P2_ROM_MUX_1D_SDA")
	)
	(segment
		(start 159.50438 -413.76854)
		(end 158.8897 -414.38322)
		(width 0.10668)
		(layer "B.Cu")
		(net "SMB_RT_CPU1_P2_ROM_MUX_1D_SDA")
	)
	(segment
		(start 155.33624 -417.17468)
		(end 155.72994 -417.56838)
		(width 0.10668)
		(layer "B.Cu")
		(net "SMB_RT_CPU1_P2_ROM_MUX_1D_SDA")
	)
	(segment
		(start 163.4236 -412.45536)
		(end 163.4236 -412.48076)
		(width 0.10668)
		(layer "B.Cu")
		(net "SMB_RT_CPU1_P2_ROM_MUX_1D_SDA")
	)
	(segment
		(start 155.33624 -416.6997)
		(end 155.33624 -417.17468)
		(width 0.10668)
		(layer "B.Cu")
		(net "SMB_RT_CPU1_P2_ROM_MUX_1D_SDA")
	)
	(segment
		(start 157.33014 -417.56838)
		(end 157.4927 -417.40582)
		(width 0.10668)
		(layer "B.Cu")
		(net "SMB_RT_CPU1_P2_ROM_MUX_1D_SDA")
	)
	(segment
		(start 163.4236 -412.48076)
		(end 162.13582 -413.76854)
		(width 0.10668)
		(layer "B.Cu")
		(net "SMB_RT_CPU1_P2_ROM_MUX_1D_SDA")
	)
	(segment
		(start 162.13582 -413.76854)
		(end 159.50438 -413.76854)
		(width 0.10668)
		(layer "B.Cu")
		(net "SMB_RT_CPU1_P2_ROM_MUX_1D_SDA")
	)
	(segment
		(start 159.463232 -417.254944)
		(end 158.665164 -417.254944)
		(width 0.10668)
		(layer "B.Cu")
		(net "SMB_RT_CPU1_P2_ROM_MUX_1D_SDA")
	)
	(segment
		(start 158.28645 -417.633658)
		(end 157.619192 -416.9664)
		(width 0.10668)
		(layer "B.Cu")
		(net "SMB_RT_CPU1_P2_ROM_MUX_1D_SDA")
	)
	(segment
		(start 155.72994 -417.56838)
		(end 157.33014 -417.56838)
		(width 0.10668)
		(layer "B.Cu")
		(net "SMB_RT_CPU1_P2_ROM_MUX_1D_SDA")
	)
	(segment
		(start 157.4927 -417.40582)
		(end 157.4927 -416.9664)
		(width 0.10668)
		(layer "B.Cu")
		(net "SMB_RT_CPU1_P2_ROM_MUX_1D_SDA")
	)
	(via
		(at 158.29407 -416.331146)
		(size 0.6604)
		(drill 0.3302)
		(layers "F.Cu" "B.Cu")
		(net "SMB_RT_CPU1_P2_ROM_MUX_1D_SCL")
	)
	(segment
		(start 163.00196 -413.8041)
		(end 162.60064 -414.20542)
		(width 0.10668)
		(layer "B.Cu")
		(net "SMB_RT_CPU1_P2_ROM_MUX_1D_SCL")
	)
	(segment
		(start 159.03829 -416.754818)
		(end 158.614618 -416.331146)
		(width 0.10668)
		(layer "B.Cu")
		(net "SMB_RT_CPU1_P2_ROM_MUX_1D_SCL")
	)
	(segment
		(start 157.59938 -415.29)
		(end 157.4927 -415.39668)
		(width 0.10668)
		(layer "B.Cu")
		(net "SMB_RT_CPU1_P2_ROM_MUX_1D_SCL")
	)
	(segment
		(start 158.116524 -416.1536)
		(end 158.29407 -416.331146)
		(width 0.10668)
		(layer "B.Cu")
		(net "SMB_RT_CPU1_P2_ROM_MUX_1D_SCL")
	)
	(segment
		(start 157.4927 -416.1536)
		(end 158.116524 -416.1536)
		(width 0.10668)
		(layer "B.Cu")
		(net "SMB_RT_CPU1_P2_ROM_MUX_1D_SCL")
	)
	(segment
		(start 158.614618 -416.331146)
		(end 158.29407 -416.331146)
		(width 0.10668)
		(layer "B.Cu")
		(net "SMB_RT_CPU1_P2_ROM_MUX_1D_SCL")
	)
	(segment
		(start 159.69996 -414.20542)
		(end 158.61538 -415.29)
		(width 0.10668)
		(layer "B.Cu")
		(net "SMB_RT_CPU1_P2_ROM_MUX_1D_SCL")
	)
	(segment
		(start 162.60064 -414.20542)
		(end 159.69996 -414.20542)
		(width 0.10668)
		(layer "B.Cu")
		(net "SMB_RT_CPU1_P2_ROM_MUX_1D_SCL")
	)
	(segment
		(start 158.61538 -415.29)
		(end 157.59938 -415.29)
		(width 0.10668)
		(layer "B.Cu")
		(net "SMB_RT_CPU1_P2_ROM_MUX_1D_SCL")
	)
	(segment
		(start 157.4927 -415.39668)
		(end 157.4927 -416.1536)
		(width 0.10668)
		(layer "B.Cu")
		(net "SMB_RT_CPU1_P2_ROM_MUX_1D_SCL")
	)
	(segment
		(start 159.463232 -416.754818)
		(end 159.03829 -416.754818)
		(width 0.10668)
		(layer "B.Cu")
		(net "SMB_RT_CPU1_P2_ROM_MUX_1D_SCL")
	)
	(segment
		(start 163.46932 -413.8041)
		(end 163.00196 -413.8041)
		(width 0.10668)
		(layer "B.Cu")
		(net "SMB_RT_CPU1_P2_ROM_MUX_1D_SCL")
	)
	(segment
		(start 116.29644 -402.371052)
		(end 116.029232 -402.103844)
		(width 0.10668)
		(layer "F.Cu")
		(net "SMB_RT_CPU1_P1_ROM_MUX_2D_SDA")
	)
	(segment
		(start 120.200928 -399.354802)
		(end 120.200928 -401.479258)
		(width 0.10668)
		(layer "F.Cu")
		(net "SMB_RT_CPU1_P1_ROM_MUX_2D_SDA")
	)
	(segment
		(start 118.297198 -403.382988)
		(end 117.104414 -403.382988)
		(width 0.10668)
		(layer "F.Cu")
		(net "SMB_RT_CPU1_P1_ROM_MUX_2D_SDA")
	)
	(segment
		(start 120.200928 -401.479258)
		(end 118.297198 -403.382988)
		(width 0.10668)
		(layer "F.Cu")
		(net "SMB_RT_CPU1_P1_ROM_MUX_2D_SDA")
	)
	(segment
		(start 113.51514 -396.772892)
		(end 117.619018 -396.772892)
		(width 0.10668)
		(layer "F.Cu")
		(net "SMB_RT_CPU1_P1_ROM_MUX_2D_SDA")
	)
	(segment
		(start 117.104414 -403.382988)
		(end 116.29644 -402.575014)
		(width 0.10668)
		(layer "F.Cu")
		(net "SMB_RT_CPU1_P1_ROM_MUX_2D_SDA")
	)
	(segment
		(start 117.619018 -396.772892)
		(end 120.200928 -399.354802)
		(width 0.10668)
		(layer "F.Cu")
		(net "SMB_RT_CPU1_P1_ROM_MUX_2D_SDA")
	)
	(segment
		(start 116.29644 -402.575014)
		(end 116.29644 -402.371052)
		(width 0.10668)
		(layer "F.Cu")
		(net "SMB_RT_CPU1_P1_ROM_MUX_2D_SDA")
	)
	(via
		(at 236.528864 -336.0547)
		(size 0.508)
		(drill 0.254)
		(layers "F.Cu" "B.Cu")
		(net "SMB_RT_CPU1_P1_ROM_MUX_2D_SDA")
	)
	(via
		(at 113.51514 -396.772892)
		(size 0.508)
		(drill 0.254)
		(layers "F.Cu" "B.Cu")
		(net "SMB_RT_CPU1_P1_ROM_MUX_2D_SDA")
	)
	(segment
		(start 236.643164 -336.169)
		(end 236.528864 -336.0547)
		(width 0.10668)
		(layer "B.Cu")
		(net "SMB_RT_CPU1_P1_ROM_MUX_2D_SDA")
	)
	(segment
		(start 238.3663 -336.169)
		(end 236.643164 -336.169)
		(width 0.10668)
		(layer "B.Cu")
		(net "SMB_RT_CPU1_P1_ROM_MUX_2D_SDA")
	)
	(segment
		(start 215.901016 -365.148876)
		(end 221.478348 -359.571544)
		(width 0.11684)
		(layer "In2.Cu")
		(net "SMB_RT_CPU1_P1_ROM_MUX_2D_SDA")
	)
	(segment
		(start 173.211998 -395.30528)
		(end 173.211998 -392.265916)
		(width 0.11684)
		(layer "In2.Cu")
		(net "SMB_RT_CPU1_P1_ROM_MUX_2D_SDA")
	)
	(segment
		(start 201.915014 -369.348512)
		(end 206.11465 -365.148876)
		(width 0.11684)
		(layer "In2.Cu")
		(net "SMB_RT_CPU1_P1_ROM_MUX_2D_SDA")
	)
	(segment
		(start 186.420252 -379.90399)
		(end 186.420252 -378.747782)
		(width 0.11684)
		(layer "In2.Cu")
		(net "SMB_RT_CPU1_P1_ROM_MUX_2D_SDA")
	)
	(segment
		(start 223.674178 -350.089724)
		(end 223.674178 -338.556854)
		(width 0.11684)
		(layer "In2.Cu")
		(net "SMB_RT_CPU1_P1_ROM_MUX_2D_SDA")
	)
	(segment
		(start 171.115736 -397.401542)
		(end 173.211998 -395.30528)
		(width 0.11684)
		(layer "In2.Cu")
		(net "SMB_RT_CPU1_P1_ROM_MUX_2D_SDA")
	)
	(segment
		(start 206.11465 -365.148876)
		(end 215.901016 -365.148876)
		(width 0.11684)
		(layer "In2.Cu")
		(net "SMB_RT_CPU1_P1_ROM_MUX_2D_SDA")
	)
	(segment
		(start 166.9288 -397.082264)
		(end 167.248078 -397.401542)
		(width 0.11684)
		(layer "In2.Cu")
		(net "SMB_RT_CPU1_P1_ROM_MUX_2D_SDA")
	)
	(segment
		(start 113.675668 -396.93342)
		(end 164.63264 -396.93342)
		(width 0.11684)
		(layer "In2.Cu")
		(net "SMB_RT_CPU1_P1_ROM_MUX_2D_SDA")
	)
	(segment
		(start 227.282248 -334.948784)
		(end 234.204256 -334.948784)
		(width 0.11684)
		(layer "In2.Cu")
		(net "SMB_RT_CPU1_P1_ROM_MUX_2D_SDA")
	)
	(segment
		(start 164.63264 -396.93342)
		(end 164.781484 -397.082264)
		(width 0.11684)
		(layer "In2.Cu")
		(net "SMB_RT_CPU1_P1_ROM_MUX_2D_SDA")
	)
	(segment
		(start 198.323454 -369.348512)
		(end 201.915014 -369.348512)
		(width 0.11684)
		(layer "In2.Cu")
		(net "SMB_RT_CPU1_P1_ROM_MUX_2D_SDA")
	)
	(segment
		(start 235.310172 -336.0547)
		(end 236.528864 -336.0547)
		(width 0.11684)
		(layer "In2.Cu")
		(net "SMB_RT_CPU1_P1_ROM_MUX_2D_SDA")
	)
	(segment
		(start 113.51514 -396.772892)
		(end 113.675668 -396.93342)
		(width 0.11684)
		(layer "In2.Cu")
		(net "SMB_RT_CPU1_P1_ROM_MUX_2D_SDA")
	)
	(segment
		(start 186.420252 -378.747782)
		(end 190.20155 -374.966484)
		(width 0.11684)
		(layer "In2.Cu")
		(net "SMB_RT_CPU1_P1_ROM_MUX_2D_SDA")
	)
	(segment
		(start 190.20155 -374.966484)
		(end 192.705482 -374.966484)
		(width 0.11684)
		(layer "In2.Cu")
		(net "SMB_RT_CPU1_P1_ROM_MUX_2D_SDA")
	)
	(segment
		(start 181.393338 -384.930904)
		(end 186.420252 -379.90399)
		(width 0.11684)
		(layer "In2.Cu")
		(net "SMB_RT_CPU1_P1_ROM_MUX_2D_SDA")
	)
	(segment
		(start 234.204256 -334.948784)
		(end 235.310172 -336.0547)
		(width 0.11684)
		(layer "In2.Cu")
		(net "SMB_RT_CPU1_P1_ROM_MUX_2D_SDA")
	)
	(segment
		(start 223.674178 -338.556854)
		(end 227.282248 -334.948784)
		(width 0.11684)
		(layer "In2.Cu")
		(net "SMB_RT_CPU1_P1_ROM_MUX_2D_SDA")
	)
	(segment
		(start 221.478348 -359.571544)
		(end 221.478348 -352.285554)
		(width 0.11684)
		(layer "In2.Cu")
		(net "SMB_RT_CPU1_P1_ROM_MUX_2D_SDA")
	)
	(segment
		(start 167.248078 -397.401542)
		(end 171.115736 -397.401542)
		(width 0.11684)
		(layer "In2.Cu")
		(net "SMB_RT_CPU1_P1_ROM_MUX_2D_SDA")
	)
	(segment
		(start 192.705482 -374.966484)
		(end 198.323454 -369.348512)
		(width 0.11684)
		(layer "In2.Cu")
		(net "SMB_RT_CPU1_P1_ROM_MUX_2D_SDA")
	)
	(segment
		(start 173.211998 -392.265916)
		(end 180.54701 -384.930904)
		(width 0.11684)
		(layer "In2.Cu")
		(net "SMB_RT_CPU1_P1_ROM_MUX_2D_SDA")
	)
	(segment
		(start 164.781484 -397.082264)
		(end 166.9288 -397.082264)
		(width 0.11684)
		(layer "In2.Cu")
		(net "SMB_RT_CPU1_P1_ROM_MUX_2D_SDA")
	)
	(segment
		(start 180.54701 -384.930904)
		(end 181.393338 -384.930904)
		(width 0.11684)
		(layer "In2.Cu")
		(net "SMB_RT_CPU1_P1_ROM_MUX_2D_SDA")
	)
	(segment
		(start 221.478348 -352.285554)
		(end 223.674178 -350.089724)
		(width 0.11684)
		(layer "In2.Cu")
		(net "SMB_RT_CPU1_P1_ROM_MUX_2D_SDA")
	)
	(segment
		(start 116.45138 -401.832826)
		(end 116.222272 -401.603718)
		(width 0.10668)
		(layer "F.Cu")
		(net "SMB_RT_CPU1_P1_ROM_MUX_2D_SCL")
	)
	(segment
		(start 119.84736 -399.50136)
		(end 119.84736 -401.3327)
		(width 0.10668)
		(layer "F.Cu")
		(net "SMB_RT_CPU1_P1_ROM_MUX_2D_SCL")
	)
	(segment
		(start 113.48974 -397.51508)
		(end 113.87836 -397.12646)
		(width 0.10668)
		(layer "F.Cu")
		(net "SMB_RT_CPU1_P1_ROM_MUX_2D_SCL")
	)
	(segment
		(start 118.15064 -403.02942)
		(end 117.3988 -403.02942)
		(width 0.10668)
		(layer "F.Cu")
		(net "SMB_RT_CPU1_P1_ROM_MUX_2D_SCL")
	)
	(segment
		(start 117.3988 -403.02942)
		(end 116.627148 -402.257768)
		(width 0.10668)
		(layer "F.Cu")
		(net "SMB_RT_CPU1_P1_ROM_MUX_2D_SCL")
	)
	(segment
		(start 116.222272 -401.603718)
		(end 116.029232 -401.603718)
		(width 0.10668)
		(layer "F.Cu")
		(net "SMB_RT_CPU1_P1_ROM_MUX_2D_SCL")
	)
	(segment
		(start 116.627148 -402.257768)
		(end 116.45138 -401.832826)
		(width 0.10668)
		(layer "F.Cu")
		(net "SMB_RT_CPU1_P1_ROM_MUX_2D_SCL")
	)
	(segment
		(start 119.84736 -401.3327)
		(end 118.15064 -403.02942)
		(width 0.10668)
		(layer "F.Cu")
		(net "SMB_RT_CPU1_P1_ROM_MUX_2D_SCL")
	)
	(segment
		(start 117.47246 -397.12646)
		(end 119.84736 -399.50136)
		(width 0.10668)
		(layer "F.Cu")
		(net "SMB_RT_CPU1_P1_ROM_MUX_2D_SCL")
	)
	(segment
		(start 113.87836 -397.12646)
		(end 117.47246 -397.12646)
		(width 0.10668)
		(layer "F.Cu")
		(net "SMB_RT_CPU1_P1_ROM_MUX_2D_SCL")
	)
	(via
		(at 113.48974 -397.51508)
		(size 0.508)
		(drill 0.254)
		(layers "F.Cu" "B.Cu")
		(net "SMB_RT_CPU1_P1_ROM_MUX_2D_SCL")
	)
	(via
		(at 236.556804 -337.430618)
		(size 0.508)
		(drill 0.254)
		(layers "F.Cu" "B.Cu")
		(net "SMB_RT_CPU1_P1_ROM_MUX_2D_SCL")
	)
	(segment
		(start 236.675422 -337.312)
		(end 236.556804 -337.430618)
		(width 0.10668)
		(layer "B.Cu")
		(net "SMB_RT_CPU1_P1_ROM_MUX_2D_SCL")
	)
	(segment
		(start 238.3663 -337.312)
		(end 236.675422 -337.312)
		(width 0.10668)
		(layer "B.Cu")
		(net "SMB_RT_CPU1_P1_ROM_MUX_2D_SCL")
	)
	(segment
		(start 192.83299 -375.435622)
		(end 198.44639 -369.822222)
		(width 0.11684)
		(layer "In2.Cu")
		(net "SMB_RT_CPU1_P1_ROM_MUX_2D_SCL")
	)
	(segment
		(start 190.382144 -375.435622)
		(end 192.83299 -375.435622)
		(width 0.11684)
		(layer "In2.Cu")
		(net "SMB_RT_CPU1_P1_ROM_MUX_2D_SCL")
	)
	(segment
		(start 173.633638 -395.480032)
		(end 173.633638 -392.440922)
		(width 0.11684)
		(layer "In2.Cu")
		(net "SMB_RT_CPU1_P1_ROM_MUX_2D_SCL")
	)
	(segment
		(start 186.855608 -380.06528)
		(end 186.855608 -378.962158)
		(width 0.11684)
		(layer "In2.Cu")
		(net "SMB_RT_CPU1_P1_ROM_MUX_2D_SCL")
	)
	(segment
		(start 222.864934 -351.6884)
		(end 224.232216 -350.321118)
		(width 0.11684)
		(layer "In2.Cu")
		(net "SMB_RT_CPU1_P1_ROM_MUX_2D_SCL")
	)
	(segment
		(start 165.895528 -397.63573)
		(end 166.08298 -397.823182)
		(width 0.11684)
		(layer "In2.Cu")
		(net "SMB_RT_CPU1_P1_ROM_MUX_2D_SCL")
	)
	(segment
		(start 221.943676 -359.407714)
		(end 222.864934 -358.486456)
		(width 0.11684)
		(layer "In2.Cu")
		(net "SMB_RT_CPU1_P1_ROM_MUX_2D_SCL")
	)
	(segment
		(start 206.300578 -365.684054)
		(end 215.982042 -365.684054)
		(width 0.11684)
		(layer "In2.Cu")
		(net "SMB_RT_CPU1_P1_ROM_MUX_2D_SCL")
	)
	(segment
		(start 164.27958 -397.36776)
		(end 164.54755 -397.63573)
		(width 0.11684)
		(layer "In2.Cu")
		(net "SMB_RT_CPU1_P1_ROM_MUX_2D_SCL")
	)
	(segment
		(start 186.855608 -378.962158)
		(end 190.382144 -375.435622)
		(width 0.11684)
		(layer "In2.Cu")
		(net "SMB_RT_CPU1_P1_ROM_MUX_2D_SCL")
	)
	(segment
		(start 166.08298 -397.823182)
		(end 171.290488 -397.823182)
		(width 0.11684)
		(layer "In2.Cu")
		(net "SMB_RT_CPU1_P1_ROM_MUX_2D_SCL")
	)
	(segment
		(start 224.232216 -338.788248)
		(end 226.534218 -336.486246)
		(width 0.11684)
		(layer "In2.Cu")
		(net "SMB_RT_CPU1_P1_ROM_MUX_2D_SCL")
	)
	(segment
		(start 233.873548 -336.82686)
		(end 235.635292 -336.82686)
		(width 0.11684)
		(layer "In2.Cu")
		(net "SMB_RT_CPU1_P1_ROM_MUX_2D_SCL")
	)
	(segment
		(start 173.633638 -392.440922)
		(end 180.722016 -385.352544)
		(width 0.11684)
		(layer "In2.Cu")
		(net "SMB_RT_CPU1_P1_ROM_MUX_2D_SCL")
	)
	(segment
		(start 198.44639 -369.822222)
		(end 202.16241 -369.822222)
		(width 0.11684)
		(layer "In2.Cu")
		(net "SMB_RT_CPU1_P1_ROM_MUX_2D_SCL")
	)
	(segment
		(start 226.534218 -336.486246)
		(end 233.532934 -336.486246)
		(width 0.11684)
		(layer "In2.Cu")
		(net "SMB_RT_CPU1_P1_ROM_MUX_2D_SCL")
	)
	(segment
		(start 236.23905 -337.430618)
		(end 236.556804 -337.430618)
		(width 0.11684)
		(layer "In2.Cu")
		(net "SMB_RT_CPU1_P1_ROM_MUX_2D_SCL")
	)
	(segment
		(start 215.982042 -365.684054)
		(end 221.943676 -359.72242)
		(width 0.11684)
		(layer "In2.Cu")
		(net "SMB_RT_CPU1_P1_ROM_MUX_2D_SCL")
	)
	(segment
		(start 113.63706 -397.36776)
		(end 164.27958 -397.36776)
		(width 0.11684)
		(layer "In2.Cu")
		(net "SMB_RT_CPU1_P1_ROM_MUX_2D_SCL")
	)
	(segment
		(start 180.722016 -385.352544)
		(end 181.568344 -385.352544)
		(width 0.11684)
		(layer "In2.Cu")
		(net "SMB_RT_CPU1_P1_ROM_MUX_2D_SCL")
	)
	(segment
		(start 233.532934 -336.486246)
		(end 233.873548 -336.82686)
		(width 0.11684)
		(layer "In2.Cu")
		(net "SMB_RT_CPU1_P1_ROM_MUX_2D_SCL")
	)
	(segment
		(start 202.16241 -369.822222)
		(end 206.300578 -365.684054)
		(width 0.11684)
		(layer "In2.Cu")
		(net "SMB_RT_CPU1_P1_ROM_MUX_2D_SCL")
	)
	(segment
		(start 224.232216 -350.321118)
		(end 224.232216 -338.788248)
		(width 0.11684)
		(layer "In2.Cu")
		(net "SMB_RT_CPU1_P1_ROM_MUX_2D_SCL")
	)
	(segment
		(start 221.943676 -359.72242)
		(end 221.943676 -359.407714)
		(width 0.11684)
		(layer "In2.Cu")
		(net "SMB_RT_CPU1_P1_ROM_MUX_2D_SCL")
	)
	(segment
		(start 113.48974 -397.51508)
		(end 113.63706 -397.36776)
		(width 0.11684)
		(layer "In2.Cu")
		(net "SMB_RT_CPU1_P1_ROM_MUX_2D_SCL")
	)
	(segment
		(start 235.635292 -336.82686)
		(end 236.23905 -337.430618)
		(width 0.11684)
		(layer "In2.Cu")
		(net "SMB_RT_CPU1_P1_ROM_MUX_2D_SCL")
	)
	(segment
		(start 222.864934 -358.486456)
		(end 222.864934 -351.6884)
		(width 0.11684)
		(layer "In2.Cu")
		(net "SMB_RT_CPU1_P1_ROM_MUX_2D_SCL")
	)
	(segment
		(start 181.568344 -385.352544)
		(end 186.855608 -380.06528)
		(width 0.11684)
		(layer "In2.Cu")
		(net "SMB_RT_CPU1_P1_ROM_MUX_2D_SCL")
	)
	(segment
		(start 164.54755 -397.63573)
		(end 165.895528 -397.63573)
		(width 0.11684)
		(layer "In2.Cu")
		(net "SMB_RT_CPU1_P1_ROM_MUX_2D_SCL")
	)
	(segment
		(start 171.290488 -397.823182)
		(end 173.633638 -395.480032)
		(width 0.11684)
		(layer "In2.Cu")
		(net "SMB_RT_CPU1_P1_ROM_MUX_2D_SCL")
	)
	(segment
		(start 118.80342 -401.1676)
		(end 119.291608 -400.679412)
		(width 0.10668)
		(layer "F.Cu")
		(net "SMB_RT_CPU1_P1_ROM_MUX_1D_SDA")
	)
	(segment
		(start 117.749574 -402.39188)
		(end 118.3767 -401.764754)
		(width 0.10668)
		(layer "F.Cu")
		(net "SMB_RT_CPU1_P1_ROM_MUX_1D_SDA")
	)
	(segment
		(start 117.25148 -402.39188)
		(end 117.749574 -402.39188)
		(width 0.10668)
		(layer "F.Cu")
		(net "SMB_RT_CPU1_P1_ROM_MUX_1D_SDA")
	)
	(segment
		(start 116.029232 -401.103846)
		(end 116.22024 -401.103846)
		(width 0.10668)
		(layer "F.Cu")
		(net "SMB_RT_CPU1_P1_ROM_MUX_1D_SDA")
	)
	(segment
		(start 104.83342 -394.91666)
		(end 104.71658 -395.0335)
		(width 0.10668)
		(layer "F.Cu")
		(net "SMB_RT_CPU1_P1_ROM_MUX_1D_SDA")
	)
	(segment
		(start 116.22024 -401.103846)
		(end 116.761006 -401.644612)
		(width 0.10668)
		(layer "F.Cu")
		(net "SMB_RT_CPU1_P1_ROM_MUX_1D_SDA")
	)
	(segment
		(start 104.71658 -395.0335)
		(end 104.47528 -395.0335)
		(width 0.10668)
		(layer "F.Cu")
		(net "SMB_RT_CPU1_P1_ROM_MUX_1D_SDA")
	)
	(segment
		(start 119.291608 -400.679412)
		(end 119.291608 -399.580354)
		(width 0.10668)
		(layer "F.Cu")
		(net "SMB_RT_CPU1_P1_ROM_MUX_1D_SDA")
	)
	(segment
		(start 111.188754 -396.225268)
		(end 111.188754 -395.760956)
		(width 0.10668)
		(layer "F.Cu")
		(net "SMB_RT_CPU1_P1_ROM_MUX_1D_SDA")
	)
	(segment
		(start 112.25022 -397.107918)
		(end 112.071404 -397.107918)
		(width 0.10668)
		(layer "F.Cu")
		(net "SMB_RT_CPU1_P1_ROM_MUX_1D_SDA")
	)
	(segment
		(start 112.071404 -397.107918)
		(end 111.188754 -396.225268)
		(width 0.10668)
		(layer "F.Cu")
		(net "SMB_RT_CPU1_P1_ROM_MUX_1D_SDA")
	)
	(segment
		(start 118.3767 -401.764754)
		(end 118.3767 -401.1676)
		(width 0.10668)
		(layer "F.Cu")
		(net "SMB_RT_CPU1_P1_ROM_MUX_1D_SDA")
	)
	(segment
		(start 119.291608 -399.580354)
		(end 117.877844 -398.16659)
		(width 0.10668)
		(layer "F.Cu")
		(net "SMB_RT_CPU1_P1_ROM_MUX_1D_SDA")
	)
	(segment
		(start 118.3767 -401.1676)
		(end 118.80342 -401.1676)
		(width 0.10668)
		(layer "F.Cu")
		(net "SMB_RT_CPU1_P1_ROM_MUX_1D_SDA")
	)
	(segment
		(start 106.32948 -394.91666)
		(end 104.83342 -394.91666)
		(width 0.10668)
		(layer "F.Cu")
		(net "SMB_RT_CPU1_P1_ROM_MUX_1D_SDA")
	)
	(segment
		(start 116.942616 -402.083016)
		(end 117.25148 -402.39188)
		(width 0.10668)
		(layer "F.Cu")
		(net "SMB_RT_CPU1_P1_ROM_MUX_1D_SDA")
	)
	(segment
		(start 116.761006 -401.644612)
		(end 116.942616 -402.083016)
		(width 0.10668)
		(layer "F.Cu")
		(net "SMB_RT_CPU1_P1_ROM_MUX_1D_SDA")
	)
	(segment
		(start 106.548936 -394.697204)
		(end 106.32948 -394.91666)
		(width 0.10668)
		(layer "F.Cu")
		(net "SMB_RT_CPU1_P1_ROM_MUX_1D_SDA")
	)
	(segment
		(start 113.308892 -398.16659)
		(end 112.25022 -397.107918)
		(width 0.10668)
		(layer "F.Cu")
		(net "SMB_RT_CPU1_P1_ROM_MUX_1D_SDA")
	)
	(segment
		(start 117.877844 -398.16659)
		(end 113.308892 -398.16659)
		(width 0.10668)
		(layer "F.Cu")
		(net "SMB_RT_CPU1_P1_ROM_MUX_1D_SDA")
	)
	(segment
		(start 110.125002 -394.697204)
		(end 106.548936 -394.697204)
		(width 0.10668)
		(layer "F.Cu")
		(net "SMB_RT_CPU1_P1_ROM_MUX_1D_SDA")
	)
	(segment
		(start 111.188754 -395.760956)
		(end 110.125002 -394.697204)
		(width 0.10668)
		(layer "F.Cu")
		(net "SMB_RT_CPU1_P1_ROM_MUX_1D_SDA")
	)
	(via
		(at 117.749574 -402.39188)
		(size 0.762)
		(drill 0.381)
		(layers "F.Cu" "B.Cu")
		(net "SMB_RT_CPU1_P1_ROM_MUX_1D_SDA")
	)
	(segment
		(start 117.615208 -398.532604)
		(end 113.157254 -398.532604)
		(width 0.10668)
		(layer "F.Cu")
		(net "SMB_RT_CPU1_P1_ROM_MUX_1D_SCL")
	)
	(segment
		(start 118.3767 -400.3548)
		(end 118.76786 -400.3548)
		(width 0.10668)
		(layer "F.Cu")
		(net "SMB_RT_CPU1_P1_ROM_MUX_1D_SCL")
	)
	(segment
		(start 116.756942 -400.301714)
		(end 116.454936 -400.60372)
		(width 0.10668)
		(layer "F.Cu")
		(net "SMB_RT_CPU1_P1_ROM_MUX_1D_SCL")
	)
	(segment
		(start 118.3767 -400.3548)
		(end 118.3767 -400.25955)
		(width 0.10668)
		(layer "F.Cu")
		(net "SMB_RT_CPU1_P1_ROM_MUX_1D_SCL")
	)
	(segment
		(start 112.24006 -397.61541)
		(end 112.091724 -397.61541)
		(width 0.10668)
		(layer "F.Cu")
		(net "SMB_RT_CPU1_P1_ROM_MUX_1D_SCL")
	)
	(segment
		(start 118.3767 -400.25955)
		(end 117.558566 -399.441416)
		(width 0.10668)
		(layer "F.Cu")
		(net "SMB_RT_CPU1_P1_ROM_MUX_1D_SCL")
	)
	(segment
		(start 106.688382 -395.063218)
		(end 106.19486 -395.55674)
		(width 0.10668)
		(layer "F.Cu")
		(net "SMB_RT_CPU1_P1_ROM_MUX_1D_SCL")
	)
	(segment
		(start 116.756942 -399.441416)
		(end 116.756942 -400.301714)
		(width 0.10668)
		(layer "F.Cu")
		(net "SMB_RT_CPU1_P1_ROM_MUX_1D_SCL")
	)
	(segment
		(start 109.97438 -395.063218)
		(end 106.688382 -395.063218)
		(width 0.10668)
		(layer "F.Cu")
		(net "SMB_RT_CPU1_P1_ROM_MUX_1D_SCL")
	)
	(segment
		(start 112.091724 -397.61541)
		(end 110.834678 -396.358364)
		(width 0.10668)
		(layer "F.Cu")
		(net "SMB_RT_CPU1_P1_ROM_MUX_1D_SCL")
	)
	(segment
		(start 117.558566 -399.441416)
		(end 116.756942 -399.441416)
		(width 0.10668)
		(layer "F.Cu")
		(net "SMB_RT_CPU1_P1_ROM_MUX_1D_SCL")
	)
	(segment
		(start 118.76786 -400.3548)
		(end 118.8847 -400.23796)
		(width 0.10668)
		(layer "F.Cu")
		(net "SMB_RT_CPU1_P1_ROM_MUX_1D_SCL")
	)
	(segment
		(start 118.8847 -399.802096)
		(end 117.615208 -398.532604)
		(width 0.10668)
		(layer "F.Cu")
		(net "SMB_RT_CPU1_P1_ROM_MUX_1D_SCL")
	)
	(segment
		(start 110.834678 -395.923516)
		(end 109.97438 -395.063218)
		(width 0.10668)
		(layer "F.Cu")
		(net "SMB_RT_CPU1_P1_ROM_MUX_1D_SCL")
	)
	(segment
		(start 116.454936 -400.60372)
		(end 116.029232 -400.60372)
		(width 0.10668)
		(layer "F.Cu")
		(net "SMB_RT_CPU1_P1_ROM_MUX_1D_SCL")
	)
	(segment
		(start 113.157254 -398.532604)
		(end 112.24006 -397.61541)
		(width 0.10668)
		(layer "F.Cu")
		(net "SMB_RT_CPU1_P1_ROM_MUX_1D_SCL")
	)
	(segment
		(start 118.8847 -400.23796)
		(end 118.8847 -399.802096)
		(width 0.10668)
		(layer "F.Cu")
		(net "SMB_RT_CPU1_P1_ROM_MUX_1D_SCL")
	)
	(segment
		(start 110.834678 -396.358364)
		(end 110.834678 -395.923516)
		(width 0.10668)
		(layer "F.Cu")
		(net "SMB_RT_CPU1_P1_ROM_MUX_1D_SCL")
	)
	(via
		(at 116.756942 -399.441416)
		(size 0.762)
		(drill 0.381)
		(layers "F.Cu" "B.Cu")
		(net "SMB_RT_CPU1_P1_ROM_MUX_1D_SCL")
	)
	(segment
		(start 105.05313 -401.487894)
		(end 107.004358 -399.536666)
		(width 0.10668)
		(layer "F.Cu")
		(net "SMB_RT_CPU1_P0_ROM_MUX_2D_SDA")
	)
	(segment
		(start 97.33534 -399.3642)
		(end 98.35388 -399.3642)
		(width 0.10668)
		(layer "F.Cu")
		(net "SMB_RT_CPU1_P0_ROM_MUX_2D_SDA")
	)
	(segment
		(start 99.52609 -399.134838)
		(end 100.111306 -399.134838)
		(width 0.10668)
		(layer "F.Cu")
		(net "SMB_RT_CPU1_P0_ROM_MUX_2D_SDA")
	)
	(segment
		(start 100.111306 -399.134838)
		(end 101.27361 -400.297142)
		(width 0.10668)
		(layer "F.Cu")
		(net "SMB_RT_CPU1_P0_ROM_MUX_2D_SDA")
	)
	(segment
		(start 98.40214 -399.31594)
		(end 99.344988 -399.31594)
		(width 0.10668)
		(layer "F.Cu")
		(net "SMB_RT_CPU1_P0_ROM_MUX_2D_SDA")
	)
	(segment
		(start 103.394764 -401.487894)
		(end 105.05313 -401.487894)
		(width 0.10668)
		(layer "F.Cu")
		(net "SMB_RT_CPU1_P0_ROM_MUX_2D_SDA")
	)
	(segment
		(start 98.35388 -399.3642)
		(end 98.40214 -399.31594)
		(width 0.10668)
		(layer "F.Cu")
		(net "SMB_RT_CPU1_P0_ROM_MUX_2D_SDA")
	)
	(segment
		(start 99.344988 -399.31594)
		(end 99.52609 -399.134838)
		(width 0.10668)
		(layer "F.Cu")
		(net "SMB_RT_CPU1_P0_ROM_MUX_2D_SDA")
	)
	(segment
		(start 101.27361 -400.297142)
		(end 102.204012 -400.297142)
		(width 0.10668)
		(layer "F.Cu")
		(net "SMB_RT_CPU1_P0_ROM_MUX_2D_SDA")
	)
	(segment
		(start 107.004358 -399.536666)
		(end 107.004358 -399.268442)
		(width 0.10668)
		(layer "F.Cu")
		(net "SMB_RT_CPU1_P0_ROM_MUX_2D_SDA")
	)
	(segment
		(start 96.590358 -400.109182)
		(end 97.33534 -399.3642)
		(width 0.10668)
		(layer "F.Cu")
		(net "SMB_RT_CPU1_P0_ROM_MUX_2D_SDA")
	)
	(segment
		(start 102.204012 -400.297142)
		(end 103.394764 -401.487894)
		(width 0.10668)
		(layer "F.Cu")
		(net "SMB_RT_CPU1_P0_ROM_MUX_2D_SDA")
	)
	(segment
		(start 96.590358 -401.641564)
		(end 96.590358 -400.109182)
		(width 0.10668)
		(layer "F.Cu")
		(net "SMB_RT_CPU1_P0_ROM_MUX_2D_SDA")
	)
	(via
		(at 237.497112 -333.697326)
		(size 0.508)
		(drill 0.254)
		(layers "F.Cu" "B.Cu")
		(net "SMB_RT_CPU1_P0_ROM_MUX_2D_SDA")
	)
	(via
		(at 107.004358 -399.268442)
		(size 0.508)
		(drill 0.254)
		(layers "F.Cu" "B.Cu")
		(net "SMB_RT_CPU1_P0_ROM_MUX_2D_SDA")
	)
	(segment
		(start 238.3663 -333.883)
		(end 237.682786 -333.883)
		(width 0.10668)
		(layer "B.Cu")
		(net "SMB_RT_CPU1_P0_ROM_MUX_2D_SDA")
	)
	(segment
		(start 237.682786 -333.883)
		(end 237.497112 -333.697326)
		(width 0.10668)
		(layer "B.Cu")
		(net "SMB_RT_CPU1_P0_ROM_MUX_2D_SDA")
	)
	(segment
		(start 225.21037 -350.726502)
		(end 225.21037 -339.644228)
		(width 0.11684)
		(layer "In2.Cu")
		(net "SMB_RT_CPU1_P0_ROM_MUX_2D_SDA")
	)
	(segment
		(start 163.275772 -398.257014)
		(end 164.139372 -399.120614)
		(width 0.11684)
		(layer "In2.Cu")
		(net "SMB_RT_CPU1_P0_ROM_MUX_2D_SDA")
	)
	(segment
		(start 193.900552 -375.77522)
		(end 193.900552 -375.561098)
		(width 0.11684)
		(layer "In2.Cu")
		(net "SMB_RT_CPU1_P0_ROM_MUX_2D_SDA")
	)
	(segment
		(start 223.86798 -358.801162)
		(end 223.86798 -352.068892)
		(width 0.11684)
		(layer "In2.Cu")
		(net "SMB_RT_CPU1_P0_ROM_MUX_2D_SDA")
	)
	(segment
		(start 234.120182 -339.09)
		(end 236.424978 -339.09)
		(width 0.11684)
		(layer "In2.Cu")
		(net "SMB_RT_CPU1_P0_ROM_MUX_2D_SDA")
	)
	(segment
		(start 109.560106 -399.268442)
		(end 110.175548 -398.653)
		(width 0.11684)
		(layer "In2.Cu")
		(net "SMB_RT_CPU1_P0_ROM_MUX_2D_SDA")
	)
	(segment
		(start 225.21037 -339.644228)
		(end 225.905314 -338.949284)
		(width 0.11684)
		(layer "In2.Cu")
		(net "SMB_RT_CPU1_P0_ROM_MUX_2D_SDA")
	)
	(segment
		(start 198.600568 -370.861082)
		(end 202.579986 -370.861082)
		(width 0.11684)
		(layer "In2.Cu")
		(net "SMB_RT_CPU1_P0_ROM_MUX_2D_SDA")
	)
	(segment
		(start 191.04483 -377.06935)
		(end 192.606422 -377.06935)
		(width 0.11684)
		(layer "In2.Cu")
		(net "SMB_RT_CPU1_P0_ROM_MUX_2D_SDA")
	)
	(segment
		(start 172.429932 -398.666462)
		(end 174.476918 -396.619476)
		(width 0.11684)
		(layer "In2.Cu")
		(net "SMB_RT_CPU1_P0_ROM_MUX_2D_SDA")
	)
	(segment
		(start 216.32799 -366.6109)
		(end 223.036892 -359.901998)
		(width 0.11684)
		(layer "In2.Cu")
		(net "SMB_RT_CPU1_P0_ROM_MUX_2D_SDA")
	)
	(segment
		(start 206.830168 -366.6109)
		(end 216.32799 -366.6109)
		(width 0.11684)
		(layer "In2.Cu")
		(net "SMB_RT_CPU1_P0_ROM_MUX_2D_SDA")
	)
	(segment
		(start 181.918356 -386.195824)
		(end 191.04483 -377.06935)
		(width 0.11684)
		(layer "In2.Cu")
		(net "SMB_RT_CPU1_P0_ROM_MUX_2D_SDA")
	)
	(segment
		(start 107.004358 -399.268442)
		(end 109.560106 -399.268442)
		(width 0.11684)
		(layer "In2.Cu")
		(net "SMB_RT_CPU1_P0_ROM_MUX_2D_SDA")
	)
	(segment
		(start 174.476918 -392.790934)
		(end 181.072028 -386.195824)
		(width 0.11684)
		(layer "In2.Cu")
		(net "SMB_RT_CPU1_P0_ROM_MUX_2D_SDA")
	)
	(segment
		(start 238.077502 -337.437476)
		(end 238.077502 -334.277716)
		(width 0.11684)
		(layer "In2.Cu")
		(net "SMB_RT_CPU1_P0_ROM_MUX_2D_SDA")
	)
	(segment
		(start 181.072028 -386.195824)
		(end 181.918356 -386.195824)
		(width 0.11684)
		(layer "In2.Cu")
		(net "SMB_RT_CPU1_P0_ROM_MUX_2D_SDA")
	)
	(segment
		(start 164.139372 -399.120614)
		(end 165.9509 -399.120614)
		(width 0.11684)
		(layer "In2.Cu")
		(net "SMB_RT_CPU1_P0_ROM_MUX_2D_SDA")
	)
	(segment
		(start 225.905314 -338.949284)
		(end 233.979466 -338.949284)
		(width 0.11684)
		(layer "In2.Cu")
		(net "SMB_RT_CPU1_P0_ROM_MUX_2D_SDA")
	)
	(segment
		(start 174.476918 -396.619476)
		(end 174.476918 -392.790934)
		(width 0.11684)
		(layer "In2.Cu")
		(net "SMB_RT_CPU1_P0_ROM_MUX_2D_SDA")
	)
	(segment
		(start 193.900552 -375.561098)
		(end 198.600568 -370.861082)
		(width 0.11684)
		(layer "In2.Cu")
		(net "SMB_RT_CPU1_P0_ROM_MUX_2D_SDA")
	)
	(segment
		(start 223.036892 -359.63225)
		(end 223.86798 -358.801162)
		(width 0.11684)
		(layer "In2.Cu")
		(net "SMB_RT_CPU1_P0_ROM_MUX_2D_SDA")
	)
	(segment
		(start 165.9509 -399.120614)
		(end 166.405052 -398.666462)
		(width 0.11684)
		(layer "In2.Cu")
		(net "SMB_RT_CPU1_P0_ROM_MUX_2D_SDA")
	)
	(segment
		(start 110.175548 -398.653)
		(end 117.851174 -398.653)
		(width 0.11684)
		(layer "In2.Cu")
		(net "SMB_RT_CPU1_P0_ROM_MUX_2D_SDA")
	)
	(segment
		(start 236.424978 -339.09)
		(end 238.077502 -337.437476)
		(width 0.11684)
		(layer "In2.Cu")
		(net "SMB_RT_CPU1_P0_ROM_MUX_2D_SDA")
	)
	(segment
		(start 233.979466 -338.949284)
		(end 234.120182 -339.09)
		(width 0.11684)
		(layer "In2.Cu")
		(net "SMB_RT_CPU1_P0_ROM_MUX_2D_SDA")
	)
	(segment
		(start 166.405052 -398.666462)
		(end 172.429932 -398.666462)
		(width 0.11684)
		(layer "In2.Cu")
		(net "SMB_RT_CPU1_P0_ROM_MUX_2D_SDA")
	)
	(segment
		(start 238.077502 -334.277716)
		(end 237.497112 -333.697326)
		(width 0.11684)
		(layer "In2.Cu")
		(net "SMB_RT_CPU1_P0_ROM_MUX_2D_SDA")
	)
	(segment
		(start 117.851174 -398.653)
		(end 118.24716 -398.257014)
		(width 0.11684)
		(layer "In2.Cu")
		(net "SMB_RT_CPU1_P0_ROM_MUX_2D_SDA")
	)
	(segment
		(start 223.86798 -352.068892)
		(end 225.21037 -350.726502)
		(width 0.11684)
		(layer "In2.Cu")
		(net "SMB_RT_CPU1_P0_ROM_MUX_2D_SDA")
	)
	(segment
		(start 118.24716 -398.257014)
		(end 163.275772 -398.257014)
		(width 0.11684)
		(layer "In2.Cu")
		(net "SMB_RT_CPU1_P0_ROM_MUX_2D_SDA")
	)
	(segment
		(start 202.579986 -370.861082)
		(end 206.830168 -366.6109)
		(width 0.11684)
		(layer "In2.Cu")
		(net "SMB_RT_CPU1_P0_ROM_MUX_2D_SDA")
	)
	(segment
		(start 192.606422 -377.06935)
		(end 193.900552 -375.77522)
		(width 0.11684)
		(layer "In2.Cu")
		(net "SMB_RT_CPU1_P0_ROM_MUX_2D_SDA")
	)
	(segment
		(start 223.036892 -359.901998)
		(end 223.036892 -359.63225)
		(width 0.11684)
		(layer "In2.Cu")
		(net "SMB_RT_CPU1_P0_ROM_MUX_2D_SDA")
	)
	(segment
		(start 98.27006 -398.973294)
		(end 98.219514 -399.02384)
		(width 0.10668)
		(layer "F.Cu")
		(net "SMB_RT_CPU1_P0_ROM_MUX_2D_SCL")
	)
	(segment
		(start 102.331774 -399.94332)
		(end 101.54793 -399.94332)
		(width 0.10668)
		(layer "F.Cu")
		(net "SMB_RT_CPU1_P0_ROM_MUX_2D_SCL")
	)
	(segment
		(start 106.186224 -398.278604)
		(end 106.186224 -399.569178)
		(width 0.10668)
		(layer "F.Cu")
		(net "SMB_RT_CPU1_P0_ROM_MUX_2D_SCL")
	)
	(segment
		(start 96.142302 -400.074638)
		(end 96.142302 -401.871434)
		(width 0.10668)
		(layer "F.Cu")
		(net "SMB_RT_CPU1_P0_ROM_MUX_2D_SCL")
	)
	(segment
		(start 106.490516 -397.974312)
		(end 106.186224 -398.278604)
		(width 0.10668)
		(layer "F.Cu")
		(net "SMB_RT_CPU1_P0_ROM_MUX_2D_SCL")
	)
	(segment
		(start 99.390962 -398.767808)
		(end 99.185476 -398.973294)
		(width 0.10668)
		(layer "F.Cu")
		(net "SMB_RT_CPU1_P0_ROM_MUX_2D_SCL")
	)
	(segment
		(start 106.186224 -399.569178)
		(end 104.607868 -401.147534)
		(width 0.10668)
		(layer "F.Cu")
		(net "SMB_RT_CPU1_P0_ROM_MUX_2D_SCL")
	)
	(segment
		(start 101.54793 -399.94332)
		(end 100.372418 -398.767808)
		(width 0.10668)
		(layer "F.Cu")
		(net "SMB_RT_CPU1_P0_ROM_MUX_2D_SCL")
	)
	(segment
		(start 99.185476 -398.973294)
		(end 98.27006 -398.973294)
		(width 0.10668)
		(layer "F.Cu")
		(net "SMB_RT_CPU1_P0_ROM_MUX_2D_SCL")
	)
	(segment
		(start 103.535988 -401.147534)
		(end 102.331774 -399.94332)
		(width 0.10668)
		(layer "F.Cu")
		(net "SMB_RT_CPU1_P0_ROM_MUX_2D_SCL")
	)
	(segment
		(start 104.607868 -401.147534)
		(end 103.535988 -401.147534)
		(width 0.10668)
		(layer "F.Cu")
		(net "SMB_RT_CPU1_P0_ROM_MUX_2D_SCL")
	)
	(segment
		(start 98.219514 -399.02384)
		(end 97.1931 -399.02384)
		(width 0.10668)
		(layer "F.Cu")
		(net "SMB_RT_CPU1_P0_ROM_MUX_2D_SCL")
	)
	(segment
		(start 96.412558 -402.14169)
		(end 96.590358 -402.14169)
		(width 0.10668)
		(layer "F.Cu")
		(net "SMB_RT_CPU1_P0_ROM_MUX_2D_SCL")
	)
	(segment
		(start 100.372418 -398.767808)
		(end 99.390962 -398.767808)
		(width 0.10668)
		(layer "F.Cu")
		(net "SMB_RT_CPU1_P0_ROM_MUX_2D_SCL")
	)
	(segment
		(start 96.142302 -401.871434)
		(end 96.412558 -402.14169)
		(width 0.10668)
		(layer "F.Cu")
		(net "SMB_RT_CPU1_P0_ROM_MUX_2D_SCL")
	)
	(segment
		(start 97.1931 -399.02384)
		(end 96.142302 -400.074638)
		(width 0.10668)
		(layer "F.Cu")
		(net "SMB_RT_CPU1_P0_ROM_MUX_2D_SCL")
	)
	(via
		(at 106.490516 -397.974312)
		(size 0.508)
		(drill 0.254)
		(layers "F.Cu" "B.Cu")
		(net "SMB_RT_CPU1_P0_ROM_MUX_2D_SCL")
	)
	(via
		(at 237.5662 -334.65135)
		(size 0.508)
		(drill 0.254)
		(layers "F.Cu" "B.Cu")
		(net "SMB_RT_CPU1_P0_ROM_MUX_2D_SCL")
	)
	(segment
		(start 237.99165 -334.65135)
		(end 237.5662 -334.65135)
		(width 0.10668)
		(layer "B.Cu")
		(net "SMB_RT_CPU1_P0_ROM_MUX_2D_SCL")
	)
	(segment
		(start 238.3663 -335.026)
		(end 237.99165 -334.65135)
		(width 0.10668)
		(layer "B.Cu")
		(net "SMB_RT_CPU1_P0_ROM_MUX_2D_SCL")
	)
	(segment
		(start 233.976164 -337.998562)
		(end 233.010456 -337.032854)
		(width 0.11684)
		(layer "In2.Cu")
		(net "SMB_RT_CPU1_P0_ROM_MUX_2D_SCL")
	)
	(segment
		(start 224.78873 -339.01888)
		(end 224.78873 -350.55175)
		(width 0.11684)
		(layer "In2.Cu")
		(net "SMB_RT_CPU1_P0_ROM_MUX_2D_SCL")
	)
	(segment
		(start 107.304586 -398.062704)
		(end 106.578908 -398.062704)
		(width 0.11684)
		(layer "In2.Cu")
		(net "SMB_RT_CPU1_P0_ROM_MUX_2D_SCL")
	)
	(segment
		(start 171.46524 -398.244822)
		(end 166.2303 -398.244822)
		(width 0.11684)
		(layer "In2.Cu")
		(net "SMB_RT_CPU1_P0_ROM_MUX_2D_SCL")
	)
	(segment
		(start 166.2303 -398.244822)
		(end 165.776148 -398.698974)
		(width 0.11684)
		(layer "In2.Cu")
		(net "SMB_RT_CPU1_P0_ROM_MUX_2D_SCL")
	)
	(segment
		(start 223.44634 -358.626156)
		(end 222.615252 -359.457244)
		(width 0.11684)
		(layer "In2.Cu")
		(net "SMB_RT_CPU1_P0_ROM_MUX_2D_SCL")
	)
	(segment
		(start 223.44634 -351.89414)
		(end 223.44634 -358.626156)
		(width 0.11684)
		(layer "In2.Cu")
		(net "SMB_RT_CPU1_P0_ROM_MUX_2D_SCL")
	)
	(segment
		(start 224.78873 -350.55175)
		(end 223.44634 -351.89414)
		(width 0.11684)
		(layer "In2.Cu")
		(net "SMB_RT_CPU1_P0_ROM_MUX_2D_SCL")
	)
	(segment
		(start 226.774756 -337.032854)
		(end 224.78873 -339.01888)
		(width 0.11684)
		(layer "In2.Cu")
		(net "SMB_RT_CPU1_P0_ROM_MUX_2D_SCL")
	)
	(segment
		(start 236.694218 -337.998562)
		(end 233.976164 -337.998562)
		(width 0.11684)
		(layer "In2.Cu")
		(net "SMB_RT_CPU1_P0_ROM_MUX_2D_SCL")
	)
	(segment
		(start 180.897022 -385.774184)
		(end 174.055278 -392.615928)
		(width 0.11684)
		(layer "In2.Cu")
		(net "SMB_RT_CPU1_P0_ROM_MUX_2D_SCL")
	)
	(segment
		(start 174.055278 -392.615928)
		(end 174.055278 -395.654784)
		(width 0.11684)
		(layer "In2.Cu")
		(net "SMB_RT_CPU1_P0_ROM_MUX_2D_SCL")
	)
	(segment
		(start 202.311254 -370.422932)
		(end 198.442326 -370.422932)
		(width 0.11684)
		(layer "In2.Cu")
		(net "SMB_RT_CPU1_P0_ROM_MUX_2D_SCL")
	)
	(segment
		(start 165.776148 -398.698974)
		(end 164.314124 -398.698974)
		(width 0.11684)
		(layer "In2.Cu")
		(net "SMB_RT_CPU1_P0_ROM_MUX_2D_SCL")
	)
	(segment
		(start 237.617 -334.70215)
		(end 237.617 -337.07578)
		(width 0.11684)
		(layer "In2.Cu")
		(net "SMB_RT_CPU1_P0_ROM_MUX_2D_SCL")
	)
	(segment
		(start 206.544926 -366.18926)
		(end 202.311254 -370.422932)
		(width 0.11684)
		(layer "In2.Cu")
		(net "SMB_RT_CPU1_P0_ROM_MUX_2D_SCL")
	)
	(segment
		(start 187.412122 -379.19279)
		(end 187.412122 -380.105412)
		(width 0.11684)
		(layer "In2.Cu")
		(net "SMB_RT_CPU1_P0_ROM_MUX_2D_SCL")
	)
	(segment
		(start 164.314124 -398.698974)
		(end 163.414964 -397.799814)
		(width 0.11684)
		(layer "In2.Cu")
		(net "SMB_RT_CPU1_P0_ROM_MUX_2D_SCL")
	)
	(segment
		(start 216.153238 -366.18926)
		(end 206.544926 -366.18926)
		(width 0.11684)
		(layer "In2.Cu")
		(net "SMB_RT_CPU1_P0_ROM_MUX_2D_SCL")
	)
	(segment
		(start 106.578908 -398.062704)
		(end 106.490516 -397.974312)
		(width 0.11684)
		(layer "In2.Cu")
		(net "SMB_RT_CPU1_P0_ROM_MUX_2D_SCL")
	)
	(segment
		(start 237.617 -337.07578)
		(end 236.694218 -337.998562)
		(width 0.11684)
		(layer "In2.Cu")
		(net "SMB_RT_CPU1_P0_ROM_MUX_2D_SCL")
	)
	(segment
		(start 187.412122 -380.105412)
		(end 181.74335 -385.774184)
		(width 0.11684)
		(layer "In2.Cu")
		(net "SMB_RT_CPU1_P0_ROM_MUX_2D_SCL")
	)
	(segment
		(start 222.615252 -359.457244)
		(end 222.615252 -359.727246)
		(width 0.11684)
		(layer "In2.Cu")
		(net "SMB_RT_CPU1_P0_ROM_MUX_2D_SCL")
	)
	(segment
		(start 233.010456 -337.032854)
		(end 226.774756 -337.032854)
		(width 0.11684)
		(layer "In2.Cu")
		(net "SMB_RT_CPU1_P0_ROM_MUX_2D_SCL")
	)
	(segment
		(start 117.936772 -397.799814)
		(end 117.520466 -398.21612)
		(width 0.11684)
		(layer "In2.Cu")
		(net "SMB_RT_CPU1_P0_ROM_MUX_2D_SCL")
	)
	(segment
		(start 117.520466 -398.21612)
		(end 107.458002 -398.21612)
		(width 0.11684)
		(layer "In2.Cu")
		(net "SMB_RT_CPU1_P0_ROM_MUX_2D_SCL")
	)
	(segment
		(start 190.683388 -375.921524)
		(end 187.412122 -379.19279)
		(width 0.11684)
		(layer "In2.Cu")
		(net "SMB_RT_CPU1_P0_ROM_MUX_2D_SCL")
	)
	(segment
		(start 237.5662 -334.65135)
		(end 237.617 -334.70215)
		(width 0.11684)
		(layer "In2.Cu")
		(net "SMB_RT_CPU1_P0_ROM_MUX_2D_SCL")
	)
	(segment
		(start 222.615252 -359.727246)
		(end 216.153238 -366.18926)
		(width 0.11684)
		(layer "In2.Cu")
		(net "SMB_RT_CPU1_P0_ROM_MUX_2D_SCL")
	)
	(segment
		(start 198.442326 -370.422932)
		(end 192.943734 -375.921524)
		(width 0.11684)
		(layer "In2.Cu")
		(net "SMB_RT_CPU1_P0_ROM_MUX_2D_SCL")
	)
	(segment
		(start 192.943734 -375.921524)
		(end 190.683388 -375.921524)
		(width 0.11684)
		(layer "In2.Cu")
		(net "SMB_RT_CPU1_P0_ROM_MUX_2D_SCL")
	)
	(segment
		(start 163.414964 -397.799814)
		(end 117.936772 -397.799814)
		(width 0.11684)
		(layer "In2.Cu")
		(net "SMB_RT_CPU1_P0_ROM_MUX_2D_SCL")
	)
	(segment
		(start 107.458002 -398.21612)
		(end 107.304586 -398.062704)
		(width 0.11684)
		(layer "In2.Cu")
		(net "SMB_RT_CPU1_P0_ROM_MUX_2D_SCL")
	)
	(segment
		(start 181.74335 -385.774184)
		(end 180.897022 -385.774184)
		(width 0.11684)
		(layer "In2.Cu")
		(net "SMB_RT_CPU1_P0_ROM_MUX_2D_SCL")
	)
	(segment
		(start 174.055278 -395.654784)
		(end 171.46524 -398.244822)
		(width 0.11684)
		(layer "In2.Cu")
		(net "SMB_RT_CPU1_P0_ROM_MUX_2D_SCL")
	)
	(segment
		(start 96.590358 -402.641562)
		(end 96.32569 -402.641562)
		(width 0.10668)
		(layer "F.Cu")
		(net "SMB_RT_CPU1_P0_ROM_MUX_1D_SDA")
	)
	(segment
		(start 95.7961 -400.596862)
		(end 95.554038 -400.3548)
		(width 0.10668)
		(layer "F.Cu")
		(net "SMB_RT_CPU1_P0_ROM_MUX_1D_SDA")
	)
	(segment
		(start 94.62262 -400.3548)
		(end 93.9165 -401.06092)
		(width 0.10668)
		(layer "F.Cu")
		(net "SMB_RT_CPU1_P0_ROM_MUX_1D_SDA")
	)
	(segment
		(start 94.15526 -399.89252)
		(end 95.1484 -399.89252)
		(width 0.10668)
		(layer "F.Cu")
		(net "SMB_RT_CPU1_P0_ROM_MUX_1D_SDA")
	)
	(segment
		(start 96.32569 -402.641562)
		(end 95.7961 -402.111972)
		(width 0.10668)
		(layer "F.Cu")
		(net "SMB_RT_CPU1_P0_ROM_MUX_1D_SDA")
	)
	(segment
		(start 93.9165 -401.06092)
		(end 93.9165 -401.1676)
		(width 0.10668)
		(layer "F.Cu")
		(net "SMB_RT_CPU1_P0_ROM_MUX_1D_SDA")
	)
	(segment
		(start 93.5228 -400.52498)
		(end 94.15526 -399.89252)
		(width 0.10668)
		(layer "F.Cu")
		(net "SMB_RT_CPU1_P0_ROM_MUX_1D_SDA")
	)
	(segment
		(start 98.031046 -398.68348)
		(end 98.337624 -398.376902)
		(width 0.10668)
		(layer "F.Cu")
		(net "SMB_RT_CPU1_P0_ROM_MUX_1D_SDA")
	)
	(segment
		(start 93.9165 -401.1676)
		(end 93.62948 -401.1676)
		(width 0.10668)
		(layer "F.Cu")
		(net "SMB_RT_CPU1_P0_ROM_MUX_1D_SDA")
	)
	(segment
		(start 95.7961 -402.111972)
		(end 95.7961 -400.596862)
		(width 0.10668)
		(layer "F.Cu")
		(net "SMB_RT_CPU1_P0_ROM_MUX_1D_SDA")
	)
	(segment
		(start 93.5228 -401.06092)
		(end 93.5228 -400.52498)
		(width 0.10668)
		(layer "F.Cu")
		(net "SMB_RT_CPU1_P0_ROM_MUX_1D_SDA")
	)
	(segment
		(start 98.337624 -398.376902)
		(end 98.876104 -398.376902)
		(width 0.10668)
		(layer "F.Cu")
		(net "SMB_RT_CPU1_P0_ROM_MUX_1D_SDA")
	)
	(segment
		(start 42.07256 -379.56236)
		(end 41.48328 -379.56236)
		(width 0.10668)
		(layer "F.Cu")
		(net "SMB_RT_CPU1_P0_ROM_MUX_1D_SDA")
	)
	(segment
		(start 96.89084 -398.68348)
		(end 98.031046 -398.68348)
		(width 0.10668)
		(layer "F.Cu")
		(net "SMB_RT_CPU1_P0_ROM_MUX_1D_SDA")
	)
	(segment
		(start 95.1484 -399.89252)
		(end 95.33636 -399.70456)
		(width 0.10668)
		(layer "F.Cu")
		(net "SMB_RT_CPU1_P0_ROM_MUX_1D_SDA")
	)
	(segment
		(start 95.554038 -400.3548)
		(end 94.62262 -400.3548)
		(width 0.10668)
		(layer "F.Cu")
		(net "SMB_RT_CPU1_P0_ROM_MUX_1D_SDA")
	)
	(segment
		(start 93.62948 -401.1676)
		(end 93.5228 -401.06092)
		(width 0.10668)
		(layer "F.Cu")
		(net "SMB_RT_CPU1_P0_ROM_MUX_1D_SDA")
	)
	(segment
		(start 95.86976 -399.70456)
		(end 96.89084 -398.68348)
		(width 0.10668)
		(layer "F.Cu")
		(net "SMB_RT_CPU1_P0_ROM_MUX_1D_SDA")
	)
	(segment
		(start 95.33636 -399.70456)
		(end 95.86976 -399.70456)
		(width 0.10668)
		(layer "F.Cu")
		(net "SMB_RT_CPU1_P0_ROM_MUX_1D_SDA")
	)
	(via
		(at 41.48328 -379.56236)
		(size 0.508)
		(drill 0.254)
		(layers "F.Cu" "B.Cu")
		(net "SMB_RT_CPU1_P0_ROM_MUX_1D_SDA")
	)
	(via
		(at 44.06646 -391.80516)
		(size 0.508)
		(drill 0.254)
		(layers "F.Cu" "B.Cu")
		(net "SMB_RT_CPU1_P0_ROM_MUX_1D_SDA")
	)
	(via
		(at 98.876104 -398.376902)
		(size 0.508)
		(drill 0.254)
		(layers "F.Cu" "B.Cu")
		(net "SMB_RT_CPU1_P0_ROM_MUX_1D_SDA")
	)
	(via
		(at 95.554038 -400.3548)
		(size 0.762)
		(drill 0.381)
		(layers "F.Cu" "B.Cu")
		(net "SMB_RT_CPU1_P0_ROM_MUX_1D_SDA")
	)
	(segment
		(start 41.91254 -389.97636)
		(end 42.23766 -389.97636)
		(width 0.11684)
		(layer "In2.Cu")
		(net "SMB_RT_CPU1_P0_ROM_MUX_1D_SDA")
	)
	(segment
		(start 39.251128 -385.927346)
		(end 39.88816 -386.564378)
		(width 0.11684)
		(layer "In2.Cu")
		(net "SMB_RT_CPU1_P0_ROM_MUX_1D_SDA")
	)
	(segment
		(start 39.88816 -386.564378)
		(end 39.88816 -387.95198)
		(width 0.11684)
		(layer "In2.Cu")
		(net "SMB_RT_CPU1_P0_ROM_MUX_1D_SDA")
	)
	(segment
		(start 41.482772 -379.562868)
		(end 40.716454 -379.562868)
		(width 0.11684)
		(layer "In2.Cu")
		(net "SMB_RT_CPU1_P0_ROM_MUX_1D_SDA")
	)
	(segment
		(start 39.251128 -381.028194)
		(end 39.251128 -385.927346)
		(width 0.11684)
		(layer "In2.Cu")
		(net "SMB_RT_CPU1_P0_ROM_MUX_1D_SDA")
	)
	(segment
		(start 41.48328 -379.56236)
		(end 41.482772 -379.562868)
		(width 0.11684)
		(layer "In2.Cu")
		(net "SMB_RT_CPU1_P0_ROM_MUX_1D_SDA")
	)
	(segment
		(start 42.23766 -389.97636)
		(end 44.06646 -391.80516)
		(width 0.11684)
		(layer "In2.Cu")
		(net "SMB_RT_CPU1_P0_ROM_MUX_1D_SDA")
	)
	(segment
		(start 39.88816 -387.95198)
		(end 41.91254 -389.97636)
		(width 0.11684)
		(layer "In2.Cu")
		(net "SMB_RT_CPU1_P0_ROM_MUX_1D_SDA")
	)
	(segment
		(start 40.716454 -379.562868)
		(end 39.251128 -381.028194)
		(width 0.11684)
		(layer "In2.Cu")
		(net "SMB_RT_CPU1_P0_ROM_MUX_1D_SDA")
	)
	(segment
		(start 44.06646 -392.3919)
		(end 46.6217 -394.94714)
		(width 0.11684)
		(layer "In4.Cu")
		(net "SMB_RT_CPU1_P0_ROM_MUX_1D_SDA")
	)
	(segment
		(start 96.8883 -396.17142)
		(end 97.76968 -397.0528)
		(width 0.11684)
		(layer "In4.Cu")
		(net "SMB_RT_CPU1_P0_ROM_MUX_1D_SDA")
	)
	(segment
		(start 99.021646 -398.23136)
		(end 98.876104 -398.376902)
		(width 0.11684)
		(layer "In4.Cu")
		(net "SMB_RT_CPU1_P0_ROM_MUX_1D_SDA")
	)
	(segment
		(start 52.61737 -396.17142)
		(end 96.8883 -396.17142)
		(width 0.11684)
		(layer "In4.Cu")
		(net "SMB_RT_CPU1_P0_ROM_MUX_1D_SDA")
	)
	(segment
		(start 46.6217 -394.94714)
		(end 51.39309 -394.94714)
		(width 0.11684)
		(layer "In4.Cu")
		(net "SMB_RT_CPU1_P0_ROM_MUX_1D_SDA")
	)
	(segment
		(start 44.06646 -391.80516)
		(end 44.06646 -392.3919)
		(width 0.11684)
		(layer "In4.Cu")
		(net "SMB_RT_CPU1_P0_ROM_MUX_1D_SDA")
	)
	(segment
		(start 97.76968 -397.0528)
		(end 98.721926 -397.0528)
		(width 0.11684)
		(layer "In4.Cu")
		(net "SMB_RT_CPU1_P0_ROM_MUX_1D_SDA")
	)
	(segment
		(start 98.721926 -397.0528)
		(end 99.021646 -397.35252)
		(width 0.11684)
		(layer "In4.Cu")
		(net "SMB_RT_CPU1_P0_ROM_MUX_1D_SDA")
	)
	(segment
		(start 99.021646 -397.35252)
		(end 99.021646 -398.23136)
		(width 0.11684)
		(layer "In4.Cu")
		(net "SMB_RT_CPU1_P0_ROM_MUX_1D_SDA")
	)
	(segment
		(start 51.39309 -394.94714)
		(end 52.61737 -396.17142)
		(width 0.11684)
		(layer "In4.Cu")
		(net "SMB_RT_CPU1_P0_ROM_MUX_1D_SDA")
	)
	(segment
		(start 93.00718 -400.38782)
		(end 94.02318 -399.37182)
		(width 0.10668)
		(layer "F.Cu")
		(net "SMB_RT_CPU1_P0_ROM_MUX_1D_SCL")
	)
	(segment
		(start 93.9165 -401.9804)
		(end 93.9165 -402.271992)
		(width 0.10668)
		(layer "F.Cu")
		(net "SMB_RT_CPU1_P0_ROM_MUX_1D_SCL")
	)
	(segment
		(start 96.87306 -398.08912)
		(end 98.093022 -398.08912)
		(width 0.10668)
		(layer "F.Cu")
		(net "SMB_RT_CPU1_P0_ROM_MUX_1D_SCL")
	)
	(segment
		(start 94.437962 -402.793454)
		(end 95.032576 -402.793962)
		(width 0.10668)
		(layer "F.Cu")
		(net "SMB_RT_CPU1_P0_ROM_MUX_1D_SCL")
	)
	(segment
		(start 98.093022 -398.08912)
		(end 98.536506 -397.645636)
		(width 0.10668)
		(layer "F.Cu")
		(net "SMB_RT_CPU1_P0_ROM_MUX_1D_SCL")
	)
	(segment
		(start 94.02318 -399.37182)
		(end 94.67596 -399.37182)
		(width 0.10668)
		(layer "F.Cu")
		(net "SMB_RT_CPU1_P0_ROM_MUX_1D_SCL")
	)
	(segment
		(start 93.9165 -402.271992)
		(end 94.437962 -402.793454)
		(width 0.10668)
		(layer "F.Cu")
		(net "SMB_RT_CPU1_P0_ROM_MUX_1D_SCL")
	)
	(segment
		(start 93.9165 -401.9804)
		(end 93.00718 -401.07108)
		(width 0.10668)
		(layer "F.Cu")
		(net "SMB_RT_CPU1_P0_ROM_MUX_1D_SCL")
	)
	(segment
		(start 42.1005 -378.71654)
		(end 41.51884 -378.71654)
		(width 0.10668)
		(layer "F.Cu")
		(net "SMB_RT_CPU1_P0_ROM_MUX_1D_SCL")
	)
	(segment
		(start 94.83598 -399.2118)
		(end 95.75038 -399.2118)
		(width 0.10668)
		(layer "F.Cu")
		(net "SMB_RT_CPU1_P0_ROM_MUX_1D_SCL")
	)
	(segment
		(start 95.75038 -399.2118)
		(end 96.87306 -398.08912)
		(width 0.10668)
		(layer "F.Cu")
		(net "SMB_RT_CPU1_P0_ROM_MUX_1D_SCL")
	)
	(segment
		(start 93.00718 -401.07108)
		(end 93.00718 -400.38782)
		(width 0.10668)
		(layer "F.Cu")
		(net "SMB_RT_CPU1_P0_ROM_MUX_1D_SCL")
	)
	(segment
		(start 96.590358 -403.141688)
		(end 95.380302 -403.141688)
		(width 0.10668)
		(layer "F.Cu")
		(net "SMB_RT_CPU1_P0_ROM_MUX_1D_SCL")
	)
	(segment
		(start 95.032576 -402.793962)
		(end 95.380302 -403.141688)
		(width 0.10668)
		(layer "F.Cu")
		(net "SMB_RT_CPU1_P0_ROM_MUX_1D_SCL")
	)
	(segment
		(start 94.67596 -399.37182)
		(end 94.83598 -399.2118)
		(width 0.10668)
		(layer "F.Cu")
		(net "SMB_RT_CPU1_P0_ROM_MUX_1D_SCL")
	)
	(via
		(at 98.536506 -397.645636)
		(size 0.508)
		(drill 0.254)
		(layers "F.Cu" "B.Cu")
		(net "SMB_RT_CPU1_P0_ROM_MUX_1D_SCL")
	)
	(via
		(at 43.23842 -391.91184)
		(size 0.508)
		(drill 0.254)
		(layers "F.Cu" "B.Cu")
		(net "SMB_RT_CPU1_P0_ROM_MUX_1D_SCL")
	)
	(via
		(at 95.380302 -403.141688)
		(size 0.762)
		(drill 0.381)
		(layers "F.Cu" "B.Cu")
		(net "SMB_RT_CPU1_P0_ROM_MUX_1D_SCL")
	)
	(via
		(at 41.51884 -378.71654)
		(size 0.508)
		(drill 0.254)
		(layers "F.Cu" "B.Cu")
		(net "SMB_RT_CPU1_P0_ROM_MUX_1D_SCL")
	)
	(segment
		(start 41.7576 -390.43102)
		(end 41.69918 -390.43102)
		(width 0.11684)
		(layer "In2.Cu")
		(net "SMB_RT_CPU1_P0_ROM_MUX_1D_SCL")
	)
	(segment
		(start 41.69918 -390.43102)
		(end 39.46652 -388.19836)
		(width 0.11684)
		(layer "In2.Cu")
		(net "SMB_RT_CPU1_P0_ROM_MUX_1D_SCL")
	)
	(segment
		(start 38.4048 -380.67742)
		(end 40.36568 -378.71654)
		(width 0.11684)
		(layer "In2.Cu")
		(net "SMB_RT_CPU1_P0_ROM_MUX_1D_SCL")
	)
	(segment
		(start 38.4048 -386.27812)
		(end 38.4048 -380.67742)
		(width 0.11684)
		(layer "In2.Cu")
		(net "SMB_RT_CPU1_P0_ROM_MUX_1D_SCL")
	)
	(segment
		(start 39.46652 -388.19836)
		(end 39.46652 -387.33984)
		(width 0.11684)
		(layer "In2.Cu")
		(net "SMB_RT_CPU1_P0_ROM_MUX_1D_SCL")
	)
	(segment
		(start 39.46652 -387.33984)
		(end 38.4048 -386.27812)
		(width 0.11684)
		(layer "In2.Cu")
		(net "SMB_RT_CPU1_P0_ROM_MUX_1D_SCL")
	)
	(segment
		(start 40.36568 -378.71654)
		(end 41.51884 -378.71654)
		(width 0.11684)
		(layer "In2.Cu")
		(net "SMB_RT_CPU1_P0_ROM_MUX_1D_SCL")
	)
	(segment
		(start 43.23842 -391.91184)
		(end 41.7576 -390.43102)
		(width 0.11684)
		(layer "In2.Cu")
		(net "SMB_RT_CPU1_P0_ROM_MUX_1D_SCL")
	)
	(segment
		(start 46.63948 -395.59484)
		(end 43.23842 -392.19378)
		(width 0.11684)
		(layer "In4.Cu")
		(net "SMB_RT_CPU1_P0_ROM_MUX_1D_SCL")
	)
	(segment
		(start 43.23842 -392.19378)
		(end 43.23842 -391.91184)
		(width 0.11684)
		(layer "In4.Cu")
		(net "SMB_RT_CPU1_P0_ROM_MUX_1D_SCL")
	)
	(segment
		(start 96.314514 -396.59306)
		(end 51.966876 -396.59306)
		(width 0.11684)
		(layer "In4.Cu")
		(net "SMB_RT_CPU1_P0_ROM_MUX_1D_SCL")
	)
	(segment
		(start 98.536506 -397.645636)
		(end 97.36709 -397.645636)
		(width 0.11684)
		(layer "In4.Cu")
		(net "SMB_RT_CPU1_P0_ROM_MUX_1D_SCL")
	)
	(segment
		(start 50.968656 -395.59484)
		(end 46.63948 -395.59484)
		(width 0.11684)
		(layer "In4.Cu")
		(net "SMB_RT_CPU1_P0_ROM_MUX_1D_SCL")
	)
	(segment
		(start 97.36709 -397.645636)
		(end 96.314514 -396.59306)
		(width 0.11684)
		(layer "In4.Cu")
		(net "SMB_RT_CPU1_P0_ROM_MUX_1D_SCL")
	)
	(segment
		(start 51.966876 -396.59306)
		(end 50.968656 -395.59484)
		(width 0.11684)
		(layer "In4.Cu")
		(net "SMB_RT_CPU1_P0_ROM_MUX_1D_SCL")
	)
	(segment
		(start 373.381524 -427.509178)
		(end 372.87581 -428.014892)
		(width 0.10668)
		(layer "F.Cu")
		(net "SMB_RT_CPU0_P3_ROM_MUX_2D_SDA")
	)
	(segment
		(start 373.381524 -427.207934)
		(end 373.381524 -427.509178)
		(width 0.10668)
		(layer "F.Cu")
		(net "SMB_RT_CPU0_P3_ROM_MUX_2D_SDA")
	)
	(segment
		(start 372.87581 -428.014892)
		(end 372.392194 -428.014892)
		(width 0.10668)
		(layer "F.Cu")
		(net "SMB_RT_CPU0_P3_ROM_MUX_2D_SDA")
	)
	(via
		(at 362.639102 -394.627608)
		(size 0.508)
		(drill 0.254)
		(layers "F.Cu" "B.Cu")
		(net "SMB_RT_CPU0_P3_ROM_MUX_2D_SDA")
	)
	(via
		(at 257.175 -337.439)
		(size 0.508)
		(drill 0.254)
		(layers "F.Cu" "B.Cu")
		(net "SMB_RT_CPU0_P3_ROM_MUX_2D_SDA")
	)
	(via
		(at 249.117866 -368.69243)
		(size 0.508)
		(drill 0.254)
		(layers "F.Cu" "B.Cu")
		(net "SMB_RT_CPU0_P3_ROM_MUX_2D_SDA")
	)
	(via
		(at 372.392194 -428.014892)
		(size 0.508)
		(drill 0.254)
		(layers "F.Cu" "B.Cu")
		(net "SMB_RT_CPU0_P3_ROM_MUX_2D_SDA")
	)
	(segment
		(start 257.11404 -337.37804)
		(end 257.175 -337.439)
		(width 0.10668)
		(layer "B.Cu")
		(net "SMB_RT_CPU0_P3_ROM_MUX_2D_SDA")
	)
	(segment
		(start 256.1717 -337.37804)
		(end 257.11404 -337.37804)
		(width 0.10668)
		(layer "B.Cu")
		(net "SMB_RT_CPU0_P3_ROM_MUX_2D_SDA")
	)
	(segment
		(start 289.706812 -375.99493)
		(end 288.372804 -374.660922)
		(width 0.11684)
		(layer "In2.Cu")
		(net "SMB_RT_CPU0_P3_ROM_MUX_2D_SDA")
	)
	(segment
		(start 299.175424 -375.99493)
		(end 289.706812 -375.99493)
		(width 0.11684)
		(layer "In2.Cu")
		(net "SMB_RT_CPU0_P3_ROM_MUX_2D_SDA")
	)
	(segment
		(start 362.132118 -394.120624)
		(end 362.132118 -379.632972)
		(width 0.11684)
		(layer "In2.Cu")
		(net "SMB_RT_CPU0_P3_ROM_MUX_2D_SDA")
	)
	(segment
		(start 250.071636 -369.6462)
		(end 249.117866 -368.69243)
		(width 0.11684)
		(layer "In2.Cu")
		(net "SMB_RT_CPU0_P3_ROM_MUX_2D_SDA")
	)
	(segment
		(start 362.132118 -379.632972)
		(end 357.947976 -375.44883)
		(width 0.11684)
		(layer "In2.Cu")
		(net "SMB_RT_CPU0_P3_ROM_MUX_2D_SDA")
	)
	(segment
		(start 282.825952 -374.660922)
		(end 277.81123 -369.6462)
		(width 0.11684)
		(layer "In2.Cu")
		(net "SMB_RT_CPU0_P3_ROM_MUX_2D_SDA")
	)
	(segment
		(start 362.639102 -394.627608)
		(end 362.132118 -394.120624)
		(width 0.11684)
		(layer "In2.Cu")
		(net "SMB_RT_CPU0_P3_ROM_MUX_2D_SDA")
	)
	(segment
		(start 357.947976 -375.44883)
		(end 299.721524 -375.44883)
		(width 0.11684)
		(layer "In2.Cu")
		(net "SMB_RT_CPU0_P3_ROM_MUX_2D_SDA")
	)
	(segment
		(start 288.372804 -374.660922)
		(end 282.825952 -374.660922)
		(width 0.11684)
		(layer "In2.Cu")
		(net "SMB_RT_CPU0_P3_ROM_MUX_2D_SDA")
	)
	(segment
		(start 277.81123 -369.6462)
		(end 250.071636 -369.6462)
		(width 0.11684)
		(layer "In2.Cu")
		(net "SMB_RT_CPU0_P3_ROM_MUX_2D_SDA")
	)
	(segment
		(start 299.721524 -375.44883)
		(end 299.175424 -375.99493)
		(width 0.11684)
		(layer "In2.Cu")
		(net "SMB_RT_CPU0_P3_ROM_MUX_2D_SDA")
	)
	(segment
		(start 249.117866 -368.634518)
		(end 249.117866 -368.69243)
		(width 0.11684)
		(layer "In4.Cu")
		(net "SMB_RT_CPU0_P3_ROM_MUX_2D_SDA")
	)
	(segment
		(start 360.505248 -399.556986)
		(end 360.505248 -404.800054)
		(width 0.11684)
		(layer "In4.Cu")
		(net "SMB_RT_CPU0_P3_ROM_MUX_2D_SDA")
	)
	(segment
		(start 362.48213 -405.753316)
		(end 362.05287 -406.182576)
		(width 0.11684)
		(layer "In4.Cu")
		(net "SMB_RT_CPU0_P3_ROM_MUX_2D_SDA")
	)
	(segment
		(start 369.51412 -426.4025)
		(end 369.763294 -426.651674)
		(width 0.11684)
		(layer "In4.Cu")
		(net "SMB_RT_CPU0_P3_ROM_MUX_2D_SDA")
	)
	(segment
		(start 364.060232 -408.355038)
		(end 364.060232 -410.036264)
		(width 0.11684)
		(layer "In4.Cu")
		(net "SMB_RT_CPU0_P3_ROM_MUX_2D_SDA")
	)
	(segment
		(start 362.639102 -395.122654)
		(end 361.312714 -396.449042)
		(width 0.11684)
		(layer "In4.Cu")
		(net "SMB_RT_CPU0_P3_ROM_MUX_2D_SDA")
	)
	(segment
		(start 361.89285 -416.648392)
		(end 361.89285 -417.69284)
		(width 0.11684)
		(layer "In4.Cu")
		(net "SMB_RT_CPU0_P3_ROM_MUX_2D_SDA")
	)
	(segment
		(start 361.587796 -405.882602)
		(end 361.752896 -405.882602)
		(width 0.11684)
		(layer "In4.Cu")
		(net "SMB_RT_CPU0_P3_ROM_MUX_2D_SDA")
	)
	(segment
		(start 250.674632 -352.923856)
		(end 250.674632 -367.077752)
		(width 0.11684)
		(layer "In4.Cu")
		(net "SMB_RT_CPU0_P3_ROM_MUX_2D_SDA")
	)
	(segment
		(start 368.42446 -426.651674)
		(end 368.673634 -426.4025)
		(width 0.11684)
		(layer "In4.Cu")
		(net "SMB_RT_CPU0_P3_ROM_MUX_2D_SDA")
	)
	(segment
		(start 361.452922 -405.582628)
		(end 361.452922 -405.747728)
		(width 0.11684)
		(layer "In4.Cu")
		(net "SMB_RT_CPU0_P3_ROM_MUX_2D_SDA")
	)
	(segment
		(start 360.78414 -397.725392)
		(end 360.78414 -399.278094)
		(width 0.11684)
		(layer "In4.Cu")
		(net "SMB_RT_CPU0_P3_ROM_MUX_2D_SDA")
	)
	(segment
		(start 368.673634 -426.4025)
		(end 369.51412 -426.4025)
		(width 0.11684)
		(layer "In4.Cu")
		(net "SMB_RT_CPU0_P3_ROM_MUX_2D_SDA")
	)
	(segment
		(start 362.639102 -394.627608)
		(end 362.639102 -395.122654)
		(width 0.11684)
		(layer "In4.Cu")
		(net "SMB_RT_CPU0_P3_ROM_MUX_2D_SDA")
	)
	(segment
		(start 362.347256 -405.453342)
		(end 362.48213 -405.588216)
		(width 0.11684)
		(layer "In4.Cu")
		(net "SMB_RT_CPU0_P3_ROM_MUX_2D_SDA")
	)
	(segment
		(start 360.987848 -405.282654)
		(end 361.152948 -405.282654)
		(width 0.11684)
		(layer "In4.Cu")
		(net "SMB_RT_CPU0_P3_ROM_MUX_2D_SDA")
	)
	(segment
		(start 362.05287 -406.182576)
		(end 362.05287 -406.347676)
		(width 0.11684)
		(layer "In4.Cu")
		(net "SMB_RT_CPU0_P3_ROM_MUX_2D_SDA")
	)
	(segment
		(start 363.79404 -412.654496)
		(end 363.041692 -413.406844)
		(width 0.11684)
		(layer "In4.Cu")
		(net "SMB_RT_CPU0_P3_ROM_MUX_2D_SDA")
	)
	(segment
		(start 363.85881 -422.948354)
		(end 363.85881 -425.453556)
		(width 0.11684)
		(layer "In4.Cu")
		(net "SMB_RT_CPU0_P3_ROM_MUX_2D_SDA")
	)
	(segment
		(start 363.041692 -415.49955)
		(end 361.89285 -416.648392)
		(width 0.11684)
		(layer "In4.Cu")
		(net "SMB_RT_CPU0_P3_ROM_MUX_2D_SDA")
	)
	(segment
		(start 361.752896 -405.882602)
		(end 362.182156 -405.453342)
		(width 0.11684)
		(layer "In4.Cu")
		(net "SMB_RT_CPU0_P3_ROM_MUX_2D_SDA")
	)
	(segment
		(start 362.48213 -405.588216)
		(end 362.48213 -405.753316)
		(width 0.11684)
		(layer "In4.Cu")
		(net "SMB_RT_CPU0_P3_ROM_MUX_2D_SDA")
	)
	(segment
		(start 364.060232 -410.036264)
		(end 363.79404 -410.302456)
		(width 0.11684)
		(layer "In4.Cu")
		(net "SMB_RT_CPU0_P3_ROM_MUX_2D_SDA")
	)
	(segment
		(start 256.413 -347.185488)
		(end 250.674632 -352.923856)
		(width 0.11684)
		(layer "In4.Cu")
		(net "SMB_RT_CPU0_P3_ROM_MUX_2D_SDA")
	)
	(segment
		(start 361.747308 -404.853394)
		(end 361.882182 -404.988268)
		(width 0.11684)
		(layer "In4.Cu")
		(net "SMB_RT_CPU0_P3_ROM_MUX_2D_SDA")
	)
	(segment
		(start 360.78414 -399.278094)
		(end 360.505248 -399.556986)
		(width 0.11684)
		(layer "In4.Cu")
		(net "SMB_RT_CPU0_P3_ROM_MUX_2D_SDA")
	)
	(segment
		(start 360.505248 -404.800054)
		(end 360.987848 -405.282654)
		(width 0.11684)
		(layer "In4.Cu")
		(net "SMB_RT_CPU0_P3_ROM_MUX_2D_SDA")
	)
	(segment
		(start 257.175 -337.439)
		(end 256.413 -338.201)
		(width 0.11684)
		(layer "In4.Cu")
		(net "SMB_RT_CPU0_P3_ROM_MUX_2D_SDA")
	)
	(segment
		(start 371.028976 -426.651674)
		(end 372.392194 -428.014892)
		(width 0.11684)
		(layer "In4.Cu")
		(net "SMB_RT_CPU0_P3_ROM_MUX_2D_SDA")
	)
	(segment
		(start 361.452922 -405.747728)
		(end 361.587796 -405.882602)
		(width 0.11684)
		(layer "In4.Cu")
		(net "SMB_RT_CPU0_P3_ROM_MUX_2D_SDA")
	)
	(segment
		(start 363.85881 -425.453556)
		(end 365.056928 -426.651674)
		(width 0.11684)
		(layer "In4.Cu")
		(net "SMB_RT_CPU0_P3_ROM_MUX_2D_SDA")
	)
	(segment
		(start 362.182156 -405.453342)
		(end 362.347256 -405.453342)
		(width 0.11684)
		(layer "In4.Cu")
		(net "SMB_RT_CPU0_P3_ROM_MUX_2D_SDA")
	)
	(segment
		(start 362.327952 -421.417496)
		(end 363.85881 -422.948354)
		(width 0.11684)
		(layer "In4.Cu")
		(net "SMB_RT_CPU0_P3_ROM_MUX_2D_SDA")
	)
	(segment
		(start 361.89285 -417.69284)
		(end 362.327952 -418.127942)
		(width 0.11684)
		(layer "In4.Cu")
		(net "SMB_RT_CPU0_P3_ROM_MUX_2D_SDA")
	)
	(segment
		(start 363.79404 -410.302456)
		(end 363.79404 -412.654496)
		(width 0.11684)
		(layer "In4.Cu")
		(net "SMB_RT_CPU0_P3_ROM_MUX_2D_SDA")
	)
	(segment
		(start 361.882182 -405.153368)
		(end 361.452922 -405.582628)
		(width 0.11684)
		(layer "In4.Cu")
		(net "SMB_RT_CPU0_P3_ROM_MUX_2D_SDA")
	)
	(segment
		(start 250.674632 -367.077752)
		(end 249.117866 -368.634518)
		(width 0.11684)
		(layer "In4.Cu")
		(net "SMB_RT_CPU0_P3_ROM_MUX_2D_SDA")
	)
	(segment
		(start 256.413 -338.201)
		(end 256.413 -347.185488)
		(width 0.11684)
		(layer "In4.Cu")
		(net "SMB_RT_CPU0_P3_ROM_MUX_2D_SDA")
	)
	(segment
		(start 361.882182 -404.988268)
		(end 361.882182 -405.153368)
		(width 0.11684)
		(layer "In4.Cu")
		(net "SMB_RT_CPU0_P3_ROM_MUX_2D_SDA")
	)
	(segment
		(start 361.312714 -396.449042)
		(end 360.78414 -397.725392)
		(width 0.11684)
		(layer "In4.Cu")
		(net "SMB_RT_CPU0_P3_ROM_MUX_2D_SDA")
	)
	(segment
		(start 362.327952 -418.127942)
		(end 362.327952 -421.417496)
		(width 0.11684)
		(layer "In4.Cu")
		(net "SMB_RT_CPU0_P3_ROM_MUX_2D_SDA")
	)
	(segment
		(start 361.152948 -405.282654)
		(end 361.582208 -404.853394)
		(width 0.11684)
		(layer "In4.Cu")
		(net "SMB_RT_CPU0_P3_ROM_MUX_2D_SDA")
	)
	(segment
		(start 363.041692 -413.406844)
		(end 363.041692 -415.49955)
		(width 0.11684)
		(layer "In4.Cu")
		(net "SMB_RT_CPU0_P3_ROM_MUX_2D_SDA")
	)
	(segment
		(start 365.056928 -426.651674)
		(end 368.42446 -426.651674)
		(width 0.11684)
		(layer "In4.Cu")
		(net "SMB_RT_CPU0_P3_ROM_MUX_2D_SDA")
	)
	(segment
		(start 369.763294 -426.651674)
		(end 371.028976 -426.651674)
		(width 0.11684)
		(layer "In4.Cu")
		(net "SMB_RT_CPU0_P3_ROM_MUX_2D_SDA")
	)
	(segment
		(start 362.05287 -406.347676)
		(end 364.060232 -408.355038)
		(width 0.11684)
		(layer "In4.Cu")
		(net "SMB_RT_CPU0_P3_ROM_MUX_2D_SDA")
	)
	(segment
		(start 361.582208 -404.853394)
		(end 361.747308 -404.853394)
		(width 0.11684)
		(layer "In4.Cu")
		(net "SMB_RT_CPU0_P3_ROM_MUX_2D_SDA")
	)
	(segment
		(start 373.88165 -427.207934)
		(end 373.88165 -427.74235)
		(width 0.10668)
		(layer "F.Cu")
		(net "SMB_RT_CPU0_P3_ROM_MUX_2D_SCL")
	)
	(segment
		(start 373.88165 -427.74235)
		(end 373.507 -428.117)
		(width 0.10668)
		(layer "F.Cu")
		(net "SMB_RT_CPU0_P3_ROM_MUX_2D_SCL")
	)
	(via
		(at 257.175 -335.915)
		(size 0.508)
		(drill 0.254)
		(layers "F.Cu" "B.Cu")
		(net "SMB_RT_CPU0_P3_ROM_MUX_2D_SCL")
	)
	(via
		(at 373.507 -428.117)
		(size 0.508)
		(drill 0.254)
		(layers "F.Cu" "B.Cu")
		(net "SMB_RT_CPU0_P3_ROM_MUX_2D_SCL")
	)
	(via
		(at 363.274102 -394.627608)
		(size 0.508)
		(drill 0.254)
		(layers "F.Cu" "B.Cu")
		(net "SMB_RT_CPU0_P3_ROM_MUX_2D_SCL")
	)
	(via
		(at 247.828562 -368.647218)
		(size 0.508)
		(drill 0.254)
		(layers "F.Cu" "B.Cu")
		(net "SMB_RT_CPU0_P3_ROM_MUX_2D_SCL")
	)
	(segment
		(start 256.83464 -336.25536)
		(end 257.175 -335.915)
		(width 0.10668)
		(layer "B.Cu")
		(net "SMB_RT_CPU0_P3_ROM_MUX_2D_SCL")
	)
	(segment
		(start 256.1717 -336.25536)
		(end 256.83464 -336.25536)
		(width 0.10668)
		(layer "B.Cu")
		(net "SMB_RT_CPU0_P3_ROM_MUX_2D_SCL")
	)
	(segment
		(start 363.274102 -394.627608)
		(end 363.274102 -394.175234)
		(width 0.11684)
		(layer "In2.Cu")
		(net "SMB_RT_CPU0_P3_ROM_MUX_2D_SCL")
	)
	(segment
		(start 289.881564 -375.57329)
		(end 286.729424 -372.42115)
		(width 0.11684)
		(layer "In2.Cu")
		(net "SMB_RT_CPU0_P3_ROM_MUX_2D_SCL")
	)
	(segment
		(start 249.474482 -368.198654)
		(end 248.277126 -368.198654)
		(width 0.11684)
		(layer "In2.Cu")
		(net "SMB_RT_CPU0_P3_ROM_MUX_2D_SCL")
	)
	(segment
		(start 271.801082 -368.215672)
		(end 270.792194 -369.22456)
		(width 0.11684)
		(layer "In2.Cu")
		(net "SMB_RT_CPU0_P3_ROM_MUX_2D_SCL")
	)
	(segment
		(start 248.277126 -368.198654)
		(end 247.828562 -368.647218)
		(width 0.11684)
		(layer "In2.Cu")
		(net "SMB_RT_CPU0_P3_ROM_MUX_2D_SCL")
	)
	(segment
		(start 276.977094 -368.215672)
		(end 271.801082 -368.215672)
		(width 0.11684)
		(layer "In2.Cu")
		(net "SMB_RT_CPU0_P3_ROM_MUX_2D_SCL")
	)
	(segment
		(start 299.517562 -375.02719)
		(end 298.971462 -375.57329)
		(width 0.11684)
		(layer "In2.Cu")
		(net "SMB_RT_CPU0_P3_ROM_MUX_2D_SCL")
	)
	(segment
		(start 281.182572 -372.42115)
		(end 276.977094 -368.215672)
		(width 0.11684)
		(layer "In2.Cu")
		(net "SMB_RT_CPU0_P3_ROM_MUX_2D_SCL")
	)
	(segment
		(start 250.500388 -369.22456)
		(end 249.474482 -368.198654)
		(width 0.11684)
		(layer "In2.Cu")
		(net "SMB_RT_CPU0_P3_ROM_MUX_2D_SCL")
	)
	(segment
		(start 270.792194 -369.22456)
		(end 250.500388 -369.22456)
		(width 0.11684)
		(layer "In2.Cu")
		(net "SMB_RT_CPU0_P3_ROM_MUX_2D_SCL")
	)
	(segment
		(start 358.284272 -375.02719)
		(end 299.517562 -375.02719)
		(width 0.11684)
		(layer "In2.Cu")
		(net "SMB_RT_CPU0_P3_ROM_MUX_2D_SCL")
	)
	(segment
		(start 363.274102 -394.175234)
		(end 362.613702 -393.514834)
		(width 0.11684)
		(layer "In2.Cu")
		(net "SMB_RT_CPU0_P3_ROM_MUX_2D_SCL")
	)
	(segment
		(start 298.971462 -375.57329)
		(end 289.881564 -375.57329)
		(width 0.11684)
		(layer "In2.Cu")
		(net "SMB_RT_CPU0_P3_ROM_MUX_2D_SCL")
	)
	(segment
		(start 362.613702 -393.514834)
		(end 362.613702 -379.35662)
		(width 0.11684)
		(layer "In2.Cu")
		(net "SMB_RT_CPU0_P3_ROM_MUX_2D_SCL")
	)
	(segment
		(start 362.613702 -379.35662)
		(end 358.284272 -375.02719)
		(width 0.11684)
		(layer "In2.Cu")
		(net "SMB_RT_CPU0_P3_ROM_MUX_2D_SCL")
	)
	(segment
		(start 286.729424 -372.42115)
		(end 281.182572 -372.42115)
		(width 0.11684)
		(layer "In2.Cu")
		(net "SMB_RT_CPU0_P3_ROM_MUX_2D_SCL")
	)
	(segment
		(start 364.28045 -422.770046)
		(end 362.820966 -421.310562)
		(width 0.11684)
		(layer "In4.Cu")
		(net "SMB_RT_CPU0_P3_ROM_MUX_2D_SCL")
	)
	(segment
		(start 372.830598 -427.440598)
		(end 372.576598 -427.440598)
		(width 0.11684)
		(layer "In4.Cu")
		(net "SMB_RT_CPU0_P3_ROM_MUX_2D_SCL")
	)
	(segment
		(start 363.274102 -395.19479)
		(end 363.274102 -394.627608)
		(width 0.11684)
		(layer "In4.Cu")
		(net "SMB_RT_CPU0_P3_ROM_MUX_2D_SCL")
	)
	(segment
		(start 249.97791 -352.89109)
		(end 249.97791 -366.49787)
		(width 0.11684)
		(layer "In4.Cu")
		(net "SMB_RT_CPU0_P3_ROM_MUX_2D_SCL")
	)
	(segment
		(start 365.613696 -410.485844)
		(end 364.552738 -409.424886)
		(width 0.11684)
		(layer "In4.Cu")
		(net "SMB_RT_CPU0_P3_ROM_MUX_2D_SCL")
	)
	(segment
		(start 362.372148 -417.575746)
		(end 362.372148 -416.814762)
		(width 0.11684)
		(layer "In4.Cu")
		(net "SMB_RT_CPU0_P3_ROM_MUX_2D_SCL")
	)
	(segment
		(start 370.055902 -426.21962)
		(end 369.70208 -425.865798)
		(width 0.11684)
		(layer "In4.Cu")
		(net "SMB_RT_CPU0_P3_ROM_MUX_2D_SCL")
	)
	(segment
		(start 361.037886 -403.345904)
		(end 361.037886 -399.80235)
		(width 0.11684)
		(layer "In4.Cu")
		(net "SMB_RT_CPU0_P3_ROM_MUX_2D_SCL")
	)
	(segment
		(start 361.254294 -397.718534)
		(end 361.610402 -396.85849)
		(width 0.11684)
		(layer "In4.Cu")
		(net "SMB_RT_CPU0_P3_ROM_MUX_2D_SCL")
	)
	(segment
		(start 371.35562 -426.21962)
		(end 370.055902 -426.21962)
		(width 0.11684)
		(layer "In4.Cu")
		(net "SMB_RT_CPU0_P3_ROM_MUX_2D_SCL")
	)
	(segment
		(start 249.97791 -366.49787)
		(end 247.828562 -368.647218)
		(width 0.11684)
		(layer "In4.Cu")
		(net "SMB_RT_CPU0_P3_ROM_MUX_2D_SCL")
	)
	(segment
		(start 365.613696 -411.550104)
		(end 365.613696 -410.485844)
		(width 0.11684)
		(layer "In4.Cu")
		(net "SMB_RT_CPU0_P3_ROM_MUX_2D_SCL")
	)
	(segment
		(start 255.73736 -337.439)
		(end 255.73736 -347.13164)
		(width 0.11684)
		(layer "In4.Cu")
		(net "SMB_RT_CPU0_P3_ROM_MUX_2D_SCL")
	)
	(segment
		(start 257.175 -336.00136)
		(end 255.73736 -337.439)
		(width 0.11684)
		(layer "In4.Cu")
		(net "SMB_RT_CPU0_P3_ROM_MUX_2D_SCL")
	)
	(segment
		(start 365.342424 -426.21962)
		(end 364.28045 -425.157646)
		(width 0.11684)
		(layer "In4.Cu")
		(net "SMB_RT_CPU0_P3_ROM_MUX_2D_SCL")
	)
	(segment
		(start 362.968794 -405.276812)
		(end 361.037886 -403.345904)
		(width 0.11684)
		(layer "In4.Cu")
		(net "SMB_RT_CPU0_P3_ROM_MUX_2D_SCL")
	)
	(segment
		(start 364.552738 -409.424886)
		(end 364.552738 -407.798016)
		(width 0.11684)
		(layer "In4.Cu")
		(net "SMB_RT_CPU0_P3_ROM_MUX_2D_SCL")
	)
	(segment
		(start 368.527584 -425.865798)
		(end 368.173762 -426.21962)
		(width 0.11684)
		(layer "In4.Cu")
		(net "SMB_RT_CPU0_P3_ROM_MUX_2D_SCL")
	)
	(segment
		(start 363.510068 -415.676842)
		(end 363.510068 -413.653732)
		(width 0.11684)
		(layer "In4.Cu")
		(net "SMB_RT_CPU0_P3_ROM_MUX_2D_SCL")
	)
	(segment
		(start 361.610402 -396.85849)
		(end 363.274102 -395.19479)
		(width 0.11684)
		(layer "In4.Cu")
		(net "SMB_RT_CPU0_P3_ROM_MUX_2D_SCL")
	)
	(segment
		(start 257.175 -335.915)
		(end 257.175 -336.00136)
		(width 0.11684)
		(layer "In4.Cu")
		(net "SMB_RT_CPU0_P3_ROM_MUX_2D_SCL")
	)
	(segment
		(start 361.037886 -399.80235)
		(end 361.254294 -399.585942)
		(width 0.11684)
		(layer "In4.Cu")
		(net "SMB_RT_CPU0_P3_ROM_MUX_2D_SCL")
	)
	(segment
		(start 369.70208 -425.865798)
		(end 368.527584 -425.865798)
		(width 0.11684)
		(layer "In4.Cu")
		(net "SMB_RT_CPU0_P3_ROM_MUX_2D_SCL")
	)
	(segment
		(start 368.173762 -426.21962)
		(end 365.342424 -426.21962)
		(width 0.11684)
		(layer "In4.Cu")
		(net "SMB_RT_CPU0_P3_ROM_MUX_2D_SCL")
	)
	(segment
		(start 364.552738 -407.798016)
		(end 362.968794 -406.214072)
		(width 0.11684)
		(layer "In4.Cu")
		(net "SMB_RT_CPU0_P3_ROM_MUX_2D_SCL")
	)
	(segment
		(start 364.28045 -425.157646)
		(end 364.28045 -422.770046)
		(width 0.11684)
		(layer "In4.Cu")
		(net "SMB_RT_CPU0_P3_ROM_MUX_2D_SCL")
	)
	(segment
		(start 361.254294 -399.585942)
		(end 361.254294 -397.718534)
		(width 0.11684)
		(layer "In4.Cu")
		(net "SMB_RT_CPU0_P3_ROM_MUX_2D_SCL")
	)
	(segment
		(start 362.820966 -418.024564)
		(end 362.372148 -417.575746)
		(width 0.11684)
		(layer "In4.Cu")
		(net "SMB_RT_CPU0_P3_ROM_MUX_2D_SCL")
	)
	(segment
		(start 373.507 -428.117)
		(end 372.830598 -427.440598)
		(width 0.11684)
		(layer "In4.Cu")
		(net "SMB_RT_CPU0_P3_ROM_MUX_2D_SCL")
	)
	(segment
		(start 363.510068 -413.653732)
		(end 365.613696 -411.550104)
		(width 0.11684)
		(layer "In4.Cu")
		(net "SMB_RT_CPU0_P3_ROM_MUX_2D_SCL")
	)
	(segment
		(start 372.576598 -427.440598)
		(end 371.35562 -426.21962)
		(width 0.11684)
		(layer "In4.Cu")
		(net "SMB_RT_CPU0_P3_ROM_MUX_2D_SCL")
	)
	(segment
		(start 362.968794 -406.214072)
		(end 362.968794 -405.276812)
		(width 0.11684)
		(layer "In4.Cu")
		(net "SMB_RT_CPU0_P3_ROM_MUX_2D_SCL")
	)
	(segment
		(start 362.372148 -416.814762)
		(end 363.510068 -415.676842)
		(width 0.11684)
		(layer "In4.Cu")
		(net "SMB_RT_CPU0_P3_ROM_MUX_2D_SCL")
	)
	(segment
		(start 362.820966 -421.310562)
		(end 362.820966 -418.024564)
		(width 0.11684)
		(layer "In4.Cu")
		(net "SMB_RT_CPU0_P3_ROM_MUX_2D_SCL")
	)
	(segment
		(start 255.73736 -347.13164)
		(end 249.97791 -352.89109)
		(width 0.11684)
		(layer "In4.Cu")
		(net "SMB_RT_CPU0_P3_ROM_MUX_2D_SCL")
	)
	(segment
		(start 367.055908 -429.25746)
		(end 367.221516 -429.25746)
		(width 0.10668)
		(layer "F.Cu")
		(net "SMB_RT_CPU0_P3_ROM_MUX_1D_SDA")
	)
	(segment
		(start 366.0521 -426.604176)
		(end 366.0521 -427.387512)
		(width 0.10668)
		(layer "F.Cu")
		(net "SMB_RT_CPU0_P3_ROM_MUX_1D_SDA")
	)
	(segment
		(start 367.221516 -429.25746)
		(end 373.043704 -429.25746)
		(width 0.10668)
		(layer "F.Cu")
		(net "SMB_RT_CPU0_P3_ROM_MUX_1D_SDA")
	)
	(segment
		(start 366.061498 -427.39691)
		(end 366.471708 -427.80712)
		(width 0.10668)
		(layer "F.Cu")
		(net "SMB_RT_CPU0_P3_ROM_MUX_1D_SDA")
	)
	(segment
		(start 366.0521 -427.387512)
		(end 366.061498 -427.39691)
		(width 0.10668)
		(layer "F.Cu")
		(net "SMB_RT_CPU0_P3_ROM_MUX_1D_SDA")
	)
	(segment
		(start 373.043704 -429.25746)
		(end 374.381522 -427.919642)
		(width 0.10668)
		(layer "F.Cu")
		(net "SMB_RT_CPU0_P3_ROM_MUX_1D_SDA")
	)
	(segment
		(start 366.471708 -428.495714)
		(end 366.597184 -428.798736)
		(width 0.10668)
		(layer "F.Cu")
		(net "SMB_RT_CPU0_P3_ROM_MUX_1D_SDA")
	)
	(segment
		(start 374.381522 -427.919642)
		(end 374.381522 -427.207934)
		(width 0.10668)
		(layer "F.Cu")
		(net "SMB_RT_CPU0_P3_ROM_MUX_1D_SDA")
	)
	(segment
		(start 366.471708 -427.80712)
		(end 366.471708 -428.495714)
		(width 0.10668)
		(layer "F.Cu")
		(net "SMB_RT_CPU0_P3_ROM_MUX_1D_SDA")
	)
	(segment
		(start 366.597184 -428.798736)
		(end 367.055908 -429.25746)
		(width 0.10668)
		(layer "F.Cu")
		(net "SMB_RT_CPU0_P3_ROM_MUX_1D_SDA")
	)
	(via
		(at 367.221516 -429.25746)
		(size 0.762)
		(drill 0.381)
		(layers "F.Cu" "B.Cu")
		(net "SMB_RT_CPU0_P3_ROM_MUX_1D_SDA")
	)
	(segment
		(start 374.881648 -427.207934)
		(end 374.881648 -428.266352)
		(width 0.10668)
		(layer "F.Cu")
		(net "SMB_RT_CPU0_P3_ROM_MUX_1D_SCL")
	)
	(segment
		(start 366.056418 -429.29175)
		(end 366.056418 -429.075342)
		(width 0.10668)
		(layer "F.Cu")
		(net "SMB_RT_CPU0_P3_ROM_MUX_1D_SCL")
	)
	(segment
		(start 366.056418 -429.075342)
		(end 366.056418 -428.29099)
		(width 0.10668)
		(layer "F.Cu")
		(net "SMB_RT_CPU0_P3_ROM_MUX_1D_SCL")
	)
	(segment
		(start 366.668304 -429.903636)
		(end 366.056418 -429.29175)
		(width 0.10668)
		(layer "F.Cu")
		(net "SMB_RT_CPU0_P3_ROM_MUX_1D_SCL")
	)
	(segment
		(start 366.056418 -428.29099)
		(end 366.061498 -428.28591)
		(width 0.10668)
		(layer "F.Cu")
		(net "SMB_RT_CPU0_P3_ROM_MUX_1D_SCL")
	)
	(segment
		(start 374.433084 -428.714916)
		(end 373.244364 -429.903636)
		(width 0.10668)
		(layer "F.Cu")
		(net "SMB_RT_CPU0_P3_ROM_MUX_1D_SCL")
	)
	(segment
		(start 373.244364 -429.903636)
		(end 366.668304 -429.903636)
		(width 0.10668)
		(layer "F.Cu")
		(net "SMB_RT_CPU0_P3_ROM_MUX_1D_SCL")
	)
	(segment
		(start 374.881648 -428.266352)
		(end 374.433084 -428.714916)
		(width 0.10668)
		(layer "F.Cu")
		(net "SMB_RT_CPU0_P3_ROM_MUX_1D_SCL")
	)
	(via
		(at 374.433084 -428.714916)
		(size 0.762)
		(drill 0.381)
		(layers "F.Cu" "B.Cu")
		(net "SMB_RT_CPU0_P3_ROM_MUX_1D_SCL")
	)
	(via
		(at 435.88178 -373.897398)
		(size 0.508)
		(drill 0.254)
		(layers "F.Cu" "B.Cu")
		(net "SMB_RT_CPU0_P2_ROM_MUX_2D_SDA")
	)
	(via
		(at 247.20677 -370.005356)
		(size 0.508)
		(drill 0.254)
		(layers "F.Cu" "B.Cu")
		(net "SMB_RT_CPU0_P2_ROM_MUX_2D_SDA")
	)
	(via
		(at 424.021758 -425.511214)
		(size 0.508)
		(drill 0.254)
		(layers "F.Cu" "B.Cu")
		(net "SMB_RT_CPU0_P2_ROM_MUX_2D_SDA")
	)
	(via
		(at 257.436366 -335.0133)
		(size 0.508)
		(drill 0.254)
		(layers "F.Cu" "B.Cu")
		(net "SMB_RT_CPU0_P2_ROM_MUX_2D_SDA")
	)
	(segment
		(start 287.913064 -372.677944)
		(end 291.194744 -375.959624)
		(width 0.10668)
		(layer "B.Cu")
		(net "SMB_RT_CPU0_P2_ROM_MUX_2D_SDA")
	)
	(segment
		(start 283.591508 -370.843556)
		(end 285.425896 -372.677944)
		(width 0.10668)
		(layer "B.Cu")
		(net "SMB_RT_CPU0_P2_ROM_MUX_2D_SDA")
	)
	(segment
		(start 285.425896 -372.677944)
		(end 287.913064 -372.677944)
		(width 0.10668)
		(layer "B.Cu")
		(net "SMB_RT_CPU0_P2_ROM_MUX_2D_SDA")
	)
	(segment
		(start 251.15774 -370.404898)
		(end 251.596398 -370.843556)
		(width 0.10668)
		(layer "B.Cu")
		(net "SMB_RT_CPU0_P2_ROM_MUX_2D_SDA")
	)
	(segment
		(start 247.89892 -369.313206)
		(end 249.0724 -369.313206)
		(width 0.10668)
		(layer "B.Cu")
		(net "SMB_RT_CPU0_P2_ROM_MUX_2D_SDA")
	)
	(segment
		(start 249.0724 -369.313206)
		(end 250.164092 -370.404898)
		(width 0.10668)
		(layer "B.Cu")
		(net "SMB_RT_CPU0_P2_ROM_MUX_2D_SDA")
	)
	(segment
		(start 435.274974 -374.504204)
		(end 435.88178 -373.897398)
		(width 0.10668)
		(layer "B.Cu")
		(net "SMB_RT_CPU0_P2_ROM_MUX_2D_SDA")
	)
	(segment
		(start 291.194744 -375.959624)
		(end 295.439592 -375.959624)
		(width 0.10668)
		(layer "B.Cu")
		(net "SMB_RT_CPU0_P2_ROM_MUX_2D_SDA")
	)
	(segment
		(start 295.439592 -375.959624)
		(end 299.372528 -372.026688)
		(width 0.10668)
		(layer "B.Cu")
		(net "SMB_RT_CPU0_P2_ROM_MUX_2D_SDA")
	)
	(segment
		(start 423.004488 -426.015912)
		(end 422.54297 -426.015912)
		(width 0.10668)
		(layer "B.Cu")
		(net "SMB_RT_CPU0_P2_ROM_MUX_2D_SDA")
	)
	(segment
		(start 299.372528 -372.026688)
		(end 427.662086 -372.026688)
		(width 0.10668)
		(layer "B.Cu")
		(net "SMB_RT_CPU0_P2_ROM_MUX_2D_SDA")
	)
	(segment
		(start 250.164092 -370.404898)
		(end 251.15774 -370.404898)
		(width 0.10668)
		(layer "B.Cu")
		(net "SMB_RT_CPU0_P2_ROM_MUX_2D_SDA")
	)
	(segment
		(start 424.021758 -425.511214)
		(end 423.509186 -425.511214)
		(width 0.10668)
		(layer "B.Cu")
		(net "SMB_RT_CPU0_P2_ROM_MUX_2D_SDA")
	)
	(segment
		(start 427.662086 -372.026688)
		(end 430.139602 -374.504204)
		(width 0.10668)
		(layer "B.Cu")
		(net "SMB_RT_CPU0_P2_ROM_MUX_2D_SDA")
	)
	(segment
		(start 430.139602 -374.504204)
		(end 435.274974 -374.504204)
		(width 0.10668)
		(layer "B.Cu")
		(net "SMB_RT_CPU0_P2_ROM_MUX_2D_SDA")
	)
	(segment
		(start 423.509186 -425.511214)
		(end 423.004488 -426.015912)
		(width 0.10668)
		(layer "B.Cu")
		(net "SMB_RT_CPU0_P2_ROM_MUX_2D_SDA")
	)
	(segment
		(start 257.316986 -335.13268)
		(end 257.436366 -335.0133)
		(width 0.10668)
		(layer "B.Cu")
		(net "SMB_RT_CPU0_P2_ROM_MUX_2D_SDA")
	)
	(segment
		(start 247.20677 -370.005356)
		(end 247.89892 -369.313206)
		(width 0.10668)
		(layer "B.Cu")
		(net "SMB_RT_CPU0_P2_ROM_MUX_2D_SDA")
	)
	(segment
		(start 251.596398 -370.843556)
		(end 283.591508 -370.843556)
		(width 0.10668)
		(layer "B.Cu")
		(net "SMB_RT_CPU0_P2_ROM_MUX_2D_SDA")
	)
	(segment
		(start 256.1717 -335.13268)
		(end 257.316986 -335.13268)
		(width 0.10668)
		(layer "B.Cu")
		(net "SMB_RT_CPU0_P2_ROM_MUX_2D_SDA")
	)
	(segment
		(start 420.557198 -417.99383)
		(end 421.908986 -419.345618)
		(width 0.11684)
		(layer "In4.Cu")
		(net "SMB_RT_CPU0_P2_ROM_MUX_2D_SDA")
	)
	(segment
		(start 423.128186 -401.960334)
		(end 423.128186 -406.291034)
		(width 0.11684)
		(layer "In4.Cu")
		(net "SMB_RT_CPU0_P2_ROM_MUX_2D_SDA")
	)
	(segment
		(start 435.88178 -373.897398)
		(end 437.827674 -375.843292)
		(width 0.11684)
		(layer "In4.Cu")
		(net "SMB_RT_CPU0_P2_ROM_MUX_2D_SDA")
	)
	(segment
		(start 249.32767 -366.468152)
		(end 249.32767 -352.779076)
		(width 0.11684)
		(layer "In4.Cu")
		(net "SMB_RT_CPU0_P2_ROM_MUX_2D_SDA")
	)
	(segment
		(start 421.908986 -423.739818)
		(end 423.680382 -425.511214)
		(width 0.11684)
		(layer "In4.Cu")
		(net "SMB_RT_CPU0_P2_ROM_MUX_2D_SDA")
	)
	(segment
		(start 437.827674 -375.843292)
		(end 437.827674 -386.672328)
		(width 0.11684)
		(layer "In4.Cu")
		(net "SMB_RT_CPU0_P2_ROM_MUX_2D_SDA")
	)
	(segment
		(start 249.32767 -352.779076)
		(end 255.143 -346.963746)
		(width 0.11684)
		(layer "In4.Cu")
		(net "SMB_RT_CPU0_P2_ROM_MUX_2D_SDA")
	)
	(segment
		(start 423.961306 -401.127214)
		(end 423.128186 -401.960334)
		(width 0.11684)
		(layer "In4.Cu")
		(net "SMB_RT_CPU0_P2_ROM_MUX_2D_SDA")
	)
	(segment
		(start 255.143 -336.549746)
		(end 256.679446 -335.0133)
		(width 0.11684)
		(layer "In4.Cu")
		(net "SMB_RT_CPU0_P2_ROM_MUX_2D_SDA")
	)
	(segment
		(start 425.899326 -394.966698)
		(end 425.899326 -399.868898)
		(width 0.11684)
		(layer "In4.Cu")
		(net "SMB_RT_CPU0_P2_ROM_MUX_2D_SDA")
	)
	(segment
		(start 427.839632 -393.026392)
		(end 425.899326 -394.966698)
		(width 0.11684)
		(layer "In4.Cu")
		(net "SMB_RT_CPU0_P2_ROM_MUX_2D_SDA")
	)
	(segment
		(start 423.680382 -425.511214)
		(end 424.021758 -425.511214)
		(width 0.11684)
		(layer "In4.Cu")
		(net "SMB_RT_CPU0_P2_ROM_MUX_2D_SDA")
	)
	(segment
		(start 421.908986 -419.345618)
		(end 421.908986 -423.739818)
		(width 0.11684)
		(layer "In4.Cu")
		(net "SMB_RT_CPU0_P2_ROM_MUX_2D_SDA")
	)
	(segment
		(start 247.20677 -368.589052)
		(end 249.32767 -366.468152)
		(width 0.11684)
		(layer "In4.Cu")
		(net "SMB_RT_CPU0_P2_ROM_MUX_2D_SDA")
	)
	(segment
		(start 431.47361 -393.026392)
		(end 427.839632 -393.026392)
		(width 0.11684)
		(layer "In4.Cu")
		(net "SMB_RT_CPU0_P2_ROM_MUX_2D_SDA")
	)
	(segment
		(start 437.827674 -386.672328)
		(end 431.47361 -393.026392)
		(width 0.11684)
		(layer "In4.Cu")
		(net "SMB_RT_CPU0_P2_ROM_MUX_2D_SDA")
	)
	(segment
		(start 247.20677 -370.005356)
		(end 247.20677 -368.589052)
		(width 0.11684)
		(layer "In4.Cu")
		(net "SMB_RT_CPU0_P2_ROM_MUX_2D_SDA")
	)
	(segment
		(start 423.128186 -406.291034)
		(end 420.557198 -408.862022)
		(width 0.11684)
		(layer "In4.Cu")
		(net "SMB_RT_CPU0_P2_ROM_MUX_2D_SDA")
	)
	(segment
		(start 424.64101 -401.127214)
		(end 423.961306 -401.127214)
		(width 0.11684)
		(layer "In4.Cu")
		(net "SMB_RT_CPU0_P2_ROM_MUX_2D_SDA")
	)
	(segment
		(start 420.557198 -408.862022)
		(end 420.557198 -417.99383)
		(width 0.11684)
		(layer "In4.Cu")
		(net "SMB_RT_CPU0_P2_ROM_MUX_2D_SDA")
	)
	(segment
		(start 256.679446 -335.0133)
		(end 257.436366 -335.0133)
		(width 0.11684)
		(layer "In4.Cu")
		(net "SMB_RT_CPU0_P2_ROM_MUX_2D_SDA")
	)
	(segment
		(start 425.899326 -399.868898)
		(end 424.64101 -401.127214)
		(width 0.11684)
		(layer "In4.Cu")
		(net "SMB_RT_CPU0_P2_ROM_MUX_2D_SDA")
	)
	(segment
		(start 255.143 -346.963746)
		(end 255.143 -336.549746)
		(width 0.11684)
		(layer "In4.Cu")
		(net "SMB_RT_CPU0_P2_ROM_MUX_2D_SDA")
	)
	(via
		(at 257.45567 -334.2767)
		(size 0.508)
		(drill 0.254)
		(layers "F.Cu" "B.Cu")
		(net "SMB_RT_CPU0_P2_ROM_MUX_2D_SCL")
	)
	(via
		(at 437.476138 -373.696484)
		(size 0.508)
		(drill 0.254)
		(layers "F.Cu" "B.Cu")
		(net "SMB_RT_CPU0_P2_ROM_MUX_2D_SCL")
	)
	(via
		(at 424.663108 -425.771818)
		(size 0.508)
		(drill 0.254)
		(layers "F.Cu" "B.Cu")
		(net "SMB_RT_CPU0_P2_ROM_MUX_2D_SCL")
	)
	(via
		(at 246.257826 -369.007136)
		(size 0.508)
		(drill 0.254)
		(layers "F.Cu" "B.Cu")
		(net "SMB_RT_CPU0_P2_ROM_MUX_2D_SCL")
	)
	(segment
		(start 252.36678 -371.268752)
		(end 283.415232 -371.268752)
		(width 0.10668)
		(layer "B.Cu")
		(net "SMB_RT_CPU0_P2_ROM_MUX_2D_SCL")
	)
	(segment
		(start 422.54297 -426.516038)
		(end 423.154348 -426.516038)
		(width 0.10668)
		(layer "B.Cu")
		(net "SMB_RT_CPU0_P2_ROM_MUX_2D_SCL")
	)
	(segment
		(start 299.513752 -372.367048)
		(end 426.360082 -372.367048)
		(width 0.10668)
		(layer "B.Cu")
		(net "SMB_RT_CPU0_P2_ROM_MUX_2D_SCL")
	)
	(segment
		(start 423.154348 -426.516038)
		(end 423.49801 -426.172376)
		(width 0.10668)
		(layer "B.Cu")
		(net "SMB_RT_CPU0_P2_ROM_MUX_2D_SCL")
	)
	(segment
		(start 426.360082 -372.367048)
		(end 428.850298 -374.857264)
		(width 0.10668)
		(layer "B.Cu")
		(net "SMB_RT_CPU0_P2_ROM_MUX_2D_SCL")
	)
	(segment
		(start 287.736788 -373.10314)
		(end 290.971224 -376.337576)
		(width 0.10668)
		(layer "B.Cu")
		(net "SMB_RT_CPU0_P2_ROM_MUX_2D_SCL")
	)
	(segment
		(start 424.26255 -426.172376)
		(end 424.663108 -425.771818)
		(width 0.10668)
		(layer "B.Cu")
		(net "SMB_RT_CPU0_P2_ROM_MUX_2D_SCL")
	)
	(segment
		(start 285.24962 -373.10314)
		(end 287.736788 -373.10314)
		(width 0.10668)
		(layer "B.Cu")
		(net "SMB_RT_CPU0_P2_ROM_MUX_2D_SCL")
	)
	(segment
		(start 246.257826 -369.007136)
		(end 246.257826 -369.988846)
		(width 0.10668)
		(layer "B.Cu")
		(net "SMB_RT_CPU0_P2_ROM_MUX_2D_SCL")
	)
	(segment
		(start 283.415232 -371.268752)
		(end 285.24962 -373.10314)
		(width 0.10668)
		(layer "B.Cu")
		(net "SMB_RT_CPU0_P2_ROM_MUX_2D_SCL")
	)
	(segment
		(start 436.315358 -374.857264)
		(end 437.476138 -373.696484)
		(width 0.10668)
		(layer "B.Cu")
		(net "SMB_RT_CPU0_P2_ROM_MUX_2D_SCL")
	)
	(segment
		(start 256.1717 -334.01)
		(end 257.18897 -334.01)
		(width 0.10668)
		(layer "B.Cu")
		(net "SMB_RT_CPU0_P2_ROM_MUX_2D_SCL")
	)
	(segment
		(start 252.065028 -371.570504)
		(end 252.36678 -371.268752)
		(width 0.10668)
		(layer "B.Cu")
		(net "SMB_RT_CPU0_P2_ROM_MUX_2D_SCL")
	)
	(segment
		(start 257.18897 -334.01)
		(end 257.45567 -334.2767)
		(width 0.10668)
		(layer "B.Cu")
		(net "SMB_RT_CPU0_P2_ROM_MUX_2D_SCL")
	)
	(segment
		(start 428.850298 -374.857264)
		(end 436.315358 -374.857264)
		(width 0.10668)
		(layer "B.Cu")
		(net "SMB_RT_CPU0_P2_ROM_MUX_2D_SCL")
	)
	(segment
		(start 423.49801 -426.172376)
		(end 424.26255 -426.172376)
		(width 0.10668)
		(layer "B.Cu")
		(net "SMB_RT_CPU0_P2_ROM_MUX_2D_SCL")
	)
	(segment
		(start 246.257826 -369.988846)
		(end 247.839484 -371.570504)
		(width 0.10668)
		(layer "B.Cu")
		(net "SMB_RT_CPU0_P2_ROM_MUX_2D_SCL")
	)
	(segment
		(start 295.543224 -376.337576)
		(end 299.513752 -372.367048)
		(width 0.10668)
		(layer "B.Cu")
		(net "SMB_RT_CPU0_P2_ROM_MUX_2D_SCL")
	)
	(segment
		(start 290.971224 -376.337576)
		(end 295.543224 -376.337576)
		(width 0.10668)
		(layer "B.Cu")
		(net "SMB_RT_CPU0_P2_ROM_MUX_2D_SCL")
	)
	(segment
		(start 247.839484 -371.570504)
		(end 252.065028 -371.570504)
		(width 0.10668)
		(layer "B.Cu")
		(net "SMB_RT_CPU0_P2_ROM_MUX_2D_SCL")
	)
	(segment
		(start 422.330626 -419.20414)
		(end 422.330626 -419.170866)
		(width 0.11684)
		(layer "In4.Cu")
		(net "SMB_RT_CPU0_P2_ROM_MUX_2D_SCL")
	)
	(segment
		(start 422.330626 -419.170866)
		(end 420.978838 -417.819078)
		(width 0.11684)
		(layer "In4.Cu")
		(net "SMB_RT_CPU0_P2_ROM_MUX_2D_SCL")
	)
	(segment
		(start 426.93717 -399.58391)
		(end 427.745398 -399.58391)
		(width 0.11684)
		(layer "In4.Cu")
		(net "SMB_RT_CPU0_P2_ROM_MUX_2D_SCL")
	)
	(segment
		(start 256.4003 -334.2767)
		(end 257.45567 -334.2767)
		(width 0.11684)
		(layer "In4.Cu")
		(net "SMB_RT_CPU0_P2_ROM_MUX_2D_SCL")
	)
	(segment
		(start 248.398792 -366.544606)
		(end 248.398792 -352.946462)
		(width 0.11684)
		(layer "In4.Cu")
		(net "SMB_RT_CPU0_P2_ROM_MUX_2D_SCL")
	)
	(segment
		(start 423.64914 -424.870372)
		(end 422.340024 -423.561256)
		(width 0.11684)
		(layer "In4.Cu")
		(net "SMB_RT_CPU0_P2_ROM_MUX_2D_SCL")
	)
	(segment
		(start 254.508 -346.837254)
		(end 254.508 -336.169)
		(width 0.11684)
		(layer "In4.Cu")
		(net "SMB_RT_CPU0_P2_ROM_MUX_2D_SCL")
	)
	(segment
		(start 425.088558 -401.600924)
		(end 425.088558 -401.432522)
		(width 0.11684)
		(layer "In4.Cu")
		(net "SMB_RT_CPU0_P2_ROM_MUX_2D_SCL")
	)
	(segment
		(start 248.398792 -352.946462)
		(end 254.508 -346.837254)
		(width 0.11684)
		(layer "In4.Cu")
		(net "SMB_RT_CPU0_P2_ROM_MUX_2D_SCL")
	)
	(segment
		(start 423.612818 -406.416002)
		(end 423.612818 -403.076664)
		(width 0.11684)
		(layer "In4.Cu")
		(net "SMB_RT_CPU0_P2_ROM_MUX_2D_SCL")
	)
	(segment
		(start 431.434494 -393.783566)
		(end 438.253378 -386.964682)
		(width 0.11684)
		(layer "In4.Cu")
		(net "SMB_RT_CPU0_P2_ROM_MUX_2D_SCL")
	)
	(segment
		(start 428.184818 -399.14449)
		(end 428.184818 -398.269968)
		(width 0.11684)
		(layer "In4.Cu")
		(net "SMB_RT_CPU0_P2_ROM_MUX_2D_SCL")
	)
	(segment
		(start 428.398686 -398.0561)
		(end 429.408336 -398.0561)
		(width 0.11684)
		(layer "In4.Cu")
		(net "SMB_RT_CPU0_P2_ROM_MUX_2D_SCL")
	)
	(segment
		(start 254.508 -336.169)
		(end 256.4003 -334.2767)
		(width 0.11684)
		(layer "In4.Cu")
		(net "SMB_RT_CPU0_P2_ROM_MUX_2D_SCL")
	)
	(segment
		(start 438.253378 -386.964682)
		(end 438.253378 -374.473724)
		(width 0.11684)
		(layer "In4.Cu")
		(net "SMB_RT_CPU0_P2_ROM_MUX_2D_SCL")
	)
	(segment
		(start 431.434494 -396.029942)
		(end 431.434494 -393.783566)
		(width 0.11684)
		(layer "In4.Cu")
		(net "SMB_RT_CPU0_P2_ROM_MUX_2D_SCL")
	)
	(segment
		(start 246.257826 -369.007136)
		(end 246.257826 -368.685572)
		(width 0.11684)
		(layer "In4.Cu")
		(net "SMB_RT_CPU0_P2_ROM_MUX_2D_SCL")
	)
	(segment
		(start 420.978838 -417.819078)
		(end 420.978838 -409.049982)
		(width 0.11684)
		(layer "In4.Cu")
		(net "SMB_RT_CPU0_P2_ROM_MUX_2D_SCL")
	)
	(segment
		(start 424.663108 -425.771818)
		(end 424.683936 -425.75099)
		(width 0.11684)
		(layer "In4.Cu")
		(net "SMB_RT_CPU0_P2_ROM_MUX_2D_SCL")
	)
	(segment
		(start 425.088558 -401.432522)
		(end 426.93717 -399.58391)
		(width 0.11684)
		(layer "In4.Cu")
		(net "SMB_RT_CPU0_P2_ROM_MUX_2D_SCL")
	)
	(segment
		(start 246.257826 -368.685572)
		(end 248.398792 -366.544606)
		(width 0.11684)
		(layer "In4.Cu")
		(net "SMB_RT_CPU0_P2_ROM_MUX_2D_SCL")
	)
	(segment
		(start 423.612818 -403.076664)
		(end 425.088558 -401.600924)
		(width 0.11684)
		(layer "In4.Cu")
		(net "SMB_RT_CPU0_P2_ROM_MUX_2D_SCL")
	)
	(segment
		(start 420.978838 -409.049982)
		(end 423.612818 -406.416002)
		(width 0.11684)
		(layer "In4.Cu")
		(net "SMB_RT_CPU0_P2_ROM_MUX_2D_SCL")
	)
	(segment
		(start 424.683936 -425.494196)
		(end 424.060112 -424.870372)
		(width 0.11684)
		(layer "In4.Cu")
		(net "SMB_RT_CPU0_P2_ROM_MUX_2D_SCL")
	)
	(segment
		(start 422.340024 -423.561256)
		(end 422.340024 -419.213538)
		(width 0.11684)
		(layer "In4.Cu")
		(net "SMB_RT_CPU0_P2_ROM_MUX_2D_SCL")
	)
	(segment
		(start 429.408336 -398.0561)
		(end 431.434494 -396.029942)
		(width 0.11684)
		(layer "In4.Cu")
		(net "SMB_RT_CPU0_P2_ROM_MUX_2D_SCL")
	)
	(segment
		(start 422.340024 -419.213538)
		(end 422.330626 -419.20414)
		(width 0.11684)
		(layer "In4.Cu")
		(net "SMB_RT_CPU0_P2_ROM_MUX_2D_SCL")
	)
	(segment
		(start 428.184818 -398.269968)
		(end 428.398686 -398.0561)
		(width 0.11684)
		(layer "In4.Cu")
		(net "SMB_RT_CPU0_P2_ROM_MUX_2D_SCL")
	)
	(segment
		(start 427.745398 -399.58391)
		(end 428.184818 -399.14449)
		(width 0.11684)
		(layer "In4.Cu")
		(net "SMB_RT_CPU0_P2_ROM_MUX_2D_SCL")
	)
	(segment
		(start 438.253378 -374.473724)
		(end 437.476138 -373.696484)
		(width 0.11684)
		(layer "In4.Cu")
		(net "SMB_RT_CPU0_P2_ROM_MUX_2D_SCL")
	)
	(segment
		(start 424.060112 -424.870372)
		(end 423.64914 -424.870372)
		(width 0.11684)
		(layer "In4.Cu")
		(net "SMB_RT_CPU0_P2_ROM_MUX_2D_SCL")
	)
	(segment
		(start 424.683936 -425.75099)
		(end 424.683936 -425.494196)
		(width 0.11684)
		(layer "In4.Cu")
		(net "SMB_RT_CPU0_P2_ROM_MUX_2D_SCL")
	)
	(via
		(at 423.737278 -426.717968)
		(size 0.6604)
		(drill 0.3302)
		(layers "F.Cu" "B.Cu")
		(net "SMB_RT_CPU0_P2_ROM_MUX_1D_SDA")
	)
	(segment
		(start 423.737278 -426.717968)
		(end 424.004232 -426.984922)
		(width 0.10668)
		(layer "B.Cu")
		(net "SMB_RT_CPU0_P2_ROM_MUX_1D_SDA")
	)
	(segment
		(start 422.54297 -427.01591)
		(end 423.439336 -427.01591)
		(width 0.10668)
		(layer "B.Cu")
		(net "SMB_RT_CPU0_P2_ROM_MUX_1D_SDA")
	)
	(segment
		(start 423.871136 -423.45102)
		(end 424.257216 -423.45102)
		(width 0.10668)
		(layer "B.Cu")
		(net "SMB_RT_CPU0_P2_ROM_MUX_1D_SDA")
	)
	(segment
		(start 424.004232 -426.984922)
		(end 424.684444 -426.984922)
		(width 0.10668)
		(layer "B.Cu")
		(net "SMB_RT_CPU0_P2_ROM_MUX_1D_SDA")
	)
	(segment
		(start 425.87418 -426.591984)
		(end 425.435776 -427.030388)
		(width 0.10668)
		(layer "B.Cu")
		(net "SMB_RT_CPU0_P2_ROM_MUX_1D_SDA")
	)
	(segment
		(start 425.87418 -425.067984)
		(end 425.87418 -426.591984)
		(width 0.10668)
		(layer "B.Cu")
		(net "SMB_RT_CPU0_P2_ROM_MUX_1D_SDA")
	)
	(segment
		(start 423.439336 -427.01591)
		(end 423.737278 -426.717968)
		(width 0.10668)
		(layer "B.Cu")
		(net "SMB_RT_CPU0_P2_ROM_MUX_1D_SDA")
	)
	(segment
		(start 422.22547 -422.28897)
		(end 422.709086 -422.28897)
		(width 0.10668)
		(layer "B.Cu")
		(net "SMB_RT_CPU0_P2_ROM_MUX_1D_SDA")
	)
	(segment
		(start 424.72991 -427.030388)
		(end 424.684444 -426.984922)
		(width 0.10668)
		(layer "B.Cu")
		(net "SMB_RT_CPU0_P2_ROM_MUX_1D_SDA")
	)
	(segment
		(start 422.709086 -422.28897)
		(end 423.871136 -423.45102)
		(width 0.10668)
		(layer "B.Cu")
		(net "SMB_RT_CPU0_P2_ROM_MUX_1D_SDA")
	)
	(segment
		(start 424.257216 -423.45102)
		(end 425.87418 -425.067984)
		(width 0.10668)
		(layer "B.Cu")
		(net "SMB_RT_CPU0_P2_ROM_MUX_1D_SDA")
	)
	(segment
		(start 425.435776 -427.030388)
		(end 424.72991 -427.030388)
		(width 0.10668)
		(layer "B.Cu")
		(net "SMB_RT_CPU0_P2_ROM_MUX_1D_SDA")
	)
	(via
		(at 423.794174 -428.309786)
		(size 0.6604)
		(drill 0.3302)
		(layers "F.Cu" "B.Cu")
		(net "SMB_RT_CPU0_P2_ROM_MUX_1D_SCL")
	)
	(segment
		(start 421.235124 -420.534592)
		(end 421.436292 -420.534592)
		(width 0.10668)
		(layer "B.Cu")
		(net "SMB_RT_CPU0_P2_ROM_MUX_1D_SCL")
	)
	(segment
		(start 424.39844 -423.11066)
		(end 426.21454 -424.92676)
		(width 0.10668)
		(layer "B.Cu")
		(net "SMB_RT_CPU0_P2_ROM_MUX_1D_SCL")
	)
	(segment
		(start 424.01236 -423.11066)
		(end 424.39844 -423.11066)
		(width 0.10668)
		(layer "B.Cu")
		(net "SMB_RT_CPU0_P2_ROM_MUX_1D_SCL")
	)
	(segment
		(start 424.669458 -427.84649)
		(end 424.664124 -427.851824)
		(width 0.10668)
		(layer "B.Cu")
		(net "SMB_RT_CPU0_P2_ROM_MUX_1D_SCL")
	)
	(segment
		(start 422.54297 -427.516036)
		(end 423.000424 -427.516036)
		(width 0.10668)
		(layer "B.Cu")
		(net "SMB_RT_CPU0_P2_ROM_MUX_1D_SCL")
	)
	(segment
		(start 425.43349 -427.84649)
		(end 424.669458 -427.84649)
		(width 0.10668)
		(layer "B.Cu")
		(net "SMB_RT_CPU0_P2_ROM_MUX_1D_SCL")
	)
	(segment
		(start 424.252136 -427.851824)
		(end 423.794174 -428.309786)
		(width 0.10668)
		(layer "B.Cu")
		(net "SMB_RT_CPU0_P2_ROM_MUX_1D_SCL")
	)
	(segment
		(start 426.21454 -424.92676)
		(end 426.21454 -427.06544)
		(width 0.10668)
		(layer "B.Cu")
		(net "SMB_RT_CPU0_P2_ROM_MUX_1D_SCL")
	)
	(segment
		(start 423.000424 -427.516036)
		(end 423.794174 -428.309786)
		(width 0.10668)
		(layer "B.Cu")
		(net "SMB_RT_CPU0_P2_ROM_MUX_1D_SCL")
	)
	(segment
		(start 424.664124 -427.851824)
		(end 424.252136 -427.851824)
		(width 0.10668)
		(layer "B.Cu")
		(net "SMB_RT_CPU0_P2_ROM_MUX_1D_SCL")
	)
	(segment
		(start 426.21454 -427.06544)
		(end 425.43349 -427.84649)
		(width 0.10668)
		(layer "B.Cu")
		(net "SMB_RT_CPU0_P2_ROM_MUX_1D_SCL")
	)
	(segment
		(start 421.436292 -420.534592)
		(end 424.01236 -423.11066)
		(width 0.10668)
		(layer "B.Cu")
		(net "SMB_RT_CPU0_P2_ROM_MUX_1D_SCL")
	)
	(segment
		(start 291.64026 -394.591286)
		(end 291.64026 -394.429742)
		(width 0.10668)
		(layer "F.Cu")
		(net "SMB_RT_CPU0_P1_ROM_MUX_2D_SDA")
	)
	(segment
		(start 292.289738 -394.30706)
		(end 293.201344 -395.218666)
		(width 0.10668)
		(layer "F.Cu")
		(net "SMB_RT_CPU0_P1_ROM_MUX_2D_SDA")
	)
	(segment
		(start 291.762942 -394.30706)
		(end 292.289738 -394.30706)
		(width 0.10668)
		(layer "F.Cu")
		(net "SMB_RT_CPU0_P1_ROM_MUX_2D_SDA")
	)
	(segment
		(start 291.64026 -394.429742)
		(end 291.762942 -394.30706)
		(width 0.10668)
		(layer "F.Cu")
		(net "SMB_RT_CPU0_P1_ROM_MUX_2D_SDA")
	)
	(via
		(at 293.201344 -395.218666)
		(size 0.508)
		(drill 0.254)
		(layers "F.Cu" "B.Cu")
		(net "SMB_RT_CPU0_P1_ROM_MUX_2D_SDA")
	)
	(via
		(at 257.429 -339.63864)
		(size 0.508)
		(drill 0.254)
		(layers "F.Cu" "B.Cu")
		(net "SMB_RT_CPU0_P1_ROM_MUX_2D_SDA")
	)
	(segment
		(start 256.1717 -339.63864)
		(end 257.429 -339.63864)
		(width 0.10668)
		(layer "B.Cu")
		(net "SMB_RT_CPU0_P1_ROM_MUX_2D_SDA")
	)
	(segment
		(start 273.622008 -356.107746)
		(end 273.93773 -356.423468)
		(width 0.11684)
		(layer "In13.Cu")
		(net "SMB_RT_CPU0_P1_ROM_MUX_2D_SDA")
	)
	(segment
		(start 257.59664 -339.63864)
		(end 258.953 -340.995)
		(width 0.11684)
		(layer "In13.Cu")
		(net "SMB_RT_CPU0_P1_ROM_MUX_2D_SDA")
	)
	(segment
		(start 258.953 -347.682566)
		(end 267.37818 -356.107746)
		(width 0.11684)
		(layer "In13.Cu")
		(net "SMB_RT_CPU0_P1_ROM_MUX_2D_SDA")
	)
	(segment
		(start 273.93773 -362.320078)
		(end 277.242524 -365.624872)
		(width 0.11684)
		(layer "In13.Cu")
		(net "SMB_RT_CPU0_P1_ROM_MUX_2D_SDA")
	)
	(segment
		(start 257.429 -339.63864)
		(end 257.59664 -339.63864)
		(width 0.11684)
		(layer "In13.Cu")
		(net "SMB_RT_CPU0_P1_ROM_MUX_2D_SDA")
	)
	(segment
		(start 285.428436 -371.29593)
		(end 285.428436 -375.933208)
		(width 0.11684)
		(layer "In13.Cu")
		(net "SMB_RT_CPU0_P1_ROM_MUX_2D_SDA")
	)
	(segment
		(start 285.12008 -376.241564)
		(end 285.12008 -378.68479)
		(width 0.11684)
		(layer "In13.Cu")
		(net "SMB_RT_CPU0_P1_ROM_MUX_2D_SDA")
	)
	(segment
		(start 267.37818 -356.107746)
		(end 273.622008 -356.107746)
		(width 0.11684)
		(layer "In13.Cu")
		(net "SMB_RT_CPU0_P1_ROM_MUX_2D_SDA")
	)
	(segment
		(start 292.734492 -394.751814)
		(end 293.201344 -395.218666)
		(width 0.11684)
		(layer "In13.Cu")
		(net "SMB_RT_CPU0_P1_ROM_MUX_2D_SDA")
	)
	(segment
		(start 288.22523 -392.32713)
		(end 290.649914 -394.751814)
		(width 0.11684)
		(layer "In13.Cu")
		(net "SMB_RT_CPU0_P1_ROM_MUX_2D_SDA")
	)
	(segment
		(start 279.757378 -365.624872)
		(end 285.428436 -371.29593)
		(width 0.11684)
		(layer "In13.Cu")
		(net "SMB_RT_CPU0_P1_ROM_MUX_2D_SDA")
	)
	(segment
		(start 286.32023 -379.88494)
		(end 286.32023 -387.909562)
		(width 0.11684)
		(layer "In13.Cu")
		(net "SMB_RT_CPU0_P1_ROM_MUX_2D_SDA")
	)
	(segment
		(start 277.242524 -365.624872)
		(end 279.757378 -365.624872)
		(width 0.11684)
		(layer "In13.Cu")
		(net "SMB_RT_CPU0_P1_ROM_MUX_2D_SDA")
	)
	(segment
		(start 286.32023 -387.909562)
		(end 288.22523 -389.814562)
		(width 0.11684)
		(layer "In13.Cu")
		(net "SMB_RT_CPU0_P1_ROM_MUX_2D_SDA")
	)
	(segment
		(start 288.22523 -389.814562)
		(end 288.22523 -392.32713)
		(width 0.11684)
		(layer "In13.Cu")
		(net "SMB_RT_CPU0_P1_ROM_MUX_2D_SDA")
	)
	(segment
		(start 285.12008 -378.68479)
		(end 286.32023 -379.88494)
		(width 0.11684)
		(layer "In13.Cu")
		(net "SMB_RT_CPU0_P1_ROM_MUX_2D_SDA")
	)
	(segment
		(start 273.93773 -356.423468)
		(end 273.93773 -362.320078)
		(width 0.11684)
		(layer "In13.Cu")
		(net "SMB_RT_CPU0_P1_ROM_MUX_2D_SDA")
	)
	(segment
		(start 285.428436 -375.933208)
		(end 285.12008 -376.241564)
		(width 0.11684)
		(layer "In13.Cu")
		(net "SMB_RT_CPU0_P1_ROM_MUX_2D_SDA")
	)
	(segment
		(start 290.649914 -394.751814)
		(end 292.734492 -394.751814)
		(width 0.11684)
		(layer "In13.Cu")
		(net "SMB_RT_CPU0_P1_ROM_MUX_2D_SDA")
	)
	(segment
		(start 258.953 -340.995)
		(end 258.953 -347.682566)
		(width 0.11684)
		(layer "In13.Cu")
		(net "SMB_RT_CPU0_P1_ROM_MUX_2D_SDA")
	)
	(segment
		(start 291.140134 -394.591286)
		(end 291.140134 -394.122656)
		(width 0.10668)
		(layer "F.Cu")
		(net "SMB_RT_CPU0_P1_ROM_MUX_2D_SCL")
	)
	(segment
		(start 291.38372 -393.87907)
		(end 292.379146 -393.87907)
		(width 0.10668)
		(layer "F.Cu")
		(net "SMB_RT_CPU0_P1_ROM_MUX_2D_SCL")
	)
	(segment
		(start 293.94277 -394.970508)
		(end 293.94277 -395.224)
		(width 0.10668)
		(layer "F.Cu")
		(net "SMB_RT_CPU0_P1_ROM_MUX_2D_SCL")
	)
	(segment
		(start 291.140134 -394.122656)
		(end 291.38372 -393.87907)
		(width 0.10668)
		(layer "F.Cu")
		(net "SMB_RT_CPU0_P1_ROM_MUX_2D_SCL")
	)
	(segment
		(start 293.040308 -394.540232)
		(end 293.512494 -394.540232)
		(width 0.10668)
		(layer "F.Cu")
		(net "SMB_RT_CPU0_P1_ROM_MUX_2D_SCL")
	)
	(segment
		(start 293.512494 -394.540232)
		(end 293.94277 -394.970508)
		(width 0.10668)
		(layer "F.Cu")
		(net "SMB_RT_CPU0_P1_ROM_MUX_2D_SCL")
	)
	(segment
		(start 292.379146 -393.87907)
		(end 293.040308 -394.540232)
		(width 0.10668)
		(layer "F.Cu")
		(net "SMB_RT_CPU0_P1_ROM_MUX_2D_SCL")
	)
	(via
		(at 293.94277 -395.224)
		(size 0.508)
		(drill 0.254)
		(layers "F.Cu" "B.Cu")
		(net "SMB_RT_CPU0_P1_ROM_MUX_2D_SCL")
	)
	(via
		(at 257.429 -338.51596)
		(size 0.508)
		(drill 0.254)
		(layers "F.Cu" "B.Cu")
		(net "SMB_RT_CPU0_P1_ROM_MUX_2D_SCL")
	)
	(segment
		(start 256.1717 -338.51596)
		(end 257.429 -338.51596)
		(width 0.10668)
		(layer "B.Cu")
		(net "SMB_RT_CPU0_P1_ROM_MUX_2D_SCL")
	)
	(segment
		(start 290.794948 -394.264134)
		(end 293.220648 -394.264134)
		(width 0.11684)
		(layer "In13.Cu")
		(net "SMB_RT_CPU0_P1_ROM_MUX_2D_SCL")
	)
	(segment
		(start 286.847534 -380.725426)
		(end 286.74187 -380.83109)
		(width 0.11684)
		(layer "In13.Cu")
		(net "SMB_RT_CPU0_P1_ROM_MUX_2D_SCL")
	)
	(segment
		(start 267.552932 -355.686106)
		(end 273.79676 -355.686106)
		(width 0.11684)
		(layer "In13.Cu")
		(net "SMB_RT_CPU0_P1_ROM_MUX_2D_SCL")
	)
	(segment
		(start 275.130006 -362.915962)
		(end 277.417276 -365.203232)
		(width 0.11684)
		(layer "In13.Cu")
		(net "SMB_RT_CPU0_P1_ROM_MUX_2D_SCL")
	)
	(segment
		(start 293.94277 -394.986256)
		(end 293.94277 -395.224)
		(width 0.11684)
		(layer "In13.Cu")
		(net "SMB_RT_CPU0_P1_ROM_MUX_2D_SCL")
	)
	(segment
		(start 285.850076 -375.370344)
		(end 286.847534 -376.367802)
		(width 0.11684)
		(layer "In13.Cu")
		(net "SMB_RT_CPU0_P1_ROM_MUX_2D_SCL")
	)
	(segment
		(start 279.93213 -365.203232)
		(end 285.850076 -371.121178)
		(width 0.11684)
		(layer "In13.Cu")
		(net "SMB_RT_CPU0_P1_ROM_MUX_2D_SCL")
	)
	(segment
		(start 286.847534 -376.367802)
		(end 286.847534 -380.725426)
		(width 0.11684)
		(layer "In13.Cu")
		(net "SMB_RT_CPU0_P1_ROM_MUX_2D_SCL")
	)
	(segment
		(start 293.220648 -394.264134)
		(end 293.94277 -394.986256)
		(width 0.11684)
		(layer "In13.Cu")
		(net "SMB_RT_CPU0_P1_ROM_MUX_2D_SCL")
	)
	(segment
		(start 273.79676 -355.686106)
		(end 275.130006 -357.019352)
		(width 0.11684)
		(layer "In13.Cu")
		(net "SMB_RT_CPU0_P1_ROM_MUX_2D_SCL")
	)
	(segment
		(start 288.735262 -392.204448)
		(end 290.794948 -394.264134)
		(width 0.11684)
		(layer "In13.Cu")
		(net "SMB_RT_CPU0_P1_ROM_MUX_2D_SCL")
	)
	(segment
		(start 288.735262 -389.399526)
		(end 288.735262 -392.204448)
		(width 0.11684)
		(layer "In13.Cu")
		(net "SMB_RT_CPU0_P1_ROM_MUX_2D_SCL")
	)
	(segment
		(start 286.74187 -380.83109)
		(end 286.74187 -387.406134)
		(width 0.11684)
		(layer "In13.Cu")
		(net "SMB_RT_CPU0_P1_ROM_MUX_2D_SCL")
	)
	(segment
		(start 275.130006 -357.019352)
		(end 275.130006 -362.915962)
		(width 0.11684)
		(layer "In13.Cu")
		(net "SMB_RT_CPU0_P1_ROM_MUX_2D_SCL")
	)
	(segment
		(start 277.417276 -365.203232)
		(end 279.93213 -365.203232)
		(width 0.11684)
		(layer "In13.Cu")
		(net "SMB_RT_CPU0_P1_ROM_MUX_2D_SCL")
	)
	(segment
		(start 257.429 -338.51596)
		(end 259.842 -340.92896)
		(width 0.11684)
		(layer "In13.Cu")
		(net "SMB_RT_CPU0_P1_ROM_MUX_2D_SCL")
	)
	(segment
		(start 259.842 -340.92896)
		(end 259.842 -347.975174)
		(width 0.11684)
		(layer "In13.Cu")
		(net "SMB_RT_CPU0_P1_ROM_MUX_2D_SCL")
	)
	(segment
		(start 285.850076 -371.121178)
		(end 285.850076 -375.370344)
		(width 0.11684)
		(layer "In13.Cu")
		(net "SMB_RT_CPU0_P1_ROM_MUX_2D_SCL")
	)
	(segment
		(start 286.74187 -387.406134)
		(end 288.735262 -389.399526)
		(width 0.11684)
		(layer "In13.Cu")
		(net "SMB_RT_CPU0_P1_ROM_MUX_2D_SCL")
	)
	(segment
		(start 259.842 -347.975174)
		(end 267.552932 -355.686106)
		(width 0.11684)
		(layer "In13.Cu")
		(net "SMB_RT_CPU0_P1_ROM_MUX_2D_SCL")
	)
	(segment
		(start 329.59548 -388.501636)
		(end 329.947778 -388.149338)
		(width 0.10668)
		(layer "F.Cu")
		(net "SMB_RT_CPU0_P1_ROM_MUX_1D_SDA")
	)
	(segment
		(start 294.42156 -394.614654)
		(end 294.314372 -394.721842)
		(width 0.10668)
		(layer "F.Cu")
		(net "SMB_RT_CPU0_P1_ROM_MUX_1D_SDA")
	)
	(segment
		(start 294.314372 -394.721842)
		(end 293.525448 -393.932918)
		(width 0.10668)
		(layer "F.Cu")
		(net "SMB_RT_CPU0_P1_ROM_MUX_1D_SDA")
	)
	(segment
		(start 294.755316 -393.99845)
		(end 294.42156 -394.332206)
		(width 0.10668)
		(layer "F.Cu")
		(net "SMB_RT_CPU0_P1_ROM_MUX_1D_SDA")
	)
	(segment
		(start 290.908232 -393.515088)
		(end 290.640262 -393.783058)
		(width 0.10668)
		(layer "F.Cu")
		(net "SMB_RT_CPU0_P1_ROM_MUX_1D_SDA")
	)
	(segment
		(start 329.947778 -388.149338)
		(end 330.665836 -388.149338)
		(width 0.10668)
		(layer "F.Cu")
		(net "SMB_RT_CPU0_P1_ROM_MUX_1D_SDA")
	)
	(segment
		(start 295.018968 -393.99845)
		(end 294.755316 -393.99845)
		(width 0.10668)
		(layer "F.Cu")
		(net "SMB_RT_CPU0_P1_ROM_MUX_1D_SDA")
	)
	(segment
		(start 292.867588 -393.515088)
		(end 290.908232 -393.515088)
		(width 0.10668)
		(layer "F.Cu")
		(net "SMB_RT_CPU0_P1_ROM_MUX_1D_SDA")
	)
	(segment
		(start 293.525448 -393.932918)
		(end 293.285418 -393.932918)
		(width 0.10668)
		(layer "F.Cu")
		(net "SMB_RT_CPU0_P1_ROM_MUX_1D_SDA")
	)
	(segment
		(start 294.42156 -394.332206)
		(end 294.42156 -394.614654)
		(width 0.10668)
		(layer "F.Cu")
		(net "SMB_RT_CPU0_P1_ROM_MUX_1D_SDA")
	)
	(segment
		(start 293.285418 -393.932918)
		(end 292.867588 -393.515088)
		(width 0.10668)
		(layer "F.Cu")
		(net "SMB_RT_CPU0_P1_ROM_MUX_1D_SDA")
	)
	(segment
		(start 290.640262 -393.783058)
		(end 290.640262 -394.591286)
		(width 0.10668)
		(layer "F.Cu")
		(net "SMB_RT_CPU0_P1_ROM_MUX_1D_SDA")
	)
	(via
		(at 295.018968 -393.99845)
		(size 0.508)
		(drill 0.254)
		(layers "F.Cu" "B.Cu")
		(net "SMB_RT_CPU0_P1_ROM_MUX_1D_SDA")
	)
	(via
		(at 329.59548 -388.501636)
		(size 0.508)
		(drill 0.254)
		(layers "F.Cu" "B.Cu")
		(net "SMB_RT_CPU0_P1_ROM_MUX_1D_SDA")
	)
	(segment
		(start 302.965866 -387.808724)
		(end 322.286884 -387.808724)
		(width 0.11684)
		(layer "In2.Cu")
		(net "SMB_RT_CPU0_P1_ROM_MUX_1D_SDA")
	)
	(segment
		(start 297.97375 -392.80084)
		(end 302.965866 -387.808724)
		(width 0.11684)
		(layer "In2.Cu")
		(net "SMB_RT_CPU0_P1_ROM_MUX_1D_SDA")
	)
	(segment
		(start 297.004232 -392.80084)
		(end 297.97375 -392.80084)
		(width 0.11684)
		(layer "In2.Cu")
		(net "SMB_RT_CPU0_P1_ROM_MUX_1D_SDA")
	)
	(segment
		(start 295.806622 -393.99845)
		(end 297.004232 -392.80084)
		(width 0.11684)
		(layer "In2.Cu")
		(net "SMB_RT_CPU0_P1_ROM_MUX_1D_SDA")
	)
	(segment
		(start 322.286884 -387.808724)
		(end 324.63867 -390.16051)
		(width 0.11684)
		(layer "In2.Cu")
		(net "SMB_RT_CPU0_P1_ROM_MUX_1D_SDA")
	)
	(segment
		(start 327.44283 -390.16051)
		(end 329.101704 -388.501636)
		(width 0.11684)
		(layer "In2.Cu")
		(net "SMB_RT_CPU0_P1_ROM_MUX_1D_SDA")
	)
	(segment
		(start 295.018968 -393.99845)
		(end 295.806622 -393.99845)
		(width 0.11684)
		(layer "In2.Cu")
		(net "SMB_RT_CPU0_P1_ROM_MUX_1D_SDA")
	)
	(segment
		(start 324.63867 -390.16051)
		(end 327.44283 -390.16051)
		(width 0.11684)
		(layer "In2.Cu")
		(net "SMB_RT_CPU0_P1_ROM_MUX_1D_SDA")
	)
	(segment
		(start 329.101704 -388.501636)
		(end 329.59548 -388.501636)
		(width 0.11684)
		(layer "In2.Cu")
		(net "SMB_RT_CPU0_P1_ROM_MUX_1D_SDA")
	)
	(segment
		(start 330.665836 -387.350254)
		(end 330.047346 -387.350254)
		(width 0.10668)
		(layer "F.Cu")
		(net "SMB_RT_CPU0_P1_ROM_MUX_1D_SCL")
	)
	(segment
		(start 294.493188 -392.32205)
		(end 294.08374 -392.32205)
		(width 0.10668)
		(layer "F.Cu")
		(net "SMB_RT_CPU0_P1_ROM_MUX_1D_SCL")
	)
	(segment
		(start 294.493188 -392.32205)
		(end 294.493188 -392.594338)
		(width 0.10668)
		(layer "F.Cu")
		(net "SMB_RT_CPU0_P1_ROM_MUX_1D_SCL")
	)
	(segment
		(start 290.140136 -393.426696)
		(end 290.140136 -394.591286)
		(width 0.10668)
		(layer "F.Cu")
		(net "SMB_RT_CPU0_P1_ROM_MUX_1D_SCL")
	)
	(segment
		(start 293.326312 -393.079478)
		(end 290.487354 -393.079478)
		(width 0.10668)
		(layer "F.Cu")
		(net "SMB_RT_CPU0_P1_ROM_MUX_1D_SCL")
	)
	(segment
		(start 290.487354 -393.079478)
		(end 290.140136 -393.426696)
		(width 0.10668)
		(layer "F.Cu")
		(net "SMB_RT_CPU0_P1_ROM_MUX_1D_SCL")
	)
	(segment
		(start 330.047346 -387.350254)
		(end 329.56246 -387.83514)
		(width 0.10668)
		(layer "F.Cu")
		(net "SMB_RT_CPU0_P1_ROM_MUX_1D_SCL")
	)
	(segment
		(start 294.493188 -392.594338)
		(end 294.63238 -392.73353)
		(width 0.10668)
		(layer "F.Cu")
		(net "SMB_RT_CPU0_P1_ROM_MUX_1D_SCL")
	)
	(segment
		(start 294.63238 -392.73353)
		(end 295.52519 -392.73353)
		(width 0.10668)
		(layer "F.Cu")
		(net "SMB_RT_CPU0_P1_ROM_MUX_1D_SCL")
	)
	(segment
		(start 294.08374 -392.32205)
		(end 293.326312 -393.079478)
		(width 0.10668)
		(layer "F.Cu")
		(net "SMB_RT_CPU0_P1_ROM_MUX_1D_SCL")
	)
	(via
		(at 295.52519 -392.73353)
		(size 0.508)
		(drill 0.254)
		(layers "F.Cu" "B.Cu")
		(net "SMB_RT_CPU0_P1_ROM_MUX_1D_SCL")
	)
	(via
		(at 329.56246 -387.83514)
		(size 0.508)
		(drill 0.254)
		(layers "F.Cu" "B.Cu")
		(net "SMB_RT_CPU0_P1_ROM_MUX_1D_SCL")
	)
	(segment
		(start 296.26052 -391.9982)
		(end 295.52519 -392.73353)
		(width 0.11684)
		(layer "In2.Cu")
		(net "SMB_RT_CPU0_P1_ROM_MUX_1D_SCL")
	)
	(segment
		(start 297.03776 -388.59968)
		(end 296.26052 -389.37692)
		(width 0.11684)
		(layer "In2.Cu")
		(net "SMB_RT_CPU0_P1_ROM_MUX_1D_SCL")
	)
	(segment
		(start 328.40549 -386.67817)
		(end 303.363376 -386.67817)
		(width 0.11684)
		(layer "In2.Cu")
		(net "SMB_RT_CPU0_P1_ROM_MUX_1D_SCL")
	)
	(segment
		(start 301.441866 -388.59968)
		(end 297.03776 -388.59968)
		(width 0.11684)
		(layer "In2.Cu")
		(net "SMB_RT_CPU0_P1_ROM_MUX_1D_SCL")
	)
	(segment
		(start 296.26052 -389.37692)
		(end 296.26052 -391.9982)
		(width 0.11684)
		(layer "In2.Cu")
		(net "SMB_RT_CPU0_P1_ROM_MUX_1D_SCL")
	)
	(segment
		(start 303.363376 -386.67817)
		(end 301.441866 -388.59968)
		(width 0.11684)
		(layer "In2.Cu")
		(net "SMB_RT_CPU0_P1_ROM_MUX_1D_SCL")
	)
	(segment
		(start 329.56246 -387.83514)
		(end 328.40549 -386.67817)
		(width 0.11684)
		(layer "In2.Cu")
		(net "SMB_RT_CPU0_P1_ROM_MUX_1D_SCL")
	)
	(via
		(at 257.175 -342.265)
		(size 0.508)
		(drill 0.254)
		(layers "F.Cu" "B.Cu")
		(net "SMB_RT_CPU0_P0_ROM_MUX_2D_SDA")
	)
	(via
		(at 300.07179 -424.259248)
		(size 0.508)
		(drill 0.254)
		(layers "F.Cu" "B.Cu")
		(net "SMB_RT_CPU0_P0_ROM_MUX_2D_SDA")
	)
	(segment
		(start 256.1717 -341.884)
		(end 256.794 -341.884)
		(width 0.10668)
		(layer "B.Cu")
		(net "SMB_RT_CPU0_P0_ROM_MUX_2D_SDA")
	)
	(segment
		(start 299.205396 -424.538902)
		(end 299.792136 -424.538902)
		(width 0.10668)
		(layer "B.Cu")
		(net "SMB_RT_CPU0_P0_ROM_MUX_2D_SDA")
	)
	(segment
		(start 256.794 -341.884)
		(end 257.175 -342.265)
		(width 0.10668)
		(layer "B.Cu")
		(net "SMB_RT_CPU0_P0_ROM_MUX_2D_SDA")
	)
	(segment
		(start 299.792136 -424.538902)
		(end 300.07179 -424.259248)
		(width 0.10668)
		(layer "B.Cu")
		(net "SMB_RT_CPU0_P0_ROM_MUX_2D_SDA")
	)
	(segment
		(start 285.47695 -388.25932)
		(end 287.181798 -389.964168)
		(width 0.11684)
		(layer "In13.Cu")
		(net "SMB_RT_CPU0_P0_ROM_MUX_2D_SDA")
	)
	(segment
		(start 285.47695 -380.234698)
		(end 285.47695 -388.25932)
		(width 0.11684)
		(layer "In13.Cu")
		(net "SMB_RT_CPU0_P0_ROM_MUX_2D_SDA")
	)
	(segment
		(start 271.238726 -363.587792)
		(end 271.820386 -364.169452)
		(width 0.11684)
		(layer "In13.Cu")
		(net "SMB_RT_CPU0_P0_ROM_MUX_2D_SDA")
	)
	(segment
		(start 291.309044 -417.198302)
		(end 291.803328 -417.692586)
		(width 0.11684)
		(layer "In13.Cu")
		(net "SMB_RT_CPU0_P0_ROM_MUX_2D_SDA")
	)
	(segment
		(start 282.567634 -374.1801)
		(end 284.181042 -375.793508)
		(width 0.11684)
		(layer "In13.Cu")
		(net "SMB_RT_CPU0_P0_ROM_MUX_2D_SDA")
	)
	(segment
		(start 292.268402 -417.99256)
		(end 292.268402 -418.15766)
		(width 0.11684)
		(layer "In13.Cu")
		(net "SMB_RT_CPU0_P0_ROM_MUX_2D_SDA")
	)
	(segment
		(start 292.68547 -418.574728)
		(end 292.68547 -420.991538)
		(width 0.11684)
		(layer "In13.Cu")
		(net "SMB_RT_CPU0_P0_ROM_MUX_2D_SDA")
	)
	(segment
		(start 290.452556 -395.924786)
		(end 291.381942 -395.924786)
		(width 0.11684)
		(layer "In13.Cu")
		(net "SMB_RT_CPU0_P0_ROM_MUX_2D_SDA")
	)
	(segment
		(start 293.38778 -399.89506)
		(end 293.38778 -405.773636)
		(width 0.11684)
		(layer "In13.Cu")
		(net "SMB_RT_CPU0_P0_ROM_MUX_2D_SDA")
	)
	(segment
		(start 271.238726 -361.347512)
		(end 271.238726 -363.587792)
		(width 0.11684)
		(layer "In13.Cu")
		(net "SMB_RT_CPU0_P0_ROM_MUX_2D_SDA")
	)
	(segment
		(start 256.29235 -346.401136)
		(end 271.238726 -361.347512)
		(width 0.11684)
		(layer "In13.Cu")
		(net "SMB_RT_CPU0_P0_ROM_MUX_2D_SDA")
	)
	(segment
		(start 299.089318 -423.64025)
		(end 299.708316 -424.259248)
		(width 0.11684)
		(layer "In13.Cu")
		(net "SMB_RT_CPU0_P0_ROM_MUX_2D_SDA")
	)
	(segment
		(start 273.930618 -364.169452)
		(end 282.567634 -372.806468)
		(width 0.11684)
		(layer "In13.Cu")
		(net "SMB_RT_CPU0_P0_ROM_MUX_2D_SDA")
	)
	(segment
		(start 287.181798 -389.964168)
		(end 287.181798 -392.654028)
		(width 0.11684)
		(layer "In13.Cu")
		(net "SMB_RT_CPU0_P0_ROM_MUX_2D_SDA")
	)
	(segment
		(start 287.181798 -392.654028)
		(end 290.452556 -395.924786)
		(width 0.11684)
		(layer "In13.Cu")
		(net "SMB_RT_CPU0_P0_ROM_MUX_2D_SDA")
	)
	(segment
		(start 271.820386 -364.169452)
		(end 273.930618 -364.169452)
		(width 0.11684)
		(layer "In13.Cu")
		(net "SMB_RT_CPU0_P0_ROM_MUX_2D_SDA")
	)
	(segment
		(start 292.664642 -416.996372)
		(end 292.829742 -416.996372)
		(width 0.11684)
		(layer "In13.Cu")
		(net "SMB_RT_CPU0_P0_ROM_MUX_2D_SDA")
	)
	(segment
		(start 291.309044 -407.852372)
		(end 291.309044 -417.198302)
		(width 0.11684)
		(layer "In13.Cu")
		(net "SMB_RT_CPU0_P0_ROM_MUX_2D_SDA")
	)
	(segment
		(start 256.29235 -343.14765)
		(end 256.29235 -346.401136)
		(width 0.11684)
		(layer "In13.Cu")
		(net "SMB_RT_CPU0_P0_ROM_MUX_2D_SDA")
	)
	(segment
		(start 293.839392 -398.382236)
		(end 293.839392 -399.443448)
		(width 0.11684)
		(layer "In13.Cu")
		(net "SMB_RT_CPU0_P0_ROM_MUX_2D_SDA")
	)
	(segment
		(start 292.68547 -420.991538)
		(end 293.541704 -421.847772)
		(width 0.11684)
		(layer "In13.Cu")
		(net "SMB_RT_CPU0_P0_ROM_MUX_2D_SDA")
	)
	(segment
		(start 291.381942 -395.924786)
		(end 293.839392 -398.382236)
		(width 0.11684)
		(layer "In13.Cu")
		(net "SMB_RT_CPU0_P0_ROM_MUX_2D_SDA")
	)
	(segment
		(start 293.839392 -399.443448)
		(end 293.38778 -399.89506)
		(width 0.11684)
		(layer "In13.Cu")
		(net "SMB_RT_CPU0_P0_ROM_MUX_2D_SDA")
	)
	(segment
		(start 292.829742 -416.996372)
		(end 292.964616 -417.131246)
		(width 0.11684)
		(layer "In13.Cu")
		(net "SMB_RT_CPU0_P0_ROM_MUX_2D_SDA")
	)
	(segment
		(start 293.38778 -405.773636)
		(end 291.309044 -407.852372)
		(width 0.11684)
		(layer "In13.Cu")
		(net "SMB_RT_CPU0_P0_ROM_MUX_2D_SDA")
	)
	(segment
		(start 292.964616 -417.296346)
		(end 292.268402 -417.99256)
		(width 0.11684)
		(layer "In13.Cu")
		(net "SMB_RT_CPU0_P0_ROM_MUX_2D_SDA")
	)
	(segment
		(start 257.175 -342.265)
		(end 256.29235 -343.14765)
		(width 0.11684)
		(layer "In13.Cu")
		(net "SMB_RT_CPU0_P0_ROM_MUX_2D_SDA")
	)
	(segment
		(start 284.181042 -378.93879)
		(end 285.47695 -380.234698)
		(width 0.11684)
		(layer "In13.Cu")
		(net "SMB_RT_CPU0_P0_ROM_MUX_2D_SDA")
	)
	(segment
		(start 297.709082 -421.847772)
		(end 298.797726 -422.936416)
		(width 0.11684)
		(layer "In13.Cu")
		(net "SMB_RT_CPU0_P0_ROM_MUX_2D_SDA")
	)
	(segment
		(start 284.181042 -375.793508)
		(end 284.181042 -378.93879)
		(width 0.11684)
		(layer "In13.Cu")
		(net "SMB_RT_CPU0_P0_ROM_MUX_2D_SDA")
	)
	(segment
		(start 299.708316 -424.259248)
		(end 300.07179 -424.259248)
		(width 0.11684)
		(layer "In13.Cu")
		(net "SMB_RT_CPU0_P0_ROM_MUX_2D_SDA")
	)
	(segment
		(start 291.803328 -417.692586)
		(end 291.968428 -417.692586)
		(width 0.11684)
		(layer "In13.Cu")
		(net "SMB_RT_CPU0_P0_ROM_MUX_2D_SDA")
	)
	(segment
		(start 292.268402 -418.15766)
		(end 292.68547 -418.574728)
		(width 0.11684)
		(layer "In13.Cu")
		(net "SMB_RT_CPU0_P0_ROM_MUX_2D_SDA")
	)
	(segment
		(start 291.968428 -417.692586)
		(end 292.664642 -416.996372)
		(width 0.11684)
		(layer "In13.Cu")
		(net "SMB_RT_CPU0_P0_ROM_MUX_2D_SDA")
	)
	(segment
		(start 293.541704 -421.847772)
		(end 297.709082 -421.847772)
		(width 0.11684)
		(layer "In13.Cu")
		(net "SMB_RT_CPU0_P0_ROM_MUX_2D_SDA")
	)
	(segment
		(start 298.797726 -422.936416)
		(end 299.089318 -423.64025)
		(width 0.11684)
		(layer "In13.Cu")
		(net "SMB_RT_CPU0_P0_ROM_MUX_2D_SDA")
	)
	(segment
		(start 282.567634 -372.806468)
		(end 282.567634 -374.1801)
		(width 0.11684)
		(layer "In13.Cu")
		(net "SMB_RT_CPU0_P0_ROM_MUX_2D_SDA")
	)
	(segment
		(start 292.964616 -417.131246)
		(end 292.964616 -417.296346)
		(width 0.11684)
		(layer "In13.Cu")
		(net "SMB_RT_CPU0_P0_ROM_MUX_2D_SDA")
	)
	(via
		(at 300.827948 -424.244516)
		(size 0.508)
		(drill 0.254)
		(layers "F.Cu" "B.Cu")
		(net "SMB_RT_CPU0_P0_ROM_MUX_2D_SCL")
	)
	(via
		(at 257.175 -340.76132)
		(size 0.508)
		(drill 0.254)
		(layers "F.Cu" "B.Cu")
		(net "SMB_RT_CPU0_P0_ROM_MUX_2D_SCL")
	)
	(segment
		(start 300.263052 -424.809412)
		(end 300.131226 -424.809412)
		(width 0.10668)
		(layer "B.Cu")
		(net "SMB_RT_CPU0_P0_ROM_MUX_2D_SCL")
	)
	(segment
		(start 256.1717 -340.76132)
		(end 257.175 -340.76132)
		(width 0.10668)
		(layer "B.Cu")
		(net "SMB_RT_CPU0_P0_ROM_MUX_2D_SCL")
	)
	(segment
		(start 299.90161 -425.039028)
		(end 299.205396 -425.039028)
		(width 0.10668)
		(layer "B.Cu")
		(net "SMB_RT_CPU0_P0_ROM_MUX_2D_SCL")
	)
	(segment
		(start 300.827948 -424.244516)
		(end 300.263052 -424.809412)
		(width 0.10668)
		(layer "B.Cu")
		(net "SMB_RT_CPU0_P0_ROM_MUX_2D_SCL")
	)
	(segment
		(start 300.131226 -424.809412)
		(end 299.90161 -425.039028)
		(width 0.10668)
		(layer "B.Cu")
		(net "SMB_RT_CPU0_P0_ROM_MUX_2D_SCL")
	)
	(segment
		(start 292.9382 -405.209248)
		(end 290.887404 -407.260044)
		(width 0.11684)
		(layer "In13.Cu")
		(net "SMB_RT_CPU0_P0_ROM_MUX_2D_SCL")
	)
	(segment
		(start 285.05531 -380.661672)
		(end 285.05531 -388.76732)
		(width 0.11684)
		(layer "In13.Cu")
		(net "SMB_RT_CPU0_P0_ROM_MUX_2D_SCL")
	)
	(segment
		(start 293.315898 -398.788128)
		(end 293.315898 -399.329656)
		(width 0.11684)
		(layer "In13.Cu")
		(net "SMB_RT_CPU0_P0_ROM_MUX_2D_SCL")
	)
	(segment
		(start 257.175 -340.76132)
		(end 256.90068 -340.76132)
		(width 0.11684)
		(layer "In13.Cu")
		(net "SMB_RT_CPU0_P0_ROM_MUX_2D_SCL")
	)
	(segment
		(start 290.52647 -396.4178)
		(end 290.829492 -396.720822)
		(width 0.11684)
		(layer "In13.Cu")
		(net "SMB_RT_CPU0_P0_ROM_MUX_2D_SCL")
	)
	(segment
		(start 293.01948 -422.297606)
		(end 297.010074 -422.297606)
		(width 0.11684)
		(layer "In13.Cu")
		(net "SMB_RT_CPU0_P0_ROM_MUX_2D_SCL")
	)
	(segment
		(start 297.781218 -423.692574)
		(end 298.94403 -424.855386)
		(width 0.11684)
		(layer "In13.Cu")
		(net "SMB_RT_CPU0_P0_ROM_MUX_2D_SCL")
	)
	(segment
		(start 271.636236 -364.70082)
		(end 273.865594 -364.70082)
		(width 0.11684)
		(layer "In13.Cu")
		(net "SMB_RT_CPU0_P0_ROM_MUX_2D_SCL")
	)
	(segment
		(start 256.90068 -340.76132)
		(end 255.778 -341.884)
		(width 0.11684)
		(layer "In13.Cu")
		(net "SMB_RT_CPU0_P0_ROM_MUX_2D_SCL")
	)
	(segment
		(start 292.350698 -397.822928)
		(end 293.315898 -398.788128)
		(width 0.11684)
		(layer "In13.Cu")
		(net "SMB_RT_CPU0_P0_ROM_MUX_2D_SCL")
	)
	(segment
		(start 290.887404 -417.473638)
		(end 292.173152 -418.759386)
		(width 0.11684)
		(layer "In13.Cu")
		(net "SMB_RT_CPU0_P0_ROM_MUX_2D_SCL")
	)
	(segment
		(start 270.729202 -363.793786)
		(end 271.636236 -364.70082)
		(width 0.11684)
		(layer "In13.Cu")
		(net "SMB_RT_CPU0_P0_ROM_MUX_2D_SCL")
	)
	(segment
		(start 286.760158 -395.913864)
		(end 287.264094 -396.4178)
		(width 0.11684)
		(layer "In13.Cu")
		(net "SMB_RT_CPU0_P0_ROM_MUX_2D_SCL")
	)
	(segment
		(start 273.865594 -364.70082)
		(end 282.145994 -372.98122)
		(width 0.11684)
		(layer "In13.Cu")
		(net "SMB_RT_CPU0_P0_ROM_MUX_2D_SCL")
	)
	(segment
		(start 293.315898 -399.329656)
		(end 292.9382 -399.707354)
		(width 0.11684)
		(layer "In13.Cu")
		(net "SMB_RT_CPU0_P0_ROM_MUX_2D_SCL")
	)
	(segment
		(start 292.173152 -421.451278)
		(end 293.01948 -422.297606)
		(width 0.11684)
		(layer "In13.Cu")
		(net "SMB_RT_CPU0_P0_ROM_MUX_2D_SCL")
	)
	(segment
		(start 270.729202 -361.43438)
		(end 270.729202 -363.793786)
		(width 0.11684)
		(layer "In13.Cu")
		(net "SMB_RT_CPU0_P0_ROM_MUX_2D_SCL")
	)
	(segment
		(start 297.781218 -423.06875)
		(end 297.781218 -423.692574)
		(width 0.11684)
		(layer "In13.Cu")
		(net "SMB_RT_CPU0_P0_ROM_MUX_2D_SCL")
	)
	(segment
		(start 255.778 -346.483178)
		(end 270.729202 -361.43438)
		(width 0.11684)
		(layer "In13.Cu")
		(net "SMB_RT_CPU0_P0_ROM_MUX_2D_SCL")
	)
	(segment
		(start 290.829492 -396.720822)
		(end 290.829492 -397.532606)
		(width 0.11684)
		(layer "In13.Cu")
		(net "SMB_RT_CPU0_P0_ROM_MUX_2D_SCL")
	)
	(segment
		(start 255.778 -341.884)
		(end 255.778 -346.483178)
		(width 0.11684)
		(layer "In13.Cu")
		(net "SMB_RT_CPU0_P0_ROM_MUX_2D_SCL")
	)
	(segment
		(start 292.173152 -418.759386)
		(end 292.173152 -421.451278)
		(width 0.11684)
		(layer "In13.Cu")
		(net "SMB_RT_CPU0_P0_ROM_MUX_2D_SCL")
	)
	(segment
		(start 282.145994 -374.45188)
		(end 283.759402 -376.065288)
		(width 0.11684)
		(layer "In13.Cu")
		(net "SMB_RT_CPU0_P0_ROM_MUX_2D_SCL")
	)
	(segment
		(start 290.829492 -397.532606)
		(end 291.119814 -397.822928)
		(width 0.11684)
		(layer "In13.Cu")
		(net "SMB_RT_CPU0_P0_ROM_MUX_2D_SCL")
	)
	(segment
		(start 300.217078 -424.855386)
		(end 300.827948 -424.244516)
		(width 0.11684)
		(layer "In13.Cu")
		(net "SMB_RT_CPU0_P0_ROM_MUX_2D_SCL")
	)
	(segment
		(start 287.264094 -396.4178)
		(end 290.52647 -396.4178)
		(width 0.11684)
		(layer "In13.Cu")
		(net "SMB_RT_CPU0_P0_ROM_MUX_2D_SCL")
	)
	(segment
		(start 286.760158 -390.472168)
		(end 286.760158 -395.913864)
		(width 0.11684)
		(layer "In13.Cu")
		(net "SMB_RT_CPU0_P0_ROM_MUX_2D_SCL")
	)
	(segment
		(start 297.010074 -422.297606)
		(end 297.781218 -423.06875)
		(width 0.11684)
		(layer "In13.Cu")
		(net "SMB_RT_CPU0_P0_ROM_MUX_2D_SCL")
	)
	(segment
		(start 298.94403 -424.855386)
		(end 300.217078 -424.855386)
		(width 0.11684)
		(layer "In13.Cu")
		(net "SMB_RT_CPU0_P0_ROM_MUX_2D_SCL")
	)
	(segment
		(start 291.119814 -397.822928)
		(end 292.350698 -397.822928)
		(width 0.11684)
		(layer "In13.Cu")
		(net "SMB_RT_CPU0_P0_ROM_MUX_2D_SCL")
	)
	(segment
		(start 283.759402 -376.065288)
		(end 283.759402 -379.365764)
		(width 0.11684)
		(layer "In13.Cu")
		(net "SMB_RT_CPU0_P0_ROM_MUX_2D_SCL")
	)
	(segment
		(start 290.887404 -407.260044)
		(end 290.887404 -417.473638)
		(width 0.11684)
		(layer "In13.Cu")
		(net "SMB_RT_CPU0_P0_ROM_MUX_2D_SCL")
	)
	(segment
		(start 283.759402 -379.365764)
		(end 285.05531 -380.661672)
		(width 0.11684)
		(layer "In13.Cu")
		(net "SMB_RT_CPU0_P0_ROM_MUX_2D_SCL")
	)
	(segment
		(start 292.9382 -399.707354)
		(end 292.9382 -405.209248)
		(width 0.11684)
		(layer "In13.Cu")
		(net "SMB_RT_CPU0_P0_ROM_MUX_2D_SCL")
	)
	(segment
		(start 282.145994 -372.98122)
		(end 282.145994 -374.45188)
		(width 0.11684)
		(layer "In13.Cu")
		(net "SMB_RT_CPU0_P0_ROM_MUX_2D_SCL")
	)
	(segment
		(start 285.05531 -388.76732)
		(end 286.760158 -390.472168)
		(width 0.11684)
		(layer "In13.Cu")
		(net "SMB_RT_CPU0_P0_ROM_MUX_2D_SCL")
	)
	(via
		(at 300.367192 -425.360846)
		(size 0.6604)
		(drill 0.3302)
		(layers "F.Cu" "B.Cu")
		(net "SMB_RT_CPU0_P0_ROM_MUX_1D_SDA")
	)
	(segment
		(start 301.121572 -425.498768)
		(end 300.505114 -425.498768)
		(width 0.10668)
		(layer "B.Cu")
		(net "SMB_RT_CPU0_P0_ROM_MUX_1D_SDA")
	)
	(segment
		(start 301.121572 -425.498768)
		(end 301.121572 -425.130214)
		(width 0.10668)
		(layer "B.Cu")
		(net "SMB_RT_CPU0_P0_ROM_MUX_1D_SDA")
	)
	(segment
		(start 301.121572 -425.130214)
		(end 301.535338 -424.716448)
		(width 0.10668)
		(layer "B.Cu")
		(net "SMB_RT_CPU0_P0_ROM_MUX_1D_SDA")
	)
	(segment
		(start 300.189138 -425.5389)
		(end 300.367192 -425.360846)
		(width 0.10668)
		(layer "B.Cu")
		(net "SMB_RT_CPU0_P0_ROM_MUX_1D_SDA")
	)
	(segment
		(start 299.205396 -425.5389)
		(end 300.189138 -425.5389)
		(width 0.10668)
		(layer "B.Cu")
		(net "SMB_RT_CPU0_P0_ROM_MUX_1D_SDA")
	)
	(segment
		(start 300.505114 -425.498768)
		(end 300.367192 -425.360846)
		(width 0.10668)
		(layer "B.Cu")
		(net "SMB_RT_CPU0_P0_ROM_MUX_1D_SDA")
	)
	(via
		(at 300.367192 -426.630846)
		(size 0.6604)
		(drill 0.3302)
		(layers "F.Cu" "B.Cu")
		(net "SMB_RT_CPU0_P0_ROM_MUX_1D_SCL")
	)
	(segment
		(start 301.082202 -426.527214)
		(end 301.110904 -426.498512)
		(width 0.10668)
		(layer "B.Cu")
		(net "SMB_RT_CPU0_P0_ROM_MUX_1D_SCL")
	)
	(segment
		(start 299.699426 -426.039026)
		(end 300.291246 -426.630846)
		(width 0.10668)
		(layer "B.Cu")
		(net "SMB_RT_CPU0_P0_ROM_MUX_1D_SCL")
	)
	(segment
		(start 299.205396 -426.039026)
		(end 299.699426 -426.039026)
		(width 0.10668)
		(layer "B.Cu")
		(net "SMB_RT_CPU0_P0_ROM_MUX_1D_SCL")
	)
	(segment
		(start 301.082202 -427.401736)
		(end 301.082202 -426.527214)
		(width 0.10668)
		(layer "B.Cu")
		(net "SMB_RT_CPU0_P0_ROM_MUX_1D_SCL")
	)
	(segment
		(start 300.291246 -426.630846)
		(end 300.367192 -426.630846)
		(width 0.10668)
		(layer "B.Cu")
		(net "SMB_RT_CPU0_P0_ROM_MUX_1D_SCL")
	)
	(segment
		(start 301.110904 -426.498512)
		(end 300.499526 -426.498512)
		(width 0.10668)
		(layer "B.Cu")
		(net "SMB_RT_CPU0_P0_ROM_MUX_1D_SCL")
	)
	(segment
		(start 300.499526 -426.498512)
		(end 300.367192 -426.630846)
		(width 0.10668)
		(layer "B.Cu")
		(net "SMB_RT_CPU0_P0_ROM_MUX_1D_SCL")
	)
	(segment
		(start 323.48297 -102.558088)
		(end 323.69506 -102.558088)
		(width 0.10668)
		(layer "F.Cu")
		(net "SMB_INA230_8_3V3AUX_SDA_R1")
	)
	(segment
		(start 323.500496 -98.97618)
		(end 323.500496 -99.284536)
		(width 0.10668)
		(layer "F.Cu")
		(net "SMB_INA230_8_3V3AUX_SDA_R1")
	)
	(segment
		(start 323.204078 -102.279196)
		(end 323.48297 -102.558088)
		(width 0.10668)
		(layer "F.Cu")
		(net "SMB_INA230_8_3V3AUX_SDA_R1")
	)
	(segment
		(start 321.45605 -99.187)
		(end 321.45605 -98.806)
		(width 0.10668)
		(layer "F.Cu")
		(net "SMB_INA230_8_3V3AUX_SDA_R1")
	)
	(segment
		(start 323.204078 -99.883722)
		(end 323.204078 -100.217986)
		(width 0.10668)
		(layer "F.Cu")
		(net "SMB_INA230_8_3V3AUX_SDA_R1")
	)
	(segment
		(start 321.58305 -98.679)
		(end 323.203316 -98.679)
		(width 0.10668)
		(layer "F.Cu")
		(net "SMB_INA230_8_3V3AUX_SDA_R1")
	)
	(segment
		(start 323.500496 -99.284536)
		(end 323.500496 -99.587304)
		(width 0.10668)
		(layer "F.Cu")
		(net "SMB_INA230_8_3V3AUX_SDA_R1")
	)
	(segment
		(start 323.500496 -99.587304)
		(end 323.204078 -99.883722)
		(width 0.10668)
		(layer "F.Cu")
		(net "SMB_INA230_8_3V3AUX_SDA_R1")
	)
	(segment
		(start 321.45605 -98.806)
		(end 321.58305 -98.679)
		(width 0.10668)
		(layer "F.Cu")
		(net "SMB_INA230_8_3V3AUX_SDA_R1")
	)
	(segment
		(start 323.204078 -100.217986)
		(end 323.204078 -102.279196)
		(width 0.10668)
		(layer "F.Cu")
		(net "SMB_INA230_8_3V3AUX_SDA_R1")
	)
	(segment
		(start 323.203316 -98.679)
		(end 323.500496 -98.97618)
		(width 0.10668)
		(layer "F.Cu")
		(net "SMB_INA230_8_3V3AUX_SDA_R1")
	)
	(via
		(at 323.204078 -100.217986)
		(size 0.762)
		(drill 0.381)
		(layers "F.Cu" "B.Cu")
		(net "SMB_INA230_8_3V3AUX_SDA_R1")
	)
	(segment
		(start 319.024 -99.568)
		(end 319.151 -99.695)
		(width 0.10668)
		(layer "F.Cu")
		(net "SMB_INA230_8_3V3AUX_SDA_R")
	)
	(segment
		(start 307.79974 -105.33126)
		(end 313.563 -99.568)
		(width 0.10668)
		(layer "F.Cu")
		(net "SMB_INA230_8_3V3AUX_SDA_R")
	)
	(segment
		(start 306.184554 -106.79557)
		(end 305.191668 -105.802684)
		(width 0.10668)
		(layer "F.Cu")
		(net "SMB_INA230_8_3V3AUX_SDA_R")
	)
	(segment
		(start 306.770278 -106.209846)
		(end 305.777392 -105.21696)
		(width 0.10668)
		(layer "F.Cu")
		(net "SMB_INA230_8_3V3AUX_SDA_R")
	)
	(segment
		(start 300.736 -108.1659)
		(end 304.9651 -108.1659)
		(width 0.10668)
		(layer "F.Cu")
		(net "SMB_INA230_8_3V3AUX_SDA_R")
	)
	(segment
		(start 304.9651 -108.1659)
		(end 305.59883 -107.53217)
		(width 0.10668)
		(layer "F.Cu")
		(net "SMB_INA230_8_3V3AUX_SDA_R")
	)
	(segment
		(start 305.59883 -107.53217)
		(end 305.59883 -107.381294)
		(width 0.10668)
		(layer "F.Cu")
		(net "SMB_INA230_8_3V3AUX_SDA_R")
	)
	(segment
		(start 319.151 -99.695)
		(end 319.659 -99.695)
		(width 0.10668)
		(layer "F.Cu")
		(net "SMB_INA230_8_3V3AUX_SDA_R")
	)
	(segment
		(start 322.700396 -99.284536)
		(end 322.289932 -99.695)
		(width 0.10668)
		(layer "F.Cu")
		(net "SMB_INA230_8_3V3AUX_SDA_R")
	)
	(segment
		(start 307.356002 -105.624122)
		(end 306.363116 -104.631236)
		(width 0.10668)
		(layer "F.Cu")
		(net "SMB_INA230_8_3V3AUX_SDA_R")
	)
	(segment
		(start 307.356002 -105.774998)
		(end 307.356002 -105.624122)
		(width 0.10668)
		(layer "F.Cu")
		(net "SMB_INA230_8_3V3AUX_SDA_R")
	)
	(segment
		(start 305.919378 -104.924098)
		(end 306.070254 -104.924098)
		(width 0.10668)
		(layer "F.Cu")
		(net "SMB_INA230_8_3V3AUX_SDA_R")
	)
	(segment
		(start 306.770278 -106.360722)
		(end 306.770278 -106.209846)
		(width 0.10668)
		(layer "F.Cu")
		(net "SMB_INA230_8_3V3AUX_SDA_R")
	)
	(segment
		(start 304.898806 -106.095546)
		(end 305.891692 -107.088432)
		(width 0.10668)
		(layer "F.Cu")
		(net "SMB_INA230_8_3V3AUX_SDA_R")
	)
	(segment
		(start 304.605944 -106.237532)
		(end 304.74793 -106.095546)
		(width 0.10668)
		(layer "F.Cu")
		(net "SMB_INA230_8_3V3AUX_SDA_R")
	)
	(segment
		(start 305.191668 -105.802684)
		(end 305.191668 -105.651808)
		(width 0.10668)
		(layer "F.Cu")
		(net "SMB_INA230_8_3V3AUX_SDA_R")
	)
	(segment
		(start 304.74793 -106.095546)
		(end 304.898806 -106.095546)
		(width 0.10668)
		(layer "F.Cu")
		(net "SMB_INA230_8_3V3AUX_SDA_R")
	)
	(segment
		(start 313.563 -99.568)
		(end 319.024 -99.568)
		(width 0.10668)
		(layer "F.Cu")
		(net "SMB_INA230_8_3V3AUX_SDA_R")
	)
	(segment
		(start 305.191668 -105.651808)
		(end 305.333654 -105.509822)
		(width 0.10668)
		(layer "F.Cu")
		(net "SMB_INA230_8_3V3AUX_SDA_R")
	)
	(segment
		(start 306.184554 -106.946446)
		(end 306.184554 -106.79557)
		(width 0.10668)
		(layer "F.Cu")
		(net "SMB_INA230_8_3V3AUX_SDA_R")
	)
	(segment
		(start 307.06314 -105.916984)
		(end 307.214016 -105.916984)
		(width 0.10668)
		(layer "F.Cu")
		(net "SMB_INA230_8_3V3AUX_SDA_R")
	)
	(segment
		(start 305.777392 -105.066084)
		(end 305.919378 -104.924098)
		(width 0.10668)
		(layer "F.Cu")
		(net "SMB_INA230_8_3V3AUX_SDA_R")
	)
	(segment
		(start 305.777392 -105.21696)
		(end 305.777392 -105.066084)
		(width 0.10668)
		(layer "F.Cu")
		(net "SMB_INA230_8_3V3AUX_SDA_R")
	)
	(segment
		(start 305.59883 -107.381294)
		(end 304.605944 -106.388408)
		(width 0.10668)
		(layer "F.Cu")
		(net "SMB_INA230_8_3V3AUX_SDA_R")
	)
	(segment
		(start 306.363116 -104.631236)
		(end 306.363116 -104.48036)
		(width 0.10668)
		(layer "F.Cu")
		(net "SMB_INA230_8_3V3AUX_SDA_R")
	)
	(segment
		(start 305.891692 -107.088432)
		(end 306.042568 -107.088432)
		(width 0.10668)
		(layer "F.Cu")
		(net "SMB_INA230_8_3V3AUX_SDA_R")
	)
	(segment
		(start 322.289932 -99.695)
		(end 319.659 -99.695)
		(width 0.10668)
		(layer "F.Cu")
		(net "SMB_INA230_8_3V3AUX_SDA_R")
	)
	(segment
		(start 306.505102 -104.338374)
		(end 306.655978 -104.338374)
		(width 0.10668)
		(layer "F.Cu")
		(net "SMB_INA230_8_3V3AUX_SDA_R")
	)
	(segment
		(start 307.214016 -105.916984)
		(end 307.356002 -105.774998)
		(width 0.10668)
		(layer "F.Cu")
		(net "SMB_INA230_8_3V3AUX_SDA_R")
	)
	(segment
		(start 306.628292 -106.502708)
		(end 306.770278 -106.360722)
		(width 0.10668)
		(layer "F.Cu")
		(net "SMB_INA230_8_3V3AUX_SDA_R")
	)
	(segment
		(start 307.648864 -105.33126)
		(end 307.79974 -105.33126)
		(width 0.10668)
		(layer "F.Cu")
		(net "SMB_INA230_8_3V3AUX_SDA_R")
	)
	(segment
		(start 305.48453 -105.509822)
		(end 306.477416 -106.502708)
		(width 0.10668)
		(layer "F.Cu")
		(net "SMB_INA230_8_3V3AUX_SDA_R")
	)
	(segment
		(start 304.605944 -106.388408)
		(end 304.605944 -106.237532)
		(width 0.10668)
		(layer "F.Cu")
		(net "SMB_INA230_8_3V3AUX_SDA_R")
	)
	(segment
		(start 306.070254 -104.924098)
		(end 307.06314 -105.916984)
		(width 0.10668)
		(layer "F.Cu")
		(net "SMB_INA230_8_3V3AUX_SDA_R")
	)
	(segment
		(start 306.363116 -104.48036)
		(end 306.505102 -104.338374)
		(width 0.10668)
		(layer "F.Cu")
		(net "SMB_INA230_8_3V3AUX_SDA_R")
	)
	(segment
		(start 305.333654 -105.509822)
		(end 305.48453 -105.509822)
		(width 0.10668)
		(layer "F.Cu")
		(net "SMB_INA230_8_3V3AUX_SDA_R")
	)
	(segment
		(start 306.042568 -107.088432)
		(end 306.184554 -106.946446)
		(width 0.10668)
		(layer "F.Cu")
		(net "SMB_INA230_8_3V3AUX_SDA_R")
	)
	(segment
		(start 306.655978 -104.338374)
		(end 307.648864 -105.33126)
		(width 0.10668)
		(layer "F.Cu")
		(net "SMB_INA230_8_3V3AUX_SDA_R")
	)
	(segment
		(start 306.477416 -106.502708)
		(end 306.628292 -106.502708)
		(width 0.10668)
		(layer "F.Cu")
		(net "SMB_INA230_8_3V3AUX_SDA_R")
	)
	(via
		(at 319.659 -99.695)
		(size 0.762)
		(drill 0.381)
		(layers "F.Cu" "B.Cu")
		(net "SMB_INA230_8_3V3AUX_SDA_R")
	)
	(segment
		(start 323.870828 -100.1014)
		(end 323.99859 -99.973638)
		(width 0.10668)
		(layer "F.Cu")
		(net "SMB_INA230_8_3V3AUX_SCL_R1")
	)
	(segment
		(start 323.870828 -100.969064)
		(end 323.870828 -100.1014)
		(width 0.10668)
		(layer "F.Cu")
		(net "SMB_INA230_8_3V3AUX_SCL_R1")
	)
	(segment
		(start 324.345046 -101.908102)
		(end 324.345046 -101.443282)
		(width 0.10668)
		(layer "F.Cu")
		(net "SMB_INA230_8_3V3AUX_SCL_R1")
	)
	(segment
		(start 323.99859 -99.973638)
		(end 323.99859 -99.738942)
		(width 0.10668)
		(layer "F.Cu")
		(net "SMB_INA230_8_3V3AUX_SCL_R1")
	)
	(segment
		(start 324.345046 -101.443282)
		(end 323.870828 -100.969064)
		(width 0.10668)
		(layer "F.Cu")
		(net "SMB_INA230_8_3V3AUX_SCL_R1")
	)
	(segment
		(start 323.99859 -99.738942)
		(end 324.452996 -99.284536)
		(width 0.10668)
		(layer "F.Cu")
		(net "SMB_INA230_8_3V3AUX_SCL_R1")
	)
	(via
		(at 323.99859 -99.973638)
		(size 0.508)
		(drill 0.254)
		(layers "F.Cu" "B.Cu")
		(net "SMB_INA230_8_3V3AUX_SCL_R1")
	)
	(segment
		(start 318.953896 -98.552)
		(end 319.715896 -97.79)
		(width 0.10668)
		(layer "F.Cu")
		(net "SMB_INA230_8_3V3AUX_SCL_R")
	)
	(segment
		(start 324.612 -97.79)
		(end 323.596 -97.79)
		(width 0.10668)
		(layer "F.Cu")
		(net "SMB_INA230_8_3V3AUX_SCL_R")
	)
	(segment
		(start 319.715896 -97.79)
		(end 323.596 -97.79)
		(width 0.10668)
		(layer "F.Cu")
		(net "SMB_INA230_8_3V3AUX_SCL_R")
	)
	(segment
		(start 297.688 -101.904038)
		(end 301.040038 -98.552)
		(width 0.10668)
		(layer "F.Cu")
		(net "SMB_INA230_8_3V3AUX_SCL_R")
	)
	(segment
		(start 301.040038 -98.552)
		(end 318.953896 -98.552)
		(width 0.10668)
		(layer "F.Cu")
		(net "SMB_INA230_8_3V3AUX_SCL_R")
	)
	(segment
		(start 297.688 -108.56595)
		(end 297.688 -101.904038)
		(width 0.10668)
		(layer "F.Cu")
		(net "SMB_INA230_8_3V3AUX_SCL_R")
	)
	(segment
		(start 325.253096 -99.284536)
		(end 325.253096 -98.431096)
		(width 0.10668)
		(layer "F.Cu")
		(net "SMB_INA230_8_3V3AUX_SCL_R")
	)
	(segment
		(start 325.253096 -98.431096)
		(end 324.612 -97.79)
		(width 0.10668)
		(layer "F.Cu")
		(net "SMB_INA230_8_3V3AUX_SCL_R")
	)
	(via
		(at 323.596 -97.79)
		(size 0.762)
		(drill 0.381)
		(layers "F.Cu" "B.Cu")
		(net "SMB_INA230_8_3V3AUX_SCL_R")
	)
	(segment
		(start 21.338286 -36.400486)
		(end 21.338286 -37.225478)
		(width 0.10668)
		(layer "F.Cu")
		(net "SMB_INA230_7_3V3AUX_SDA_R1")
	)
	(segment
		(start 21.634704 -35.8013)
		(end 21.634704 -36.104068)
		(width 0.10668)
		(layer "F.Cu")
		(net "SMB_INA230_7_3V3AUX_SDA_R1")
	)
	(segment
		(start 21.617178 -39.074852)
		(end 21.829268 -39.074852)
		(width 0.10668)
		(layer "F.Cu")
		(net "SMB_INA230_7_3V3AUX_SDA_R1")
	)
	(segment
		(start 21.338286 -37.225478)
		(end 21.338286 -38.79596)
		(width 0.10668)
		(layer "F.Cu")
		(net "SMB_INA230_7_3V3AUX_SDA_R1")
	)
	(segment
		(start 21.338286 -38.79596)
		(end 21.617178 -39.074852)
		(width 0.10668)
		(layer "F.Cu")
		(net "SMB_INA230_7_3V3AUX_SDA_R1")
	)
	(segment
		(start 21.634704 -36.104068)
		(end 21.338286 -36.400486)
		(width 0.10668)
		(layer "F.Cu")
		(net "SMB_INA230_7_3V3AUX_SDA_R1")
	)
	(via
		(at 21.338286 -37.225478)
		(size 0.762)
		(drill 0.381)
		(layers "F.Cu" "B.Cu")
		(net "SMB_INA230_7_3V3AUX_SDA_R1")
	)
	(segment
		(start 146.971258 -50.160174)
		(end 147.828508 -50.160174)
		(width 0.10668)
		(layer "F.Cu")
		(net "SMB_INA230_7_3V3AUX_SDA_R")
	)
	(segment
		(start 20.834604 -35.8013)
		(end 20.834604 -36.446714)
		(width 0.10668)
		(layer "F.Cu")
		(net "SMB_INA230_7_3V3AUX_SDA_R")
	)
	(via
		(at 20.834604 -36.446714)
		(size 0.508)
		(drill 0.254)
		(layers "F.Cu" "B.Cu")
		(net "SMB_INA230_7_3V3AUX_SDA_R")
	)
	(via
		(at 147.828508 -50.160174)
		(size 0.508)
		(drill 0.254)
		(layers "F.Cu" "B.Cu")
		(net "SMB_INA230_7_3V3AUX_SDA_R")
	)
	(segment
		(start 57.912508 -29.024326)
		(end 59.585352 -27.351482)
		(width 0.11684)
		(layer "In6.Cu")
		(net "SMB_INA230_7_3V3AUX_SDA_R")
	)
	(segment
		(start 59.585352 -27.351482)
		(end 60.199778 -27.351482)
		(width 0.11684)
		(layer "In6.Cu")
		(net "SMB_INA230_7_3V3AUX_SDA_R")
	)
	(segment
		(start 57.124854 -23.864824)
		(end 53.237892 -27.751786)
		(width 0.11684)
		(layer "In6.Cu")
		(net "SMB_INA230_7_3V3AUX_SDA_R")
	)
	(segment
		(start 48.974756 -38.59022)
		(end 42.755058 -38.59022)
		(width 0.11684)
		(layer "In6.Cu")
		(net "SMB_INA230_7_3V3AUX_SDA_R")
	)
	(segment
		(start 58.058304 -35.898836)
		(end 57.912508 -35.75304)
		(width 0.11684)
		(layer "In6.Cu")
		(net "SMB_INA230_7_3V3AUX_SDA_R")
	)
	(segment
		(start 36.463478 -44.8818)
		(end 24.909526 -44.8818)
		(width 0.11684)
		(layer "In6.Cu")
		(net "SMB_INA230_7_3V3AUX_SDA_R")
	)
	(segment
		(start 66.364358 -37.906706)
		(end 66.001392 -37.54374)
		(width 0.11684)
		(layer "In6.Cu")
		(net "SMB_INA230_7_3V3AUX_SDA_R")
	)
	(segment
		(start 146.29638 -50.47107)
		(end 143.350234 -47.524924)
		(width 0.11684)
		(layer "In6.Cu")
		(net "SMB_INA230_7_3V3AUX_SDA_R")
	)
	(segment
		(start 60.536836 -23.864824)
		(end 57.124854 -23.864824)
		(width 0.11684)
		(layer "In6.Cu")
		(net "SMB_INA230_7_3V3AUX_SDA_R")
	)
	(segment
		(start 116.651024 -48.061626)
		(end 106.405426 -48.061626)
		(width 0.11684)
		(layer "In6.Cu")
		(net "SMB_INA230_7_3V3AUX_SDA_R")
	)
	(segment
		(start 21.422868 -37.034978)
		(end 20.834604 -36.446714)
		(width 0.11684)
		(layer "In6.Cu")
		(net "SMB_INA230_7_3V3AUX_SDA_R")
	)
	(segment
		(start 60.978542 -24.30653)
		(end 60.536836 -23.864824)
		(width 0.11684)
		(layer "In6.Cu")
		(net "SMB_INA230_7_3V3AUX_SDA_R")
	)
	(segment
		(start 74.114914 -39.83863)
		(end 71.700644 -37.42436)
		(width 0.11684)
		(layer "In6.Cu")
		(net "SMB_INA230_7_3V3AUX_SDA_R")
	)
	(segment
		(start 24.909526 -44.8818)
		(end 21.422868 -41.395142)
		(width 0.11684)
		(layer "In6.Cu")
		(net "SMB_INA230_7_3V3AUX_SDA_R")
	)
	(segment
		(start 62.49289 -37.54374)
		(end 61.961014 -37.011864)
		(width 0.11684)
		(layer "In6.Cu")
		(net "SMB_INA230_7_3V3AUX_SDA_R")
	)
	(segment
		(start 71.700644 -37.42436)
		(end 67.889374 -37.42436)
		(width 0.11684)
		(layer "In6.Cu")
		(net "SMB_INA230_7_3V3AUX_SDA_R")
	)
	(segment
		(start 143.350234 -47.524924)
		(end 129.98958 -47.524924)
		(width 0.11684)
		(layer "In6.Cu")
		(net "SMB_INA230_7_3V3AUX_SDA_R")
	)
	(segment
		(start 61.961014 -37.011864)
		(end 60.564268 -37.011864)
		(width 0.11684)
		(layer "In6.Cu")
		(net "SMB_INA230_7_3V3AUX_SDA_R")
	)
	(segment
		(start 91.073732 -43.490134)
		(end 90.424254 -44.139612)
		(width 0.11684)
		(layer "In6.Cu")
		(net "SMB_INA230_7_3V3AUX_SDA_R")
	)
	(segment
		(start 123.742704 -47.326804)
		(end 117.385846 -47.326804)
		(width 0.11684)
		(layer "In6.Cu")
		(net "SMB_INA230_7_3V3AUX_SDA_R")
	)
	(segment
		(start 49.795176 -37.7698)
		(end 48.974756 -38.59022)
		(width 0.11684)
		(layer "In6.Cu")
		(net "SMB_INA230_7_3V3AUX_SDA_R")
	)
	(segment
		(start 147.828508 -50.160174)
		(end 147.517612 -50.47107)
		(width 0.11684)
		(layer "In6.Cu")
		(net "SMB_INA230_7_3V3AUX_SDA_R")
	)
	(segment
		(start 100.621846 -43.490134)
		(end 91.073732 -43.490134)
		(width 0.11684)
		(layer "In6.Cu")
		(net "SMB_INA230_7_3V3AUX_SDA_R")
	)
	(segment
		(start 66.001392 -37.54374)
		(end 62.49289 -37.54374)
		(width 0.11684)
		(layer "In6.Cu")
		(net "SMB_INA230_7_3V3AUX_SDA_R")
	)
	(segment
		(start 60.564268 -37.011864)
		(end 59.45124 -35.898836)
		(width 0.11684)
		(layer "In6.Cu")
		(net "SMB_INA230_7_3V3AUX_SDA_R")
	)
	(segment
		(start 60.199778 -27.351482)
		(end 60.978542 -26.572718)
		(width 0.11684)
		(layer "In6.Cu")
		(net "SMB_INA230_7_3V3AUX_SDA_R")
	)
	(segment
		(start 42.755058 -38.59022)
		(end 36.463478 -44.8818)
		(width 0.11684)
		(layer "In6.Cu")
		(net "SMB_INA230_7_3V3AUX_SDA_R")
	)
	(segment
		(start 67.889374 -37.42436)
		(end 67.407028 -37.906706)
		(width 0.11684)
		(layer "In6.Cu")
		(net "SMB_INA230_7_3V3AUX_SDA_R")
	)
	(segment
		(start 102.691184 -44.347384)
		(end 100.621846 -43.490134)
		(width 0.11684)
		(layer "In6.Cu")
		(net "SMB_INA230_7_3V3AUX_SDA_R")
	)
	(segment
		(start 53.237892 -27.751786)
		(end 53.237892 -28.54198)
		(width 0.11684)
		(layer "In6.Cu")
		(net "SMB_INA230_7_3V3AUX_SDA_R")
	)
	(segment
		(start 53.237892 -28.54198)
		(end 49.795176 -31.984696)
		(width 0.11684)
		(layer "In6.Cu")
		(net "SMB_INA230_7_3V3AUX_SDA_R")
	)
	(segment
		(start 129.23901 -48.275494)
		(end 126.52375 -48.275494)
		(width 0.11684)
		(layer "In6.Cu")
		(net "SMB_INA230_7_3V3AUX_SDA_R")
	)
	(segment
		(start 129.98958 -47.524924)
		(end 129.23901 -48.275494)
		(width 0.11684)
		(layer "In6.Cu")
		(net "SMB_INA230_7_3V3AUX_SDA_R")
	)
	(segment
		(start 67.407028 -37.906706)
		(end 66.364358 -37.906706)
		(width 0.11684)
		(layer "In6.Cu")
		(net "SMB_INA230_7_3V3AUX_SDA_R")
	)
	(segment
		(start 125.047502 -48.631602)
		(end 123.742704 -47.326804)
		(width 0.11684)
		(layer "In6.Cu")
		(net "SMB_INA230_7_3V3AUX_SDA_R")
	)
	(segment
		(start 117.385846 -47.326804)
		(end 116.651024 -48.061626)
		(width 0.11684)
		(layer "In6.Cu")
		(net "SMB_INA230_7_3V3AUX_SDA_R")
	)
	(segment
		(start 77.17663 -39.83863)
		(end 74.114914 -39.83863)
		(width 0.11684)
		(layer "In6.Cu")
		(net "SMB_INA230_7_3V3AUX_SDA_R")
	)
	(segment
		(start 59.45124 -35.898836)
		(end 58.058304 -35.898836)
		(width 0.11684)
		(layer "In6.Cu")
		(net "SMB_INA230_7_3V3AUX_SDA_R")
	)
	(segment
		(start 147.517612 -50.47107)
		(end 146.29638 -50.47107)
		(width 0.11684)
		(layer "In6.Cu")
		(net "SMB_INA230_7_3V3AUX_SDA_R")
	)
	(segment
		(start 81.477612 -44.139612)
		(end 77.17663 -39.83863)
		(width 0.11684)
		(layer "In6.Cu")
		(net "SMB_INA230_7_3V3AUX_SDA_R")
	)
	(segment
		(start 106.405426 -48.061626)
		(end 102.691184 -44.347384)
		(width 0.11684)
		(layer "In6.Cu")
		(net "SMB_INA230_7_3V3AUX_SDA_R")
	)
	(segment
		(start 21.422868 -41.395142)
		(end 21.422868 -37.034978)
		(width 0.11684)
		(layer "In6.Cu")
		(net "SMB_INA230_7_3V3AUX_SDA_R")
	)
	(segment
		(start 126.52375 -48.275494)
		(end 126.167642 -48.631602)
		(width 0.11684)
		(layer "In6.Cu")
		(net "SMB_INA230_7_3V3AUX_SDA_R")
	)
	(segment
		(start 60.978542 -26.572718)
		(end 60.978542 -24.30653)
		(width 0.11684)
		(layer "In6.Cu")
		(net "SMB_INA230_7_3V3AUX_SDA_R")
	)
	(segment
		(start 49.795176 -31.984696)
		(end 49.795176 -37.7698)
		(width 0.11684)
		(layer "In6.Cu")
		(net "SMB_INA230_7_3V3AUX_SDA_R")
	)
	(segment
		(start 57.912508 -35.75304)
		(end 57.912508 -29.024326)
		(width 0.11684)
		(layer "In6.Cu")
		(net "SMB_INA230_7_3V3AUX_SDA_R")
	)
	(segment
		(start 126.167642 -48.631602)
		(end 125.047502 -48.631602)
		(width 0.11684)
		(layer "In6.Cu")
		(net "SMB_INA230_7_3V3AUX_SDA_R")
	)
	(segment
		(start 90.424254 -44.139612)
		(end 81.477612 -44.139612)
		(width 0.11684)
		(layer "In6.Cu")
		(net "SMB_INA230_7_3V3AUX_SDA_R")
	)
	(segment
		(start 22.479254 -37.960046)
		(end 22.005036 -37.485828)
		(width 0.10668)
		(layer "F.Cu")
		(net "SMB_INA230_7_3V3AUX_SCL_R1")
	)
	(segment
		(start 22.479254 -38.424866)
		(end 22.479254 -37.960046)
		(width 0.10668)
		(layer "F.Cu")
		(net "SMB_INA230_7_3V3AUX_SCL_R1")
	)
	(segment
		(start 22.132798 -36.490402)
		(end 22.132798 -36.255706)
		(width 0.10668)
		(layer "F.Cu")
		(net "SMB_INA230_7_3V3AUX_SCL_R1")
	)
	(segment
		(start 18.841466 -38.910514)
		(end 18.231612 -38.910514)
		(width 0.10668)
		(layer "F.Cu")
		(net "SMB_INA230_7_3V3AUX_SCL_R1")
	)
	(segment
		(start 22.005036 -36.618164)
		(end 22.132798 -36.490402)
		(width 0.10668)
		(layer "F.Cu")
		(net "SMB_INA230_7_3V3AUX_SCL_R1")
	)
	(segment
		(start 22.132798 -36.255706)
		(end 22.587204 -35.8013)
		(width 0.10668)
		(layer "F.Cu")
		(net "SMB_INA230_7_3V3AUX_SCL_R1")
	)
	(segment
		(start 18.231612 -38.910514)
		(end 18.23085 -38.911276)
		(width 0.10668)
		(layer "F.Cu")
		(net "SMB_INA230_7_3V3AUX_SCL_R1")
	)
	(segment
		(start 22.005036 -37.485828)
		(end 22.005036 -36.618164)
		(width 0.10668)
		(layer "F.Cu")
		(net "SMB_INA230_7_3V3AUX_SCL_R1")
	)
	(via
		(at 22.132798 -36.490402)
		(size 0.508)
		(drill 0.254)
		(layers "F.Cu" "B.Cu")
		(net "SMB_INA230_7_3V3AUX_SCL_R1")
	)
	(via
		(at 18.23085 -38.911276)
		(size 0.508)
		(drill 0.254)
		(layers "F.Cu" "B.Cu")
		(net "SMB_INA230_7_3V3AUX_SCL_R1")
	)
	(segment
		(start 22.132798 -36.490402)
		(end 22.005036 -36.618164)
		(width 0.10668)
		(layer "B.Cu")
		(net "SMB_INA230_7_3V3AUX_SCL_R1")
	)
	(segment
		(start 22.005036 -36.618164)
		(end 22.005036 -37.54628)
		(width 0.10668)
		(layer "B.Cu")
		(net "SMB_INA230_7_3V3AUX_SCL_R1")
	)
	(segment
		(start 22.005036 -37.54628)
		(end 20.64004 -38.911276)
		(width 0.10668)
		(layer "B.Cu")
		(net "SMB_INA230_7_3V3AUX_SCL_R1")
	)
	(segment
		(start 20.64004 -38.911276)
		(end 18.23085 -38.911276)
		(width 0.10668)
		(layer "B.Cu")
		(net "SMB_INA230_7_3V3AUX_SCL_R1")
	)
	(segment
		(start 147.69846 -49.153064)
		(end 147.859496 -49.3141)
		(width 0.10668)
		(layer "F.Cu")
		(net "SMB_INA230_7_3V3AUX_SCL_R")
	)
	(segment
		(start 23.387304 -35.8013)
		(end 23.418038 -35.832034)
		(width 0.10668)
		(layer "F.Cu")
		(net "SMB_INA230_7_3V3AUX_SCL_R")
	)
	(segment
		(start 146.967448 -49.153064)
		(end 147.69846 -49.153064)
		(width 0.10668)
		(layer "F.Cu")
		(net "SMB_INA230_7_3V3AUX_SCL_R")
	)
	(segment
		(start 23.418038 -35.832034)
		(end 23.418038 -36.538662)
		(width 0.10668)
		(layer "F.Cu")
		(net "SMB_INA230_7_3V3AUX_SCL_R")
	)
	(via
		(at 23.418038 -36.538662)
		(size 0.508)
		(drill 0.254)
		(layers "F.Cu" "B.Cu")
		(net "SMB_INA230_7_3V3AUX_SCL_R")
	)
	(via
		(at 147.859496 -49.3141)
		(size 0.508)
		(drill 0.254)
		(layers "F.Cu" "B.Cu")
		(net "SMB_INA230_7_3V3AUX_SCL_R")
	)
	(segment
		(start 56.942482 -23.443184)
		(end 52.810918 -27.574748)
		(width 0.11684)
		(layer "In6.Cu")
		(net "SMB_INA230_7_3V3AUX_SCL_R")
	)
	(segment
		(start 21.849842 -38.106858)
		(end 23.418038 -36.538662)
		(width 0.11684)
		(layer "In6.Cu")
		(net "SMB_INA230_7_3V3AUX_SCL_R")
	)
	(segment
		(start 147.859496 -49.3141)
		(end 147.69846 -49.153064)
		(width 0.11684)
		(layer "In6.Cu")
		(net "SMB_INA230_7_3V3AUX_SCL_R")
	)
	(segment
		(start 106.580178 -47.639986)
		(end 102.777544 -43.837352)
		(width 0.11684)
		(layer "In6.Cu")
		(net "SMB_INA230_7_3V3AUX_SCL_R")
	)
	(segment
		(start 60.192412 -35.31235)
		(end 58.466482 -35.31235)
		(width 0.11684)
		(layer "In6.Cu")
		(net "SMB_INA230_7_3V3AUX_SCL_R")
	)
	(segment
		(start 58.466482 -35.31235)
		(end 58.339482 -35.18535)
		(width 0.11684)
		(layer "In6.Cu")
		(net "SMB_INA230_7_3V3AUX_SCL_R")
	)
	(segment
		(start 127.577342 -47.665894)
		(end 124.84227 -47.665894)
		(width 0.11684)
		(layer "In6.Cu")
		(net "SMB_INA230_7_3V3AUX_SCL_R")
	)
	(segment
		(start 52.810918 -27.574748)
		(end 52.810918 -28.364942)
		(width 0.11684)
		(layer "In6.Cu")
		(net "SMB_INA230_7_3V3AUX_SCL_R")
	)
	(segment
		(start 61.400182 -26.74747)
		(end 61.400182 -24.131778)
		(width 0.11684)
		(layer "In6.Cu")
		(net "SMB_INA230_7_3V3AUX_SCL_R")
	)
	(segment
		(start 49.368202 -31.807658)
		(end 49.368202 -37.592762)
		(width 0.11684)
		(layer "In6.Cu")
		(net "SMB_INA230_7_3V3AUX_SCL_R")
	)
	(segment
		(start 60.37453 -27.773122)
		(end 61.400182 -26.74747)
		(width 0.11684)
		(layer "In6.Cu")
		(net "SMB_INA230_7_3V3AUX_SCL_R")
	)
	(segment
		(start 76.475082 -38.54069)
		(end 73.413366 -38.54069)
		(width 0.11684)
		(layer "In6.Cu")
		(net "SMB_INA230_7_3V3AUX_SCL_R")
	)
	(segment
		(start 117.211094 -46.905164)
		(end 116.476272 -47.639986)
		(width 0.11684)
		(layer "In6.Cu")
		(net "SMB_INA230_7_3V3AUX_SCL_R")
	)
	(segment
		(start 124.08154 -46.905164)
		(end 117.211094 -46.905164)
		(width 0.11684)
		(layer "In6.Cu")
		(net "SMB_INA230_7_3V3AUX_SCL_R")
	)
	(segment
		(start 61.400182 -24.131778)
		(end 60.711588 -23.443184)
		(width 0.11684)
		(layer "In6.Cu")
		(net "SMB_INA230_7_3V3AUX_SCL_R")
	)
	(segment
		(start 60.711588 -23.443184)
		(end 56.942482 -23.443184)
		(width 0.11684)
		(layer "In6.Cu")
		(net "SMB_INA230_7_3V3AUX_SCL_R")
	)
	(segment
		(start 73.413366 -38.54069)
		(end 71.525892 -36.653216)
		(width 0.11684)
		(layer "In6.Cu")
		(net "SMB_INA230_7_3V3AUX_SCL_R")
	)
	(segment
		(start 124.84227 -47.665894)
		(end 124.08154 -46.905164)
		(width 0.11684)
		(layer "In6.Cu")
		(net "SMB_INA230_7_3V3AUX_SCL_R")
	)
	(segment
		(start 63.42761 -37.1221)
		(end 61.383672 -35.078162)
		(width 0.11684)
		(layer "In6.Cu")
		(net "SMB_INA230_7_3V3AUX_SCL_R")
	)
	(segment
		(start 52.810918 -28.364942)
		(end 49.368202 -31.807658)
		(width 0.11684)
		(layer "In6.Cu")
		(net "SMB_INA230_7_3V3AUX_SCL_R")
	)
	(segment
		(start 21.849842 -41.218104)
		(end 21.849842 -38.106858)
		(width 0.11684)
		(layer "In6.Cu")
		(net "SMB_INA230_7_3V3AUX_SCL_R")
	)
	(segment
		(start 116.476272 -47.639986)
		(end 106.580178 -47.639986)
		(width 0.11684)
		(layer "In6.Cu")
		(net "SMB_INA230_7_3V3AUX_SCL_R")
	)
	(segment
		(start 58.339482 -29.193744)
		(end 59.760104 -27.773122)
		(width 0.11684)
		(layer "In6.Cu")
		(net "SMB_INA230_7_3V3AUX_SCL_R")
	)
	(segment
		(start 147.69846 -49.153064)
		(end 145.574766 -49.153064)
		(width 0.11684)
		(layer "In6.Cu")
		(net "SMB_INA230_7_3V3AUX_SCL_R")
	)
	(segment
		(start 129.064258 -47.853854)
		(end 127.765302 -47.853854)
		(width 0.11684)
		(layer "In6.Cu")
		(net "SMB_INA230_7_3V3AUX_SCL_R")
	)
	(segment
		(start 25.086564 -44.454826)
		(end 21.849842 -41.218104)
		(width 0.11684)
		(layer "In6.Cu")
		(net "SMB_INA230_7_3V3AUX_SCL_R")
	)
	(segment
		(start 64.846962 -37.1221)
		(end 63.42761 -37.1221)
		(width 0.11684)
		(layer "In6.Cu")
		(net "SMB_INA230_7_3V3AUX_SCL_R")
	)
	(segment
		(start 143.524986 -47.103284)
		(end 129.814828 -47.103284)
		(width 0.11684)
		(layer "In6.Cu")
		(net "SMB_INA230_7_3V3AUX_SCL_R")
	)
	(segment
		(start 71.525892 -36.653216)
		(end 65.315846 -36.653216)
		(width 0.11684)
		(layer "In6.Cu")
		(net "SMB_INA230_7_3V3AUX_SCL_R")
	)
	(segment
		(start 90.89898 -43.068494)
		(end 90.249502 -43.717972)
		(width 0.11684)
		(layer "In6.Cu")
		(net "SMB_INA230_7_3V3AUX_SCL_R")
	)
	(segment
		(start 49.368202 -37.592762)
		(end 48.797718 -38.163246)
		(width 0.11684)
		(layer "In6.Cu")
		(net "SMB_INA230_7_3V3AUX_SCL_R")
	)
	(segment
		(start 90.249502 -43.717972)
		(end 81.652364 -43.717972)
		(width 0.11684)
		(layer "In6.Cu")
		(net "SMB_INA230_7_3V3AUX_SCL_R")
	)
	(segment
		(start 100.921566 -43.068494)
		(end 90.89898 -43.068494)
		(width 0.11684)
		(layer "In6.Cu")
		(net "SMB_INA230_7_3V3AUX_SCL_R")
	)
	(segment
		(start 81.652364 -43.717972)
		(end 76.475082 -38.54069)
		(width 0.11684)
		(layer "In6.Cu")
		(net "SMB_INA230_7_3V3AUX_SCL_R")
	)
	(segment
		(start 127.765302 -47.853854)
		(end 127.577342 -47.665894)
		(width 0.11684)
		(layer "In6.Cu")
		(net "SMB_INA230_7_3V3AUX_SCL_R")
	)
	(segment
		(start 102.777544 -43.837352)
		(end 100.921566 -43.068494)
		(width 0.11684)
		(layer "In6.Cu")
		(net "SMB_INA230_7_3V3AUX_SCL_R")
	)
	(segment
		(start 48.797718 -38.163246)
		(end 42.57802 -38.163246)
		(width 0.11684)
		(layer "In6.Cu")
		(net "SMB_INA230_7_3V3AUX_SCL_R")
	)
	(segment
		(start 59.760104 -27.773122)
		(end 60.37453 -27.773122)
		(width 0.11684)
		(layer "In6.Cu")
		(net "SMB_INA230_7_3V3AUX_SCL_R")
	)
	(segment
		(start 58.339482 -35.18535)
		(end 58.339482 -29.193744)
		(width 0.11684)
		(layer "In6.Cu")
		(net "SMB_INA230_7_3V3AUX_SCL_R")
	)
	(segment
		(start 42.57802 -38.163246)
		(end 36.28644 -44.454826)
		(width 0.11684)
		(layer "In6.Cu")
		(net "SMB_INA230_7_3V3AUX_SCL_R")
	)
	(segment
		(start 129.814828 -47.103284)
		(end 129.064258 -47.853854)
		(width 0.11684)
		(layer "In6.Cu")
		(net "SMB_INA230_7_3V3AUX_SCL_R")
	)
	(segment
		(start 60.4266 -35.078162)
		(end 60.192412 -35.31235)
		(width 0.11684)
		(layer "In6.Cu")
		(net "SMB_INA230_7_3V3AUX_SCL_R")
	)
	(segment
		(start 145.574766 -49.153064)
		(end 143.524986 -47.103284)
		(width 0.11684)
		(layer "In6.Cu")
		(net "SMB_INA230_7_3V3AUX_SCL_R")
	)
	(segment
		(start 36.28644 -44.454826)
		(end 25.086564 -44.454826)
		(width 0.11684)
		(layer "In6.Cu")
		(net "SMB_INA230_7_3V3AUX_SCL_R")
	)
	(segment
		(start 61.383672 -35.078162)
		(end 60.4266 -35.078162)
		(width 0.11684)
		(layer "In6.Cu")
		(net "SMB_INA230_7_3V3AUX_SCL_R")
	)
	(segment
		(start 65.315846 -36.653216)
		(end 64.846962 -37.1221)
		(width 0.11684)
		(layer "In6.Cu")
		(net "SMB_INA230_7_3V3AUX_SCL_R")
	)
	(segment
		(start 393.66698 -75.555602)
		(end 393.87907 -75.555602)
		(width 0.10668)
		(layer "F.Cu")
		(net "SMB_INA230_6_3V3AUX_SDA_R1")
	)
	(segment
		(start 390.281414 -75.391264)
		(end 390.280652 -75.392026)
		(width 0.10668)
		(layer "F.Cu")
		(net "SMB_INA230_6_3V3AUX_SDA_R1")
	)
	(segment
		(start 390.891268 -75.391264)
		(end 390.281414 -75.391264)
		(width 0.10668)
		(layer "F.Cu")
		(net "SMB_INA230_6_3V3AUX_SDA_R1")
	)
	(segment
		(start 393.684506 -72.584818)
		(end 393.388088 -72.881236)
		(width 0.10668)
		(layer "F.Cu")
		(net "SMB_INA230_6_3V3AUX_SDA_R1")
	)
	(segment
		(start 393.684506 -72.28205)
		(end 393.684506 -72.584818)
		(width 0.10668)
		(layer "F.Cu")
		(net "SMB_INA230_6_3V3AUX_SDA_R1")
	)
	(segment
		(start 393.388088 -72.881236)
		(end 393.388088 -74.146664)
		(width 0.10668)
		(layer "F.Cu")
		(net "SMB_INA230_6_3V3AUX_SDA_R1")
	)
	(segment
		(start 393.388088 -75.27671)
		(end 393.66698 -75.555602)
		(width 0.10668)
		(layer "F.Cu")
		(net "SMB_INA230_6_3V3AUX_SDA_R1")
	)
	(segment
		(start 393.388088 -74.146664)
		(end 393.388088 -75.27671)
		(width 0.10668)
		(layer "F.Cu")
		(net "SMB_INA230_6_3V3AUX_SDA_R1")
	)
	(via
		(at 393.388088 -74.146664)
		(size 0.508)
		(drill 0.254)
		(layers "F.Cu" "B.Cu")
		(net "SMB_INA230_6_3V3AUX_SDA_R1")
	)
	(via
		(at 390.280652 -75.392026)
		(size 0.508)
		(drill 0.254)
		(layers "F.Cu" "B.Cu")
		(net "SMB_INA230_6_3V3AUX_SDA_R1")
	)
	(segment
		(start 392.142726 -75.392026)
		(end 390.280652 -75.392026)
		(width 0.10668)
		(layer "B.Cu")
		(net "SMB_INA230_6_3V3AUX_SDA_R1")
	)
	(segment
		(start 393.388088 -74.146664)
		(end 392.142726 -75.392026)
		(width 0.10668)
		(layer "B.Cu")
		(net "SMB_INA230_6_3V3AUX_SDA_R1")
	)
	(segment
		(start 392.884406 -72.28205)
		(end 392.884406 -72.927464)
		(width 0.10668)
		(layer "F.Cu")
		(net "SMB_INA230_6_3V3AUX_SDA_R")
	)
	(segment
		(start 299.72 -108.56595)
		(end 299.72 -107.442)
		(width 0.10668)
		(layer "F.Cu")
		(net "SMB_INA230_6_3V3AUX_SDA_R")
	)
	(segment
		(start 299.974 -107.188)
		(end 299.974 -102.235)
		(width 0.10668)
		(layer "F.Cu")
		(net "SMB_INA230_6_3V3AUX_SDA_R")
	)
	(segment
		(start 299.72 -107.442)
		(end 299.974 -107.188)
		(width 0.10668)
		(layer "F.Cu")
		(net "SMB_INA230_6_3V3AUX_SDA_R")
	)
	(via
		(at 392.884406 -72.927464)
		(size 0.508)
		(drill 0.254)
		(layers "F.Cu" "B.Cu")
		(net "SMB_INA230_6_3V3AUX_SDA_R")
	)
	(via
		(at 299.974 -102.235)
		(size 0.508)
		(drill 0.254)
		(layers "F.Cu" "B.Cu")
		(net "SMB_INA230_6_3V3AUX_SDA_R")
	)
	(segment
		(start 392.884406 -72.844406)
		(end 392.884406 -72.927464)
		(width 0.11684)
		(layer "In2.Cu")
		(net "SMB_INA230_6_3V3AUX_SDA_R")
	)
	(segment
		(start 335.026254 -98.453702)
		(end 335.026254 -97.27184)
		(width 0.11684)
		(layer "In2.Cu")
		(net "SMB_INA230_6_3V3AUX_SDA_R")
	)
	(segment
		(start 334.602074 -97.27184)
		(end 334.602074 -98.453702)
		(width 0.11684)
		(layer "In2.Cu")
		(net "SMB_INA230_6_3V3AUX_SDA_R")
	)
	(segment
		(start 312.801 -97.155)
		(end 334.485234 -97.155)
		(width 0.11684)
		(layer "In2.Cu")
		(net "SMB_INA230_6_3V3AUX_SDA_R")
	)
	(segment
		(start 335.450434 -97.27184)
		(end 335.450434 -98.453702)
		(width 0.11684)
		(layer "In2.Cu")
		(net "SMB_INA230_6_3V3AUX_SDA_R")
	)
	(segment
		(start 334.485234 -97.155)
		(end 334.602074 -97.27184)
		(width 0.11684)
		(layer "In2.Cu")
		(net "SMB_INA230_6_3V3AUX_SDA_R")
	)
	(segment
		(start 341.249 -97.155)
		(end 366.141 -72.263)
		(width 0.11684)
		(layer "In2.Cu")
		(net "SMB_INA230_6_3V3AUX_SDA_R")
	)
	(segment
		(start 392.303 -72.263)
		(end 392.884406 -72.844406)
		(width 0.11684)
		(layer "In2.Cu")
		(net "SMB_INA230_6_3V3AUX_SDA_R")
	)
	(segment
		(start 335.874614 -98.453702)
		(end 335.874614 -97.27184)
		(width 0.11684)
		(layer "In2.Cu")
		(net "SMB_INA230_6_3V3AUX_SDA_R")
	)
	(segment
		(start 335.143094 -97.155)
		(end 335.333594 -97.155)
		(width 0.11684)
		(layer "In2.Cu")
		(net "SMB_INA230_6_3V3AUX_SDA_R")
	)
	(segment
		(start 335.991454 -97.155)
		(end 341.249 -97.155)
		(width 0.11684)
		(layer "In2.Cu")
		(net "SMB_INA230_6_3V3AUX_SDA_R")
	)
	(segment
		(start 334.602074 -98.453702)
		(end 334.718914 -98.570542)
		(width 0.11684)
		(layer "In2.Cu")
		(net "SMB_INA230_6_3V3AUX_SDA_R")
	)
	(segment
		(start 366.141 -72.263)
		(end 392.303 -72.263)
		(width 0.11684)
		(layer "In2.Cu")
		(net "SMB_INA230_6_3V3AUX_SDA_R")
	)
	(segment
		(start 335.874614 -97.27184)
		(end 335.991454 -97.155)
		(width 0.11684)
		(layer "In2.Cu")
		(net "SMB_INA230_6_3V3AUX_SDA_R")
	)
	(segment
		(start 335.333594 -97.155)
		(end 335.450434 -97.27184)
		(width 0.11684)
		(layer "In2.Cu")
		(net "SMB_INA230_6_3V3AUX_SDA_R")
	)
	(segment
		(start 334.909414 -98.570542)
		(end 335.026254 -98.453702)
		(width 0.11684)
		(layer "In2.Cu")
		(net "SMB_INA230_6_3V3AUX_SDA_R")
	)
	(segment
		(start 299.974 -102.235)
		(end 307.721 -102.235)
		(width 0.11684)
		(layer "In2.Cu")
		(net "SMB_INA230_6_3V3AUX_SDA_R")
	)
	(segment
		(start 335.757774 -98.570542)
		(end 335.874614 -98.453702)
		(width 0.11684)
		(layer "In2.Cu")
		(net "SMB_INA230_6_3V3AUX_SDA_R")
	)
	(segment
		(start 335.450434 -98.453702)
		(end 335.567274 -98.570542)
		(width 0.11684)
		(layer "In2.Cu")
		(net "SMB_INA230_6_3V3AUX_SDA_R")
	)
	(segment
		(start 335.026254 -97.27184)
		(end 335.143094 -97.155)
		(width 0.11684)
		(layer "In2.Cu")
		(net "SMB_INA230_6_3V3AUX_SDA_R")
	)
	(segment
		(start 307.721 -102.235)
		(end 312.801 -97.155)
		(width 0.11684)
		(layer "In2.Cu")
		(net "SMB_INA230_6_3V3AUX_SDA_R")
	)
	(segment
		(start 334.718914 -98.570542)
		(end 334.909414 -98.570542)
		(width 0.11684)
		(layer "In2.Cu")
		(net "SMB_INA230_6_3V3AUX_SDA_R")
	)
	(segment
		(start 335.567274 -98.570542)
		(end 335.757774 -98.570542)
		(width 0.11684)
		(layer "In2.Cu")
		(net "SMB_INA230_6_3V3AUX_SDA_R")
	)
	(segment
		(start 394.054838 -73.966578)
		(end 394.529056 -74.440796)
		(width 0.10668)
		(layer "F.Cu")
		(net "SMB_INA230_6_3V3AUX_SCL_R1")
	)
	(segment
		(start 394.529056 -74.440796)
		(end 394.529056 -74.905616)
		(width 0.10668)
		(layer "F.Cu")
		(net "SMB_INA230_6_3V3AUX_SCL_R1")
	)
	(segment
		(start 394.1826 -72.971152)
		(end 394.054838 -73.098914)
		(width 0.10668)
		(layer "F.Cu")
		(net "SMB_INA230_6_3V3AUX_SCL_R1")
	)
	(segment
		(start 394.637006 -72.28205)
		(end 394.1826 -72.736456)
		(width 0.10668)
		(layer "F.Cu")
		(net "SMB_INA230_6_3V3AUX_SCL_R1")
	)
	(segment
		(start 394.054838 -73.098914)
		(end 394.054838 -73.966578)
		(width 0.10668)
		(layer "F.Cu")
		(net "SMB_INA230_6_3V3AUX_SCL_R1")
	)
	(segment
		(start 394.1826 -72.736456)
		(end 394.1826 -72.971152)
		(width 0.10668)
		(layer "F.Cu")
		(net "SMB_INA230_6_3V3AUX_SCL_R1")
	)
	(via
		(at 394.1826 -72.971152)
		(size 0.508)
		(drill 0.254)
		(layers "F.Cu" "B.Cu")
		(net "SMB_INA230_6_3V3AUX_SCL_R1")
	)
	(segment
		(start 298.704 -108.56595)
		(end 298.704 -102.993952)
		(width 0.10668)
		(layer "F.Cu")
		(net "SMB_INA230_6_3V3AUX_SCL_R")
	)
	(segment
		(start 298.704 -102.993952)
		(end 298.203874 -102.493826)
		(width 0.10668)
		(layer "F.Cu")
		(net "SMB_INA230_6_3V3AUX_SCL_R")
	)
	(segment
		(start 395.46784 -72.312784)
		(end 395.437106 -72.28205)
		(width 0.10668)
		(layer "F.Cu")
		(net "SMB_INA230_6_3V3AUX_SCL_R")
	)
	(segment
		(start 395.46784 -73.019412)
		(end 395.46784 -72.312784)
		(width 0.10668)
		(layer "F.Cu")
		(net "SMB_INA230_6_3V3AUX_SCL_R")
	)
	(via
		(at 298.203874 -102.493826)
		(size 0.508)
		(drill 0.254)
		(layers "F.Cu" "B.Cu")
		(net "SMB_INA230_6_3V3AUX_SCL_R")
	)
	(via
		(at 395.46784 -73.019412)
		(size 0.508)
		(drill 0.254)
		(layers "F.Cu" "B.Cu")
		(net "SMB_INA230_6_3V3AUX_SCL_R")
	)
	(segment
		(start 298.203874 -102.493826)
		(end 298.953174 -102.493826)
		(width 0.11684)
		(layer "In2.Cu")
		(net "SMB_INA230_6_3V3AUX_SCL_R")
	)
	(segment
		(start 395.46784 -72.88784)
		(end 395.46784 -73.019412)
		(width 0.11684)
		(layer "In2.Cu")
		(net "SMB_INA230_6_3V3AUX_SCL_R")
	)
	(segment
		(start 312.039 -96.393)
		(end 340.487 -96.393)
		(width 0.11684)
		(layer "In2.Cu")
		(net "SMB_INA230_6_3V3AUX_SCL_R")
	)
	(segment
		(start 365.506 -71.374)
		(end 393.954 -71.374)
		(width 0.11684)
		(layer "In2.Cu")
		(net "SMB_INA230_6_3V3AUX_SCL_R")
	)
	(segment
		(start 298.953174 -102.493826)
		(end 299.847 -101.6)
		(width 0.11684)
		(layer "In2.Cu")
		(net "SMB_INA230_6_3V3AUX_SCL_R")
	)
	(segment
		(start 393.954 -71.374)
		(end 395.46784 -72.88784)
		(width 0.11684)
		(layer "In2.Cu")
		(net "SMB_INA230_6_3V3AUX_SCL_R")
	)
	(segment
		(start 299.847 -101.6)
		(end 306.832 -101.6)
		(width 0.11684)
		(layer "In2.Cu")
		(net "SMB_INA230_6_3V3AUX_SCL_R")
	)
	(segment
		(start 306.832 -101.6)
		(end 312.039 -96.393)
		(width 0.11684)
		(layer "In2.Cu")
		(net "SMB_INA230_6_3V3AUX_SCL_R")
	)
	(segment
		(start 340.487 -96.393)
		(end 365.506 -71.374)
		(width 0.11684)
		(layer "In2.Cu")
		(net "SMB_INA230_6_3V3AUX_SCL_R")
	)
	(via
		(at 420.106856 -425.818046)
		(size 0.6604)
		(drill 0.3302)
		(layers "F.Cu" "B.Cu")
		(net "RT_ROM_MUX8_OE_N")
	)
	(segment
		(start 420.686992 -426.015912)
		(end 420.489126 -425.818046)
		(width 0.10668)
		(layer "B.Cu")
		(net "RT_ROM_MUX8_OE_N")
	)
	(segment
		(start 419.356286 -425.82338)
		(end 419.36162 -425.818046)
		(width 0.10668)
		(layer "B.Cu")
		(net "RT_ROM_MUX8_OE_N")
	)
	(segment
		(start 421.26281 -426.015912)
		(end 420.686992 -426.015912)
		(width 0.10668)
		(layer "B.Cu")
		(net "RT_ROM_MUX8_OE_N")
	)
	(segment
		(start 420.489126 -425.818046)
		(end 420.106856 -425.818046)
		(width 0.10668)
		(layer "B.Cu")
		(net "RT_ROM_MUX8_OE_N")
	)
	(segment
		(start 419.36162 -425.818046)
		(end 420.106856 -425.818046)
		(width 0.10668)
		(layer "B.Cu")
		(net "RT_ROM_MUX8_OE_N")
	)
	(segment
		(start 371.747288 -425.985178)
		(end 372.863872 -425.985178)
		(width 0.10668)
		(layer "F.Cu")
		(net "RT_ROM_MUX7_OE_N")
	)
	(segment
		(start 371.660674 -425.898564)
		(end 371.747288 -425.985178)
		(width 0.10668)
		(layer "F.Cu")
		(net "RT_ROM_MUX7_OE_N")
	)
	(segment
		(start 371.660674 -425.464732)
		(end 371.660674 -425.898564)
		(width 0.10668)
		(layer "F.Cu")
		(net "RT_ROM_MUX7_OE_N")
	)
	(segment
		(start 372.237 -424.888406)
		(end 371.660674 -425.464732)
		(width 0.10668)
		(layer "F.Cu")
		(net "RT_ROM_MUX7_OE_N")
	)
	(segment
		(start 372.863872 -425.985178)
		(end 373.026432 -426.147738)
		(width 0.10668)
		(layer "F.Cu")
		(net "RT_ROM_MUX7_OE_N")
	)
	(segment
		(start 372.237 -424.3197)
		(end 372.237 -424.888406)
		(width 0.10668)
		(layer "F.Cu")
		(net "RT_ROM_MUX7_OE_N")
	)
	(segment
		(start 373.026432 -426.147738)
		(end 373.254524 -426.147738)
		(width 0.10668)
		(layer "F.Cu")
		(net "RT_ROM_MUX7_OE_N")
	)
	(segment
		(start 373.381524 -426.020738)
		(end 373.381524 -425.927774)
		(width 0.10668)
		(layer "F.Cu")
		(net "RT_ROM_MUX7_OE_N")
	)
	(segment
		(start 373.254524 -426.147738)
		(end 373.381524 -426.020738)
		(width 0.10668)
		(layer "F.Cu")
		(net "RT_ROM_MUX7_OE_N")
	)
	(via
		(at 371.660674 -425.898564)
		(size 0.762)
		(drill 0.381)
		(layers "F.Cu" "B.Cu")
		(net "RT_ROM_MUX7_OE_N")
	)
	(segment
		(start 292.099746 -396.647924)
		(end 292.620446 -396.647924)
		(width 0.10668)
		(layer "F.Cu")
		(net "RT_ROM_MUX6_OE_N")
	)
	(segment
		(start 292.620446 -396.647924)
		(end 292.747446 -396.774924)
		(width 0.10668)
		(layer "F.Cu")
		(net "RT_ROM_MUX6_OE_N")
	)
	(segment
		(start 291.64026 -396.188438)
		(end 292.099746 -396.647924)
		(width 0.10668)
		(layer "F.Cu")
		(net "RT_ROM_MUX6_OE_N")
	)
	(segment
		(start 292.747446 -397.525494)
		(end 292.655244 -397.617696)
		(width 0.10668)
		(layer "F.Cu")
		(net "RT_ROM_MUX6_OE_N")
	)
	(segment
		(start 292.747446 -396.774924)
		(end 292.747446 -396.826994)
		(width 0.10668)
		(layer "F.Cu")
		(net "RT_ROM_MUX6_OE_N")
	)
	(segment
		(start 292.747446 -396.826994)
		(end 292.747446 -397.525494)
		(width 0.10668)
		(layer "F.Cu")
		(net "RT_ROM_MUX6_OE_N")
	)
	(segment
		(start 291.64026 -395.871446)
		(end 291.64026 -396.188438)
		(width 0.10668)
		(layer "F.Cu")
		(net "RT_ROM_MUX6_OE_N")
	)
	(via
		(at 292.747446 -396.826994)
		(size 0.762)
		(drill 0.381)
		(layers "F.Cu" "B.Cu")
		(net "RT_ROM_MUX6_OE_N")
	)
	(via
		(at 296.475912 -424.463464)
		(size 0.6604)
		(drill 0.3302)
		(layers "F.Cu" "B.Cu")
		(net "RT_ROM_MUX5_OE_N")
	)
	(segment
		(start 297.849798 -424.463464)
		(end 296.475912 -424.463464)
		(width 0.10668)
		(layer "B.Cu")
		(net "RT_ROM_MUX5_OE_N")
	)
	(segment
		(start 296.028364 -424.463464)
		(end 295.683686 -424.118786)
		(width 0.10668)
		(layer "B.Cu")
		(net "RT_ROM_MUX5_OE_N")
	)
	(segment
		(start 296.475912 -424.463464)
		(end 296.028364 -424.463464)
		(width 0.10668)
		(layer "B.Cu")
		(net "RT_ROM_MUX5_OE_N")
	)
	(segment
		(start 297.925236 -424.538902)
		(end 297.849798 -424.463464)
		(width 0.10668)
		(layer "B.Cu")
		(net "RT_ROM_MUX5_OE_N")
	)
	(via
		(at 160.518094 -419.595046)
		(size 0.6604)
		(drill 0.3302)
		(layers "F.Cu" "B.Cu")
		(net "RT_ROM_MUX4_OE_N")
	)
	(segment
		(start 161.024824 -419.649148)
		(end 160.572196 -419.649148)
		(width 0.10668)
		(layer "B.Cu")
		(net "RT_ROM_MUX4_OE_N")
	)
	(segment
		(start 160.518348 -418.821362)
		(end 160.743392 -418.596318)
		(width 0.10668)
		(layer "B.Cu")
		(net "RT_ROM_MUX4_OE_N")
	)
	(segment
		(start 160.518094 -419.595046)
		(end 160.518348 -419.594792)
		(width 0.10668)
		(layer "B.Cu")
		(net "RT_ROM_MUX4_OE_N")
	)
	(segment
		(start 160.518348 -419.594792)
		(end 160.518348 -418.821362)
		(width 0.10668)
		(layer "B.Cu")
		(net "RT_ROM_MUX4_OE_N")
	)
	(segment
		(start 161.411666 -419.262306)
		(end 161.024824 -419.649148)
		(width 0.10668)
		(layer "B.Cu")
		(net "RT_ROM_MUX4_OE_N")
	)
	(segment
		(start 160.572196 -419.649148)
		(end 160.518094 -419.595046)
		(width 0.10668)
		(layer "B.Cu")
		(net "RT_ROM_MUX4_OE_N")
	)
	(segment
		(start 160.743392 -418.596318)
		(end 160.743392 -418.254942)
		(width 0.10668)
		(layer "B.Cu")
		(net "RT_ROM_MUX4_OE_N")
	)
	(segment
		(start 161.67354 -419.262306)
		(end 161.411666 -419.262306)
		(width 0.10668)
		(layer "B.Cu")
		(net "RT_ROM_MUX4_OE_N")
	)
	(via
		(at 167.081454 -425.932092)
		(size 0.6604)
		(drill 0.3302)
		(layers "F.Cu" "B.Cu")
		(net "RT_ROM_MUX3_OE_N")
	)
	(segment
		(start 167.549322 -424.904408)
		(end 167.549322 -425.464224)
		(width 0.10668)
		(layer "B.Cu")
		(net "RT_ROM_MUX3_OE_N")
	)
	(segment
		(start 167.696388 -424.757342)
		(end 167.549322 -424.904408)
		(width 0.10668)
		(layer "B.Cu")
		(net "RT_ROM_MUX3_OE_N")
	)
	(segment
		(start 167.081454 -425.932092)
		(end 166.600124 -425.932092)
		(width 0.10668)
		(layer "B.Cu")
		(net "RT_ROM_MUX3_OE_N")
	)
	(segment
		(start 167.549322 -425.464224)
		(end 167.081454 -425.932092)
		(width 0.10668)
		(layer "B.Cu")
		(net "RT_ROM_MUX3_OE_N")
	)
	(segment
		(start 166.473124 -425.805092)
		(end 166.473124 -425.088304)
		(width 0.10668)
		(layer "B.Cu")
		(net "RT_ROM_MUX3_OE_N")
	)
	(segment
		(start 166.600124 -425.932092)
		(end 166.473124 -425.805092)
		(width 0.10668)
		(layer "B.Cu")
		(net "RT_ROM_MUX3_OE_N")
	)
	(segment
		(start 113.645188 -402.479002)
		(end 113.488978 -402.635212)
		(width 0.10668)
		(layer "F.Cu")
		(net "RT_ROM_MUX2_OE_N")
	)
	(segment
		(start 114.735864 -402.103844)
		(end 114.360706 -402.479002)
		(width 0.10668)
		(layer "F.Cu")
		(net "RT_ROM_MUX2_OE_N")
	)
	(segment
		(start 114.749072 -402.103844)
		(end 114.735864 -402.103844)
		(width 0.10668)
		(layer "F.Cu")
		(net "RT_ROM_MUX2_OE_N")
	)
	(segment
		(start 114.360706 -402.479002)
		(end 113.645188 -402.479002)
		(width 0.10668)
		(layer "F.Cu")
		(net "RT_ROM_MUX2_OE_N")
	)
	(segment
		(start 113.339372 -402.784818)
		(end 113.339372 -403.457918)
		(width 0.10668)
		(layer "F.Cu")
		(net "RT_ROM_MUX2_OE_N")
	)
	(segment
		(start 113.488978 -402.635212)
		(end 113.339372 -402.784818)
		(width 0.10668)
		(layer "F.Cu")
		(net "RT_ROM_MUX2_OE_N")
	)
	(via
		(at 113.488978 -402.635212)
		(size 0.762)
		(drill 0.381)
		(layers "F.Cu" "B.Cu")
		(net "RT_ROM_MUX2_OE_N")
	)
	(segment
		(start 97.870518 -401.641564)
		(end 98.101658 -401.641564)
		(width 0.10668)
		(layer "F.Cu")
		(net "RT_ROM_MUX1_OE_N")
	)
	(segment
		(start 98.838512 -400.550126)
		(end 98.706178 -400.417792)
		(width 0.10668)
		(layer "F.Cu")
		(net "RT_ROM_MUX1_OE_N")
	)
	(segment
		(start 98.838512 -400.90471)
		(end 98.838512 -400.550126)
		(width 0.10668)
		(layer "F.Cu")
		(net "RT_ROM_MUX1_OE_N")
	)
	(segment
		(start 98.101658 -401.641564)
		(end 98.838512 -400.90471)
		(width 0.10668)
		(layer "F.Cu")
		(net "RT_ROM_MUX1_OE_N")
	)
	(segment
		(start 98.706178 -400.417792)
		(end 97.986342 -400.417792)
		(width 0.10668)
		(layer "F.Cu")
		(net "RT_ROM_MUX1_OE_N")
	)
	(via
		(at 98.838512 -400.550126)
		(size 0.762)
		(drill 0.381)
		(layers "F.Cu" "B.Cu")
		(net "RT_ROM_MUX1_OE_N")
	)
	(segment
		(start 74.35596 -62.516258)
		(end 74.409046 -62.569344)
		(width 0.10668)
		(layer "F.Cu")
		(net "RST_PERST_OCP_V3_2_R_N")
	)
	(segment
		(start 74.35596 -60.254896)
		(end 74.35596 -61.643514)
		(width 0.10668)
		(layer "F.Cu")
		(net "RST_PERST_OCP_V3_2_R_N")
	)
	(segment
		(start 74.35596 -61.643514)
		(end 74.35596 -62.516258)
		(width 0.10668)
		(layer "F.Cu")
		(net "RST_PERST_OCP_V3_2_R_N")
	)
	(via
		(at 74.35596 -61.643514)
		(size 0.762)
		(drill 0.381)
		(layers "F.Cu" "B.Cu")
		(net "RST_PERST_OCP_V3_2_R_N")
	)
	(segment
		(start 73.303638 -55.522876)
		(end 73.303638 -55.897018)
		(width 0.10668)
		(layer "F.Cu")
		(net "RST_PERST_OCP_V3_2_BUF_R_N")
	)
	(segment
		(start 73.303638 -55.897018)
		(end 72.782684 -56.417972)
		(width 0.10668)
		(layer "F.Cu")
		(net "RST_PERST_OCP_V3_2_BUF_R_N")
	)
	(segment
		(start 72.45604 -56.744616)
		(end 72.45604 -57.855104)
		(width 0.10668)
		(layer "F.Cu")
		(net "RST_PERST_OCP_V3_2_BUF_R_N")
	)
	(segment
		(start 72.782684 -56.417972)
		(end 72.45604 -56.744616)
		(width 0.10668)
		(layer "F.Cu")
		(net "RST_PERST_OCP_V3_2_BUF_R_N")
	)
	(via
		(at 72.782684 -56.417972)
		(size 0.762)
		(drill 0.381)
		(layers "F.Cu" "B.Cu")
		(net "RST_PERST_OCP_V3_2_BUF_R_N")
	)
	(segment
		(start 73.340722 -54.722776)
		(end 73.447402 -54.616096)
		(width 0.10668)
		(layer "F.Cu")
		(net "RST_PERST_OCP_V3_2_BUF_N")
	)
	(segment
		(start 84.27212 -45.36694)
		(end 84.27212 -46.4566)
		(width 0.10668)
		(layer "F.Cu")
		(net "RST_PERST_OCP_V3_2_BUF_N")
	)
	(segment
		(start 73.447402 -54.616096)
		(end 73.447402 -53.975762)
		(width 0.10668)
		(layer "F.Cu")
		(net "RST_PERST_OCP_V3_2_BUF_N")
	)
	(segment
		(start 73.303638 -54.722776)
		(end 73.340722 -54.722776)
		(width 0.10668)
		(layer "F.Cu")
		(net "RST_PERST_OCP_V3_2_BUF_N")
	)
	(via
		(at 84.27212 -46.4566)
		(size 0.508)
		(drill 0.254)
		(layers "F.Cu" "B.Cu")
		(net "RST_PERST_OCP_V3_2_BUF_N")
	)
	(via
		(at 73.447402 -53.975762)
		(size 0.508)
		(drill 0.254)
		(layers "F.Cu" "B.Cu")
		(net "RST_PERST_OCP_V3_2_BUF_N")
	)
	(segment
		(start 83.630262 -47.098458)
		(end 84.27212 -46.4566)
		(width 0.11684)
		(layer "In2.Cu")
		(net "RST_PERST_OCP_V3_2_BUF_N")
	)
	(segment
		(start 73.532238 -53.975762)
		(end 80.409542 -47.098458)
		(width 0.11684)
		(layer "In2.Cu")
		(net "RST_PERST_OCP_V3_2_BUF_N")
	)
	(segment
		(start 80.409542 -47.098458)
		(end 83.630262 -47.098458)
		(width 0.11684)
		(layer "In2.Cu")
		(net "RST_PERST_OCP_V3_2_BUF_N")
	)
	(segment
		(start 73.447402 -53.975762)
		(end 73.532238 -53.975762)
		(width 0.11684)
		(layer "In2.Cu")
		(net "RST_PERST_OCP_V3_2_BUF_N")
	)
	(segment
		(start 214.376 -119.634)
		(end 212.979 -119.634)
		(width 0.10668)
		(layer "F.Cu")
		(net "RST_PERST_OCP_SFF_R_N")
	)
	(segment
		(start 212.10905 -119.634)
		(end 212.979 -119.634)
		(width 0.10668)
		(layer "F.Cu")
		(net "RST_PERST_OCP_SFF_R_N")
	)
	(segment
		(start 214.56904 -118.688104)
		(end 214.56904 -119.44096)
		(width 0.10668)
		(layer "F.Cu")
		(net "RST_PERST_OCP_SFF_R_N")
	)
	(segment
		(start 214.56904 -119.44096)
		(end 214.376 -119.634)
		(width 0.10668)
		(layer "F.Cu")
		(net "RST_PERST_OCP_SFF_R_N")
	)
	(via
		(at 212.979 -119.634)
		(size 0.762)
		(drill 0.381)
		(layers "F.Cu" "B.Cu")
		(net "RST_PERST_OCP_SFF_R_N")
	)
	(segment
		(start 216.408 -123.42495)
		(end 216.408 -122.61596)
		(width 0.10668)
		(layer "F.Cu")
		(net "RST_PERST_OCP_SFF_BUF_R_N")
	)
	(segment
		(start 216.408 -122.61596)
		(end 216.46896 -122.555)
		(width 0.10668)
		(layer "F.Cu")
		(net "RST_PERST_OCP_SFF_BUF_R_N")
	)
	(segment
		(start 216.46896 -121.087896)
		(end 216.46896 -122.555)
		(width 0.10668)
		(layer "F.Cu")
		(net "RST_PERST_OCP_SFF_BUF_R_N")
	)
	(via
		(at 216.46896 -122.555)
		(size 0.762)
		(drill 0.381)
		(layers "F.Cu" "B.Cu")
		(net "RST_PERST_OCP_SFF_BUF_R_N")
	)
	(segment
		(start 215.380824 -125.864874)
		(end 215.114886 -126.130812)
		(width 0.10668)
		(layer "F.Cu")
		(net "RST_PERST_OCP_SFF_BUF_N")
	)
	(segment
		(start 215.114886 -126.130812)
		(end 213.215474 -126.130812)
		(width 0.10668)
		(layer "F.Cu")
		(net "RST_PERST_OCP_SFF_BUF_N")
	)
	(segment
		(start 215.380824 -125.252226)
		(end 215.380824 -125.864874)
		(width 0.10668)
		(layer "F.Cu")
		(net "RST_PERST_OCP_SFF_BUF_N")
	)
	(segment
		(start 213.215474 -126.130812)
		(end 211.304632 -124.21997)
		(width 0.10668)
		(layer "F.Cu")
		(net "RST_PERST_OCP_SFF_BUF_N")
	)
	(segment
		(start 216.408 -124.22505)
		(end 215.380824 -125.252226)
		(width 0.10668)
		(layer "F.Cu")
		(net "RST_PERST_OCP_SFF_BUF_N")
	)
	(segment
		(start 208.683352 -124.21997)
		(end 210.058 -124.21997)
		(width 0.10668)
		(layer "F.Cu")
		(net "RST_PERST_OCP_SFF_BUF_N")
	)
	(segment
		(start 211.304632 -124.21997)
		(end 210.058 -124.21997)
		(width 0.10668)
		(layer "F.Cu")
		(net "RST_PERST_OCP_SFF_BUF_N")
	)
	(via
		(at 210.058 -124.21997)
		(size 0.508)
		(drill 0.254)
		(layers "F.Cu" "B.Cu")
		(net "RST_PERST_OCP_SFF_BUF_N")
	)
	(via
		(at 227.04425 -327.994264)
		(size 0.6604)
		(drill 0.3302)
		(layers "F.Cu" "B.Cu")
		(net "PVDD_33_S5_ADC_TIC")
	)
	(segment
		(start 227.04425 -327.994264)
		(end 227.472494 -327.56602)
		(width 0.10668)
		(layer "B.Cu")
		(net "PVDD_33_S5_ADC_TIC")
	)
	(segment
		(start 226.559364 -327.509378)
		(end 227.04425 -327.994264)
		(width 0.10668)
		(layer "B.Cu")
		(net "PVDD_33_S5_ADC_TIC")
	)
	(segment
		(start 230.65105 -327.21169)
		(end 230.494078 -327.054718)
		(width 0.10668)
		(layer "B.Cu")
		(net "PVDD_33_S5_ADC_TIC")
	)
	(segment
		(start 228.590856 -327.054718)
		(end 228.079554 -327.56602)
		(width 0.10668)
		(layer "B.Cu")
		(net "PVDD_33_S5_ADC_TIC")
	)
	(segment
		(start 230.494078 -327.054718)
		(end 228.590856 -327.054718)
		(width 0.10668)
		(layer "B.Cu")
		(net "PVDD_33_S5_ADC_TIC")
	)
	(segment
		(start 227.472494 -327.56602)
		(end 228.079554 -327.56602)
		(width 0.10668)
		(layer "B.Cu")
		(net "PVDD_33_S5_ADC_TIC")
	)
	(segment
		(start 225.208338 -327.509378)
		(end 226.559364 -327.509378)
		(width 0.10668)
		(layer "B.Cu")
		(net "PVDD_33_S5_ADC_TIC")
	)
	(segment
		(start 245.025926 -322.834)
		(end 243.2939 -322.834)
		(width 0.10668)
		(layer "F.Cu")
		(net "PVDD_33_S5_ADC_MAM")
	)
	(segment
		(start 236.082332 -326.41413)
		(end 233.724196 -326.41413)
		(width 0.10668)
		(layer "F.Cu")
		(net "PVDD_33_S5_ADC_MAM")
	)
	(segment
		(start 233.724196 -326.41413)
		(end 232.926636 -327.21169)
		(width 0.10668)
		(layer "F.Cu")
		(net "PVDD_33_S5_ADC_MAM")
	)
	(segment
		(start 242.7859 -323.342)
		(end 239.154462 -323.342)
		(width 0.10668)
		(layer "F.Cu")
		(net "PVDD_33_S5_ADC_MAM")
	)
	(segment
		(start 243.2939 -322.834)
		(end 242.7859 -323.342)
		(width 0.10668)
		(layer "F.Cu")
		(net "PVDD_33_S5_ADC_MAM")
	)
	(segment
		(start 239.154462 -323.342)
		(end 236.082332 -326.41413)
		(width 0.10668)
		(layer "F.Cu")
		(net "PVDD_33_S5_ADC_MAM")
	)
	(via
		(at 232.926636 -327.21169)
		(size 0.508)
		(drill 0.254)
		(layers "F.Cu" "B.Cu")
		(net "PVDD_33_S5_ADC_MAM")
	)
	(via
		(at 245.025926 -322.834)
		(size 0.508)
		(drill 0.254)
		(layers "F.Cu" "B.Cu")
		(net "PVDD_33_S5_ADC_MAM")
	)
	(segment
		(start 245.213632 -322.834)
		(end 245.025926 -322.834)
		(width 0.10668)
		(layer "B.Cu")
		(net "PVDD_33_S5_ADC_MAM")
	)
	(segment
		(start 247.249442 -324.026022)
		(end 246.405654 -324.026022)
		(width 0.10668)
		(layer "B.Cu")
		(net "PVDD_33_S5_ADC_MAM")
	)
	(segment
		(start 232.25125 -327.21169)
		(end 232.926636 -327.21169)
		(width 0.10668)
		(layer "B.Cu")
		(net "PVDD_33_S5_ADC_MAM")
	)
	(segment
		(start 246.405654 -324.026022)
		(end 245.213632 -322.834)
		(width 0.10668)
		(layer "B.Cu")
		(net "PVDD_33_S5_ADC_MAM")
	)
	(segment
		(start 245.025926 -322.834)
		(end 244.11305 -322.834)
		(width 0.10668)
		(layer "B.Cu")
		(net "PVDD_33_S5_ADC_MAM")
	)
	(via
		(at 236.602524 -326.41159)
		(size 0.6604)
		(drill 0.3302)
		(layers "F.Cu" "B.Cu")
		(net "PVDD_33_S5_ADC")
	)
	(segment
		(start 234.430824 -327.26122)
		(end 234.430824 -326.947022)
		(width 0.10668)
		(layer "B.Cu")
		(net "PVDD_33_S5_ADC")
	)
	(segment
		(start 234.430824 -326.595232)
		(end 234.614466 -326.41159)
		(width 0.10668)
		(layer "B.Cu")
		(net "PVDD_33_S5_ADC")
	)
	(segment
		(start 234.241086 -327.450958)
		(end 234.430824 -327.26122)
		(width 0.10668)
		(layer "B.Cu")
		(net "PVDD_33_S5_ADC")
	)
	(segment
		(start 233.110786 -327.742296)
		(end 233.402124 -327.450958)
		(width 0.10668)
		(layer "B.Cu")
		(net "PVDD_33_S5_ADC")
	)
	(segment
		(start 231.45115 -327.615042)
		(end 231.578404 -327.742296)
		(width 0.10668)
		(layer "B.Cu")
		(net "PVDD_33_S5_ADC")
	)
	(segment
		(start 237.23854 -326.41159)
		(end 237.510574 -326.683624)
		(width 0.10668)
		(layer "B.Cu")
		(net "PVDD_33_S5_ADC")
	)
	(segment
		(start 233.402124 -327.450958)
		(end 234.241086 -327.450958)
		(width 0.10668)
		(layer "B.Cu")
		(net "PVDD_33_S5_ADC")
	)
	(segment
		(start 234.430824 -326.947022)
		(end 234.430824 -326.595232)
		(width 0.10668)
		(layer "B.Cu")
		(net "PVDD_33_S5_ADC")
	)
	(segment
		(start 231.578404 -327.742296)
		(end 233.110786 -327.742296)
		(width 0.10668)
		(layer "B.Cu")
		(net "PVDD_33_S5_ADC")
	)
	(segment
		(start 234.614466 -326.41159)
		(end 236.602524 -326.41159)
		(width 0.10668)
		(layer "B.Cu")
		(net "PVDD_33_S5_ADC")
	)
	(segment
		(start 231.45115 -327.21169)
		(end 231.45115 -327.615042)
		(width 0.10668)
		(layer "B.Cu")
		(net "PVDD_33_S5_ADC")
	)
	(segment
		(start 236.602524 -326.41159)
		(end 237.23854 -326.41159)
		(width 0.10668)
		(layer "B.Cu")
		(net "PVDD_33_S5_ADC")
	)
	(via
		(at 225.208338 -329.992482)
		(size 0.6604)
		(drill 0.3302)
		(layers "F.Cu" "B.Cu")
		(net "PVDD18_S5_P1_ADC_TIC")
	)
	(segment
		(start 225.208338 -328.80935)
		(end 225.208338 -329.992482)
		(width 0.10668)
		(layer "B.Cu")
		(net "PVDD18_S5_P1_ADC_TIC")
	)
	(segment
		(start 227.726748 -329.992482)
		(end 228.020372 -329.698858)
		(width 0.10668)
		(layer "B.Cu")
		(net "PVDD18_S5_P1_ADC_TIC")
	)
	(segment
		(start 225.208338 -329.992482)
		(end 227.726748 -329.992482)
		(width 0.10668)
		(layer "B.Cu")
		(net "PVDD18_S5_P1_ADC_TIC")
	)
	(segment
		(start 228.553518 -329.165712)
		(end 228.020372 -329.698858)
		(width 0.10668)
		(layer "B.Cu")
		(net "PVDD18_S5_P1_ADC_TIC")
	)
	(segment
		(start 230.429562 -329.165712)
		(end 228.553518 -329.165712)
		(width 0.10668)
		(layer "B.Cu")
		(net "PVDD18_S5_P1_ADC_TIC")
	)
	(segment
		(start 230.628952 -329.365102)
		(end 230.429562 -329.165712)
		(width 0.10668)
		(layer "B.Cu")
		(net "PVDD18_S5_P1_ADC_TIC")
	)
	(segment
		(start 233.268012 -329.729084)
		(end 238.789718 -329.729084)
		(width 0.10668)
		(layer "F.Cu")
		(net "PVDD18_S5_P1_ADC_MAM")
	)
	(segment
		(start 239.84331 -326.575166)
		(end 241.044476 -325.374)
		(width 0.10668)
		(layer "F.Cu")
		(net "PVDD18_S5_P1_ADC_MAM")
	)
	(segment
		(start 238.789718 -329.729084)
		(end 239.84331 -328.675492)
		(width 0.10668)
		(layer "F.Cu")
		(net "PVDD18_S5_P1_ADC_MAM")
	)
	(segment
		(start 239.84331 -328.675492)
		(end 239.84331 -326.575166)
		(width 0.10668)
		(layer "F.Cu")
		(net "PVDD18_S5_P1_ADC_MAM")
	)
	(segment
		(start 241.044476 -325.374)
		(end 244.750844 -325.374)
		(width 0.10668)
		(layer "F.Cu")
		(net "PVDD18_S5_P1_ADC_MAM")
	)
	(segment
		(start 232.90403 -329.365102)
		(end 233.268012 -329.729084)
		(width 0.10668)
		(layer "F.Cu")
		(net "PVDD18_S5_P1_ADC_MAM")
	)
	(segment
		(start 244.750844 -325.374)
		(end 245.476014 -324.64883)
		(width 0.10668)
		(layer "F.Cu")
		(net "PVDD18_S5_P1_ADC_MAM")
	)
	(via
		(at 245.476014 -324.64883)
		(size 0.508)
		(drill 0.254)
		(layers "F.Cu" "B.Cu")
		(net "PVDD18_S5_P1_ADC_MAM")
	)
	(via
		(at 239.84331 -326.575166)
		(size 0.762)
		(drill 0.381)
		(layers "F.Cu" "B.Cu")
		(net "PVDD18_S5_P1_ADC_MAM")
	)
	(via
		(at 232.90403 -329.365102)
		(size 0.508)
		(drill 0.254)
		(layers "F.Cu" "B.Cu")
		(net "PVDD18_S5_P1_ADC_MAM")
	)
	(segment
		(start 245.476014 -324.64883)
		(end 244.862858 -324.64883)
		(width 0.10668)
		(layer "B.Cu")
		(net "PVDD18_S5_P1_ADC_MAM")
	)
	(segment
		(start 244.645688 -324.866)
		(end 244.11305 -324.866)
		(width 0.10668)
		(layer "B.Cu")
		(net "PVDD18_S5_P1_ADC_MAM")
	)
	(segment
		(start 232.229152 -329.365102)
		(end 232.90403 -329.365102)
		(width 0.10668)
		(layer "B.Cu")
		(net "PVDD18_S5_P1_ADC_MAM")
	)
	(segment
		(start 247.249442 -325.296022)
		(end 246.30761 -325.296022)
		(width 0.10668)
		(layer "B.Cu")
		(net "PVDD18_S5_P1_ADC_MAM")
	)
	(segment
		(start 244.862858 -324.64883)
		(end 244.645688 -324.866)
		(width 0.10668)
		(layer "B.Cu")
		(net "PVDD18_S5_P1_ADC_MAM")
	)
	(segment
		(start 245.660418 -324.64883)
		(end 245.476014 -324.64883)
		(width 0.10668)
		(layer "B.Cu")
		(net "PVDD18_S5_P1_ADC_MAM")
	)
	(segment
		(start 246.30761 -325.296022)
		(end 245.660418 -324.64883)
		(width 0.10668)
		(layer "B.Cu")
		(net "PVDD18_S5_P1_ADC_MAM")
	)
	(via
		(at 236.653832 -328.674476)
		(size 0.6604)
		(drill 0.3302)
		(layers "F.Cu" "B.Cu")
		(net "PVDD18_S5_P1_ADC")
	)
	(via
		(at 233.625136 -329.433936)
		(size 0.6604)
		(drill 0.3302)
		(layers "F.Cu" "B.Cu")
		(net "PVDD18_S5_P1_ADC")
	)
	(segment
		(start 231.606344 -329.877674)
		(end 233.181398 -329.877674)
		(width 0.10668)
		(layer "B.Cu")
		(net "PVDD18_S5_P1_ADC")
	)
	(segment
		(start 236.653832 -328.674476)
		(end 236.70387 -328.724514)
		(width 0.10668)
		(layer "B.Cu")
		(net "PVDD18_S5_P1_ADC")
	)
	(segment
		(start 233.625136 -329.433936)
		(end 233.885994 -329.173078)
		(width 0.10668)
		(layer "B.Cu")
		(net "PVDD18_S5_P1_ADC")
	)
	(segment
		(start 231.429052 -329.365102)
		(end 231.429052 -329.700382)
		(width 0.10668)
		(layer "B.Cu")
		(net "PVDD18_S5_P1_ADC")
	)
	(segment
		(start 234.444794 -329.173078)
		(end 234.943396 -328.674476)
		(width 0.10668)
		(layer "B.Cu")
		(net "PVDD18_S5_P1_ADC")
	)
	(segment
		(start 236.70387 -328.724514)
		(end 237.48111 -328.724514)
		(width 0.10668)
		(layer "B.Cu")
		(net "PVDD18_S5_P1_ADC")
	)
	(segment
		(start 234.943396 -328.674476)
		(end 236.653832 -328.674476)
		(width 0.10668)
		(layer "B.Cu")
		(net "PVDD18_S5_P1_ADC")
	)
	(segment
		(start 233.181398 -329.877674)
		(end 233.625136 -329.433936)
		(width 0.10668)
		(layer "B.Cu")
		(net "PVDD18_S5_P1_ADC")
	)
	(segment
		(start 231.429052 -329.700382)
		(end 231.606344 -329.877674)
		(width 0.10668)
		(layer "B.Cu")
		(net "PVDD18_S5_P1_ADC")
	)
	(segment
		(start 233.885994 -329.173078)
		(end 234.444794 -329.173078)
		(width 0.10668)
		(layer "B.Cu")
		(net "PVDD18_S5_P1_ADC")
	)
	(via
		(at 226.950524 -329.336146)
		(size 0.6604)
		(drill 0.3302)
		(layers "F.Cu" "B.Cu")
		(net "PVDD18_S5_P0_ADC_TIC")
	)
	(segment
		(start 226.109784 -328.159364)
		(end 226.950524 -329.000104)
		(width 0.10668)
		(layer "B.Cu")
		(net "PVDD18_S5_P0_ADC_TIC")
	)
	(segment
		(start 226.950524 -329.336146)
		(end 227.312982 -329.336146)
		(width 0.10668)
		(layer "B.Cu")
		(net "PVDD18_S5_P0_ADC_TIC")
	)
	(segment
		(start 230.480108 -328.097896)
		(end 228.551232 -328.097896)
		(width 0.10668)
		(layer "B.Cu")
		(net "PVDD18_S5_P0_ADC_TIC")
	)
	(segment
		(start 227.312982 -329.336146)
		(end 228.010466 -328.638662)
		(width 0.10668)
		(layer "B.Cu")
		(net "PVDD18_S5_P0_ADC_TIC")
	)
	(segment
		(start 230.634032 -328.25182)
		(end 230.480108 -328.097896)
		(width 0.10668)
		(layer "B.Cu")
		(net "PVDD18_S5_P0_ADC_TIC")
	)
	(segment
		(start 228.551232 -328.097896)
		(end 228.010466 -328.638662)
		(width 0.10668)
		(layer "B.Cu")
		(net "PVDD18_S5_P0_ADC_TIC")
	)
	(segment
		(start 225.208338 -328.159364)
		(end 226.109784 -328.159364)
		(width 0.10668)
		(layer "B.Cu")
		(net "PVDD18_S5_P0_ADC_TIC")
	)
	(segment
		(start 226.950524 -329.000104)
		(end 226.950524 -329.336146)
		(width 0.10668)
		(layer "B.Cu")
		(net "PVDD18_S5_P0_ADC_TIC")
	)
	(segment
		(start 238.53902 -325.011542)
		(end 236.028484 -327.522078)
		(width 0.10668)
		(layer "F.Cu")
		(net "PVDD18_S5_P0_ADC_MAM")
	)
	(segment
		(start 244.729 -323.85)
		(end 244.221 -324.358)
		(width 0.10668)
		(layer "F.Cu")
		(net "PVDD18_S5_P0_ADC_MAM")
	)
	(segment
		(start 236.028484 -327.522078)
		(end 233.621072 -327.522078)
		(width 0.10668)
		(layer "F.Cu")
		(net "PVDD18_S5_P0_ADC_MAM")
	)
	(segment
		(start 238.53902 -324.428866)
		(end 238.53902 -325.011542)
		(width 0.10668)
		(layer "F.Cu")
		(net "PVDD18_S5_P0_ADC_MAM")
	)
	(segment
		(start 241.680746 -324.358)
		(end 241.294666 -323.97192)
		(width 0.10668)
		(layer "F.Cu")
		(net "PVDD18_S5_P0_ADC_MAM")
	)
	(segment
		(start 238.995966 -323.97192)
		(end 238.53902 -324.428866)
		(width 0.10668)
		(layer "F.Cu")
		(net "PVDD18_S5_P0_ADC_MAM")
	)
	(segment
		(start 244.221 -324.358)
		(end 241.680746 -324.358)
		(width 0.10668)
		(layer "F.Cu")
		(net "PVDD18_S5_P0_ADC_MAM")
	)
	(segment
		(start 241.294666 -323.97192)
		(end 238.995966 -323.97192)
		(width 0.10668)
		(layer "F.Cu")
		(net "PVDD18_S5_P0_ADC_MAM")
	)
	(segment
		(start 233.621072 -327.522078)
		(end 232.89133 -328.25182)
		(width 0.10668)
		(layer "F.Cu")
		(net "PVDD18_S5_P0_ADC_MAM")
	)
	(via
		(at 244.729 -323.85)
		(size 0.762)
		(drill 0.254)
		(layers "F.Cu" "B.Cu")
		(net "PVDD18_S5_P0_ADC_MAM")
	)
	(via
		(at 248.444004 -322.206112)
		(size 0.6604)
		(drill 0.3302)
		(layers "F.Cu" "B.Cu")
		(net "PVDD18_S5_P0_ADC_MAM")
	)
	(via
		(at 232.89133 -328.25182)
		(size 0.508)
		(drill 0.254)
		(layers "F.Cu" "B.Cu")
		(net "PVDD18_S5_P0_ADC_MAM")
	)
	(segment
		(start 246.399558 -324.661022)
		(end 247.249442 -324.661022)
		(width 0.10668)
		(layer "B.Cu")
		(net "PVDD18_S5_P0_ADC_MAM")
	)
	(segment
		(start 247.249442 -324.661022)
		(end 248.314972 -324.661022)
		(width 0.10668)
		(layer "B.Cu")
		(net "PVDD18_S5_P0_ADC_MAM")
	)
	(segment
		(start 245.588536 -323.85)
		(end 246.399558 -324.661022)
		(width 0.10668)
		(layer "B.Cu")
		(net "PVDD18_S5_P0_ADC_MAM")
	)
	(segment
		(start 248.314972 -324.661022)
		(end 248.444004 -324.53199)
		(width 0.10668)
		(layer "B.Cu")
		(net "PVDD18_S5_P0_ADC_MAM")
	)
	(segment
		(start 232.234232 -328.25182)
		(end 232.89133 -328.25182)
		(width 0.10668)
		(layer "B.Cu")
		(net "PVDD18_S5_P0_ADC_MAM")
	)
	(segment
		(start 248.444004 -324.53199)
		(end 248.444004 -322.206112)
		(width 0.10668)
		(layer "B.Cu")
		(net "PVDD18_S5_P0_ADC_MAM")
	)
	(segment
		(start 244.11305 -323.85)
		(end 244.729 -323.85)
		(width 0.10668)
		(layer "B.Cu")
		(net "PVDD18_S5_P0_ADC_MAM")
	)
	(segment
		(start 244.729 -323.85)
		(end 245.588536 -323.85)
		(width 0.10668)
		(layer "B.Cu")
		(net "PVDD18_S5_P0_ADC_MAM")
	)
	(via
		(at 233.609134 -328.085704)
		(size 0.6604)
		(drill 0.3302)
		(layers "F.Cu" "B.Cu")
		(net "PVDD18_S5_P0_ADC")
	)
	(segment
		(start 233.609134 -328.085704)
		(end 234.425236 -328.085704)
		(width 0.10668)
		(layer "B.Cu")
		(net "PVDD18_S5_P0_ADC")
	)
	(segment
		(start 234.425236 -328.085704)
		(end 234.954064 -327.556876)
		(width 0.10668)
		(layer "B.Cu")
		(net "PVDD18_S5_P0_ADC")
	)
	(segment
		(start 231.561386 -328.782426)
		(end 233.362754 -328.782426)
		(width 0.10668)
		(layer "B.Cu")
		(net "PVDD18_S5_P0_ADC")
	)
	(segment
		(start 237.359698 -327.556876)
		(end 237.50143 -327.698608)
		(width 0.10668)
		(layer "B.Cu")
		(net "PVDD18_S5_P0_ADC")
	)
	(segment
		(start 234.954064 -327.556876)
		(end 237.359698 -327.556876)
		(width 0.10668)
		(layer "B.Cu")
		(net "PVDD18_S5_P0_ADC")
	)
	(segment
		(start 233.609134 -328.536046)
		(end 233.609134 -328.085704)
		(width 0.10668)
		(layer "B.Cu")
		(net "PVDD18_S5_P0_ADC")
	)
	(segment
		(start 231.434132 -328.25182)
		(end 231.434132 -328.655172)
		(width 0.10668)
		(layer "B.Cu")
		(net "PVDD18_S5_P0_ADC")
	)
	(segment
		(start 231.434132 -328.655172)
		(end 231.561386 -328.782426)
		(width 0.10668)
		(layer "B.Cu")
		(net "PVDD18_S5_P0_ADC")
	)
	(segment
		(start 233.362754 -328.782426)
		(end 233.609134 -328.536046)
		(width 0.10668)
		(layer "B.Cu")
		(net "PVDD18_S5_P0_ADC")
	)
	(via
		(at 225.08083 -322.79209)
		(size 0.6604)
		(drill 0.3302)
		(layers "F.Cu" "B.Cu")
		(net "P5V_AUX_ADC_TIC")
	)
	(segment
		(start 225.08083 -323.266054)
		(end 225.208338 -323.393562)
		(width 0.10668)
		(layer "B.Cu")
		(net "P5V_AUX_ADC_TIC")
	)
	(segment
		(start 230.384858 -321.446398)
		(end 228.413056 -321.446398)
		(width 0.10668)
		(layer "B.Cu")
		(net "P5V_AUX_ADC_TIC")
	)
	(segment
		(start 230.714042 -321.775582)
		(end 230.384858 -321.446398)
		(width 0.10668)
		(layer "B.Cu")
		(net "P5V_AUX_ADC_TIC")
	)
	(segment
		(start 228.094032 -322.17868)
		(end 227.794312 -322.17868)
		(width 0.10668)
		(layer "B.Cu")
		(net "P5V_AUX_ADC_TIC")
	)
	(segment
		(start 225.08083 -322.79209)
		(end 225.08083 -323.266054)
		(width 0.10668)
		(layer "B.Cu")
		(net "P5V_AUX_ADC_TIC")
	)
	(segment
		(start 225.765614 -321.590924)
		(end 225.08083 -322.275708)
		(width 0.10668)
		(layer "B.Cu")
		(net "P5V_AUX_ADC_TIC")
	)
	(segment
		(start 227.206556 -321.590924)
		(end 225.765614 -321.590924)
		(width 0.10668)
		(layer "B.Cu")
		(net "P5V_AUX_ADC_TIC")
	)
	(segment
		(start 225.208338 -323.393562)
		(end 225.208338 -324.259194)
		(width 0.10668)
		(layer "B.Cu")
		(net "P5V_AUX_ADC_TIC")
	)
	(segment
		(start 228.413056 -321.446398)
		(end 228.094032 -321.765422)
		(width 0.10668)
		(layer "B.Cu")
		(net "P5V_AUX_ADC_TIC")
	)
	(segment
		(start 227.794312 -322.17868)
		(end 227.206556 -321.590924)
		(width 0.10668)
		(layer "B.Cu")
		(net "P5V_AUX_ADC_TIC")
	)
	(segment
		(start 225.08083 -322.275708)
		(end 225.08083 -322.79209)
		(width 0.10668)
		(layer "B.Cu")
		(net "P5V_AUX_ADC_TIC")
	)
	(segment
		(start 228.094032 -321.765422)
		(end 228.094032 -322.17868)
		(width 0.10668)
		(layer "B.Cu")
		(net "P5V_AUX_ADC_TIC")
	)
	(via
		(at 248.492772 -320.834512)
		(size 0.508)
		(drill 0.254)
		(layers "F.Cu" "B.Cu")
		(net "P5V_AUX_ADC_MAM")
	)
	(via
		(at 232.946448 -321.6402)
		(size 0.508)
		(drill 0.254)
		(layers "F.Cu" "B.Cu")
		(net "P5V_AUX_ADC_MAM")
	)
	(via
		(at 255.561592 -326.007222)
		(size 0.6604)
		(drill 0.3302)
		(layers "F.Cu" "B.Cu")
		(net "P5V_AUX_ADC_MAM")
	)
	(segment
		(start 255.561592 -325.26097)
		(end 255.561592 -326.007222)
		(width 0.10668)
		(layer "B.Cu")
		(net "P5V_AUX_ADC_MAM")
	)
	(segment
		(start 255.357376 -325.056754)
		(end 255.341628 -325.041006)
		(width 0.10668)
		(layer "B.Cu")
		(net "P5V_AUX_ADC_MAM")
	)
	(segment
		(start 255.357376 -325.056754)
		(end 255.561592 -325.26097)
		(width 0.10668)
		(layer "B.Cu")
		(net "P5V_AUX_ADC_MAM")
	)
	(segment
		(start 252.559566 -325.296022)
		(end 250.801886 -325.296022)
		(width 0.10668)
		(layer "B.Cu")
		(net "P5V_AUX_ADC_MAM")
	)
	(segment
		(start 250.801886 -325.296022)
		(end 248.996962 -323.491098)
		(width 0.10668)
		(layer "B.Cu")
		(net "P5V_AUX_ADC_MAM")
	)
	(segment
		(start 255.341628 -325.041006)
		(end 253.853188 -325.041006)
		(width 0.10668)
		(layer "B.Cu")
		(net "P5V_AUX_ADC_MAM")
	)
	(segment
		(start 232.314242 -321.775582)
		(end 232.811066 -321.775582)
		(width 0.10668)
		(layer "B.Cu")
		(net "P5V_AUX_ADC_MAM")
	)
	(segment
		(start 253.598172 -325.296022)
		(end 252.559566 -325.296022)
		(width 0.10668)
		(layer "B.Cu")
		(net "P5V_AUX_ADC_MAM")
	)
	(segment
		(start 248.996962 -321.338702)
		(end 248.492772 -320.834512)
		(width 0.10668)
		(layer "B.Cu")
		(net "P5V_AUX_ADC_MAM")
	)
	(segment
		(start 253.853188 -325.041006)
		(end 253.598172 -325.296022)
		(width 0.10668)
		(layer "B.Cu")
		(net "P5V_AUX_ADC_MAM")
	)
	(segment
		(start 232.811066 -321.775582)
		(end 232.946448 -321.6402)
		(width 0.10668)
		(layer "B.Cu")
		(net "P5V_AUX_ADC_MAM")
	)
	(segment
		(start 248.996962 -323.491098)
		(end 248.996962 -321.338702)
		(width 0.10668)
		(layer "B.Cu")
		(net "P5V_AUX_ADC_MAM")
	)
	(segment
		(start 232.946448 -321.6402)
		(end 234.093004 -320.493644)
		(width 0.11684)
		(layer "In2.Cu")
		(net "P5V_AUX_ADC_MAM")
	)
	(segment
		(start 248.151904 -320.493644)
		(end 248.492772 -320.834512)
		(width 0.11684)
		(layer "In2.Cu")
		(net "P5V_AUX_ADC_MAM")
	)
	(segment
		(start 234.093004 -320.493644)
		(end 248.151904 -320.493644)
		(width 0.11684)
		(layer "In2.Cu")
		(net "P5V_AUX_ADC_MAM")
	)
	(via
		(at 233.601514 -322.18376)
		(size 0.6604)
		(drill 0.3302)
		(layers "F.Cu" "B.Cu")
		(net "P5V_AUX_ADC")
	)
	(segment
		(start 237.183422 -321.149472)
		(end 237.505494 -321.471544)
		(width 0.10668)
		(layer "B.Cu")
		(net "P5V_AUX_ADC")
	)
	(segment
		(start 233.601514 -321.779138)
		(end 233.728514 -321.652138)
		(width 0.10668)
		(layer "B.Cu")
		(net "P5V_AUX_ADC")
	)
	(segment
		(start 233.728514 -321.652138)
		(end 234.385866 -321.652138)
		(width 0.10668)
		(layer "B.Cu")
		(net "P5V_AUX_ADC")
	)
	(segment
		(start 231.514142 -321.775582)
		(end 231.514142 -322.222622)
		(width 0.10668)
		(layer "B.Cu")
		(net "P5V_AUX_ADC")
	)
	(segment
		(start 234.512866 -321.149472)
		(end 237.183422 -321.149472)
		(width 0.10668)
		(layer "B.Cu")
		(net "P5V_AUX_ADC")
	)
	(segment
		(start 234.385866 -321.276472)
		(end 234.512866 -321.149472)
		(width 0.10668)
		(layer "B.Cu")
		(net "P5V_AUX_ADC")
	)
	(segment
		(start 233.455972 -322.329302)
		(end 233.601514 -322.18376)
		(width 0.10668)
		(layer "B.Cu")
		(net "P5V_AUX_ADC")
	)
	(segment
		(start 234.385866 -321.652138)
		(end 234.385866 -321.276472)
		(width 0.10668)
		(layer "B.Cu")
		(net "P5V_AUX_ADC")
	)
	(segment
		(start 231.514142 -322.222622)
		(end 231.620822 -322.329302)
		(width 0.10668)
		(layer "B.Cu")
		(net "P5V_AUX_ADC")
	)
	(segment
		(start 233.601514 -322.18376)
		(end 233.601514 -321.779138)
		(width 0.10668)
		(layer "B.Cu")
		(net "P5V_AUX_ADC")
	)
	(segment
		(start 231.620822 -322.329302)
		(end 233.455972 -322.329302)
		(width 0.10668)
		(layer "B.Cu")
		(net "P5V_AUX_ADC")
	)
	(via
		(at 247.495314 -328.954892)
		(size 0.6604)
		(drill 0.3302)
		(layers "F.Cu" "B.Cu")
		(net "P3V3_MAX11617_2_VDD")
	)
	(via
		(at 227.04425 -326.724264)
		(size 0.6604)
		(drill 0.3302)
		(layers "F.Cu" "B.Cu")
		(net "P1V8_CPU1_RT_1D_ADC_TIC")
	)
	(segment
		(start 228.602286 -325.979536)
		(end 228.085142 -326.49668)
		(width 0.10668)
		(layer "B.Cu")
		(net "P1V8_CPU1_RT_1D_ADC_TIC")
	)
	(segment
		(start 228.085142 -326.49668)
		(end 227.271834 -326.49668)
		(width 0.10668)
		(layer "B.Cu")
		(net "P1V8_CPU1_RT_1D_ADC_TIC")
	)
	(segment
		(start 226.909122 -326.859392)
		(end 227.04425 -326.724264)
		(width 0.10668)
		(layer "B.Cu")
		(net "P1V8_CPU1_RT_1D_ADC_TIC")
	)
	(segment
		(start 225.208338 -326.859392)
		(end 226.909122 -326.859392)
		(width 0.10668)
		(layer "B.Cu")
		(net "P1V8_CPU1_RT_1D_ADC_TIC")
	)
	(segment
		(start 230.672386 -326.07885)
		(end 230.573072 -325.979536)
		(width 0.10668)
		(layer "B.Cu")
		(net "P1V8_CPU1_RT_1D_ADC_TIC")
	)
	(segment
		(start 227.271834 -326.49668)
		(end 227.04425 -326.724264)
		(width 0.10668)
		(layer "B.Cu")
		(net "P1V8_CPU1_RT_1D_ADC_TIC")
	)
	(segment
		(start 230.573072 -325.979536)
		(end 228.602286 -325.979536)
		(width 0.10668)
		(layer "B.Cu")
		(net "P1V8_CPU1_RT_1D_ADC_TIC")
	)
	(segment
		(start 233.736642 -325.346822)
		(end 236.09681 -325.346822)
		(width 0.10668)
		(layer "F.Cu")
		(net "P1V8_CPU1_RT_1D_ADC_MAM")
	)
	(segment
		(start 236.09681 -325.346822)
		(end 238.393732 -323.0499)
		(width 0.10668)
		(layer "F.Cu")
		(net "P1V8_CPU1_RT_1D_ADC_MAM")
	)
	(segment
		(start 238.393732 -323.0499)
		(end 241.564922 -323.0499)
		(width 0.10668)
		(layer "F.Cu")
		(net "P1V8_CPU1_RT_1D_ADC_MAM")
	)
	(segment
		(start 233.004614 -326.07885)
		(end 233.736642 -325.346822)
		(width 0.10668)
		(layer "F.Cu")
		(net "P1V8_CPU1_RT_1D_ADC_MAM")
	)
	(segment
		(start 242.288822 -322.326)
		(end 244.348 -322.326)
		(width 0.10668)
		(layer "F.Cu")
		(net "P1V8_CPU1_RT_1D_ADC_MAM")
	)
	(segment
		(start 241.564922 -323.0499)
		(end 242.288822 -322.326)
		(width 0.10668)
		(layer "F.Cu")
		(net "P1V8_CPU1_RT_1D_ADC_MAM")
	)
	(segment
		(start 244.348 -322.326)
		(end 244.856 -321.818)
		(width 0.10668)
		(layer "F.Cu")
		(net "P1V8_CPU1_RT_1D_ADC_MAM")
	)
	(via
		(at 244.856 -321.818)
		(size 0.508)
		(drill 0.254)
		(layers "F.Cu" "B.Cu")
		(net "P1V8_CPU1_RT_1D_ADC_MAM")
	)
	(via
		(at 233.004614 -326.07885)
		(size 0.508)
		(drill 0.254)
		(layers "F.Cu" "B.Cu")
		(net "P1V8_CPU1_RT_1D_ADC_MAM")
	)
	(via
		(at 246.081042 -321.818)
		(size 0.6604)
		(drill 0.3302)
		(layers "F.Cu" "B.Cu")
		(net "P1V8_CPU1_RT_1D_ADC_MAM")
	)
	(segment
		(start 246.15013 -321.887088)
		(end 246.15013 -323.264022)
		(width 0.10668)
		(layer "B.Cu")
		(net "P1V8_CPU1_RT_1D_ADC_MAM")
	)
	(segment
		(start 244.856 -321.818)
		(end 246.081042 -321.818)
		(width 0.10668)
		(layer "B.Cu")
		(net "P1V8_CPU1_RT_1D_ADC_MAM")
	)
	(segment
		(start 246.27713 -323.391022)
		(end 247.249442 -323.391022)
		(width 0.10668)
		(layer "B.Cu")
		(net "P1V8_CPU1_RT_1D_ADC_MAM")
	)
	(segment
		(start 246.15013 -323.264022)
		(end 246.27713 -323.391022)
		(width 0.10668)
		(layer "B.Cu")
		(net "P1V8_CPU1_RT_1D_ADC_MAM")
	)
	(segment
		(start 244.11305 -321.818)
		(end 244.856 -321.818)
		(width 0.10668)
		(layer "B.Cu")
		(net "P1V8_CPU1_RT_1D_ADC_MAM")
	)
	(segment
		(start 246.081042 -321.818)
		(end 246.15013 -321.887088)
		(width 0.10668)
		(layer "B.Cu")
		(net "P1V8_CPU1_RT_1D_ADC_MAM")
	)
	(segment
		(start 232.272586 -326.07885)
		(end 233.004614 -326.07885)
		(width 0.10668)
		(layer "B.Cu")
		(net "P1V8_CPU1_RT_1D_ADC_MAM")
	)
	(via
		(at 233.458512 -326.632062)
		(size 0.6604)
		(drill 0.3302)
		(layers "F.Cu" "B.Cu")
		(net "P1V8_CPU1_RT_1D_ADC")
	)
	(segment
		(start 233.458512 -326.632062)
		(end 233.6673 -326.632062)
		(width 0.10668)
		(layer "B.Cu")
		(net "P1V8_CPU1_RT_1D_ADC")
	)
	(segment
		(start 233.6673 -326.632062)
		(end 234.40517 -325.894192)
		(width 0.10668)
		(layer "B.Cu")
		(net "P1V8_CPU1_RT_1D_ADC")
	)
	(segment
		(start 231.579166 -326.632062)
		(end 233.458512 -326.632062)
		(width 0.10668)
		(layer "B.Cu")
		(net "P1V8_CPU1_RT_1D_ADC")
	)
	(segment
		(start 237.15345 -325.305166)
		(end 237.505494 -325.65721)
		(width 0.10668)
		(layer "B.Cu")
		(net "P1V8_CPU1_RT_1D_ADC")
	)
	(segment
		(start 234.40517 -325.894192)
		(end 234.994196 -325.305166)
		(width 0.10668)
		(layer "B.Cu")
		(net "P1V8_CPU1_RT_1D_ADC")
	)
	(segment
		(start 234.994196 -325.305166)
		(end 237.15345 -325.305166)
		(width 0.10668)
		(layer "B.Cu")
		(net "P1V8_CPU1_RT_1D_ADC")
	)
	(segment
		(start 231.472486 -326.525382)
		(end 231.579166 -326.632062)
		(width 0.10668)
		(layer "B.Cu")
		(net "P1V8_CPU1_RT_1D_ADC")
	)
	(segment
		(start 231.472486 -326.07885)
		(end 231.472486 -326.525382)
		(width 0.10668)
		(layer "B.Cu")
		(net "P1V8_CPU1_RT_1D_ADC")
	)
	(via
		(at 227.04425 -325.428864)
		(size 0.6604)
		(drill 0.3302)
		(layers "F.Cu" "B.Cu")
		(net "P1V8_CPU0_RT_1D_ADC_TIC")
	)
	(segment
		(start 226.708462 -326.209152)
		(end 226.876864 -326.04075)
		(width 0.10668)
		(layer "B.Cu")
		(net "P1V8_CPU0_RT_1D_ADC_TIC")
	)
	(segment
		(start 228.073458 -325.425562)
		(end 227.047552 -325.425562)
		(width 0.10668)
		(layer "B.Cu")
		(net "P1V8_CPU0_RT_1D_ADC_TIC")
	)
	(segment
		(start 225.208338 -326.209152)
		(end 226.708462 -326.209152)
		(width 0.10668)
		(layer "B.Cu")
		(net "P1V8_CPU0_RT_1D_ADC_TIC")
	)
	(segment
		(start 227.047552 -325.425562)
		(end 227.04425 -325.428864)
		(width 0.10668)
		(layer "B.Cu")
		(net "P1V8_CPU0_RT_1D_ADC_TIC")
	)
	(segment
		(start 228.585014 -324.914006)
		(end 228.073458 -325.425562)
		(width 0.10668)
		(layer "B.Cu")
		(net "P1V8_CPU0_RT_1D_ADC_TIC")
	)
	(segment
		(start 230.682546 -324.980554)
		(end 230.615998 -324.914006)
		(width 0.10668)
		(layer "B.Cu")
		(net "P1V8_CPU0_RT_1D_ADC_TIC")
	)
	(segment
		(start 230.615998 -324.914006)
		(end 228.585014 -324.914006)
		(width 0.10668)
		(layer "B.Cu")
		(net "P1V8_CPU0_RT_1D_ADC_TIC")
	)
	(segment
		(start 226.876864 -326.04075)
		(end 226.876864 -325.59625)
		(width 0.10668)
		(layer "B.Cu")
		(net "P1V8_CPU0_RT_1D_ADC_TIC")
	)
	(segment
		(start 226.876864 -325.59625)
		(end 227.04425 -325.428864)
		(width 0.10668)
		(layer "B.Cu")
		(net "P1V8_CPU0_RT_1D_ADC_TIC")
	)
	(via
		(at 232.958132 -324.980554)
		(size 0.508)
		(drill 0.254)
		(layers "F.Cu" "B.Cu")
		(net "P1V8_CPU0_RT_1D_ADC_MAM")
	)
	(via
		(at 251.013468 -323.391022)
		(size 0.762)
		(drill 0.254)
		(layers "F.Cu" "B.Cu")
		(net "P1V8_CPU0_RT_1D_ADC_MAM")
	)
	(segment
		(start 252.559566 -323.391022)
		(end 252.559566 -322.32727)
		(width 0.10668)
		(layer "B.Cu")
		(net "P1V8_CPU0_RT_1D_ADC_MAM")
	)
	(segment
		(start 232.282746 -324.980554)
		(end 232.958132 -324.980554)
		(width 0.10668)
		(layer "B.Cu")
		(net "P1V8_CPU0_RT_1D_ADC_MAM")
	)
	(segment
		(start 252.550676 -322.31838)
		(end 252.550676 -321.850004)
		(width 0.10668)
		(layer "B.Cu")
		(net "P1V8_CPU0_RT_1D_ADC_MAM")
	)
	(segment
		(start 252.559566 -323.391022)
		(end 251.013468 -323.391022)
		(width 0.10668)
		(layer "B.Cu")
		(net "P1V8_CPU0_RT_1D_ADC_MAM")
	)
	(segment
		(start 252.559566 -322.32727)
		(end 252.550676 -322.31838)
		(width 0.10668)
		(layer "B.Cu")
		(net "P1V8_CPU0_RT_1D_ADC_MAM")
	)
	(segment
		(start 238.064548 -324.253606)
		(end 238.211106 -324.107048)
		(width 0.11684)
		(layer "In2.Cu")
		(net "P1V8_CPU0_RT_1D_ADC_MAM")
	)
	(segment
		(start 235.092494 -324.253606)
		(end 238.064548 -324.253606)
		(width 0.11684)
		(layer "In2.Cu")
		(net "P1V8_CPU0_RT_1D_ADC_MAM")
	)
	(segment
		(start 234.365546 -324.980554)
		(end 235.092494 -324.253606)
		(width 0.11684)
		(layer "In2.Cu")
		(net "P1V8_CPU0_RT_1D_ADC_MAM")
	)
	(segment
		(start 238.211106 -324.107048)
		(end 239.099598 -324.107048)
		(width 0.11684)
		(layer "In2.Cu")
		(net "P1V8_CPU0_RT_1D_ADC_MAM")
	)
	(segment
		(start 232.958132 -324.980554)
		(end 234.365546 -324.980554)
		(width 0.11684)
		(layer "In2.Cu")
		(net "P1V8_CPU0_RT_1D_ADC_MAM")
	)
	(segment
		(start 250.964446 -323.342)
		(end 251.013468 -323.391022)
		(width 0.11684)
		(layer "In2.Cu")
		(net "P1V8_CPU0_RT_1D_ADC_MAM")
	)
	(segment
		(start 239.099598 -324.107048)
		(end 239.864646 -323.342)
		(width 0.11684)
		(layer "In2.Cu")
		(net "P1V8_CPU0_RT_1D_ADC_MAM")
	)
	(segment
		(start 239.864646 -323.342)
		(end 250.964446 -323.342)
		(width 0.11684)
		(layer "In2.Cu")
		(net "P1V8_CPU0_RT_1D_ADC_MAM")
	)
	(via
		(at 236.546136 -324.317614)
		(size 0.6604)
		(drill 0.3302)
		(layers "F.Cu" "B.Cu")
		(net "P1V8_CPU0_RT_1D_ADC")
	)
	(segment
		(start 231.482646 -325.392796)
		(end 231.589326 -325.499476)
		(width 0.10668)
		(layer "B.Cu")
		(net "P1V8_CPU0_RT_1D_ADC")
	)
	(segment
		(start 237.20806 -324.317614)
		(end 237.517432 -324.626986)
		(width 0.10668)
		(layer "B.Cu")
		(net "P1V8_CPU0_RT_1D_ADC")
	)
	(segment
		(start 234.919266 -324.317614)
		(end 236.546136 -324.317614)
		(width 0.10668)
		(layer "B.Cu")
		(net "P1V8_CPU0_RT_1D_ADC")
	)
	(segment
		(start 231.589326 -325.499476)
		(end 233.737404 -325.499476)
		(width 0.10668)
		(layer "B.Cu")
		(net "P1V8_CPU0_RT_1D_ADC")
	)
	(segment
		(start 234.443778 -324.793102)
		(end 234.919266 -324.317614)
		(width 0.10668)
		(layer "B.Cu")
		(net "P1V8_CPU0_RT_1D_ADC")
	)
	(segment
		(start 231.482646 -324.980554)
		(end 231.482646 -325.392796)
		(width 0.10668)
		(layer "B.Cu")
		(net "P1V8_CPU0_RT_1D_ADC")
	)
	(segment
		(start 233.737404 -325.499476)
		(end 234.443778 -324.793102)
		(width 0.10668)
		(layer "B.Cu")
		(net "P1V8_CPU0_RT_1D_ADC")
	)
	(segment
		(start 236.546136 -324.317614)
		(end 237.20806 -324.317614)
		(width 0.10668)
		(layer "B.Cu")
		(net "P1V8_CPU0_RT_1D_ADC")
	)
	(via
		(at 226.751896 -322.711064)
		(size 0.6604)
		(drill 0.3302)
		(layers "F.Cu" "B.Cu")
		(net "P1V8_AUX_ADC_TIC")
	)
	(segment
		(start 227.180902 -322.71462)
		(end 227.73005 -323.263768)
		(width 0.10668)
		(layer "B.Cu")
		(net "P1V8_AUX_ADC_TIC")
	)
	(segment
		(start 227.73005 -323.263768)
		(end 228.105208 -323.263768)
		(width 0.10668)
		(layer "B.Cu")
		(net "P1V8_AUX_ADC_TIC")
	)
	(segment
		(start 226.755452 -322.71462)
		(end 227.180902 -322.71462)
		(width 0.10668)
		(layer "B.Cu")
		(net "P1V8_AUX_ADC_TIC")
	)
	(segment
		(start 225.208338 -324.90918)
		(end 226.134422 -324.90918)
		(width 0.10668)
		(layer "B.Cu")
		(net "P1V8_AUX_ADC_TIC")
	)
	(segment
		(start 226.302062 -324.74154)
		(end 226.302062 -323.161406)
		(width 0.10668)
		(layer "B.Cu")
		(net "P1V8_AUX_ADC_TIC")
	)
	(segment
		(start 226.134422 -324.90918)
		(end 226.302062 -324.74154)
		(width 0.10668)
		(layer "B.Cu")
		(net "P1V8_AUX_ADC_TIC")
	)
	(segment
		(start 226.751896 -322.711064)
		(end 226.755452 -322.71462)
		(width 0.10668)
		(layer "B.Cu")
		(net "P1V8_AUX_ADC_TIC")
	)
	(segment
		(start 228.147118 -323.263768)
		(end 228.105208 -323.263768)
		(width 0.10668)
		(layer "B.Cu")
		(net "P1V8_AUX_ADC_TIC")
	)
	(segment
		(start 226.302062 -323.161406)
		(end 226.751896 -322.711572)
		(width 0.10668)
		(layer "B.Cu")
		(net "P1V8_AUX_ADC_TIC")
	)
	(segment
		(start 226.751896 -322.711572)
		(end 226.751896 -322.711064)
		(width 0.10668)
		(layer "B.Cu")
		(net "P1V8_AUX_ADC_TIC")
	)
	(segment
		(start 228.682804 -322.728082)
		(end 228.147118 -323.263768)
		(width 0.10668)
		(layer "B.Cu")
		(net "P1V8_AUX_ADC_TIC")
	)
	(segment
		(start 230.63073 -322.728082)
		(end 228.682804 -322.728082)
		(width 0.10668)
		(layer "B.Cu")
		(net "P1V8_AUX_ADC_TIC")
	)
	(segment
		(start 230.742998 -322.84035)
		(end 230.63073 -322.728082)
		(width 0.10668)
		(layer "B.Cu")
		(net "P1V8_AUX_ADC_TIC")
	)
	(via
		(at 233.018584 -322.84035)
		(size 0.508)
		(drill 0.254)
		(layers "F.Cu" "B.Cu")
		(net "P1V8_AUX_ADC_MAM")
	)
	(via
		(at 249.59691 -321.430396)
		(size 0.508)
		(drill 0.254)
		(layers "F.Cu" "B.Cu")
		(net "P1V8_AUX_ADC_MAM")
	)
	(segment
		(start 232.343198 -322.84035)
		(end 233.018584 -322.84035)
		(width 0.10668)
		(layer "B.Cu")
		(net "P1V8_AUX_ADC_MAM")
	)
	(segment
		(start 255.123696 -324.053962)
		(end 255.132586 -324.045072)
		(width 0.10668)
		(layer "B.Cu")
		(net "P1V8_AUX_ADC_MAM")
	)
	(segment
		(start 254.139192 -324.661022)
		(end 254.746252 -324.053962)
		(width 0.10668)
		(layer "B.Cu")
		(net "P1V8_AUX_ADC_MAM")
	)
	(segment
		(start 252.559566 -324.661022)
		(end 254.139192 -324.661022)
		(width 0.10668)
		(layer "B.Cu")
		(net "P1V8_AUX_ADC_MAM")
	)
	(segment
		(start 255.132586 -324.045072)
		(end 255.33731 -324.045072)
		(width 0.10668)
		(layer "B.Cu")
		(net "P1V8_AUX_ADC_MAM")
	)
	(segment
		(start 249.59691 -323.375274)
		(end 249.59691 -321.430396)
		(width 0.10668)
		(layer "B.Cu")
		(net "P1V8_AUX_ADC_MAM")
	)
	(segment
		(start 254.746252 -324.053962)
		(end 255.123696 -324.053962)
		(width 0.10668)
		(layer "B.Cu")
		(net "P1V8_AUX_ADC_MAM")
	)
	(segment
		(start 250.882658 -324.661022)
		(end 249.59691 -323.375274)
		(width 0.10668)
		(layer "B.Cu")
		(net "P1V8_AUX_ADC_MAM")
	)
	(segment
		(start 252.559566 -324.661022)
		(end 250.882658 -324.661022)
		(width 0.10668)
		(layer "B.Cu")
		(net "P1V8_AUX_ADC_MAM")
	)
	(segment
		(start 248.012458 -321.430396)
		(end 249.59691 -321.430396)
		(width 0.11684)
		(layer "In2.Cu")
		(net "P1V8_AUX_ADC_MAM")
	)
	(segment
		(start 247.518174 -320.936112)
		(end 248.012458 -321.430396)
		(width 0.11684)
		(layer "In2.Cu")
		(net "P1V8_AUX_ADC_MAM")
	)
	(segment
		(start 234.922822 -320.936112)
		(end 247.518174 -320.936112)
		(width 0.11684)
		(layer "In2.Cu")
		(net "P1V8_AUX_ADC_MAM")
	)
	(segment
		(start 233.018584 -322.84035)
		(end 234.922822 -320.936112)
		(width 0.11684)
		(layer "In2.Cu")
		(net "P1V8_AUX_ADC_MAM")
	)
	(via
		(at 236.49559 -322.199)
		(size 0.6604)
		(drill 0.3302)
		(layers "F.Cu" "B.Cu")
		(net "P1V8_AUX_ADC")
	)
	(segment
		(start 234.908598 -322.199)
		(end 236.49559 -322.199)
		(width 0.10668)
		(layer "B.Cu")
		(net "P1V8_AUX_ADC")
	)
	(segment
		(start 236.49559 -322.199)
		(end 237.184438 -322.199)
		(width 0.10668)
		(layer "B.Cu")
		(net "P1V8_AUX_ADC")
	)
	(segment
		(start 231.649778 -323.320918)
		(end 233.78668 -323.320918)
		(width 0.10668)
		(layer "B.Cu")
		(net "P1V8_AUX_ADC")
	)
	(segment
		(start 233.78668 -323.320918)
		(end 234.423966 -322.683632)
		(width 0.10668)
		(layer "B.Cu")
		(net "P1V8_AUX_ADC")
	)
	(segment
		(start 231.543098 -322.84035)
		(end 231.543098 -323.214238)
		(width 0.10668)
		(layer "B.Cu")
		(net "P1V8_AUX_ADC")
	)
	(segment
		(start 237.184438 -322.199)
		(end 237.496604 -322.511166)
		(width 0.10668)
		(layer "B.Cu")
		(net "P1V8_AUX_ADC")
	)
	(segment
		(start 234.423966 -322.683632)
		(end 234.908598 -322.199)
		(width 0.10668)
		(layer "B.Cu")
		(net "P1V8_AUX_ADC")
	)
	(segment
		(start 231.543098 -323.214238)
		(end 231.649778 -323.320918)
		(width 0.10668)
		(layer "B.Cu")
		(net "P1V8_AUX_ADC")
	)
	(via
		(at 227.04425 -324.133464)
		(size 0.6604)
		(drill 0.3302)
		(layers "F.Cu" "B.Cu")
		(net "P1V2_AUX_ADC_TIC")
	)
	(segment
		(start 230.616252 -323.855334)
		(end 228.580188 -323.855334)
		(width 0.10668)
		(layer "B.Cu")
		(net "P1V2_AUX_ADC_TIC")
	)
	(segment
		(start 228.08565 -324.349872)
		(end 227.717858 -324.349872)
		(width 0.10668)
		(layer "B.Cu")
		(net "P1V2_AUX_ADC_TIC")
	)
	(segment
		(start 230.674672 -323.913754)
		(end 230.616252 -323.855334)
		(width 0.10668)
		(layer "B.Cu")
		(net "P1V2_AUX_ADC_TIC")
	)
	(segment
		(start 228.580188 -323.855334)
		(end 228.08565 -324.349872)
		(width 0.10668)
		(layer "B.Cu")
		(net "P1V2_AUX_ADC_TIC")
	)
	(segment
		(start 227.50145 -324.133464)
		(end 227.04425 -324.133464)
		(width 0.10668)
		(layer "B.Cu")
		(net "P1V2_AUX_ADC_TIC")
	)
	(segment
		(start 226.124262 -325.559166)
		(end 227.04425 -324.639178)
		(width 0.10668)
		(layer "B.Cu")
		(net "P1V2_AUX_ADC_TIC")
	)
	(segment
		(start 225.208338 -325.559166)
		(end 226.124262 -325.559166)
		(width 0.10668)
		(layer "B.Cu")
		(net "P1V2_AUX_ADC_TIC")
	)
	(segment
		(start 227.04425 -324.639178)
		(end 227.04425 -324.133464)
		(width 0.10668)
		(layer "B.Cu")
		(net "P1V2_AUX_ADC_TIC")
	)
	(segment
		(start 227.717858 -324.349872)
		(end 227.50145 -324.133464)
		(width 0.10668)
		(layer "B.Cu")
		(net "P1V2_AUX_ADC_TIC")
	)
	(via
		(at 250.290584 -322.111116)
		(size 0.508)
		(drill 0.254)
		(layers "F.Cu" "B.Cu")
		(net "P1V2_AUX_ADC_MAM")
	)
	(via
		(at 254.52197 -323.26326)
		(size 0.6604)
		(drill 0.3302)
		(layers "F.Cu" "B.Cu")
		(net "P1V2_AUX_ADC_MAM")
	)
	(via
		(at 232.950258 -323.913754)
		(size 0.508)
		(drill 0.254)
		(layers "F.Cu" "B.Cu")
		(net "P1V2_AUX_ADC_MAM")
	)
	(segment
		(start 232.274872 -323.913754)
		(end 232.950258 -323.913754)
		(width 0.10668)
		(layer "B.Cu")
		(net "P1V2_AUX_ADC_MAM")
	)
	(segment
		(start 252.559566 -324.026022)
		(end 250.926092 -324.026022)
		(width 0.10668)
		(layer "B.Cu")
		(net "P1V2_AUX_ADC_MAM")
	)
	(segment
		(start 250.290584 -323.390514)
		(end 250.290584 -322.111116)
		(width 0.10668)
		(layer "B.Cu")
		(net "P1V2_AUX_ADC_MAM")
	)
	(segment
		(start 253.759208 -324.026022)
		(end 254.52197 -323.26326)
		(width 0.10668)
		(layer "B.Cu")
		(net "P1V2_AUX_ADC_MAM")
	)
	(segment
		(start 254.762508 -323.022722)
		(end 254.52197 -323.26326)
		(width 0.10668)
		(layer "B.Cu")
		(net "P1V2_AUX_ADC_MAM")
	)
	(segment
		(start 250.926092 -324.026022)
		(end 250.290584 -323.390514)
		(width 0.10668)
		(layer "B.Cu")
		(net "P1V2_AUX_ADC_MAM")
	)
	(segment
		(start 252.559566 -324.026022)
		(end 253.759208 -324.026022)
		(width 0.10668)
		(layer "B.Cu")
		(net "P1V2_AUX_ADC_MAM")
	)
	(segment
		(start 255.344676 -323.022722)
		(end 254.762508 -323.022722)
		(width 0.10668)
		(layer "B.Cu")
		(net "P1V2_AUX_ADC_MAM")
	)
	(segment
		(start 250.290584 -322.111116)
		(end 250.0757 -322.326)
		(width 0.11684)
		(layer "In2.Cu")
		(net "P1V2_AUX_ADC_MAM")
	)
	(segment
		(start 240.078768 -322.326)
		(end 239.18799 -323.216778)
		(width 0.11684)
		(layer "In2.Cu")
		(net "P1V2_AUX_ADC_MAM")
	)
	(segment
		(start 239.18799 -323.216778)
		(end 234.905042 -323.216778)
		(width 0.11684)
		(layer "In2.Cu")
		(net "P1V2_AUX_ADC_MAM")
	)
	(segment
		(start 234.905042 -323.216778)
		(end 234.208066 -323.913754)
		(width 0.11684)
		(layer "In2.Cu")
		(net "P1V2_AUX_ADC_MAM")
	)
	(segment
		(start 250.0757 -322.326)
		(end 240.078768 -322.326)
		(width 0.11684)
		(layer "In2.Cu")
		(net "P1V2_AUX_ADC_MAM")
	)
	(segment
		(start 234.208066 -323.913754)
		(end 232.950258 -323.913754)
		(width 0.11684)
		(layer "In2.Cu")
		(net "P1V2_AUX_ADC_MAM")
	)
	(via
		(at 233.61015 -324.195948)
		(size 0.6604)
		(drill 0.3302)
		(layers "F.Cu" "B.Cu")
		(net "P1V2_AUX_ADC")
	)
	(segment
		(start 234.41152 -323.746114)
		(end 234.877356 -323.280278)
		(width 0.10668)
		(layer "B.Cu")
		(net "P1V2_AUX_ADC")
	)
	(segment
		(start 231.474772 -323.913754)
		(end 231.474772 -324.311772)
		(width 0.10668)
		(layer "B.Cu")
		(net "P1V2_AUX_ADC")
	)
	(segment
		(start 233.375708 -324.43039)
		(end 233.61015 -324.195948)
		(width 0.10668)
		(layer "B.Cu")
		(net "P1V2_AUX_ADC")
	)
	(segment
		(start 231.474772 -324.311772)
		(end 231.59339 -324.43039)
		(width 0.10668)
		(layer "B.Cu")
		(net "P1V2_AUX_ADC")
	)
	(segment
		(start 231.59339 -324.43039)
		(end 233.375708 -324.43039)
		(width 0.10668)
		(layer "B.Cu")
		(net "P1V2_AUX_ADC")
	)
	(segment
		(start 234.877356 -323.280278)
		(end 237.218474 -323.280278)
		(width 0.10668)
		(layer "B.Cu")
		(net "P1V2_AUX_ADC")
	)
	(segment
		(start 234.059984 -323.746114)
		(end 234.41152 -323.746114)
		(width 0.10668)
		(layer "B.Cu")
		(net "P1V2_AUX_ADC")
	)
	(segment
		(start 233.61015 -324.195948)
		(end 234.059984 -323.746114)
		(width 0.10668)
		(layer "B.Cu")
		(net "P1V2_AUX_ADC")
	)
	(segment
		(start 237.218474 -323.280278)
		(end 237.523528 -323.585332)
		(width 0.10668)
		(layer "B.Cu")
		(net "P1V2_AUX_ADC")
	)
	(segment
		(start 69.057774 -18.932144)
		(end 69.00037 -18.932144)
		(width 0.3556)
		(layer "F.Cu")
		(net "P12V_OCP_V3_2_R")
	)
	(segment
		(start 69.00037 -18.932144)
		(end 68.54444 -18.476214)
		(width 0.3556)
		(layer "F.Cu")
		(net "P12V_OCP_V3_2_R")
	)
	(via
		(at 64.088264 -12.43711)
		(size 0.508)
		(drill 0.254)
		(layers "F.Cu" "B.Cu")
		(net "P12V_OCP_V3_2_R")
	)
	(via
		(at 66.933064 -13.09751)
		(size 0.508)
		(drill 0.254)
		(layers "F.Cu" "B.Cu")
		(net "P12V_OCP_V3_2_R")
	)
	(via
		(at 68.54444 -18.476214)
		(size 0.508)
		(drill 0.254)
		(layers "F.Cu" "B.Cu")
		(net "P12V_OCP_V3_2_R")
	)
	(via
		(at 65.866264 -12.43711)
		(size 0.508)
		(drill 0.254)
		(layers "F.Cu" "B.Cu")
		(net "P12V_OCP_V3_2_R")
	)
	(via
		(at 66.501264 -12.43711)
		(size 0.508)
		(drill 0.254)
		(layers "F.Cu" "B.Cu")
		(net "P12V_OCP_V3_2_R")
	)
	(via
		(at 68.07073 -17.359376)
		(size 0.6604)
		(drill 0.3302)
		(layers "F.Cu" "B.Cu")
		(net "P12V_OCP_V3_2_R")
	)
	(via
		(at 65.409064 -13.09751)
		(size 0.508)
		(drill 0.254)
		(layers "F.Cu" "B.Cu")
		(net "P12V_OCP_V3_2_R")
	)
	(via
		(at 66.298064 -13.09751)
		(size 0.508)
		(drill 0.254)
		(layers "F.Cu" "B.Cu")
		(net "P12V_OCP_V3_2_R")
	)
	(via
		(at 64.520064 -13.09751)
		(size 0.508)
		(drill 0.254)
		(layers "F.Cu" "B.Cu")
		(net "P12V_OCP_V3_2_R")
	)
	(via
		(at 64.977264 -12.43711)
		(size 0.508)
		(drill 0.254)
		(layers "F.Cu" "B.Cu")
		(net "P12V_OCP_V3_2_R")
	)
	(via
		(at 63.631064 -13.09751)
		(size 0.508)
		(drill 0.254)
		(layers "F.Cu" "B.Cu")
		(net "P12V_OCP_V3_2_R")
	)
	(via
		(at 63.199264 -12.43711)
		(size 0.508)
		(drill 0.254)
		(layers "F.Cu" "B.Cu")
		(net "P12V_OCP_V3_2_R")
	)
	(via
		(at 68.054474 -15.0495)
		(size 0.6604)
		(drill 0.3302)
		(layers "F.Cu" "B.Cu")
		(net "P12V_OCP_V3_2_R")
	)
	(via
		(at 67.40271 -12.489434)
		(size 0.508)
		(drill 0.254)
		(layers "F.Cu" "B.Cu")
		(net "P12V_OCP_V3_2_R")
	)
	(segment
		(start 100.05695 -77.216)
		(end 98.86696 -77.216)
		(width 0.10668)
		(layer "F.Cu")
		(net "P12V_OCP_V3_2_PLD_R_PWRGD")
	)
	(segment
		(start 97.110042 -77.15504)
		(end 98.806 -77.15504)
		(width 0.10668)
		(layer "F.Cu")
		(net "P12V_OCP_V3_2_PLD_R_PWRGD")
	)
	(segment
		(start 98.86696 -77.216)
		(end 98.806 -77.15504)
		(width 0.10668)
		(layer "F.Cu")
		(net "P12V_OCP_V3_2_PLD_R_PWRGD")
	)
	(via
		(at 98.806 -77.15504)
		(size 0.762)
		(drill 0.381)
		(layers "F.Cu" "B.Cu")
		(net "P12V_OCP_V3_2_PLD_R_PWRGD")
	)
	(segment
		(start 101.96195 -77.83195)
		(end 102.362 -78.232)
		(width 0.10668)
		(layer "F.Cu")
		(net "P12V_OCP_V3_2_PLD_PWRGD")
	)
	(segment
		(start 102.362 -78.232)
		(end 106.582718 -78.232)
		(width 0.10668)
		(layer "F.Cu")
		(net "P12V_OCP_V3_2_PLD_PWRGD")
	)
	(segment
		(start 101.96195 -77.216)
		(end 101.96195 -77.83195)
		(width 0.10668)
		(layer "F.Cu")
		(net "P12V_OCP_V3_2_PLD_PWRGD")
	)
	(segment
		(start 100.85705 -77.216)
		(end 101.96195 -77.216)
		(width 0.10668)
		(layer "F.Cu")
		(net "P12V_OCP_V3_2_PLD_PWRGD")
	)
	(via
		(at 106.582718 -78.232)
		(size 0.508)
		(drill 0.254)
		(layers "F.Cu" "B.Cu")
		(net "P12V_OCP_V3_2_PLD_PWRGD")
	)
	(via
		(at 159.48152 -115.64874)
		(size 0.508)
		(drill 0.254)
		(layers "F.Cu" "B.Cu")
		(net "P12V_OCP_V3_2_PLD_PWRGD")
	)
	(segment
		(start 160.3756 -116.54282)
		(end 162.55873 -116.54282)
		(width 0.10668)
		(layer "B.Cu")
		(net "P12V_OCP_V3_2_PLD_PWRGD")
	)
	(segment
		(start 162.55873 -116.54282)
		(end 163.34613 -117.33022)
		(width 0.10668)
		(layer "B.Cu")
		(net "P12V_OCP_V3_2_PLD_PWRGD")
	)
	(segment
		(start 159.48152 -115.64874)
		(end 160.3756 -116.54282)
		(width 0.10668)
		(layer "B.Cu")
		(net "P12V_OCP_V3_2_PLD_PWRGD")
	)
	(segment
		(start 152.386284 -105.245916)
		(end 151.08936 -106.54284)
		(width 0.11684)
		(layer "In11.Cu")
		(net "P12V_OCP_V3_2_PLD_PWRGD")
	)
	(segment
		(start 114.632994 -85.81644)
		(end 107.048554 -78.232)
		(width 0.11684)
		(layer "In11.Cu")
		(net "P12V_OCP_V3_2_PLD_PWRGD")
	)
	(segment
		(start 159.48152 -115.64874)
		(end 159.117538 -115.284758)
		(width 0.11684)
		(layer "In11.Cu")
		(net "P12V_OCP_V3_2_PLD_PWRGD")
	)
	(segment
		(start 151.08936 -106.54284)
		(end 149.30628 -106.54284)
		(width 0.11684)
		(layer "In11.Cu")
		(net "P12V_OCP_V3_2_PLD_PWRGD")
	)
	(segment
		(start 131.14274 -91.1606)
		(end 125.79858 -85.81644)
		(width 0.11684)
		(layer "In11.Cu")
		(net "P12V_OCP_V3_2_PLD_PWRGD")
	)
	(segment
		(start 159.117538 -115.284758)
		(end 159.117538 -109.981238)
		(width 0.11684)
		(layer "In11.Cu")
		(net "P12V_OCP_V3_2_PLD_PWRGD")
	)
	(segment
		(start 135.10514 -104.2289)
		(end 131.14274 -100.2665)
		(width 0.11684)
		(layer "In11.Cu")
		(net "P12V_OCP_V3_2_PLD_PWRGD")
	)
	(segment
		(start 144.01038 -104.2289)
		(end 135.10514 -104.2289)
		(width 0.11684)
		(layer "In11.Cu")
		(net "P12V_OCP_V3_2_PLD_PWRGD")
	)
	(segment
		(start 159.117538 -109.981238)
		(end 154.382216 -105.245916)
		(width 0.11684)
		(layer "In11.Cu")
		(net "P12V_OCP_V3_2_PLD_PWRGD")
	)
	(segment
		(start 131.14274 -100.2665)
		(end 131.14274 -91.1606)
		(width 0.11684)
		(layer "In11.Cu")
		(net "P12V_OCP_V3_2_PLD_PWRGD")
	)
	(segment
		(start 148.75002 -105.98658)
		(end 145.76806 -105.98658)
		(width 0.11684)
		(layer "In11.Cu")
		(net "P12V_OCP_V3_2_PLD_PWRGD")
	)
	(segment
		(start 107.048554 -78.232)
		(end 106.582718 -78.232)
		(width 0.11684)
		(layer "In11.Cu")
		(net "P12V_OCP_V3_2_PLD_PWRGD")
	)
	(segment
		(start 125.79858 -85.81644)
		(end 114.632994 -85.81644)
		(width 0.11684)
		(layer "In11.Cu")
		(net "P12V_OCP_V3_2_PLD_PWRGD")
	)
	(segment
		(start 154.382216 -105.245916)
		(end 152.386284 -105.245916)
		(width 0.11684)
		(layer "In11.Cu")
		(net "P12V_OCP_V3_2_PLD_PWRGD")
	)
	(segment
		(start 149.30628 -106.54284)
		(end 148.75002 -105.98658)
		(width 0.11684)
		(layer "In11.Cu")
		(net "P12V_OCP_V3_2_PLD_PWRGD")
	)
	(segment
		(start 145.76806 -105.98658)
		(end 144.01038 -104.2289)
		(width 0.11684)
		(layer "In11.Cu")
		(net "P12V_OCP_V3_2_PLD_PWRGD")
	)
	(segment
		(start 50.160936 -40.181276)
		(end 50.160936 -39.774114)
		(width 0.10668)
		(layer "F.Cu")
		(net "P12V_OCP_V3_2_EN_R3")
	)
	(segment
		(start 50.18405 -40.20439)
		(end 50.160936 -40.181276)
		(width 0.10668)
		(layer "F.Cu")
		(net "P12V_OCP_V3_2_EN_R3")
	)
	(segment
		(start 49.672494 -41.261284)
		(end 50.18405 -40.749728)
		(width 0.10668)
		(layer "F.Cu")
		(net "P12V_OCP_V3_2_EN_R3")
	)
	(segment
		(start 50.18405 -39.751)
		(end 50.25009 -39.68496)
		(width 0.10668)
		(layer "F.Cu")
		(net "P12V_OCP_V3_2_EN_R3")
	)
	(segment
		(start 50.160936 -39.774114)
		(end 50.18405 -39.751)
		(width 0.10668)
		(layer "F.Cu")
		(net "P12V_OCP_V3_2_EN_R3")
	)
	(segment
		(start 49.672494 -41.99255)
		(end 49.672494 -41.261284)
		(width 0.10668)
		(layer "F.Cu")
		(net "P12V_OCP_V3_2_EN_R3")
	)
	(segment
		(start 50.25009 -39.68496)
		(end 51.505104 -39.68496)
		(width 0.10668)
		(layer "F.Cu")
		(net "P12V_OCP_V3_2_EN_R3")
	)
	(segment
		(start 50.18405 -40.749728)
		(end 50.18405 -40.20439)
		(width 0.10668)
		(layer "F.Cu")
		(net "P12V_OCP_V3_2_EN_R3")
	)
	(via
		(at 50.18405 -40.749728)
		(size 0.762)
		(drill 0.381)
		(layers "F.Cu" "B.Cu")
		(net "P12V_OCP_V3_2_EN_R3")
	)
	(segment
		(start 58.89498 -34.84753)
		(end 59.254136 -34.84753)
		(width 0.10668)
		(layer "F.Cu")
		(net "P12V_OCP_V3_2_BUF_EN_R")
	)
	(segment
		(start 69.265292 -34.874708)
		(end 71.064882 -33.075118)
		(width 0.10668)
		(layer "F.Cu")
		(net "P12V_OCP_V3_2_BUF_EN_R")
	)
	(segment
		(start 78.29296 -37.6174)
		(end 76.0984 -35.42284)
		(width 0.10668)
		(layer "F.Cu")
		(net "P12V_OCP_V3_2_BUF_EN_R")
	)
	(segment
		(start 76.0984 -35.42284)
		(end 74.4347 -35.42284)
		(width 0.10668)
		(layer "F.Cu")
		(net "P12V_OCP_V3_2_BUF_EN_R")
	)
	(segment
		(start 72.34936 -33.3375)
		(end 72.34936 -32.69996)
		(width 0.10668)
		(layer "F.Cu")
		(net "P12V_OCP_V3_2_BUF_EN_R")
	)
	(segment
		(start 156.82468 -30.38856)
		(end 153.61666 -33.59658)
		(width 0.10668)
		(layer "F.Cu")
		(net "P12V_OCP_V3_2_BUF_EN_R")
	)
	(segment
		(start 57.258458 -37.7825)
		(end 57.258458 -36.75634)
		(width 0.10668)
		(layer "F.Cu")
		(net "P12V_OCP_V3_2_BUF_EN_R")
	)
	(segment
		(start 68.625212 -34.874708)
		(end 69.265292 -34.874708)
		(width 0.10668)
		(layer "F.Cu")
		(net "P12V_OCP_V3_2_BUF_EN_R")
	)
	(segment
		(start 153.61666 -33.59658)
		(end 153.24963 -33.59658)
		(width 0.10668)
		(layer "F.Cu")
		(net "P12V_OCP_V3_2_BUF_EN_R")
	)
	(segment
		(start 57.258458 -36.75634)
		(end 57.258458 -36.484052)
		(width 0.10668)
		(layer "F.Cu")
		(net "P12V_OCP_V3_2_BUF_EN_R")
	)
	(segment
		(start 57.258458 -38.344602)
		(end 57.17286 -38.4302)
		(width 0.10668)
		(layer "F.Cu")
		(net "P12V_OCP_V3_2_BUF_EN_R")
	)
	(segment
		(start 74.4347 -35.42284)
		(end 72.34936 -33.3375)
		(width 0.10668)
		(layer "F.Cu")
		(net "P12V_OCP_V3_2_BUF_EN_R")
	)
	(segment
		(start 57.258458 -37.7825)
		(end 57.258458 -38.344602)
		(width 0.10668)
		(layer "F.Cu")
		(net "P12V_OCP_V3_2_BUF_EN_R")
	)
	(segment
		(start 71.064882 -33.075118)
		(end 71.064882 -32.294322)
		(width 0.10668)
		(layer "F.Cu")
		(net "P12V_OCP_V3_2_BUF_EN_R")
	)
	(segment
		(start 71.943722 -32.294322)
		(end 71.064882 -32.294322)
		(width 0.10668)
		(layer "F.Cu")
		(net "P12V_OCP_V3_2_BUF_EN_R")
	)
	(segment
		(start 57.258458 -36.484052)
		(end 58.89498 -34.84753)
		(width 0.10668)
		(layer "F.Cu")
		(net "P12V_OCP_V3_2_BUF_EN_R")
	)
	(segment
		(start 57.17286 -38.4302)
		(end 57.17286 -38.96233)
		(width 0.10668)
		(layer "F.Cu")
		(net "P12V_OCP_V3_2_BUF_EN_R")
	)
	(segment
		(start 68.625212 -35.641788)
		(end 68.625212 -34.874708)
		(width 0.10668)
		(layer "F.Cu")
		(net "P12V_OCP_V3_2_BUF_EN_R")
	)
	(segment
		(start 72.34936 -32.69996)
		(end 71.943722 -32.294322)
		(width 0.10668)
		(layer "F.Cu")
		(net "P12V_OCP_V3_2_BUF_EN_R")
	)
	(via
		(at 68.625212 -35.641788)
		(size 0.508)
		(drill 0.254)
		(layers "F.Cu" "B.Cu")
		(net "P12V_OCP_V3_2_BUF_EN_R")
	)
	(via
		(at 156.82468 -30.38856)
		(size 0.508)
		(drill 0.254)
		(layers "F.Cu" "B.Cu")
		(net "P12V_OCP_V3_2_BUF_EN_R")
	)
	(via
		(at 59.254136 -34.84753)
		(size 0.508)
		(drill 0.254)
		(layers "F.Cu" "B.Cu")
		(net "P12V_OCP_V3_2_BUF_EN_R")
	)
	(via
		(at 126.46279 -13.03401)
		(size 0.508)
		(drill 0.254)
		(layers "F.Cu" "B.Cu")
		(net "P12V_OCP_V3_2_BUF_EN_R")
	)
	(via
		(at 78.29296 -37.6174)
		(size 0.508)
		(drill 0.254)
		(layers "F.Cu" "B.Cu")
		(net "P12V_OCP_V3_2_BUF_EN_R")
	)
	(segment
		(start 68.035424 -36.231576)
		(end 68.625212 -35.641788)
		(width 0.11684)
		(layer "In6.Cu")
		(net "P12V_OCP_V3_2_BUF_EN_R")
	)
	(segment
		(start 143.8148 -17.65046)
		(end 143.8148 -21.21154)
		(width 0.11684)
		(layer "In6.Cu")
		(net "P12V_OCP_V3_2_BUF_EN_R")
	)
	(segment
		(start 61.720984 -34.62528)
		(end 63.164466 -36.068762)
		(width 0.11684)
		(layer "In6.Cu")
		(net "P12V_OCP_V3_2_BUF_EN_R")
	)
	(segment
		(start 129.90068 -16.4719)
		(end 142.63624 -16.4719)
		(width 0.11684)
		(layer "In6.Cu")
		(net "P12V_OCP_V3_2_BUF_EN_R")
	)
	(segment
		(start 126.46279 -13.03401)
		(end 129.90068 -16.4719)
		(width 0.11684)
		(layer "In6.Cu")
		(net "P12V_OCP_V3_2_BUF_EN_R")
	)
	(segment
		(start 63.164466 -36.068762)
		(end 64.978026 -36.068762)
		(width 0.11684)
		(layer "In6.Cu")
		(net "P12V_OCP_V3_2_BUF_EN_R")
	)
	(segment
		(start 64.978026 -36.068762)
		(end 65.14084 -36.231576)
		(width 0.11684)
		(layer "In6.Cu")
		(net "P12V_OCP_V3_2_BUF_EN_R")
	)
	(segment
		(start 146.03222 -23.42896)
		(end 147.2819 -23.42896)
		(width 0.11684)
		(layer "In6.Cu")
		(net "P12V_OCP_V3_2_BUF_EN_R")
	)
	(segment
		(start 147.2819 -23.42896)
		(end 148.18995 -24.33701)
		(width 0.11684)
		(layer "In6.Cu")
		(net "P12V_OCP_V3_2_BUF_EN_R")
	)
	(segment
		(start 143.8148 -21.21154)
		(end 146.03222 -23.42896)
		(width 0.11684)
		(layer "In6.Cu")
		(net "P12V_OCP_V3_2_BUF_EN_R")
	)
	(segment
		(start 59.476386 -34.62528)
		(end 61.720984 -34.62528)
		(width 0.11684)
		(layer "In6.Cu")
		(net "P12V_OCP_V3_2_BUF_EN_R")
	)
	(segment
		(start 142.63624 -16.4719)
		(end 143.8148 -17.65046)
		(width 0.11684)
		(layer "In6.Cu")
		(net "P12V_OCP_V3_2_BUF_EN_R")
	)
	(segment
		(start 65.14084 -36.231576)
		(end 68.035424 -36.231576)
		(width 0.11684)
		(layer "In6.Cu")
		(net "P12V_OCP_V3_2_BUF_EN_R")
	)
	(segment
		(start 59.254136 -34.84753)
		(end 59.476386 -34.62528)
		(width 0.11684)
		(layer "In6.Cu")
		(net "P12V_OCP_V3_2_BUF_EN_R")
	)
	(segment
		(start 148.18995 -24.78659)
		(end 153.79192 -30.38856)
		(width 0.11684)
		(layer "In6.Cu")
		(net "P12V_OCP_V3_2_BUF_EN_R")
	)
	(segment
		(start 153.79192 -30.38856)
		(end 156.82468 -30.38856)
		(width 0.11684)
		(layer "In6.Cu")
		(net "P12V_OCP_V3_2_BUF_EN_R")
	)
	(segment
		(start 148.18995 -24.33701)
		(end 148.18995 -24.78659)
		(width 0.11684)
		(layer "In6.Cu")
		(net "P12V_OCP_V3_2_BUF_EN_R")
	)
	(segment
		(start 125.78969 -13.03401)
		(end 126.46279 -13.03401)
		(width 0.11684)
		(layer "In15.Cu")
		(net "P12V_OCP_V3_2_BUF_EN_R")
	)
	(segment
		(start 84.09686 -14.3256)
		(end 85.25256 -13.1699)
		(width 0.11684)
		(layer "In15.Cu")
		(net "P12V_OCP_V3_2_BUF_EN_R")
	)
	(segment
		(start 84.09686 -30.29204)
		(end 84.09686 -14.3256)
		(width 0.11684)
		(layer "In15.Cu")
		(net "P12V_OCP_V3_2_BUF_EN_R")
	)
	(segment
		(start 125.6538 -13.1699)
		(end 125.78969 -13.03401)
		(width 0.11684)
		(layer "In15.Cu")
		(net "P12V_OCP_V3_2_BUF_EN_R")
	)
	(segment
		(start 85.25256 -13.1699)
		(end 125.6538 -13.1699)
		(width 0.11684)
		(layer "In15.Cu")
		(net "P12V_OCP_V3_2_BUF_EN_R")
	)
	(segment
		(start 78.48092 -35.90798)
		(end 84.09686 -30.29204)
		(width 0.11684)
		(layer "In15.Cu")
		(net "P12V_OCP_V3_2_BUF_EN_R")
	)
	(segment
		(start 78.29296 -37.6174)
		(end 78.48092 -37.42944)
		(width 0.11684)
		(layer "In15.Cu")
		(net "P12V_OCP_V3_2_BUF_EN_R")
	)
	(segment
		(start 78.48092 -37.42944)
		(end 78.48092 -35.90798)
		(width 0.11684)
		(layer "In15.Cu")
		(net "P12V_OCP_V3_2_BUF_EN_R")
	)
	(segment
		(start 55.817262 -37.78504)
		(end 55.474108 -37.78504)
		(width 0.10668)
		(layer "F.Cu")
		(net "P12V_OCP_V3_2_BUF_EN")
	)
	(segment
		(start 56.458358 -37.7825)
		(end 55.819802 -37.7825)
		(width 0.10668)
		(layer "F.Cu")
		(net "P12V_OCP_V3_2_BUF_EN")
	)
	(segment
		(start 53.904896 -37.78504)
		(end 55.474108 -37.78504)
		(width 0.10668)
		(layer "F.Cu")
		(net "P12V_OCP_V3_2_BUF_EN")
	)
	(segment
		(start 55.819802 -37.7825)
		(end 55.817262 -37.78504)
		(width 0.10668)
		(layer "F.Cu")
		(net "P12V_OCP_V3_2_BUF_EN")
	)
	(via
		(at 55.474108 -37.78504)
		(size 0.762)
		(drill 0.381)
		(layers "F.Cu" "B.Cu")
		(net "P12V_OCP_V3_2_BUF_EN")
	)
	(segment
		(start 20.861528 -38.69182)
		(end 20.861528 -39.012876)
		(width 0.10668)
		(layer "F.Cu")
		(net "P12V_OCP_V3_2_ADC_ALERT_R")
	)
	(segment
		(start 20.861528 -39.012876)
		(end 21.42363 -39.574978)
		(width 0.10668)
		(layer "F.Cu")
		(net "P12V_OCP_V3_2_ADC_ALERT_R")
	)
	(segment
		(start 19.641566 -37.894514)
		(end 20.064222 -37.894514)
		(width 0.10668)
		(layer "F.Cu")
		(net "P12V_OCP_V3_2_ADC_ALERT_R")
	)
	(segment
		(start 20.571714 -38.402006)
		(end 20.861528 -38.69182)
		(width 0.10668)
		(layer "F.Cu")
		(net "P12V_OCP_V3_2_ADC_ALERT_R")
	)
	(segment
		(start 20.064222 -37.894514)
		(end 20.571714 -38.402006)
		(width 0.10668)
		(layer "F.Cu")
		(net "P12V_OCP_V3_2_ADC_ALERT_R")
	)
	(segment
		(start 21.42363 -39.574978)
		(end 21.829268 -39.574978)
		(width 0.10668)
		(layer "F.Cu")
		(net "P12V_OCP_V3_2_ADC_ALERT_R")
	)
	(via
		(at 20.571714 -38.402006)
		(size 0.762)
		(drill 0.381)
		(layers "F.Cu" "B.Cu")
		(net "P12V_OCP_V3_2_ADC_ALERT_R")
	)
	(segment
		(start 202.577954 -95.872808)
		(end 203.671424 -95.872808)
		(width 0.10668)
		(layer "F.Cu")
		(net "P12V_OCP_V3_1_PLD_R_PWRGD")
	)
	(segment
		(start 203.671424 -95.872808)
		(end 203.84897 -95.695262)
		(width 0.10668)
		(layer "F.Cu")
		(net "P12V_OCP_V3_1_PLD_R_PWRGD")
	)
	(segment
		(start 203.84897 -95.695262)
		(end 204.594714 -95.695262)
		(width 0.10668)
		(layer "F.Cu")
		(net "P12V_OCP_V3_1_PLD_R_PWRGD")
	)
	(segment
		(start 204.594714 -95.695262)
		(end 204.594714 -94.782132)
		(width 0.10668)
		(layer "F.Cu")
		(net "P12V_OCP_V3_1_PLD_R_PWRGD")
	)
	(via
		(at 204.594714 -94.782132)
		(size 0.762)
		(drill 0.381)
		(layers "F.Cu" "B.Cu")
		(net "P12V_OCP_V3_1_PLD_R_PWRGD")
	)
	(segment
		(start 205.394814 -96.77908)
		(end 205.394814 -95.695262)
		(width 0.10668)
		(layer "F.Cu")
		(net "P12V_OCP_V3_1_PLD_PWRGD")
	)
	(segment
		(start 205.394814 -96.77908)
		(end 207.811878 -96.77908)
		(width 0.10668)
		(layer "F.Cu")
		(net "P12V_OCP_V3_1_PLD_PWRGD")
	)
	(segment
		(start 209.294476 -105.497376)
		(end 210.144614 -105.497376)
		(width 0.10668)
		(layer "F.Cu")
		(net "P12V_OCP_V3_1_PLD_PWRGD")
	)
	(via
		(at 210.144614 -105.497376)
		(size 0.508)
		(drill 0.254)
		(layers "F.Cu" "B.Cu")
		(net "P12V_OCP_V3_1_PLD_PWRGD")
	)
	(via
		(at 207.811878 -96.77908)
		(size 0.762)
		(drill 0.254)
		(layers "F.Cu" "B.Cu")
		(net "P12V_OCP_V3_1_PLD_PWRGD")
	)
	(segment
		(start 209.456528 -99.691952)
		(end 209.804762 -100.040186)
		(width 0.11684)
		(layer "In11.Cu")
		(net "P12V_OCP_V3_1_PLD_PWRGD")
	)
	(segment
		(start 209.804762 -100.040186)
		(end 209.804762 -102.439978)
		(width 0.11684)
		(layer "In11.Cu")
		(net "P12V_OCP_V3_1_PLD_PWRGD")
	)
	(segment
		(start 210.144614 -102.77983)
		(end 210.144614 -105.497376)
		(width 0.11684)
		(layer "In11.Cu")
		(net "P12V_OCP_V3_1_PLD_PWRGD")
	)
	(segment
		(start 209.456528 -98.42373)
		(end 209.456528 -99.691952)
		(width 0.11684)
		(layer "In11.Cu")
		(net "P12V_OCP_V3_1_PLD_PWRGD")
	)
	(segment
		(start 207.811878 -96.77908)
		(end 209.456528 -98.42373)
		(width 0.11684)
		(layer "In11.Cu")
		(net "P12V_OCP_V3_1_PLD_PWRGD")
	)
	(segment
		(start 209.804762 -102.439978)
		(end 210.144614 -102.77983)
		(width 0.11684)
		(layer "In11.Cu")
		(net "P12V_OCP_V3_1_PLD_PWRGD")
	)
	(via
		(at 441.354718 -19.21256)
		(size 0.508)
		(drill 0.254)
		(layers "F.Cu" "B.Cu")
		(net "P12V_OCP_SFF_R")
	)
	(via
		(at 439.481214 -12.400788)
		(size 0.508)
		(drill 0.254)
		(layers "F.Cu" "B.Cu")
		(net "P12V_OCP_SFF_R")
	)
	(via
		(at 439.862722 -11.430254)
		(size 0.6604)
		(drill 0.3302)
		(layers "F.Cu" "B.Cu")
		(net "P12V_OCP_SFF_R")
	)
	(via
		(at 441.475622 -13.488162)
		(size 0.508)
		(drill 0.254)
		(layers "F.Cu" "B.Cu")
		(net "P12V_OCP_SFF_R")
	)
	(via
		(at 441.475622 -14.123162)
		(size 0.508)
		(drill 0.254)
		(layers "F.Cu" "B.Cu")
		(net "P12V_OCP_SFF_R")
	)
	(via
		(at 441.928504 -10.348468)
		(size 0.6604)
		(drill 0.3302)
		(layers "F.Cu" "B.Cu")
		(net "P12V_OCP_SFF_R")
	)
	(via
		(at 441.354718 -20.73656)
		(size 0.508)
		(drill 0.254)
		(layers "F.Cu" "B.Cu")
		(net "P12V_OCP_SFF_R")
	)
	(via
		(at 438.592214 -12.400788)
		(size 0.508)
		(drill 0.254)
		(layers "F.Cu" "B.Cu")
		(net "P12V_OCP_SFF_R")
	)
	(via
		(at 438.06999 -13.069316)
		(size 0.508)
		(drill 0.254)
		(layers "F.Cu" "B.Cu")
		(net "P12V_OCP_SFF_R")
	)
	(via
		(at 440.945524 -11.261852)
		(size 0.508)
		(drill 0.254)
		(layers "F.Cu" "B.Cu")
		(net "P12V_OCP_SFF_R")
	)
	(via
		(at 441.354718 -18.57756)
		(size 0.508)
		(drill 0.254)
		(layers "F.Cu" "B.Cu")
		(net "P12V_OCP_SFF_R")
	)
	(via
		(at 441.354718 -20.10156)
		(size 0.508)
		(drill 0.254)
		(layers "F.Cu" "B.Cu")
		(net "P12V_OCP_SFF_R")
	)
	(via
		(at 441.830968 -12.438634)
		(size 0.6604)
		(drill 0.3302)
		(layers "F.Cu" "B.Cu")
		(net "P12V_OCP_SFF_R")
	)
	(via
		(at 439.39333 -13.043916)
		(size 0.508)
		(drill 0.254)
		(layers "F.Cu" "B.Cu")
		(net "P12V_OCP_SFF_R")
	)
	(via
		(at 437.703214 -12.400788)
		(size 0.508)
		(drill 0.254)
		(layers "F.Cu" "B.Cu")
		(net "P12V_OCP_SFF_R")
	)
	(via
		(at 440.945524 -10.626852)
		(size 0.508)
		(drill 0.254)
		(layers "F.Cu" "B.Cu")
		(net "P12V_OCP_SFF_R")
	)
	(via
		(at 438.71515 -13.061696)
		(size 0.508)
		(drill 0.254)
		(layers "F.Cu" "B.Cu")
		(net "P12V_OCP_SFF_R")
	)
	(via
		(at 438.048908 -10.405364)
		(size 0.6604)
		(drill 0.3302)
		(layers "F.Cu" "B.Cu")
		(net "P12V_OCP_SFF_R")
	)
	(segment
		(start 156.31795 -106.172)
		(end 156.31795 -107.30611)
		(width 0.10668)
		(layer "F.Cu")
		(net "P12V_OCP_SFF_EN_R3")
	)
	(segment
		(start 156.31795 -107.30611)
		(end 156.31795 -108.405168)
		(width 0.10668)
		(layer "F.Cu")
		(net "P12V_OCP_SFF_EN_R3")
	)
	(segment
		(start 156.25699 -106.11104)
		(end 156.31795 -106.172)
		(width 0.10668)
		(layer "F.Cu")
		(net "P12V_OCP_SFF_EN_R3")
	)
	(segment
		(start 154.742896 -106.11104)
		(end 156.25699 -106.11104)
		(width 0.10668)
		(layer "F.Cu")
		(net "P12V_OCP_SFF_EN_R3")
	)
	(segment
		(start 156.31795 -108.405168)
		(end 156.290264 -108.432854)
		(width 0.10668)
		(layer "F.Cu")
		(net "P12V_OCP_SFF_EN_R3")
	)
	(via
		(at 156.31795 -107.30611)
		(size 0.762)
		(drill 0.381)
		(layers "F.Cu" "B.Cu")
		(net "P12V_OCP_SFF_EN_R3")
	)
	(segment
		(start 410.21508 -46.4947)
		(end 412.13024 -48.40986)
		(width 0.10668)
		(layer "F.Cu")
		(net "P12V_OCP_SFF_BUF_EN_R")
	)
	(segment
		(start 412.881318 -62.744858)
		(end 412.881318 -70.74408)
		(width 0.10668)
		(layer "F.Cu")
		(net "P12V_OCP_SFF_BUF_EN_R")
	)
	(segment
		(start 453.169782 -37.482018)
		(end 454.3933 -36.2585)
		(width 0.10668)
		(layer "F.Cu")
		(net "P12V_OCP_SFF_BUF_EN_R")
	)
	(segment
		(start 413.09798 -93.19768)
		(end 414.51276 -91.7829)
		(width 0.10668)
		(layer "F.Cu")
		(net "P12V_OCP_SFF_BUF_EN_R")
	)
	(segment
		(start 412.13024 -61.99378)
		(end 412.881318 -62.744858)
		(width 0.10668)
		(layer "F.Cu")
		(net "P12V_OCP_SFF_BUF_EN_R")
	)
	(segment
		(start 446.359788 -32.574484)
		(end 447.071496 -32.574484)
		(width 0.10668)
		(layer "F.Cu")
		(net "P12V_OCP_SFF_BUF_EN_R")
	)
	(segment
		(start 412.13024 -48.40986)
		(end 412.13024 -61.99378)
		(width 0.10668)
		(layer "F.Cu")
		(net "P12V_OCP_SFF_BUF_EN_R")
	)
	(segment
		(start 469.350344 -43.252898)
		(end 470.100914 -43.252898)
		(width 0.10668)
		(layer "F.Cu")
		(net "P12V_OCP_SFF_BUF_EN_R")
	)
	(segment
		(start 413.35706 -70.74408)
		(end 412.881318 -70.74408)
		(width 0.10668)
		(layer "F.Cu")
		(net "P12V_OCP_SFF_BUF_EN_R")
	)
	(segment
		(start 150.814532 -106.33202)
		(end 150.814532 -105.6259)
		(width 0.10668)
		(layer "F.Cu")
		(net "P12V_OCP_SFF_BUF_EN_R")
	)
	(segment
		(start 453.169782 -39.55669)
		(end 453.169782 -37.482018)
		(width 0.10668)
		(layer "F.Cu")
		(net "P12V_OCP_SFF_BUF_EN_R")
	)
	(segment
		(start 411.90672 -93.19768)
		(end 413.09798 -93.19768)
		(width 0.10668)
		(layer "F.Cu")
		(net "P12V_OCP_SFF_BUF_EN_R")
	)
	(segment
		(start 414.51276 -71.89978)
		(end 413.35706 -70.74408)
		(width 0.10668)
		(layer "F.Cu")
		(net "P12V_OCP_SFF_BUF_EN_R")
	)
	(segment
		(start 419.10889 -109.631226)
		(end 419.10889 -110.4265)
		(width 0.10668)
		(layer "F.Cu")
		(net "P12V_OCP_SFF_BUF_EN_R")
	)
	(segment
		(start 414.51276 -91.7829)
		(end 414.51276 -71.89978)
		(width 0.10668)
		(layer "F.Cu")
		(net "P12V_OCP_SFF_BUF_EN_R")
	)
	(via
		(at 411.90672 -93.19768)
		(size 0.508)
		(drill 0.254)
		(layers "F.Cu" "B.Cu")
		(net "P12V_OCP_SFF_BUF_EN_R")
	)
	(via
		(at 447.071496 -32.574484)
		(size 0.508)
		(drill 0.254)
		(layers "F.Cu" "B.Cu")
		(net "P12V_OCP_SFF_BUF_EN_R")
	)
	(via
		(at 470.100914 -43.252898)
		(size 0.508)
		(drill 0.254)
		(layers "F.Cu" "B.Cu")
		(net "P12V_OCP_SFF_BUF_EN_R")
	)
	(via
		(at 419.10889 -110.4265)
		(size 0.508)
		(drill 0.254)
		(layers "F.Cu" "B.Cu")
		(net "P12V_OCP_SFF_BUF_EN_R")
	)
	(via
		(at 410.21508 -46.4947)
		(size 0.508)
		(drill 0.254)
		(layers "F.Cu" "B.Cu")
		(net "P12V_OCP_SFF_BUF_EN_R")
	)
	(via
		(at 454.3933 -36.2585)
		(size 0.508)
		(drill 0.254)
		(layers "F.Cu" "B.Cu")
		(net "P12V_OCP_SFF_BUF_EN_R")
	)
	(via
		(at 150.814532 -105.6259)
		(size 0.508)
		(drill 0.254)
		(layers "F.Cu" "B.Cu")
		(net "P12V_OCP_SFF_BUF_EN_R")
	)
	(segment
		(start 411.90672 -93.19768)
		(end 411.64764 -93.45676)
		(width 0.11684)
		(layer "In4.Cu")
		(net "P12V_OCP_SFF_BUF_EN_R")
	)
	(segment
		(start 411.64764 -102.44328)
		(end 419.10889 -109.90453)
		(width 0.11684)
		(layer "In4.Cu")
		(net "P12V_OCP_SFF_BUF_EN_R")
	)
	(segment
		(start 411.64764 -93.45676)
		(end 411.64764 -102.44328)
		(width 0.11684)
		(layer "In4.Cu")
		(net "P12V_OCP_SFF_BUF_EN_R")
	)
	(segment
		(start 419.10889 -109.90453)
		(end 419.10889 -110.4265)
		(width 0.11684)
		(layer "In4.Cu")
		(net "P12V_OCP_SFF_BUF_EN_R")
	)
	(segment
		(start 467.181946 -37.32784)
		(end 470.100914 -40.246808)
		(width 0.11684)
		(layer "In6.Cu")
		(net "P12V_OCP_SFF_BUF_EN_R")
	)
	(segment
		(start 432.816 -43.28922)
		(end 432.816 -37.98316)
		(width 0.11684)
		(layer "In6.Cu")
		(net "P12V_OCP_SFF_BUF_EN_R")
	)
	(segment
		(start 450.755512 -36.2585)
		(end 454.3933 -36.2585)
		(width 0.11684)
		(layer "In6.Cu")
		(net "P12V_OCP_SFF_BUF_EN_R")
	)
	(segment
		(start 470.100914 -40.246808)
		(end 470.100914 -43.252898)
		(width 0.11684)
		(layer "In6.Cu")
		(net "P12V_OCP_SFF_BUF_EN_R")
	)
	(segment
		(start 432.816 -37.98316)
		(end 434.42128 -36.37788)
		(width 0.11684)
		(layer "In6.Cu")
		(net "P12V_OCP_SFF_BUF_EN_R")
	)
	(segment
		(start 454.3933 -36.2585)
		(end 454.661016 -36.526216)
		(width 0.11684)
		(layer "In6.Cu")
		(net "P12V_OCP_SFF_BUF_EN_R")
	)
	(segment
		(start 431.35296 -44.75226)
		(end 432.816 -43.28922)
		(width 0.11684)
		(layer "In6.Cu")
		(net "P12V_OCP_SFF_BUF_EN_R")
	)
	(segment
		(start 410.21508 -46.4947)
		(end 414.909 -46.4947)
		(width 0.11684)
		(layer "In6.Cu")
		(net "P12V_OCP_SFF_BUF_EN_R")
	)
	(segment
		(start 436.51932 -36.37788)
		(end 439.70194 -33.19526)
		(width 0.11684)
		(layer "In6.Cu")
		(net "P12V_OCP_SFF_BUF_EN_R")
	)
	(segment
		(start 434.42128 -36.37788)
		(end 436.51932 -36.37788)
		(width 0.11684)
		(layer "In6.Cu")
		(net "P12V_OCP_SFF_BUF_EN_R")
	)
	(segment
		(start 439.70194 -33.19526)
		(end 446.42532 -33.19526)
		(width 0.11684)
		(layer "In6.Cu")
		(net "P12V_OCP_SFF_BUF_EN_R")
	)
	(segment
		(start 416.65144 -44.75226)
		(end 431.35296 -44.75226)
		(width 0.11684)
		(layer "In6.Cu")
		(net "P12V_OCP_SFF_BUF_EN_R")
	)
	(segment
		(start 446.42532 -33.19526)
		(end 447.046096 -32.574484)
		(width 0.11684)
		(layer "In6.Cu")
		(net "P12V_OCP_SFF_BUF_EN_R")
	)
	(segment
		(start 459.79969 -37.32784)
		(end 467.181946 -37.32784)
		(width 0.11684)
		(layer "In6.Cu")
		(net "P12V_OCP_SFF_BUF_EN_R")
	)
	(segment
		(start 447.046096 -32.574484)
		(end 447.071496 -32.574484)
		(width 0.11684)
		(layer "In6.Cu")
		(net "P12V_OCP_SFF_BUF_EN_R")
	)
	(segment
		(start 414.909 -46.4947)
		(end 416.65144 -44.75226)
		(width 0.11684)
		(layer "In6.Cu")
		(net "P12V_OCP_SFF_BUF_EN_R")
	)
	(segment
		(start 454.661016 -36.526216)
		(end 458.998066 -36.526216)
		(width 0.11684)
		(layer "In6.Cu")
		(net "P12V_OCP_SFF_BUF_EN_R")
	)
	(segment
		(start 447.071496 -32.574484)
		(end 450.755512 -36.2585)
		(width 0.11684)
		(layer "In6.Cu")
		(net "P12V_OCP_SFF_BUF_EN_R")
	)
	(segment
		(start 458.998066 -36.526216)
		(end 459.79969 -37.32784)
		(width 0.11684)
		(layer "In6.Cu")
		(net "P12V_OCP_SFF_BUF_EN_R")
	)
	(segment
		(start 206.23276 -85.261704)
		(end 209.222594 -82.27187)
		(width 0.11684)
		(layer "In15.Cu")
		(net "P12V_OCP_SFF_BUF_EN_R")
	)
	(segment
		(start 372.970806 -23.654512)
		(end 377.775216 -28.458922)
		(width 0.11684)
		(layer "In15.Cu")
		(net "P12V_OCP_SFF_BUF_EN_R")
	)
	(segment
		(start 225.733356 -82.622644)
		(end 233.048302 -75.307698)
		(width 0.11684)
		(layer "In15.Cu")
		(net "P12V_OCP_SFF_BUF_EN_R")
	)
	(segment
		(start 158.952184 -102.52964)
		(end 158.952184 -100.349304)
		(width 0.11684)
		(layer "In15.Cu")
		(net "P12V_OCP_SFF_BUF_EN_R")
	)
	(segment
		(start 428.24146 -22.287484)
		(end 432.442366 -26.48839)
		(width 0.11684)
		(layer "In15.Cu")
		(net "P12V_OCP_SFF_BUF_EN_R")
	)
	(segment
		(start 320.01333 -30.012894)
		(end 327.852786 -22.173438)
		(width 0.11684)
		(layer "In15.Cu")
		(net "P12V_OCP_SFF_BUF_EN_R")
	)
	(segment
		(start 446.496948 -31.999936)
		(end 447.071496 -32.574484)
		(width 0.11684)
		(layer "In15.Cu")
		(net "P12V_OCP_SFF_BUF_EN_R")
	)
	(segment
		(start 284.531308 -50.564034)
		(end 305.082448 -30.012894)
		(width 0.11684)
		(layer "In15.Cu")
		(net "P12V_OCP_SFF_BUF_EN_R")
	)
	(segment
		(start 160.54578 -88.92794)
		(end 165.543992 -83.929728)
		(width 0.11684)
		(layer "In15.Cu")
		(net "P12V_OCP_SFF_BUF_EN_R")
	)
	(segment
		(start 221.758002 -82.965036)
		(end 222.100394 -82.622644)
		(width 0.11684)
		(layer "In15.Cu")
		(net "P12V_OCP_SFF_BUF_EN_R")
	)
	(segment
		(start 331.98689 -22.173438)
		(end 333.467964 -23.654512)
		(width 0.11684)
		(layer "In15.Cu")
		(net "P12V_OCP_SFF_BUF_EN_R")
	)
	(segment
		(start 305.082448 -30.012894)
		(end 320.01333 -30.012894)
		(width 0.11684)
		(layer "In15.Cu")
		(net "P12V_OCP_SFF_BUF_EN_R")
	)
	(segment
		(start 436.200804 -31.999936)
		(end 446.496948 -31.999936)
		(width 0.11684)
		(layer "In15.Cu")
		(net "P12V_OCP_SFF_BUF_EN_R")
	)
	(segment
		(start 165.543992 -83.929728)
		(end 188.163708 -83.929728)
		(width 0.11684)
		(layer "In15.Cu")
		(net "P12V_OCP_SFF_BUF_EN_R")
	)
	(segment
		(start 158.952184 -100.349304)
		(end 160.54578 -98.755708)
		(width 0.11684)
		(layer "In15.Cu")
		(net "P12V_OCP_SFF_BUF_EN_R")
	)
	(segment
		(start 222.100394 -82.622644)
		(end 225.733356 -82.622644)
		(width 0.11684)
		(layer "In15.Cu")
		(net "P12V_OCP_SFF_BUF_EN_R")
	)
	(segment
		(start 432.442366 -28.241498)
		(end 436.200804 -31.999936)
		(width 0.11684)
		(layer "In15.Cu")
		(net "P12V_OCP_SFF_BUF_EN_R")
	)
	(segment
		(start 219.714572 -82.27187)
		(end 220.407738 -82.965036)
		(width 0.11684)
		(layer "In15.Cu")
		(net "P12V_OCP_SFF_BUF_EN_R")
	)
	(segment
		(start 188.163708 -83.929728)
		(end 188.994542 -83.098894)
		(width 0.11684)
		(layer "In15.Cu")
		(net "P12V_OCP_SFF_BUF_EN_R")
	)
	(segment
		(start 258.718558 -77.687678)
		(end 263.57072 -72.835516)
		(width 0.11684)
		(layer "In15.Cu")
		(net "P12V_OCP_SFF_BUF_EN_R")
	)
	(segment
		(start 198.032878 -83.967828)
		(end 199.962262 -83.967828)
		(width 0.11684)
		(layer "In15.Cu")
		(net "P12V_OCP_SFF_BUF_EN_R")
	)
	(segment
		(start 197.163944 -83.098894)
		(end 198.032878 -83.967828)
		(width 0.11684)
		(layer "In15.Cu")
		(net "P12V_OCP_SFF_BUF_EN_R")
	)
	(segment
		(start 263.57072 -72.835516)
		(end 276.447758 -72.835516)
		(width 0.11684)
		(layer "In15.Cu")
		(net "P12V_OCP_SFF_BUF_EN_R")
	)
	(segment
		(start 155.855924 -105.6259)
		(end 158.952184 -102.52964)
		(width 0.11684)
		(layer "In15.Cu")
		(net "P12V_OCP_SFF_BUF_EN_R")
	)
	(segment
		(start 233.048302 -75.307698)
		(end 252.840236 -75.307698)
		(width 0.11684)
		(layer "In15.Cu")
		(net "P12V_OCP_SFF_BUF_EN_R")
	)
	(segment
		(start 252.840236 -75.307698)
		(end 255.220216 -77.687678)
		(width 0.11684)
		(layer "In15.Cu")
		(net "P12V_OCP_SFF_BUF_EN_R")
	)
	(segment
		(start 384.023616 -28.458922)
		(end 390.195054 -22.287484)
		(width 0.11684)
		(layer "In15.Cu")
		(net "P12V_OCP_SFF_BUF_EN_R")
	)
	(segment
		(start 150.814532 -105.6259)
		(end 155.855924 -105.6259)
		(width 0.11684)
		(layer "In15.Cu")
		(net "P12V_OCP_SFF_BUF_EN_R")
	)
	(segment
		(start 333.467964 -23.654512)
		(end 372.970806 -23.654512)
		(width 0.11684)
		(layer "In15.Cu")
		(net "P12V_OCP_SFF_BUF_EN_R")
	)
	(segment
		(start 199.962262 -83.967828)
		(end 201.256138 -85.261704)
		(width 0.11684)
		(layer "In15.Cu")
		(net "P12V_OCP_SFF_BUF_EN_R")
	)
	(segment
		(start 276.447758 -72.835516)
		(end 284.531308 -64.751966)
		(width 0.11684)
		(layer "In15.Cu")
		(net "P12V_OCP_SFF_BUF_EN_R")
	)
	(segment
		(start 201.256138 -85.261704)
		(end 206.23276 -85.261704)
		(width 0.11684)
		(layer "In15.Cu")
		(net "P12V_OCP_SFF_BUF_EN_R")
	)
	(segment
		(start 220.407738 -82.965036)
		(end 221.758002 -82.965036)
		(width 0.11684)
		(layer "In15.Cu")
		(net "P12V_OCP_SFF_BUF_EN_R")
	)
	(segment
		(start 160.54578 -98.755708)
		(end 160.54578 -88.92794)
		(width 0.11684)
		(layer "In15.Cu")
		(net "P12V_OCP_SFF_BUF_EN_R")
	)
	(segment
		(start 390.195054 -22.287484)
		(end 428.24146 -22.287484)
		(width 0.11684)
		(layer "In15.Cu")
		(net "P12V_OCP_SFF_BUF_EN_R")
	)
	(segment
		(start 327.852786 -22.173438)
		(end 331.98689 -22.173438)
		(width 0.11684)
		(layer "In15.Cu")
		(net "P12V_OCP_SFF_BUF_EN_R")
	)
	(segment
		(start 432.442366 -26.48839)
		(end 432.442366 -28.241498)
		(width 0.11684)
		(layer "In15.Cu")
		(net "P12V_OCP_SFF_BUF_EN_R")
	)
	(segment
		(start 188.994542 -83.098894)
		(end 197.163944 -83.098894)
		(width 0.11684)
		(layer "In15.Cu")
		(net "P12V_OCP_SFF_BUF_EN_R")
	)
	(segment
		(start 377.775216 -28.458922)
		(end 384.023616 -28.458922)
		(width 0.11684)
		(layer "In15.Cu")
		(net "P12V_OCP_SFF_BUF_EN_R")
	)
	(segment
		(start 284.531308 -64.751966)
		(end 284.531308 -50.564034)
		(width 0.11684)
		(layer "In15.Cu")
		(net "P12V_OCP_SFF_BUF_EN_R")
	)
	(segment
		(start 209.222594 -82.27187)
		(end 219.714572 -82.27187)
		(width 0.11684)
		(layer "In15.Cu")
		(net "P12V_OCP_SFF_BUF_EN_R")
	)
	(segment
		(start 255.220216 -77.687678)
		(end 258.718558 -77.687678)
		(width 0.11684)
		(layer "In15.Cu")
		(net "P12V_OCP_SFF_BUF_EN_R")
	)
	(segment
		(start 150.814532 -107.13212)
		(end 150.814532 -107.885738)
		(width 0.10668)
		(layer "F.Cu")
		(net "P12V_OCP_SFF_BUF_EN")
	)
	(segment
		(start 152.343104 -108.01096)
		(end 150.939754 -108.01096)
		(width 0.10668)
		(layer "F.Cu")
		(net "P12V_OCP_SFF_BUF_EN")
	)
	(segment
		(start 150.814532 -107.885738)
		(end 150.939754 -108.01096)
		(width 0.10668)
		(layer "F.Cu")
		(net "P12V_OCP_SFF_BUF_EN")
	)
	(via
		(at 150.939754 -108.01096)
		(size 0.762)
		(drill 0.381)
		(layers "F.Cu" "B.Cu")
		(net "P12V_OCP_SFF_BUF_EN")
	)
	(segment
		(start 392.99388 -75.576176)
		(end 392.99388 -74.79792)
		(width 0.10668)
		(layer "F.Cu")
		(net "P12V_OCP_SFF_ADC_ALERT_R")
	)
	(segment
		(start 393.87907 -76.055728)
		(end 393.473432 -76.055728)
		(width 0.10668)
		(layer "F.Cu")
		(net "P12V_OCP_SFF_ADC_ALERT_R")
	)
	(segment
		(start 392.99388 -74.79792)
		(end 392.571224 -74.375264)
		(width 0.10668)
		(layer "F.Cu")
		(net "P12V_OCP_SFF_ADC_ALERT_R")
	)
	(segment
		(start 392.571224 -74.375264)
		(end 391.691368 -74.375264)
		(width 0.10668)
		(layer "F.Cu")
		(net "P12V_OCP_SFF_ADC_ALERT_R")
	)
	(segment
		(start 393.473432 -76.055728)
		(end 392.99388 -75.576176)
		(width 0.10668)
		(layer "F.Cu")
		(net "P12V_OCP_SFF_ADC_ALERT_R")
	)
	(via
		(at 392.571224 -74.375264)
		(size 0.762)
		(drill 0.381)
		(layers "F.Cu" "B.Cu")
		(net "P12V_OCP_SFF_ADC_ALERT_R")
	)
	(via
		(at 242.010692 -42.15003)
		(size 0.6604)
		(drill 0.3302)
		(layers "F.Cu" "B.Cu")
		(net "P12V_E1S_0_R")
	)
	(via
		(at 240.213134 -44.802806)
		(size 0.508)
		(drill 0.254)
		(layers "F.Cu" "B.Cu")
		(net "P12V_E1S_0_R")
	)
	(via
		(at 238.292894 -44.802806)
		(size 0.508)
		(drill 0.254)
		(layers "F.Cu" "B.Cu")
		(net "P12V_E1S_0_R")
	)
	(via
		(at 239.578134 -44.040806)
		(size 0.508)
		(drill 0.254)
		(layers "F.Cu" "B.Cu")
		(net "P12V_E1S_0_R")
	)
	(via
		(at 245.052596 -43.955462)
		(size 0.6604)
		(drill 0.3302)
		(layers "F.Cu" "B.Cu")
		(net "P12V_E1S_0_R")
	)
	(via
		(at 243.946426 -41.222676)
		(size 0.6604)
		(drill 0.3302)
		(layers "F.Cu" "B.Cu")
		(net "P12V_E1S_0_R")
	)
	(via
		(at 237.640114 -44.716446)
		(size 0.508)
		(drill 0.254)
		(layers "F.Cu" "B.Cu")
		(net "P12V_E1S_0_R")
	)
	(via
		(at 239.578134 -44.802806)
		(size 0.508)
		(drill 0.254)
		(layers "F.Cu" "B.Cu")
		(net "P12V_E1S_0_R")
	)
	(via
		(at 238.292894 -44.040806)
		(size 0.508)
		(drill 0.254)
		(layers "F.Cu" "B.Cu")
		(net "P12V_E1S_0_R")
	)
	(via
		(at 244.518942 -43.246802)
		(size 0.508)
		(drill 0.254)
		(layers "F.Cu" "B.Cu")
		(net "P12V_E1S_0_R")
	)
	(via
		(at 244.518942 -42.611802)
		(size 0.508)
		(drill 0.254)
		(layers "F.Cu" "B.Cu")
		(net "P12V_E1S_0_R")
	)
	(via
		(at 240.893854 -44.830746)
		(size 0.508)
		(drill 0.254)
		(layers "F.Cu" "B.Cu")
		(net "P12V_E1S_0_R")
	)
	(via
		(at 241.848132 -44.34586)
		(size 0.6604)
		(drill 0.3302)
		(layers "F.Cu" "B.Cu")
		(net "P12V_E1S_0_R")
	)
	(via
		(at 237.629954 -44.025566)
		(size 0.508)
		(drill 0.254)
		(layers "F.Cu" "B.Cu")
		(net "P12V_E1S_0_R")
	)
	(via
		(at 238.943134 -44.040806)
		(size 0.508)
		(drill 0.254)
		(layers "F.Cu" "B.Cu")
		(net "P12V_E1S_0_R")
	)
	(via
		(at 240.213134 -44.040806)
		(size 0.508)
		(drill 0.254)
		(layers "F.Cu" "B.Cu")
		(net "P12V_E1S_0_R")
	)
	(via
		(at 238.943134 -44.802806)
		(size 0.508)
		(drill 0.254)
		(layers "F.Cu" "B.Cu")
		(net "P12V_E1S_0_R")
	)
	(segment
		(start 322.72732 -101.713538)
		(end 322.391532 -101.37775)
		(width 0.10668)
		(layer "F.Cu")
		(net "P12V_E1S_0_ADC_ALERT_R")
	)
	(segment
		(start 322.391532 -101.37775)
		(end 321.507358 -101.37775)
		(width 0.10668)
		(layer "F.Cu")
		(net "P12V_E1S_0_ADC_ALERT_R")
	)
	(segment
		(start 322.72732 -102.496112)
		(end 322.72732 -101.713538)
		(width 0.10668)
		(layer "F.Cu")
		(net "P12V_E1S_0_ADC_ALERT_R")
	)
	(segment
		(start 323.69506 -103.058214)
		(end 323.289422 -103.058214)
		(width 0.10668)
		(layer "F.Cu")
		(net "P12V_E1S_0_ADC_ALERT_R")
	)
	(segment
		(start 323.289422 -103.058214)
		(end 322.72732 -102.496112)
		(width 0.10668)
		(layer "F.Cu")
		(net "P12V_E1S_0_ADC_ALERT_R")
	)
	(via
		(at 322.391532 -101.37775)
		(size 0.762)
		(drill 0.381)
		(layers "F.Cu" "B.Cu")
		(net "P12V_E1S_0_ADC_ALERT_R")
	)
	(segment
		(start 81.188814 -69.596)
		(end 81.18729 -69.597524)
		(width 0.10668)
		(layer "F.Cu")
		(net "OCP_V3_2_P3V3_R2_PWRGD")
	)
	(segment
		(start 82.848958 -69.596)
		(end 81.188814 -69.596)
		(width 0.10668)
		(layer "F.Cu")
		(net "OCP_V3_2_P3V3_R2_PWRGD")
	)
	(segment
		(start 79.949548 -69.597524)
		(end 79.908908 -69.638164)
		(width 0.10668)
		(layer "F.Cu")
		(net "OCP_V3_2_P3V3_R2_PWRGD")
	)
	(segment
		(start 81.18729 -69.597524)
		(end 79.949548 -69.597524)
		(width 0.10668)
		(layer "F.Cu")
		(net "OCP_V3_2_P3V3_R2_PWRGD")
	)
	(via
		(at 81.188814 -69.596)
		(size 0.762)
		(drill 0.381)
		(layers "F.Cu" "B.Cu")
		(net "OCP_V3_2_P3V3_R2_PWRGD")
	)
	(segment
		(start 87.536274 -70.46595)
		(end 87.95385 -70.883526)
		(width 0.10668)
		(layer "F.Cu")
		(net "OCP_V3_2_P3V3_PLD_R_PWRGD")
	)
	(segment
		(start 87.95385 -75.969622)
		(end 93.454474 -81.470246)
		(width 0.10668)
		(layer "F.Cu")
		(net "OCP_V3_2_P3V3_PLD_R_PWRGD")
	)
	(segment
		(start 86.868 -70.46595)
		(end 87.536274 -70.46595)
		(width 0.10668)
		(layer "F.Cu")
		(net "OCP_V3_2_P3V3_PLD_R_PWRGD")
	)
	(segment
		(start 86.868 -70.056756)
		(end 86.868 -70.46595)
		(width 0.10668)
		(layer "F.Cu")
		(net "OCP_V3_2_P3V3_PLD_R_PWRGD")
	)
	(segment
		(start 181.122066 -117.852952)
		(end 180.732176 -118.242842)
		(width 0.10668)
		(layer "F.Cu")
		(net "OCP_V3_2_P3V3_PLD_R_PWRGD")
	)
	(segment
		(start 87.465662 -69.459094)
		(end 86.868 -70.056756)
		(width 0.10668)
		(layer "F.Cu")
		(net "OCP_V3_2_P3V3_PLD_R_PWRGD")
	)
	(segment
		(start 87.95385 -70.883526)
		(end 87.95385 -75.969622)
		(width 0.10668)
		(layer "F.Cu")
		(net "OCP_V3_2_P3V3_PLD_R_PWRGD")
	)
	(segment
		(start 93.454474 -81.470246)
		(end 108.444538 -81.470246)
		(width 0.10668)
		(layer "F.Cu")
		(net "OCP_V3_2_P3V3_PLD_R_PWRGD")
	)
	(segment
		(start 87.922862 -69.459094)
		(end 87.465662 -69.459094)
		(width 0.10668)
		(layer "F.Cu")
		(net "OCP_V3_2_P3V3_PLD_R_PWRGD")
	)
	(via
		(at 172.843952 -128.215136)
		(size 0.508)
		(drill 0.254)
		(layers "F.Cu" "B.Cu")
		(net "OCP_V3_2_P3V3_PLD_R_PWRGD")
	)
	(via
		(at 180.732176 -118.242842)
		(size 0.4572)
		(drill 0.254)
		(layers "F.Cu" "B.Cu")
		(net "OCP_V3_2_P3V3_PLD_R_PWRGD")
	)
	(via
		(at 108.444538 -81.470246)
		(size 0.508)
		(drill 0.254)
		(layers "F.Cu" "B.Cu")
		(net "OCP_V3_2_P3V3_PLD_R_PWRGD")
	)
	(segment
		(start 178.975512 -120.239028)
		(end 179.296568 -120.239028)
		(width 0.10668)
		(layer "B.Cu")
		(net "OCP_V3_2_P3V3_PLD_R_PWRGD")
	)
	(segment
		(start 171.99864 -127.369824)
		(end 171.99864 -124.30506)
		(width 0.10668)
		(layer "B.Cu")
		(net "OCP_V3_2_P3V3_PLD_R_PWRGD")
	)
	(segment
		(start 178.53152 -121.04116)
		(end 178.73599 -120.83669)
		(width 0.10668)
		(layer "B.Cu")
		(net "OCP_V3_2_P3V3_PLD_R_PWRGD")
	)
	(segment
		(start 178.967892 -120.246394)
		(end 178.968146 -120.246394)
		(width 0.10668)
		(layer "B.Cu")
		(net "OCP_V3_2_P3V3_PLD_R_PWRGD")
	)
	(segment
		(start 179.52847 -120.007126)
		(end 179.52847 -118.88597)
		(width 0.10668)
		(layer "B.Cu")
		(net "OCP_V3_2_P3V3_PLD_R_PWRGD")
	)
	(segment
		(start 174.52594 -122.8725)
		(end 174.71136 -123.05792)
		(width 0.10668)
		(layer "B.Cu")
		(net "OCP_V3_2_P3V3_PLD_R_PWRGD")
	)
	(segment
		(start 178.968146 -120.246394)
		(end 178.975512 -120.239028)
		(width 0.10668)
		(layer "B.Cu")
		(net "OCP_V3_2_P3V3_PLD_R_PWRGD")
	)
	(segment
		(start 178.73599 -120.478296)
		(end 178.967892 -120.246394)
		(width 0.10668)
		(layer "B.Cu")
		(net "OCP_V3_2_P3V3_PLD_R_PWRGD")
	)
	(segment
		(start 178.73599 -120.83669)
		(end 178.73599 -120.478296)
		(width 0.10668)
		(layer "B.Cu")
		(net "OCP_V3_2_P3V3_PLD_R_PWRGD")
	)
	(segment
		(start 177.89906 -121.04116)
		(end 178.53152 -121.04116)
		(width 0.10668)
		(layer "B.Cu")
		(net "OCP_V3_2_P3V3_PLD_R_PWRGD")
	)
	(segment
		(start 179.52847 -118.88597)
		(end 179.767992 -118.646448)
		(width 0.10668)
		(layer "B.Cu")
		(net "OCP_V3_2_P3V3_PLD_R_PWRGD")
	)
	(segment
		(start 171.99864 -124.30506)
		(end 173.4312 -122.8725)
		(width 0.10668)
		(layer "B.Cu")
		(net "OCP_V3_2_P3V3_PLD_R_PWRGD")
	)
	(segment
		(start 179.296568 -120.239028)
		(end 179.52847 -120.007126)
		(width 0.10668)
		(layer "B.Cu")
		(net "OCP_V3_2_P3V3_PLD_R_PWRGD")
	)
	(segment
		(start 179.767992 -118.646448)
		(end 179.783232 -118.646448)
		(width 0.10668)
		(layer "B.Cu")
		(net "OCP_V3_2_P3V3_PLD_R_PWRGD")
	)
	(segment
		(start 180.33238 -118.642638)
		(end 180.732176 -118.242842)
		(width 0.10668)
		(layer "B.Cu")
		(net "OCP_V3_2_P3V3_PLD_R_PWRGD")
	)
	(segment
		(start 175.8823 -123.05792)
		(end 177.89906 -121.04116)
		(width 0.10668)
		(layer "B.Cu")
		(net "OCP_V3_2_P3V3_PLD_R_PWRGD")
	)
	(segment
		(start 173.4312 -122.8725)
		(end 174.52594 -122.8725)
		(width 0.10668)
		(layer "B.Cu")
		(net "OCP_V3_2_P3V3_PLD_R_PWRGD")
	)
	(segment
		(start 174.71136 -123.05792)
		(end 175.8823 -123.05792)
		(width 0.10668)
		(layer "B.Cu")
		(net "OCP_V3_2_P3V3_PLD_R_PWRGD")
	)
	(segment
		(start 172.843952 -128.215136)
		(end 171.99864 -127.369824)
		(width 0.10668)
		(layer "B.Cu")
		(net "OCP_V3_2_P3V3_PLD_R_PWRGD")
	)
	(segment
		(start 179.787042 -118.642638)
		(end 180.33238 -118.642638)
		(width 0.10668)
		(layer "B.Cu")
		(net "OCP_V3_2_P3V3_PLD_R_PWRGD")
	)
	(segment
		(start 179.783232 -118.646448)
		(end 179.787042 -118.642638)
		(width 0.10668)
		(layer "B.Cu")
		(net "OCP_V3_2_P3V3_PLD_R_PWRGD")
	)
	(segment
		(start 156.44622 -123.07062)
		(end 162.306 -128.9304)
		(width 0.11684)
		(layer "In11.Cu")
		(net "OCP_V3_2_P3V3_PLD_R_PWRGD")
	)
	(segment
		(start 131.962652 -104.98836)
		(end 137.0965 -104.98836)
		(width 0.11684)
		(layer "In11.Cu")
		(net "OCP_V3_2_P3V3_PLD_R_PWRGD")
	)
	(segment
		(start 108.444538 -81.470246)
		(end 131.962652 -104.98836)
		(width 0.11684)
		(layer "In11.Cu")
		(net "OCP_V3_2_P3V3_PLD_R_PWRGD")
	)
	(segment
		(start 157.095444 -111.61522)
		(end 157.095444 -116.063014)
		(width 0.11684)
		(layer "In11.Cu")
		(net "OCP_V3_2_P3V3_PLD_R_PWRGD")
	)
	(segment
		(start 156.44622 -107.969304)
		(end 156.44622 -110.965996)
		(width 0.11684)
		(layer "In11.Cu")
		(net "OCP_V3_2_P3V3_PLD_R_PWRGD")
	)
	(segment
		(start 165.578028 -128.9304)
		(end 166.293292 -128.215136)
		(width 0.11684)
		(layer "In11.Cu")
		(net "OCP_V3_2_P3V3_PLD_R_PWRGD")
	)
	(segment
		(start 162.306 -128.9304)
		(end 165.578028 -128.9304)
		(width 0.11684)
		(layer "In11.Cu")
		(net "OCP_V3_2_P3V3_PLD_R_PWRGD")
	)
	(segment
		(start 148.62048 -107.00004)
		(end 151.73198 -107.00004)
		(width 0.11684)
		(layer "In11.Cu")
		(net "OCP_V3_2_P3V3_PLD_R_PWRGD")
	)
	(segment
		(start 166.293292 -128.215136)
		(end 172.843952 -128.215136)
		(width 0.11684)
		(layer "In11.Cu")
		(net "OCP_V3_2_P3V3_PLD_R_PWRGD")
	)
	(segment
		(start 156.44622 -116.712238)
		(end 156.44622 -123.07062)
		(width 0.11684)
		(layer "In11.Cu")
		(net "OCP_V3_2_P3V3_PLD_R_PWRGD")
	)
	(segment
		(start 148.09216 -106.47172)
		(end 148.62048 -107.00004)
		(width 0.11684)
		(layer "In11.Cu")
		(net "OCP_V3_2_P3V3_PLD_R_PWRGD")
	)
	(segment
		(start 137.0965 -104.98836)
		(end 138.57986 -106.47172)
		(width 0.11684)
		(layer "In11.Cu")
		(net "OCP_V3_2_P3V3_PLD_R_PWRGD")
	)
	(segment
		(start 138.57986 -106.47172)
		(end 148.09216 -106.47172)
		(width 0.11684)
		(layer "In11.Cu")
		(net "OCP_V3_2_P3V3_PLD_R_PWRGD")
	)
	(segment
		(start 157.095444 -116.063014)
		(end 156.44622 -116.712238)
		(width 0.11684)
		(layer "In11.Cu")
		(net "OCP_V3_2_P3V3_PLD_R_PWRGD")
	)
	(segment
		(start 154.165554 -105.688638)
		(end 156.44622 -107.969304)
		(width 0.11684)
		(layer "In11.Cu")
		(net "OCP_V3_2_P3V3_PLD_R_PWRGD")
	)
	(segment
		(start 156.44622 -110.965996)
		(end 157.095444 -111.61522)
		(width 0.11684)
		(layer "In11.Cu")
		(net "OCP_V3_2_P3V3_PLD_R_PWRGD")
	)
	(segment
		(start 153.043382 -105.688638)
		(end 154.165554 -105.688638)
		(width 0.11684)
		(layer "In11.Cu")
		(net "OCP_V3_2_P3V3_PLD_R_PWRGD")
	)
	(segment
		(start 151.73198 -107.00004)
		(end 153.043382 -105.688638)
		(width 0.11684)
		(layer "In11.Cu")
		(net "OCP_V3_2_P3V3_PLD_R_PWRGD")
	)
	(segment
		(start 86.916768 -68.64604)
		(end 87.502492 -68.64604)
		(width 0.10668)
		(layer "F.Cu")
		(net "OCP_V3_2_P3V3_PLD_PWRGD")
	)
	(segment
		(start 87.922608 -68.659248)
		(end 87.922862 -68.658994)
		(width 0.10668)
		(layer "F.Cu")
		(net "OCP_V3_2_P3V3_PLD_PWRGD")
	)
	(segment
		(start 85.299042 -68.64604)
		(end 86.916768 -68.64604)
		(width 0.10668)
		(layer "F.Cu")
		(net "OCP_V3_2_P3V3_PLD_PWRGD")
	)
	(segment
		(start 87.5157 -68.659248)
		(end 87.922608 -68.659248)
		(width 0.10668)
		(layer "F.Cu")
		(net "OCP_V3_2_P3V3_PLD_PWRGD")
	)
	(segment
		(start 87.502492 -68.64604)
		(end 87.5157 -68.659248)
		(width 0.10668)
		(layer "F.Cu")
		(net "OCP_V3_2_P3V3_PLD_PWRGD")
	)
	(via
		(at 86.916768 -68.64604)
		(size 0.762)
		(drill 0.381)
		(layers "F.Cu" "B.Cu")
		(net "OCP_V3_2_P3V3_PLD_PWRGD")
	)
	(segment
		(start 71.71055 -55.992014)
		(end 70.739 -55.992014)
		(width 0.10668)
		(layer "F.Cu")
		(net "OCP_V3_2_AUX_PWR_EN_R2")
	)
	(segment
		(start 71.13905 -54.61)
		(end 71.867014 -54.61)
		(width 0.10668)
		(layer "F.Cu")
		(net "OCP_V3_2_AUX_PWR_EN_R2")
	)
	(segment
		(start 71.867014 -54.61)
		(end 72.087994 -54.83098)
		(width 0.10668)
		(layer "F.Cu")
		(net "OCP_V3_2_AUX_PWR_EN_R2")
	)
	(segment
		(start 71.011796 -54.102)
		(end 71.13905 -54.229254)
		(width 0.10668)
		(layer "F.Cu")
		(net "OCP_V3_2_AUX_PWR_EN_R2")
	)
	(segment
		(start 70.44563 -54.102)
		(end 71.011796 -54.102)
		(width 0.10668)
		(layer "F.Cu")
		(net "OCP_V3_2_AUX_PWR_EN_R2")
	)
	(segment
		(start 72.087994 -55.61457)
		(end 71.71055 -55.992014)
		(width 0.10668)
		(layer "F.Cu")
		(net "OCP_V3_2_AUX_PWR_EN_R2")
	)
	(segment
		(start 70.33895 -53.99532)
		(end 70.44563 -54.102)
		(width 0.10668)
		(layer "F.Cu")
		(net "OCP_V3_2_AUX_PWR_EN_R2")
	)
	(segment
		(start 71.13905 -54.229254)
		(end 71.13905 -54.61)
		(width 0.10668)
		(layer "F.Cu")
		(net "OCP_V3_2_AUX_PWR_EN_R2")
	)
	(segment
		(start 69.36105 -53.594)
		(end 70.33895 -53.594)
		(width 0.10668)
		(layer "F.Cu")
		(net "OCP_V3_2_AUX_PWR_EN_R2")
	)
	(segment
		(start 72.087994 -54.83098)
		(end 72.087994 -55.61457)
		(width 0.10668)
		(layer "F.Cu")
		(net "OCP_V3_2_AUX_PWR_EN_R2")
	)
	(segment
		(start 70.33895 -53.594)
		(end 70.33895 -53.99532)
		(width 0.10668)
		(layer "F.Cu")
		(net "OCP_V3_2_AUX_PWR_EN_R2")
	)
	(via
		(at 72.087994 -54.83098)
		(size 0.762)
		(drill 0.381)
		(layers "F.Cu" "B.Cu")
		(net "OCP_V3_2_AUX_PWR_EN_R2")
	)
	(segment
		(start 167.386 -92.428568)
		(end 167.468804 -92.345764)
		(width 0.10668)
		(layer "F.Cu")
		(net "OCP_V3_1_P3V3_R2_PWRGD")
	)
	(segment
		(start 167.546274 -92.268294)
		(end 167.468804 -92.345764)
		(width 0.10668)
		(layer "F.Cu")
		(net "OCP_V3_1_P3V3_R2_PWRGD")
	)
	(segment
		(start 167.386 -94.151958)
		(end 167.386 -92.428568)
		(width 0.10668)
		(layer "F.Cu")
		(net "OCP_V3_1_P3V3_R2_PWRGD")
	)
	(segment
		(start 168.820592 -92.268294)
		(end 167.546274 -92.268294)
		(width 0.10668)
		(layer "F.Cu")
		(net "OCP_V3_1_P3V3_R2_PWRGD")
	)
	(via
		(at 167.468804 -92.345764)
		(size 0.762)
		(drill 0.381)
		(layers "F.Cu" "B.Cu")
		(net "OCP_V3_1_P3V3_R2_PWRGD")
	)
	(segment
		(start 177.122074 -113.05286)
		(end 176.70526 -113.05286)
		(width 0.10668)
		(layer "F.Cu")
		(net "OCP_V3_1_P3V3_PLD_R_PWRGD")
	)
	(segment
		(start 172.1231 -113.3348)
		(end 170.221148 -113.3348)
		(width 0.10668)
		(layer "F.Cu")
		(net "OCP_V3_1_P3V3_PLD_R_PWRGD")
	)
	(segment
		(start 172.6184 -113.8301)
		(end 172.1231 -113.3348)
		(width 0.10668)
		(layer "F.Cu")
		(net "OCP_V3_1_P3V3_PLD_R_PWRGD")
	)
	(segment
		(start 170.221148 -113.3348)
		(end 170.18 -113.375948)
		(width 0.10668)
		(layer "F.Cu")
		(net "OCP_V3_1_P3V3_PLD_R_PWRGD")
	)
	(segment
		(start 167.49395 -99.06)
		(end 166.51605 -99.06)
		(width 0.10668)
		(layer "F.Cu")
		(net "OCP_V3_1_P3V3_PLD_R_PWRGD")
	)
	(segment
		(start 176.70526 -113.05286)
		(end 175.92802 -113.8301)
		(width 0.10668)
		(layer "F.Cu")
		(net "OCP_V3_1_P3V3_PLD_R_PWRGD")
	)
	(segment
		(start 175.92802 -113.8301)
		(end 172.6184 -113.8301)
		(width 0.10668)
		(layer "F.Cu")
		(net "OCP_V3_1_P3V3_PLD_R_PWRGD")
	)
	(segment
		(start 166.51605 -99.719384)
		(end 166.51605 -99.06)
		(width 0.10668)
		(layer "F.Cu")
		(net "OCP_V3_1_P3V3_PLD_R_PWRGD")
	)
	(segment
		(start 166.101268 -99.897184)
		(end 166.33825 -99.897184)
		(width 0.10668)
		(layer "F.Cu")
		(net "OCP_V3_1_P3V3_PLD_R_PWRGD")
	)
	(segment
		(start 166.33825 -99.897184)
		(end 166.51605 -99.719384)
		(width 0.10668)
		(layer "F.Cu")
		(net "OCP_V3_1_P3V3_PLD_R_PWRGD")
	)
	(segment
		(start 165.850316 -100.148136)
		(end 166.101268 -99.897184)
		(width 0.10668)
		(layer "F.Cu")
		(net "OCP_V3_1_P3V3_PLD_R_PWRGD")
	)
	(via
		(at 165.850316 -100.148136)
		(size 0.508)
		(drill 0.254)
		(layers "F.Cu" "B.Cu")
		(net "OCP_V3_1_P3V3_PLD_R_PWRGD")
	)
	(via
		(at 170.18 -113.375948)
		(size 0.508)
		(drill 0.254)
		(layers "F.Cu" "B.Cu")
		(net "OCP_V3_1_P3V3_PLD_R_PWRGD")
	)
	(segment
		(start 170.00728 -111.816388)
		(end 169.6593 -112.164368)
		(width 0.11684)
		(layer "In6.Cu")
		(net "OCP_V3_1_P3V3_PLD_R_PWRGD")
	)
	(segment
		(start 168.097454 -106.774488)
		(end 169.47642 -106.774488)
		(width 0.11684)
		(layer "In6.Cu")
		(net "OCP_V3_1_P3V3_PLD_R_PWRGD")
	)
	(segment
		(start 169.6593 -112.164368)
		(end 169.6593 -112.855248)
		(width 0.11684)
		(layer "In6.Cu")
		(net "OCP_V3_1_P3V3_PLD_R_PWRGD")
	)
	(segment
		(start 170.7134 -108.011468)
		(end 170.7134 -111.409988)
		(width 0.11684)
		(layer "In6.Cu")
		(net "OCP_V3_1_P3V3_PLD_R_PWRGD")
	)
	(segment
		(start 164.954458 -100.734622)
		(end 164.954458 -103.631492)
		(width 0.11684)
		(layer "In6.Cu")
		(net "OCP_V3_1_P3V3_PLD_R_PWRGD")
	)
	(segment
		(start 165.540944 -100.148136)
		(end 164.954458 -100.734622)
		(width 0.11684)
		(layer "In6.Cu")
		(net "OCP_V3_1_P3V3_PLD_R_PWRGD")
	)
	(segment
		(start 169.47642 -106.774488)
		(end 170.7134 -108.011468)
		(width 0.11684)
		(layer "In6.Cu")
		(net "OCP_V3_1_P3V3_PLD_R_PWRGD")
	)
	(segment
		(start 170.7134 -111.409988)
		(end 170.307 -111.816388)
		(width 0.11684)
		(layer "In6.Cu")
		(net "OCP_V3_1_P3V3_PLD_R_PWRGD")
	)
	(segment
		(start 169.6593 -112.855248)
		(end 170.18 -113.375948)
		(width 0.11684)
		(layer "In6.Cu")
		(net "OCP_V3_1_P3V3_PLD_R_PWRGD")
	)
	(segment
		(start 164.954458 -103.631492)
		(end 168.097454 -106.774488)
		(width 0.11684)
		(layer "In6.Cu")
		(net "OCP_V3_1_P3V3_PLD_R_PWRGD")
	)
	(segment
		(start 165.850316 -100.148136)
		(end 165.540944 -100.148136)
		(width 0.11684)
		(layer "In6.Cu")
		(net "OCP_V3_1_P3V3_PLD_R_PWRGD")
	)
	(segment
		(start 170.307 -111.816388)
		(end 170.00728 -111.816388)
		(width 0.11684)
		(layer "In6.Cu")
		(net "OCP_V3_1_P3V3_PLD_R_PWRGD")
	)
	(segment
		(start 165.21811 -100.512118)
		(end 165.386258 -100.680266)
		(width 0.10668)
		(layer "F.Cu")
		(net "OCP_V3_1_P3V3_PLD_PWRGD")
	)
	(segment
		(start 168.33596 -99.01809)
		(end 168.29405 -99.06)
		(width 0.10668)
		(layer "F.Cu")
		(net "OCP_V3_1_P3V3_PLD_PWRGD")
	)
	(segment
		(start 168.33596 -96.602042)
		(end 168.33596 -99.01809)
		(width 0.10668)
		(layer "F.Cu")
		(net "OCP_V3_1_P3V3_PLD_PWRGD")
	)
	(segment
		(start 165.071552 -100.512118)
		(end 165.21811 -100.512118)
		(width 0.10668)
		(layer "F.Cu")
		(net "OCP_V3_1_P3V3_PLD_PWRGD")
	)
	(segment
		(start 165.386258 -100.680266)
		(end 167.78478 -100.680266)
		(width 0.10668)
		(layer "F.Cu")
		(net "OCP_V3_1_P3V3_PLD_PWRGD")
	)
	(segment
		(start 168.29405 -100.170996)
		(end 168.29405 -99.06)
		(width 0.10668)
		(layer "F.Cu")
		(net "OCP_V3_1_P3V3_PLD_PWRGD")
	)
	(segment
		(start 167.78478 -100.680266)
		(end 168.29405 -100.170996)
		(width 0.10668)
		(layer "F.Cu")
		(net "OCP_V3_1_P3V3_PLD_PWRGD")
	)
	(via
		(at 165.071552 -100.512118)
		(size 0.762)
		(drill 0.381)
		(layers "F.Cu" "B.Cu")
		(net "OCP_V3_1_P3V3_PLD_PWRGD")
	)
	(segment
		(start 216.30005 -98.187002)
		(end 216.30005 -97.79)
		(width 0.10668)
		(layer "F.Cu")
		(net "OCP_SFF_AUX_PWR_EN_R3")
	)
	(segment
		(start 216.535 -99.172014)
		(end 217.27795 -99.172014)
		(width 0.10668)
		(layer "F.Cu")
		(net "OCP_SFF_AUX_PWR_EN_R3")
	)
	(segment
		(start 217.461084 -97.54362)
		(end 217.052144 -97.54362)
		(width 0.10668)
		(layer "F.Cu")
		(net "OCP_SFF_AUX_PWR_EN_R3")
	)
	(segment
		(start 216.805764 -97.79)
		(end 216.30005 -97.79)
		(width 0.10668)
		(layer "F.Cu")
		(net "OCP_SFF_AUX_PWR_EN_R3")
	)
	(segment
		(start 216.164668 -98.322384)
		(end 216.30005 -98.187002)
		(width 0.10668)
		(layer "F.Cu")
		(net "OCP_SFF_AUX_PWR_EN_R3")
	)
	(segment
		(start 217.052144 -97.54362)
		(end 216.805764 -97.79)
		(width 0.10668)
		(layer "F.Cu")
		(net "OCP_SFF_AUX_PWR_EN_R3")
	)
	(segment
		(start 214.227918 -97.761552)
		(end 214.362538 -97.761552)
		(width 0.10668)
		(layer "F.Cu")
		(net "OCP_SFF_AUX_PWR_EN_R3")
	)
	(segment
		(start 217.484452 -98.965512)
		(end 217.484452 -97.566988)
		(width 0.10668)
		(layer "F.Cu")
		(net "OCP_SFF_AUX_PWR_EN_R3")
	)
	(segment
		(start 214.362538 -97.761552)
		(end 214.92337 -98.322384)
		(width 0.10668)
		(layer "F.Cu")
		(net "OCP_SFF_AUX_PWR_EN_R3")
	)
	(segment
		(start 213.106 -98.02495)
		(end 213.458044 -98.02495)
		(width 0.10668)
		(layer "F.Cu")
		(net "OCP_SFF_AUX_PWR_EN_R3")
	)
	(segment
		(start 217.484452 -97.566988)
		(end 217.461084 -97.54362)
		(width 0.10668)
		(layer "F.Cu")
		(net "OCP_SFF_AUX_PWR_EN_R3")
	)
	(segment
		(start 214.92337 -98.322384)
		(end 216.164668 -98.322384)
		(width 0.10668)
		(layer "F.Cu")
		(net "OCP_SFF_AUX_PWR_EN_R3")
	)
	(segment
		(start 213.458044 -98.02495)
		(end 213.721442 -97.761552)
		(width 0.10668)
		(layer "F.Cu")
		(net "OCP_SFF_AUX_PWR_EN_R3")
	)
	(segment
		(start 217.27795 -99.172014)
		(end 217.484452 -98.965512)
		(width 0.10668)
		(layer "F.Cu")
		(net "OCP_SFF_AUX_PWR_EN_R3")
	)
	(segment
		(start 213.721442 -97.761552)
		(end 214.227918 -97.761552)
		(width 0.10668)
		(layer "F.Cu")
		(net "OCP_SFF_AUX_PWR_EN_R3")
	)
	(via
		(at 214.227918 -97.761552)
		(size 0.762)
		(drill 0.381)
		(layers "F.Cu" "B.Cu")
		(net "OCP_SFF_AUX_PWR_EN_R3")
	)
	(segment
		(start 324.345046 -105.05567)
		(end 324.345046 -104.708198)
		(width 0.10668)
		(layer "F.Cu")
		(net "NC_INA230_8_NC5")
	)
	(segment
		(start 323.29755 -105.73893)
		(end 323.661786 -105.73893)
		(width 0.10668)
		(layer "F.Cu")
		(net "NC_INA230_8_NC5")
	)
	(segment
		(start 323.661786 -105.73893)
		(end 324.345046 -105.05567)
		(width 0.10668)
		(layer "F.Cu")
		(net "NC_INA230_8_NC5")
	)
	(via
		(at 323.29755 -105.73893)
		(size 0.762)
		(drill 0.381)
		(layers "F.Cu" "B.Cu")
		(net "NC_INA230_8_NC5")
	)
	(segment
		(start 324.545452 -105.979214)
		(end 324.845172 -105.679494)
		(width 0.10668)
		(layer "F.Cu")
		(net "NC_INA230_8_NC4")
	)
	(segment
		(start 324.845172 -105.679494)
		(end 324.845172 -104.708198)
		(width 0.10668)
		(layer "F.Cu")
		(net "NC_INA230_8_NC4")
	)
	(via
		(at 324.545452 -105.979214)
		(size 0.762)
		(drill 0.381)
		(layers "F.Cu" "B.Cu")
		(net "NC_INA230_8_NC4")
	)
	(segment
		(start 325.345044 -106.97083)
		(end 325.345044 -104.708198)
		(width 0.10668)
		(layer "F.Cu")
		(net "NC_INA230_8_NC3")
	)
	(via
		(at 325.345044 -106.97083)
		(size 0.762)
		(drill 0.381)
		(layers "F.Cu" "B.Cu")
		(net "NC_INA230_8_NC3")
	)
	(segment
		(start 326.641714 -101.251512)
		(end 326.356726 -101.251512)
		(width 0.10668)
		(layer "F.Cu")
		(net "NC_INA230_8_NC2")
	)
	(segment
		(start 325.84517 -101.763068)
		(end 325.84517 -101.908102)
		(width 0.10668)
		(layer "F.Cu")
		(net "NC_INA230_8_NC2")
	)
	(segment
		(start 326.356726 -101.251512)
		(end 325.84517 -101.763068)
		(width 0.10668)
		(layer "F.Cu")
		(net "NC_INA230_8_NC2")
	)
	(segment
		(start 326.98436 -100.908866)
		(end 326.641714 -101.251512)
		(width 0.10668)
		(layer "F.Cu")
		(net "NC_INA230_8_NC2")
	)
	(via
		(at 326.98436 -100.908866)
		(size 0.762)
		(drill 0.381)
		(layers "F.Cu" "B.Cu")
		(net "NC_INA230_8_NC2")
	)
	(segment
		(start 325.345044 -101.030024)
		(end 325.345044 -101.908102)
		(width 0.10668)
		(layer "F.Cu")
		(net "NC_INA230_8_NC1")
	)
	(segment
		(start 325.744332 -100.630736)
		(end 325.345044 -101.030024)
		(width 0.10668)
		(layer "F.Cu")
		(net "NC_INA230_8_NC1")
	)
	(via
		(at 325.744332 -100.630736)
		(size 0.762)
		(drill 0.381)
		(layers "F.Cu" "B.Cu")
		(net "NC_INA230_8_NC1")
	)
	(segment
		(start 324.845172 -100.997004)
		(end 324.845172 -101.908102)
		(width 0.10668)
		(layer "F.Cu")
		(net "NC_INA230_8_NC0")
	)
	(segment
		(start 324.474078 -100.62591)
		(end 324.845172 -100.997004)
		(width 0.10668)
		(layer "F.Cu")
		(net "NC_INA230_8_NC0")
	)
	(via
		(at 324.474078 -100.62591)
		(size 0.762)
		(drill 0.381)
		(layers "F.Cu" "B.Cu")
		(net "NC_INA230_8_NC0")
	)
	(segment
		(start 21.795994 -42.255694)
		(end 22.479254 -41.572434)
		(width 0.10668)
		(layer "F.Cu")
		(net "NC_INA230_7_NC5")
	)
	(segment
		(start 21.431758 -42.255694)
		(end 21.795994 -42.255694)
		(width 0.10668)
		(layer "F.Cu")
		(net "NC_INA230_7_NC5")
	)
	(segment
		(start 22.479254 -41.572434)
		(end 22.479254 -41.224962)
		(width 0.10668)
		(layer "F.Cu")
		(net "NC_INA230_7_NC5")
	)
	(via
		(at 21.431758 -42.255694)
		(size 0.762)
		(drill 0.381)
		(layers "F.Cu" "B.Cu")
		(net "NC_INA230_7_NC5")
	)
	(segment
		(start 22.97938 -41.224962)
		(end 22.97938 -42.196258)
		(width 0.10668)
		(layer "F.Cu")
		(net "NC_INA230_7_NC4")
	)
	(segment
		(start 22.97938 -42.196258)
		(end 22.67966 -42.495978)
		(width 0.10668)
		(layer "F.Cu")
		(net "NC_INA230_7_NC4")
	)
	(via
		(at 22.67966 -42.495978)
		(size 0.762)
		(drill 0.381)
		(layers "F.Cu" "B.Cu")
		(net "NC_INA230_7_NC4")
	)
	(segment
		(start 23.479252 -42.017188)
		(end 23.949914 -42.48785)
		(width 0.10668)
		(layer "F.Cu")
		(net "NC_INA230_7_NC3")
	)
	(segment
		(start 23.479252 -41.224962)
		(end 23.479252 -42.017188)
		(width 0.10668)
		(layer "F.Cu")
		(net "NC_INA230_7_NC3")
	)
	(via
		(at 23.949914 -42.48785)
		(size 0.762)
		(drill 0.381)
		(layers "F.Cu" "B.Cu")
		(net "NC_INA230_7_NC3")
	)
	(segment
		(start 24.775922 -37.768276)
		(end 24.490934 -37.768276)
		(width 0.10668)
		(layer "F.Cu")
		(net "NC_INA230_7_NC2")
	)
	(segment
		(start 25.118568 -37.42563)
		(end 24.775922 -37.768276)
		(width 0.10668)
		(layer "F.Cu")
		(net "NC_INA230_7_NC2")
	)
	(segment
		(start 24.490934 -37.768276)
		(end 23.979378 -38.279832)
		(width 0.10668)
		(layer "F.Cu")
		(net "NC_INA230_7_NC2")
	)
	(segment
		(start 23.979378 -38.279832)
		(end 23.979378 -38.424866)
		(width 0.10668)
		(layer "F.Cu")
		(net "NC_INA230_7_NC2")
	)
	(via
		(at 25.118568 -37.42563)
		(size 0.762)
		(drill 0.381)
		(layers "F.Cu" "B.Cu")
		(net "NC_INA230_7_NC2")
	)
	(segment
		(start 23.479252 -37.546788)
		(end 23.479252 -38.424866)
		(width 0.10668)
		(layer "F.Cu")
		(net "NC_INA230_7_NC1")
	)
	(segment
		(start 23.87854 -37.1475)
		(end 23.479252 -37.546788)
		(width 0.10668)
		(layer "F.Cu")
		(net "NC_INA230_7_NC1")
	)
	(via
		(at 23.87854 -37.1475)
		(size 0.762)
		(drill 0.381)
		(layers "F.Cu" "B.Cu")
		(net "NC_INA230_7_NC1")
	)
	(segment
		(start 22.97938 -37.513768)
		(end 22.608286 -37.142674)
		(width 0.10668)
		(layer "F.Cu")
		(net "NC_INA230_7_NC0")
	)
	(segment
		(start 22.97938 -38.424866)
		(end 22.97938 -37.513768)
		(width 0.10668)
		(layer "F.Cu")
		(net "NC_INA230_7_NC0")
	)
	(via
		(at 22.608286 -37.142674)
		(size 0.762)
		(drill 0.381)
		(layers "F.Cu" "B.Cu")
		(net "NC_INA230_7_NC0")
	)
	(segment
		(start 393.242038 -79.047086)
		(end 393.69746 -78.591664)
		(width 0.10668)
		(layer "F.Cu")
		(net "NC_INA230_6_NC5")
	)
	(segment
		(start 394.149072 -78.591664)
		(end 394.529056 -78.21168)
		(width 0.10668)
		(layer "F.Cu")
		(net "NC_INA230_6_NC5")
	)
	(segment
		(start 394.529056 -78.21168)
		(end 394.529056 -77.705712)
		(width 0.10668)
		(layer "F.Cu")
		(net "NC_INA230_6_NC5")
	)
	(segment
		(start 393.69746 -78.591664)
		(end 394.149072 -78.591664)
		(width 0.10668)
		(layer "F.Cu")
		(net "NC_INA230_6_NC5")
	)
	(via
		(at 393.242038 -79.047086)
		(size 0.762)
		(drill 0.381)
		(layers "F.Cu" "B.Cu")
		(net "NC_INA230_6_NC5")
	)
	(segment
		(start 395.029182 -78.5876)
		(end 395.029182 -77.705712)
		(width 0.10668)
		(layer "F.Cu")
		(net "NC_INA230_6_NC4")
	)
	(segment
		(start 394.627862 -78.98892)
		(end 395.029182 -78.5876)
		(width 0.10668)
		(layer "F.Cu")
		(net "NC_INA230_6_NC4")
	)
	(via
		(at 394.627862 -78.98892)
		(size 0.762)
		(drill 0.381)
		(layers "F.Cu" "B.Cu")
		(net "NC_INA230_6_NC4")
	)
	(segment
		(start 395.529054 -78.497938)
		(end 395.529054 -77.705712)
		(width 0.10668)
		(layer "F.Cu")
		(net "NC_INA230_6_NC3")
	)
	(segment
		(start 395.999716 -78.9686)
		(end 395.529054 -78.497938)
		(width 0.10668)
		(layer "F.Cu")
		(net "NC_INA230_6_NC3")
	)
	(via
		(at 395.999716 -78.9686)
		(size 0.762)
		(drill 0.381)
		(layers "F.Cu" "B.Cu")
		(net "NC_INA230_6_NC3")
	)
	(segment
		(start 396.520162 -73.90638)
		(end 396.02918 -74.397362)
		(width 0.10668)
		(layer "F.Cu")
		(net "NC_INA230_6_NC2")
	)
	(segment
		(start 396.02918 -74.397362)
		(end 396.02918 -74.905616)
		(width 0.10668)
		(layer "F.Cu")
		(net "NC_INA230_6_NC2")
	)
	(segment
		(start 397.16837 -73.90638)
		(end 396.520162 -73.90638)
		(width 0.10668)
		(layer "F.Cu")
		(net "NC_INA230_6_NC2")
	)
	(via
		(at 397.16837 -73.90638)
		(size 0.762)
		(drill 0.381)
		(layers "F.Cu" "B.Cu")
		(net "NC_INA230_6_NC2")
	)
	(segment
		(start 395.529054 -74.027538)
		(end 395.529054 -74.905616)
		(width 0.10668)
		(layer "F.Cu")
		(net "NC_INA230_6_NC1")
	)
	(segment
		(start 395.928342 -73.62825)
		(end 395.529054 -74.027538)
		(width 0.10668)
		(layer "F.Cu")
		(net "NC_INA230_6_NC1")
	)
	(via
		(at 395.928342 -73.62825)
		(size 0.762)
		(drill 0.381)
		(layers "F.Cu" "B.Cu")
		(net "NC_INA230_6_NC1")
	)
	(segment
		(start 395.029182 -73.994518)
		(end 395.029182 -74.905616)
		(width 0.10668)
		(layer "F.Cu")
		(net "NC_INA230_6_NC0")
	)
	(segment
		(start 394.658088 -73.623424)
		(end 395.029182 -73.994518)
		(width 0.10668)
		(layer "F.Cu")
		(net "NC_INA230_6_NC0")
	)
	(via
		(at 394.658088 -73.623424)
		(size 0.762)
		(drill 0.381)
		(layers "F.Cu" "B.Cu")
		(net "NC_INA230_6_NC0")
	)
	(via
		(at 255.138682 -328.744072)
		(size 0.6604)
		(drill 0.3302)
		(layers "F.Cu" "B.Cu")
		(net "MAX11617_2_VREF_R")
	)
	(segment
		(start 252.559566 -327.836022)
		(end 253.521464 -327.836022)
		(width 0.10668)
		(layer "B.Cu")
		(net "MAX11617_2_VREF_R")
	)
	(segment
		(start 253.521464 -327.836022)
		(end 254.429514 -328.744072)
		(width 0.10668)
		(layer "B.Cu")
		(net "MAX11617_2_VREF_R")
	)
	(segment
		(start 255.138682 -328.744072)
		(end 256.032508 -328.744072)
		(width 0.10668)
		(layer "B.Cu")
		(net "MAX11617_2_VREF_R")
	)
	(segment
		(start 254.429514 -328.744072)
		(end 255.138682 -328.744072)
		(width 0.10668)
		(layer "B.Cu")
		(net "MAX11617_2_VREF_R")
	)
	(via
		(at 257.725164 -328.744072)
		(size 0.6604)
		(drill 0.3302)
		(layers "F.Cu" "B.Cu")
		(net "MAX11617_2_VREF")
	)
	(segment
		(start 256.830576 -327.682352)
		(end 256.832608 -327.684384)
		(width 0.10668)
		(layer "B.Cu")
		(net "MAX11617_2_VREF")
	)
	(segment
		(start 256.832608 -328.744072)
		(end 256.832608 -327.684384)
		(width 0.10668)
		(layer "B.Cu")
		(net "MAX11617_2_VREF")
	)
	(segment
		(start 256.832608 -328.744072)
		(end 257.725164 -328.744072)
		(width 0.10668)
		(layer "B.Cu")
		(net "MAX11617_2_VREF")
	)
	(segment
		(start 256.830576 -326.335898)
		(end 256.830576 -327.682352)
		(width 0.10668)
		(layer "B.Cu")
		(net "MAX11617_2_VREF")
	)
	(segment
		(start 320.65595 -99.187)
		(end 320.218562 -99.187)
		(width 0.10668)
		(layer "F.Cu")
		(net "INA230_8_A1")
	)
	(segment
		(start 323.304154 -104.058212)
		(end 323.69506 -104.058212)
		(width 0.10668)
		(layer "F.Cu")
		(net "INA230_8_A1")
	)
	(segment
		(start 320.218562 -99.187)
		(end 319.953386 -98.921824)
		(width 0.10668)
		(layer "F.Cu")
		(net "INA230_8_A1")
	)
	(segment
		(start 322.53936 -104.426512)
		(end 322.935854 -104.426512)
		(width 0.10668)
		(layer "F.Cu")
		(net "INA230_8_A1")
	)
	(segment
		(start 321.507358 -104.42575)
		(end 322.43014 -104.42575)
		(width 0.10668)
		(layer "F.Cu")
		(net "INA230_8_A1")
	)
	(segment
		(start 322.43014 -104.42575)
		(end 322.430902 -104.426512)
		(width 0.10668)
		(layer "F.Cu")
		(net "INA230_8_A1")
	)
	(segment
		(start 321.507358 -105.44175)
		(end 321.507358 -104.42575)
		(width 0.10668)
		(layer "F.Cu")
		(net "INA230_8_A1")
	)
	(segment
		(start 322.935854 -104.426512)
		(end 323.304154 -104.058212)
		(width 0.10668)
		(layer "F.Cu")
		(net "INA230_8_A1")
	)
	(segment
		(start 322.430902 -104.426512)
		(end 322.53936 -104.426512)
		(width 0.10668)
		(layer "F.Cu")
		(net "INA230_8_A1")
	)
	(via
		(at 319.953386 -98.921824)
		(size 0.508)
		(drill 0.254)
		(layers "F.Cu" "B.Cu")
		(net "INA230_8_A1")
	)
	(via
		(at 322.53936 -104.426512)
		(size 0.508)
		(drill 0.254)
		(layers "F.Cu" "B.Cu")
		(net "INA230_8_A1")
	)
	(segment
		(start 322.53936 -102.06736)
		(end 322.53936 -104.426512)
		(width 0.10668)
		(layer "B.Cu")
		(net "INA230_8_A1")
	)
	(segment
		(start 319.953386 -98.921824)
		(end 319.953386 -99.481386)
		(width 0.10668)
		(layer "B.Cu")
		(net "INA230_8_A1")
	)
	(segment
		(start 319.953386 -99.481386)
		(end 322.53936 -102.06736)
		(width 0.10668)
		(layer "B.Cu")
		(net "INA230_8_A1")
	)
	(segment
		(start 321.695318 -103.59771)
		(end 321.507358 -103.40975)
		(width 0.10668)
		(layer "F.Cu")
		(net "INA230_8_A0")
	)
	(segment
		(start 323.095874 -103.558086)
		(end 323.69506 -103.558086)
		(width 0.10668)
		(layer "F.Cu")
		(net "INA230_8_A0")
	)
	(segment
		(start 323.05625 -103.59771)
		(end 323.095874 -103.558086)
		(width 0.10668)
		(layer "F.Cu")
		(net "INA230_8_A0")
	)
	(segment
		(start 322.384166 -103.59771)
		(end 323.05625 -103.59771)
		(width 0.10668)
		(layer "F.Cu")
		(net "INA230_8_A0")
	)
	(segment
		(start 322.384166 -103.59771)
		(end 321.695318 -103.59771)
		(width 0.10668)
		(layer "F.Cu")
		(net "INA230_8_A0")
	)
	(via
		(at 322.384166 -103.59771)
		(size 0.762)
		(drill 0.381)
		(layers "F.Cu" "B.Cu")
		(net "INA230_8_A0")
	)
	(segment
		(start 20.564348 -40.942514)
		(end 19.641566 -40.942514)
		(width 0.10668)
		(layer "F.Cu")
		(net "INA230_7_A1")
	)
	(segment
		(start 21.829268 -40.574976)
		(end 21.438362 -40.574976)
		(width 0.10668)
		(layer "F.Cu")
		(net "INA230_7_A1")
	)
	(segment
		(start 19.641566 -41.958514)
		(end 19.641566 -40.942514)
		(width 0.10668)
		(layer "F.Cu")
		(net "INA230_7_A1")
	)
	(segment
		(start 21.070062 -40.943276)
		(end 20.56511 -40.943276)
		(width 0.10668)
		(layer "F.Cu")
		(net "INA230_7_A1")
	)
	(segment
		(start 21.438362 -40.574976)
		(end 21.070062 -40.943276)
		(width 0.10668)
		(layer "F.Cu")
		(net "INA230_7_A1")
	)
	(segment
		(start 20.56511 -40.943276)
		(end 20.564348 -40.942514)
		(width 0.10668)
		(layer "F.Cu")
		(net "INA230_7_A1")
	)
	(via
		(at 20.56511 -40.943276)
		(size 0.762)
		(drill 0.381)
		(layers "F.Cu" "B.Cu")
		(net "INA230_7_A1")
	)
	(segment
		(start 20.059904 -39.672768)
		(end 19.806158 -39.926514)
		(width 0.10668)
		(layer "F.Cu")
		(net "INA230_7_A0")
	)
	(segment
		(start 21.829268 -40.07485)
		(end 21.432266 -40.07485)
		(width 0.10668)
		(layer "F.Cu")
		(net "INA230_7_A0")
	)
	(segment
		(start 21.432266 -40.07485)
		(end 21.030184 -39.672768)
		(width 0.10668)
		(layer "F.Cu")
		(net "INA230_7_A0")
	)
	(segment
		(start 19.806158 -39.926514)
		(end 19.641566 -39.926514)
		(width 0.10668)
		(layer "F.Cu")
		(net "INA230_7_A0")
	)
	(segment
		(start 21.030184 -39.672768)
		(end 20.568666 -39.672768)
		(width 0.10668)
		(layer "F.Cu")
		(net "INA230_7_A0")
	)
	(segment
		(start 19.641566 -39.926514)
		(end 19.641566 -38.910514)
		(width 0.10668)
		(layer "F.Cu")
		(net "INA230_7_A0")
	)
	(segment
		(start 20.568666 -39.672768)
		(end 20.059904 -39.672768)
		(width 0.10668)
		(layer "F.Cu")
		(net "INA230_7_A0")
	)
	(via
		(at 20.568666 -39.672768)
		(size 0.762)
		(drill 0.381)
		(layers "F.Cu" "B.Cu")
		(net "INA230_7_A0")
	)
	(segment
		(start 393.87907 -77.055726)
		(end 393.362688 -77.055726)
		(width 0.10668)
		(layer "F.Cu")
		(net "INA230_6_A1")
	)
	(segment
		(start 391.959846 -77.423264)
		(end 391.691368 -77.423264)
		(width 0.10668)
		(layer "F.Cu")
		(net "INA230_6_A1")
	)
	(segment
		(start 393.362688 -77.055726)
		(end 392.477498 -77.940916)
		(width 0.10668)
		(layer "F.Cu")
		(net "INA230_6_A1")
	)
	(segment
		(start 392.477498 -77.940916)
		(end 391.959846 -77.423264)
		(width 0.10668)
		(layer "F.Cu")
		(net "INA230_6_A1")
	)
	(segment
		(start 391.691368 -78.439264)
		(end 391.691368 -77.423264)
		(width 0.10668)
		(layer "F.Cu")
		(net "INA230_6_A1")
	)
	(via
		(at 392.477498 -77.940916)
		(size 0.762)
		(drill 0.381)
		(layers "F.Cu" "B.Cu")
		(net "INA230_6_A1")
	)
	(segment
		(start 391.691368 -76.407264)
		(end 391.691368 -75.391264)
		(width 0.10668)
		(layer "F.Cu")
		(net "INA230_6_A0")
	)
	(segment
		(start 392.619738 -76.5556)
		(end 392.471402 -76.407264)
		(width 0.10668)
		(layer "F.Cu")
		(net "INA230_6_A0")
	)
	(segment
		(start 392.471402 -76.407264)
		(end 391.691368 -76.407264)
		(width 0.10668)
		(layer "F.Cu")
		(net "INA230_6_A0")
	)
	(segment
		(start 393.87907 -76.5556)
		(end 392.619738 -76.5556)
		(width 0.10668)
		(layer "F.Cu")
		(net "INA230_6_A0")
	)
	(via
		(at 392.619738 -76.5556)
		(size 0.762)
		(drill 0.381)
		(layers "F.Cu" "B.Cu")
		(net "INA230_6_A0")
	)
	(segment
		(start 68.961 -57.291986)
		(end 69.596 -57.291986)
		(width 0.10668)
		(layer "F.Cu")
		(net "HP_LVC3_OCP_V3_2_PWRGD_R1")
	)
	(segment
		(start 67.871086 -57.291986)
		(end 67.263772 -57.8993)
		(width 0.10668)
		(layer "F.Cu")
		(net "HP_LVC3_OCP_V3_2_PWRGD_R1")
	)
	(segment
		(start 69.85 -57.037986)
		(end 69.85 -55.753)
		(width 0.10668)
		(layer "F.Cu")
		(net "HP_LVC3_OCP_V3_2_PWRGD_R1")
	)
	(segment
		(start 69.596 -57.291986)
		(end 69.85 -57.037986)
		(width 0.10668)
		(layer "F.Cu")
		(net "HP_LVC3_OCP_V3_2_PWRGD_R1")
	)
	(segment
		(start 68.961 -57.291986)
		(end 67.871086 -57.291986)
		(width 0.10668)
		(layer "F.Cu")
		(net "HP_LVC3_OCP_V3_2_PWRGD_R1")
	)
	(segment
		(start 69.36105 -55.26405)
		(end 69.36105 -54.61)
		(width 0.10668)
		(layer "F.Cu")
		(net "HP_LVC3_OCP_V3_2_PWRGD_R1")
	)
	(segment
		(start 69.85 -55.753)
		(end 69.36105 -55.26405)
		(width 0.10668)
		(layer "F.Cu")
		(net "HP_LVC3_OCP_V3_2_PWRGD_R1")
	)
	(segment
		(start 69.36105 -54.61)
		(end 70.33895 -54.61)
		(width 0.10668)
		(layer "F.Cu")
		(net "HP_LVC3_OCP_V3_2_PWRGD_R1")
	)
	(via
		(at 67.263772 -57.8993)
		(size 0.762)
		(drill 0.381)
		(layers "F.Cu" "B.Cu")
		(net "HP_LVC3_OCP_V3_2_PWRGD_R1")
	)
	(segment
		(start 72.898 -61.739526)
		(end 72.898 -62.074298)
		(width 0.10668)
		(layer "F.Cu")
		(net "HP_LVC3_OCP_V3_2_PWRGD")
	)
	(segment
		(start 73.406 -60.946792)
		(end 72.898 -61.454792)
		(width 0.10668)
		(layer "F.Cu")
		(net "HP_LVC3_OCP_V3_2_PWRGD")
	)
	(segment
		(start 73.406 -60.254896)
		(end 73.406 -60.946792)
		(width 0.10668)
		(layer "F.Cu")
		(net "HP_LVC3_OCP_V3_2_PWRGD")
	)
	(segment
		(start 72.898 -61.454792)
		(end 72.898 -61.739526)
		(width 0.10668)
		(layer "F.Cu")
		(net "HP_LVC3_OCP_V3_2_PWRGD")
	)
	(segment
		(start 72.898 -62.074298)
		(end 73.393046 -62.569344)
		(width 0.10668)
		(layer "F.Cu")
		(net "HP_LVC3_OCP_V3_2_PWRGD")
	)
	(via
		(at 72.898 -61.739526)
		(size 0.762)
		(drill 0.381)
		(layers "F.Cu" "B.Cu")
		(net "HP_LVC3_OCP_V3_2_PWRGD")
	)
	(segment
		(start 45.254926 -39.30396)
		(end 45.254926 -40.257222)
		(width 0.10668)
		(layer "F.Cu")
		(net "HP_LVC3_OCP_V3_2_PRSNT2_N")
	)
	(segment
		(start 15.9512 -68.128642)
		(end 16.9291 -68.128642)
		(width 0.10668)
		(layer "F.Cu")
		(net "HP_LVC3_OCP_V3_2_PRSNT2_N")
	)
	(segment
		(start 16.9291 -68.128642)
		(end 16.9291 -67.390264)
		(width 0.10668)
		(layer "F.Cu")
		(net "HP_LVC3_OCP_V3_2_PRSNT2_N")
	)
	(segment
		(start 45.254926 -40.257222)
		(end 45.414946 -40.417242)
		(width 0.10668)
		(layer "F.Cu")
		(net "HP_LVC3_OCP_V3_2_PRSNT2_N")
	)
	(segment
		(start 45.414946 -40.417242)
		(end 45.98035 -40.417242)
		(width 0.10668)
		(layer "F.Cu")
		(net "HP_LVC3_OCP_V3_2_PRSNT2_N")
	)
	(via
		(at 16.9291 -67.390264)
		(size 0.508)
		(drill 0.254)
		(layers "F.Cu" "B.Cu")
		(net "HP_LVC3_OCP_V3_2_PRSNT2_N")
	)
	(via
		(at 45.98035 -40.417242)
		(size 0.508)
		(drill 0.254)
		(layers "F.Cu" "B.Cu")
		(net "HP_LVC3_OCP_V3_2_PRSNT2_N")
	)
	(segment
		(start 30.664912 -42.087546)
		(end 44.310046 -42.087546)
		(width 0.10668)
		(layer "B.Cu")
		(net "HP_LVC3_OCP_V3_2_PRSNT2_N")
	)
	(segment
		(start 16.9291 -67.390264)
		(end 16.9291 -55.823358)
		(width 0.10668)
		(layer "B.Cu")
		(net "HP_LVC3_OCP_V3_2_PRSNT2_N")
	)
	(segment
		(start 44.310046 -42.087546)
		(end 45.98035 -40.417242)
		(width 0.10668)
		(layer "B.Cu")
		(net "HP_LVC3_OCP_V3_2_PRSNT2_N")
	)
	(segment
		(start 16.9291 -55.823358)
		(end 30.664912 -42.087546)
		(width 0.10668)
		(layer "B.Cu")
		(net "HP_LVC3_OCP_V3_2_PRSNT2_N")
	)
	(segment
		(start 50.05705 -38.6588)
		(end 50.13325 -38.735)
		(width 0.10668)
		(layer "F.Cu")
		(net "HP_LVC3_OCP_V3_2_PRSNT2")
	)
	(segment
		(start 49.54905 -38.354)
		(end 47.455074 -38.354)
		(width 0.10668)
		(layer "F.Cu")
		(net "HP_LVC3_OCP_V3_2_PRSNT2")
	)
	(segment
		(start 50.05705 -37.846)
		(end 49.54905 -38.354)
		(width 0.10668)
		(layer "F.Cu")
		(net "HP_LVC3_OCP_V3_2_PRSNT2")
	)
	(segment
		(start 50.05705 -37.846)
		(end 50.05705 -38.6588)
		(width 0.10668)
		(layer "F.Cu")
		(net "HP_LVC3_OCP_V3_2_PRSNT2")
	)
	(segment
		(start 51.505104 -38.735)
		(end 50.13325 -38.735)
		(width 0.10668)
		(layer "F.Cu")
		(net "HP_LVC3_OCP_V3_2_PRSNT2")
	)
	(via
		(at 50.13325 -38.735)
		(size 0.762)
		(drill 0.381)
		(layers "F.Cu" "B.Cu")
		(net "HP_LVC3_OCP_V3_2_PRSNT2")
	)
	(segment
		(start 91.71305 -78.105)
		(end 92.964 -78.105)
		(width 0.10668)
		(layer "F.Cu")
		(net "HP_LVC3_OCP_V3_2_P12V_R_PWRGD")
	)
	(segment
		(start 94.659958 -78.105)
		(end 92.964 -78.105)
		(width 0.10668)
		(layer "F.Cu")
		(net "HP_LVC3_OCP_V3_2_P12V_R_PWRGD")
	)
	(via
		(at 92.964 -78.105)
		(size 0.762)
		(drill 0.381)
		(layers "F.Cu" "B.Cu")
		(net "HP_LVC3_OCP_V3_2_P12V_R_PWRGD")
	)
	(segment
		(start 215.362536 -100.471986)
		(end 215.98382 -99.850702)
		(width 0.10668)
		(layer "F.Cu")
		(net "HP_LVC3_OCP_V3_1_PWRGD_R1")
	)
	(segment
		(start 214.757 -100.471986)
		(end 215.362536 -100.471986)
		(width 0.10668)
		(layer "F.Cu")
		(net "HP_LVC3_OCP_V3_1_PWRGD_R1")
	)
	(segment
		(start 218.16695 -99.441)
		(end 218.20505 -99.4029)
		(width 0.10668)
		(layer "F.Cu")
		(net "HP_LVC3_OCP_V3_1_PWRGD_R1")
	)
	(segment
		(start 218.261184 -98.429572)
		(end 218.261184 -97.54362)
		(width 0.10668)
		(layer "F.Cu")
		(net "HP_LVC3_OCP_V3_1_PWRGD_R1")
	)
	(segment
		(start 218.20505 -99.4029)
		(end 218.20505 -98.485706)
		(width 0.10668)
		(layer "F.Cu")
		(net "HP_LVC3_OCP_V3_1_PWRGD_R1")
	)
	(segment
		(start 217.757248 -99.850702)
		(end 218.16695 -99.441)
		(width 0.10668)
		(layer "F.Cu")
		(net "HP_LVC3_OCP_V3_1_PWRGD_R1")
	)
	(segment
		(start 215.98382 -99.850702)
		(end 217.757248 -99.850702)
		(width 0.10668)
		(layer "F.Cu")
		(net "HP_LVC3_OCP_V3_1_PWRGD_R1")
	)
	(segment
		(start 218.20505 -98.485706)
		(end 218.261184 -98.429572)
		(width 0.10668)
		(layer "F.Cu")
		(net "HP_LVC3_OCP_V3_1_PWRGD_R1")
	)
	(via
		(at 218.20505 -98.485706)
		(size 0.762)
		(drill 0.381)
		(layers "F.Cu" "B.Cu")
		(net "HP_LVC3_OCP_V3_1_PWRGD_R1")
	)
	(segment
		(start 215.519 -118.688104)
		(end 215.519 -117.221)
		(width 0.10668)
		(layer "F.Cu")
		(net "HP_LVC3_OCP_V3_1_PWRGD")
	)
	(segment
		(start 215.519 -116.35105)
		(end 215.519 -117.221)
		(width 0.10668)
		(layer "F.Cu")
		(net "HP_LVC3_OCP_V3_1_PWRGD")
	)
	(via
		(at 215.519 -117.221)
		(size 0.762)
		(drill 0.381)
		(layers "F.Cu" "B.Cu")
		(net "HP_LVC3_OCP_V3_1_PWRGD")
	)
	(segment
		(start 197.92061 -96.822768)
		(end 196.218302 -95.12046)
		(width 0.10668)
		(layer "F.Cu")
		(net "HP_LVC3_OCP_V3_1_P12V_R_PWRGD")
	)
	(segment
		(start 200.12787 -96.822768)
		(end 198.489824 -96.822768)
		(width 0.10668)
		(layer "F.Cu")
		(net "HP_LVC3_OCP_V3_1_P12V_R_PWRGD")
	)
	(segment
		(start 198.489824 -96.822768)
		(end 197.92061 -96.822768)
		(width 0.10668)
		(layer "F.Cu")
		(net "HP_LVC3_OCP_V3_1_P12V_R_PWRGD")
	)
	(via
		(at 196.218302 -95.12046)
		(size 0.762)
		(drill 0.381)
		(layers "F.Cu" "B.Cu")
		(net "HP_LVC3_OCP_V3_1_P12V_R_PWRGD")
	)
	(segment
		(start 153.314146 -112.969802)
		(end 153.865326 -112.418622)
		(width 0.10668)
		(layer "F.Cu")
		(net "HP_LVC3_OCP_SFF_PRSNT2_N")
	)
	(segment
		(start 154.474926 -115.50396)
		(end 153.45156 -115.50396)
		(width 0.10668)
		(layer "F.Cu")
		(net "HP_LVC3_OCP_SFF_PRSNT2_N")
	)
	(segment
		(start 153.45156 -115.50396)
		(end 153.314146 -115.366546)
		(width 0.10668)
		(layer "F.Cu")
		(net "HP_LVC3_OCP_SFF_PRSNT2_N")
	)
	(segment
		(start 461.992218 -109.646212)
		(end 462.970118 -109.646212)
		(width 0.10668)
		(layer "F.Cu")
		(net "HP_LVC3_OCP_SFF_PRSNT2_N")
	)
	(segment
		(start 153.314146 -115.366546)
		(end 153.314146 -112.969802)
		(width 0.10668)
		(layer "F.Cu")
		(net "HP_LVC3_OCP_SFF_PRSNT2_N")
	)
	(segment
		(start 462.888076 -110.80115)
		(end 462.970118 -110.719108)
		(width 0.10668)
		(layer "F.Cu")
		(net "HP_LVC3_OCP_SFF_PRSNT2_N")
	)
	(segment
		(start 462.970118 -110.719108)
		(end 462.970118 -109.646212)
		(width 0.10668)
		(layer "F.Cu")
		(net "HP_LVC3_OCP_SFF_PRSNT2_N")
	)
	(via
		(at 462.888076 -110.80115)
		(size 0.508)
		(drill 0.254)
		(layers "F.Cu" "B.Cu")
		(net "HP_LVC3_OCP_SFF_PRSNT2_N")
	)
	(via
		(at 153.865326 -112.418622)
		(size 0.508)
		(drill 0.254)
		(layers "F.Cu" "B.Cu")
		(net "HP_LVC3_OCP_SFF_PRSNT2_N")
	)
	(via
		(at 167.619172 -82.931762)
		(size 0.508)
		(drill 0.254)
		(layers "F.Cu" "B.Cu")
		(net "HP_LVC3_OCP_SFF_PRSNT2_N")
	)
	(segment
		(start 214.350346 -81.369916)
		(end 213.130892 -82.58937)
		(width 0.11684)
		(layer "In2.Cu")
		(net "HP_LVC3_OCP_SFF_PRSNT2_N")
	)
	(segment
		(start 462.888076 -110.80115)
		(end 457.980034 -115.709192)
		(width 0.11684)
		(layer "In2.Cu")
		(net "HP_LVC3_OCP_SFF_PRSNT2_N")
	)
	(segment
		(start 312.264806 -107.0991)
		(end 310.152034 -104.986328)
		(width 0.11684)
		(layer "In2.Cu")
		(net "HP_LVC3_OCP_SFF_PRSNT2_N")
	)
	(segment
		(start 193.67373 -83.625182)
		(end 183.068722 -83.625182)
		(width 0.11684)
		(layer "In2.Cu")
		(net "HP_LVC3_OCP_SFF_PRSNT2_N")
	)
	(segment
		(start 182.375302 -82.931762)
		(end 167.619172 -82.931762)
		(width 0.11684)
		(layer "In2.Cu")
		(net "HP_LVC3_OCP_SFF_PRSNT2_N")
	)
	(segment
		(start 376.424444 -115.709192)
		(end 373.117364 -119.016272)
		(width 0.11684)
		(layer "In2.Cu")
		(net "HP_LVC3_OCP_SFF_PRSNT2_N")
	)
	(segment
		(start 234.999784 -76.259182)
		(end 226.523296 -79.76997)
		(width 0.11684)
		(layer "In2.Cu")
		(net "HP_LVC3_OCP_SFF_PRSNT2_N")
	)
	(segment
		(start 213.130892 -82.58937)
		(end 194.709542 -82.58937)
		(width 0.11684)
		(layer "In2.Cu")
		(net "HP_LVC3_OCP_SFF_PRSNT2_N")
	)
	(segment
		(start 373.117364 -119.016272)
		(end 329.693524 -119.016272)
		(width 0.11684)
		(layer "In2.Cu")
		(net "HP_LVC3_OCP_SFF_PRSNT2_N")
	)
	(segment
		(start 194.709542 -82.58937)
		(end 193.67373 -83.625182)
		(width 0.11684)
		(layer "In2.Cu")
		(net "HP_LVC3_OCP_SFF_PRSNT2_N")
	)
	(segment
		(start 317.776352 -107.0991)
		(end 312.264806 -107.0991)
		(width 0.11684)
		(layer "In2.Cu")
		(net "HP_LVC3_OCP_SFF_PRSNT2_N")
	)
	(segment
		(start 224.92335 -81.369916)
		(end 214.350346 -81.369916)
		(width 0.11684)
		(layer "In2.Cu")
		(net "HP_LVC3_OCP_SFF_PRSNT2_N")
	)
	(segment
		(start 254.334772 -77.39507)
		(end 253.198884 -76.259182)
		(width 0.11684)
		(layer "In2.Cu")
		(net "HP_LVC3_OCP_SFF_PRSNT2_N")
	)
	(segment
		(start 226.523296 -79.76997)
		(end 224.92335 -81.369916)
		(width 0.11684)
		(layer "In2.Cu")
		(net "HP_LVC3_OCP_SFF_PRSNT2_N")
	)
	(segment
		(start 310.152034 -104.986328)
		(end 292.949122 -104.986328)
		(width 0.11684)
		(layer "In2.Cu")
		(net "HP_LVC3_OCP_SFF_PRSNT2_N")
	)
	(segment
		(start 329.693524 -119.016272)
		(end 317.776352 -107.0991)
		(width 0.11684)
		(layer "In2.Cu")
		(net "HP_LVC3_OCP_SFF_PRSNT2_N")
	)
	(segment
		(start 253.198884 -76.259182)
		(end 234.999784 -76.259182)
		(width 0.11684)
		(layer "In2.Cu")
		(net "HP_LVC3_OCP_SFF_PRSNT2_N")
	)
	(segment
		(start 183.068722 -83.625182)
		(end 182.375302 -82.931762)
		(width 0.11684)
		(layer "In2.Cu")
		(net "HP_LVC3_OCP_SFF_PRSNT2_N")
	)
	(segment
		(start 292.949122 -104.986328)
		(end 265.357864 -77.39507)
		(width 0.11684)
		(layer "In2.Cu")
		(net "HP_LVC3_OCP_SFF_PRSNT2_N")
	)
	(segment
		(start 457.980034 -115.709192)
		(end 376.424444 -115.709192)
		(width 0.11684)
		(layer "In2.Cu")
		(net "HP_LVC3_OCP_SFF_PRSNT2_N")
	)
	(segment
		(start 265.357864 -77.39507)
		(end 254.334772 -77.39507)
		(width 0.11684)
		(layer "In2.Cu")
		(net "HP_LVC3_OCP_SFF_PRSNT2_N")
	)
	(segment
		(start 166.95166 -82.931762)
		(end 167.619172 -82.931762)
		(width 0.11684)
		(layer "In6.Cu")
		(net "HP_LVC3_OCP_SFF_PRSNT2_N")
	)
	(segment
		(start 153.865326 -112.418622)
		(end 153.865326 -110.89005)
		(width 0.11684)
		(layer "In6.Cu")
		(net "HP_LVC3_OCP_SFF_PRSNT2_N")
	)
	(segment
		(start 154.650694 -95.232728)
		(end 166.95166 -82.931762)
		(width 0.11684)
		(layer "In6.Cu")
		(net "HP_LVC3_OCP_SFF_PRSNT2_N")
	)
	(segment
		(start 154.650694 -110.104682)
		(end 154.650694 -95.232728)
		(width 0.11684)
		(layer "In6.Cu")
		(net "HP_LVC3_OCP_SFF_PRSNT2_N")
	)
	(segment
		(start 153.865326 -110.89005)
		(end 154.650694 -110.104682)
		(width 0.11684)
		(layer "In6.Cu")
		(net "HP_LVC3_OCP_SFF_PRSNT2_N")
	)
	(segment
		(start 155.587954 -109.520482)
		(end 155.587954 -107.200954)
		(width 0.10668)
		(layer "F.Cu")
		(net "HP_LVC3_OCP_SFF_PRSNT2")
	)
	(segment
		(start 156.718 -110.650528)
		(end 155.587954 -109.520482)
		(width 0.10668)
		(layer "F.Cu")
		(net "HP_LVC3_OCP_SFF_PRSNT2")
	)
	(segment
		(start 156.675074 -114.554)
		(end 156.675074 -113.580672)
		(width 0.10668)
		(layer "F.Cu")
		(net "HP_LVC3_OCP_SFF_PRSNT2")
	)
	(segment
		(start 156.718 -112.03305)
		(end 156.718 -110.650528)
		(width 0.10668)
		(layer "F.Cu")
		(net "HP_LVC3_OCP_SFF_PRSNT2")
	)
	(segment
		(start 157.353 -112.28705)
		(end 156.972 -112.28705)
		(width 0.10668)
		(layer "F.Cu")
		(net "HP_LVC3_OCP_SFF_PRSNT2")
	)
	(segment
		(start 156.972 -112.28705)
		(end 156.718 -112.03305)
		(width 0.10668)
		(layer "F.Cu")
		(net "HP_LVC3_OCP_SFF_PRSNT2")
	)
	(segment
		(start 155.448 -107.061)
		(end 154.742896 -107.061)
		(width 0.10668)
		(layer "F.Cu")
		(net "HP_LVC3_OCP_SFF_PRSNT2")
	)
	(segment
		(start 157.353 -112.902746)
		(end 157.353 -112.28705)
		(width 0.10668)
		(layer "F.Cu")
		(net "HP_LVC3_OCP_SFF_PRSNT2")
	)
	(segment
		(start 155.587954 -107.200954)
		(end 155.448 -107.061)
		(width 0.10668)
		(layer "F.Cu")
		(net "HP_LVC3_OCP_SFF_PRSNT2")
	)
	(segment
		(start 156.675074 -113.580672)
		(end 157.353 -112.902746)
		(width 0.10668)
		(layer "F.Cu")
		(net "HP_LVC3_OCP_SFF_PRSNT2")
	)
	(via
		(at 156.718 -110.650528)
		(size 0.762)
		(drill 0.381)
		(layers "F.Cu" "B.Cu")
		(net "HP_LVC3_OCP_SFF_PRSNT2")
	)
	(via
		(at 420.111936 -428.510954)
		(size 0.6604)
		(drill 0.3302)
		(layers "F.Cu" "B.Cu")
		(net "FM_SMB_RT_ROM_MUX8_SEL")
	)
	(segment
		(start 419.265608 -428.682912)
		(end 419.939978 -428.682912)
		(width 0.10668)
		(layer "B.Cu")
		(net "FM_SMB_RT_ROM_MUX8_SEL")
	)
	(segment
		(start 420.432484 -427.516036)
		(end 421.26281 -427.516036)
		(width 0.10668)
		(layer "B.Cu")
		(net "FM_SMB_RT_ROM_MUX8_SEL")
	)
	(segment
		(start 420.111936 -428.510954)
		(end 420.258494 -428.364396)
		(width 0.10668)
		(layer "B.Cu")
		(net "FM_SMB_RT_ROM_MUX8_SEL")
	)
	(segment
		(start 419.939978 -428.682912)
		(end 420.111936 -428.510954)
		(width 0.10668)
		(layer "B.Cu")
		(net "FM_SMB_RT_ROM_MUX8_SEL")
	)
	(segment
		(start 420.258494 -427.690026)
		(end 420.432484 -427.516036)
		(width 0.10668)
		(layer "B.Cu")
		(net "FM_SMB_RT_ROM_MUX8_SEL")
	)
	(segment
		(start 420.258494 -428.364396)
		(end 420.258494 -427.690026)
		(width 0.10668)
		(layer "B.Cu")
		(net "FM_SMB_RT_ROM_MUX8_SEL")
	)
	(segment
		(start 374.881648 -425.599352)
		(end 374.881648 -425.927774)
		(width 0.10668)
		(layer "F.Cu")
		(net "FM_SMB_RT_ROM_MUX7_SEL")
	)
	(segment
		(start 376.329448 -425.478448)
		(end 376.174 -425.323)
		(width 0.10668)
		(layer "F.Cu")
		(net "FM_SMB_RT_ROM_MUX7_SEL")
	)
	(segment
		(start 376.5423 -425.6913)
		(end 376.329448 -425.478448)
		(width 0.10668)
		(layer "F.Cu")
		(net "FM_SMB_RT_ROM_MUX7_SEL")
	)
	(segment
		(start 376.174 -425.323)
		(end 375.158 -425.323)
		(width 0.10668)
		(layer "F.Cu")
		(net "FM_SMB_RT_ROM_MUX7_SEL")
	)
	(segment
		(start 375.158 -425.323)
		(end 374.881648 -425.599352)
		(width 0.10668)
		(layer "F.Cu")
		(net "FM_SMB_RT_ROM_MUX7_SEL")
	)
	(segment
		(start 376.5423 -426.339)
		(end 376.5423 -425.6913)
		(width 0.10668)
		(layer "F.Cu")
		(net "FM_SMB_RT_ROM_MUX7_SEL")
	)
	(via
		(at 376.329448 -425.478448)
		(size 0.762)
		(drill 0.381)
		(layers "F.Cu" "B.Cu")
		(net "FM_SMB_RT_ROM_MUX7_SEL")
	)
	(segment
		(start 290.140136 -395.871446)
		(end 290.140136 -396.071598)
		(width 0.10668)
		(layer "F.Cu")
		(net "FM_SMB_RT_ROM_MUX6_SEL")
	)
	(segment
		(start 288.951416 -396.653258)
		(end 288.951416 -397.400272)
		(width 0.10668)
		(layer "F.Cu")
		(net "FM_SMB_RT_ROM_MUX6_SEL")
	)
	(segment
		(start 289.905186 -396.306548)
		(end 289.092386 -396.306548)
		(width 0.10668)
		(layer "F.Cu")
		(net "FM_SMB_RT_ROM_MUX6_SEL")
	)
	(segment
		(start 288.951416 -397.400272)
		(end 289.136074 -397.58493)
		(width 0.10668)
		(layer "F.Cu")
		(net "FM_SMB_RT_ROM_MUX6_SEL")
	)
	(segment
		(start 289.092386 -396.306548)
		(end 288.951416 -396.447518)
		(width 0.10668)
		(layer "F.Cu")
		(net "FM_SMB_RT_ROM_MUX6_SEL")
	)
	(segment
		(start 290.140136 -396.071598)
		(end 289.905186 -396.306548)
		(width 0.10668)
		(layer "F.Cu")
		(net "FM_SMB_RT_ROM_MUX6_SEL")
	)
	(segment
		(start 288.951416 -396.447518)
		(end 288.951416 -396.653258)
		(width 0.10668)
		(layer "F.Cu")
		(net "FM_SMB_RT_ROM_MUX6_SEL")
	)
	(via
		(at 288.951416 -396.653258)
		(size 0.762)
		(drill 0.381)
		(layers "F.Cu" "B.Cu")
		(net "FM_SMB_RT_ROM_MUX6_SEL")
	)
	(via
		(at 296.480738 -426.93463)
		(size 0.6604)
		(drill 0.3302)
		(layers "F.Cu" "B.Cu")
		(net "FM_SMB_RT_ROM_MUX5_SEL")
	)
	(segment
		(start 296.480738 -426.93463)
		(end 296.187368 -427.228)
		(width 0.10668)
		(layer "B.Cu")
		(net "FM_SMB_RT_ROM_MUX5_SEL")
	)
	(segment
		(start 296.187368 -427.228)
		(end 295.6687 -427.228)
		(width 0.10668)
		(layer "B.Cu")
		(net "FM_SMB_RT_ROM_MUX5_SEL")
	)
	(segment
		(start 297.376342 -426.039026)
		(end 296.480738 -426.93463)
		(width 0.10668)
		(layer "B.Cu")
		(net "FM_SMB_RT_ROM_MUX5_SEL")
	)
	(segment
		(start 297.925236 -426.039026)
		(end 297.376342 -426.039026)
		(width 0.10668)
		(layer "B.Cu")
		(net "FM_SMB_RT_ROM_MUX5_SEL")
	)
	(via
		(at 161.931096 -417.07054)
		(size 0.6604)
		(drill 0.3302)
		(layers "F.Cu" "B.Cu")
		(net "FM_SMB_RT_ROM_MUX4_SEL")
	)
	(segment
		(start 160.743392 -416.754818)
		(end 161.615374 -416.754818)
		(width 0.10668)
		(layer "B.Cu")
		(net "FM_SMB_RT_ROM_MUX4_SEL")
	)
	(segment
		(start 162.15614 -417.295584)
		(end 163.156392 -417.295584)
		(width 0.10668)
		(layer "B.Cu")
		(net "FM_SMB_RT_ROM_MUX4_SEL")
	)
	(segment
		(start 161.931096 -417.07054)
		(end 162.15614 -417.295584)
		(width 0.10668)
		(layer "B.Cu")
		(net "FM_SMB_RT_ROM_MUX4_SEL")
	)
	(segment
		(start 161.615374 -416.754818)
		(end 161.931096 -417.07054)
		(width 0.10668)
		(layer "B.Cu")
		(net "FM_SMB_RT_ROM_MUX4_SEL")
	)
	(via
		(at 169.642028 -425.948348)
		(size 0.6604)
		(drill 0.3302)
		(layers "F.Cu" "B.Cu")
		(net "FM_SMB_RT_ROM_MUX3_SEL")
	)
	(segment
		(start 169.319194 -425.625514)
		(end 169.642028 -425.948348)
		(width 0.10668)
		(layer "B.Cu")
		(net "FM_SMB_RT_ROM_MUX3_SEL")
	)
	(segment
		(start 169.196512 -424.757342)
		(end 169.319194 -424.880024)
		(width 0.10668)
		(layer "B.Cu")
		(net "FM_SMB_RT_ROM_MUX3_SEL")
	)
	(segment
		(start 169.642028 -425.948348)
		(end 170.26382 -425.948348)
		(width 0.10668)
		(layer "B.Cu")
		(net "FM_SMB_RT_ROM_MUX3_SEL")
	)
	(segment
		(start 169.319194 -424.880024)
		(end 169.319194 -425.625514)
		(width 0.10668)
		(layer "B.Cu")
		(net "FM_SMB_RT_ROM_MUX3_SEL")
	)
	(segment
		(start 170.39082 -425.821348)
		(end 170.39082 -425.320206)
		(width 0.10668)
		(layer "B.Cu")
		(net "FM_SMB_RT_ROM_MUX3_SEL")
	)
	(segment
		(start 170.26382 -425.948348)
		(end 170.39082 -425.821348)
		(width 0.10668)
		(layer "B.Cu")
		(net "FM_SMB_RT_ROM_MUX3_SEL")
	)
	(segment
		(start 113.527586 -400.438874)
		(end 114.392964 -400.438874)
		(width 0.10668)
		(layer "F.Cu")
		(net "FM_SMB_RT_ROM_MUX2_SEL")
	)
	(segment
		(start 114.55781 -400.60372)
		(end 114.749072 -400.60372)
		(width 0.10668)
		(layer "F.Cu")
		(net "FM_SMB_RT_ROM_MUX2_SEL")
	)
	(segment
		(start 113.527586 -400.871944)
		(end 113.707418 -401.051776)
		(width 0.10668)
		(layer "F.Cu")
		(net "FM_SMB_RT_ROM_MUX2_SEL")
	)
	(segment
		(start 113.707418 -401.051776)
		(end 113.707418 -401.280122)
		(width 0.10668)
		(layer "F.Cu")
		(net "FM_SMB_RT_ROM_MUX2_SEL")
	)
	(segment
		(start 113.527586 -400.438874)
		(end 113.527586 -400.871944)
		(width 0.10668)
		(layer "F.Cu")
		(net "FM_SMB_RT_ROM_MUX2_SEL")
	)
	(segment
		(start 114.392964 -400.438874)
		(end 114.55781 -400.60372)
		(width 0.10668)
		(layer "F.Cu")
		(net "FM_SMB_RT_ROM_MUX2_SEL")
	)
	(via
		(at 113.527586 -400.438874)
		(size 0.762)
		(drill 0.381)
		(layers "F.Cu" "B.Cu")
		(net "FM_SMB_RT_ROM_MUX2_SEL")
	)
	(segment
		(start 97.870518 -403.141688)
		(end 98.170746 -403.141688)
		(width 0.10668)
		(layer "F.Cu")
		(net "FM_SMB_RT_ROM_MUX1_SEL")
	)
	(segment
		(start 99.467416 -403.141688)
		(end 99.955604 -402.6535)
		(width 0.10668)
		(layer "F.Cu")
		(net "FM_SMB_RT_ROM_MUX1_SEL")
	)
	(segment
		(start 98.170746 -403.141688)
		(end 98.318066 -403.289008)
		(width 0.10668)
		(layer "F.Cu")
		(net "FM_SMB_RT_ROM_MUX1_SEL")
	)
	(segment
		(start 100.329492 -402.6535)
		(end 100.332286 -402.650706)
		(width 0.10668)
		(layer "F.Cu")
		(net "FM_SMB_RT_ROM_MUX1_SEL")
	)
	(segment
		(start 99.320096 -403.289008)
		(end 99.467416 -403.141688)
		(width 0.10668)
		(layer "F.Cu")
		(net "FM_SMB_RT_ROM_MUX1_SEL")
	)
	(segment
		(start 99.955604 -402.6535)
		(end 100.329492 -402.6535)
		(width 0.10668)
		(layer "F.Cu")
		(net "FM_SMB_RT_ROM_MUX1_SEL")
	)
	(segment
		(start 98.318066 -403.289008)
		(end 99.320096 -403.289008)
		(width 0.10668)
		(layer "F.Cu")
		(net "FM_SMB_RT_ROM_MUX1_SEL")
	)
	(via
		(at 99.467416 -403.141688)
		(size 0.762)
		(drill 0.381)
		(layers "F.Cu" "B.Cu")
		(net "FM_SMB_RT_ROM_MUX1_SEL")
	)
	(segment
		(start 206.53502 -91.290902)
		(end 211.168742 -95.924624)
		(width 0.10668)
		(layer "F.Cu")
		(net "FM_PLD_OCP_SFF_AUX_PWR_EN")
	)
	(segment
		(start 211.168742 -97.411794)
		(end 212.581998 -98.82505)
		(width 0.10668)
		(layer "F.Cu")
		(net "FM_PLD_OCP_SFF_AUX_PWR_EN")
	)
	(segment
		(start 213.12505 -99.822)
		(end 213.12505 -98.8441)
		(width 0.10668)
		(layer "F.Cu")
		(net "FM_PLD_OCP_SFF_AUX_PWR_EN")
	)
	(segment
		(start 214.757 -99.822)
		(end 213.12505 -99.822)
		(width 0.10668)
		(layer "F.Cu")
		(net "FM_PLD_OCP_SFF_AUX_PWR_EN")
	)
	(segment
		(start 211.168742 -95.924624)
		(end 211.168742 -97.411794)
		(width 0.10668)
		(layer "F.Cu")
		(net "FM_PLD_OCP_SFF_AUX_PWR_EN")
	)
	(segment
		(start 213.12505 -98.8441)
		(end 213.106 -98.82505)
		(width 0.10668)
		(layer "F.Cu")
		(net "FM_PLD_OCP_SFF_AUX_PWR_EN")
	)
	(segment
		(start 201.721212 -91.290902)
		(end 206.53502 -91.290902)
		(width 0.10668)
		(layer "F.Cu")
		(net "FM_PLD_OCP_SFF_AUX_PWR_EN")
	)
	(segment
		(start 201.244708 -90.814398)
		(end 201.721212 -91.290902)
		(width 0.10668)
		(layer "F.Cu")
		(net "FM_PLD_OCP_SFF_AUX_PWR_EN")
	)
	(segment
		(start 212.581998 -98.82505)
		(end 213.106 -98.82505)
		(width 0.10668)
		(layer "F.Cu")
		(net "FM_PLD_OCP_SFF_AUX_PWR_EN")
	)
	(via
		(at 201.244708 -90.814398)
		(size 0.508)
		(drill 0.254)
		(layers "F.Cu" "B.Cu")
		(net "FM_PLD_OCP_SFF_AUX_PWR_EN")
	)
	(segment
		(start 187.887864 -92.943426)
		(end 186.726068 -92.943426)
		(width 0.10668)
		(layer "B.Cu")
		(net "FM_PLD_OCP_SFF_AUX_PWR_EN")
	)
	(segment
		(start 185.34126 -98.727514)
		(end 185.801 -99.187254)
		(width 0.10668)
		(layer "B.Cu")
		(net "FM_PLD_OCP_SFF_AUX_PWR_EN")
	)
	(segment
		(start 200.952862 -90.522552)
		(end 190.308738 -90.522552)
		(width 0.10668)
		(layer "B.Cu")
		(net "FM_PLD_OCP_SFF_AUX_PWR_EN")
	)
	(segment
		(start 186.726068 -92.943426)
		(end 186.346592 -93.322902)
		(width 0.10668)
		(layer "B.Cu")
		(net "FM_PLD_OCP_SFF_AUX_PWR_EN")
	)
	(segment
		(start 186.346592 -93.322902)
		(end 186.346592 -96.176846)
		(width 0.10668)
		(layer "B.Cu")
		(net "FM_PLD_OCP_SFF_AUX_PWR_EN")
	)
	(segment
		(start 185.801 -99.187254)
		(end 185.801 -99.894898)
		(width 0.10668)
		(layer "B.Cu")
		(net "FM_PLD_OCP_SFF_AUX_PWR_EN")
	)
	(segment
		(start 190.308738 -90.522552)
		(end 187.887864 -92.943426)
		(width 0.10668)
		(layer "B.Cu")
		(net "FM_PLD_OCP_SFF_AUX_PWR_EN")
	)
	(segment
		(start 186.346592 -96.176846)
		(end 185.34126 -97.182178)
		(width 0.10668)
		(layer "B.Cu")
		(net "FM_PLD_OCP_SFF_AUX_PWR_EN")
	)
	(segment
		(start 185.34126 -97.182178)
		(end 185.34126 -98.727514)
		(width 0.10668)
		(layer "B.Cu")
		(net "FM_PLD_OCP_SFF_AUX_PWR_EN")
	)
	(segment
		(start 201.244708 -90.814398)
		(end 200.952862 -90.522552)
		(width 0.10668)
		(layer "B.Cu")
		(net "FM_PLD_OCP_SFF_AUX_PWR_EN")
	)
	(segment
		(start 67.32905 -56.261)
		(end 67.71005 -56.642)
		(width 0.10668)
		(layer "F.Cu")
		(net "FM_OCP_V3_2_AUX_PWR_R_EN")
	)
	(segment
		(start 67.32905 -56.261)
		(end 67.32905 -55.245)
		(width 0.10668)
		(layer "F.Cu")
		(net "FM_OCP_V3_2_AUX_PWR_R_EN")
	)
	(segment
		(start 67.32905 -54.121558)
		(end 67.32905 -53.892196)
		(width 0.10668)
		(layer "F.Cu")
		(net "FM_OCP_V3_2_AUX_PWR_R_EN")
	)
	(segment
		(start 67.32905 -53.892196)
		(end 67.627246 -53.594)
		(width 0.10668)
		(layer "F.Cu")
		(net "FM_OCP_V3_2_AUX_PWR_R_EN")
	)
	(segment
		(start 67.627246 -53.594)
		(end 68.56095 -53.594)
		(width 0.10668)
		(layer "F.Cu")
		(net "FM_OCP_V3_2_AUX_PWR_R_EN")
	)
	(segment
		(start 67.32905 -55.245)
		(end 67.32905 -54.121558)
		(width 0.10668)
		(layer "F.Cu")
		(net "FM_OCP_V3_2_AUX_PWR_R_EN")
	)
	(segment
		(start 67.71005 -56.642)
		(end 68.961 -56.642)
		(width 0.10668)
		(layer "F.Cu")
		(net "FM_OCP_V3_2_AUX_PWR_R_EN")
	)
	(via
		(at 67.32905 -54.121558)
		(size 0.762)
		(drill 0.381)
		(layers "F.Cu" "B.Cu")
		(net "FM_OCP_V3_2_AUX_PWR_R_EN")
	)
	(segment
		(start 66.52895 -55.245)
		(end 66.52895 -53.989224)
		(width 0.10668)
		(layer "F.Cu")
		(net "FM_OCP_V3_2_AUX_PWR_EN")
	)
	(segment
		(start 68.501006 -52.017168)
		(end 72.995536 -52.017168)
		(width 0.10668)
		(layer "F.Cu")
		(net "FM_OCP_V3_2_AUX_PWR_EN")
	)
	(segment
		(start 72.995536 -52.017168)
		(end 74.373994 -53.395626)
		(width 0.10668)
		(layer "F.Cu")
		(net "FM_OCP_V3_2_AUX_PWR_EN")
	)
	(segment
		(start 66.52895 -53.989224)
		(end 68.501006 -52.017168)
		(width 0.10668)
		(layer "F.Cu")
		(net "FM_OCP_V3_2_AUX_PWR_EN")
	)
	(segment
		(start 74.373994 -53.395626)
		(end 74.373994 -54.163468)
		(width 0.10668)
		(layer "F.Cu")
		(net "FM_OCP_V3_2_AUX_PWR_EN")
	)
	(segment
		(start 178.72202 -120.252744)
		(end 178.33213 -120.642634)
		(width 0.10668)
		(layer "F.Cu")
		(net "FM_OCP_V3_2_AUX_PWR_EN")
	)
	(via
		(at 85.913976 -48.835056)
		(size 0.508)
		(drill 0.254)
		(layers "F.Cu" "B.Cu")
		(net "FM_OCP_V3_2_AUX_PWR_EN")
	)
	(via
		(at 136.410954 -53.837586)
		(size 0.508)
		(drill 0.254)
		(layers "F.Cu" "B.Cu")
		(net "FM_OCP_V3_2_AUX_PWR_EN")
	)
	(via
		(at 141.154658 -121.911872)
		(size 0.508)
		(drill 0.254)
		(layers "F.Cu" "B.Cu")
		(net "FM_OCP_V3_2_AUX_PWR_EN")
	)
	(via
		(at 74.373994 -54.163468)
		(size 0.508)
		(drill 0.254)
		(layers "F.Cu" "B.Cu")
		(net "FM_OCP_V3_2_AUX_PWR_EN")
	)
	(via
		(at 178.33213 -120.642634)
		(size 0.4572)
		(drill 0.254)
		(layers "F.Cu" "B.Cu")
		(net "FM_OCP_V3_2_AUX_PWR_EN")
	)
	(segment
		(start 176.134776 -120.642634)
		(end 178.33213 -120.642634)
		(width 0.11684)
		(layer "In2.Cu")
		(net "FM_OCP_V3_2_AUX_PWR_EN")
	)
	(segment
		(start 141.154658 -121.911872)
		(end 145.021808 -121.911872)
		(width 0.11684)
		(layer "In2.Cu")
		(net "FM_OCP_V3_2_AUX_PWR_EN")
	)
	(segment
		(start 171.74718 -123.131072)
		(end 171.74718 -121.183908)
		(width 0.11684)
		(layer "In2.Cu")
		(net "FM_OCP_V3_2_AUX_PWR_EN")
	)
	(segment
		(start 155.857702 -124.37745)
		(end 156.2227 -124.742448)
		(width 0.11684)
		(layer "In2.Cu")
		(net "FM_OCP_V3_2_AUX_PWR_EN")
	)
	(segment
		(start 165.603174 -123.922028)
		(end 166.423594 -124.742448)
		(width 0.11684)
		(layer "In2.Cu")
		(net "FM_OCP_V3_2_AUX_PWR_EN")
	)
	(segment
		(start 171.74718 -121.183908)
		(end 172.049948 -120.88114)
		(width 0.11684)
		(layer "In2.Cu")
		(net "FM_OCP_V3_2_AUX_PWR_EN")
	)
	(segment
		(start 74.373994 -54.163468)
		(end 80.585564 -54.163468)
		(width 0.11684)
		(layer "In2.Cu")
		(net "FM_OCP_V3_2_AUX_PWR_EN")
	)
	(segment
		(start 170.135804 -124.742448)
		(end 171.74718 -123.131072)
		(width 0.11684)
		(layer "In2.Cu")
		(net "FM_OCP_V3_2_AUX_PWR_EN")
	)
	(segment
		(start 163.849812 -123.922028)
		(end 165.603174 -123.922028)
		(width 0.11684)
		(layer "In2.Cu")
		(net "FM_OCP_V3_2_AUX_PWR_EN")
	)
	(segment
		(start 147.487386 -124.37745)
		(end 155.857702 -124.37745)
		(width 0.11684)
		(layer "In2.Cu")
		(net "FM_OCP_V3_2_AUX_PWR_EN")
	)
	(segment
		(start 175.89627 -120.88114)
		(end 176.134776 -120.642634)
		(width 0.11684)
		(layer "In2.Cu")
		(net "FM_OCP_V3_2_AUX_PWR_EN")
	)
	(segment
		(start 156.2227 -124.742448)
		(end 163.029392 -124.742448)
		(width 0.11684)
		(layer "In2.Cu")
		(net "FM_OCP_V3_2_AUX_PWR_EN")
	)
	(segment
		(start 172.049948 -120.88114)
		(end 175.89627 -120.88114)
		(width 0.11684)
		(layer "In2.Cu")
		(net "FM_OCP_V3_2_AUX_PWR_EN")
	)
	(segment
		(start 145.021808 -121.911872)
		(end 147.487386 -124.37745)
		(width 0.11684)
		(layer "In2.Cu")
		(net "FM_OCP_V3_2_AUX_PWR_EN")
	)
	(segment
		(start 80.585564 -54.163468)
		(end 85.913976 -48.835056)
		(width 0.11684)
		(layer "In2.Cu")
		(net "FM_OCP_V3_2_AUX_PWR_EN")
	)
	(segment
		(start 166.423594 -124.742448)
		(end 170.135804 -124.742448)
		(width 0.11684)
		(layer "In2.Cu")
		(net "FM_OCP_V3_2_AUX_PWR_EN")
	)
	(segment
		(start 163.029392 -124.742448)
		(end 163.849812 -123.922028)
		(width 0.11684)
		(layer "In2.Cu")
		(net "FM_OCP_V3_2_AUX_PWR_EN")
	)
	(segment
		(start 88.514682 -52.229512)
		(end 102.309168 -52.229512)
		(width 0.11684)
		(layer "In6.Cu")
		(net "FM_OCP_V3_2_AUX_PWR_EN")
	)
	(segment
		(start 128.515618 -53.703728)
		(end 129.186178 -54.374288)
		(width 0.11684)
		(layer "In6.Cu")
		(net "FM_OCP_V3_2_AUX_PWR_EN")
	)
	(segment
		(start 118.958614 -53.34)
		(end 120.463056 -54.844442)
		(width 0.11684)
		(layer "In6.Cu")
		(net "FM_OCP_V3_2_AUX_PWR_EN")
	)
	(segment
		(start 129.186178 -54.374288)
		(end 135.874252 -54.374288)
		(width 0.11684)
		(layer "In6.Cu")
		(net "FM_OCP_V3_2_AUX_PWR_EN")
	)
	(segment
		(start 85.913976 -48.835056)
		(end 85.913976 -49.628806)
		(width 0.11684)
		(layer "In6.Cu")
		(net "FM_OCP_V3_2_AUX_PWR_EN")
	)
	(segment
		(start 120.463056 -54.844442)
		(end 123.367546 -54.844442)
		(width 0.11684)
		(layer "In6.Cu")
		(net "FM_OCP_V3_2_AUX_PWR_EN")
	)
	(segment
		(start 102.309168 -52.229512)
		(end 103.419656 -53.34)
		(width 0.11684)
		(layer "In6.Cu")
		(net "FM_OCP_V3_2_AUX_PWR_EN")
	)
	(segment
		(start 124.738384 -53.473604)
		(end 125.542802 -53.473604)
		(width 0.11684)
		(layer "In6.Cu")
		(net "FM_OCP_V3_2_AUX_PWR_EN")
	)
	(segment
		(start 125.542802 -53.473604)
		(end 125.772926 -53.703728)
		(width 0.11684)
		(layer "In6.Cu")
		(net "FM_OCP_V3_2_AUX_PWR_EN")
	)
	(segment
		(start 123.367546 -54.844442)
		(end 124.738384 -53.473604)
		(width 0.11684)
		(layer "In6.Cu")
		(net "FM_OCP_V3_2_AUX_PWR_EN")
	)
	(segment
		(start 103.419656 -53.34)
		(end 118.958614 -53.34)
		(width 0.11684)
		(layer "In6.Cu")
		(net "FM_OCP_V3_2_AUX_PWR_EN")
	)
	(segment
		(start 125.772926 -53.703728)
		(end 128.515618 -53.703728)
		(width 0.11684)
		(layer "In6.Cu")
		(net "FM_OCP_V3_2_AUX_PWR_EN")
	)
	(segment
		(start 85.913976 -49.628806)
		(end 88.514682 -52.229512)
		(width 0.11684)
		(layer "In6.Cu")
		(net "FM_OCP_V3_2_AUX_PWR_EN")
	)
	(segment
		(start 135.874252 -54.374288)
		(end 136.410954 -53.837586)
		(width 0.11684)
		(layer "In6.Cu")
		(net "FM_OCP_V3_2_AUX_PWR_EN")
	)
	(segment
		(start 141.154658 -121.911872)
		(end 141.364716 -121.701814)
		(width 0.11684)
		(layer "In15.Cu")
		(net "FM_OCP_V3_2_AUX_PWR_EN")
	)
	(segment
		(start 136.331198 -86.841838)
		(end 136.331198 -73.208388)
		(width 0.11684)
		(layer "In15.Cu")
		(net "FM_OCP_V3_2_AUX_PWR_EN")
	)
	(segment
		(start 136.543288 -111.607346)
		(end 136.543288 -110.291118)
		(width 0.11684)
		(layer "In15.Cu")
		(net "FM_OCP_V3_2_AUX_PWR_EN")
	)
	(segment
		(start 137.455656 -114.423952)
		(end 137.455656 -112.519714)
		(width 0.11684)
		(layer "In15.Cu")
		(net "FM_OCP_V3_2_AUX_PWR_EN")
	)
	(segment
		(start 141.364716 -121.701814)
		(end 141.364716 -118.333012)
		(width 0.11684)
		(layer "In15.Cu")
		(net "FM_OCP_V3_2_AUX_PWR_EN")
	)
	(segment
		(start 140.012166 -71.524114)
		(end 140.730478 -70.805802)
		(width 0.11684)
		(layer "In15.Cu")
		(net "FM_OCP_V3_2_AUX_PWR_EN")
	)
	(segment
		(start 140.730478 -70.805802)
		(end 140.730478 -65.018158)
		(width 0.11684)
		(layer "In15.Cu")
		(net "FM_OCP_V3_2_AUX_PWR_EN")
	)
	(segment
		(start 141.364716 -118.333012)
		(end 137.455656 -114.423952)
		(width 0.11684)
		(layer "In15.Cu")
		(net "FM_OCP_V3_2_AUX_PWR_EN")
	)
	(segment
		(start 140.730478 -65.018158)
		(end 136.814052 -61.101732)
		(width 0.11684)
		(layer "In15.Cu")
		(net "FM_OCP_V3_2_AUX_PWR_EN")
	)
	(segment
		(start 137.455656 -112.519714)
		(end 136.543288 -111.607346)
		(width 0.11684)
		(layer "In15.Cu")
		(net "FM_OCP_V3_2_AUX_PWR_EN")
	)
	(segment
		(start 137.455656 -87.966296)
		(end 136.331198 -86.841838)
		(width 0.11684)
		(layer "In15.Cu")
		(net "FM_OCP_V3_2_AUX_PWR_EN")
	)
	(segment
		(start 136.331198 -73.208388)
		(end 138.015472 -71.524114)
		(width 0.11684)
		(layer "In15.Cu")
		(net "FM_OCP_V3_2_AUX_PWR_EN")
	)
	(segment
		(start 134.798308 -59.977274)
		(end 134.798308 -57.167018)
		(width 0.11684)
		(layer "In15.Cu")
		(net "FM_OCP_V3_2_AUX_PWR_EN")
	)
	(segment
		(start 134.798308 -57.167018)
		(end 136.410954 -55.554372)
		(width 0.11684)
		(layer "In15.Cu")
		(net "FM_OCP_V3_2_AUX_PWR_EN")
	)
	(segment
		(start 136.814052 -61.101732)
		(end 135.922766 -61.101732)
		(width 0.11684)
		(layer "In15.Cu")
		(net "FM_OCP_V3_2_AUX_PWR_EN")
	)
	(segment
		(start 137.455656 -109.37875)
		(end 137.455656 -87.966296)
		(width 0.11684)
		(layer "In15.Cu")
		(net "FM_OCP_V3_2_AUX_PWR_EN")
	)
	(segment
		(start 136.410954 -55.554372)
		(end 136.410954 -53.837586)
		(width 0.11684)
		(layer "In15.Cu")
		(net "FM_OCP_V3_2_AUX_PWR_EN")
	)
	(segment
		(start 136.543288 -110.291118)
		(end 137.455656 -109.37875)
		(width 0.11684)
		(layer "In15.Cu")
		(net "FM_OCP_V3_2_AUX_PWR_EN")
	)
	(segment
		(start 135.922766 -61.101732)
		(end 134.798308 -59.977274)
		(width 0.11684)
		(layer "In15.Cu")
		(net "FM_OCP_V3_2_AUX_PWR_EN")
	)
	(segment
		(start 138.015472 -71.524114)
		(end 140.012166 -71.524114)
		(width 0.11684)
		(layer "In15.Cu")
		(net "FM_OCP_V3_2_AUX_PWR_EN")
	)
	(segment
		(start 214.4395 -325.12127)
		(end 214.833454 -325.515224)
		(width 0.10668)
		(layer "F.Cu")
		(net "ADC128_2_VREF")
	)
	(segment
		(start 214.833454 -325.515224)
		(end 214.833454 -327.095104)
		(width 0.10668)
		(layer "F.Cu")
		(net "ADC128_2_VREF")
	)
	(segment
		(start 214.4395 -321.756786)
		(end 214.4395 -325.12127)
		(width 0.10668)
		(layer "F.Cu")
		(net "ADC128_2_VREF")
	)
	(via
		(at 214.833454 -327.095104)
		(size 0.508)
		(drill 0.254)
		(layers "F.Cu" "B.Cu")
		(net "ADC128_2_VREF")
	)
	(via
		(at 214.4395 -321.756786)
		(size 0.508)
		(drill 0.254)
		(layers "F.Cu" "B.Cu")
		(net "ADC128_2_VREF")
	)
	(segment
		(start 215.392 -327.009252)
		(end 215.306148 -327.095104)
		(width 0.10668)
		(layer "B.Cu")
		(net "ADC128_2_VREF")
	)
	(segment
		(start 216.49055 -321.863466)
		(end 216.49055 -322.52539)
		(width 0.10668)
		(layer "B.Cu")
		(net "ADC128_2_VREF")
	)
	(segment
		(start 218.546426 -324.259194)
		(end 216.812622 -322.52539)
		(width 0.10668)
		(layer "B.Cu")
		(net "ADC128_2_VREF")
	)
	(segment
		(start 215.727026 -327.009252)
		(end 215.392 -327.009252)
		(width 0.10668)
		(layer "B.Cu")
		(net "ADC128_2_VREF")
	)
	(segment
		(start 216.38387 -321.756786)
		(end 216.49055 -321.863466)
		(width 0.10668)
		(layer "B.Cu")
		(net "ADC128_2_VREF")
	)
	(segment
		(start 219.608146 -324.259194)
		(end 218.546426 -324.259194)
		(width 0.10668)
		(layer "B.Cu")
		(net "ADC128_2_VREF")
	)
	(segment
		(start 214.4395 -321.756786)
		(end 216.38387 -321.756786)
		(width 0.10668)
		(layer "B.Cu")
		(net "ADC128_2_VREF")
	)
	(segment
		(start 215.306148 -327.095104)
		(end 214.833454 -327.095104)
		(width 0.10668)
		(layer "B.Cu")
		(net "ADC128_2_VREF")
	)
	(segment
		(start 216.812622 -322.52539)
		(end 216.49055 -322.52539)
		(width 0.10668)
		(layer "B.Cu")
		(net "ADC128_2_VREF")
	)
	(via
		(at 217.597482 -329.495912)
		(size 0.6604)
		(drill 0.3302)
		(layers "F.Cu" "B.Cu")
		(net "ADC128_2_A1")
	)
	(segment
		(start 217.597482 -329.495912)
		(end 217.280744 -329.179174)
		(width 0.10668)
		(layer "B.Cu")
		(net "ADC128_2_A1")
	)
	(segment
		(start 219.608146 -328.80935)
		(end 218.921584 -329.495912)
		(width 0.10668)
		(layer "B.Cu")
		(net "ADC128_2_A1")
	)
	(segment
		(start 215.96604 -329.746864)
		(end 214.561928 -329.746864)
		(width 0.10668)
		(layer "B.Cu")
		(net "ADC128_2_A1")
	)
	(segment
		(start 217.280744 -329.179174)
		(end 216.53373 -329.179174)
		(width 0.10668)
		(layer "B.Cu")
		(net "ADC128_2_A1")
	)
	(segment
		(start 214.561928 -329.746864)
		(end 214.016336 -329.201272)
		(width 0.10668)
		(layer "B.Cu")
		(net "ADC128_2_A1")
	)
	(segment
		(start 218.921584 -329.495912)
		(end 217.597482 -329.495912)
		(width 0.10668)
		(layer "B.Cu")
		(net "ADC128_2_A1")
	)
	(segment
		(start 216.53373 -329.179174)
		(end 215.96604 -329.746864)
		(width 0.10668)
		(layer "B.Cu")
		(net "ADC128_2_A1")
	)
	(via
		(at 217.673174 -328.098404)
		(size 0.6604)
		(drill 0.3302)
		(layers "F.Cu" "B.Cu")
		(net "ADC128_2_A0")
	)
	(segment
		(start 214.017352 -328.110088)
		(end 214.51316 -328.605896)
		(width 0.10668)
		(layer "B.Cu")
		(net "ADC128_2_A0")
	)
	(segment
		(start 217.607642 -328.032872)
		(end 217.673174 -328.098404)
		(width 0.10668)
		(layer "B.Cu")
		(net "ADC128_2_A0")
	)
	(segment
		(start 216.517728 -328.032872)
		(end 216.542874 -328.032872)
		(width 0.10668)
		(layer "B.Cu")
		(net "ADC128_2_A0")
	)
	(segment
		(start 214.51316 -328.605896)
		(end 215.944704 -328.605896)
		(width 0.10668)
		(layer "B.Cu")
		(net "ADC128_2_A0")
	)
	(segment
		(start 216.542874 -328.032872)
		(end 217.607642 -328.032872)
		(width 0.10668)
		(layer "B.Cu")
		(net "ADC128_2_A0")
	)
	(segment
		(start 215.944704 -328.605896)
		(end 216.517728 -328.032872)
		(width 0.10668)
		(layer "B.Cu")
		(net "ADC128_2_A0")
	)
	(segment
		(start 217.734134 -328.159364)
		(end 219.608146 -328.159364)
		(width 0.10668)
		(layer "B.Cu")
		(net "ADC128_2_A0")
	)
	(segment
		(start 217.673174 -328.098404)
		(end 217.734134 -328.159364)
		(width 0.10668)
		(layer "B.Cu")
		(net "ADC128_2_A0")
	)
	(segment
		(start 163.195 -107.20705)
		(end 163.1061 -107.29595)
		(width 0.10668)
		(layer "F.Cu")
		(net "IRQ_HSC_FAULT_BUF_N")
	)
	(segment
		(start 164.865812 -108.677964)
		(end 164.31895 -108.131102)
		(width 0.10668)
		(layer "F.Cu")
		(net "IRQ_HSC_FAULT_BUF_N")
	)
	(segment
		(start 165.801802 -108.677964)
		(end 168.455086 -108.677964)
		(width 0.10668)
		(layer "F.Cu")
		(net "IRQ_HSC_FAULT_BUF_N")
	)
	(segment
		(start 162.052 -107.29595)
		(end 161.832036 -107.075986)
		(width 0.10668)
		(layer "F.Cu")
		(net "IRQ_HSC_FAULT_BUF_N")
	)
	(segment
		(start 168.677082 -108.89996)
		(end 168.677082 -109.495082)
		(width 0.10668)
		(layer "F.Cu")
		(net "IRQ_HSC_FAULT_BUF_N")
	)
	(segment
		(start 168.455086 -108.677964)
		(end 168.677082 -108.89996)
		(width 0.10668)
		(layer "F.Cu")
		(net "IRQ_HSC_FAULT_BUF_N")
	)
	(segment
		(start 164.31895 -107.315)
		(end 164.211 -107.20705)
		(width 0.10668)
		(layer "F.Cu")
		(net "IRQ_HSC_FAULT_BUF_N")
	)
	(segment
		(start 164.31895 -108.131102)
		(end 164.31895 -107.315)
		(width 0.10668)
		(layer "F.Cu")
		(net "IRQ_HSC_FAULT_BUF_N")
	)
	(segment
		(start 165.801802 -108.677964)
		(end 164.865812 -108.677964)
		(width 0.10668)
		(layer "F.Cu")
		(net "IRQ_HSC_FAULT_BUF_N")
	)
	(segment
		(start 170.66895 -109.728)
		(end 170.79595 -109.855)
		(width 0.10668)
		(layer "F.Cu")
		(net "IRQ_HSC_FAULT_BUF_N")
	)
	(segment
		(start 163.1061 -107.29595)
		(end 162.052 -107.29595)
		(width 0.10668)
		(layer "F.Cu")
		(net "IRQ_HSC_FAULT_BUF_N")
	)
	(segment
		(start 164.211 -107.20705)
		(end 163.195 -107.20705)
		(width 0.10668)
		(layer "F.Cu")
		(net "IRQ_HSC_FAULT_BUF_N")
	)
	(segment
		(start 170.79595 -109.855)
		(end 170.79595 -110.200948)
		(width 0.10668)
		(layer "F.Cu")
		(net "IRQ_HSC_FAULT_BUF_N")
	)
	(segment
		(start 168.677082 -109.495082)
		(end 168.91 -109.728)
		(width 0.10668)
		(layer "F.Cu")
		(net "IRQ_HSC_FAULT_BUF_N")
	)
	(segment
		(start 161.832036 -107.075986)
		(end 160.58896 -107.075986)
		(width 0.10668)
		(layer "F.Cu")
		(net "IRQ_HSC_FAULT_BUF_N")
	)
	(segment
		(start 168.91 -109.728)
		(end 170.66895 -109.728)
		(width 0.10668)
		(layer "F.Cu")
		(net "IRQ_HSC_FAULT_BUF_N")
	)
	(via
		(at 165.801802 -108.677964)
		(size 0.508)
		(drill 0.254)
		(layers "F.Cu" "B.Cu")
		(net "IRQ_HSC_FAULT_BUF_N")
	)
	(segment
		(start 158.68904 -105.776014)
		(end 159.174688 -105.776014)
		(width 0.10668)
		(layer "F.Cu")
		(net "IRQ_HSC_FAULT")
	)
	(segment
		(start 159.49295 -108.458)
		(end 159.49295 -107.179364)
		(width 0.10668)
		(layer "F.Cu")
		(net "IRQ_HSC_FAULT")
	)
	(segment
		(start 159.174688 -105.776014)
		(end 159.333438 -105.934764)
		(width 0.10668)
		(layer "F.Cu")
		(net "IRQ_HSC_FAULT")
	)
	(segment
		(start 159.49295 -107.179364)
		(end 159.49295 -106.740706)
		(width 0.10668)
		(layer "F.Cu")
		(net "IRQ_HSC_FAULT")
	)
	(segment
		(start 159.178244 -106.426)
		(end 158.68904 -106.426)
		(width 0.10668)
		(layer "F.Cu")
		(net "IRQ_HSC_FAULT")
	)
	(segment
		(start 159.333438 -105.934764)
		(end 159.333438 -106.270806)
		(width 0.10668)
		(layer "F.Cu")
		(net "IRQ_HSC_FAULT")
	)
	(segment
		(start 159.49295 -106.740706)
		(end 159.178244 -106.426)
		(width 0.10668)
		(layer "F.Cu")
		(net "IRQ_HSC_FAULT")
	)
	(segment
		(start 159.333438 -106.270806)
		(end 159.178244 -106.426)
		(width 0.10668)
		(layer "F.Cu")
		(net "IRQ_HSC_FAULT")
	)
	(via
		(at 159.49295 -107.179364)
		(size 0.508)
		(drill 0.254)
		(layers "F.Cu" "B.Cu")
		(net "IRQ_HSC_FAULT")
	)
	(segment
		(start 438.056782 -433.89931)
		(end 439.072782 -433.89931)
		(width 0.10668)
		(layer "F.Cu")
		(net "GPU_WP_HW_CTRL_ISO_N")
	)
	(segment
		(start 439.991754 -433.89931)
		(end 441.23356 -433.89931)
		(width 0.10668)
		(layer "F.Cu")
		(net "GPU_WP_HW_CTRL_ISO_N")
	)
	(segment
		(start 439.072782 -433.89931)
		(end 439.991754 -433.89931)
		(width 0.10668)
		(layer "F.Cu")
		(net "GPU_WP_HW_CTRL_ISO_N")
	)
	(via
		(at 439.991754 -433.89931)
		(size 0.508)
		(drill 0.254)
		(layers "F.Cu" "B.Cu")
		(net "GPU_WP_HW_CTRL_ISO_N")
	)
	(segment
		(start 429.691546 -435.362096)
		(end 432.88839 -435.362096)
		(width 0.10668)
		(layer "B.Cu")
		(net "GPU_WP_HW_CTRL_ISO_N")
	)
	(segment
		(start 438.715404 -440.136026)
		(end 438.715404 -435.17566)
		(width 0.10668)
		(layer "B.Cu")
		(net "GPU_WP_HW_CTRL_ISO_N")
	)
	(segment
		(start 438.588404 -440.263026)
		(end 438.715404 -440.136026)
		(width 0.10668)
		(layer "B.Cu")
		(net "GPU_WP_HW_CTRL_ISO_N")
	)
	(segment
		(start 402.498814 -440.489848)
		(end 401.82419 -439.815224)
		(width 0.10668)
		(layer "B.Cu")
		(net "GPU_WP_HW_CTRL_ISO_N")
	)
	(segment
		(start 433.196746 -435.670452)
		(end 434.860446 -435.670452)
		(width 0.10668)
		(layer "B.Cu")
		(net "GPU_WP_HW_CTRL_ISO_N")
	)
	(segment
		(start 435.633622 -440.263026)
		(end 438.588404 -440.263026)
		(width 0.10668)
		(layer "B.Cu")
		(net "GPU_WP_HW_CTRL_ISO_N")
	)
	(segment
		(start 432.88839 -435.362096)
		(end 433.196746 -435.670452)
		(width 0.10668)
		(layer "B.Cu")
		(net "GPU_WP_HW_CTRL_ISO_N")
	)
	(segment
		(start 423.175938 -431.445162)
		(end 425.14647 -433.415694)
		(width 0.10668)
		(layer "B.Cu")
		(net "GPU_WP_HW_CTRL_ISO_N")
	)
	(segment
		(start 418.547804 -431.445162)
		(end 423.175938 -431.445162)
		(width 0.10668)
		(layer "B.Cu")
		(net "GPU_WP_HW_CTRL_ISO_N")
	)
	(segment
		(start 427.745144 -433.415694)
		(end 429.691546 -435.362096)
		(width 0.10668)
		(layer "B.Cu")
		(net "GPU_WP_HW_CTRL_ISO_N")
	)
	(segment
		(start 401.82419 -424.20032)
		(end 402.71827 -423.30624)
		(width 0.10668)
		(layer "B.Cu")
		(net "GPU_WP_HW_CTRL_ISO_N")
	)
	(segment
		(start 425.14647 -433.415694)
		(end 427.745144 -433.415694)
		(width 0.10668)
		(layer "B.Cu")
		(net "GPU_WP_HW_CTRL_ISO_N")
	)
	(segment
		(start 402.71827 -423.30624)
		(end 413.60598 -423.30624)
		(width 0.10668)
		(layer "B.Cu")
		(net "GPU_WP_HW_CTRL_ISO_N")
	)
	(segment
		(start 435.2798 -439.909204)
		(end 435.633622 -440.263026)
		(width 0.10668)
		(layer "B.Cu")
		(net "GPU_WP_HW_CTRL_ISO_N")
	)
	(segment
		(start 413.60598 -423.30624)
		(end 416.017456 -425.717716)
		(width 0.10668)
		(layer "B.Cu")
		(net "GPU_WP_HW_CTRL_ISO_N")
	)
	(segment
		(start 435.2798 -436.089806)
		(end 435.2798 -439.909204)
		(width 0.10668)
		(layer "B.Cu")
		(net "GPU_WP_HW_CTRL_ISO_N")
	)
	(segment
		(start 438.715404 -435.17566)
		(end 439.991754 -433.89931)
		(width 0.10668)
		(layer "B.Cu")
		(net "GPU_WP_HW_CTRL_ISO_N")
	)
	(segment
		(start 434.860446 -435.670452)
		(end 435.2798 -436.089806)
		(width 0.10668)
		(layer "B.Cu")
		(net "GPU_WP_HW_CTRL_ISO_N")
	)
	(segment
		(start 402.75002 -440.489848)
		(end 402.498814 -440.489848)
		(width 0.10668)
		(layer "B.Cu")
		(net "GPU_WP_HW_CTRL_ISO_N")
	)
	(segment
		(start 416.017456 -428.914814)
		(end 418.547804 -431.445162)
		(width 0.10668)
		(layer "B.Cu")
		(net "GPU_WP_HW_CTRL_ISO_N")
	)
	(segment
		(start 401.82419 -439.815224)
		(end 401.82419 -424.20032)
		(width 0.10668)
		(layer "B.Cu")
		(net "GPU_WP_HW_CTRL_ISO_N")
	)
	(segment
		(start 416.017456 -425.717716)
		(end 416.017456 -428.914814)
		(width 0.10668)
		(layer "B.Cu")
		(net "GPU_WP_HW_CTRL_ISO_N")
	)
	(segment
		(start 190.542672 -171.661582)
		(end 190.542672 -172.511466)
		(width 0.10668)
		(layer "F.Cu")
		(net "FM_PDB_BUF_EN_R_N")
	)
	(segment
		(start 190.542672 -172.511466)
		(end 198.743824 -180.712618)
		(width 0.10668)
		(layer "F.Cu")
		(net "FM_PDB_BUF_EN_R_N")
	)
	(segment
		(start 210.070192 -193.775838)
		(end 209.565494 -194.280536)
		(width 0.10668)
		(layer "F.Cu")
		(net "FM_PDB_BUF_EN_R_N")
	)
	(segment
		(start 198.743824 -180.712618)
		(end 204.034136 -180.712618)
		(width 0.10668)
		(layer "F.Cu")
		(net "FM_PDB_BUF_EN_R_N")
	)
	(segment
		(start 191.055498 -429.528732)
		(end 191.055498 -430.009046)
		(width 0.10668)
		(layer "F.Cu")
		(net "FM_PDB_BUF_EN_R_N")
	)
	(segment
		(start 204.034136 -180.712618)
		(end 208.197704 -184.876186)
		(width 0.10668)
		(layer "F.Cu")
		(net "FM_PDB_BUF_EN_R_N")
	)
	(segment
		(start 191.055498 -430.009046)
		(end 191.162178 -430.115726)
		(width 0.10668)
		(layer "F.Cu")
		(net "FM_PDB_BUF_EN_R_N")
	)
	(segment
		(start 210.070192 -189.39637)
		(end 210.070192 -193.775838)
		(width 0.10668)
		(layer "F.Cu")
		(net "FM_PDB_BUF_EN_R_N")
	)
	(segment
		(start 191.162178 -430.115726)
		(end 192.300098 -430.115726)
		(width 0.10668)
		(layer "F.Cu")
		(net "FM_PDB_BUF_EN_R_N")
	)
	(segment
		(start 189.865 -95.703898)
		(end 189.865 -95.087948)
		(width 0.10668)
		(layer "F.Cu")
		(net "FM_PDB_BUF_EN_R_N")
	)
	(segment
		(start 208.197704 -184.876186)
		(end 210.070192 -189.39637)
		(width 0.10668)
		(layer "F.Cu")
		(net "FM_PDB_BUF_EN_R_N")
	)
	(via
		(at 165.754304 -126.482856)
		(size 0.508)
		(drill 0.254)
		(layers "F.Cu" "B.Cu")
		(net "FM_PDB_BUF_EN_R_N")
	)
	(via
		(at 189.865 -95.087948)
		(size 0.508)
		(drill 0.254)
		(layers "F.Cu" "B.Cu")
		(net "FM_PDB_BUF_EN_R_N")
	)
	(via
		(at 191.055498 -429.528732)
		(size 0.508)
		(drill 0.254)
		(layers "F.Cu" "B.Cu")
		(net "FM_PDB_BUF_EN_R_N")
	)
	(via
		(at 209.565494 -194.280536)
		(size 0.508)
		(drill 0.254)
		(layers "F.Cu" "B.Cu")
		(net "FM_PDB_BUF_EN_R_N")
	)
	(via
		(at 190.542672 -171.661582)
		(size 0.508)
		(drill 0.254)
		(layers "F.Cu" "B.Cu")
		(net "FM_PDB_BUF_EN_R_N")
	)
	(segment
		(start 172.69968 -152.724866)
		(end 172.69968 -135.292338)
		(width 0.10668)
		(layer "B.Cu")
		(net "FM_PDB_BUF_EN_R_N")
	)
	(segment
		(start 166.030148 -127.592582)
		(end 166.030148 -126.7587)
		(width 0.10668)
		(layer "B.Cu")
		(net "FM_PDB_BUF_EN_R_N")
	)
	(segment
		(start 187.041028 -167.225726)
		(end 178.035966 -167.225726)
		(width 0.10668)
		(layer "B.Cu")
		(net "FM_PDB_BUF_EN_R_N")
	)
	(segment
		(start 172.072554 -134.665212)
		(end 172.072554 -133.634988)
		(width 0.10668)
		(layer "B.Cu")
		(net "FM_PDB_BUF_EN_R_N")
	)
	(segment
		(start 190.542672 -171.661582)
		(end 190.542672 -170.72737)
		(width 0.10668)
		(layer "B.Cu")
		(net "FM_PDB_BUF_EN_R_N")
	)
	(segment
		(start 172.072554 -133.634988)
		(end 166.030148 -127.592582)
		(width 0.10668)
		(layer "B.Cu")
		(net "FM_PDB_BUF_EN_R_N")
	)
	(segment
		(start 178.035966 -167.225726)
		(end 177.275236 -166.464996)
		(width 0.10668)
		(layer "B.Cu")
		(net "FM_PDB_BUF_EN_R_N")
	)
	(segment
		(start 172.69968 -135.292338)
		(end 172.072554 -134.665212)
		(width 0.10668)
		(layer "B.Cu")
		(net "FM_PDB_BUF_EN_R_N")
	)
	(segment
		(start 190.542672 -170.72737)
		(end 187.041028 -167.225726)
		(width 0.10668)
		(layer "B.Cu")
		(net "FM_PDB_BUF_EN_R_N")
	)
	(segment
		(start 177.275236 -157.300422)
		(end 172.69968 -152.724866)
		(width 0.10668)
		(layer "B.Cu")
		(net "FM_PDB_BUF_EN_R_N")
	)
	(segment
		(start 177.275236 -166.464996)
		(end 177.275236 -157.300422)
		(width 0.10668)
		(layer "B.Cu")
		(net "FM_PDB_BUF_EN_R_N")
	)
	(segment
		(start 166.030148 -126.7587)
		(end 165.754304 -126.482856)
		(width 0.10668)
		(layer "B.Cu")
		(net "FM_PDB_BUF_EN_R_N")
	)
	(segment
		(start 188.461142 -429.528732)
		(end 191.055498 -429.528732)
		(width 0.11684)
		(layer "In6.Cu")
		(net "FM_PDB_BUF_EN_R_N")
	)
	(segment
		(start 191.930274 -375.937272)
		(end 190.353696 -375.937272)
		(width 0.11684)
		(layer "In6.Cu")
		(net "FM_PDB_BUF_EN_R_N")
	)
	(segment
		(start 178.562 -390.67232)
		(end 177.10658 -392.12774)
		(width 0.11684)
		(layer "In6.Cu")
		(net "FM_PDB_BUF_EN_R_N")
	)
	(segment
		(start 177.10658 -399.621502)
		(end 177.432716 -399.947638)
		(width 0.11684)
		(layer "In6.Cu")
		(net "FM_PDB_BUF_EN_R_N")
	)
	(segment
		(start 181.271418 -419.289992)
		(end 180.76164 -419.79977)
		(width 0.11684)
		(layer "In6.Cu")
		(net "FM_PDB_BUF_EN_R_N")
	)
	(segment
		(start 180.658262 -410.527754)
		(end 180.658262 -411.389322)
		(width 0.11684)
		(layer "In6.Cu")
		(net "FM_PDB_BUF_EN_R_N")
	)
	(segment
		(start 180.76164 -419.79977)
		(end 180.76164 -421.82923)
		(width 0.11684)
		(layer "In6.Cu")
		(net "FM_PDB_BUF_EN_R_N")
	)
	(segment
		(start 178.63058 -405.689308)
		(end 178.627786 -405.692102)
		(width 0.11684)
		(layer "In6.Cu")
		(net "FM_PDB_BUF_EN_R_N")
	)
	(segment
		(start 178.932586 -407.443432)
		(end 179.172616 -407.683462)
		(width 0.11684)
		(layer "In6.Cu")
		(net "FM_PDB_BUF_EN_R_N")
	)
	(segment
		(start 179.172616 -407.683462)
		(end 179.172616 -409.042108)
		(width 0.11684)
		(layer "In6.Cu")
		(net "FM_PDB_BUF_EN_R_N")
	)
	(segment
		(start 180.658262 -411.389322)
		(end 181.271418 -412.002478)
		(width 0.11684)
		(layer "In6.Cu")
		(net "FM_PDB_BUF_EN_R_N")
	)
	(segment
		(start 193.542412 -374.325134)
		(end 191.930274 -375.937272)
		(width 0.11684)
		(layer "In6.Cu")
		(net "FM_PDB_BUF_EN_R_N")
	)
	(segment
		(start 209.565494 -194.280536)
		(end 209.800698 -194.280536)
		(width 0.11684)
		(layer "In6.Cu")
		(net "FM_PDB_BUF_EN_R_N")
	)
	(segment
		(start 181.271418 -412.002478)
		(end 181.271418 -419.289992)
		(width 0.11684)
		(layer "In6.Cu")
		(net "FM_PDB_BUF_EN_R_N")
	)
	(segment
		(start 227.794566 -367.980722)
		(end 221.450154 -374.325134)
		(width 0.11684)
		(layer "In6.Cu")
		(net "FM_PDB_BUF_EN_R_N")
	)
	(segment
		(start 221.450154 -374.325134)
		(end 193.542412 -374.325134)
		(width 0.11684)
		(layer "In6.Cu")
		(net "FM_PDB_BUF_EN_R_N")
	)
	(segment
		(start 227.794566 -364.713774)
		(end 227.794566 -367.980722)
		(width 0.11684)
		(layer "In6.Cu")
		(net "FM_PDB_BUF_EN_R_N")
	)
	(segment
		(start 178.627786 -405.692102)
		(end 178.932586 -405.996902)
		(width 0.11684)
		(layer "In6.Cu")
		(net "FM_PDB_BUF_EN_R_N")
	)
	(segment
		(start 217.058748 -201.538586)
		(end 217.058748 -319.721484)
		(width 0.11684)
		(layer "In6.Cu")
		(net "FM_PDB_BUF_EN_R_N")
	)
	(segment
		(start 209.800698 -194.280536)
		(end 217.058748 -201.538586)
		(width 0.11684)
		(layer "In6.Cu")
		(net "FM_PDB_BUF_EN_R_N")
	)
	(segment
		(start 179.172616 -409.042108)
		(end 180.658262 -410.527754)
		(width 0.11684)
		(layer "In6.Cu")
		(net "FM_PDB_BUF_EN_R_N")
	)
	(segment
		(start 228.888036 -331.550772)
		(end 228.888036 -363.620304)
		(width 0.11684)
		(layer "In6.Cu")
		(net "FM_PDB_BUF_EN_R_N")
	)
	(segment
		(start 190.353696 -375.937272)
		(end 183.138064 -383.152904)
		(width 0.11684)
		(layer "In6.Cu")
		(net "FM_PDB_BUF_EN_R_N")
	)
	(segment
		(start 178.63058 -400.37004)
		(end 178.63058 -405.689308)
		(width 0.11684)
		(layer "In6.Cu")
		(net "FM_PDB_BUF_EN_R_N")
	)
	(segment
		(start 178.208178 -399.947638)
		(end 178.63058 -400.37004)
		(width 0.11684)
		(layer "In6.Cu")
		(net "FM_PDB_BUF_EN_R_N")
	)
	(segment
		(start 183.138064 -383.152904)
		(end 183.138064 -388.76605)
		(width 0.11684)
		(layer "In6.Cu")
		(net "FM_PDB_BUF_EN_R_N")
	)
	(segment
		(start 228.888036 -363.620304)
		(end 227.794566 -364.713774)
		(width 0.11684)
		(layer "In6.Cu")
		(net "FM_PDB_BUF_EN_R_N")
	)
	(segment
		(start 181.231794 -390.67232)
		(end 178.562 -390.67232)
		(width 0.11684)
		(layer "In6.Cu")
		(net "FM_PDB_BUF_EN_R_N")
	)
	(segment
		(start 177.10658 -392.12774)
		(end 177.10658 -399.621502)
		(width 0.11684)
		(layer "In6.Cu")
		(net "FM_PDB_BUF_EN_R_N")
	)
	(segment
		(start 217.058748 -319.721484)
		(end 228.888036 -331.550772)
		(width 0.11684)
		(layer "In6.Cu")
		(net "FM_PDB_BUF_EN_R_N")
	)
	(segment
		(start 178.932586 -405.996902)
		(end 178.932586 -407.443432)
		(width 0.11684)
		(layer "In6.Cu")
		(net "FM_PDB_BUF_EN_R_N")
	)
	(segment
		(start 183.138064 -388.76605)
		(end 181.231794 -390.67232)
		(width 0.11684)
		(layer "In6.Cu")
		(net "FM_PDB_BUF_EN_R_N")
	)
	(segment
		(start 180.76164 -421.82923)
		(end 188.461142 -429.528732)
		(width 0.11684)
		(layer "In6.Cu")
		(net "FM_PDB_BUF_EN_R_N")
	)
	(segment
		(start 177.432716 -399.947638)
		(end 178.208178 -399.947638)
		(width 0.11684)
		(layer "In6.Cu")
		(net "FM_PDB_BUF_EN_R_N")
	)
	(segment
		(start 165.75024 -103.517192)
		(end 165.246812 -103.517192)
		(width 0.11684)
		(layer "In15.Cu")
		(net "FM_PDB_BUF_EN_R_N")
	)
	(segment
		(start 161.91738 -112.573562)
		(end 162.850322 -113.506504)
		(width 0.11684)
		(layer "In15.Cu")
		(net "FM_PDB_BUF_EN_R_N")
	)
	(segment
		(start 171.30522 -91.087702)
		(end 166.858696 -95.534226)
		(width 0.11684)
		(layer "In15.Cu")
		(net "FM_PDB_BUF_EN_R_N")
	)
	(segment
		(start 162.473386 -111.844328)
		(end 162.219386 -111.844328)
		(width 0.11684)
		(layer "In15.Cu")
		(net "FM_PDB_BUF_EN_R_N")
	)
	(segment
		(start 160.420304 -123.064524)
		(end 160.420304 -126.675642)
		(width 0.11684)
		(layer "In15.Cu")
		(net "FM_PDB_BUF_EN_R_N")
	)
	(segment
		(start 162.850322 -113.506504)
		(end 162.850322 -120.634506)
		(width 0.11684)
		(layer "In15.Cu")
		(net "FM_PDB_BUF_EN_R_N")
	)
	(segment
		(start 162.824414 -111.107728)
		(end 162.824414 -111.4933)
		(width 0.11684)
		(layer "In15.Cu")
		(net "FM_PDB_BUF_EN_R_N")
	)
	(segment
		(start 161.843974 -110.414562)
		(end 162.14598 -110.716568)
		(width 0.11684)
		(layer "In15.Cu")
		(net "FM_PDB_BUF_EN_R_N")
	)
	(segment
		(start 162.219386 -111.844328)
		(end 161.91738 -112.146334)
		(width 0.11684)
		(layer "In15.Cu")
		(net "FM_PDB_BUF_EN_R_N")
	)
	(segment
		(start 176.76495 -91.087702)
		(end 171.30522 -91.087702)
		(width 0.11684)
		(layer "In15.Cu")
		(net "FM_PDB_BUF_EN_R_N")
	)
	(segment
		(start 182.26278 -93.858334)
		(end 182.26278 -93.559122)
		(width 0.11684)
		(layer "In15.Cu")
		(net "FM_PDB_BUF_EN_R_N")
	)
	(segment
		(start 162.850322 -120.634506)
		(end 160.420304 -123.064524)
		(width 0.11684)
		(layer "In15.Cu")
		(net "FM_PDB_BUF_EN_R_N")
	)
	(segment
		(start 162.824414 -111.4933)
		(end 162.473386 -111.844328)
		(width 0.11684)
		(layer "In15.Cu")
		(net "FM_PDB_BUF_EN_R_N")
	)
	(segment
		(start 182.26278 -93.559122)
		(end 181.476904 -92.773246)
		(width 0.11684)
		(layer "In15.Cu")
		(net "FM_PDB_BUF_EN_R_N")
	)
	(segment
		(start 164.721286 -126.947676)
		(end 165.186106 -126.482856)
		(width 0.11684)
		(layer "In15.Cu")
		(net "FM_PDB_BUF_EN_R_N")
	)
	(segment
		(start 189.041532 -96.350836)
		(end 184.755282 -96.350836)
		(width 0.11684)
		(layer "In15.Cu")
		(net "FM_PDB_BUF_EN_R_N")
	)
	(segment
		(start 181.476904 -92.773246)
		(end 178.450494 -92.773246)
		(width 0.11684)
		(layer "In15.Cu")
		(net "FM_PDB_BUF_EN_R_N")
	)
	(segment
		(start 165.186106 -126.482856)
		(end 165.754304 -126.482856)
		(width 0.11684)
		(layer "In15.Cu")
		(net "FM_PDB_BUF_EN_R_N")
	)
	(segment
		(start 178.450494 -92.773246)
		(end 176.76495 -91.087702)
		(width 0.11684)
		(layer "In15.Cu")
		(net "FM_PDB_BUF_EN_R_N")
	)
	(segment
		(start 162.573462 -106.190542)
		(end 162.573462 -109.257846)
		(width 0.11684)
		(layer "In15.Cu")
		(net "FM_PDB_BUF_EN_R_N")
	)
	(segment
		(start 160.420304 -126.675642)
		(end 160.692338 -126.947676)
		(width 0.11684)
		(layer "In15.Cu")
		(net "FM_PDB_BUF_EN_R_N")
	)
	(segment
		(start 161.91738 -112.146334)
		(end 161.91738 -112.573562)
		(width 0.11684)
		(layer "In15.Cu")
		(net "FM_PDB_BUF_EN_R_N")
	)
	(segment
		(start 160.692338 -126.947676)
		(end 164.721286 -126.947676)
		(width 0.11684)
		(layer "In15.Cu")
		(net "FM_PDB_BUF_EN_R_N")
	)
	(segment
		(start 162.14598 -110.716568)
		(end 162.433254 -110.716568)
		(width 0.11684)
		(layer "In15.Cu")
		(net "FM_PDB_BUF_EN_R_N")
	)
	(segment
		(start 166.858696 -102.408736)
		(end 165.75024 -103.517192)
		(width 0.11684)
		(layer "In15.Cu")
		(net "FM_PDB_BUF_EN_R_N")
	)
	(segment
		(start 189.865 -95.527368)
		(end 189.041532 -96.350836)
		(width 0.11684)
		(layer "In15.Cu")
		(net "FM_PDB_BUF_EN_R_N")
	)
	(segment
		(start 161.843974 -109.987334)
		(end 161.843974 -110.414562)
		(width 0.11684)
		(layer "In15.Cu")
		(net "FM_PDB_BUF_EN_R_N")
	)
	(segment
		(start 165.246812 -103.517192)
		(end 162.573462 -106.190542)
		(width 0.11684)
		(layer "In15.Cu")
		(net "FM_PDB_BUF_EN_R_N")
	)
	(segment
		(start 166.858696 -95.534226)
		(end 166.858696 -102.408736)
		(width 0.11684)
		(layer "In15.Cu")
		(net "FM_PDB_BUF_EN_R_N")
	)
	(segment
		(start 189.865 -95.087948)
		(end 189.865 -95.527368)
		(width 0.11684)
		(layer "In15.Cu")
		(net "FM_PDB_BUF_EN_R_N")
	)
	(segment
		(start 162.573462 -109.257846)
		(end 161.843974 -109.987334)
		(width 0.11684)
		(layer "In15.Cu")
		(net "FM_PDB_BUF_EN_R_N")
	)
	(segment
		(start 162.433254 -110.716568)
		(end 162.824414 -111.107728)
		(width 0.11684)
		(layer "In15.Cu")
		(net "FM_PDB_BUF_EN_R_N")
	)
	(segment
		(start 184.755282 -96.350836)
		(end 182.26278 -93.858334)
		(width 0.11684)
		(layer "In15.Cu")
		(net "FM_PDB_BUF_EN_R_N")
	)
	(segment
		(start 193.100198 -429.667416)
		(end 192.973198 -429.540416)
		(width 0.10668)
		(layer "F.Cu")
		(net "FM_PDB_BUF_EN_R1_N")
	)
	(segment
		(start 191.91097 -429.540416)
		(end 191.70142 -429.330866)
		(width 0.10668)
		(layer "F.Cu")
		(net "FM_PDB_BUF_EN_R1_N")
	)
	(segment
		(start 192.973198 -429.540416)
		(end 191.91097 -429.540416)
		(width 0.10668)
		(layer "F.Cu")
		(net "FM_PDB_BUF_EN_R1_N")
	)
	(segment
		(start 191.70142 -428.982886)
		(end 191.61506 -428.896526)
		(width 0.10668)
		(layer "F.Cu")
		(net "FM_PDB_BUF_EN_R1_N")
	)
	(segment
		(start 194.578986 -430.115726)
		(end 193.100198 -430.115726)
		(width 0.10668)
		(layer "F.Cu")
		(net "FM_PDB_BUF_EN_R1_N")
	)
	(segment
		(start 195.189602 -428.693326)
		(end 195.189602 -429.50511)
		(width 0.10668)
		(layer "F.Cu")
		(net "FM_PDB_BUF_EN_R1_N")
	)
	(segment
		(start 195.189602 -429.50511)
		(end 194.578986 -430.115726)
		(width 0.10668)
		(layer "F.Cu")
		(net "FM_PDB_BUF_EN_R1_N")
	)
	(segment
		(start 193.100198 -430.115726)
		(end 193.100198 -429.667416)
		(width 0.10668)
		(layer "F.Cu")
		(net "FM_PDB_BUF_EN_R1_N")
	)
	(segment
		(start 194.319398 -428.693326)
		(end 195.189602 -428.693326)
		(width 0.10668)
		(layer "F.Cu")
		(net "FM_PDB_BUF_EN_R1_N")
	)
	(segment
		(start 191.61506 -428.896526)
		(end 191.055498 -428.896526)
		(width 0.10668)
		(layer "F.Cu")
		(net "FM_PDB_BUF_EN_R1_N")
	)
	(segment
		(start 191.70142 -429.330866)
		(end 191.70142 -428.982886)
		(width 0.10668)
		(layer "F.Cu")
		(net "FM_PDB_BUF_EN_R1_N")
	)
	(via
		(at 195.189602 -428.693326)
		(size 0.508)
		(drill 0.254)
		(layers "F.Cu" "B.Cu")
		(net "FM_PDB_BUF_EN_R1_N")
	)
	(segment
		(start 105.49636 -412.350712)
		(end 104.734868 -413.112204)
		(width 0.10668)
		(layer "F.Cu")
		(net "SMB_9ZXL045_P1_SDA")
	)
	(segment
		(start 103.525574 -414.329626)
		(end 104.224582 -413.630618)
		(width 0.10668)
		(layer "F.Cu")
		(net "SMB_9ZXL045_P1_SDA")
	)
	(segment
		(start 104.224582 -413.630618)
		(end 104.734868 -413.630618)
		(width 0.10668)
		(layer "F.Cu")
		(net "SMB_9ZXL045_P1_SDA")
	)
	(segment
		(start 105.49636 -412.00705)
		(end 105.49636 -412.350712)
		(width 0.10668)
		(layer "F.Cu")
		(net "SMB_9ZXL045_P1_SDA")
	)
	(segment
		(start 104.734868 -413.112204)
		(end 104.734868 -413.630618)
		(width 0.10668)
		(layer "F.Cu")
		(net "SMB_9ZXL045_P1_SDA")
	)
	(via
		(at 104.734868 -413.630618)
		(size 0.762)
		(drill 0.381)
		(layers "F.Cu" "B.Cu")
		(net "SMB_9ZXL045_P1_SDA")
	)
	(segment
		(start 104.996488 -412.357824)
		(end 104.996488 -412.00705)
		(width 0.10668)
		(layer "F.Cu")
		(net "SMB_9ZXL045_P1_SCL")
	)
	(segment
		(start 103.4034 -412.978346)
		(end 103.549704 -413.12465)
		(width 0.10668)
		(layer "F.Cu")
		(net "SMB_9ZXL045_P1_SCL")
	)
	(segment
		(start 103.549704 -413.12465)
		(end 104.229662 -413.12465)
		(width 0.10668)
		(layer "F.Cu")
		(net "SMB_9ZXL045_P1_SCL")
	)
	(segment
		(start 104.229662 -413.12465)
		(end 104.996488 -412.357824)
		(width 0.10668)
		(layer "F.Cu")
		(net "SMB_9ZXL045_P1_SCL")
	)
	(segment
		(start 102.354126 -412.978346)
		(end 103.4034 -412.978346)
		(width 0.10668)
		(layer "F.Cu")
		(net "SMB_9ZXL045_P1_SCL")
	)
	(via
		(at 103.549704 -413.12465)
		(size 0.762)
		(drill 0.381)
		(layers "F.Cu" "B.Cu")
		(net "SMB_9ZXL045_P1_SCL")
	)
	(segment
		(start 281.288998 -416.459162)
		(end 282.236418 -417.406582)
		(width 0.10668)
		(layer "F.Cu")
		(net "SMB_9ZXL045_P0_SDA")
	)
	(segment
		(start 282.402788 -417.572952)
		(end 283.506164 -417.572952)
		(width 0.10668)
		(layer "F.Cu")
		(net "SMB_9ZXL045_P0_SDA")
	)
	(segment
		(start 282.236418 -417.406582)
		(end 282.402788 -417.572952)
		(width 0.10668)
		(layer "F.Cu")
		(net "SMB_9ZXL045_P0_SDA")
	)
	(segment
		(start 280.059892 -415.1376)
		(end 280.059892 -415.59099)
		(width 0.10668)
		(layer "F.Cu")
		(net "SMB_9ZXL045_P0_SDA")
	)
	(segment
		(start 280.928064 -416.459162)
		(end 281.288998 -416.459162)
		(width 0.10668)
		(layer "F.Cu")
		(net "SMB_9ZXL045_P0_SDA")
	)
	(segment
		(start 280.059892 -415.59099)
		(end 280.928064 -416.459162)
		(width 0.10668)
		(layer "F.Cu")
		(net "SMB_9ZXL045_P0_SDA")
	)
	(via
		(at 282.236418 -417.406582)
		(size 0.762)
		(drill 0.381)
		(layers "F.Cu" "B.Cu")
		(net "SMB_9ZXL045_P0_SDA")
	)
	(segment
		(start 280.46553 -414.62452)
		(end 280.46553 -414.42894)
		(width 0.10668)
		(layer "F.Cu")
		(net "SMB_9ZXL045_P0_SCL")
	)
	(segment
		(start 280.108914 -414.072324)
		(end 280.108914 -414.051242)
		(width 0.10668)
		(layer "F.Cu")
		(net "SMB_9ZXL045_P0_SCL")
	)
	(segment
		(start 283.506164 -417.07308)
		(end 282.91409 -417.07308)
		(width 0.10668)
		(layer "F.Cu")
		(net "SMB_9ZXL045_P0_SCL")
	)
	(segment
		(start 281.372564 -415.531554)
		(end 280.46553 -414.62452)
		(width 0.10668)
		(layer "F.Cu")
		(net "SMB_9ZXL045_P0_SCL")
	)
	(segment
		(start 282.91409 -417.07308)
		(end 281.372564 -415.531554)
		(width 0.10668)
		(layer "F.Cu")
		(net "SMB_9ZXL045_P0_SCL")
	)
	(segment
		(start 280.46553 -414.42894)
		(end 280.108914 -414.072324)
		(width 0.10668)
		(layer "F.Cu")
		(net "SMB_9ZXL045_P0_SCL")
	)
	(via
		(at 281.372564 -415.531554)
		(size 0.762)
		(drill 0.381)
		(layers "F.Cu" "B.Cu")
		(net "SMB_9ZXL045_P0_SCL")
	)
	(segment
		(start 176.97196 -136.61517)
		(end 177.042572 -136.544558)
		(width 0.10668)
		(layer "F.Cu")
		(net "PWRGD_P0V9_RETIMER_CPU1_R2")
	)
	(segment
		(start 176.97196 -136.632696)
		(end 176.97196 -136.61517)
		(width 0.10668)
		(layer "F.Cu")
		(net "PWRGD_P0V9_RETIMER_CPU1_R2")
	)
	(segment
		(start 180.32222 -121.852944)
		(end 179.93233 -122.242834)
		(width 0.10668)
		(layer "F.Cu")
		(net "PWRGD_P0V9_RETIMER_CPU1_R2")
	)
	(segment
		(start 176.855882 -137.340848)
		(end 176.855882 -136.748774)
		(width 0.10668)
		(layer "F.Cu")
		(net "PWRGD_P0V9_RETIMER_CPU1_R2")
	)
	(segment
		(start 176.855882 -136.748774)
		(end 176.97196 -136.632696)
		(width 0.10668)
		(layer "F.Cu")
		(net "PWRGD_P0V9_RETIMER_CPU1_R2")
	)
	(via
		(at 177.042572 -136.544558)
		(size 0.508)
		(drill 0.254)
		(layers "F.Cu" "B.Cu")
		(net "PWRGD_P0V9_RETIMER_CPU1_R2")
	)
	(via
		(at 179.93233 -122.242834)
		(size 0.4572)
		(drill 0.254)
		(layers "F.Cu" "B.Cu")
		(net "PWRGD_P0V9_RETIMER_CPU1_R2")
	)
	(segment
		(start 179.528724 -122.896122)
		(end 179.528724 -125.767592)
		(width 0.11684)
		(layer "In11.Cu")
		(net "PWRGD_P0V9_RETIMER_CPU1_R2")
	)
	(segment
		(start 179.528724 -125.767592)
		(end 178.667918 -126.628398)
		(width 0.11684)
		(layer "In11.Cu")
		(net "PWRGD_P0V9_RETIMER_CPU1_R2")
	)
	(segment
		(start 174.043594 -126.794768)
		(end 174.043594 -129.682494)
		(width 0.11684)
		(layer "In11.Cu")
		(net "PWRGD_P0V9_RETIMER_CPU1_R2")
	)
	(segment
		(start 174.043594 -129.682494)
		(end 174.598838 -130.237738)
		(width 0.11684)
		(layer "In11.Cu")
		(net "PWRGD_P0V9_RETIMER_CPU1_R2")
	)
	(segment
		(start 178.667918 -126.628398)
		(end 174.209964 -126.628398)
		(width 0.11684)
		(layer "In11.Cu")
		(net "PWRGD_P0V9_RETIMER_CPU1_R2")
	)
	(segment
		(start 174.598838 -130.237738)
		(end 174.598838 -130.967988)
		(width 0.11684)
		(layer "In11.Cu")
		(net "PWRGD_P0V9_RETIMER_CPU1_R2")
	)
	(segment
		(start 179.93233 -122.242834)
		(end 179.93233 -122.492516)
		(width 0.11684)
		(layer "In11.Cu")
		(net "PWRGD_P0V9_RETIMER_CPU1_R2")
	)
	(segment
		(start 179.93233 -122.492516)
		(end 179.528724 -122.896122)
		(width 0.11684)
		(layer "In11.Cu")
		(net "PWRGD_P0V9_RETIMER_CPU1_R2")
	)
	(segment
		(start 175.88357 -132.25272)
		(end 175.88357 -135.385556)
		(width 0.11684)
		(layer "In11.Cu")
		(net "PWRGD_P0V9_RETIMER_CPU1_R2")
	)
	(segment
		(start 174.209964 -126.628398)
		(end 174.043594 -126.794768)
		(width 0.11684)
		(layer "In11.Cu")
		(net "PWRGD_P0V9_RETIMER_CPU1_R2")
	)
	(segment
		(start 175.88357 -135.385556)
		(end 177.042572 -136.544558)
		(width 0.11684)
		(layer "In11.Cu")
		(net "PWRGD_P0V9_RETIMER_CPU1_R2")
	)
	(segment
		(start 174.598838 -130.967988)
		(end 175.88357 -132.25272)
		(width 0.11684)
		(layer "In11.Cu")
		(net "PWRGD_P0V9_RETIMER_CPU1_R2")
	)
	(segment
		(start 179.52212 -121.052844)
		(end 179.13223 -121.442734)
		(width 0.10668)
		(layer "F.Cu")
		(net "PWRGD_P0V9_RETIMER_CPU0_R2")
	)
	(via
		(at 176.2506 -124.9934)
		(size 0.6604)
		(drill 0.3302)
		(layers "F.Cu" "B.Cu")
		(net "PWRGD_P0V9_RETIMER_CPU0_R2")
	)
	(via
		(at 179.13223 -121.442734)
		(size 0.4572)
		(drill 0.254)
		(layers "F.Cu" "B.Cu")
		(net "PWRGD_P0V9_RETIMER_CPU0_R2")
	)
	(segment
		(start 179.13223 -121.442734)
		(end 179.13223 -121.60377)
		(width 0.10668)
		(layer "B.Cu")
		(net "PWRGD_P0V9_RETIMER_CPU0_R2")
	)
	(segment
		(start 178.73599 -122.00001)
		(end 178.73599 -123.65101)
		(width 0.10668)
		(layer "B.Cu")
		(net "PWRGD_P0V9_RETIMER_CPU0_R2")
	)
	(segment
		(start 177.3936 -124.9934)
		(end 176.2506 -124.9934)
		(width 0.10668)
		(layer "B.Cu")
		(net "PWRGD_P0V9_RETIMER_CPU0_R2")
	)
	(segment
		(start 175.53305 -125.71095)
		(end 176.2506 -124.9934)
		(width 0.10668)
		(layer "B.Cu")
		(net "PWRGD_P0V9_RETIMER_CPU0_R2")
	)
	(segment
		(start 179.13223 -121.60377)
		(end 178.73599 -122.00001)
		(width 0.10668)
		(layer "B.Cu")
		(net "PWRGD_P0V9_RETIMER_CPU0_R2")
	)
	(segment
		(start 175.53305 -126.238)
		(end 175.53305 -125.71095)
		(width 0.10668)
		(layer "B.Cu")
		(net "PWRGD_P0V9_RETIMER_CPU0_R2")
	)
	(segment
		(start 178.73599 -123.65101)
		(end 177.3936 -124.9934)
		(width 0.10668)
		(layer "B.Cu")
		(net "PWRGD_P0V9_RETIMER_CPU0_R2")
	)
	(segment
		(start 173.519846 -124.840238)
		(end 173.031658 -124.35205)
		(width 0.10668)
		(layer "F.Cu")
		(net "P1V8_RETIMER_CPU1_R_EN")
	)
	(segment
		(start 174.026068 -124.736352)
		(end 175.265334 -124.736352)
		(width 0.10668)
		(layer "F.Cu")
		(net "P1V8_RETIMER_CPU1_R_EN")
	)
	(segment
		(start 175.265334 -124.736352)
		(end 175.884078 -124.117608)
		(width 0.10668)
		(layer "F.Cu")
		(net "P1V8_RETIMER_CPU1_R_EN")
	)
	(segment
		(start 173.120812 -126.492)
		(end 173.519846 -126.092966)
		(width 0.10668)
		(layer "F.Cu")
		(net "P1V8_RETIMER_CPU1_R_EN")
	)
	(segment
		(start 173.031658 -124.35205)
		(end 173.031658 -124.058426)
		(width 0.10668)
		(layer "F.Cu")
		(net "P1V8_RETIMER_CPU1_R_EN")
	)
	(segment
		(start 170.144694 -128.24333)
		(end 171.896024 -126.492)
		(width 0.10668)
		(layer "F.Cu")
		(net "P1V8_RETIMER_CPU1_R_EN")
	)
	(segment
		(start 171.896024 -126.492)
		(end 173.120812 -126.492)
		(width 0.10668)
		(layer "F.Cu")
		(net "P1V8_RETIMER_CPU1_R_EN")
	)
	(segment
		(start 175.884078 -124.117608)
		(end 175.884078 -123.09094)
		(width 0.10668)
		(layer "F.Cu")
		(net "P1V8_RETIMER_CPU1_R_EN")
	)
	(segment
		(start 175.884078 -123.09094)
		(end 177.122074 -121.852944)
		(width 0.10668)
		(layer "F.Cu")
		(net "P1V8_RETIMER_CPU1_R_EN")
	)
	(segment
		(start 173.348142 -124.058426)
		(end 174.026068 -124.736352)
		(width 0.10668)
		(layer "F.Cu")
		(net "P1V8_RETIMER_CPU1_R_EN")
	)
	(segment
		(start 173.519846 -126.092966)
		(end 173.519846 -124.840238)
		(width 0.10668)
		(layer "F.Cu")
		(net "P1V8_RETIMER_CPU1_R_EN")
	)
	(segment
		(start 173.031658 -124.058426)
		(end 173.348142 -124.058426)
		(width 0.10668)
		(layer "F.Cu")
		(net "P1V8_RETIMER_CPU1_R_EN")
	)
	(via
		(at 173.031658 -124.058426)
		(size 0.762)
		(drill 0.381)
		(layers "F.Cu" "B.Cu")
		(net "P1V8_RETIMER_CPU1_R_EN")
	)
	(segment
		(start 172.176694 -128.24333)
		(end 172.176694 -127.436626)
		(width 0.10668)
		(layer "F.Cu")
		(net "P1V8_RETIMER_CPU0_R_EN")
	)
	(segment
		(start 172.176694 -127.436626)
		(end 172.469048 -127.144272)
		(width 0.10668)
		(layer "F.Cu")
		(net "P1V8_RETIMER_CPU0_R_EN")
	)
	(segment
		(start 172.469048 -127.144272)
		(end 173.46041 -127.144272)
		(width 0.10668)
		(layer "F.Cu")
		(net "P1V8_RETIMER_CPU0_R_EN")
	)
	(segment
		(start 177.922174 -117.852952)
		(end 177.532284 -118.242842)
		(width 0.10668)
		(layer "F.Cu")
		(net "P1V8_RETIMER_CPU0_R_EN")
	)
	(via
		(at 177.532284 -118.242842)
		(size 0.4572)
		(drill 0.254)
		(layers "F.Cu" "B.Cu")
		(net "P1V8_RETIMER_CPU0_R_EN")
	)
	(via
		(at 178.217068 -123.038616)
		(size 0.6604)
		(drill 0.3302)
		(layers "F.Cu" "B.Cu")
		(net "P1V8_RETIMER_CPU0_R_EN")
	)
	(via
		(at 173.46041 -127.144272)
		(size 0.508)
		(drill 0.254)
		(layers "F.Cu" "B.Cu")
		(net "P1V8_RETIMER_CPU0_R_EN")
	)
	(segment
		(start 177.93589 -117.839236)
		(end 180.901848 -117.839236)
		(width 0.10668)
		(layer "B.Cu")
		(net "P1V8_RETIMER_CPU0_R_EN")
	)
	(segment
		(start 180.335936 -120.023128)
		(end 180.120036 -120.239028)
		(width 0.10668)
		(layer "B.Cu")
		(net "P1V8_RETIMER_CPU0_R_EN")
	)
	(segment
		(start 177.932588 -122.754136)
		(end 178.217068 -123.038616)
		(width 0.10668)
		(layer "B.Cu")
		(net "P1V8_RETIMER_CPU0_R_EN")
	)
	(segment
		(start 179.321968 -121.042176)
		(end 178.968908 -121.042176)
		(width 0.10668)
		(layer "B.Cu")
		(net "P1V8_RETIMER_CPU0_R_EN")
	)
	(segment
		(start 177.523648 -124.412248)
		(end 178.217068 -123.718828)
		(width 0.10668)
		(layer "B.Cu")
		(net "P1V8_RETIMER_CPU0_R_EN")
	)
	(segment
		(start 180.490368 -119.441976)
		(end 180.335936 -119.596408)
		(width 0.10668)
		(layer "B.Cu")
		(net "P1V8_RETIMER_CPU0_R_EN")
	)
	(segment
		(start 178.968908 -121.042176)
		(end 178.732688 -121.278396)
		(width 0.10668)
		(layer "B.Cu")
		(net "P1V8_RETIMER_CPU0_R_EN")
	)
	(segment
		(start 181.128416 -119.250968)
		(end 180.937408 -119.441976)
		(width 0.10668)
		(layer "B.Cu")
		(net "P1V8_RETIMER_CPU0_R_EN")
	)
	(segment
		(start 180.335936 -119.596408)
		(end 180.335936 -120.023128)
		(width 0.10668)
		(layer "B.Cu")
		(net "P1V8_RETIMER_CPU0_R_EN")
	)
	(segment
		(start 178.217068 -123.718828)
		(end 178.217068 -123.038616)
		(width 0.10668)
		(layer "B.Cu")
		(net "P1V8_RETIMER_CPU0_R_EN")
	)
	(segment
		(start 179.535328 -120.479058)
		(end 179.535328 -120.828816)
		(width 0.10668)
		(layer "B.Cu")
		(net "P1V8_RETIMER_CPU0_R_EN")
	)
	(segment
		(start 173.46041 -127.144272)
		(end 173.459902 -127.143764)
		(width 0.10668)
		(layer "B.Cu")
		(net "P1V8_RETIMER_CPU0_R_EN")
	)
	(segment
		(start 180.901848 -117.839236)
		(end 181.128416 -118.065804)
		(width 0.10668)
		(layer "B.Cu")
		(net "P1V8_RETIMER_CPU0_R_EN")
	)
	(segment
		(start 173.459902 -127.143764)
		(end 173.459902 -126.311914)
		(width 0.10668)
		(layer "B.Cu")
		(net "P1V8_RETIMER_CPU0_R_EN")
	)
	(segment
		(start 173.459902 -126.311914)
		(end 175.359568 -124.412248)
		(width 0.10668)
		(layer "B.Cu")
		(net "P1V8_RETIMER_CPU0_R_EN")
	)
	(segment
		(start 175.359568 -124.412248)
		(end 177.523648 -124.412248)
		(width 0.10668)
		(layer "B.Cu")
		(net "P1V8_RETIMER_CPU0_R_EN")
	)
	(segment
		(start 177.532284 -118.242842)
		(end 177.93589 -117.839236)
		(width 0.10668)
		(layer "B.Cu")
		(net "P1V8_RETIMER_CPU0_R_EN")
	)
	(segment
		(start 178.059588 -121.839736)
		(end 177.932588 -121.966736)
		(width 0.10668)
		(layer "B.Cu")
		(net "P1V8_RETIMER_CPU0_R_EN")
	)
	(segment
		(start 179.535328 -120.828816)
		(end 179.321968 -121.042176)
		(width 0.10668)
		(layer "B.Cu")
		(net "P1V8_RETIMER_CPU0_R_EN")
	)
	(segment
		(start 178.732688 -121.608596)
		(end 178.501548 -121.839736)
		(width 0.10668)
		(layer "B.Cu")
		(net "P1V8_RETIMER_CPU0_R_EN")
	)
	(segment
		(start 177.932588 -121.966736)
		(end 177.932588 -122.754136)
		(width 0.10668)
		(layer "B.Cu")
		(net "P1V8_RETIMER_CPU0_R_EN")
	)
	(segment
		(start 178.732688 -121.278396)
		(end 178.732688 -121.608596)
		(width 0.10668)
		(layer "B.Cu")
		(net "P1V8_RETIMER_CPU0_R_EN")
	)
	(segment
		(start 178.501548 -121.839736)
		(end 178.059588 -121.839736)
		(width 0.10668)
		(layer "B.Cu")
		(net "P1V8_RETIMER_CPU0_R_EN")
	)
	(segment
		(start 181.128416 -118.065804)
		(end 181.128416 -119.250968)
		(width 0.10668)
		(layer "B.Cu")
		(net "P1V8_RETIMER_CPU0_R_EN")
	)
	(segment
		(start 180.937408 -119.441976)
		(end 180.490368 -119.441976)
		(width 0.10668)
		(layer "B.Cu")
		(net "P1V8_RETIMER_CPU0_R_EN")
	)
	(segment
		(start 180.120036 -120.239028)
		(end 179.775358 -120.239028)
		(width 0.10668)
		(layer "B.Cu")
		(net "P1V8_RETIMER_CPU0_R_EN")
	)
	(segment
		(start 179.775358 -120.239028)
		(end 179.535328 -120.479058)
		(width 0.10668)
		(layer "B.Cu")
		(net "P1V8_RETIMER_CPU0_R_EN")
	)
	(segment
		(start 195.205096 -125.792484)
		(end 195.944236 -126.531624)
		(width 0.10668)
		(layer "F.Cu")
		(net "P0V9_RETIMER_CPU1_EN_R2")
	)
	(segment
		(start 195.29552 -132.659628)
		(end 195.29552 -134.549388)
		(width 0.10668)
		(layer "F.Cu")
		(net "P0V9_RETIMER_CPU1_EN_R2")
	)
	(segment
		(start 195.46951 -135.73887)
		(end 195.7832 -136.05256)
		(width 0.10668)
		(layer "F.Cu")
		(net "P0V9_RETIMER_CPU1_EN_R2")
	)
	(segment
		(start 193.523108 -123.64466)
		(end 194.126612 -124.248164)
		(width 0.10668)
		(layer "F.Cu")
		(net "P0V9_RETIMER_CPU1_EN_R2")
	)
	(segment
		(start 195.205096 -124.657612)
		(end 195.205096 -125.792484)
		(width 0.10668)
		(layer "F.Cu")
		(net "P0V9_RETIMER_CPU1_EN_R2")
	)
	(segment
		(start 196.320664 -129.598674)
		(end 196.320664 -131.634484)
		(width 0.10668)
		(layer "F.Cu")
		(net "P0V9_RETIMER_CPU1_EN_R2")
	)
	(segment
		(start 195.29552 -134.549388)
		(end 195.46951 -134.723378)
		(width 0.10668)
		(layer "F.Cu")
		(net "P0V9_RETIMER_CPU1_EN_R2")
	)
	(segment
		(start 193.523108 -123.053856)
		(end 193.523108 -123.64466)
		(width 0.10668)
		(layer "F.Cu")
		(net "P0V9_RETIMER_CPU1_EN_R2")
	)
	(segment
		(start 193.122042 -122.65279)
		(end 193.523108 -123.053856)
		(width 0.10668)
		(layer "F.Cu")
		(net "P0V9_RETIMER_CPU1_EN_R2")
	)
	(segment
		(start 195.7832 -136.73455)
		(end 195.7832 -136.05256)
		(width 0.10668)
		(layer "F.Cu")
		(net "P0V9_RETIMER_CPU1_EN_R2")
	)
	(segment
		(start 195.46951 -134.723378)
		(end 195.46951 -135.73887)
		(width 0.10668)
		(layer "F.Cu")
		(net "P0V9_RETIMER_CPU1_EN_R2")
	)
	(segment
		(start 195.944236 -129.222246)
		(end 196.320664 -129.598674)
		(width 0.10668)
		(layer "F.Cu")
		(net "P0V9_RETIMER_CPU1_EN_R2")
	)
	(segment
		(start 194.126612 -124.248164)
		(end 194.795648 -124.248164)
		(width 0.10668)
		(layer "F.Cu")
		(net "P0V9_RETIMER_CPU1_EN_R2")
	)
	(segment
		(start 194.795648 -124.248164)
		(end 195.205096 -124.657612)
		(width 0.10668)
		(layer "F.Cu")
		(net "P0V9_RETIMER_CPU1_EN_R2")
	)
	(segment
		(start 195.2498 -137.26795)
		(end 195.7832 -136.73455)
		(width 0.10668)
		(layer "F.Cu")
		(net "P0V9_RETIMER_CPU1_EN_R2")
	)
	(segment
		(start 196.320664 -131.634484)
		(end 195.29552 -132.659628)
		(width 0.10668)
		(layer "F.Cu")
		(net "P0V9_RETIMER_CPU1_EN_R2")
	)
	(segment
		(start 195.944236 -126.531624)
		(end 195.944236 -129.222246)
		(width 0.10668)
		(layer "F.Cu")
		(net "P0V9_RETIMER_CPU1_EN_R2")
	)
	(via
		(at 195.7832 -136.05256)
		(size 0.762)
		(drill 0.381)
		(layers "F.Cu" "B.Cu")
		(net "P0V9_RETIMER_CPU1_EN_R2")
	)
	(segment
		(start 193.122042 -113.85296)
		(end 193.511932 -113.46307)
		(width 0.10668)
		(layer "F.Cu")
		(net "P0V9_RETIMER_CPU0_EN_R2")
	)
	(via
		(at 193.511932 -113.46307)
		(size 0.4572)
		(drill 0.254)
		(layers "F.Cu" "B.Cu")
		(net "P0V9_RETIMER_CPU0_EN_R2")
	)
	(via
		(at 194.409822 -112.773206)
		(size 0.6604)
		(drill 0.3302)
		(layers "F.Cu" "B.Cu")
		(net "P0V9_RETIMER_CPU0_EN_R2")
	)
	(segment
		(start 194.201796 -112.773206)
		(end 194.409822 -112.773206)
		(width 0.10668)
		(layer "B.Cu")
		(net "P0V9_RETIMER_CPU0_EN_R2")
	)
	(segment
		(start 195.137024 -112.98682)
		(end 195.98513 -112.98682)
		(width 0.10668)
		(layer "B.Cu")
		(net "P0V9_RETIMER_CPU0_EN_R2")
	)
	(segment
		(start 194.92341 -112.773206)
		(end 195.137024 -112.98682)
		(width 0.10668)
		(layer "B.Cu")
		(net "P0V9_RETIMER_CPU0_EN_R2")
	)
	(segment
		(start 195.98513 -112.98682)
		(end 196.57695 -112.395)
		(width 0.10668)
		(layer "B.Cu")
		(net "P0V9_RETIMER_CPU0_EN_R2")
	)
	(segment
		(start 193.511932 -113.46307)
		(end 194.201796 -112.773206)
		(width 0.10668)
		(layer "B.Cu")
		(net "P0V9_RETIMER_CPU0_EN_R2")
	)
	(segment
		(start 194.409822 -112.773206)
		(end 194.92341 -112.773206)
		(width 0.10668)
		(layer "B.Cu")
		(net "P0V9_RETIMER_CPU0_EN_R2")
	)
	(segment
		(start 377.863608 -423.904918)
		(end 378.17425 -424.21556)
		(width 0.10668)
		(layer "F.Cu")
		(net "U17_E2")
	)
	(segment
		(start 378.17425 -424.21556)
		(end 378.17425 -426.05579)
		(width 0.10668)
		(layer "F.Cu")
		(net "U17_E2")
	)
	(segment
		(start 376.60072 -423.904918)
		(end 377.863608 -423.904918)
		(width 0.10668)
		(layer "F.Cu")
		(net "U17_E2")
	)
	(via
		(at 378.17425 -426.05579)
		(size 0.508)
		(drill 0.254)
		(layers "F.Cu" "B.Cu")
		(net "U17_E2")
	)
	(segment
		(start 376.57659 -423.888916)
		(end 377.652788 -423.888916)
		(width 0.10668)
		(layer "B.Cu")
		(net "U17_E2")
	)
	(segment
		(start 378.17425 -424.410378)
		(end 378.17425 -426.05579)
		(width 0.10668)
		(layer "B.Cu")
		(net "U17_E2")
	)
	(segment
		(start 377.652788 -423.888916)
		(end 378.17425 -424.410378)
		(width 0.10668)
		(layer "B.Cu")
		(net "U17_E2")
	)
	(segment
		(start 420.649654 -432.87315)
		(end 420.649654 -432.077876)
		(width 0.10668)
		(layer "F.Cu")
		(net "U16_E2")
	)
	(segment
		(start 420.649654 -432.077876)
		(end 420.649654 -430.885346)
		(width 0.10668)
		(layer "F.Cu")
		(net "U16_E2")
	)
	(segment
		(start 420.646606 -432.876198)
		(end 420.649654 -432.87315)
		(width 0.10668)
		(layer "F.Cu")
		(net "U16_E2")
	)
	(via
		(at 420.649654 -432.077876)
		(size 0.508)
		(drill 0.254)
		(layers "F.Cu" "B.Cu")
		(net "U16_E2")
	)
	(segment
		(start 289.56889 -401.828762)
		(end 289.56889 -400.791426)
		(width 0.10668)
		(layer "F.Cu")
		(net "U15_E2")
	)
	(segment
		(start 287.79978 -402.451062)
		(end 288.94659 -402.451062)
		(width 0.10668)
		(layer "F.Cu")
		(net "U15_E2")
	)
	(segment
		(start 288.94659 -402.451062)
		(end 289.56889 -401.828762)
		(width 0.10668)
		(layer "F.Cu")
		(net "U15_E2")
	)
	(segment
		(start 289.17392 -400.396456)
		(end 289.17392 -399.820384)
		(width 0.10668)
		(layer "F.Cu")
		(net "U15_E2")
	)
	(segment
		(start 289.56889 -400.791426)
		(end 289.17392 -400.396456)
		(width 0.10668)
		(layer "F.Cu")
		(net "U15_E2")
	)
	(via
		(at 289.17392 -400.396456)
		(size 0.508)
		(drill 0.254)
		(layers "F.Cu" "B.Cu")
		(net "U15_E2")
	)
	(segment
		(start 298.069 -428.879254)
		(end 298.660312 -429.470566)
		(width 0.10668)
		(layer "F.Cu")
		(net "U11_E2")
	)
	(segment
		(start 300.14164 -429.470566)
		(end 301.034704 -429.470566)
		(width 0.10668)
		(layer "F.Cu")
		(net "U11_E2")
	)
	(segment
		(start 298.069 -427.562772)
		(end 298.069 -428.879254)
		(width 0.10668)
		(layer "F.Cu")
		(net "U11_E2")
	)
	(segment
		(start 298.660312 -429.470566)
		(end 300.14164 -429.470566)
		(width 0.10668)
		(layer "F.Cu")
		(net "U11_E2")
	)
	(segment
		(start 298.243498 -427.388274)
		(end 298.069 -427.562772)
		(width 0.10668)
		(layer "F.Cu")
		(net "U11_E2")
	)
	(segment
		(start 301.161704 -429.597566)
		(end 301.161704 -430.01692)
		(width 0.10668)
		(layer "F.Cu")
		(net "U11_E2")
	)
	(segment
		(start 301.034704 -429.470566)
		(end 301.161704 -429.597566)
		(width 0.10668)
		(layer "F.Cu")
		(net "U11_E2")
	)
	(via
		(at 300.14164 -429.470566)
		(size 0.762)
		(drill 0.381)
		(layers "F.Cu" "B.Cu")
		(net "U11_E2")
	)
	(segment
		(start 366.385094 -391.65784)
		(end 366.09909 -391.943844)
		(width 0.10668)
		(layer "F.Cu")
		(net "TEST2_RT_CPU0_P3")
	)
	(segment
		(start 365.10849 -392.1252)
		(end 365.10849 -392.21029)
		(width 0.10668)
		(layer "F.Cu")
		(net "TEST2_RT_CPU0_P3")
	)
	(segment
		(start 369.2017 -393.513056)
		(end 368.50701 -393.513056)
		(width 0.10668)
		(layer "F.Cu")
		(net "TEST2_RT_CPU0_P3")
	)
	(segment
		(start 365.10849 -392.1252)
		(end 366.09909 -392.1252)
		(width 0.10668)
		(layer "F.Cu")
		(net "TEST2_RT_CPU0_P3")
	)
	(segment
		(start 367.35258 -391.65784)
		(end 366.385094 -391.65784)
		(width 0.10668)
		(layer "F.Cu")
		(net "TEST2_RT_CPU0_P3")
	)
	(segment
		(start 368.076226 -392.381486)
		(end 367.35258 -391.65784)
		(width 0.10668)
		(layer "F.Cu")
		(net "TEST2_RT_CPU0_P3")
	)
	(segment
		(start 368.50701 -393.513056)
		(end 368.076226 -393.082272)
		(width 0.10668)
		(layer "F.Cu")
		(net "TEST2_RT_CPU0_P3")
	)
	(segment
		(start 366.09909 -391.943844)
		(end 366.09909 -392.1252)
		(width 0.10668)
		(layer "F.Cu")
		(net "TEST2_RT_CPU0_P3")
	)
	(segment
		(start 368.076226 -393.082272)
		(end 368.076226 -392.381486)
		(width 0.10668)
		(layer "F.Cu")
		(net "TEST2_RT_CPU0_P3")
	)
	(segment
		(start 364.301024 -393.017756)
		(end 364.035086 -393.017756)
		(width 0.10668)
		(layer "F.Cu")
		(net "TEST2_RT_CPU0_P3")
	)
	(segment
		(start 365.10849 -392.21029)
		(end 364.301024 -393.017756)
		(width 0.10668)
		(layer "F.Cu")
		(net "TEST2_RT_CPU0_P3")
	)
	(via
		(at 364.035086 -393.017756)
		(size 0.762)
		(drill 0.381)
		(layers "F.Cu" "B.Cu")
		(net "TEST2_RT_CPU0_P3")
	)
	(segment
		(start 397.636238 -392.21029)
		(end 396.828772 -393.017756)
		(width 0.10668)
		(layer "F.Cu")
		(net "TEST2_RT_CPU0_P2")
	)
	(segment
		(start 400.603974 -392.381486)
		(end 400.603974 -393.082272)
		(width 0.10668)
		(layer "F.Cu")
		(net "TEST2_RT_CPU0_P2")
	)
	(segment
		(start 398.626838 -391.800588)
		(end 398.837912 -391.589514)
		(width 0.10668)
		(layer "F.Cu")
		(net "TEST2_RT_CPU0_P2")
	)
	(segment
		(start 398.626838 -392.1252)
		(end 398.626838 -391.800588)
		(width 0.10668)
		(layer "F.Cu")
		(net "TEST2_RT_CPU0_P2")
	)
	(segment
		(start 398.626838 -392.1252)
		(end 397.636238 -392.1252)
		(width 0.10668)
		(layer "F.Cu")
		(net "TEST2_RT_CPU0_P2")
	)
	(segment
		(start 396.828772 -393.017756)
		(end 396.562834 -393.017756)
		(width 0.10668)
		(layer "F.Cu")
		(net "TEST2_RT_CPU0_P2")
	)
	(segment
		(start 397.636238 -392.1252)
		(end 397.636238 -392.21029)
		(width 0.10668)
		(layer "F.Cu")
		(net "TEST2_RT_CPU0_P2")
	)
	(segment
		(start 400.603974 -393.082272)
		(end 401.034758 -393.513056)
		(width 0.10668)
		(layer "F.Cu")
		(net "TEST2_RT_CPU0_P2")
	)
	(segment
		(start 398.837912 -391.589514)
		(end 399.812002 -391.589514)
		(width 0.10668)
		(layer "F.Cu")
		(net "TEST2_RT_CPU0_P2")
	)
	(segment
		(start 401.034758 -393.513056)
		(end 401.729448 -393.513056)
		(width 0.10668)
		(layer "F.Cu")
		(net "TEST2_RT_CPU0_P2")
	)
	(segment
		(start 399.812002 -391.589514)
		(end 400.603974 -392.381486)
		(width 0.10668)
		(layer "F.Cu")
		(net "TEST2_RT_CPU0_P2")
	)
	(via
		(at 396.562834 -393.017756)
		(size 0.762)
		(drill 0.381)
		(layers "F.Cu" "B.Cu")
		(net "TEST2_RT_CPU0_P2")
	)
	(segment
		(start 331.526642 -392.1252)
		(end 331.526642 -391.800588)
		(width 0.10668)
		(layer "F.Cu")
		(net "TEST2_RT_CPU0_P1")
	)
	(segment
		(start 330.536042 -392.1252)
		(end 331.526642 -392.1252)
		(width 0.10668)
		(layer "F.Cu")
		(net "TEST2_RT_CPU0_P1")
	)
	(segment
		(start 330.536042 -392.21029)
		(end 329.728576 -393.017756)
		(width 0.10668)
		(layer "F.Cu")
		(net "TEST2_RT_CPU0_P1")
	)
	(segment
		(start 332.711806 -391.589514)
		(end 333.503778 -392.381486)
		(width 0.10668)
		(layer "F.Cu")
		(net "TEST2_RT_CPU0_P1")
	)
	(segment
		(start 333.503778 -392.381486)
		(end 333.503778 -393.082272)
		(width 0.10668)
		(layer "F.Cu")
		(net "TEST2_RT_CPU0_P1")
	)
	(segment
		(start 331.737716 -391.589514)
		(end 332.711806 -391.589514)
		(width 0.10668)
		(layer "F.Cu")
		(net "TEST2_RT_CPU0_P1")
	)
	(segment
		(start 333.503778 -393.082272)
		(end 333.934562 -393.513056)
		(width 0.10668)
		(layer "F.Cu")
		(net "TEST2_RT_CPU0_P1")
	)
	(segment
		(start 329.728576 -393.017756)
		(end 329.462638 -393.017756)
		(width 0.10668)
		(layer "F.Cu")
		(net "TEST2_RT_CPU0_P1")
	)
	(segment
		(start 333.934562 -393.513056)
		(end 334.629252 -393.513056)
		(width 0.10668)
		(layer "F.Cu")
		(net "TEST2_RT_CPU0_P1")
	)
	(segment
		(start 330.536042 -392.1252)
		(end 330.536042 -392.21029)
		(width 0.10668)
		(layer "F.Cu")
		(net "TEST2_RT_CPU0_P1")
	)
	(segment
		(start 331.526642 -391.800588)
		(end 331.737716 -391.589514)
		(width 0.10668)
		(layer "F.Cu")
		(net "TEST2_RT_CPU0_P1")
	)
	(via
		(at 329.462638 -393.017756)
		(size 0.762)
		(drill 0.381)
		(layers "F.Cu" "B.Cu")
		(net "TEST2_RT_CPU0_P1")
	)
	(segment
		(start 300.97603 -392.381486)
		(end 300.97603 -393.082272)
		(width 0.10668)
		(layer "F.Cu")
		(net "TEST2_RT_CPU0_P0")
	)
	(segment
		(start 299.209968 -391.589514)
		(end 300.184058 -391.589514)
		(width 0.10668)
		(layer "F.Cu")
		(net "TEST2_RT_CPU0_P0")
	)
	(segment
		(start 300.184058 -391.589514)
		(end 300.97603 -392.381486)
		(width 0.10668)
		(layer "F.Cu")
		(net "TEST2_RT_CPU0_P0")
	)
	(segment
		(start 301.406814 -393.513056)
		(end 302.101504 -393.513056)
		(width 0.10668)
		(layer "F.Cu")
		(net "TEST2_RT_CPU0_P0")
	)
	(segment
		(start 298.008294 -392.21029)
		(end 297.200828 -393.017756)
		(width 0.10668)
		(layer "F.Cu")
		(net "TEST2_RT_CPU0_P0")
	)
	(segment
		(start 298.998894 -391.800588)
		(end 299.209968 -391.589514)
		(width 0.10668)
		(layer "F.Cu")
		(net "TEST2_RT_CPU0_P0")
	)
	(segment
		(start 300.97603 -393.082272)
		(end 301.406814 -393.513056)
		(width 0.10668)
		(layer "F.Cu")
		(net "TEST2_RT_CPU0_P0")
	)
	(segment
		(start 298.998894 -392.1252)
		(end 298.998894 -391.800588)
		(width 0.10668)
		(layer "F.Cu")
		(net "TEST2_RT_CPU0_P0")
	)
	(segment
		(start 297.200828 -393.017756)
		(end 296.93489 -393.017756)
		(width 0.10668)
		(layer "F.Cu")
		(net "TEST2_RT_CPU0_P0")
	)
	(segment
		(start 298.008294 -392.1252)
		(end 298.998894 -392.1252)
		(width 0.10668)
		(layer "F.Cu")
		(net "TEST2_RT_CPU0_P0")
	)
	(segment
		(start 298.008294 -392.1252)
		(end 298.008294 -392.21029)
		(width 0.10668)
		(layer "F.Cu")
		(net "TEST2_RT_CPU0_P0")
	)
	(via
		(at 296.93489 -393.017756)
		(size 0.762)
		(drill 0.381)
		(layers "F.Cu" "B.Cu")
		(net "TEST2_RT_CPU0_P0")
	)
	(segment
		(start 368.460782 -394.113004)
		(end 369.2017 -394.113004)
		(width 0.10668)
		(layer "F.Cu")
		(net "TEST1_RT_CPU0_P3")
	)
	(segment
		(start 368.332512 -393.984734)
		(end 368.460782 -394.113004)
		(width 0.10668)
		(layer "F.Cu")
		(net "TEST1_RT_CPU0_P3")
	)
	(segment
		(start 368.079782 -393.984734)
		(end 368.332512 -393.984734)
		(width 0.10668)
		(layer "F.Cu")
		(net "TEST1_RT_CPU0_P3")
	)
	(via
		(at 368.079782 -393.267946)
		(size 0.6604)
		(drill 0.3302)
		(layers "F.Cu" "B.Cu")
		(net "TEST1_RT_CPU0_P3")
	)
	(via
		(at 368.079782 -393.984734)
		(size 0.4064)
		(drill 0.2032)
		(layers "F.Cu" "B.Cu")
		(net "TEST1_RT_CPU0_P3")
	)
	(segment
		(start 366.267238 -392.58494)
		(end 366.09909 -392.753088)
		(width 0.10668)
		(layer "B.Cu")
		(net "TEST1_RT_CPU0_P3")
	)
	(segment
		(start 367.396776 -392.58494)
		(end 366.267238 -392.58494)
		(width 0.10668)
		(layer "B.Cu")
		(net "TEST1_RT_CPU0_P3")
	)
	(segment
		(start 368.079782 -393.267946)
		(end 367.396776 -392.58494)
		(width 0.10668)
		(layer "B.Cu")
		(net "TEST1_RT_CPU0_P3")
	)
	(segment
		(start 365.36249 -393.04468)
		(end 366.09909 -393.04468)
		(width 0.10668)
		(layer "B.Cu")
		(net "TEST1_RT_CPU0_P3")
	)
	(segment
		(start 368.079782 -393.984734)
		(end 368.079782 -393.267946)
		(width 0.10668)
		(layer "B.Cu")
		(net "TEST1_RT_CPU0_P3")
	)
	(segment
		(start 366.09909 -392.753088)
		(end 366.09909 -393.04468)
		(width 0.10668)
		(layer "B.Cu")
		(net "TEST1_RT_CPU0_P3")
	)
	(segment
		(start 400.60753 -393.984734)
		(end 400.86026 -393.984734)
		(width 0.10668)
		(layer "F.Cu")
		(net "TEST1_RT_CPU0_P2")
	)
	(segment
		(start 400.98853 -394.113004)
		(end 401.729448 -394.113004)
		(width 0.10668)
		(layer "F.Cu")
		(net "TEST1_RT_CPU0_P2")
	)
	(segment
		(start 400.86026 -393.984734)
		(end 400.98853 -394.113004)
		(width 0.10668)
		(layer "F.Cu")
		(net "TEST1_RT_CPU0_P2")
	)
	(via
		(at 400.60753 -393.984734)
		(size 0.4064)
		(drill 0.2032)
		(layers "F.Cu" "B.Cu")
		(net "TEST1_RT_CPU0_P2")
	)
	(via
		(at 400.60753 -393.267946)
		(size 0.6604)
		(drill 0.3302)
		(layers "F.Cu" "B.Cu")
		(net "TEST1_RT_CPU0_P2")
	)
	(segment
		(start 397.890238 -393.04468)
		(end 398.626838 -393.04468)
		(width 0.10668)
		(layer "B.Cu")
		(net "TEST1_RT_CPU0_P2")
	)
	(segment
		(start 398.794986 -392.58494)
		(end 398.626838 -392.753088)
		(width 0.10668)
		(layer "B.Cu")
		(net "TEST1_RT_CPU0_P2")
	)
	(segment
		(start 399.924524 -392.58494)
		(end 398.794986 -392.58494)
		(width 0.10668)
		(layer "B.Cu")
		(net "TEST1_RT_CPU0_P2")
	)
	(segment
		(start 400.60753 -393.267946)
		(end 399.924524 -392.58494)
		(width 0.10668)
		(layer "B.Cu")
		(net "TEST1_RT_CPU0_P2")
	)
	(segment
		(start 398.626838 -392.753088)
		(end 398.626838 -393.04468)
		(width 0.10668)
		(layer "B.Cu")
		(net "TEST1_RT_CPU0_P2")
	)
	(segment
		(start 400.60753 -393.984734)
		(end 400.60753 -393.267946)
		(width 0.10668)
		(layer "B.Cu")
		(net "TEST1_RT_CPU0_P2")
	)
	(segment
		(start 333.760064 -393.984734)
		(end 333.888334 -394.113004)
		(width 0.10668)
		(layer "F.Cu")
		(net "TEST1_RT_CPU0_P1")
	)
	(segment
		(start 333.507334 -393.984734)
		(end 333.760064 -393.984734)
		(width 0.10668)
		(layer "F.Cu")
		(net "TEST1_RT_CPU0_P1")
	)
	(segment
		(start 333.888334 -394.113004)
		(end 334.629252 -394.113004)
		(width 0.10668)
		(layer "F.Cu")
		(net "TEST1_RT_CPU0_P1")
	)
	(via
		(at 333.507334 -393.984734)
		(size 0.4064)
		(drill 0.2032)
		(layers "F.Cu" "B.Cu")
		(net "TEST1_RT_CPU0_P1")
	)
	(via
		(at 333.507334 -393.267946)
		(size 0.6604)
		(drill 0.3302)
		(layers "F.Cu" "B.Cu")
		(net "TEST1_RT_CPU0_P1")
	)
	(segment
		(start 330.790042 -393.04468)
		(end 331.526642 -393.04468)
		(width 0.10668)
		(layer "B.Cu")
		(net "TEST1_RT_CPU0_P1")
	)
	(segment
		(start 332.824328 -392.58494)
		(end 331.69479 -392.58494)
		(width 0.10668)
		(layer "B.Cu")
		(net "TEST1_RT_CPU0_P1")
	)
	(segment
		(start 331.69479 -392.58494)
		(end 331.526642 -392.753088)
		(width 0.10668)
		(layer "B.Cu")
		(net "TEST1_RT_CPU0_P1")
	)
	(segment
		(start 333.507334 -393.267946)
		(end 332.824328 -392.58494)
		(width 0.10668)
		(layer "B.Cu")
		(net "TEST1_RT_CPU0_P1")
	)
	(segment
		(start 333.507334 -393.984734)
		(end 333.507334 -393.267946)
		(width 0.10668)
		(layer "B.Cu")
		(net "TEST1_RT_CPU0_P1")
	)
	(segment
		(start 331.526642 -392.753088)
		(end 331.526642 -393.04468)
		(width 0.10668)
		(layer "B.Cu")
		(net "TEST1_RT_CPU0_P1")
	)
	(segment
		(start 301.232316 -393.984734)
		(end 301.360586 -394.113004)
		(width 0.10668)
		(layer "F.Cu")
		(net "TEST1_RT_CPU0_P0")
	)
	(segment
		(start 301.360586 -394.113004)
		(end 302.101504 -394.113004)
		(width 0.10668)
		(layer "F.Cu")
		(net "TEST1_RT_CPU0_P0")
	)
	(segment
		(start 300.979586 -393.984734)
		(end 301.232316 -393.984734)
		(width 0.10668)
		(layer "F.Cu")
		(net "TEST1_RT_CPU0_P0")
	)
	(via
		(at 300.771052 -393.325096)
		(size 0.6604)
		(drill 0.3302)
		(layers "F.Cu" "B.Cu")
		(net "TEST1_RT_CPU0_P0")
	)
	(via
		(at 300.979586 -393.984734)
		(size 0.4064)
		(drill 0.2032)
		(layers "F.Cu" "B.Cu")
		(net "TEST1_RT_CPU0_P0")
	)
	(segment
		(start 300.979586 -393.984734)
		(end 300.979586 -393.53363)
		(width 0.10668)
		(layer "B.Cu")
		(net "TEST1_RT_CPU0_P0")
	)
	(segment
		(start 298.998894 -392.850624)
		(end 299.532294 -393.384024)
		(width 0.10668)
		(layer "B.Cu")
		(net "TEST1_RT_CPU0_P0")
	)
	(segment
		(start 300.591728 -393.50442)
		(end 299.555154 -393.50442)
		(width 0.10668)
		(layer "B.Cu")
		(net "TEST1_RT_CPU0_P0")
	)
	(segment
		(start 299.555154 -393.50442)
		(end 299.532294 -393.48156)
		(width 0.10668)
		(layer "B.Cu")
		(net "TEST1_RT_CPU0_P0")
	)
	(segment
		(start 299.532294 -393.384024)
		(end 299.532294 -393.48156)
		(width 0.10668)
		(layer "B.Cu")
		(net "TEST1_RT_CPU0_P0")
	)
	(segment
		(start 300.771052 -393.325096)
		(end 300.591728 -393.50442)
		(width 0.10668)
		(layer "B.Cu")
		(net "TEST1_RT_CPU0_P0")
	)
	(segment
		(start 300.979586 -393.53363)
		(end 300.771052 -393.325096)
		(width 0.10668)
		(layer "B.Cu")
		(net "TEST1_RT_CPU0_P0")
	)
	(segment
		(start 298.998894 -392.66876)
		(end 298.998894 -392.850624)
		(width 0.10668)
		(layer "B.Cu")
		(net "TEST1_RT_CPU0_P0")
	)
	(segment
		(start 368.340132 -394.712952)
		(end 368.181636 -394.871448)
		(width 0.10668)
		(layer "F.Cu")
		(net "TEST0_RT_CPU0_P3")
	)
	(segment
		(start 369.2017 -394.712952)
		(end 368.340132 -394.712952)
		(width 0.10668)
		(layer "F.Cu")
		(net "TEST0_RT_CPU0_P3")
	)
	(via
		(at 368.181636 -394.871448)
		(size 0.4064)
		(drill 0.2032)
		(layers "F.Cu" "B.Cu")
		(net "TEST0_RT_CPU0_P3")
	)
	(via
		(at 367.627916 -394.511022)
		(size 0.6604)
		(drill 0.3302)
		(layers "F.Cu" "B.Cu")
		(net "TEST0_RT_CPU0_P3")
	)
	(segment
		(start 367.627916 -393.718288)
		(end 367.414048 -393.50442)
		(width 0.10668)
		(layer "B.Cu")
		(net "TEST0_RT_CPU0_P3")
	)
	(segment
		(start 366.09909 -393.672568)
		(end 366.09909 -393.96416)
		(width 0.10668)
		(layer "B.Cu")
		(net "TEST0_RT_CPU0_P3")
	)
	(segment
		(start 365.36249 -393.96416)
		(end 366.09909 -393.96416)
		(width 0.10668)
		(layer "B.Cu")
		(net "TEST0_RT_CPU0_P3")
	)
	(segment
		(start 367.988342 -394.871448)
		(end 367.627916 -394.511022)
		(width 0.10668)
		(layer "B.Cu")
		(net "TEST0_RT_CPU0_P3")
	)
	(segment
		(start 366.267238 -393.50442)
		(end 366.09909 -393.672568)
		(width 0.10668)
		(layer "B.Cu")
		(net "TEST0_RT_CPU0_P3")
	)
	(segment
		(start 367.627916 -394.511022)
		(end 367.627916 -393.718288)
		(width 0.10668)
		(layer "B.Cu")
		(net "TEST0_RT_CPU0_P3")
	)
	(segment
		(start 368.181636 -394.871448)
		(end 367.988342 -394.871448)
		(width 0.10668)
		(layer "B.Cu")
		(net "TEST0_RT_CPU0_P3")
	)
	(segment
		(start 367.414048 -393.50442)
		(end 366.267238 -393.50442)
		(width 0.10668)
		(layer "B.Cu")
		(net "TEST0_RT_CPU0_P3")
	)
	(segment
		(start 400.709384 -394.871448)
		(end 400.86788 -394.712952)
		(width 0.10668)
		(layer "F.Cu")
		(net "TEST0_RT_CPU0_P2")
	)
	(segment
		(start 400.86788 -394.712952)
		(end 401.729448 -394.712952)
		(width 0.10668)
		(layer "F.Cu")
		(net "TEST0_RT_CPU0_P2")
	)
	(via
		(at 400.155664 -394.511022)
		(size 0.6604)
		(drill 0.3302)
		(layers "F.Cu" "B.Cu")
		(net "TEST0_RT_CPU0_P2")
	)
	(via
		(at 400.709384 -394.871448)
		(size 0.4064)
		(drill 0.2032)
		(layers "F.Cu" "B.Cu")
		(net "TEST0_RT_CPU0_P2")
	)
	(segment
		(start 400.155664 -393.718288)
		(end 399.941796 -393.50442)
		(width 0.10668)
		(layer "B.Cu")
		(net "TEST0_RT_CPU0_P2")
	)
	(segment
		(start 400.155664 -394.511022)
		(end 400.155664 -393.718288)
		(width 0.10668)
		(layer "B.Cu")
		(net "TEST0_RT_CPU0_P2")
	)
	(segment
		(start 400.709384 -394.871448)
		(end 400.51609 -394.871448)
		(width 0.10668)
		(layer "B.Cu")
		(net "TEST0_RT_CPU0_P2")
	)
	(segment
		(start 400.51609 -394.871448)
		(end 400.155664 -394.511022)
		(width 0.10668)
		(layer "B.Cu")
		(net "TEST0_RT_CPU0_P2")
	)
	(segment
		(start 398.626838 -393.672568)
		(end 398.626838 -393.96416)
		(width 0.10668)
		(layer "B.Cu")
		(net "TEST0_RT_CPU0_P2")
	)
	(segment
		(start 398.794986 -393.50442)
		(end 398.626838 -393.672568)
		(width 0.10668)
		(layer "B.Cu")
		(net "TEST0_RT_CPU0_P2")
	)
	(segment
		(start 399.941796 -393.50442)
		(end 398.794986 -393.50442)
		(width 0.10668)
		(layer "B.Cu")
		(net "TEST0_RT_CPU0_P2")
	)
	(segment
		(start 397.890238 -393.96416)
		(end 398.626838 -393.96416)
		(width 0.10668)
		(layer "B.Cu")
		(net "TEST0_RT_CPU0_P2")
	)
	(segment
		(start 333.609188 -394.871448)
		(end 333.767684 -394.712952)
		(width 0.10668)
		(layer "F.Cu")
		(net "TEST0_RT_CPU0_P1")
	)
	(segment
		(start 333.767684 -394.712952)
		(end 334.629252 -394.712952)
		(width 0.10668)
		(layer "F.Cu")
		(net "TEST0_RT_CPU0_P1")
	)
	(via
		(at 333.055468 -394.511022)
		(size 0.6604)
		(drill 0.3302)
		(layers "F.Cu" "B.Cu")
		(net "TEST0_RT_CPU0_P1")
	)
	(via
		(at 333.609188 -394.871448)
		(size 0.4064)
		(drill 0.2032)
		(layers "F.Cu" "B.Cu")
		(net "TEST0_RT_CPU0_P1")
	)
	(segment
		(start 332.8416 -393.50442)
		(end 331.69479 -393.50442)
		(width 0.10668)
		(layer "B.Cu")
		(net "TEST0_RT_CPU0_P1")
	)
	(segment
		(start 331.69479 -393.50442)
		(end 331.526642 -393.672568)
		(width 0.10668)
		(layer "B.Cu")
		(net "TEST0_RT_CPU0_P1")
	)
	(segment
		(start 333.055468 -394.511022)
		(end 333.055468 -393.718288)
		(width 0.10668)
		(layer "B.Cu")
		(net "TEST0_RT_CPU0_P1")
	)
	(segment
		(start 333.609188 -394.871448)
		(end 333.415894 -394.871448)
		(width 0.10668)
		(layer "B.Cu")
		(net "TEST0_RT_CPU0_P1")
	)
	(segment
		(start 331.526642 -393.672568)
		(end 331.526642 -393.96416)
		(width 0.10668)
		(layer "B.Cu")
		(net "TEST0_RT_CPU0_P1")
	)
	(segment
		(start 333.415894 -394.871448)
		(end 333.055468 -394.511022)
		(width 0.10668)
		(layer "B.Cu")
		(net "TEST0_RT_CPU0_P1")
	)
	(segment
		(start 330.790042 -393.96416)
		(end 331.526642 -393.96416)
		(width 0.10668)
		(layer "B.Cu")
		(net "TEST0_RT_CPU0_P1")
	)
	(segment
		(start 333.055468 -393.718288)
		(end 332.8416 -393.50442)
		(width 0.10668)
		(layer "B.Cu")
		(net "TEST0_RT_CPU0_P1")
	)
	(segment
		(start 302.101504 -394.712952)
		(end 301.239936 -394.712952)
		(width 0.10668)
		(layer "F.Cu")
		(net "TEST0_RT_CPU0_P0")
	)
	(segment
		(start 301.239936 -394.712952)
		(end 301.08144 -394.871448)
		(width 0.10668)
		(layer "F.Cu")
		(net "TEST0_RT_CPU0_P0")
	)
	(via
		(at 300.355762 -395.10716)
		(size 0.6604)
		(drill 0.3302)
		(layers "F.Cu" "B.Cu")
		(net "TEST0_RT_CPU0_P0")
	)
	(via
		(at 301.08144 -394.871448)
		(size 0.4064)
		(drill 0.2032)
		(layers "F.Cu" "B.Cu")
		(net "TEST0_RT_CPU0_P0")
	)
	(segment
		(start 301.08144 -394.871448)
		(end 300.591474 -394.871448)
		(width 0.10668)
		(layer "B.Cu")
		(net "TEST0_RT_CPU0_P0")
	)
	(segment
		(start 300.591474 -394.871448)
		(end 300.355762 -395.10716)
		(width 0.10668)
		(layer "B.Cu")
		(net "TEST0_RT_CPU0_P0")
	)
	(segment
		(start 298.998894 -394.29436)
		(end 298.998894 -394.479272)
		(width 0.10668)
		(layer "B.Cu")
		(net "TEST0_RT_CPU0_P0")
	)
	(segment
		(start 298.998894 -394.479272)
		(end 299.532294 -395.012672)
		(width 0.10668)
		(layer "B.Cu")
		(net "TEST0_RT_CPU0_P0")
	)
	(segment
		(start 299.532294 -395.012672)
		(end 299.532294 -395.10716)
		(width 0.10668)
		(layer "B.Cu")
		(net "TEST0_RT_CPU0_P0")
	)
	(segment
		(start 300.355762 -395.10716)
		(end 299.532294 -395.10716)
		(width 0.10668)
		(layer "B.Cu")
		(net "TEST0_RT_CPU0_P0")
	)
	(segment
		(start 390.45388 -393.81303)
		(end 390.860026 -393.531344)
		(width 0.10668)
		(layer "F.Cu")
		(net "SMB_RT_CPU0_P3_R2_SDA")
	)
	(via
		(at 244.237764 -367.878614)
		(size 0.508)
		(drill 0.254)
		(layers "F.Cu" "B.Cu")
		(net "SMB_RT_CPU0_P3_R2_SDA")
	)
	(via
		(at 390.860026 -393.531344)
		(size 0.4064)
		(drill 0.2032)
		(layers "F.Cu" "B.Cu")
		(net "SMB_RT_CPU0_P3_R2_SDA")
	)
	(via
		(at 234.188 -337.312)
		(size 0.508)
		(drill 0.254)
		(layers "F.Cu" "B.Cu")
		(net "SMB_RT_CPU0_P3_R2_SDA")
	)
	(segment
		(start 233.4387 -337.312)
		(end 234.188 -337.312)
		(width 0.10668)
		(layer "B.Cu")
		(net "SMB_RT_CPU0_P3_R2_SDA")
	)
	(segment
		(start 244.237764 -367.878614)
		(end 244.640608 -368.281458)
		(width 0.11684)
		(layer "In2.Cu")
		(net "SMB_RT_CPU0_P3_R2_SDA")
	)
	(segment
		(start 382.664462 -386.062728)
		(end 387.255512 -390.653778)
		(width 0.11684)
		(layer "In2.Cu")
		(net "SMB_RT_CPU0_P3_R2_SDA")
	)
	(segment
		(start 286.904176 -371.99951)
		(end 290.02101 -375.116344)
		(width 0.11684)
		(layer "In2.Cu")
		(net "SMB_RT_CPU0_P3_R2_SDA")
	)
	(segment
		(start 244.640608 -368.281458)
		(end 247.175782 -368.281458)
		(width 0.11684)
		(layer "In2.Cu")
		(net "SMB_RT_CPU0_P3_R2_SDA")
	)
	(segment
		(start 388.325614 -392.55827)
		(end 389.274558 -392.55827)
		(width 0.11684)
		(layer "In2.Cu")
		(net "SMB_RT_CPU0_P3_R2_SDA")
	)
	(segment
		(start 363.691424 -380.817628)
		(end 368.936524 -386.062728)
		(width 0.11684)
		(layer "In2.Cu")
		(net "SMB_RT_CPU0_P3_R2_SDA")
	)
	(segment
		(start 281.357324 -371.99951)
		(end 286.904176 -371.99951)
		(width 0.11684)
		(layer "In2.Cu")
		(net "SMB_RT_CPU0_P3_R2_SDA")
	)
	(segment
		(start 298.790868 -375.116344)
		(end 299.301662 -374.60555)
		(width 0.11684)
		(layer "In2.Cu")
		(net "SMB_RT_CPU0_P3_R2_SDA")
	)
	(segment
		(start 249.874786 -367.777014)
		(end 250.900692 -368.80292)
		(width 0.11684)
		(layer "In2.Cu")
		(net "SMB_RT_CPU0_P3_R2_SDA")
	)
	(segment
		(start 390.247632 -393.531344)
		(end 390.860026 -393.531344)
		(width 0.11684)
		(layer "In2.Cu")
		(net "SMB_RT_CPU0_P3_R2_SDA")
	)
	(segment
		(start 277.151846 -367.794032)
		(end 281.357324 -371.99951)
		(width 0.11684)
		(layer "In2.Cu")
		(net "SMB_RT_CPU0_P3_R2_SDA")
	)
	(segment
		(start 389.274558 -392.55827)
		(end 390.247632 -393.531344)
		(width 0.11684)
		(layer "In2.Cu")
		(net "SMB_RT_CPU0_P3_R2_SDA")
	)
	(segment
		(start 363.691424 -379.377702)
		(end 363.691424 -380.817628)
		(width 0.11684)
		(layer "In2.Cu")
		(net "SMB_RT_CPU0_P3_R2_SDA")
	)
	(segment
		(start 299.301662 -374.60555)
		(end 358.919272 -374.60555)
		(width 0.11684)
		(layer "In2.Cu")
		(net "SMB_RT_CPU0_P3_R2_SDA")
	)
	(segment
		(start 271.62633 -367.794032)
		(end 277.151846 -367.794032)
		(width 0.11684)
		(layer "In2.Cu")
		(net "SMB_RT_CPU0_P3_R2_SDA")
	)
	(segment
		(start 358.919272 -374.60555)
		(end 363.691424 -379.377702)
		(width 0.11684)
		(layer "In2.Cu")
		(net "SMB_RT_CPU0_P3_R2_SDA")
	)
	(segment
		(start 247.680226 -367.777014)
		(end 249.874786 -367.777014)
		(width 0.11684)
		(layer "In2.Cu")
		(net "SMB_RT_CPU0_P3_R2_SDA")
	)
	(segment
		(start 290.02101 -375.116344)
		(end 298.790868 -375.116344)
		(width 0.11684)
		(layer "In2.Cu")
		(net "SMB_RT_CPU0_P3_R2_SDA")
	)
	(segment
		(start 270.617442 -368.80292)
		(end 271.62633 -367.794032)
		(width 0.11684)
		(layer "In2.Cu")
		(net "SMB_RT_CPU0_P3_R2_SDA")
	)
	(segment
		(start 387.255512 -390.653778)
		(end 387.255512 -391.488168)
		(width 0.11684)
		(layer "In2.Cu")
		(net "SMB_RT_CPU0_P3_R2_SDA")
	)
	(segment
		(start 250.900692 -368.80292)
		(end 270.617442 -368.80292)
		(width 0.11684)
		(layer "In2.Cu")
		(net "SMB_RT_CPU0_P3_R2_SDA")
	)
	(segment
		(start 387.255512 -391.488168)
		(end 388.325614 -392.55827)
		(width 0.11684)
		(layer "In2.Cu")
		(net "SMB_RT_CPU0_P3_R2_SDA")
	)
	(segment
		(start 247.175782 -368.281458)
		(end 247.680226 -367.777014)
		(width 0.11684)
		(layer "In2.Cu")
		(net "SMB_RT_CPU0_P3_R2_SDA")
	)
	(segment
		(start 368.936524 -386.062728)
		(end 382.664462 -386.062728)
		(width 0.11684)
		(layer "In2.Cu")
		(net "SMB_RT_CPU0_P3_R2_SDA")
	)
	(segment
		(start 244.237764 -367.878614)
		(end 244.348762 -367.767616)
		(width 0.11684)
		(layer "In4.Cu")
		(net "SMB_RT_CPU0_P3_R2_SDA")
	)
	(segment
		(start 236.370368 -341.841582)
		(end 236.370368 -339.1662)
		(width 0.11684)
		(layer "In4.Cu")
		(net "SMB_RT_CPU0_P3_R2_SDA")
	)
	(segment
		(start 234.516168 -337.312)
		(end 234.188 -337.312)
		(width 0.11684)
		(layer "In4.Cu")
		(net "SMB_RT_CPU0_P3_R2_SDA")
	)
	(segment
		(start 236.370368 -339.1662)
		(end 234.516168 -337.312)
		(width 0.11684)
		(layer "In4.Cu")
		(net "SMB_RT_CPU0_P3_R2_SDA")
	)
	(segment
		(start 244.348762 -349.819976)
		(end 236.370368 -341.841582)
		(width 0.11684)
		(layer "In4.Cu")
		(net "SMB_RT_CPU0_P3_R2_SDA")
	)
	(segment
		(start 244.348762 -367.767616)
		(end 244.348762 -349.819976)
		(width 0.11684)
		(layer "In4.Cu")
		(net "SMB_RT_CPU0_P3_R2_SDA")
	)
	(segment
		(start 390.45388 -393.213082)
		(end 390.87425 -392.956542)
		(width 0.10668)
		(layer "F.Cu")
		(net "SMB_RT_CPU0_P3_R2_SCL")
	)
	(via
		(at 244.983762 -367.816638)
		(size 0.508)
		(drill 0.254)
		(layers "F.Cu" "B.Cu")
		(net "SMB_RT_CPU0_P3_R2_SCL")
	)
	(via
		(at 234.188 -336.296)
		(size 0.508)
		(drill 0.254)
		(layers "F.Cu" "B.Cu")
		(net "SMB_RT_CPU0_P3_R2_SCL")
	)
	(via
		(at 390.87425 -392.956542)
		(size 0.4064)
		(drill 0.2032)
		(layers "F.Cu" "B.Cu")
		(net "SMB_RT_CPU0_P3_R2_SCL")
	)
	(segment
		(start 233.4387 -336.296)
		(end 234.188 -336.296)
		(width 0.10668)
		(layer "B.Cu")
		(net "SMB_RT_CPU0_P3_R2_SCL")
	)
	(segment
		(start 388.253732 -390.838944)
		(end 382.902714 -385.487926)
		(width 0.11684)
		(layer "In2.Cu")
		(net "SMB_RT_CPU0_P3_R2_SCL")
	)
	(segment
		(start 245.148354 -367.323878)
		(end 244.983762 -367.48847)
		(width 0.11684)
		(layer "In2.Cu")
		(net "SMB_RT_CPU0_P3_R2_SCL")
	)
	(segment
		(start 364.266226 -379.13945)
		(end 359.310686 -374.18391)
		(width 0.11684)
		(layer "In2.Cu")
		(net "SMB_RT_CPU0_P3_R2_SCL")
	)
	(segment
		(start 290.179506 -374.678448)
		(end 287.078928 -371.57787)
		(width 0.11684)
		(layer "In2.Cu")
		(net "SMB_RT_CPU0_P3_R2_SCL")
	)
	(segment
		(start 382.902714 -385.487926)
		(end 369.174776 -385.487926)
		(width 0.11684)
		(layer "In2.Cu")
		(net "SMB_RT_CPU0_P3_R2_SCL")
	)
	(segment
		(start 369.174776 -385.487926)
		(end 364.266226 -380.579376)
		(width 0.11684)
		(layer "In2.Cu")
		(net "SMB_RT_CPU0_P3_R2_SCL")
	)
	(segment
		(start 388.659116 -391.853166)
		(end 388.253732 -391.447782)
		(width 0.11684)
		(layer "In2.Cu")
		(net "SMB_RT_CPU0_P3_R2_SCL")
	)
	(segment
		(start 276.520656 -366.56645)
		(end 271.870932 -366.56645)
		(width 0.11684)
		(layer "In2.Cu")
		(net "SMB_RT_CPU0_P3_R2_SCL")
	)
	(segment
		(start 298.40301 -374.678448)
		(end 290.179506 -374.678448)
		(width 0.11684)
		(layer "In2.Cu")
		(net "SMB_RT_CPU0_P3_R2_SCL")
	)
	(segment
		(start 281.532076 -371.57787)
		(end 276.520656 -366.56645)
		(width 0.11684)
		(layer "In2.Cu")
		(net "SMB_RT_CPU0_P3_R2_SCL")
	)
	(segment
		(start 388.253732 -391.447782)
		(end 388.253732 -390.838944)
		(width 0.11684)
		(layer "In2.Cu")
		(net "SMB_RT_CPU0_P3_R2_SCL")
	)
	(segment
		(start 250.018296 -367.323878)
		(end 245.148354 -367.323878)
		(width 0.11684)
		(layer "In2.Cu")
		(net "SMB_RT_CPU0_P3_R2_SCL")
	)
	(segment
		(start 270.056102 -368.38128)
		(end 251.075698 -368.38128)
		(width 0.11684)
		(layer "In2.Cu")
		(net "SMB_RT_CPU0_P3_R2_SCL")
	)
	(segment
		(start 389.382508 -391.853166)
		(end 388.659116 -391.853166)
		(width 0.11684)
		(layer "In2.Cu")
		(net "SMB_RT_CPU0_P3_R2_SCL")
	)
	(segment
		(start 271.870932 -366.56645)
		(end 270.056102 -368.38128)
		(width 0.11684)
		(layer "In2.Cu")
		(net "SMB_RT_CPU0_P3_R2_SCL")
	)
	(segment
		(start 359.310686 -374.18391)
		(end 298.897548 -374.18391)
		(width 0.11684)
		(layer "In2.Cu")
		(net "SMB_RT_CPU0_P3_R2_SCL")
	)
	(segment
		(start 298.897548 -374.18391)
		(end 298.40301 -374.678448)
		(width 0.11684)
		(layer "In2.Cu")
		(net "SMB_RT_CPU0_P3_R2_SCL")
	)
	(segment
		(start 364.266226 -380.579376)
		(end 364.266226 -379.13945)
		(width 0.11684)
		(layer "In2.Cu")
		(net "SMB_RT_CPU0_P3_R2_SCL")
	)
	(segment
		(start 390.485884 -392.956542)
		(end 389.382508 -391.853166)
		(width 0.11684)
		(layer "In2.Cu")
		(net "SMB_RT_CPU0_P3_R2_SCL")
	)
	(segment
		(start 390.87425 -392.956542)
		(end 390.485884 -392.956542)
		(width 0.11684)
		(layer "In2.Cu")
		(net "SMB_RT_CPU0_P3_R2_SCL")
	)
	(segment
		(start 287.078928 -371.57787)
		(end 281.532076 -371.57787)
		(width 0.11684)
		(layer "In2.Cu")
		(net "SMB_RT_CPU0_P3_R2_SCL")
	)
	(segment
		(start 244.983762 -367.48847)
		(end 244.983762 -367.816638)
		(width 0.11684)
		(layer "In2.Cu")
		(net "SMB_RT_CPU0_P3_R2_SCL")
	)
	(segment
		(start 251.075698 -368.38128)
		(end 250.018296 -367.323878)
		(width 0.11684)
		(layer "In2.Cu")
		(net "SMB_RT_CPU0_P3_R2_SCL")
	)
	(segment
		(start 237.03407 -339.14207)
		(end 237.03407 -341.838026)
		(width 0.11684)
		(layer "In4.Cu")
		(net "SMB_RT_CPU0_P3_R2_SCL")
	)
	(segment
		(start 237.03407 -341.838026)
		(end 244.983762 -349.787718)
		(width 0.11684)
		(layer "In4.Cu")
		(net "SMB_RT_CPU0_P3_R2_SCL")
	)
	(segment
		(start 234.188 -336.296)
		(end 237.03407 -339.14207)
		(width 0.11684)
		(layer "In4.Cu")
		(net "SMB_RT_CPU0_P3_R2_SCL")
	)
	(segment
		(start 244.983762 -349.787718)
		(end 244.983762 -367.816638)
		(width 0.11684)
		(layer "In4.Cu")
		(net "SMB_RT_CPU0_P3_R2_SCL")
	)
	(segment
		(start 422.981628 -393.81303)
		(end 423.387774 -393.531344)
		(width 0.10668)
		(layer "F.Cu")
		(net "SMB_RT_CPU0_P2_R2_SDA")
	)
	(via
		(at 235.077 -335.026)
		(size 0.508)
		(drill 0.254)
		(layers "F.Cu" "B.Cu")
		(net "SMB_RT_CPU0_P2_R2_SDA")
	)
	(via
		(at 436.47995 -372.93423)
		(size 0.508)
		(drill 0.254)
		(layers "F.Cu" "B.Cu")
		(net "SMB_RT_CPU0_P2_R2_SDA")
	)
	(via
		(at 245.618508 -367.795302)
		(size 0.508)
		(drill 0.254)
		(layers "F.Cu" "B.Cu")
		(net "SMB_RT_CPU0_P2_R2_SDA")
	)
	(via
		(at 423.387774 -393.531344)
		(size 0.4064)
		(drill 0.2032)
		(layers "F.Cu" "B.Cu")
		(net "SMB_RT_CPU0_P2_R2_SDA")
	)
	(segment
		(start 299.23105 -371.686328)
		(end 295.298114 -375.619264)
		(width 0.10668)
		(layer "B.Cu")
		(net "SMB_RT_CPU0_P2_R2_SDA")
	)
	(segment
		(start 234.790742 -334.739742)
		(end 235.077 -335.026)
		(width 0.10668)
		(layer "B.Cu")
		(net "SMB_RT_CPU0_P2_R2_SDA")
	)
	(segment
		(start 283.750766 -370.459254)
		(end 252.211332 -370.459254)
		(width 0.10668)
		(layer "B.Cu")
		(net "SMB_RT_CPU0_P2_R2_SDA")
	)
	(segment
		(start 295.298114 -375.619264)
		(end 291.397944 -375.619264)
		(width 0.10668)
		(layer "B.Cu")
		(net "SMB_RT_CPU0_P2_R2_SDA")
	)
	(segment
		(start 234.0737 -335.026)
		(end 234.359958 -334.739742)
		(width 0.10668)
		(layer "B.Cu")
		(net "SMB_RT_CPU0_P2_R2_SDA")
	)
	(segment
		(start 252.211332 -370.459254)
		(end 249.848878 -368.0968)
		(width 0.10668)
		(layer "B.Cu")
		(net "SMB_RT_CPU0_P2_R2_SDA")
	)
	(segment
		(start 288.072322 -372.293642)
		(end 285.585154 -372.293642)
		(width 0.10668)
		(layer "B.Cu")
		(net "SMB_RT_CPU0_P2_R2_SDA")
	)
	(segment
		(start 433.206906 -374.053354)
		(end 430.246536 -374.053354)
		(width 0.10668)
		(layer "B.Cu")
		(net "SMB_RT_CPU0_P2_R2_SDA")
	)
	(segment
		(start 234.359958 -334.739742)
		(end 234.790742 -334.739742)
		(width 0.10668)
		(layer "B.Cu")
		(net "SMB_RT_CPU0_P2_R2_SDA")
	)
	(segment
		(start 246.20728 -368.384074)
		(end 245.618508 -367.795302)
		(width 0.10668)
		(layer "B.Cu")
		(net "SMB_RT_CPU0_P2_R2_SDA")
	)
	(segment
		(start 427.87951 -371.686328)
		(end 299.23105 -371.686328)
		(width 0.10668)
		(layer "B.Cu")
		(net "SMB_RT_CPU0_P2_R2_SDA")
	)
	(segment
		(start 436.47995 -372.93423)
		(end 434.32603 -372.93423)
		(width 0.10668)
		(layer "B.Cu")
		(net "SMB_RT_CPU0_P2_R2_SDA")
	)
	(segment
		(start 434.32603 -372.93423)
		(end 433.206906 -374.053354)
		(width 0.10668)
		(layer "B.Cu")
		(net "SMB_RT_CPU0_P2_R2_SDA")
	)
	(segment
		(start 249.848878 -368.0968)
		(end 246.992648 -368.0968)
		(width 0.10668)
		(layer "B.Cu")
		(net "SMB_RT_CPU0_P2_R2_SDA")
	)
	(segment
		(start 430.246536 -374.053354)
		(end 427.87951 -371.686328)
		(width 0.10668)
		(layer "B.Cu")
		(net "SMB_RT_CPU0_P2_R2_SDA")
	)
	(segment
		(start 291.397944 -375.619264)
		(end 288.072322 -372.293642)
		(width 0.10668)
		(layer "B.Cu")
		(net "SMB_RT_CPU0_P2_R2_SDA")
	)
	(segment
		(start 285.585154 -372.293642)
		(end 283.750766 -370.459254)
		(width 0.10668)
		(layer "B.Cu")
		(net "SMB_RT_CPU0_P2_R2_SDA")
	)
	(segment
		(start 246.705374 -368.384074)
		(end 246.20728 -368.384074)
		(width 0.10668)
		(layer "B.Cu")
		(net "SMB_RT_CPU0_P2_R2_SDA")
	)
	(segment
		(start 246.992648 -368.0968)
		(end 246.705374 -368.384074)
		(width 0.10668)
		(layer "B.Cu")
		(net "SMB_RT_CPU0_P2_R2_SDA")
	)
	(segment
		(start 237.684056 -341.7316)
		(end 245.607078 -349.654622)
		(width 0.11684)
		(layer "In4.Cu")
		(net "SMB_RT_CPU0_P2_R2_SDA")
	)
	(segment
		(start 245.607078 -349.654622)
		(end 245.607078 -367.783872)
		(width 0.11684)
		(layer "In4.Cu")
		(net "SMB_RT_CPU0_P2_R2_SDA")
	)
	(segment
		(start 422.911524 -392.71321)
		(end 423.908474 -391.71626)
		(width 0.11684)
		(layer "In4.Cu")
		(net "SMB_RT_CPU0_P2_R2_SDA")
	)
	(segment
		(start 236.759496 -335.39811)
		(end 237.684056 -336.32267)
		(width 0.11684)
		(layer "In4.Cu")
		(net "SMB_RT_CPU0_P2_R2_SDA")
	)
	(segment
		(start 235.44911 -335.39811)
		(end 236.759496 -335.39811)
		(width 0.11684)
		(layer "In4.Cu")
		(net "SMB_RT_CPU0_P2_R2_SDA")
	)
	(segment
		(start 423.387774 -393.531344)
		(end 422.911524 -393.055094)
		(width 0.11684)
		(layer "In4.Cu")
		(net "SMB_RT_CPU0_P2_R2_SDA")
	)
	(segment
		(start 235.077 -335.026)
		(end 235.44911 -335.39811)
		(width 0.11684)
		(layer "In4.Cu")
		(net "SMB_RT_CPU0_P2_R2_SDA")
	)
	(segment
		(start 428.285402 -389.20547)
		(end 428.285402 -380.141226)
		(width 0.11684)
		(layer "In4.Cu")
		(net "SMB_RT_CPU0_P2_R2_SDA")
	)
	(segment
		(start 422.911524 -393.055094)
		(end 422.911524 -392.71321)
		(width 0.11684)
		(layer "In4.Cu")
		(net "SMB_RT_CPU0_P2_R2_SDA")
	)
	(segment
		(start 425.450254 -391.71626)
		(end 427.69282 -389.473694)
		(width 0.11684)
		(layer "In4.Cu")
		(net "SMB_RT_CPU0_P2_R2_SDA")
	)
	(segment
		(start 245.607078 -367.783872)
		(end 245.618508 -367.795302)
		(width 0.11684)
		(layer "In4.Cu")
		(net "SMB_RT_CPU0_P2_R2_SDA")
	)
	(segment
		(start 428.017178 -389.473694)
		(end 428.285402 -389.20547)
		(width 0.11684)
		(layer "In4.Cu")
		(net "SMB_RT_CPU0_P2_R2_SDA")
	)
	(segment
		(start 423.908474 -391.71626)
		(end 425.450254 -391.71626)
		(width 0.11684)
		(layer "In4.Cu")
		(net "SMB_RT_CPU0_P2_R2_SDA")
	)
	(segment
		(start 237.684056 -336.32267)
		(end 237.684056 -341.7316)
		(width 0.11684)
		(layer "In4.Cu")
		(net "SMB_RT_CPU0_P2_R2_SDA")
	)
	(segment
		(start 428.285402 -380.141226)
		(end 435.492398 -372.93423)
		(width 0.11684)
		(layer "In4.Cu")
		(net "SMB_RT_CPU0_P2_R2_SDA")
	)
	(segment
		(start 435.492398 -372.93423)
		(end 436.47995 -372.93423)
		(width 0.11684)
		(layer "In4.Cu")
		(net "SMB_RT_CPU0_P2_R2_SDA")
	)
	(segment
		(start 427.69282 -389.473694)
		(end 428.017178 -389.473694)
		(width 0.11684)
		(layer "In4.Cu")
		(net "SMB_RT_CPU0_P2_R2_SDA")
	)
	(segment
		(start 422.981628 -393.213082)
		(end 423.401998 -392.956542)
		(width 0.10668)
		(layer "F.Cu")
		(net "SMB_RT_CPU0_P2_R2_SCL")
	)
	(via
		(at 437.472836 -372.909084)
		(size 0.508)
		(drill 0.254)
		(layers "F.Cu" "B.Cu")
		(net "SMB_RT_CPU0_P2_R2_SCL")
	)
	(via
		(at 423.401998 -392.956542)
		(size 0.4064)
		(drill 0.2032)
		(layers "F.Cu" "B.Cu")
		(net "SMB_RT_CPU0_P2_R2_SCL")
	)
	(via
		(at 246.32539 -367.788698)
		(size 0.508)
		(drill 0.254)
		(layers "F.Cu" "B.Cu")
		(net "SMB_RT_CPU0_P2_R2_SCL")
	)
	(via
		(at 235.066586 -334.099408)
		(size 0.508)
		(drill 0.254)
		(layers "F.Cu" "B.Cu")
		(net "SMB_RT_CPU0_P2_R2_SCL")
	)
	(via
		(at 433.5399 -372.909084)
		(size 0.6604)
		(drill 0.3302)
		(layers "F.Cu" "B.Cu")
		(net "SMB_RT_CPU0_P2_R2_SCL")
	)
	(segment
		(start 432.763168 -373.685816)
		(end 433.5399 -372.909084)
		(width 0.10668)
		(layer "B.Cu")
		(net "SMB_RT_CPU0_P2_R2_SCL")
	)
	(segment
		(start 252.878844 -370.052854)
		(end 283.929328 -370.052854)
		(width 0.10668)
		(layer "B.Cu")
		(net "SMB_RT_CPU0_P2_R2_SCL")
	)
	(segment
		(start 291.593778 -375.278904)
		(end 295.15689 -375.278904)
		(width 0.10668)
		(layer "B.Cu")
		(net "SMB_RT_CPU0_P2_R2_SCL")
	)
	(segment
		(start 288.185606 -371.870732)
		(end 291.593778 -375.278904)
		(width 0.10668)
		(layer "B.Cu")
		(net "SMB_RT_CPU0_P2_R2_SCL")
	)
	(segment
		(start 436.913782 -372.35003)
		(end 437.472836 -372.909084)
		(width 0.10668)
		(layer "B.Cu")
		(net "SMB_RT_CPU0_P2_R2_SCL")
	)
	(segment
		(start 283.929328 -370.052854)
		(end 285.747206 -371.870732)
		(width 0.10668)
		(layer "B.Cu")
		(net "SMB_RT_CPU0_P2_R2_SCL")
	)
	(segment
		(start 250.35891 -367.53292)
		(end 252.878844 -370.052854)
		(width 0.10668)
		(layer "B.Cu")
		(net "SMB_RT_CPU0_P2_R2_SCL")
	)
	(segment
		(start 428.020988 -371.345968)
		(end 430.360836 -373.685816)
		(width 0.10668)
		(layer "B.Cu")
		(net "SMB_RT_CPU0_P2_R2_SCL")
	)
	(segment
		(start 295.15689 -375.278904)
		(end 299.089826 -371.345968)
		(width 0.10668)
		(layer "B.Cu")
		(net "SMB_RT_CPU0_P2_R2_SCL")
	)
	(segment
		(start 285.747206 -371.870732)
		(end 288.185606 -371.870732)
		(width 0.10668)
		(layer "B.Cu")
		(net "SMB_RT_CPU0_P2_R2_SCL")
	)
	(segment
		(start 433.5399 -372.909084)
		(end 434.098954 -372.35003)
		(width 0.10668)
		(layer "B.Cu")
		(net "SMB_RT_CPU0_P2_R2_SCL")
	)
	(segment
		(start 434.098954 -372.35003)
		(end 436.913782 -372.35003)
		(width 0.10668)
		(layer "B.Cu")
		(net "SMB_RT_CPU0_P2_R2_SCL")
	)
	(segment
		(start 430.360836 -373.685816)
		(end 432.763168 -373.685816)
		(width 0.10668)
		(layer "B.Cu")
		(net "SMB_RT_CPU0_P2_R2_SCL")
	)
	(segment
		(start 234.837732 -334.328262)
		(end 235.066586 -334.099408)
		(width 0.10668)
		(layer "B.Cu")
		(net "SMB_RT_CPU0_P2_R2_SCL")
	)
	(segment
		(start 234.391962 -334.328262)
		(end 234.837732 -334.328262)
		(width 0.10668)
		(layer "B.Cu")
		(net "SMB_RT_CPU0_P2_R2_SCL")
	)
	(segment
		(start 246.581168 -367.53292)
		(end 250.35891 -367.53292)
		(width 0.10668)
		(layer "B.Cu")
		(net "SMB_RT_CPU0_P2_R2_SCL")
	)
	(segment
		(start 246.32539 -367.788698)
		(end 246.581168 -367.53292)
		(width 0.10668)
		(layer "B.Cu")
		(net "SMB_RT_CPU0_P2_R2_SCL")
	)
	(segment
		(start 234.0737 -334.01)
		(end 234.391962 -334.328262)
		(width 0.10668)
		(layer "B.Cu")
		(net "SMB_RT_CPU0_P2_R2_SCL")
	)
	(segment
		(start 299.089826 -371.345968)
		(end 428.020988 -371.345968)
		(width 0.10668)
		(layer "B.Cu")
		(net "SMB_RT_CPU0_P2_R2_SCL")
	)
	(segment
		(start 428.762922 -389.468106)
		(end 428.762922 -380.331218)
		(width 0.11684)
		(layer "In4.Cu")
		(net "SMB_RT_CPU0_P2_R2_SCL")
	)
	(segment
		(start 423.401998 -392.956542)
		(end 424.110404 -392.248136)
		(width 0.11684)
		(layer "In4.Cu")
		(net "SMB_RT_CPU0_P2_R2_SCL")
	)
	(segment
		(start 238.49965 -341.703914)
		(end 246.32539 -349.529654)
		(width 0.11684)
		(layer "In4.Cu")
		(net "SMB_RT_CPU0_P2_R2_SCL")
	)
	(segment
		(start 435.672738 -373.421402)
		(end 436.960518 -373.421402)
		(width 0.11684)
		(layer "In4.Cu")
		(net "SMB_RT_CPU0_P2_R2_SCL")
	)
	(segment
		(start 425.526454 -392.248136)
		(end 427.799754 -389.974836)
		(width 0.11684)
		(layer "In4.Cu")
		(net "SMB_RT_CPU0_P2_R2_SCL")
	)
	(segment
		(start 236.728254 -334.851756)
		(end 237.074202 -334.851756)
		(width 0.11684)
		(layer "In4.Cu")
		(net "SMB_RT_CPU0_P2_R2_SCL")
	)
	(segment
		(start 246.32539 -349.529654)
		(end 246.32539 -367.788698)
		(width 0.11684)
		(layer "In4.Cu")
		(net "SMB_RT_CPU0_P2_R2_SCL")
	)
	(segment
		(start 428.256192 -389.974836)
		(end 428.762922 -389.468106)
		(width 0.11684)
		(layer "In4.Cu")
		(net "SMB_RT_CPU0_P2_R2_SCL")
	)
	(segment
		(start 235.975906 -334.099408)
		(end 236.728254 -334.851756)
		(width 0.11684)
		(layer "In4.Cu")
		(net "SMB_RT_CPU0_P2_R2_SCL")
	)
	(segment
		(start 428.762922 -380.331218)
		(end 435.672738 -373.421402)
		(width 0.11684)
		(layer "In4.Cu")
		(net "SMB_RT_CPU0_P2_R2_SCL")
	)
	(segment
		(start 235.066586 -334.099408)
		(end 235.975906 -334.099408)
		(width 0.11684)
		(layer "In4.Cu")
		(net "SMB_RT_CPU0_P2_R2_SCL")
	)
	(segment
		(start 238.49965 -336.277204)
		(end 238.49965 -341.703914)
		(width 0.11684)
		(layer "In4.Cu")
		(net "SMB_RT_CPU0_P2_R2_SCL")
	)
	(segment
		(start 424.110404 -392.248136)
		(end 425.526454 -392.248136)
		(width 0.11684)
		(layer "In4.Cu")
		(net "SMB_RT_CPU0_P2_R2_SCL")
	)
	(segment
		(start 237.074202 -334.851756)
		(end 238.49965 -336.277204)
		(width 0.11684)
		(layer "In4.Cu")
		(net "SMB_RT_CPU0_P2_R2_SCL")
	)
	(segment
		(start 436.960518 -373.421402)
		(end 437.472836 -372.909084)
		(width 0.11684)
		(layer "In4.Cu")
		(net "SMB_RT_CPU0_P2_R2_SCL")
	)
	(segment
		(start 427.799754 -389.974836)
		(end 428.256192 -389.974836)
		(width 0.11684)
		(layer "In4.Cu")
		(net "SMB_RT_CPU0_P2_R2_SCL")
	)
	(segment
		(start 355.881432 -393.81303)
		(end 356.287578 -393.531344)
		(width 0.10668)
		(layer "F.Cu")
		(net "SMB_RT_CPU0_P1_R2_SDA")
	)
	(via
		(at 235.077 -339.598)
		(size 0.508)
		(drill 0.254)
		(layers "F.Cu" "B.Cu")
		(net "SMB_RT_CPU0_P1_R2_SDA")
	)
	(via
		(at 356.287578 -393.531344)
		(size 0.4064)
		(drill 0.2032)
		(layers "F.Cu" "B.Cu")
		(net "SMB_RT_CPU0_P1_R2_SDA")
	)
	(via
		(at 242.453414 -367.869978)
		(size 0.508)
		(drill 0.254)
		(layers "F.Cu" "B.Cu")
		(net "SMB_RT_CPU0_P1_R2_SDA")
	)
	(segment
		(start 234.0737 -339.598)
		(end 234.27309 -339.39861)
		(width 0.10668)
		(layer "B.Cu")
		(net "SMB_RT_CPU0_P1_R2_SDA")
	)
	(segment
		(start 234.87761 -339.39861)
		(end 235.077 -339.598)
		(width 0.10668)
		(layer "B.Cu")
		(net "SMB_RT_CPU0_P1_R2_SDA")
	)
	(segment
		(start 234.27309 -339.39861)
		(end 234.87761 -339.39861)
		(width 0.10668)
		(layer "B.Cu")
		(net "SMB_RT_CPU0_P1_R2_SDA")
	)
	(segment
		(start 249.08383 -370.48948)
		(end 277.178262 -370.48948)
		(width 0.11684)
		(layer "In2.Cu")
		(net "SMB_RT_CPU0_P1_R2_SDA")
	)
	(segment
		(start 288.174938 -375.703084)
		(end 289.310064 -376.83821)
		(width 0.11684)
		(layer "In2.Cu")
		(net "SMB_RT_CPU0_P1_R2_SDA")
	)
	(segment
		(start 300.129194 -376.29211)
		(end 326.378824 -376.29211)
		(width 0.11684)
		(layer "In2.Cu")
		(net "SMB_RT_CPU0_P1_R2_SDA")
	)
	(segment
		(start 289.310064 -376.83821)
		(end 299.583094 -376.83821)
		(width 0.11684)
		(layer "In2.Cu")
		(net "SMB_RT_CPU0_P1_R2_SDA")
	)
	(segment
		(start 354.454206 -392.082528)
		(end 355.903022 -393.531344)
		(width 0.11684)
		(layer "In2.Cu")
		(net "SMB_RT_CPU0_P1_R2_SDA")
	)
	(segment
		(start 334.134968 -384.924554)
		(end 335.45272 -386.242306)
		(width 0.11684)
		(layer "In2.Cu")
		(net "SMB_RT_CPU0_P1_R2_SDA")
	)
	(segment
		(start 352.674428 -391.36828)
		(end 353.388676 -392.082528)
		(width 0.11684)
		(layer "In2.Cu")
		(net "SMB_RT_CPU0_P1_R2_SDA")
	)
	(segment
		(start 348.048326 -386.242306)
		(end 352.674428 -390.868408)
		(width 0.11684)
		(layer "In2.Cu")
		(net "SMB_RT_CPU0_P1_R2_SDA")
	)
	(segment
		(start 326.378824 -376.29211)
		(end 328.871072 -378.784358)
		(width 0.11684)
		(layer "In2.Cu")
		(net "SMB_RT_CPU0_P1_R2_SDA")
	)
	(segment
		(start 352.674428 -390.868408)
		(end 352.674428 -391.36828)
		(width 0.11684)
		(layer "In2.Cu")
		(net "SMB_RT_CPU0_P1_R2_SDA")
	)
	(segment
		(start 245.053612 -370.470176)
		(end 247.509284 -370.470176)
		(width 0.11684)
		(layer "In2.Cu")
		(net "SMB_RT_CPU0_P1_R2_SDA")
	)
	(segment
		(start 242.453414 -367.869978)
		(end 245.053612 -370.470176)
		(width 0.11684)
		(layer "In2.Cu")
		(net "SMB_RT_CPU0_P1_R2_SDA")
	)
	(segment
		(start 277.178262 -370.48948)
		(end 282.391866 -375.703084)
		(width 0.11684)
		(layer "In2.Cu")
		(net "SMB_RT_CPU0_P1_R2_SDA")
	)
	(segment
		(start 328.871072 -380.551944)
		(end 333.243682 -384.924554)
		(width 0.11684)
		(layer "In2.Cu")
		(net "SMB_RT_CPU0_P1_R2_SDA")
	)
	(segment
		(start 247.608598 -370.370862)
		(end 248.965212 -370.370862)
		(width 0.11684)
		(layer "In2.Cu")
		(net "SMB_RT_CPU0_P1_R2_SDA")
	)
	(segment
		(start 299.583094 -376.83821)
		(end 300.129194 -376.29211)
		(width 0.11684)
		(layer "In2.Cu")
		(net "SMB_RT_CPU0_P1_R2_SDA")
	)
	(segment
		(start 333.243682 -384.924554)
		(end 334.134968 -384.924554)
		(width 0.11684)
		(layer "In2.Cu")
		(net "SMB_RT_CPU0_P1_R2_SDA")
	)
	(segment
		(start 328.871072 -378.784358)
		(end 328.871072 -380.551944)
		(width 0.11684)
		(layer "In2.Cu")
		(net "SMB_RT_CPU0_P1_R2_SDA")
	)
	(segment
		(start 248.965212 -370.370862)
		(end 249.08383 -370.48948)
		(width 0.11684)
		(layer "In2.Cu")
		(net "SMB_RT_CPU0_P1_R2_SDA")
	)
	(segment
		(start 247.509284 -370.470176)
		(end 247.608598 -370.370862)
		(width 0.11684)
		(layer "In2.Cu")
		(net "SMB_RT_CPU0_P1_R2_SDA")
	)
	(segment
		(start 353.388676 -392.082528)
		(end 354.454206 -392.082528)
		(width 0.11684)
		(layer "In2.Cu")
		(net "SMB_RT_CPU0_P1_R2_SDA")
	)
	(segment
		(start 282.391866 -375.703084)
		(end 288.174938 -375.703084)
		(width 0.11684)
		(layer "In2.Cu")
		(net "SMB_RT_CPU0_P1_R2_SDA")
	)
	(segment
		(start 335.45272 -386.242306)
		(end 348.048326 -386.242306)
		(width 0.11684)
		(layer "In2.Cu")
		(net "SMB_RT_CPU0_P1_R2_SDA")
	)
	(segment
		(start 355.903022 -393.531344)
		(end 356.287578 -393.531344)
		(width 0.11684)
		(layer "In2.Cu")
		(net "SMB_RT_CPU0_P1_R2_SDA")
	)
	(segment
		(start 235.291884 -339.812884)
		(end 235.077 -339.598)
		(width 0.11684)
		(layer "In4.Cu")
		(net "SMB_RT_CPU0_P1_R2_SDA")
	)
	(segment
		(start 242.453414 -367.869978)
		(end 243.216684 -367.106708)
		(width 0.11684)
		(layer "In4.Cu")
		(net "SMB_RT_CPU0_P1_R2_SDA")
	)
	(segment
		(start 243.216684 -350.181672)
		(end 235.291884 -342.256872)
		(width 0.11684)
		(layer "In4.Cu")
		(net "SMB_RT_CPU0_P1_R2_SDA")
	)
	(segment
		(start 235.291884 -342.256872)
		(end 235.291884 -339.812884)
		(width 0.11684)
		(layer "In4.Cu")
		(net "SMB_RT_CPU0_P1_R2_SDA")
	)
	(segment
		(start 243.216684 -367.106708)
		(end 243.216684 -350.181672)
		(width 0.11684)
		(layer "In4.Cu")
		(net "SMB_RT_CPU0_P1_R2_SDA")
	)
	(segment
		(start 355.881432 -393.213082)
		(end 356.301802 -392.956542)
		(width 0.10668)
		(layer "F.Cu")
		(net "SMB_RT_CPU0_P1_R2_SCL")
	)
	(via
		(at 356.301802 -392.956542)
		(size 0.4064)
		(drill 0.2032)
		(layers "F.Cu" "B.Cu")
		(net "SMB_RT_CPU0_P1_R2_SCL")
	)
	(via
		(at 243.409724 -367.806224)
		(size 0.508)
		(drill 0.254)
		(layers "F.Cu" "B.Cu")
		(net "SMB_RT_CPU0_P1_R2_SCL")
	)
	(via
		(at 235.077 -338.582)
		(size 0.508)
		(drill 0.254)
		(layers "F.Cu" "B.Cu")
		(net "SMB_RT_CPU0_P1_R2_SCL")
	)
	(segment
		(start 234.338114 -338.846414)
		(end 234.0737 -338.582)
		(width 0.10668)
		(layer "B.Cu")
		(net "SMB_RT_CPU0_P1_R2_SCL")
	)
	(segment
		(start 235.077 -338.582)
		(end 234.812586 -338.846414)
		(width 0.10668)
		(layer "B.Cu")
		(net "SMB_RT_CPU0_P1_R2_SCL")
	)
	(segment
		(start 234.812586 -338.846414)
		(end 234.338114 -338.846414)
		(width 0.10668)
		(layer "B.Cu")
		(net "SMB_RT_CPU0_P1_R2_SCL")
	)
	(segment
		(start 288.261298 -375.145808)
		(end 282.430982 -375.145808)
		(width 0.11684)
		(layer "In2.Cu")
		(net "SMB_RT_CPU0_P1_R2_SCL")
	)
	(segment
		(start 249.823478 -370.06784)
		(end 248.98477 -369.229132)
		(width 0.11684)
		(layer "In2.Cu")
		(net "SMB_RT_CPU0_P1_R2_SCL")
	)
	(segment
		(start 248.98477 -369.229132)
		(end 248.07291 -369.229132)
		(width 0.11684)
		(layer "In2.Cu")
		(net "SMB_RT_CPU0_P1_R2_SCL")
	)
	(segment
		(start 244.968776 -369.646708)
		(end 243.409724 -368.087656)
		(width 0.11684)
		(layer "In2.Cu")
		(net "SMB_RT_CPU0_P1_R2_SCL")
	)
	(segment
		(start 246.898668 -369.16868)
		(end 246.42064 -369.646708)
		(width 0.11684)
		(layer "In2.Cu")
		(net "SMB_RT_CPU0_P1_R2_SCL")
	)
	(segment
		(start 282.430982 -375.145808)
		(end 277.353014 -370.06784)
		(width 0.11684)
		(layer "In2.Cu")
		(net "SMB_RT_CPU0_P1_R2_SCL")
	)
	(segment
		(start 289.53206 -376.41657)
		(end 288.261298 -375.145808)
		(width 0.11684)
		(layer "In2.Cu")
		(net "SMB_RT_CPU0_P1_R2_SCL")
	)
	(segment
		(start 335.67116 -385.71551)
		(end 334.353408 -384.397758)
		(width 0.11684)
		(layer "In2.Cu")
		(net "SMB_RT_CPU0_P1_R2_SCL")
	)
	(segment
		(start 353.62896 -390.47293)
		(end 348.87154 -385.71551)
		(width 0.11684)
		(layer "In2.Cu")
		(net "SMB_RT_CPU0_P1_R2_SCL")
	)
	(segment
		(start 299.367194 -376.41657)
		(end 289.53206 -376.41657)
		(width 0.11684)
		(layer "In2.Cu")
		(net "SMB_RT_CPU0_P1_R2_SCL")
	)
	(segment
		(start 356.301802 -392.956542)
		(end 355.00183 -391.65657)
		(width 0.11684)
		(layer "In2.Cu")
		(net "SMB_RT_CPU0_P1_R2_SCL")
	)
	(segment
		(start 329.397868 -378.565918)
		(end 326.70242 -375.87047)
		(width 0.11684)
		(layer "In2.Cu")
		(net "SMB_RT_CPU0_P1_R2_SCL")
	)
	(segment
		(start 326.70242 -375.87047)
		(end 299.913294 -375.87047)
		(width 0.11684)
		(layer "In2.Cu")
		(net "SMB_RT_CPU0_P1_R2_SCL")
	)
	(segment
		(start 334.353408 -384.397758)
		(end 333.462122 -384.397758)
		(width 0.11684)
		(layer "In2.Cu")
		(net "SMB_RT_CPU0_P1_R2_SCL")
	)
	(segment
		(start 243.409724 -368.087656)
		(end 243.409724 -367.806224)
		(width 0.11684)
		(layer "In2.Cu")
		(net "SMB_RT_CPU0_P1_R2_SCL")
	)
	(segment
		(start 277.353014 -370.06784)
		(end 249.823478 -370.06784)
		(width 0.11684)
		(layer "In2.Cu")
		(net "SMB_RT_CPU0_P1_R2_SCL")
	)
	(segment
		(start 355.00183 -391.65657)
		(end 353.992688 -391.65657)
		(width 0.11684)
		(layer "In2.Cu")
		(net "SMB_RT_CPU0_P1_R2_SCL")
	)
	(segment
		(start 348.87154 -385.71551)
		(end 335.67116 -385.71551)
		(width 0.11684)
		(layer "In2.Cu")
		(net "SMB_RT_CPU0_P1_R2_SCL")
	)
	(segment
		(start 353.62896 -391.292842)
		(end 353.62896 -390.47293)
		(width 0.11684)
		(layer "In2.Cu")
		(net "SMB_RT_CPU0_P1_R2_SCL")
	)
	(segment
		(start 353.992688 -391.65657)
		(end 353.62896 -391.292842)
		(width 0.11684)
		(layer "In2.Cu")
		(net "SMB_RT_CPU0_P1_R2_SCL")
	)
	(segment
		(start 246.42064 -369.646708)
		(end 244.968776 -369.646708)
		(width 0.11684)
		(layer "In2.Cu")
		(net "SMB_RT_CPU0_P1_R2_SCL")
	)
	(segment
		(start 299.913294 -375.87047)
		(end 299.367194 -376.41657)
		(width 0.11684)
		(layer "In2.Cu")
		(net "SMB_RT_CPU0_P1_R2_SCL")
	)
	(segment
		(start 248.012458 -369.16868)
		(end 246.898668 -369.16868)
		(width 0.11684)
		(layer "In2.Cu")
		(net "SMB_RT_CPU0_P1_R2_SCL")
	)
	(segment
		(start 329.397868 -380.333504)
		(end 329.397868 -378.565918)
		(width 0.11684)
		(layer "In2.Cu")
		(net "SMB_RT_CPU0_P1_R2_SCL")
	)
	(segment
		(start 333.462122 -384.397758)
		(end 329.397868 -380.333504)
		(width 0.11684)
		(layer "In2.Cu")
		(net "SMB_RT_CPU0_P1_R2_SCL")
	)
	(segment
		(start 248.07291 -369.229132)
		(end 248.012458 -369.16868)
		(width 0.11684)
		(layer "In2.Cu")
		(net "SMB_RT_CPU0_P1_R2_SCL")
	)
	(segment
		(start 243.838476 -350.09836)
		(end 243.838476 -367.377472)
		(width 0.11684)
		(layer "In4.Cu")
		(net "SMB_RT_CPU0_P1_R2_SCL")
	)
	(segment
		(start 235.077 -338.582)
		(end 235.900214 -339.405214)
		(width 0.11684)
		(layer "In4.Cu")
		(net "SMB_RT_CPU0_P1_R2_SCL")
	)
	(segment
		(start 243.838476 -367.377472)
		(end 243.409724 -367.806224)
		(width 0.11684)
		(layer "In4.Cu")
		(net "SMB_RT_CPU0_P1_R2_SCL")
	)
	(segment
		(start 235.900214 -339.405214)
		(end 235.900214 -342.160098)
		(width 0.11684)
		(layer "In4.Cu")
		(net "SMB_RT_CPU0_P1_R2_SCL")
	)
	(segment
		(start 235.900214 -342.160098)
		(end 243.838476 -350.09836)
		(width 0.11684)
		(layer "In4.Cu")
		(net "SMB_RT_CPU0_P1_R2_SCL")
	)
	(segment
		(start 323.353684 -393.81303)
		(end 323.75983 -393.531344)
		(width 0.10668)
		(layer "F.Cu")
		(net "SMB_RT_CPU0_P0_R2_SDA")
	)
	(via
		(at 239.80267 -367.872518)
		(size 0.508)
		(drill 0.254)
		(layers "F.Cu" "B.Cu")
		(net "SMB_RT_CPU0_P0_R2_SDA")
	)
	(via
		(at 323.75983 -393.531344)
		(size 0.4064)
		(drill 0.2032)
		(layers "F.Cu" "B.Cu")
		(net "SMB_RT_CPU0_P0_R2_SDA")
	)
	(via
		(at 234.188 -341.884)
		(size 0.508)
		(drill 0.254)
		(layers "F.Cu" "B.Cu")
		(net "SMB_RT_CPU0_P0_R2_SDA")
	)
	(segment
		(start 233.4387 -341.884)
		(end 234.188 -341.884)
		(width 0.10668)
		(layer "B.Cu")
		(net "SMB_RT_CPU0_P0_R2_SDA")
	)
	(segment
		(start 297.562016 -394.354304)
		(end 299.500036 -394.354304)
		(width 0.11684)
		(layer "In2.Cu")
		(net "SMB_RT_CPU0_P0_R2_SDA")
	)
	(segment
		(start 300.564804 -394.376402)
		(end 300.564804 -391.487406)
		(width 0.11684)
		(layer "In2.Cu")
		(net "SMB_RT_CPU0_P0_R2_SDA")
	)
	(segment
		(start 281.91968 -387.02996)
		(end 282.10002 -387.2103)
		(width 0.11684)
		(layer "In2.Cu")
		(net "SMB_RT_CPU0_P0_R2_SDA")
	)
	(segment
		(start 300.322488 -394.618718)
		(end 300.564804 -394.376402)
		(width 0.11684)
		(layer "In2.Cu")
		(net "SMB_RT_CPU0_P0_R2_SDA")
	)
	(segment
		(start 320.156586 -391.51306)
		(end 320.721228 -392.077702)
		(width 0.11684)
		(layer "In2.Cu")
		(net "SMB_RT_CPU0_P0_R2_SDA")
	)
	(segment
		(start 323.097652 -393.531344)
		(end 323.75983 -393.531344)
		(width 0.11684)
		(layer "In2.Cu")
		(net "SMB_RT_CPU0_P0_R2_SDA")
	)
	(segment
		(start 297.368976 -394.547344)
		(end 297.562016 -394.354304)
		(width 0.11684)
		(layer "In2.Cu")
		(net "SMB_RT_CPU0_P0_R2_SDA")
	)
	(segment
		(start 318.050418 -389.039608)
		(end 320.156586 -391.145776)
		(width 0.11684)
		(layer "In2.Cu")
		(net "SMB_RT_CPU0_P0_R2_SDA")
	)
	(segment
		(start 294.505888 -394.952728)
		(end 296.451274 -394.952728)
		(width 0.11684)
		(layer "In2.Cu")
		(net "SMB_RT_CPU0_P0_R2_SDA")
	)
	(segment
		(start 242.229386 -369.133628)
		(end 244.850158 -371.7544)
		(width 0.11684)
		(layer "In2.Cu")
		(net "SMB_RT_CPU0_P0_R2_SDA")
	)
	(segment
		(start 303.012602 -389.039608)
		(end 318.050418 -389.039608)
		(width 0.11684)
		(layer "In2.Cu")
		(net "SMB_RT_CPU0_P0_R2_SDA")
	)
	(segment
		(start 282.10002 -387.2103)
		(end 282.10002 -389.721344)
		(width 0.11684)
		(layer "In2.Cu")
		(net "SMB_RT_CPU0_P0_R2_SDA")
	)
	(segment
		(start 241.06378 -369.133628)
		(end 242.229386 -369.133628)
		(width 0.11684)
		(layer "In2.Cu")
		(net "SMB_RT_CPU0_P0_R2_SDA")
	)
	(segment
		(start 244.850158 -371.7544)
		(end 276.65172 -371.7544)
		(width 0.11684)
		(layer "In2.Cu")
		(net "SMB_RT_CPU0_P0_R2_SDA")
	)
	(segment
		(start 320.156586 -391.145776)
		(end 320.156586 -391.51306)
		(width 0.11684)
		(layer "In2.Cu")
		(net "SMB_RT_CPU0_P0_R2_SDA")
	)
	(segment
		(start 321.64401 -392.077702)
		(end 323.097652 -393.531344)
		(width 0.11684)
		(layer "In2.Cu")
		(net "SMB_RT_CPU0_P0_R2_SDA")
	)
	(segment
		(start 296.451274 -394.952728)
		(end 296.856658 -394.547344)
		(width 0.11684)
		(layer "In2.Cu")
		(net "SMB_RT_CPU0_P0_R2_SDA")
	)
	(segment
		(start 299.500036 -394.354304)
		(end 299.76445 -394.618718)
		(width 0.11684)
		(layer "In2.Cu")
		(net "SMB_RT_CPU0_P0_R2_SDA")
	)
	(segment
		(start 286.429196 -394.05052)
		(end 293.60368 -394.05052)
		(width 0.11684)
		(layer "In2.Cu")
		(net "SMB_RT_CPU0_P0_R2_SDA")
	)
	(segment
		(start 276.65172 -371.7544)
		(end 281.91968 -377.02236)
		(width 0.11684)
		(layer "In2.Cu")
		(net "SMB_RT_CPU0_P0_R2_SDA")
	)
	(segment
		(start 293.60368 -394.05052)
		(end 294.505888 -394.952728)
		(width 0.11684)
		(layer "In2.Cu")
		(net "SMB_RT_CPU0_P0_R2_SDA")
	)
	(segment
		(start 281.91968 -377.02236)
		(end 281.91968 -387.02996)
		(width 0.11684)
		(layer "In2.Cu")
		(net "SMB_RT_CPU0_P0_R2_SDA")
	)
	(segment
		(start 300.564804 -391.487406)
		(end 303.012602 -389.039608)
		(width 0.11684)
		(layer "In2.Cu")
		(net "SMB_RT_CPU0_P0_R2_SDA")
	)
	(segment
		(start 239.80267 -367.872518)
		(end 241.06378 -369.133628)
		(width 0.11684)
		(layer "In2.Cu")
		(net "SMB_RT_CPU0_P0_R2_SDA")
	)
	(segment
		(start 320.721228 -392.077702)
		(end 321.64401 -392.077702)
		(width 0.11684)
		(layer "In2.Cu")
		(net "SMB_RT_CPU0_P0_R2_SDA")
	)
	(segment
		(start 299.76445 -394.618718)
		(end 300.322488 -394.618718)
		(width 0.11684)
		(layer "In2.Cu")
		(net "SMB_RT_CPU0_P0_R2_SDA")
	)
	(segment
		(start 296.856658 -394.547344)
		(end 297.368976 -394.547344)
		(width 0.11684)
		(layer "In2.Cu")
		(net "SMB_RT_CPU0_P0_R2_SDA")
	)
	(segment
		(start 282.10002 -389.721344)
		(end 286.429196 -394.05052)
		(width 0.11684)
		(layer "In2.Cu")
		(net "SMB_RT_CPU0_P0_R2_SDA")
	)
	(segment
		(start 239.80267 -367.872518)
		(end 239.80267 -367.026698)
		(width 0.11684)
		(layer "In4.Cu")
		(net "SMB_RT_CPU0_P0_R2_SDA")
	)
	(segment
		(start 234.188 -342.480392)
		(end 234.188 -341.884)
		(width 0.11684)
		(layer "In4.Cu")
		(net "SMB_RT_CPU0_P0_R2_SDA")
	)
	(segment
		(start 242.220496 -364.608872)
		(end 242.220496 -350.512888)
		(width 0.11684)
		(layer "In4.Cu")
		(net "SMB_RT_CPU0_P0_R2_SDA")
	)
	(segment
		(start 242.220496 -350.512888)
		(end 234.188 -342.480392)
		(width 0.11684)
		(layer "In4.Cu")
		(net "SMB_RT_CPU0_P0_R2_SDA")
	)
	(segment
		(start 239.80267 -367.026698)
		(end 242.220496 -364.608872)
		(width 0.11684)
		(layer "In4.Cu")
		(net "SMB_RT_CPU0_P0_R2_SDA")
	)
	(segment
		(start 323.353684 -393.213082)
		(end 323.774054 -392.956542)
		(width 0.10668)
		(layer "F.Cu")
		(net "SMB_RT_CPU0_P0_R2_SCL")
	)
	(via
		(at 241.100864 -367.877598)
		(size 0.508)
		(drill 0.254)
		(layers "F.Cu" "B.Cu")
		(net "SMB_RT_CPU0_P0_R2_SCL")
	)
	(via
		(at 323.774054 -392.956542)
		(size 0.4064)
		(drill 0.2032)
		(layers "F.Cu" "B.Cu")
		(net "SMB_RT_CPU0_P0_R2_SCL")
	)
	(via
		(at 234.188 -340.868)
		(size 0.508)
		(drill 0.254)
		(layers "F.Cu" "B.Cu")
		(net "SMB_RT_CPU0_P0_R2_SCL")
	)
	(segment
		(start 233.4387 -340.868)
		(end 234.188 -340.868)
		(width 0.10668)
		(layer "B.Cu")
		(net "SMB_RT_CPU0_P0_R2_SCL")
	)
	(segment
		(start 318.233552 -388.250684)
		(end 303.179988 -388.250684)
		(width 0.11684)
		(layer "In2.Cu")
		(net "SMB_RT_CPU0_P0_R2_SCL")
	)
	(segment
		(start 294.679878 -394.52042)
		(end 293.714678 -393.55522)
		(width 0.11684)
		(layer "In2.Cu")
		(net "SMB_RT_CPU0_P0_R2_SCL")
	)
	(segment
		(start 286.530288 -393.55522)
		(end 282.58262 -389.607552)
		(width 0.11684)
		(layer "In2.Cu")
		(net "SMB_RT_CPU0_P0_R2_SCL")
	)
	(segment
		(start 242.413282 -368.557302)
		(end 241.650774 -368.557302)
		(width 0.11684)
		(layer "In2.Cu")
		(net "SMB_RT_CPU0_P0_R2_SCL")
	)
	(segment
		(start 321.633596 -391.650728)
		(end 318.233552 -388.250684)
		(width 0.11684)
		(layer "In2.Cu")
		(net "SMB_RT_CPU0_P0_R2_SCL")
	)
	(segment
		(start 322.100194 -391.650728)
		(end 321.633596 -391.650728)
		(width 0.11684)
		(layer "In2.Cu")
		(net "SMB_RT_CPU0_P0_R2_SCL")
	)
	(segment
		(start 282.48102 -376.985022)
		(end 276.828758 -371.33276)
		(width 0.11684)
		(layer "In2.Cu")
		(net "SMB_RT_CPU0_P0_R2_SCL")
	)
	(segment
		(start 282.58262 -389.607552)
		(end 282.58262 -387.1214)
		(width 0.11684)
		(layer "In2.Cu")
		(net "SMB_RT_CPU0_P0_R2_SCL")
	)
	(segment
		(start 303.179988 -388.250684)
		(end 298.078652 -393.35202)
		(width 0.11684)
		(layer "In2.Cu")
		(net "SMB_RT_CPU0_P0_R2_SCL")
	)
	(segment
		(start 241.650774 -368.557302)
		(end 241.100864 -368.007392)
		(width 0.11684)
		(layer "In2.Cu")
		(net "SMB_RT_CPU0_P0_R2_SCL")
	)
	(segment
		(start 241.100864 -368.007392)
		(end 241.100864 -367.877598)
		(width 0.11684)
		(layer "In2.Cu")
		(net "SMB_RT_CPU0_P0_R2_SCL")
	)
	(segment
		(start 297.049698 -393.35202)
		(end 295.881298 -394.52042)
		(width 0.11684)
		(layer "In2.Cu")
		(net "SMB_RT_CPU0_P0_R2_SCL")
	)
	(segment
		(start 295.881298 -394.52042)
		(end 294.679878 -394.52042)
		(width 0.11684)
		(layer "In2.Cu")
		(net "SMB_RT_CPU0_P0_R2_SCL")
	)
	(segment
		(start 298.078652 -393.35202)
		(end 297.049698 -393.35202)
		(width 0.11684)
		(layer "In2.Cu")
		(net "SMB_RT_CPU0_P0_R2_SCL")
	)
	(segment
		(start 323.774054 -392.956542)
		(end 323.406008 -392.956542)
		(width 0.11684)
		(layer "In2.Cu")
		(net "SMB_RT_CPU0_P0_R2_SCL")
	)
	(segment
		(start 323.406008 -392.956542)
		(end 322.100194 -391.650728)
		(width 0.11684)
		(layer "In2.Cu")
		(net "SMB_RT_CPU0_P0_R2_SCL")
	)
	(segment
		(start 276.828758 -371.33276)
		(end 245.18874 -371.33276)
		(width 0.11684)
		(layer "In2.Cu")
		(net "SMB_RT_CPU0_P0_R2_SCL")
	)
	(segment
		(start 293.714678 -393.55522)
		(end 286.530288 -393.55522)
		(width 0.11684)
		(layer "In2.Cu")
		(net "SMB_RT_CPU0_P0_R2_SCL")
	)
	(segment
		(start 282.48102 -387.0198)
		(end 282.48102 -376.985022)
		(width 0.11684)
		(layer "In2.Cu")
		(net "SMB_RT_CPU0_P0_R2_SCL")
	)
	(segment
		(start 245.18874 -371.33276)
		(end 242.413282 -368.557302)
		(width 0.11684)
		(layer "In2.Cu")
		(net "SMB_RT_CPU0_P0_R2_SCL")
	)
	(segment
		(start 282.58262 -387.1214)
		(end 282.48102 -387.0198)
		(width 0.11684)
		(layer "In2.Cu")
		(net "SMB_RT_CPU0_P0_R2_SCL")
	)
	(segment
		(start 242.644168 -365.764572)
		(end 242.644168 -350.314768)
		(width 0.11684)
		(layer "In4.Cu")
		(net "SMB_RT_CPU0_P0_R2_SCL")
	)
	(segment
		(start 234.724956 -342.395556)
		(end 234.724956 -341.404956)
		(width 0.11684)
		(layer "In4.Cu")
		(net "SMB_RT_CPU0_P0_R2_SCL")
	)
	(segment
		(start 234.724956 -341.404956)
		(end 234.188 -340.868)
		(width 0.11684)
		(layer "In4.Cu")
		(net "SMB_RT_CPU0_P0_R2_SCL")
	)
	(segment
		(start 242.644168 -350.314768)
		(end 234.724956 -342.395556)
		(width 0.11684)
		(layer "In4.Cu")
		(net "SMB_RT_CPU0_P0_R2_SCL")
	)
	(segment
		(start 241.100864 -367.307876)
		(end 242.644168 -365.764572)
		(width 0.11684)
		(layer "In4.Cu")
		(net "SMB_RT_CPU0_P0_R2_SCL")
	)
	(segment
		(start 241.100864 -367.877598)
		(end 241.100864 -367.307876)
		(width 0.11684)
		(layer "In4.Cu")
		(net "SMB_RT_CPU0_P0_R2_SCL")
	)
	(segment
		(start 389.653018 -403.0091)
		(end 389.653018 -403.7457)
		(width 0.10668)
		(layer "F.Cu")
		(net "RT_CPU0_P3_VQPS")
	)
	(segment
		(start 390.112758 -401.22602)
		(end 390.112758 -402.763736)
		(width 0.10668)
		(layer "F.Cu")
		(net "RT_CPU0_P3_VQPS")
	)
	(segment
		(start 389.653018 -403.7457)
		(end 388.824978 -403.7457)
		(width 0.10668)
		(layer "F.Cu")
		(net "RT_CPU0_P3_VQPS")
	)
	(segment
		(start 389.418068 -400.53133)
		(end 390.112758 -401.22602)
		(width 0.10668)
		(layer "F.Cu")
		(net "RT_CPU0_P3_VQPS")
	)
	(segment
		(start 389.867394 -403.0091)
		(end 389.653018 -403.0091)
		(width 0.10668)
		(layer "F.Cu")
		(net "RT_CPU0_P3_VQPS")
	)
	(segment
		(start 389.418068 -399.663158)
		(end 389.418068 -400.53133)
		(width 0.10668)
		(layer "F.Cu")
		(net "RT_CPU0_P3_VQPS")
	)
	(segment
		(start 390.112758 -402.763736)
		(end 389.867394 -403.0091)
		(width 0.10668)
		(layer "F.Cu")
		(net "RT_CPU0_P3_VQPS")
	)
	(via
		(at 388.824978 -403.7457)
		(size 0.762)
		(drill 0.381)
		(layers "F.Cu" "B.Cu")
		(net "RT_CPU0_P3_VQPS")
	)
	(segment
		(start 369.027964 -392.739372)
		(end 369.2017 -392.913108)
		(width 0.10668)
		(layer "F.Cu")
		(net "RT_CPU0_P3_SCAN_MODE")
	)
	(segment
		(start 368.501168 -392.739372)
		(end 369.027964 -392.739372)
		(width 0.10668)
		(layer "F.Cu")
		(net "RT_CPU0_P3_SCAN_MODE")
	)
	(via
		(at 367.816638 -391.66546)
		(size 0.6604)
		(drill 0.3302)
		(layers "F.Cu" "B.Cu")
		(net "RT_CPU0_P3_SCAN_MODE")
	)
	(via
		(at 368.501168 -392.739372)
		(size 0.4064)
		(drill 0.2032)
		(layers "F.Cu" "B.Cu")
		(net "RT_CPU0_P3_SCAN_MODE")
	)
	(segment
		(start 366.267238 -391.66546)
		(end 366.09909 -391.833608)
		(width 0.10668)
		(layer "B.Cu")
		(net "RT_CPU0_P3_SCAN_MODE")
	)
	(segment
		(start 368.501168 -392.34999)
		(end 367.816638 -391.66546)
		(width 0.10668)
		(layer "B.Cu")
		(net "RT_CPU0_P3_SCAN_MODE")
	)
	(segment
		(start 367.816638 -391.66546)
		(end 366.267238 -391.66546)
		(width 0.10668)
		(layer "B.Cu")
		(net "RT_CPU0_P3_SCAN_MODE")
	)
	(segment
		(start 366.09909 -391.833608)
		(end 366.09909 -392.1252)
		(width 0.10668)
		(layer "B.Cu")
		(net "RT_CPU0_P3_SCAN_MODE")
	)
	(segment
		(start 365.36249 -392.1252)
		(end 366.09909 -392.1252)
		(width 0.10668)
		(layer "B.Cu")
		(net "RT_CPU0_P3_SCAN_MODE")
	)
	(segment
		(start 368.501168 -392.739372)
		(end 368.501168 -392.34999)
		(width 0.10668)
		(layer "B.Cu")
		(net "RT_CPU0_P3_SCAN_MODE")
	)
	(segment
		(start 394.606526 -395.481048)
		(end 394.464286 -395.623288)
		(width 0.10668)
		(layer "F.Cu")
		(net "RT_CPU0_P3_ADDR3")
	)
	(segment
		(start 393.754864 -395.855952)
		(end 393.382754 -396.228062)
		(width 0.10668)
		(layer "F.Cu")
		(net "RT_CPU0_P3_ADDR3")
	)
	(segment
		(start 390.82472 -395.037818)
		(end 392.014964 -396.228062)
		(width 0.10668)
		(layer "F.Cu")
		(net "RT_CPU0_P3_ADDR3")
	)
	(segment
		(start 394.848842 -394.90523)
		(end 394.606526 -395.144752)
		(width 0.10668)
		(layer "F.Cu")
		(net "RT_CPU0_P3_ADDR3")
	)
	(segment
		(start 390.82472 -394.783818)
		(end 390.82472 -395.037818)
		(width 0.10668)
		(layer "F.Cu")
		(net "RT_CPU0_P3_ADDR3")
	)
	(segment
		(start 394.981938 -394.1699)
		(end 394.981938 -394.9065)
		(width 0.10668)
		(layer "F.Cu")
		(net "RT_CPU0_P3_ADDR3")
	)
	(segment
		(start 393.902692 -395.855952)
		(end 393.754864 -395.855952)
		(width 0.10668)
		(layer "F.Cu")
		(net "RT_CPU0_P3_ADDR3")
	)
	(segment
		(start 394.606526 -395.144752)
		(end 394.606526 -395.481048)
		(width 0.10668)
		(layer "F.Cu")
		(net "RT_CPU0_P3_ADDR3")
	)
	(segment
		(start 394.981938 -394.9065)
		(end 394.848842 -394.90523)
		(width 0.10668)
		(layer "F.Cu")
		(net "RT_CPU0_P3_ADDR3")
	)
	(segment
		(start 392.014964 -396.228062)
		(end 393.382754 -396.228062)
		(width 0.10668)
		(layer "F.Cu")
		(net "RT_CPU0_P3_ADDR3")
	)
	(segment
		(start 390.45388 -394.412978)
		(end 390.82472 -394.783818)
		(width 0.10668)
		(layer "F.Cu")
		(net "RT_CPU0_P3_ADDR3")
	)
	(segment
		(start 394.464286 -395.623288)
		(end 393.902692 -395.855952)
		(width 0.10668)
		(layer "F.Cu")
		(net "RT_CPU0_P3_ADDR3")
	)
	(via
		(at 393.382754 -396.228062)
		(size 0.762)
		(drill 0.381)
		(layers "F.Cu" "B.Cu")
		(net "RT_CPU0_P3_ADDR3")
	)
	(segment
		(start 393.02436 -396.715996)
		(end 393.262866 -396.814802)
		(width 0.10668)
		(layer "F.Cu")
		(net "RT_CPU0_P3_ADDR2")
	)
	(segment
		(start 395.880082 -394.9065)
		(end 395.794738 -394.9065)
		(width 0.10668)
		(layer "F.Cu")
		(net "RT_CPU0_P3_ADDR2")
	)
	(segment
		(start 394.652754 -396.228062)
		(end 395.109446 -396.684754)
		(width 0.10668)
		(layer "F.Cu")
		(net "RT_CPU0_P3_ADDR2")
	)
	(segment
		(start 392.77544 -396.467076)
		(end 393.02436 -396.715996)
		(width 0.10668)
		(layer "F.Cu")
		(net "RT_CPU0_P3_ADDR2")
	)
	(segment
		(start 394.066014 -396.814802)
		(end 394.652754 -396.228062)
		(width 0.10668)
		(layer "F.Cu")
		(net "RT_CPU0_P3_ADDR2")
	)
	(segment
		(start 395.603476 -396.684754)
		(end 396.1765 -396.11173)
		(width 0.10668)
		(layer "F.Cu")
		(net "RT_CPU0_P3_ADDR2")
	)
	(segment
		(start 396.1765 -395.202918)
		(end 395.880082 -394.9065)
		(width 0.10668)
		(layer "F.Cu")
		(net "RT_CPU0_P3_ADDR2")
	)
	(segment
		(start 390.45388 -395.012926)
		(end 391.90803 -396.467076)
		(width 0.10668)
		(layer "F.Cu")
		(net "RT_CPU0_P3_ADDR2")
	)
	(segment
		(start 395.794738 -394.9065)
		(end 395.794738 -394.1699)
		(width 0.10668)
		(layer "F.Cu")
		(net "RT_CPU0_P3_ADDR2")
	)
	(segment
		(start 396.1765 -396.11173)
		(end 396.1765 -395.202918)
		(width 0.10668)
		(layer "F.Cu")
		(net "RT_CPU0_P3_ADDR2")
	)
	(segment
		(start 395.109446 -396.684754)
		(end 395.603476 -396.684754)
		(width 0.10668)
		(layer "F.Cu")
		(net "RT_CPU0_P3_ADDR2")
	)
	(segment
		(start 393.262866 -396.814802)
		(end 394.066014 -396.814802)
		(width 0.10668)
		(layer "F.Cu")
		(net "RT_CPU0_P3_ADDR2")
	)
	(segment
		(start 391.90803 -396.467076)
		(end 392.77544 -396.467076)
		(width 0.10668)
		(layer "F.Cu")
		(net "RT_CPU0_P3_ADDR2")
	)
	(via
		(at 394.652754 -396.228062)
		(size 0.762)
		(drill 0.381)
		(layers "F.Cu" "B.Cu")
		(net "RT_CPU0_P3_ADDR2")
	)
	(segment
		(start 389.718042 -392.30427)
		(end 389.718042 -392.304524)
		(width 0.10668)
		(layer "F.Cu")
		(net "RT_CPU0_P3_ADDR1")
	)
	(segment
		(start 393.800584 -391.0584)
		(end 393.800584 -390.957308)
		(width 0.10668)
		(layer "F.Cu")
		(net "RT_CPU0_P3_ADDR1")
	)
	(segment
		(start 391.208768 -391.941812)
		(end 392.433302 -391.941812)
		(width 0.10668)
		(layer "F.Cu")
		(net "RT_CPU0_P3_ADDR1")
	)
	(segment
		(start 394.105892 -390.652)
		(end 395.121384 -390.652)
		(width 0.10668)
		(layer "F.Cu")
		(net "RT_CPU0_P3_ADDR1")
	)
	(segment
		(start 393.487656 -391.371328)
		(end 393.800584 -391.0584)
		(width 0.10668)
		(layer "F.Cu")
		(net "RT_CPU0_P3_ADDR1")
	)
	(segment
		(start 395.121384 -390.652)
		(end 395.121384 -390.816338)
		(width 0.10668)
		(layer "F.Cu")
		(net "RT_CPU0_P3_ADDR1")
	)
	(segment
		(start 389.718042 -392.304524)
		(end 389.92683 -392.513312)
		(width 0.10668)
		(layer "F.Cu")
		(net "RT_CPU0_P3_ADDR1")
	)
	(segment
		(start 395.121384 -390.816338)
		(end 395.966696 -391.66165)
		(width 0.10668)
		(layer "F.Cu")
		(net "RT_CPU0_P3_ADDR1")
	)
	(segment
		(start 390.048242 -392.513312)
		(end 390.200896 -392.665966)
		(width 0.10668)
		(layer "F.Cu")
		(net "RT_CPU0_P3_ADDR1")
	)
	(segment
		(start 390.200896 -392.665966)
		(end 390.484614 -392.665966)
		(width 0.10668)
		(layer "F.Cu")
		(net "RT_CPU0_P3_ADDR1")
	)
	(segment
		(start 393.003786 -391.371328)
		(end 393.487656 -391.371328)
		(width 0.10668)
		(layer "F.Cu")
		(net "RT_CPU0_P3_ADDR1")
	)
	(segment
		(start 390.484614 -392.665966)
		(end 391.208768 -391.941812)
		(width 0.10668)
		(layer "F.Cu")
		(net "RT_CPU0_P3_ADDR1")
	)
	(segment
		(start 392.433302 -391.941812)
		(end 393.003786 -391.371328)
		(width 0.10668)
		(layer "F.Cu")
		(net "RT_CPU0_P3_ADDR1")
	)
	(segment
		(start 393.800584 -390.957308)
		(end 394.105892 -390.652)
		(width 0.10668)
		(layer "F.Cu")
		(net "RT_CPU0_P3_ADDR1")
	)
	(segment
		(start 389.92683 -392.513312)
		(end 390.048242 -392.513312)
		(width 0.10668)
		(layer "F.Cu")
		(net "RT_CPU0_P3_ADDR1")
	)
	(via
		(at 395.966696 -391.66165)
		(size 0.762)
		(drill 0.381)
		(layers "F.Cu" "B.Cu")
		(net "RT_CPU0_P3_ADDR1")
	)
	(segment
		(start 422.640506 -402.763736)
		(end 422.395142 -403.0091)
		(width 0.10668)
		(layer "F.Cu")
		(net "RT_CPU0_P2_VQPS")
	)
	(segment
		(start 422.180766 -403.7457)
		(end 421.352726 -403.7457)
		(width 0.10668)
		(layer "F.Cu")
		(net "RT_CPU0_P2_VQPS")
	)
	(segment
		(start 421.945816 -399.663158)
		(end 421.945816 -400.53133)
		(width 0.10668)
		(layer "F.Cu")
		(net "RT_CPU0_P2_VQPS")
	)
	(segment
		(start 422.395142 -403.0091)
		(end 422.180766 -403.0091)
		(width 0.10668)
		(layer "F.Cu")
		(net "RT_CPU0_P2_VQPS")
	)
	(segment
		(start 422.180766 -403.0091)
		(end 422.180766 -403.7457)
		(width 0.10668)
		(layer "F.Cu")
		(net "RT_CPU0_P2_VQPS")
	)
	(segment
		(start 421.945816 -400.53133)
		(end 422.640506 -401.22602)
		(width 0.10668)
		(layer "F.Cu")
		(net "RT_CPU0_P2_VQPS")
	)
	(segment
		(start 422.640506 -401.22602)
		(end 422.640506 -402.763736)
		(width 0.10668)
		(layer "F.Cu")
		(net "RT_CPU0_P2_VQPS")
	)
	(via
		(at 421.352726 -403.7457)
		(size 0.762)
		(drill 0.381)
		(layers "F.Cu" "B.Cu")
		(net "RT_CPU0_P2_VQPS")
	)
	(segment
		(start 401.555712 -392.739372)
		(end 401.729448 -392.913108)
		(width 0.10668)
		(layer "F.Cu")
		(net "RT_CPU0_P2_SCAN_MODE")
	)
	(segment
		(start 401.028916 -392.739372)
		(end 401.555712 -392.739372)
		(width 0.10668)
		(layer "F.Cu")
		(net "RT_CPU0_P2_SCAN_MODE")
	)
	(via
		(at 400.236436 -391.66546)
		(size 0.6604)
		(drill 0.3302)
		(layers "F.Cu" "B.Cu")
		(net "RT_CPU0_P2_SCAN_MODE")
	)
	(via
		(at 401.028916 -392.739372)
		(size 0.4064)
		(drill 0.2032)
		(layers "F.Cu" "B.Cu")
		(net "RT_CPU0_P2_SCAN_MODE")
	)
	(segment
		(start 401.028916 -392.45794)
		(end 400.236436 -391.66546)
		(width 0.10668)
		(layer "B.Cu")
		(net "RT_CPU0_P2_SCAN_MODE")
	)
	(segment
		(start 400.236436 -391.66546)
		(end 398.794986 -391.66546)
		(width 0.10668)
		(layer "B.Cu")
		(net "RT_CPU0_P2_SCAN_MODE")
	)
	(segment
		(start 397.890238 -392.1252)
		(end 398.626838 -392.1252)
		(width 0.10668)
		(layer "B.Cu")
		(net "RT_CPU0_P2_SCAN_MODE")
	)
	(segment
		(start 398.626838 -391.833608)
		(end 398.626838 -392.1252)
		(width 0.10668)
		(layer "B.Cu")
		(net "RT_CPU0_P2_SCAN_MODE")
	)
	(segment
		(start 398.794986 -391.66546)
		(end 398.626838 -391.833608)
		(width 0.10668)
		(layer "B.Cu")
		(net "RT_CPU0_P2_SCAN_MODE")
	)
	(segment
		(start 401.028916 -392.739372)
		(end 401.028916 -392.45794)
		(width 0.10668)
		(layer "B.Cu")
		(net "RT_CPU0_P2_SCAN_MODE")
	)
	(segment
		(start 423.35577 -394.887196)
		(end 423.35577 -394.78712)
		(width 0.10668)
		(layer "F.Cu")
		(net "RT_CPU0_P2_ADDR3")
	)
	(segment
		(start 430.29505 -398.058132)
		(end 430.29505 -398.91208)
		(width 0.10668)
		(layer "F.Cu")
		(net "RT_CPU0_P2_ADDR3")
	)
	(segment
		(start 424.650662 -396.888462)
		(end 423.974006 -396.211806)
		(width 0.10668)
		(layer "F.Cu")
		(net "RT_CPU0_P2_ADDR3")
	)
	(segment
		(start 423.974006 -396.211806)
		(end 423.974006 -395.505432)
		(width 0.10668)
		(layer "F.Cu")
		(net "RT_CPU0_P2_ADDR3")
	)
	(segment
		(start 423.974006 -395.505432)
		(end 423.35577 -394.887196)
		(width 0.10668)
		(layer "F.Cu")
		(net "RT_CPU0_P2_ADDR3")
	)
	(segment
		(start 430.29505 -398.058132)
		(end 429.857408 -397.62049)
		(width 0.10668)
		(layer "F.Cu")
		(net "RT_CPU0_P2_ADDR3")
	)
	(segment
		(start 423.35577 -394.78712)
		(end 422.981628 -394.412978)
		(width 0.10668)
		(layer "F.Cu")
		(net "RT_CPU0_P2_ADDR3")
	)
	(segment
		(start 429.857408 -397.62049)
		(end 424.844972 -397.62049)
		(width 0.10668)
		(layer "F.Cu")
		(net "RT_CPU0_P2_ADDR3")
	)
	(segment
		(start 424.844972 -397.62049)
		(end 424.650662 -397.42618)
		(width 0.10668)
		(layer "F.Cu")
		(net "RT_CPU0_P2_ADDR3")
	)
	(segment
		(start 430.654206 -399.271236)
		(end 430.654206 -400.304762)
		(width 0.10668)
		(layer "F.Cu")
		(net "RT_CPU0_P2_ADDR3")
	)
	(segment
		(start 424.650662 -397.42618)
		(end 424.650662 -396.888462)
		(width 0.10668)
		(layer "F.Cu")
		(net "RT_CPU0_P2_ADDR3")
	)
	(segment
		(start 430.654206 -400.304762)
		(end 430.2379 -400.721068)
		(width 0.10668)
		(layer "F.Cu")
		(net "RT_CPU0_P2_ADDR3")
	)
	(segment
		(start 430.29505 -398.91208)
		(end 430.654206 -399.271236)
		(width 0.10668)
		(layer "F.Cu")
		(net "RT_CPU0_P2_ADDR3")
	)
	(via
		(at 430.29505 -398.058132)
		(size 0.762)
		(drill 0.381)
		(layers "F.Cu" "B.Cu")
		(net "RT_CPU0_P2_ADDR3")
	)
	(segment
		(start 428.260256 -397.84401)
		(end 424.719242 -397.84401)
		(width 0.10668)
		(layer "F.Cu")
		(net "RT_CPU0_P2_ADDR2")
	)
	(segment
		(start 423.750486 -395.781784)
		(end 422.981628 -395.012926)
		(width 0.10668)
		(layer "F.Cu")
		(net "RT_CPU0_P2_ADDR2")
	)
	(segment
		(start 424.719242 -397.84401)
		(end 424.40479 -397.529558)
		(width 0.10668)
		(layer "F.Cu")
		(net "RT_CPU0_P2_ADDR2")
	)
	(segment
		(start 429.077628 -400.373596)
		(end 429.4251 -400.721068)
		(width 0.10668)
		(layer "F.Cu")
		(net "RT_CPU0_P2_ADDR2")
	)
	(segment
		(start 424.40479 -397.529558)
		(end 424.40479 -396.961614)
		(width 0.10668)
		(layer "F.Cu")
		(net "RT_CPU0_P2_ADDR2")
	)
	(segment
		(start 428.634398 -398.218152)
		(end 428.634398 -399.091404)
		(width 0.10668)
		(layer "F.Cu")
		(net "RT_CPU0_P2_ADDR2")
	)
	(segment
		(start 430.29505 -399.72488)
		(end 430.29505 -399.851118)
		(width 0.10668)
		(layer "F.Cu")
		(net "RT_CPU0_P2_ADDR2")
	)
	(segment
		(start 428.837852 -399.582386)
		(end 429.077628 -399.822162)
		(width 0.10668)
		(layer "F.Cu")
		(net "RT_CPU0_P2_ADDR2")
	)
	(segment
		(start 428.634398 -398.218152)
		(end 428.260256 -397.84401)
		(width 0.10668)
		(layer "F.Cu")
		(net "RT_CPU0_P2_ADDR2")
	)
	(segment
		(start 430.29505 -399.851118)
		(end 429.4251 -400.721068)
		(width 0.10668)
		(layer "F.Cu")
		(net "RT_CPU0_P2_ADDR2")
	)
	(segment
		(start 423.750486 -396.30731)
		(end 423.750486 -395.781784)
		(width 0.10668)
		(layer "F.Cu")
		(net "RT_CPU0_P2_ADDR2")
	)
	(segment
		(start 424.40479 -396.961614)
		(end 423.750486 -396.30731)
		(width 0.10668)
		(layer "F.Cu")
		(net "RT_CPU0_P2_ADDR2")
	)
	(segment
		(start 428.634398 -399.091404)
		(end 428.837852 -399.582386)
		(width 0.10668)
		(layer "F.Cu")
		(net "RT_CPU0_P2_ADDR2")
	)
	(segment
		(start 429.077628 -399.822162)
		(end 429.077628 -400.373596)
		(width 0.10668)
		(layer "F.Cu")
		(net "RT_CPU0_P2_ADDR2")
	)
	(via
		(at 428.634398 -398.218152)
		(size 0.762)
		(drill 0.381)
		(layers "F.Cu" "B.Cu")
		(net "RT_CPU0_P2_ADDR2")
	)
	(segment
		(start 426.712888 -391.49909)
		(end 426.712888 -390.68629)
		(width 0.10668)
		(layer "F.Cu")
		(net "RT_CPU0_P2_ADDR1")
	)
	(segment
		(start 422.728644 -392.665966)
		(end 422.57599 -392.513312)
		(width 0.10668)
		(layer "F.Cu")
		(net "RT_CPU0_P2_ADDR1")
	)
	(segment
		(start 426.549312 -391.662666)
		(end 426.712888 -391.49909)
		(width 0.10668)
		(layer "F.Cu")
		(net "RT_CPU0_P2_ADDR1")
	)
	(segment
		(start 425.912026 -391.662666)
		(end 425.68368 -391.891012)
		(width 0.10668)
		(layer "F.Cu")
		(net "RT_CPU0_P2_ADDR1")
	)
	(segment
		(start 425.68368 -391.891012)
		(end 423.787316 -391.891012)
		(width 0.10668)
		(layer "F.Cu")
		(net "RT_CPU0_P2_ADDR1")
	)
	(segment
		(start 423.012362 -392.665966)
		(end 422.728644 -392.665966)
		(width 0.10668)
		(layer "F.Cu")
		(net "RT_CPU0_P2_ADDR1")
	)
	(segment
		(start 422.454832 -392.513312)
		(end 422.24579 -392.30427)
		(width 0.10668)
		(layer "F.Cu")
		(net "RT_CPU0_P2_ADDR1")
	)
	(segment
		(start 423.787316 -391.891012)
		(end 423.012362 -392.665966)
		(width 0.10668)
		(layer "F.Cu")
		(net "RT_CPU0_P2_ADDR1")
	)
	(segment
		(start 422.57599 -392.513312)
		(end 422.454832 -392.513312)
		(width 0.10668)
		(layer "F.Cu")
		(net "RT_CPU0_P2_ADDR1")
	)
	(segment
		(start 425.912026 -391.662666)
		(end 426.549312 -391.662666)
		(width 0.10668)
		(layer "F.Cu")
		(net "RT_CPU0_P2_ADDR1")
	)
	(via
		(at 425.912026 -391.662666)
		(size 0.762)
		(drill 0.381)
		(layers "F.Cu" "B.Cu")
		(net "RT_CPU0_P2_ADDR1")
	)
	(segment
		(start 355.08057 -403.0091)
		(end 355.08057 -403.7457)
		(width 0.10668)
		(layer "F.Cu")
		(net "RT_CPU0_P1_VQPS")
	)
	(segment
		(start 355.294946 -403.0091)
		(end 355.08057 -403.0091)
		(width 0.10668)
		(layer "F.Cu")
		(net "RT_CPU0_P1_VQPS")
	)
	(segment
		(start 355.54031 -402.763736)
		(end 355.294946 -403.0091)
		(width 0.10668)
		(layer "F.Cu")
		(net "RT_CPU0_P1_VQPS")
	)
	(segment
		(start 354.84562 -400.53133)
		(end 355.54031 -401.22602)
		(width 0.10668)
		(layer "F.Cu")
		(net "RT_CPU0_P1_VQPS")
	)
	(segment
		(start 355.54031 -401.22602)
		(end 355.54031 -402.763736)
		(width 0.10668)
		(layer "F.Cu")
		(net "RT_CPU0_P1_VQPS")
	)
	(segment
		(start 354.84562 -399.663158)
		(end 354.84562 -400.53133)
		(width 0.10668)
		(layer "F.Cu")
		(net "RT_CPU0_P1_VQPS")
	)
	(segment
		(start 355.08057 -403.7457)
		(end 354.25253 -403.7457)
		(width 0.10668)
		(layer "F.Cu")
		(net "RT_CPU0_P1_VQPS")
	)
	(via
		(at 354.25253 -403.7457)
		(size 0.762)
		(drill 0.381)
		(layers "F.Cu" "B.Cu")
		(net "RT_CPU0_P1_VQPS")
	)
	(segment
		(start 333.92872 -392.739372)
		(end 334.455516 -392.739372)
		(width 0.10668)
		(layer "F.Cu")
		(net "RT_CPU0_P1_SCAN_MODE")
	)
	(segment
		(start 334.455516 -392.739372)
		(end 334.629252 -392.913108)
		(width 0.10668)
		(layer "F.Cu")
		(net "RT_CPU0_P1_SCAN_MODE")
	)
	(via
		(at 333.188818 -391.665206)
		(size 0.6604)
		(drill 0.3302)
		(layers "F.Cu" "B.Cu")
		(net "RT_CPU0_P1_SCAN_MODE")
	)
	(via
		(at 333.92872 -392.739372)
		(size 0.4064)
		(drill 0.2032)
		(layers "F.Cu" "B.Cu")
		(net "RT_CPU0_P1_SCAN_MODE")
	)
	(segment
		(start 331.526642 -391.833608)
		(end 331.526642 -392.1252)
		(width 0.10668)
		(layer "B.Cu")
		(net "RT_CPU0_P1_SCAN_MODE")
	)
	(segment
		(start 333.92872 -392.405108)
		(end 333.188818 -391.665206)
		(width 0.10668)
		(layer "B.Cu")
		(net "RT_CPU0_P1_SCAN_MODE")
	)
	(segment
		(start 333.188818 -391.665206)
		(end 333.188564 -391.66546)
		(width 0.10668)
		(layer "B.Cu")
		(net "RT_CPU0_P1_SCAN_MODE")
	)
	(segment
		(start 331.69479 -391.66546)
		(end 331.526642 -391.833608)
		(width 0.10668)
		(layer "B.Cu")
		(net "RT_CPU0_P1_SCAN_MODE")
	)
	(segment
		(start 333.188564 -391.66546)
		(end 331.69479 -391.66546)
		(width 0.10668)
		(layer "B.Cu")
		(net "RT_CPU0_P1_SCAN_MODE")
	)
	(segment
		(start 330.790042 -392.1252)
		(end 331.526642 -392.1252)
		(width 0.10668)
		(layer "B.Cu")
		(net "RT_CPU0_P1_SCAN_MODE")
	)
	(segment
		(start 333.92872 -392.739372)
		(end 333.92872 -392.405108)
		(width 0.10668)
		(layer "B.Cu")
		(net "RT_CPU0_P1_SCAN_MODE")
	)
	(segment
		(start 360.40949 -394.9065)
		(end 360.276394 -394.90523)
		(width 0.10668)
		(layer "F.Cu")
		(net "RT_CPU0_P1_ADDR3")
	)
	(segment
		(start 358.810306 -396.228062)
		(end 358.463342 -395.881098)
		(width 0.10668)
		(layer "F.Cu")
		(net "RT_CPU0_P1_ADDR3")
	)
	(segment
		(start 358.463342 -395.881098)
		(end 357.065834 -395.881098)
		(width 0.10668)
		(layer "F.Cu")
		(net "RT_CPU0_P1_ADDR3")
	)
	(segment
		(start 360.40949 -394.1699)
		(end 360.40949 -394.9065)
		(width 0.10668)
		(layer "F.Cu")
		(net "RT_CPU0_P1_ADDR3")
	)
	(segment
		(start 360.034078 -395.481048)
		(end 359.891838 -395.623288)
		(width 0.10668)
		(layer "F.Cu")
		(net "RT_CPU0_P1_ADDR3")
	)
	(segment
		(start 359.891838 -395.623288)
		(end 359.330244 -395.855952)
		(width 0.10668)
		(layer "F.Cu")
		(net "RT_CPU0_P1_ADDR3")
	)
	(segment
		(start 359.182416 -395.855952)
		(end 358.810306 -396.228062)
		(width 0.10668)
		(layer "F.Cu")
		(net "RT_CPU0_P1_ADDR3")
	)
	(segment
		(start 356.252526 -394.784072)
		(end 355.881432 -394.412978)
		(width 0.10668)
		(layer "F.Cu")
		(net "RT_CPU0_P1_ADDR3")
	)
	(segment
		(start 360.276394 -394.90523)
		(end 360.034078 -395.144752)
		(width 0.10668)
		(layer "F.Cu")
		(net "RT_CPU0_P1_ADDR3")
	)
	(segment
		(start 357.065834 -395.881098)
		(end 356.252526 -395.06779)
		(width 0.10668)
		(layer "F.Cu")
		(net "RT_CPU0_P1_ADDR3")
	)
	(segment
		(start 356.252526 -395.06779)
		(end 356.252526 -394.784072)
		(width 0.10668)
		(layer "F.Cu")
		(net "RT_CPU0_P1_ADDR3")
	)
	(segment
		(start 359.330244 -395.855952)
		(end 359.182416 -395.855952)
		(width 0.10668)
		(layer "F.Cu")
		(net "RT_CPU0_P1_ADDR3")
	)
	(segment
		(start 360.034078 -395.144752)
		(end 360.034078 -395.481048)
		(width 0.10668)
		(layer "F.Cu")
		(net "RT_CPU0_P1_ADDR3")
	)
	(via
		(at 358.810306 -396.228062)
		(size 0.762)
		(drill 0.381)
		(layers "F.Cu" "B.Cu")
		(net "RT_CPU0_P1_ADDR3")
	)
	(segment
		(start 358.6734 -396.814802)
		(end 359.493566 -396.814802)
		(width 0.10668)
		(layer "F.Cu")
		(net "RT_CPU0_P1_ADDR2")
	)
	(segment
		(start 361.22229 -394.1699)
		(end 361.22229 -394.9065)
		(width 0.10668)
		(layer "F.Cu")
		(net "RT_CPU0_P1_ADDR2")
	)
	(segment
		(start 361.604052 -395.202918)
		(end 361.307634 -394.9065)
		(width 0.10668)
		(layer "F.Cu")
		(net "RT_CPU0_P1_ADDR2")
	)
	(segment
		(start 361.604052 -395.696186)
		(end 361.604052 -395.202918)
		(width 0.10668)
		(layer "F.Cu")
		(net "RT_CPU0_P1_ADDR2")
	)
	(segment
		(start 361.307634 -394.9065)
		(end 361.22229 -394.9065)
		(width 0.10668)
		(layer "F.Cu")
		(net "RT_CPU0_P1_ADDR2")
	)
	(segment
		(start 357.042974 -396.174468)
		(end 357.923846 -396.174468)
		(width 0.10668)
		(layer "F.Cu")
		(net "RT_CPU0_P1_ADDR2")
	)
	(segment
		(start 360.536998 -396.684754)
		(end 361.031028 -396.684754)
		(width 0.10668)
		(layer "F.Cu")
		(net "RT_CPU0_P1_ADDR2")
	)
	(segment
		(start 357.923846 -396.174468)
		(end 358.486964 -396.737586)
		(width 0.10668)
		(layer "F.Cu")
		(net "RT_CPU0_P1_ADDR2")
	)
	(segment
		(start 359.493566 -396.814802)
		(end 360.080306 -396.228062)
		(width 0.10668)
		(layer "F.Cu")
		(net "RT_CPU0_P1_ADDR2")
	)
	(segment
		(start 358.486964 -396.737586)
		(end 358.6734 -396.814802)
		(width 0.10668)
		(layer "F.Cu")
		(net "RT_CPU0_P1_ADDR2")
	)
	(segment
		(start 355.881432 -395.012926)
		(end 357.042974 -396.174468)
		(width 0.10668)
		(layer "F.Cu")
		(net "RT_CPU0_P1_ADDR2")
	)
	(segment
		(start 361.310428 -396.405354)
		(end 361.604052 -395.696186)
		(width 0.10668)
		(layer "F.Cu")
		(net "RT_CPU0_P1_ADDR2")
	)
	(segment
		(start 360.080306 -396.228062)
		(end 360.536998 -396.684754)
		(width 0.10668)
		(layer "F.Cu")
		(net "RT_CPU0_P1_ADDR2")
	)
	(segment
		(start 361.031028 -396.684754)
		(end 361.310428 -396.405354)
		(width 0.10668)
		(layer "F.Cu")
		(net "RT_CPU0_P1_ADDR2")
	)
	(via
		(at 360.080306 -396.228062)
		(size 0.762)
		(drill 0.381)
		(layers "F.Cu" "B.Cu")
		(net "RT_CPU0_P1_ADDR2")
	)
	(segment
		(start 355.476048 -392.513312)
		(end 355.354636 -392.513312)
		(width 0.10668)
		(layer "F.Cu")
		(net "RT_CPU0_P1_ADDR1")
	)
	(segment
		(start 359.22839 -391.0584)
		(end 359.22839 -390.957308)
		(width 0.10668)
		(layer "F.Cu")
		(net "RT_CPU0_P1_ADDR1")
	)
	(segment
		(start 355.628702 -392.665966)
		(end 355.476048 -392.513312)
		(width 0.10668)
		(layer "F.Cu")
		(net "RT_CPU0_P1_ADDR1")
	)
	(segment
		(start 356.655878 -391.922508)
		(end 355.91242 -392.665966)
		(width 0.10668)
		(layer "F.Cu")
		(net "RT_CPU0_P1_ADDR1")
	)
	(segment
		(start 359.533698 -390.652)
		(end 360.54919 -390.652)
		(width 0.10668)
		(layer "F.Cu")
		(net "RT_CPU0_P1_ADDR1")
	)
	(segment
		(start 358.74452 -391.0584)
		(end 357.880412 -391.922508)
		(width 0.10668)
		(layer "F.Cu")
		(net "RT_CPU0_P1_ADDR1")
	)
	(segment
		(start 360.54919 -390.652)
		(end 360.54919 -390.819386)
		(width 0.10668)
		(layer "F.Cu")
		(net "RT_CPU0_P1_ADDR1")
	)
	(segment
		(start 359.22839 -390.957308)
		(end 359.533698 -390.652)
		(width 0.10668)
		(layer "F.Cu")
		(net "RT_CPU0_P1_ADDR1")
	)
	(segment
		(start 360.54919 -390.819386)
		(end 361.392978 -391.663174)
		(width 0.10668)
		(layer "F.Cu")
		(net "RT_CPU0_P1_ADDR1")
	)
	(segment
		(start 355.91242 -392.665966)
		(end 355.628702 -392.665966)
		(width 0.10668)
		(layer "F.Cu")
		(net "RT_CPU0_P1_ADDR1")
	)
	(segment
		(start 355.354636 -392.513312)
		(end 355.145594 -392.30427)
		(width 0.10668)
		(layer "F.Cu")
		(net "RT_CPU0_P1_ADDR1")
	)
	(segment
		(start 359.22839 -391.0584)
		(end 358.74452 -391.0584)
		(width 0.10668)
		(layer "F.Cu")
		(net "RT_CPU0_P1_ADDR1")
	)
	(segment
		(start 357.880412 -391.922508)
		(end 356.655878 -391.922508)
		(width 0.10668)
		(layer "F.Cu")
		(net "RT_CPU0_P1_ADDR1")
	)
	(via
		(at 361.392978 -391.663174)
		(size 0.762)
		(drill 0.381)
		(layers "F.Cu" "B.Cu")
		(net "RT_CPU0_P1_ADDR1")
	)
	(segment
		(start 323.012562 -403.15134)
		(end 323.012562 -401.22602)
		(width 0.10668)
		(layer "F.Cu")
		(net "RT_CPU0_P0_VQPS")
	)
	(segment
		(start 322.682362 -403.48154)
		(end 323.012562 -403.15134)
		(width 0.10668)
		(layer "F.Cu")
		(net "RT_CPU0_P0_VQPS")
	)
	(segment
		(start 322.317872 -400.53133)
		(end 322.317872 -399.663158)
		(width 0.10668)
		(layer "F.Cu")
		(net "RT_CPU0_P0_VQPS")
	)
	(segment
		(start 322.364862 -403.48154)
		(end 322.682362 -403.48154)
		(width 0.10668)
		(layer "F.Cu")
		(net "RT_CPU0_P0_VQPS")
	)
	(segment
		(start 321.508882 -403.94636)
		(end 321.900042 -403.94636)
		(width 0.10668)
		(layer "F.Cu")
		(net "RT_CPU0_P0_VQPS")
	)
	(segment
		(start 321.900042 -403.94636)
		(end 322.364862 -403.48154)
		(width 0.10668)
		(layer "F.Cu")
		(net "RT_CPU0_P0_VQPS")
	)
	(segment
		(start 323.012562 -401.22602)
		(end 322.317872 -400.53133)
		(width 0.10668)
		(layer "F.Cu")
		(net "RT_CPU0_P0_VQPS")
	)
	(segment
		(start 320.612262 -403.4282)
		(end 321.130422 -403.94636)
		(width 0.10668)
		(layer "F.Cu")
		(net "RT_CPU0_P0_VQPS")
	)
	(segment
		(start 321.130422 -403.94636)
		(end 321.508882 -403.94636)
		(width 0.10668)
		(layer "F.Cu")
		(net "RT_CPU0_P0_VQPS")
	)
	(via
		(at 321.508882 -403.94636)
		(size 0.762)
		(drill 0.381)
		(layers "F.Cu" "B.Cu")
		(net "RT_CPU0_P0_VQPS")
	)
	(segment
		(start 301.400972 -392.739372)
		(end 301.927768 -392.739372)
		(width 0.10668)
		(layer "F.Cu")
		(net "RT_CPU0_P0_SCAN_MODE")
	)
	(segment
		(start 301.927768 -392.739372)
		(end 302.101504 -392.913108)
		(width 0.10668)
		(layer "F.Cu")
		(net "RT_CPU0_P0_SCAN_MODE")
	)
	(via
		(at 300.30547 -391.06856)
		(size 0.6604)
		(drill 0.3302)
		(layers "F.Cu" "B.Cu")
		(net "RT_CPU0_P0_SCAN_MODE")
	)
	(via
		(at 301.400972 -392.739372)
		(size 0.4064)
		(drill 0.2032)
		(layers "F.Cu" "B.Cu")
		(net "RT_CPU0_P0_SCAN_MODE")
	)
	(segment
		(start 299.532294 -391.164572)
		(end 298.998894 -391.697972)
		(width 0.10668)
		(layer "B.Cu")
		(net "RT_CPU0_P0_SCAN_MODE")
	)
	(segment
		(start 301.400972 -392.164062)
		(end 300.30547 -391.06856)
		(width 0.10668)
		(layer "B.Cu")
		(net "RT_CPU0_P0_SCAN_MODE")
	)
	(segment
		(start 300.30547 -391.06856)
		(end 299.532294 -391.06856)
		(width 0.10668)
		(layer "B.Cu")
		(net "RT_CPU0_P0_SCAN_MODE")
	)
	(segment
		(start 301.400972 -392.739372)
		(end 301.400972 -392.164062)
		(width 0.10668)
		(layer "B.Cu")
		(net "RT_CPU0_P0_SCAN_MODE")
	)
	(segment
		(start 299.532294 -391.06856)
		(end 299.532294 -391.164572)
		(width 0.10668)
		(layer "B.Cu")
		(net "RT_CPU0_P0_SCAN_MODE")
	)
	(segment
		(start 298.998894 -391.697972)
		(end 298.998894 -391.88136)
		(width 0.10668)
		(layer "B.Cu")
		(net "RT_CPU0_P0_SCAN_MODE")
	)
	(segment
		(start 327.881742 -394.9065)
		(end 327.748646 -394.90523)
		(width 0.10668)
		(layer "F.Cu")
		(net "RT_CPU0_P0_ADDR3")
	)
	(segment
		(start 327.50633 -395.144752)
		(end 327.50633 -395.481048)
		(width 0.10668)
		(layer "F.Cu")
		(net "RT_CPU0_P0_ADDR3")
	)
	(segment
		(start 326.654668 -395.855952)
		(end 326.282558 -396.228062)
		(width 0.10668)
		(layer "F.Cu")
		(net "RT_CPU0_P0_ADDR3")
	)
	(segment
		(start 327.50633 -395.481048)
		(end 327.36409 -395.623288)
		(width 0.10668)
		(layer "F.Cu")
		(net "RT_CPU0_P0_ADDR3")
	)
	(segment
		(start 325.947786 -395.89329)
		(end 324.550278 -395.89329)
		(width 0.10668)
		(layer "F.Cu")
		(net "RT_CPU0_P0_ADDR3")
	)
	(segment
		(start 326.282558 -396.228062)
		(end 325.947786 -395.89329)
		(width 0.10668)
		(layer "F.Cu")
		(net "RT_CPU0_P0_ADDR3")
	)
	(segment
		(start 323.724778 -395.06779)
		(end 323.724778 -394.784072)
		(width 0.10668)
		(layer "F.Cu")
		(net "RT_CPU0_P0_ADDR3")
	)
	(segment
		(start 327.748646 -394.90523)
		(end 327.50633 -395.144752)
		(width 0.10668)
		(layer "F.Cu")
		(net "RT_CPU0_P0_ADDR3")
	)
	(segment
		(start 327.36409 -395.623288)
		(end 326.802496 -395.855952)
		(width 0.10668)
		(layer "F.Cu")
		(net "RT_CPU0_P0_ADDR3")
	)
	(segment
		(start 324.550278 -395.89329)
		(end 323.724778 -395.06779)
		(width 0.10668)
		(layer "F.Cu")
		(net "RT_CPU0_P0_ADDR3")
	)
	(segment
		(start 323.724778 -394.784072)
		(end 323.353684 -394.412978)
		(width 0.10668)
		(layer "F.Cu")
		(net "RT_CPU0_P0_ADDR3")
	)
	(segment
		(start 327.881742 -394.1699)
		(end 327.881742 -394.9065)
		(width 0.10668)
		(layer "F.Cu")
		(net "RT_CPU0_P0_ADDR3")
	)
	(segment
		(start 326.802496 -395.855952)
		(end 326.654668 -395.855952)
		(width 0.10668)
		(layer "F.Cu")
		(net "RT_CPU0_P0_ADDR3")
	)
	(via
		(at 326.282558 -396.228062)
		(size 0.762)
		(drill 0.381)
		(layers "F.Cu" "B.Cu")
		(net "RT_CPU0_P0_ADDR3")
	)
	(segment
		(start 325.311262 -396.14348)
		(end 325.879968 -396.712186)
		(width 0.10668)
		(layer "F.Cu")
		(net "RT_CPU0_P0_ADDR2")
	)
	(segment
		(start 328.50328 -396.684754)
		(end 329.076304 -396.11173)
		(width 0.10668)
		(layer "F.Cu")
		(net "RT_CPU0_P0_ADDR2")
	)
	(segment
		(start 324.484238 -396.14348)
		(end 325.311262 -396.14348)
		(width 0.10668)
		(layer "F.Cu")
		(net "RT_CPU0_P0_ADDR2")
	)
	(segment
		(start 329.076304 -395.202918)
		(end 328.779886 -394.9065)
		(width 0.10668)
		(layer "F.Cu")
		(net "RT_CPU0_P0_ADDR2")
	)
	(segment
		(start 328.779886 -394.9065)
		(end 328.694542 -394.9065)
		(width 0.10668)
		(layer "F.Cu")
		(net "RT_CPU0_P0_ADDR2")
	)
	(segment
		(start 323.353684 -395.012926)
		(end 324.484238 -396.14348)
		(width 0.10668)
		(layer "F.Cu")
		(net "RT_CPU0_P0_ADDR2")
	)
	(segment
		(start 327.552558 -396.228062)
		(end 328.00925 -396.684754)
		(width 0.10668)
		(layer "F.Cu")
		(net "RT_CPU0_P0_ADDR2")
	)
	(segment
		(start 326.127618 -396.814802)
		(end 326.965818 -396.814802)
		(width 0.10668)
		(layer "F.Cu")
		(net "RT_CPU0_P0_ADDR2")
	)
	(segment
		(start 326.965818 -396.814802)
		(end 327.552558 -396.228062)
		(width 0.10668)
		(layer "F.Cu")
		(net "RT_CPU0_P0_ADDR2")
	)
	(segment
		(start 328.694542 -394.9065)
		(end 328.694542 -394.1699)
		(width 0.10668)
		(layer "F.Cu")
		(net "RT_CPU0_P0_ADDR2")
	)
	(segment
		(start 325.879968 -396.712186)
		(end 326.127618 -396.814802)
		(width 0.10668)
		(layer "F.Cu")
		(net "RT_CPU0_P0_ADDR2")
	)
	(segment
		(start 328.00925 -396.684754)
		(end 328.50328 -396.684754)
		(width 0.10668)
		(layer "F.Cu")
		(net "RT_CPU0_P0_ADDR2")
	)
	(segment
		(start 329.076304 -396.11173)
		(end 329.076304 -395.202918)
		(width 0.10668)
		(layer "F.Cu")
		(net "RT_CPU0_P0_ADDR2")
	)
	(via
		(at 327.552558 -396.228062)
		(size 0.762)
		(drill 0.381)
		(layers "F.Cu" "B.Cu")
		(net "RT_CPU0_P0_ADDR2")
	)
	(segment
		(start 325.322184 -391.952988)
		(end 326.216772 -391.0584)
		(width 0.10668)
		(layer "F.Cu")
		(net "RT_CPU0_P0_ADDR1")
	)
	(segment
		(start 322.826888 -392.513312)
		(end 322.9483 -392.513312)
		(width 0.10668)
		(layer "F.Cu")
		(net "RT_CPU0_P0_ADDR1")
	)
	(segment
		(start 328.021442 -390.819386)
		(end 328.86523 -391.663174)
		(width 0.10668)
		(layer "F.Cu")
		(net "RT_CPU0_P0_ADDR1")
	)
	(segment
		(start 328.021442 -390.652)
		(end 328.021442 -390.819386)
		(width 0.10668)
		(layer "F.Cu")
		(net "RT_CPU0_P0_ADDR1")
	)
	(segment
		(start 323.384672 -392.665966)
		(end 324.09765 -391.952988)
		(width 0.10668)
		(layer "F.Cu")
		(net "RT_CPU0_P0_ADDR1")
	)
	(segment
		(start 326.700642 -390.957308)
		(end 327.00595 -390.652)
		(width 0.10668)
		(layer "F.Cu")
		(net "RT_CPU0_P0_ADDR1")
	)
	(segment
		(start 326.700642 -391.0584)
		(end 326.700642 -390.957308)
		(width 0.10668)
		(layer "F.Cu")
		(net "RT_CPU0_P0_ADDR1")
	)
	(segment
		(start 327.00595 -390.652)
		(end 328.021442 -390.652)
		(width 0.10668)
		(layer "F.Cu")
		(net "RT_CPU0_P0_ADDR1")
	)
	(segment
		(start 326.216772 -391.0584)
		(end 326.700642 -391.0584)
		(width 0.10668)
		(layer "F.Cu")
		(net "RT_CPU0_P0_ADDR1")
	)
	(segment
		(start 323.100954 -392.665966)
		(end 323.384672 -392.665966)
		(width 0.10668)
		(layer "F.Cu")
		(net "RT_CPU0_P0_ADDR1")
	)
	(segment
		(start 322.617846 -392.30427)
		(end 322.826888 -392.513312)
		(width 0.10668)
		(layer "F.Cu")
		(net "RT_CPU0_P0_ADDR1")
	)
	(segment
		(start 324.09765 -391.952988)
		(end 325.322184 -391.952988)
		(width 0.10668)
		(layer "F.Cu")
		(net "RT_CPU0_P0_ADDR1")
	)
	(segment
		(start 322.9483 -392.513312)
		(end 323.100954 -392.665966)
		(width 0.10668)
		(layer "F.Cu")
		(net "RT_CPU0_P0_ADDR1")
	)
	(via
		(at 328.86523 -391.663174)
		(size 0.762)
		(drill 0.381)
		(layers "F.Cu" "B.Cu")
		(net "RT_CPU0_P0_ADDR1")
	)
	(segment
		(start 367.54054 -402.815552)
		(end 367.339372 -402.614384)
		(width 0.10668)
		(layer "F.Cu")
		(net "RST_RT_CPU0_P3_RESET_R_N")
	)
	(segment
		(start 217.447876 -122.955304)
		(end 217.447876 -125.62459)
		(width 0.10668)
		(layer "F.Cu")
		(net "RST_RT_CPU0_P3_RESET_R_N")
	)
	(segment
		(start 217.144092 -122.65152)
		(end 217.447876 -122.955304)
		(width 0.10668)
		(layer "F.Cu")
		(net "RST_RT_CPU0_P3_RESET_R_N")
	)
	(segment
		(start 216.95283 -120.298464)
		(end 217.144092 -120.489726)
		(width 0.10668)
		(layer "F.Cu")
		(net "RST_RT_CPU0_P3_RESET_R_N")
	)
	(segment
		(start 366.822736 -403.552152)
		(end 367.787936 -403.552152)
		(width 0.10668)
		(layer "F.Cu")
		(net "RST_RT_CPU0_P3_RESET_R_N")
	)
	(segment
		(start 367.787936 -402.815552)
		(end 367.54054 -402.815552)
		(width 0.10668)
		(layer "F.Cu")
		(net "RST_RT_CPU0_P3_RESET_R_N")
	)
	(segment
		(start 367.339372 -402.614384)
		(end 367.339372 -400.839178)
		(width 0.10668)
		(layer "F.Cu")
		(net "RST_RT_CPU0_P3_RESET_R_N")
	)
	(segment
		(start 367.339372 -400.839178)
		(end 367.544604 -400.633946)
		(width 0.10668)
		(layer "F.Cu")
		(net "RST_RT_CPU0_P3_RESET_R_N")
	)
	(segment
		(start 215.89619 -120.298464)
		(end 216.95283 -120.298464)
		(width 0.10668)
		(layer "F.Cu")
		(net "RST_RT_CPU0_P3_RESET_R_N")
	)
	(segment
		(start 217.144092 -120.489726)
		(end 217.144092 -122.65152)
		(width 0.10668)
		(layer "F.Cu")
		(net "RST_RT_CPU0_P3_RESET_R_N")
	)
	(segment
		(start 367.787936 -403.552152)
		(end 367.787936 -402.815552)
		(width 0.10668)
		(layer "F.Cu")
		(net "RST_RT_CPU0_P3_RESET_R_N")
	)
	(segment
		(start 215.312244 -120.88241)
		(end 215.89619 -120.298464)
		(width 0.10668)
		(layer "F.Cu")
		(net "RST_RT_CPU0_P3_RESET_R_N")
	)
	(via
		(at 374.382538 -125.010926)
		(size 0.508)
		(drill 0.254)
		(layers "F.Cu" "B.Cu")
		(net "RST_RT_CPU0_P3_RESET_R_N")
	)
	(via
		(at 365.7219 -391.53338)
		(size 0.508)
		(drill 0.254)
		(layers "F.Cu" "B.Cu")
		(net "RST_RT_CPU0_P3_RESET_R_N")
	)
	(via
		(at 215.312244 -120.88241)
		(size 0.508)
		(drill 0.254)
		(layers "F.Cu" "B.Cu")
		(net "RST_RT_CPU0_P3_RESET_R_N")
	)
	(via
		(at 367.544604 -400.633946)
		(size 0.508)
		(drill 0.254)
		(layers "F.Cu" "B.Cu")
		(net "RST_RT_CPU0_P3_RESET_R_N")
	)
	(via
		(at 392.069828 -387.238748)
		(size 0.508)
		(drill 0.254)
		(layers "F.Cu" "B.Cu")
		(net "RST_RT_CPU0_P3_RESET_R_N")
	)
	(segment
		(start 423.835576 -376.215148)
		(end 428.33544 -371.715284)
		(width 0.11684)
		(layer "In2.Cu")
		(net "RST_RT_CPU0_P3_RESET_R_N")
	)
	(segment
		(start 462.118456 -176.043336)
		(end 450.626226 -164.551106)
		(width 0.11684)
		(layer "In2.Cu")
		(net "RST_RT_CPU0_P3_RESET_R_N")
	)
	(segment
		(start 397.381984 -125.563376)
		(end 374.934988 -125.563376)
		(width 0.11684)
		(layer "In2.Cu")
		(net "RST_RT_CPU0_P3_RESET_R_N")
	)
	(segment
		(start 449.641722 -362.09097)
		(end 449.641722 -335.086706)
		(width 0.11684)
		(layer "In2.Cu")
		(net "RST_RT_CPU0_P3_RESET_R_N")
	)
	(segment
		(start 445.673734 -366.058958)
		(end 449.641722 -362.09097)
		(width 0.11684)
		(layer "In2.Cu")
		(net "RST_RT_CPU0_P3_RESET_R_N")
	)
	(segment
		(start 437.7182 -366.058958)
		(end 445.673734 -366.058958)
		(width 0.11684)
		(layer "In2.Cu")
		(net "RST_RT_CPU0_P3_RESET_R_N")
	)
	(segment
		(start 374.934988 -125.563376)
		(end 374.382538 -125.010926)
		(width 0.11684)
		(layer "In2.Cu")
		(net "RST_RT_CPU0_P3_RESET_R_N")
	)
	(segment
		(start 426.43679 -123.478036)
		(end 400.796252 -123.478036)
		(width 0.11684)
		(layer "In2.Cu")
		(net "RST_RT_CPU0_P3_RESET_R_N")
	)
	(segment
		(start 393.554712 -386.633466)
		(end 394.968222 -386.633466)
		(width 0.11684)
		(layer "In2.Cu")
		(net "RST_RT_CPU0_P3_RESET_R_N")
	)
	(segment
		(start 428.33544 -371.715284)
		(end 432.061874 -371.715284)
		(width 0.11684)
		(layer "In2.Cu")
		(net "RST_RT_CPU0_P3_RESET_R_N")
	)
	(segment
		(start 450.626226 -164.551106)
		(end 450.626226 -147.667472)
		(width 0.11684)
		(layer "In2.Cu")
		(net "RST_RT_CPU0_P3_RESET_R_N")
	)
	(segment
		(start 366.4331 -397.36268)
		(end 367.544604 -398.474184)
		(width 0.11684)
		(layer "In2.Cu")
		(net "RST_RT_CPU0_P3_RESET_R_N")
	)
	(segment
		(start 462.118456 -322.609972)
		(end 462.118456 -176.043336)
		(width 0.11684)
		(layer "In2.Cu")
		(net "RST_RT_CPU0_P3_RESET_R_N")
	)
	(segment
		(start 397.992346 -124.953014)
		(end 397.381984 -125.563376)
		(width 0.11684)
		(layer "In2.Cu")
		(net "RST_RT_CPU0_P3_RESET_R_N")
	)
	(segment
		(start 396.925038 -381.627126)
		(end 396.925038 -377.66752)
		(width 0.11684)
		(layer "In2.Cu")
		(net "RST_RT_CPU0_P3_RESET_R_N")
	)
	(segment
		(start 394.968222 -386.633466)
		(end 395.79423 -385.807458)
		(width 0.11684)
		(layer "In2.Cu")
		(net "RST_RT_CPU0_P3_RESET_R_N")
	)
	(segment
		(start 398.37741 -376.215148)
		(end 423.835576 -376.215148)
		(width 0.11684)
		(layer "In2.Cu")
		(net "RST_RT_CPU0_P3_RESET_R_N")
	)
	(segment
		(start 432.061874 -371.715284)
		(end 437.7182 -366.058958)
		(width 0.11684)
		(layer "In2.Cu")
		(net "RST_RT_CPU0_P3_RESET_R_N")
	)
	(segment
		(start 395.79423 -382.757934)
		(end 396.925038 -381.627126)
		(width 0.11684)
		(layer "In2.Cu")
		(net "RST_RT_CPU0_P3_RESET_R_N")
	)
	(segment
		(start 400.796252 -123.478036)
		(end 399.321274 -124.953014)
		(width 0.11684)
		(layer "In2.Cu")
		(net "RST_RT_CPU0_P3_RESET_R_N")
	)
	(segment
		(start 392.069828 -387.238748)
		(end 392.94943 -387.238748)
		(width 0.11684)
		(layer "In2.Cu")
		(net "RST_RT_CPU0_P3_RESET_R_N")
	)
	(segment
		(start 449.641722 -335.086706)
		(end 462.118456 -322.609972)
		(width 0.11684)
		(layer "In2.Cu")
		(net "RST_RT_CPU0_P3_RESET_R_N")
	)
	(segment
		(start 367.544604 -398.474184)
		(end 367.544604 -400.633946)
		(width 0.11684)
		(layer "In2.Cu")
		(net "RST_RT_CPU0_P3_RESET_R_N")
	)
	(segment
		(start 450.626226 -147.667472)
		(end 426.43679 -123.478036)
		(width 0.11684)
		(layer "In2.Cu")
		(net "RST_RT_CPU0_P3_RESET_R_N")
	)
	(segment
		(start 399.321274 -124.953014)
		(end 397.992346 -124.953014)
		(width 0.11684)
		(layer "In2.Cu")
		(net "RST_RT_CPU0_P3_RESET_R_N")
	)
	(segment
		(start 396.925038 -377.66752)
		(end 398.37741 -376.215148)
		(width 0.11684)
		(layer "In2.Cu")
		(net "RST_RT_CPU0_P3_RESET_R_N")
	)
	(segment
		(start 365.7219 -391.53338)
		(end 366.4331 -392.24458)
		(width 0.11684)
		(layer "In2.Cu")
		(net "RST_RT_CPU0_P3_RESET_R_N")
	)
	(segment
		(start 392.94943 -387.238748)
		(end 393.554712 -386.633466)
		(width 0.11684)
		(layer "In2.Cu")
		(net "RST_RT_CPU0_P3_RESET_R_N")
	)
	(segment
		(start 366.4331 -392.24458)
		(end 366.4331 -397.36268)
		(width 0.11684)
		(layer "In2.Cu")
		(net "RST_RT_CPU0_P3_RESET_R_N")
	)
	(segment
		(start 395.79423 -385.807458)
		(end 395.79423 -382.757934)
		(width 0.11684)
		(layer "In2.Cu")
		(net "RST_RT_CPU0_P3_RESET_R_N")
	)
	(segment
		(start 365.7219 -391.53338)
		(end 366.64646 -390.60882)
		(width 0.11684)
		(layer "In13.Cu")
		(net "RST_RT_CPU0_P3_RESET_R_N")
	)
	(segment
		(start 390.64692 -387.24078)
		(end 392.067796 -387.24078)
		(width 0.11684)
		(layer "In13.Cu")
		(net "RST_RT_CPU0_P3_RESET_R_N")
	)
	(segment
		(start 392.067796 -387.24078)
		(end 392.069828 -387.238748)
		(width 0.11684)
		(layer "In13.Cu")
		(net "RST_RT_CPU0_P3_RESET_R_N")
	)
	(segment
		(start 366.64646 -390.60882)
		(end 387.27888 -390.60882)
		(width 0.11684)
		(layer "In13.Cu")
		(net "RST_RT_CPU0_P3_RESET_R_N")
	)
	(segment
		(start 387.27888 -390.60882)
		(end 390.64692 -387.24078)
		(width 0.11684)
		(layer "In13.Cu")
		(net "RST_RT_CPU0_P3_RESET_R_N")
	)
	(segment
		(start 245.769384 -124.236226)
		(end 227.20808 -124.236226)
		(width 0.11684)
		(layer "In15.Cu")
		(net "RST_RT_CPU0_P3_RESET_R_N")
	)
	(segment
		(start 270.237458 -124.0409)
		(end 268.700758 -124.0409)
		(width 0.11684)
		(layer "In15.Cu")
		(net "RST_RT_CPU0_P3_RESET_R_N")
	)
	(segment
		(start 256.920238 -121.19483)
		(end 248.81078 -121.19483)
		(width 0.11684)
		(layer "In15.Cu")
		(net "RST_RT_CPU0_P3_RESET_R_N")
	)
	(segment
		(start 289.31362 -128.721358)
		(end 287.168336 -126.576074)
		(width 0.11684)
		(layer "In15.Cu")
		(net "RST_RT_CPU0_P3_RESET_R_N")
	)
	(segment
		(start 292.905434 -128.721358)
		(end 289.31362 -128.721358)
		(width 0.11684)
		(layer "In15.Cu")
		(net "RST_RT_CPU0_P3_RESET_R_N")
	)
	(segment
		(start 372.717822 -125.010926)
		(end 371.849396 -124.1425)
		(width 0.11684)
		(layer "In15.Cu")
		(net "RST_RT_CPU0_P3_RESET_R_N")
	)
	(segment
		(start 227.20808 -124.236226)
		(end 225.22561 -122.253756)
		(width 0.11684)
		(layer "In15.Cu")
		(net "RST_RT_CPU0_P3_RESET_R_N")
	)
	(segment
		(start 248.81078 -121.19483)
		(end 245.769384 -124.236226)
		(width 0.11684)
		(layer "In15.Cu")
		(net "RST_RT_CPU0_P3_RESET_R_N")
	)
	(segment
		(start 297.484292 -124.1425)
		(end 292.905434 -128.721358)
		(width 0.11684)
		(layer "In15.Cu")
		(net "RST_RT_CPU0_P3_RESET_R_N")
	)
	(segment
		(start 273.747992 -126.576074)
		(end 272.315686 -125.143768)
		(width 0.11684)
		(layer "In15.Cu")
		(net "RST_RT_CPU0_P3_RESET_R_N")
	)
	(segment
		(start 371.849396 -124.1425)
		(end 297.484292 -124.1425)
		(width 0.11684)
		(layer "In15.Cu")
		(net "RST_RT_CPU0_P3_RESET_R_N")
	)
	(segment
		(start 374.382538 -125.010926)
		(end 372.717822 -125.010926)
		(width 0.11684)
		(layer "In15.Cu")
		(net "RST_RT_CPU0_P3_RESET_R_N")
	)
	(segment
		(start 271.340326 -125.143768)
		(end 270.237458 -124.0409)
		(width 0.11684)
		(layer "In15.Cu")
		(net "RST_RT_CPU0_P3_RESET_R_N")
	)
	(segment
		(start 217.542618 -122.253756)
		(end 216.171272 -120.88241)
		(width 0.11684)
		(layer "In15.Cu")
		(net "RST_RT_CPU0_P3_RESET_R_N")
	)
	(segment
		(start 259.780532 -124.055124)
		(end 256.920238 -121.19483)
		(width 0.11684)
		(layer "In15.Cu")
		(net "RST_RT_CPU0_P3_RESET_R_N")
	)
	(segment
		(start 268.700758 -124.0409)
		(end 268.686534 -124.055124)
		(width 0.11684)
		(layer "In15.Cu")
		(net "RST_RT_CPU0_P3_RESET_R_N")
	)
	(segment
		(start 287.168336 -126.576074)
		(end 273.747992 -126.576074)
		(width 0.11684)
		(layer "In15.Cu")
		(net "RST_RT_CPU0_P3_RESET_R_N")
	)
	(segment
		(start 225.22561 -122.253756)
		(end 217.542618 -122.253756)
		(width 0.11684)
		(layer "In15.Cu")
		(net "RST_RT_CPU0_P3_RESET_R_N")
	)
	(segment
		(start 272.315686 -125.143768)
		(end 271.340326 -125.143768)
		(width 0.11684)
		(layer "In15.Cu")
		(net "RST_RT_CPU0_P3_RESET_R_N")
	)
	(segment
		(start 216.171272 -120.88241)
		(end 215.312244 -120.88241)
		(width 0.11684)
		(layer "In15.Cu")
		(net "RST_RT_CPU0_P3_RESET_R_N")
	)
	(segment
		(start 268.686534 -124.055124)
		(end 259.780532 -124.055124)
		(width 0.11684)
		(layer "In15.Cu")
		(net "RST_RT_CPU0_P3_RESET_R_N")
	)
	(segment
		(start 189.12205 -119.452898)
		(end 189.51194 -119.842788)
		(width 0.10668)
		(layer "F.Cu")
		(net "RST_RT_CPU0_P3_RESET_R2_N")
	)
	(segment
		(start 216.647776 -125.62459)
		(end 215.842088 -125.62459)
		(width 0.10668)
		(layer "F.Cu")
		(net "RST_RT_CPU0_P3_RESET_R2_N")
	)
	(via
		(at 215.842088 -125.62459)
		(size 0.508)
		(drill 0.254)
		(layers "F.Cu" "B.Cu")
		(net "RST_RT_CPU0_P3_RESET_R2_N")
	)
	(via
		(at 189.51194 -119.842788)
		(size 0.4572)
		(drill 0.254)
		(layers "F.Cu" "B.Cu")
		(net "RST_RT_CPU0_P3_RESET_R2_N")
	)
	(segment
		(start 193.491866 -123.918218)
		(end 191.633094 -123.918218)
		(width 0.11684)
		(layer "In15.Cu")
		(net "RST_RT_CPU0_P3_RESET_R2_N")
	)
	(segment
		(start 195.873624 -126.299976)
		(end 193.491866 -123.918218)
		(width 0.11684)
		(layer "In15.Cu")
		(net "RST_RT_CPU0_P3_RESET_R2_N")
	)
	(segment
		(start 202.836526 -125.574044)
		(end 202.836526 -126.29769)
		(width 0.11684)
		(layer "In15.Cu")
		(net "RST_RT_CPU0_P3_RESET_R2_N")
	)
	(segment
		(start 197.740016 -126.299976)
		(end 195.873624 -126.299976)
		(width 0.11684)
		(layer "In15.Cu")
		(net "RST_RT_CPU0_P3_RESET_R2_N")
	)
	(segment
		(start 215.720168 -125.62459)
		(end 215.01227 -126.332488)
		(width 0.11684)
		(layer "In15.Cu")
		(net "RST_RT_CPU0_P3_RESET_R2_N")
	)
	(segment
		(start 201.018648 -128.115568)
		(end 200.781666 -128.115568)
		(width 0.11684)
		(layer "In15.Cu")
		(net "RST_RT_CPU0_P3_RESET_R2_N")
	)
	(segment
		(start 191.506094 -120.374918)
		(end 191.382142 -120.250966)
		(width 0.11684)
		(layer "In15.Cu")
		(net "RST_RT_CPU0_P3_RESET_R2_N")
	)
	(segment
		(start 207.217518 -125.468888)
		(end 207.02778 -125.27915)
		(width 0.11684)
		(layer "In15.Cu")
		(net "RST_RT_CPU0_P3_RESET_R2_N")
	)
	(segment
		(start 212.60943 -126.332488)
		(end 211.74583 -125.468888)
		(width 0.11684)
		(layer "In15.Cu")
		(net "RST_RT_CPU0_P3_RESET_R2_N")
	)
	(segment
		(start 198.801736 -127.361696)
		(end 197.740016 -126.299976)
		(width 0.11684)
		(layer "In15.Cu")
		(net "RST_RT_CPU0_P3_RESET_R2_N")
	)
	(segment
		(start 191.506094 -123.791218)
		(end 191.506094 -120.374918)
		(width 0.11684)
		(layer "In15.Cu")
		(net "RST_RT_CPU0_P3_RESET_R2_N")
	)
	(segment
		(start 203.13142 -125.27915)
		(end 202.836526 -125.574044)
		(width 0.11684)
		(layer "In15.Cu")
		(net "RST_RT_CPU0_P3_RESET_R2_N")
	)
	(segment
		(start 202.836526 -126.29769)
		(end 201.018648 -128.115568)
		(width 0.11684)
		(layer "In15.Cu")
		(net "RST_RT_CPU0_P3_RESET_R2_N")
	)
	(segment
		(start 207.02778 -125.27915)
		(end 203.13142 -125.27915)
		(width 0.11684)
		(layer "In15.Cu")
		(net "RST_RT_CPU0_P3_RESET_R2_N")
	)
	(segment
		(start 191.382142 -120.250966)
		(end 189.920118 -120.250966)
		(width 0.11684)
		(layer "In15.Cu")
		(net "RST_RT_CPU0_P3_RESET_R2_N")
	)
	(segment
		(start 215.842088 -125.62459)
		(end 215.720168 -125.62459)
		(width 0.11684)
		(layer "In15.Cu")
		(net "RST_RT_CPU0_P3_RESET_R2_N")
	)
	(segment
		(start 191.633094 -123.918218)
		(end 191.506094 -123.791218)
		(width 0.11684)
		(layer "In15.Cu")
		(net "RST_RT_CPU0_P3_RESET_R2_N")
	)
	(segment
		(start 200.781666 -128.115568)
		(end 200.027794 -127.361696)
		(width 0.11684)
		(layer "In15.Cu")
		(net "RST_RT_CPU0_P3_RESET_R2_N")
	)
	(segment
		(start 215.01227 -126.332488)
		(end 212.60943 -126.332488)
		(width 0.11684)
		(layer "In15.Cu")
		(net "RST_RT_CPU0_P3_RESET_R2_N")
	)
	(segment
		(start 200.027794 -127.361696)
		(end 198.801736 -127.361696)
		(width 0.11684)
		(layer "In15.Cu")
		(net "RST_RT_CPU0_P3_RESET_R2_N")
	)
	(segment
		(start 211.74583 -125.468888)
		(end 207.217518 -125.468888)
		(width 0.11684)
		(layer "In15.Cu")
		(net "RST_RT_CPU0_P3_RESET_R2_N")
	)
	(segment
		(start 189.920118 -120.250966)
		(end 189.51194 -119.842788)
		(width 0.11684)
		(layer "In15.Cu")
		(net "RST_RT_CPU0_P3_RESET_R2_N")
	)
	(segment
		(start 369.2017 -397.112998)
		(end 367.890044 -397.112998)
		(width 0.10668)
		(layer "F.Cu")
		(net "RST_RT_CPU0_P3_RESET_N")
	)
	(segment
		(start 366.822736 -402.362416)
		(end 366.822736 -403.018752)
		(width 0.10668)
		(layer "F.Cu")
		(net "RST_RT_CPU0_P3_RESET_N")
	)
	(segment
		(start 366.395508 -404.79599)
		(end 366.395508 -403.166326)
		(width 0.10668)
		(layer "F.Cu")
		(net "RST_RT_CPU0_P3_RESET_N")
	)
	(segment
		(start 366.962944 -402.222208)
		(end 366.822736 -402.362416)
		(width 0.10668)
		(layer "F.Cu")
		(net "RST_RT_CPU0_P3_RESET_N")
	)
	(segment
		(start 366.395508 -403.166326)
		(end 366.543082 -403.018752)
		(width 0.10668)
		(layer "F.Cu")
		(net "RST_RT_CPU0_P3_RESET_N")
	)
	(segment
		(start 369.385596 -406.430734)
		(end 367.071402 -405.471884)
		(width 0.10668)
		(layer "F.Cu")
		(net "RST_RT_CPU0_P3_RESET_N")
	)
	(segment
		(start 367.890044 -397.112998)
		(end 366.962944 -398.040098)
		(width 0.10668)
		(layer "F.Cu")
		(net "RST_RT_CPU0_P3_RESET_N")
	)
	(segment
		(start 367.071402 -405.471884)
		(end 366.395508 -404.79599)
		(width 0.10668)
		(layer "F.Cu")
		(net "RST_RT_CPU0_P3_RESET_N")
	)
	(segment
		(start 366.962944 -398.040098)
		(end 366.962944 -402.222208)
		(width 0.10668)
		(layer "F.Cu")
		(net "RST_RT_CPU0_P3_RESET_N")
	)
	(segment
		(start 366.543082 -403.018752)
		(end 366.822736 -403.018752)
		(width 0.10668)
		(layer "F.Cu")
		(net "RST_RT_CPU0_P3_RESET_N")
	)
	(via
		(at 369.385596 -406.430734)
		(size 0.762)
		(drill 0.381)
		(layers "F.Cu" "B.Cu")
		(net "RST_RT_CPU0_P3_RESET_N")
	)
	(segment
		(start 217.3986 -127.801116)
		(end 218.526614 -127.801116)
		(width 0.10668)
		(layer "F.Cu")
		(net "RST_RT_CPU0_P3_PERST_R_N")
	)
	(segment
		(start 391.268458 -403.7457)
		(end 391.268458 -403.0091)
		(width 0.10668)
		(layer "F.Cu")
		(net "RST_RT_CPU0_P3_PERST_R_N")
	)
	(segment
		(start 391.268458 -403.0091)
		(end 390.974326 -403.0091)
		(width 0.10668)
		(layer "F.Cu")
		(net "RST_RT_CPU0_P3_PERST_R_N")
	)
	(segment
		(start 390.974326 -403.0091)
		(end 390.834118 -402.868892)
		(width 0.10668)
		(layer "F.Cu")
		(net "RST_RT_CPU0_P3_PERST_R_N")
	)
	(segment
		(start 390.834118 -402.868892)
		(end 390.834118 -401.357084)
		(width 0.10668)
		(layer "F.Cu")
		(net "RST_RT_CPU0_P3_PERST_R_N")
	)
	(segment
		(start 390.834118 -401.357084)
		(end 390.993376 -401.197826)
		(width 0.10668)
		(layer "F.Cu")
		(net "RST_RT_CPU0_P3_PERST_R_N")
	)
	(via
		(at 218.526614 -127.801116)
		(size 0.508)
		(drill 0.254)
		(layers "F.Cu" "B.Cu")
		(net "RST_RT_CPU0_P3_PERST_R_N")
	)
	(via
		(at 446.882266 -129.013458)
		(size 0.508)
		(drill 0.254)
		(layers "F.Cu" "B.Cu")
		(net "RST_RT_CPU0_P3_PERST_R_N")
	)
	(via
		(at 425.430442 -402.075142)
		(size 0.508)
		(drill 0.254)
		(layers "F.Cu" "B.Cu")
		(net "RST_RT_CPU0_P3_PERST_R_N")
	)
	(via
		(at 390.993376 -401.197826)
		(size 0.508)
		(drill 0.254)
		(layers "F.Cu" "B.Cu")
		(net "RST_RT_CPU0_P3_PERST_R_N")
	)
	(segment
		(start 399.969482 -403.781768)
		(end 423.723816 -403.781768)
		(width 0.11684)
		(layer "In2.Cu")
		(net "RST_RT_CPU0_P3_PERST_R_N")
	)
	(segment
		(start 399.641822 -403.454108)
		(end 399.969482 -403.781768)
		(width 0.11684)
		(layer "In2.Cu")
		(net "RST_RT_CPU0_P3_PERST_R_N")
	)
	(segment
		(start 390.993376 -401.197826)
		(end 390.993376 -401.449032)
		(width 0.11684)
		(layer "In2.Cu")
		(net "RST_RT_CPU0_P3_PERST_R_N")
	)
	(segment
		(start 391.427716 -402.498306)
		(end 391.427716 -402.865082)
		(width 0.11684)
		(layer "In2.Cu")
		(net "RST_RT_CPU0_P3_PERST_R_N")
	)
	(segment
		(start 390.993376 -401.449032)
		(end 391.427716 -402.498306)
		(width 0.11684)
		(layer "In2.Cu")
		(net "RST_RT_CPU0_P3_PERST_R_N")
	)
	(segment
		(start 423.723816 -403.781768)
		(end 425.430442 -402.075142)
		(width 0.11684)
		(layer "In2.Cu")
		(net "RST_RT_CPU0_P3_PERST_R_N")
	)
	(segment
		(start 392.016742 -403.454108)
		(end 399.641822 -403.454108)
		(width 0.11684)
		(layer "In2.Cu")
		(net "RST_RT_CPU0_P3_PERST_R_N")
	)
	(segment
		(start 391.427716 -402.865082)
		(end 392.016742 -403.454108)
		(width 0.11684)
		(layer "In2.Cu")
		(net "RST_RT_CPU0_P3_PERST_R_N")
	)
	(segment
		(start 425.430442 -402.075142)
		(end 427.972982 -402.075142)
		(width 0.11684)
		(layer "In4.Cu")
		(net "RST_RT_CPU0_P3_PERST_R_N")
	)
	(segment
		(start 429.953166 -400.094958)
		(end 429.953166 -399.056098)
		(width 0.11684)
		(layer "In4.Cu")
		(net "RST_RT_CPU0_P3_PERST_R_N")
	)
	(segment
		(start 432.493166 -393.97559)
		(end 439.153808 -387.314948)
		(width 0.11684)
		(layer "In4.Cu")
		(net "RST_RT_CPU0_P3_PERST_R_N")
	)
	(segment
		(start 439.153808 -378.251466)
		(end 442.609478 -374.795796)
		(width 0.11684)
		(layer "In4.Cu")
		(net "RST_RT_CPU0_P3_PERST_R_N")
	)
	(segment
		(start 455.629264 -374.795796)
		(end 455.854054 -374.571006)
		(width 0.11684)
		(layer "In4.Cu")
		(net "RST_RT_CPU0_P3_PERST_R_N")
	)
	(segment
		(start 448.657218 -129.013458)
		(end 446.882266 -129.013458)
		(width 0.11684)
		(layer "In4.Cu")
		(net "RST_RT_CPU0_P3_PERST_R_N")
	)
	(segment
		(start 439.153808 -387.314948)
		(end 439.153808 -378.251466)
		(width 0.11684)
		(layer "In4.Cu")
		(net "RST_RT_CPU0_P3_PERST_R_N")
	)
	(segment
		(start 466.762084 -167.181784)
		(end 465.630514 -166.050214)
		(width 0.11684)
		(layer "In4.Cu")
		(net "RST_RT_CPU0_P3_PERST_R_N")
	)
	(segment
		(start 429.953166 -399.056098)
		(end 432.493166 -396.516098)
		(width 0.11684)
		(layer "In4.Cu")
		(net "RST_RT_CPU0_P3_PERST_R_N")
	)
	(segment
		(start 466.762084 -328.181716)
		(end 466.762084 -167.181784)
		(width 0.11684)
		(layer "In4.Cu")
		(net "RST_RT_CPU0_P3_PERST_R_N")
	)
	(segment
		(start 442.609478 -374.795796)
		(end 455.629264 -374.795796)
		(width 0.11684)
		(layer "In4.Cu")
		(net "RST_RT_CPU0_P3_PERST_R_N")
	)
	(segment
		(start 465.630514 -166.050214)
		(end 458.81671 -166.050214)
		(width 0.11684)
		(layer "In4.Cu")
		(net "RST_RT_CPU0_P3_PERST_R_N")
	)
	(segment
		(start 427.972982 -402.075142)
		(end 429.953166 -400.094958)
		(width 0.11684)
		(layer "In4.Cu")
		(net "RST_RT_CPU0_P3_PERST_R_N")
	)
	(segment
		(start 456.11542 -163.348924)
		(end 456.11542 -136.47166)
		(width 0.11684)
		(layer "In4.Cu")
		(net "RST_RT_CPU0_P3_PERST_R_N")
	)
	(segment
		(start 456.11542 -136.47166)
		(end 448.657218 -129.013458)
		(width 0.11684)
		(layer "In4.Cu")
		(net "RST_RT_CPU0_P3_PERST_R_N")
	)
	(segment
		(start 432.493166 -396.516098)
		(end 432.493166 -393.97559)
		(width 0.11684)
		(layer "In4.Cu")
		(net "RST_RT_CPU0_P3_PERST_R_N")
	)
	(segment
		(start 458.81671 -166.050214)
		(end 456.11542 -163.348924)
		(width 0.11684)
		(layer "In4.Cu")
		(net "RST_RT_CPU0_P3_PERST_R_N")
	)
	(segment
		(start 455.854054 -374.571006)
		(end 455.854054 -339.089746)
		(width 0.11684)
		(layer "In4.Cu")
		(net "RST_RT_CPU0_P3_PERST_R_N")
	)
	(segment
		(start 455.854054 -339.089746)
		(end 466.762084 -328.181716)
		(width 0.11684)
		(layer "In4.Cu")
		(net "RST_RT_CPU0_P3_PERST_R_N")
	)
	(segment
		(start 293.520114 -130.204718)
		(end 298.098972 -125.62586)
		(width 0.11684)
		(layer "In15.Cu")
		(net "RST_RT_CPU0_P3_PERST_R_N")
	)
	(segment
		(start 298.098972 -125.62586)
		(end 371.234716 -125.62586)
		(width 0.11684)
		(layer "In15.Cu")
		(net "RST_RT_CPU0_P3_PERST_R_N")
	)
	(segment
		(start 257.628644 -125.85319)
		(end 257.69316 -125.788674)
		(width 0.11684)
		(layer "In15.Cu")
		(net "RST_RT_CPU0_P3_PERST_R_N")
	)
	(segment
		(start 288.69894 -130.204718)
		(end 293.520114 -130.204718)
		(width 0.11684)
		(layer "In15.Cu")
		(net "RST_RT_CPU0_P3_PERST_R_N")
	)
	(segment
		(start 254.900684 -125.85319)
		(end 257.628644 -125.85319)
		(width 0.11684)
		(layer "In15.Cu")
		(net "RST_RT_CPU0_P3_PERST_R_N")
	)
	(segment
		(start 252.597412 -125.394212)
		(end 254.441706 -125.394212)
		(width 0.11684)
		(layer "In15.Cu")
		(net "RST_RT_CPU0_P3_PERST_R_N")
	)
	(segment
		(start 271.522698 -126.764542)
		(end 272.81759 -128.059434)
		(width 0.11684)
		(layer "In15.Cu")
		(net "RST_RT_CPU0_P3_PERST_R_N")
	)
	(segment
		(start 248.01195 -125.419104)
		(end 250.41352 -125.419104)
		(width 0.11684)
		(layer "In15.Cu")
		(net "RST_RT_CPU0_P3_PERST_R_N")
	)
	(segment
		(start 218.526614 -127.801116)
		(end 219.134436 -127.193294)
		(width 0.11684)
		(layer "In15.Cu")
		(net "RST_RT_CPU0_P3_PERST_R_N")
	)
	(segment
		(start 371.234716 -125.62586)
		(end 374.273826 -128.66497)
		(width 0.11684)
		(layer "In15.Cu")
		(net "RST_RT_CPU0_P3_PERST_R_N")
	)
	(segment
		(start 250.41352 -125.419104)
		(end 251.194316 -126.1999)
		(width 0.11684)
		(layer "In15.Cu")
		(net "RST_RT_CPU0_P3_PERST_R_N")
	)
	(segment
		(start 265.601958 -126.764542)
		(end 271.522698 -126.764542)
		(width 0.11684)
		(layer "In15.Cu")
		(net "RST_RT_CPU0_P3_PERST_R_N")
	)
	(segment
		(start 446.533778 -128.66497)
		(end 446.882266 -129.013458)
		(width 0.11684)
		(layer "In15.Cu")
		(net "RST_RT_CPU0_P3_PERST_R_N")
	)
	(segment
		(start 374.273826 -128.66497)
		(end 446.533778 -128.66497)
		(width 0.11684)
		(layer "In15.Cu")
		(net "RST_RT_CPU0_P3_PERST_R_N")
	)
	(segment
		(start 219.134436 -127.193294)
		(end 246.23776 -127.193294)
		(width 0.11684)
		(layer "In15.Cu")
		(net "RST_RT_CPU0_P3_PERST_R_N")
	)
	(segment
		(start 251.791724 -126.1999)
		(end 252.597412 -125.394212)
		(width 0.11684)
		(layer "In15.Cu")
		(net "RST_RT_CPU0_P3_PERST_R_N")
	)
	(segment
		(start 246.23776 -127.193294)
		(end 248.01195 -125.419104)
		(width 0.11684)
		(layer "In15.Cu")
		(net "RST_RT_CPU0_P3_PERST_R_N")
	)
	(segment
		(start 251.194316 -126.1999)
		(end 251.791724 -126.1999)
		(width 0.11684)
		(layer "In15.Cu")
		(net "RST_RT_CPU0_P3_PERST_R_N")
	)
	(segment
		(start 286.553656 -128.059434)
		(end 288.69894 -130.204718)
		(width 0.11684)
		(layer "In15.Cu")
		(net "RST_RT_CPU0_P3_PERST_R_N")
	)
	(segment
		(start 264.62609 -125.788674)
		(end 265.601958 -126.764542)
		(width 0.11684)
		(layer "In15.Cu")
		(net "RST_RT_CPU0_P3_PERST_R_N")
	)
	(segment
		(start 254.441706 -125.394212)
		(end 254.900684 -125.85319)
		(width 0.11684)
		(layer "In15.Cu")
		(net "RST_RT_CPU0_P3_PERST_R_N")
	)
	(segment
		(start 272.81759 -128.059434)
		(end 286.553656 -128.059434)
		(width 0.11684)
		(layer "In15.Cu")
		(net "RST_RT_CPU0_P3_PERST_R_N")
	)
	(segment
		(start 257.69316 -125.788674)
		(end 264.62609 -125.788674)
		(width 0.11684)
		(layer "In15.Cu")
		(net "RST_RT_CPU0_P3_PERST_R_N")
	)
	(segment
		(start 189.12205 -121.052844)
		(end 189.51194 -121.442734)
		(width 0.10668)
		(layer "F.Cu")
		(net "RST_RT_CPU0_P3_PERST_R2_N")
	)
	(segment
		(start 216.5985 -127.801116)
		(end 216.079324 -127.801116)
		(width 0.10668)
		(layer "F.Cu")
		(net "RST_RT_CPU0_P3_PERST_R2_N")
	)
	(segment
		(start 216.079324 -127.801116)
		(end 216.03843 -127.84201)
		(width 0.10668)
		(layer "F.Cu")
		(net "RST_RT_CPU0_P3_PERST_R2_N")
	)
	(segment
		(start 216.03843 -127.84201)
		(end 215.416638 -127.84201)
		(width 0.10668)
		(layer "F.Cu")
		(net "RST_RT_CPU0_P3_PERST_R2_N")
	)
	(via
		(at 189.51194 -121.442734)
		(size 0.4572)
		(drill 0.254)
		(layers "F.Cu" "B.Cu")
		(net "RST_RT_CPU0_P3_PERST_R2_N")
	)
	(via
		(at 215.416638 -127.84201)
		(size 0.508)
		(drill 0.254)
		(layers "F.Cu" "B.Cu")
		(net "RST_RT_CPU0_P3_PERST_R2_N")
	)
	(segment
		(start 198.425054 -128.262888)
		(end 197.328028 -127.165862)
		(width 0.11684)
		(layer "In15.Cu")
		(net "RST_RT_CPU0_P3_PERST_R2_N")
	)
	(segment
		(start 199.735948 -128.262888)
		(end 198.425054 -128.262888)
		(width 0.11684)
		(layer "In15.Cu")
		(net "RST_RT_CPU0_P3_PERST_R2_N")
	)
	(segment
		(start 201.348848 -128.978406)
		(end 200.451466 -128.978406)
		(width 0.11684)
		(layer "In15.Cu")
		(net "RST_RT_CPU0_P3_PERST_R2_N")
	)
	(segment
		(start 197.328028 -127.165862)
		(end 195.296028 -127.165862)
		(width 0.11684)
		(layer "In15.Cu")
		(net "RST_RT_CPU0_P3_PERST_R2_N")
	)
	(segment
		(start 194.717162 -126.586996)
		(end 191.099186 -126.586996)
		(width 0.11684)
		(layer "In15.Cu")
		(net "RST_RT_CPU0_P3_PERST_R2_N")
	)
	(segment
		(start 190.574676 -125.254766)
		(end 189.915292 -124.595382)
		(width 0.11684)
		(layer "In15.Cu")
		(net "RST_RT_CPU0_P3_PERST_R2_N")
	)
	(segment
		(start 203.563982 -127.5842)
		(end 202.743054 -127.5842)
		(width 0.11684)
		(layer "In15.Cu")
		(net "RST_RT_CPU0_P3_PERST_R2_N")
	)
	(segment
		(start 215.416638 -127.84201)
		(end 214.375746 -128.882902)
		(width 0.11684)
		(layer "In15.Cu")
		(net "RST_RT_CPU0_P3_PERST_R2_N")
	)
	(segment
		(start 190.574676 -126.062486)
		(end 190.574676 -125.254766)
		(width 0.11684)
		(layer "In15.Cu")
		(net "RST_RT_CPU0_P3_PERST_R2_N")
	)
	(segment
		(start 189.915292 -121.846086)
		(end 189.51194 -121.442734)
		(width 0.11684)
		(layer "In15.Cu")
		(net "RST_RT_CPU0_P3_PERST_R2_N")
	)
	(segment
		(start 191.099186 -126.586996)
		(end 190.574676 -126.062486)
		(width 0.11684)
		(layer "In15.Cu")
		(net "RST_RT_CPU0_P3_PERST_R2_N")
	)
	(segment
		(start 205.589886 -128.882902)
		(end 204.44841 -127.741426)
		(width 0.11684)
		(layer "In15.Cu")
		(net "RST_RT_CPU0_P3_PERST_R2_N")
	)
	(segment
		(start 203.721208 -127.741426)
		(end 203.563982 -127.5842)
		(width 0.11684)
		(layer "In15.Cu")
		(net "RST_RT_CPU0_P3_PERST_R2_N")
	)
	(segment
		(start 195.296028 -127.165862)
		(end 194.717162 -126.586996)
		(width 0.11684)
		(layer "In15.Cu")
		(net "RST_RT_CPU0_P3_PERST_R2_N")
	)
	(segment
		(start 204.44841 -127.741426)
		(end 203.721208 -127.741426)
		(width 0.11684)
		(layer "In15.Cu")
		(net "RST_RT_CPU0_P3_PERST_R2_N")
	)
	(segment
		(start 189.915292 -124.595382)
		(end 189.915292 -121.846086)
		(width 0.11684)
		(layer "In15.Cu")
		(net "RST_RT_CPU0_P3_PERST_R2_N")
	)
	(segment
		(start 214.375746 -128.882902)
		(end 205.589886 -128.882902)
		(width 0.11684)
		(layer "In15.Cu")
		(net "RST_RT_CPU0_P3_PERST_R2_N")
	)
	(segment
		(start 202.743054 -127.5842)
		(end 201.348848 -128.978406)
		(width 0.11684)
		(layer "In15.Cu")
		(net "RST_RT_CPU0_P3_PERST_R2_N")
	)
	(segment
		(start 200.451466 -128.978406)
		(end 199.735948 -128.262888)
		(width 0.11684)
		(layer "In15.Cu")
		(net "RST_RT_CPU0_P3_PERST_R2_N")
	)
	(segment
		(start 391.268458 -404.673816)
		(end 390.934194 -405.00808)
		(width 0.10668)
		(layer "F.Cu")
		(net "RST_RT_CPU0_P3_PERST_N")
	)
	(segment
		(start 390.473438 -400.981672)
		(end 389.718042 -400.226276)
		(width 0.10668)
		(layer "F.Cu")
		(net "RST_RT_CPU0_P3_PERST_N")
	)
	(segment
		(start 390.473438 -404.02764)
		(end 390.473438 -400.981672)
		(width 0.10668)
		(layer "F.Cu")
		(net "RST_RT_CPU0_P3_PERST_N")
	)
	(segment
		(start 391.268458 -404.2791)
		(end 390.724898 -404.2791)
		(width 0.10668)
		(layer "F.Cu")
		(net "RST_RT_CPU0_P3_PERST_N")
	)
	(segment
		(start 390.724898 -404.2791)
		(end 390.473438 -404.02764)
		(width 0.10668)
		(layer "F.Cu")
		(net "RST_RT_CPU0_P3_PERST_N")
	)
	(segment
		(start 389.718042 -400.226276)
		(end 389.718042 -399.143474)
		(width 0.10668)
		(layer "F.Cu")
		(net "RST_RT_CPU0_P3_PERST_N")
	)
	(segment
		(start 391.268458 -404.2791)
		(end 391.268458 -404.673816)
		(width 0.10668)
		(layer "F.Cu")
		(net "RST_RT_CPU0_P3_PERST_N")
	)
	(segment
		(start 390.934194 -405.00808)
		(end 390.312656 -405.00808)
		(width 0.10668)
		(layer "F.Cu")
		(net "RST_RT_CPU0_P3_PERST_N")
	)
	(via
		(at 390.312656 -405.00808)
		(size 0.762)
		(drill 0.381)
		(layers "F.Cu" "B.Cu")
		(net "RST_RT_CPU0_P3_PERST_N")
	)
	(segment
		(start 400.315684 -402.815552)
		(end 400.315684 -403.552152)
		(width 0.10668)
		(layer "F.Cu")
		(net "RST_RT_CPU0_P2_RESET_R_N")
	)
	(segment
		(start 400.041364 -400.567652)
		(end 399.86712 -400.741896)
		(width 0.10668)
		(layer "F.Cu")
		(net "RST_RT_CPU0_P2_RESET_R_N")
	)
	(segment
		(start 399.350484 -403.552152)
		(end 400.315684 -403.552152)
		(width 0.10668)
		(layer "F.Cu")
		(net "RST_RT_CPU0_P2_RESET_R_N")
	)
	(segment
		(start 399.86712 -400.741896)
		(end 399.86712 -402.614384)
		(width 0.10668)
		(layer "F.Cu")
		(net "RST_RT_CPU0_P2_RESET_R_N")
	)
	(segment
		(start 399.86712 -402.614384)
		(end 400.068288 -402.815552)
		(width 0.10668)
		(layer "F.Cu")
		(net "RST_RT_CPU0_P2_RESET_R_N")
	)
	(segment
		(start 400.068288 -402.815552)
		(end 400.315684 -402.815552)
		(width 0.10668)
		(layer "F.Cu")
		(net "RST_RT_CPU0_P2_RESET_R_N")
	)
	(via
		(at 190.011558 -132.534406)
		(size 0.508)
		(drill 0.254)
		(layers "F.Cu" "B.Cu")
		(net "RST_RT_CPU0_P2_RESET_R_N")
	)
	(via
		(at 425.748704 -401.4851)
		(size 0.508)
		(drill 0.254)
		(layers "F.Cu" "B.Cu")
		(net "RST_RT_CPU0_P2_RESET_R_N")
	)
	(via
		(at 400.041364 -400.567652)
		(size 0.508)
		(drill 0.254)
		(layers "F.Cu" "B.Cu")
		(net "RST_RT_CPU0_P2_RESET_R_N")
	)
	(via
		(at 445.405764 -130.293872)
		(size 0.508)
		(drill 0.254)
		(layers "F.Cu" "B.Cu")
		(net "RST_RT_CPU0_P2_RESET_R_N")
	)
	(segment
		(start 190.315596 -130.86207)
		(end 189.94755 -130.86207)
		(width 0.10668)
		(layer "B.Cu")
		(net "RST_RT_CPU0_P2_RESET_R_N")
	)
	(segment
		(start 189.94755 -130.86207)
		(end 189.621414 -131.188206)
		(width 0.10668)
		(layer "B.Cu")
		(net "RST_RT_CPU0_P2_RESET_R_N")
	)
	(segment
		(start 189.621414 -131.563872)
		(end 190.011558 -131.954016)
		(width 0.10668)
		(layer "B.Cu")
		(net "RST_RT_CPU0_P2_RESET_R_N")
	)
	(segment
		(start 190.011558 -131.954016)
		(end 190.011558 -132.534406)
		(width 0.10668)
		(layer "B.Cu")
		(net "RST_RT_CPU0_P2_RESET_R_N")
	)
	(segment
		(start 190.595758 -129.951734)
		(end 190.595758 -130.581908)
		(width 0.10668)
		(layer "B.Cu")
		(net "RST_RT_CPU0_P2_RESET_R_N")
	)
	(segment
		(start 189.993778 -127.33401)
		(end 189.993778 -129.349754)
		(width 0.10668)
		(layer "B.Cu")
		(net "RST_RT_CPU0_P2_RESET_R_N")
	)
	(segment
		(start 189.993778 -129.349754)
		(end 190.595758 -129.951734)
		(width 0.10668)
		(layer "B.Cu")
		(net "RST_RT_CPU0_P2_RESET_R_N")
	)
	(segment
		(start 190.595758 -130.581908)
		(end 190.315596 -130.86207)
		(width 0.10668)
		(layer "B.Cu")
		(net "RST_RT_CPU0_P2_RESET_R_N")
	)
	(segment
		(start 189.621414 -131.188206)
		(end 189.621414 -131.563872)
		(width 0.10668)
		(layer "B.Cu")
		(net "RST_RT_CPU0_P2_RESET_R_N")
	)
	(segment
		(start 399.674334 -400.934682)
		(end 400.041364 -400.567652)
		(width 0.11684)
		(layer "In2.Cu")
		(net "RST_RT_CPU0_P2_RESET_R_N")
	)
	(segment
		(start 425.748704 -401.4851)
		(end 425.288964 -401.4851)
		(width 0.11684)
		(layer "In2.Cu")
		(net "RST_RT_CPU0_P2_RESET_R_N")
	)
	(segment
		(start 400.263106 -403.355556)
		(end 399.674334 -402.766784)
		(width 0.11684)
		(layer "In2.Cu")
		(net "RST_RT_CPU0_P2_RESET_R_N")
	)
	(segment
		(start 425.288964 -401.4851)
		(end 423.418508 -403.355556)
		(width 0.11684)
		(layer "In2.Cu")
		(net "RST_RT_CPU0_P2_RESET_R_N")
	)
	(segment
		(start 399.674334 -402.766784)
		(end 399.674334 -400.934682)
		(width 0.11684)
		(layer "In2.Cu")
		(net "RST_RT_CPU0_P2_RESET_R_N")
	)
	(segment
		(start 423.418508 -403.355556)
		(end 400.263106 -403.355556)
		(width 0.11684)
		(layer "In2.Cu")
		(net "RST_RT_CPU0_P2_RESET_R_N")
	)
	(segment
		(start 455.409808 -338.792312)
		(end 466.30717 -327.89495)
		(width 0.11684)
		(layer "In4.Cu")
		(net "RST_RT_CPU0_P2_RESET_R_N")
	)
	(segment
		(start 429.502316 -398.628108)
		(end 431.945542 -396.184882)
		(width 0.11684)
		(layer "In4.Cu")
		(net "RST_RT_CPU0_P2_RESET_R_N")
	)
	(segment
		(start 428.940214 -398.628108)
		(end 429.502316 -398.628108)
		(width 0.11684)
		(layer "In4.Cu")
		(net "RST_RT_CPU0_P2_RESET_R_N")
	)
	(segment
		(start 428.40402 -400.435572)
		(end 428.40402 -399.726404)
		(width 0.11684)
		(layer "In4.Cu")
		(net "RST_RT_CPU0_P2_RESET_R_N")
	)
	(segment
		(start 442.30163 -374.366536)
		(end 455.282808 -374.366536)
		(width 0.11684)
		(layer "In4.Cu")
		(net "RST_RT_CPU0_P2_RESET_R_N")
	)
	(segment
		(start 427.354492 -401.4851)
		(end 428.40402 -400.435572)
		(width 0.11684)
		(layer "In4.Cu")
		(net "RST_RT_CPU0_P2_RESET_R_N")
	)
	(segment
		(start 458.61478 -166.520876)
		(end 455.629264 -163.53536)
		(width 0.11684)
		(layer "In4.Cu")
		(net "RST_RT_CPU0_P2_RESET_R_N")
	)
	(segment
		(start 455.409808 -374.239536)
		(end 455.409808 -338.792312)
		(width 0.11684)
		(layer "In4.Cu")
		(net "RST_RT_CPU0_P2_RESET_R_N")
	)
	(segment
		(start 438.691528 -387.158484)
		(end 438.691528 -377.976638)
		(width 0.11684)
		(layer "In4.Cu")
		(net "RST_RT_CPU0_P2_RESET_R_N")
	)
	(segment
		(start 466.30717 -327.89495)
		(end 466.30717 -167.444674)
		(width 0.11684)
		(layer "In4.Cu")
		(net "RST_RT_CPU0_P2_RESET_R_N")
	)
	(segment
		(start 428.40402 -399.726404)
		(end 428.643288 -399.487136)
		(width 0.11684)
		(layer "In4.Cu")
		(net "RST_RT_CPU0_P2_RESET_R_N")
	)
	(segment
		(start 428.643288 -398.925034)
		(end 428.940214 -398.628108)
		(width 0.11684)
		(layer "In4.Cu")
		(net "RST_RT_CPU0_P2_RESET_R_N")
	)
	(segment
		(start 425.748704 -401.4851)
		(end 427.354492 -401.4851)
		(width 0.11684)
		(layer "In4.Cu")
		(net "RST_RT_CPU0_P2_RESET_R_N")
	)
	(segment
		(start 428.643288 -399.487136)
		(end 428.643288 -398.925034)
		(width 0.11684)
		(layer "In4.Cu")
		(net "RST_RT_CPU0_P2_RESET_R_N")
	)
	(segment
		(start 431.945542 -396.184882)
		(end 431.945542 -393.90447)
		(width 0.11684)
		(layer "In4.Cu")
		(net "RST_RT_CPU0_P2_RESET_R_N")
	)
	(segment
		(start 466.30717 -167.444674)
		(end 465.383372 -166.520876)
		(width 0.11684)
		(layer "In4.Cu")
		(net "RST_RT_CPU0_P2_RESET_R_N")
	)
	(segment
		(start 447.180716 -130.293872)
		(end 445.405764 -130.293872)
		(width 0.11684)
		(layer "In4.Cu")
		(net "RST_RT_CPU0_P2_RESET_R_N")
	)
	(segment
		(start 438.691528 -377.976638)
		(end 442.30163 -374.366536)
		(width 0.11684)
		(layer "In4.Cu")
		(net "RST_RT_CPU0_P2_RESET_R_N")
	)
	(segment
		(start 455.629264 -163.53536)
		(end 455.629264 -138.74242)
		(width 0.11684)
		(layer "In4.Cu")
		(net "RST_RT_CPU0_P2_RESET_R_N")
	)
	(segment
		(start 455.282808 -374.366536)
		(end 455.409808 -374.239536)
		(width 0.11684)
		(layer "In4.Cu")
		(net "RST_RT_CPU0_P2_RESET_R_N")
	)
	(segment
		(start 455.629264 -138.74242)
		(end 447.180716 -130.293872)
		(width 0.11684)
		(layer "In4.Cu")
		(net "RST_RT_CPU0_P2_RESET_R_N")
	)
	(segment
		(start 465.383372 -166.520876)
		(end 458.61478 -166.520876)
		(width 0.11684)
		(layer "In4.Cu")
		(net "RST_RT_CPU0_P2_RESET_R_N")
	)
	(segment
		(start 431.945542 -393.90447)
		(end 438.691528 -387.158484)
		(width 0.11684)
		(layer "In4.Cu")
		(net "RST_RT_CPU0_P2_RESET_R_N")
	)
	(segment
		(start 252.918976 -128.882648)
		(end 270.030702 -128.882648)
		(width 0.11684)
		(layer "In15.Cu")
		(net "RST_RT_CPU0_P2_RESET_R_N")
	)
	(segment
		(start 272.023586 -130.875532)
		(end 287.62071 -130.875532)
		(width 0.11684)
		(layer "In15.Cu")
		(net "RST_RT_CPU0_P2_RESET_R_N")
	)
	(segment
		(start 370.3066 -126.78918)
		(end 373.811292 -130.293872)
		(width 0.11684)
		(layer "In15.Cu")
		(net "RST_RT_CPU0_P2_RESET_R_N")
	)
	(segment
		(start 291.35705 -131.368038)
		(end 294.17137 -131.368038)
		(width 0.11684)
		(layer "In15.Cu")
		(net "RST_RT_CPU0_P2_RESET_R_N")
	)
	(segment
		(start 190.011558 -132.534406)
		(end 190.49492 -133.017768)
		(width 0.11684)
		(layer "In15.Cu")
		(net "RST_RT_CPU0_P2_RESET_R_N")
	)
	(segment
		(start 246.525288 -133.45033)
		(end 249.876564 -130.099054)
		(width 0.11684)
		(layer "In15.Cu")
		(net "RST_RT_CPU0_P2_RESET_R_N")
	)
	(segment
		(start 287.62071 -130.875532)
		(end 288.452306 -131.707128)
		(width 0.11684)
		(layer "In15.Cu")
		(net "RST_RT_CPU0_P2_RESET_R_N")
	)
	(segment
		(start 288.452306 -131.707128)
		(end 291.01796 -131.707128)
		(width 0.11684)
		(layer "In15.Cu")
		(net "RST_RT_CPU0_P2_RESET_R_N")
	)
	(segment
		(start 194.49796 -133.017768)
		(end 195.13296 -132.382768)
		(width 0.11684)
		(layer "In15.Cu")
		(net "RST_RT_CPU0_P2_RESET_R_N")
	)
	(segment
		(start 270.030702 -128.882648)
		(end 272.023586 -130.875532)
		(width 0.11684)
		(layer "In15.Cu")
		(net "RST_RT_CPU0_P2_RESET_R_N")
	)
	(segment
		(start 373.811292 -130.293872)
		(end 445.405764 -130.293872)
		(width 0.11684)
		(layer "In15.Cu")
		(net "RST_RT_CPU0_P2_RESET_R_N")
	)
	(segment
		(start 294.17137 -131.368038)
		(end 298.750228 -126.78918)
		(width 0.11684)
		(layer "In15.Cu")
		(net "RST_RT_CPU0_P2_RESET_R_N")
	)
	(segment
		(start 190.49492 -133.017768)
		(end 194.49796 -133.017768)
		(width 0.11684)
		(layer "In15.Cu")
		(net "RST_RT_CPU0_P2_RESET_R_N")
	)
	(segment
		(start 206.020162 -132.382768)
		(end 207.087724 -133.45033)
		(width 0.11684)
		(layer "In15.Cu")
		(net "RST_RT_CPU0_P2_RESET_R_N")
	)
	(segment
		(start 249.876564 -130.099054)
		(end 251.70257 -130.099054)
		(width 0.11684)
		(layer "In15.Cu")
		(net "RST_RT_CPU0_P2_RESET_R_N")
	)
	(segment
		(start 251.70257 -130.099054)
		(end 252.918976 -128.882648)
		(width 0.11684)
		(layer "In15.Cu")
		(net "RST_RT_CPU0_P2_RESET_R_N")
	)
	(segment
		(start 298.750228 -126.78918)
		(end 370.3066 -126.78918)
		(width 0.11684)
		(layer "In15.Cu")
		(net "RST_RT_CPU0_P2_RESET_R_N")
	)
	(segment
		(start 207.087724 -133.45033)
		(end 246.525288 -133.45033)
		(width 0.11684)
		(layer "In15.Cu")
		(net "RST_RT_CPU0_P2_RESET_R_N")
	)
	(segment
		(start 291.01796 -131.707128)
		(end 291.35705 -131.368038)
		(width 0.11684)
		(layer "In15.Cu")
		(net "RST_RT_CPU0_P2_RESET_R_N")
	)
	(segment
		(start 195.13296 -132.382768)
		(end 206.020162 -132.382768)
		(width 0.11684)
		(layer "In15.Cu")
		(net "RST_RT_CPU0_P2_RESET_R_N")
	)
	(segment
		(start 188.322204 -121.852944)
		(end 188.712094 -122.242834)
		(width 0.10668)
		(layer "F.Cu")
		(net "RST_RT_CPU0_P2_RESET_R2_N")
	)
	(via
		(at 188.712094 -122.242834)
		(size 0.4572)
		(drill 0.254)
		(layers "F.Cu" "B.Cu")
		(net "RST_RT_CPU0_P2_RESET_R2_N")
	)
	(via
		(at 189.6999 -123.866148)
		(size 0.6604)
		(drill 0.3302)
		(layers "F.Cu" "B.Cu")
		(net "RST_RT_CPU0_P2_RESET_R2_N")
	)
	(segment
		(start 189.113668 -122.76709)
		(end 188.712094 -122.365516)
		(width 0.10668)
		(layer "B.Cu")
		(net "RST_RT_CPU0_P2_RESET_R2_N")
	)
	(segment
		(start 189.53988 -124.817632)
		(end 189.53988 -126.080012)
		(width 0.10668)
		(layer "B.Cu")
		(net "RST_RT_CPU0_P2_RESET_R2_N")
	)
	(segment
		(start 189.6999 -123.866148)
		(end 189.113668 -123.279916)
		(width 0.10668)
		(layer "B.Cu")
		(net "RST_RT_CPU0_P2_RESET_R2_N")
	)
	(segment
		(start 189.53988 -126.080012)
		(end 189.993778 -126.53391)
		(width 0.10668)
		(layer "B.Cu")
		(net "RST_RT_CPU0_P2_RESET_R2_N")
	)
	(segment
		(start 189.6999 -124.657612)
		(end 189.53988 -124.817632)
		(width 0.10668)
		(layer "B.Cu")
		(net "RST_RT_CPU0_P2_RESET_R2_N")
	)
	(segment
		(start 189.113668 -123.279916)
		(end 189.113668 -122.76709)
		(width 0.10668)
		(layer "B.Cu")
		(net "RST_RT_CPU0_P2_RESET_R2_N")
	)
	(segment
		(start 188.712094 -122.365516)
		(end 188.712094 -122.242834)
		(width 0.10668)
		(layer "B.Cu")
		(net "RST_RT_CPU0_P2_RESET_R2_N")
	)
	(segment
		(start 189.6999 -123.866148)
		(end 189.6999 -124.657612)
		(width 0.10668)
		(layer "B.Cu")
		(net "RST_RT_CPU0_P2_RESET_R2_N")
	)
	(segment
		(start 398.923256 -403.166326)
		(end 398.923256 -405.01951)
		(width 0.10668)
		(layer "F.Cu")
		(net "RST_RT_CPU0_P2_RESET_N")
	)
	(segment
		(start 399.07083 -403.018752)
		(end 398.923256 -403.166326)
		(width 0.10668)
		(layer "F.Cu")
		(net "RST_RT_CPU0_P2_RESET_N")
	)
	(segment
		(start 399.490692 -402.222208)
		(end 399.350484 -402.362416)
		(width 0.10668)
		(layer "F.Cu")
		(net "RST_RT_CPU0_P2_RESET_N")
	)
	(segment
		(start 398.923256 -405.01951)
		(end 400.385534 -406.481788)
		(width 0.10668)
		(layer "F.Cu")
		(net "RST_RT_CPU0_P2_RESET_N")
	)
	(segment
		(start 400.325336 -397.112998)
		(end 399.490692 -397.947642)
		(width 0.10668)
		(layer "F.Cu")
		(net "RST_RT_CPU0_P2_RESET_N")
	)
	(segment
		(start 399.350484 -403.018752)
		(end 399.07083 -403.018752)
		(width 0.10668)
		(layer "F.Cu")
		(net "RST_RT_CPU0_P2_RESET_N")
	)
	(segment
		(start 399.350484 -402.362416)
		(end 399.350484 -403.018752)
		(width 0.10668)
		(layer "F.Cu")
		(net "RST_RT_CPU0_P2_RESET_N")
	)
	(segment
		(start 399.490692 -397.947642)
		(end 399.490692 -402.222208)
		(width 0.10668)
		(layer "F.Cu")
		(net "RST_RT_CPU0_P2_RESET_N")
	)
	(segment
		(start 401.729448 -397.112998)
		(end 400.325336 -397.112998)
		(width 0.10668)
		(layer "F.Cu")
		(net "RST_RT_CPU0_P2_RESET_N")
	)
	(segment
		(start 400.385534 -406.481788)
		(end 401.349718 -406.481788)
		(width 0.10668)
		(layer "F.Cu")
		(net "RST_RT_CPU0_P2_RESET_N")
	)
	(via
		(at 401.349718 -406.481788)
		(size 0.762)
		(drill 0.381)
		(layers "F.Cu" "B.Cu")
		(net "RST_RT_CPU0_P2_RESET_N")
	)
	(segment
		(start 428.850552 -403.740366)
		(end 424.691048 -403.740366)
		(width 0.10668)
		(layer "F.Cu")
		(net "RST_RT_CPU0_P2_PERST_R_N")
	)
	(segment
		(start 424.691048 -403.740366)
		(end 423.959782 -403.0091)
		(width 0.10668)
		(layer "F.Cu")
		(net "RST_RT_CPU0_P2_PERST_R_N")
	)
	(segment
		(start 429.349662 -404.239476)
		(end 428.850552 -403.740366)
		(width 0.10668)
		(layer "F.Cu")
		(net "RST_RT_CPU0_P2_PERST_R_N")
	)
	(segment
		(start 423.796206 -403.7457)
		(end 423.796206 -403.0091)
		(width 0.10668)
		(layer "F.Cu")
		(net "RST_RT_CPU0_P2_PERST_R_N")
	)
	(segment
		(start 423.959782 -403.0091)
		(end 423.796206 -403.0091)
		(width 0.10668)
		(layer "F.Cu")
		(net "RST_RT_CPU0_P2_PERST_R_N")
	)
	(via
		(at 429.349662 -404.239476)
		(size 0.508)
		(drill 0.254)
		(layers "F.Cu" "B.Cu")
		(net "RST_RT_CPU0_P2_PERST_R_N")
	)
	(via
		(at 219.547694 -125.222254)
		(size 0.508)
		(drill 0.254)
		(layers "F.Cu" "B.Cu")
		(net "RST_RT_CPU0_P2_PERST_R_N")
	)
	(via
		(at 216.452958 -86.838028)
		(size 0.508)
		(drill 0.254)
		(layers "F.Cu" "B.Cu")
		(net "RST_RT_CPU0_P2_PERST_R_N")
	)
	(segment
		(start 205.982062 -128.51384)
		(end 211.987892 -128.51384)
		(width 0.10668)
		(layer "B.Cu")
		(net "RST_RT_CPU0_P2_PERST_R_N")
	)
	(segment
		(start 218.941142 -127.28829)
		(end 219.547694 -126.681738)
		(width 0.10668)
		(layer "B.Cu")
		(net "RST_RT_CPU0_P2_PERST_R_N")
	)
	(segment
		(start 219.547694 -126.681738)
		(end 219.547694 -125.222254)
		(width 0.10668)
		(layer "B.Cu")
		(net "RST_RT_CPU0_P2_PERST_R_N")
	)
	(segment
		(start 205.550516 -128.082294)
		(end 205.982062 -128.51384)
		(width 0.10668)
		(layer "B.Cu")
		(net "RST_RT_CPU0_P2_PERST_R_N")
	)
	(segment
		(start 211.987892 -128.51384)
		(end 213.213442 -127.28829)
		(width 0.10668)
		(layer "B.Cu")
		(net "RST_RT_CPU0_P2_PERST_R_N")
	)
	(segment
		(start 213.213442 -127.28829)
		(end 218.941142 -127.28829)
		(width 0.10668)
		(layer "B.Cu")
		(net "RST_RT_CPU0_P2_PERST_R_N")
	)
	(segment
		(start 439.710322 -387.453632)
		(end 439.710322 -375.70537)
		(width 0.11684)
		(layer "In2.Cu")
		(net "RST_RT_CPU0_P2_PERST_R_N")
	)
	(segment
		(start 382.430782 -117.28196)
		(end 376.707654 -117.28196)
		(width 0.11684)
		(layer "In2.Cu")
		(net "RST_RT_CPU0_P2_PERST_R_N")
	)
	(segment
		(start 317.801244 -111.099092)
		(end 314.30976 -111.099092)
		(width 0.11684)
		(layer "In2.Cu")
		(net "RST_RT_CPU0_P2_PERST_R_N")
	)
	(segment
		(start 327.044558 -120.342406)
		(end 317.801244 -111.099092)
		(width 0.11684)
		(layer "In2.Cu")
		(net "RST_RT_CPU0_P2_PERST_R_N")
	)
	(segment
		(start 455.090276 -152.96769)
		(end 457.361798 -150.696168)
		(width 0.11684)
		(layer "In2.Cu")
		(net "RST_RT_CPU0_P2_PERST_R_N")
	)
	(segment
		(start 455.090276 -163.210748)
		(end 455.090276 -152.96769)
		(width 0.11684)
		(layer "In2.Cu")
		(net "RST_RT_CPU0_P2_PERST_R_N")
	)
	(segment
		(start 435.374796 -391.789158)
		(end 439.710322 -387.453632)
		(width 0.11684)
		(layer "In2.Cu")
		(net "RST_RT_CPU0_P2_PERST_R_N")
	)
	(segment
		(start 454.468992 -364.842806)
		(end 454.468992 -344.299794)
		(width 0.11684)
		(layer "In2.Cu")
		(net "RST_RT_CPU0_P2_PERST_R_N")
	)
	(segment
		(start 431.659284 -398.143476)
		(end 432.21275 -396.806928)
		(width 0.11684)
		(layer "In2.Cu")
		(net "RST_RT_CPU0_P2_PERST_R_N")
	)
	(segment
		(start 239.638078 -88.3285)
		(end 217.372692 -88.3285)
		(width 0.11684)
		(layer "In2.Cu")
		(net "RST_RT_CPU0_P2_PERST_R_N")
	)
	(segment
		(start 457.361798 -150.696168)
		(end 457.361798 -141.576806)
		(width 0.11684)
		(layer "In2.Cu")
		(net "RST_RT_CPU0_P2_PERST_R_N")
	)
	(segment
		(start 376.707654 -117.28196)
		(end 373.647208 -120.342406)
		(width 0.11684)
		(layer "In2.Cu")
		(net "RST_RT_CPU0_P2_PERST_R_N")
	)
	(segment
		(start 246.332756 -78.62951)
		(end 244.715792 -80.246474)
		(width 0.11684)
		(layer "In2.Cu")
		(net "RST_RT_CPU0_P2_PERST_R_N")
	)
	(segment
		(start 433.412392 -117.6274)
		(end 382.776222 -117.6274)
		(width 0.11684)
		(layer "In2.Cu")
		(net "RST_RT_CPU0_P2_PERST_R_N")
	)
	(segment
		(start 448.651376 -372.99138)
		(end 451.409308 -370.233448)
		(width 0.11684)
		(layer "In2.Cu")
		(net "RST_RT_CPU0_P2_PERST_R_N")
	)
	(segment
		(start 451.409308 -367.90249)
		(end 454.468992 -364.842806)
		(width 0.11684)
		(layer "In2.Cu")
		(net "RST_RT_CPU0_P2_PERST_R_N")
	)
	(segment
		(start 382.776222 -117.6274)
		(end 382.430782 -117.28196)
		(width 0.11684)
		(layer "In2.Cu")
		(net "RST_RT_CPU0_P2_PERST_R_N")
	)
	(segment
		(start 309.547006 -106.336338)
		(end 290.555426 -106.336338)
		(width 0.11684)
		(layer "In2.Cu")
		(net "RST_RT_CPU0_P2_PERST_R_N")
	)
	(segment
		(start 460.643478 -168.76395)
		(end 455.090276 -163.210748)
		(width 0.11684)
		(layer "In2.Cu")
		(net "RST_RT_CPU0_P2_PERST_R_N")
	)
	(segment
		(start 244.715792 -80.246474)
		(end 244.715792 -83.250786)
		(width 0.11684)
		(layer "In2.Cu")
		(net "RST_RT_CPU0_P2_PERST_R_N")
	)
	(segment
		(start 442.424312 -372.99138)
		(end 448.651376 -372.99138)
		(width 0.11684)
		(layer "In2.Cu")
		(net "RST_RT_CPU0_P2_PERST_R_N")
	)
	(segment
		(start 439.710322 -375.70537)
		(end 442.424312 -372.99138)
		(width 0.11684)
		(layer "In2.Cu")
		(net "RST_RT_CPU0_P2_PERST_R_N")
	)
	(segment
		(start 435.374796 -393.644882)
		(end 435.374796 -391.789158)
		(width 0.11684)
		(layer "In2.Cu")
		(net "RST_RT_CPU0_P2_PERST_R_N")
	)
	(segment
		(start 454.468992 -344.299794)
		(end 465.918296 -332.85049)
		(width 0.11684)
		(layer "In2.Cu")
		(net "RST_RT_CPU0_P2_PERST_R_N")
	)
	(segment
		(start 314.30976 -111.099092)
		(end 309.547006 -106.336338)
		(width 0.11684)
		(layer "In2.Cu")
		(net "RST_RT_CPU0_P2_PERST_R_N")
	)
	(segment
		(start 465.918296 -171.549568)
		(end 463.132678 -168.76395)
		(width 0.11684)
		(layer "In2.Cu")
		(net "RST_RT_CPU0_P2_PERST_R_N")
	)
	(segment
		(start 264.895076 -79.200756)
		(end 264.32383 -78.62951)
		(width 0.11684)
		(layer "In2.Cu")
		(net "RST_RT_CPU0_P2_PERST_R_N")
	)
	(segment
		(start 465.918296 -332.85049)
		(end 465.918296 -171.549568)
		(width 0.11684)
		(layer "In2.Cu")
		(net "RST_RT_CPU0_P2_PERST_R_N")
	)
	(segment
		(start 429.349662 -404.239476)
		(end 431.659284 -401.929854)
		(width 0.11684)
		(layer "In2.Cu")
		(net "RST_RT_CPU0_P2_PERST_R_N")
	)
	(segment
		(start 431.659284 -401.929854)
		(end 431.659284 -398.143476)
		(width 0.11684)
		(layer "In2.Cu")
		(net "RST_RT_CPU0_P2_PERST_R_N")
	)
	(segment
		(start 451.409308 -370.233448)
		(end 451.409308 -367.90249)
		(width 0.11684)
		(layer "In2.Cu")
		(net "RST_RT_CPU0_P2_PERST_R_N")
	)
	(segment
		(start 373.647208 -120.342406)
		(end 327.044558 -120.342406)
		(width 0.11684)
		(layer "In2.Cu")
		(net "RST_RT_CPU0_P2_PERST_R_N")
	)
	(segment
		(start 463.132678 -168.76395)
		(end 460.643478 -168.76395)
		(width 0.11684)
		(layer "In2.Cu")
		(net "RST_RT_CPU0_P2_PERST_R_N")
	)
	(segment
		(start 216.452958 -87.408766)
		(end 216.452958 -86.838028)
		(width 0.11684)
		(layer "In2.Cu")
		(net "RST_RT_CPU0_P2_PERST_R_N")
	)
	(segment
		(start 244.715792 -83.250786)
		(end 239.638078 -88.3285)
		(width 0.11684)
		(layer "In2.Cu")
		(net "RST_RT_CPU0_P2_PERST_R_N")
	)
	(segment
		(start 264.895076 -80.675988)
		(end 264.895076 -79.200756)
		(width 0.11684)
		(layer "In2.Cu")
		(net "RST_RT_CPU0_P2_PERST_R_N")
	)
	(segment
		(start 457.361798 -141.576806)
		(end 433.412392 -117.6274)
		(width 0.11684)
		(layer "In2.Cu")
		(net "RST_RT_CPU0_P2_PERST_R_N")
	)
	(segment
		(start 290.555426 -106.336338)
		(end 264.895076 -80.675988)
		(width 0.11684)
		(layer "In2.Cu")
		(net "RST_RT_CPU0_P2_PERST_R_N")
	)
	(segment
		(start 217.372692 -88.3285)
		(end 216.452958 -87.408766)
		(width 0.11684)
		(layer "In2.Cu")
		(net "RST_RT_CPU0_P2_PERST_R_N")
	)
	(segment
		(start 432.21275 -396.806928)
		(end 435.374796 -393.644882)
		(width 0.11684)
		(layer "In2.Cu")
		(net "RST_RT_CPU0_P2_PERST_R_N")
	)
	(segment
		(start 264.32383 -78.62951)
		(end 246.332756 -78.62951)
		(width 0.11684)
		(layer "In2.Cu")
		(net "RST_RT_CPU0_P2_PERST_R_N")
	)
	(segment
		(start 219.547694 -125.222254)
		(end 219.78239 -124.987558)
		(width 0.11684)
		(layer "In11.Cu")
		(net "RST_RT_CPU0_P2_PERST_R_N")
	)
	(segment
		(start 219.818966 -105.599992)
		(end 220.130624 -105.288334)
		(width 0.11684)
		(layer "In11.Cu")
		(net "RST_RT_CPU0_P2_PERST_R_N")
	)
	(segment
		(start 219.529152 -95.621856)
		(end 219.529152 -90.93454)
		(width 0.11684)
		(layer "In11.Cu")
		(net "RST_RT_CPU0_P2_PERST_R_N")
	)
	(segment
		(start 219.529152 -90.93454)
		(end 216.452958 -87.858346)
		(width 0.11684)
		(layer "In11.Cu")
		(net "RST_RT_CPU0_P2_PERST_R_N")
	)
	(segment
		(start 219.78239 -105.599992)
		(end 219.818966 -105.599992)
		(width 0.11684)
		(layer "In11.Cu")
		(net "RST_RT_CPU0_P2_PERST_R_N")
	)
	(segment
		(start 219.78239 -124.987558)
		(end 219.78239 -105.599992)
		(width 0.11684)
		(layer "In11.Cu")
		(net "RST_RT_CPU0_P2_PERST_R_N")
	)
	(segment
		(start 220.130624 -96.223328)
		(end 219.529152 -95.621856)
		(width 0.11684)
		(layer "In11.Cu")
		(net "RST_RT_CPU0_P2_PERST_R_N")
	)
	(segment
		(start 220.130624 -105.288334)
		(end 220.130624 -96.223328)
		(width 0.11684)
		(layer "In11.Cu")
		(net "RST_RT_CPU0_P2_PERST_R_N")
	)
	(segment
		(start 216.452958 -87.858346)
		(end 216.452958 -86.838028)
		(width 0.11684)
		(layer "In11.Cu")
		(net "RST_RT_CPU0_P2_PERST_R_N")
	)
	(segment
		(start 186.722004 -120.252744)
		(end 187.111894 -120.642634)
		(width 0.10668)
		(layer "F.Cu")
		(net "RST_RT_CPU0_P2_PERST_R2_N")
	)
	(via
		(at 203.371196 -128.04902)
		(size 0.508)
		(drill 0.254)
		(layers "F.Cu" "B.Cu")
		(net "RST_RT_CPU0_P2_PERST_R2_N")
	)
	(via
		(at 187.111894 -120.642634)
		(size 0.4572)
		(drill 0.254)
		(layers "F.Cu" "B.Cu")
		(net "RST_RT_CPU0_P2_PERST_R2_N")
	)
	(segment
		(start 204.717142 -128.04902)
		(end 203.371196 -128.04902)
		(width 0.10668)
		(layer "B.Cu")
		(net "RST_RT_CPU0_P2_PERST_R2_N")
	)
	(segment
		(start 204.750416 -128.082294)
		(end 204.717142 -128.04902)
		(width 0.10668)
		(layer "B.Cu")
		(net "RST_RT_CPU0_P2_PERST_R2_N")
	)
	(segment
		(start 187.111894 -120.642634)
		(end 186.706002 -121.048526)
		(width 0.11684)
		(layer "In15.Cu")
		(net "RST_RT_CPU0_P2_PERST_R2_N")
	)
	(segment
		(start 186.706002 -121.048526)
		(end 186.706002 -126.35992)
		(width 0.11684)
		(layer "In15.Cu")
		(net "RST_RT_CPU0_P2_PERST_R2_N")
	)
	(segment
		(start 187.856876 -127.510794)
		(end 193.616834 -127.510794)
		(width 0.11684)
		(layer "In15.Cu")
		(net "RST_RT_CPU0_P2_PERST_R2_N")
	)
	(segment
		(start 195.505324 -129.399284)
		(end 197.918578 -129.399284)
		(width 0.11684)
		(layer "In15.Cu")
		(net "RST_RT_CPU0_P2_PERST_R2_N")
	)
	(segment
		(start 200.988422 -129.935478)
		(end 202.87488 -128.04902)
		(width 0.11684)
		(layer "In15.Cu")
		(net "RST_RT_CPU0_P2_PERST_R2_N")
	)
	(segment
		(start 193.616834 -127.510794)
		(end 195.505324 -129.399284)
		(width 0.11684)
		(layer "In15.Cu")
		(net "RST_RT_CPU0_P2_PERST_R2_N")
	)
	(segment
		(start 197.918578 -129.399284)
		(end 198.454772 -129.935478)
		(width 0.11684)
		(layer "In15.Cu")
		(net "RST_RT_CPU0_P2_PERST_R2_N")
	)
	(segment
		(start 202.87488 -128.04902)
		(end 203.371196 -128.04902)
		(width 0.11684)
		(layer "In15.Cu")
		(net "RST_RT_CPU0_P2_PERST_R2_N")
	)
	(segment
		(start 186.706002 -126.35992)
		(end 187.856876 -127.510794)
		(width 0.11684)
		(layer "In15.Cu")
		(net "RST_RT_CPU0_P2_PERST_R2_N")
	)
	(segment
		(start 198.454772 -129.935478)
		(end 200.988422 -129.935478)
		(width 0.11684)
		(layer "In15.Cu")
		(net "RST_RT_CPU0_P2_PERST_R2_N")
	)
	(segment
		(start 422.24579 -399.143474)
		(end 422.24579 -399.963894)
		(width 0.10668)
		(layer "F.Cu")
		(net "RST_RT_CPU0_P2_PERST_N")
	)
	(segment
		(start 422.24579 -399.963894)
		(end 423.001186 -400.71929)
		(width 0.10668)
		(layer "F.Cu")
		(net "RST_RT_CPU0_P2_PERST_N")
	)
	(segment
		(start 423.001186 -400.71929)
		(end 423.001186 -404.87473)
		(width 0.10668)
		(layer "F.Cu")
		(net "RST_RT_CPU0_P2_PERST_N")
	)
	(segment
		(start 423.107358 -404.967948)
		(end 423.094404 -404.967948)
		(width 0.10668)
		(layer "F.Cu")
		(net "RST_RT_CPU0_P2_PERST_N")
	)
	(segment
		(start 423.001186 -404.87473)
		(end 423.094404 -404.967948)
		(width 0.10668)
		(layer "F.Cu")
		(net "RST_RT_CPU0_P2_PERST_N")
	)
	(segment
		(start 423.796206 -404.2791)
		(end 423.107358 -404.967948)
		(width 0.10668)
		(layer "F.Cu")
		(net "RST_RT_CPU0_P2_PERST_N")
	)
	(via
		(at 423.094404 -404.967948)
		(size 0.762)
		(drill 0.381)
		(layers "F.Cu" "B.Cu")
		(net "RST_RT_CPU0_P2_PERST_N")
	)
	(segment
		(start 333.215488 -402.815552)
		(end 333.215488 -403.552152)
		(width 0.10668)
		(layer "F.Cu")
		(net "RST_RT_CPU0_P1_RESET_R_N")
	)
	(segment
		(start 332.250288 -403.552152)
		(end 333.215488 -403.552152)
		(width 0.10668)
		(layer "F.Cu")
		(net "RST_RT_CPU0_P1_RESET_R_N")
	)
	(segment
		(start 259.252212 -323.32803)
		(end 259.252212 -226.404932)
		(width 0.10668)
		(layer "F.Cu")
		(net "RST_RT_CPU0_P1_RESET_R_N")
	)
	(segment
		(start 252.73 -345.948)
		(end 254.456438 -344.221562)
		(width 0.10668)
		(layer "F.Cu")
		(net "RST_RT_CPU0_P1_RESET_R_N")
	)
	(segment
		(start 332.766924 -402.614384)
		(end 332.968092 -402.815552)
		(width 0.10668)
		(layer "F.Cu")
		(net "RST_RT_CPU0_P1_RESET_R_N")
	)
	(segment
		(start 241.932206 -179.481988)
		(end 241.932206 -167.421814)
		(width 0.10668)
		(layer "F.Cu")
		(net "RST_RT_CPU0_P1_RESET_R_N")
	)
	(segment
		(start 254.456438 -344.221562)
		(end 254.456438 -328.123804)
		(width 0.10668)
		(layer "F.Cu")
		(net "RST_RT_CPU0_P1_RESET_R_N")
	)
	(segment
		(start 332.968092 -402.815552)
		(end 333.215488 -402.815552)
		(width 0.10668)
		(layer "F.Cu")
		(net "RST_RT_CPU0_P1_RESET_R_N")
	)
	(segment
		(start 332.972156 -400.633946)
		(end 332.766924 -400.839178)
		(width 0.10668)
		(layer "F.Cu")
		(net "RST_RT_CPU0_P1_RESET_R_N")
	)
	(segment
		(start 241.932206 -167.421814)
		(end 242.381786 -166.972234)
		(width 0.10668)
		(layer "F.Cu")
		(net "RST_RT_CPU0_P1_RESET_R_N")
	)
	(segment
		(start 246.3165 -213.46922)
		(end 246.3165 -190.066676)
		(width 0.10668)
		(layer "F.Cu")
		(net "RST_RT_CPU0_P1_RESET_R_N")
	)
	(segment
		(start 246.3165 -190.066676)
		(end 241.932206 -179.481988)
		(width 0.10668)
		(layer "F.Cu")
		(net "RST_RT_CPU0_P1_RESET_R_N")
	)
	(segment
		(start 332.766924 -400.839178)
		(end 332.766924 -402.614384)
		(width 0.10668)
		(layer "F.Cu")
		(net "RST_RT_CPU0_P1_RESET_R_N")
	)
	(segment
		(start 259.252212 -226.404932)
		(end 246.3165 -213.46922)
		(width 0.10668)
		(layer "F.Cu")
		(net "RST_RT_CPU0_P1_RESET_R_N")
	)
	(segment
		(start 254.456438 -328.123804)
		(end 259.252212 -323.32803)
		(width 0.10668)
		(layer "F.Cu")
		(net "RST_RT_CPU0_P1_RESET_R_N")
	)
	(via
		(at 252.73 -345.948)
		(size 0.508)
		(drill 0.254)
		(layers "F.Cu" "B.Cu")
		(net "RST_RT_CPU0_P1_RESET_R_N")
	)
	(via
		(at 242.381786 -166.972234)
		(size 0.508)
		(drill 0.254)
		(layers "F.Cu" "B.Cu")
		(net "RST_RT_CPU0_P1_RESET_R_N")
	)
	(via
		(at 332.972156 -400.633946)
		(size 0.508)
		(drill 0.254)
		(layers "F.Cu" "B.Cu")
		(net "RST_RT_CPU0_P1_RESET_R_N")
	)
	(via
		(at 289.64255 -406.069038)
		(size 0.508)
		(drill 0.254)
		(layers "F.Cu" "B.Cu")
		(net "RST_RT_CPU0_P1_RESET_R_N")
	)
	(segment
		(start 235.406438 -160.714436)
		(end 241.664236 -166.972234)
		(width 0.10668)
		(layer "B.Cu")
		(net "RST_RT_CPU0_P1_RESET_R_N")
	)
	(segment
		(start 215.765126 -130.126994)
		(end 218.940634 -130.126994)
		(width 0.10668)
		(layer "B.Cu")
		(net "RST_RT_CPU0_P1_RESET_R_N")
	)
	(segment
		(start 222.31858 -133.50494)
		(end 222.31858 -142.184882)
		(width 0.10668)
		(layer "B.Cu")
		(net "RST_RT_CPU0_P1_RESET_R_N")
	)
	(segment
		(start 226.491292 -146.357594)
		(end 226.491292 -157.265116)
		(width 0.10668)
		(layer "B.Cu")
		(net "RST_RT_CPU0_P1_RESET_R_N")
	)
	(segment
		(start 218.940634 -130.126994)
		(end 222.31858 -133.50494)
		(width 0.10668)
		(layer "B.Cu")
		(net "RST_RT_CPU0_P1_RESET_R_N")
	)
	(segment
		(start 226.491292 -157.265116)
		(end 229.940612 -160.714436)
		(width 0.10668)
		(layer "B.Cu")
		(net "RST_RT_CPU0_P1_RESET_R_N")
	)
	(segment
		(start 222.31858 -142.184882)
		(end 226.491292 -146.357594)
		(width 0.10668)
		(layer "B.Cu")
		(net "RST_RT_CPU0_P1_RESET_R_N")
	)
	(segment
		(start 241.664236 -166.972234)
		(end 242.381786 -166.972234)
		(width 0.10668)
		(layer "B.Cu")
		(net "RST_RT_CPU0_P1_RESET_R_N")
	)
	(segment
		(start 214.712296 -129.074164)
		(end 215.765126 -130.126994)
		(width 0.10668)
		(layer "B.Cu")
		(net "RST_RT_CPU0_P1_RESET_R_N")
	)
	(segment
		(start 229.940612 -160.714436)
		(end 235.406438 -160.714436)
		(width 0.10668)
		(layer "B.Cu")
		(net "RST_RT_CPU0_P1_RESET_R_N")
	)
	(segment
		(start 205.546198 -129.074164)
		(end 214.712296 -129.074164)
		(width 0.10668)
		(layer "B.Cu")
		(net "RST_RT_CPU0_P1_RESET_R_N")
	)
	(segment
		(start 325.192644 -402.243798)
		(end 325.05904 -402.377402)
		(width 0.11684)
		(layer "In6.Cu")
		(net "RST_RT_CPU0_P1_RESET_R_N")
	)
	(segment
		(start 301.94504 -410.87548)
		(end 299.71492 -408.64536)
		(width 0.11684)
		(layer "In6.Cu")
		(net "RST_RT_CPU0_P1_RESET_R_N")
	)
	(segment
		(start 322.0466 -404.23592)
		(end 318.641476 -404.23592)
		(width 0.11684)
		(layer "In6.Cu")
		(net "RST_RT_CPU0_P1_RESET_R_N")
	)
	(segment
		(start 325.192644 -400.345656)
		(end 325.192644 -402.243798)
		(width 0.11684)
		(layer "In6.Cu")
		(net "RST_RT_CPU0_P1_RESET_R_N")
	)
	(segment
		(start 299.71492 -408.64536)
		(end 295.677082 -408.64536)
		(width 0.11684)
		(layer "In6.Cu")
		(net "RST_RT_CPU0_P1_RESET_R_N")
	)
	(segment
		(start 325.388986 -400.149314)
		(end 325.192644 -400.345656)
		(width 0.11684)
		(layer "In6.Cu")
		(net "RST_RT_CPU0_P1_RESET_R_N")
	)
	(segment
		(start 332.972156 -400.633946)
		(end 332.972156 -399.420334)
		(width 0.11684)
		(layer "In6.Cu")
		(net "RST_RT_CPU0_P1_RESET_R_N")
	)
	(segment
		(start 326.468994 -398.05483)
		(end 325.388986 -399.134838)
		(width 0.11684)
		(layer "In6.Cu")
		(net "RST_RT_CPU0_P1_RESET_R_N")
	)
	(segment
		(start 332.972156 -399.420334)
		(end 331.606652 -398.05483)
		(width 0.11684)
		(layer "In6.Cu")
		(net "RST_RT_CPU0_P1_RESET_R_N")
	)
	(segment
		(start 293.10076 -406.069038)
		(end 289.64255 -406.069038)
		(width 0.11684)
		(layer "In6.Cu")
		(net "RST_RT_CPU0_P1_RESET_R_N")
	)
	(segment
		(start 323.905118 -402.377402)
		(end 322.0466 -404.23592)
		(width 0.11684)
		(layer "In6.Cu")
		(net "RST_RT_CPU0_P1_RESET_R_N")
	)
	(segment
		(start 325.388986 -399.134838)
		(end 325.388986 -400.149314)
		(width 0.11684)
		(layer "In6.Cu")
		(net "RST_RT_CPU0_P1_RESET_R_N")
	)
	(segment
		(start 331.606652 -398.05483)
		(end 326.468994 -398.05483)
		(width 0.11684)
		(layer "In6.Cu")
		(net "RST_RT_CPU0_P1_RESET_R_N")
	)
	(segment
		(start 318.641476 -404.23592)
		(end 302.612044 -410.87548)
		(width 0.11684)
		(layer "In6.Cu")
		(net "RST_RT_CPU0_P1_RESET_R_N")
	)
	(segment
		(start 302.612044 -410.87548)
		(end 301.94504 -410.87548)
		(width 0.11684)
		(layer "In6.Cu")
		(net "RST_RT_CPU0_P1_RESET_R_N")
	)
	(segment
		(start 295.677082 -408.64536)
		(end 293.10076 -406.069038)
		(width 0.11684)
		(layer "In6.Cu")
		(net "RST_RT_CPU0_P1_RESET_R_N")
	)
	(segment
		(start 325.05904 -402.377402)
		(end 323.905118 -402.377402)
		(width 0.11684)
		(layer "In6.Cu")
		(net "RST_RT_CPU0_P1_RESET_R_N")
	)
	(segment
		(start 283.181298 -385.25831)
		(end 284.63367 -386.710682)
		(width 0.11684)
		(layer "In13.Cu")
		(net "RST_RT_CPU0_P1_RESET_R_N")
	)
	(segment
		(start 284.64129 -389.145018)
		(end 286.24276 -390.746488)
		(width 0.11684)
		(layer "In13.Cu")
		(net "RST_RT_CPU0_P1_RESET_R_N")
	)
	(segment
		(start 286.24276 -396.10792)
		(end 287.133284 -396.998444)
		(width 0.11684)
		(layer "In13.Cu")
		(net "RST_RT_CPU0_P1_RESET_R_N")
	)
	(segment
		(start 284.63367 -389.145018)
		(end 284.64129 -389.145018)
		(width 0.11684)
		(layer "In13.Cu")
		(net "RST_RT_CPU0_P1_RESET_R_N")
	)
	(segment
		(start 254.64643 -345.948)
		(end 270.241522 -361.543092)
		(width 0.11684)
		(layer "In13.Cu")
		(net "RST_RT_CPU0_P1_RESET_R_N")
	)
	(segment
		(start 287.133284 -396.998444)
		(end 289.59302 -396.998444)
		(width 0.11684)
		(layer "In13.Cu")
		(net "RST_RT_CPU0_P1_RESET_R_N")
	)
	(segment
		(start 281.670252 -373.10187)
		(end 281.670252 -374.602502)
		(width 0.11684)
		(layer "In13.Cu")
		(net "RST_RT_CPU0_P1_RESET_R_N")
	)
	(segment
		(start 283.181298 -376.113548)
		(end 283.181298 -385.25831)
		(width 0.11684)
		(layer "In13.Cu")
		(net "RST_RT_CPU0_P1_RESET_R_N")
	)
	(segment
		(start 252.73 -345.948)
		(end 254.64643 -345.948)
		(width 0.11684)
		(layer "In13.Cu")
		(net "RST_RT_CPU0_P1_RESET_R_N")
	)
	(segment
		(start 290.428172 -406.069038)
		(end 289.64255 -406.069038)
		(width 0.11684)
		(layer "In13.Cu")
		(net "RST_RT_CPU0_P1_RESET_R_N")
	)
	(segment
		(start 271.379188 -365.224822)
		(end 273.793204 -365.224822)
		(width 0.11684)
		(layer "In13.Cu")
		(net "RST_RT_CPU0_P1_RESET_R_N")
	)
	(segment
		(start 273.793204 -365.224822)
		(end 281.670252 -373.10187)
		(width 0.11684)
		(layer "In13.Cu")
		(net "RST_RT_CPU0_P1_RESET_R_N")
	)
	(segment
		(start 289.59302 -396.998444)
		(end 292.500304 -399.905728)
		(width 0.11684)
		(layer "In13.Cu")
		(net "RST_RT_CPU0_P1_RESET_R_N")
	)
	(segment
		(start 270.241522 -361.543092)
		(end 270.241522 -364.087156)
		(width 0.11684)
		(layer "In13.Cu")
		(net "RST_RT_CPU0_P1_RESET_R_N")
	)
	(segment
		(start 270.241522 -364.087156)
		(end 271.379188 -365.224822)
		(width 0.11684)
		(layer "In13.Cu")
		(net "RST_RT_CPU0_P1_RESET_R_N")
	)
	(segment
		(start 281.670252 -374.602502)
		(end 283.181298 -376.113548)
		(width 0.11684)
		(layer "In13.Cu")
		(net "RST_RT_CPU0_P1_RESET_R_N")
	)
	(segment
		(start 292.500304 -403.996906)
		(end 290.428172 -406.069038)
		(width 0.11684)
		(layer "In13.Cu")
		(net "RST_RT_CPU0_P1_RESET_R_N")
	)
	(segment
		(start 286.24276 -390.746488)
		(end 286.24276 -396.10792)
		(width 0.11684)
		(layer "In13.Cu")
		(net "RST_RT_CPU0_P1_RESET_R_N")
	)
	(segment
		(start 284.63367 -386.710682)
		(end 284.63367 -389.145018)
		(width 0.11684)
		(layer "In13.Cu")
		(net "RST_RT_CPU0_P1_RESET_R_N")
	)
	(segment
		(start 292.500304 -399.905728)
		(end 292.500304 -403.996906)
		(width 0.11684)
		(layer "In13.Cu")
		(net "RST_RT_CPU0_P1_RESET_R_N")
	)
	(segment
		(start 185.922158 -119.452898)
		(end 186.312048 -119.842788)
		(width 0.10668)
		(layer "F.Cu")
		(net "RST_RT_CPU0_P1_RESET_R2_N")
	)
	(via
		(at 203.671678 -129.039874)
		(size 0.508)
		(drill 0.254)
		(layers "F.Cu" "B.Cu")
		(net "RST_RT_CPU0_P1_RESET_R2_N")
	)
	(via
		(at 186.312048 -119.842788)
		(size 0.4572)
		(drill 0.254)
		(layers "F.Cu" "B.Cu")
		(net "RST_RT_CPU0_P1_RESET_R2_N")
	)
	(segment
		(start 204.746098 -129.074164)
		(end 204.370432 -129.074164)
		(width 0.10668)
		(layer "B.Cu")
		(net "RST_RT_CPU0_P1_RESET_R2_N")
	)
	(segment
		(start 204.370432 -129.074164)
		(end 204.336142 -129.039874)
		(width 0.10668)
		(layer "B.Cu")
		(net "RST_RT_CPU0_P1_RESET_R2_N")
	)
	(segment
		(start 204.336142 -129.039874)
		(end 203.671678 -129.039874)
		(width 0.10668)
		(layer "B.Cu")
		(net "RST_RT_CPU0_P1_RESET_R2_N")
	)
	(segment
		(start 195.201286 -130.007868)
		(end 195.201286 -130.638804)
		(width 0.11684)
		(layer "In15.Cu")
		(net "RST_RT_CPU0_P1_RESET_R2_N")
	)
	(segment
		(start 188.04255 -128.854708)
		(end 194.048126 -128.854708)
		(width 0.11684)
		(layer "In15.Cu")
		(net "RST_RT_CPU0_P1_RESET_R2_N")
	)
	(segment
		(start 195.68033 -131.117848)
		(end 200.402698 -131.117848)
		(width 0.11684)
		(layer "In15.Cu")
		(net "RST_RT_CPU0_P1_RESET_R2_N")
	)
	(segment
		(start 200.402698 -131.117848)
		(end 202.480672 -129.039874)
		(width 0.11684)
		(layer "In15.Cu")
		(net "RST_RT_CPU0_P1_RESET_R2_N")
	)
	(segment
		(start 202.480672 -129.039874)
		(end 203.671678 -129.039874)
		(width 0.11684)
		(layer "In15.Cu")
		(net "RST_RT_CPU0_P1_RESET_R2_N")
	)
	(segment
		(start 185.912252 -126.72441)
		(end 188.04255 -128.854708)
		(width 0.11684)
		(layer "In15.Cu")
		(net "RST_RT_CPU0_P1_RESET_R2_N")
	)
	(segment
		(start 185.784744 -123.837954)
		(end 185.912252 -123.965462)
		(width 0.11684)
		(layer "In15.Cu")
		(net "RST_RT_CPU0_P1_RESET_R2_N")
	)
	(segment
		(start 186.312048 -119.842788)
		(end 185.784744 -120.370092)
		(width 0.11684)
		(layer "In15.Cu")
		(net "RST_RT_CPU0_P1_RESET_R2_N")
	)
	(segment
		(start 185.912252 -123.965462)
		(end 185.912252 -126.72441)
		(width 0.11684)
		(layer "In15.Cu")
		(net "RST_RT_CPU0_P1_RESET_R2_N")
	)
	(segment
		(start 194.048126 -128.854708)
		(end 195.201286 -130.007868)
		(width 0.11684)
		(layer "In15.Cu")
		(net "RST_RT_CPU0_P1_RESET_R2_N")
	)
	(segment
		(start 185.784744 -120.370092)
		(end 185.784744 -123.837954)
		(width 0.11684)
		(layer "In15.Cu")
		(net "RST_RT_CPU0_P1_RESET_R2_N")
	)
	(segment
		(start 195.201286 -130.638804)
		(end 195.68033 -131.117848)
		(width 0.11684)
		(layer "In15.Cu")
		(net "RST_RT_CPU0_P1_RESET_R2_N")
	)
	(segment
		(start 331.82306 -403.166326)
		(end 331.82306 -404.055326)
		(width 0.10668)
		(layer "F.Cu")
		(net "RST_RT_CPU0_P1_RESET_N")
	)
	(segment
		(start 332.250288 -402.362416)
		(end 332.250288 -403.018752)
		(width 0.10668)
		(layer "F.Cu")
		(net "RST_RT_CPU0_P1_RESET_N")
	)
	(segment
		(start 331.82306 -404.055326)
		(end 334.249522 -406.481788)
		(width 0.10668)
		(layer "F.Cu")
		(net "RST_RT_CPU0_P1_RESET_N")
	)
	(segment
		(start 332.390496 -402.222208)
		(end 332.250288 -402.362416)
		(width 0.10668)
		(layer "F.Cu")
		(net "RST_RT_CPU0_P1_RESET_N")
	)
	(segment
		(start 332.250288 -403.018752)
		(end 331.970634 -403.018752)
		(width 0.10668)
		(layer "F.Cu")
		(net "RST_RT_CPU0_P1_RESET_N")
	)
	(segment
		(start 331.970634 -403.018752)
		(end 331.82306 -403.166326)
		(width 0.10668)
		(layer "F.Cu")
		(net "RST_RT_CPU0_P1_RESET_N")
	)
	(segment
		(start 332.390496 -397.938498)
		(end 332.390496 -402.222208)
		(width 0.10668)
		(layer "F.Cu")
		(net "RST_RT_CPU0_P1_RESET_N")
	)
	(segment
		(start 333.215996 -397.112998)
		(end 332.390496 -397.938498)
		(width 0.10668)
		(layer "F.Cu")
		(net "RST_RT_CPU0_P1_RESET_N")
	)
	(segment
		(start 334.629252 -397.112998)
		(end 333.215996 -397.112998)
		(width 0.10668)
		(layer "F.Cu")
		(net "RST_RT_CPU0_P1_RESET_N")
	)
	(via
		(at 334.249522 -406.481788)
		(size 0.762)
		(drill 0.381)
		(layers "F.Cu" "B.Cu")
		(net "RST_RT_CPU0_P1_RESET_N")
	)
	(segment
		(start 183.76519 -135.403336)
		(end 183.437276 -135.73125)
		(width 0.10668)
		(layer "F.Cu")
		(net "RST_RT_CPU0_P1_PERST_R_N")
	)
	(segment
		(start 182.62219 -139.31011)
		(end 182.415434 -139.516866)
		(width 0.10668)
		(layer "F.Cu")
		(net "RST_RT_CPU0_P1_PERST_R_N")
	)
	(segment
		(start 356.69601 -403.0091)
		(end 356.401878 -403.0091)
		(width 0.10668)
		(layer "F.Cu")
		(net "RST_RT_CPU0_P1_PERST_R_N")
	)
	(segment
		(start 183.57342 -139.1031)
		(end 183.36641 -139.31011)
		(width 0.10668)
		(layer "F.Cu")
		(net "RST_RT_CPU0_P1_PERST_R_N")
	)
	(segment
		(start 184.583578 -134.667752)
		(end 184.583578 -135.174482)
		(width 0.10668)
		(layer "F.Cu")
		(net "RST_RT_CPU0_P1_PERST_R_N")
	)
	(segment
		(start 184.534048 -134.618222)
		(end 184.583578 -134.667752)
		(width 0.10668)
		(layer "F.Cu")
		(net "RST_RT_CPU0_P1_PERST_R_N")
	)
	(segment
		(start 244.244368 -208.721198)
		(end 245.25478 -207.710786)
		(width 0.10668)
		(layer "F.Cu")
		(net "RST_RT_CPU0_P1_PERST_R_N")
	)
	(segment
		(start 184.583578 -135.174482)
		(end 184.354724 -135.403336)
		(width 0.10668)
		(layer "F.Cu")
		(net "RST_RT_CPU0_P1_PERST_R_N")
	)
	(segment
		(start 356.26167 -401.357084)
		(end 356.420928 -401.197826)
		(width 0.10668)
		(layer "F.Cu")
		(net "RST_RT_CPU0_P1_PERST_R_N")
	)
	(segment
		(start 184.605422 -134.201916)
		(end 184.534048 -134.27329)
		(width 0.10668)
		(layer "F.Cu")
		(net "RST_RT_CPU0_P1_PERST_R_N")
	)
	(segment
		(start 189.701424 -142.532354)
		(end 191.592962 -142.532354)
		(width 0.10668)
		(layer "F.Cu")
		(net "RST_RT_CPU0_P1_PERST_R_N")
	)
	(segment
		(start 192.889378 -143.82877)
		(end 193.844164 -144.224248)
		(width 0.10668)
		(layer "F.Cu")
		(net "RST_RT_CPU0_P1_PERST_R_N")
	)
	(segment
		(start 184.605422 -133.965696)
		(end 184.605422 -134.201916)
		(width 0.10668)
		(layer "F.Cu")
		(net "RST_RT_CPU0_P1_PERST_R_N")
	)
	(segment
		(start 240.844578 -168.62679)
		(end 240.22304 -168.005252)
		(width 0.10668)
		(layer "F.Cu")
		(net "RST_RT_CPU0_P1_PERST_R_N")
	)
	(segment
		(start 240.22304 -168.005252)
		(end 239.12449 -168.005252)
		(width 0.10668)
		(layer "F.Cu")
		(net "RST_RT_CPU0_P1_PERST_R_N")
	)
	(segment
		(start 195.092574 -144.611598)
		(end 197.05701 -144.611598)
		(width 0.10668)
		(layer "F.Cu")
		(net "RST_RT_CPU0_P1_PERST_R_N")
	)
	(segment
		(start 188.952124 -141.783054)
		(end 189.701424 -142.532354)
		(width 0.10668)
		(layer "F.Cu")
		(net "RST_RT_CPU0_P1_PERST_R_N")
	)
	(segment
		(start 182.415434 -141.43101)
		(end 182.767478 -141.783054)
		(width 0.10668)
		(layer "F.Cu")
		(net "RST_RT_CPU0_P1_PERST_R_N")
	)
	(segment
		(start 356.26167 -402.868892)
		(end 356.26167 -401.357084)
		(width 0.10668)
		(layer "F.Cu")
		(net "RST_RT_CPU0_P1_PERST_R_N")
	)
	(segment
		(start 197.05701 -144.611598)
		(end 197.801738 -145.356326)
		(width 0.10668)
		(layer "F.Cu")
		(net "RST_RT_CPU0_P1_PERST_R_N")
	)
	(segment
		(start 194.157346 -144.224248)
		(end 195.092574 -144.611598)
		(width 0.10668)
		(layer "F.Cu")
		(net "RST_RT_CPU0_P1_PERST_R_N")
	)
	(segment
		(start 183.437276 -137.662666)
		(end 183.57342 -137.79881)
		(width 0.10668)
		(layer "F.Cu")
		(net "RST_RT_CPU0_P1_PERST_R_N")
	)
	(segment
		(start 356.401878 -403.0091)
		(end 356.26167 -402.868892)
		(width 0.10668)
		(layer "F.Cu")
		(net "RST_RT_CPU0_P1_PERST_R_N")
	)
	(segment
		(start 182.767478 -141.783054)
		(end 188.952124 -141.783054)
		(width 0.10668)
		(layer "F.Cu")
		(net "RST_RT_CPU0_P1_PERST_R_N")
	)
	(segment
		(start 239.985042 -171.087796)
		(end 240.844578 -170.22826)
		(width 0.10668)
		(layer "F.Cu")
		(net "RST_RT_CPU0_P1_PERST_R_N")
	)
	(segment
		(start 356.69601 -403.7457)
		(end 356.69601 -403.0091)
		(width 0.10668)
		(layer "F.Cu")
		(net "RST_RT_CPU0_P1_PERST_R_N")
	)
	(segment
		(start 238.14532 -167.026082)
		(end 238.14532 -166.610284)
		(width 0.10668)
		(layer "F.Cu")
		(net "RST_RT_CPU0_P1_PERST_R_N")
	)
	(segment
		(start 240.844578 -170.22826)
		(end 240.844578 -168.62679)
		(width 0.10668)
		(layer "F.Cu")
		(net "RST_RT_CPU0_P1_PERST_R_N")
	)
	(segment
		(start 239.985042 -177.556922)
		(end 239.985042 -171.087796)
		(width 0.10668)
		(layer "F.Cu")
		(net "RST_RT_CPU0_P1_PERST_R_N")
	)
	(segment
		(start 245.25478 -190.279274)
		(end 239.985042 -177.556922)
		(width 0.10668)
		(layer "F.Cu")
		(net "RST_RT_CPU0_P1_PERST_R_N")
	)
	(segment
		(start 183.36641 -139.31011)
		(end 182.62219 -139.31011)
		(width 0.10668)
		(layer "F.Cu")
		(net "RST_RT_CPU0_P1_PERST_R_N")
	)
	(segment
		(start 239.12449 -168.005252)
		(end 238.14532 -167.026082)
		(width 0.10668)
		(layer "F.Cu")
		(net "RST_RT_CPU0_P1_PERST_R_N")
	)
	(segment
		(start 183.437276 -135.73125)
		(end 183.437276 -137.662666)
		(width 0.10668)
		(layer "F.Cu")
		(net "RST_RT_CPU0_P1_PERST_R_N")
	)
	(segment
		(start 193.844164 -144.224248)
		(end 194.157346 -144.224248)
		(width 0.10668)
		(layer "F.Cu")
		(net "RST_RT_CPU0_P1_PERST_R_N")
	)
	(segment
		(start 183.57342 -137.79881)
		(end 183.57342 -139.1031)
		(width 0.10668)
		(layer "F.Cu")
		(net "RST_RT_CPU0_P1_PERST_R_N")
	)
	(segment
		(start 191.592962 -142.532354)
		(end 192.889378 -143.82877)
		(width 0.10668)
		(layer "F.Cu")
		(net "RST_RT_CPU0_P1_PERST_R_N")
	)
	(segment
		(start 184.354724 -135.403336)
		(end 183.76519 -135.403336)
		(width 0.10668)
		(layer "F.Cu")
		(net "RST_RT_CPU0_P1_PERST_R_N")
	)
	(segment
		(start 184.534048 -134.27329)
		(end 184.534048 -134.618222)
		(width 0.10668)
		(layer "F.Cu")
		(net "RST_RT_CPU0_P1_PERST_R_N")
	)
	(segment
		(start 182.415434 -139.516866)
		(end 182.415434 -141.43101)
		(width 0.10668)
		(layer "F.Cu")
		(net "RST_RT_CPU0_P1_PERST_R_N")
	)
	(segment
		(start 245.25478 -207.710786)
		(end 245.25478 -190.279274)
		(width 0.10668)
		(layer "F.Cu")
		(net "RST_RT_CPU0_P1_PERST_R_N")
	)
	(via
		(at 238.14532 -166.610284)
		(size 0.508)
		(drill 0.254)
		(layers "F.Cu" "B.Cu")
		(net "RST_RT_CPU0_P1_PERST_R_N")
	)
	(via
		(at 244.244368 -208.721198)
		(size 0.508)
		(drill 0.254)
		(layers "F.Cu" "B.Cu")
		(net "RST_RT_CPU0_P1_PERST_R_N")
	)
	(via
		(at 248.418604 -370.839492)
		(size 0.508)
		(drill 0.254)
		(layers "F.Cu" "B.Cu")
		(net "RST_RT_CPU0_P1_PERST_R_N")
	)
	(via
		(at 356.420928 -401.197826)
		(size 0.508)
		(drill 0.254)
		(layers "F.Cu" "B.Cu")
		(net "RST_RT_CPU0_P1_PERST_R_N")
	)
	(via
		(at 197.801738 -145.356326)
		(size 0.508)
		(drill 0.254)
		(layers "F.Cu" "B.Cu")
		(net "RST_RT_CPU0_P1_PERST_R_N")
	)
	(segment
		(start 328.356976 -383.181606)
		(end 326.545702 -383.181606)
		(width 0.11684)
		(layer "In2.Cu")
		(net "RST_RT_CPU0_P1_PERST_R_N")
	)
	(segment
		(start 355.74859 -400.433032)
		(end 355.74859 -394.47724)
		(width 0.11684)
		(layer "In2.Cu")
		(net "RST_RT_CPU0_P1_PERST_R_N")
	)
	(segment
		(start 356.420928 -401.10537)
		(end 355.74859 -400.433032)
		(width 0.11684)
		(layer "In2.Cu")
		(net "RST_RT_CPU0_P1_PERST_R_N")
	)
	(segment
		(start 354.284788 -392.571732)
		(end 352.230944 -392.571732)
		(width 0.11684)
		(layer "In2.Cu")
		(net "RST_RT_CPU0_P1_PERST_R_N")
	)
	(segment
		(start 352.230944 -392.571732)
		(end 351.49663 -391.837418)
		(width 0.11684)
		(layer "In2.Cu")
		(net "RST_RT_CPU0_P1_PERST_R_N")
	)
	(segment
		(start 355.45395 -393.740894)
		(end 354.284788 -392.571732)
		(width 0.11684)
		(layer "In2.Cu")
		(net "RST_RT_CPU0_P1_PERST_R_N")
	)
	(segment
		(start 355.45395 -394.1826)
		(end 355.45395 -393.740894)
		(width 0.11684)
		(layer "In2.Cu")
		(net "RST_RT_CPU0_P1_PERST_R_N")
	)
	(segment
		(start 325.492618 -383.665984)
		(end 324.06717 -385.091432)
		(width 0.11684)
		(layer "In2.Cu")
		(net "RST_RT_CPU0_P1_PERST_R_N")
	)
	(segment
		(start 329.073256 -386.535168)
		(end 328.75728 -386.219192)
		(width 0.11684)
		(layer "In2.Cu")
		(net "RST_RT_CPU0_P1_PERST_R_N")
	)
	(segment
		(start 248.741184 -370.839492)
		(end 248.418604 -370.839492)
		(width 0.11684)
		(layer "In2.Cu")
		(net "RST_RT_CPU0_P1_PERST_R_N")
	)
	(segment
		(start 326.545702 -383.181606)
		(end 326.061324 -383.665984)
		(width 0.11684)
		(layer "In2.Cu")
		(net "RST_RT_CPU0_P1_PERST_R_N")
	)
	(segment
		(start 351.49663 -391.837418)
		(end 351.49663 -390.679178)
		(width 0.11684)
		(layer "In2.Cu")
		(net "RST_RT_CPU0_P1_PERST_R_N")
	)
	(segment
		(start 297.77182 -381.268986)
		(end 297.77182 -378.6759)
		(width 0.11684)
		(layer "In2.Cu")
		(net "RST_RT_CPU0_P1_PERST_R_N")
	)
	(segment
		(start 355.74859 -394.47724)
		(end 355.45395 -394.1826)
		(width 0.11684)
		(layer "In2.Cu")
		(net "RST_RT_CPU0_P1_PERST_R_N")
	)
	(segment
		(start 328.75728 -383.58191)
		(end 328.356976 -383.181606)
		(width 0.11684)
		(layer "In2.Cu")
		(net "RST_RT_CPU0_P1_PERST_R_N")
	)
	(segment
		(start 326.061324 -383.665984)
		(end 325.492618 -383.665984)
		(width 0.11684)
		(layer "In2.Cu")
		(net "RST_RT_CPU0_P1_PERST_R_N")
	)
	(segment
		(start 334.274668 -386.535168)
		(end 329.073256 -386.535168)
		(width 0.11684)
		(layer "In2.Cu")
		(net "RST_RT_CPU0_P1_PERST_R_N")
	)
	(segment
		(start 351.49663 -390.679178)
		(end 347.679772 -386.86232)
		(width 0.11684)
		(layer "In2.Cu")
		(net "RST_RT_CPU0_P1_PERST_R_N")
	)
	(segment
		(start 334.60182 -386.86232)
		(end 334.274668 -386.535168)
		(width 0.11684)
		(layer "In2.Cu")
		(net "RST_RT_CPU0_P1_PERST_R_N")
	)
	(segment
		(start 347.679772 -386.86232)
		(end 334.60182 -386.86232)
		(width 0.11684)
		(layer "In2.Cu")
		(net "RST_RT_CPU0_P1_PERST_R_N")
	)
	(segment
		(start 248.812812 -370.91112)
		(end 248.741184 -370.839492)
		(width 0.11684)
		(layer "In2.Cu")
		(net "RST_RT_CPU0_P1_PERST_R_N")
	)
	(segment
		(start 282.217114 -376.124724)
		(end 277.00351 -370.91112)
		(width 0.11684)
		(layer "In2.Cu")
		(net "RST_RT_CPU0_P1_PERST_R_N")
	)
	(segment
		(start 296.59072 -377.4948)
		(end 289.35172 -377.4948)
		(width 0.11684)
		(layer "In2.Cu")
		(net "RST_RT_CPU0_P1_PERST_R_N")
	)
	(segment
		(start 287.981644 -376.124724)
		(end 282.217114 -376.124724)
		(width 0.11684)
		(layer "In2.Cu")
		(net "RST_RT_CPU0_P1_PERST_R_N")
	)
	(segment
		(start 289.35172 -377.4948)
		(end 287.981644 -376.124724)
		(width 0.11684)
		(layer "In2.Cu")
		(net "RST_RT_CPU0_P1_PERST_R_N")
	)
	(segment
		(start 277.00351 -370.91112)
		(end 248.812812 -370.91112)
		(width 0.11684)
		(layer "In2.Cu")
		(net "RST_RT_CPU0_P1_PERST_R_N")
	)
	(segment
		(start 328.75728 -386.219192)
		(end 328.75728 -383.58191)
		(width 0.11684)
		(layer "In2.Cu")
		(net "RST_RT_CPU0_P1_PERST_R_N")
	)
	(segment
		(start 356.420928 -401.197826)
		(end 356.420928 -401.10537)
		(width 0.11684)
		(layer "In2.Cu")
		(net "RST_RT_CPU0_P1_PERST_R_N")
	)
	(segment
		(start 324.06717 -385.091432)
		(end 301.594266 -385.091432)
		(width 0.11684)
		(layer "In2.Cu")
		(net "RST_RT_CPU0_P1_PERST_R_N")
	)
	(segment
		(start 297.77182 -378.6759)
		(end 296.59072 -377.4948)
		(width 0.11684)
		(layer "In2.Cu")
		(net "RST_RT_CPU0_P1_PERST_R_N")
	)
	(segment
		(start 301.594266 -385.091432)
		(end 297.77182 -381.268986)
		(width 0.11684)
		(layer "In2.Cu")
		(net "RST_RT_CPU0_P1_PERST_R_N")
	)
	(segment
		(start 255.50622 -322.035932)
		(end 257.043428 -320.498724)
		(width 0.11684)
		(layer "In4.Cu")
		(net "RST_RT_CPU0_P1_PERST_R_N")
	)
	(segment
		(start 251.371354 -353.035616)
		(end 257.043428 -347.363542)
		(width 0.11684)
		(layer "In4.Cu")
		(net "RST_RT_CPU0_P1_PERST_R_N")
	)
	(segment
		(start 245.243096 -208.721198)
		(end 244.244368 -208.721198)
		(width 0.11684)
		(layer "In4.Cu")
		(net "RST_RT_CPU0_P1_PERST_R_N")
	)
	(segment
		(start 251.371354 -367.794794)
		(end 251.371354 -353.035616)
		(width 0.11684)
		(layer "In4.Cu")
		(net "RST_RT_CPU0_P1_PERST_R_N")
	)
	(segment
		(start 255.50622 -328.676)
		(end 255.50622 -322.035932)
		(width 0.11684)
		(layer "In4.Cu")
		(net "RST_RT_CPU0_P1_PERST_R_N")
	)
	(segment
		(start 257.043428 -347.363542)
		(end 257.043428 -345.317572)
		(width 0.11684)
		(layer "In4.Cu")
		(net "RST_RT_CPU0_P1_PERST_R_N")
	)
	(segment
		(start 257.043428 -320.498724)
		(end 257.043428 -257.486658)
		(width 0.11684)
		(layer "In4.Cu")
		(net "RST_RT_CPU0_P1_PERST_R_N")
	)
	(segment
		(start 258.064 -344.297)
		(end 258.064 -331.851)
		(width 0.11684)
		(layer "In4.Cu")
		(net "RST_RT_CPU0_P1_PERST_R_N")
	)
	(segment
		(start 257.302 -331.089)
		(end 257.302 -330.47178)
		(width 0.11684)
		(layer "In4.Cu")
		(net "RST_RT_CPU0_P1_PERST_R_N")
	)
	(segment
		(start 248.418604 -370.747544)
		(end 251.371354 -367.794794)
		(width 0.11684)
		(layer "In4.Cu")
		(net "RST_RT_CPU0_P1_PERST_R_N")
	)
	(segment
		(start 258.064 -331.851)
		(end 257.302 -331.089)
		(width 0.11684)
		(layer "In4.Cu")
		(net "RST_RT_CPU0_P1_PERST_R_N")
	)
	(segment
		(start 248.418604 -370.839492)
		(end 248.418604 -370.747544)
		(width 0.11684)
		(layer "In4.Cu")
		(net "RST_RT_CPU0_P1_PERST_R_N")
	)
	(segment
		(start 257.043428 -345.317572)
		(end 258.064 -344.297)
		(width 0.11684)
		(layer "In4.Cu")
		(net "RST_RT_CPU0_P1_PERST_R_N")
	)
	(segment
		(start 248.52376 -212.001862)
		(end 245.243096 -208.721198)
		(width 0.11684)
		(layer "In4.Cu")
		(net "RST_RT_CPU0_P1_PERST_R_N")
	)
	(segment
		(start 257.043428 -257.486658)
		(end 248.52376 -248.96699)
		(width 0.11684)
		(layer "In4.Cu")
		(net "RST_RT_CPU0_P1_PERST_R_N")
	)
	(segment
		(start 257.302 -330.47178)
		(end 255.50622 -328.676)
		(width 0.11684)
		(layer "In4.Cu")
		(net "RST_RT_CPU0_P1_PERST_R_N")
	)
	(segment
		(start 248.52376 -248.96699)
		(end 248.52376 -212.001862)
		(width 0.11684)
		(layer "In4.Cu")
		(net "RST_RT_CPU0_P1_PERST_R_N")
	)
	(segment
		(start 232.862882 -161.31921)
		(end 214.392764 -161.31921)
		(width 0.11684)
		(layer "In15.Cu")
		(net "RST_RT_CPU0_P1_PERST_R_N")
	)
	(segment
		(start 198.42988 -145.356326)
		(end 197.801738 -145.356326)
		(width 0.11684)
		(layer "In15.Cu")
		(net "RST_RT_CPU0_P1_PERST_R_N")
	)
	(segment
		(start 238.14532 -166.601648)
		(end 232.862882 -161.31921)
		(width 0.11684)
		(layer "In15.Cu")
		(net "RST_RT_CPU0_P1_PERST_R_N")
	)
	(segment
		(start 238.14532 -166.610284)
		(end 238.14532 -166.601648)
		(width 0.11684)
		(layer "In15.Cu")
		(net "RST_RT_CPU0_P1_PERST_R_N")
	)
	(segment
		(start 214.392764 -161.31921)
		(end 198.42988 -145.356326)
		(width 0.11684)
		(layer "In15.Cu")
		(net "RST_RT_CPU0_P1_PERST_R_N")
	)
	(segment
		(start 184.530492 -133.090666)
		(end 184.530492 -128.690878)
		(width 0.10668)
		(layer "F.Cu")
		(net "RST_RT_CPU0_P1_PERST_R2_N")
	)
	(segment
		(start 184.605422 -133.165596)
		(end 184.530492 -133.090666)
		(width 0.10668)
		(layer "F.Cu")
		(net "RST_RT_CPU0_P1_PERST_R2_N")
	)
	(segment
		(start 184.416192 -126.60757)
		(end 184.732168 -126.291594)
		(width 0.10668)
		(layer "F.Cu")
		(net "RST_RT_CPU0_P1_PERST_R2_N")
	)
	(segment
		(start 184.530492 -128.690878)
		(end 184.657238 -128.564132)
		(width 0.10668)
		(layer "F.Cu")
		(net "RST_RT_CPU0_P1_PERST_R2_N")
	)
	(segment
		(start 184.732168 -126.291594)
		(end 184.732168 -123.84278)
		(width 0.10668)
		(layer "F.Cu")
		(net "RST_RT_CPU0_P1_PERST_R2_N")
	)
	(segment
		(start 184.657238 -127.524764)
		(end 184.416192 -127.283718)
		(width 0.10668)
		(layer "F.Cu")
		(net "RST_RT_CPU0_P1_PERST_R2_N")
	)
	(segment
		(start 184.416192 -127.283718)
		(end 184.416192 -126.60757)
		(width 0.10668)
		(layer "F.Cu")
		(net "RST_RT_CPU0_P1_PERST_R2_N")
	)
	(segment
		(start 185.122058 -123.45289)
		(end 184.732168 -123.84278)
		(width 0.10668)
		(layer "F.Cu")
		(net "RST_RT_CPU0_P1_PERST_R2_N")
	)
	(segment
		(start 184.657238 -128.564132)
		(end 184.657238 -127.524764)
		(width 0.10668)
		(layer "F.Cu")
		(net "RST_RT_CPU0_P1_PERST_R2_N")
	)
	(via
		(at 184.732168 -123.84278)
		(size 0.4572)
		(drill 0.254)
		(layers "F.Cu" "B.Cu")
		(net "RST_RT_CPU0_P1_PERST_R2_N")
	)
	(segment
		(start 356.69601 -404.673816)
		(end 356.401878 -404.967948)
		(width 0.10668)
		(layer "F.Cu")
		(net "RST_RT_CPU0_P1_PERST_N")
	)
	(segment
		(start 355.90099 -400.981672)
		(end 355.145594 -400.226276)
		(width 0.10668)
		(layer "F.Cu")
		(net "RST_RT_CPU0_P1_PERST_N")
	)
	(segment
		(start 355.145594 -400.226276)
		(end 355.145594 -399.143474)
		(width 0.10668)
		(layer "F.Cu")
		(net "RST_RT_CPU0_P1_PERST_N")
	)
	(segment
		(start 355.90099 -404.02764)
		(end 355.90099 -400.981672)
		(width 0.10668)
		(layer "F.Cu")
		(net "RST_RT_CPU0_P1_PERST_N")
	)
	(segment
		(start 356.69601 -404.2791)
		(end 356.69601 -404.673816)
		(width 0.10668)
		(layer "F.Cu")
		(net "RST_RT_CPU0_P1_PERST_N")
	)
	(segment
		(start 356.401878 -404.967948)
		(end 355.994208 -404.967948)
		(width 0.10668)
		(layer "F.Cu")
		(net "RST_RT_CPU0_P1_PERST_N")
	)
	(segment
		(start 356.69601 -404.2791)
		(end 356.15245 -404.2791)
		(width 0.10668)
		(layer "F.Cu")
		(net "RST_RT_CPU0_P1_PERST_N")
	)
	(segment
		(start 356.15245 -404.2791)
		(end 355.90099 -404.02764)
		(width 0.10668)
		(layer "F.Cu")
		(net "RST_RT_CPU0_P1_PERST_N")
	)
	(via
		(at 355.994208 -404.967948)
		(size 0.762)
		(drill 0.381)
		(layers "F.Cu" "B.Cu")
		(net "RST_RT_CPU0_P1_PERST_N")
	)
	(segment
		(start 297.004994 -397.4084)
		(end 297.287442 -397.4084)
		(width 0.10668)
		(layer "F.Cu")
		(net "RST_RT_CPU0_P0_RESET_R_N")
	)
	(segment
		(start 260.102858 -323.786246)
		(end 260.102858 -226.135692)
		(width 0.10668)
		(layer "F.Cu")
		(net "RST_RT_CPU0_P0_RESET_R_N")
	)
	(segment
		(start 260.102858 -226.135692)
		(end 247.03786 -213.070694)
		(width 0.10668)
		(layer "F.Cu")
		(net "RST_RT_CPU0_P0_RESET_R_N")
	)
	(segment
		(start 296.385742 -397.1417)
		(end 296.738294 -397.1417)
		(width 0.10668)
		(layer "F.Cu")
		(net "RST_RT_CPU0_P0_RESET_R_N")
	)
	(segment
		(start 243.195348 -180.6448)
		(end 243.195348 -169.8498)
		(width 0.10668)
		(layer "F.Cu")
		(net "RST_RT_CPU0_P0_RESET_R_N")
	)
	(segment
		(start 257.175 -330.962)
		(end 257.175 -326.714104)
		(width 0.10668)
		(layer "F.Cu")
		(net "RST_RT_CPU0_P0_RESET_R_N")
	)
	(segment
		(start 296.738294 -397.1417)
		(end 297.004994 -397.4084)
		(width 0.10668)
		(layer "F.Cu")
		(net "RST_RT_CPU0_P0_RESET_R_N")
	)
	(segment
		(start 257.175 -326.714104)
		(end 260.102858 -323.786246)
		(width 0.10668)
		(layer "F.Cu")
		(net "RST_RT_CPU0_P0_RESET_R_N")
	)
	(segment
		(start 296.385742 -397.1417)
		(end 296.385742 -396.603474)
		(width 0.10668)
		(layer "F.Cu")
		(net "RST_RT_CPU0_P0_RESET_R_N")
	)
	(segment
		(start 247.03786 -189.922404)
		(end 243.195348 -180.6448)
		(width 0.10668)
		(layer "F.Cu")
		(net "RST_RT_CPU0_P0_RESET_R_N")
	)
	(segment
		(start 297.287442 -397.4084)
		(end 297.287442 -398.2212)
		(width 0.10668)
		(layer "F.Cu")
		(net "RST_RT_CPU0_P0_RESET_R_N")
	)
	(segment
		(start 247.03786 -213.070694)
		(end 247.03786 -189.922404)
		(width 0.10668)
		(layer "F.Cu")
		(net "RST_RT_CPU0_P0_RESET_R_N")
	)
	(segment
		(start 258.064 -331.851)
		(end 257.175 -330.962)
		(width 0.10668)
		(layer "F.Cu")
		(net "RST_RT_CPU0_P0_RESET_R_N")
	)
	(segment
		(start 258.064 -345.694)
		(end 258.064 -331.851)
		(width 0.10668)
		(layer "F.Cu")
		(net "RST_RT_CPU0_P0_RESET_R_N")
	)
	(via
		(at 243.195348 -169.8498)
		(size 0.508)
		(drill 0.254)
		(layers "F.Cu" "B.Cu")
		(net "RST_RT_CPU0_P0_RESET_R_N")
	)
	(via
		(at 185.290206 -169.302938)
		(size 0.508)
		(drill 0.254)
		(layers "F.Cu" "B.Cu")
		(net "RST_RT_CPU0_P0_RESET_R_N")
	)
	(via
		(at 184.073038 -135.903462)
		(size 0.508)
		(drill 0.254)
		(layers "F.Cu" "B.Cu")
		(net "RST_RT_CPU0_P0_RESET_R_N")
	)
	(via
		(at 258.064 -345.694)
		(size 0.508)
		(drill 0.254)
		(layers "F.Cu" "B.Cu")
		(net "RST_RT_CPU0_P0_RESET_R_N")
	)
	(via
		(at 296.385742 -396.603474)
		(size 0.508)
		(drill 0.254)
		(layers "F.Cu" "B.Cu")
		(net "RST_RT_CPU0_P0_RESET_R_N")
	)
	(segment
		(start 184.573926 -135.402574)
		(end 184.073038 -135.903462)
		(width 0.10668)
		(layer "B.Cu")
		(net "RST_RT_CPU0_P0_RESET_R_N")
	)
	(segment
		(start 184.257696 -134.191502)
		(end 184.573926 -134.507732)
		(width 0.10668)
		(layer "B.Cu")
		(net "RST_RT_CPU0_P0_RESET_R_N")
	)
	(segment
		(start 184.573926 -134.507732)
		(end 184.573926 -135.402574)
		(width 0.10668)
		(layer "B.Cu")
		(net "RST_RT_CPU0_P0_RESET_R_N")
	)
	(segment
		(start 185.290206 -169.302938)
		(end 186.37123 -170.383962)
		(width 0.11684)
		(layer "In2.Cu")
		(net "RST_RT_CPU0_P0_RESET_R_N")
	)
	(segment
		(start 242.661186 -170.383962)
		(end 243.195348 -169.8498)
		(width 0.11684)
		(layer "In2.Cu")
		(net "RST_RT_CPU0_P0_RESET_R_N")
	)
	(segment
		(start 186.37123 -170.383962)
		(end 242.661186 -170.383962)
		(width 0.11684)
		(layer "In2.Cu")
		(net "RST_RT_CPU0_P0_RESET_R_N")
	)
	(segment
		(start 185.543952 -144.676876)
		(end 185.543952 -155.498292)
		(width 0.11684)
		(layer "In11.Cu")
		(net "RST_RT_CPU0_P0_RESET_R_N")
	)
	(segment
		(start 184.568338 -136.405366)
		(end 184.568338 -143.701262)
		(width 0.11684)
		(layer "In11.Cu")
		(net "RST_RT_CPU0_P0_RESET_R_N")
	)
	(segment
		(start 185.290206 -164.2491)
		(end 185.290206 -169.302938)
		(width 0.11684)
		(layer "In11.Cu")
		(net "RST_RT_CPU0_P0_RESET_R_N")
	)
	(segment
		(start 184.856374 -156.18968)
		(end 184.856374 -163.815268)
		(width 0.11684)
		(layer "In11.Cu")
		(net "RST_RT_CPU0_P0_RESET_R_N")
	)
	(segment
		(start 184.856374 -163.815268)
		(end 185.290206 -164.2491)
		(width 0.11684)
		(layer "In11.Cu")
		(net "RST_RT_CPU0_P0_RESET_R_N")
	)
	(segment
		(start 184.862724 -156.17952)
		(end 184.862724 -156.18333)
		(width 0.11684)
		(layer "In11.Cu")
		(net "RST_RT_CPU0_P0_RESET_R_N")
	)
	(segment
		(start 184.862724 -156.18333)
		(end 184.856374 -156.18968)
		(width 0.11684)
		(layer "In11.Cu")
		(net "RST_RT_CPU0_P0_RESET_R_N")
	)
	(segment
		(start 184.073038 -135.910066)
		(end 184.568338 -136.405366)
		(width 0.11684)
		(layer "In11.Cu")
		(net "RST_RT_CPU0_P0_RESET_R_N")
	)
	(segment
		(start 184.568338 -143.701262)
		(end 185.543952 -144.676876)
		(width 0.11684)
		(layer "In11.Cu")
		(net "RST_RT_CPU0_P0_RESET_R_N")
	)
	(segment
		(start 184.073038 -135.903462)
		(end 184.073038 -135.910066)
		(width 0.11684)
		(layer "In11.Cu")
		(net "RST_RT_CPU0_P0_RESET_R_N")
	)
	(segment
		(start 185.543952 -155.498292)
		(end 184.862724 -156.17952)
		(width 0.11684)
		(layer "In11.Cu")
		(net "RST_RT_CPU0_P0_RESET_R_N")
	)
	(segment
		(start 290.774374 -395.503146)
		(end 291.563806 -395.503146)
		(width 0.11684)
		(layer "In13.Cu")
		(net "RST_RT_CPU0_P0_RESET_R_N")
	)
	(segment
		(start 284.665928 -378.82703)
		(end 285.89859 -380.059692)
		(width 0.11684)
		(layer "In13.Cu")
		(net "RST_RT_CPU0_P0_RESET_R_N")
	)
	(segment
		(start 267.182092 -356.648512)
		(end 273.2024 -356.648512)
		(width 0.11684)
		(layer "In13.Cu")
		(net "RST_RT_CPU0_P0_RESET_R_N")
	)
	(segment
		(start 285.89859 -380.059692)
		(end 285.89859 -388.084568)
		(width 0.11684)
		(layer "In13.Cu")
		(net "RST_RT_CPU0_P0_RESET_R_N")
	)
	(segment
		(start 258.064 -347.53042)
		(end 267.182092 -356.648512)
		(width 0.11684)
		(layer "In13.Cu")
		(net "RST_RT_CPU0_P0_RESET_R_N")
	)
	(segment
		(start 281.699208 -370.69522)
		(end 282.769818 -370.69522)
		(width 0.11684)
		(layer "In13.Cu")
		(net "RST_RT_CPU0_P0_RESET_R_N")
	)
	(segment
		(start 291.563806 -395.503146)
		(end 292.664134 -396.603474)
		(width 0.11684)
		(layer "In13.Cu")
		(net "RST_RT_CPU0_P0_RESET_R_N")
	)
	(segment
		(start 287.689036 -392.417808)
		(end 290.774374 -395.503146)
		(width 0.11684)
		(layer "In13.Cu")
		(net "RST_RT_CPU0_P0_RESET_R_N")
	)
	(segment
		(start 284.793944 -375.552716)
		(end 284.665928 -375.680732)
		(width 0.11684)
		(layer "In13.Cu")
		(net "RST_RT_CPU0_P0_RESET_R_N")
	)
	(segment
		(start 273.51482 -356.960932)
		(end 273.51482 -362.510832)
		(width 0.11684)
		(layer "In13.Cu")
		(net "RST_RT_CPU0_P0_RESET_R_N")
	)
	(segment
		(start 273.2024 -356.648512)
		(end 273.51482 -356.960932)
		(width 0.11684)
		(layer "In13.Cu")
		(net "RST_RT_CPU0_P0_RESET_R_N")
	)
	(segment
		(start 284.665928 -375.680732)
		(end 284.665928 -378.82703)
		(width 0.11684)
		(layer "In13.Cu")
		(net "RST_RT_CPU0_P0_RESET_R_N")
	)
	(segment
		(start 273.51482 -362.510832)
		(end 281.699208 -370.69522)
		(width 0.11684)
		(layer "In13.Cu")
		(net "RST_RT_CPU0_P0_RESET_R_N")
	)
	(segment
		(start 285.89859 -388.084568)
		(end 287.689036 -389.875014)
		(width 0.11684)
		(layer "In13.Cu")
		(net "RST_RT_CPU0_P0_RESET_R_N")
	)
	(segment
		(start 282.769818 -370.69522)
		(end 284.793944 -372.719346)
		(width 0.11684)
		(layer "In13.Cu")
		(net "RST_RT_CPU0_P0_RESET_R_N")
	)
	(segment
		(start 258.064 -345.694)
		(end 258.064 -347.53042)
		(width 0.11684)
		(layer "In13.Cu")
		(net "RST_RT_CPU0_P0_RESET_R_N")
	)
	(segment
		(start 292.664134 -396.603474)
		(end 296.385742 -396.603474)
		(width 0.11684)
		(layer "In13.Cu")
		(net "RST_RT_CPU0_P0_RESET_R_N")
	)
	(segment
		(start 287.689036 -389.875014)
		(end 287.689036 -392.417808)
		(width 0.11684)
		(layer "In13.Cu")
		(net "RST_RT_CPU0_P0_RESET_R_N")
	)
	(segment
		(start 284.793944 -372.719346)
		(end 284.793944 -375.552716)
		(width 0.11684)
		(layer "In13.Cu")
		(net "RST_RT_CPU0_P0_RESET_R_N")
	)
	(segment
		(start 185.122058 -122.65279)
		(end 184.732168 -123.04268)
		(width 0.10668)
		(layer "F.Cu")
		(net "RST_RT_CPU0_P0_RESET_R2_N")
	)
	(via
		(at 184.732168 -123.04268)
		(size 0.4572)
		(drill 0.254)
		(layers "F.Cu" "B.Cu")
		(net "RST_RT_CPU0_P0_RESET_R2_N")
	)
	(via
		(at 184.7342 -128.3716)
		(size 0.6604)
		(drill 0.3302)
		(layers "F.Cu" "B.Cu")
		(net "RST_RT_CPU0_P0_RESET_R2_N")
	)
	(segment
		(start 184.510426 -129.043938)
		(end 184.7342 -128.820164)
		(width 0.10668)
		(layer "B.Cu")
		(net "RST_RT_CPU0_P0_RESET_R2_N")
	)
	(segment
		(start 184.510426 -129.911602)
		(end 184.510426 -129.043938)
		(width 0.10668)
		(layer "B.Cu")
		(net "RST_RT_CPU0_P0_RESET_R2_N")
	)
	(segment
		(start 184.565798 -129.966974)
		(end 184.510426 -129.911602)
		(width 0.10668)
		(layer "B.Cu")
		(net "RST_RT_CPU0_P0_RESET_R2_N")
	)
	(segment
		(start 184.565798 -133.0833)
		(end 184.565798 -129.966974)
		(width 0.10668)
		(layer "B.Cu")
		(net "RST_RT_CPU0_P0_RESET_R2_N")
	)
	(segment
		(start 185.13044 -123.30684)
		(end 185.13044 -127.97536)
		(width 0.10668)
		(layer "B.Cu")
		(net "RST_RT_CPU0_P0_RESET_R2_N")
	)
	(segment
		(start 184.7342 -128.820164)
		(end 184.7342 -128.3716)
		(width 0.10668)
		(layer "B.Cu")
		(net "RST_RT_CPU0_P0_RESET_R2_N")
	)
	(segment
		(start 184.86628 -123.04268)
		(end 185.13044 -123.30684)
		(width 0.10668)
		(layer "B.Cu")
		(net "RST_RT_CPU0_P0_RESET_R2_N")
	)
	(segment
		(start 184.732168 -123.04268)
		(end 184.86628 -123.04268)
		(width 0.10668)
		(layer "B.Cu")
		(net "RST_RT_CPU0_P0_RESET_R2_N")
	)
	(segment
		(start 184.257696 -133.391402)
		(end 184.565798 -133.0833)
		(width 0.10668)
		(layer "B.Cu")
		(net "RST_RT_CPU0_P0_RESET_R2_N")
	)
	(segment
		(start 185.13044 -127.97536)
		(end 184.7342 -128.3716)
		(width 0.10668)
		(layer "B.Cu")
		(net "RST_RT_CPU0_P0_RESET_R2_N")
	)
	(segment
		(start 298.304712 -397.34363)
		(end 298.304712 -397.73733)
		(width 0.10668)
		(layer "F.Cu")
		(net "RST_RT_CPU0_P0_RESET_N")
	)
	(segment
		(start 298.947586 -397.303244)
		(end 298.646342 -397.002)
		(width 0.10668)
		(layer "F.Cu")
		(net "RST_RT_CPU0_P0_RESET_N")
	)
	(segment
		(start 298.646342 -397.002)
		(end 298.304712 -397.34363)
		(width 0.10668)
		(layer "F.Cu")
		(net "RST_RT_CPU0_P0_RESET_N")
	)
	(segment
		(start 300.676056 -397.112998)
		(end 300.48581 -397.303244)
		(width 0.10668)
		(layer "F.Cu")
		(net "RST_RT_CPU0_P0_RESET_N")
	)
	(segment
		(start 302.101504 -397.112998)
		(end 300.676056 -397.112998)
		(width 0.10668)
		(layer "F.Cu")
		(net "RST_RT_CPU0_P0_RESET_N")
	)
	(segment
		(start 298.304712 -397.73733)
		(end 297.820842 -398.2212)
		(width 0.10668)
		(layer "F.Cu")
		(net "RST_RT_CPU0_P0_RESET_N")
	)
	(segment
		(start 300.48581 -397.303244)
		(end 298.947586 -397.303244)
		(width 0.10668)
		(layer "F.Cu")
		(net "RST_RT_CPU0_P0_RESET_N")
	)
	(via
		(at 298.646342 -397.002)
		(size 0.762)
		(drill 0.381)
		(layers "F.Cu" "B.Cu")
		(net "RST_RT_CPU0_P0_RESET_N")
	)
	(segment
		(start 170.774614 -120.464072)
		(end 170.113706 -120.464072)
		(width 0.10668)
		(layer "F.Cu")
		(net "RST_RT_CPU0_P0_PERST_R_N")
	)
	(segment
		(start 254.861314 -345.467686)
		(end 254.861314 -328.30389)
		(width 0.10668)
		(layer "F.Cu")
		(net "RST_RT_CPU0_P0_PERST_R_N")
	)
	(segment
		(start 324.168262 -403.0091)
		(end 323.87413 -403.0091)
		(width 0.10668)
		(layer "F.Cu")
		(net "RST_RT_CPU0_P0_PERST_R_N")
	)
	(segment
		(start 323.733922 -401.357084)
		(end 323.89318 -401.197826)
		(width 0.10668)
		(layer "F.Cu")
		(net "RST_RT_CPU0_P0_PERST_R_N")
	)
	(segment
		(start 242.407694 -179.686458)
		(end 242.407694 -167.69461)
		(width 0.10668)
		(layer "F.Cu")
		(net "RST_RT_CPU0_P0_PERST_R_N")
	)
	(segment
		(start 259.677662 -323.487542)
		(end 259.677662 -226.228656)
		(width 0.10668)
		(layer "F.Cu")
		(net "RST_RT_CPU0_P0_PERST_R_N")
	)
	(segment
		(start 253.492 -346.837)
		(end 254.861314 -345.467686)
		(width 0.10668)
		(layer "F.Cu")
		(net "RST_RT_CPU0_P0_PERST_R_N")
	)
	(segment
		(start 169.128948 -121.44883)
		(end 168.955466 -121.44883)
		(width 0.10668)
		(layer "F.Cu")
		(net "RST_RT_CPU0_P0_PERST_R_N")
	)
	(segment
		(start 168.955466 -121.44883)
		(end 167.69461 -122.709686)
		(width 0.10668)
		(layer "F.Cu")
		(net "RST_RT_CPU0_P0_PERST_R_N")
	)
	(segment
		(start 170.113706 -120.464072)
		(end 169.128948 -121.44883)
		(width 0.10668)
		(layer "F.Cu")
		(net "RST_RT_CPU0_P0_PERST_R_N")
	)
	(segment
		(start 254.861314 -328.30389)
		(end 259.677662 -323.487542)
		(width 0.10668)
		(layer "F.Cu")
		(net "RST_RT_CPU0_P0_PERST_R_N")
	)
	(segment
		(start 323.87413 -403.0091)
		(end 323.733922 -402.868892)
		(width 0.10668)
		(layer "F.Cu")
		(net "RST_RT_CPU0_P0_PERST_R_N")
	)
	(segment
		(start 259.677662 -226.228656)
		(end 246.67718 -213.228174)
		(width 0.10668)
		(layer "F.Cu")
		(net "RST_RT_CPU0_P0_PERST_R_N")
	)
	(segment
		(start 323.733922 -402.868892)
		(end 323.733922 -401.357084)
		(width 0.10668)
		(layer "F.Cu")
		(net "RST_RT_CPU0_P0_PERST_R_N")
	)
	(segment
		(start 246.67718 -189.99454)
		(end 242.407694 -179.686458)
		(width 0.10668)
		(layer "F.Cu")
		(net "RST_RT_CPU0_P0_PERST_R_N")
	)
	(segment
		(start 246.67718 -213.228174)
		(end 246.67718 -189.99454)
		(width 0.10668)
		(layer "F.Cu")
		(net "RST_RT_CPU0_P0_PERST_R_N")
	)
	(segment
		(start 324.168262 -403.7457)
		(end 324.168262 -403.0091)
		(width 0.10668)
		(layer "F.Cu")
		(net "RST_RT_CPU0_P0_PERST_R_N")
	)
	(via
		(at 242.407694 -167.69461)
		(size 0.508)
		(drill 0.254)
		(layers "F.Cu" "B.Cu")
		(net "RST_RT_CPU0_P0_PERST_R_N")
	)
	(via
		(at 323.89318 -401.197826)
		(size 0.508)
		(drill 0.254)
		(layers "F.Cu" "B.Cu")
		(net "RST_RT_CPU0_P0_PERST_R_N")
	)
	(via
		(at 167.69461 -122.709686)
		(size 0.508)
		(drill 0.254)
		(layers "F.Cu" "B.Cu")
		(net "RST_RT_CPU0_P0_PERST_R_N")
	)
	(via
		(at 253.492 -346.837)
		(size 0.508)
		(drill 0.254)
		(layers "F.Cu" "B.Cu")
		(net "RST_RT_CPU0_P0_PERST_R_N")
	)
	(via
		(at 289.667188 -405.24557)
		(size 0.508)
		(drill 0.254)
		(layers "F.Cu" "B.Cu")
		(net "RST_RT_CPU0_P0_PERST_R_N")
	)
	(via
		(at 179.06111 -162.246818)
		(size 0.508)
		(drill 0.254)
		(layers "F.Cu" "B.Cu")
		(net "RST_RT_CPU0_P0_PERST_R_N")
	)
	(segment
		(start 233.825542 -154.631898)
		(end 217.71102 -154.631898)
		(width 0.11684)
		(layer "In2.Cu")
		(net "RST_RT_CPU0_P0_PERST_R_N")
	)
	(segment
		(start 217.90533 -164.797232)
		(end 214.08644 -168.616122)
		(width 0.11684)
		(layer "In2.Cu")
		(net "RST_RT_CPU0_P0_PERST_R_N")
	)
	(segment
		(start 206.796386 -167.268398)
		(end 199.408796 -167.268398)
		(width 0.11684)
		(layer "In2.Cu")
		(net "RST_RT_CPU0_P0_PERST_R_N")
	)
	(segment
		(start 217.71102 -154.631898)
		(end 216.183464 -156.159454)
		(width 0.11684)
		(layer "In2.Cu")
		(net "RST_RT_CPU0_P0_PERST_R_N")
	)
	(segment
		(start 216.183464 -158.631128)
		(end 217.90533 -160.352994)
		(width 0.11684)
		(layer "In2.Cu")
		(net "RST_RT_CPU0_P0_PERST_R_N")
	)
	(segment
		(start 208.14411 -168.616122)
		(end 206.796386 -167.268398)
		(width 0.11684)
		(layer "In2.Cu")
		(net "RST_RT_CPU0_P0_PERST_R_N")
	)
	(segment
		(start 214.08644 -168.616122)
		(end 208.14411 -168.616122)
		(width 0.11684)
		(layer "In2.Cu")
		(net "RST_RT_CPU0_P0_PERST_R_N")
	)
	(segment
		(start 180.882036 -162.876738)
		(end 180.252116 -162.246818)
		(width 0.11684)
		(layer "In2.Cu")
		(net "RST_RT_CPU0_P0_PERST_R_N")
	)
	(segment
		(start 238.20755 -163.494466)
		(end 238.20755 -159.013906)
		(width 0.11684)
		(layer "In2.Cu")
		(net "RST_RT_CPU0_P0_PERST_R_N")
	)
	(segment
		(start 217.90533 -160.352994)
		(end 217.90533 -164.797232)
		(width 0.11684)
		(layer "In2.Cu")
		(net "RST_RT_CPU0_P0_PERST_R_N")
	)
	(segment
		(start 216.183464 -156.159454)
		(end 216.183464 -158.631128)
		(width 0.11684)
		(layer "In2.Cu")
		(net "RST_RT_CPU0_P0_PERST_R_N")
	)
	(segment
		(start 242.407694 -167.69461)
		(end 238.20755 -163.494466)
		(width 0.11684)
		(layer "In2.Cu")
		(net "RST_RT_CPU0_P0_PERST_R_N")
	)
	(segment
		(start 180.252116 -162.246818)
		(end 179.06111 -162.246818)
		(width 0.11684)
		(layer "In2.Cu")
		(net "RST_RT_CPU0_P0_PERST_R_N")
	)
	(segment
		(start 238.20755 -159.013906)
		(end 233.825542 -154.631898)
		(width 0.11684)
		(layer "In2.Cu")
		(net "RST_RT_CPU0_P0_PERST_R_N")
	)
	(segment
		(start 195.017136 -162.876738)
		(end 180.882036 -162.876738)
		(width 0.11684)
		(layer "In2.Cu")
		(net "RST_RT_CPU0_P0_PERST_R_N")
	)
	(segment
		(start 199.408796 -167.268398)
		(end 195.017136 -162.876738)
		(width 0.11684)
		(layer "In2.Cu")
		(net "RST_RT_CPU0_P0_PERST_R_N")
	)
	(segment
		(start 301.38624 -409.62834)
		(end 304.11293 -409.62834)
		(width 0.11684)
		(layer "In6.Cu")
		(net "RST_RT_CPU0_P0_PERST_R_N")
	)
	(segment
		(start 321.855846 -403.606)
		(end 323.89318 -401.568666)
		(width 0.11684)
		(layer "In6.Cu")
		(net "RST_RT_CPU0_P0_PERST_R_N")
	)
	(segment
		(start 293.41953 -405.24557)
		(end 296.31386 -408.1399)
		(width 0.11684)
		(layer "In6.Cu")
		(net "RST_RT_CPU0_P0_PERST_R_N")
	)
	(segment
		(start 304.11293 -409.62834)
		(end 318.652398 -403.606)
		(width 0.11684)
		(layer "In6.Cu")
		(net "RST_RT_CPU0_P0_PERST_R_N")
	)
	(segment
		(start 289.667188 -405.24557)
		(end 293.41953 -405.24557)
		(width 0.11684)
		(layer "In6.Cu")
		(net "RST_RT_CPU0_P0_PERST_R_N")
	)
	(segment
		(start 318.652398 -403.606)
		(end 321.855846 -403.606)
		(width 0.11684)
		(layer "In6.Cu")
		(net "RST_RT_CPU0_P0_PERST_R_N")
	)
	(segment
		(start 323.89318 -401.568666)
		(end 323.89318 -401.197826)
		(width 0.11684)
		(layer "In6.Cu")
		(net "RST_RT_CPU0_P0_PERST_R_N")
	)
	(segment
		(start 299.8978 -408.1399)
		(end 301.38624 -409.62834)
		(width 0.11684)
		(layer "In6.Cu")
		(net "RST_RT_CPU0_P0_PERST_R_N")
	)
	(segment
		(start 296.31386 -408.1399)
		(end 299.8978 -408.1399)
		(width 0.11684)
		(layer "In6.Cu")
		(net "RST_RT_CPU0_P0_PERST_R_N")
	)
	(segment
		(start 269.786862 -361.75696)
		(end 269.786862 -364.304326)
		(width 0.11684)
		(layer "In13.Cu")
		(net "RST_RT_CPU0_P0_PERST_R_N")
	)
	(segment
		(start 281.243786 -374.796812)
		(end 282.759658 -376.312684)
		(width 0.11684)
		(layer "In13.Cu")
		(net "RST_RT_CPU0_P0_PERST_R_N")
	)
	(segment
		(start 289.31997 -397.451072)
		(end 290.873434 -399.004536)
		(width 0.11684)
		(layer "In13.Cu")
		(net "RST_RT_CPU0_P0_PERST_R_N")
	)
	(segment
		(start 271.152112 -365.669576)
		(end 273.56943 -365.669576)
		(width 0.11684)
		(layer "In13.Cu")
		(net "RST_RT_CPU0_P0_PERST_R_N")
	)
	(segment
		(start 285.655766 -396.131542)
		(end 286.975296 -397.451072)
		(width 0.11684)
		(layer "In13.Cu")
		(net "RST_RT_CPU0_P0_PERST_R_N")
	)
	(segment
		(start 269.786862 -364.304326)
		(end 271.152112 -365.669576)
		(width 0.11684)
		(layer "In13.Cu")
		(net "RST_RT_CPU0_P0_PERST_R_N")
	)
	(segment
		(start 282.759658 -376.312684)
		(end 282.759658 -385.433316)
		(width 0.11684)
		(layer "In13.Cu")
		(net "RST_RT_CPU0_P0_PERST_R_N")
	)
	(segment
		(start 291.355018 -400.10461)
		(end 291.355018 -403.977602)
		(width 0.11684)
		(layer "In13.Cu")
		(net "RST_RT_CPU0_P0_PERST_R_N")
	)
	(segment
		(start 282.759658 -385.433316)
		(end 284.21203 -386.885688)
		(width 0.11684)
		(layer "In13.Cu")
		(net "RST_RT_CPU0_P0_PERST_R_N")
	)
	(segment
		(start 254.866902 -346.837)
		(end 269.786862 -361.75696)
		(width 0.11684)
		(layer "In13.Cu")
		(net "RST_RT_CPU0_P0_PERST_R_N")
	)
	(segment
		(start 281.243786 -373.343932)
		(end 281.243786 -374.796812)
		(width 0.11684)
		(layer "In13.Cu")
		(net "RST_RT_CPU0_P0_PERST_R_N")
	)
	(segment
		(start 285.655766 -390.901428)
		(end 285.655766 -396.131542)
		(width 0.11684)
		(layer "In13.Cu")
		(net "RST_RT_CPU0_P0_PERST_R_N")
	)
	(segment
		(start 284.21203 -389.457692)
		(end 285.655766 -390.901428)
		(width 0.11684)
		(layer "In13.Cu")
		(net "RST_RT_CPU0_P0_PERST_R_N")
	)
	(segment
		(start 253.492 -346.837)
		(end 254.866902 -346.837)
		(width 0.11684)
		(layer "In13.Cu")
		(net "RST_RT_CPU0_P0_PERST_R_N")
	)
	(segment
		(start 273.56943 -365.669576)
		(end 281.243786 -373.343932)
		(width 0.11684)
		(layer "In13.Cu")
		(net "RST_RT_CPU0_P0_PERST_R_N")
	)
	(segment
		(start 286.975296 -397.451072)
		(end 289.31997 -397.451072)
		(width 0.11684)
		(layer "In13.Cu")
		(net "RST_RT_CPU0_P0_PERST_R_N")
	)
	(segment
		(start 284.21203 -386.885688)
		(end 284.21203 -389.457692)
		(width 0.11684)
		(layer "In13.Cu")
		(net "RST_RT_CPU0_P0_PERST_R_N")
	)
	(segment
		(start 291.355018 -403.977602)
		(end 290.08705 -405.24557)
		(width 0.11684)
		(layer "In13.Cu")
		(net "RST_RT_CPU0_P0_PERST_R_N")
	)
	(segment
		(start 290.873434 -399.004536)
		(end 290.873434 -399.623026)
		(width 0.11684)
		(layer "In13.Cu")
		(net "RST_RT_CPU0_P0_PERST_R_N")
	)
	(segment
		(start 290.873434 -399.623026)
		(end 291.355018 -400.10461)
		(width 0.11684)
		(layer "In13.Cu")
		(net "RST_RT_CPU0_P0_PERST_R_N")
	)
	(segment
		(start 290.08705 -405.24557)
		(end 289.667188 -405.24557)
		(width 0.11684)
		(layer "In13.Cu")
		(net "RST_RT_CPU0_P0_PERST_R_N")
	)
	(segment
		(start 167.752776 -152.343358)
		(end 167.752776 -151.838152)
		(width 0.11684)
		(layer "In15.Cu")
		(net "RST_RT_CPU0_P0_PERST_R_N")
	)
	(segment
		(start 168.725088 -124.25934)
		(end 167.69461 -123.228862)
		(width 0.11684)
		(layer "In15.Cu")
		(net "RST_RT_CPU0_P0_PERST_R_N")
	)
	(segment
		(start 168.734486 -147.660106)
		(end 168.734486 -147.08759)
		(width 0.11684)
		(layer "In15.Cu")
		(net "RST_RT_CPU0_P0_PERST_R_N")
	)
	(segment
		(start 168.604946 -143.606012)
		(end 168.604946 -138.628374)
		(width 0.11684)
		(layer "In15.Cu")
		(net "RST_RT_CPU0_P0_PERST_R_N")
	)
	(segment
		(start 168.069514 -130.74396)
		(end 167.633396 -130.307842)
		(width 0.11684)
		(layer "In15.Cu")
		(net "RST_RT_CPU0_P0_PERST_R_N")
	)
	(segment
		(start 179.06111 -161.734754)
		(end 170.963844 -153.637488)
		(width 0.11684)
		(layer "In15.Cu")
		(net "RST_RT_CPU0_P0_PERST_R_N")
	)
	(segment
		(start 167.633396 -127.96139)
		(end 168.725088 -126.869698)
		(width 0.11684)
		(layer "In15.Cu")
		(net "RST_RT_CPU0_P0_PERST_R_N")
	)
	(segment
		(start 168.291002 -146.644106)
		(end 168.291002 -143.919956)
		(width 0.11684)
		(layer "In15.Cu")
		(net "RST_RT_CPU0_P0_PERST_R_N")
	)
	(segment
		(start 167.488616 -151.573992)
		(end 167.488616 -148.905976)
		(width 0.11684)
		(layer "In15.Cu")
		(net "RST_RT_CPU0_P0_PERST_R_N")
	)
	(segment
		(start 168.069514 -133.170168)
		(end 168.069514 -130.74396)
		(width 0.11684)
		(layer "In15.Cu")
		(net "RST_RT_CPU0_P0_PERST_R_N")
	)
	(segment
		(start 167.488616 -148.905976)
		(end 168.734486 -147.660106)
		(width 0.11684)
		(layer "In15.Cu")
		(net "RST_RT_CPU0_P0_PERST_R_N")
	)
	(segment
		(start 167.69461 -123.228862)
		(end 167.69461 -122.709686)
		(width 0.11684)
		(layer "In15.Cu")
		(net "RST_RT_CPU0_P0_PERST_R_N")
	)
	(segment
		(start 168.725088 -126.869698)
		(end 168.725088 -124.25934)
		(width 0.11684)
		(layer "In15.Cu")
		(net "RST_RT_CPU0_P0_PERST_R_N")
	)
	(segment
		(start 169.046906 -153.637488)
		(end 167.752776 -152.343358)
		(width 0.11684)
		(layer "In15.Cu")
		(net "RST_RT_CPU0_P0_PERST_R_N")
	)
	(segment
		(start 168.734486 -147.08759)
		(end 168.291002 -146.644106)
		(width 0.11684)
		(layer "In15.Cu")
		(net "RST_RT_CPU0_P0_PERST_R_N")
	)
	(segment
		(start 167.633396 -130.307842)
		(end 167.633396 -127.96139)
		(width 0.11684)
		(layer "In15.Cu")
		(net "RST_RT_CPU0_P0_PERST_R_N")
	)
	(segment
		(start 179.06111 -162.246818)
		(end 179.06111 -161.734754)
		(width 0.11684)
		(layer "In15.Cu")
		(net "RST_RT_CPU0_P0_PERST_R_N")
	)
	(segment
		(start 167.924734 -133.314948)
		(end 168.069514 -133.170168)
		(width 0.11684)
		(layer "In15.Cu")
		(net "RST_RT_CPU0_P0_PERST_R_N")
	)
	(segment
		(start 168.604946 -138.628374)
		(end 167.924734 -137.948162)
		(width 0.11684)
		(layer "In15.Cu")
		(net "RST_RT_CPU0_P0_PERST_R_N")
	)
	(segment
		(start 167.924734 -137.948162)
		(end 167.924734 -133.314948)
		(width 0.11684)
		(layer "In15.Cu")
		(net "RST_RT_CPU0_P0_PERST_R_N")
	)
	(segment
		(start 168.291002 -143.919956)
		(end 168.604946 -143.606012)
		(width 0.11684)
		(layer "In15.Cu")
		(net "RST_RT_CPU0_P0_PERST_R_N")
	)
	(segment
		(start 167.752776 -151.838152)
		(end 167.488616 -151.573992)
		(width 0.11684)
		(layer "In15.Cu")
		(net "RST_RT_CPU0_P0_PERST_R_N")
	)
	(segment
		(start 170.963844 -153.637488)
		(end 169.046906 -153.637488)
		(width 0.11684)
		(layer "In15.Cu")
		(net "RST_RT_CPU0_P0_PERST_R_N")
	)
	(segment
		(start 173.170088 -123.348242)
		(end 174.08652 -124.264674)
		(width 0.10668)
		(layer "F.Cu")
		(net "RST_RT_CPU0_P0_PERST_R2_N")
	)
	(segment
		(start 184.322212 -123.45289)
		(end 183.932322 -123.84278)
		(width 0.10668)
		(layer "F.Cu")
		(net "RST_RT_CPU0_P0_PERST_R2_N")
	)
	(segment
		(start 173.170088 -121.463562)
		(end 173.170088 -123.348242)
		(width 0.10668)
		(layer "F.Cu")
		(net "RST_RT_CPU0_P0_PERST_R2_N")
	)
	(segment
		(start 174.08652 -124.264674)
		(end 174.80407 -124.264674)
		(width 0.10668)
		(layer "F.Cu")
		(net "RST_RT_CPU0_P0_PERST_R2_N")
	)
	(segment
		(start 172.170598 -120.464072)
		(end 173.170088 -121.463562)
		(width 0.10668)
		(layer "F.Cu")
		(net "RST_RT_CPU0_P0_PERST_R2_N")
	)
	(segment
		(start 171.574714 -120.464072)
		(end 172.170598 -120.464072)
		(width 0.10668)
		(layer "F.Cu")
		(net "RST_RT_CPU0_P0_PERST_R2_N")
	)
	(segment
		(start 174.80407 -124.264674)
		(end 175.374808 -123.693936)
		(width 0.10668)
		(layer "F.Cu")
		(net "RST_RT_CPU0_P0_PERST_R2_N")
	)
	(via
		(at 183.932322 -123.84278)
		(size 0.4572)
		(drill 0.254)
		(layers "F.Cu" "B.Cu")
		(net "RST_RT_CPU0_P0_PERST_R2_N")
	)
	(via
		(at 175.374808 -123.693936)
		(size 0.508)
		(drill 0.254)
		(layers "F.Cu" "B.Cu")
		(net "RST_RT_CPU0_P0_PERST_R2_N")
	)
	(segment
		(start 175.628808 -123.439936)
		(end 178.549808 -123.439936)
		(width 0.11684)
		(layer "In6.Cu")
		(net "RST_RT_CPU0_P0_PERST_R2_N")
	)
	(segment
		(start 178.952652 -123.84278)
		(end 183.932322 -123.84278)
		(width 0.11684)
		(layer "In6.Cu")
		(net "RST_RT_CPU0_P0_PERST_R2_N")
	)
	(segment
		(start 175.374808 -123.693936)
		(end 175.628808 -123.439936)
		(width 0.11684)
		(layer "In6.Cu")
		(net "RST_RT_CPU0_P0_PERST_R2_N")
	)
	(segment
		(start 178.549808 -123.439936)
		(end 178.952652 -123.84278)
		(width 0.11684)
		(layer "In6.Cu")
		(net "RST_RT_CPU0_P0_PERST_R2_N")
	)
	(segment
		(start 324.168262 -404.2791)
		(end 324.168262 -404.673816)
		(width 0.10668)
		(layer "F.Cu")
		(net "RST_RT_CPU0_P0_PERST_N")
	)
	(segment
		(start 322.617846 -400.226276)
		(end 322.617846 -399.143474)
		(width 0.10668)
		(layer "F.Cu")
		(net "RST_RT_CPU0_P0_PERST_N")
	)
	(segment
		(start 324.168262 -404.673816)
		(end 323.833998 -405.00808)
		(width 0.10668)
		(layer "F.Cu")
		(net "RST_RT_CPU0_P0_PERST_N")
	)
	(segment
		(start 323.373242 -404.02764)
		(end 323.373242 -400.981672)
		(width 0.10668)
		(layer "F.Cu")
		(net "RST_RT_CPU0_P0_PERST_N")
	)
	(segment
		(start 323.624702 -404.2791)
		(end 323.373242 -404.02764)
		(width 0.10668)
		(layer "F.Cu")
		(net "RST_RT_CPU0_P0_PERST_N")
	)
	(segment
		(start 324.168262 -404.2791)
		(end 323.624702 -404.2791)
		(width 0.10668)
		(layer "F.Cu")
		(net "RST_RT_CPU0_P0_PERST_N")
	)
	(segment
		(start 323.833998 -405.00808)
		(end 323.21246 -405.00808)
		(width 0.10668)
		(layer "F.Cu")
		(net "RST_RT_CPU0_P0_PERST_N")
	)
	(segment
		(start 323.373242 -400.981672)
		(end 322.617846 -400.226276)
		(width 0.10668)
		(layer "F.Cu")
		(net "RST_RT_CPU0_P0_PERST_N")
	)
	(via
		(at 323.21246 -405.00808)
		(size 0.762)
		(drill 0.381)
		(layers "F.Cu" "B.Cu")
		(net "RST_RT_CPU0_P0_PERST_N")
	)
	(via
		(at 393.362434 -392.48588)
		(size 0.508)
		(drill 0.254)
		(layers "F.Cu" "B.Cu")
		(net "P1V8_CPU0_RT3_1A_1D")
	)
	(via
		(at 381.418338 -396.075662)
		(size 0.4064)
		(drill 0.2032)
		(layers "F.Cu" "B.Cu")
		(net "P1V8_CPU0_RT3_1A_1D")
	)
	(via
		(at 393.362434 -393.47648)
		(size 0.508)
		(drill 0.254)
		(layers "F.Cu" "B.Cu")
		(net "P1V8_CPU0_RT3_1A_1D")
	)
	(via
		(at 381.278384 -395.466062)
		(size 0.4064)
		(drill 0.2032)
		(layers "F.Cu" "B.Cu")
		(net "P1V8_CPU0_RT3_1A_1D")
	)
	(via
		(at 391.462514 -393.053062)
		(size 0.508)
		(drill 0.254)
		(layers "F.Cu" "B.Cu")
		(net "P1V8_CPU0_RT3_1A")
	)
	(via
		(at 377.678442 -395.466062)
		(size 0.4064)
		(drill 0.2032)
		(layers "F.Cu" "B.Cu")
		(net "P1V8_CPU0_RT3_1A")
	)
	(via
		(at 391.636504 -394.826744)
		(size 0.508)
		(drill 0.254)
		(layers "F.Cu" "B.Cu")
		(net "P1V8_CPU0_RT3_1A")
	)
	(via
		(at 392.562334 -392.48588)
		(size 0.508)
		(drill 0.254)
		(layers "F.Cu" "B.Cu")
		(net "P1V8_CPU0_RT3_1A")
	)
	(via
		(at 390.46658 -392.43508)
		(size 0.6604)
		(drill 0.3302)
		(layers "F.Cu" "B.Cu")
		(net "P1V8_CPU0_RT3_1A")
	)
	(via
		(at 390.999726 -394.2715)
		(size 0.508)
		(drill 0.254)
		(layers "F.Cu" "B.Cu")
		(net "P1V8_CPU0_RT3_1A")
	)
	(via
		(at 392.593576 -394.42263)
		(size 0.508)
		(drill 0.254)
		(layers "F.Cu" "B.Cu")
		(net "P1V8_CPU0_RT3_1A")
	)
	(via
		(at 379.018546 -396.075662)
		(size 0.4064)
		(drill 0.2032)
		(layers "F.Cu" "B.Cu")
		(net "P1V8_CPU0_RT3_1A")
	)
	(via
		(at 378.878592 -395.466062)
		(size 0.4064)
		(drill 0.2032)
		(layers "F.Cu" "B.Cu")
		(net "P1V8_CPU0_RT3_1A")
	)
	(via
		(at 392.562334 -393.47648)
		(size 0.508)
		(drill 0.254)
		(layers "F.Cu" "B.Cu")
		(net "P1V8_CPU0_RT3_1A")
	)
	(via
		(at 391.462514 -392.418062)
		(size 0.508)
		(drill 0.254)
		(layers "F.Cu" "B.Cu")
		(net "P1V8_CPU0_RT3_1A")
	)
	(via
		(at 380.078488 -395.466062)
		(size 0.4064)
		(drill 0.2032)
		(layers "F.Cu" "B.Cu")
		(net "P1V8_CPU0_RT3_1A")
	)
	(via
		(at 390.33958 -393.95146)
		(size 0.6604)
		(drill 0.3302)
		(layers "F.Cu" "B.Cu")
		(net "P1V8_CPU0_RT3_1A")
	)
	(via
		(at 391.462514 -393.688062)
		(size 0.508)
		(drill 0.254)
		(layers "F.Cu" "B.Cu")
		(net "P1V8_CPU0_RT3_1A")
	)
	(via
		(at 377.818396 -396.075662)
		(size 0.4064)
		(drill 0.2032)
		(layers "F.Cu" "B.Cu")
		(net "P1V8_CPU0_RT3_1A")
	)
	(via
		(at 380.218442 -396.075662)
		(size 0.4064)
		(drill 0.2032)
		(layers "F.Cu" "B.Cu")
		(net "P1V8_CPU0_RT3_1A")
	)
	(via
		(at 426.869606 -396.145004)
		(size 0.508)
		(drill 0.254)
		(layers "F.Cu" "B.Cu")
		(net "P1V8_CPU0_RT2_1A_1D")
	)
	(via
		(at 426.869606 -397.135604)
		(size 0.508)
		(drill 0.254)
		(layers "F.Cu" "B.Cu")
		(net "P1V8_CPU0_RT2_1A_1D")
	)
	(via
		(at 413.806132 -395.466062)
		(size 0.4064)
		(drill 0.2032)
		(layers "F.Cu" "B.Cu")
		(net "P1V8_CPU0_RT2_1A_1D")
	)
	(via
		(at 426.208952 -396.658846)
		(size 0.6604)
		(drill 0.3302)
		(layers "F.Cu" "B.Cu")
		(net "P1V8_CPU0_RT2_1A_1D")
	)
	(via
		(at 413.946086 -396.075662)
		(size 0.4064)
		(drill 0.2032)
		(layers "F.Cu" "B.Cu")
		(net "P1V8_CPU0_RT2_1A_1D")
	)
	(via
		(at 423.850562 -393.928092)
		(size 0.508)
		(drill 0.254)
		(layers "F.Cu" "B.Cu")
		(net "P1V8_CPU0_RT2_1A")
	)
	(via
		(at 411.546294 -396.075662)
		(size 0.4064)
		(drill 0.2032)
		(layers "F.Cu" "B.Cu")
		(net "P1V8_CPU0_RT2_1A")
	)
	(via
		(at 424.442636 -393.632436)
		(size 0.508)
		(drill 0.254)
		(layers "F.Cu" "B.Cu")
		(net "P1V8_CPU0_RT2_1A")
	)
	(via
		(at 424.442636 -395.537436)
		(size 0.508)
		(drill 0.254)
		(layers "F.Cu" "B.Cu")
		(net "P1V8_CPU0_RT2_1A")
	)
	(via
		(at 424.442636 -394.267436)
		(size 0.508)
		(drill 0.254)
		(layers "F.Cu" "B.Cu")
		(net "P1V8_CPU0_RT2_1A")
	)
	(via
		(at 411.40634 -395.466062)
		(size 0.4064)
		(drill 0.2032)
		(layers "F.Cu" "B.Cu")
		(net "P1V8_CPU0_RT2_1A")
	)
	(via
		(at 410.20619 -395.466062)
		(size 0.4064)
		(drill 0.2032)
		(layers "F.Cu" "B.Cu")
		(net "P1V8_CPU0_RT2_1A")
	)
	(via
		(at 412.74619 -396.075662)
		(size 0.4064)
		(drill 0.2032)
		(layers "F.Cu" "B.Cu")
		(net "P1V8_CPU0_RT2_1A")
	)
	(via
		(at 425.121324 -396.34795)
		(size 0.508)
		(drill 0.254)
		(layers "F.Cu" "B.Cu")
		(net "P1V8_CPU0_RT2_1A")
	)
	(via
		(at 410.346144 -396.075662)
		(size 0.4064)
		(drill 0.2032)
		(layers "F.Cu" "B.Cu")
		(net "P1V8_CPU0_RT2_1A")
	)
	(via
		(at 424.442636 -392.921236)
		(size 0.508)
		(drill 0.254)
		(layers "F.Cu" "B.Cu")
		(net "P1V8_CPU0_RT2_1A")
	)
	(via
		(at 412.606236 -395.466062)
		(size 0.4064)
		(drill 0.2032)
		(layers "F.Cu" "B.Cu")
		(net "P1V8_CPU0_RT2_1A")
	)
	(via
		(at 424.442636 -394.902436)
		(size 0.508)
		(drill 0.254)
		(layers "F.Cu" "B.Cu")
		(net "P1V8_CPU0_RT2_1A")
	)
	(via
		(at 423.882058 -394.601954)
		(size 0.508)
		(drill 0.254)
		(layers "F.Cu" "B.Cu")
		(net "P1V8_CPU0_RT2_1A")
	)
	(via
		(at 358.789986 -392.48588)
		(size 0.508)
		(drill 0.254)
		(layers "F.Cu" "B.Cu")
		(net "P1V8_CPU0_RT1_1A_1D")
	)
	(via
		(at 346.705936 -395.466062)
		(size 0.4064)
		(drill 0.2032)
		(layers "F.Cu" "B.Cu")
		(net "P1V8_CPU0_RT1_1A_1D")
	)
	(via
		(at 346.84589 -396.075662)
		(size 0.4064)
		(drill 0.2032)
		(layers "F.Cu" "B.Cu")
		(net "P1V8_CPU0_RT1_1A_1D")
	)
	(via
		(at 358.789986 -393.47648)
		(size 0.508)
		(drill 0.254)
		(layers "F.Cu" "B.Cu")
		(net "P1V8_CPU0_RT1_1A_1D")
	)
	(via
		(at 356.890066 -393.688062)
		(size 0.508)
		(drill 0.254)
		(layers "F.Cu" "B.Cu")
		(net "P1V8_CPU0_RT1_1A")
	)
	(via
		(at 345.50604 -395.466062)
		(size 0.4064)
		(drill 0.2032)
		(layers "F.Cu" "B.Cu")
		(net "P1V8_CPU0_RT1_1A")
	)
	(via
		(at 355.9048 -392.40968)
		(size 0.6604)
		(drill 0.3302)
		(layers "F.Cu" "B.Cu")
		(net "P1V8_CPU0_RT1_1A")
	)
	(via
		(at 356.890066 -393.053062)
		(size 0.508)
		(drill 0.254)
		(layers "F.Cu" "B.Cu")
		(net "P1V8_CPU0_RT1_1A")
	)
	(via
		(at 356.427278 -394.2715)
		(size 0.508)
		(drill 0.254)
		(layers "F.Cu" "B.Cu")
		(net "P1V8_CPU0_RT1_1A")
	)
	(via
		(at 343.105994 -395.466062)
		(size 0.4064)
		(drill 0.2032)
		(layers "F.Cu" "B.Cu")
		(net "P1V8_CPU0_RT1_1A")
	)
	(via
		(at 357.064056 -394.826744)
		(size 0.508)
		(drill 0.254)
		(layers "F.Cu" "B.Cu")
		(net "P1V8_CPU0_RT1_1A")
	)
	(via
		(at 344.446098 -396.075662)
		(size 0.4064)
		(drill 0.2032)
		(layers "F.Cu" "B.Cu")
		(net "P1V8_CPU0_RT1_1A")
	)
	(via
		(at 344.306144 -395.466062)
		(size 0.4064)
		(drill 0.2032)
		(layers "F.Cu" "B.Cu")
		(net "P1V8_CPU0_RT1_1A")
	)
	(via
		(at 345.645994 -396.075662)
		(size 0.4064)
		(drill 0.2032)
		(layers "F.Cu" "B.Cu")
		(net "P1V8_CPU0_RT1_1A")
	)
	(via
		(at 357.989886 -392.48588)
		(size 0.508)
		(drill 0.254)
		(layers "F.Cu" "B.Cu")
		(net "P1V8_CPU0_RT1_1A")
	)
	(via
		(at 343.245948 -396.075662)
		(size 0.4064)
		(drill 0.2032)
		(layers "F.Cu" "B.Cu")
		(net "P1V8_CPU0_RT1_1A")
	)
	(via
		(at 356.890066 -392.418062)
		(size 0.508)
		(drill 0.254)
		(layers "F.Cu" "B.Cu")
		(net "P1V8_CPU0_RT1_1A")
	)
	(via
		(at 357.989886 -393.47648)
		(size 0.508)
		(drill 0.254)
		(layers "F.Cu" "B.Cu")
		(net "P1V8_CPU0_RT1_1A")
	)
	(via
		(at 355.7651 -393.93876)
		(size 0.6604)
		(drill 0.3302)
		(layers "F.Cu" "B.Cu")
		(net "P1V8_CPU0_RT1_1A")
	)
	(via
		(at 358.021128 -394.42263)
		(size 0.508)
		(drill 0.254)
		(layers "F.Cu" "B.Cu")
		(net "P1V8_CPU0_RT1_1A")
	)
	(via
		(at 326.262238 -392.48588)
		(size 0.508)
		(drill 0.254)
		(layers "F.Cu" "B.Cu")
		(net "P1V8_CPU0_RT0_1A_1D")
	)
	(via
		(at 314.318142 -396.075662)
		(size 0.4064)
		(drill 0.2032)
		(layers "F.Cu" "B.Cu")
		(net "P1V8_CPU0_RT0_1A_1D")
	)
	(via
		(at 326.262238 -393.47648)
		(size 0.508)
		(drill 0.254)
		(layers "F.Cu" "B.Cu")
		(net "P1V8_CPU0_RT0_1A_1D")
	)
	(via
		(at 314.178188 -395.466062)
		(size 0.4064)
		(drill 0.2032)
		(layers "F.Cu" "B.Cu")
		(net "P1V8_CPU0_RT0_1A_1D")
	)
	(via
		(at 325.49338 -394.42263)
		(size 0.508)
		(drill 0.254)
		(layers "F.Cu" "B.Cu")
		(net "P1V8_CPU0_RT0_1A")
	)
	(via
		(at 311.91835 -396.075662)
		(size 0.4064)
		(drill 0.2032)
		(layers "F.Cu" "B.Cu")
		(net "P1V8_CPU0_RT0_1A")
	)
	(via
		(at 324.362318 -393.053062)
		(size 0.508)
		(drill 0.254)
		(layers "F.Cu" "B.Cu")
		(net "P1V8_CPU0_RT0_1A")
	)
	(via
		(at 325.462138 -392.48588)
		(size 0.508)
		(drill 0.254)
		(layers "F.Cu" "B.Cu")
		(net "P1V8_CPU0_RT0_1A")
	)
	(via
		(at 323.89953 -394.2715)
		(size 0.508)
		(drill 0.254)
		(layers "F.Cu" "B.Cu")
		(net "P1V8_CPU0_RT0_1A")
	)
	(via
		(at 323.34708 -392.4427)
		(size 0.6604)
		(drill 0.3302)
		(layers "F.Cu" "B.Cu")
		(net "P1V8_CPU0_RT0_1A")
	)
	(via
		(at 310.578246 -395.466062)
		(size 0.4064)
		(drill 0.2032)
		(layers "F.Cu" "B.Cu")
		(net "P1V8_CPU0_RT0_1A")
	)
	(via
		(at 310.7182 -396.075662)
		(size 0.4064)
		(drill 0.2032)
		(layers "F.Cu" "B.Cu")
		(net "P1V8_CPU0_RT0_1A")
	)
	(via
		(at 311.778396 -395.466062)
		(size 0.4064)
		(drill 0.2032)
		(layers "F.Cu" "B.Cu")
		(net "P1V8_CPU0_RT0_1A")
	)
	(via
		(at 313.118246 -396.075662)
		(size 0.4064)
		(drill 0.2032)
		(layers "F.Cu" "B.Cu")
		(net "P1V8_CPU0_RT0_1A")
	)
	(via
		(at 323.23278 -393.93114)
		(size 0.6604)
		(drill 0.3302)
		(layers "F.Cu" "B.Cu")
		(net "P1V8_CPU0_RT0_1A")
	)
	(via
		(at 324.536308 -394.826744)
		(size 0.508)
		(drill 0.254)
		(layers "F.Cu" "B.Cu")
		(net "P1V8_CPU0_RT0_1A")
	)
	(via
		(at 325.462138 -393.47648)
		(size 0.508)
		(drill 0.254)
		(layers "F.Cu" "B.Cu")
		(net "P1V8_CPU0_RT0_1A")
	)
	(via
		(at 312.978292 -395.466062)
		(size 0.4064)
		(drill 0.2032)
		(layers "F.Cu" "B.Cu")
		(net "P1V8_CPU0_RT0_1A")
	)
	(via
		(at 324.362318 -392.418062)
		(size 0.508)
		(drill 0.254)
		(layers "F.Cu" "B.Cu")
		(net "P1V8_CPU0_RT0_1A")
	)
	(via
		(at 324.362318 -393.688062)
		(size 0.508)
		(drill 0.254)
		(layers "F.Cu" "B.Cu")
		(net "P1V8_CPU0_RT0_1A")
	)
	(via
		(at 375.278396 -395.466062)
		(size 0.4064)
		(drill 0.2032)
		(layers "F.Cu" "B.Cu")
		(net "P0V9_CPU0_RT3_2A_2D")
	)
	(via
		(at 375.41835 -396.075662)
		(size 0.4064)
		(drill 0.2032)
		(layers "F.Cu" "B.Cu")
		(net "P0V9_CPU0_RT3_2A_2D")
	)
	(via
		(at 383.818384 -396.075662)
		(size 0.4064)
		(drill 0.2032)
		(layers "F.Cu" "B.Cu")
		(net "P0V9_CPU0_RT3_2A_2D")
	)
	(via
		(at 363.111034 -402.550376)
		(size 0.508)
		(drill 0.254)
		(layers "F.Cu" "B.Cu")
		(net "P0V9_CPU0_RT3_2A_2D")
	)
	(via
		(at 363.725206 -402.361146)
		(size 0.508)
		(drill 0.254)
		(layers "F.Cu" "B.Cu")
		(net "P0V9_CPU0_RT3_2A_2D")
	)
	(via
		(at 363.725206 -401.624546)
		(size 0.508)
		(drill 0.254)
		(layers "F.Cu" "B.Cu")
		(net "P0V9_CPU0_RT3_2A_2D")
	)
	(via
		(at 364.361476 -402.550376)
		(size 0.508)
		(drill 0.254)
		(layers "F.Cu" "B.Cu")
		(net "P0V9_CPU0_RT3_2A_2D")
	)
	(via
		(at 383.67843 -395.466062)
		(size 0.4064)
		(drill 0.2032)
		(layers "F.Cu" "B.Cu")
		(net "P0V9_CPU0_RT3_2A_2D")
	)
	(via
		(at 363.723174 -403.081236)
		(size 0.6604)
		(drill 0.3302)
		(layers "F.Cu" "B.Cu")
		(net "P0V9_CPU0_RT3_2A_2D")
	)
	(via
		(at 365.226854 -401.26793)
		(size 0.508)
		(drill 0.254)
		(layers "F.Cu" "B.Cu")
		(net "P0V9_CPU0_RT3_2A")
	)
	(via
		(at 364.591854 -400.63293)
		(size 0.508)
		(drill 0.254)
		(layers "F.Cu" "B.Cu")
		(net "P0V9_CPU0_RT3_2A")
	)
	(via
		(at 385.092956 -404.666196)
		(size 0.6604)
		(drill 0.3302)
		(layers "F.Cu" "B.Cu")
		(net "P0V9_CPU0_RT3_2A")
	)
	(via
		(at 384.87858 -395.466062)
		(size 0.4064)
		(drill 0.2032)
		(layers "F.Cu" "B.Cu")
		(net "P0V9_CPU0_RT3_2A")
	)
	(via
		(at 364.591854 -401.90293)
		(size 0.508)
		(drill 0.254)
		(layers "F.Cu" "B.Cu")
		(net "P0V9_CPU0_RT3_2A")
	)
	(via
		(at 371.818408 -396.075662)
		(size 0.4064)
		(drill 0.2032)
		(layers "F.Cu" "B.Cu")
		(net "P0V9_CPU0_RT3_2A")
	)
	(via
		(at 366.496854 -399.99793)
		(size 0.508)
		(drill 0.254)
		(layers "F.Cu" "B.Cu")
		(net "P0V9_CPU0_RT3_2A")
	)
	(via
		(at 371.678454 -395.466062)
		(size 0.4064)
		(drill 0.2032)
		(layers "F.Cu" "B.Cu")
		(net "P0V9_CPU0_RT3_2A")
	)
	(via
		(at 370.478558 -395.466062)
		(size 0.4064)
		(drill 0.2032)
		(layers "F.Cu" "B.Cu")
		(net "P0V9_CPU0_RT3_2A")
	)
	(via
		(at 388.618476 -396.075662)
		(size 0.4064)
		(drill 0.2032)
		(layers "F.Cu" "B.Cu")
		(net "P0V9_CPU0_RT3_2A")
	)
	(via
		(at 366.496854 -401.26793)
		(size 0.508)
		(drill 0.254)
		(layers "F.Cu" "B.Cu")
		(net "P0V9_CPU0_RT3_2A")
	)
	(via
		(at 365.226854 -400.63293)
		(size 0.508)
		(drill 0.254)
		(layers "F.Cu" "B.Cu")
		(net "P0V9_CPU0_RT3_2A")
	)
	(via
		(at 386.21843 -396.075662)
		(size 0.4064)
		(drill 0.2032)
		(layers "F.Cu" "B.Cu")
		(net "P0V9_CPU0_RT3_2A")
	)
	(via
		(at 390.370822 -404.772622)
		(size 0.6604)
		(drill 0.3302)
		(layers "F.Cu" "B.Cu")
		(net "P0V9_CPU0_RT3_2A")
	)
	(via
		(at 386.078476 -395.466062)
		(size 0.4064)
		(drill 0.2032)
		(layers "F.Cu" "B.Cu")
		(net "P0V9_CPU0_RT3_2A")
	)
	(via
		(at 373.899684 -404.59533)
		(size 0.6604)
		(drill 0.3302)
		(layers "F.Cu" "B.Cu")
		(net "P0V9_CPU0_RT3_2A")
	)
	(via
		(at 365.861854 -401.26793)
		(size 0.508)
		(drill 0.254)
		(layers "F.Cu" "B.Cu")
		(net "P0V9_CPU0_RT3_2A")
	)
	(via
		(at 364.591854 -401.26793)
		(size 0.508)
		(drill 0.254)
		(layers "F.Cu" "B.Cu")
		(net "P0V9_CPU0_RT3_2A")
	)
	(via
		(at 366.496854 -401.90293)
		(size 0.508)
		(drill 0.254)
		(layers "F.Cu" "B.Cu")
		(net "P0V9_CPU0_RT3_2A")
	)
	(via
		(at 388.478522 -395.466062)
		(size 0.4064)
		(drill 0.2032)
		(layers "F.Cu" "B.Cu")
		(net "P0V9_CPU0_RT3_2A")
	)
	(via
		(at 366.496854 -400.63293)
		(size 0.508)
		(drill 0.254)
		(layers "F.Cu" "B.Cu")
		(net "P0V9_CPU0_RT3_2A")
	)
	(via
		(at 365.861854 -400.63293)
		(size 0.508)
		(drill 0.254)
		(layers "F.Cu" "B.Cu")
		(net "P0V9_CPU0_RT3_2A")
	)
	(via
		(at 373.018558 -396.075662)
		(size 0.4064)
		(drill 0.2032)
		(layers "F.Cu" "B.Cu")
		(net "P0V9_CPU0_RT3_2A")
	)
	(via
		(at 378.894086 -404.737062)
		(size 0.6604)
		(drill 0.3302)
		(layers "F.Cu" "B.Cu")
		(net "P0V9_CPU0_RT3_2A")
	)
	(via
		(at 365.861854 -401.90293)
		(size 0.508)
		(drill 0.254)
		(layers "F.Cu" "B.Cu")
		(net "P0V9_CPU0_RT3_2A")
	)
	(via
		(at 364.591854 -399.99793)
		(size 0.508)
		(drill 0.254)
		(layers "F.Cu" "B.Cu")
		(net "P0V9_CPU0_RT3_2A")
	)
	(via
		(at 370.618512 -396.075662)
		(size 0.4064)
		(drill 0.2032)
		(layers "F.Cu" "B.Cu")
		(net "P0V9_CPU0_RT3_2A")
	)
	(via
		(at 365.226854 -399.99793)
		(size 0.508)
		(drill 0.254)
		(layers "F.Cu" "B.Cu")
		(net "P0V9_CPU0_RT3_2A")
	)
	(via
		(at 374.0785 -395.466062)
		(size 0.4064)
		(drill 0.2032)
		(layers "F.Cu" "B.Cu")
		(net "P0V9_CPU0_RT3_2A")
	)
	(via
		(at 365.226854 -401.90293)
		(size 0.508)
		(drill 0.254)
		(layers "F.Cu" "B.Cu")
		(net "P0V9_CPU0_RT3_2A")
	)
	(via
		(at 365.861854 -399.99793)
		(size 0.508)
		(drill 0.254)
		(layers "F.Cu" "B.Cu")
		(net "P0V9_CPU0_RT3_2A")
	)
	(via
		(at 369.649248 -404.63089)
		(size 0.6604)
		(drill 0.3302)
		(layers "F.Cu" "B.Cu")
		(net "P0V9_CPU0_RT3_2A")
	)
	(via
		(at 387.278626 -395.466062)
		(size 0.4064)
		(drill 0.2032)
		(layers "F.Cu" "B.Cu")
		(net "P0V9_CPU0_RT3_2A")
	)
	(via
		(at 387.41858 -396.075662)
		(size 0.4064)
		(drill 0.2032)
		(layers "F.Cu" "B.Cu")
		(net "P0V9_CPU0_RT3_2A")
	)
	(via
		(at 385.018534 -396.075662)
		(size 0.4064)
		(drill 0.2032)
		(layers "F.Cu" "B.Cu")
		(net "P0V9_CPU0_RT3_2A")
	)
	(via
		(at 372.878604 -395.466062)
		(size 0.4064)
		(drill 0.2032)
		(layers "F.Cu" "B.Cu")
		(net "P0V9_CPU0_RT3_2A")
	)
	(via
		(at 374.218454 -396.075662)
		(size 0.4064)
		(drill 0.2032)
		(layers "F.Cu" "B.Cu")
		(net "P0V9_CPU0_RT3_2A")
	)
	(via
		(at 396.252954 -401.624546)
		(size 0.508)
		(drill 0.254)
		(layers "F.Cu" "B.Cu")
		(net "P0V9_CPU0_RT2_2A_2D")
	)
	(via
		(at 396.889224 -402.550376)
		(size 0.508)
		(drill 0.254)
		(layers "F.Cu" "B.Cu")
		(net "P0V9_CPU0_RT2_2A_2D")
	)
	(via
		(at 407.806144 -395.466062)
		(size 0.4064)
		(drill 0.2032)
		(layers "F.Cu" "B.Cu")
		(net "P0V9_CPU0_RT2_2A_2D")
	)
	(via
		(at 395.638782 -402.550376)
		(size 0.508)
		(drill 0.254)
		(layers "F.Cu" "B.Cu")
		(net "P0V9_CPU0_RT2_2A_2D")
	)
	(via
		(at 396.250922 -403.081236)
		(size 0.6604)
		(drill 0.3302)
		(layers "F.Cu" "B.Cu")
		(net "P0V9_CPU0_RT2_2A_2D")
	)
	(via
		(at 416.206178 -395.466062)
		(size 0.4064)
		(drill 0.2032)
		(layers "F.Cu" "B.Cu")
		(net "P0V9_CPU0_RT2_2A_2D")
	)
	(via
		(at 407.946098 -396.075662)
		(size 0.4064)
		(drill 0.2032)
		(layers "F.Cu" "B.Cu")
		(net "P0V9_CPU0_RT2_2A_2D")
	)
	(via
		(at 396.252954 -402.361146)
		(size 0.508)
		(drill 0.254)
		(layers "F.Cu" "B.Cu")
		(net "P0V9_CPU0_RT2_2A_2D")
	)
	(via
		(at 416.346132 -396.075662)
		(size 0.4064)
		(drill 0.2032)
		(layers "F.Cu" "B.Cu")
		(net "P0V9_CPU0_RT2_2A_2D")
	)
	(via
		(at 421.146224 -396.075662)
		(size 0.4064)
		(drill 0.2032)
		(layers "F.Cu" "B.Cu")
		(net "P0V9_CPU0_RT2_2A")
	)
	(via
		(at 398.389602 -401.90293)
		(size 0.508)
		(drill 0.254)
		(layers "F.Cu" "B.Cu")
		(net "P0V9_CPU0_RT2_2A")
	)
	(via
		(at 399.024602 -400.63293)
		(size 0.508)
		(drill 0.254)
		(layers "F.Cu" "B.Cu")
		(net "P0V9_CPU0_RT2_2A")
	)
	(via
		(at 397.119602 -400.63293)
		(size 0.508)
		(drill 0.254)
		(layers "F.Cu" "B.Cu")
		(net "P0V9_CPU0_RT2_2A")
	)
	(via
		(at 419.946328 -396.075662)
		(size 0.4064)
		(drill 0.2032)
		(layers "F.Cu" "B.Cu")
		(net "P0V9_CPU0_RT2_2A")
	)
	(via
		(at 424.435524 -399.222976)
		(size 0.508)
		(drill 0.254)
		(layers "F.Cu" "B.Cu")
		(net "P0V9_CPU0_RT2_2A")
	)
	(via
		(at 418.746178 -396.075662)
		(size 0.4064)
		(drill 0.2032)
		(layers "F.Cu" "B.Cu")
		(net "P0V9_CPU0_RT2_2A")
	)
	(via
		(at 417.546282 -396.075662)
		(size 0.4064)
		(drill 0.2032)
		(layers "F.Cu" "B.Cu")
		(net "P0V9_CPU0_RT2_2A")
	)
	(via
		(at 399.024602 -401.26793)
		(size 0.508)
		(drill 0.254)
		(layers "F.Cu" "B.Cu")
		(net "P0V9_CPU0_RT2_2A")
	)
	(via
		(at 398.389602 -401.26793)
		(size 0.508)
		(drill 0.254)
		(layers "F.Cu" "B.Cu")
		(net "P0V9_CPU0_RT2_2A")
	)
	(via
		(at 404.206202 -395.466062)
		(size 0.4064)
		(drill 0.2032)
		(layers "F.Cu" "B.Cu")
		(net "P0V9_CPU0_RT2_2A")
	)
	(via
		(at 405.546306 -396.075662)
		(size 0.4064)
		(drill 0.2032)
		(layers "F.Cu" "B.Cu")
		(net "P0V9_CPU0_RT2_2A")
	)
	(via
		(at 403.006306 -395.466062)
		(size 0.4064)
		(drill 0.2032)
		(layers "F.Cu" "B.Cu")
		(net "P0V9_CPU0_RT2_2A")
	)
	(via
		(at 421.00627 -395.466062)
		(size 0.4064)
		(drill 0.2032)
		(layers "F.Cu" "B.Cu")
		(net "P0V9_CPU0_RT2_2A")
	)
	(via
		(at 404.346156 -396.075662)
		(size 0.4064)
		(drill 0.2032)
		(layers "F.Cu" "B.Cu")
		(net "P0V9_CPU0_RT2_2A")
	)
	(via
		(at 397.754602 -400.63293)
		(size 0.508)
		(drill 0.254)
		(layers "F.Cu" "B.Cu")
		(net "P0V9_CPU0_RT2_2A")
	)
	(via
		(at 406.746202 -396.075662)
		(size 0.4064)
		(drill 0.2032)
		(layers "F.Cu" "B.Cu")
		(net "P0V9_CPU0_RT2_2A")
	)
	(via
		(at 423.881804 -399.541492)
		(size 0.508)
		(drill 0.254)
		(layers "F.Cu" "B.Cu")
		(net "P0V9_CPU0_RT2_2A")
	)
	(via
		(at 400.448272 -404.081742)
		(size 0.6604)
		(drill 0.3302)
		(layers "F.Cu" "B.Cu")
		(net "P0V9_CPU0_RT2_2A")
	)
	(via
		(at 406.606248 -395.466062)
		(size 0.4064)
		(drill 0.2032)
		(layers "F.Cu" "B.Cu")
		(net "P0V9_CPU0_RT2_2A")
	)
	(via
		(at 417.406328 -395.466062)
		(size 0.4064)
		(drill 0.2032)
		(layers "F.Cu" "B.Cu")
		(net "P0V9_CPU0_RT2_2A")
	)
	(via
		(at 397.754602 -399.99793)
		(size 0.508)
		(drill 0.254)
		(layers "F.Cu" "B.Cu")
		(net "P0V9_CPU0_RT2_2A")
	)
	(via
		(at 418.606224 -395.466062)
		(size 0.4064)
		(drill 0.2032)
		(layers "F.Cu" "B.Cu")
		(net "P0V9_CPU0_RT2_2A")
	)
	(via
		(at 424.435524 -399.857976)
		(size 0.508)
		(drill 0.254)
		(layers "F.Cu" "B.Cu")
		(net "P0V9_CPU0_RT2_2A")
	)
	(via
		(at 419.806374 -395.466062)
		(size 0.4064)
		(drill 0.2032)
		(layers "F.Cu" "B.Cu")
		(net "P0V9_CPU0_RT2_2A")
	)
	(via
		(at 423.881804 -400.176492)
		(size 0.508)
		(drill 0.254)
		(layers "F.Cu" "B.Cu")
		(net "P0V9_CPU0_RT2_2A")
	)
	(via
		(at 399.024602 -399.99793)
		(size 0.508)
		(drill 0.254)
		(layers "F.Cu" "B.Cu")
		(net "P0V9_CPU0_RT2_2A")
	)
	(via
		(at 405.141684 -404.57755)
		(size 0.6604)
		(drill 0.3302)
		(layers "F.Cu" "B.Cu")
		(net "P0V9_CPU0_RT2_2A")
	)
	(via
		(at 397.119602 -401.90293)
		(size 0.508)
		(drill 0.254)
		(layers "F.Cu" "B.Cu")
		(net "P0V9_CPU0_RT2_2A")
	)
	(via
		(at 397.754602 -401.26793)
		(size 0.508)
		(drill 0.254)
		(layers "F.Cu" "B.Cu")
		(net "P0V9_CPU0_RT2_2A")
	)
	(via
		(at 424.435524 -400.492976)
		(size 0.508)
		(drill 0.254)
		(layers "F.Cu" "B.Cu")
		(net "P0V9_CPU0_RT2_2A")
	)
	(via
		(at 397.754602 -401.90293)
		(size 0.508)
		(drill 0.254)
		(layers "F.Cu" "B.Cu")
		(net "P0V9_CPU0_RT2_2A")
	)
	(via
		(at 398.389602 -399.99793)
		(size 0.508)
		(drill 0.254)
		(layers "F.Cu" "B.Cu")
		(net "P0V9_CPU0_RT2_2A")
	)
	(via
		(at 412.403036 -404.843234)
		(size 0.6604)
		(drill 0.3302)
		(layers "F.Cu" "B.Cu")
		(net "P0V9_CPU0_RT2_2A")
	)
	(via
		(at 398.389602 -400.63293)
		(size 0.508)
		(drill 0.254)
		(layers "F.Cu" "B.Cu")
		(net "P0V9_CPU0_RT2_2A")
	)
	(via
		(at 403.14626 -396.075662)
		(size 0.4064)
		(drill 0.2032)
		(layers "F.Cu" "B.Cu")
		(net "P0V9_CPU0_RT2_2A")
	)
	(via
		(at 397.119602 -401.26793)
		(size 0.508)
		(drill 0.254)
		(layers "F.Cu" "B.Cu")
		(net "P0V9_CPU0_RT2_2A")
	)
	(via
		(at 397.119602 -399.99793)
		(size 0.508)
		(drill 0.254)
		(layers "F.Cu" "B.Cu")
		(net "P0V9_CPU0_RT2_2A")
	)
	(via
		(at 423.1005 -403.32025)
		(size 0.6604)
		(drill 0.3302)
		(layers "F.Cu" "B.Cu")
		(net "P0V9_CPU0_RT2_2A")
	)
	(via
		(at 405.406352 -395.466062)
		(size 0.4064)
		(drill 0.2032)
		(layers "F.Cu" "B.Cu")
		(net "P0V9_CPU0_RT2_2A")
	)
	(via
		(at 399.024602 -401.90293)
		(size 0.508)
		(drill 0.254)
		(layers "F.Cu" "B.Cu")
		(net "P0V9_CPU0_RT2_2A")
	)
	(via
		(at 417.362132 -404.701502)
		(size 0.6604)
		(drill 0.3302)
		(layers "F.Cu" "B.Cu")
		(net "P0V9_CPU0_RT2_2A")
	)
	(via
		(at 340.845902 -396.075662)
		(size 0.4064)
		(drill 0.2032)
		(layers "F.Cu" "B.Cu")
		(net "P0V9_CPU0_RT1_2A_2D")
	)
	(via
		(at 329.789028 -402.550376)
		(size 0.508)
		(drill 0.254)
		(layers "F.Cu" "B.Cu")
		(net "P0V9_CPU0_RT1_2A_2D")
	)
	(via
		(at 349.105982 -395.466062)
		(size 0.4064)
		(drill 0.2032)
		(layers "F.Cu" "B.Cu")
		(net "P0V9_CPU0_RT1_2A_2D")
	)
	(via
		(at 329.152758 -401.624546)
		(size 0.508)
		(drill 0.254)
		(layers "F.Cu" "B.Cu")
		(net "P0V9_CPU0_RT1_2A_2D")
	)
	(via
		(at 329.150726 -403.081236)
		(size 0.6604)
		(drill 0.3302)
		(layers "F.Cu" "B.Cu")
		(net "P0V9_CPU0_RT1_2A_2D")
	)
	(via
		(at 340.705948 -395.466062)
		(size 0.4064)
		(drill 0.2032)
		(layers "F.Cu" "B.Cu")
		(net "P0V9_CPU0_RT1_2A_2D")
	)
	(via
		(at 349.245936 -396.075662)
		(size 0.4064)
		(drill 0.2032)
		(layers "F.Cu" "B.Cu")
		(net "P0V9_CPU0_RT1_2A_2D")
	)
	(via
		(at 328.538586 -402.550376)
		(size 0.508)
		(drill 0.254)
		(layers "F.Cu" "B.Cu")
		(net "P0V9_CPU0_RT1_2A_2D")
	)
	(via
		(at 329.152758 -402.361146)
		(size 0.508)
		(drill 0.254)
		(layers "F.Cu" "B.Cu")
		(net "P0V9_CPU0_RT1_2A_2D")
	)
	(via
		(at 352.257106 -405.162004)
		(size 0.6604)
		(drill 0.3302)
		(layers "F.Cu" "B.Cu")
		(net "P0V9_CPU0_RT1_2A")
	)
	(via
		(at 331.289406 -401.90293)
		(size 0.508)
		(drill 0.254)
		(layers "F.Cu" "B.Cu")
		(net "P0V9_CPU0_RT1_2A")
	)
	(via
		(at 331.289406 -400.63293)
		(size 0.508)
		(drill 0.254)
		(layers "F.Cu" "B.Cu")
		(net "P0V9_CPU0_RT1_2A")
	)
	(via
		(at 331.289406 -401.26793)
		(size 0.508)
		(drill 0.254)
		(layers "F.Cu" "B.Cu")
		(net "P0V9_CPU0_RT1_2A")
	)
	(via
		(at 330.654406 -401.26793)
		(size 0.508)
		(drill 0.254)
		(layers "F.Cu" "B.Cu")
		(net "P0V9_CPU0_RT1_2A")
	)
	(via
		(at 331.289406 -399.99793)
		(size 0.508)
		(drill 0.254)
		(layers "F.Cu" "B.Cu")
		(net "P0V9_CPU0_RT1_2A")
	)
	(via
		(at 330.019406 -399.99793)
		(size 0.508)
		(drill 0.254)
		(layers "F.Cu" "B.Cu")
		(net "P0V9_CPU0_RT1_2A")
	)
	(via
		(at 332.61554 -403.568154)
		(size 0.6604)
		(drill 0.3302)
		(layers "F.Cu" "B.Cu")
		(net "P0V9_CPU0_RT1_2A")
	)
	(via
		(at 353.906074 -395.466062)
		(size 0.4064)
		(drill 0.2032)
		(layers "F.Cu" "B.Cu")
		(net "P0V9_CPU0_RT1_2A")
	)
	(via
		(at 351.645982 -396.075662)
		(size 0.4064)
		(drill 0.2032)
		(layers "F.Cu" "B.Cu")
		(net "P0V9_CPU0_RT1_2A")
	)
	(via
		(at 331.924406 -401.90293)
		(size 0.508)
		(drill 0.254)
		(layers "F.Cu" "B.Cu")
		(net "P0V9_CPU0_RT1_2A")
	)
	(via
		(at 354.046028 -396.075662)
		(size 0.4064)
		(drill 0.2032)
		(layers "F.Cu" "B.Cu")
		(net "P0V9_CPU0_RT1_2A")
	)
	(via
		(at 336.370422 -404.241)
		(size 0.6604)
		(drill 0.3302)
		(layers "F.Cu" "B.Cu")
		(net "P0V9_CPU0_RT1_2A")
	)
	(via
		(at 339.506052 -395.466062)
		(size 0.4064)
		(drill 0.2032)
		(layers "F.Cu" "B.Cu")
		(net "P0V9_CPU0_RT1_2A")
	)
	(via
		(at 335.90611 -395.466062)
		(size 0.4064)
		(drill 0.2032)
		(layers "F.Cu" "B.Cu")
		(net "P0V9_CPU0_RT1_2A")
	)
	(via
		(at 330.654406 -400.63293)
		(size 0.508)
		(drill 0.254)
		(layers "F.Cu" "B.Cu")
		(net "P0V9_CPU0_RT1_2A")
	)
	(via
		(at 339.646006 -396.075662)
		(size 0.4064)
		(drill 0.2032)
		(layers "F.Cu" "B.Cu")
		(net "P0V9_CPU0_RT1_2A")
	)
	(via
		(at 330.019406 -400.63293)
		(size 0.508)
		(drill 0.254)
		(layers "F.Cu" "B.Cu")
		(net "P0V9_CPU0_RT1_2A")
	)
	(via
		(at 330.019406 -401.26793)
		(size 0.508)
		(drill 0.254)
		(layers "F.Cu" "B.Cu")
		(net "P0V9_CPU0_RT1_2A")
	)
	(via
		(at 350.446086 -396.075662)
		(size 0.4064)
		(drill 0.2032)
		(layers "F.Cu" "B.Cu")
		(net "P0V9_CPU0_RT1_2A")
	)
	(via
		(at 356.649528 -403.5679)
		(size 0.6604)
		(drill 0.3302)
		(layers "F.Cu" "B.Cu")
		(net "P0V9_CPU0_RT1_2A")
	)
	(via
		(at 337.106006 -395.466062)
		(size 0.4064)
		(drill 0.2032)
		(layers "F.Cu" "B.Cu")
		(net "P0V9_CPU0_RT1_2A")
	)
	(via
		(at 337.24596 -396.075662)
		(size 0.4064)
		(drill 0.2032)
		(layers "F.Cu" "B.Cu")
		(net "P0V9_CPU0_RT1_2A")
	)
	(via
		(at 351.506028 -395.466062)
		(size 0.4064)
		(drill 0.2032)
		(layers "F.Cu" "B.Cu")
		(net "P0V9_CPU0_RT1_2A")
	)
	(via
		(at 330.654406 -401.90293)
		(size 0.508)
		(drill 0.254)
		(layers "F.Cu" "B.Cu")
		(net "P0V9_CPU0_RT1_2A")
	)
	(via
		(at 350.306132 -395.466062)
		(size 0.4064)
		(drill 0.2032)
		(layers "F.Cu" "B.Cu")
		(net "P0V9_CPU0_RT1_2A")
	)
	(via
		(at 331.924406 -401.26793)
		(size 0.508)
		(drill 0.254)
		(layers "F.Cu" "B.Cu")
		(net "P0V9_CPU0_RT1_2A")
	)
	(via
		(at 336.046064 -396.075662)
		(size 0.4064)
		(drill 0.2032)
		(layers "F.Cu" "B.Cu")
		(net "P0V9_CPU0_RT1_2A")
	)
	(via
		(at 338.44611 -396.075662)
		(size 0.4064)
		(drill 0.2032)
		(layers "F.Cu" "B.Cu")
		(net "P0V9_CPU0_RT1_2A")
	)
	(via
		(at 331.924406 -400.63293)
		(size 0.508)
		(drill 0.254)
		(layers "F.Cu" "B.Cu")
		(net "P0V9_CPU0_RT1_2A")
	)
	(via
		(at 330.019406 -401.90293)
		(size 0.508)
		(drill 0.254)
		(layers "F.Cu" "B.Cu")
		(net "P0V9_CPU0_RT1_2A")
	)
	(via
		(at 352.706178 -395.466062)
		(size 0.4064)
		(drill 0.2032)
		(layers "F.Cu" "B.Cu")
		(net "P0V9_CPU0_RT1_2A")
	)
	(via
		(at 352.846132 -396.075662)
		(size 0.4064)
		(drill 0.2032)
		(layers "F.Cu" "B.Cu")
		(net "P0V9_CPU0_RT1_2A")
	)
	(via
		(at 330.654406 -399.99793)
		(size 0.508)
		(drill 0.254)
		(layers "F.Cu" "B.Cu")
		(net "P0V9_CPU0_RT1_2A")
	)
	(via
		(at 338.306156 -395.466062)
		(size 0.4064)
		(drill 0.2032)
		(layers "F.Cu" "B.Cu")
		(net "P0V9_CPU0_RT1_2A")
	)
	(via
		(at 331.924406 -399.99793)
		(size 0.508)
		(drill 0.254)
		(layers "F.Cu" "B.Cu")
		(net "P0V9_CPU0_RT1_2A")
	)
	(via
		(at 341.41791 -404.666196)
		(size 0.6604)
		(drill 0.3302)
		(layers "F.Cu" "B.Cu")
		(net "P0V9_CPU0_RT1_2A")
	)
	(via
		(at 308.1782 -395.466062)
		(size 0.4064)
		(drill 0.2032)
		(layers "F.Cu" "B.Cu")
		(net "P0V9_CPU0_RT0_2A_2D")
	)
	(via
		(at 301.35957 -407.79446)
		(size 0.508)
		(drill 0.254)
		(layers "F.Cu" "B.Cu")
		(net "P0V9_CPU0_RT0_2A_2D")
	)
	(via
		(at 308.318154 -396.075662)
		(size 0.4064)
		(drill 0.2032)
		(layers "F.Cu" "B.Cu")
		(net "P0V9_CPU0_RT0_2A_2D")
	)
	(via
		(at 301.35957 -408.53106)
		(size 0.508)
		(drill 0.254)
		(layers "F.Cu" "B.Cu")
		(net "P0V9_CPU0_RT0_2A_2D")
	)
	(via
		(at 316.718188 -396.075662)
		(size 0.4064)
		(drill 0.2032)
		(layers "F.Cu" "B.Cu")
		(net "P0V9_CPU0_RT0_2A_2D")
	)
	(via
		(at 301.99584 -408.72029)
		(size 0.508)
		(drill 0.254)
		(layers "F.Cu" "B.Cu")
		(net "P0V9_CPU0_RT0_2A_2D")
	)
	(via
		(at 301.35957 -407.05786)
		(size 0.508)
		(drill 0.254)
		(layers "F.Cu" "B.Cu")
		(net "P0V9_CPU0_RT0_2A_2D")
	)
	(via
		(at 302.257206 -407.73604)
		(size 0.6604)
		(drill 0.3302)
		(layers "F.Cu" "B.Cu")
		(net "P0V9_CPU0_RT0_2A_2D")
	)
	(via
		(at 316.578234 -395.466062)
		(size 0.4064)
		(drill 0.2032)
		(layers "F.Cu" "B.Cu")
		(net "P0V9_CPU0_RT0_2A_2D")
	)
	(via
		(at 297.951906 -403.542754)
		(size 0.508)
		(drill 0.254)
		(layers "F.Cu" "B.Cu")
		(net "P0V9_CPU0_RT0_2A")
	)
	(via
		(at 302.45177 -403.600412)
		(size 0.6604)
		(drill 0.3302)
		(layers "F.Cu" "B.Cu")
		(net "P0V9_CPU0_RT0_2A")
	)
	(via
		(at 305.918362 -396.075662)
		(size 0.4064)
		(drill 0.2032)
		(layers "F.Cu" "B.Cu")
		(net "P0V9_CPU0_RT0_2A")
	)
	(via
		(at 303.378362 -395.466062)
		(size 0.4064)
		(drill 0.2032)
		(layers "F.Cu" "B.Cu")
		(net "P0V9_CPU0_RT0_2A")
	)
	(via
		(at 321.378326 -395.466062)
		(size 0.4064)
		(drill 0.2032)
		(layers "F.Cu" "B.Cu")
		(net "P0V9_CPU0_RT0_2A")
	)
	(via
		(at 304.718212 -396.075662)
		(size 0.4064)
		(drill 0.2032)
		(layers "F.Cu" "B.Cu")
		(net "P0V9_CPU0_RT0_2A")
	)
	(via
		(at 322.99656 -404.114254)
		(size 0.6604)
		(drill 0.3302)
		(layers "F.Cu" "B.Cu")
		(net "P0V9_CPU0_RT0_2A")
	)
	(via
		(at 320.17843 -395.466062)
		(size 0.4064)
		(drill 0.2032)
		(layers "F.Cu" "B.Cu")
		(net "P0V9_CPU0_RT0_2A")
	)
	(via
		(at 297.316906 -403.542754)
		(size 0.508)
		(drill 0.254)
		(layers "F.Cu" "B.Cu")
		(net "P0V9_CPU0_RT0_2A")
	)
	(via
		(at 297.951906 -402.907754)
		(size 0.508)
		(drill 0.254)
		(layers "F.Cu" "B.Cu")
		(net "P0V9_CPU0_RT0_2A")
	)
	(via
		(at 321.51828 -396.075662)
		(size 0.4064)
		(drill 0.2032)
		(layers "F.Cu" "B.Cu")
		(net "P0V9_CPU0_RT0_2A")
	)
	(via
		(at 307.269134 -404.14956)
		(size 0.6604)
		(drill 0.3302)
		(layers "F.Cu" "B.Cu")
		(net "P0V9_CPU0_RT0_2A")
	)
	(via
		(at 317.918338 -396.075662)
		(size 0.4064)
		(drill 0.2032)
		(layers "F.Cu" "B.Cu")
		(net "P0V9_CPU0_RT0_2A")
	)
	(via
		(at 299.954442 -402.907754)
		(size 0.508)
		(drill 0.254)
		(layers "F.Cu" "B.Cu")
		(net "P0V9_CPU0_RT0_2A")
	)
	(via
		(at 307.118258 -396.075662)
		(size 0.4064)
		(drill 0.2032)
		(layers "F.Cu" "B.Cu")
		(net "P0V9_CPU0_RT0_2A")
	)
	(via
		(at 298.586906 -402.907754)
		(size 0.508)
		(drill 0.254)
		(layers "F.Cu" "B.Cu")
		(net "P0V9_CPU0_RT0_2A")
	)
	(via
		(at 299.954442 -403.542754)
		(size 0.508)
		(drill 0.254)
		(layers "F.Cu" "B.Cu")
		(net "P0V9_CPU0_RT0_2A")
	)
	(via
		(at 298.586906 -402.272754)
		(size 0.508)
		(drill 0.254)
		(layers "F.Cu" "B.Cu")
		(net "P0V9_CPU0_RT0_2A")
	)
	(via
		(at 317.778384 -395.466062)
		(size 0.4064)
		(drill 0.2032)
		(layers "F.Cu" "B.Cu")
		(net "P0V9_CPU0_RT0_2A")
	)
	(via
		(at 296.677842 -403.542754)
		(size 0.508)
		(drill 0.254)
		(layers "F.Cu" "B.Cu")
		(net "P0V9_CPU0_RT0_2A")
	)
	(via
		(at 297.316906 -402.907754)
		(size 0.508)
		(drill 0.254)
		(layers "F.Cu" "B.Cu")
		(net "P0V9_CPU0_RT0_2A")
	)
	(via
		(at 314.814204 -404.309072)
		(size 0.6604)
		(drill 0.3302)
		(layers "F.Cu" "B.Cu")
		(net "P0V9_CPU0_RT0_2A")
	)
	(via
		(at 305.778408 -395.466062)
		(size 0.4064)
		(drill 0.2032)
		(layers "F.Cu" "B.Cu")
		(net "P0V9_CPU0_RT0_2A")
	)
	(via
		(at 297.316906 -402.272754)
		(size 0.508)
		(drill 0.254)
		(layers "F.Cu" "B.Cu")
		(net "P0V9_CPU0_RT0_2A")
	)
	(via
		(at 298.586906 -403.542754)
		(size 0.508)
		(drill 0.254)
		(layers "F.Cu" "B.Cu")
		(net "P0V9_CPU0_RT0_2A")
	)
	(via
		(at 297.951906 -402.272754)
		(size 0.508)
		(drill 0.254)
		(layers "F.Cu" "B.Cu")
		(net "P0V9_CPU0_RT0_2A")
	)
	(via
		(at 296.677842 -402.907754)
		(size 0.508)
		(drill 0.254)
		(layers "F.Cu" "B.Cu")
		(net "P0V9_CPU0_RT0_2A")
	)
	(via
		(at 318.97828 -395.466062)
		(size 0.4064)
		(drill 0.2032)
		(layers "F.Cu" "B.Cu")
		(net "P0V9_CPU0_RT0_2A")
	)
	(via
		(at 299.221906 -402.907754)
		(size 0.508)
		(drill 0.254)
		(layers "F.Cu" "B.Cu")
		(net "P0V9_CPU0_RT0_2A")
	)
	(via
		(at 306.978304 -395.466062)
		(size 0.4064)
		(drill 0.2032)
		(layers "F.Cu" "B.Cu")
		(net "P0V9_CPU0_RT0_2A")
	)
	(via
		(at 320.318384 -396.075662)
		(size 0.4064)
		(drill 0.2032)
		(layers "F.Cu" "B.Cu")
		(net "P0V9_CPU0_RT0_2A")
	)
	(via
		(at 304.578258 -395.466062)
		(size 0.4064)
		(drill 0.2032)
		(layers "F.Cu" "B.Cu")
		(net "P0V9_CPU0_RT0_2A")
	)
	(via
		(at 299.221906 -402.272754)
		(size 0.508)
		(drill 0.254)
		(layers "F.Cu" "B.Cu")
		(net "P0V9_CPU0_RT0_2A")
	)
	(via
		(at 319.118234 -396.075662)
		(size 0.4064)
		(drill 0.2032)
		(layers "F.Cu" "B.Cu")
		(net "P0V9_CPU0_RT0_2A")
	)
	(via
		(at 299.742098 -400.271234)
		(size 0.6604)
		(drill 0.3302)
		(layers "F.Cu" "B.Cu")
		(net "P0V9_CPU0_RT0_2A")
	)
	(via
		(at 299.221906 -403.542754)
		(size 0.508)
		(drill 0.254)
		(layers "F.Cu" "B.Cu")
		(net "P0V9_CPU0_RT0_2A")
	)
	(via
		(at 303.518316 -396.075662)
		(size 0.4064)
		(drill 0.2032)
		(layers "F.Cu" "B.Cu")
		(net "P0V9_CPU0_RT0_2A")
	)
	(segment
		(start 368.560858 -399.622518)
		(end 368.560858 -399.47977)
		(width 0.254)
		(layer "F.Cu")
		(net "NCF_CPU0_P3_GND")
	)
	(segment
		(start 389.983472 -391.750042)
		(end 389.983472 -391.25017)
		(width 0.254)
		(layer "F.Cu")
		(net "NCF_CPU0_P3_GND")
	)
	(segment
		(start 369.018058 -400.298412)
		(end 369.018058 -399.663158)
		(width 0.254)
		(layer "F.Cu")
		(net "NCF_CPU0_P3_GND")
	)
	(segment
		(start 369.318032 -392.30427)
		(end 368.71783 -392.30427)
		(width 0.254)
		(layer "F.Cu")
		(net "NCF_CPU0_P3_GND")
	)
	(segment
		(start 390.018016 -391.784586)
		(end 390.31799 -392.30427)
		(width 0.254)
		(layer "F.Cu")
		(net "NCF_CPU0_P3_GND")
	)
	(segment
		(start 369.436396 -400.71675)
		(end 369.018058 -400.298412)
		(width 0.254)
		(layer "F.Cu")
		(net "NCF_CPU0_P3_GND")
	)
	(segment
		(start 368.71783 -392.30427)
		(end 368.459258 -392.045698)
		(width 0.254)
		(layer "F.Cu")
		(net "NCF_CPU0_P3_GND")
	)
	(segment
		(start 369.018058 -391.289286)
		(end 369.018058 -391.784586)
		(width 0.254)
		(layer "F.Cu")
		(net "NCF_CPU0_P3_GND")
	)
	(segment
		(start 390.516872 -391.683494)
		(end 390.617964 -391.784586)
		(width 0.254)
		(layer "F.Cu")
		(net "NCF_CPU0_P3_GND")
	)
	(segment
		(start 390.31799 -399.363184)
		(end 390.018016 -399.663158)
		(width 0.254)
		(layer "F.Cu")
		(net "NCF_CPU0_P3_GND")
	)
	(segment
		(start 390.80059 -399.201132)
		(end 390.742932 -399.143474)
		(width 0.254)
		(layer "F.Cu")
		(net "NCF_CPU0_P3_GND")
	)
	(segment
		(start 369.594892 -400.71675)
		(end 369.436396 -400.71675)
		(width 0.254)
		(layer "F.Cu")
		(net "NCF_CPU0_P3_GND")
	)
	(segment
		(start 390.31799 -399.143474)
		(end 390.31799 -399.363184)
		(width 0.254)
		(layer "F.Cu")
		(net "NCF_CPU0_P3_GND")
	)
	(segment
		(start 390.742932 -399.143474)
		(end 390.31799 -399.143474)
		(width 0.254)
		(layer "F.Cu")
		(net "NCF_CPU0_P3_GND")
	)
	(segment
		(start 368.459258 -392.045698)
		(end 368.459258 -391.289286)
		(width 0.254)
		(layer "F.Cu")
		(net "NCF_CPU0_P3_GND")
	)
	(segment
		(start 369.318032 -399.143474)
		(end 369.018058 -399.663158)
		(width 0.254)
		(layer "F.Cu")
		(net "NCF_CPU0_P3_GND")
	)
	(segment
		(start 368.71783 -399.322798)
		(end 368.71783 -399.143474)
		(width 0.254)
		(layer "F.Cu")
		(net "NCF_CPU0_P3_GND")
	)
	(segment
		(start 368.560858 -399.47977)
		(end 368.71783 -399.322798)
		(width 0.254)
		(layer "F.Cu")
		(net "NCF_CPU0_P3_GND")
	)
	(segment
		(start 390.516872 -391.25017)
		(end 390.516872 -391.683494)
		(width 0.254)
		(layer "F.Cu")
		(net "NCF_CPU0_P3_GND")
	)
	(segment
		(start 390.018016 -391.784586)
		(end 389.983472 -391.750042)
		(width 0.254)
		(layer "F.Cu")
		(net "NCF_CPU0_P3_GND")
	)
	(via
		(at 369.018058 -391.289286)
		(size 0.4064)
		(drill 0.2032)
		(layers "F.Cu" "B.Cu")
		(net "NCF_CPU0_P3_GND")
	)
	(via
		(at 369.594892 -400.71675)
		(size 0.4064)
		(drill 0.2032)
		(layers "F.Cu" "B.Cu")
		(net "NCF_CPU0_P3_GND")
	)
	(via
		(at 391.8458 -391.3124)
		(size 0.6604)
		(drill 0.3302)
		(layers "F.Cu" "B.Cu")
		(net "NCF_CPU0_P3_GND")
	)
	(via
		(at 368.459258 -391.289286)
		(size 0.4064)
		(drill 0.2032)
		(layers "F.Cu" "B.Cu")
		(net "NCF_CPU0_P3_GND")
	)
	(via
		(at 390.80059 -399.201132)
		(size 0.4064)
		(drill 0.2032)
		(layers "F.Cu" "B.Cu")
		(net "NCF_CPU0_P3_GND")
	)
	(via
		(at 368.560858 -399.622518)
		(size 0.4064)
		(drill 0.2032)
		(layers "F.Cu" "B.Cu")
		(net "NCF_CPU0_P3_GND")
	)
	(via
		(at 389.983472 -391.25017)
		(size 0.4064)
		(drill 0.2032)
		(layers "F.Cu" "B.Cu")
		(net "NCF_CPU0_P3_GND")
	)
	(via
		(at 390.516872 -391.25017)
		(size 0.4064)
		(drill 0.2032)
		(layers "F.Cu" "B.Cu")
		(net "NCF_CPU0_P3_GND")
	)
	(segment
		(start 422.51122 -391.750042)
		(end 422.51122 -391.25017)
		(width 0.254)
		(layer "F.Cu")
		(net "NCF_CPU0_P2_GND")
	)
	(segment
		(start 423.328338 -399.201132)
		(end 423.27068 -399.143474)
		(width 0.254)
		(layer "F.Cu")
		(net "NCF_CPU0_P2_GND")
	)
	(segment
		(start 401.545806 -391.492994)
		(end 401.55876 -391.48004)
		(width 0.254)
		(layer "F.Cu")
		(net "NCF_CPU0_P2_GND")
	)
	(segment
		(start 422.845738 -399.143474)
		(end 422.845738 -399.363184)
		(width 0.254)
		(layer "F.Cu")
		(net "NCF_CPU0_P2_GND")
	)
	(segment
		(start 401.545806 -391.784586)
		(end 401.545806 -391.492994)
		(width 0.254)
		(layer "F.Cu")
		(net "NCF_CPU0_P2_GND")
	)
	(segment
		(start 423.04462 -391.683494)
		(end 423.145712 -391.784586)
		(width 0.254)
		(layer "F.Cu")
		(net "NCF_CPU0_P2_GND")
	)
	(segment
		(start 422.845738 -399.363184)
		(end 422.545764 -399.663158)
		(width 0.254)
		(layer "F.Cu")
		(net "NCF_CPU0_P2_GND")
	)
	(segment
		(start 401.964144 -400.71675)
		(end 401.545806 -400.298412)
		(width 0.254)
		(layer "F.Cu")
		(net "NCF_CPU0_P2_GND")
	)
	(segment
		(start 422.545764 -391.784586)
		(end 422.51122 -391.750042)
		(width 0.254)
		(layer "F.Cu")
		(net "NCF_CPU0_P2_GND")
	)
	(segment
		(start 401.088606 -399.47977)
		(end 401.245578 -399.322798)
		(width 0.254)
		(layer "F.Cu")
		(net "NCF_CPU0_P2_GND")
	)
	(segment
		(start 401.245578 -399.322798)
		(end 401.245578 -399.143474)
		(width 0.254)
		(layer "F.Cu")
		(net "NCF_CPU0_P2_GND")
	)
	(segment
		(start 400.987006 -392.045698)
		(end 400.987006 -391.289286)
		(width 0.254)
		(layer "F.Cu")
		(net "NCF_CPU0_P2_GND")
	)
	(segment
		(start 401.84578 -392.30427)
		(end 401.245578 -392.30427)
		(width 0.254)
		(layer "F.Cu")
		(net "NCF_CPU0_P2_GND")
	)
	(segment
		(start 402.12264 -400.71675)
		(end 401.964144 -400.71675)
		(width 0.254)
		(layer "F.Cu")
		(net "NCF_CPU0_P2_GND")
	)
	(segment
		(start 423.27068 -399.143474)
		(end 422.845738 -399.143474)
		(width 0.254)
		(layer "F.Cu")
		(net "NCF_CPU0_P2_GND")
	)
	(segment
		(start 401.245578 -392.30427)
		(end 400.987006 -392.045698)
		(width 0.254)
		(layer "F.Cu")
		(net "NCF_CPU0_P2_GND")
	)
	(segment
		(start 422.545764 -391.784586)
		(end 422.845738 -392.30427)
		(width 0.254)
		(layer "F.Cu")
		(net "NCF_CPU0_P2_GND")
	)
	(segment
		(start 401.088606 -399.622518)
		(end 401.088606 -399.47977)
		(width 0.254)
		(layer "F.Cu")
		(net "NCF_CPU0_P2_GND")
	)
	(segment
		(start 401.84578 -399.143474)
		(end 401.545806 -399.663158)
		(width 0.254)
		(layer "F.Cu")
		(net "NCF_CPU0_P2_GND")
	)
	(segment
		(start 401.55876 -391.48004)
		(end 401.55876 -391.27684)
		(width 0.254)
		(layer "F.Cu")
		(net "NCF_CPU0_P2_GND")
	)
	(segment
		(start 423.04462 -391.25017)
		(end 423.04462 -391.683494)
		(width 0.254)
		(layer "F.Cu")
		(net "NCF_CPU0_P2_GND")
	)
	(segment
		(start 401.545806 -400.298412)
		(end 401.545806 -399.663158)
		(width 0.254)
		(layer "F.Cu")
		(net "NCF_CPU0_P2_GND")
	)
	(via
		(at 423.328338 -399.201132)
		(size 0.4064)
		(drill 0.2032)
		(layers "F.Cu" "B.Cu")
		(net "NCF_CPU0_P2_GND")
	)
	(via
		(at 401.55876 -391.27684)
		(size 0.4064)
		(drill 0.2032)
		(layers "F.Cu" "B.Cu")
		(net "NCF_CPU0_P2_GND")
	)
	(via
		(at 400.987006 -391.289286)
		(size 0.4064)
		(drill 0.2032)
		(layers "F.Cu" "B.Cu")
		(net "NCF_CPU0_P2_GND")
	)
	(via
		(at 423.04462 -391.25017)
		(size 0.4064)
		(drill 0.2032)
		(layers "F.Cu" "B.Cu")
		(net "NCF_CPU0_P2_GND")
	)
	(via
		(at 402.12264 -400.71675)
		(size 0.4064)
		(drill 0.2032)
		(layers "F.Cu" "B.Cu")
		(net "NCF_CPU0_P2_GND")
	)
	(via
		(at 423.678858 -391.468864)
		(size 0.6604)
		(drill 0.3302)
		(layers "F.Cu" "B.Cu")
		(net "NCF_CPU0_P2_GND")
	)
	(via
		(at 422.51122 -391.25017)
		(size 0.4064)
		(drill 0.2032)
		(layers "F.Cu" "B.Cu")
		(net "NCF_CPU0_P2_GND")
	)
	(via
		(at 401.088606 -399.622518)
		(size 0.4064)
		(drill 0.2032)
		(layers "F.Cu" "B.Cu")
		(net "NCF_CPU0_P2_GND")
	)
	(segment
		(start 355.745542 -399.143474)
		(end 355.745542 -399.363184)
		(width 0.254)
		(layer "F.Cu")
		(net "NCF_CPU0_P1_GND")
	)
	(segment
		(start 333.98841 -399.47977)
		(end 334.145382 -399.322798)
		(width 0.254)
		(layer "F.Cu")
		(net "NCF_CPU0_P1_GND")
	)
	(segment
		(start 334.44561 -391.784586)
		(end 334.44561 -391.492994)
		(width 0.254)
		(layer "F.Cu")
		(net "NCF_CPU0_P1_GND")
	)
	(segment
		(start 334.745584 -392.30427)
		(end 334.145382 -392.30427)
		(width 0.254)
		(layer "F.Cu")
		(net "NCF_CPU0_P1_GND")
	)
	(segment
		(start 333.88681 -392.045698)
		(end 333.88681 -391.289286)
		(width 0.254)
		(layer "F.Cu")
		(net "NCF_CPU0_P1_GND")
	)
	(segment
		(start 356.170484 -399.143474)
		(end 355.745542 -399.143474)
		(width 0.254)
		(layer "F.Cu")
		(net "NCF_CPU0_P1_GND")
	)
	(segment
		(start 334.145382 -399.322798)
		(end 334.145382 -399.143474)
		(width 0.254)
		(layer "F.Cu")
		(net "NCF_CPU0_P1_GND")
	)
	(segment
		(start 334.745584 -399.143474)
		(end 334.44561 -399.663158)
		(width 0.254)
		(layer "F.Cu")
		(net "NCF_CPU0_P1_GND")
	)
	(segment
		(start 334.458564 -391.48004)
		(end 334.458564 -391.27684)
		(width 0.254)
		(layer "F.Cu")
		(net "NCF_CPU0_P1_GND")
	)
	(segment
		(start 355.445568 -391.784586)
		(end 355.745542 -392.30427)
		(width 0.254)
		(layer "F.Cu")
		(net "NCF_CPU0_P1_GND")
	)
	(segment
		(start 355.944424 -391.25017)
		(end 355.944424 -391.683494)
		(width 0.254)
		(layer "F.Cu")
		(net "NCF_CPU0_P1_GND")
	)
	(segment
		(start 355.745542 -399.363184)
		(end 355.445568 -399.663158)
		(width 0.254)
		(layer "F.Cu")
		(net "NCF_CPU0_P1_GND")
	)
	(segment
		(start 334.145382 -392.30427)
		(end 333.88681 -392.045698)
		(width 0.254)
		(layer "F.Cu")
		(net "NCF_CPU0_P1_GND")
	)
	(segment
		(start 334.863948 -400.71675)
		(end 334.44561 -400.298412)
		(width 0.254)
		(layer "F.Cu")
		(net "NCF_CPU0_P1_GND")
	)
	(segment
		(start 334.44561 -391.492994)
		(end 334.458564 -391.48004)
		(width 0.254)
		(layer "F.Cu")
		(net "NCF_CPU0_P1_GND")
	)
	(segment
		(start 333.98841 -399.622518)
		(end 333.98841 -399.47977)
		(width 0.254)
		(layer "F.Cu")
		(net "NCF_CPU0_P1_GND")
	)
	(segment
		(start 335.022444 -400.71675)
		(end 334.863948 -400.71675)
		(width 0.254)
		(layer "F.Cu")
		(net "NCF_CPU0_P1_GND")
	)
	(segment
		(start 355.411024 -391.750042)
		(end 355.411024 -391.25017)
		(width 0.254)
		(layer "F.Cu")
		(net "NCF_CPU0_P1_GND")
	)
	(segment
		(start 355.944424 -391.683494)
		(end 356.045516 -391.784586)
		(width 0.254)
		(layer "F.Cu")
		(net "NCF_CPU0_P1_GND")
	)
	(segment
		(start 355.445568 -391.784586)
		(end 355.411024 -391.750042)
		(width 0.254)
		(layer "F.Cu")
		(net "NCF_CPU0_P1_GND")
	)
	(segment
		(start 356.228142 -399.201132)
		(end 356.170484 -399.143474)
		(width 0.254)
		(layer "F.Cu")
		(net "NCF_CPU0_P1_GND")
	)
	(segment
		(start 334.44561 -400.298412)
		(end 334.44561 -399.663158)
		(width 0.254)
		(layer "F.Cu")
		(net "NCF_CPU0_P1_GND")
	)
	(via
		(at 357.01478 -391.28954)
		(size 0.6604)
		(drill 0.3302)
		(layers "F.Cu" "B.Cu")
		(net "NCF_CPU0_P1_GND")
	)
	(via
		(at 355.944424 -391.25017)
		(size 0.4064)
		(drill 0.2032)
		(layers "F.Cu" "B.Cu")
		(net "NCF_CPU0_P1_GND")
	)
	(via
		(at 335.022444 -400.71675)
		(size 0.4064)
		(drill 0.2032)
		(layers "F.Cu" "B.Cu")
		(net "NCF_CPU0_P1_GND")
	)
	(via
		(at 334.458564 -391.27684)
		(size 0.4064)
		(drill 0.2032)
		(layers "F.Cu" "B.Cu")
		(net "NCF_CPU0_P1_GND")
	)
	(via
		(at 333.98841 -399.622518)
		(size 0.4064)
		(drill 0.2032)
		(layers "F.Cu" "B.Cu")
		(net "NCF_CPU0_P1_GND")
	)
	(via
		(at 355.411024 -391.25017)
		(size 0.4064)
		(drill 0.2032)
		(layers "F.Cu" "B.Cu")
		(net "NCF_CPU0_P1_GND")
	)
	(via
		(at 356.228142 -399.201132)
		(size 0.4064)
		(drill 0.2032)
		(layers "F.Cu" "B.Cu")
		(net "NCF_CPU0_P1_GND")
	)
	(via
		(at 333.88681 -391.289286)
		(size 0.4064)
		(drill 0.2032)
		(layers "F.Cu" "B.Cu")
		(net "NCF_CPU0_P1_GND")
	)
	(segment
		(start 323.416676 -391.683494)
		(end 323.517768 -391.784586)
		(width 0.254)
		(layer "F.Cu")
		(net "NCF_CPU0_P0_GND")
	)
	(segment
		(start 323.642736 -399.143474)
		(end 323.217794 -399.143474)
		(width 0.254)
		(layer "F.Cu")
		(net "NCF_CPU0_P0_GND")
	)
	(segment
		(start 302.494696 -400.71675)
		(end 302.3362 -400.71675)
		(width 0.254)
		(layer "F.Cu")
		(net "NCF_CPU0_P0_GND")
	)
	(segment
		(start 302.217836 -399.143474)
		(end 301.917862 -399.663158)
		(width 0.254)
		(layer "F.Cu")
		(net "NCF_CPU0_P0_GND")
	)
	(segment
		(start 301.617634 -399.322798)
		(end 301.617634 -399.143474)
		(width 0.254)
		(layer "F.Cu")
		(net "NCF_CPU0_P0_GND")
	)
	(segment
		(start 323.217794 -399.143474)
		(end 323.217794 -399.363184)
		(width 0.254)
		(layer "F.Cu")
		(net "NCF_CPU0_P0_GND")
	)
	(segment
		(start 323.217794 -399.363184)
		(end 322.91782 -399.663158)
		(width 0.254)
		(layer "F.Cu")
		(net "NCF_CPU0_P0_GND")
	)
	(segment
		(start 322.883276 -391.750042)
		(end 322.883276 -391.25017)
		(width 0.254)
		(layer "F.Cu")
		(net "NCF_CPU0_P0_GND")
	)
	(segment
		(start 302.3362 -400.71675)
		(end 301.917862 -400.298412)
		(width 0.254)
		(layer "F.Cu")
		(net "NCF_CPU0_P0_GND")
	)
	(segment
		(start 322.91782 -391.784586)
		(end 322.883276 -391.750042)
		(width 0.254)
		(layer "F.Cu")
		(net "NCF_CPU0_P0_GND")
	)
	(segment
		(start 301.460662 -399.47977)
		(end 301.617634 -399.322798)
		(width 0.254)
		(layer "F.Cu")
		(net "NCF_CPU0_P0_GND")
	)
	(segment
		(start 322.91782 -391.784586)
		(end 323.217794 -392.30427)
		(width 0.254)
		(layer "F.Cu")
		(net "NCF_CPU0_P0_GND")
	)
	(segment
		(start 301.460662 -399.622518)
		(end 301.460662 -399.47977)
		(width 0.254)
		(layer "F.Cu")
		(net "NCF_CPU0_P0_GND")
	)
	(segment
		(start 301.617634 -392.30427)
		(end 301.359062 -392.045698)
		(width 0.254)
		(layer "F.Cu")
		(net "NCF_CPU0_P0_GND")
	)
	(segment
		(start 301.917862 -400.298412)
		(end 301.917862 -399.663158)
		(width 0.254)
		(layer "F.Cu")
		(net "NCF_CPU0_P0_GND")
	)
	(segment
		(start 323.700394 -399.201132)
		(end 323.642736 -399.143474)
		(width 0.254)
		(layer "F.Cu")
		(net "NCF_CPU0_P0_GND")
	)
	(segment
		(start 301.917862 -391.289286)
		(end 301.917862 -391.784586)
		(width 0.254)
		(layer "F.Cu")
		(net "NCF_CPU0_P0_GND")
	)
	(segment
		(start 302.217836 -392.30427)
		(end 301.617634 -392.30427)
		(width 0.254)
		(layer "F.Cu")
		(net "NCF_CPU0_P0_GND")
	)
	(segment
		(start 323.416676 -391.25017)
		(end 323.416676 -391.683494)
		(width 0.254)
		(layer "F.Cu")
		(net "NCF_CPU0_P0_GND")
	)
	(segment
		(start 301.359062 -392.045698)
		(end 301.359062 -391.289286)
		(width 0.254)
		(layer "F.Cu")
		(net "NCF_CPU0_P0_GND")
	)
	(via
		(at 323.700394 -399.201132)
		(size 0.4064)
		(drill 0.2032)
		(layers "F.Cu" "B.Cu")
		(net "NCF_CPU0_P0_GND")
	)
	(via
		(at 323.416676 -391.25017)
		(size 0.4064)
		(drill 0.2032)
		(layers "F.Cu" "B.Cu")
		(net "NCF_CPU0_P0_GND")
	)
	(via
		(at 324.35292 -391.29716)
		(size 0.6604)
		(drill 0.3302)
		(layers "F.Cu" "B.Cu")
		(net "NCF_CPU0_P0_GND")
	)
	(via
		(at 301.460662 -399.622518)
		(size 0.4064)
		(drill 0.2032)
		(layers "F.Cu" "B.Cu")
		(net "NCF_CPU0_P0_GND")
	)
	(via
		(at 301.359062 -391.289286)
		(size 0.4064)
		(drill 0.2032)
		(layers "F.Cu" "B.Cu")
		(net "NCF_CPU0_P0_GND")
	)
	(via
		(at 301.917862 -391.289286)
		(size 0.4064)
		(drill 0.2032)
		(layers "F.Cu" "B.Cu")
		(net "NCF_CPU0_P0_GND")
	)
	(via
		(at 322.883276 -391.25017)
		(size 0.4064)
		(drill 0.2032)
		(layers "F.Cu" "B.Cu")
		(net "NCF_CPU0_P0_GND")
	)
	(via
		(at 302.494696 -400.71675)
		(size 0.4064)
		(drill 0.2032)
		(layers "F.Cu" "B.Cu")
		(net "NCF_CPU0_P0_GND")
	)
	(segment
		(start 392.263376 -401.784312)
		(end 392.263376 -402.229828)
		(width 0.10668)
		(layer "F.Cu")
		(net "NCF_A1_CPU0_P3_GND")
	)
	(segment
		(start 390.617964 -399.663158)
		(end 391.92708 -400.972274)
		(width 0.10668)
		(layer "F.Cu")
		(net "NCF_A1_CPU0_P3_GND")
	)
	(segment
		(start 389.0645 -405.94026)
		(end 390.650476 -405.94026)
		(width 0.10668)
		(layer "F.Cu")
		(net "NCF_A1_CPU0_P3_GND")
	)
	(segment
		(start 392.152378 -403.1869)
		(end 392.081258 -403.1869)
		(width 0.10668)
		(layer "F.Cu")
		(net "NCF_A1_CPU0_P3_GND")
	)
	(segment
		(start 391.92708 -400.972274)
		(end 392.263376 -401.784312)
		(width 0.10668)
		(layer "F.Cu")
		(net "NCF_A1_CPU0_P3_GND")
	)
	(segment
		(start 392.469624 -402.869654)
		(end 392.152378 -403.1869)
		(width 0.10668)
		(layer "F.Cu")
		(net "NCF_A1_CPU0_P3_GND")
	)
	(segment
		(start 392.469624 -402.436076)
		(end 392.469624 -402.869654)
		(width 0.10668)
		(layer "F.Cu")
		(net "NCF_A1_CPU0_P3_GND")
	)
	(segment
		(start 392.263376 -402.229828)
		(end 392.469624 -402.436076)
		(width 0.10668)
		(layer "F.Cu")
		(net "NCF_A1_CPU0_P3_GND")
	)
	(segment
		(start 392.081258 -404.509478)
		(end 392.081258 -403.1869)
		(width 0.10668)
		(layer "F.Cu")
		(net "NCF_A1_CPU0_P3_GND")
	)
	(segment
		(start 390.650476 -405.94026)
		(end 392.081258 -404.509478)
		(width 0.10668)
		(layer "F.Cu")
		(net "NCF_A1_CPU0_P3_GND")
	)
	(via
		(at 389.0645 -405.94026)
		(size 0.762)
		(drill 0.381)
		(layers "F.Cu" "B.Cu")
		(net "NCF_A1_CPU0_P3_GND")
	)
	(segment
		(start 423.145712 -399.663158)
		(end 423.145712 -400.156426)
		(width 0.10668)
		(layer "F.Cu")
		(net "NCF_A1_CPU0_P2_GND")
	)
	(segment
		(start 424.500802 -401.316952)
		(end 424.692572 -401.508722)
		(width 0.10668)
		(layer "F.Cu")
		(net "NCF_A1_CPU0_P2_GND")
	)
	(segment
		(start 424.609006 -403.0091)
		(end 424.609006 -403.146514)
		(width 0.10668)
		(layer "F.Cu")
		(net "NCF_A1_CPU0_P2_GND")
	)
	(segment
		(start 427.186852 -403.326092)
		(end 428.260256 -402.252688)
		(width 0.10668)
		(layer "F.Cu")
		(net "NCF_A1_CPU0_P2_GND")
	)
	(segment
		(start 424.70959 -403.0091)
		(end 424.609006 -403.0091)
		(width 0.10668)
		(layer "F.Cu")
		(net "NCF_A1_CPU0_P2_GND")
	)
	(segment
		(start 424.788584 -403.326092)
		(end 427.186852 -403.326092)
		(width 0.10668)
		(layer "F.Cu")
		(net "NCF_A1_CPU0_P2_GND")
	)
	(segment
		(start 425.021502 -402.303234)
		(end 425.021502 -402.697188)
		(width 0.10668)
		(layer "F.Cu")
		(net "NCF_A1_CPU0_P2_GND")
	)
	(segment
		(start 424.609006 -403.146514)
		(end 424.788584 -403.326092)
		(width 0.10668)
		(layer "F.Cu")
		(net "NCF_A1_CPU0_P2_GND")
	)
	(segment
		(start 425.021502 -402.697188)
		(end 424.70959 -403.0091)
		(width 0.10668)
		(layer "F.Cu")
		(net "NCF_A1_CPU0_P2_GND")
	)
	(segment
		(start 424.16857 -401.179284)
		(end 424.500802 -401.316952)
		(width 0.10668)
		(layer "F.Cu")
		(net "NCF_A1_CPU0_P2_GND")
	)
	(segment
		(start 424.692572 -401.508722)
		(end 425.021502 -402.303234)
		(width 0.10668)
		(layer "F.Cu")
		(net "NCF_A1_CPU0_P2_GND")
	)
	(segment
		(start 423.145712 -400.156426)
		(end 424.16857 -401.179284)
		(width 0.10668)
		(layer "F.Cu")
		(net "NCF_A1_CPU0_P2_GND")
	)
	(segment
		(start 428.260256 -402.252688)
		(end 428.260256 -399.768568)
		(width 0.10668)
		(layer "F.Cu")
		(net "NCF_A1_CPU0_P2_GND")
	)
	(via
		(at 428.260256 -399.768568)
		(size 0.762)
		(drill 0.381)
		(layers "F.Cu" "B.Cu")
		(net "NCF_A1_CPU0_P2_GND")
	)
	(segment
		(start 357.897176 -402.706078)
		(end 357.594154 -403.0091)
		(width 0.10668)
		(layer "F.Cu")
		(net "NCF_A1_CPU0_P1_GND")
	)
	(segment
		(start 357.594154 -403.0091)
		(end 357.50881 -403.0091)
		(width 0.10668)
		(layer "F.Cu")
		(net "NCF_A1_CPU0_P1_GND")
	)
	(segment
		(start 355.902006 -406.116282)
		(end 355.348286 -406.116282)
		(width 0.10668)
		(layer "F.Cu")
		(net "NCF_A1_CPU0_P1_GND")
	)
	(segment
		(start 357.50881 -403.0091)
		(end 357.50881 -404.509478)
		(width 0.10668)
		(layer "F.Cu")
		(net "NCF_A1_CPU0_P1_GND")
	)
	(segment
		(start 356.045516 -399.663158)
		(end 357.354632 -400.972274)
		(width 0.10668)
		(layer "F.Cu")
		(net "NCF_A1_CPU0_P1_GND")
	)
	(segment
		(start 357.897176 -402.282152)
		(end 357.897176 -402.706078)
		(width 0.10668)
		(layer "F.Cu")
		(net "NCF_A1_CPU0_P1_GND")
	)
	(segment
		(start 357.354632 -400.972274)
		(end 357.897176 -402.282152)
		(width 0.10668)
		(layer "F.Cu")
		(net "NCF_A1_CPU0_P1_GND")
	)
	(segment
		(start 357.50881 -404.509478)
		(end 355.902006 -406.116282)
		(width 0.10668)
		(layer "F.Cu")
		(net "NCF_A1_CPU0_P1_GND")
	)
	(via
		(at 355.348286 -406.116282)
		(size 0.762)
		(drill 0.381)
		(layers "F.Cu" "B.Cu")
		(net "NCF_A1_CPU0_P1_GND")
	)
	(segment
		(start 325.369428 -402.500338)
		(end 325.369428 -402.88083)
		(width 0.10668)
		(layer "F.Cu")
		(net "NCF_A1_CPU0_P0_GND")
	)
	(segment
		(start 325.063358 -403.1869)
		(end 324.981062 -403.1869)
		(width 0.10668)
		(layer "F.Cu")
		(net "NCF_A1_CPU0_P0_GND")
	)
	(segment
		(start 323.517768 -399.663158)
		(end 324.826884 -400.972274)
		(width 0.10668)
		(layer "F.Cu")
		(net "NCF_A1_CPU0_P0_GND")
	)
	(segment
		(start 325.15683 -401.768818)
		(end 325.15683 -401.987004)
		(width 0.10668)
		(layer "F.Cu")
		(net "NCF_A1_CPU0_P0_GND")
	)
	(segment
		(start 324.981062 -404.509478)
		(end 324.981062 -403.1869)
		(width 0.10668)
		(layer "F.Cu")
		(net "NCF_A1_CPU0_P0_GND")
	)
	(segment
		(start 325.15683 -401.987004)
		(end 325.369428 -402.500338)
		(width 0.10668)
		(layer "F.Cu")
		(net "NCF_A1_CPU0_P0_GND")
	)
	(segment
		(start 323.44106 -406.04948)
		(end 324.981062 -404.509478)
		(width 0.10668)
		(layer "F.Cu")
		(net "NCF_A1_CPU0_P0_GND")
	)
	(segment
		(start 321.95262 -406.04948)
		(end 323.44106 -406.04948)
		(width 0.10668)
		(layer "F.Cu")
		(net "NCF_A1_CPU0_P0_GND")
	)
	(segment
		(start 325.369428 -402.88083)
		(end 325.063358 -403.1869)
		(width 0.10668)
		(layer "F.Cu")
		(net "NCF_A1_CPU0_P0_GND")
	)
	(segment
		(start 324.826884 -400.972274)
		(end 325.15683 -401.768818)
		(width 0.10668)
		(layer "F.Cu")
		(net "NCF_A1_CPU0_P0_GND")
	)
	(via
		(at 321.95262 -406.04948)
		(size 0.762)
		(drill 0.381)
		(layers "F.Cu" "B.Cu")
		(net "NCF_A1_CPU0_P0_GND")
	)
	(segment
		(start 368.600736 -403.552152)
		(end 368.867182 -403.552152)
		(width 0.10668)
		(layer "F.Cu")
		(net "MODE_RT_CPU0_P3")
	)
	(segment
		(start 369.003834 -401.373848)
		(end 369.003834 -402.577808)
		(width 0.10668)
		(layer "F.Cu")
		(net "MODE_RT_CPU0_P3")
	)
	(segment
		(start 368.867182 -403.552152)
		(end 369.09121 -403.77618)
		(width 0.10668)
		(layer "F.Cu")
		(net "MODE_RT_CPU0_P3")
	)
	(segment
		(start 368.76609 -402.815552)
		(end 368.600736 -402.815552)
		(width 0.10668)
		(layer "F.Cu")
		(net "MODE_RT_CPU0_P3")
	)
	(segment
		(start 368.682016 -397.412972)
		(end 368.127534 -397.412972)
		(width 0.10668)
		(layer "F.Cu")
		(net "MODE_RT_CPU0_P3")
	)
	(segment
		(start 369.09121 -403.77618)
		(end 369.09121 -404.665434)
		(width 0.10668)
		(layer "F.Cu")
		(net "MODE_RT_CPU0_P3")
	)
	(segment
		(start 367.3729 -398.167606)
		(end 367.3729 -399.742914)
		(width 0.10668)
		(layer "F.Cu")
		(net "MODE_RT_CPU0_P3")
	)
	(segment
		(start 369.003834 -402.577808)
		(end 368.76609 -402.815552)
		(width 0.10668)
		(layer "F.Cu")
		(net "MODE_RT_CPU0_P3")
	)
	(segment
		(start 369.09121 -404.665434)
		(end 368.860578 -404.896066)
		(width 0.10668)
		(layer "F.Cu")
		(net "MODE_RT_CPU0_P3")
	)
	(segment
		(start 368.600736 -403.552152)
		(end 368.600736 -402.815552)
		(width 0.10668)
		(layer "F.Cu")
		(net "MODE_RT_CPU0_P3")
	)
	(segment
		(start 368.127534 -397.412972)
		(end 367.3729 -398.167606)
		(width 0.10668)
		(layer "F.Cu")
		(net "MODE_RT_CPU0_P3")
	)
	(segment
		(start 367.3729 -399.742914)
		(end 369.003834 -401.373848)
		(width 0.10668)
		(layer "F.Cu")
		(net "MODE_RT_CPU0_P3")
	)
	(via
		(at 368.860578 -404.896066)
		(size 0.762)
		(drill 0.381)
		(layers "F.Cu" "B.Cu")
		(net "MODE_RT_CPU0_P3")
	)
	(segment
		(start 401.531582 -402.577808)
		(end 401.293838 -402.815552)
		(width 0.10668)
		(layer "F.Cu")
		(net "MODE_RT_CPU0_P2")
	)
	(segment
		(start 401.39493 -403.552152)
		(end 401.618958 -403.77618)
		(width 0.10668)
		(layer "F.Cu")
		(net "MODE_RT_CPU0_P2")
	)
	(segment
		(start 399.9103 -398.109186)
		(end 399.9103 -399.762726)
		(width 0.10668)
		(layer "F.Cu")
		(net "MODE_RT_CPU0_P2")
	)
	(segment
		(start 401.128484 -403.552152)
		(end 401.128484 -402.815552)
		(width 0.10668)
		(layer "F.Cu")
		(net "MODE_RT_CPU0_P2")
	)
	(segment
		(start 401.531582 -401.384008)
		(end 401.531582 -402.577808)
		(width 0.10668)
		(layer "F.Cu")
		(net "MODE_RT_CPU0_P2")
	)
	(segment
		(start 399.9103 -399.762726)
		(end 401.531582 -401.384008)
		(width 0.10668)
		(layer "F.Cu")
		(net "MODE_RT_CPU0_P2")
	)
	(segment
		(start 401.618958 -404.665434)
		(end 401.388326 -404.896066)
		(width 0.10668)
		(layer "F.Cu")
		(net "MODE_RT_CPU0_P2")
	)
	(segment
		(start 401.128484 -403.552152)
		(end 401.39493 -403.552152)
		(width 0.10668)
		(layer "F.Cu")
		(net "MODE_RT_CPU0_P2")
	)
	(segment
		(start 401.293838 -402.815552)
		(end 401.128484 -402.815552)
		(width 0.10668)
		(layer "F.Cu")
		(net "MODE_RT_CPU0_P2")
	)
	(segment
		(start 400.606514 -397.412972)
		(end 399.9103 -398.109186)
		(width 0.10668)
		(layer "F.Cu")
		(net "MODE_RT_CPU0_P2")
	)
	(segment
		(start 401.209764 -397.412972)
		(end 400.606514 -397.412972)
		(width 0.10668)
		(layer "F.Cu")
		(net "MODE_RT_CPU0_P2")
	)
	(segment
		(start 401.618958 -403.77618)
		(end 401.618958 -404.665434)
		(width 0.10668)
		(layer "F.Cu")
		(net "MODE_RT_CPU0_P2")
	)
	(via
		(at 401.388326 -404.896066)
		(size 0.762)
		(drill 0.381)
		(layers "F.Cu" "B.Cu")
		(net "MODE_RT_CPU0_P2")
	)
	(segment
		(start 334.028288 -403.552152)
		(end 334.028288 -402.815552)
		(width 0.10668)
		(layer "F.Cu")
		(net "MODE_RT_CPU0_P1")
	)
	(segment
		(start 332.7908 -399.765774)
		(end 334.431386 -401.40636)
		(width 0.10668)
		(layer "F.Cu")
		(net "MODE_RT_CPU0_P1")
	)
	(segment
		(start 334.028288 -403.552152)
		(end 334.294734 -403.552152)
		(width 0.10668)
		(layer "F.Cu")
		(net "MODE_RT_CPU0_P1")
	)
	(segment
		(start 334.109568 -397.412972)
		(end 333.520542 -397.412972)
		(width 0.10668)
		(layer "F.Cu")
		(net "MODE_RT_CPU0_P1")
	)
	(segment
		(start 334.518762 -403.77618)
		(end 334.518762 -404.665434)
		(width 0.10668)
		(layer "F.Cu")
		(net "MODE_RT_CPU0_P1")
	)
	(segment
		(start 334.431386 -402.577808)
		(end 334.193642 -402.815552)
		(width 0.10668)
		(layer "F.Cu")
		(net "MODE_RT_CPU0_P1")
	)
	(segment
		(start 333.520542 -397.412972)
		(end 332.7908 -398.142714)
		(width 0.10668)
		(layer "F.Cu")
		(net "MODE_RT_CPU0_P1")
	)
	(segment
		(start 334.193642 -402.815552)
		(end 334.028288 -402.815552)
		(width 0.10668)
		(layer "F.Cu")
		(net "MODE_RT_CPU0_P1")
	)
	(segment
		(start 334.294734 -403.552152)
		(end 334.518762 -403.77618)
		(width 0.10668)
		(layer "F.Cu")
		(net "MODE_RT_CPU0_P1")
	)
	(segment
		(start 334.431386 -401.40636)
		(end 334.431386 -402.577808)
		(width 0.10668)
		(layer "F.Cu")
		(net "MODE_RT_CPU0_P1")
	)
	(segment
		(start 334.518762 -404.665434)
		(end 334.28813 -404.896066)
		(width 0.10668)
		(layer "F.Cu")
		(net "MODE_RT_CPU0_P1")
	)
	(segment
		(start 332.7908 -398.142714)
		(end 332.7908 -399.765774)
		(width 0.10668)
		(layer "F.Cu")
		(net "MODE_RT_CPU0_P1")
	)
	(via
		(at 334.28813 -404.896066)
		(size 0.762)
		(drill 0.381)
		(layers "F.Cu" "B.Cu")
		(net "MODE_RT_CPU0_P1")
	)
	(segment
		(start 298.646342 -398.272)
		(end 298.27474 -398.643602)
		(width 0.10668)
		(layer "F.Cu")
		(net "MODE_RT_CPU0_P0")
	)
	(segment
		(start 297.548046 -398.643602)
		(end 297.287442 -398.904206)
		(width 0.10668)
		(layer "F.Cu")
		(net "MODE_RT_CPU0_P0")
	)
	(segment
		(start 300.990508 -397.412972)
		(end 300.13148 -398.272)
		(width 0.10668)
		(layer "F.Cu")
		(net "MODE_RT_CPU0_P0")
	)
	(segment
		(start 298.27474 -398.643602)
		(end 297.548046 -398.643602)
		(width 0.10668)
		(layer "F.Cu")
		(net "MODE_RT_CPU0_P0")
	)
	(segment
		(start 297.287442 -398.904206)
		(end 297.287442 -399.034)
		(width 0.10668)
		(layer "F.Cu")
		(net "MODE_RT_CPU0_P0")
	)
	(segment
		(start 297.274742 -399.0467)
		(end 297.287442 -399.034)
		(width 0.10668)
		(layer "F.Cu")
		(net "MODE_RT_CPU0_P0")
	)
	(segment
		(start 301.58182 -397.412972)
		(end 300.990508 -397.412972)
		(width 0.10668)
		(layer "F.Cu")
		(net "MODE_RT_CPU0_P0")
	)
	(segment
		(start 296.385742 -399.0467)
		(end 297.274742 -399.0467)
		(width 0.10668)
		(layer "F.Cu")
		(net "MODE_RT_CPU0_P0")
	)
	(segment
		(start 300.13148 -398.272)
		(end 298.646342 -398.272)
		(width 0.10668)
		(layer "F.Cu")
		(net "MODE_RT_CPU0_P0")
	)
	(via
		(at 298.646342 -398.272)
		(size 0.762)
		(drill 0.381)
		(layers "F.Cu" "B.Cu")
		(net "MODE_RT_CPU0_P0")
	)
	(segment
		(start 369.687094 -404.606506)
		(end 369.687094 -403.869906)
		(width 0.10668)
		(layer "F.Cu")
		(net "JTAG_TEST_MODE_RT_CPU0_P3")
	)
	(segment
		(start 369.687094 -403.869906)
		(end 370.217954 -403.869906)
		(width 0.10668)
		(layer "F.Cu")
		(net "JTAG_TEST_MODE_RT_CPU0_P3")
	)
	(segment
		(start 367.749582 -399.634202)
		(end 370.456968 -402.341588)
		(width 0.10668)
		(layer "F.Cu")
		(net "JTAG_TEST_MODE_RT_CPU0_P3")
	)
	(segment
		(start 368.322352 -397.712946)
		(end 367.749582 -398.285716)
		(width 0.10668)
		(layer "F.Cu")
		(net "JTAG_TEST_MODE_RT_CPU0_P3")
	)
	(segment
		(start 370.456968 -403.49678)
		(end 370.524024 -403.563836)
		(width 0.10668)
		(layer "F.Cu")
		(net "JTAG_TEST_MODE_RT_CPU0_P3")
	)
	(segment
		(start 369.2017 -397.712946)
		(end 368.322352 -397.712946)
		(width 0.10668)
		(layer "F.Cu")
		(net "JTAG_TEST_MODE_RT_CPU0_P3")
	)
	(segment
		(start 370.217954 -403.869906)
		(end 370.524024 -403.563836)
		(width 0.10668)
		(layer "F.Cu")
		(net "JTAG_TEST_MODE_RT_CPU0_P3")
	)
	(segment
		(start 370.456968 -402.341588)
		(end 370.456968 -403.49678)
		(width 0.10668)
		(layer "F.Cu")
		(net "JTAG_TEST_MODE_RT_CPU0_P3")
	)
	(segment
		(start 367.749582 -398.285716)
		(end 367.749582 -399.634202)
		(width 0.10668)
		(layer "F.Cu")
		(net "JTAG_TEST_MODE_RT_CPU0_P3")
	)
	(via
		(at 370.524024 -403.563836)
		(size 0.762)
		(drill 0.381)
		(layers "F.Cu" "B.Cu")
		(net "JTAG_TEST_MODE_RT_CPU0_P3")
	)
	(segment
		(start 402.984716 -403.49678)
		(end 403.051772 -403.563836)
		(width 0.10668)
		(layer "F.Cu")
		(net "JTAG_TEST_MODE_RT_CPU0_P2")
	)
	(segment
		(start 402.214842 -404.606506)
		(end 402.214842 -403.869906)
		(width 0.10668)
		(layer "F.Cu")
		(net "JTAG_TEST_MODE_RT_CPU0_P2")
	)
	(segment
		(start 400.8501 -397.712946)
		(end 400.27733 -398.285716)
		(width 0.10668)
		(layer "F.Cu")
		(net "JTAG_TEST_MODE_RT_CPU0_P2")
	)
	(segment
		(start 400.27733 -398.285716)
		(end 400.27733 -399.60423)
		(width 0.10668)
		(layer "F.Cu")
		(net "JTAG_TEST_MODE_RT_CPU0_P2")
	)
	(segment
		(start 400.27733 -399.60423)
		(end 402.984716 -402.311616)
		(width 0.10668)
		(layer "F.Cu")
		(net "JTAG_TEST_MODE_RT_CPU0_P2")
	)
	(segment
		(start 402.984716 -402.311616)
		(end 402.984716 -403.49678)
		(width 0.10668)
		(layer "F.Cu")
		(net "JTAG_TEST_MODE_RT_CPU0_P2")
	)
	(segment
		(start 402.214842 -403.869906)
		(end 402.745702 -403.869906)
		(width 0.10668)
		(layer "F.Cu")
		(net "JTAG_TEST_MODE_RT_CPU0_P2")
	)
	(segment
		(start 402.745702 -403.869906)
		(end 403.051772 -403.563836)
		(width 0.10668)
		(layer "F.Cu")
		(net "JTAG_TEST_MODE_RT_CPU0_P2")
	)
	(segment
		(start 401.729448 -397.712946)
		(end 400.8501 -397.712946)
		(width 0.10668)
		(layer "F.Cu")
		(net "JTAG_TEST_MODE_RT_CPU0_P2")
	)
	(via
		(at 403.051772 -403.563836)
		(size 0.762)
		(drill 0.381)
		(layers "F.Cu" "B.Cu")
		(net "JTAG_TEST_MODE_RT_CPU0_P2")
	)
	(segment
		(start 333.177134 -399.638774)
		(end 335.88452 -402.34616)
		(width 0.10668)
		(layer "F.Cu")
		(net "JTAG_TEST_MODE_RT_CPU0_P1")
	)
	(segment
		(start 335.114646 -404.606506)
		(end 335.114646 -403.869906)
		(width 0.10668)
		(layer "F.Cu")
		(net "JTAG_TEST_MODE_RT_CPU0_P1")
	)
	(segment
		(start 333.177134 -398.285716)
		(end 333.177134 -399.638774)
		(width 0.10668)
		(layer "F.Cu")
		(net "JTAG_TEST_MODE_RT_CPU0_P1")
	)
	(segment
		(start 335.645506 -403.869906)
		(end 335.951576 -403.563836)
		(width 0.10668)
		(layer "F.Cu")
		(net "JTAG_TEST_MODE_RT_CPU0_P1")
	)
	(segment
		(start 335.88452 -403.49678)
		(end 335.951576 -403.563836)
		(width 0.10668)
		(layer "F.Cu")
		(net "JTAG_TEST_MODE_RT_CPU0_P1")
	)
	(segment
		(start 335.88452 -402.34616)
		(end 335.88452 -403.49678)
		(width 0.10668)
		(layer "F.Cu")
		(net "JTAG_TEST_MODE_RT_CPU0_P1")
	)
	(segment
		(start 334.629252 -397.712946)
		(end 333.749904 -397.712946)
		(width 0.10668)
		(layer "F.Cu")
		(net "JTAG_TEST_MODE_RT_CPU0_P1")
	)
	(segment
		(start 333.749904 -397.712946)
		(end 333.177134 -398.285716)
		(width 0.10668)
		(layer "F.Cu")
		(net "JTAG_TEST_MODE_RT_CPU0_P1")
	)
	(segment
		(start 335.114646 -403.869906)
		(end 335.645506 -403.869906)
		(width 0.10668)
		(layer "F.Cu")
		(net "JTAG_TEST_MODE_RT_CPU0_P1")
	)
	(via
		(at 335.951576 -403.563836)
		(size 0.762)
		(drill 0.381)
		(layers "F.Cu" "B.Cu")
		(net "JTAG_TEST_MODE_RT_CPU0_P1")
	)
	(segment
		(start 298.331636 -400.55038)
		(end 297.477434 -400.55038)
		(width 0.10668)
		(layer "F.Cu")
		(net "JTAG_TEST_MODE_RT_CPU0_P0")
	)
	(segment
		(start 298.646342 -400.235674)
		(end 298.331636 -400.55038)
		(width 0.10668)
		(layer "F.Cu")
		(net "JTAG_TEST_MODE_RT_CPU0_P0")
	)
	(segment
		(start 296.385742 -399.8849)
		(end 296.995342 -399.8849)
		(width 0.10668)
		(layer "F.Cu")
		(net "JTAG_TEST_MODE_RT_CPU0_P0")
	)
	(segment
		(start 300.297596 -398.601438)
		(end 299.586904 -398.601438)
		(width 0.10668)
		(layer "F.Cu")
		(net "JTAG_TEST_MODE_RT_CPU0_P0")
	)
	(segment
		(start 297.477434 -400.55038)
		(end 297.287442 -400.360388)
		(width 0.10668)
		(layer "F.Cu")
		(net "JTAG_TEST_MODE_RT_CPU0_P0")
	)
	(segment
		(start 298.646342 -399.542)
		(end 298.646342 -400.235674)
		(width 0.10668)
		(layer "F.Cu")
		(net "JTAG_TEST_MODE_RT_CPU0_P0")
	)
	(segment
		(start 302.101504 -397.712946)
		(end 301.186088 -397.712946)
		(width 0.10668)
		(layer "F.Cu")
		(net "JTAG_TEST_MODE_RT_CPU0_P0")
	)
	(segment
		(start 296.995342 -399.8849)
		(end 297.287442 -400.177)
		(width 0.10668)
		(layer "F.Cu")
		(net "JTAG_TEST_MODE_RT_CPU0_P0")
	)
	(segment
		(start 301.186088 -397.712946)
		(end 300.297596 -398.601438)
		(width 0.10668)
		(layer "F.Cu")
		(net "JTAG_TEST_MODE_RT_CPU0_P0")
	)
	(segment
		(start 299.586904 -398.601438)
		(end 298.646342 -399.542)
		(width 0.10668)
		(layer "F.Cu")
		(net "JTAG_TEST_MODE_RT_CPU0_P0")
	)
	(segment
		(start 297.287442 -400.360388)
		(end 297.287442 -400.177)
		(width 0.10668)
		(layer "F.Cu")
		(net "JTAG_TEST_MODE_RT_CPU0_P0")
	)
	(via
		(at 298.646342 -399.542)
		(size 0.762)
		(drill 0.381)
		(layers "F.Cu" "B.Cu")
		(net "JTAG_TEST_MODE_RT_CPU0_P0")
	)
	(segment
		(start 365.33201 -393.04468)
		(end 365.305086 -393.017756)
		(width 0.10668)
		(layer "F.Cu")
		(net "GPIO3_RT_CPU0_P3")
	)
	(segment
		(start 366.09909 -393.04468)
		(end 365.33201 -393.04468)
		(width 0.10668)
		(layer "F.Cu")
		(net "GPIO3_RT_CPU0_P3")
	)
	(segment
		(start 366.25657 -392.58494)
		(end 366.09909 -392.74242)
		(width 0.10668)
		(layer "F.Cu")
		(net "GPIO3_RT_CPU0_P3")
	)
	(segment
		(start 367.819432 -393.141962)
		(end 367.819432 -393.000992)
		(width 0.10668)
		(layer "F.Cu")
		(net "GPIO3_RT_CPU0_P3")
	)
	(segment
		(start 366.09909 -392.74242)
		(end 366.09909 -393.04468)
		(width 0.10668)
		(layer "F.Cu")
		(net "GPIO3_RT_CPU0_P3")
	)
	(segment
		(start 367.40338 -392.58494)
		(end 366.25657 -392.58494)
		(width 0.10668)
		(layer "F.Cu")
		(net "GPIO3_RT_CPU0_P3")
	)
	(segment
		(start 368.682016 -393.81303)
		(end 368.4905 -393.81303)
		(width 0.10668)
		(layer "F.Cu")
		(net "GPIO3_RT_CPU0_P3")
	)
	(segment
		(start 368.4905 -393.81303)
		(end 367.819432 -393.141962)
		(width 0.10668)
		(layer "F.Cu")
		(net "GPIO3_RT_CPU0_P3")
	)
	(segment
		(start 367.819432 -393.000992)
		(end 367.40338 -392.58494)
		(width 0.10668)
		(layer "F.Cu")
		(net "GPIO3_RT_CPU0_P3")
	)
	(via
		(at 365.305086 -393.017756)
		(size 0.762)
		(drill 0.381)
		(layers "F.Cu" "B.Cu")
		(net "GPIO3_RT_CPU0_P3")
	)
	(segment
		(start 397.859758 -393.04468)
		(end 397.832834 -393.017756)
		(width 0.10668)
		(layer "F.Cu")
		(net "GPIO3_RT_CPU0_P2")
	)
	(segment
		(start 400.34718 -393.000992)
		(end 399.931128 -392.58494)
		(width 0.10668)
		(layer "F.Cu")
		(net "GPIO3_RT_CPU0_P2")
	)
	(segment
		(start 398.626838 -392.74242)
		(end 398.626838 -393.04468)
		(width 0.10668)
		(layer "F.Cu")
		(net "GPIO3_RT_CPU0_P2")
	)
	(segment
		(start 399.931128 -392.58494)
		(end 398.784318 -392.58494)
		(width 0.10668)
		(layer "F.Cu")
		(net "GPIO3_RT_CPU0_P2")
	)
	(segment
		(start 401.018248 -393.81303)
		(end 400.34718 -393.141962)
		(width 0.10668)
		(layer "F.Cu")
		(net "GPIO3_RT_CPU0_P2")
	)
	(segment
		(start 398.626838 -393.04468)
		(end 397.859758 -393.04468)
		(width 0.10668)
		(layer "F.Cu")
		(net "GPIO3_RT_CPU0_P2")
	)
	(segment
		(start 401.209764 -393.81303)
		(end 401.018248 -393.81303)
		(width 0.10668)
		(layer "F.Cu")
		(net "GPIO3_RT_CPU0_P2")
	)
	(segment
		(start 398.784318 -392.58494)
		(end 398.626838 -392.74242)
		(width 0.10668)
		(layer "F.Cu")
		(net "GPIO3_RT_CPU0_P2")
	)
	(segment
		(start 400.34718 -393.141962)
		(end 400.34718 -393.000992)
		(width 0.10668)
		(layer "F.Cu")
		(net "GPIO3_RT_CPU0_P2")
	)
	(via
		(at 397.832834 -393.017756)
		(size 0.762)
		(drill 0.381)
		(layers "F.Cu" "B.Cu")
		(net "GPIO3_RT_CPU0_P2")
	)
	(segment
		(start 331.526642 -392.74242)
		(end 331.526642 -393.04468)
		(width 0.10668)
		(layer "F.Cu")
		(net "GPIO3_RT_CPU0_P1")
	)
	(segment
		(start 331.684122 -392.58494)
		(end 331.526642 -392.74242)
		(width 0.10668)
		(layer "F.Cu")
		(net "GPIO3_RT_CPU0_P1")
	)
	(segment
		(start 333.918052 -393.81303)
		(end 333.246984 -393.141962)
		(width 0.10668)
		(layer "F.Cu")
		(net "GPIO3_RT_CPU0_P1")
	)
	(segment
		(start 332.830932 -392.58494)
		(end 331.684122 -392.58494)
		(width 0.10668)
		(layer "F.Cu")
		(net "GPIO3_RT_CPU0_P1")
	)
	(segment
		(start 334.109568 -393.81303)
		(end 333.918052 -393.81303)
		(width 0.10668)
		(layer "F.Cu")
		(net "GPIO3_RT_CPU0_P1")
	)
	(segment
		(start 333.246984 -393.141962)
		(end 333.246984 -393.000992)
		(width 0.10668)
		(layer "F.Cu")
		(net "GPIO3_RT_CPU0_P1")
	)
	(segment
		(start 331.526642 -393.04468)
		(end 330.759562 -393.04468)
		(width 0.10668)
		(layer "F.Cu")
		(net "GPIO3_RT_CPU0_P1")
	)
	(segment
		(start 333.246984 -393.000992)
		(end 332.830932 -392.58494)
		(width 0.10668)
		(layer "F.Cu")
		(net "GPIO3_RT_CPU0_P1")
	)
	(segment
		(start 330.759562 -393.04468)
		(end 330.732638 -393.017756)
		(width 0.10668)
		(layer "F.Cu")
		(net "GPIO3_RT_CPU0_P1")
	)
	(via
		(at 330.732638 -393.017756)
		(size 0.762)
		(drill 0.381)
		(layers "F.Cu" "B.Cu")
		(net "GPIO3_RT_CPU0_P1")
	)
	(segment
		(start 299.156374 -392.58494)
		(end 298.998894 -392.74242)
		(width 0.10668)
		(layer "F.Cu")
		(net "GPIO3_RT_CPU0_P0")
	)
	(segment
		(start 300.719236 -393.141962)
		(end 300.719236 -393.000992)
		(width 0.10668)
		(layer "F.Cu")
		(net "GPIO3_RT_CPU0_P0")
	)
	(segment
		(start 300.719236 -393.000992)
		(end 300.303184 -392.58494)
		(width 0.10668)
		(layer "F.Cu")
		(net "GPIO3_RT_CPU0_P0")
	)
	(segment
		(start 300.303184 -392.58494)
		(end 299.156374 -392.58494)
		(width 0.10668)
		(layer "F.Cu")
		(net "GPIO3_RT_CPU0_P0")
	)
	(segment
		(start 298.998894 -393.04468)
		(end 298.209462 -393.04468)
		(width 0.10668)
		(layer "F.Cu")
		(net "GPIO3_RT_CPU0_P0")
	)
	(segment
		(start 301.390304 -393.81303)
		(end 300.719236 -393.141962)
		(width 0.10668)
		(layer "F.Cu")
		(net "GPIO3_RT_CPU0_P0")
	)
	(segment
		(start 298.998894 -392.74242)
		(end 298.998894 -393.04468)
		(width 0.10668)
		(layer "F.Cu")
		(net "GPIO3_RT_CPU0_P0")
	)
	(segment
		(start 301.58182 -393.81303)
		(end 301.390304 -393.81303)
		(width 0.10668)
		(layer "F.Cu")
		(net "GPIO3_RT_CPU0_P0")
	)
	(via
		(at 298.209462 -393.04468)
		(size 0.762)
		(drill 0.381)
		(layers "F.Cu" "B.Cu")
		(net "GPIO3_RT_CPU0_P0")
	)
	(segment
		(start 366.253776 -393.50442)
		(end 367.46053 -393.50442)
		(width 0.10668)
		(layer "F.Cu")
		(net "GPIO2_RT_CPU0_P3")
	)
	(segment
		(start 367.46053 -393.50442)
		(end 367.65738 -393.70127)
		(width 0.10668)
		(layer "F.Cu")
		(net "GPIO2_RT_CPU0_P3")
	)
	(segment
		(start 365.747808 -393.96416)
		(end 366.09909 -393.96416)
		(width 0.10668)
		(layer "F.Cu")
		(net "GPIO2_RT_CPU0_P3")
	)
	(segment
		(start 366.09909 -393.96416)
		(end 366.09909 -393.659106)
		(width 0.10668)
		(layer "F.Cu")
		(net "GPIO2_RT_CPU0_P3")
	)
	(segment
		(start 365.36249 -393.86256)
		(end 365.646208 -393.86256)
		(width 0.10668)
		(layer "F.Cu")
		(net "GPIO2_RT_CPU0_P3")
	)
	(segment
		(start 364.28299 -394.32484)
		(end 363.1692 -395.43863)
		(width 0.10668)
		(layer "F.Cu")
		(net "GPIO2_RT_CPU0_P3")
	)
	(segment
		(start 365.36249 -394.19784)
		(end 365.23549 -394.32484)
		(width 0.10668)
		(layer "F.Cu")
		(net "GPIO2_RT_CPU0_P3")
	)
	(segment
		(start 367.65738 -393.70127)
		(end 367.65738 -394.238734)
		(width 0.10668)
		(layer "F.Cu")
		(net "GPIO2_RT_CPU0_P3")
	)
	(segment
		(start 365.646208 -393.86256)
		(end 365.747808 -393.96416)
		(width 0.10668)
		(layer "F.Cu")
		(net "GPIO2_RT_CPU0_P3")
	)
	(segment
		(start 365.36249 -393.86256)
		(end 365.36249 -394.19784)
		(width 0.10668)
		(layer "F.Cu")
		(net "GPIO2_RT_CPU0_P3")
	)
	(segment
		(start 367.65738 -394.238734)
		(end 367.831624 -394.412978)
		(width 0.10668)
		(layer "F.Cu")
		(net "GPIO2_RT_CPU0_P3")
	)
	(segment
		(start 363.1692 -395.43863)
		(end 363.1692 -395.671548)
		(width 0.10668)
		(layer "F.Cu")
		(net "GPIO2_RT_CPU0_P3")
	)
	(segment
		(start 366.09909 -393.659106)
		(end 366.253776 -393.50442)
		(width 0.10668)
		(layer "F.Cu")
		(net "GPIO2_RT_CPU0_P3")
	)
	(segment
		(start 367.831624 -394.412978)
		(end 368.682016 -394.412978)
		(width 0.10668)
		(layer "F.Cu")
		(net "GPIO2_RT_CPU0_P3")
	)
	(segment
		(start 365.23549 -394.32484)
		(end 364.28299 -394.32484)
		(width 0.10668)
		(layer "F.Cu")
		(net "GPIO2_RT_CPU0_P3")
	)
	(via
		(at 363.1692 -395.671548)
		(size 0.762)
		(drill 0.381)
		(layers "F.Cu" "B.Cu")
		(net "GPIO2_RT_CPU0_P3")
	)
	(segment
		(start 400.185128 -394.238734)
		(end 400.359372 -394.412978)
		(width 0.10668)
		(layer "F.Cu")
		(net "GPIO2_RT_CPU0_P2")
	)
	(segment
		(start 397.890238 -394.205206)
		(end 397.729964 -394.36548)
		(width 0.10668)
		(layer "F.Cu")
		(net "GPIO2_RT_CPU0_P2")
	)
	(segment
		(start 398.781524 -393.50442)
		(end 399.988278 -393.50442)
		(width 0.10668)
		(layer "F.Cu")
		(net "GPIO2_RT_CPU0_P2")
	)
	(segment
		(start 400.359372 -394.412978)
		(end 401.209764 -394.412978)
		(width 0.10668)
		(layer "F.Cu")
		(net "GPIO2_RT_CPU0_P2")
	)
	(segment
		(start 398.267936 -393.96416)
		(end 398.626838 -393.96416)
		(width 0.10668)
		(layer "F.Cu")
		(net "GPIO2_RT_CPU0_P2")
	)
	(segment
		(start 399.988278 -393.50442)
		(end 400.185128 -393.70127)
		(width 0.10668)
		(layer "F.Cu")
		(net "GPIO2_RT_CPU0_P2")
	)
	(segment
		(start 400.185128 -393.70127)
		(end 400.185128 -394.238734)
		(width 0.10668)
		(layer "F.Cu")
		(net "GPIO2_RT_CPU0_P2")
	)
	(segment
		(start 397.729964 -394.36548)
		(end 396.770098 -394.36548)
		(width 0.10668)
		(layer "F.Cu")
		(net "GPIO2_RT_CPU0_P2")
	)
	(segment
		(start 398.626838 -393.659106)
		(end 398.781524 -393.50442)
		(width 0.10668)
		(layer "F.Cu")
		(net "GPIO2_RT_CPU0_P2")
	)
	(segment
		(start 397.890238 -393.86256)
		(end 398.166336 -393.86256)
		(width 0.10668)
		(layer "F.Cu")
		(net "GPIO2_RT_CPU0_P2")
	)
	(segment
		(start 398.626838 -393.96416)
		(end 398.626838 -393.659106)
		(width 0.10668)
		(layer "F.Cu")
		(net "GPIO2_RT_CPU0_P2")
	)
	(segment
		(start 398.166336 -393.86256)
		(end 398.267936 -393.96416)
		(width 0.10668)
		(layer "F.Cu")
		(net "GPIO2_RT_CPU0_P2")
	)
	(segment
		(start 396.770098 -394.36548)
		(end 396.622778 -394.5128)
		(width 0.10668)
		(layer "F.Cu")
		(net "GPIO2_RT_CPU0_P2")
	)
	(segment
		(start 397.890238 -393.86256)
		(end 397.890238 -394.205206)
		(width 0.10668)
		(layer "F.Cu")
		(net "GPIO2_RT_CPU0_P2")
	)
	(via
		(at 396.622778 -394.5128)
		(size 0.762)
		(drill 0.381)
		(layers "F.Cu" "B.Cu")
		(net "GPIO2_RT_CPU0_P2")
	)
	(segment
		(start 331.526642 -393.96416)
		(end 331.526642 -393.659106)
		(width 0.10668)
		(layer "F.Cu")
		(net "GPIO2_RT_CPU0_P1")
	)
	(segment
		(start 333.084932 -393.70127)
		(end 333.084932 -394.238734)
		(width 0.10668)
		(layer "F.Cu")
		(net "GPIO2_RT_CPU0_P1")
	)
	(segment
		(start 330.790042 -394.154152)
		(end 330.663042 -394.281152)
		(width 0.10668)
		(layer "F.Cu")
		(net "GPIO2_RT_CPU0_P1")
	)
	(segment
		(start 333.259176 -394.412978)
		(end 334.109568 -394.412978)
		(width 0.10668)
		(layer "F.Cu")
		(net "GPIO2_RT_CPU0_P1")
	)
	(segment
		(start 330.790042 -393.86256)
		(end 331.066648 -393.86256)
		(width 0.10668)
		(layer "F.Cu")
		(net "GPIO2_RT_CPU0_P1")
	)
	(segment
		(start 329.75423 -394.281152)
		(end 329.522582 -394.5128)
		(width 0.10668)
		(layer "F.Cu")
		(net "GPIO2_RT_CPU0_P1")
	)
	(segment
		(start 332.888082 -393.50442)
		(end 333.084932 -393.70127)
		(width 0.10668)
		(layer "F.Cu")
		(net "GPIO2_RT_CPU0_P1")
	)
	(segment
		(start 331.526642 -393.659106)
		(end 331.681328 -393.50442)
		(width 0.10668)
		(layer "F.Cu")
		(net "GPIO2_RT_CPU0_P1")
	)
	(segment
		(start 333.084932 -394.238734)
		(end 333.259176 -394.412978)
		(width 0.10668)
		(layer "F.Cu")
		(net "GPIO2_RT_CPU0_P1")
	)
	(segment
		(start 330.790042 -393.86256)
		(end 330.790042 -394.154152)
		(width 0.10668)
		(layer "F.Cu")
		(net "GPIO2_RT_CPU0_P1")
	)
	(segment
		(start 331.168248 -393.96416)
		(end 331.526642 -393.96416)
		(width 0.10668)
		(layer "F.Cu")
		(net "GPIO2_RT_CPU0_P1")
	)
	(segment
		(start 331.681328 -393.50442)
		(end 332.888082 -393.50442)
		(width 0.10668)
		(layer "F.Cu")
		(net "GPIO2_RT_CPU0_P1")
	)
	(segment
		(start 330.663042 -394.281152)
		(end 329.75423 -394.281152)
		(width 0.10668)
		(layer "F.Cu")
		(net "GPIO2_RT_CPU0_P1")
	)
	(segment
		(start 331.066648 -393.86256)
		(end 331.168248 -393.96416)
		(width 0.10668)
		(layer "F.Cu")
		(net "GPIO2_RT_CPU0_P1")
	)
	(via
		(at 329.522582 -394.5128)
		(size 0.762)
		(drill 0.381)
		(layers "F.Cu" "B.Cu")
		(net "GPIO2_RT_CPU0_P1")
	)
	(segment
		(start 298.262294 -393.96416)
		(end 298.998894 -393.96416)
		(width 0.10668)
		(layer "F.Cu")
		(net "GPIO2_RT_CPU0_P0")
	)
	(segment
		(start 296.69486 -394.707872)
		(end 296.339514 -395.063218)
		(width 0.10668)
		(layer "F.Cu")
		(net "GPIO2_RT_CPU0_P0")
	)
	(segment
		(start 298.079668 -394.387324)
		(end 297.744896 -394.387324)
		(width 0.10668)
		(layer "F.Cu")
		(net "GPIO2_RT_CPU0_P0")
	)
	(segment
		(start 298.262294 -394.204698)
		(end 298.079668 -394.387324)
		(width 0.10668)
		(layer "F.Cu")
		(net "GPIO2_RT_CPU0_P0")
	)
	(segment
		(start 300.731428 -394.412978)
		(end 301.58182 -394.412978)
		(width 0.10668)
		(layer "F.Cu")
		(net "GPIO2_RT_CPU0_P0")
	)
	(segment
		(start 296.971212 -394.707872)
		(end 296.69486 -394.707872)
		(width 0.10668)
		(layer "F.Cu")
		(net "GPIO2_RT_CPU0_P0")
	)
	(segment
		(start 298.998894 -393.659106)
		(end 299.15358 -393.50442)
		(width 0.10668)
		(layer "F.Cu")
		(net "GPIO2_RT_CPU0_P0")
	)
	(segment
		(start 300.557184 -394.238734)
		(end 300.731428 -394.412978)
		(width 0.10668)
		(layer "F.Cu")
		(net "GPIO2_RT_CPU0_P0")
	)
	(segment
		(start 298.262294 -393.96416)
		(end 298.262294 -394.204698)
		(width 0.10668)
		(layer "F.Cu")
		(net "GPIO2_RT_CPU0_P0")
	)
	(segment
		(start 297.744896 -394.387324)
		(end 296.971212 -394.707872)
		(width 0.10668)
		(layer "F.Cu")
		(net "GPIO2_RT_CPU0_P0")
	)
	(segment
		(start 299.15358 -393.50442)
		(end 300.360334 -393.50442)
		(width 0.10668)
		(layer "F.Cu")
		(net "GPIO2_RT_CPU0_P0")
	)
	(segment
		(start 300.557184 -393.70127)
		(end 300.557184 -394.238734)
		(width 0.10668)
		(layer "F.Cu")
		(net "GPIO2_RT_CPU0_P0")
	)
	(segment
		(start 298.998894 -393.96416)
		(end 298.998894 -393.659106)
		(width 0.10668)
		(layer "F.Cu")
		(net "GPIO2_RT_CPU0_P0")
	)
	(segment
		(start 300.360334 -393.50442)
		(end 300.557184 -393.70127)
		(width 0.10668)
		(layer "F.Cu")
		(net "GPIO2_RT_CPU0_P0")
	)
	(via
		(at 296.339514 -395.063218)
		(size 0.762)
		(drill 0.381)
		(layers "F.Cu" "B.Cu")
		(net "GPIO2_RT_CPU0_P0")
	)
	(segment
		(start 169.664634 -426.470826)
		(end 169.664634 -428.095918)
		(width 0.10668)
		(layer "F.Cu")
		(net "U21_E2")
	)
	(segment
		(start 169.664634 -428.281592)
		(end 169.497248 -428.448978)
		(width 0.10668)
		(layer "F.Cu")
		(net "U21_E2")
	)
	(segment
		(start 169.497248 -428.448978)
		(end 169.497248 -429.022002)
		(width 0.10668)
		(layer "F.Cu")
		(net "U21_E2")
	)
	(segment
		(start 169.664634 -428.095918)
		(end 169.664634 -428.281592)
		(width 0.10668)
		(layer "F.Cu")
		(net "U21_E2")
	)
	(via
		(at 169.664634 -428.095918)
		(size 0.762)
		(drill 0.381)
		(layers "F.Cu" "B.Cu")
		(net "U21_E2")
	)
	(segment
		(start 163.332414 -427.452282)
		(end 163.648136 -427.13656)
		(width 0.10668)
		(layer "F.Cu")
		(net "U20_E2")
	)
	(segment
		(start 163.43757 -428.23638)
		(end 163.332414 -428.131224)
		(width 0.10668)
		(layer "F.Cu")
		(net "U20_E2")
	)
	(segment
		(start 163.648136 -427.13656)
		(end 163.648136 -426.41647)
		(width 0.10668)
		(layer "F.Cu")
		(net "U20_E2")
	)
	(segment
		(start 163.332414 -428.131224)
		(end 163.332414 -427.452282)
		(width 0.10668)
		(layer "F.Cu")
		(net "U20_E2")
	)
	(via
		(at 163.332414 -427.452282)
		(size 0.508)
		(drill 0.254)
		(layers "F.Cu" "B.Cu")
		(net "U20_E2")
	)
	(segment
		(start 109.206538 -404.038308)
		(end 109.206538 -404.977092)
		(width 0.10668)
		(layer "F.Cu")
		(net "U19_E2")
	)
	(segment
		(start 109.206538 -404.977092)
		(end 109.598714 -405.369268)
		(width 0.10668)
		(layer "F.Cu")
		(net "U19_E2")
	)
	(segment
		(start 109.598714 -405.369268)
		(end 109.598714 -405.633682)
		(width 0.10668)
		(layer "F.Cu")
		(net "U19_E2")
	)
	(segment
		(start 109.314996 -403.92985)
		(end 109.206538 -404.038308)
		(width 0.10668)
		(layer "F.Cu")
		(net "U19_E2")
	)
	(via
		(at 109.206538 -404.977092)
		(size 0.508)
		(drill 0.254)
		(layers "F.Cu" "B.Cu")
		(net "U19_E2")
	)
	(segment
		(start 102.785926 -405.611584)
		(end 102.785926 -404.956518)
		(width 0.10668)
		(layer "F.Cu")
		(net "U12_E2")
	)
	(segment
		(start 102.785926 -404.956518)
		(end 102.966266 -404.776178)
		(width 0.10668)
		(layer "F.Cu")
		(net "U12_E2")
	)
	(segment
		(start 102.36327 -406.03424)
		(end 102.785926 -405.611584)
		(width 0.10668)
		(layer "F.Cu")
		(net "U12_E2")
	)
	(segment
		(start 102.966266 -404.776178)
		(end 102.966266 -403.92985)
		(width 0.10668)
		(layer "F.Cu")
		(net "U12_E2")
	)
	(via
		(at 102.785926 -404.956518)
		(size 0.508)
		(drill 0.254)
		(layers "F.Cu" "B.Cu")
		(net "U12_E2")
	)
	(segment
		(start 149.734778 -117.489986)
		(end 150.802594 -118.557802)
		(width 0.10668)
		(layer "F.Cu")
		(net "U206_VS")
	)
	(segment
		(start 148.971 -117.96395)
		(end 148.971 -117.11305)
		(width 0.10668)
		(layer "F.Cu")
		(net "U206_VS")
	)
	(segment
		(start 149.260814 -117.96395)
		(end 149.734778 -117.489986)
		(width 0.10668)
		(layer "F.Cu")
		(net "U206_VS")
	)
	(segment
		(start 151.805386 -118.557802)
		(end 152.418542 -117.944646)
		(width 0.10668)
		(layer "F.Cu")
		(net "U206_VS")
	)
	(segment
		(start 154.15006 -118.132352)
		(end 153.962354 -117.944646)
		(width 0.10668)
		(layer "F.Cu")
		(net "U206_VS")
	)
	(segment
		(start 150.802594 -118.557802)
		(end 151.805386 -118.557802)
		(width 0.10668)
		(layer "F.Cu")
		(net "U206_VS")
	)
	(segment
		(start 153.962354 -117.944646)
		(end 152.418542 -117.944646)
		(width 0.10668)
		(layer "F.Cu")
		(net "U206_VS")
	)
	(segment
		(start 148.971 -117.96395)
		(end 149.260814 -117.96395)
		(width 0.10668)
		(layer "F.Cu")
		(net "U206_VS")
	)
	(via
		(at 149.734778 -117.489986)
		(size 0.508)
		(drill 0.254)
		(layers "F.Cu" "B.Cu")
		(net "U206_VS")
	)
	(via
		(at 179.648866 -422.565576)
		(size 0.6604)
		(drill 0.3302)
		(layers "F.Cu" "B.Cu")
		(net "U142_VS")
	)
	(segment
		(start 179.27701 -422.19372)
		(end 179.648866 -422.565576)
		(width 0.10668)
		(layer "B.Cu")
		(net "U142_VS")
	)
	(segment
		(start 179.27701 -421.774874)
		(end 179.27701 -422.19372)
		(width 0.10668)
		(layer "B.Cu")
		(net "U142_VS")
	)
	(segment
		(start 180.281834 -421.77716)
		(end 179.279296 -421.77716)
		(width 0.10668)
		(layer "B.Cu")
		(net "U142_VS")
	)
	(segment
		(start 179.648866 -422.565576)
		(end 179.162964 -423.051478)
		(width 0.10668)
		(layer "B.Cu")
		(net "U142_VS")
	)
	(segment
		(start 181.297834 -421.77716)
		(end 180.281834 -421.77716)
		(width 0.10668)
		(layer "B.Cu")
		(net "U142_VS")
	)
	(segment
		(start 179.162964 -423.051478)
		(end 179.162964 -424.085004)
		(width 0.10668)
		(layer "B.Cu")
		(net "U142_VS")
	)
	(segment
		(start 179.279296 -421.77716)
		(end 179.27701 -421.774874)
		(width 0.10668)
		(layer "B.Cu")
		(net "U142_VS")
	)
	(segment
		(start 110.099094 -383.7432)
		(end 109.108494 -383.7432)
		(width 0.10668)
		(layer "F.Cu")
		(net "TEST2_RT_CPU1_P3")
	)
	(segment
		(start 110.099094 -383.7432)
		(end 110.099094 -383.418588)
		(width 0.10668)
		(layer "F.Cu")
		(net "TEST2_RT_CPU1_P3")
	)
	(segment
		(start 111.284258 -383.207514)
		(end 112.07623 -383.999486)
		(width 0.10668)
		(layer "F.Cu")
		(net "TEST2_RT_CPU1_P3")
	)
	(segment
		(start 112.07623 -384.700272)
		(end 112.507014 -385.131056)
		(width 0.10668)
		(layer "F.Cu")
		(net "TEST2_RT_CPU1_P3")
	)
	(segment
		(start 112.07623 -383.999486)
		(end 112.07623 -384.700272)
		(width 0.10668)
		(layer "F.Cu")
		(net "TEST2_RT_CPU1_P3")
	)
	(segment
		(start 110.099094 -383.418588)
		(end 110.310168 -383.207514)
		(width 0.10668)
		(layer "F.Cu")
		(net "TEST2_RT_CPU1_P3")
	)
	(segment
		(start 110.310168 -383.207514)
		(end 111.284258 -383.207514)
		(width 0.10668)
		(layer "F.Cu")
		(net "TEST2_RT_CPU1_P3")
	)
	(segment
		(start 109.108494 -383.82829)
		(end 109.108494 -383.7432)
		(width 0.10668)
		(layer "F.Cu")
		(net "TEST2_RT_CPU1_P3")
	)
	(segment
		(start 107.89285 -384.532378)
		(end 108.404406 -384.532378)
		(width 0.10668)
		(layer "F.Cu")
		(net "TEST2_RT_CPU1_P3")
	)
	(segment
		(start 108.404406 -384.532378)
		(end 109.108494 -383.82829)
		(width 0.10668)
		(layer "F.Cu")
		(net "TEST2_RT_CPU1_P3")
	)
	(segment
		(start 112.507014 -385.131056)
		(end 113.201704 -385.131056)
		(width 0.10668)
		(layer "F.Cu")
		(net "TEST2_RT_CPU1_P3")
	)
	(via
		(at 107.89285 -384.532378)
		(size 0.762)
		(drill 0.381)
		(layers "F.Cu" "B.Cu")
		(net "TEST2_RT_CPU1_P3")
	)
	(segment
		(start 141.636242 -383.849372)
		(end 140.849858 -384.635756)
		(width 0.10668)
		(layer "F.Cu")
		(net "TEST2_RT_CPU1_P2")
	)
	(segment
		(start 143.00962 -383.207514)
		(end 144.229582 -383.207514)
		(width 0.10668)
		(layer "F.Cu")
		(net "TEST2_RT_CPU1_P2")
	)
	(segment
		(start 140.849858 -384.635756)
		(end 140.562838 -384.635756)
		(width 0.10668)
		(layer "F.Cu")
		(net "TEST2_RT_CPU1_P2")
	)
	(segment
		(start 145.034762 -385.131056)
		(end 145.729452 -385.131056)
		(width 0.10668)
		(layer "F.Cu")
		(net "TEST2_RT_CPU1_P2")
	)
	(segment
		(start 142.626842 -383.590292)
		(end 143.00962 -383.207514)
		(width 0.10668)
		(layer "F.Cu")
		(net "TEST2_RT_CPU1_P2")
	)
	(segment
		(start 141.636242 -383.7432)
		(end 141.636242 -383.849372)
		(width 0.10668)
		(layer "F.Cu")
		(net "TEST2_RT_CPU1_P2")
	)
	(segment
		(start 142.626842 -383.7432)
		(end 142.626842 -383.590292)
		(width 0.10668)
		(layer "F.Cu")
		(net "TEST2_RT_CPU1_P2")
	)
	(segment
		(start 142.626842 -383.7432)
		(end 141.636242 -383.7432)
		(width 0.10668)
		(layer "F.Cu")
		(net "TEST2_RT_CPU1_P2")
	)
	(segment
		(start 144.229582 -383.207514)
		(end 144.603978 -383.58191)
		(width 0.10668)
		(layer "F.Cu")
		(net "TEST2_RT_CPU1_P2")
	)
	(segment
		(start 144.603978 -384.700272)
		(end 145.034762 -385.131056)
		(width 0.10668)
		(layer "F.Cu")
		(net "TEST2_RT_CPU1_P2")
	)
	(segment
		(start 144.603978 -383.58191)
		(end 144.603978 -384.700272)
		(width 0.10668)
		(layer "F.Cu")
		(net "TEST2_RT_CPU1_P2")
	)
	(via
		(at 140.562838 -384.635756)
		(size 0.762)
		(drill 0.381)
		(layers "F.Cu" "B.Cu")
		(net "TEST2_RT_CPU1_P2")
	)
	(segment
		(start 112.332516 -385.602734)
		(end 112.460786 -385.731004)
		(width 0.10668)
		(layer "F.Cu")
		(net "TEST1_RT_CPU1_P3")
	)
	(segment
		(start 112.079786 -385.602734)
		(end 112.332516 -385.602734)
		(width 0.10668)
		(layer "F.Cu")
		(net "TEST1_RT_CPU1_P3")
	)
	(segment
		(start 112.460786 -385.731004)
		(end 113.201704 -385.731004)
		(width 0.10668)
		(layer "F.Cu")
		(net "TEST1_RT_CPU1_P3")
	)
	(via
		(at 112.079786 -384.885946)
		(size 0.6604)
		(drill 0.3302)
		(layers "F.Cu" "B.Cu")
		(net "TEST1_RT_CPU1_P3")
	)
	(via
		(at 112.079786 -385.602734)
		(size 0.4064)
		(drill 0.2032)
		(layers "F.Cu" "B.Cu")
		(net "TEST1_RT_CPU1_P3")
	)
	(segment
		(start 110.267242 -384.20294)
		(end 110.099094 -384.371088)
		(width 0.10668)
		(layer "B.Cu")
		(net "TEST1_RT_CPU1_P3")
	)
	(segment
		(start 112.079786 -384.885946)
		(end 111.39678 -384.20294)
		(width 0.10668)
		(layer "B.Cu")
		(net "TEST1_RT_CPU1_P3")
	)
	(segment
		(start 112.079786 -385.602734)
		(end 112.079786 -384.885946)
		(width 0.10668)
		(layer "B.Cu")
		(net "TEST1_RT_CPU1_P3")
	)
	(segment
		(start 109.362494 -384.66268)
		(end 110.099094 -384.66268)
		(width 0.10668)
		(layer "B.Cu")
		(net "TEST1_RT_CPU1_P3")
	)
	(segment
		(start 110.099094 -384.371088)
		(end 110.099094 -384.66268)
		(width 0.10668)
		(layer "B.Cu")
		(net "TEST1_RT_CPU1_P3")
	)
	(segment
		(start 111.39678 -384.20294)
		(end 110.267242 -384.20294)
		(width 0.10668)
		(layer "B.Cu")
		(net "TEST1_RT_CPU1_P3")
	)
	(segment
		(start 144.607534 -385.602734)
		(end 144.860264 -385.602734)
		(width 0.10668)
		(layer "F.Cu")
		(net "TEST1_RT_CPU1_P2")
	)
	(segment
		(start 144.988534 -385.731004)
		(end 145.729452 -385.731004)
		(width 0.10668)
		(layer "F.Cu")
		(net "TEST1_RT_CPU1_P2")
	)
	(segment
		(start 144.860264 -385.602734)
		(end 144.988534 -385.731004)
		(width 0.10668)
		(layer "F.Cu")
		(net "TEST1_RT_CPU1_P2")
	)
	(via
		(at 144.607534 -384.885946)
		(size 0.6604)
		(drill 0.3302)
		(layers "F.Cu" "B.Cu")
		(net "TEST1_RT_CPU1_P2")
	)
	(via
		(at 144.607534 -385.602734)
		(size 0.4064)
		(drill 0.2032)
		(layers "F.Cu" "B.Cu")
		(net "TEST1_RT_CPU1_P2")
	)
	(segment
		(start 142.626842 -384.371088)
		(end 142.626842 -384.66268)
		(width 0.10668)
		(layer "B.Cu")
		(net "TEST1_RT_CPU1_P2")
	)
	(segment
		(start 144.607534 -384.885946)
		(end 143.924528 -384.20294)
		(width 0.10668)
		(layer "B.Cu")
		(net "TEST1_RT_CPU1_P2")
	)
	(segment
		(start 141.890242 -384.66268)
		(end 142.626842 -384.66268)
		(width 0.10668)
		(layer "B.Cu")
		(net "TEST1_RT_CPU1_P2")
	)
	(segment
		(start 144.607534 -385.602734)
		(end 144.607534 -384.885946)
		(width 0.10668)
		(layer "B.Cu")
		(net "TEST1_RT_CPU1_P2")
	)
	(segment
		(start 143.924528 -384.20294)
		(end 142.79499 -384.20294)
		(width 0.10668)
		(layer "B.Cu")
		(net "TEST1_RT_CPU1_P2")
	)
	(segment
		(start 142.79499 -384.20294)
		(end 142.626842 -384.371088)
		(width 0.10668)
		(layer "B.Cu")
		(net "TEST1_RT_CPU1_P2")
	)
	(segment
		(start 113.201704 -386.330952)
		(end 112.340136 -386.330952)
		(width 0.10668)
		(layer "F.Cu")
		(net "TEST0_RT_CPU1_P3")
	)
	(segment
		(start 112.340136 -386.330952)
		(end 112.18164 -386.489448)
		(width 0.10668)
		(layer "F.Cu")
		(net "TEST0_RT_CPU1_P3")
	)
	(via
		(at 112.18164 -386.489448)
		(size 0.4064)
		(drill 0.2032)
		(layers "F.Cu" "B.Cu")
		(net "TEST0_RT_CPU1_P3")
	)
	(via
		(at 111.62792 -386.129022)
		(size 0.6604)
		(drill 0.3302)
		(layers "F.Cu" "B.Cu")
		(net "TEST0_RT_CPU1_P3")
	)
	(segment
		(start 110.099094 -385.290568)
		(end 110.099094 -385.58216)
		(width 0.10668)
		(layer "B.Cu")
		(net "TEST0_RT_CPU1_P3")
	)
	(segment
		(start 111.988346 -386.489448)
		(end 111.62792 -386.129022)
		(width 0.10668)
		(layer "B.Cu")
		(net "TEST0_RT_CPU1_P3")
	)
	(segment
		(start 110.267242 -385.12242)
		(end 110.099094 -385.290568)
		(width 0.10668)
		(layer "B.Cu")
		(net "TEST0_RT_CPU1_P3")
	)
	(segment
		(start 111.62792 -385.336288)
		(end 111.414052 -385.12242)
		(width 0.10668)
		(layer "B.Cu")
		(net "TEST0_RT_CPU1_P3")
	)
	(segment
		(start 111.62792 -386.129022)
		(end 111.62792 -385.336288)
		(width 0.10668)
		(layer "B.Cu")
		(net "TEST0_RT_CPU1_P3")
	)
	(segment
		(start 112.18164 -386.489448)
		(end 111.988346 -386.489448)
		(width 0.10668)
		(layer "B.Cu")
		(net "TEST0_RT_CPU1_P3")
	)
	(segment
		(start 111.414052 -385.12242)
		(end 110.267242 -385.12242)
		(width 0.10668)
		(layer "B.Cu")
		(net "TEST0_RT_CPU1_P3")
	)
	(segment
		(start 109.362494 -385.58216)
		(end 110.099094 -385.58216)
		(width 0.10668)
		(layer "B.Cu")
		(net "TEST0_RT_CPU1_P3")
	)
	(segment
		(start 144.867884 -386.330952)
		(end 145.729452 -386.330952)
		(width 0.10668)
		(layer "F.Cu")
		(net "TEST0_RT_CPU1_P2")
	)
	(segment
		(start 144.709388 -386.489448)
		(end 144.867884 -386.330952)
		(width 0.10668)
		(layer "F.Cu")
		(net "TEST0_RT_CPU1_P2")
	)
	(via
		(at 144.155668 -386.129022)
		(size 0.6604)
		(drill 0.3302)
		(layers "F.Cu" "B.Cu")
		(net "TEST0_RT_CPU1_P2")
	)
	(via
		(at 144.709388 -386.489448)
		(size 0.4064)
		(drill 0.2032)
		(layers "F.Cu" "B.Cu")
		(net "TEST0_RT_CPU1_P2")
	)
	(segment
		(start 141.890242 -385.58216)
		(end 142.626842 -385.58216)
		(width 0.10668)
		(layer "B.Cu")
		(net "TEST0_RT_CPU1_P2")
	)
	(segment
		(start 142.626842 -385.290568)
		(end 142.626842 -385.58216)
		(width 0.10668)
		(layer "B.Cu")
		(net "TEST0_RT_CPU1_P2")
	)
	(segment
		(start 142.79499 -385.12242)
		(end 142.626842 -385.290568)
		(width 0.10668)
		(layer "B.Cu")
		(net "TEST0_RT_CPU1_P2")
	)
	(segment
		(start 144.709388 -386.489448)
		(end 144.516094 -386.489448)
		(width 0.10668)
		(layer "B.Cu")
		(net "TEST0_RT_CPU1_P2")
	)
	(segment
		(start 144.155668 -385.336288)
		(end 143.9418 -385.12242)
		(width 0.10668)
		(layer "B.Cu")
		(net "TEST0_RT_CPU1_P2")
	)
	(segment
		(start 144.516094 -386.489448)
		(end 144.155668 -386.129022)
		(width 0.10668)
		(layer "B.Cu")
		(net "TEST0_RT_CPU1_P2")
	)
	(segment
		(start 144.155668 -386.129022)
		(end 144.155668 -385.336288)
		(width 0.10668)
		(layer "B.Cu")
		(net "TEST0_RT_CPU1_P2")
	)
	(segment
		(start 143.9418 -385.12242)
		(end 142.79499 -385.12242)
		(width 0.10668)
		(layer "B.Cu")
		(net "TEST0_RT_CPU1_P2")
	)
	(segment
		(start 327.074022 -36.001706)
		(end 326.645778 -35.573462)
		(width 0.10668)
		(layer "F.Cu")
		(net "SMB_SEN_MAM_3V3AUX_SDA")
	)
	(segment
		(start 328.959972 -36.001706)
		(end 327.709022 -36.001706)
		(width 0.10668)
		(layer "F.Cu")
		(net "SMB_SEN_MAM_3V3AUX_SDA")
	)
	(segment
		(start 327.709022 -36.001706)
		(end 327.074022 -36.001706)
		(width 0.10668)
		(layer "F.Cu")
		(net "SMB_SEN_MAM_3V3AUX_SDA")
	)
	(segment
		(start 326.645778 -35.573462)
		(end 325.308214 -35.573462)
		(width 0.10668)
		(layer "F.Cu")
		(net "SMB_SEN_MAM_3V3AUX_SDA")
	)
	(via
		(at 327.709022 -36.001706)
		(size 0.762)
		(drill 0.381)
		(layers "F.Cu" "B.Cu")
		(net "SMB_SEN_MAM_3V3AUX_SDA")
	)
	(segment
		(start 327.074022 -34.858706)
		(end 326.312022 -34.858706)
		(width 0.10668)
		(layer "F.Cu")
		(net "SMB_SEN_MAM_3V3AUX_SCL")
	)
	(segment
		(start 326.232266 -34.938462)
		(end 325.308214 -34.938462)
		(width 0.10668)
		(layer "F.Cu")
		(net "SMB_SEN_MAM_3V3AUX_SCL")
	)
	(segment
		(start 328.959972 -34.985706)
		(end 328.254868 -34.985706)
		(width 0.10668)
		(layer "F.Cu")
		(net "SMB_SEN_MAM_3V3AUX_SCL")
	)
	(segment
		(start 328.127868 -34.858706)
		(end 327.074022 -34.858706)
		(width 0.10668)
		(layer "F.Cu")
		(net "SMB_SEN_MAM_3V3AUX_SCL")
	)
	(segment
		(start 326.312022 -34.858706)
		(end 326.232266 -34.938462)
		(width 0.10668)
		(layer "F.Cu")
		(net "SMB_SEN_MAM_3V3AUX_SCL")
	)
	(segment
		(start 328.254868 -34.985706)
		(end 328.127868 -34.858706)
		(width 0.10668)
		(layer "F.Cu")
		(net "SMB_SEN_MAM_3V3AUX_SCL")
	)
	(via
		(at 327.074022 -34.858706)
		(size 0.762)
		(drill 0.381)
		(layers "F.Cu" "B.Cu")
		(net "SMB_SEN_MAM_3V3AUX_SCL")
	)
	(via
		(at 218.694 -338.455)
		(size 0.6604)
		(drill 0.3302)
		(layers "F.Cu" "B.Cu")
		(net "SMB_RT_CPU1_P3_SDA")
	)
	(segment
		(start 220.47073 -337.82127)
		(end 219.837 -338.455)
		(width 0.10668)
		(layer "B.Cu")
		(net "SMB_RT_CPU1_P3_SDA")
	)
	(segment
		(start 217.9447 -338.582)
		(end 218.567 -338.582)
		(width 0.10668)
		(layer "B.Cu")
		(net "SMB_RT_CPU1_P3_SDA")
	)
	(segment
		(start 219.837 -338.455)
		(end 218.694 -338.455)
		(width 0.10668)
		(layer "B.Cu")
		(net "SMB_RT_CPU1_P3_SDA")
	)
	(segment
		(start 218.567 -338.582)
		(end 218.694 -338.455)
		(width 0.10668)
		(layer "B.Cu")
		(net "SMB_RT_CPU1_P3_SDA")
	)
	(segment
		(start 221.510098 -337.82127)
		(end 220.47073 -337.82127)
		(width 0.10668)
		(layer "B.Cu")
		(net "SMB_RT_CPU1_P3_SDA")
	)
	(via
		(at 218.694 -339.725)
		(size 0.6604)
		(drill 0.3302)
		(layers "F.Cu" "B.Cu")
		(net "SMB_RT_CPU1_P3_SCL")
	)
	(segment
		(start 220.455744 -338.471256)
		(end 219.202 -339.725)
		(width 0.10668)
		(layer "B.Cu")
		(net "SMB_RT_CPU1_P3_SCL")
	)
	(segment
		(start 218.567 -339.598)
		(end 218.694 -339.725)
		(width 0.10668)
		(layer "B.Cu")
		(net "SMB_RT_CPU1_P3_SCL")
	)
	(segment
		(start 219.202 -339.725)
		(end 218.694 -339.725)
		(width 0.10668)
		(layer "B.Cu")
		(net "SMB_RT_CPU1_P3_SCL")
	)
	(segment
		(start 217.9447 -339.598)
		(end 218.567 -339.598)
		(width 0.10668)
		(layer "B.Cu")
		(net "SMB_RT_CPU1_P3_SCL")
	)
	(segment
		(start 221.510098 -338.471256)
		(end 220.455744 -338.471256)
		(width 0.10668)
		(layer "B.Cu")
		(net "SMB_RT_CPU1_P3_SCL")
	)
	(via
		(at 215.142064 -338.338414)
		(size 0.6604)
		(drill 0.3302)
		(layers "F.Cu" "B.Cu")
		(net "SMB_RT_CPU1_P3_R_SDA")
	)
	(segment
		(start 217.097864 -338.895436)
		(end 217.4113 -338.582)
		(width 0.10668)
		(layer "B.Cu")
		(net "SMB_RT_CPU1_P3_R_SDA")
	)
	(segment
		(start 216.027 -338.7217)
		(end 215.52535 -338.7217)
		(width 0.10668)
		(layer "B.Cu")
		(net "SMB_RT_CPU1_P3_R_SDA")
	)
	(segment
		(start 214.898478 -338.582)
		(end 215.142064 -338.338414)
		(width 0.10668)
		(layer "B.Cu")
		(net "SMB_RT_CPU1_P3_R_SDA")
	)
	(segment
		(start 216.027 -338.7217)
		(end 216.200736 -338.895436)
		(width 0.10668)
		(layer "B.Cu")
		(net "SMB_RT_CPU1_P3_R_SDA")
	)
	(segment
		(start 214.3887 -338.582)
		(end 214.898478 -338.582)
		(width 0.10668)
		(layer "B.Cu")
		(net "SMB_RT_CPU1_P3_R_SDA")
	)
	(segment
		(start 216.200736 -338.895436)
		(end 217.097864 -338.895436)
		(width 0.10668)
		(layer "B.Cu")
		(net "SMB_RT_CPU1_P3_R_SDA")
	)
	(segment
		(start 215.52535 -338.7217)
		(end 215.142064 -338.338414)
		(width 0.10668)
		(layer "B.Cu")
		(net "SMB_RT_CPU1_P3_R_SDA")
	)
	(via
		(at 215.146128 -339.696552)
		(size 0.6604)
		(drill 0.3302)
		(layers "F.Cu" "B.Cu")
		(net "SMB_RT_CPU1_P3_R_SCL")
	)
	(segment
		(start 215.38438 -339.4583)
		(end 215.146128 -339.696552)
		(width 0.10668)
		(layer "B.Cu")
		(net "SMB_RT_CPU1_P3_R_SCL")
	)
	(segment
		(start 216.22385 -339.26145)
		(end 217.07475 -339.26145)
		(width 0.10668)
		(layer "B.Cu")
		(net "SMB_RT_CPU1_P3_R_SCL")
	)
	(segment
		(start 216.027 -339.4583)
		(end 215.38438 -339.4583)
		(width 0.10668)
		(layer "B.Cu")
		(net "SMB_RT_CPU1_P3_R_SCL")
	)
	(segment
		(start 214.3887 -339.598)
		(end 215.047576 -339.598)
		(width 0.10668)
		(layer "B.Cu")
		(net "SMB_RT_CPU1_P3_R_SCL")
	)
	(segment
		(start 215.047576 -339.598)
		(end 215.146128 -339.696552)
		(width 0.10668)
		(layer "B.Cu")
		(net "SMB_RT_CPU1_P3_R_SCL")
	)
	(segment
		(start 217.07475 -339.26145)
		(end 217.4113 -339.598)
		(width 0.10668)
		(layer "B.Cu")
		(net "SMB_RT_CPU1_P3_R_SCL")
	)
	(segment
		(start 216.027 -339.4583)
		(end 216.22385 -339.26145)
		(width 0.10668)
		(layer "B.Cu")
		(net "SMB_RT_CPU1_P3_R_SCL")
	)
	(via
		(at 241.648488 -338.455)
		(size 0.6604)
		(drill 0.3302)
		(layers "F.Cu" "B.Cu")
		(net "SMB_RT_CPU1_P3_ROM_MUX_2D_R_SDA")
	)
	(segment
		(start 241.087148 -339.01634)
		(end 241.648488 -338.455)
		(width 0.10668)
		(layer "B.Cu")
		(net "SMB_RT_CPU1_P3_ROM_MUX_2D_R_SDA")
	)
	(segment
		(start 244.464586 -337.82127)
		(end 243.425218 -337.82127)
		(width 0.10668)
		(layer "B.Cu")
		(net "SMB_RT_CPU1_P3_ROM_MUX_2D_R_SDA")
	)
	(segment
		(start 242.791488 -338.455)
		(end 241.648488 -338.455)
		(width 0.10668)
		(layer "B.Cu")
		(net "SMB_RT_CPU1_P3_ROM_MUX_2D_R_SDA")
	)
	(segment
		(start 239.6363 -338.86394)
		(end 239.7887 -339.01634)
		(width 0.10668)
		(layer "B.Cu")
		(net "SMB_RT_CPU1_P3_ROM_MUX_2D_R_SDA")
	)
	(segment
		(start 238.8997 -338.455)
		(end 239.6363 -338.455)
		(width 0.10668)
		(layer "B.Cu")
		(net "SMB_RT_CPU1_P3_ROM_MUX_2D_R_SDA")
	)
	(segment
		(start 239.7887 -339.01634)
		(end 241.087148 -339.01634)
		(width 0.10668)
		(layer "B.Cu")
		(net "SMB_RT_CPU1_P3_ROM_MUX_2D_R_SDA")
	)
	(segment
		(start 239.6363 -338.455)
		(end 239.6363 -338.86394)
		(width 0.10668)
		(layer "B.Cu")
		(net "SMB_RT_CPU1_P3_ROM_MUX_2D_R_SDA")
	)
	(segment
		(start 243.425218 -337.82127)
		(end 242.791488 -338.455)
		(width 0.10668)
		(layer "B.Cu")
		(net "SMB_RT_CPU1_P3_ROM_MUX_2D_R_SDA")
	)
	(via
		(at 241.648488 -339.725)
		(size 0.6604)
		(drill 0.3302)
		(layers "F.Cu" "B.Cu")
		(net "SMB_RT_CPU1_P3_ROM_MUX_2D_R_SCL")
	)
	(segment
		(start 244.464586 -338.471256)
		(end 243.410232 -338.471256)
		(width 0.10668)
		(layer "B.Cu")
		(net "SMB_RT_CPU1_P3_ROM_MUX_2D_R_SCL")
	)
	(segment
		(start 239.6363 -339.598)
		(end 239.6363 -340.00694)
		(width 0.10668)
		(layer "B.Cu")
		(net "SMB_RT_CPU1_P3_ROM_MUX_2D_R_SCL")
	)
	(segment
		(start 238.8997 -339.598)
		(end 239.6363 -339.598)
		(width 0.10668)
		(layer "B.Cu")
		(net "SMB_RT_CPU1_P3_ROM_MUX_2D_R_SCL")
	)
	(segment
		(start 242.156488 -339.725)
		(end 241.648488 -339.725)
		(width 0.10668)
		(layer "B.Cu")
		(net "SMB_RT_CPU1_P3_ROM_MUX_2D_R_SCL")
	)
	(segment
		(start 243.410232 -338.471256)
		(end 242.156488 -339.725)
		(width 0.10668)
		(layer "B.Cu")
		(net "SMB_RT_CPU1_P3_ROM_MUX_2D_R_SCL")
	)
	(segment
		(start 239.6363 -340.00694)
		(end 239.7887 -340.15934)
		(width 0.10668)
		(layer "B.Cu")
		(net "SMB_RT_CPU1_P3_ROM_MUX_2D_R_SCL")
	)
	(segment
		(start 239.7887 -340.15934)
		(end 241.214148 -340.15934)
		(width 0.10668)
		(layer "B.Cu")
		(net "SMB_RT_CPU1_P3_ROM_MUX_2D_R_SCL")
	)
	(segment
		(start 241.214148 -340.15934)
		(end 241.648488 -339.725)
		(width 0.10668)
		(layer "B.Cu")
		(net "SMB_RT_CPU1_P3_ROM_MUX_2D_R_SCL")
	)
	(segment
		(start 134.453884 -385.43103)
		(end 134.86003 -385.149344)
		(width 0.10668)
		(layer "F.Cu")
		(net "SMB_RT_CPU1_P3_R2_SDA")
	)
	(via
		(at 134.86003 -385.149344)
		(size 0.4064)
		(drill 0.2032)
		(layers "F.Cu" "B.Cu")
		(net "SMB_RT_CPU1_P3_R2_SDA")
	)
	(via
		(at 213.096602 -341.877396)
		(size 0.508)
		(drill 0.254)
		(layers "F.Cu" "B.Cu")
		(net "SMB_RT_CPU1_P3_R2_SDA")
	)
	(segment
		(start 213.42985 -339.00745)
		(end 213.42985 -341.544148)
		(width 0.10668)
		(layer "B.Cu")
		(net "SMB_RT_CPU1_P3_R2_SDA")
	)
	(segment
		(start 213.8553 -338.582)
		(end 213.42985 -339.00745)
		(width 0.10668)
		(layer "B.Cu")
		(net "SMB_RT_CPU1_P3_R2_SDA")
	)
	(segment
		(start 213.42985 -341.544148)
		(end 213.096602 -341.877396)
		(width 0.10668)
		(layer "B.Cu")
		(net "SMB_RT_CPU1_P3_R2_SDA")
	)
	(segment
		(start 173.933866 -380.8476)
		(end 180.081428 -380.8476)
		(width 0.11684)
		(layer "In2.Cu")
		(net "SMB_RT_CPU1_P3_R2_SDA")
	)
	(segment
		(start 134.530592 -385.478782)
		(end 134.530592 -386.10794)
		(width 0.11684)
		(layer "In2.Cu")
		(net "SMB_RT_CPU1_P3_R2_SDA")
	)
	(segment
		(start 182.233062 -376.820684)
		(end 188.203332 -370.850414)
		(width 0.11684)
		(layer "In2.Cu")
		(net "SMB_RT_CPU1_P3_R2_SDA")
	)
	(segment
		(start 209.134964 -353.765104)
		(end 209.134964 -351.494852)
		(width 0.11684)
		(layer "In2.Cu")
		(net "SMB_RT_CPU1_P3_R2_SDA")
	)
	(segment
		(start 137.743438 -387.595364)
		(end 140.058648 -385.280154)
		(width 0.11684)
		(layer "In2.Cu")
		(net "SMB_RT_CPU1_P3_R2_SDA")
	)
	(segment
		(start 169.134028 -378.349256)
		(end 171.435522 -378.349256)
		(width 0.11684)
		(layer "In2.Cu")
		(net "SMB_RT_CPU1_P3_R2_SDA")
	)
	(segment
		(start 209.134964 -351.494852)
		(end 212.061552 -348.568264)
		(width 0.11684)
		(layer "In2.Cu")
		(net "SMB_RT_CPU1_P3_R2_SDA")
	)
	(segment
		(start 134.530592 -386.10794)
		(end 136.018016 -387.595364)
		(width 0.11684)
		(layer "In2.Cu")
		(net "SMB_RT_CPU1_P3_R2_SDA")
	)
	(segment
		(start 140.662406 -385.280154)
		(end 144.50822 -381.43434)
		(width 0.11684)
		(layer "In2.Cu")
		(net "SMB_RT_CPU1_P3_R2_SDA")
	)
	(segment
		(start 165.075616 -379.566932)
		(end 167.916352 -379.566932)
		(width 0.11684)
		(layer "In2.Cu")
		(net "SMB_RT_CPU1_P3_R2_SDA")
	)
	(segment
		(start 188.203332 -370.850414)
		(end 192.049654 -370.850414)
		(width 0.11684)
		(layer "In2.Cu")
		(net "SMB_RT_CPU1_P3_R2_SDA")
	)
	(segment
		(start 212.061552 -348.568264)
		(end 212.061552 -342.912446)
		(width 0.11684)
		(layer "In2.Cu")
		(net "SMB_RT_CPU1_P3_R2_SDA")
	)
	(segment
		(start 136.018016 -387.595364)
		(end 137.743438 -387.595364)
		(width 0.11684)
		(layer "In2.Cu")
		(net "SMB_RT_CPU1_P3_R2_SDA")
	)
	(segment
		(start 144.50822 -381.43434)
		(end 163.208208 -381.43434)
		(width 0.11684)
		(layer "In2.Cu")
		(net "SMB_RT_CPU1_P3_R2_SDA")
	)
	(segment
		(start 212.061552 -342.912446)
		(end 213.096602 -341.877396)
		(width 0.11684)
		(layer "In2.Cu")
		(net "SMB_RT_CPU1_P3_R2_SDA")
	)
	(segment
		(start 192.049654 -370.850414)
		(end 209.134964 -353.765104)
		(width 0.11684)
		(layer "In2.Cu")
		(net "SMB_RT_CPU1_P3_R2_SDA")
	)
	(segment
		(start 180.081428 -380.8476)
		(end 182.233062 -378.695966)
		(width 0.11684)
		(layer "In2.Cu")
		(net "SMB_RT_CPU1_P3_R2_SDA")
	)
	(segment
		(start 140.058648 -385.280154)
		(end 140.662406 -385.280154)
		(width 0.11684)
		(layer "In2.Cu")
		(net "SMB_RT_CPU1_P3_R2_SDA")
	)
	(segment
		(start 167.916352 -379.566932)
		(end 169.134028 -378.349256)
		(width 0.11684)
		(layer "In2.Cu")
		(net "SMB_RT_CPU1_P3_R2_SDA")
	)
	(segment
		(start 163.208208 -381.43434)
		(end 165.075616 -379.566932)
		(width 0.11684)
		(layer "In2.Cu")
		(net "SMB_RT_CPU1_P3_R2_SDA")
	)
	(segment
		(start 171.435522 -378.349256)
		(end 173.933866 -380.8476)
		(width 0.11684)
		(layer "In2.Cu")
		(net "SMB_RT_CPU1_P3_R2_SDA")
	)
	(segment
		(start 182.233062 -378.695966)
		(end 182.233062 -376.820684)
		(width 0.11684)
		(layer "In2.Cu")
		(net "SMB_RT_CPU1_P3_R2_SDA")
	)
	(segment
		(start 134.86003 -385.149344)
		(end 134.530592 -385.478782)
		(width 0.11684)
		(layer "In2.Cu")
		(net "SMB_RT_CPU1_P3_R2_SDA")
	)
	(segment
		(start 134.453884 -384.831082)
		(end 134.874254 -384.574542)
		(width 0.10668)
		(layer "F.Cu")
		(net "SMB_RT_CPU1_P3_R2_SCL")
	)
	(via
		(at 213.167976 -343.431876)
		(size 0.508)
		(drill 0.254)
		(layers "F.Cu" "B.Cu")
		(net "SMB_RT_CPU1_P3_R2_SCL")
	)
	(via
		(at 134.874254 -384.574542)
		(size 0.4064)
		(drill 0.2032)
		(layers "F.Cu" "B.Cu")
		(net "SMB_RT_CPU1_P3_R2_SCL")
	)
	(segment
		(start 213.8553 -339.598)
		(end 213.8553 -342.744552)
		(width 0.10668)
		(layer "B.Cu")
		(net "SMB_RT_CPU1_P3_R2_SCL")
	)
	(segment
		(start 213.8553 -342.744552)
		(end 213.167976 -343.431876)
		(width 0.10668)
		(layer "B.Cu")
		(net "SMB_RT_CPU1_P3_R2_SCL")
	)
	(segment
		(start 169.496232 -383.29616)
		(end 168.088818 -383.29616)
		(width 0.11684)
		(layer "In2.Cu")
		(net "SMB_RT_CPU1_P3_R2_SCL")
	)
	(segment
		(start 188.461904 -371.291612)
		(end 182.685436 -377.06808)
		(width 0.11684)
		(layer "In2.Cu")
		(net "SMB_RT_CPU1_P3_R2_SCL")
	)
	(segment
		(start 212.559392 -344.04046)
		(end 212.559392 -348.752922)
		(width 0.11684)
		(layer "In2.Cu")
		(net "SMB_RT_CPU1_P3_R2_SCL")
	)
	(segment
		(start 209.556604 -351.75571)
		(end 209.556604 -353.94011)
		(width 0.11684)
		(layer "In2.Cu")
		(net "SMB_RT_CPU1_P3_R2_SCL")
	)
	(segment
		(start 168.088818 -383.29616)
		(end 166.656766 -381.864108)
		(width 0.11684)
		(layer "In2.Cu")
		(net "SMB_RT_CPU1_P3_R2_SCL")
	)
	(segment
		(start 134.55523 -384.574542)
		(end 134.874254 -384.574542)
		(width 0.11684)
		(layer "In2.Cu")
		(net "SMB_RT_CPU1_P3_R2_SCL")
	)
	(segment
		(start 140.122402 -385.835906)
		(end 137.938256 -388.020052)
		(width 0.11684)
		(layer "In2.Cu")
		(net "SMB_RT_CPU1_P3_R2_SCL")
	)
	(segment
		(start 209.556604 -353.94011)
		(end 192.205102 -371.291612)
		(width 0.11684)
		(layer "In2.Cu")
		(net "SMB_RT_CPU1_P3_R2_SCL")
	)
	(segment
		(start 180.20919 -381.317754)
		(end 171.474638 -381.317754)
		(width 0.11684)
		(layer "In2.Cu")
		(net "SMB_RT_CPU1_P3_R2_SCL")
	)
	(segment
		(start 213.167976 -343.431876)
		(end 212.559392 -344.04046)
		(width 0.11684)
		(layer "In2.Cu")
		(net "SMB_RT_CPU1_P3_R2_SCL")
	)
	(segment
		(start 135.821674 -388.020052)
		(end 134.094982 -386.29336)
		(width 0.11684)
		(layer "In2.Cu")
		(net "SMB_RT_CPU1_P3_R2_SCL")
	)
	(segment
		(start 182.685436 -377.06808)
		(end 182.685436 -378.841508)
		(width 0.11684)
		(layer "In2.Cu")
		(net "SMB_RT_CPU1_P3_R2_SCL")
	)
	(segment
		(start 137.938256 -388.020052)
		(end 135.821674 -388.020052)
		(width 0.11684)
		(layer "In2.Cu")
		(net "SMB_RT_CPU1_P3_R2_SCL")
	)
	(segment
		(start 212.559392 -348.752922)
		(end 209.556604 -351.75571)
		(width 0.11684)
		(layer "In2.Cu")
		(net "SMB_RT_CPU1_P3_R2_SCL")
	)
	(segment
		(start 182.685436 -378.841508)
		(end 180.20919 -381.317754)
		(width 0.11684)
		(layer "In2.Cu")
		(net "SMB_RT_CPU1_P3_R2_SCL")
	)
	(segment
		(start 171.474638 -381.317754)
		(end 169.496232 -383.29616)
		(width 0.11684)
		(layer "In2.Cu")
		(net "SMB_RT_CPU1_P3_R2_SCL")
	)
	(segment
		(start 166.656766 -381.864108)
		(end 144.825212 -381.864108)
		(width 0.11684)
		(layer "In2.Cu")
		(net "SMB_RT_CPU1_P3_R2_SCL")
	)
	(segment
		(start 140.853414 -385.835906)
		(end 140.122402 -385.835906)
		(width 0.11684)
		(layer "In2.Cu")
		(net "SMB_RT_CPU1_P3_R2_SCL")
	)
	(segment
		(start 192.205102 -371.291612)
		(end 188.461904 -371.291612)
		(width 0.11684)
		(layer "In2.Cu")
		(net "SMB_RT_CPU1_P3_R2_SCL")
	)
	(segment
		(start 134.094982 -385.03479)
		(end 134.55523 -384.574542)
		(width 0.11684)
		(layer "In2.Cu")
		(net "SMB_RT_CPU1_P3_R2_SCL")
	)
	(segment
		(start 144.825212 -381.864108)
		(end 140.853414 -385.835906)
		(width 0.11684)
		(layer "In2.Cu")
		(net "SMB_RT_CPU1_P3_R2_SCL")
	)
	(segment
		(start 134.094982 -386.29336)
		(end 134.094982 -385.03479)
		(width 0.11684)
		(layer "In2.Cu")
		(net "SMB_RT_CPU1_P3_R2_SCL")
	)
	(via
		(at 219.794582 -340.696296)
		(size 0.6604)
		(drill 0.3302)
		(layers "F.Cu" "B.Cu")
		(net "SMB_RT_CPU1_P2_SDA")
	)
	(segment
		(start 219.794582 -339.894418)
		(end 219.794582 -340.696296)
		(width 0.10668)
		(layer "B.Cu")
		(net "SMB_RT_CPU1_P2_SDA")
	)
	(segment
		(start 220.567758 -339.121242)
		(end 219.794582 -339.894418)
		(width 0.10668)
		(layer "B.Cu")
		(net "SMB_RT_CPU1_P2_SDA")
	)
	(segment
		(start 221.510098 -339.121242)
		(end 220.567758 -339.121242)
		(width 0.10668)
		(layer "B.Cu")
		(net "SMB_RT_CPU1_P2_SDA")
	)
	(segment
		(start 219.794582 -340.696296)
		(end 219.282518 -340.696296)
		(width 0.10668)
		(layer "B.Cu")
		(net "SMB_RT_CPU1_P2_SDA")
	)
	(segment
		(start 219.110814 -340.868)
		(end 218.3257 -340.868)
		(width 0.10668)
		(layer "B.Cu")
		(net "SMB_RT_CPU1_P2_SDA")
	)
	(segment
		(start 219.282518 -340.696296)
		(end 219.110814 -340.868)
		(width 0.10668)
		(layer "B.Cu")
		(net "SMB_RT_CPU1_P2_SDA")
	)
	(via
		(at 219.074492 -341.884)
		(size 0.6604)
		(drill 0.3302)
		(layers "F.Cu" "B.Cu")
		(net "SMB_RT_CPU1_P2_SCL")
	)
	(segment
		(start 219.632276 -341.884)
		(end 219.074492 -341.884)
		(width 0.10668)
		(layer "B.Cu")
		(net "SMB_RT_CPU1_P2_SCL")
	)
	(segment
		(start 219.074492 -341.884)
		(end 218.3257 -341.884)
		(width 0.10668)
		(layer "B.Cu")
		(net "SMB_RT_CPU1_P2_SCL")
	)
	(segment
		(start 220.345 -339.979)
		(end 220.345 -341.171276)
		(width 0.10668)
		(layer "B.Cu")
		(net "SMB_RT_CPU1_P2_SCL")
	)
	(segment
		(start 221.510098 -339.771228)
		(end 220.552772 -339.771228)
		(width 0.10668)
		(layer "B.Cu")
		(net "SMB_RT_CPU1_P2_SCL")
	)
	(segment
		(start 220.345 -341.171276)
		(end 219.632276 -341.884)
		(width 0.10668)
		(layer "B.Cu")
		(net "SMB_RT_CPU1_P2_SCL")
	)
	(segment
		(start 220.552772 -339.771228)
		(end 220.345 -339.979)
		(width 0.10668)
		(layer "B.Cu")
		(net "SMB_RT_CPU1_P2_SCL")
	)
	(via
		(at 216.089484 -340.868)
		(size 0.6604)
		(drill 0.3302)
		(layers "F.Cu" "B.Cu")
		(net "SMB_RT_CPU1_P2_R_SDA")
	)
	(segment
		(start 216.916 -341.0077)
		(end 216.229184 -341.0077)
		(width 0.10668)
		(layer "B.Cu")
		(net "SMB_RT_CPU1_P2_R_SDA")
	)
	(segment
		(start 215.3285 -340.868)
		(end 216.089484 -340.868)
		(width 0.10668)
		(layer "B.Cu")
		(net "SMB_RT_CPU1_P2_R_SDA")
	)
	(segment
		(start 216.916 -341.0077)
		(end 217.6526 -341.0077)
		(width 0.10668)
		(layer "B.Cu")
		(net "SMB_RT_CPU1_P2_R_SDA")
	)
	(segment
		(start 217.6526 -341.0077)
		(end 217.7923 -340.868)
		(width 0.10668)
		(layer "B.Cu")
		(net "SMB_RT_CPU1_P2_R_SDA")
	)
	(segment
		(start 216.229184 -341.0077)
		(end 216.089484 -340.868)
		(width 0.10668)
		(layer "B.Cu")
		(net "SMB_RT_CPU1_P2_R_SDA")
	)
	(via
		(at 216.093548 -342.16086)
		(size 0.6604)
		(drill 0.3302)
		(layers "F.Cu" "B.Cu")
		(net "SMB_RT_CPU1_P2_R_SCL")
	)
	(segment
		(start 217.6526 -341.7443)
		(end 217.7923 -341.884)
		(width 0.10668)
		(layer "B.Cu")
		(net "SMB_RT_CPU1_P2_R_SCL")
	)
	(segment
		(start 216.510108 -341.7443)
		(end 216.916 -341.7443)
		(width 0.10668)
		(layer "B.Cu")
		(net "SMB_RT_CPU1_P2_R_SCL")
	)
	(segment
		(start 216.093548 -342.16086)
		(end 216.510108 -341.7443)
		(width 0.10668)
		(layer "B.Cu")
		(net "SMB_RT_CPU1_P2_R_SCL")
	)
	(segment
		(start 215.3285 -341.884)
		(end 215.816688 -341.884)
		(width 0.10668)
		(layer "B.Cu")
		(net "SMB_RT_CPU1_P2_R_SCL")
	)
	(segment
		(start 215.816688 -341.884)
		(end 216.093548 -342.16086)
		(width 0.10668)
		(layer "B.Cu")
		(net "SMB_RT_CPU1_P2_R_SCL")
	)
	(segment
		(start 216.916 -341.7443)
		(end 217.6526 -341.7443)
		(width 0.10668)
		(layer "B.Cu")
		(net "SMB_RT_CPU1_P2_R_SCL")
	)
	(via
		(at 242.537488 -340.741)
		(size 0.6604)
		(drill 0.3302)
		(layers "F.Cu" "B.Cu")
		(net "SMB_RT_CPU1_P2_ROM_MUX_2D_R_SDA")
	)
	(segment
		(start 238.8997 -340.741)
		(end 239.6363 -340.741)
		(width 0.10668)
		(layer "B.Cu")
		(net "SMB_RT_CPU1_P2_ROM_MUX_2D_R_SDA")
	)
	(segment
		(start 239.6363 -341.14994)
		(end 239.7887 -341.30234)
		(width 0.10668)
		(layer "B.Cu")
		(net "SMB_RT_CPU1_P2_ROM_MUX_2D_R_SDA")
	)
	(segment
		(start 239.7887 -341.30234)
		(end 241.976148 -341.30234)
		(width 0.10668)
		(layer "B.Cu")
		(net "SMB_RT_CPU1_P2_ROM_MUX_2D_R_SDA")
	)
	(segment
		(start 242.918488 -339.725)
		(end 242.918488 -340.36)
		(width 0.10668)
		(layer "B.Cu")
		(net "SMB_RT_CPU1_P2_ROM_MUX_2D_R_SDA")
	)
	(segment
		(start 242.918488 -340.36)
		(end 242.537488 -340.741)
		(width 0.10668)
		(layer "B.Cu")
		(net "SMB_RT_CPU1_P2_ROM_MUX_2D_R_SDA")
	)
	(segment
		(start 241.976148 -341.30234)
		(end 242.537488 -340.741)
		(width 0.10668)
		(layer "B.Cu")
		(net "SMB_RT_CPU1_P2_ROM_MUX_2D_R_SDA")
	)
	(segment
		(start 239.6363 -340.741)
		(end 239.6363 -341.14994)
		(width 0.10668)
		(layer "B.Cu")
		(net "SMB_RT_CPU1_P2_ROM_MUX_2D_R_SDA")
	)
	(segment
		(start 243.522246 -339.121242)
		(end 242.918488 -339.725)
		(width 0.10668)
		(layer "B.Cu")
		(net "SMB_RT_CPU1_P2_ROM_MUX_2D_R_SDA")
	)
	(segment
		(start 244.464586 -339.121242)
		(end 243.522246 -339.121242)
		(width 0.10668)
		(layer "B.Cu")
		(net "SMB_RT_CPU1_P2_ROM_MUX_2D_R_SDA")
	)
	(via
		(at 242.537488 -342.011)
		(size 0.6604)
		(drill 0.3302)
		(layers "F.Cu" "B.Cu")
		(net "SMB_RT_CPU1_P2_ROM_MUX_2D_R_SCL")
	)
	(segment
		(start 242.103148 -342.44534)
		(end 242.537488 -342.011)
		(width 0.10668)
		(layer "B.Cu")
		(net "SMB_RT_CPU1_P2_ROM_MUX_2D_R_SCL")
	)
	(segment
		(start 243.299488 -341.249)
		(end 242.537488 -342.011)
		(width 0.10668)
		(layer "B.Cu")
		(net "SMB_RT_CPU1_P2_ROM_MUX_2D_R_SCL")
	)
	(segment
		(start 239.6363 -341.884)
		(end 239.6363 -342.29294)
		(width 0.10668)
		(layer "B.Cu")
		(net "SMB_RT_CPU1_P2_ROM_MUX_2D_R_SCL")
	)
	(segment
		(start 243.299488 -339.979)
		(end 243.299488 -341.249)
		(width 0.10668)
		(layer "B.Cu")
		(net "SMB_RT_CPU1_P2_ROM_MUX_2D_R_SCL")
	)
	(segment
		(start 238.8997 -341.884)
		(end 239.6363 -341.884)
		(width 0.10668)
		(layer "B.Cu")
		(net "SMB_RT_CPU1_P2_ROM_MUX_2D_R_SCL")
	)
	(segment
		(start 239.6363 -342.29294)
		(end 239.7887 -342.44534)
		(width 0.10668)
		(layer "B.Cu")
		(net "SMB_RT_CPU1_P2_ROM_MUX_2D_R_SCL")
	)
	(segment
		(start 243.50726 -339.771228)
		(end 243.299488 -339.979)
		(width 0.10668)
		(layer "B.Cu")
		(net "SMB_RT_CPU1_P2_ROM_MUX_2D_R_SCL")
	)
	(segment
		(start 244.464586 -339.771228)
		(end 243.50726 -339.771228)
		(width 0.10668)
		(layer "B.Cu")
		(net "SMB_RT_CPU1_P2_ROM_MUX_2D_R_SCL")
	)
	(segment
		(start 239.7887 -342.44534)
		(end 242.103148 -342.44534)
		(width 0.10668)
		(layer "B.Cu")
		(net "SMB_RT_CPU1_P2_ROM_MUX_2D_R_SCL")
	)
	(segment
		(start 166.981632 -385.43103)
		(end 167.387778 -385.149344)
		(width 0.10668)
		(layer "F.Cu")
		(net "SMB_RT_CPU1_P2_R2_SDA")
	)
	(via
		(at 213.623906 -344.952828)
		(size 0.508)
		(drill 0.254)
		(layers "F.Cu" "B.Cu")
		(net "SMB_RT_CPU1_P2_R2_SDA")
	)
	(via
		(at 167.387778 -385.149344)
		(size 0.4064)
		(drill 0.2032)
		(layers "F.Cu" "B.Cu")
		(net "SMB_RT_CPU1_P2_R2_SDA")
	)
	(segment
		(start 214.7951 -340.868)
		(end 214.210646 -341.452454)
		(width 0.10668)
		(layer "B.Cu")
		(net "SMB_RT_CPU1_P2_R2_SDA")
	)
	(segment
		(start 214.210646 -341.452454)
		(end 214.210646 -344.366088)
		(width 0.10668)
		(layer "B.Cu")
		(net "SMB_RT_CPU1_P2_R2_SDA")
	)
	(segment
		(start 214.210646 -344.366088)
		(end 213.623906 -344.952828)
		(width 0.10668)
		(layer "B.Cu")
		(net "SMB_RT_CPU1_P2_R2_SDA")
	)
	(segment
		(start 167.301164 -385.235958)
		(end 167.387778 -385.149344)
		(width 0.11684)
		(layer "In2.Cu")
		(net "SMB_RT_CPU1_P2_R2_SDA")
	)
	(segment
		(start 171.747688 -381.753364)
		(end 169.3545 -384.146552)
		(width 0.11684)
		(layer "In2.Cu")
		(net "SMB_RT_CPU1_P2_R2_SDA")
	)
	(segment
		(start 169.3545 -386.96392)
		(end 168.681908 -387.636512)
		(width 0.11684)
		(layer "In2.Cu")
		(net "SMB_RT_CPU1_P2_R2_SDA")
	)
	(segment
		(start 180.377592 -381.753364)
		(end 171.747688 -381.753364)
		(width 0.11684)
		(layer "In2.Cu")
		(net "SMB_RT_CPU1_P2_R2_SDA")
	)
	(segment
		(start 213.623906 -344.952828)
		(end 213.043262 -345.533472)
		(width 0.11684)
		(layer "In2.Cu")
		(net "SMB_RT_CPU1_P2_R2_SDA")
	)
	(segment
		(start 168.681908 -387.636512)
		(end 168.103042 -387.636512)
		(width 0.11684)
		(layer "In2.Cu")
		(net "SMB_RT_CPU1_P2_R2_SDA")
	)
	(segment
		(start 183.403748 -378.727208)
		(end 180.377592 -381.753364)
		(width 0.11684)
		(layer "In2.Cu")
		(net "SMB_RT_CPU1_P2_R2_SDA")
	)
	(segment
		(start 188.926216 -371.74297)
		(end 183.403748 -377.265438)
		(width 0.11684)
		(layer "In2.Cu")
		(net "SMB_RT_CPU1_P2_R2_SDA")
	)
	(segment
		(start 213.043262 -345.533472)
		(end 213.043262 -351.049844)
		(width 0.11684)
		(layer "In2.Cu")
		(net "SMB_RT_CPU1_P2_R2_SDA")
	)
	(segment
		(start 183.403748 -377.265438)
		(end 183.403748 -378.727208)
		(width 0.11684)
		(layer "In2.Cu")
		(net "SMB_RT_CPU1_P2_R2_SDA")
	)
	(segment
		(start 213.043262 -351.049844)
		(end 192.350136 -371.74297)
		(width 0.11684)
		(layer "In2.Cu")
		(net "SMB_RT_CPU1_P2_R2_SDA")
	)
	(segment
		(start 169.3545 -384.146552)
		(end 169.3545 -386.96392)
		(width 0.11684)
		(layer "In2.Cu")
		(net "SMB_RT_CPU1_P2_R2_SDA")
	)
	(segment
		(start 167.301164 -386.834634)
		(end 167.301164 -385.235958)
		(width 0.11684)
		(layer "In2.Cu")
		(net "SMB_RT_CPU1_P2_R2_SDA")
	)
	(segment
		(start 168.103042 -387.636512)
		(end 167.301164 -386.834634)
		(width 0.11684)
		(layer "In2.Cu")
		(net "SMB_RT_CPU1_P2_R2_SDA")
	)
	(segment
		(start 192.350136 -371.74297)
		(end 188.926216 -371.74297)
		(width 0.11684)
		(layer "In2.Cu")
		(net "SMB_RT_CPU1_P2_R2_SDA")
	)
	(segment
		(start 166.981632 -384.831082)
		(end 167.402002 -384.574542)
		(width 0.10668)
		(layer "F.Cu")
		(net "SMB_RT_CPU1_P2_R2_SCL")
	)
	(via
		(at 167.402002 -384.574542)
		(size 0.4064)
		(drill 0.2032)
		(layers "F.Cu" "B.Cu")
		(net "SMB_RT_CPU1_P2_R2_SCL")
	)
	(via
		(at 213.733888 -346.7227)
		(size 0.508)
		(drill 0.254)
		(layers "F.Cu" "B.Cu")
		(net "SMB_RT_CPU1_P2_R2_SCL")
	)
	(segment
		(start 214.7951 -345.661488)
		(end 213.733888 -346.7227)
		(width 0.10668)
		(layer "B.Cu")
		(net "SMB_RT_CPU1_P2_R2_SCL")
	)
	(segment
		(start 214.7951 -341.884)
		(end 214.7951 -345.661488)
		(width 0.10668)
		(layer "B.Cu")
		(net "SMB_RT_CPU1_P2_R2_SCL")
	)
	(segment
		(start 183.872886 -377.392946)
		(end 189.086998 -372.178834)
		(width 0.11684)
		(layer "In2.Cu")
		(net "SMB_RT_CPU1_P2_R2_SCL")
	)
	(segment
		(start 168.739058 -389.36168)
		(end 169.560748 -389.36168)
		(width 0.11684)
		(layer "In2.Cu")
		(net "SMB_RT_CPU1_P2_R2_SCL")
	)
	(segment
		(start 167.402002 -384.574542)
		(end 167.149526 -384.574542)
		(width 0.11684)
		(layer "In2.Cu")
		(net "SMB_RT_CPU1_P2_R2_SCL")
	)
	(segment
		(start 167.149526 -384.574542)
		(end 166.696136 -385.027932)
		(width 0.11684)
		(layer "In2.Cu")
		(net "SMB_RT_CPU1_P2_R2_SCL")
	)
	(segment
		(start 192.510918 -372.178834)
		(end 213.733888 -350.955864)
		(width 0.11684)
		(layer "In2.Cu")
		(net "SMB_RT_CPU1_P2_R2_SCL")
	)
	(segment
		(start 169.807382 -389.115046)
		(end 169.807382 -384.332734)
		(width 0.11684)
		(layer "In2.Cu")
		(net "SMB_RT_CPU1_P2_R2_SCL")
	)
	(segment
		(start 168.612058 -388.80923)
		(end 168.612058 -389.23468)
		(width 0.11684)
		(layer "In2.Cu")
		(net "SMB_RT_CPU1_P2_R2_SCL")
	)
	(segment
		(start 189.086998 -372.178834)
		(end 192.510918 -372.178834)
		(width 0.11684)
		(layer "In2.Cu")
		(net "SMB_RT_CPU1_P2_R2_SCL")
	)
	(segment
		(start 213.733888 -350.955864)
		(end 213.733888 -346.7227)
		(width 0.11684)
		(layer "In2.Cu")
		(net "SMB_RT_CPU1_P2_R2_SCL")
	)
	(segment
		(start 169.807382 -384.332734)
		(end 171.94657 -382.193546)
		(width 0.11684)
		(layer "In2.Cu")
		(net "SMB_RT_CPU1_P2_R2_SCL")
	)
	(segment
		(start 169.560748 -389.36168)
		(end 169.807382 -389.115046)
		(width 0.11684)
		(layer "In2.Cu")
		(net "SMB_RT_CPU1_P2_R2_SCL")
	)
	(segment
		(start 166.696136 -386.893308)
		(end 168.612058 -388.80923)
		(width 0.11684)
		(layer "In2.Cu")
		(net "SMB_RT_CPU1_P2_R2_SCL")
	)
	(segment
		(start 183.872886 -378.97054)
		(end 183.872886 -377.392946)
		(width 0.11684)
		(layer "In2.Cu")
		(net "SMB_RT_CPU1_P2_R2_SCL")
	)
	(segment
		(start 168.612058 -389.23468)
		(end 168.739058 -389.36168)
		(width 0.11684)
		(layer "In2.Cu")
		(net "SMB_RT_CPU1_P2_R2_SCL")
	)
	(segment
		(start 180.64988 -382.193546)
		(end 183.872886 -378.97054)
		(width 0.11684)
		(layer "In2.Cu")
		(net "SMB_RT_CPU1_P2_R2_SCL")
	)
	(segment
		(start 171.94657 -382.193546)
		(end 180.64988 -382.193546)
		(width 0.11684)
		(layer "In2.Cu")
		(net "SMB_RT_CPU1_P2_R2_SCL")
	)
	(segment
		(start 166.696136 -385.027932)
		(end 166.696136 -386.893308)
		(width 0.11684)
		(layer "In2.Cu")
		(net "SMB_RT_CPU1_P2_R2_SCL")
	)
	(via
		(at 242.664488 -336.169)
		(size 0.6604)
		(drill 0.3302)
		(layers "F.Cu" "B.Cu")
		(net "SMB_RT_CPU1_P1_ROM_MUX_2D_R_SDA")
	)
	(segment
		(start 244.464586 -336.521044)
		(end 243.016532 -336.521044)
		(width 0.10668)
		(layer "B.Cu")
		(net "SMB_RT_CPU1_P1_ROM_MUX_2D_R_SDA")
	)
	(segment
		(start 239.6363 -336.169)
		(end 239.6363 -336.57794)
		(width 0.10668)
		(layer "B.Cu")
		(net "SMB_RT_CPU1_P1_ROM_MUX_2D_R_SDA")
	)
	(segment
		(start 238.8997 -336.169)
		(end 239.6363 -336.169)
		(width 0.10668)
		(layer "B.Cu")
		(net "SMB_RT_CPU1_P1_ROM_MUX_2D_R_SDA")
	)
	(segment
		(start 241.808 -336.169)
		(end 242.664488 -336.169)
		(width 0.10668)
		(layer "B.Cu")
		(net "SMB_RT_CPU1_P1_ROM_MUX_2D_R_SDA")
	)
	(segment
		(start 243.016532 -336.521044)
		(end 242.664488 -336.169)
		(width 0.10668)
		(layer "B.Cu")
		(net "SMB_RT_CPU1_P1_ROM_MUX_2D_R_SDA")
	)
	(segment
		(start 241.24666 -336.73034)
		(end 241.808 -336.169)
		(width 0.10668)
		(layer "B.Cu")
		(net "SMB_RT_CPU1_P1_ROM_MUX_2D_R_SDA")
	)
	(segment
		(start 239.6363 -336.57794)
		(end 239.7887 -336.73034)
		(width 0.10668)
		(layer "B.Cu")
		(net "SMB_RT_CPU1_P1_ROM_MUX_2D_R_SDA")
	)
	(segment
		(start 239.7887 -336.73034)
		(end 241.24666 -336.73034)
		(width 0.10668)
		(layer "B.Cu")
		(net "SMB_RT_CPU1_P1_ROM_MUX_2D_R_SDA")
	)
	(via
		(at 242.664488 -337.439)
		(size 0.6604)
		(drill 0.3302)
		(layers "F.Cu" "B.Cu")
		(net "SMB_RT_CPU1_P1_ROM_MUX_2D_R_SCL")
	)
	(segment
		(start 241.11966 -337.87334)
		(end 241.935 -337.058)
		(width 0.10668)
		(layer "B.Cu")
		(net "SMB_RT_CPU1_P1_ROM_MUX_2D_R_SCL")
	)
	(segment
		(start 239.6363 -337.312)
		(end 239.6363 -337.72094)
		(width 0.10668)
		(layer "B.Cu")
		(net "SMB_RT_CPU1_P1_ROM_MUX_2D_R_SCL")
	)
	(segment
		(start 239.7887 -337.87334)
		(end 241.11966 -337.87334)
		(width 0.10668)
		(layer "B.Cu")
		(net "SMB_RT_CPU1_P1_ROM_MUX_2D_R_SCL")
	)
	(segment
		(start 242.283488 -337.058)
		(end 242.664488 -337.439)
		(width 0.10668)
		(layer "B.Cu")
		(net "SMB_RT_CPU1_P1_ROM_MUX_2D_R_SCL")
	)
	(segment
		(start 241.935 -337.058)
		(end 242.283488 -337.058)
		(width 0.10668)
		(layer "B.Cu")
		(net "SMB_RT_CPU1_P1_ROM_MUX_2D_R_SCL")
	)
	(segment
		(start 238.8997 -337.312)
		(end 239.6363 -337.312)
		(width 0.10668)
		(layer "B.Cu")
		(net "SMB_RT_CPU1_P1_ROM_MUX_2D_R_SCL")
	)
	(segment
		(start 239.6363 -337.72094)
		(end 239.7887 -337.87334)
		(width 0.10668)
		(layer "B.Cu")
		(net "SMB_RT_CPU1_P1_ROM_MUX_2D_R_SCL")
	)
	(segment
		(start 242.932204 -337.171284)
		(end 242.664488 -337.439)
		(width 0.10668)
		(layer "B.Cu")
		(net "SMB_RT_CPU1_P1_ROM_MUX_2D_R_SCL")
	)
	(segment
		(start 244.464586 -337.171284)
		(end 242.932204 -337.171284)
		(width 0.10668)
		(layer "B.Cu")
		(net "SMB_RT_CPU1_P1_ROM_MUX_2D_R_SCL")
	)
	(via
		(at 241.521488 -333.883)
		(size 0.6604)
		(drill 0.3302)
		(layers "F.Cu" "B.Cu")
		(net "SMB_RT_CPU1_P0_ROM_MUX_2D_R_SDA")
	)
	(segment
		(start 238.8997 -333.883)
		(end 239.6363 -333.883)
		(width 0.10668)
		(layer "B.Cu")
		(net "SMB_RT_CPU1_P0_ROM_MUX_2D_R_SDA")
	)
	(segment
		(start 243.36756 -335.221072)
		(end 244.464586 -335.221072)
		(width 0.10668)
		(layer "B.Cu")
		(net "SMB_RT_CPU1_P0_ROM_MUX_2D_R_SDA")
	)
	(segment
		(start 241.521488 -333.883)
		(end 242.029488 -333.883)
		(width 0.10668)
		(layer "B.Cu")
		(net "SMB_RT_CPU1_P0_ROM_MUX_2D_R_SDA")
	)
	(segment
		(start 240.960148 -334.44434)
		(end 241.521488 -333.883)
		(width 0.10668)
		(layer "B.Cu")
		(net "SMB_RT_CPU1_P0_ROM_MUX_2D_R_SDA")
	)
	(segment
		(start 239.6363 -333.883)
		(end 239.6363 -334.29194)
		(width 0.10668)
		(layer "B.Cu")
		(net "SMB_RT_CPU1_P0_ROM_MUX_2D_R_SDA")
	)
	(segment
		(start 239.6363 -334.29194)
		(end 239.7887 -334.44434)
		(width 0.10668)
		(layer "B.Cu")
		(net "SMB_RT_CPU1_P0_ROM_MUX_2D_R_SDA")
	)
	(segment
		(start 239.7887 -334.44434)
		(end 240.960148 -334.44434)
		(width 0.10668)
		(layer "B.Cu")
		(net "SMB_RT_CPU1_P0_ROM_MUX_2D_R_SDA")
	)
	(segment
		(start 242.029488 -333.883)
		(end 243.36756 -335.221072)
		(width 0.10668)
		(layer "B.Cu")
		(net "SMB_RT_CPU1_P0_ROM_MUX_2D_R_SDA")
	)
	(via
		(at 241.521488 -335.153)
		(size 0.6604)
		(drill 0.3302)
		(layers "F.Cu" "B.Cu")
		(net "SMB_RT_CPU1_P0_ROM_MUX_2D_R_SCL")
	)
	(segment
		(start 241.087148 -335.58734)
		(end 241.521488 -335.153)
		(width 0.10668)
		(layer "B.Cu")
		(net "SMB_RT_CPU1_P0_ROM_MUX_2D_R_SCL")
	)
	(segment
		(start 238.8997 -335.026)
		(end 239.6363 -335.026)
		(width 0.10668)
		(layer "B.Cu")
		(net "SMB_RT_CPU1_P0_ROM_MUX_2D_R_SCL")
	)
	(segment
		(start 239.6363 -335.026)
		(end 239.6363 -335.43494)
		(width 0.10668)
		(layer "B.Cu")
		(net "SMB_RT_CPU1_P0_ROM_MUX_2D_R_SCL")
	)
	(segment
		(start 242.537488 -335.153)
		(end 241.521488 -335.153)
		(width 0.10668)
		(layer "B.Cu")
		(net "SMB_RT_CPU1_P0_ROM_MUX_2D_R_SCL")
	)
	(segment
		(start 244.464586 -335.871058)
		(end 243.255546 -335.871058)
		(width 0.10668)
		(layer "B.Cu")
		(net "SMB_RT_CPU1_P0_ROM_MUX_2D_R_SCL")
	)
	(segment
		(start 239.7887 -335.58734)
		(end 241.087148 -335.58734)
		(width 0.10668)
		(layer "B.Cu")
		(net "SMB_RT_CPU1_P0_ROM_MUX_2D_R_SCL")
	)
	(segment
		(start 239.6363 -335.43494)
		(end 239.7887 -335.58734)
		(width 0.10668)
		(layer "B.Cu")
		(net "SMB_RT_CPU1_P0_ROM_MUX_2D_R_SCL")
	)
	(segment
		(start 243.255546 -335.871058)
		(end 242.537488 -335.153)
		(width 0.10668)
		(layer "B.Cu")
		(net "SMB_RT_CPU1_P0_ROM_MUX_2D_R_SCL")
	)
	(via
		(at 228.826314 -337.82127)
		(size 0.6604)
		(drill 0.3302)
		(layers "F.Cu" "B.Cu")
		(net "SMB_RT_CPU0_P3_SDA")
	)
	(segment
		(start 229.335584 -337.312)
		(end 229.5779 -337.312)
		(width 0.10668)
		(layer "B.Cu")
		(net "SMB_RT_CPU0_P3_SDA")
	)
	(segment
		(start 227.11029 -337.82127)
		(end 228.826314 -337.82127)
		(width 0.10668)
		(layer "B.Cu")
		(net "SMB_RT_CPU0_P3_SDA")
	)
	(segment
		(start 228.826314 -337.82127)
		(end 229.335584 -337.312)
		(width 0.10668)
		(layer "B.Cu")
		(net "SMB_RT_CPU0_P3_SDA")
	)
	(via
		(at 228.826314 -336.524092)
		(size 0.6604)
		(drill 0.3302)
		(layers "F.Cu" "B.Cu")
		(net "SMB_RT_CPU0_P3_SCL")
	)
	(segment
		(start 228.826314 -336.524092)
		(end 229.054406 -336.296)
		(width 0.10668)
		(layer "B.Cu")
		(net "SMB_RT_CPU0_P3_SCL")
	)
	(segment
		(start 228.179122 -337.171284)
		(end 228.826314 -336.524092)
		(width 0.10668)
		(layer "B.Cu")
		(net "SMB_RT_CPU0_P3_SCL")
	)
	(segment
		(start 229.054406 -336.296)
		(end 229.5779 -336.296)
		(width 0.10668)
		(layer "B.Cu")
		(net "SMB_RT_CPU0_P3_SCL")
	)
	(segment
		(start 227.11029 -337.171284)
		(end 228.179122 -337.171284)
		(width 0.10668)
		(layer "B.Cu")
		(net "SMB_RT_CPU0_P3_SCL")
	)
	(via
		(at 230.859076 -337.312)
		(size 0.6604)
		(drill 0.3302)
		(layers "F.Cu" "B.Cu")
		(net "SMB_RT_CPU0_P3_R_SDA")
	)
	(segment
		(start 231.811576 -337.008724)
		(end 232.602024 -337.008724)
		(width 0.10668)
		(layer "B.Cu")
		(net "SMB_RT_CPU0_P3_R_SDA")
	)
	(segment
		(start 231.648 -337.1723)
		(end 231.811576 -337.008724)
		(width 0.10668)
		(layer "B.Cu")
		(net "SMB_RT_CPU0_P3_R_SDA")
	)
	(segment
		(start 230.998776 -337.1723)
		(end 231.648 -337.1723)
		(width 0.10668)
		(layer "B.Cu")
		(net "SMB_RT_CPU0_P3_R_SDA")
	)
	(segment
		(start 232.602024 -337.008724)
		(end 232.9053 -337.312)
		(width 0.10668)
		(layer "B.Cu")
		(net "SMB_RT_CPU0_P3_R_SDA")
	)
	(segment
		(start 230.859076 -337.312)
		(end 230.998776 -337.1723)
		(width 0.10668)
		(layer "B.Cu")
		(net "SMB_RT_CPU0_P3_R_SDA")
	)
	(segment
		(start 230.1113 -337.312)
		(end 230.859076 -337.312)
		(width 0.10668)
		(layer "B.Cu")
		(net "SMB_RT_CPU0_P3_R_SDA")
	)
	(via
		(at 230.858568 -335.991962)
		(size 0.6604)
		(drill 0.3302)
		(layers "F.Cu" "B.Cu")
		(net "SMB_RT_CPU0_P3_R_SCL")
	)
	(segment
		(start 230.55453 -336.296)
		(end 230.858568 -335.991962)
		(width 0.10668)
		(layer "B.Cu")
		(net "SMB_RT_CPU0_P3_R_SCL")
	)
	(segment
		(start 231.302306 -336.4357)
		(end 231.648 -336.4357)
		(width 0.10668)
		(layer "B.Cu")
		(net "SMB_RT_CPU0_P3_R_SCL")
	)
	(segment
		(start 230.1113 -336.296)
		(end 230.55453 -336.296)
		(width 0.10668)
		(layer "B.Cu")
		(net "SMB_RT_CPU0_P3_R_SCL")
	)
	(segment
		(start 231.846882 -336.634582)
		(end 231.648 -336.4357)
		(width 0.10668)
		(layer "B.Cu")
		(net "SMB_RT_CPU0_P3_R_SCL")
	)
	(segment
		(start 232.566718 -336.634582)
		(end 231.846882 -336.634582)
		(width 0.10668)
		(layer "B.Cu")
		(net "SMB_RT_CPU0_P3_R_SCL")
	)
	(segment
		(start 230.858568 -335.991962)
		(end 231.302306 -336.4357)
		(width 0.10668)
		(layer "B.Cu")
		(net "SMB_RT_CPU0_P3_R_SCL")
	)
	(segment
		(start 232.9053 -336.296)
		(end 232.566718 -336.634582)
		(width 0.10668)
		(layer "B.Cu")
		(net "SMB_RT_CPU0_P3_R_SCL")
	)
	(via
		(at 251.968 -338.074)
		(size 0.6604)
		(drill 0.3302)
		(layers "F.Cu" "B.Cu")
		(net "SMB_RT_CPU0_P3_ROM_MUX_2D_R_SDA")
	)
	(segment
		(start 254.7493 -337.93938)
		(end 252.10262 -337.93938)
		(width 0.10668)
		(layer "B.Cu")
		(net "SMB_RT_CPU0_P3_ROM_MUX_2D_R_SDA")
	)
	(segment
		(start 251.71527 -337.82127)
		(end 250.064778 -337.82127)
		(width 0.10668)
		(layer "B.Cu")
		(net "SMB_RT_CPU0_P3_ROM_MUX_2D_R_SDA")
	)
	(segment
		(start 254.9017 -337.37804)
		(end 255.6383 -337.37804)
		(width 0.10668)
		(layer "B.Cu")
		(net "SMB_RT_CPU0_P3_ROM_MUX_2D_R_SDA")
	)
	(segment
		(start 254.9017 -337.78698)
		(end 254.7493 -337.93938)
		(width 0.10668)
		(layer "B.Cu")
		(net "SMB_RT_CPU0_P3_ROM_MUX_2D_R_SDA")
	)
	(segment
		(start 252.10262 -337.93938)
		(end 251.968 -338.074)
		(width 0.10668)
		(layer "B.Cu")
		(net "SMB_RT_CPU0_P3_ROM_MUX_2D_R_SDA")
	)
	(segment
		(start 254.9017 -337.37804)
		(end 254.9017 -337.78698)
		(width 0.10668)
		(layer "B.Cu")
		(net "SMB_RT_CPU0_P3_ROM_MUX_2D_R_SDA")
	)
	(segment
		(start 251.968 -338.074)
		(end 251.71527 -337.82127)
		(width 0.10668)
		(layer "B.Cu")
		(net "SMB_RT_CPU0_P3_ROM_MUX_2D_R_SDA")
	)
	(via
		(at 253.111 -336.8167)
		(size 0.6604)
		(drill 0.3302)
		(layers "F.Cu" "B.Cu")
		(net "SMB_RT_CPU0_P3_ROM_MUX_2D_R_SCL")
	)
	(segment
		(start 254.9017 -336.6643)
		(end 254.7493 -336.8167)
		(width 0.10668)
		(layer "B.Cu")
		(net "SMB_RT_CPU0_P3_ROM_MUX_2D_R_SCL")
	)
	(segment
		(start 254.9017 -336.25536)
		(end 255.6383 -336.25536)
		(width 0.10668)
		(layer "B.Cu")
		(net "SMB_RT_CPU0_P3_ROM_MUX_2D_R_SCL")
	)
	(segment
		(start 252.756416 -337.171284)
		(end 250.064778 -337.171284)
		(width 0.10668)
		(layer "B.Cu")
		(net "SMB_RT_CPU0_P3_ROM_MUX_2D_R_SCL")
	)
	(segment
		(start 254.7493 -336.8167)
		(end 253.111 -336.8167)
		(width 0.10668)
		(layer "B.Cu")
		(net "SMB_RT_CPU0_P3_ROM_MUX_2D_R_SCL")
	)
	(segment
		(start 254.9017 -336.25536)
		(end 254.9017 -336.6643)
		(width 0.10668)
		(layer "B.Cu")
		(net "SMB_RT_CPU0_P3_ROM_MUX_2D_R_SCL")
	)
	(segment
		(start 253.111 -336.8167)
		(end 252.756416 -337.171284)
		(width 0.10668)
		(layer "B.Cu")
		(net "SMB_RT_CPU0_P3_ROM_MUX_2D_R_SCL")
	)
	(via
		(at 229.621842 -335.506568)
		(size 0.6604)
		(drill 0.3302)
		(layers "F.Cu" "B.Cu")
		(net "SMB_RT_CPU0_P2_SDA")
	)
	(segment
		(start 229.067868 -335.506568)
		(end 228.053392 -336.521044)
		(width 0.10668)
		(layer "B.Cu")
		(net "SMB_RT_CPU0_P2_SDA")
	)
	(segment
		(start 230.4161 -335.026)
		(end 230.10241 -335.026)
		(width 0.10668)
		(layer "B.Cu")
		(net "SMB_RT_CPU0_P2_SDA")
	)
	(segment
		(start 228.053392 -336.521044)
		(end 227.11029 -336.521044)
		(width 0.10668)
		(layer "B.Cu")
		(net "SMB_RT_CPU0_P2_SDA")
	)
	(segment
		(start 229.621842 -335.506568)
		(end 229.067868 -335.506568)
		(width 0.10668)
		(layer "B.Cu")
		(net "SMB_RT_CPU0_P2_SDA")
	)
	(segment
		(start 230.10241 -335.026)
		(end 229.621842 -335.506568)
		(width 0.10668)
		(layer "B.Cu")
		(net "SMB_RT_CPU0_P2_SDA")
	)
	(via
		(at 229.436168 -334.218788)
		(size 0.6604)
		(drill 0.3302)
		(layers "F.Cu" "B.Cu")
		(net "SMB_RT_CPU0_P2_SCL")
	)
	(segment
		(start 229.436168 -334.218788)
		(end 229.436168 -334.69072)
		(width 0.10668)
		(layer "B.Cu")
		(net "SMB_RT_CPU0_P2_SCL")
	)
	(segment
		(start 230.4161 -334.01)
		(end 230.116888 -334.01)
		(width 0.10668)
		(layer "B.Cu")
		(net "SMB_RT_CPU0_P2_SCL")
	)
	(segment
		(start 230.116888 -334.01)
		(end 229.9081 -334.218788)
		(width 0.10668)
		(layer "B.Cu")
		(net "SMB_RT_CPU0_P2_SCL")
	)
	(segment
		(start 228.064568 -335.871058)
		(end 227.11029 -335.871058)
		(width 0.10668)
		(layer "B.Cu")
		(net "SMB_RT_CPU0_P2_SCL")
	)
	(segment
		(start 229.9081 -334.218788)
		(end 229.436168 -334.218788)
		(width 0.10668)
		(layer "B.Cu")
		(net "SMB_RT_CPU0_P2_SCL")
	)
	(segment
		(start 228.992938 -334.942688)
		(end 228.064568 -335.871058)
		(width 0.10668)
		(layer "B.Cu")
		(net "SMB_RT_CPU0_P2_SCL")
	)
	(segment
		(start 229.1842 -334.942688)
		(end 228.992938 -334.942688)
		(width 0.10668)
		(layer "B.Cu")
		(net "SMB_RT_CPU0_P2_SCL")
	)
	(segment
		(start 229.436168 -334.69072)
		(end 229.1842 -334.942688)
		(width 0.10668)
		(layer "B.Cu")
		(net "SMB_RT_CPU0_P2_SCL")
	)
	(via
		(at 231.746298 -335.026)
		(size 0.6604)
		(drill 0.3302)
		(layers "F.Cu" "B.Cu")
		(net "SMB_RT_CPU0_P2_R_SDA")
	)
	(segment
		(start 232.537 -334.8863)
		(end 233.4006 -334.8863)
		(width 0.10668)
		(layer "B.Cu")
		(net "SMB_RT_CPU0_P2_R_SDA")
	)
	(segment
		(start 231.746298 -335.026)
		(end 230.9495 -335.026)
		(width 0.10668)
		(layer "B.Cu")
		(net "SMB_RT_CPU0_P2_R_SDA")
	)
	(segment
		(start 232.537 -334.8863)
		(end 231.885998 -334.8863)
		(width 0.10668)
		(layer "B.Cu")
		(net "SMB_RT_CPU0_P2_R_SDA")
	)
	(segment
		(start 233.4006 -334.8863)
		(end 233.5403 -335.026)
		(width 0.10668)
		(layer "B.Cu")
		(net "SMB_RT_CPU0_P2_R_SDA")
	)
	(segment
		(start 231.885998 -334.8863)
		(end 231.746298 -335.026)
		(width 0.10668)
		(layer "B.Cu")
		(net "SMB_RT_CPU0_P2_R_SDA")
	)
	(via
		(at 231.742234 -333.72679)
		(size 0.6604)
		(drill 0.3302)
		(layers "F.Cu" "B.Cu")
		(net "SMB_RT_CPU0_P2_R_SCL")
	)
	(segment
		(start 232.537 -334.1497)
		(end 233.4006 -334.1497)
		(width 0.10668)
		(layer "B.Cu")
		(net "SMB_RT_CPU0_P2_R_SCL")
	)
	(segment
		(start 231.23271 -333.72679)
		(end 230.9495 -334.01)
		(width 0.10668)
		(layer "B.Cu")
		(net "SMB_RT_CPU0_P2_R_SCL")
	)
	(segment
		(start 232.165144 -334.1497)
		(end 231.742234 -333.72679)
		(width 0.10668)
		(layer "B.Cu")
		(net "SMB_RT_CPU0_P2_R_SCL")
	)
	(segment
		(start 233.4006 -334.1497)
		(end 233.5403 -334.01)
		(width 0.10668)
		(layer "B.Cu")
		(net "SMB_RT_CPU0_P2_R_SCL")
	)
	(segment
		(start 232.537 -334.1497)
		(end 232.165144 -334.1497)
		(width 0.10668)
		(layer "B.Cu")
		(net "SMB_RT_CPU0_P2_R_SCL")
	)
	(segment
		(start 231.742234 -333.72679)
		(end 231.23271 -333.72679)
		(width 0.10668)
		(layer "B.Cu")
		(net "SMB_RT_CPU0_P2_R_SCL")
	)
	(via
		(at 251.841 -336.169)
		(size 0.6604)
		(drill 0.3302)
		(layers "F.Cu" "B.Cu")
		(net "SMB_RT_CPU0_P2_ROM_MUX_2D_R_SDA")
	)
	(segment
		(start 253.458726 -335.69402)
		(end 253.110746 -336.042)
		(width 0.10668)
		(layer "B.Cu")
		(net "SMB_RT_CPU0_P2_ROM_MUX_2D_R_SDA")
	)
	(segment
		(start 254.7493 -335.69402)
		(end 253.458726 -335.69402)
		(width 0.10668)
		(layer "B.Cu")
		(net "SMB_RT_CPU0_P2_ROM_MUX_2D_R_SDA")
	)
	(segment
		(start 254.9017 -335.54162)
		(end 254.7493 -335.69402)
		(width 0.10668)
		(layer "B.Cu")
		(net "SMB_RT_CPU0_P2_ROM_MUX_2D_R_SDA")
	)
	(segment
		(start 253.110746 -336.042)
		(end 251.968 -336.042)
		(width 0.10668)
		(layer "B.Cu")
		(net "SMB_RT_CPU0_P2_ROM_MUX_2D_R_SDA")
	)
	(segment
		(start 254.9017 -335.13268)
		(end 255.6383 -335.13268)
		(width 0.10668)
		(layer "B.Cu")
		(net "SMB_RT_CPU0_P2_ROM_MUX_2D_R_SDA")
	)
	(segment
		(start 251.968 -336.042)
		(end 251.841 -336.169)
		(width 0.10668)
		(layer "B.Cu")
		(net "SMB_RT_CPU0_P2_ROM_MUX_2D_R_SDA")
	)
	(segment
		(start 250.064778 -336.521044)
		(end 251.488956 -336.521044)
		(width 0.10668)
		(layer "B.Cu")
		(net "SMB_RT_CPU0_P2_ROM_MUX_2D_R_SDA")
	)
	(segment
		(start 254.9017 -335.13268)
		(end 254.9017 -335.54162)
		(width 0.10668)
		(layer "B.Cu")
		(net "SMB_RT_CPU0_P2_ROM_MUX_2D_R_SDA")
	)
	(segment
		(start 251.488956 -336.521044)
		(end 251.841 -336.169)
		(width 0.10668)
		(layer "B.Cu")
		(net "SMB_RT_CPU0_P2_ROM_MUX_2D_R_SDA")
	)
	(via
		(at 252.984 -334.899)
		(size 0.6604)
		(drill 0.3302)
		(layers "F.Cu" "B.Cu")
		(net "SMB_RT_CPU0_P2_ROM_MUX_2D_R_SCL")
	)
	(segment
		(start 254.9017 -334.01)
		(end 255.6383 -334.01)
		(width 0.10668)
		(layer "B.Cu")
		(net "SMB_RT_CPU0_P2_ROM_MUX_2D_R_SCL")
	)
	(segment
		(start 254.9017 -334.01)
		(end 254.9017 -334.41894)
		(width 0.10668)
		(layer "B.Cu")
		(net "SMB_RT_CPU0_P2_ROM_MUX_2D_R_SCL")
	)
	(segment
		(start 254.7493 -334.57134)
		(end 253.31166 -334.57134)
		(width 0.10668)
		(layer "B.Cu")
		(net "SMB_RT_CPU0_P2_ROM_MUX_2D_R_SCL")
	)
	(segment
		(start 252.984 -334.899)
		(end 252.010418 -334.899)
		(width 0.10668)
		(layer "B.Cu")
		(net "SMB_RT_CPU0_P2_ROM_MUX_2D_R_SCL")
	)
	(segment
		(start 253.31166 -334.57134)
		(end 252.984 -334.899)
		(width 0.10668)
		(layer "B.Cu")
		(net "SMB_RT_CPU0_P2_ROM_MUX_2D_R_SCL")
	)
	(segment
		(start 251.03836 -335.871058)
		(end 250.064778 -335.871058)
		(width 0.10668)
		(layer "B.Cu")
		(net "SMB_RT_CPU0_P2_ROM_MUX_2D_R_SCL")
	)
	(segment
		(start 252.010418 -334.899)
		(end 251.03836 -335.871058)
		(width 0.10668)
		(layer "B.Cu")
		(net "SMB_RT_CPU0_P2_ROM_MUX_2D_R_SCL")
	)
	(segment
		(start 254.9017 -334.41894)
		(end 254.7493 -334.57134)
		(width 0.10668)
		(layer "B.Cu")
		(net "SMB_RT_CPU0_P2_ROM_MUX_2D_R_SCL")
	)
	(via
		(at 228.834188 -339.78215)
		(size 0.6604)
		(drill 0.3302)
		(layers "F.Cu" "B.Cu")
		(net "SMB_RT_CPU0_P1_SDA")
	)
	(segment
		(start 230.4161 -339.598)
		(end 229.599998 -339.598)
		(width 0.10668)
		(layer "B.Cu")
		(net "SMB_RT_CPU0_P1_SDA")
	)
	(segment
		(start 229.415848 -339.78215)
		(end 228.834188 -339.78215)
		(width 0.10668)
		(layer "B.Cu")
		(net "SMB_RT_CPU0_P1_SDA")
	)
	(segment
		(start 229.599998 -339.598)
		(end 229.415848 -339.78215)
		(width 0.10668)
		(layer "B.Cu")
		(net "SMB_RT_CPU0_P1_SDA")
	)
	(segment
		(start 228.834188 -339.78215)
		(end 228.17328 -339.121242)
		(width 0.10668)
		(layer "B.Cu")
		(net "SMB_RT_CPU0_P1_SDA")
	)
	(segment
		(start 228.17328 -339.121242)
		(end 227.11029 -339.121242)
		(width 0.10668)
		(layer "B.Cu")
		(net "SMB_RT_CPU0_P1_SDA")
	)
	(via
		(at 229.672896 -338.796122)
		(size 0.6604)
		(drill 0.3302)
		(layers "F.Cu" "B.Cu")
		(net "SMB_RT_CPU0_P1_SCL")
	)
	(segment
		(start 228.788468 -338.471256)
		(end 227.11029 -338.471256)
		(width 0.10668)
		(layer "B.Cu")
		(net "SMB_RT_CPU0_P1_SCL")
	)
	(segment
		(start 230.4161 -338.582)
		(end 229.887018 -338.582)
		(width 0.10668)
		(layer "B.Cu")
		(net "SMB_RT_CPU0_P1_SCL")
	)
	(segment
		(start 229.113334 -338.796122)
		(end 228.788468 -338.471256)
		(width 0.10668)
		(layer "B.Cu")
		(net "SMB_RT_CPU0_P1_SCL")
	)
	(segment
		(start 229.887018 -338.582)
		(end 229.672896 -338.796122)
		(width 0.10668)
		(layer "B.Cu")
		(net "SMB_RT_CPU0_P1_SCL")
	)
	(segment
		(start 229.672896 -338.796122)
		(end 229.113334 -338.796122)
		(width 0.10668)
		(layer "B.Cu")
		(net "SMB_RT_CPU0_P1_SCL")
	)
	(via
		(at 231.704388 -339.728302)
		(size 0.6604)
		(drill 0.3302)
		(layers "F.Cu" "B.Cu")
		(net "SMB_RT_CPU0_P1_R_SDA")
	)
	(segment
		(start 232.537 -339.4583)
		(end 233.4006 -339.4583)
		(width 0.10668)
		(layer "B.Cu")
		(net "SMB_RT_CPU0_P1_R_SDA")
	)
	(segment
		(start 231.97439 -339.4583)
		(end 231.704388 -339.728302)
		(width 0.10668)
		(layer "B.Cu")
		(net "SMB_RT_CPU0_P1_R_SDA")
	)
	(segment
		(start 231.704388 -339.728302)
		(end 231.574086 -339.598)
		(width 0.10668)
		(layer "B.Cu")
		(net "SMB_RT_CPU0_P1_R_SDA")
	)
	(segment
		(start 233.4006 -339.4583)
		(end 233.5403 -339.598)
		(width 0.10668)
		(layer "B.Cu")
		(net "SMB_RT_CPU0_P1_R_SDA")
	)
	(segment
		(start 232.537 -339.4583)
		(end 231.97439 -339.4583)
		(width 0.10668)
		(layer "B.Cu")
		(net "SMB_RT_CPU0_P1_R_SDA")
	)
	(segment
		(start 231.574086 -339.598)
		(end 230.9495 -339.598)
		(width 0.10668)
		(layer "B.Cu")
		(net "SMB_RT_CPU0_P1_R_SDA")
	)
	(via
		(at 231.701594 -338.448142)
		(size 0.6604)
		(drill 0.3302)
		(layers "F.Cu" "B.Cu")
		(net "SMB_RT_CPU0_P1_R_SCL")
	)
	(segment
		(start 232.537 -338.7217)
		(end 231.975152 -338.7217)
		(width 0.10668)
		(layer "B.Cu")
		(net "SMB_RT_CPU0_P1_R_SCL")
	)
	(segment
		(start 233.4006 -338.7217)
		(end 233.5403 -338.582)
		(width 0.10668)
		(layer "B.Cu")
		(net "SMB_RT_CPU0_P1_R_SCL")
	)
	(segment
		(start 231.567736 -338.582)
		(end 231.701594 -338.448142)
		(width 0.10668)
		(layer "B.Cu")
		(net "SMB_RT_CPU0_P1_R_SCL")
	)
	(segment
		(start 232.537 -338.7217)
		(end 233.4006 -338.7217)
		(width 0.10668)
		(layer "B.Cu")
		(net "SMB_RT_CPU0_P1_R_SCL")
	)
	(segment
		(start 230.9495 -338.582)
		(end 231.567736 -338.582)
		(width 0.10668)
		(layer "B.Cu")
		(net "SMB_RT_CPU0_P1_R_SCL")
	)
	(segment
		(start 231.975152 -338.7217)
		(end 231.701594 -338.448142)
		(width 0.10668)
		(layer "B.Cu")
		(net "SMB_RT_CPU0_P1_R_SCL")
	)
	(via
		(at 252.349 -340.19998)
		(size 0.6604)
		(drill 0.3302)
		(layers "F.Cu" "B.Cu")
		(net "SMB_RT_CPU0_P1_ROM_MUX_2D_R_SDA")
	)
	(segment
		(start 252.349 -340.19998)
		(end 251.270262 -339.121242)
		(width 0.10668)
		(layer "B.Cu")
		(net "SMB_RT_CPU0_P1_ROM_MUX_2D_R_SDA")
	)
	(segment
		(start 254.9017 -339.63864)
		(end 255.6383 -339.63864)
		(width 0.10668)
		(layer "B.Cu")
		(net "SMB_RT_CPU0_P1_ROM_MUX_2D_R_SDA")
	)
	(segment
		(start 254.9017 -339.63864)
		(end 254.9017 -340.04758)
		(width 0.10668)
		(layer "B.Cu")
		(net "SMB_RT_CPU0_P1_ROM_MUX_2D_R_SDA")
	)
	(segment
		(start 254.7493 -340.19998)
		(end 252.349 -340.19998)
		(width 0.10668)
		(layer "B.Cu")
		(net "SMB_RT_CPU0_P1_ROM_MUX_2D_R_SDA")
	)
	(segment
		(start 254.9017 -340.04758)
		(end 254.7493 -340.19998)
		(width 0.10668)
		(layer "B.Cu")
		(net "SMB_RT_CPU0_P1_ROM_MUX_2D_R_SDA")
	)
	(segment
		(start 251.270262 -339.121242)
		(end 250.064778 -339.121242)
		(width 0.10668)
		(layer "B.Cu")
		(net "SMB_RT_CPU0_P1_ROM_MUX_2D_R_SDA")
	)
	(via
		(at 253.111 -339.0773)
		(size 0.6604)
		(drill 0.3302)
		(layers "F.Cu" "B.Cu")
		(net "SMB_RT_CPU0_P1_ROM_MUX_2D_R_SCL")
	)
	(segment
		(start 253.111 -339.0773)
		(end 251.8283 -339.0773)
		(width 0.10668)
		(layer "B.Cu")
		(net "SMB_RT_CPU0_P1_ROM_MUX_2D_R_SCL")
	)
	(segment
		(start 251.222256 -338.471256)
		(end 250.064778 -338.471256)
		(width 0.10668)
		(layer "B.Cu")
		(net "SMB_RT_CPU0_P1_ROM_MUX_2D_R_SCL")
	)
	(segment
		(start 254.7493 -339.0773)
		(end 253.111 -339.0773)
		(width 0.10668)
		(layer "B.Cu")
		(net "SMB_RT_CPU0_P1_ROM_MUX_2D_R_SCL")
	)
	(segment
		(start 254.9017 -338.51596)
		(end 255.6383 -338.51596)
		(width 0.10668)
		(layer "B.Cu")
		(net "SMB_RT_CPU0_P1_ROM_MUX_2D_R_SCL")
	)
	(segment
		(start 254.9017 -338.51596)
		(end 254.9017 -338.9249)
		(width 0.10668)
		(layer "B.Cu")
		(net "SMB_RT_CPU0_P1_ROM_MUX_2D_R_SCL")
	)
	(segment
		(start 251.8283 -339.0773)
		(end 251.222256 -338.471256)
		(width 0.10668)
		(layer "B.Cu")
		(net "SMB_RT_CPU0_P1_ROM_MUX_2D_R_SCL")
	)
	(segment
		(start 254.9017 -338.9249)
		(end 254.7493 -339.0773)
		(width 0.10668)
		(layer "B.Cu")
		(net "SMB_RT_CPU0_P1_ROM_MUX_2D_R_SCL")
	)
	(via
		(at 227.803964 -341.884)
		(size 0.6604)
		(drill 0.3302)
		(layers "F.Cu" "B.Cu")
		(net "SMB_RT_CPU0_P0_SDA")
	)
	(segment
		(start 228.165914 -340.548214)
		(end 228.165914 -340.828122)
		(width 0.10668)
		(layer "B.Cu")
		(net "SMB_RT_CPU0_P0_SDA")
	)
	(segment
		(start 227.803964 -341.190072)
		(end 227.803964 -341.884)
		(width 0.10668)
		(layer "B.Cu")
		(net "SMB_RT_CPU0_P0_SDA")
	)
	(segment
		(start 228.038914 -340.421214)
		(end 228.165914 -340.548214)
		(width 0.10668)
		(layer "B.Cu")
		(net "SMB_RT_CPU0_P0_SDA")
	)
	(segment
		(start 228.165914 -340.828122)
		(end 227.803964 -341.190072)
		(width 0.10668)
		(layer "B.Cu")
		(net "SMB_RT_CPU0_P0_SDA")
	)
	(segment
		(start 227.803964 -341.884)
		(end 229.5779 -341.884)
		(width 0.10668)
		(layer "B.Cu")
		(net "SMB_RT_CPU0_P0_SDA")
	)
	(segment
		(start 227.11029 -340.421214)
		(end 228.038914 -340.421214)
		(width 0.10668)
		(layer "B.Cu")
		(net "SMB_RT_CPU0_P0_SDA")
	)
	(via
		(at 228.82606 -341.073232)
		(size 0.6604)
		(drill 0.3302)
		(layers "F.Cu" "B.Cu")
		(net "SMB_RT_CPU0_P0_SCL")
	)
	(segment
		(start 228.507544 -340.754716)
		(end 228.507544 -340.266274)
		(width 0.10668)
		(layer "B.Cu")
		(net "SMB_RT_CPU0_P0_SCL")
	)
	(segment
		(start 229.031292 -340.868)
		(end 228.82606 -341.073232)
		(width 0.10668)
		(layer "B.Cu")
		(net "SMB_RT_CPU0_P0_SCL")
	)
	(segment
		(start 228.012498 -339.771228)
		(end 227.11029 -339.771228)
		(width 0.10668)
		(layer "B.Cu")
		(net "SMB_RT_CPU0_P0_SCL")
	)
	(segment
		(start 228.507544 -340.266274)
		(end 228.012498 -339.771228)
		(width 0.10668)
		(layer "B.Cu")
		(net "SMB_RT_CPU0_P0_SCL")
	)
	(segment
		(start 229.5779 -340.868)
		(end 229.031292 -340.868)
		(width 0.10668)
		(layer "B.Cu")
		(net "SMB_RT_CPU0_P0_SCL")
	)
	(segment
		(start 228.82606 -341.073232)
		(end 228.507544 -340.754716)
		(width 0.10668)
		(layer "B.Cu")
		(net "SMB_RT_CPU0_P0_SCL")
	)
	(via
		(at 230.863648 -341.990426)
		(size 0.6604)
		(drill 0.3302)
		(layers "F.Cu" "B.Cu")
		(net "SMB_RT_CPU0_P0_R_SDA")
	)
	(segment
		(start 232.58653 -341.56523)
		(end 232.9053 -341.884)
		(width 0.10668)
		(layer "B.Cu")
		(net "SMB_RT_CPU0_P0_R_SDA")
	)
	(segment
		(start 231.648 -341.7443)
		(end 231.82707 -341.56523)
		(width 0.10668)
		(layer "B.Cu")
		(net "SMB_RT_CPU0_P0_R_SDA")
	)
	(segment
		(start 230.863648 -341.990426)
		(end 231.109774 -341.7443)
		(width 0.10668)
		(layer "B.Cu")
		(net "SMB_RT_CPU0_P0_R_SDA")
	)
	(segment
		(start 230.757222 -341.884)
		(end 230.863648 -341.990426)
		(width 0.10668)
		(layer "B.Cu")
		(net "SMB_RT_CPU0_P0_R_SDA")
	)
	(segment
		(start 231.82707 -341.56523)
		(end 232.58653 -341.56523)
		(width 0.10668)
		(layer "B.Cu")
		(net "SMB_RT_CPU0_P0_R_SDA")
	)
	(segment
		(start 231.109774 -341.7443)
		(end 231.648 -341.7443)
		(width 0.10668)
		(layer "B.Cu")
		(net "SMB_RT_CPU0_P0_R_SDA")
	)
	(segment
		(start 230.1113 -341.884)
		(end 230.757222 -341.884)
		(width 0.10668)
		(layer "B.Cu")
		(net "SMB_RT_CPU0_P0_R_SDA")
	)
	(via
		(at 230.857806 -340.701122)
		(size 0.6604)
		(drill 0.3302)
		(layers "F.Cu" "B.Cu")
		(net "SMB_RT_CPU0_P0_R_SCL")
	)
	(segment
		(start 232.563924 -341.209376)
		(end 232.9053 -340.868)
		(width 0.10668)
		(layer "B.Cu")
		(net "SMB_RT_CPU0_P0_R_SCL")
	)
	(segment
		(start 230.690928 -340.868)
		(end 230.1113 -340.868)
		(width 0.10668)
		(layer "B.Cu")
		(net "SMB_RT_CPU0_P0_R_SCL")
	)
	(segment
		(start 231.648 -341.0077)
		(end 231.164384 -341.0077)
		(width 0.10668)
		(layer "B.Cu")
		(net "SMB_RT_CPU0_P0_R_SCL")
	)
	(segment
		(start 231.849676 -341.209376)
		(end 232.563924 -341.209376)
		(width 0.10668)
		(layer "B.Cu")
		(net "SMB_RT_CPU0_P0_R_SCL")
	)
	(segment
		(start 231.164384 -341.0077)
		(end 230.857806 -340.701122)
		(width 0.10668)
		(layer "B.Cu")
		(net "SMB_RT_CPU0_P0_R_SCL")
	)
	(segment
		(start 230.857806 -340.701122)
		(end 230.690928 -340.868)
		(width 0.10668)
		(layer "B.Cu")
		(net "SMB_RT_CPU0_P0_R_SCL")
	)
	(segment
		(start 231.648 -341.0077)
		(end 231.849676 -341.209376)
		(width 0.10668)
		(layer "B.Cu")
		(net "SMB_RT_CPU0_P0_R_SCL")
	)
	(via
		(at 252.967744 -342.662256)
		(size 0.6604)
		(drill 0.3302)
		(layers "F.Cu" "B.Cu")
		(net "SMB_RT_CPU0_P0_ROM_MUX_2D_R_SDA")
	)
	(segment
		(start 250.726702 -340.421214)
		(end 252.967744 -342.662256)
		(width 0.10668)
		(layer "B.Cu")
		(net "SMB_RT_CPU0_P0_ROM_MUX_2D_R_SDA")
	)
	(segment
		(start 254.9017 -341.884)
		(end 255.6383 -341.884)
		(width 0.10668)
		(layer "B.Cu")
		(net "SMB_RT_CPU0_P0_ROM_MUX_2D_R_SDA")
	)
	(segment
		(start 254.9017 -342.29294)
		(end 254.9017 -341.884)
		(width 0.10668)
		(layer "B.Cu")
		(net "SMB_RT_CPU0_P0_ROM_MUX_2D_R_SDA")
	)
	(segment
		(start 254.42164 -342.773)
		(end 254.9017 -342.29294)
		(width 0.10668)
		(layer "B.Cu")
		(net "SMB_RT_CPU0_P0_ROM_MUX_2D_R_SDA")
	)
	(segment
		(start 252.967744 -342.662256)
		(end 253.078488 -342.773)
		(width 0.10668)
		(layer "B.Cu")
		(net "SMB_RT_CPU0_P0_ROM_MUX_2D_R_SDA")
	)
	(segment
		(start 253.078488 -342.773)
		(end 254.42164 -342.773)
		(width 0.10668)
		(layer "B.Cu")
		(net "SMB_RT_CPU0_P0_ROM_MUX_2D_R_SDA")
	)
	(segment
		(start 250.064778 -340.421214)
		(end 250.726702 -340.421214)
		(width 0.10668)
		(layer "B.Cu")
		(net "SMB_RT_CPU0_P0_ROM_MUX_2D_R_SDA")
	)
	(via
		(at 252.984 -341.32266)
		(size 0.6604)
		(drill 0.3302)
		(layers "F.Cu" "B.Cu")
		(net "SMB_RT_CPU0_P0_ROM_MUX_2D_R_SCL")
	)
	(segment
		(start 252.984 -341.32266)
		(end 254.7493 -341.32266)
		(width 0.10668)
		(layer "B.Cu")
		(net "SMB_RT_CPU0_P0_ROM_MUX_2D_R_SCL")
	)
	(segment
		(start 254.9017 -341.17026)
		(end 254.9017 -340.76132)
		(width 0.10668)
		(layer "B.Cu")
		(net "SMB_RT_CPU0_P0_ROM_MUX_2D_R_SCL")
	)
	(segment
		(start 250.838716 -339.771228)
		(end 252.390148 -341.32266)
		(width 0.10668)
		(layer "B.Cu")
		(net "SMB_RT_CPU0_P0_ROM_MUX_2D_R_SCL")
	)
	(segment
		(start 254.9017 -340.76132)
		(end 255.6383 -340.76132)
		(width 0.10668)
		(layer "B.Cu")
		(net "SMB_RT_CPU0_P0_ROM_MUX_2D_R_SCL")
	)
	(segment
		(start 250.064778 -339.771228)
		(end 250.838716 -339.771228)
		(width 0.10668)
		(layer "B.Cu")
		(net "SMB_RT_CPU0_P0_ROM_MUX_2D_R_SCL")
	)
	(segment
		(start 252.390148 -341.32266)
		(end 252.984 -341.32266)
		(width 0.10668)
		(layer "B.Cu")
		(net "SMB_RT_CPU0_P0_ROM_MUX_2D_R_SCL")
	)
	(segment
		(start 254.7493 -341.32266)
		(end 254.9017 -341.17026)
		(width 0.10668)
		(layer "B.Cu")
		(net "SMB_RT_CPU0_P0_ROM_MUX_2D_R_SCL")
	)
	(via
		(at 228.19233 -331.95768)
		(size 0.6604)
		(drill 0.3302)
		(layers "F.Cu" "B.Cu")
		(net "SMB_MUX_RT_SDA")
	)
	(segment
		(start 228.046788 -333.9211)
		(end 228.19233 -333.775558)
		(width 0.10668)
		(layer "B.Cu")
		(net "SMB_MUX_RT_SDA")
	)
	(segment
		(start 228.19233 -331.95768)
		(end 229.44201 -330.708)
		(width 0.10668)
		(layer "B.Cu")
		(net "SMB_MUX_RT_SDA")
	)
	(segment
		(start 229.44201 -330.708)
		(end 230.6193 -330.708)
		(width 0.10668)
		(layer "B.Cu")
		(net "SMB_MUX_RT_SDA")
	)
	(segment
		(start 228.19233 -333.775558)
		(end 228.19233 -331.95768)
		(width 0.10668)
		(layer "B.Cu")
		(net "SMB_MUX_RT_SDA")
	)
	(segment
		(start 227.11029 -333.9211)
		(end 228.046788 -333.9211)
		(width 0.10668)
		(layer "B.Cu")
		(net "SMB_MUX_RT_SDA")
	)
	(via
		(at 228.82225 -333.08417)
		(size 0.6604)
		(drill 0.3302)
		(layers "F.Cu" "B.Cu")
		(net "SMB_MUX_RT_SCL")
	)
	(segment
		(start 230.6193 -331.724)
		(end 230.18242 -331.724)
		(width 0.10668)
		(layer "B.Cu")
		(net "SMB_MUX_RT_SCL")
	)
	(segment
		(start 228.82225 -333.08417)
		(end 228.538024 -333.368396)
		(width 0.10668)
		(layer "B.Cu")
		(net "SMB_MUX_RT_SCL")
	)
	(segment
		(start 228.538024 -334.072484)
		(end 228.039422 -334.571086)
		(width 0.10668)
		(layer "B.Cu")
		(net "SMB_MUX_RT_SCL")
	)
	(segment
		(start 228.039422 -334.571086)
		(end 227.11029 -334.571086)
		(width 0.10668)
		(layer "B.Cu")
		(net "SMB_MUX_RT_SCL")
	)
	(segment
		(start 228.538024 -333.368396)
		(end 228.538024 -334.072484)
		(width 0.10668)
		(layer "B.Cu")
		(net "SMB_MUX_RT_SCL")
	)
	(segment
		(start 230.18242 -331.724)
		(end 228.82225 -333.08417)
		(width 0.10668)
		(layer "B.Cu")
		(net "SMB_MUX_RT_SCL")
	)
	(via
		(at 253.199392 -331.368908)
		(size 0.6604)
		(drill 0.3302)
		(layers "F.Cu" "B.Cu")
		(net "SMB_MUX_RT_ROM_SDA")
	)
	(segment
		(start 253.6063 -330.962)
		(end 253.199392 -331.368908)
		(width 0.10668)
		(layer "B.Cu")
		(net "SMB_MUX_RT_ROM_SDA")
	)
	(segment
		(start 253.199392 -331.368908)
		(end 252.831854 -331.368908)
		(width 0.10668)
		(layer "B.Cu")
		(net "SMB_MUX_RT_ROM_SDA")
	)
	(segment
		(start 251.34316 -333.61884)
		(end 251.0409 -333.9211)
		(width 0.10668)
		(layer "B.Cu")
		(net "SMB_MUX_RT_ROM_SDA")
	)
	(segment
		(start 252.831854 -331.368908)
		(end 251.34316 -332.857602)
		(width 0.10668)
		(layer "B.Cu")
		(net "SMB_MUX_RT_ROM_SDA")
	)
	(segment
		(start 251.34316 -332.857602)
		(end 251.34316 -333.61884)
		(width 0.10668)
		(layer "B.Cu")
		(net "SMB_MUX_RT_ROM_SDA")
	)
	(segment
		(start 251.0409 -333.9211)
		(end 250.064778 -333.9211)
		(width 0.10668)
		(layer "B.Cu")
		(net "SMB_MUX_RT_ROM_SDA")
	)
	(segment
		(start 254.3683 -330.962)
		(end 253.6063 -330.962)
		(width 0.10668)
		(layer "B.Cu")
		(net "SMB_MUX_RT_ROM_SDA")
	)
	(via
		(at 251.923042 -333.24927)
		(size 0.6604)
		(drill 0.3302)
		(layers "F.Cu" "B.Cu")
		(net "SMB_MUX_RT_ROM_SCL")
	)
	(segment
		(start 253.092458 -332.079854)
		(end 251.923042 -333.24927)
		(width 0.10668)
		(layer "B.Cu")
		(net "SMB_MUX_RT_ROM_SCL")
	)
	(segment
		(start 253.504446 -332.079854)
		(end 253.092458 -332.079854)
		(width 0.10668)
		(layer "B.Cu")
		(net "SMB_MUX_RT_ROM_SCL")
	)
	(segment
		(start 254.3683 -331.978)
		(end 253.6063 -331.978)
		(width 0.10668)
		(layer "B.Cu")
		(net "SMB_MUX_RT_ROM_SCL")
	)
	(segment
		(start 251.923042 -333.24927)
		(end 251.923042 -333.661258)
		(width 0.10668)
		(layer "B.Cu")
		(net "SMB_MUX_RT_ROM_SCL")
	)
	(segment
		(start 251.923042 -333.661258)
		(end 251.013214 -334.571086)
		(width 0.10668)
		(layer "B.Cu")
		(net "SMB_MUX_RT_ROM_SCL")
	)
	(segment
		(start 251.013214 -334.571086)
		(end 250.064778 -334.571086)
		(width 0.10668)
		(layer "B.Cu")
		(net "SMB_MUX_RT_ROM_SCL")
	)
	(segment
		(start 253.6063 -331.978)
		(end 253.504446 -332.079854)
		(width 0.10668)
		(layer "B.Cu")
		(net "SMB_MUX_RT_ROM_SCL")
	)
	(segment
		(start 276.733 -414.655)
		(end 277.044404 -414.966404)
		(width 0.10668)
		(layer "F.Cu")
		(net "SMB_MUX_RT_ROM_R1_SDA")
	)
	(segment
		(start 279.644094 -412.125922)
		(end 278.373078 -412.125922)
		(width 0.10668)
		(layer "F.Cu")
		(net "SMB_MUX_RT_ROM_R1_SDA")
	)
	(segment
		(start 276.733 -413.766)
		(end 276.733 -414.655)
		(width 0.10668)
		(layer "F.Cu")
		(net "SMB_MUX_RT_ROM_R1_SDA")
	)
	(segment
		(start 277.044404 -414.966404)
		(end 277.181056 -414.966404)
		(width 0.10668)
		(layer "F.Cu")
		(net "SMB_MUX_RT_ROM_R1_SDA")
	)
	(segment
		(start 278.373078 -412.125922)
		(end 276.733 -413.766)
		(width 0.10668)
		(layer "F.Cu")
		(net "SMB_MUX_RT_ROM_R1_SDA")
	)
	(via
		(at 279.644094 -412.125922)
		(size 0.508)
		(drill 0.254)
		(layers "F.Cu" "B.Cu")
		(net "SMB_MUX_RT_ROM_R1_SDA")
	)
	(via
		(at 256.513584 -330.581)
		(size 0.508)
		(drill 0.254)
		(layers "F.Cu" "B.Cu")
		(net "SMB_MUX_RT_ROM_R1_SDA")
	)
	(segment
		(start 254.9017 -330.962)
		(end 256.132584 -330.962)
		(width 0.10668)
		(layer "B.Cu")
		(net "SMB_MUX_RT_ROM_R1_SDA")
	)
	(segment
		(start 256.132584 -330.962)
		(end 256.513584 -330.581)
		(width 0.10668)
		(layer "B.Cu")
		(net "SMB_MUX_RT_ROM_R1_SDA")
	)
	(segment
		(start 279.775666 -373.910352)
		(end 273.96948 -368.104166)
		(width 0.11684)
		(layer "In13.Cu")
		(net "SMB_MUX_RT_ROM_R1_SDA")
	)
	(segment
		(start 282.051506 -392.781282)
		(end 282.051506 -386.760974)
		(width 0.11684)
		(layer "In13.Cu")
		(net "SMB_MUX_RT_ROM_R1_SDA")
	)
	(segment
		(start 250.38812 -334.6704)
		(end 254.47752 -330.581)
		(width 0.11684)
		(layer "In13.Cu")
		(net "SMB_MUX_RT_ROM_R1_SDA")
	)
	(segment
		(start 282.566618 -410.816044)
		(end 282.566618 -409.889452)
		(width 0.11684)
		(layer "In13.Cu")
		(net "SMB_MUX_RT_ROM_R1_SDA")
	)
	(segment
		(start 281.462734 -386.172202)
		(end 281.462734 -377.823222)
		(width 0.11684)
		(layer "In13.Cu")
		(net "SMB_MUX_RT_ROM_R1_SDA")
	)
	(segment
		(start 273.96948 -368.104166)
		(end 269.597886 -368.104166)
		(width 0.11684)
		(layer "In13.Cu")
		(net "SMB_MUX_RT_ROM_R1_SDA")
	)
	(segment
		(start 281.462734 -377.823222)
		(end 279.775666 -376.136154)
		(width 0.11684)
		(layer "In13.Cu")
		(net "SMB_MUX_RT_ROM_R1_SDA")
	)
	(segment
		(start 250.38812 -346.40012)
		(end 250.38812 -334.6704)
		(width 0.11684)
		(layer "In13.Cu")
		(net "SMB_MUX_RT_ROM_R1_SDA")
	)
	(segment
		(start 280.016458 -412.498286)
		(end 280.884376 -412.498286)
		(width 0.11684)
		(layer "In13.Cu")
		(net "SMB_MUX_RT_ROM_R1_SDA")
	)
	(segment
		(start 281.418792 -393.413996)
		(end 282.051506 -392.781282)
		(width 0.11684)
		(layer "In13.Cu")
		(net "SMB_MUX_RT_ROM_R1_SDA")
	)
	(segment
		(start 282.051506 -386.760974)
		(end 281.462734 -386.172202)
		(width 0.11684)
		(layer "In13.Cu")
		(net "SMB_MUX_RT_ROM_R1_SDA")
	)
	(segment
		(start 279.775666 -376.136154)
		(end 279.775666 -373.910352)
		(width 0.11684)
		(layer "In13.Cu")
		(net "SMB_MUX_RT_ROM_R1_SDA")
	)
	(segment
		(start 267.240512 -363.252512)
		(end 250.38812 -346.40012)
		(width 0.11684)
		(layer "In13.Cu")
		(net "SMB_MUX_RT_ROM_R1_SDA")
	)
	(segment
		(start 281.418792 -408.741626)
		(end 281.418792 -393.413996)
		(width 0.11684)
		(layer "In13.Cu")
		(net "SMB_MUX_RT_ROM_R1_SDA")
	)
	(segment
		(start 267.240512 -365.746792)
		(end 267.240512 -363.252512)
		(width 0.11684)
		(layer "In13.Cu")
		(net "SMB_MUX_RT_ROM_R1_SDA")
	)
	(segment
		(start 279.644094 -412.125922)
		(end 280.016458 -412.498286)
		(width 0.11684)
		(layer "In13.Cu")
		(net "SMB_MUX_RT_ROM_R1_SDA")
	)
	(segment
		(start 282.566618 -409.889452)
		(end 281.418792 -408.741626)
		(width 0.11684)
		(layer "In13.Cu")
		(net "SMB_MUX_RT_ROM_R1_SDA")
	)
	(segment
		(start 280.884376 -412.498286)
		(end 282.566618 -410.816044)
		(width 0.11684)
		(layer "In13.Cu")
		(net "SMB_MUX_RT_ROM_R1_SDA")
	)
	(segment
		(start 269.597886 -368.104166)
		(end 267.240512 -365.746792)
		(width 0.11684)
		(layer "In13.Cu")
		(net "SMB_MUX_RT_ROM_R1_SDA")
	)
	(segment
		(start 254.47752 -330.581)
		(end 256.513584 -330.581)
		(width 0.11684)
		(layer "In13.Cu")
		(net "SMB_MUX_RT_ROM_R1_SDA")
	)
	(segment
		(start 277.191724 -414.00603)
		(end 277.217124 -414.00603)
		(width 0.10668)
		(layer "F.Cu")
		(net "SMB_MUX_RT_ROM_R1_SCL")
	)
	(segment
		(start 277.217124 -414.00603)
		(end 278.282908 -412.940246)
		(width 0.10668)
		(layer "F.Cu")
		(net "SMB_MUX_RT_ROM_R1_SCL")
	)
	(segment
		(start 278.282908 -412.940246)
		(end 279.031446 -412.940246)
		(width 0.10668)
		(layer "F.Cu")
		(net "SMB_MUX_RT_ROM_R1_SCL")
	)
	(via
		(at 279.031446 -412.940246)
		(size 0.508)
		(drill 0.254)
		(layers "F.Cu" "B.Cu")
		(net "SMB_MUX_RT_ROM_R1_SCL")
	)
	(via
		(at 256.51587 -331.597)
		(size 0.508)
		(drill 0.254)
		(layers "F.Cu" "B.Cu")
		(net "SMB_MUX_RT_ROM_R1_SCL")
	)
	(segment
		(start 254.9017 -331.978)
		(end 256.13487 -331.978)
		(width 0.10668)
		(layer "B.Cu")
		(net "SMB_MUX_RT_ROM_R1_SCL")
	)
	(segment
		(start 256.13487 -331.978)
		(end 256.51587 -331.597)
		(width 0.10668)
		(layer "B.Cu")
		(net "SMB_MUX_RT_ROM_R1_SCL")
	)
	(segment
		(start 254.247904 -331.597)
		(end 250.818904 -335.026)
		(width 0.11684)
		(layer "In13.Cu")
		(net "SMB_MUX_RT_ROM_R1_SCL")
	)
	(segment
		(start 274.036028 -367.574322)
		(end 280.281126 -373.81942)
		(width 0.11684)
		(layer "In13.Cu")
		(net "SMB_MUX_RT_ROM_R1_SCL")
	)
	(segment
		(start 250.818904 -335.026)
		(end 250.818904 -346.195904)
		(width 0.11684)
		(layer "In13.Cu")
		(net "SMB_MUX_RT_ROM_R1_SCL")
	)
	(segment
		(start 267.716254 -363.093254)
		(end 267.716254 -365.572294)
		(width 0.11684)
		(layer "In13.Cu")
		(net "SMB_MUX_RT_ROM_R1_SCL")
	)
	(segment
		(start 281.916378 -377.392438)
		(end 281.916378 -385.861306)
		(width 0.11684)
		(layer "In13.Cu")
		(net "SMB_MUX_RT_ROM_R1_SCL")
	)
	(segment
		(start 281.861006 -395.139418)
		(end 281.861006 -408.374596)
		(width 0.11684)
		(layer "In13.Cu")
		(net "SMB_MUX_RT_ROM_R1_SCL")
	)
	(segment
		(start 283.008832 -409.522422)
		(end 283.008832 -411.164024)
		(width 0.11684)
		(layer "In13.Cu")
		(net "SMB_MUX_RT_ROM_R1_SCL")
	)
	(segment
		(start 281.23261 -412.940246)
		(end 279.031446 -412.940246)
		(width 0.11684)
		(layer "In13.Cu")
		(net "SMB_MUX_RT_ROM_R1_SCL")
	)
	(segment
		(start 280.281126 -375.757186)
		(end 281.916378 -377.392438)
		(width 0.11684)
		(layer "In13.Cu")
		(net "SMB_MUX_RT_ROM_R1_SCL")
	)
	(segment
		(start 269.718282 -367.574322)
		(end 274.036028 -367.574322)
		(width 0.11684)
		(layer "In13.Cu")
		(net "SMB_MUX_RT_ROM_R1_SCL")
	)
	(segment
		(start 250.818904 -346.195904)
		(end 267.716254 -363.093254)
		(width 0.11684)
		(layer "In13.Cu")
		(net "SMB_MUX_RT_ROM_R1_SCL")
	)
	(segment
		(start 281.916378 -385.861306)
		(end 282.570428 -386.515356)
		(width 0.11684)
		(layer "In13.Cu")
		(net "SMB_MUX_RT_ROM_R1_SCL")
	)
	(segment
		(start 267.716254 -365.572294)
		(end 269.718282 -367.574322)
		(width 0.11684)
		(layer "In13.Cu")
		(net "SMB_MUX_RT_ROM_R1_SCL")
	)
	(segment
		(start 283.008832 -411.164024)
		(end 281.23261 -412.940246)
		(width 0.11684)
		(layer "In13.Cu")
		(net "SMB_MUX_RT_ROM_R1_SCL")
	)
	(segment
		(start 282.570428 -389.501888)
		(end 283.79547 -390.72693)
		(width 0.11684)
		(layer "In13.Cu")
		(net "SMB_MUX_RT_ROM_R1_SCL")
	)
	(segment
		(start 281.861006 -408.374596)
		(end 283.008832 -409.522422)
		(width 0.11684)
		(layer "In13.Cu")
		(net "SMB_MUX_RT_ROM_R1_SCL")
	)
	(segment
		(start 283.79547 -393.204954)
		(end 281.861006 -395.139418)
		(width 0.11684)
		(layer "In13.Cu")
		(net "SMB_MUX_RT_ROM_R1_SCL")
	)
	(segment
		(start 280.281126 -373.81942)
		(end 280.281126 -375.757186)
		(width 0.11684)
		(layer "In13.Cu")
		(net "SMB_MUX_RT_ROM_R1_SCL")
	)
	(segment
		(start 283.79547 -390.72693)
		(end 283.79547 -393.204954)
		(width 0.11684)
		(layer "In13.Cu")
		(net "SMB_MUX_RT_ROM_R1_SCL")
	)
	(segment
		(start 256.51587 -331.597)
		(end 254.247904 -331.597)
		(width 0.11684)
		(layer "In13.Cu")
		(net "SMB_MUX_RT_ROM_R1_SCL")
	)
	(segment
		(start 282.570428 -386.515356)
		(end 282.570428 -389.501888)
		(width 0.11684)
		(layer "In13.Cu")
		(net "SMB_MUX_RT_ROM_R1_SCL")
	)
	(via
		(at 235.894372 -330.224892)
		(size 0.6604)
		(drill 0.3302)
		(layers "F.Cu" "B.Cu")
		(net "SMB_MUX_RT_R1_SDA")
	)
	(segment
		(start 231.1527 -330.708)
		(end 233.27995 -330.708)
		(width 0.10668)
		(layer "B.Cu")
		(net "SMB_MUX_RT_R1_SDA")
	)
	(segment
		(start 233.27995 -330.708)
		(end 233.27995 -330.51369)
		(width 0.10668)
		(layer "B.Cu")
		(net "SMB_MUX_RT_R1_SDA")
	)
	(segment
		(start 238.207296 -329.332336)
		(end 237.31474 -330.224892)
		(width 0.10668)
		(layer "B.Cu")
		(net "SMB_MUX_RT_R1_SDA")
	)
	(segment
		(start 237.31474 -330.224892)
		(end 235.894372 -330.224892)
		(width 0.10668)
		(layer "B.Cu")
		(net "SMB_MUX_RT_R1_SDA")
	)
	(segment
		(start 244.118384 -331.2668)
		(end 242.18392 -329.332336)
		(width 0.10668)
		(layer "B.Cu")
		(net "SMB_MUX_RT_R1_SDA")
	)
	(segment
		(start 233.27995 -330.51369)
		(end 233.568748 -330.224892)
		(width 0.10668)
		(layer "B.Cu")
		(net "SMB_MUX_RT_R1_SDA")
	)
	(segment
		(start 245.5037 -331.2668)
		(end 244.118384 -331.2668)
		(width 0.10668)
		(layer "B.Cu")
		(net "SMB_MUX_RT_R1_SDA")
	)
	(segment
		(start 242.18392 -329.332336)
		(end 238.207296 -329.332336)
		(width 0.10668)
		(layer "B.Cu")
		(net "SMB_MUX_RT_R1_SDA")
	)
	(segment
		(start 233.568748 -330.224892)
		(end 235.894372 -330.224892)
		(width 0.10668)
		(layer "B.Cu")
		(net "SMB_MUX_RT_R1_SDA")
	)
	(via
		(at 235.767626 -332.25359)
		(size 0.6604)
		(drill 0.3302)
		(layers "F.Cu" "B.Cu")
		(net "SMB_MUX_RT_R1_SCL")
	)
	(segment
		(start 233.27995 -332.015338)
		(end 233.27995 -331.724)
		(width 0.10668)
		(layer "B.Cu")
		(net "SMB_MUX_RT_R1_SCL")
	)
	(segment
		(start 233.518202 -332.25359)
		(end 233.27995 -332.015338)
		(width 0.10668)
		(layer "B.Cu")
		(net "SMB_MUX_RT_R1_SCL")
	)
	(segment
		(start 244.4496 -332.0796)
		(end 242.0493 -329.6793)
		(width 0.10668)
		(layer "B.Cu")
		(net "SMB_MUX_RT_R1_SCL")
	)
	(segment
		(start 245.5037 -332.0796)
		(end 244.4496 -332.0796)
		(width 0.10668)
		(layer "B.Cu")
		(net "SMB_MUX_RT_R1_SCL")
	)
	(segment
		(start 231.1527 -331.724)
		(end 233.27995 -331.724)
		(width 0.10668)
		(layer "B.Cu")
		(net "SMB_MUX_RT_R1_SCL")
	)
	(segment
		(start 238.341916 -329.6793)
		(end 235.767626 -332.25359)
		(width 0.10668)
		(layer "B.Cu")
		(net "SMB_MUX_RT_R1_SCL")
	)
	(segment
		(start 235.767626 -332.25359)
		(end 233.518202 -332.25359)
		(width 0.10668)
		(layer "B.Cu")
		(net "SMB_MUX_RT_R1_SCL")
	)
	(segment
		(start 242.0493 -329.6793)
		(end 238.341916 -329.6793)
		(width 0.10668)
		(layer "B.Cu")
		(net "SMB_MUX_RT_R1_SCL")
	)
	(via
		(at 232.76941 -332.74)
		(size 0.6604)
		(drill 0.3302)
		(layers "F.Cu" "B.Cu")
		(net "RT_SMB_MUX_ADDR2")
	)
	(segment
		(start 229.951788 -332.74)
		(end 228.891846 -333.799942)
		(width 0.10668)
		(layer "B.Cu")
		(net "RT_SMB_MUX_ADDR2")
	)
	(segment
		(start 230.6193 -332.405736)
		(end 230.846376 -332.17866)
		(width 0.10668)
		(layer "B.Cu")
		(net "RT_SMB_MUX_ADDR2")
	)
	(segment
		(start 230.846376 -332.17866)
		(end 232.20807 -332.17866)
		(width 0.10668)
		(layer "B.Cu")
		(net "RT_SMB_MUX_ADDR2")
	)
	(segment
		(start 230.6193 -332.74)
		(end 229.951788 -332.74)
		(width 0.10668)
		(layer "B.Cu")
		(net "RT_SMB_MUX_ADDR2")
	)
	(segment
		(start 228.891846 -334.467454)
		(end 228.138228 -335.221072)
		(width 0.10668)
		(layer "B.Cu")
		(net "RT_SMB_MUX_ADDR2")
	)
	(segment
		(start 228.138228 -335.221072)
		(end 227.11029 -335.221072)
		(width 0.10668)
		(layer "B.Cu")
		(net "RT_SMB_MUX_ADDR2")
	)
	(segment
		(start 232.76941 -332.74)
		(end 233.5403 -332.74)
		(width 0.10668)
		(layer "B.Cu")
		(net "RT_SMB_MUX_ADDR2")
	)
	(segment
		(start 230.6193 -332.74)
		(end 230.6193 -332.405736)
		(width 0.10668)
		(layer "B.Cu")
		(net "RT_SMB_MUX_ADDR2")
	)
	(segment
		(start 232.20807 -332.17866)
		(end 232.76941 -332.74)
		(width 0.10668)
		(layer "B.Cu")
		(net "RT_SMB_MUX_ADDR2")
	)
	(segment
		(start 228.891846 -333.799942)
		(end 228.891846 -334.467454)
		(width 0.10668)
		(layer "B.Cu")
		(net "RT_SMB_MUX_ADDR2")
	)
	(via
		(at 218.181428 -331.724)
		(size 0.6604)
		(drill 0.3302)
		(layers "F.Cu" "B.Cu")
		(net "RT_SMB_MUX_ADDR1")
	)
	(segment
		(start 215.1507 -332.062582)
		(end 215.2777 -332.189582)
		(width 0.10668)
		(layer "B.Cu")
		(net "RT_SMB_MUX_ADDR1")
	)
	(segment
		(start 215.2777 -332.189582)
		(end 217.3097 -332.189582)
		(width 0.10668)
		(layer "B.Cu")
		(net "RT_SMB_MUX_ADDR1")
	)
	(segment
		(start 217.4367 -332.062582)
		(end 217.4367 -331.724)
		(width 0.10668)
		(layer "B.Cu")
		(net "RT_SMB_MUX_ADDR1")
	)
	(segment
		(start 215.1507 -331.724)
		(end 215.1507 -332.062582)
		(width 0.10668)
		(layer "B.Cu")
		(net "RT_SMB_MUX_ADDR1")
	)
	(segment
		(start 220.345 -333.755746)
		(end 220.510354 -333.9211)
		(width 0.10668)
		(layer "B.Cu")
		(net "RT_SMB_MUX_ADDR1")
	)
	(segment
		(start 220.345 -332.994)
		(end 220.345 -333.755746)
		(width 0.10668)
		(layer "B.Cu")
		(net "RT_SMB_MUX_ADDR1")
	)
	(segment
		(start 220.510354 -333.9211)
		(end 221.510098 -333.9211)
		(width 0.10668)
		(layer "B.Cu")
		(net "RT_SMB_MUX_ADDR1")
	)
	(segment
		(start 217.3097 -332.189582)
		(end 217.4367 -332.062582)
		(width 0.10668)
		(layer "B.Cu")
		(net "RT_SMB_MUX_ADDR1")
	)
	(segment
		(start 218.181428 -331.724)
		(end 219.075 -331.724)
		(width 0.10668)
		(layer "B.Cu")
		(net "RT_SMB_MUX_ADDR1")
	)
	(segment
		(start 217.4367 -331.724)
		(end 218.181428 -331.724)
		(width 0.10668)
		(layer "B.Cu")
		(net "RT_SMB_MUX_ADDR1")
	)
	(segment
		(start 219.075 -331.724)
		(end 220.345 -332.994)
		(width 0.10668)
		(layer "B.Cu")
		(net "RT_SMB_MUX_ADDR1")
	)
	(via
		(at 219.412058 -331.270102)
		(size 0.6604)
		(drill 0.3302)
		(layers "F.Cu" "B.Cu")
		(net "RT_SMB_MUX_ADDR0")
	)
	(segment
		(start 217.4367 -330.708)
		(end 218.849956 -330.708)
		(width 0.10668)
		(layer "B.Cu")
		(net "RT_SMB_MUX_ADDR0")
	)
	(segment
		(start 220.726 -333.121)
		(end 220.876114 -333.271114)
		(width 0.10668)
		(layer "B.Cu")
		(net "RT_SMB_MUX_ADDR0")
	)
	(segment
		(start 217.4367 -330.708)
		(end 217.4367 -330.3397)
		(width 0.10668)
		(layer "B.Cu")
		(net "RT_SMB_MUX_ADDR0")
	)
	(segment
		(start 217.221054 -330.124054)
		(end 215.734646 -330.124054)
		(width 0.10668)
		(layer "B.Cu")
		(net "RT_SMB_MUX_ADDR0")
	)
	(segment
		(start 219.412058 -331.270102)
		(end 220.726 -332.584044)
		(width 0.10668)
		(layer "B.Cu")
		(net "RT_SMB_MUX_ADDR0")
	)
	(segment
		(start 218.849956 -330.708)
		(end 219.412058 -331.270102)
		(width 0.10668)
		(layer "B.Cu")
		(net "RT_SMB_MUX_ADDR0")
	)
	(segment
		(start 217.4367 -330.3397)
		(end 217.221054 -330.124054)
		(width 0.10668)
		(layer "B.Cu")
		(net "RT_SMB_MUX_ADDR0")
	)
	(segment
		(start 220.876114 -333.271114)
		(end 221.510098 -333.271114)
		(width 0.10668)
		(layer "B.Cu")
		(net "RT_SMB_MUX_ADDR0")
	)
	(segment
		(start 215.734646 -330.124054)
		(end 215.1507 -330.708)
		(width 0.10668)
		(layer "B.Cu")
		(net "RT_SMB_MUX_ADDR0")
	)
	(segment
		(start 220.726 -332.584044)
		(end 220.726 -333.121)
		(width 0.10668)
		(layer "B.Cu")
		(net "RT_SMB_MUX_ADDR0")
	)
	(via
		(at 253.234952 -333.365348)
		(size 0.6604)
		(drill 0.3302)
		(layers "F.Cu" "B.Cu")
		(net "RT_ROM_SMB_MUX_ADDR2")
	)
	(segment
		(start 253.234952 -333.365348)
		(end 253.297944 -333.42834)
		(width 0.10668)
		(layer "B.Cu")
		(net "RT_ROM_SMB_MUX_ADDR2")
	)
	(segment
		(start 252.4633 -334.137)
		(end 251.98324 -334.137)
		(width 0.10668)
		(layer "B.Cu")
		(net "RT_ROM_SMB_MUX_ADDR2")
	)
	(segment
		(start 253.297944 -333.42834)
		(end 254.7493 -333.42834)
		(width 0.10668)
		(layer "B.Cu")
		(net "RT_ROM_SMB_MUX_ADDR2")
	)
	(segment
		(start 254.9017 -333.27594)
		(end 254.9017 -332.867)
		(width 0.10668)
		(layer "B.Cu")
		(net "RT_ROM_SMB_MUX_ADDR2")
	)
	(segment
		(start 253.234952 -333.365348)
		(end 252.4633 -334.137)
		(width 0.10668)
		(layer "B.Cu")
		(net "RT_ROM_SMB_MUX_ADDR2")
	)
	(segment
		(start 254.9017 -332.867)
		(end 255.6383 -332.867)
		(width 0.10668)
		(layer "B.Cu")
		(net "RT_ROM_SMB_MUX_ADDR2")
	)
	(segment
		(start 251.98324 -334.137)
		(end 250.899168 -335.221072)
		(width 0.10668)
		(layer "B.Cu")
		(net "RT_ROM_SMB_MUX_ADDR2")
	)
	(segment
		(start 250.899168 -335.221072)
		(end 250.064778 -335.221072)
		(width 0.10668)
		(layer "B.Cu")
		(net "RT_ROM_SMB_MUX_ADDR2")
	)
	(segment
		(start 254.7493 -333.42834)
		(end 254.9017 -333.27594)
		(width 0.10668)
		(layer "B.Cu")
		(net "RT_ROM_SMB_MUX_ADDR2")
	)
	(via
		(at 242.193064 -331.597)
		(size 0.6604)
		(drill 0.3302)
		(layers "F.Cu" "B.Cu")
		(net "RT_ROM_SMB_MUX_ADDR1")
	)
	(segment
		(start 241.407188 -331.969618)
		(end 241.280188 -332.096618)
		(width 0.10668)
		(layer "B.Cu")
		(net "RT_ROM_SMB_MUX_ADDR1")
	)
	(segment
		(start 242.193064 -331.597)
		(end 243.299488 -332.703424)
		(width 0.10668)
		(layer "B.Cu")
		(net "RT_ROM_SMB_MUX_ADDR1")
	)
	(segment
		(start 241.280188 -332.096618)
		(end 240.034318 -332.096618)
		(width 0.10668)
		(layer "B.Cu")
		(net "RT_ROM_SMB_MUX_ADDR1")
	)
	(segment
		(start 243.299488 -332.703424)
		(end 243.299488 -333.755746)
		(width 0.10668)
		(layer "B.Cu")
		(net "RT_ROM_SMB_MUX_ADDR1")
	)
	(segment
		(start 241.407188 -331.597)
		(end 242.193064 -331.597)
		(width 0.10668)
		(layer "B.Cu")
		(net "RT_ROM_SMB_MUX_ADDR1")
	)
	(segment
		(start 243.464842 -333.9211)
		(end 244.464586 -333.9211)
		(width 0.10668)
		(layer "B.Cu")
		(net "RT_ROM_SMB_MUX_ADDR1")
	)
	(segment
		(start 240.034318 -332.096618)
		(end 239.4077 -331.47)
		(width 0.10668)
		(layer "B.Cu")
		(net "RT_ROM_SMB_MUX_ADDR1")
	)
	(segment
		(start 243.299488 -333.755746)
		(end 243.464842 -333.9211)
		(width 0.10668)
		(layer "B.Cu")
		(net "RT_ROM_SMB_MUX_ADDR1")
	)
	(segment
		(start 241.407188 -331.597)
		(end 241.407188 -331.969618)
		(width 0.10668)
		(layer "B.Cu")
		(net "RT_ROM_SMB_MUX_ADDR1")
	)
	(via
		(at 243.459 -331.851)
		(size 0.6604)
		(drill 0.3302)
		(layers "F.Cu" "B.Cu")
		(net "RT_ROM_SMB_MUX_ADDR0")
	)
	(segment
		(start 241.407188 -330.581)
		(end 242.189 -330.581)
		(width 0.10668)
		(layer "B.Cu")
		(net "RT_ROM_SMB_MUX_ADDR0")
	)
	(segment
		(start 243.680488 -333.121)
		(end 243.830602 -333.271114)
		(width 0.10668)
		(layer "B.Cu")
		(net "RT_ROM_SMB_MUX_ADDR0")
	)
	(segment
		(start 241.407188 -330.581)
		(end 241.407188 -330.2127)
		(width 0.10668)
		(layer "B.Cu")
		(net "RT_ROM_SMB_MUX_ADDR0")
	)
	(segment
		(start 241.214148 -330.01966)
		(end 239.96904 -330.01966)
		(width 0.10668)
		(layer "B.Cu")
		(net "RT_ROM_SMB_MUX_ADDR0")
	)
	(segment
		(start 243.830602 -333.271114)
		(end 244.464586 -333.271114)
		(width 0.10668)
		(layer "B.Cu")
		(net "RT_ROM_SMB_MUX_ADDR0")
	)
	(segment
		(start 239.96904 -330.01966)
		(end 239.4077 -330.581)
		(width 0.10668)
		(layer "B.Cu")
		(net "RT_ROM_SMB_MUX_ADDR0")
	)
	(segment
		(start 241.407188 -330.2127)
		(end 241.214148 -330.01966)
		(width 0.10668)
		(layer "B.Cu")
		(net "RT_ROM_SMB_MUX_ADDR0")
	)
	(segment
		(start 242.189 -330.581)
		(end 243.459 -331.851)
		(width 0.10668)
		(layer "B.Cu")
		(net "RT_ROM_SMB_MUX_ADDR0")
	)
	(segment
		(start 243.459 -331.851)
		(end 243.680488 -332.072488)
		(width 0.10668)
		(layer "B.Cu")
		(net "RT_ROM_SMB_MUX_ADDR0")
	)
	(segment
		(start 243.680488 -332.072488)
		(end 243.680488 -333.121)
		(width 0.10668)
		(layer "B.Cu")
		(net "RT_ROM_SMB_MUX_ADDR0")
	)
	(segment
		(start 133.418072 -394.425932)
		(end 133.418072 -391.281158)
		(width 0.10668)
		(layer "F.Cu")
		(net "RT_CPU1_P3_VQPS")
	)
	(segment
		(start 133.60654 -394.6144)
		(end 133.418072 -394.425932)
		(width 0.10668)
		(layer "F.Cu")
		(net "RT_CPU1_P3_VQPS")
	)
	(segment
		(start 134.00024 -395.3637)
		(end 134.23138 -395.13256)
		(width 0.10668)
		(layer "F.Cu")
		(net "RT_CPU1_P3_VQPS")
	)
	(segment
		(start 134.23138 -394.6144)
		(end 133.60654 -394.6144)
		(width 0.10668)
		(layer "F.Cu")
		(net "RT_CPU1_P3_VQPS")
	)
	(segment
		(start 133.653022 -395.3637)
		(end 132.824982 -395.3637)
		(width 0.10668)
		(layer "F.Cu")
		(net "RT_CPU1_P3_VQPS")
	)
	(segment
		(start 133.653022 -395.3637)
		(end 134.00024 -395.3637)
		(width 0.10668)
		(layer "F.Cu")
		(net "RT_CPU1_P3_VQPS")
	)
	(segment
		(start 134.23138 -395.13256)
		(end 134.23138 -394.6144)
		(width 0.10668)
		(layer "F.Cu")
		(net "RT_CPU1_P3_VQPS")
	)
	(via
		(at 132.824982 -395.3637)
		(size 0.762)
		(drill 0.381)
		(layers "F.Cu" "B.Cu")
		(net "RT_CPU1_P3_VQPS")
	)
	(segment
		(start 112.501172 -384.357372)
		(end 113.027968 -384.357372)
		(width 0.10668)
		(layer "F.Cu")
		(net "RT_CPU1_P3_SCAN_MODE")
	)
	(segment
		(start 113.027968 -384.357372)
		(end 113.201704 -384.531108)
		(width 0.10668)
		(layer "F.Cu")
		(net "RT_CPU1_P3_SCAN_MODE")
	)
	(via
		(at 111.76762 -383.04978)
		(size 0.6604)
		(drill 0.3302)
		(layers "F.Cu" "B.Cu")
		(net "RT_CPU1_P3_SCAN_MODE")
	)
	(via
		(at 112.501172 -384.357372)
		(size 0.4064)
		(drill 0.2032)
		(layers "F.Cu" "B.Cu")
		(net "RT_CPU1_P3_SCAN_MODE")
	)
	(segment
		(start 110.099094 -383.7432)
		(end 109.362494 -383.7432)
		(width 0.10668)
		(layer "B.Cu")
		(net "RT_CPU1_P3_SCAN_MODE")
	)
	(segment
		(start 112.501172 -384.357372)
		(end 112.501172 -383.783332)
		(width 0.10668)
		(layer "B.Cu")
		(net "RT_CPU1_P3_SCAN_MODE")
	)
	(segment
		(start 112.501172 -383.783332)
		(end 111.76762 -383.04978)
		(width 0.10668)
		(layer "B.Cu")
		(net "RT_CPU1_P3_SCAN_MODE")
	)
	(segment
		(start 110.500922 -383.04978)
		(end 110.099094 -383.451608)
		(width 0.10668)
		(layer "B.Cu")
		(net "RT_CPU1_P3_SCAN_MODE")
	)
	(segment
		(start 110.099094 -383.451608)
		(end 110.099094 -383.7432)
		(width 0.10668)
		(layer "B.Cu")
		(net "RT_CPU1_P3_SCAN_MODE")
	)
	(segment
		(start 111.76762 -383.04978)
		(end 110.500922 -383.04978)
		(width 0.10668)
		(layer "B.Cu")
		(net "RT_CPU1_P3_SCAN_MODE")
	)
	(segment
		(start 138.981942 -385.7879)
		(end 138.981942 -386.5245)
		(width 0.10668)
		(layer "F.Cu")
		(net "RT_CPU1_P3_ADDR3")
	)
	(segment
		(start 137.382758 -387.846062)
		(end 135.98525 -387.846062)
		(width 0.10668)
		(layer "F.Cu")
		(net "RT_CPU1_P3_ADDR3")
	)
	(segment
		(start 138.46429 -387.241288)
		(end 137.902696 -387.473952)
		(width 0.10668)
		(layer "F.Cu")
		(net "RT_CPU1_P3_ADDR3")
	)
	(segment
		(start 138.60653 -387.099048)
		(end 138.46429 -387.241288)
		(width 0.10668)
		(layer "F.Cu")
		(net "RT_CPU1_P3_ADDR3")
	)
	(segment
		(start 134.824978 -386.68579)
		(end 134.824978 -386.402072)
		(width 0.10668)
		(layer "F.Cu")
		(net "RT_CPU1_P3_ADDR3")
	)
	(segment
		(start 137.754868 -387.473952)
		(end 137.382758 -387.846062)
		(width 0.10668)
		(layer "F.Cu")
		(net "RT_CPU1_P3_ADDR3")
	)
	(segment
		(start 137.902696 -387.473952)
		(end 137.754868 -387.473952)
		(width 0.10668)
		(layer "F.Cu")
		(net "RT_CPU1_P3_ADDR3")
	)
	(segment
		(start 135.98525 -387.846062)
		(end 134.824978 -386.68579)
		(width 0.10668)
		(layer "F.Cu")
		(net "RT_CPU1_P3_ADDR3")
	)
	(segment
		(start 134.824978 -386.402072)
		(end 134.453884 -386.030978)
		(width 0.10668)
		(layer "F.Cu")
		(net "RT_CPU1_P3_ADDR3")
	)
	(segment
		(start 138.981942 -386.5245)
		(end 138.848846 -386.52323)
		(width 0.10668)
		(layer "F.Cu")
		(net "RT_CPU1_P3_ADDR3")
	)
	(segment
		(start 138.848846 -386.52323)
		(end 138.60653 -386.762752)
		(width 0.10668)
		(layer "F.Cu")
		(net "RT_CPU1_P3_ADDR3")
	)
	(segment
		(start 138.60653 -386.762752)
		(end 138.60653 -387.099048)
		(width 0.10668)
		(layer "F.Cu")
		(net "RT_CPU1_P3_ADDR3")
	)
	(via
		(at 137.382758 -387.846062)
		(size 0.762)
		(drill 0.381)
		(layers "F.Cu" "B.Cu")
		(net "RT_CPU1_P3_ADDR3")
	)
	(segment
		(start 140.2969 -388.038086)
		(end 140.035026 -388.29996)
		(width 0.10668)
		(layer "F.Cu")
		(net "RT_CPU1_P3_ADDR2")
	)
	(segment
		(start 140.2969 -386.941314)
		(end 140.2969 -388.038086)
		(width 0.10668)
		(layer "F.Cu")
		(net "RT_CPU1_P3_ADDR2")
	)
	(segment
		(start 137.263124 -388.432802)
		(end 138.066018 -388.432802)
		(width 0.10668)
		(layer "F.Cu")
		(net "RT_CPU1_P3_ADDR2")
	)
	(segment
		(start 139.880086 -386.5245)
		(end 140.2969 -386.941314)
		(width 0.10668)
		(layer "F.Cu")
		(net "RT_CPU1_P3_ADDR2")
	)
	(segment
		(start 135.908034 -388.085076)
		(end 136.775698 -388.085076)
		(width 0.10668)
		(layer "F.Cu")
		(net "RT_CPU1_P3_ADDR2")
	)
	(segment
		(start 136.775698 -388.085076)
		(end 137.024618 -388.333996)
		(width 0.10668)
		(layer "F.Cu")
		(net "RT_CPU1_P3_ADDR2")
	)
	(segment
		(start 138.066018 -388.432802)
		(end 138.652758 -387.846062)
		(width 0.10668)
		(layer "F.Cu")
		(net "RT_CPU1_P3_ADDR2")
	)
	(segment
		(start 139.794742 -386.5245)
		(end 139.880086 -386.5245)
		(width 0.10668)
		(layer "F.Cu")
		(net "RT_CPU1_P3_ADDR2")
	)
	(segment
		(start 137.024618 -388.333996)
		(end 137.263124 -388.432802)
		(width 0.10668)
		(layer "F.Cu")
		(net "RT_CPU1_P3_ADDR2")
	)
	(segment
		(start 140.035026 -388.29996)
		(end 139.106656 -388.29996)
		(width 0.10668)
		(layer "F.Cu")
		(net "RT_CPU1_P3_ADDR2")
	)
	(segment
		(start 139.106656 -388.29996)
		(end 138.652758 -387.846062)
		(width 0.10668)
		(layer "F.Cu")
		(net "RT_CPU1_P3_ADDR2")
	)
	(segment
		(start 134.453884 -386.630926)
		(end 135.908034 -388.085076)
		(width 0.10668)
		(layer "F.Cu")
		(net "RT_CPU1_P3_ADDR2")
	)
	(segment
		(start 139.794742 -386.5245)
		(end 139.794742 -385.7879)
		(width 0.10668)
		(layer "F.Cu")
		(net "RT_CPU1_P3_ADDR2")
	)
	(via
		(at 138.652758 -387.846062)
		(size 0.762)
		(drill 0.381)
		(layers "F.Cu" "B.Cu")
		(net "RT_CPU1_P3_ADDR2")
	)
	(segment
		(start 134.201154 -384.283966)
		(end 134.0485 -384.131312)
		(width 0.10668)
		(layer "F.Cu")
		(net "RT_CPU1_P3_ADDR1")
	)
	(segment
		(start 137.800842 -382.6764)
		(end 137.800842 -382.575308)
		(width 0.10668)
		(layer "F.Cu")
		(net "RT_CPU1_P3_ADDR1")
	)
	(segment
		(start 135.226552 -383.542286)
		(end 134.484872 -384.283966)
		(width 0.10668)
		(layer "F.Cu")
		(net "RT_CPU1_P3_ADDR1")
	)
	(segment
		(start 138.680952 -382.27)
		(end 138.945112 -382.00584)
		(width 0.10668)
		(layer "F.Cu")
		(net "RT_CPU1_P3_ADDR1")
	)
	(segment
		(start 133.927088 -384.131312)
		(end 133.718046 -383.92227)
		(width 0.10668)
		(layer "F.Cu")
		(net "RT_CPU1_P3_ADDR1")
	)
	(segment
		(start 137.316972 -382.6764)
		(end 136.451086 -383.542286)
		(width 0.10668)
		(layer "F.Cu")
		(net "RT_CPU1_P3_ADDR1")
	)
	(segment
		(start 138.10615 -382.27)
		(end 138.680952 -382.27)
		(width 0.10668)
		(layer "F.Cu")
		(net "RT_CPU1_P3_ADDR1")
	)
	(segment
		(start 138.945112 -382.00584)
		(end 139.277852 -382.00584)
		(width 0.10668)
		(layer "F.Cu")
		(net "RT_CPU1_P3_ADDR1")
	)
	(segment
		(start 139.277852 -382.37668)
		(end 139.121642 -382.53289)
		(width 0.10668)
		(layer "F.Cu")
		(net "RT_CPU1_P3_ADDR1")
	)
	(segment
		(start 136.451086 -383.542286)
		(end 135.226552 -383.542286)
		(width 0.10668)
		(layer "F.Cu")
		(net "RT_CPU1_P3_ADDR1")
	)
	(segment
		(start 137.800842 -382.6764)
		(end 137.316972 -382.6764)
		(width 0.10668)
		(layer "F.Cu")
		(net "RT_CPU1_P3_ADDR1")
	)
	(segment
		(start 139.277852 -382.00584)
		(end 139.277852 -382.37668)
		(width 0.10668)
		(layer "F.Cu")
		(net "RT_CPU1_P3_ADDR1")
	)
	(segment
		(start 139.121642 -382.726438)
		(end 139.10183 -382.74625)
		(width 0.10668)
		(layer "F.Cu")
		(net "RT_CPU1_P3_ADDR1")
	)
	(segment
		(start 139.10183 -382.74625)
		(end 139.10183 -383.30759)
		(width 0.10668)
		(layer "F.Cu")
		(net "RT_CPU1_P3_ADDR1")
	)
	(segment
		(start 134.0485 -384.131312)
		(end 133.927088 -384.131312)
		(width 0.10668)
		(layer "F.Cu")
		(net "RT_CPU1_P3_ADDR1")
	)
	(segment
		(start 137.800842 -382.575308)
		(end 138.10615 -382.27)
		(width 0.10668)
		(layer "F.Cu")
		(net "RT_CPU1_P3_ADDR1")
	)
	(segment
		(start 139.121642 -382.53289)
		(end 139.121642 -382.726438)
		(width 0.10668)
		(layer "F.Cu")
		(net "RT_CPU1_P3_ADDR1")
	)
	(segment
		(start 134.484872 -384.283966)
		(end 134.201154 -384.283966)
		(width 0.10668)
		(layer "F.Cu")
		(net "RT_CPU1_P3_ADDR1")
	)
	(via
		(at 139.10183 -383.30759)
		(size 0.762)
		(drill 0.381)
		(layers "F.Cu" "B.Cu")
		(net "RT_CPU1_P3_ADDR1")
	)
	(segment
		(start 166.608252 -394.413994)
		(end 166.395146 -394.6271)
		(width 0.10668)
		(layer "F.Cu")
		(net "RT_CPU1_P2_VQPS")
	)
	(segment
		(start 166.18077 -395.3637)
		(end 165.35273 -395.3637)
		(width 0.10668)
		(layer "F.Cu")
		(net "RT_CPU1_P2_VQPS")
	)
	(segment
		(start 166.608252 -392.811762)
		(end 166.608252 -394.413994)
		(width 0.10668)
		(layer "F.Cu")
		(net "RT_CPU1_P2_VQPS")
	)
	(segment
		(start 165.94582 -391.281158)
		(end 165.94582 -392.14933)
		(width 0.10668)
		(layer "F.Cu")
		(net "RT_CPU1_P2_VQPS")
	)
	(segment
		(start 165.94582 -392.14933)
		(end 166.608252 -392.811762)
		(width 0.10668)
		(layer "F.Cu")
		(net "RT_CPU1_P2_VQPS")
	)
	(segment
		(start 166.395146 -394.6271)
		(end 166.18077 -394.6271)
		(width 0.10668)
		(layer "F.Cu")
		(net "RT_CPU1_P2_VQPS")
	)
	(segment
		(start 166.18077 -394.6271)
		(end 166.18077 -395.3637)
		(width 0.10668)
		(layer "F.Cu")
		(net "RT_CPU1_P2_VQPS")
	)
	(via
		(at 165.35273 -395.3637)
		(size 0.762)
		(drill 0.381)
		(layers "F.Cu" "B.Cu")
		(net "RT_CPU1_P2_VQPS")
	)
	(segment
		(start 145.555716 -384.357372)
		(end 145.729452 -384.531108)
		(width 0.10668)
		(layer "F.Cu")
		(net "RT_CPU1_P2_SCAN_MODE")
	)
	(segment
		(start 145.02892 -384.357372)
		(end 145.555716 -384.357372)
		(width 0.10668)
		(layer "F.Cu")
		(net "RT_CPU1_P2_SCAN_MODE")
	)
	(via
		(at 145.02892 -384.357372)
		(size 0.4064)
		(drill 0.2032)
		(layers "F.Cu" "B.Cu")
		(net "RT_CPU1_P2_SCAN_MODE")
	)
	(via
		(at 144.42567 -383.367788)
		(size 0.6604)
		(drill 0.3302)
		(layers "F.Cu" "B.Cu")
		(net "RT_CPU1_P2_SCAN_MODE")
	)
	(segment
		(start 145.02892 -383.971038)
		(end 144.42567 -383.367788)
		(width 0.10668)
		(layer "B.Cu")
		(net "RT_CPU1_P2_SCAN_MODE")
	)
	(segment
		(start 145.02892 -384.357372)
		(end 145.02892 -383.971038)
		(width 0.10668)
		(layer "B.Cu")
		(net "RT_CPU1_P2_SCAN_MODE")
	)
	(segment
		(start 144.341342 -383.28346)
		(end 142.79499 -383.28346)
		(width 0.10668)
		(layer "B.Cu")
		(net "RT_CPU1_P2_SCAN_MODE")
	)
	(segment
		(start 142.79499 -383.28346)
		(end 142.626842 -383.451608)
		(width 0.10668)
		(layer "B.Cu")
		(net "RT_CPU1_P2_SCAN_MODE")
	)
	(segment
		(start 144.42567 -383.367788)
		(end 144.341342 -383.28346)
		(width 0.10668)
		(layer "B.Cu")
		(net "RT_CPU1_P2_SCAN_MODE")
	)
	(segment
		(start 142.626842 -383.451608)
		(end 142.626842 -383.7432)
		(width 0.10668)
		(layer "B.Cu")
		(net "RT_CPU1_P2_SCAN_MODE")
	)
	(segment
		(start 141.890242 -383.7432)
		(end 142.626842 -383.7432)
		(width 0.10668)
		(layer "B.Cu")
		(net "RT_CPU1_P2_SCAN_MODE")
	)
	(segment
		(start 173.859952 -389.23849)
		(end 174.297594 -389.676132)
		(width 0.10668)
		(layer "F.Cu")
		(net "RT_CPU1_P2_ADDR3")
	)
	(segment
		(start 174.297594 -389.676132)
		(end 174.297594 -390.53008)
		(width 0.10668)
		(layer "F.Cu")
		(net "RT_CPU1_P2_ADDR3")
	)
	(segment
		(start 167.974264 -387.829806)
		(end 168.65092 -388.506462)
		(width 0.10668)
		(layer "F.Cu")
		(net "RT_CPU1_P2_ADDR3")
	)
	(segment
		(start 174.297594 -390.53008)
		(end 175.034194 -390.53008)
		(width 0.10668)
		(layer "F.Cu")
		(net "RT_CPU1_P2_ADDR3")
	)
	(segment
		(start 168.65092 -388.506462)
		(end 168.65092 -389.04418)
		(width 0.10668)
		(layer "F.Cu")
		(net "RT_CPU1_P2_ADDR3")
	)
	(segment
		(start 168.65092 -389.04418)
		(end 168.84523 -389.23849)
		(width 0.10668)
		(layer "F.Cu")
		(net "RT_CPU1_P2_ADDR3")
	)
	(segment
		(start 168.84523 -389.23849)
		(end 173.859952 -389.23849)
		(width 0.10668)
		(layer "F.Cu")
		(net "RT_CPU1_P2_ADDR3")
	)
	(segment
		(start 167.974264 -387.02361)
		(end 167.974264 -387.829806)
		(width 0.10668)
		(layer "F.Cu")
		(net "RT_CPU1_P2_ADDR3")
	)
	(segment
		(start 166.981632 -386.030978)
		(end 167.974264 -387.02361)
		(width 0.10668)
		(layer "F.Cu")
		(net "RT_CPU1_P2_ADDR3")
	)
	(via
		(at 174.297594 -389.676132)
		(size 0.762)
		(drill 0.381)
		(layers "F.Cu" "B.Cu")
		(net "RT_CPU1_P2_ADDR3")
	)
	(segment
		(start 168.405048 -389.147558)
		(end 168.7195 -389.46201)
		(width 0.10668)
		(layer "F.Cu")
		(net "RT_CPU1_P2_ADDR2")
	)
	(segment
		(start 167.149272 -386.630926)
		(end 167.750744 -387.232398)
		(width 0.10668)
		(layer "F.Cu")
		(net "RT_CPU1_P2_ADDR2")
	)
	(segment
		(start 173.027848 -391.743946)
		(end 174.16526 -391.743946)
		(width 0.10668)
		(layer "F.Cu")
		(net "RT_CPU1_P2_ADDR2")
	)
	(segment
		(start 167.750744 -387.232398)
		(end 167.750744 -387.92531)
		(width 0.10668)
		(layer "F.Cu")
		(net "RT_CPU1_P2_ADDR2")
	)
	(segment
		(start 166.981632 -386.630926)
		(end 167.149272 -386.630926)
		(width 0.10668)
		(layer "F.Cu")
		(net "RT_CPU1_P2_ADDR2")
	)
	(segment
		(start 172.307758 -389.46201)
		(end 172.667168 -389.82142)
		(width 0.10668)
		(layer "F.Cu")
		(net "RT_CPU1_P2_ADDR2")
	)
	(segment
		(start 174.297594 -391.34288)
		(end 175.034194 -391.34288)
		(width 0.10668)
		(layer "F.Cu")
		(net "RT_CPU1_P2_ADDR2")
	)
	(segment
		(start 172.667168 -390.301988)
		(end 172.667168 -391.383266)
		(width 0.10668)
		(layer "F.Cu")
		(net "RT_CPU1_P2_ADDR2")
	)
	(segment
		(start 168.7195 -389.46201)
		(end 172.307758 -389.46201)
		(width 0.10668)
		(layer "F.Cu")
		(net "RT_CPU1_P2_ADDR2")
	)
	(segment
		(start 172.667168 -389.82142)
		(end 172.667168 -390.301988)
		(width 0.10668)
		(layer "F.Cu")
		(net "RT_CPU1_P2_ADDR2")
	)
	(segment
		(start 174.297594 -391.611612)
		(end 174.297594 -391.34288)
		(width 0.10668)
		(layer "F.Cu")
		(net "RT_CPU1_P2_ADDR2")
	)
	(segment
		(start 174.16526 -391.743946)
		(end 174.297594 -391.611612)
		(width 0.10668)
		(layer "F.Cu")
		(net "RT_CPU1_P2_ADDR2")
	)
	(segment
		(start 172.667168 -391.383266)
		(end 173.027848 -391.743946)
		(width 0.10668)
		(layer "F.Cu")
		(net "RT_CPU1_P2_ADDR2")
	)
	(segment
		(start 168.405048 -388.579614)
		(end 168.405048 -389.147558)
		(width 0.10668)
		(layer "F.Cu")
		(net "RT_CPU1_P2_ADDR2")
	)
	(segment
		(start 167.750744 -387.92531)
		(end 168.405048 -388.579614)
		(width 0.10668)
		(layer "F.Cu")
		(net "RT_CPU1_P2_ADDR2")
	)
	(via
		(at 172.667168 -390.301988)
		(size 0.762)
		(drill 0.381)
		(layers "F.Cu" "B.Cu")
		(net "RT_CPU1_P2_ADDR2")
	)
	(segment
		(start 169.912284 -383.280666)
		(end 170.54957 -383.280666)
		(width 0.10668)
		(layer "F.Cu")
		(net "RT_CPU1_P2_ADDR1")
	)
	(segment
		(start 170.54957 -383.280666)
		(end 170.713146 -383.11709)
		(width 0.10668)
		(layer "F.Cu")
		(net "RT_CPU1_P2_ADDR1")
	)
	(segment
		(start 167.01262 -384.283966)
		(end 167.787574 -383.509012)
		(width 0.10668)
		(layer "F.Cu")
		(net "RT_CPU1_P2_ADDR1")
	)
	(segment
		(start 169.683938 -383.509012)
		(end 169.912284 -383.280666)
		(width 0.10668)
		(layer "F.Cu")
		(net "RT_CPU1_P2_ADDR1")
	)
	(segment
		(start 166.454836 -384.131312)
		(end 166.576248 -384.131312)
		(width 0.10668)
		(layer "F.Cu")
		(net "RT_CPU1_P2_ADDR1")
	)
	(segment
		(start 170.713146 -383.11709)
		(end 170.713146 -382.30429)
		(width 0.10668)
		(layer "F.Cu")
		(net "RT_CPU1_P2_ADDR1")
	)
	(segment
		(start 166.245794 -383.92227)
		(end 166.454836 -384.131312)
		(width 0.10668)
		(layer "F.Cu")
		(net "RT_CPU1_P2_ADDR1")
	)
	(segment
		(start 166.576248 -384.131312)
		(end 166.728902 -384.283966)
		(width 0.10668)
		(layer "F.Cu")
		(net "RT_CPU1_P2_ADDR1")
	)
	(segment
		(start 166.728902 -384.283966)
		(end 167.01262 -384.283966)
		(width 0.10668)
		(layer "F.Cu")
		(net "RT_CPU1_P2_ADDR1")
	)
	(segment
		(start 167.787574 -383.509012)
		(end 169.683938 -383.509012)
		(width 0.10668)
		(layer "F.Cu")
		(net "RT_CPU1_P2_ADDR1")
	)
	(via
		(at 169.912284 -383.280666)
		(size 0.762)
		(drill 0.381)
		(layers "F.Cu" "B.Cu")
		(net "RT_CPU1_P2_ADDR1")
	)
	(segment
		(start 182.722012 -106.652822)
		(end 182.332122 -106.262932)
		(width 0.10668)
		(layer "F.Cu")
		(net "RT_BOARD_ID_ID1")
	)
	(segment
		(start 177.67808 -93.085666)
		(end 178.69408 -93.085666)
		(width 0.10668)
		(layer "F.Cu")
		(net "RT_BOARD_ID_ID1")
	)
	(segment
		(start 178.69408 -93.085666)
		(end 179.206398 -93.597984)
		(width 0.10668)
		(layer "F.Cu")
		(net "RT_BOARD_ID_ID1")
	)
	(segment
		(start 179.206398 -93.597984)
		(end 179.206398 -94.136464)
		(width 0.10668)
		(layer "F.Cu")
		(net "RT_BOARD_ID_ID1")
	)
	(segment
		(start 179.206398 -94.136464)
		(end 179.333398 -94.263464)
		(width 0.10668)
		(layer "F.Cu")
		(net "RT_BOARD_ID_ID1")
	)
	(segment
		(start 179.333398 -94.263464)
		(end 180.218334 -94.263464)
		(width 0.10668)
		(layer "F.Cu")
		(net "RT_BOARD_ID_ID1")
	)
	(segment
		(start 180.218334 -94.263464)
		(end 180.686202 -93.795596)
		(width 0.10668)
		(layer "F.Cu")
		(net "RT_BOARD_ID_ID1")
	)
	(via
		(at 182.696104 -105.105962)
		(size 0.6604)
		(drill 0.3302)
		(layers "F.Cu" "B.Cu")
		(net "RT_BOARD_ID_ID1")
	)
	(via
		(at 180.686202 -93.795596)
		(size 0.508)
		(drill 0.254)
		(layers "F.Cu" "B.Cu")
		(net "RT_BOARD_ID_ID1")
	)
	(via
		(at 182.332122 -106.262932)
		(size 0.4572)
		(drill 0.254)
		(layers "F.Cu" "B.Cu")
		(net "RT_BOARD_ID_ID1")
	)
	(segment
		(start 182.332122 -106.262932)
		(end 182.332122 -106.026966)
		(width 0.10668)
		(layer "B.Cu")
		(net "RT_BOARD_ID_ID1")
	)
	(segment
		(start 182.332122 -106.026966)
		(end 182.696104 -105.662984)
		(width 0.10668)
		(layer "B.Cu")
		(net "RT_BOARD_ID_ID1")
	)
	(segment
		(start 182.696104 -105.662984)
		(end 182.696104 -105.105962)
		(width 0.10668)
		(layer "B.Cu")
		(net "RT_BOARD_ID_ID1")
	)
	(segment
		(start 182.332122 -104.7496)
		(end 181.69382 -104.111298)
		(width 0.11684)
		(layer "In11.Cu")
		(net "RT_BOARD_ID_ID1")
	)
	(segment
		(start 180.214778 -99.528884)
		(end 180.214778 -94.26702)
		(width 0.11684)
		(layer "In11.Cu")
		(net "RT_BOARD_ID_ID1")
	)
	(segment
		(start 181.69382 -101.007926)
		(end 180.214778 -99.528884)
		(width 0.11684)
		(layer "In11.Cu")
		(net "RT_BOARD_ID_ID1")
	)
	(segment
		(start 181.69382 -104.111298)
		(end 181.69382 -101.007926)
		(width 0.11684)
		(layer "In11.Cu")
		(net "RT_BOARD_ID_ID1")
	)
	(segment
		(start 182.332122 -106.262932)
		(end 182.332122 -104.7496)
		(width 0.11684)
		(layer "In11.Cu")
		(net "RT_BOARD_ID_ID1")
	)
	(segment
		(start 180.214778 -94.26702)
		(end 180.686202 -93.795596)
		(width 0.11684)
		(layer "In11.Cu")
		(net "RT_BOARD_ID_ID1")
	)
	(segment
		(start 183.522112 -109.052868)
		(end 183.132222 -108.662978)
		(width 0.10668)
		(layer "F.Cu")
		(net "RT_BOARD_ID_ID0")
	)
	(segment
		(start 176.65827 -93.628718)
		(end 176.883314 -93.628718)
		(width 0.10668)
		(layer "F.Cu")
		(net "RT_BOARD_ID_ID0")
	)
	(segment
		(start 175.11776 -93.085666)
		(end 176.115218 -93.085666)
		(width 0.10668)
		(layer "F.Cu")
		(net "RT_BOARD_ID_ID0")
	)
	(segment
		(start 176.115218 -93.085666)
		(end 176.65827 -93.628718)
		(width 0.10668)
		(layer "F.Cu")
		(net "RT_BOARD_ID_ID0")
	)
	(via
		(at 176.883314 -93.628718)
		(size 0.508)
		(drill 0.254)
		(layers "F.Cu" "B.Cu")
		(net "RT_BOARD_ID_ID0")
	)
	(via
		(at 183.132222 -108.662978)
		(size 0.4572)
		(drill 0.254)
		(layers "F.Cu" "B.Cu")
		(net "RT_BOARD_ID_ID0")
	)
	(segment
		(start 179.196746 -101.47173)
		(end 179.196746 -102.167436)
		(width 0.11684)
		(layer "In11.Cu")
		(net "RT_BOARD_ID_ID0")
	)
	(segment
		(start 179.026312 -102.33787)
		(end 179.026312 -104.794304)
		(width 0.11684)
		(layer "In11.Cu")
		(net "RT_BOARD_ID_ID0")
	)
	(segment
		(start 177.176938 -99.451922)
		(end 179.196746 -101.47173)
		(width 0.11684)
		(layer "In11.Cu")
		(net "RT_BOARD_ID_ID0")
	)
	(segment
		(start 179.026312 -104.794304)
		(end 181.939184 -107.707176)
		(width 0.11684)
		(layer "In11.Cu")
		(net "RT_BOARD_ID_ID0")
	)
	(segment
		(start 182.084218 -109.071918)
		(end 182.723282 -109.071918)
		(width 0.11684)
		(layer "In11.Cu")
		(net "RT_BOARD_ID_ID0")
	)
	(segment
		(start 176.883314 -93.628718)
		(end 177.176938 -93.922342)
		(width 0.11684)
		(layer "In11.Cu")
		(net "RT_BOARD_ID_ID0")
	)
	(segment
		(start 179.196746 -102.167436)
		(end 179.026312 -102.33787)
		(width 0.11684)
		(layer "In11.Cu")
		(net "RT_BOARD_ID_ID0")
	)
	(segment
		(start 182.723282 -109.071918)
		(end 183.132222 -108.662978)
		(width 0.11684)
		(layer "In11.Cu")
		(net "RT_BOARD_ID_ID0")
	)
	(segment
		(start 177.176938 -93.922342)
		(end 177.176938 -99.451922)
		(width 0.11684)
		(layer "In11.Cu")
		(net "RT_BOARD_ID_ID0")
	)
	(segment
		(start 181.939184 -107.707176)
		(end 181.939184 -108.926884)
		(width 0.11684)
		(layer "In11.Cu")
		(net "RT_BOARD_ID_ID0")
	)
	(segment
		(start 181.939184 -108.926884)
		(end 182.084218 -109.071918)
		(width 0.11684)
		(layer "In11.Cu")
		(net "RT_BOARD_ID_ID0")
	)
	(segment
		(start 216.666064 -126.710694)
		(end 215.78824 -126.710694)
		(width 0.10668)
		(layer "F.Cu")
		(net "RST_SMB_RT_ROM_R2_N")
	)
	(segment
		(start 215.78824 -126.710694)
		(end 215.735154 -126.76378)
		(width 0.10668)
		(layer "F.Cu")
		(net "RST_SMB_RT_ROM_R2_N")
	)
	(segment
		(start 190.721996 -120.252744)
		(end 191.111886 -120.642634)
		(width 0.10668)
		(layer "F.Cu")
		(net "RST_SMB_RT_ROM_R2_N")
	)
	(via
		(at 215.735154 -126.76378)
		(size 0.762)
		(drill 0.254)
		(layers "F.Cu" "B.Cu")
		(net "RST_SMB_RT_ROM_R2_N")
	)
	(via
		(at 191.111886 -120.642634)
		(size 0.4572)
		(drill 0.254)
		(layers "F.Cu" "B.Cu")
		(net "RST_SMB_RT_ROM_R2_N")
	)
	(segment
		(start 194.750436 -125.866652)
		(end 195.620894 -126.73711)
		(width 0.11684)
		(layer "In15.Cu")
		(net "RST_SMB_RT_ROM_R2_N")
	)
	(segment
		(start 212.003132 -128.41732)
		(end 213.211664 -127.208788)
		(width 0.11684)
		(layer "In15.Cu")
		(net "RST_SMB_RT_ROM_R2_N")
	)
	(segment
		(start 203.166472 -126.564136)
		(end 203.929742 -126.564136)
		(width 0.11684)
		(layer "In15.Cu")
		(net "RST_SMB_RT_ROM_R2_N")
	)
	(segment
		(start 198.643494 -127.825754)
		(end 199.895206 -127.825754)
		(width 0.11684)
		(layer "In15.Cu")
		(net "RST_SMB_RT_ROM_R2_N")
	)
	(segment
		(start 190.708788 -124.084842)
		(end 192.490598 -125.866652)
		(width 0.11684)
		(layer "In15.Cu")
		(net "RST_SMB_RT_ROM_R2_N")
	)
	(segment
		(start 191.111886 -120.642634)
		(end 190.708788 -121.045732)
		(width 0.11684)
		(layer "In15.Cu")
		(net "RST_SMB_RT_ROM_R2_N")
	)
	(segment
		(start 199.895206 -127.825754)
		(end 200.626218 -128.556766)
		(width 0.11684)
		(layer "In15.Cu")
		(net "RST_SMB_RT_ROM_R2_N")
	)
	(segment
		(start 204.582522 -127.216916)
		(end 208.839308 -127.216916)
		(width 0.11684)
		(layer "In15.Cu")
		(net "RST_SMB_RT_ROM_R2_N")
	)
	(segment
		(start 208.839308 -127.216916)
		(end 210.039712 -128.41732)
		(width 0.11684)
		(layer "In15.Cu")
		(net "RST_SMB_RT_ROM_R2_N")
	)
	(segment
		(start 213.211664 -127.208788)
		(end 214.758016 -127.208788)
		(width 0.11684)
		(layer "In15.Cu")
		(net "RST_SMB_RT_ROM_R2_N")
	)
	(segment
		(start 190.708788 -121.045732)
		(end 190.708788 -124.084842)
		(width 0.11684)
		(layer "In15.Cu")
		(net "RST_SMB_RT_ROM_R2_N")
	)
	(segment
		(start 201.173842 -128.556766)
		(end 203.166472 -126.564136)
		(width 0.11684)
		(layer "In15.Cu")
		(net "RST_SMB_RT_ROM_R2_N")
	)
	(segment
		(start 195.620894 -126.73711)
		(end 197.55485 -126.73711)
		(width 0.11684)
		(layer "In15.Cu")
		(net "RST_SMB_RT_ROM_R2_N")
	)
	(segment
		(start 214.758016 -127.208788)
		(end 215.203024 -126.76378)
		(width 0.11684)
		(layer "In15.Cu")
		(net "RST_SMB_RT_ROM_R2_N")
	)
	(segment
		(start 197.55485 -126.73711)
		(end 198.643494 -127.825754)
		(width 0.11684)
		(layer "In15.Cu")
		(net "RST_SMB_RT_ROM_R2_N")
	)
	(segment
		(start 203.929742 -126.564136)
		(end 204.582522 -127.216916)
		(width 0.11684)
		(layer "In15.Cu")
		(net "RST_SMB_RT_ROM_R2_N")
	)
	(segment
		(start 192.490598 -125.866652)
		(end 194.750436 -125.866652)
		(width 0.11684)
		(layer "In15.Cu")
		(net "RST_SMB_RT_ROM_R2_N")
	)
	(segment
		(start 200.626218 -128.556766)
		(end 201.173842 -128.556766)
		(width 0.11684)
		(layer "In15.Cu")
		(net "RST_SMB_RT_ROM_R2_N")
	)
	(segment
		(start 215.203024 -126.76378)
		(end 215.735154 -126.76378)
		(width 0.11684)
		(layer "In15.Cu")
		(net "RST_SMB_RT_ROM_R2_N")
	)
	(segment
		(start 210.039712 -128.41732)
		(end 212.003132 -128.41732)
		(width 0.11684)
		(layer "In15.Cu")
		(net "RST_SMB_RT_ROM_R2_N")
	)
	(segment
		(start 170.072304 -411.699202)
		(end 167.447976 -414.32353)
		(width 0.10668)
		(layer "F.Cu")
		(net "RST_SMB_RT_ROM_R1_N")
	)
	(segment
		(start 106.110532 -402.332952)
		(end 107.508802 -400.934682)
		(width 0.10668)
		(layer "F.Cu")
		(net "RST_SMB_RT_ROM_R1_N")
	)
	(segment
		(start 218.32316 -157.587696)
		(end 218.435936 -157.47492)
		(width 0.10668)
		(layer "F.Cu")
		(net "RST_SMB_RT_ROM_R1_N")
	)
	(segment
		(start 222.42272 -198.037704)
		(end 223.20631 -197.254114)
		(width 0.10668)
		(layer "F.Cu")
		(net "RST_SMB_RT_ROM_R1_N")
	)
	(segment
		(start 219.047822 -207.720692)
		(end 221.09811 -205.670404)
		(width 0.10668)
		(layer "F.Cu")
		(net "RST_SMB_RT_ROM_R1_N")
	)
	(segment
		(start 222.42272 -200.671176)
		(end 222.42272 -198.037704)
		(width 0.10668)
		(layer "F.Cu")
		(net "RST_SMB_RT_ROM_R1_N")
	)
	(segment
		(start 222.995744 -329.121516)
		(end 216.778332 -322.904104)
		(width 0.10668)
		(layer "F.Cu")
		(net "RST_SMB_RT_ROM_R1_N")
	)
	(segment
		(start 377.698 -426.9613)
		(end 377.698 -427.99)
		(width 0.10668)
		(layer "F.Cu")
		(net "RST_SMB_RT_ROM_R1_N")
	)
	(segment
		(start 221.09811 -201.995786)
		(end 222.42272 -200.671176)
		(width 0.10668)
		(layer "F.Cu")
		(net "RST_SMB_RT_ROM_R1_N")
	)
	(segment
		(start 218.435936 -157.47492)
		(end 218.435936 -138.276838)
		(width 0.10668)
		(layer "F.Cu")
		(net "RST_SMB_RT_ROM_R1_N")
	)
	(segment
		(start 377.0757 -426.339)
		(end 377.698 -426.9613)
		(width 0.10668)
		(layer "F.Cu")
		(net "RST_SMB_RT_ROM_R1_N")
	)
	(segment
		(start 220.308424 -136.40435)
		(end 220.308424 -135.201406)
		(width 0.10668)
		(layer "F.Cu")
		(net "RST_SMB_RT_ROM_R1_N")
	)
	(segment
		(start 216.778332 -322.904104)
		(end 216.778332 -208.653634)
		(width 0.10668)
		(layer "F.Cu")
		(net "RST_SMB_RT_ROM_R1_N")
	)
	(segment
		(start 222.995744 -333.333344)
		(end 222.995744 -329.121516)
		(width 0.10668)
		(layer "F.Cu")
		(net "RST_SMB_RT_ROM_R1_N")
	)
	(segment
		(start 219.079572 -164.425376)
		(end 218.32316 -163.668964)
		(width 0.10668)
		(layer "F.Cu")
		(net "RST_SMB_RT_ROM_R1_N")
	)
	(segment
		(start 106.003852 -402.842476)
		(end 106.110532 -402.735796)
		(width 0.10668)
		(layer "F.Cu")
		(net "RST_SMB_RT_ROM_R1_N")
	)
	(segment
		(start 223.20631 -169.123106)
		(end 220.9927 -166.909496)
		(width 0.10668)
		(layer "F.Cu")
		(net "RST_SMB_RT_ROM_R1_N")
	)
	(segment
		(start 220.9927 -166.909496)
		(end 220.9927 -165.000178)
		(width 0.10668)
		(layer "F.Cu")
		(net "RST_SMB_RT_ROM_R1_N")
	)
	(segment
		(start 112.7125 -401.280122)
		(end 112.250474 -401.742148)
		(width 0.10668)
		(layer "F.Cu")
		(net "RST_SMB_RT_ROM_R1_N")
	)
	(segment
		(start 107.508802 -400.934682)
		(end 111.443008 -400.934682)
		(width 0.10668)
		(layer "F.Cu")
		(net "RST_SMB_RT_ROM_R1_N")
	)
	(segment
		(start 220.03385 -128.27)
		(end 219.015056 -127.251206)
		(width 0.10668)
		(layer "F.Cu")
		(net "RST_SMB_RT_ROM_R1_N")
	)
	(segment
		(start 218.006676 -127.251206)
		(end 217.466164 -126.710694)
		(width 0.10668)
		(layer "F.Cu")
		(net "RST_SMB_RT_ROM_R1_N")
	)
	(segment
		(start 113.174018 -401.280122)
		(end 112.7125 -401.280122)
		(width 0.10668)
		(layer "F.Cu")
		(net "RST_SMB_RT_ROM_R1_N")
	)
	(segment
		(start 106.110532 -402.735796)
		(end 106.110532 -402.332952)
		(width 0.10668)
		(layer "F.Cu")
		(net "RST_SMB_RT_ROM_R1_N")
	)
	(segment
		(start 100.332286 -403.184106)
		(end 100.888038 -403.184106)
		(width 0.10668)
		(layer "F.Cu")
		(net "RST_SMB_RT_ROM_R1_N")
	)
	(segment
		(start 220.308424 -135.201406)
		(end 220.03385 -134.926832)
		(width 0.10668)
		(layer "F.Cu")
		(net "RST_SMB_RT_ROM_R1_N")
	)
	(segment
		(start 163.56838 -416.296094)
		(end 163.354512 -416.509962)
		(width 0.10668)
		(layer "F.Cu")
		(net "RST_SMB_RT_ROM_R1_N")
	)
	(segment
		(start 166.757604 -414.32353)
		(end 164.78504 -416.296094)
		(width 0.10668)
		(layer "F.Cu")
		(net "RST_SMB_RT_ROM_R1_N")
	)
	(segment
		(start 219.015056 -127.251206)
		(end 218.006676 -127.251206)
		(width 0.10668)
		(layer "F.Cu")
		(net "RST_SMB_RT_ROM_R1_N")
	)
	(segment
		(start 377.698 -427.99)
		(end 377.444 -428.244)
		(width 0.10668)
		(layer "F.Cu")
		(net "RST_SMB_RT_ROM_R1_N")
	)
	(segment
		(start 289.136074 -398.11833)
		(end 288.98977 -398.264634)
		(width 0.10668)
		(layer "F.Cu")
		(net "RST_SMB_RT_ROM_R1_N")
	)
	(segment
		(start 221.09811 -205.670404)
		(end 221.09811 -201.995786)
		(width 0.10668)
		(layer "F.Cu")
		(net "RST_SMB_RT_ROM_R1_N")
	)
	(segment
		(start 218.32316 -163.668964)
		(end 218.32316 -157.587696)
		(width 0.10668)
		(layer "F.Cu")
		(net "RST_SMB_RT_ROM_R1_N")
	)
	(segment
		(start 223.20631 -197.254114)
		(end 223.20631 -169.123106)
		(width 0.10668)
		(layer "F.Cu")
		(net "RST_SMB_RT_ROM_R1_N")
	)
	(segment
		(start 170.393106 -411.699202)
		(end 170.072304 -411.699202)
		(width 0.10668)
		(layer "F.Cu")
		(net "RST_SMB_RT_ROM_R1_N")
	)
	(segment
		(start 111.443008 -400.934682)
		(end 112.250474 -401.742148)
		(width 0.10668)
		(layer "F.Cu")
		(net "RST_SMB_RT_ROM_R1_N")
	)
	(segment
		(start 217.711274 -207.720692)
		(end 219.047822 -207.720692)
		(width 0.10668)
		(layer "F.Cu")
		(net "RST_SMB_RT_ROM_R1_N")
	)
	(segment
		(start 220.417898 -164.425376)
		(end 219.079572 -164.425376)
		(width 0.10668)
		(layer "F.Cu")
		(net "RST_SMB_RT_ROM_R1_N")
	)
	(segment
		(start 218.435936 -138.276838)
		(end 220.308424 -136.40435)
		(width 0.10668)
		(layer "F.Cu")
		(net "RST_SMB_RT_ROM_R1_N")
	)
	(segment
		(start 216.778332 -208.653634)
		(end 217.711274 -207.720692)
		(width 0.10668)
		(layer "F.Cu")
		(net "RST_SMB_RT_ROM_R1_N")
	)
	(segment
		(start 101.229668 -402.842476)
		(end 106.003852 -402.842476)
		(width 0.10668)
		(layer "F.Cu")
		(net "RST_SMB_RT_ROM_R1_N")
	)
	(segment
		(start 220.03385 -134.926832)
		(end 220.03385 -128.27)
		(width 0.10668)
		(layer "F.Cu")
		(net "RST_SMB_RT_ROM_R1_N")
	)
	(segment
		(start 164.78504 -416.296094)
		(end 163.56838 -416.296094)
		(width 0.10668)
		(layer "F.Cu")
		(net "RST_SMB_RT_ROM_R1_N")
	)
	(segment
		(start 100.888038 -403.184106)
		(end 101.229668 -402.842476)
		(width 0.10668)
		(layer "F.Cu")
		(net "RST_SMB_RT_ROM_R1_N")
	)
	(segment
		(start 167.447976 -414.32353)
		(end 166.757604 -414.32353)
		(width 0.10668)
		(layer "F.Cu")
		(net "RST_SMB_RT_ROM_R1_N")
	)
	(segment
		(start 220.9927 -165.000178)
		(end 220.417898 -164.425376)
		(width 0.10668)
		(layer "F.Cu")
		(net "RST_SMB_RT_ROM_R1_N")
	)
	(segment
		(start 288.98977 -398.264634)
		(end 288.98977 -398.663922)
		(width 0.10668)
		(layer "F.Cu")
		(net "RST_SMB_RT_ROM_R1_N")
	)
	(via
		(at 377.444 -428.244)
		(size 0.508)
		(drill 0.254)
		(layers "F.Cu" "B.Cu")
		(net "RST_SMB_RT_ROM_R1_N")
	)
	(via
		(at 225.327718 -364.93069)
		(size 0.508)
		(drill 0.254)
		(layers "F.Cu" "B.Cu")
		(net "RST_SMB_RT_ROM_R1_N")
	)
	(via
		(at 288.98977 -398.663922)
		(size 0.508)
		(drill 0.254)
		(layers "F.Cu" "B.Cu")
		(net "RST_SMB_RT_ROM_R1_N")
	)
	(via
		(at 171.033186 -425.299886)
		(size 0.508)
		(drill 0.254)
		(layers "F.Cu" "B.Cu")
		(net "RST_SMB_RT_ROM_R1_N")
	)
	(via
		(at 294.513 -427.355)
		(size 0.508)
		(drill 0.254)
		(layers "F.Cu" "B.Cu")
		(net "RST_SMB_RT_ROM_R1_N")
	)
	(via
		(at 163.354512 -416.509962)
		(size 0.508)
		(drill 0.254)
		(layers "F.Cu" "B.Cu")
		(net "RST_SMB_RT_ROM_R1_N")
	)
	(via
		(at 112.250474 -401.742148)
		(size 0.508)
		(drill 0.254)
		(layers "F.Cu" "B.Cu")
		(net "RST_SMB_RT_ROM_R1_N")
	)
	(via
		(at 222.995744 -333.333344)
		(size 0.508)
		(drill 0.254)
		(layers "F.Cu" "B.Cu")
		(net "RST_SMB_RT_ROM_R1_N")
	)
	(via
		(at 240.186718 -332.613)
		(size 0.508)
		(drill 0.254)
		(layers "F.Cu" "B.Cu")
		(net "RST_SMB_RT_ROM_R1_N")
	)
	(via
		(at 170.393106 -411.699202)
		(size 0.508)
		(drill 0.254)
		(layers "F.Cu" "B.Cu")
		(net "RST_SMB_RT_ROM_R1_N")
	)
	(via
		(at 252.857 -347.472)
		(size 0.508)
		(drill 0.254)
		(layers "F.Cu" "B.Cu")
		(net "RST_SMB_RT_ROM_R1_N")
	)
	(segment
		(start 239.4077 -332.218538)
		(end 239.22609 -332.036928)
		(width 0.10668)
		(layer "B.Cu")
		(net "RST_SMB_RT_ROM_R1_N")
	)
	(segment
		(start 378.662184 -427.955202)
		(end 377.732798 -427.955202)
		(width 0.10668)
		(layer "B.Cu")
		(net "RST_SMB_RT_ROM_R1_N")
	)
	(segment
		(start 236.892338 -333.013558)
		(end 235.714286 -335.857596)
		(width 0.10668)
		(layer "B.Cu")
		(net "RST_SMB_RT_ROM_R1_N")
	)
	(segment
		(start 237.868968 -332.036928)
		(end 236.892338 -333.013558)
		(width 0.10668)
		(layer "B.Cu")
		(net "RST_SMB_RT_ROM_R1_N")
	)
	(segment
		(start 170.39082 -424.786806)
		(end 170.850814 -424.786806)
		(width 0.10668)
		(layer "B.Cu")
		(net "RST_SMB_RT_ROM_R1_N")
	)
	(segment
		(start 163.689792 -416.845242)
		(end 163.354512 -416.509962)
		(width 0.10668)
		(layer "B.Cu")
		(net "RST_SMB_RT_ROM_R1_N")
	)
	(segment
		(start 417.195762 -428.327058)
		(end 417.195762 -425.489624)
		(width 0.10668)
		(layer "B.Cu")
		(net "RST_SMB_RT_ROM_R1_N")
	)
	(segment
		(start 170.850814 -424.786806)
		(end 171.033186 -424.969178)
		(width 0.10668)
		(layer "B.Cu")
		(net "RST_SMB_RT_ROM_R1_N")
	)
	(segment
		(start 418.732208 -428.682912)
		(end 417.551616 -428.682912)
		(width 0.10668)
		(layer "B.Cu")
		(net "RST_SMB_RT_ROM_R1_N")
	)
	(segment
		(start 239.589564 -332.794864)
		(end 240.004854 -332.794864)
		(width 0.10668)
		(layer "B.Cu")
		(net "RST_SMB_RT_ROM_R1_N")
	)
	(segment
		(start 239.4077 -332.613)
		(end 239.4077 -332.218538)
		(width 0.10668)
		(layer "B.Cu")
		(net "RST_SMB_RT_ROM_R1_N")
	)
	(segment
		(start 224.593658 -364.93069)
		(end 225.327718 -364.93069)
		(width 0.10668)
		(layer "B.Cu")
		(net "RST_SMB_RT_ROM_R1_N")
	)
	(segment
		(start 379.757432 -422.113202)
		(end 379.269244 -422.60139)
		(width 0.10668)
		(layer "B.Cu")
		(net "RST_SMB_RT_ROM_R1_N")
	)
	(segment
		(start 379.269244 -427.348142)
		(end 378.662184 -427.955202)
		(width 0.10668)
		(layer "B.Cu")
		(net "RST_SMB_RT_ROM_R1_N")
	)
	(segment
		(start 240.186718 -332.613)
		(end 240.873788 -332.613)
		(width 0.10668)
		(layer "B.Cu")
		(net "RST_SMB_RT_ROM_R1_N")
	)
	(segment
		(start 235.714286 -342.254332)
		(end 221.698058 -356.27056)
		(width 0.10668)
		(layer "B.Cu")
		(net "RST_SMB_RT_ROM_R1_N")
	)
	(segment
		(start 377.732798 -427.955202)
		(end 377.444 -428.244)
		(width 0.10668)
		(layer "B.Cu")
		(net "RST_SMB_RT_ROM_R1_N")
	)
	(segment
		(start 223.392746 -363.729778)
		(end 224.593658 -364.93069)
		(width 0.10668)
		(layer "B.Cu")
		(net "RST_SMB_RT_ROM_R1_N")
	)
	(segment
		(start 240.004854 -332.794864)
		(end 240.186718 -332.613)
		(width 0.10668)
		(layer "B.Cu")
		(net "RST_SMB_RT_ROM_R1_N")
	)
	(segment
		(start 379.269244 -422.60139)
		(end 379.269244 -427.348142)
		(width 0.10668)
		(layer "B.Cu")
		(net "RST_SMB_RT_ROM_R1_N")
	)
	(segment
		(start 413.81934 -422.113202)
		(end 379.757432 -422.113202)
		(width 0.10668)
		(layer "B.Cu")
		(net "RST_SMB_RT_ROM_R1_N")
	)
	(segment
		(start 235.714286 -335.857596)
		(end 235.714286 -342.254332)
		(width 0.10668)
		(layer "B.Cu")
		(net "RST_SMB_RT_ROM_R1_N")
	)
	(segment
		(start 221.698058 -359.638346)
		(end 223.392746 -363.729778)
		(width 0.10668)
		(layer "B.Cu")
		(net "RST_SMB_RT_ROM_R1_N")
	)
	(segment
		(start 163.689792 -417.295584)
		(end 163.689792 -416.845242)
		(width 0.10668)
		(layer "B.Cu")
		(net "RST_SMB_RT_ROM_R1_N")
	)
	(segment
		(start 239.4077 -332.613)
		(end 239.589564 -332.794864)
		(width 0.10668)
		(layer "B.Cu")
		(net "RST_SMB_RT_ROM_R1_N")
	)
	(segment
		(start 221.698058 -356.27056)
		(end 221.698058 -359.638346)
		(width 0.10668)
		(layer "B.Cu")
		(net "RST_SMB_RT_ROM_R1_N")
	)
	(segment
		(start 171.033186 -424.969178)
		(end 171.033186 -425.299886)
		(width 0.10668)
		(layer "B.Cu")
		(net "RST_SMB_RT_ROM_R1_N")
	)
	(segment
		(start 294.64 -427.228)
		(end 294.513 -427.355)
		(width 0.10668)
		(layer "B.Cu")
		(net "RST_SMB_RT_ROM_R1_N")
	)
	(segment
		(start 417.195762 -425.489624)
		(end 413.81934 -422.113202)
		(width 0.10668)
		(layer "B.Cu")
		(net "RST_SMB_RT_ROM_R1_N")
	)
	(segment
		(start 417.551616 -428.682912)
		(end 417.195762 -428.327058)
		(width 0.10668)
		(layer "B.Cu")
		(net "RST_SMB_RT_ROM_R1_N")
	)
	(segment
		(start 295.1353 -427.228)
		(end 294.64 -427.228)
		(width 0.10668)
		(layer "B.Cu")
		(net "RST_SMB_RT_ROM_R1_N")
	)
	(segment
		(start 239.22609 -332.036928)
		(end 237.868968 -332.036928)
		(width 0.10668)
		(layer "B.Cu")
		(net "RST_SMB_RT_ROM_R1_N")
	)
	(segment
		(start 164.057838 -402.22678)
		(end 112.735106 -402.22678)
		(width 0.11684)
		(layer "In2.Cu")
		(net "RST_SMB_RT_ROM_R1_N")
	)
	(segment
		(start 240.004854 -332.794864)
		(end 240.186718 -332.613)
		(width 0.11684)
		(layer "In2.Cu")
		(net "RST_SMB_RT_ROM_R1_N")
	)
	(segment
		(start 234.269534 -334.021176)
		(end 235.16971 -333.121)
		(width 0.11684)
		(layer "In2.Cu")
		(net "RST_SMB_RT_ROM_R1_N")
	)
	(segment
		(start 247.782334 -339.52307)
		(end 247.782334 -341.725504)
		(width 0.11684)
		(layer "In2.Cu")
		(net "RST_SMB_RT_ROM_R1_N")
	)
	(segment
		(start 305.523646 -423.836846)
		(end 304.310034 -423.836846)
		(width 0.11684)
		(layer "In2.Cu")
		(net "RST_SMB_RT_ROM_R1_N")
	)
	(segment
		(start 235.16971 -333.121)
		(end 239.255808 -333.121)
		(width 0.11684)
		(layer "In2.Cu")
		(net "RST_SMB_RT_ROM_R1_N")
	)
	(segment
		(start 297.942 -426.847)
		(end 295.021 -426.847)
		(width 0.11684)
		(layer "In2.Cu")
		(net "RST_SMB_RT_ROM_R1_N")
	)
	(segment
		(start 347.729556 -423.316654)
		(end 306.043838 -423.316654)
		(width 0.11684)
		(layer "In2.Cu")
		(net "RST_SMB_RT_ROM_R1_N")
	)
	(segment
		(start 247.782334 -341.725504)
		(end 252.857 -346.80017)
		(width 0.11684)
		(layer "In2.Cu")
		(net "RST_SMB_RT_ROM_R1_N")
	)
	(segment
		(start 239.581944 -332.794864)
		(end 240.004854 -332.794864)
		(width 0.11684)
		(layer "In2.Cu")
		(net "RST_SMB_RT_ROM_R1_N")
	)
	(segment
		(start 165.826694 -403.995636)
		(end 164.057838 -402.22678)
		(width 0.11684)
		(layer "In2.Cu")
		(net "RST_SMB_RT_ROM_R1_N")
	)
	(segment
		(start 240.872264 -332.613)
		(end 247.782334 -339.52307)
		(width 0.11684)
		(layer "In2.Cu")
		(net "RST_SMB_RT_ROM_R1_N")
	)
	(segment
		(start 170.393106 -411.699202)
		(end 169.9895 -411.699202)
		(width 0.11684)
		(layer "In2.Cu")
		(net "RST_SMB_RT_ROM_R1_N")
	)
	(segment
		(start 240.186718 -332.613)
		(end 240.872264 -332.613)
		(width 0.11684)
		(layer "In2.Cu")
		(net "RST_SMB_RT_ROM_R1_N")
	)
	(segment
		(start 303.003966 -425.142914)
		(end 299.646086 -425.142914)
		(width 0.11684)
		(layer "In2.Cu")
		(net "RST_SMB_RT_ROM_R1_N")
	)
	(segment
		(start 355.383338 -425.313856)
		(end 349.726758 -425.313856)
		(width 0.11684)
		(layer "In2.Cu")
		(net "RST_SMB_RT_ROM_R1_N")
	)
	(segment
		(start 362.6104 -426.55744)
		(end 362.6104 -423.133012)
		(width 0.11684)
		(layer "In2.Cu")
		(net "RST_SMB_RT_ROM_R1_N")
	)
	(segment
		(start 306.043838 -423.316654)
		(end 305.523646 -423.836846)
		(width 0.11684)
		(layer "In2.Cu")
		(net "RST_SMB_RT_ROM_R1_N")
	)
	(segment
		(start 361.452922 -421.975534)
		(end 358.72166 -421.975534)
		(width 0.11684)
		(layer "In2.Cu")
		(net "RST_SMB_RT_ROM_R1_N")
	)
	(segment
		(start 304.310034 -423.836846)
		(end 303.003966 -425.142914)
		(width 0.11684)
		(layer "In2.Cu")
		(net "RST_SMB_RT_ROM_R1_N")
	)
	(segment
		(start 358.72166 -421.975534)
		(end 355.383338 -425.313856)
		(width 0.11684)
		(layer "In2.Cu")
		(net "RST_SMB_RT_ROM_R1_N")
	)
	(segment
		(start 252.857 -346.80017)
		(end 252.857 -347.472)
		(width 0.11684)
		(layer "In2.Cu")
		(net "RST_SMB_RT_ROM_R1_N")
	)
	(segment
		(start 366.208818 -430.155858)
		(end 362.6104 -426.55744)
		(width 0.11684)
		(layer "In2.Cu")
		(net "RST_SMB_RT_ROM_R1_N")
	)
	(segment
		(start 377.444 -428.244)
		(end 375.532142 -430.155858)
		(width 0.11684)
		(layer "In2.Cu")
		(net "RST_SMB_RT_ROM_R1_N")
	)
	(segment
		(start 299.646086 -425.142914)
		(end 297.942 -426.847)
		(width 0.11684)
		(layer "In2.Cu")
		(net "RST_SMB_RT_ROM_R1_N")
	)
	(segment
		(start 349.726758 -425.313856)
		(end 347.729556 -423.316654)
		(width 0.11684)
		(layer "In2.Cu")
		(net "RST_SMB_RT_ROM_R1_N")
	)
	(segment
		(start 295.021 -426.847)
		(end 294.513 -427.355)
		(width 0.11684)
		(layer "In2.Cu")
		(net "RST_SMB_RT_ROM_R1_N")
	)
	(segment
		(start 112.735106 -402.22678)
		(end 112.250474 -401.742148)
		(width 0.11684)
		(layer "In2.Cu")
		(net "RST_SMB_RT_ROM_R1_N")
	)
	(segment
		(start 222.995744 -333.333344)
		(end 223.683576 -334.021176)
		(width 0.11684)
		(layer "In2.Cu")
		(net "RST_SMB_RT_ROM_R1_N")
	)
	(segment
		(start 239.255808 -333.121)
		(end 239.581944 -332.794864)
		(width 0.11684)
		(layer "In2.Cu")
		(net "RST_SMB_RT_ROM_R1_N")
	)
	(segment
		(start 375.532142 -430.155858)
		(end 366.208818 -430.155858)
		(width 0.11684)
		(layer "In2.Cu")
		(net "RST_SMB_RT_ROM_R1_N")
	)
	(segment
		(start 165.826694 -407.536396)
		(end 165.826694 -403.995636)
		(width 0.11684)
		(layer "In2.Cu")
		(net "RST_SMB_RT_ROM_R1_N")
	)
	(segment
		(start 223.683576 -334.021176)
		(end 234.269534 -334.021176)
		(width 0.11684)
		(layer "In2.Cu")
		(net "RST_SMB_RT_ROM_R1_N")
	)
	(segment
		(start 169.9895 -411.699202)
		(end 165.826694 -407.536396)
		(width 0.11684)
		(layer "In2.Cu")
		(net "RST_SMB_RT_ROM_R1_N")
	)
	(segment
		(start 362.6104 -423.133012)
		(end 361.452922 -421.975534)
		(width 0.11684)
		(layer "In2.Cu")
		(net "RST_SMB_RT_ROM_R1_N")
	)
	(segment
		(start 293.774622 -422.10228)
		(end 292.344094 -420.671752)
		(width 0.11684)
		(layer "In4.Cu")
		(net "RST_SMB_RT_ROM_R1_N")
	)
	(segment
		(start 294.513 -427.355)
		(end 293.774622 -426.616622)
		(width 0.11684)
		(layer "In4.Cu")
		(net "RST_SMB_RT_ROM_R1_N")
	)
	(segment
		(start 291.3253 -404.262082)
		(end 291.3253 -400.999452)
		(width 0.11684)
		(layer "In4.Cu")
		(net "RST_SMB_RT_ROM_R1_N")
	)
	(segment
		(start 290.913566 -404.673816)
		(end 291.3253 -404.262082)
		(width 0.11684)
		(layer "In4.Cu")
		(net "RST_SMB_RT_ROM_R1_N")
	)
	(segment
		(start 292.344094 -420.671752)
		(end 292.344094 -419.2905)
		(width 0.11684)
		(layer "In4.Cu")
		(net "RST_SMB_RT_ROM_R1_N")
	)
	(segment
		(start 290.913566 -417.859972)
		(end 290.913566 -404.673816)
		(width 0.11684)
		(layer "In4.Cu")
		(net "RST_SMB_RT_ROM_R1_N")
	)
	(segment
		(start 292.344094 -419.2905)
		(end 290.913566 -417.859972)
		(width 0.11684)
		(layer "In4.Cu")
		(net "RST_SMB_RT_ROM_R1_N")
	)
	(segment
		(start 291.3253 -400.999452)
		(end 288.98977 -398.663922)
		(width 0.11684)
		(layer "In4.Cu")
		(net "RST_SMB_RT_ROM_R1_N")
	)
	(segment
		(start 293.774622 -426.616622)
		(end 293.774622 -422.10228)
		(width 0.11684)
		(layer "In4.Cu")
		(net "RST_SMB_RT_ROM_R1_N")
	)
	(segment
		(start 219.30995 -372.289578)
		(end 223.4184 -368.181128)
		(width 0.11684)
		(layer "In6.Cu")
		(net "RST_SMB_RT_ROM_R1_N")
	)
	(segment
		(start 225.327718 -366.021874)
		(end 225.327718 -364.93069)
		(width 0.11684)
		(layer "In6.Cu")
		(net "RST_SMB_RT_ROM_R1_N")
	)
	(segment
		(start 175.742854 -401.499324)
		(end 174.911258 -400.667728)
		(width 0.11684)
		(layer "In6.Cu")
		(net "RST_SMB_RT_ROM_R1_N")
	)
	(segment
		(start 174.911258 -390.816592)
		(end 180.235352 -385.492498)
		(width 0.11684)
		(layer "In6.Cu")
		(net "RST_SMB_RT_ROM_R1_N")
	)
	(segment
		(start 192.883536 -372.289578)
		(end 219.30995 -372.289578)
		(width 0.11684)
		(layer "In6.Cu")
		(net "RST_SMB_RT_ROM_R1_N")
	)
	(segment
		(start 223.4184 -367.931192)
		(end 225.327718 -366.021874)
		(width 0.11684)
		(layer "In6.Cu")
		(net "RST_SMB_RT_ROM_R1_N")
	)
	(segment
		(start 170.67022 -418.565076)
		(end 171.270422 -419.165278)
		(width 0.11684)
		(layer "In6.Cu")
		(net "RST_SMB_RT_ROM_R1_N")
	)
	(segment
		(start 180.235352 -383.361184)
		(end 189.564264 -374.032272)
		(width 0.11684)
		(layer "In6.Cu")
		(net "RST_SMB_RT_ROM_R1_N")
	)
	(segment
		(start 170.896026 -411.196282)
		(end 171.305982 -411.196282)
		(width 0.11684)
		(layer "In6.Cu")
		(net "RST_SMB_RT_ROM_R1_N")
	)
	(segment
		(start 174.911258 -400.667728)
		(end 174.911258 -390.816592)
		(width 0.11684)
		(layer "In6.Cu")
		(net "RST_SMB_RT_ROM_R1_N")
	)
	(segment
		(start 170.565572 -424.832272)
		(end 171.033186 -425.299886)
		(width 0.11684)
		(layer "In6.Cu")
		(net "RST_SMB_RT_ROM_R1_N")
	)
	(segment
		(start 171.305982 -411.196282)
		(end 175.742854 -406.75941)
		(width 0.11684)
		(layer "In6.Cu")
		(net "RST_SMB_RT_ROM_R1_N")
	)
	(segment
		(start 170.393106 -411.699202)
		(end 170.67022 -411.976316)
		(width 0.11684)
		(layer "In6.Cu")
		(net "RST_SMB_RT_ROM_R1_N")
	)
	(segment
		(start 171.270422 -419.165278)
		(end 171.270422 -421.422576)
		(width 0.11684)
		(layer "In6.Cu")
		(net "RST_SMB_RT_ROM_R1_N")
	)
	(segment
		(start 170.393106 -411.699202)
		(end 170.896026 -411.196282)
		(width 0.11684)
		(layer "In6.Cu")
		(net "RST_SMB_RT_ROM_R1_N")
	)
	(segment
		(start 191.140842 -374.032272)
		(end 192.883536 -372.289578)
		(width 0.11684)
		(layer "In6.Cu")
		(net "RST_SMB_RT_ROM_R1_N")
	)
	(segment
		(start 175.742854 -406.75941)
		(end 175.742854 -401.499324)
		(width 0.11684)
		(layer "In6.Cu")
		(net "RST_SMB_RT_ROM_R1_N")
	)
	(segment
		(start 170.67022 -411.976316)
		(end 170.67022 -418.565076)
		(width 0.11684)
		(layer "In6.Cu")
		(net "RST_SMB_RT_ROM_R1_N")
	)
	(segment
		(start 171.270422 -421.422576)
		(end 170.565572 -422.127426)
		(width 0.11684)
		(layer "In6.Cu")
		(net "RST_SMB_RT_ROM_R1_N")
	)
	(segment
		(start 223.4184 -368.181128)
		(end 223.4184 -367.931192)
		(width 0.11684)
		(layer "In6.Cu")
		(net "RST_SMB_RT_ROM_R1_N")
	)
	(segment
		(start 189.564264 -374.032272)
		(end 191.140842 -374.032272)
		(width 0.11684)
		(layer "In6.Cu")
		(net "RST_SMB_RT_ROM_R1_N")
	)
	(segment
		(start 180.235352 -385.492498)
		(end 180.235352 -383.361184)
		(width 0.11684)
		(layer "In6.Cu")
		(net "RST_SMB_RT_ROM_R1_N")
	)
	(segment
		(start 170.565572 -422.127426)
		(end 170.565572 -424.832272)
		(width 0.11684)
		(layer "In6.Cu")
		(net "RST_SMB_RT_ROM_R1_N")
	)
	(segment
		(start 283.79039 -387.060694)
		(end 283.79039 -389.767572)
		(width 0.11684)
		(layer "In13.Cu")
		(net "RST_SMB_RT_ROM_R1_N")
	)
	(segment
		(start 288.595816 -397.973804)
		(end 288.98977 -398.367758)
		(width 0.11684)
		(layer "In13.Cu")
		(net "RST_SMB_RT_ROM_R1_N")
	)
	(segment
		(start 288.98977 -398.367758)
		(end 288.98977 -398.663922)
		(width 0.11684)
		(layer "In13.Cu")
		(net "RST_SMB_RT_ROM_R1_N")
	)
	(segment
		(start 280.78684 -375.377964)
		(end 282.338018 -376.929142)
		(width 0.11684)
		(layer "In13.Cu")
		(net "RST_SMB_RT_ROM_R1_N")
	)
	(segment
		(start 285.047182 -396.228824)
		(end 286.792162 -397.973804)
		(width 0.11684)
		(layer "In13.Cu")
		(net "RST_SMB_RT_ROM_R1_N")
	)
	(segment
		(start 252.857 -347.472)
		(end 268.214856 -362.829856)
		(width 0.11684)
		(layer "In13.Cu")
		(net "RST_SMB_RT_ROM_R1_N")
	)
	(segment
		(start 280.78684 -373.608854)
		(end 280.78684 -375.377964)
		(width 0.11684)
		(layer "In13.Cu")
		(net "RST_SMB_RT_ROM_R1_N")
	)
	(segment
		(start 273.530568 -366.352582)
		(end 280.78684 -373.608854)
		(width 0.11684)
		(layer "In13.Cu")
		(net "RST_SMB_RT_ROM_R1_N")
	)
	(segment
		(start 282.338018 -385.608322)
		(end 283.79039 -387.060694)
		(width 0.11684)
		(layer "In13.Cu")
		(net "RST_SMB_RT_ROM_R1_N")
	)
	(segment
		(start 282.338018 -376.929142)
		(end 282.338018 -385.608322)
		(width 0.11684)
		(layer "In13.Cu")
		(net "RST_SMB_RT_ROM_R1_N")
	)
	(segment
		(start 269.255494 -366.352582)
		(end 273.530568 -366.352582)
		(width 0.11684)
		(layer "In13.Cu")
		(net "RST_SMB_RT_ROM_R1_N")
	)
	(segment
		(start 283.79039 -389.767572)
		(end 285.047182 -391.024364)
		(width 0.11684)
		(layer "In13.Cu")
		(net "RST_SMB_RT_ROM_R1_N")
	)
	(segment
		(start 286.792162 -397.973804)
		(end 288.595816 -397.973804)
		(width 0.11684)
		(layer "In13.Cu")
		(net "RST_SMB_RT_ROM_R1_N")
	)
	(segment
		(start 285.047182 -391.024364)
		(end 285.047182 -396.228824)
		(width 0.11684)
		(layer "In13.Cu")
		(net "RST_SMB_RT_ROM_R1_N")
	)
	(segment
		(start 268.214856 -365.311944)
		(end 269.255494 -366.352582)
		(width 0.11684)
		(layer "In13.Cu")
		(net "RST_SMB_RT_ROM_R1_N")
	)
	(segment
		(start 268.214856 -362.829856)
		(end 268.214856 -365.311944)
		(width 0.11684)
		(layer "In13.Cu")
		(net "RST_SMB_RT_ROM_R1_N")
	)
	(via
		(at 242.664488 -333.121)
		(size 0.6604)
		(drill 0.3302)
		(layers "F.Cu" "B.Cu")
		(net "RST_SMB_RT_ROM_N")
	)
	(segment
		(start 242.156488 -332.613)
		(end 242.664488 -333.121)
		(width 0.10668)
		(layer "B.Cu")
		(net "RST_SMB_RT_ROM_N")
	)
	(segment
		(start 242.664488 -333.891128)
		(end 242.664488 -333.121)
		(width 0.10668)
		(layer "B.Cu")
		(net "RST_SMB_RT_ROM_N")
	)
	(segment
		(start 241.407188 -332.613)
		(end 242.156488 -332.613)
		(width 0.10668)
		(layer "B.Cu")
		(net "RST_SMB_RT_ROM_N")
	)
	(segment
		(start 243.344446 -334.571086)
		(end 242.664488 -333.891128)
		(width 0.10668)
		(layer "B.Cu")
		(net "RST_SMB_RT_ROM_N")
	)
	(segment
		(start 244.464586 -334.571086)
		(end 243.344446 -334.571086)
		(width 0.10668)
		(layer "B.Cu")
		(net "RST_SMB_RT_ROM_N")
	)
	(segment
		(start 192.322196 -121.852944)
		(end 192.712086 -122.242834)
		(width 0.10668)
		(layer "F.Cu")
		(net "RST_SMB_RT_R2_N")
	)
	(segment
		(start 200.075292 -121.795794)
		(end 199.75576 -122.115326)
		(width 0.10668)
		(layer "F.Cu")
		(net "RST_SMB_RT_R2_N")
	)
	(segment
		(start 200.737216 -121.795794)
		(end 200.075292 -121.795794)
		(width 0.10668)
		(layer "F.Cu")
		(net "RST_SMB_RT_R2_N")
	)
	(via
		(at 192.712086 -122.242834)
		(size 0.4572)
		(drill 0.254)
		(layers "F.Cu" "B.Cu")
		(net "RST_SMB_RT_R2_N")
	)
	(via
		(at 199.75576 -122.115326)
		(size 0.508)
		(drill 0.254)
		(layers "F.Cu" "B.Cu")
		(net "RST_SMB_RT_R2_N")
	)
	(segment
		(start 196.862954 -125.984762)
		(end 196.862954 -122.8979)
		(width 0.11684)
		(layer "In6.Cu")
		(net "RST_SMB_RT_R2_N")
	)
	(segment
		(start 196.862954 -122.8979)
		(end 197.49008 -122.270774)
		(width 0.11684)
		(layer "In6.Cu")
		(net "RST_SMB_RT_R2_N")
	)
	(segment
		(start 192.712086 -122.242834)
		(end 192.712086 -122.998484)
		(width 0.11684)
		(layer "In6.Cu")
		(net "RST_SMB_RT_R2_N")
	)
	(segment
		(start 197.49008 -122.270774)
		(end 199.380348 -122.270774)
		(width 0.11684)
		(layer "In6.Cu")
		(net "RST_SMB_RT_R2_N")
	)
	(segment
		(start 196.529452 -126.318264)
		(end 196.862954 -125.984762)
		(width 0.11684)
		(layer "In6.Cu")
		(net "RST_SMB_RT_R2_N")
	)
	(segment
		(start 199.380348 -122.270774)
		(end 199.75576 -122.115326)
		(width 0.11684)
		(layer "In6.Cu")
		(net "RST_SMB_RT_R2_N")
	)
	(segment
		(start 192.712086 -122.998484)
		(end 196.031866 -126.318264)
		(width 0.11684)
		(layer "In6.Cu")
		(net "RST_SMB_RT_R2_N")
	)
	(segment
		(start 196.031866 -126.318264)
		(end 196.529452 -126.318264)
		(width 0.11684)
		(layer "In6.Cu")
		(net "RST_SMB_RT_R2_N")
	)
	(segment
		(start 260.478524 -328.547476)
		(end 260.478524 -225.983038)
		(width 0.10668)
		(layer "F.Cu")
		(net "RST_SMB_RT_R1_N")
	)
	(segment
		(start 260.478524 -225.983038)
		(end 247.39854 -212.903054)
		(width 0.10668)
		(layer "F.Cu")
		(net "RST_SMB_RT_R1_N")
	)
	(segment
		(start 209.505804 -122.4915)
		(end 209.923888 -122.909584)
		(width 0.10668)
		(layer "F.Cu")
		(net "RST_SMB_RT_R1_N")
	)
	(segment
		(start 243.699538 -169.247058)
		(end 243.407946 -168.955466)
		(width 0.10668)
		(layer "F.Cu")
		(net "RST_SMB_RT_R1_N")
	)
	(segment
		(start 203.357988 -122.215148)
		(end 203.63434 -122.4915)
		(width 0.10668)
		(layer "F.Cu")
		(net "RST_SMB_RT_R1_N")
	)
	(segment
		(start 247.39854 -189.849252)
		(end 243.699538 -180.918866)
		(width 0.10668)
		(layer "F.Cu")
		(net "RST_SMB_RT_R1_N")
	)
	(segment
		(start 203.63434 -122.4915)
		(end 209.505804 -122.4915)
		(width 0.10668)
		(layer "F.Cu")
		(net "RST_SMB_RT_R1_N")
	)
	(segment
		(start 258.064 -330.962)
		(end 260.478524 -328.547476)
		(width 0.10668)
		(layer "F.Cu")
		(net "RST_SMB_RT_R1_N")
	)
	(segment
		(start 243.699538 -180.918866)
		(end 243.699538 -169.247058)
		(width 0.10668)
		(layer "F.Cu")
		(net "RST_SMB_RT_R1_N")
	)
	(segment
		(start 243.407946 -168.955466)
		(end 243.407946 -167.611044)
		(width 0.10668)
		(layer "F.Cu")
		(net "RST_SMB_RT_R1_N")
	)
	(segment
		(start 201.537316 -121.795794)
		(end 201.95667 -122.215148)
		(width 0.10668)
		(layer "F.Cu")
		(net "RST_SMB_RT_R1_N")
	)
	(segment
		(start 247.39854 -212.903054)
		(end 247.39854 -189.849252)
		(width 0.10668)
		(layer "F.Cu")
		(net "RST_SMB_RT_R1_N")
	)
	(segment
		(start 201.95667 -122.215148)
		(end 203.357988 -122.215148)
		(width 0.10668)
		(layer "F.Cu")
		(net "RST_SMB_RT_R1_N")
	)
	(via
		(at 216.073736 -332.74)
		(size 0.508)
		(drill 0.254)
		(layers "F.Cu" "B.Cu")
		(net "RST_SMB_RT_R1_N")
	)
	(via
		(at 258.064 -330.962)
		(size 0.508)
		(drill 0.254)
		(layers "F.Cu" "B.Cu")
		(net "RST_SMB_RT_R1_N")
	)
	(via
		(at 243.407946 -167.611044)
		(size 0.508)
		(drill 0.254)
		(layers "F.Cu" "B.Cu")
		(net "RST_SMB_RT_R1_N")
	)
	(via
		(at 209.923888 -122.909584)
		(size 0.508)
		(drill 0.254)
		(layers "F.Cu" "B.Cu")
		(net "RST_SMB_RT_R1_N")
	)
	(via
		(at 234.338114 -126.154434)
		(size 0.508)
		(drill 0.254)
		(layers "F.Cu" "B.Cu")
		(net "RST_SMB_RT_R1_N")
	)
	(via
		(at 246.991632 -333.389478)
		(size 0.508)
		(drill 0.254)
		(layers "F.Cu" "B.Cu")
		(net "RST_SMB_RT_R1_N")
	)
	(segment
		(start 215.1507 -332.74)
		(end 216.073736 -332.74)
		(width 0.10668)
		(layer "B.Cu")
		(net "RST_SMB_RT_R1_N")
	)
	(segment
		(start 216.073736 -332.74)
		(end 216.9033 -332.74)
		(width 0.10668)
		(layer "B.Cu")
		(net "RST_SMB_RT_R1_N")
	)
	(segment
		(start 210.401154 -122.432318)
		(end 209.923888 -122.909584)
		(width 0.11684)
		(layer "In2.Cu")
		(net "RST_SMB_RT_R1_N")
	)
	(segment
		(start 216.268808 -329.617324)
		(end 215.42629 -330.459842)
		(width 0.11684)
		(layer "In2.Cu")
		(net "RST_SMB_RT_R1_N")
	)
	(segment
		(start 216.428828 -126.250192)
		(end 214.812626 -126.250192)
		(width 0.11684)
		(layer "In2.Cu")
		(net "RST_SMB_RT_R1_N")
	)
	(segment
		(start 233.511598 -330.756514)
		(end 228.255068 -330.756514)
		(width 0.11684)
		(layer "In2.Cu")
		(net "RST_SMB_RT_R1_N")
	)
	(segment
		(start 246.991632 -333.389478)
		(end 243.600478 -329.998324)
		(width 0.11684)
		(layer "In2.Cu")
		(net "RST_SMB_RT_R1_N")
	)
	(segment
		(start 215.42629 -332.092554)
		(end 216.073736 -332.74)
		(width 0.11684)
		(layer "In2.Cu")
		(net "RST_SMB_RT_R1_N")
	)
	(segment
		(start 234.269788 -329.998324)
		(end 233.511598 -330.756514)
		(width 0.11684)
		(layer "In2.Cu")
		(net "RST_SMB_RT_R1_N")
	)
	(segment
		(start 212.50402 -123.941586)
		(end 212.50402 -123.161044)
		(width 0.11684)
		(layer "In2.Cu")
		(net "RST_SMB_RT_R1_N")
	)
	(segment
		(start 234.338114 -126.154434)
		(end 234.296458 -126.154434)
		(width 0.11684)
		(layer "In2.Cu")
		(net "RST_SMB_RT_R1_N")
	)
	(segment
		(start 227.468176 -128.387602)
		(end 218.259914 -128.387602)
		(width 0.11684)
		(layer "In2.Cu")
		(net "RST_SMB_RT_R1_N")
	)
	(segment
		(start 243.600478 -329.998324)
		(end 234.269788 -329.998324)
		(width 0.11684)
		(layer "In2.Cu")
		(net "RST_SMB_RT_R1_N")
	)
	(segment
		(start 228.577648 -127.27813)
		(end 227.468176 -128.387602)
		(width 0.11684)
		(layer "In2.Cu")
		(net "RST_SMB_RT_R1_N")
	)
	(segment
		(start 212.50402 -123.161044)
		(end 211.775294 -122.432318)
		(width 0.11684)
		(layer "In2.Cu")
		(net "RST_SMB_RT_R1_N")
	)
	(segment
		(start 218.259914 -128.387602)
		(end 217.456766 -127.584454)
		(width 0.11684)
		(layer "In2.Cu")
		(net "RST_SMB_RT_R1_N")
	)
	(segment
		(start 233.172762 -127.27813)
		(end 228.577648 -127.27813)
		(width 0.11684)
		(layer "In2.Cu")
		(net "RST_SMB_RT_R1_N")
	)
	(segment
		(start 217.456766 -127.27813)
		(end 216.428828 -126.250192)
		(width 0.11684)
		(layer "In2.Cu")
		(net "RST_SMB_RT_R1_N")
	)
	(segment
		(start 227.115878 -329.617324)
		(end 216.268808 -329.617324)
		(width 0.11684)
		(layer "In2.Cu")
		(net "RST_SMB_RT_R1_N")
	)
	(segment
		(start 228.255068 -330.756514)
		(end 227.115878 -329.617324)
		(width 0.11684)
		(layer "In2.Cu")
		(net "RST_SMB_RT_R1_N")
	)
	(segment
		(start 217.456766 -127.584454)
		(end 217.456766 -127.27813)
		(width 0.11684)
		(layer "In2.Cu")
		(net "RST_SMB_RT_R1_N")
	)
	(segment
		(start 234.296458 -126.154434)
		(end 233.172762 -127.27813)
		(width 0.11684)
		(layer "In2.Cu")
		(net "RST_SMB_RT_R1_N")
	)
	(segment
		(start 211.775294 -122.432318)
		(end 210.401154 -122.432318)
		(width 0.11684)
		(layer "In2.Cu")
		(net "RST_SMB_RT_R1_N")
	)
	(segment
		(start 215.42629 -330.459842)
		(end 215.42629 -332.092554)
		(width 0.11684)
		(layer "In2.Cu")
		(net "RST_SMB_RT_R1_N")
	)
	(segment
		(start 214.812626 -126.250192)
		(end 212.50402 -123.941586)
		(width 0.11684)
		(layer "In2.Cu")
		(net "RST_SMB_RT_R1_N")
	)
	(segment
		(start 239.186212 -168.831768)
		(end 239.186212 -168.25214)
		(width 0.11684)
		(layer "In11.Cu")
		(net "RST_SMB_RT_R1_N")
	)
	(segment
		(start 239.717072 -169.362628)
		(end 239.186212 -168.831768)
		(width 0.11684)
		(layer "In11.Cu")
		(net "RST_SMB_RT_R1_N")
	)
	(segment
		(start 240.9444 -166.493952)
		(end 240.9444 -152.315672)
		(width 0.11684)
		(layer "In11.Cu")
		(net "RST_SMB_RT_R1_N")
	)
	(segment
		(start 243.407946 -167.611044)
		(end 241.656362 -169.362628)
		(width 0.11684)
		(layer "In11.Cu")
		(net "RST_SMB_RT_R1_N")
	)
	(segment
		(start 241.656362 -169.362628)
		(end 239.717072 -169.362628)
		(width 0.11684)
		(layer "In11.Cu")
		(net "RST_SMB_RT_R1_N")
	)
	(segment
		(start 240.9444 -152.315672)
		(end 241.826796 -151.433276)
		(width 0.11684)
		(layer "In11.Cu")
		(net "RST_SMB_RT_R1_N")
	)
	(segment
		(start 241.826796 -132.220462)
		(end 235.552488 -125.946154)
		(width 0.11684)
		(layer "In11.Cu")
		(net "RST_SMB_RT_R1_N")
	)
	(segment
		(start 239.186212 -168.25214)
		(end 240.9444 -166.493952)
		(width 0.11684)
		(layer "In11.Cu")
		(net "RST_SMB_RT_R1_N")
	)
	(segment
		(start 241.826796 -151.433276)
		(end 241.826796 -132.220462)
		(width 0.11684)
		(layer "In11.Cu")
		(net "RST_SMB_RT_R1_N")
	)
	(segment
		(start 235.552488 -125.946154)
		(end 234.546394 -125.946154)
		(width 0.11684)
		(layer "In11.Cu")
		(net "RST_SMB_RT_R1_N")
	)
	(segment
		(start 234.546394 -125.946154)
		(end 234.338114 -126.154434)
		(width 0.11684)
		(layer "In11.Cu")
		(net "RST_SMB_RT_R1_N")
	)
	(segment
		(start 250.298204 -333.389478)
		(end 246.991632 -333.389478)
		(width 0.11684)
		(layer "In13.Cu")
		(net "RST_SMB_RT_R1_N")
	)
	(segment
		(start 258.064 -330.962)
		(end 257.162808 -330.060808)
		(width 0.11684)
		(layer "In13.Cu")
		(net "RST_SMB_RT_R1_N")
	)
	(segment
		(start 257.162808 -330.060808)
		(end 253.626874 -330.060808)
		(width 0.11684)
		(layer "In13.Cu")
		(net "RST_SMB_RT_R1_N")
	)
	(segment
		(start 253.626874 -330.060808)
		(end 250.298204 -333.389478)
		(width 0.11684)
		(layer "In13.Cu")
		(net "RST_SMB_RT_R1_N")
	)
	(via
		(at 219.795598 -333.210408)
		(size 0.6604)
		(drill 0.3302)
		(layers "F.Cu" "B.Cu")
		(net "RST_SMB_RT_N")
	)
	(segment
		(start 217.4367 -332.74)
		(end 219.32519 -332.74)
		(width 0.10668)
		(layer "B.Cu")
		(net "RST_SMB_RT_N")
	)
	(segment
		(start 219.32519 -332.74)
		(end 219.795598 -333.210408)
		(width 0.10668)
		(layer "B.Cu")
		(net "RST_SMB_RT_N")
	)
	(segment
		(start 219.795598 -333.210408)
		(end 219.795598 -333.949294)
		(width 0.10668)
		(layer "B.Cu")
		(net "RST_SMB_RT_N")
	)
	(segment
		(start 220.41739 -334.571086)
		(end 221.510098 -334.571086)
		(width 0.10668)
		(layer "B.Cu")
		(net "RST_SMB_RT_N")
	)
	(segment
		(start 219.795598 -333.949294)
		(end 220.41739 -334.571086)
		(width 0.10668)
		(layer "B.Cu")
		(net "RST_SMB_RT_N")
	)
	(segment
		(start 111.003588 -390.716262)
		(end 111.003588 -392.094212)
		(width 0.10668)
		(layer "F.Cu")
		(net "RST_RT_CPU1_P3_RESET_R_N")
	)
	(segment
		(start 112.234472 -395.175232)
		(end 111.91494 -394.8557)
		(width 0.10668)
		(layer "F.Cu")
		(net "RST_RT_CPU1_P3_RESET_R_N")
	)
	(segment
		(start 111.810292 -394.433552)
		(end 110.978188 -393.601448)
		(width 0.10668)
		(layer "F.Cu")
		(net "RST_RT_CPU1_P3_RESET_R_N")
	)
	(segment
		(start 110.620302 -390.332976)
		(end 111.003588 -390.716262)
		(width 0.10668)
		(layer "F.Cu")
		(net "RST_RT_CPU1_P3_RESET_R_N")
	)
	(segment
		(start 111.003588 -392.094212)
		(end 111.184944 -392.275568)
		(width 0.10668)
		(layer "F.Cu")
		(net "RST_RT_CPU1_P3_RESET_R_N")
	)
	(segment
		(start 110.978188 -392.482324)
		(end 111.184944 -392.275568)
		(width 0.10668)
		(layer "F.Cu")
		(net "RST_RT_CPU1_P3_RESET_R_N")
	)
	(segment
		(start 183.035702 -171.96816)
		(end 196.073014 -185.005472)
		(width 0.10668)
		(layer "F.Cu")
		(net "RST_RT_CPU1_P3_RESET_R_N")
	)
	(segment
		(start 197.713854 -185.005472)
		(end 199.273922 -186.56554)
		(width 0.10668)
		(layer "F.Cu")
		(net "RST_RT_CPU1_P3_RESET_R_N")
	)
	(segment
		(start 112.53216 -395.175232)
		(end 112.234472 -395.175232)
		(width 0.10668)
		(layer "F.Cu")
		(net "RST_RT_CPU1_P3_RESET_R_N")
	)
	(segment
		(start 110.620302 -389.583676)
		(end 110.620302 -390.332976)
		(width 0.10668)
		(layer "F.Cu")
		(net "RST_RT_CPU1_P3_RESET_R_N")
	)
	(segment
		(start 196.073014 -185.005472)
		(end 197.713854 -185.005472)
		(width 0.10668)
		(layer "F.Cu")
		(net "RST_RT_CPU1_P3_RESET_R_N")
	)
	(segment
		(start 111.91494 -394.8557)
		(end 111.91494 -394.433552)
		(width 0.10668)
		(layer "F.Cu")
		(net "RST_RT_CPU1_P3_RESET_R_N")
	)
	(segment
		(start 110.978188 -393.601448)
		(end 110.978188 -392.482324)
		(width 0.10668)
		(layer "F.Cu")
		(net "RST_RT_CPU1_P3_RESET_R_N")
	)
	(segment
		(start 111.91494 -394.433552)
		(end 111.810292 -394.433552)
		(width 0.10668)
		(layer "F.Cu")
		(net "RST_RT_CPU1_P3_RESET_R_N")
	)
	(via
		(at 199.273922 -186.56554)
		(size 0.508)
		(drill 0.254)
		(layers "F.Cu" "B.Cu")
		(net "RST_RT_CPU1_P3_RESET_R_N")
	)
	(via
		(at 219.456762 -220.118686)
		(size 0.508)
		(drill 0.254)
		(layers "F.Cu" "B.Cu")
		(net "RST_RT_CPU1_P3_RESET_R_N")
	)
	(via
		(at 183.035702 -171.96816)
		(size 0.508)
		(drill 0.254)
		(layers "F.Cu" "B.Cu")
		(net "RST_RT_CPU1_P3_RESET_R_N")
	)
	(via
		(at 111.184944 -392.275568)
		(size 0.508)
		(drill 0.254)
		(layers "F.Cu" "B.Cu")
		(net "RST_RT_CPU1_P3_RESET_R_N")
	)
	(via
		(at 186.07532 -136.447022)
		(size 0.508)
		(drill 0.254)
		(layers "F.Cu" "B.Cu")
		(net "RST_RT_CPU1_P3_RESET_R_N")
	)
	(segment
		(start 186.22264 -133.608064)
		(end 186.530996 -133.91642)
		(width 0.10668)
		(layer "B.Cu")
		(net "RST_RT_CPU1_P3_RESET_R_N")
	)
	(segment
		(start 186.060334 -136.432036)
		(end 186.07532 -136.447022)
		(width 0.10668)
		(layer "B.Cu")
		(net "RST_RT_CPU1_P3_RESET_R_N")
	)
	(segment
		(start 186.530996 -133.91642)
		(end 186.530996 -135.781542)
		(width 0.10668)
		(layer "B.Cu")
		(net "RST_RT_CPU1_P3_RESET_R_N")
	)
	(segment
		(start 186.060334 -136.252204)
		(end 186.060334 -136.432036)
		(width 0.10668)
		(layer "B.Cu")
		(net "RST_RT_CPU1_P3_RESET_R_N")
	)
	(segment
		(start 199.273922 -186.122056)
		(end 199.273922 -186.56554)
		(width 0.10668)
		(layer "B.Cu")
		(net "RST_RT_CPU1_P3_RESET_R_N")
	)
	(segment
		(start 214.588344 -191.313816)
		(end 208.134712 -184.860184)
		(width 0.10668)
		(layer "B.Cu")
		(net "RST_RT_CPU1_P3_RESET_R_N")
	)
	(segment
		(start 200.535794 -184.860184)
		(end 199.273922 -186.122056)
		(width 0.10668)
		(layer "B.Cu")
		(net "RST_RT_CPU1_P3_RESET_R_N")
	)
	(segment
		(start 219.456762 -220.118686)
		(end 214.588344 -215.250268)
		(width 0.10668)
		(layer "B.Cu")
		(net "RST_RT_CPU1_P3_RESET_R_N")
	)
	(segment
		(start 208.134712 -184.860184)
		(end 200.535794 -184.860184)
		(width 0.10668)
		(layer "B.Cu")
		(net "RST_RT_CPU1_P3_RESET_R_N")
	)
	(segment
		(start 186.530996 -135.781542)
		(end 186.060334 -136.252204)
		(width 0.10668)
		(layer "B.Cu")
		(net "RST_RT_CPU1_P3_RESET_R_N")
	)
	(segment
		(start 214.588344 -215.250268)
		(end 214.588344 -191.313816)
		(width 0.10668)
		(layer "B.Cu")
		(net "RST_RT_CPU1_P3_RESET_R_N")
	)
	(segment
		(start 172.303186 -392.578082)
		(end 172.025056 -392.578082)
		(width 0.11684)
		(layer "In2.Cu")
		(net "RST_RT_CPU1_P3_RESET_R_N")
	)
	(segment
		(start 169.507916 -395.095222)
		(end 168.439084 -395.095222)
		(width 0.11684)
		(layer "In2.Cu")
		(net "RST_RT_CPU1_P3_RESET_R_N")
	)
	(segment
		(start 112.203992 -394.816838)
		(end 110.96752 -393.580366)
		(width 0.11684)
		(layer "In2.Cu")
		(net "RST_RT_CPU1_P3_RESET_R_N")
	)
	(segment
		(start 215.931242 -351.144078)
		(end 192.578228 -374.497092)
		(width 0.11684)
		(layer "In2.Cu")
		(net "RST_RT_CPU1_P3_RESET_R_N")
	)
	(segment
		(start 189.859158 -374.497092)
		(end 185.86704 -378.48921)
		(width 0.11684)
		(layer "In2.Cu")
		(net "RST_RT_CPU1_P3_RESET_R_N")
	)
	(segment
		(start 192.578228 -374.497092)
		(end 189.859158 -374.497092)
		(width 0.11684)
		(layer "In2.Cu")
		(net "RST_RT_CPU1_P3_RESET_R_N")
	)
	(segment
		(start 213.05139 -330.135484)
		(end 213.05139 -332.917292)
		(width 0.11684)
		(layer "In2.Cu")
		(net "RST_RT_CPU1_P3_RESET_R_N")
	)
	(segment
		(start 168.439084 -395.095222)
		(end 168.023794 -394.679932)
		(width 0.11684)
		(layer "In2.Cu")
		(net "RST_RT_CPU1_P3_RESET_R_N")
	)
	(segment
		(start 215.931242 -335.797144)
		(end 215.931242 -351.144078)
		(width 0.11684)
		(layer "In2.Cu")
		(net "RST_RT_CPU1_P3_RESET_R_N")
	)
	(segment
		(start 166.662862 -394.657072)
		(end 166.081456 -395.238478)
		(width 0.11684)
		(layer "In2.Cu")
		(net "RST_RT_CPU1_P3_RESET_R_N")
	)
	(segment
		(start 110.96752 -393.580366)
		(end 110.96752 -392.492992)
		(width 0.11684)
		(layer "In2.Cu")
		(net "RST_RT_CPU1_P3_RESET_R_N")
	)
	(segment
		(start 213.70163 -321.684904)
		(end 213.70163 -329.485244)
		(width 0.11684)
		(layer "In2.Cu")
		(net "RST_RT_CPU1_P3_RESET_R_N")
	)
	(segment
		(start 172.025056 -392.578082)
		(end 169.507916 -395.095222)
		(width 0.11684)
		(layer "In2.Cu")
		(net "RST_RT_CPU1_P3_RESET_R_N")
	)
	(segment
		(start 219.456762 -220.118686)
		(end 217.194892 -222.380556)
		(width 0.11684)
		(layer "In2.Cu")
		(net "RST_RT_CPU1_P3_RESET_R_N")
	)
	(segment
		(start 134.470648 -394.816838)
		(end 112.203992 -394.816838)
		(width 0.11684)
		(layer "In2.Cu")
		(net "RST_RT_CPU1_P3_RESET_R_N")
	)
	(segment
		(start 213.70163 -329.485244)
		(end 213.05139 -330.135484)
		(width 0.11684)
		(layer "In2.Cu")
		(net "RST_RT_CPU1_P3_RESET_R_N")
	)
	(segment
		(start 134.892288 -395.238478)
		(end 134.470648 -394.816838)
		(width 0.11684)
		(layer "In2.Cu")
		(net "RST_RT_CPU1_P3_RESET_R_N")
	)
	(segment
		(start 167.317674 -394.525754)
		(end 166.980108 -394.525754)
		(width 0.11684)
		(layer "In2.Cu")
		(net "RST_RT_CPU1_P3_RESET_R_N")
	)
	(segment
		(start 180.372004 -384.509264)
		(end 172.303186 -392.578082)
		(width 0.11684)
		(layer "In2.Cu")
		(net "RST_RT_CPU1_P3_RESET_R_N")
	)
	(segment
		(start 166.081456 -395.238478)
		(end 134.892288 -395.238478)
		(width 0.11684)
		(layer "In2.Cu")
		(net "RST_RT_CPU1_P3_RESET_R_N")
	)
	(segment
		(start 217.194892 -222.380556)
		(end 217.194892 -293.27094)
		(width 0.11684)
		(layer "In2.Cu")
		(net "RST_RT_CPU1_P3_RESET_R_N")
	)
	(segment
		(start 181.218332 -384.509264)
		(end 180.372004 -384.509264)
		(width 0.11684)
		(layer "In2.Cu")
		(net "RST_RT_CPU1_P3_RESET_R_N")
	)
	(segment
		(start 185.86704 -379.860556)
		(end 181.218332 -384.509264)
		(width 0.11684)
		(layer "In2.Cu")
		(net "RST_RT_CPU1_P3_RESET_R_N")
	)
	(segment
		(start 213.05139 -332.917292)
		(end 215.931242 -335.797144)
		(width 0.11684)
		(layer "In2.Cu")
		(net "RST_RT_CPU1_P3_RESET_R_N")
	)
	(segment
		(start 220.156532 -315.230002)
		(end 213.70163 -321.684904)
		(width 0.11684)
		(layer "In2.Cu")
		(net "RST_RT_CPU1_P3_RESET_R_N")
	)
	(segment
		(start 110.96752 -392.492992)
		(end 111.184944 -392.275568)
		(width 0.11684)
		(layer "In2.Cu")
		(net "RST_RT_CPU1_P3_RESET_R_N")
	)
	(segment
		(start 166.980108 -394.525754)
		(end 166.662862 -394.657072)
		(width 0.11684)
		(layer "In2.Cu")
		(net "RST_RT_CPU1_P3_RESET_R_N")
	)
	(segment
		(start 220.156532 -296.23258)
		(end 220.156532 -315.230002)
		(width 0.11684)
		(layer "In2.Cu")
		(net "RST_RT_CPU1_P3_RESET_R_N")
	)
	(segment
		(start 217.194892 -293.27094)
		(end 220.156532 -296.23258)
		(width 0.11684)
		(layer "In2.Cu")
		(net "RST_RT_CPU1_P3_RESET_R_N")
	)
	(segment
		(start 168.023794 -394.679932)
		(end 167.471852 -394.679932)
		(width 0.11684)
		(layer "In2.Cu")
		(net "RST_RT_CPU1_P3_RESET_R_N")
	)
	(segment
		(start 185.86704 -378.48921)
		(end 185.86704 -379.860556)
		(width 0.11684)
		(layer "In2.Cu")
		(net "RST_RT_CPU1_P3_RESET_R_N")
	)
	(segment
		(start 167.471852 -394.679932)
		(end 167.317674 -394.525754)
		(width 0.11684)
		(layer "In2.Cu")
		(net "RST_RT_CPU1_P3_RESET_R_N")
	)
	(segment
		(start 183.904382 -171.09948)
		(end 184.25287 -171.09948)
		(width 0.11684)
		(layer "In11.Cu")
		(net "RST_RT_CPU1_P3_RESET_R_N")
	)
	(segment
		(start 186.299094 -163.355528)
		(end 185.284364 -162.340798)
		(width 0.11684)
		(layer "In11.Cu")
		(net "RST_RT_CPU1_P3_RESET_R_N")
	)
	(segment
		(start 185.545984 -138.055858)
		(end 186.039506 -137.562336)
		(width 0.11684)
		(layer "In11.Cu")
		(net "RST_RT_CPU1_P3_RESET_R_N")
	)
	(segment
		(start 186.104022 -155.534614)
		(end 186.104022 -140.090652)
		(width 0.11684)
		(layer "In11.Cu")
		(net "RST_RT_CPU1_P3_RESET_R_N")
	)
	(segment
		(start 186.039506 -137.562336)
		(end 186.039506 -136.482836)
		(width 0.11684)
		(layer "In11.Cu")
		(net "RST_RT_CPU1_P3_RESET_R_N")
	)
	(segment
		(start 186.039506 -136.482836)
		(end 186.07532 -136.447022)
		(width 0.11684)
		(layer "In11.Cu")
		(net "RST_RT_CPU1_P3_RESET_R_N")
	)
	(segment
		(start 185.545984 -139.532614)
		(end 185.545984 -138.055858)
		(width 0.11684)
		(layer "In11.Cu")
		(net "RST_RT_CPU1_P3_RESET_R_N")
	)
	(segment
		(start 186.299094 -169.053256)
		(end 186.299094 -163.355528)
		(width 0.11684)
		(layer "In11.Cu")
		(net "RST_RT_CPU1_P3_RESET_R_N")
	)
	(segment
		(start 183.035702 -171.96816)
		(end 183.904382 -171.09948)
		(width 0.11684)
		(layer "In11.Cu")
		(net "RST_RT_CPU1_P3_RESET_R_N")
	)
	(segment
		(start 186.104022 -140.090652)
		(end 185.545984 -139.532614)
		(width 0.11684)
		(layer "In11.Cu")
		(net "RST_RT_CPU1_P3_RESET_R_N")
	)
	(segment
		(start 184.25287 -171.09948)
		(end 186.299094 -169.053256)
		(width 0.11684)
		(layer "In11.Cu")
		(net "RST_RT_CPU1_P3_RESET_R_N")
	)
	(segment
		(start 185.284364 -156.354272)
		(end 186.104022 -155.534614)
		(width 0.11684)
		(layer "In11.Cu")
		(net "RST_RT_CPU1_P3_RESET_R_N")
	)
	(segment
		(start 185.284364 -162.340798)
		(end 185.284364 -156.354272)
		(width 0.11684)
		(layer "In11.Cu")
		(net "RST_RT_CPU1_P3_RESET_R_N")
	)
	(segment
		(start 185.122058 -121.852944)
		(end 184.732168 -122.242834)
		(width 0.10668)
		(layer "F.Cu")
		(net "RST_RT_CPU1_P3_RESET_R2_N")
	)
	(via
		(at 185.06694 -129.661666)
		(size 0.6604)
		(drill 0.3302)
		(layers "F.Cu" "B.Cu")
		(net "RST_RT_CPU1_P3_RESET_R2_N")
	)
	(via
		(at 184.732168 -122.242834)
		(size 0.4572)
		(drill 0.254)
		(layers "F.Cu" "B.Cu")
		(net "RST_RT_CPU1_P3_RESET_R2_N")
	)
	(segment
		(start 185.77179 -132.147564)
		(end 185.77179 -131.181094)
		(width 0.10668)
		(layer "B.Cu")
		(net "RST_RT_CPU1_P3_RESET_R2_N")
	)
	(segment
		(start 186.22264 -132.807964)
		(end 185.919872 -132.505196)
		(width 0.10668)
		(layer "B.Cu")
		(net "RST_RT_CPU1_P3_RESET_R2_N")
	)
	(segment
		(start 185.49112 -123.203716)
		(end 185.49112 -128.124966)
		(width 0.10668)
		(layer "B.Cu")
		(net "RST_RT_CPU1_P3_RESET_R2_N")
	)
	(segment
		(start 184.732168 -122.242834)
		(end 184.732168 -122.444764)
		(width 0.10668)
		(layer "B.Cu")
		(net "RST_RT_CPU1_P3_RESET_R2_N")
	)
	(segment
		(start 185.77179 -131.181094)
		(end 185.566304 -130.975608)
		(width 0.10668)
		(layer "B.Cu")
		(net "RST_RT_CPU1_P3_RESET_R2_N")
	)
	(segment
		(start 185.919872 -132.505196)
		(end 185.77179 -132.147564)
		(width 0.10668)
		(layer "B.Cu")
		(net "RST_RT_CPU1_P3_RESET_R2_N")
	)
	(segment
		(start 185.481468 -129.247138)
		(end 185.06694 -129.661666)
		(width 0.10668)
		(layer "B.Cu")
		(net "RST_RT_CPU1_P3_RESET_R2_N")
	)
	(segment
		(start 184.732168 -122.444764)
		(end 185.49112 -123.203716)
		(width 0.10668)
		(layer "B.Cu")
		(net "RST_RT_CPU1_P3_RESET_R2_N")
	)
	(segment
		(start 185.566304 -130.975608)
		(end 185.566304 -130.16103)
		(width 0.10668)
		(layer "B.Cu")
		(net "RST_RT_CPU1_P3_RESET_R2_N")
	)
	(segment
		(start 185.481468 -128.134618)
		(end 185.481468 -129.247138)
		(width 0.10668)
		(layer "B.Cu")
		(net "RST_RT_CPU1_P3_RESET_R2_N")
	)
	(segment
		(start 185.566304 -130.16103)
		(end 185.06694 -129.661666)
		(width 0.10668)
		(layer "B.Cu")
		(net "RST_RT_CPU1_P3_RESET_R2_N")
	)
	(segment
		(start 185.49112 -128.124966)
		(end 185.481468 -128.134618)
		(width 0.10668)
		(layer "B.Cu")
		(net "RST_RT_CPU1_P3_RESET_R2_N")
	)
	(segment
		(start 111.494824 -388.730998)
		(end 111.175546 -389.050276)
		(width 0.10668)
		(layer "F.Cu")
		(net "RST_RT_CPU1_P3_RESET_N")
	)
	(segment
		(start 108.402628 -389.578342)
		(end 107.926124 -389.101838)
		(width 0.10668)
		(layer "F.Cu")
		(net "RST_RT_CPU1_P3_RESET_N")
	)
	(segment
		(start 109.075728 -389.578342)
		(end 108.402628 -389.578342)
		(width 0.10668)
		(layer "F.Cu")
		(net "RST_RT_CPU1_P3_RESET_N")
	)
	(segment
		(start 113.201704 -388.730998)
		(end 111.494824 -388.730998)
		(width 0.10668)
		(layer "F.Cu")
		(net "RST_RT_CPU1_P3_RESET_N")
	)
	(segment
		(start 110.620302 -389.050276)
		(end 109.603794 -389.050276)
		(width 0.10668)
		(layer "F.Cu")
		(net "RST_RT_CPU1_P3_RESET_N")
	)
	(segment
		(start 111.175546 -389.050276)
		(end 110.620302 -389.050276)
		(width 0.10668)
		(layer "F.Cu")
		(net "RST_RT_CPU1_P3_RESET_N")
	)
	(segment
		(start 107.926124 -389.101838)
		(end 107.926124 -388.480808)
		(width 0.10668)
		(layer "F.Cu")
		(net "RST_RT_CPU1_P3_RESET_N")
	)
	(segment
		(start 107.926124 -388.480808)
		(end 107.298998 -387.853682)
		(width 0.10668)
		(layer "F.Cu")
		(net "RST_RT_CPU1_P3_RESET_N")
	)
	(segment
		(start 109.603794 -389.050276)
		(end 109.075728 -389.578342)
		(width 0.10668)
		(layer "F.Cu")
		(net "RST_RT_CPU1_P3_RESET_N")
	)
	(via
		(at 107.298998 -387.853682)
		(size 0.762)
		(drill 0.381)
		(layers "F.Cu" "B.Cu")
		(net "RST_RT_CPU1_P3_RESET_N")
	)
	(segment
		(start 135.268462 -395.3637)
		(end 135.268462 -394.866622)
		(width 0.10668)
		(layer "F.Cu")
		(net "RST_RT_CPU1_P3_PERST_R_N")
	)
	(segment
		(start 135.268462 -394.866622)
		(end 135.02132 -394.61948)
		(width 0.10668)
		(layer "F.Cu")
		(net "RST_RT_CPU1_P3_PERST_R_N")
	)
	(segment
		(start 135.318754 -394.61948)
		(end 135.02132 -394.61948)
		(width 0.10668)
		(layer "F.Cu")
		(net "RST_RT_CPU1_P3_PERST_R_N")
	)
	(segment
		(start 135.51408 -394.424154)
		(end 135.318754 -394.61948)
		(width 0.10668)
		(layer "F.Cu")
		(net "RST_RT_CPU1_P3_PERST_R_N")
	)
	(segment
		(start 134.960106 -392.806174)
		(end 135.51408 -393.360148)
		(width 0.10668)
		(layer "F.Cu")
		(net "RST_RT_CPU1_P3_PERST_R_N")
	)
	(segment
		(start 183.023002 -172.691044)
		(end 194.200272 -183.868314)
		(width 0.10668)
		(layer "F.Cu")
		(net "RST_RT_CPU1_P3_PERST_R_N")
	)
	(segment
		(start 194.200272 -183.868314)
		(end 194.200272 -186.990482)
		(width 0.10668)
		(layer "F.Cu")
		(net "RST_RT_CPU1_P3_PERST_R_N")
	)
	(segment
		(start 135.51408 -393.360148)
		(end 135.51408 -394.424154)
		(width 0.10668)
		(layer "F.Cu")
		(net "RST_RT_CPU1_P3_PERST_R_N")
	)
	(via
		(at 183.023002 -172.691044)
		(size 0.508)
		(drill 0.254)
		(layers "F.Cu" "B.Cu")
		(net "RST_RT_CPU1_P3_PERST_R_N")
	)
	(via
		(at 186.06008 -138.680952)
		(size 0.508)
		(drill 0.254)
		(layers "F.Cu" "B.Cu")
		(net "RST_RT_CPU1_P3_PERST_R_N")
	)
	(via
		(at 194.200272 -186.990482)
		(size 0.508)
		(drill 0.254)
		(layers "F.Cu" "B.Cu")
		(net "RST_RT_CPU1_P3_PERST_R_N")
	)
	(via
		(at 134.960106 -392.806174)
		(size 0.508)
		(drill 0.254)
		(layers "F.Cu" "B.Cu")
		(net "RST_RT_CPU1_P3_PERST_R_N")
	)
	(via
		(at 219.482924 -219.337636)
		(size 0.508)
		(drill 0.254)
		(layers "F.Cu" "B.Cu")
		(net "RST_RT_CPU1_P3_PERST_R_N")
	)
	(segment
		(start 219.482924 -219.337636)
		(end 215.109298 -214.96401)
		(width 0.10668)
		(layer "B.Cu")
		(net "RST_RT_CPU1_P3_PERST_R_N")
	)
	(segment
		(start 194.200272 -186.218322)
		(end 194.200272 -186.990482)
		(width 0.10668)
		(layer "B.Cu")
		(net "RST_RT_CPU1_P3_PERST_R_N")
	)
	(segment
		(start 215.109298 -214.96401)
		(end 215.109298 -191.031876)
		(width 0.10668)
		(layer "B.Cu")
		(net "RST_RT_CPU1_P3_PERST_R_N")
	)
	(segment
		(start 186.06008 -137.15238)
		(end 186.53506 -136.6774)
		(width 0.10668)
		(layer "B.Cu")
		(net "RST_RT_CPU1_P3_PERST_R_N")
	)
	(segment
		(start 186.657996 -133.081268)
		(end 186.657996 -132.384038)
		(width 0.10668)
		(layer "B.Cu")
		(net "RST_RT_CPU1_P3_PERST_R_N")
	)
	(segment
		(start 186.805062 -136.066276)
		(end 187.325762 -136.066276)
		(width 0.10668)
		(layer "B.Cu")
		(net "RST_RT_CPU1_P3_PERST_R_N")
	)
	(segment
		(start 195.91909 -184.499504)
		(end 194.200272 -186.218322)
		(width 0.10668)
		(layer "B.Cu")
		(net "RST_RT_CPU1_P3_PERST_R_N")
	)
	(segment
		(start 215.109298 -191.031876)
		(end 208.576926 -184.499504)
		(width 0.10668)
		(layer "B.Cu")
		(net "RST_RT_CPU1_P3_PERST_R_N")
	)
	(segment
		(start 208.576926 -184.499504)
		(end 195.91909 -184.499504)
		(width 0.10668)
		(layer "B.Cu")
		(net "RST_RT_CPU1_P3_PERST_R_N")
	)
	(segment
		(start 186.657996 -132.384038)
		(end 186.230514 -131.956556)
		(width 0.10668)
		(layer "B.Cu")
		(net "RST_RT_CPU1_P3_PERST_R_N")
	)
	(segment
		(start 186.53506 -136.336278)
		(end 186.805062 -136.066276)
		(width 0.10668)
		(layer "B.Cu")
		(net "RST_RT_CPU1_P3_PERST_R_N")
	)
	(segment
		(start 186.53506 -136.6774)
		(end 186.53506 -136.336278)
		(width 0.10668)
		(layer "B.Cu")
		(net "RST_RT_CPU1_P3_PERST_R_N")
	)
	(segment
		(start 187.325762 -136.066276)
		(end 187.64631 -135.745728)
		(width 0.10668)
		(layer "B.Cu")
		(net "RST_RT_CPU1_P3_PERST_R_N")
	)
	(segment
		(start 186.06008 -138.680952)
		(end 186.06008 -137.15238)
		(width 0.10668)
		(layer "B.Cu")
		(net "RST_RT_CPU1_P3_PERST_R_N")
	)
	(segment
		(start 187.64631 -135.745728)
		(end 187.64631 -134.069582)
		(width 0.10668)
		(layer "B.Cu")
		(net "RST_RT_CPU1_P3_PERST_R_N")
	)
	(segment
		(start 187.64631 -134.069582)
		(end 186.657996 -133.081268)
		(width 0.10668)
		(layer "B.Cu")
		(net "RST_RT_CPU1_P3_PERST_R_N")
	)
	(segment
		(start 185.297318 -379.735842)
		(end 185.297318 -378.212604)
		(width 0.11684)
		(layer "In2.Cu")
		(net "RST_RT_CPU1_P3_PERST_R_N")
	)
	(segment
		(start 166.88181 -394.104114)
		(end 167.492426 -394.104114)
		(width 0.11684)
		(layer "In2.Cu")
		(net "RST_RT_CPU1_P3_PERST_R_N")
	)
	(segment
		(start 185.297318 -378.212604)
		(end 189.465204 -374.044718)
		(width 0.11684)
		(layer "In2.Cu")
		(net "RST_RT_CPU1_P3_PERST_R_N")
	)
	(segment
		(start 169.411142 -393.46886)
		(end 170.487848 -393.46886)
		(width 0.11684)
		(layer "In2.Cu")
		(net "RST_RT_CPU1_P3_PERST_R_N")
	)
	(segment
		(start 172.52823 -390.45261)
		(end 173.832266 -390.45261)
		(width 0.11684)
		(layer "In2.Cu")
		(net "RST_RT_CPU1_P3_PERST_R_N")
	)
	(segment
		(start 168.633902 -394.2461)
		(end 169.411142 -393.46886)
		(width 0.11684)
		(layer "In2.Cu")
		(net "RST_RT_CPU1_P3_PERST_R_N")
	)
	(segment
		(start 216.70391 -293.474394)
		(end 216.70391 -222.11665)
		(width 0.11684)
		(layer "In2.Cu")
		(net "RST_RT_CPU1_P3_PERST_R_N")
	)
	(segment
		(start 172.144436 -391.812272)
		(end 172.144436 -390.836404)
		(width 0.11684)
		(layer "In2.Cu")
		(net "RST_RT_CPU1_P3_PERST_R_N")
	)
	(segment
		(start 181.014878 -384.018282)
		(end 185.297318 -379.735842)
		(width 0.11684)
		(layer "In2.Cu")
		(net "RST_RT_CPU1_P3_PERST_R_N")
	)
	(segment
		(start 212.59038 -329.853036)
		(end 213.213696 -329.22972)
		(width 0.11684)
		(layer "In2.Cu")
		(net "RST_RT_CPU1_P3_PERST_R_N")
	)
	(segment
		(start 172.144436 -390.836404)
		(end 172.52823 -390.45261)
		(width 0.11684)
		(layer "In2.Cu")
		(net "RST_RT_CPU1_P3_PERST_R_N")
	)
	(segment
		(start 166.4335 -394.289788)
		(end 166.88181 -394.104114)
		(width 0.11684)
		(layer "In2.Cu")
		(net "RST_RT_CPU1_P3_PERST_R_N")
	)
	(segment
		(start 216.70391 -222.11665)
		(end 219.482924 -219.337636)
		(width 0.11684)
		(layer "In2.Cu")
		(net "RST_RT_CPU1_P3_PERST_R_N")
	)
	(segment
		(start 192.43421 -374.044718)
		(end 215.352376 -351.126552)
		(width 0.11684)
		(layer "In2.Cu")
		(net "RST_RT_CPU1_P3_PERST_R_N")
	)
	(segment
		(start 213.213696 -329.22972)
		(end 213.213696 -321.4497)
		(width 0.11684)
		(layer "In2.Cu")
		(net "RST_RT_CPU1_P3_PERST_R_N")
	)
	(segment
		(start 135.35787 -394.816838)
		(end 165.90645 -394.816838)
		(width 0.11684)
		(layer "In2.Cu")
		(net "RST_RT_CPU1_P3_PERST_R_N")
	)
	(segment
		(start 134.82574 -392.94054)
		(end 134.82574 -394.284708)
		(width 0.11684)
		(layer "In2.Cu")
		(net "RST_RT_CPU1_P3_PERST_R_N")
	)
	(segment
		(start 213.213696 -321.4497)
		(end 219.712032 -314.951364)
		(width 0.11684)
		(layer "In2.Cu")
		(net "RST_RT_CPU1_P3_PERST_R_N")
	)
	(segment
		(start 180.266594 -384.018282)
		(end 181.014878 -384.018282)
		(width 0.11684)
		(layer "In2.Cu")
		(net "RST_RT_CPU1_P3_PERST_R_N")
	)
	(segment
		(start 167.634412 -394.2461)
		(end 168.633902 -394.2461)
		(width 0.11684)
		(layer "In2.Cu")
		(net "RST_RT_CPU1_P3_PERST_R_N")
	)
	(segment
		(start 170.487848 -393.46886)
		(end 172.144436 -391.812272)
		(width 0.11684)
		(layer "In2.Cu")
		(net "RST_RT_CPU1_P3_PERST_R_N")
	)
	(segment
		(start 189.465204 -374.044718)
		(end 192.43421 -374.044718)
		(width 0.11684)
		(layer "In2.Cu")
		(net "RST_RT_CPU1_P3_PERST_R_N")
	)
	(segment
		(start 219.712032 -314.951364)
		(end 219.712032 -296.482516)
		(width 0.11684)
		(layer "In2.Cu")
		(net "RST_RT_CPU1_P3_PERST_R_N")
	)
	(segment
		(start 219.712032 -296.482516)
		(end 216.70391 -293.474394)
		(width 0.11684)
		(layer "In2.Cu")
		(net "RST_RT_CPU1_P3_PERST_R_N")
	)
	(segment
		(start 167.492426 -394.104114)
		(end 167.634412 -394.2461)
		(width 0.11684)
		(layer "In2.Cu")
		(net "RST_RT_CPU1_P3_PERST_R_N")
	)
	(segment
		(start 215.352376 -336.048604)
		(end 212.59038 -333.286608)
		(width 0.11684)
		(layer "In2.Cu")
		(net "RST_RT_CPU1_P3_PERST_R_N")
	)
	(segment
		(start 215.352376 -351.126552)
		(end 215.352376 -336.048604)
		(width 0.11684)
		(layer "In2.Cu")
		(net "RST_RT_CPU1_P3_PERST_R_N")
	)
	(segment
		(start 134.960106 -392.806174)
		(end 134.82574 -392.94054)
		(width 0.11684)
		(layer "In2.Cu")
		(net "RST_RT_CPU1_P3_PERST_R_N")
	)
	(segment
		(start 173.832266 -390.45261)
		(end 180.266594 -384.018282)
		(width 0.11684)
		(layer "In2.Cu")
		(net "RST_RT_CPU1_P3_PERST_R_N")
	)
	(segment
		(start 134.82574 -394.284708)
		(end 135.35787 -394.816838)
		(width 0.11684)
		(layer "In2.Cu")
		(net "RST_RT_CPU1_P3_PERST_R_N")
	)
	(segment
		(start 212.59038 -333.286608)
		(end 212.59038 -329.853036)
		(width 0.11684)
		(layer "In2.Cu")
		(net "RST_RT_CPU1_P3_PERST_R_N")
	)
	(segment
		(start 165.90645 -394.816838)
		(end 166.4335 -394.289788)
		(width 0.11684)
		(layer "In2.Cu")
		(net "RST_RT_CPU1_P3_PERST_R_N")
	)
	(segment
		(start 185.706004 -156.529024)
		(end 185.706004 -162.166046)
		(width 0.11684)
		(layer "In11.Cu")
		(net "RST_RT_CPU1_P3_PERST_R_N")
	)
	(segment
		(start 186.544712 -139.643866)
		(end 186.544712 -155.690316)
		(width 0.11684)
		(layer "In11.Cu")
		(net "RST_RT_CPU1_P3_PERST_R_N")
	)
	(segment
		(start 186.856624 -163.316666)
		(end 186.856624 -169.101262)
		(width 0.11684)
		(layer "In11.Cu")
		(net "RST_RT_CPU1_P3_PERST_R_N")
	)
	(segment
		(start 185.706004 -162.166046)
		(end 186.856624 -163.316666)
		(width 0.11684)
		(layer "In11.Cu")
		(net "RST_RT_CPU1_P3_PERST_R_N")
	)
	(segment
		(start 186.856624 -169.101262)
		(end 184.275222 -171.682664)
		(width 0.11684)
		(layer "In11.Cu")
		(net "RST_RT_CPU1_P3_PERST_R_N")
	)
	(segment
		(start 186.544712 -155.690316)
		(end 185.706004 -156.529024)
		(width 0.11684)
		(layer "In11.Cu")
		(net "RST_RT_CPU1_P3_PERST_R_N")
	)
	(segment
		(start 184.275222 -171.682664)
		(end 184.031382 -171.682664)
		(width 0.11684)
		(layer "In11.Cu")
		(net "RST_RT_CPU1_P3_PERST_R_N")
	)
	(segment
		(start 186.06008 -139.159234)
		(end 186.544712 -139.643866)
		(width 0.11684)
		(layer "In11.Cu")
		(net "RST_RT_CPU1_P3_PERST_R_N")
	)
	(segment
		(start 184.031382 -171.682664)
		(end 183.023002 -172.691044)
		(width 0.11684)
		(layer "In11.Cu")
		(net "RST_RT_CPU1_P3_PERST_R_N")
	)
	(segment
		(start 186.06008 -138.680952)
		(end 186.06008 -139.159234)
		(width 0.11684)
		(layer "In11.Cu")
		(net "RST_RT_CPU1_P3_PERST_R_N")
	)
	(segment
		(start 185.122058 -121.052844)
		(end 184.732168 -121.442734)
		(width 0.10668)
		(layer "F.Cu")
		(net "RST_RT_CPU1_P3_PERST_R2_N")
	)
	(via
		(at 184.732168 -121.442734)
		(size 0.4572)
		(drill 0.254)
		(layers "F.Cu" "B.Cu")
		(net "RST_RT_CPU1_P3_PERST_R2_N")
	)
	(via
		(at 186.08294 -128.899666)
		(size 0.6604)
		(drill 0.3302)
		(layers "F.Cu" "B.Cu")
		(net "RST_RT_CPU1_P3_PERST_R2_N")
	)
	(segment
		(start 186.521344 -130.00101)
		(end 186.08294 -129.562606)
		(width 0.10668)
		(layer "B.Cu")
		(net "RST_RT_CPU1_P3_PERST_R2_N")
	)
	(segment
		(start 185.308494 -122.578876)
		(end 185.8518 -123.122182)
		(width 0.10668)
		(layer "B.Cu")
		(net "RST_RT_CPU1_P3_PERST_R2_N")
	)
	(segment
		(start 186.08294 -129.562606)
		(end 186.08294 -128.899666)
		(width 0.10668)
		(layer "B.Cu")
		(net "RST_RT_CPU1_P3_PERST_R2_N")
	)
	(segment
		(start 186.230514 -131.156456)
		(end 186.230514 -131.131564)
		(width 0.10668)
		(layer "B.Cu")
		(net "RST_RT_CPU1_P3_PERST_R2_N")
	)
	(segment
		(start 185.8518 -123.122182)
		(end 185.8518 -128.668526)
		(width 0.10668)
		(layer "B.Cu")
		(net "RST_RT_CPU1_P3_PERST_R2_N")
	)
	(segment
		(start 186.230514 -131.131564)
		(end 186.521344 -130.840734)
		(width 0.10668)
		(layer "B.Cu")
		(net "RST_RT_CPU1_P3_PERST_R2_N")
	)
	(segment
		(start 184.732168 -121.442734)
		(end 185.308494 -122.01906)
		(width 0.10668)
		(layer "B.Cu")
		(net "RST_RT_CPU1_P3_PERST_R2_N")
	)
	(segment
		(start 186.521344 -130.840734)
		(end 186.521344 -130.00101)
		(width 0.10668)
		(layer "B.Cu")
		(net "RST_RT_CPU1_P3_PERST_R2_N")
	)
	(segment
		(start 185.8518 -128.668526)
		(end 186.08294 -128.899666)
		(width 0.10668)
		(layer "B.Cu")
		(net "RST_RT_CPU1_P3_PERST_R2_N")
	)
	(segment
		(start 185.308494 -122.01906)
		(end 185.308494 -122.578876)
		(width 0.10668)
		(layer "B.Cu")
		(net "RST_RT_CPU1_P3_PERST_R2_N")
	)
	(segment
		(start 135.28548 -392.05408)
		(end 134.099046 -392.05408)
		(width 0.10668)
		(layer "F.Cu")
		(net "RST_RT_CPU1_P3_PERST_N")
	)
	(segment
		(start 135.268462 -395.8971)
		(end 135.49122 -395.8971)
		(width 0.10668)
		(layer "F.Cu")
		(net "RST_RT_CPU1_P3_PERST_N")
	)
	(segment
		(start 135.90016 -392.66876)
		(end 135.28548 -392.05408)
		(width 0.10668)
		(layer "F.Cu")
		(net "RST_RT_CPU1_P3_PERST_N")
	)
	(segment
		(start 135.90016 -395.48816)
		(end 135.90016 -392.66876)
		(width 0.10668)
		(layer "F.Cu")
		(net "RST_RT_CPU1_P3_PERST_N")
	)
	(segment
		(start 134.69366 -395.8971)
		(end 133.1976 -397.39316)
		(width 0.10668)
		(layer "F.Cu")
		(net "RST_RT_CPU1_P3_PERST_N")
	)
	(segment
		(start 134.099046 -392.05408)
		(end 133.718046 -391.67308)
		(width 0.10668)
		(layer "F.Cu")
		(net "RST_RT_CPU1_P3_PERST_N")
	)
	(segment
		(start 133.1976 -397.39316)
		(end 132.9055 -397.39316)
		(width 0.10668)
		(layer "F.Cu")
		(net "RST_RT_CPU1_P3_PERST_N")
	)
	(segment
		(start 133.718046 -391.67308)
		(end 133.718046 -390.761474)
		(width 0.10668)
		(layer "F.Cu")
		(net "RST_RT_CPU1_P3_PERST_N")
	)
	(segment
		(start 135.49122 -395.8971)
		(end 135.90016 -395.48816)
		(width 0.10668)
		(layer "F.Cu")
		(net "RST_RT_CPU1_P3_PERST_N")
	)
	(segment
		(start 135.268462 -395.8971)
		(end 134.69366 -395.8971)
		(width 0.10668)
		(layer "F.Cu")
		(net "RST_RT_CPU1_P3_PERST_N")
	)
	(via
		(at 132.9055 -397.39316)
		(size 0.762)
		(drill 0.381)
		(layers "F.Cu" "B.Cu")
		(net "RST_RT_CPU1_P3_PERST_N")
	)
	(segment
		(start 143.350488 -395.170152)
		(end 144.315688 -395.170152)
		(width 0.10668)
		(layer "F.Cu")
		(net "RST_RT_CPU1_P2_RESET_R_N")
	)
	(segment
		(start 193.648584 -184.077356)
		(end 193.648584 -186.16041)
		(width 0.10668)
		(layer "F.Cu")
		(net "RST_RT_CPU1_P2_RESET_R_N")
	)
	(segment
		(start 144.315688 -394.433552)
		(end 144.315688 -395.170152)
		(width 0.10668)
		(layer "F.Cu")
		(net "RST_RT_CPU1_P2_RESET_R_N")
	)
	(segment
		(start 143.867124 -394.232384)
		(end 144.068292 -394.433552)
		(width 0.10668)
		(layer "F.Cu")
		(net "RST_RT_CPU1_P2_RESET_R_N")
	)
	(segment
		(start 143.867124 -392.457178)
		(end 143.867124 -394.232384)
		(width 0.10668)
		(layer "F.Cu")
		(net "RST_RT_CPU1_P2_RESET_R_N")
	)
	(segment
		(start 182.24881 -172.677582)
		(end 193.648584 -184.077356)
		(width 0.10668)
		(layer "F.Cu")
		(net "RST_RT_CPU1_P2_RESET_R_N")
	)
	(segment
		(start 144.072356 -392.251946)
		(end 143.867124 -392.457178)
		(width 0.10668)
		(layer "F.Cu")
		(net "RST_RT_CPU1_P2_RESET_R_N")
	)
	(segment
		(start 144.068292 -394.433552)
		(end 144.315688 -394.433552)
		(width 0.10668)
		(layer "F.Cu")
		(net "RST_RT_CPU1_P2_RESET_R_N")
	)
	(via
		(at 193.648584 -186.16041)
		(size 0.508)
		(drill 0.254)
		(layers "F.Cu" "B.Cu")
		(net "RST_RT_CPU1_P2_RESET_R_N")
	)
	(via
		(at 219.46108 -218.432888)
		(size 0.508)
		(drill 0.254)
		(layers "F.Cu" "B.Cu")
		(net "RST_RT_CPU1_P2_RESET_R_N")
	)
	(via
		(at 144.072356 -392.251946)
		(size 0.508)
		(drill 0.254)
		(layers "F.Cu" "B.Cu")
		(net "RST_RT_CPU1_P2_RESET_R_N")
	)
	(via
		(at 182.24881 -172.677582)
		(size 0.508)
		(drill 0.254)
		(layers "F.Cu" "B.Cu")
		(net "RST_RT_CPU1_P2_RESET_R_N")
	)
	(via
		(at 182.80634 -155.659074)
		(size 0.508)
		(drill 0.254)
		(layers "F.Cu" "B.Cu")
		(net "RST_RT_CPU1_P2_RESET_R_N")
	)
	(segment
		(start 215.847168 -191.085978)
		(end 208.900014 -184.138824)
		(width 0.10668)
		(layer "B.Cu")
		(net "RST_RT_CPU1_P2_RESET_R_N")
	)
	(segment
		(start 182.107078 -143.416274)
		(end 182.107078 -142.239746)
		(width 0.10668)
		(layer "B.Cu")
		(net "RST_RT_CPU1_P2_RESET_R_N")
	)
	(segment
		(start 183.589676 -138.173714)
		(end 182.331106 -136.915144)
		(width 0.10668)
		(layer "B.Cu")
		(net "RST_RT_CPU1_P2_RESET_R_N")
	)
	(segment
		(start 181.958488 -143.564864)
		(end 182.107078 -143.416274)
		(width 0.10668)
		(layer "B.Cu")
		(net "RST_RT_CPU1_P2_RESET_R_N")
	)
	(segment
		(start 182.936134 -140.14958)
		(end 183.120792 -140.14958)
		(width 0.10668)
		(layer "B.Cu")
		(net "RST_RT_CPU1_P2_RESET_R_N")
	)
	(segment
		(start 183.853074 -148.612098)
		(end 181.958488 -146.717512)
		(width 0.10668)
		(layer "B.Cu")
		(net "RST_RT_CPU1_P2_RESET_R_N")
	)
	(segment
		(start 215.847168 -214.818976)
		(end 215.847168 -191.085978)
		(width 0.10668)
		(layer "B.Cu")
		(net "RST_RT_CPU1_P2_RESET_R_N")
	)
	(segment
		(start 182.331106 -134.380732)
		(end 182.468774 -134.243064)
		(width 0.10668)
		(layer "B.Cu")
		(net "RST_RT_CPU1_P2_RESET_R_N")
	)
	(segment
		(start 182.331106 -136.915144)
		(end 182.331106 -134.380732)
		(width 0.10668)
		(layer "B.Cu")
		(net "RST_RT_CPU1_P2_RESET_R_N")
	)
	(segment
		(start 182.354982 -140.730732)
		(end 182.936134 -140.14958)
		(width 0.10668)
		(layer "B.Cu")
		(net "RST_RT_CPU1_P2_RESET_R_N")
	)
	(segment
		(start 183.589676 -139.680696)
		(end 183.589676 -138.173714)
		(width 0.10668)
		(layer "B.Cu")
		(net "RST_RT_CPU1_P2_RESET_R_N")
	)
	(segment
		(start 182.80634 -155.659074)
		(end 183.853074 -154.61234)
		(width 0.10668)
		(layer "B.Cu")
		(net "RST_RT_CPU1_P2_RESET_R_N")
	)
	(segment
		(start 181.958488 -146.717512)
		(end 181.958488 -143.564864)
		(width 0.10668)
		(layer "B.Cu")
		(net "RST_RT_CPU1_P2_RESET_R_N")
	)
	(segment
		(start 182.354982 -141.991842)
		(end 182.354982 -140.730732)
		(width 0.10668)
		(layer "B.Cu")
		(net "RST_RT_CPU1_P2_RESET_R_N")
	)
	(segment
		(start 208.900014 -184.138824)
		(end 195.67017 -184.138824)
		(width 0.10668)
		(layer "B.Cu")
		(net "RST_RT_CPU1_P2_RESET_R_N")
	)
	(segment
		(start 219.46108 -218.432888)
		(end 215.847168 -214.818976)
		(width 0.10668)
		(layer "B.Cu")
		(net "RST_RT_CPU1_P2_RESET_R_N")
	)
	(segment
		(start 183.853074 -154.61234)
		(end 183.853074 -148.612098)
		(width 0.10668)
		(layer "B.Cu")
		(net "RST_RT_CPU1_P2_RESET_R_N")
	)
	(segment
		(start 182.107078 -142.239746)
		(end 182.354982 -141.991842)
		(width 0.10668)
		(layer "B.Cu")
		(net "RST_RT_CPU1_P2_RESET_R_N")
	)
	(segment
		(start 183.120792 -140.14958)
		(end 183.589676 -139.680696)
		(width 0.10668)
		(layer "B.Cu")
		(net "RST_RT_CPU1_P2_RESET_R_N")
	)
	(segment
		(start 195.67017 -184.138824)
		(end 193.648584 -186.16041)
		(width 0.10668)
		(layer "B.Cu")
		(net "RST_RT_CPU1_P2_RESET_R_N")
	)
	(segment
		(start 166.12489 -393.958572)
		(end 166.791386 -393.682474)
		(width 0.11684)
		(layer "In2.Cu")
		(net "RST_RT_CPU1_P2_RESET_R_N")
	)
	(segment
		(start 192.298574 -373.583962)
		(end 214.85479 -351.027746)
		(width 0.11684)
		(layer "In2.Cu")
		(net "RST_RT_CPU1_P2_RESET_R_N")
	)
	(segment
		(start 214.85479 -336.214212)
		(end 211.70773 -333.067152)
		(width 0.11684)
		(layer "In2.Cu")
		(net "RST_RT_CPU1_P2_RESET_R_N")
	)
	(segment
		(start 184.811416 -377.819412)
		(end 189.046866 -373.583962)
		(width 0.11684)
		(layer "In2.Cu")
		(net "RST_RT_CPU1_P2_RESET_R_N")
	)
	(segment
		(start 212.749384 -321.085464)
		(end 219.208604 -314.626244)
		(width 0.11684)
		(layer "In2.Cu")
		(net "RST_RT_CPU1_P2_RESET_R_N")
	)
	(segment
		(start 168.439592 -393.822428)
		(end 170.01998 -392.24204)
		(width 0.11684)
		(layer "In2.Cu")
		(net "RST_RT_CPU1_P2_RESET_R_N")
	)
	(segment
		(start 214.85479 -351.027746)
		(end 214.85479 -336.214212)
		(width 0.11684)
		(layer "In2.Cu")
		(net "RST_RT_CPU1_P2_RESET_R_N")
	)
	(segment
		(start 189.046866 -373.583962)
		(end 192.298574 -373.583962)
		(width 0.11684)
		(layer "In2.Cu")
		(net "RST_RT_CPU1_P2_RESET_R_N")
	)
	(segment
		(start 180.291486 -383.396744)
		(end 180.757322 -383.396744)
		(width 0.11684)
		(layer "In2.Cu")
		(net "RST_RT_CPU1_P2_RESET_R_N")
	)
	(segment
		(start 219.208604 -314.626244)
		(end 219.208604 -296.858182)
		(width 0.11684)
		(layer "In2.Cu")
		(net "RST_RT_CPU1_P2_RESET_R_N")
	)
	(segment
		(start 170.01998 -391.800842)
		(end 170.605196 -391.215626)
		(width 0.11684)
		(layer "In2.Cu")
		(net "RST_RT_CPU1_P2_RESET_R_N")
	)
	(segment
		(start 173.773084 -389.915146)
		(end 180.291486 -383.396744)
		(width 0.11684)
		(layer "In2.Cu")
		(net "RST_RT_CPU1_P2_RESET_R_N")
	)
	(segment
		(start 211.70773 -333.067152)
		(end 211.70773 -327.90257)
		(width 0.11684)
		(layer "In2.Cu")
		(net "RST_RT_CPU1_P2_RESET_R_N")
	)
	(segment
		(start 211.70773 -327.90257)
		(end 212.749384 -326.860916)
		(width 0.11684)
		(layer "In2.Cu")
		(net "RST_RT_CPU1_P2_RESET_R_N")
	)
	(segment
		(start 146.99234 -394.343128)
		(end 165.740334 -394.343128)
		(width 0.11684)
		(layer "In2.Cu")
		(net "RST_RT_CPU1_P2_RESET_R_N")
	)
	(segment
		(start 216.082372 -293.73195)
		(end 216.082372 -221.811596)
		(width 0.11684)
		(layer "In2.Cu")
		(net "RST_RT_CPU1_P2_RESET_R_N")
	)
	(segment
		(start 216.082372 -221.811596)
		(end 219.46108 -218.432888)
		(width 0.11684)
		(layer "In2.Cu")
		(net "RST_RT_CPU1_P2_RESET_R_N")
	)
	(segment
		(start 171.103798 -391.215626)
		(end 172.404278 -389.915146)
		(width 0.11684)
		(layer "In2.Cu")
		(net "RST_RT_CPU1_P2_RESET_R_N")
	)
	(segment
		(start 144.072356 -392.251946)
		(end 144.901158 -392.251946)
		(width 0.11684)
		(layer "In2.Cu")
		(net "RST_RT_CPU1_P2_RESET_R_N")
	)
	(segment
		(start 166.791386 -393.682474)
		(end 167.667178 -393.682474)
		(width 0.11684)
		(layer "In2.Cu")
		(net "RST_RT_CPU1_P2_RESET_R_N")
	)
	(segment
		(start 170.605196 -391.215626)
		(end 171.103798 -391.215626)
		(width 0.11684)
		(layer "In2.Cu")
		(net "RST_RT_CPU1_P2_RESET_R_N")
	)
	(segment
		(start 167.807132 -393.822428)
		(end 168.439592 -393.822428)
		(width 0.11684)
		(layer "In2.Cu")
		(net "RST_RT_CPU1_P2_RESET_R_N")
	)
	(segment
		(start 170.01998 -392.24204)
		(end 170.01998 -391.800842)
		(width 0.11684)
		(layer "In2.Cu")
		(net "RST_RT_CPU1_P2_RESET_R_N")
	)
	(segment
		(start 184.811416 -379.34265)
		(end 184.811416 -377.819412)
		(width 0.11684)
		(layer "In2.Cu")
		(net "RST_RT_CPU1_P2_RESET_R_N")
	)
	(segment
		(start 144.901158 -392.251946)
		(end 146.99234 -394.343128)
		(width 0.11684)
		(layer "In2.Cu")
		(net "RST_RT_CPU1_P2_RESET_R_N")
	)
	(segment
		(start 180.757322 -383.396744)
		(end 184.811416 -379.34265)
		(width 0.11684)
		(layer "In2.Cu")
		(net "RST_RT_CPU1_P2_RESET_R_N")
	)
	(segment
		(start 172.404278 -389.915146)
		(end 173.773084 -389.915146)
		(width 0.11684)
		(layer "In2.Cu")
		(net "RST_RT_CPU1_P2_RESET_R_N")
	)
	(segment
		(start 212.749384 -326.860916)
		(end 212.749384 -321.085464)
		(width 0.11684)
		(layer "In2.Cu")
		(net "RST_RT_CPU1_P2_RESET_R_N")
	)
	(segment
		(start 219.208604 -296.858182)
		(end 216.082372 -293.73195)
		(width 0.11684)
		(layer "In2.Cu")
		(net "RST_RT_CPU1_P2_RESET_R_N")
	)
	(segment
		(start 167.667178 -393.682474)
		(end 167.807132 -393.822428)
		(width 0.11684)
		(layer "In2.Cu")
		(net "RST_RT_CPU1_P2_RESET_R_N")
	)
	(segment
		(start 165.740334 -394.343128)
		(end 166.12489 -393.958572)
		(width 0.11684)
		(layer "In2.Cu")
		(net "RST_RT_CPU1_P2_RESET_R_N")
	)
	(segment
		(start 184.40146 -159.711136)
		(end 184.40146 -163.02863)
		(width 0.11684)
		(layer "In11.Cu")
		(net "RST_RT_CPU1_P2_RESET_R_N")
	)
	(segment
		(start 182.24881 -172.051472)
		(end 182.24881 -172.677582)
		(width 0.11684)
		(layer "In11.Cu")
		(net "RST_RT_CPU1_P2_RESET_R_N")
	)
	(segment
		(start 184.178956 -170.121326)
		(end 182.24881 -172.051472)
		(width 0.11684)
		(layer "In11.Cu")
		(net "RST_RT_CPU1_P2_RESET_R_N")
	)
	(segment
		(start 184.40146 -159.281876)
		(end 184.423304 -159.30372)
		(width 0.11684)
		(layer "In11.Cu")
		(net "RST_RT_CPU1_P2_RESET_R_N")
	)
	(segment
		(start 183.800496 -163.629594)
		(end 183.800496 -166.919402)
		(width 0.11684)
		(layer "In11.Cu")
		(net "RST_RT_CPU1_P2_RESET_R_N")
	)
	(segment
		(start 183.800496 -166.919402)
		(end 184.178956 -167.297862)
		(width 0.11684)
		(layer "In11.Cu")
		(net "RST_RT_CPU1_P2_RESET_R_N")
	)
	(segment
		(start 184.178956 -167.297862)
		(end 184.178956 -170.121326)
		(width 0.11684)
		(layer "In11.Cu")
		(net "RST_RT_CPU1_P2_RESET_R_N")
	)
	(segment
		(start 182.80634 -155.659074)
		(end 184.40146 -157.254194)
		(width 0.11684)
		(layer "In11.Cu")
		(net "RST_RT_CPU1_P2_RESET_R_N")
	)
	(segment
		(start 184.423304 -159.689292)
		(end 184.40146 -159.711136)
		(width 0.11684)
		(layer "In11.Cu")
		(net "RST_RT_CPU1_P2_RESET_R_N")
	)
	(segment
		(start 184.40146 -157.254194)
		(end 184.40146 -159.281876)
		(width 0.11684)
		(layer "In11.Cu")
		(net "RST_RT_CPU1_P2_RESET_R_N")
	)
	(segment
		(start 184.423304 -159.30372)
		(end 184.423304 -159.689292)
		(width 0.11684)
		(layer "In11.Cu")
		(net "RST_RT_CPU1_P2_RESET_R_N")
	)
	(segment
		(start 184.40146 -163.02863)
		(end 183.800496 -163.629594)
		(width 0.11684)
		(layer "In11.Cu")
		(net "RST_RT_CPU1_P2_RESET_R_N")
	)
	(segment
		(start 184.322212 -121.052844)
		(end 183.932322 -121.442734)
		(width 0.10668)
		(layer "F.Cu")
		(net "RST_RT_CPU1_P2_RESET_R2_N")
	)
	(via
		(at 183.932322 -121.442734)
		(size 0.4572)
		(drill 0.254)
		(layers "F.Cu" "B.Cu")
		(net "RST_RT_CPU1_P2_RESET_R2_N")
	)
	(via
		(at 182.80888 -128.635252)
		(size 0.6604)
		(drill 0.3302)
		(layers "F.Cu" "B.Cu")
		(net "RST_RT_CPU1_P2_RESET_R2_N")
	)
	(segment
		(start 182.511446 -128.932686)
		(end 182.80888 -128.635252)
		(width 0.10668)
		(layer "B.Cu")
		(net "RST_RT_CPU1_P2_RESET_R2_N")
	)
	(segment
		(start 182.511446 -132.034534)
		(end 182.511446 -128.932686)
		(width 0.10668)
		(layer "B.Cu")
		(net "RST_RT_CPU1_P2_RESET_R2_N")
	)
	(segment
		(start 182.738776 -133.172962)
		(end 182.738776 -132.261864)
		(width 0.10668)
		(layer "B.Cu")
		(net "RST_RT_CPU1_P2_RESET_R2_N")
	)
	(segment
		(start 183.515 -125.3236)
		(end 183.515 -127.929132)
		(width 0.10668)
		(layer "B.Cu")
		(net "RST_RT_CPU1_P2_RESET_R2_N")
	)
	(segment
		(start 183.53532 -121.839736)
		(end 183.53532 -124.27712)
		(width 0.10668)
		(layer "B.Cu")
		(net "RST_RT_CPU1_P2_RESET_R2_N")
	)
	(segment
		(start 182.738776 -132.261864)
		(end 182.511446 -132.034534)
		(width 0.10668)
		(layer "B.Cu")
		(net "RST_RT_CPU1_P2_RESET_R2_N")
	)
	(segment
		(start 183.7436 -125.095)
		(end 183.515 -125.3236)
		(width 0.10668)
		(layer "B.Cu")
		(net "RST_RT_CPU1_P2_RESET_R2_N")
	)
	(segment
		(start 182.468774 -133.442964)
		(end 182.738776 -133.172962)
		(width 0.10668)
		(layer "B.Cu")
		(net "RST_RT_CPU1_P2_RESET_R2_N")
	)
	(segment
		(start 183.7436 -124.4854)
		(end 183.7436 -125.095)
		(width 0.10668)
		(layer "B.Cu")
		(net "RST_RT_CPU1_P2_RESET_R2_N")
	)
	(segment
		(start 183.515 -127.929132)
		(end 182.80888 -128.635252)
		(width 0.10668)
		(layer "B.Cu")
		(net "RST_RT_CPU1_P2_RESET_R2_N")
	)
	(segment
		(start 183.932322 -121.442734)
		(end 183.53532 -121.839736)
		(width 0.10668)
		(layer "B.Cu")
		(net "RST_RT_CPU1_P2_RESET_R2_N")
	)
	(segment
		(start 183.53532 -124.27712)
		(end 183.7436 -124.4854)
		(width 0.10668)
		(layer "B.Cu")
		(net "RST_RT_CPU1_P2_RESET_R2_N")
	)
	(segment
		(start 145.729452 -388.730998)
		(end 144.282668 -388.730998)
		(width 0.10668)
		(layer "F.Cu")
		(net "RST_RT_CPU1_P2_RESET_N")
	)
	(segment
		(start 143.490696 -393.840208)
		(end 143.350488 -393.980416)
		(width 0.10668)
		(layer "F.Cu")
		(net "RST_RT_CPU1_P2_RESET_N")
	)
	(segment
		(start 143.490696 -389.52297)
		(end 143.490696 -393.840208)
		(width 0.10668)
		(layer "F.Cu")
		(net "RST_RT_CPU1_P2_RESET_N")
	)
	(segment
		(start 143.350488 -393.980416)
		(end 143.350488 -394.636752)
		(width 0.10668)
		(layer "F.Cu")
		(net "RST_RT_CPU1_P2_RESET_N")
	)
	(segment
		(start 142.92326 -394.784326)
		(end 142.92326 -396.772638)
		(width 0.10668)
		(layer "F.Cu")
		(net "RST_RT_CPU1_P2_RESET_N")
	)
	(segment
		(start 143.350488 -394.636752)
		(end 143.070834 -394.636752)
		(width 0.10668)
		(layer "F.Cu")
		(net "RST_RT_CPU1_P2_RESET_N")
	)
	(segment
		(start 144.75968 -398.609058)
		(end 145.349722 -398.609058)
		(width 0.10668)
		(layer "F.Cu")
		(net "RST_RT_CPU1_P2_RESET_N")
	)
	(segment
		(start 143.070834 -394.636752)
		(end 142.92326 -394.784326)
		(width 0.10668)
		(layer "F.Cu")
		(net "RST_RT_CPU1_P2_RESET_N")
	)
	(segment
		(start 144.282668 -388.730998)
		(end 143.490696 -389.52297)
		(width 0.10668)
		(layer "F.Cu")
		(net "RST_RT_CPU1_P2_RESET_N")
	)
	(segment
		(start 142.92326 -396.772638)
		(end 144.75968 -398.609058)
		(width 0.10668)
		(layer "F.Cu")
		(net "RST_RT_CPU1_P2_RESET_N")
	)
	(via
		(at 145.349722 -398.609058)
		(size 0.762)
		(drill 0.381)
		(layers "F.Cu" "B.Cu")
		(net "RST_RT_CPU1_P2_RESET_N")
	)
	(segment
		(start 186.876436 -139.879578)
		(end 186.876436 -140.80617)
		(width 0.10668)
		(layer "F.Cu")
		(net "RST_RT_CPU1_P2_PERST_R_N")
	)
	(segment
		(start 183.313832 -171.485814)
		(end 184.132474 -172.304456)
		(width 0.10668)
		(layer "F.Cu")
		(net "RST_RT_CPU1_P2_PERST_R_N")
	)
	(segment
		(start 181.754272 -173.028356)
		(end 181.754272 -172.411644)
		(width 0.10668)
		(layer "F.Cu")
		(net "RST_RT_CPU1_P2_PERST_R_N")
	)
	(segment
		(start 182.680102 -171.485814)
		(end 183.313832 -171.485814)
		(width 0.10668)
		(layer "F.Cu")
		(net "RST_RT_CPU1_P2_PERST_R_N")
	)
	(segment
		(start 167.36187 -392.975084)
		(end 167.521128 -392.815826)
		(width 0.10668)
		(layer "F.Cu")
		(net "RST_RT_CPU1_P2_PERST_R_N")
	)
	(segment
		(start 189.838838 -142.109698)
		(end 192.195958 -142.109698)
		(width 0.10668)
		(layer "F.Cu")
		(net "RST_RT_CPU1_P2_PERST_R_N")
	)
	(segment
		(start 167.502078 -394.6271)
		(end 167.36187 -394.486892)
		(width 0.10668)
		(layer "F.Cu")
		(net "RST_RT_CPU1_P2_PERST_R_N")
	)
	(segment
		(start 186.876436 -140.80617)
		(end 187.480956 -141.41069)
		(width 0.10668)
		(layer "F.Cu")
		(net "RST_RT_CPU1_P2_PERST_R_N")
	)
	(segment
		(start 189.13983 -141.41069)
		(end 189.838838 -142.109698)
		(width 0.10668)
		(layer "F.Cu")
		(net "RST_RT_CPU1_P2_PERST_R_N")
	)
	(segment
		(start 167.36187 -394.486892)
		(end 167.36187 -392.975084)
		(width 0.10668)
		(layer "F.Cu")
		(net "RST_RT_CPU1_P2_PERST_R_N")
	)
	(segment
		(start 167.79621 -395.3637)
		(end 167.79621 -394.6271)
		(width 0.10668)
		(layer "F.Cu")
		(net "RST_RT_CPU1_P2_PERST_R_N")
	)
	(segment
		(start 193.14795 -184.422034)
		(end 181.754272 -173.028356)
		(width 0.10668)
		(layer "F.Cu")
		(net "RST_RT_CPU1_P2_PERST_R_N")
	)
	(segment
		(start 167.79621 -394.6271)
		(end 167.502078 -394.6271)
		(width 0.10668)
		(layer "F.Cu")
		(net "RST_RT_CPU1_P2_PERST_R_N")
	)
	(segment
		(start 181.754272 -172.411644)
		(end 182.680102 -171.485814)
		(width 0.10668)
		(layer "F.Cu")
		(net "RST_RT_CPU1_P2_PERST_R_N")
	)
	(segment
		(start 187.697618 -136.280652)
		(end 187.62726 -136.35101)
		(width 0.10668)
		(layer "F.Cu")
		(net "RST_RT_CPU1_P2_PERST_R_N")
	)
	(segment
		(start 187.62726 -136.35101)
		(end 187.62726 -139.128754)
		(width 0.10668)
		(layer "F.Cu")
		(net "RST_RT_CPU1_P2_PERST_R_N")
	)
	(segment
		(start 187.480956 -141.41069)
		(end 189.13983 -141.41069)
		(width 0.10668)
		(layer "F.Cu")
		(net "RST_RT_CPU1_P2_PERST_R_N")
	)
	(segment
		(start 187.280296 -133.877812)
		(end 187.697618 -134.295134)
		(width 0.10668)
		(layer "F.Cu")
		(net "RST_RT_CPU1_P2_PERST_R_N")
	)
	(segment
		(start 187.62726 -139.128754)
		(end 186.876436 -139.879578)
		(width 0.10668)
		(layer "F.Cu")
		(net "RST_RT_CPU1_P2_PERST_R_N")
	)
	(segment
		(start 193.14795 -187.003182)
		(end 193.14795 -184.422034)
		(width 0.10668)
		(layer "F.Cu")
		(net "RST_RT_CPU1_P2_PERST_R_N")
	)
	(segment
		(start 187.697618 -134.295134)
		(end 187.697618 -136.280652)
		(width 0.10668)
		(layer "F.Cu")
		(net "RST_RT_CPU1_P2_PERST_R_N")
	)
	(segment
		(start 192.195958 -142.109698)
		(end 193.68262 -143.59636)
		(width 0.10668)
		(layer "F.Cu")
		(net "RST_RT_CPU1_P2_PERST_R_N")
	)
	(via
		(at 184.132474 -172.304456)
		(size 0.508)
		(drill 0.254)
		(layers "F.Cu" "B.Cu")
		(net "RST_RT_CPU1_P2_PERST_R_N")
	)
	(via
		(at 193.14795 -187.003182)
		(size 0.508)
		(drill 0.254)
		(layers "F.Cu" "B.Cu")
		(net "RST_RT_CPU1_P2_PERST_R_N")
	)
	(via
		(at 193.68262 -143.59636)
		(size 0.508)
		(drill 0.254)
		(layers "F.Cu" "B.Cu")
		(net "RST_RT_CPU1_P2_PERST_R_N")
	)
	(via
		(at 167.521128 -392.815826)
		(size 0.508)
		(drill 0.254)
		(layers "F.Cu" "B.Cu")
		(net "RST_RT_CPU1_P2_PERST_R_N")
	)
	(via
		(at 219.49156 -217.437208)
		(size 0.508)
		(drill 0.254)
		(layers "F.Cu" "B.Cu")
		(net "RST_RT_CPU1_P2_PERST_R_N")
	)
	(segment
		(start 216.303352 -214.249)
		(end 216.303352 -190.836804)
		(width 0.10668)
		(layer "B.Cu")
		(net "RST_RT_CPU1_P2_PERST_R_N")
	)
	(segment
		(start 195.322952 -183.778144)
		(end 193.14795 -185.953146)
		(width 0.10668)
		(layer "B.Cu")
		(net "RST_RT_CPU1_P2_PERST_R_N")
	)
	(segment
		(start 209.244692 -183.778144)
		(end 195.322952 -183.778144)
		(width 0.10668)
		(layer "B.Cu")
		(net "RST_RT_CPU1_P2_PERST_R_N")
	)
	(segment
		(start 219.49156 -217.437208)
		(end 216.303352 -214.249)
		(width 0.10668)
		(layer "B.Cu")
		(net "RST_RT_CPU1_P2_PERST_R_N")
	)
	(segment
		(start 193.14795 -185.953146)
		(end 193.14795 -187.003182)
		(width 0.10668)
		(layer "B.Cu")
		(net "RST_RT_CPU1_P2_PERST_R_N")
	)
	(segment
		(start 216.303352 -190.836804)
		(end 209.244692 -183.778144)
		(width 0.10668)
		(layer "B.Cu")
		(net "RST_RT_CPU1_P2_PERST_R_N")
	)
	(segment
		(start 169.478198 -391.992104)
		(end 168.654476 -392.815826)
		(width 0.11684)
		(layer "In2.Cu")
		(net "RST_RT_CPU1_P2_PERST_R_N")
	)
	(segment
		(start 184.358788 -379.114558)
		(end 180.557932 -382.915414)
		(width 0.11684)
		(layer "In2.Cu")
		(net "RST_RT_CPU1_P2_PERST_R_N")
	)
	(segment
		(start 180.176424 -382.915414)
		(end 173.625256 -389.466582)
		(width 0.11684)
		(layer "In2.Cu")
		(net "RST_RT_CPU1_P2_PERST_R_N")
	)
	(segment
		(start 218.64574 -296.976038)
		(end 218.64574 -314.440316)
		(width 0.11684)
		(layer "In2.Cu")
		(net "RST_RT_CPU1_P2_PERST_R_N")
	)
	(segment
		(start 219.49156 -217.437208)
		(end 215.601042 -221.327726)
		(width 0.11684)
		(layer "In2.Cu")
		(net "RST_RT_CPU1_P2_PERST_R_N")
	)
	(segment
		(start 212.327744 -324.309486)
		(end 211.28609 -325.35114)
		(width 0.11684)
		(layer "In2.Cu")
		(net "RST_RT_CPU1_P2_PERST_R_N")
	)
	(segment
		(start 192.682876 -372.603268)
		(end 189.34684 -372.603268)
		(width 0.11684)
		(layer "In2.Cu")
		(net "RST_RT_CPU1_P2_PERST_R_N")
	)
	(segment
		(start 211.28609 -325.35114)
		(end 211.28609 -333.392272)
		(width 0.11684)
		(layer "In2.Cu")
		(net "RST_RT_CPU1_P2_PERST_R_N")
	)
	(segment
		(start 184.358788 -377.59132)
		(end 184.358788 -379.114558)
		(width 0.11684)
		(layer "In2.Cu")
		(net "RST_RT_CPU1_P2_PERST_R_N")
	)
	(segment
		(start 189.34684 -372.603268)
		(end 184.358788 -377.59132)
		(width 0.11684)
		(layer "In2.Cu")
		(net "RST_RT_CPU1_P2_PERST_R_N")
	)
	(segment
		(start 218.64574 -314.440316)
		(end 212.327744 -320.758312)
		(width 0.11684)
		(layer "In2.Cu")
		(net "RST_RT_CPU1_P2_PERST_R_N")
	)
	(segment
		(start 214.398352 -336.504534)
		(end 214.398352 -350.887792)
		(width 0.11684)
		(layer "In2.Cu")
		(net "RST_RT_CPU1_P2_PERST_R_N")
	)
	(segment
		(start 168.654476 -392.815826)
		(end 167.521128 -392.815826)
		(width 0.11684)
		(layer "In2.Cu")
		(net "RST_RT_CPU1_P2_PERST_R_N")
	)
	(segment
		(start 211.28609 -333.392272)
		(end 214.398352 -336.504534)
		(width 0.11684)
		(layer "In2.Cu")
		(net "RST_RT_CPU1_P2_PERST_R_N")
	)
	(segment
		(start 215.601042 -293.93134)
		(end 218.64574 -296.976038)
		(width 0.11684)
		(layer "In2.Cu")
		(net "RST_RT_CPU1_P2_PERST_R_N")
	)
	(segment
		(start 170.143424 -389.466582)
		(end 169.478198 -390.131808)
		(width 0.11684)
		(layer "In2.Cu")
		(net "RST_RT_CPU1_P2_PERST_R_N")
	)
	(segment
		(start 169.478198 -390.131808)
		(end 169.478198 -391.992104)
		(width 0.11684)
		(layer "In2.Cu")
		(net "RST_RT_CPU1_P2_PERST_R_N")
	)
	(segment
		(start 212.327744 -320.758312)
		(end 212.327744 -324.309486)
		(width 0.11684)
		(layer "In2.Cu")
		(net "RST_RT_CPU1_P2_PERST_R_N")
	)
	(segment
		(start 215.601042 -221.327726)
		(end 215.601042 -293.93134)
		(width 0.11684)
		(layer "In2.Cu")
		(net "RST_RT_CPU1_P2_PERST_R_N")
	)
	(segment
		(start 173.625256 -389.466582)
		(end 170.143424 -389.466582)
		(width 0.11684)
		(layer "In2.Cu")
		(net "RST_RT_CPU1_P2_PERST_R_N")
	)
	(segment
		(start 180.557932 -382.915414)
		(end 180.176424 -382.915414)
		(width 0.11684)
		(layer "In2.Cu")
		(net "RST_RT_CPU1_P2_PERST_R_N")
	)
	(segment
		(start 214.398352 -350.887792)
		(end 192.682876 -372.603268)
		(width 0.11684)
		(layer "In2.Cu")
		(net "RST_RT_CPU1_P2_PERST_R_N")
	)
	(segment
		(start 184.132474 -172.304456)
		(end 184.526682 -172.304456)
		(width 0.11684)
		(layer "In11.Cu")
		(net "RST_RT_CPU1_P2_PERST_R_N")
	)
	(segment
		(start 186.966352 -150.180294)
		(end 193.550286 -143.59636)
		(width 0.11684)
		(layer "In11.Cu")
		(net "RST_RT_CPU1_P2_PERST_R_N")
	)
	(segment
		(start 186.966352 -160.988502)
		(end 186.966352 -150.180294)
		(width 0.11684)
		(layer "In11.Cu")
		(net "RST_RT_CPU1_P2_PERST_R_N")
	)
	(segment
		(start 187.36818 -163.119054)
		(end 186.37504 -162.125914)
		(width 0.11684)
		(layer "In11.Cu")
		(net "RST_RT_CPU1_P2_PERST_R_N")
	)
	(segment
		(start 184.526682 -172.304456)
		(end 187.36818 -169.462958)
		(width 0.11684)
		(layer "In11.Cu")
		(net "RST_RT_CPU1_P2_PERST_R_N")
	)
	(segment
		(start 186.37504 -162.125914)
		(end 186.37504 -161.579814)
		(width 0.11684)
		(layer "In11.Cu")
		(net "RST_RT_CPU1_P2_PERST_R_N")
	)
	(segment
		(start 186.37504 -161.579814)
		(end 186.966352 -160.988502)
		(width 0.11684)
		(layer "In11.Cu")
		(net "RST_RT_CPU1_P2_PERST_R_N")
	)
	(segment
		(start 187.36818 -169.462958)
		(end 187.36818 -163.119054)
		(width 0.11684)
		(layer "In11.Cu")
		(net "RST_RT_CPU1_P2_PERST_R_N")
	)
	(segment
		(start 193.550286 -143.59636)
		(end 193.68262 -143.59636)
		(width 0.11684)
		(layer "In11.Cu")
		(net "RST_RT_CPU1_P2_PERST_R_N")
	)
	(segment
		(start 184.322212 -121.852944)
		(end 183.932322 -122.242834)
		(width 0.10668)
		(layer "F.Cu")
		(net "RST_RT_CPU1_P2_PERST_R2_N")
	)
	(segment
		(start 187.280296 -133.077712)
		(end 187.280296 -132.577586)
		(width 0.10668)
		(layer "F.Cu")
		(net "RST_RT_CPU1_P2_PERST_R2_N")
	)
	(segment
		(start 187.098686 -132.395976)
		(end 187.098686 -131.680204)
		(width 0.10668)
		(layer "F.Cu")
		(net "RST_RT_CPU1_P2_PERST_R2_N")
	)
	(segment
		(start 187.280296 -132.577586)
		(end 187.098686 -132.395976)
		(width 0.10668)
		(layer "F.Cu")
		(net "RST_RT_CPU1_P2_PERST_R2_N")
	)
	(via
		(at 187.098686 -131.680204)
		(size 0.508)
		(drill 0.254)
		(layers "F.Cu" "B.Cu")
		(net "RST_RT_CPU1_P2_PERST_R2_N")
	)
	(via
		(at 183.932322 -122.242834)
		(size 0.4572)
		(drill 0.254)
		(layers "F.Cu" "B.Cu")
		(net "RST_RT_CPU1_P2_PERST_R2_N")
	)
	(segment
		(start 186.537092 -131.11861)
		(end 187.098686 -131.680204)
		(width 0.11684)
		(layer "In11.Cu")
		(net "RST_RT_CPU1_P2_PERST_R2_N")
	)
	(segment
		(start 184.335928 -127.8382)
		(end 186.537092 -130.039364)
		(width 0.11684)
		(layer "In11.Cu")
		(net "RST_RT_CPU1_P2_PERST_R2_N")
	)
	(segment
		(start 186.537092 -130.039364)
		(end 186.537092 -131.11861)
		(width 0.11684)
		(layer "In11.Cu")
		(net "RST_RT_CPU1_P2_PERST_R2_N")
	)
	(segment
		(start 183.932322 -122.242834)
		(end 184.335928 -122.64644)
		(width 0.11684)
		(layer "In11.Cu")
		(net "RST_RT_CPU1_P2_PERST_R2_N")
	)
	(segment
		(start 184.335928 -122.64644)
		(end 184.335928 -127.8382)
		(width 0.11684)
		(layer "In11.Cu")
		(net "RST_RT_CPU1_P2_PERST_R2_N")
	)
	(segment
		(start 166.98722 -395.027912)
		(end 166.98722 -392.542014)
		(width 0.10668)
		(layer "F.Cu")
		(net "RST_RT_CPU1_P2_PERST_N")
	)
	(segment
		(start 166.245794 -391.800588)
		(end 166.245794 -390.761474)
		(width 0.10668)
		(layer "F.Cu")
		(net "RST_RT_CPU1_P2_PERST_N")
	)
	(segment
		(start 167.25265 -395.8971)
		(end 166.98722 -395.63167)
		(width 0.10668)
		(layer "F.Cu")
		(net "RST_RT_CPU1_P2_PERST_N")
	)
	(segment
		(start 166.98722 -392.542014)
		(end 166.245794 -391.800588)
		(width 0.10668)
		(layer "F.Cu")
		(net "RST_RT_CPU1_P2_PERST_N")
	)
	(segment
		(start 166.98722 -395.63167)
		(end 166.98722 -395.027912)
		(width 0.10668)
		(layer "F.Cu")
		(net "RST_RT_CPU1_P2_PERST_N")
	)
	(segment
		(start 167.79621 -395.8971)
		(end 167.25265 -395.8971)
		(width 0.10668)
		(layer "F.Cu")
		(net "RST_RT_CPU1_P2_PERST_N")
	)
	(via
		(at 166.98722 -395.027912)
		(size 0.508)
		(drill 0.254)
		(layers "F.Cu" "B.Cu")
		(net "RST_RT_CPU1_P2_PERST_N")
	)
	(segment
		(start 173.632876 -416.872674)
		(end 174.578772 -416.872674)
		(width 0.10668)
		(layer "F.Cu")
		(net "PRSNT_CABLE_SWB_B2_N")
	)
	(segment
		(start 173.499018 -417.006532)
		(end 172.953934 -417.551616)
		(width 0.10668)
		(layer "F.Cu")
		(net "PRSNT_CABLE_SWB_B2_N")
	)
	(segment
		(start 172.94352 -417.554664)
		(end 172.940472 -417.551616)
		(width 0.10668)
		(layer "F.Cu")
		(net "PRSNT_CABLE_SWB_B2_N")
	)
	(segment
		(start 172.94352 -418.551868)
		(end 172.94352 -417.554664)
		(width 0.10668)
		(layer "F.Cu")
		(net "PRSNT_CABLE_SWB_B2_N")
	)
	(segment
		(start 175.112426 -417.406328)
		(end 175.204374 -417.406328)
		(width 0.10668)
		(layer "F.Cu")
		(net "PRSNT_CABLE_SWB_B2_N")
	)
	(segment
		(start 173.499018 -417.006532)
		(end 173.632876 -416.872674)
		(width 0.10668)
		(layer "F.Cu")
		(net "PRSNT_CABLE_SWB_B2_N")
	)
	(segment
		(start 172.953934 -417.551616)
		(end 172.940472 -417.551616)
		(width 0.10668)
		(layer "F.Cu")
		(net "PRSNT_CABLE_SWB_B2_N")
	)
	(segment
		(start 174.578772 -416.872674)
		(end 175.112426 -417.406328)
		(width 0.10668)
		(layer "F.Cu")
		(net "PRSNT_CABLE_SWB_B2_N")
	)
	(via
		(at 169.412412 -396.48003)
		(size 0.508)
		(drill 0.254)
		(layers "F.Cu" "B.Cu")
		(net "PRSNT_CABLE_SWB_B2_N")
	)
	(via
		(at 173.499018 -417.006532)
		(size 0.508)
		(drill 0.254)
		(layers "F.Cu" "B.Cu")
		(net "PRSNT_CABLE_SWB_B2_N")
	)
	(via
		(at 333.251556 -421.933878)
		(size 0.6604)
		(drill 0.3302)
		(layers "F.Cu" "B.Cu")
		(net "PRSNT_CABLE_SWB_B2_N")
	)
	(via
		(at 173.80712 -368.87404)
		(size 0.508)
		(drill 0.254)
		(layers "F.Cu" "B.Cu")
		(net "PRSNT_CABLE_SWB_B2_N")
	)
	(segment
		(start 286.380682 -403.273768)
		(end 288.828988 -405.722074)
		(width 0.10668)
		(layer "B.Cu")
		(net "PRSNT_CABLE_SWB_B2_N")
	)
	(segment
		(start 292.925754 -418.507418)
		(end 294.038528 -419.620192)
		(width 0.10668)
		(layer "B.Cu")
		(net "PRSNT_CABLE_SWB_B2_N")
	)
	(segment
		(start 187.931298 -372.486174)
		(end 189.273688 -372.486174)
		(width 0.10668)
		(layer "B.Cu")
		(net "PRSNT_CABLE_SWB_B2_N")
	)
	(segment
		(start 187.129166 -371.684042)
		(end 187.931298 -372.486174)
		(width 0.10668)
		(layer "B.Cu")
		(net "PRSNT_CABLE_SWB_B2_N")
	)
	(segment
		(start 292.925754 -411.569662)
		(end 292.925754 -418.507418)
		(width 0.10668)
		(layer "B.Cu")
		(net "PRSNT_CABLE_SWB_B2_N")
	)
	(segment
		(start 173.80712 -368.87404)
		(end 173.80712 -369.5446)
		(width 0.10668)
		(layer "B.Cu")
		(net "PRSNT_CABLE_SWB_B2_N")
	)
	(segment
		(start 279.19553 -373.459502)
		(end 282.260802 -376.524774)
		(width 0.10668)
		(layer "B.Cu")
		(net "PRSNT_CABLE_SWB_B2_N")
	)
	(segment
		(start 284.97784 -392.691874)
		(end 286.380682 -394.094716)
		(width 0.10668)
		(layer "B.Cu")
		(net "PRSNT_CABLE_SWB_B2_N")
	)
	(segment
		(start 190.347346 -373.559832)
		(end 191.513714 -373.559832)
		(width 0.10668)
		(layer "B.Cu")
		(net "PRSNT_CABLE_SWB_B2_N")
	)
	(segment
		(start 333.649828 -422.33215)
		(end 333.251556 -421.933878)
		(width 0.10668)
		(layer "B.Cu")
		(net "PRSNT_CABLE_SWB_B2_N")
	)
	(segment
		(start 173.80712 -369.5446)
		(end 175.026828 -370.764308)
		(width 0.10668)
		(layer "B.Cu")
		(net "PRSNT_CABLE_SWB_B2_N")
	)
	(segment
		(start 282.260802 -376.524774)
		(end 282.260802 -384.388868)
		(width 0.10668)
		(layer "B.Cu")
		(net "PRSNT_CABLE_SWB_B2_N")
	)
	(segment
		(start 288.828988 -407.472896)
		(end 292.925754 -411.569662)
		(width 0.10668)
		(layer "B.Cu")
		(net "PRSNT_CABLE_SWB_B2_N")
	)
	(segment
		(start 175.026828 -370.764308)
		(end 179.425346 -370.764308)
		(width 0.10668)
		(layer "B.Cu")
		(net "PRSNT_CABLE_SWB_B2_N")
	)
	(segment
		(start 333.649828 -424.689778)
		(end 333.649828 -422.33215)
		(width 0.10668)
		(layer "B.Cu")
		(net "PRSNT_CABLE_SWB_B2_N")
	)
	(segment
		(start 180.34508 -371.684042)
		(end 187.129166 -371.684042)
		(width 0.10668)
		(layer "B.Cu")
		(net "PRSNT_CABLE_SWB_B2_N")
	)
	(segment
		(start 294.038528 -419.620192)
		(end 332.784704 -419.620192)
		(width 0.10668)
		(layer "B.Cu")
		(net "PRSNT_CABLE_SWB_B2_N")
	)
	(segment
		(start 333.251556 -420.087044)
		(end 333.251556 -421.933878)
		(width 0.10668)
		(layer "B.Cu")
		(net "PRSNT_CABLE_SWB_B2_N")
	)
	(segment
		(start 189.273688 -372.486174)
		(end 190.347346 -373.559832)
		(width 0.10668)
		(layer "B.Cu")
		(net "PRSNT_CABLE_SWB_B2_N")
	)
	(segment
		(start 179.425346 -370.764308)
		(end 180.34508 -371.684042)
		(width 0.10668)
		(layer "B.Cu")
		(net "PRSNT_CABLE_SWB_B2_N")
	)
	(segment
		(start 288.828988 -405.722074)
		(end 288.828988 -407.472896)
		(width 0.10668)
		(layer "B.Cu")
		(net "PRSNT_CABLE_SWB_B2_N")
	)
	(segment
		(start 286.380682 -394.094716)
		(end 286.380682 -403.273768)
		(width 0.10668)
		(layer "B.Cu")
		(net "PRSNT_CABLE_SWB_B2_N")
	)
	(segment
		(start 191.513714 -373.559832)
		(end 191.614044 -373.459502)
		(width 0.10668)
		(layer "B.Cu")
		(net "PRSNT_CABLE_SWB_B2_N")
	)
	(segment
		(start 284.97784 -387.105906)
		(end 284.97784 -392.691874)
		(width 0.10668)
		(layer "B.Cu")
		(net "PRSNT_CABLE_SWB_B2_N")
	)
	(segment
		(start 332.784704 -419.620192)
		(end 333.251556 -420.087044)
		(width 0.10668)
		(layer "B.Cu")
		(net "PRSNT_CABLE_SWB_B2_N")
	)
	(segment
		(start 282.260802 -384.388868)
		(end 284.97784 -387.105906)
		(width 0.10668)
		(layer "B.Cu")
		(net "PRSNT_CABLE_SWB_B2_N")
	)
	(segment
		(start 191.614044 -373.459502)
		(end 279.19553 -373.459502)
		(width 0.10668)
		(layer "B.Cu")
		(net "PRSNT_CABLE_SWB_B2_N")
	)
	(segment
		(start 172.813218 -416.320732)
		(end 173.499018 -417.006532)
		(width 0.11684)
		(layer "In11.Cu")
		(net "PRSNT_CABLE_SWB_B2_N")
	)
	(segment
		(start 171.31538 -398.081246)
		(end 172.58284 -399.348706)
		(width 0.11684)
		(layer "In11.Cu")
		(net "PRSNT_CABLE_SWB_B2_N")
	)
	(segment
		(start 173.66361 -399.348706)
		(end 175.8823 -401.567396)
		(width 0.11684)
		(layer "In11.Cu")
		(net "PRSNT_CABLE_SWB_B2_N")
	)
	(segment
		(start 175.8823 -408.341322)
		(end 172.813218 -411.410404)
		(width 0.11684)
		(layer "In11.Cu")
		(net "PRSNT_CABLE_SWB_B2_N")
	)
	(segment
		(start 172.58284 -399.348706)
		(end 173.66361 -399.348706)
		(width 0.11684)
		(layer "In11.Cu")
		(net "PRSNT_CABLE_SWB_B2_N")
	)
	(segment
		(start 169.412412 -396.48003)
		(end 171.013628 -398.081246)
		(width 0.11684)
		(layer "In11.Cu")
		(net "PRSNT_CABLE_SWB_B2_N")
	)
	(segment
		(start 175.8823 -401.567396)
		(end 175.8823 -408.341322)
		(width 0.11684)
		(layer "In11.Cu")
		(net "PRSNT_CABLE_SWB_B2_N")
	)
	(segment
		(start 171.013628 -398.081246)
		(end 171.31538 -398.081246)
		(width 0.11684)
		(layer "In11.Cu")
		(net "PRSNT_CABLE_SWB_B2_N")
	)
	(segment
		(start 172.813218 -411.410404)
		(end 172.813218 -416.320732)
		(width 0.11684)
		(layer "In11.Cu")
		(net "PRSNT_CABLE_SWB_B2_N")
	)
	(segment
		(start 171.373546 -389.228838)
		(end 173.76267 -389.228838)
		(width 0.11684)
		(layer "In15.Cu")
		(net "PRSNT_CABLE_SWB_B2_N")
	)
	(segment
		(start 169.399458 -393.230608)
		(end 169.399458 -390.812274)
		(width 0.11684)
		(layer "In15.Cu")
		(net "PRSNT_CABLE_SWB_B2_N")
	)
	(segment
		(start 169.399458 -390.812274)
		(end 170.66514 -389.546592)
		(width 0.11684)
		(layer "In15.Cu")
		(net "PRSNT_CABLE_SWB_B2_N")
	)
	(segment
		(start 173.80712 -369.52682)
		(end 173.80712 -368.87404)
		(width 0.11684)
		(layer "In15.Cu")
		(net "PRSNT_CABLE_SWB_B2_N")
	)
	(segment
		(start 183.76011 -379.231398)
		(end 183.76011 -372.90248)
		(width 0.11684)
		(layer "In15.Cu")
		(net "PRSNT_CABLE_SWB_B2_N")
	)
	(segment
		(start 171.055792 -389.546592)
		(end 171.373546 -389.228838)
		(width 0.11684)
		(layer "In15.Cu")
		(net "PRSNT_CABLE_SWB_B2_N")
	)
	(segment
		(start 175.39589 -371.11559)
		(end 173.80712 -369.52682)
		(width 0.11684)
		(layer "In15.Cu")
		(net "PRSNT_CABLE_SWB_B2_N")
	)
	(segment
		(start 173.76267 -389.228838)
		(end 183.76011 -379.231398)
		(width 0.11684)
		(layer "In15.Cu")
		(net "PRSNT_CABLE_SWB_B2_N")
	)
	(segment
		(start 168.20388 -394.426186)
		(end 169.399458 -393.230608)
		(width 0.11684)
		(layer "In15.Cu")
		(net "PRSNT_CABLE_SWB_B2_N")
	)
	(segment
		(start 170.66514 -389.546592)
		(end 171.055792 -389.546592)
		(width 0.11684)
		(layer "In15.Cu")
		(net "PRSNT_CABLE_SWB_B2_N")
	)
	(segment
		(start 183.76011 -372.90248)
		(end 181.97322 -371.11559)
		(width 0.11684)
		(layer "In15.Cu")
		(net "PRSNT_CABLE_SWB_B2_N")
	)
	(segment
		(start 181.97322 -371.11559)
		(end 175.39589 -371.11559)
		(width 0.11684)
		(layer "In15.Cu")
		(net "PRSNT_CABLE_SWB_B2_N")
	)
	(segment
		(start 168.20388 -395.271498)
		(end 168.20388 -394.426186)
		(width 0.11684)
		(layer "In15.Cu")
		(net "PRSNT_CABLE_SWB_B2_N")
	)
	(segment
		(start 169.412412 -396.48003)
		(end 168.20388 -395.271498)
		(width 0.11684)
		(layer "In15.Cu")
		(net "PRSNT_CABLE_SWB_B2_N")
	)
	(segment
		(start 187.262262 -416.605212)
		(end 187.262262 -417.404804)
		(width 0.10668)
		(layer "F.Cu")
		(net "PRSNT_CABLE_SWB_B2_ISO_R_N")
	)
	(segment
		(start 188.143642 -414.939226)
		(end 188.143642 -415.723832)
		(width 0.10668)
		(layer "F.Cu")
		(net "PRSNT_CABLE_SWB_B2_ISO_R_N")
	)
	(segment
		(start 188.143642 -415.723832)
		(end 187.262262 -416.605212)
		(width 0.10668)
		(layer "F.Cu")
		(net "PRSNT_CABLE_SWB_B2_ISO_R_N")
	)
	(segment
		(start 188.143642 -414.04413)
		(end 188.143642 -414.939226)
		(width 0.10668)
		(layer "F.Cu")
		(net "PRSNT_CABLE_SWB_B2_ISO_R_N")
	)
	(via
		(at 188.143642 -414.939226)
		(size 0.762)
		(drill 0.381)
		(layers "F.Cu" "B.Cu")
		(net "PRSNT_CABLE_SWB_B2_ISO_R_N")
	)
	(segment
		(start 174.136812 -415.919666)
		(end 174.933864 -415.919666)
		(width 0.10668)
		(layer "F.Cu")
		(net "PRSNT_CABLE_SWB_B2_ISO_N")
	)
	(segment
		(start 173.721014 -415.503868)
		(end 174.136812 -415.919666)
		(width 0.10668)
		(layer "F.Cu")
		(net "PRSNT_CABLE_SWB_B2_ISO_N")
	)
	(segment
		(start 172.940472 -415.506916)
		(end 172.94352 -415.503868)
		(width 0.10668)
		(layer "F.Cu")
		(net "PRSNT_CABLE_SWB_B2_ISO_N")
	)
	(segment
		(start 172.940472 -416.484816)
		(end 172.940472 -415.506916)
		(width 0.10668)
		(layer "F.Cu")
		(net "PRSNT_CABLE_SWB_B2_ISO_N")
	)
	(segment
		(start 172.94352 -415.503868)
		(end 173.721014 -415.503868)
		(width 0.10668)
		(layer "F.Cu")
		(net "PRSNT_CABLE_SWB_B2_ISO_N")
	)
	(segment
		(start 174.933864 -415.919666)
		(end 175.204374 -416.190176)
		(width 0.10668)
		(layer "F.Cu")
		(net "PRSNT_CABLE_SWB_B2_ISO_N")
	)
	(segment
		(start 188.143642 -413.24403)
		(end 188.890656 -413.24403)
		(width 0.10668)
		(layer "F.Cu")
		(net "PRSNT_CABLE_SWB_B2_ISO_N")
	)
	(segment
		(start 175.204374 -416.190176)
		(end 175.204374 -416.756342)
		(width 0.10668)
		(layer "F.Cu")
		(net "PRSNT_CABLE_SWB_B2_ISO_N")
	)
	(via
		(at 174.136812 -415.919666)
		(size 0.508)
		(drill 0.254)
		(layers "F.Cu" "B.Cu")
		(net "PRSNT_CABLE_SWB_B2_ISO_N")
	)
	(via
		(at 188.890656 -413.24403)
		(size 0.508)
		(drill 0.254)
		(layers "F.Cu" "B.Cu")
		(net "PRSNT_CABLE_SWB_B2_ISO_N")
	)
	(segment
		(start 182.766208 -416.826954)
		(end 184.21477 -415.378392)
		(width 0.10668)
		(layer "B.Cu")
		(net "PRSNT_CABLE_SWB_B2_ISO_N")
	)
	(segment
		(start 174.136812 -415.919666)
		(end 176.87671 -415.919666)
		(width 0.10668)
		(layer "B.Cu")
		(net "PRSNT_CABLE_SWB_B2_ISO_N")
	)
	(segment
		(start 186.756294 -415.378392)
		(end 188.890656 -413.24403)
		(width 0.10668)
		(layer "B.Cu")
		(net "PRSNT_CABLE_SWB_B2_ISO_N")
	)
	(segment
		(start 184.21477 -415.378392)
		(end 186.756294 -415.378392)
		(width 0.10668)
		(layer "B.Cu")
		(net "PRSNT_CABLE_SWB_B2_ISO_N")
	)
	(segment
		(start 181.39283 -416.48634)
		(end 181.733444 -416.826954)
		(width 0.10668)
		(layer "B.Cu")
		(net "PRSNT_CABLE_SWB_B2_ISO_N")
	)
	(segment
		(start 178.27371 -416.08756)
		(end 178.67249 -416.48634)
		(width 0.10668)
		(layer "B.Cu")
		(net "PRSNT_CABLE_SWB_B2_ISO_N")
	)
	(segment
		(start 176.87671 -415.919666)
		(end 177.044604 -416.08756)
		(width 0.10668)
		(layer "B.Cu")
		(net "PRSNT_CABLE_SWB_B2_ISO_N")
	)
	(segment
		(start 178.67249 -416.48634)
		(end 181.39283 -416.48634)
		(width 0.10668)
		(layer "B.Cu")
		(net "PRSNT_CABLE_SWB_B2_ISO_N")
	)
	(segment
		(start 177.044604 -416.08756)
		(end 178.27371 -416.08756)
		(width 0.10668)
		(layer "B.Cu")
		(net "PRSNT_CABLE_SWB_B2_ISO_N")
	)
	(segment
		(start 181.733444 -416.826954)
		(end 182.766208 -416.826954)
		(width 0.10668)
		(layer "B.Cu")
		(net "PRSNT_CABLE_SWB_B2_ISO_N")
	)
	(segment
		(start 178.34864 -418.431218)
		(end 177.479198 -418.431218)
		(width 0.10668)
		(layer "F.Cu")
		(net "PRSNT_CABLE_SWB_B2")
	)
	(segment
		(start 177.479198 -418.431218)
		(end 177.104294 -418.056314)
		(width 0.10668)
		(layer "F.Cu")
		(net "PRSNT_CABLE_SWB_B2")
	)
	(segment
		(start 177.104294 -418.056314)
		(end 177.104294 -417.406328)
		(width 0.10668)
		(layer "F.Cu")
		(net "PRSNT_CABLE_SWB_B2")
	)
	(segment
		(start 179.244752 -418.431218)
		(end 178.34864 -418.431218)
		(width 0.10668)
		(layer "F.Cu")
		(net "PRSNT_CABLE_SWB_B2")
	)
	(via
		(at 178.34864 -418.431218)
		(size 0.762)
		(drill 0.381)
		(layers "F.Cu" "B.Cu")
		(net "PRSNT_CABLE_SWB_B2")
	)
	(segment
		(start 362.425488 -411.354016)
		(end 362.425488 -410.722318)
		(width 0.10668)
		(layer "F.Cu")
		(net "PRSNT_CABLE_SWB_B1_N")
	)
	(segment
		(start 362.425488 -412.334964)
		(end 362.425488 -411.354016)
		(width 0.10668)
		(layer "F.Cu")
		(net "PRSNT_CABLE_SWB_B1_N")
	)
	(segment
		(start 362.984288 -414.779206)
		(end 362.984288 -413.934402)
		(width 0.10668)
		(layer "F.Cu")
		(net "PRSNT_CABLE_SWB_B1_N")
	)
	(segment
		(start 362.425488 -410.722318)
		(end 362.432346 -410.71546)
		(width 0.10668)
		(layer "F.Cu")
		(net "PRSNT_CABLE_SWB_B1_N")
	)
	(segment
		(start 362.984288 -413.934402)
		(end 362.425488 -413.375602)
		(width 0.10668)
		(layer "F.Cu")
		(net "PRSNT_CABLE_SWB_B1_N")
	)
	(segment
		(start 362.425488 -413.375602)
		(end 362.425488 -412.334964)
		(width 0.10668)
		(layer "F.Cu")
		(net "PRSNT_CABLE_SWB_B1_N")
	)
	(via
		(at 362.432346 -410.71546)
		(size 0.508)
		(drill 0.254)
		(layers "F.Cu" "B.Cu")
		(net "PRSNT_CABLE_SWB_B1_N")
	)
	(via
		(at 378.7902 -439.473848)
		(size 0.6604)
		(drill 0.3302)
		(layers "F.Cu" "B.Cu")
		(net "PRSNT_CABLE_SWB_B1_N")
	)
	(segment
		(start 361.660186 -419.081204)
		(end 361.044744 -418.465762)
		(width 0.10668)
		(layer "B.Cu")
		(net "PRSNT_CABLE_SWB_B1_N")
	)
	(segment
		(start 361.044744 -418.465762)
		(end 361.044744 -416.751262)
		(width 0.10668)
		(layer "B.Cu")
		(net "PRSNT_CABLE_SWB_B1_N")
	)
	(segment
		(start 360.312208 -416.018726)
		(end 360.312208 -412.951168)
		(width 0.10668)
		(layer "B.Cu")
		(net "PRSNT_CABLE_SWB_B1_N")
	)
	(segment
		(start 360.312208 -412.951168)
		(end 360.736896 -412.52648)
		(width 0.10668)
		(layer "B.Cu")
		(net "PRSNT_CABLE_SWB_B1_N")
	)
	(segment
		(start 381.749808 -440.489848)
		(end 379.8062 -440.489848)
		(width 0.10668)
		(layer "B.Cu")
		(net "PRSNT_CABLE_SWB_B1_N")
	)
	(segment
		(start 375.810272 -430.166272)
		(end 365.438182 -430.166272)
		(width 0.10668)
		(layer "B.Cu")
		(net "PRSNT_CABLE_SWB_B1_N")
	)
	(segment
		(start 379.8062 -440.489848)
		(end 378.7902 -439.473848)
		(width 0.10668)
		(layer "B.Cu")
		(net "PRSNT_CABLE_SWB_B1_N")
	)
	(segment
		(start 365.438182 -430.166272)
		(end 362.57103 -427.29912)
		(width 0.10668)
		(layer "B.Cu")
		(net "PRSNT_CABLE_SWB_B1_N")
	)
	(segment
		(start 361.674918 -412.52648)
		(end 362.432346 -411.769052)
		(width 0.10668)
		(layer "B.Cu")
		(net "PRSNT_CABLE_SWB_B1_N")
	)
	(segment
		(start 361.660186 -422.470834)
		(end 361.660186 -419.081204)
		(width 0.10668)
		(layer "B.Cu")
		(net "PRSNT_CABLE_SWB_B1_N")
	)
	(segment
		(start 361.044744 -416.751262)
		(end 360.312208 -416.018726)
		(width 0.10668)
		(layer "B.Cu")
		(net "PRSNT_CABLE_SWB_B1_N")
	)
	(segment
		(start 360.736896 -412.52648)
		(end 361.674918 -412.52648)
		(width 0.10668)
		(layer "B.Cu")
		(net "PRSNT_CABLE_SWB_B1_N")
	)
	(segment
		(start 362.432346 -411.769052)
		(end 362.432346 -410.71546)
		(width 0.10668)
		(layer "B.Cu")
		(net "PRSNT_CABLE_SWB_B1_N")
	)
	(segment
		(start 362.57103 -423.381678)
		(end 361.660186 -422.470834)
		(width 0.10668)
		(layer "B.Cu")
		(net "PRSNT_CABLE_SWB_B1_N")
	)
	(segment
		(start 378.7902 -433.1462)
		(end 375.810272 -430.166272)
		(width 0.10668)
		(layer "B.Cu")
		(net "PRSNT_CABLE_SWB_B1_N")
	)
	(segment
		(start 378.7902 -439.473848)
		(end 378.7902 -433.1462)
		(width 0.10668)
		(layer "B.Cu")
		(net "PRSNT_CABLE_SWB_B1_N")
	)
	(segment
		(start 362.57103 -427.29912)
		(end 362.57103 -423.381678)
		(width 0.10668)
		(layer "B.Cu")
		(net "PRSNT_CABLE_SWB_B1_N")
	)
	(segment
		(start 188.843412 -425.698158)
		(end 188.843412 -427.166786)
		(width 0.10668)
		(layer "F.Cu")
		(net "PRSNT_CABLE_SWB_B1_ISO_R_N")
	)
	(segment
		(start 187.262262 -424.117008)
		(end 188.843412 -425.698158)
		(width 0.10668)
		(layer "F.Cu")
		(net "PRSNT_CABLE_SWB_B1_ISO_R_N")
	)
	(segment
		(start 189.327028 -428.54753)
		(end 189.327028 -427.650402)
		(width 0.10668)
		(layer "F.Cu")
		(net "PRSNT_CABLE_SWB_B1_ISO_R_N")
	)
	(segment
		(start 187.262262 -423.254932)
		(end 187.262262 -424.117008)
		(width 0.10668)
		(layer "F.Cu")
		(net "PRSNT_CABLE_SWB_B1_ISO_R_N")
	)
	(segment
		(start 188.843412 -427.166786)
		(end 189.327028 -427.650402)
		(width 0.10668)
		(layer "F.Cu")
		(net "PRSNT_CABLE_SWB_B1_ISO_R_N")
	)
	(via
		(at 189.327028 -427.650402)
		(size 0.762)
		(drill 0.381)
		(layers "F.Cu" "B.Cu")
		(net "PRSNT_CABLE_SWB_B1_ISO_R_N")
	)
	(segment
		(start 364.762288 -411.369764)
		(end 364.762288 -411.065218)
		(width 0.10668)
		(layer "F.Cu")
		(net "PRSNT_CABLE_SWB_B1_ISO_N")
	)
	(segment
		(start 189.327028 -429.34763)
		(end 189.327028 -429.553624)
		(width 0.10668)
		(layer "F.Cu")
		(net "PRSNT_CABLE_SWB_B1_ISO_N")
	)
	(segment
		(start 364.762288 -412.370016)
		(end 364.762288 -412.810452)
		(width 0.10668)
		(layer "F.Cu")
		(net "PRSNT_CABLE_SWB_B1_ISO_N")
	)
	(segment
		(start 364.762288 -411.065218)
		(end 365.148876 -410.67863)
		(width 0.10668)
		(layer "F.Cu")
		(net "PRSNT_CABLE_SWB_B1_ISO_N")
	)
	(segment
		(start 363.634274 -413.938466)
		(end 363.634274 -414.779206)
		(width 0.10668)
		(layer "F.Cu")
		(net "PRSNT_CABLE_SWB_B1_ISO_N")
	)
	(segment
		(start 189.327028 -429.553624)
		(end 189.811406 -430.038002)
		(width 0.10668)
		(layer "F.Cu")
		(net "PRSNT_CABLE_SWB_B1_ISO_N")
	)
	(segment
		(start 364.762288 -411.369764)
		(end 364.762288 -412.370016)
		(width 0.10668)
		(layer "F.Cu")
		(net "PRSNT_CABLE_SWB_B1_ISO_N")
	)
	(segment
		(start 364.028736 -413.544004)
		(end 363.634274 -413.938466)
		(width 0.10668)
		(layer "F.Cu")
		(net "PRSNT_CABLE_SWB_B1_ISO_N")
	)
	(segment
		(start 364.762288 -412.810452)
		(end 364.028736 -413.544004)
		(width 0.10668)
		(layer "F.Cu")
		(net "PRSNT_CABLE_SWB_B1_ISO_N")
	)
	(via
		(at 187.9346 -386.880608)
		(size 0.508)
		(drill 0.254)
		(layers "F.Cu" "B.Cu")
		(net "PRSNT_CABLE_SWB_B1_ISO_N")
	)
	(via
		(at 364.028736 -413.544004)
		(size 0.762)
		(drill 0.381)
		(layers "F.Cu" "B.Cu")
		(net "PRSNT_CABLE_SWB_B1_ISO_N")
	)
	(via
		(at 189.811406 -430.038002)
		(size 0.508)
		(drill 0.254)
		(layers "F.Cu" "B.Cu")
		(net "PRSNT_CABLE_SWB_B1_ISO_N")
	)
	(via
		(at 365.148876 -410.67863)
		(size 0.508)
		(drill 0.254)
		(layers "F.Cu" "B.Cu")
		(net "PRSNT_CABLE_SWB_B1_ISO_N")
	)
	(via
		(at 289.353752 -411.887162)
		(size 0.508)
		(drill 0.254)
		(layers "F.Cu" "B.Cu")
		(net "PRSNT_CABLE_SWB_B1_ISO_N")
	)
	(segment
		(start 195.4657 -374.536208)
		(end 278.707342 -374.536208)
		(width 0.10668)
		(layer "B.Cu")
		(net "PRSNT_CABLE_SWB_B1_ISO_N")
	)
	(segment
		(start 187.9346 -386.880608)
		(end 187.540646 -386.486654)
		(width 0.10668)
		(layer "B.Cu")
		(net "PRSNT_CABLE_SWB_B1_ISO_N")
	)
	(segment
		(start 281.221434 -377.0503)
		(end 281.221434 -384.902964)
		(width 0.10668)
		(layer "B.Cu")
		(net "PRSNT_CABLE_SWB_B1_ISO_N")
	)
	(segment
		(start 281.221434 -384.902964)
		(end 283.684472 -387.366002)
		(width 0.10668)
		(layer "B.Cu")
		(net "PRSNT_CABLE_SWB_B1_ISO_N")
	)
	(segment
		(start 187.540646 -386.486654)
		(end 187.540646 -382.461262)
		(width 0.10668)
		(layer "B.Cu")
		(net "PRSNT_CABLE_SWB_B1_ISO_N")
	)
	(segment
		(start 187.540646 -382.461262)
		(end 195.4657 -374.536208)
		(width 0.10668)
		(layer "B.Cu")
		(net "PRSNT_CABLE_SWB_B1_ISO_N")
	)
	(segment
		(start 287.669478 -411.004004)
		(end 288.470594 -411.004004)
		(width 0.10668)
		(layer "B.Cu")
		(net "PRSNT_CABLE_SWB_B1_ISO_N")
	)
	(segment
		(start 284.91942 -397.904208)
		(end 284.91942 -408.253946)
		(width 0.10668)
		(layer "B.Cu")
		(net "PRSNT_CABLE_SWB_B1_ISO_N")
	)
	(segment
		(start 283.684472 -392.652504)
		(end 283.16809 -393.168886)
		(width 0.10668)
		(layer "B.Cu")
		(net "PRSNT_CABLE_SWB_B1_ISO_N")
	)
	(segment
		(start 278.707342 -374.536208)
		(end 281.221434 -377.0503)
		(width 0.10668)
		(layer "B.Cu")
		(net "PRSNT_CABLE_SWB_B1_ISO_N")
	)
	(segment
		(start 283.16809 -396.152878)
		(end 284.91942 -397.904208)
		(width 0.10668)
		(layer "B.Cu")
		(net "PRSNT_CABLE_SWB_B1_ISO_N")
	)
	(segment
		(start 288.470594 -411.004004)
		(end 289.353752 -411.887162)
		(width 0.10668)
		(layer "B.Cu")
		(net "PRSNT_CABLE_SWB_B1_ISO_N")
	)
	(segment
		(start 284.91942 -408.253946)
		(end 287.669478 -411.004004)
		(width 0.10668)
		(layer "B.Cu")
		(net "PRSNT_CABLE_SWB_B1_ISO_N")
	)
	(segment
		(start 283.684472 -387.366002)
		(end 283.684472 -392.652504)
		(width 0.10668)
		(layer "B.Cu")
		(net "PRSNT_CABLE_SWB_B1_ISO_N")
	)
	(segment
		(start 283.16809 -393.168886)
		(end 283.16809 -396.152878)
		(width 0.10668)
		(layer "B.Cu")
		(net "PRSNT_CABLE_SWB_B1_ISO_N")
	)
	(segment
		(start 308.702456 -411.719776)
		(end 306.530756 -411.719776)
		(width 0.11684)
		(layer "In2.Cu")
		(net "PRSNT_CABLE_SWB_B1_ISO_N")
	)
	(segment
		(start 305.884326 -412.366206)
		(end 305.884326 -413.967676)
		(width 0.11684)
		(layer "In2.Cu")
		(net "PRSNT_CABLE_SWB_B1_ISO_N")
	)
	(segment
		(start 303.794922 -415.450528)
		(end 303.178718 -415.450528)
		(width 0.11684)
		(layer "In2.Cu")
		(net "PRSNT_CABLE_SWB_B1_ISO_N")
	)
	(segment
		(start 363.940344 -411.887162)
		(end 362.134912 -411.887162)
		(width 0.11684)
		(layer "In2.Cu")
		(net "PRSNT_CABLE_SWB_B1_ISO_N")
	)
	(segment
		(start 360.844084 -412.468314)
		(end 360.165904 -413.146494)
		(width 0.11684)
		(layer "In2.Cu")
		(net "PRSNT_CABLE_SWB_B1_ISO_N")
	)
	(segment
		(start 300.133004 -418.496242)
		(end 294.942006 -418.496242)
		(width 0.11684)
		(layer "In2.Cu")
		(net "PRSNT_CABLE_SWB_B1_ISO_N")
	)
	(segment
		(start 303.178718 -415.450528)
		(end 300.133004 -418.496242)
		(width 0.11684)
		(layer "In2.Cu")
		(net "PRSNT_CABLE_SWB_B1_ISO_N")
	)
	(segment
		(start 304.932334 -414.313116)
		(end 303.794922 -415.450528)
		(width 0.11684)
		(layer "In2.Cu")
		(net "PRSNT_CABLE_SWB_B1_ISO_N")
	)
	(segment
		(start 360.165904 -413.146494)
		(end 353.337114 -413.146494)
		(width 0.11684)
		(layer "In2.Cu")
		(net "PRSNT_CABLE_SWB_B1_ISO_N")
	)
	(segment
		(start 362.134912 -411.887162)
		(end 361.55376 -412.468314)
		(width 0.11684)
		(layer "In2.Cu")
		(net "PRSNT_CABLE_SWB_B1_ISO_N")
	)
	(segment
		(start 306.530756 -411.719776)
		(end 305.884326 -412.366206)
		(width 0.11684)
		(layer "In2.Cu")
		(net "PRSNT_CABLE_SWB_B1_ISO_N")
	)
	(segment
		(start 361.55376 -412.468314)
		(end 360.844084 -412.468314)
		(width 0.11684)
		(layer "In2.Cu")
		(net "PRSNT_CABLE_SWB_B1_ISO_N")
	)
	(segment
		(start 305.538886 -414.313116)
		(end 304.932334 -414.313116)
		(width 0.11684)
		(layer "In2.Cu")
		(net "PRSNT_CABLE_SWB_B1_ISO_N")
	)
	(segment
		(start 305.884326 -413.967676)
		(end 305.538886 -414.313116)
		(width 0.11684)
		(layer "In2.Cu")
		(net "PRSNT_CABLE_SWB_B1_ISO_N")
	)
	(segment
		(start 291.293296 -414.847532)
		(end 291.293296 -413.826706)
		(width 0.11684)
		(layer "In2.Cu")
		(net "PRSNT_CABLE_SWB_B1_ISO_N")
	)
	(segment
		(start 291.293296 -413.826706)
		(end 289.353752 -411.887162)
		(width 0.11684)
		(layer "In2.Cu")
		(net "PRSNT_CABLE_SWB_B1_ISO_N")
	)
	(segment
		(start 351.308416 -411.117796)
		(end 309.304436 -411.117796)
		(width 0.11684)
		(layer "In2.Cu")
		(net "PRSNT_CABLE_SWB_B1_ISO_N")
	)
	(segment
		(start 353.337114 -413.146494)
		(end 351.308416 -411.117796)
		(width 0.11684)
		(layer "In2.Cu")
		(net "PRSNT_CABLE_SWB_B1_ISO_N")
	)
	(segment
		(start 294.942006 -418.496242)
		(end 291.293296 -414.847532)
		(width 0.11684)
		(layer "In2.Cu")
		(net "PRSNT_CABLE_SWB_B1_ISO_N")
	)
	(segment
		(start 365.148876 -410.67863)
		(end 363.940344 -411.887162)
		(width 0.11684)
		(layer "In2.Cu")
		(net "PRSNT_CABLE_SWB_B1_ISO_N")
	)
	(segment
		(start 309.304436 -411.117796)
		(end 308.702456 -411.719776)
		(width 0.11684)
		(layer "In2.Cu")
		(net "PRSNT_CABLE_SWB_B1_ISO_N")
	)
	(segment
		(start 187.9346 -387.424676)
		(end 187.9346 -386.880608)
		(width 0.11684)
		(layer "In15.Cu")
		(net "PRSNT_CABLE_SWB_B1_ISO_N")
	)
	(segment
		(start 176.371758 -398.102582)
		(end 179.0954 -395.37894)
		(width 0.11684)
		(layer "In15.Cu")
		(net "PRSNT_CABLE_SWB_B1_ISO_N")
	)
	(segment
		(start 176.371758 -410.515308)
		(end 176.371758 -409.194254)
		(width 0.11684)
		(layer "In15.Cu")
		(net "PRSNT_CABLE_SWB_B1_ISO_N")
	)
	(segment
		(start 179.0954 -395.37894)
		(end 179.980336 -395.37894)
		(width 0.11684)
		(layer "In15.Cu")
		(net "PRSNT_CABLE_SWB_B1_ISO_N")
	)
	(segment
		(start 183.339232 -422.638982)
		(end 183.339232 -422.025318)
		(width 0.11684)
		(layer "In15.Cu")
		(net "PRSNT_CABLE_SWB_B1_ISO_N")
	)
	(segment
		(start 177.191924 -411.335474)
		(end 176.371758 -410.515308)
		(width 0.11684)
		(layer "In15.Cu")
		(net "PRSNT_CABLE_SWB_B1_ISO_N")
	)
	(segment
		(start 189.811406 -430.023778)
		(end 187.088272 -427.300644)
		(width 0.11684)
		(layer "In15.Cu")
		(net "PRSNT_CABLE_SWB_B1_ISO_N")
	)
	(segment
		(start 176.30394 -409.126436)
		(end 176.30394 -407.991564)
		(width 0.11684)
		(layer "In15.Cu")
		(net "PRSNT_CABLE_SWB_B1_ISO_N")
	)
	(segment
		(start 176.371758 -407.923746)
		(end 176.371758 -398.102582)
		(width 0.11684)
		(layer "In15.Cu")
		(net "PRSNT_CABLE_SWB_B1_ISO_N")
	)
	(segment
		(start 177.191924 -411.639004)
		(end 177.191924 -411.335474)
		(width 0.11684)
		(layer "In15.Cu")
		(net "PRSNT_CABLE_SWB_B1_ISO_N")
	)
	(segment
		(start 187.088272 -427.300644)
		(end 187.088272 -426.388022)
		(width 0.11684)
		(layer "In15.Cu")
		(net "PRSNT_CABLE_SWB_B1_ISO_N")
	)
	(segment
		(start 177.44186 -411.88894)
		(end 177.191924 -411.639004)
		(width 0.11684)
		(layer "In15.Cu")
		(net "PRSNT_CABLE_SWB_B1_ISO_N")
	)
	(segment
		(start 176.371758 -409.194254)
		(end 176.30394 -409.126436)
		(width 0.11684)
		(layer "In15.Cu")
		(net "PRSNT_CABLE_SWB_B1_ISO_N")
	)
	(segment
		(start 182.198518 -420.884604)
		(end 178.994308 -420.884604)
		(width 0.11684)
		(layer "In15.Cu")
		(net "PRSNT_CABLE_SWB_B1_ISO_N")
	)
	(segment
		(start 179.980336 -395.37894)
		(end 187.9346 -387.424676)
		(width 0.11684)
		(layer "In15.Cu")
		(net "PRSNT_CABLE_SWB_B1_ISO_N")
	)
	(segment
		(start 177.44186 -413.173672)
		(end 177.44186 -411.88894)
		(width 0.11684)
		(layer "In15.Cu")
		(net "PRSNT_CABLE_SWB_B1_ISO_N")
	)
	(segment
		(start 189.811406 -430.038002)
		(end 189.811406 -430.023778)
		(width 0.11684)
		(layer "In15.Cu")
		(net "PRSNT_CABLE_SWB_B1_ISO_N")
	)
	(segment
		(start 177.191924 -413.423608)
		(end 177.44186 -413.173672)
		(width 0.11684)
		(layer "In15.Cu")
		(net "PRSNT_CABLE_SWB_B1_ISO_N")
	)
	(segment
		(start 177.191924 -419.08222)
		(end 177.191924 -413.423608)
		(width 0.11684)
		(layer "In15.Cu")
		(net "PRSNT_CABLE_SWB_B1_ISO_N")
	)
	(segment
		(start 187.088272 -426.388022)
		(end 183.339232 -422.638982)
		(width 0.11684)
		(layer "In15.Cu")
		(net "PRSNT_CABLE_SWB_B1_ISO_N")
	)
	(segment
		(start 183.339232 -422.025318)
		(end 182.198518 -420.884604)
		(width 0.11684)
		(layer "In15.Cu")
		(net "PRSNT_CABLE_SWB_B1_ISO_N")
	)
	(segment
		(start 176.30394 -407.991564)
		(end 176.371758 -407.923746)
		(width 0.11684)
		(layer "In15.Cu")
		(net "PRSNT_CABLE_SWB_B1_ISO_N")
	)
	(segment
		(start 178.994308 -420.884604)
		(end 177.191924 -419.08222)
		(width 0.11684)
		(layer "In15.Cu")
		(net "PRSNT_CABLE_SWB_B1_ISO_N")
	)
	(segment
		(start 362.917994 -418.360098)
		(end 362.917994 -417.554664)
		(width 0.10668)
		(layer "F.Cu")
		(net "PRSNT_CABLE_SWB_B1")
	)
	(segment
		(start 362.984288 -416.19678)
		(end 362.984288 -416.679126)
		(width 0.10668)
		(layer "F.Cu")
		(net "PRSNT_CABLE_SWB_B1")
	)
	(segment
		(start 362.334302 -416.679126)
		(end 362.334302 -416.187636)
		(width 0.10668)
		(layer "F.Cu")
		(net "PRSNT_CABLE_SWB_B1")
	)
	(segment
		(start 362.984288 -417.48837)
		(end 362.984288 -416.679126)
		(width 0.10668)
		(layer "F.Cu")
		(net "PRSNT_CABLE_SWB_B1")
	)
	(segment
		(start 362.917994 -417.554664)
		(end 362.984288 -417.48837)
		(width 0.10668)
		(layer "F.Cu")
		(net "PRSNT_CABLE_SWB_B1")
	)
	(segment
		(start 362.857288 -416.06978)
		(end 362.984288 -416.19678)
		(width 0.10668)
		(layer "F.Cu")
		(net "PRSNT_CABLE_SWB_B1")
	)
	(segment
		(start 362.334302 -416.187636)
		(end 362.452158 -416.06978)
		(width 0.10668)
		(layer "F.Cu")
		(net "PRSNT_CABLE_SWB_B1")
	)
	(segment
		(start 362.452158 -416.06978)
		(end 362.857288 -416.06978)
		(width 0.10668)
		(layer "F.Cu")
		(net "PRSNT_CABLE_SWB_B1")
	)
	(via
		(at 362.984288 -417.48837)
		(size 0.508)
		(drill 0.254)
		(layers "F.Cu" "B.Cu")
		(net "PRSNT_CABLE_SWB_B1")
	)
	(segment
		(start 186.612276 -416.192716)
		(end 186.612276 -417.404804)
		(width 0.10668)
		(layer "F.Cu")
		(net "PRSNT_CABLE_GPU_B3_ISO_R1_N")
	)
	(segment
		(start 187.127642 -414.04413)
		(end 187.127642 -415.67735)
		(width 0.10668)
		(layer "F.Cu")
		(net "PRSNT_CABLE_GPU_B3_ISO_R1_N")
	)
	(segment
		(start 187.127642 -415.67735)
		(end 187.06719 -415.737802)
		(width 0.10668)
		(layer "F.Cu")
		(net "PRSNT_CABLE_GPU_B3_ISO_R1_N")
	)
	(segment
		(start 187.06719 -415.737802)
		(end 186.612276 -416.192716)
		(width 0.10668)
		(layer "F.Cu")
		(net "PRSNT_CABLE_GPU_B3_ISO_R1_N")
	)
	(via
		(at 187.06719 -415.737802)
		(size 0.762)
		(drill 0.381)
		(layers "F.Cu" "B.Cu")
		(net "PRSNT_CABLE_GPU_B3_ISO_R1_N")
	)
	(segment
		(start 187.127642 -413.24403)
		(end 187.127642 -412.480252)
		(width 0.10668)
		(layer "F.Cu")
		(net "PRSNT_CABLE_GPU_B3_ISO_N")
	)
	(segment
		(start 204.518768 -179.544218)
		(end 209.189574 -184.215024)
		(width 0.10668)
		(layer "F.Cu")
		(net "PRSNT_CABLE_GPU_B3_ISO_N")
	)
	(segment
		(start 194.157854 -171.949872)
		(end 201.7522 -179.544218)
		(width 0.10668)
		(layer "F.Cu")
		(net "PRSNT_CABLE_GPU_B3_ISO_N")
	)
	(segment
		(start 209.189574 -184.215024)
		(end 211.238592 -189.161674)
		(width 0.10668)
		(layer "F.Cu")
		(net "PRSNT_CABLE_GPU_B3_ISO_N")
	)
	(segment
		(start 201.7522 -179.544218)
		(end 204.518768 -179.544218)
		(width 0.10668)
		(layer "F.Cu")
		(net "PRSNT_CABLE_GPU_B3_ISO_N")
	)
	(segment
		(start 174.57674 -129.777998)
		(end 174.57674 -132.623814)
		(width 0.10668)
		(layer "F.Cu")
		(net "PRSNT_CABLE_GPU_B3_ISO_N")
	)
	(segment
		(start 209.573368 -196.852794)
		(end 208.989676 -196.852794)
		(width 0.10668)
		(layer "F.Cu")
		(net "PRSNT_CABLE_GPU_B3_ISO_N")
	)
	(segment
		(start 211.238592 -189.161674)
		(end 211.238592 -195.18757)
		(width 0.10668)
		(layer "F.Cu")
		(net "PRSNT_CABLE_GPU_B3_ISO_N")
	)
	(segment
		(start 211.238592 -195.18757)
		(end 209.573368 -196.852794)
		(width 0.10668)
		(layer "F.Cu")
		(net "PRSNT_CABLE_GPU_B3_ISO_N")
	)
	(via
		(at 167.393112 -434.351938)
		(size 0.508)
		(drill 0.254)
		(layers "F.Cu" "B.Cu")
		(net "PRSNT_CABLE_GPU_B3_ISO_N")
	)
	(via
		(at 208.989676 -196.852794)
		(size 0.508)
		(drill 0.254)
		(layers "F.Cu" "B.Cu")
		(net "PRSNT_CABLE_GPU_B3_ISO_N")
	)
	(via
		(at 194.157854 -171.949872)
		(size 0.508)
		(drill 0.254)
		(layers "F.Cu" "B.Cu")
		(net "PRSNT_CABLE_GPU_B3_ISO_N")
	)
	(via
		(at 174.57674 -132.623814)
		(size 0.508)
		(drill 0.254)
		(layers "F.Cu" "B.Cu")
		(net "PRSNT_CABLE_GPU_B3_ISO_N")
	)
	(via
		(at 187.127642 -412.480252)
		(size 0.508)
		(drill 0.254)
		(layers "F.Cu" "B.Cu")
		(net "PRSNT_CABLE_GPU_B3_ISO_N")
	)
	(segment
		(start 168.09466 -433.65039)
		(end 167.393112 -434.351938)
		(width 0.10668)
		(layer "B.Cu")
		(net "PRSNT_CABLE_GPU_B3_ISO_N")
	)
	(segment
		(start 166.552372 -435.53253)
		(end 166.777162 -435.53253)
		(width 0.10668)
		(layer "B.Cu")
		(net "PRSNT_CABLE_GPU_B3_ISO_N")
	)
	(segment
		(start 185.33491 -430.793398)
		(end 184.450736 -430.793398)
		(width 0.10668)
		(layer "B.Cu")
		(net "PRSNT_CABLE_GPU_B3_ISO_N")
	)
	(segment
		(start 190.738506 -424.722544)
		(end 190.738506 -426.851064)
		(width 0.10668)
		(layer "B.Cu")
		(net "PRSNT_CABLE_GPU_B3_ISO_N")
	)
	(segment
		(start 190.3603 -431.499264)
		(end 189.134242 -432.725322)
		(width 0.10668)
		(layer "B.Cu")
		(net "PRSNT_CABLE_GPU_B3_ISO_N")
	)
	(segment
		(start 174.57674 -149.47011)
		(end 174.57674 -132.623814)
		(width 0.10668)
		(layer "B.Cu")
		(net "PRSNT_CABLE_GPU_B3_ISO_N")
	)
	(segment
		(start 163.387532 -435.53253)
		(end 164.403532 -435.53253)
		(width 0.10668)
		(layer "B.Cu")
		(net "PRSNT_CABLE_GPU_B3_ISO_N")
	)
	(segment
		(start 194.157854 -171.949872)
		(end 193.549524 -171.341542)
		(width 0.10668)
		(layer "B.Cu")
		(net "PRSNT_CABLE_GPU_B3_ISO_N")
	)
	(segment
		(start 180.392832 -155.286202)
		(end 174.57674 -149.47011)
		(width 0.10668)
		(layer "B.Cu")
		(net "PRSNT_CABLE_GPU_B3_ISO_N")
	)
	(segment
		(start 167.393112 -434.91658)
		(end 167.393112 -434.351938)
		(width 0.10668)
		(layer "B.Cu")
		(net "PRSNT_CABLE_GPU_B3_ISO_N")
	)
	(segment
		(start 191.596772 -169.825416)
		(end 190.731394 -169.825416)
		(width 0.10668)
		(layer "B.Cu")
		(net "PRSNT_CABLE_GPU_B3_ISO_N")
	)
	(segment
		(start 187.127642 -412.480252)
		(end 187.127642 -412.490666)
		(width 0.10668)
		(layer "B.Cu")
		(net "PRSNT_CABLE_GPU_B3_ISO_N")
	)
	(segment
		(start 166.777162 -435.53253)
		(end 167.393112 -434.91658)
		(width 0.10668)
		(layer "B.Cu")
		(net "PRSNT_CABLE_GPU_B3_ISO_N")
	)
	(segment
		(start 175.030638 -429.378618)
		(end 170.758866 -433.65039)
		(width 0.10668)
		(layer "B.Cu")
		(net "PRSNT_CABLE_GPU_B3_ISO_N")
	)
	(segment
		(start 187.266834 -432.725322)
		(end 185.33491 -430.793398)
		(width 0.10668)
		(layer "B.Cu")
		(net "PRSNT_CABLE_GPU_B3_ISO_N")
	)
	(segment
		(start 193.549524 -171.341542)
		(end 193.112898 -171.341542)
		(width 0.10668)
		(layer "B.Cu")
		(net "PRSNT_CABLE_GPU_B3_ISO_N")
	)
	(segment
		(start 165.419532 -435.53253)
		(end 166.552372 -435.53253)
		(width 0.10668)
		(layer "B.Cu")
		(net "PRSNT_CABLE_GPU_B3_ISO_N")
	)
	(segment
		(start 190.283846 -424.267884)
		(end 190.738506 -424.722544)
		(width 0.10668)
		(layer "B.Cu")
		(net "PRSNT_CABLE_GPU_B3_ISO_N")
	)
	(segment
		(start 189.733428 -413.250126)
		(end 189.733428 -417.684204)
		(width 0.10668)
		(layer "B.Cu")
		(net "PRSNT_CABLE_GPU_B3_ISO_N")
	)
	(segment
		(start 193.112898 -171.341542)
		(end 191.596772 -169.825416)
		(width 0.10668)
		(layer "B.Cu")
		(net "PRSNT_CABLE_GPU_B3_ISO_N")
	)
	(segment
		(start 190.731394 -169.825416)
		(end 182.221378 -161.3154)
		(width 0.10668)
		(layer "B.Cu")
		(net "PRSNT_CABLE_GPU_B3_ISO_N")
	)
	(segment
		(start 190.738506 -426.851064)
		(end 190.3603 -427.22927)
		(width 0.10668)
		(layer "B.Cu")
		(net "PRSNT_CABLE_GPU_B3_ISO_N")
	)
	(segment
		(start 182.221378 -161.3154)
		(end 182.221378 -160.706308)
		(width 0.10668)
		(layer "B.Cu")
		(net "PRSNT_CABLE_GPU_B3_ISO_N")
	)
	(segment
		(start 187.127642 -412.490666)
		(end 187.409582 -412.772606)
		(width 0.10668)
		(layer "B.Cu")
		(net "PRSNT_CABLE_GPU_B3_ISO_N")
	)
	(segment
		(start 183.035956 -429.378618)
		(end 175.030638 -429.378618)
		(width 0.10668)
		(layer "B.Cu")
		(net "PRSNT_CABLE_GPU_B3_ISO_N")
	)
	(segment
		(start 170.758866 -433.65039)
		(end 168.09466 -433.65039)
		(width 0.10668)
		(layer "B.Cu")
		(net "PRSNT_CABLE_GPU_B3_ISO_N")
	)
	(segment
		(start 184.450736 -430.793398)
		(end 183.035956 -429.378618)
		(width 0.10668)
		(layer "B.Cu")
		(net "PRSNT_CABLE_GPU_B3_ISO_N")
	)
	(segment
		(start 190.283846 -418.234622)
		(end 190.283846 -424.267884)
		(width 0.10668)
		(layer "B.Cu")
		(net "PRSNT_CABLE_GPU_B3_ISO_N")
	)
	(segment
		(start 189.134242 -432.725322)
		(end 187.266834 -432.725322)
		(width 0.10668)
		(layer "B.Cu")
		(net "PRSNT_CABLE_GPU_B3_ISO_N")
	)
	(segment
		(start 189.255908 -412.772606)
		(end 189.733428 -413.250126)
		(width 0.10668)
		(layer "B.Cu")
		(net "PRSNT_CABLE_GPU_B3_ISO_N")
	)
	(segment
		(start 190.3603 -427.22927)
		(end 190.3603 -431.499264)
		(width 0.10668)
		(layer "B.Cu")
		(net "PRSNT_CABLE_GPU_B3_ISO_N")
	)
	(segment
		(start 180.392832 -158.877762)
		(end 180.392832 -155.286202)
		(width 0.10668)
		(layer "B.Cu")
		(net "PRSNT_CABLE_GPU_B3_ISO_N")
	)
	(segment
		(start 165.419532 -435.53253)
		(end 164.403532 -435.53253)
		(width 0.10668)
		(layer "B.Cu")
		(net "PRSNT_CABLE_GPU_B3_ISO_N")
	)
	(segment
		(start 182.221378 -160.706308)
		(end 180.392832 -158.877762)
		(width 0.10668)
		(layer "B.Cu")
		(net "PRSNT_CABLE_GPU_B3_ISO_N")
	)
	(segment
		(start 189.733428 -417.684204)
		(end 190.283846 -418.234622)
		(width 0.10668)
		(layer "B.Cu")
		(net "PRSNT_CABLE_GPU_B3_ISO_N")
	)
	(segment
		(start 187.409582 -412.772606)
		(end 189.255908 -412.772606)
		(width 0.10668)
		(layer "B.Cu")
		(net "PRSNT_CABLE_GPU_B3_ISO_N")
	)
	(segment
		(start 171.661328 -421.735758)
		(end 171.661328 -425.671742)
		(width 0.11684)
		(layer "In6.Cu")
		(net "PRSNT_CABLE_GPU_B3_ISO_N")
	)
	(segment
		(start 175.332898 -400.492976)
		(end 176.191926 -401.352004)
		(width 0.11684)
		(layer "In6.Cu")
		(net "PRSNT_CABLE_GPU_B3_ISO_N")
	)
	(segment
		(start 171.661328 -425.671742)
		(end 168.111932 -429.221138)
		(width 0.11684)
		(layer "In6.Cu")
		(net "PRSNT_CABLE_GPU_B3_ISO_N")
	)
	(segment
		(start 191.315594 -374.453912)
		(end 189.739016 -374.453912)
		(width 0.11684)
		(layer "In6.Cu")
		(net "PRSNT_CABLE_GPU_B3_ISO_N")
	)
	(segment
		(start 208.989676 -196.852794)
		(end 209.429096 -196.852794)
		(width 0.11684)
		(layer "In6.Cu")
		(net "PRSNT_CABLE_GPU_B3_ISO_N")
	)
	(segment
		(start 176.191926 -407.335482)
		(end 172.05325 -411.474158)
		(width 0.11684)
		(layer "In6.Cu")
		(net "PRSNT_CABLE_GPU_B3_ISO_N")
	)
	(segment
		(start 180.754782 -383.438146)
		(end 180.754782 -385.641596)
		(width 0.11684)
		(layer "In6.Cu")
		(net "PRSNT_CABLE_GPU_B3_ISO_N")
	)
	(segment
		(start 176.191926 -401.352004)
		(end 176.191926 -407.335482)
		(width 0.11684)
		(layer "In6.Cu")
		(net "PRSNT_CABLE_GPU_B3_ISO_N")
	)
	(segment
		(start 168.111932 -433.633118)
		(end 167.393112 -434.351938)
		(width 0.11684)
		(layer "In6.Cu")
		(net "PRSNT_CABLE_GPU_B3_ISO_N")
	)
	(segment
		(start 180.754782 -385.641596)
		(end 175.332898 -391.06348)
		(width 0.11684)
		(layer "In6.Cu")
		(net "PRSNT_CABLE_GPU_B3_ISO_N")
	)
	(segment
		(start 209.429096 -196.852794)
		(end 215.450928 -202.874626)
		(width 0.11684)
		(layer "In6.Cu")
		(net "PRSNT_CABLE_GPU_B3_ISO_N")
	)
	(segment
		(start 172.05325 -411.474158)
		(end 172.05325 -421.343836)
		(width 0.11684)
		(layer "In6.Cu")
		(net "PRSNT_CABLE_GPU_B3_ISO_N")
	)
	(segment
		(start 227.08362 -331.84465)
		(end 227.08362 -363.030262)
		(width 0.11684)
		(layer "In6.Cu")
		(net "PRSNT_CABLE_GPU_B3_ISO_N")
	)
	(segment
		(start 193.058288 -372.711218)
		(end 191.315594 -374.453912)
		(width 0.11684)
		(layer "In6.Cu")
		(net "PRSNT_CABLE_GPU_B3_ISO_N")
	)
	(segment
		(start 172.05325 -421.343836)
		(end 171.661328 -421.735758)
		(width 0.11684)
		(layer "In6.Cu")
		(net "PRSNT_CABLE_GPU_B3_ISO_N")
	)
	(segment
		(start 215.450928 -320.211958)
		(end 227.08362 -331.84465)
		(width 0.11684)
		(layer "In6.Cu")
		(net "PRSNT_CABLE_GPU_B3_ISO_N")
	)
	(segment
		(start 226.098608 -364.015274)
		(end 226.098608 -366.923574)
		(width 0.11684)
		(layer "In6.Cu")
		(net "PRSNT_CABLE_GPU_B3_ISO_N")
	)
	(segment
		(start 220.310964 -372.711218)
		(end 193.058288 -372.711218)
		(width 0.11684)
		(layer "In6.Cu")
		(net "PRSNT_CABLE_GPU_B3_ISO_N")
	)
	(segment
		(start 168.111932 -429.221138)
		(end 168.111932 -433.633118)
		(width 0.11684)
		(layer "In6.Cu")
		(net "PRSNT_CABLE_GPU_B3_ISO_N")
	)
	(segment
		(start 215.450928 -202.874626)
		(end 215.450928 -320.211958)
		(width 0.11684)
		(layer "In6.Cu")
		(net "PRSNT_CABLE_GPU_B3_ISO_N")
	)
	(segment
		(start 226.098608 -366.923574)
		(end 220.310964 -372.711218)
		(width 0.11684)
		(layer "In6.Cu")
		(net "PRSNT_CABLE_GPU_B3_ISO_N")
	)
	(segment
		(start 189.739016 -374.453912)
		(end 180.754782 -383.438146)
		(width 0.11684)
		(layer "In6.Cu")
		(net "PRSNT_CABLE_GPU_B3_ISO_N")
	)
	(segment
		(start 175.332898 -391.06348)
		(end 175.332898 -400.492976)
		(width 0.11684)
		(layer "In6.Cu")
		(net "PRSNT_CABLE_GPU_B3_ISO_N")
	)
	(segment
		(start 227.08362 -363.030262)
		(end 226.098608 -364.015274)
		(width 0.11684)
		(layer "In6.Cu")
		(net "PRSNT_CABLE_GPU_B3_ISO_N")
	)
	(segment
		(start 362.475018 -409.947364)
		(end 363.280452 -410.752798)
		(width 0.10668)
		(layer "F.Cu")
		(net "PRSNT_CABLE_GPU_A3_N")
	)
	(segment
		(start 362.425488 -408.915616)
		(end 362.425488 -408.088846)
		(width 0.10668)
		(layer "F.Cu")
		(net "PRSNT_CABLE_GPU_A3_N")
	)
	(segment
		(start 362.425488 -409.947364)
		(end 362.475018 -409.947364)
		(width 0.10668)
		(layer "F.Cu")
		(net "PRSNT_CABLE_GPU_A3_N")
	)
	(segment
		(start 363.123734 -407.3906)
		(end 363.123734 -406.452324)
		(width 0.10668)
		(layer "F.Cu")
		(net "PRSNT_CABLE_GPU_A3_N")
	)
	(segment
		(start 363.123734 -406.452324)
		(end 363.403642 -406.172416)
		(width 0.10668)
		(layer "F.Cu")
		(net "PRSNT_CABLE_GPU_A3_N")
	)
	(segment
		(start 363.403642 -406.172416)
		(end 363.994446 -406.172416)
		(width 0.10668)
		(layer "F.Cu")
		(net "PRSNT_CABLE_GPU_A3_N")
	)
	(segment
		(start 362.425488 -408.088846)
		(end 363.123734 -407.3906)
		(width 0.10668)
		(layer "F.Cu")
		(net "PRSNT_CABLE_GPU_A3_N")
	)
	(segment
		(start 362.425488 -409.947364)
		(end 362.425488 -408.915616)
		(width 0.10668)
		(layer "F.Cu")
		(net "PRSNT_CABLE_GPU_A3_N")
	)
	(via
		(at 354.782882 -410.76118)
		(size 0.508)
		(drill 0.254)
		(layers "F.Cu" "B.Cu")
		(net "PRSNT_CABLE_GPU_A3_N")
	)
	(via
		(at 355.316282 -426.806614)
		(size 0.508)
		(drill 0.254)
		(layers "F.Cu" "B.Cu")
		(net "PRSNT_CABLE_GPU_A3_N")
	)
	(via
		(at 363.280452 -410.752798)
		(size 0.508)
		(drill 0.254)
		(layers "F.Cu" "B.Cu")
		(net "PRSNT_CABLE_GPU_A3_N")
	)
	(segment
		(start 361.358942 -411.128464)
		(end 360.33837 -411.128464)
		(width 0.11684)
		(layer "In2.Cu")
		(net "PRSNT_CABLE_GPU_A3_N")
	)
	(segment
		(start 349.246444 -425.917614)
		(end 349.658178 -425.917614)
		(width 0.11684)
		(layer "In2.Cu")
		(net "PRSNT_CABLE_GPU_A3_N")
	)
	(segment
		(start 328.649584 -424.495722)
		(end 329.153774 -423.991532)
		(width 0.11684)
		(layer "In2.Cu")
		(net "PRSNT_CABLE_GPU_A3_N")
	)
	(segment
		(start 361.410758 -411.18028)
		(end 361.358942 -411.128464)
		(width 0.11684)
		(layer "In2.Cu")
		(net "PRSNT_CABLE_GPU_A3_N")
	)
	(segment
		(start 357.04399 -412.506414)
		(end 355.298756 -410.76118)
		(width 0.11684)
		(layer "In2.Cu")
		(net "PRSNT_CABLE_GPU_A3_N")
	)
	(segment
		(start 347.320362 -423.991532)
		(end 349.246444 -425.917614)
		(width 0.11684)
		(layer "In2.Cu")
		(net "PRSNT_CABLE_GPU_A3_N")
	)
	(segment
		(start 355.298756 -410.76118)
		(end 354.782882 -410.76118)
		(width 0.11684)
		(layer "In2.Cu")
		(net "PRSNT_CABLE_GPU_A3_N")
	)
	(segment
		(start 328.649584 -424.689778)
		(end 328.649584 -424.495722)
		(width 0.11684)
		(layer "In2.Cu")
		(net "PRSNT_CABLE_GPU_A3_N")
	)
	(segment
		(start 360.33837 -411.128464)
		(end 358.96042 -412.506414)
		(width 0.11684)
		(layer "In2.Cu")
		(net "PRSNT_CABLE_GPU_A3_N")
	)
	(segment
		(start 362.85297 -411.18028)
		(end 361.410758 -411.18028)
		(width 0.11684)
		(layer "In2.Cu")
		(net "PRSNT_CABLE_GPU_A3_N")
	)
	(segment
		(start 363.280452 -410.752798)
		(end 362.85297 -411.18028)
		(width 0.11684)
		(layer "In2.Cu")
		(net "PRSNT_CABLE_GPU_A3_N")
	)
	(segment
		(start 358.96042 -412.506414)
		(end 357.04399 -412.506414)
		(width 0.11684)
		(layer "In2.Cu")
		(net "PRSNT_CABLE_GPU_A3_N")
	)
	(segment
		(start 329.153774 -423.991532)
		(end 347.320362 -423.991532)
		(width 0.11684)
		(layer "In2.Cu")
		(net "PRSNT_CABLE_GPU_A3_N")
	)
	(segment
		(start 349.658178 -425.917614)
		(end 350.547178 -426.806614)
		(width 0.11684)
		(layer "In2.Cu")
		(net "PRSNT_CABLE_GPU_A3_N")
	)
	(segment
		(start 350.547178 -426.806614)
		(end 355.316282 -426.806614)
		(width 0.11684)
		(layer "In2.Cu")
		(net "PRSNT_CABLE_GPU_A3_N")
	)
	(segment
		(start 354.384102 -422.059354)
		(end 354.384102 -411.15996)
		(width 0.11684)
		(layer "In4.Cu")
		(net "PRSNT_CABLE_GPU_A3_N")
	)
	(segment
		(start 355.316282 -422.991534)
		(end 354.384102 -422.059354)
		(width 0.11684)
		(layer "In4.Cu")
		(net "PRSNT_CABLE_GPU_A3_N")
	)
	(segment
		(start 355.316282 -426.806614)
		(end 355.316282 -422.991534)
		(width 0.11684)
		(layer "In4.Cu")
		(net "PRSNT_CABLE_GPU_A3_N")
	)
	(segment
		(start 354.384102 -411.15996)
		(end 354.782882 -410.76118)
		(width 0.11684)
		(layer "In4.Cu")
		(net "PRSNT_CABLE_GPU_A3_N")
	)
	(segment
		(start 181.688486 -425.835826)
		(end 181.688486 -425.949872)
		(width 0.10668)
		(layer "F.Cu")
		(net "PRSNT_CABLE_GPU_A3_ISO_R_N")
	)
	(segment
		(start 183.362092 -423.254932)
		(end 183.362092 -423.992802)
		(width 0.10668)
		(layer "F.Cu")
		(net "PRSNT_CABLE_GPU_A3_ISO_R_N")
	)
	(segment
		(start 183.362092 -423.992802)
		(end 182.945786 -424.409108)
		(width 0.10668)
		(layer "F.Cu")
		(net "PRSNT_CABLE_GPU_A3_ISO_R_N")
	)
	(segment
		(start 182.945786 -424.578526)
		(end 182.598314 -424.925998)
		(width 0.10668)
		(layer "F.Cu")
		(net "PRSNT_CABLE_GPU_A3_ISO_R_N")
	)
	(segment
		(start 182.598314 -424.925998)
		(end 181.688486 -425.835826)
		(width 0.10668)
		(layer "F.Cu")
		(net "PRSNT_CABLE_GPU_A3_ISO_R_N")
	)
	(segment
		(start 182.945786 -424.409108)
		(end 182.945786 -424.578526)
		(width 0.10668)
		(layer "F.Cu")
		(net "PRSNT_CABLE_GPU_A3_ISO_R_N")
	)
	(via
		(at 182.598314 -424.925998)
		(size 0.762)
		(drill 0.381)
		(layers "F.Cu" "B.Cu")
		(net "PRSNT_CABLE_GPU_A3_ISO_R_N")
	)
	(segment
		(start 364.587536 -406.822402)
		(end 363.994446 -406.822402)
		(width 0.10668)
		(layer "F.Cu")
		(net "PRSNT_CABLE_GPU_A3_ISO_N")
	)
	(segment
		(start 364.714536 -406.949402)
		(end 364.587536 -406.822402)
		(width 0.10668)
		(layer "F.Cu")
		(net "PRSNT_CABLE_GPU_A3_ISO_N")
	)
	(segment
		(start 364.714536 -408.931364)
		(end 364.714536 -406.949402)
		(width 0.10668)
		(layer "F.Cu")
		(net "PRSNT_CABLE_GPU_A3_ISO_N")
	)
	(segment
		(start 365.059976 -409.931616)
		(end 364.714536 -409.931616)
		(width 0.10668)
		(layer "F.Cu")
		(net "PRSNT_CABLE_GPU_A3_ISO_N")
	)
	(segment
		(start 181.688486 -426.749972)
		(end 181.994302 -426.749972)
		(width 0.10668)
		(layer "F.Cu")
		(net "PRSNT_CABLE_GPU_A3_ISO_N")
	)
	(segment
		(start 181.994302 -426.749972)
		(end 182.655718 -427.411388)
		(width 0.10668)
		(layer "F.Cu")
		(net "PRSNT_CABLE_GPU_A3_ISO_N")
	)
	(segment
		(start 364.714536 -409.931616)
		(end 364.714536 -408.931364)
		(width 0.10668)
		(layer "F.Cu")
		(net "PRSNT_CABLE_GPU_A3_ISO_N")
	)
	(segment
		(start 365.39551 -409.596082)
		(end 365.059976 -409.931616)
		(width 0.10668)
		(layer "F.Cu")
		(net "PRSNT_CABLE_GPU_A3_ISO_N")
	)
	(via
		(at 289.342068 -411.190186)
		(size 0.508)
		(drill 0.254)
		(layers "F.Cu" "B.Cu")
		(net "PRSNT_CABLE_GPU_A3_ISO_N")
	)
	(via
		(at 182.655718 -427.411388)
		(size 0.508)
		(drill 0.254)
		(layers "F.Cu" "B.Cu")
		(net "PRSNT_CABLE_GPU_A3_ISO_N")
	)
	(via
		(at 187.337954 -387.098032)
		(size 0.508)
		(drill 0.254)
		(layers "F.Cu" "B.Cu")
		(net "PRSNT_CABLE_GPU_A3_ISO_N")
	)
	(via
		(at 365.39551 -409.596082)
		(size 0.508)
		(drill 0.254)
		(layers "F.Cu" "B.Cu")
		(net "PRSNT_CABLE_GPU_A3_ISO_N")
	)
	(segment
		(start 283.932122 -387.215634)
		(end 283.932122 -392.777218)
		(width 0.10668)
		(layer "B.Cu")
		(net "PRSNT_CABLE_GPU_A3_ISO_N")
	)
	(segment
		(start 253.07671 -374.28805)
		(end 253.245366 -374.282208)
		(width 0.10668)
		(layer "B.Cu")
		(net "PRSNT_CABLE_GPU_A3_ISO_N")
	)
	(segment
		(start 187.317126 -382.368552)
		(end 195.397628 -374.28805)
		(width 0.10668)
		(layer "B.Cu")
		(net "PRSNT_CABLE_GPU_A3_ISO_N")
	)
	(segment
		(start 285.14294 -397.811498)
		(end 285.14294 -408.161236)
		(width 0.10668)
		(layer "B.Cu")
		(net "PRSNT_CABLE_GPU_A3_ISO_N")
	)
	(segment
		(start 281.444954 -384.728466)
		(end 283.932122 -387.215634)
		(width 0.10668)
		(layer "B.Cu")
		(net "PRSNT_CABLE_GPU_A3_ISO_N")
	)
	(segment
		(start 278.769572 -374.282208)
		(end 281.444954 -376.95759)
		(width 0.10668)
		(layer "B.Cu")
		(net "PRSNT_CABLE_GPU_A3_ISO_N")
	)
	(segment
		(start 287.762188 -410.780484)
		(end 288.932366 -410.780484)
		(width 0.10668)
		(layer "B.Cu")
		(net "PRSNT_CABLE_GPU_A3_ISO_N")
	)
	(segment
		(start 283.932122 -392.777218)
		(end 283.473906 -393.235434)
		(width 0.10668)
		(layer "B.Cu")
		(net "PRSNT_CABLE_GPU_A3_ISO_N")
	)
	(segment
		(start 187.317126 -387.077204)
		(end 187.317126 -382.368552)
		(width 0.10668)
		(layer "B.Cu")
		(net "PRSNT_CABLE_GPU_A3_ISO_N")
	)
	(segment
		(start 253.245366 -374.282208)
		(end 278.769572 -374.282208)
		(width 0.10668)
		(layer "B.Cu")
		(net "PRSNT_CABLE_GPU_A3_ISO_N")
	)
	(segment
		(start 281.444954 -376.95759)
		(end 281.444954 -384.728466)
		(width 0.10668)
		(layer "B.Cu")
		(net "PRSNT_CABLE_GPU_A3_ISO_N")
	)
	(segment
		(start 283.473906 -393.235434)
		(end 283.473906 -396.142464)
		(width 0.10668)
		(layer "B.Cu")
		(net "PRSNT_CABLE_GPU_A3_ISO_N")
	)
	(segment
		(start 195.397628 -374.28805)
		(end 253.07671 -374.28805)
		(width 0.10668)
		(layer "B.Cu")
		(net "PRSNT_CABLE_GPU_A3_ISO_N")
	)
	(segment
		(start 285.14294 -408.161236)
		(end 287.762188 -410.780484)
		(width 0.10668)
		(layer "B.Cu")
		(net "PRSNT_CABLE_GPU_A3_ISO_N")
	)
	(segment
		(start 187.337954 -387.098032)
		(end 187.317126 -387.077204)
		(width 0.10668)
		(layer "B.Cu")
		(net "PRSNT_CABLE_GPU_A3_ISO_N")
	)
	(segment
		(start 283.473906 -396.142464)
		(end 285.14294 -397.811498)
		(width 0.10668)
		(layer "B.Cu")
		(net "PRSNT_CABLE_GPU_A3_ISO_N")
	)
	(segment
		(start 288.932366 -410.780484)
		(end 289.342068 -411.190186)
		(width 0.10668)
		(layer "B.Cu")
		(net "PRSNT_CABLE_GPU_A3_ISO_N")
	)
	(segment
		(start 295.094152 -418.176202)
		(end 291.786564 -414.868614)
		(width 0.11684)
		(layer "In2.Cu")
		(net "PRSNT_CABLE_GPU_A3_ISO_N")
	)
	(segment
		(start 361.226354 -411.448504)
		(end 360.470958 -411.448504)
		(width 0.11684)
		(layer "In2.Cu")
		(net "PRSNT_CABLE_GPU_A3_ISO_N")
	)
	(segment
		(start 353.691698 -412.826454)
		(end 351.089976 -410.224732)
		(width 0.11684)
		(layer "In2.Cu")
		(net "PRSNT_CABLE_GPU_A3_ISO_N")
	)
	(segment
		(start 309.51297 -410.224732)
		(end 308.753002 -410.9847)
		(width 0.11684)
		(layer "In2.Cu")
		(net "PRSNT_CABLE_GPU_A3_ISO_N")
	)
	(segment
		(start 302.779938 -415.329878)
		(end 299.933614 -418.176202)
		(width 0.11684)
		(layer "In2.Cu")
		(net "PRSNT_CABLE_GPU_A3_ISO_N")
	)
	(segment
		(start 363.779562 -410.911294)
		(end 363.190536 -411.50032)
		(width 0.11684)
		(layer "In2.Cu")
		(net "PRSNT_CABLE_GPU_A3_ISO_N")
	)
	(segment
		(start 299.933614 -418.176202)
		(end 295.094152 -418.176202)
		(width 0.11684)
		(layer "In2.Cu")
		(net "PRSNT_CABLE_GPU_A3_ISO_N")
	)
	(segment
		(start 363.190536 -411.50032)
		(end 361.27817 -411.50032)
		(width 0.11684)
		(layer "In2.Cu")
		(net "PRSNT_CABLE_GPU_A3_ISO_N")
	)
	(segment
		(start 365.39551 -409.596082)
		(end 364.685834 -409.596082)
		(width 0.11684)
		(layer "In2.Cu")
		(net "PRSNT_CABLE_GPU_A3_ISO_N")
	)
	(segment
		(start 303.33442 -410.9847)
		(end 302.779938 -411.539182)
		(width 0.11684)
		(layer "In2.Cu")
		(net "PRSNT_CABLE_GPU_A3_ISO_N")
	)
	(segment
		(start 308.753002 -410.9847)
		(end 303.33442 -410.9847)
		(width 0.11684)
		(layer "In2.Cu")
		(net "PRSNT_CABLE_GPU_A3_ISO_N")
	)
	(segment
		(start 291.786564 -413.634682)
		(end 289.342068 -411.190186)
		(width 0.11684)
		(layer "In2.Cu")
		(net "PRSNT_CABLE_GPU_A3_ISO_N")
	)
	(segment
		(start 360.470958 -411.448504)
		(end 359.093008 -412.826454)
		(width 0.11684)
		(layer "In2.Cu")
		(net "PRSNT_CABLE_GPU_A3_ISO_N")
	)
	(segment
		(start 361.27817 -411.50032)
		(end 361.226354 -411.448504)
		(width 0.11684)
		(layer "In2.Cu")
		(net "PRSNT_CABLE_GPU_A3_ISO_N")
	)
	(segment
		(start 351.089976 -410.224732)
		(end 309.51297 -410.224732)
		(width 0.11684)
		(layer "In2.Cu")
		(net "PRSNT_CABLE_GPU_A3_ISO_N")
	)
	(segment
		(start 302.779938 -411.539182)
		(end 302.779938 -415.329878)
		(width 0.11684)
		(layer "In2.Cu")
		(net "PRSNT_CABLE_GPU_A3_ISO_N")
	)
	(segment
		(start 291.786564 -414.868614)
		(end 291.786564 -413.634682)
		(width 0.11684)
		(layer "In2.Cu")
		(net "PRSNT_CABLE_GPU_A3_ISO_N")
	)
	(segment
		(start 363.779562 -410.502354)
		(end 363.779562 -410.911294)
		(width 0.11684)
		(layer "In2.Cu")
		(net "PRSNT_CABLE_GPU_A3_ISO_N")
	)
	(segment
		(start 364.685834 -409.596082)
		(end 363.779562 -410.502354)
		(width 0.11684)
		(layer "In2.Cu")
		(net "PRSNT_CABLE_GPU_A3_ISO_N")
	)
	(segment
		(start 359.093008 -412.826454)
		(end 353.691698 -412.826454)
		(width 0.11684)
		(layer "In2.Cu")
		(net "PRSNT_CABLE_GPU_A3_ISO_N")
	)
	(segment
		(start 176.863502 -419.231572)
		(end 178.844956 -421.213026)
		(width 0.11684)
		(layer "In15.Cu")
		(net "PRSNT_CABLE_GPU_A3_ISO_N")
	)
	(segment
		(start 176.682908 -411.309566)
		(end 176.682908 -411.711902)
		(width 0.11684)
		(layer "In15.Cu")
		(net "PRSNT_CABLE_GPU_A3_ISO_N")
	)
	(segment
		(start 187.337954 -387.56844)
		(end 179.847494 -395.0589)
		(width 0.11684)
		(layer "In15.Cu")
		(net "PRSNT_CABLE_GPU_A3_ISO_N")
	)
	(segment
		(start 187.337954 -387.098032)
		(end 187.337954 -387.56844)
		(width 0.11684)
		(layer "In15.Cu")
		(net "PRSNT_CABLE_GPU_A3_ISO_N")
	)
	(segment
		(start 175.961294 -410.587952)
		(end 176.682908 -411.309566)
		(width 0.11684)
		(layer "In15.Cu")
		(net "PRSNT_CABLE_GPU_A3_ISO_N")
	)
	(segment
		(start 182.062374 -421.213026)
		(end 182.655718 -421.80637)
		(width 0.11684)
		(layer "In15.Cu")
		(net "PRSNT_CABLE_GPU_A3_ISO_N")
	)
	(segment
		(start 179.847494 -395.0589)
		(end 177.655728 -395.0589)
		(width 0.11684)
		(layer "In15.Cu")
		(net "PRSNT_CABLE_GPU_A3_ISO_N")
	)
	(segment
		(start 176.756568 -395.95806)
		(end 176.756568 -396.206218)
		(width 0.11684)
		(layer "In15.Cu")
		(net "PRSNT_CABLE_GPU_A3_ISO_N")
	)
	(segment
		(start 178.844956 -421.213026)
		(end 182.062374 -421.213026)
		(width 0.11684)
		(layer "In15.Cu")
		(net "PRSNT_CABLE_GPU_A3_ISO_N")
	)
	(segment
		(start 176.229264 -412.165546)
		(end 176.229264 -412.643828)
		(width 0.11684)
		(layer "In15.Cu")
		(net "PRSNT_CABLE_GPU_A3_ISO_N")
	)
	(segment
		(start 176.756568 -396.206218)
		(end 175.961294 -397.001492)
		(width 0.11684)
		(layer "In15.Cu")
		(net "PRSNT_CABLE_GPU_A3_ISO_N")
	)
	(segment
		(start 176.863502 -413.278066)
		(end 176.863502 -419.231572)
		(width 0.11684)
		(layer "In15.Cu")
		(net "PRSNT_CABLE_GPU_A3_ISO_N")
	)
	(segment
		(start 176.682908 -411.711902)
		(end 176.229264 -412.165546)
		(width 0.11684)
		(layer "In15.Cu")
		(net "PRSNT_CABLE_GPU_A3_ISO_N")
	)
	(segment
		(start 175.961294 -397.001492)
		(end 175.961294 -410.587952)
		(width 0.11684)
		(layer "In15.Cu")
		(net "PRSNT_CABLE_GPU_A3_ISO_N")
	)
	(segment
		(start 182.655718 -421.80637)
		(end 182.655718 -427.411388)
		(width 0.11684)
		(layer "In15.Cu")
		(net "PRSNT_CABLE_GPU_A3_ISO_N")
	)
	(segment
		(start 176.229264 -412.643828)
		(end 176.863502 -413.278066)
		(width 0.11684)
		(layer "In15.Cu")
		(net "PRSNT_CABLE_GPU_A3_ISO_N")
	)
	(segment
		(start 177.655728 -395.0589)
		(end 176.756568 -395.95806)
		(width 0.11684)
		(layer "In15.Cu")
		(net "PRSNT_CABLE_GPU_A3_ISO_N")
	)
	(segment
		(start 359.568242 -406.167336)
		(end 360.631994 -406.167336)
		(width 0.10668)
		(layer "F.Cu")
		(net "PRSNT_CABLE_GPU_A3")
	)
	(segment
		(start 362.094526 -406.172416)
		(end 362.094526 -405.52243)
		(width 0.10668)
		(layer "F.Cu")
		(net "PRSNT_CABLE_GPU_A3")
	)
	(segment
		(start 360.631994 -406.167336)
		(end 362.089446 -406.167336)
		(width 0.10668)
		(layer "F.Cu")
		(net "PRSNT_CABLE_GPU_A3")
	)
	(segment
		(start 362.089446 -406.167336)
		(end 362.094526 -406.172416)
		(width 0.10668)
		(layer "F.Cu")
		(net "PRSNT_CABLE_GPU_A3")
	)
	(via
		(at 360.631994 -406.167336)
		(size 0.508)
		(drill 0.254)
		(layers "F.Cu" "B.Cu")
		(net "PRSNT_CABLE_GPU_A3")
	)
	(segment
		(start 188.01207 -423.631868)
		(end 188.01207 -423.254932)
		(width 0.10668)
		(layer "F.Cu")
		(net "PRSNT_CABLE_GPU_A2_ISO_R1_N")
	)
	(segment
		(start 188.588396 -424.508422)
		(end 188.588396 -424.208194)
		(width 0.10668)
		(layer "F.Cu")
		(net "PRSNT_CABLE_GPU_A2_ISO_R1_N")
	)
	(segment
		(start 188.588396 -424.208194)
		(end 188.01207 -423.631868)
		(width 0.10668)
		(layer "F.Cu")
		(net "PRSNT_CABLE_GPU_A2_ISO_R1_N")
	)
	(segment
		(start 189.05601 -424.976036)
		(end 188.588396 -424.508422)
		(width 0.10668)
		(layer "F.Cu")
		(net "PRSNT_CABLE_GPU_A2_ISO_R1_N")
	)
	(segment
		(start 189.366398 -425.975018)
		(end 189.366398 -425.286424)
		(width 0.10668)
		(layer "F.Cu")
		(net "PRSNT_CABLE_GPU_A2_ISO_R1_N")
	)
	(segment
		(start 189.366398 -425.286424)
		(end 189.05601 -424.976036)
		(width 0.10668)
		(layer "F.Cu")
		(net "PRSNT_CABLE_GPU_A2_ISO_R1_N")
	)
	(via
		(at 189.05601 -424.976036)
		(size 0.762)
		(drill 0.381)
		(layers "F.Cu" "B.Cu")
		(net "PRSNT_CABLE_GPU_A2_ISO_R1_N")
	)
	(segment
		(start 306.820316 -430.240186)
		(end 306.820316 -429.224186)
		(width 0.10668)
		(layer "F.Cu")
		(net "PRSNT_CABLE_GPU_A2_ISO_N")
	)
	(segment
		(start 189.366398 -426.775118)
		(end 189.881002 -426.775118)
		(width 0.10668)
		(layer "F.Cu")
		(net "PRSNT_CABLE_GPU_A2_ISO_N")
	)
	(segment
		(start 306.820316 -431.256186)
		(end 306.820316 -430.240186)
		(width 0.10668)
		(layer "F.Cu")
		(net "PRSNT_CABLE_GPU_A2_ISO_N")
	)
	(segment
		(start 189.881002 -426.775118)
		(end 190.096902 -426.559218)
		(width 0.10668)
		(layer "F.Cu")
		(net "PRSNT_CABLE_GPU_A2_ISO_N")
	)
	(segment
		(start 306.820316 -428.091346)
		(end 306.820316 -429.224186)
		(width 0.10668)
		(layer "F.Cu")
		(net "PRSNT_CABLE_GPU_A2_ISO_N")
	)
	(segment
		(start 197.875398 -121.197116)
		(end 199.407018 -121.197116)
		(width 0.10668)
		(layer "F.Cu")
		(net "PRSNT_CABLE_GPU_A2_ISO_N")
	)
	(segment
		(start 197.669658 -120.991376)
		(end 197.875398 -121.197116)
		(width 0.10668)
		(layer "F.Cu")
		(net "PRSNT_CABLE_GPU_A2_ISO_N")
	)
	(segment
		(start 306.820316 -432.649122)
		(end 306.820316 -431.256186)
		(width 0.10668)
		(layer "F.Cu")
		(net "PRSNT_CABLE_GPU_A2_ISO_N")
	)
	(segment
		(start 199.407018 -121.197116)
		(end 199.866758 -120.737376)
		(width 0.10668)
		(layer "F.Cu")
		(net "PRSNT_CABLE_GPU_A2_ISO_N")
	)
	(via
		(at 187.861194 -370.385594)
		(size 0.508)
		(drill 0.254)
		(layers "F.Cu" "B.Cu")
		(net "PRSNT_CABLE_GPU_A2_ISO_N")
	)
	(via
		(at 199.866758 -120.737376)
		(size 0.508)
		(drill 0.254)
		(layers "F.Cu" "B.Cu")
		(net "PRSNT_CABLE_GPU_A2_ISO_N")
	)
	(via
		(at 293.325296 -373.668036)
		(size 0.508)
		(drill 0.254)
		(layers "F.Cu" "B.Cu")
		(net "PRSNT_CABLE_GPU_A2_ISO_N")
	)
	(via
		(at 306.820316 -432.649122)
		(size 0.508)
		(drill 0.254)
		(layers "F.Cu" "B.Cu")
		(net "PRSNT_CABLE_GPU_A2_ISO_N")
	)
	(via
		(at 190.096902 -426.559218)
		(size 0.508)
		(drill 0.254)
		(layers "F.Cu" "B.Cu")
		(net "PRSNT_CABLE_GPU_A2_ISO_N")
	)
	(via
		(at 406.512268 -364.37189)
		(size 0.508)
		(drill 0.254)
		(layers "F.Cu" "B.Cu")
		(net "PRSNT_CABLE_GPU_A2_ISO_N")
	)
	(segment
		(start 290.204906 -370.875814)
		(end 290.204906 -369.701318)
		(width 0.10668)
		(layer "B.Cu")
		(net "PRSNT_CABLE_GPU_A2_ISO_N")
	)
	(segment
		(start 217.640154 -370.314728)
		(end 217.027506 -370.927376)
		(width 0.10668)
		(layer "B.Cu")
		(net "PRSNT_CABLE_GPU_A2_ISO_N")
	)
	(segment
		(start 295.18102 -369.988846)
		(end 293.94912 -371.220746)
		(width 0.10668)
		(layer "B.Cu")
		(net "PRSNT_CABLE_GPU_A2_ISO_N")
	)
	(segment
		(start 231.603804 -371.020594)
		(end 223.716088 -371.020594)
		(width 0.10668)
		(layer "B.Cu")
		(net "PRSNT_CABLE_GPU_A2_ISO_N")
	)
	(segment
		(start 293.94912 -371.220746)
		(end 293.94912 -373.044212)
		(width 0.10668)
		(layer "B.Cu")
		(net "PRSNT_CABLE_GPU_A2_ISO_N")
	)
	(segment
		(start 293.325296 -373.668036)
		(end 292.997128 -373.668036)
		(width 0.10668)
		(layer "B.Cu")
		(net "PRSNT_CABLE_GPU_A2_ISO_N")
	)
	(segment
		(start 293.94912 -373.044212)
		(end 293.325296 -373.668036)
		(width 0.10668)
		(layer "B.Cu")
		(net "PRSNT_CABLE_GPU_A2_ISO_N")
	)
	(segment
		(start 300.961552 -368.428778)
		(end 298.104306 -368.428778)
		(width 0.10668)
		(layer "B.Cu")
		(net "PRSNT_CABLE_GPU_A2_ISO_N")
	)
	(segment
		(start 288.151062 -367.647474)
		(end 273.62531 -367.647474)
		(width 0.10668)
		(layer "B.Cu")
		(net "PRSNT_CABLE_GPU_A2_ISO_N")
	)
	(segment
		(start 290.204906 -369.701318)
		(end 288.151062 -367.647474)
		(width 0.10668)
		(layer "B.Cu")
		(net "PRSNT_CABLE_GPU_A2_ISO_N")
	)
	(segment
		(start 296.544238 -369.988846)
		(end 295.18102 -369.988846)
		(width 0.10668)
		(layer "B.Cu")
		(net "PRSNT_CABLE_GPU_A2_ISO_N")
	)
	(segment
		(start 223.716088 -371.020594)
		(end 223.010222 -370.314728)
		(width 0.10668)
		(layer "B.Cu")
		(net "PRSNT_CABLE_GPU_A2_ISO_N")
	)
	(segment
		(start 298.104306 -368.428778)
		(end 296.544238 -369.988846)
		(width 0.10668)
		(layer "B.Cu")
		(net "PRSNT_CABLE_GPU_A2_ISO_N")
	)
	(segment
		(start 252.532642 -367.294414)
		(end 251.742956 -366.504728)
		(width 0.10668)
		(layer "B.Cu")
		(net "PRSNT_CABLE_GPU_A2_ISO_N")
	)
	(segment
		(start 251.742956 -366.504728)
		(end 236.11967 -366.504728)
		(width 0.10668)
		(layer "B.Cu")
		(net "PRSNT_CABLE_GPU_A2_ISO_N")
	)
	(segment
		(start 272.482564 -366.504728)
		(end 271.112234 -366.504728)
		(width 0.10668)
		(layer "B.Cu")
		(net "PRSNT_CABLE_GPU_A2_ISO_N")
	)
	(segment
		(start 223.010222 -370.314728)
		(end 217.640154 -370.314728)
		(width 0.10668)
		(layer "B.Cu")
		(net "PRSNT_CABLE_GPU_A2_ISO_N")
	)
	(segment
		(start 273.62531 -367.647474)
		(end 272.482564 -366.504728)
		(width 0.10668)
		(layer "B.Cu")
		(net "PRSNT_CABLE_GPU_A2_ISO_N")
	)
	(segment
		(start 404.560024 -366.04067)
		(end 401.133564 -369.46713)
		(width 0.10668)
		(layer "B.Cu")
		(net "PRSNT_CABLE_GPU_A2_ISO_N")
	)
	(segment
		(start 188.402976 -370.927376)
		(end 187.861194 -370.385594)
		(width 0.10668)
		(layer "B.Cu")
		(net "PRSNT_CABLE_GPU_A2_ISO_N")
	)
	(segment
		(start 406.512268 -364.37189)
		(end 404.843488 -366.04067)
		(width 0.10668)
		(layer "B.Cu")
		(net "PRSNT_CABLE_GPU_A2_ISO_N")
	)
	(segment
		(start 401.133564 -369.46713)
		(end 301.999904 -369.46713)
		(width 0.10668)
		(layer "B.Cu")
		(net "PRSNT_CABLE_GPU_A2_ISO_N")
	)
	(segment
		(start 236.11967 -366.504728)
		(end 231.603804 -371.020594)
		(width 0.10668)
		(layer "B.Cu")
		(net "PRSNT_CABLE_GPU_A2_ISO_N")
	)
	(segment
		(start 404.843488 -366.04067)
		(end 404.560024 -366.04067)
		(width 0.10668)
		(layer "B.Cu")
		(net "PRSNT_CABLE_GPU_A2_ISO_N")
	)
	(segment
		(start 217.027506 -370.927376)
		(end 188.402976 -370.927376)
		(width 0.10668)
		(layer "B.Cu")
		(net "PRSNT_CABLE_GPU_A2_ISO_N")
	)
	(segment
		(start 270.322548 -367.294414)
		(end 252.532642 -367.294414)
		(width 0.10668)
		(layer "B.Cu")
		(net "PRSNT_CABLE_GPU_A2_ISO_N")
	)
	(segment
		(start 301.999904 -369.46713)
		(end 300.961552 -368.428778)
		(width 0.10668)
		(layer "B.Cu")
		(net "PRSNT_CABLE_GPU_A2_ISO_N")
	)
	(segment
		(start 292.997128 -373.668036)
		(end 290.204906 -370.875814)
		(width 0.10668)
		(layer "B.Cu")
		(net "PRSNT_CABLE_GPU_A2_ISO_N")
	)
	(segment
		(start 271.112234 -366.504728)
		(end 270.322548 -367.294414)
		(width 0.10668)
		(layer "B.Cu")
		(net "PRSNT_CABLE_GPU_A2_ISO_N")
	)
	(segment
		(start 188.599572 -425.75988)
		(end 189.39891 -426.559218)
		(width 0.11684)
		(layer "In4.Cu")
		(net "PRSNT_CABLE_GPU_A2_ISO_N")
	)
	(segment
		(start 295.863518 -377.141994)
		(end 293.325296 -374.603772)
		(width 0.11684)
		(layer "In4.Cu")
		(net "PRSNT_CABLE_GPU_A2_ISO_N")
	)
	(segment
		(start 165.744906 -399.923254)
		(end 164.983414 -401.761706)
		(width 0.11684)
		(layer "In4.Cu")
		(net "PRSNT_CABLE_GPU_A2_ISO_N")
	)
	(segment
		(start 301.168562 -385.232402)
		(end 300.19752 -384.26136)
		(width 0.11684)
		(layer "In4.Cu")
		(net "PRSNT_CABLE_GPU_A2_ISO_N")
	)
	(segment
		(start 299.542708 -384.26136)
		(end 295.863518 -380.58217)
		(width 0.11684)
		(layer "In4.Cu")
		(net "PRSNT_CABLE_GPU_A2_ISO_N")
	)
	(segment
		(start 300.19752 -384.26136)
		(end 299.542708 -384.26136)
		(width 0.11684)
		(layer "In4.Cu")
		(net "PRSNT_CABLE_GPU_A2_ISO_N")
	)
	(segment
		(start 296.579544 -420.333424)
		(end 292.601904 -416.355784)
		(width 0.11684)
		(layer "In4.Cu")
		(net "PRSNT_CABLE_GPU_A2_ISO_N")
	)
	(segment
		(start 300.011592 -430.534826)
		(end 296.486072 -427.009306)
		(width 0.11684)
		(layer "In4.Cu")
		(net "PRSNT_CABLE_GPU_A2_ISO_N")
	)
	(segment
		(start 293.438072 -405.031956)
		(end 293.438072 -402.860764)
		(width 0.11684)
		(layer "In4.Cu")
		(net "PRSNT_CABLE_GPU_A2_ISO_N")
	)
	(segment
		(start 292.601904 -405.868124)
		(end 293.438072 -405.031956)
		(width 0.11684)
		(layer "In4.Cu")
		(net "PRSNT_CABLE_GPU_A2_ISO_N")
	)
	(segment
		(start 301.168562 -388.906766)
		(end 301.168562 -385.232402)
		(width 0.11684)
		(layer "In4.Cu")
		(net "PRSNT_CABLE_GPU_A2_ISO_N")
	)
	(segment
		(start 170.505374 -413.027622)
		(end 171.98721 -413.027622)
		(width 0.11684)
		(layer "In4.Cu")
		(net "PRSNT_CABLE_GPU_A2_ISO_N")
	)
	(segment
		(start 294.499792 -401.799044)
		(end 294.499792 -396.399512)
		(width 0.11684)
		(layer "In4.Cu")
		(net "PRSNT_CABLE_GPU_A2_ISO_N")
	)
	(segment
		(start 172.10405 -392.957558)
		(end 172.10405 -396.944342)
		(width 0.11684)
		(layer "In4.Cu")
		(net "PRSNT_CABLE_GPU_A2_ISO_N")
	)
	(segment
		(start 186.174126 -377.958858)
		(end 173.866048 -390.266936)
		(width 0.11684)
		(layer "In4.Cu")
		(net "PRSNT_CABLE_GPU_A2_ISO_N")
	)
	(segment
		(start 296.486072 -427.009306)
		(end 296.486072 -422.685972)
		(width 0.11684)
		(layer "In4.Cu")
		(net "PRSNT_CABLE_GPU_A2_ISO_N")
	)
	(segment
		(start 295.94175 -394.957554)
		(end 295.94175 -394.133578)
		(width 0.11684)
		(layer "In4.Cu")
		(net "PRSNT_CABLE_GPU_A2_ISO_N")
	)
	(segment
		(start 295.94175 -394.133578)
		(end 301.168562 -388.906766)
		(width 0.11684)
		(layer "In4.Cu")
		(net "PRSNT_CABLE_GPU_A2_ISO_N")
	)
	(segment
		(start 171.22521 -397.823182)
		(end 167.844978 -397.823182)
		(width 0.11684)
		(layer "In4.Cu")
		(net "PRSNT_CABLE_GPU_A2_ISO_N")
	)
	(segment
		(start 187.861194 -370.385594)
		(end 186.174126 -372.072662)
		(width 0.11684)
		(layer "In4.Cu")
		(net "PRSNT_CABLE_GPU_A2_ISO_N")
	)
	(segment
		(start 186.174126 -372.072662)
		(end 186.174126 -377.958858)
		(width 0.11684)
		(layer "In4.Cu")
		(net "PRSNT_CABLE_GPU_A2_ISO_N")
	)
	(segment
		(start 189.634876 -421.466772)
		(end 188.599572 -422.502076)
		(width 0.11684)
		(layer "In4.Cu")
		(net "PRSNT_CABLE_GPU_A2_ISO_N")
	)
	(segment
		(start 295.863518 -380.58217)
		(end 295.863518 -377.141994)
		(width 0.11684)
		(layer "In4.Cu")
		(net "PRSNT_CABLE_GPU_A2_ISO_N")
	)
	(segment
		(start 306.820316 -431.957988)
		(end 305.397154 -430.534826)
		(width 0.11684)
		(layer "In4.Cu")
		(net "PRSNT_CABLE_GPU_A2_ISO_N")
	)
	(segment
		(start 164.983414 -401.761706)
		(end 164.983414 -407.505662)
		(width 0.11684)
		(layer "In4.Cu")
		(net "PRSNT_CABLE_GPU_A2_ISO_N")
	)
	(segment
		(start 172.6184 -392.443208)
		(end 172.10405 -392.957558)
		(width 0.11684)
		(layer "In4.Cu")
		(net "PRSNT_CABLE_GPU_A2_ISO_N")
	)
	(segment
		(start 172.6184 -390.863074)
		(end 172.6184 -392.443208)
		(width 0.11684)
		(layer "In4.Cu")
		(net "PRSNT_CABLE_GPU_A2_ISO_N")
	)
	(segment
		(start 173.866048 -390.266936)
		(end 173.214538 -390.266936)
		(width 0.11684)
		(layer "In4.Cu")
		(net "PRSNT_CABLE_GPU_A2_ISO_N")
	)
	(segment
		(start 305.397154 -430.534826)
		(end 300.011592 -430.534826)
		(width 0.11684)
		(layer "In4.Cu")
		(net "PRSNT_CABLE_GPU_A2_ISO_N")
	)
	(segment
		(start 189.39891 -426.559218)
		(end 190.096902 -426.559218)
		(width 0.11684)
		(layer "In4.Cu")
		(net "PRSNT_CABLE_GPU_A2_ISO_N")
	)
	(segment
		(start 293.438072 -402.860764)
		(end 294.499792 -401.799044)
		(width 0.11684)
		(layer "In4.Cu")
		(net "PRSNT_CABLE_GPU_A2_ISO_N")
	)
	(segment
		(start 171.98721 -413.027622)
		(end 174.536862 -415.577274)
		(width 0.11684)
		(layer "In4.Cu")
		(net "PRSNT_CABLE_GPU_A2_ISO_N")
	)
	(segment
		(start 188.714634 -415.137346)
		(end 189.634876 -416.057588)
		(width 0.11684)
		(layer "In4.Cu")
		(net "PRSNT_CABLE_GPU_A2_ISO_N")
	)
	(segment
		(start 294.499792 -396.399512)
		(end 295.94175 -394.957554)
		(width 0.11684)
		(layer "In4.Cu")
		(net "PRSNT_CABLE_GPU_A2_ISO_N")
	)
	(segment
		(start 189.634876 -416.057588)
		(end 189.634876 -421.466772)
		(width 0.11684)
		(layer "In4.Cu")
		(net "PRSNT_CABLE_GPU_A2_ISO_N")
	)
	(segment
		(start 173.214538 -390.266936)
		(end 172.6184 -390.863074)
		(width 0.11684)
		(layer "In4.Cu")
		(net "PRSNT_CABLE_GPU_A2_ISO_N")
	)
	(segment
		(start 306.820316 -432.649122)
		(end 306.820316 -431.957988)
		(width 0.11684)
		(layer "In4.Cu")
		(net "PRSNT_CABLE_GPU_A2_ISO_N")
	)
	(segment
		(start 188.599572 -422.502076)
		(end 188.599572 -425.75988)
		(width 0.11684)
		(layer "In4.Cu")
		(net "PRSNT_CABLE_GPU_A2_ISO_N")
	)
	(segment
		(start 164.983414 -407.505662)
		(end 170.505374 -413.027622)
		(width 0.11684)
		(layer "In4.Cu")
		(net "PRSNT_CABLE_GPU_A2_ISO_N")
	)
	(segment
		(start 292.601904 -416.355784)
		(end 292.601904 -405.868124)
		(width 0.11684)
		(layer "In4.Cu")
		(net "PRSNT_CABLE_GPU_A2_ISO_N")
	)
	(segment
		(start 167.844978 -397.823182)
		(end 165.744906 -399.923254)
		(width 0.11684)
		(layer "In4.Cu")
		(net "PRSNT_CABLE_GPU_A2_ISO_N")
	)
	(segment
		(start 172.10405 -396.944342)
		(end 171.22521 -397.823182)
		(width 0.11684)
		(layer "In4.Cu")
		(net "PRSNT_CABLE_GPU_A2_ISO_N")
	)
	(segment
		(start 293.325296 -374.603772)
		(end 293.325296 -373.668036)
		(width 0.11684)
		(layer "In4.Cu")
		(net "PRSNT_CABLE_GPU_A2_ISO_N")
	)
	(segment
		(start 296.579544 -422.5925)
		(end 296.579544 -420.333424)
		(width 0.11684)
		(layer "In4.Cu")
		(net "PRSNT_CABLE_GPU_A2_ISO_N")
	)
	(segment
		(start 296.486072 -422.685972)
		(end 296.579544 -422.5925)
		(width 0.11684)
		(layer "In4.Cu")
		(net "PRSNT_CABLE_GPU_A2_ISO_N")
	)
	(segment
		(start 181.182264 -415.137346)
		(end 188.714634 -415.137346)
		(width 0.11684)
		(layer "In4.Cu")
		(net "PRSNT_CABLE_GPU_A2_ISO_N")
	)
	(segment
		(start 180.742336 -415.577274)
		(end 181.182264 -415.137346)
		(width 0.11684)
		(layer "In4.Cu")
		(net "PRSNT_CABLE_GPU_A2_ISO_N")
	)
	(segment
		(start 174.536862 -415.577274)
		(end 180.742336 -415.577274)
		(width 0.11684)
		(layer "In4.Cu")
		(net "PRSNT_CABLE_GPU_A2_ISO_N")
	)
	(segment
		(start 454.978262 -327.246488)
		(end 415.584132 -327.246488)
		(width 0.11684)
		(layer "In15.Cu")
		(net "PRSNT_CABLE_GPU_A2_ISO_N")
	)
	(segment
		(start 297.659044 -124.56414)
		(end 371.674644 -124.56414)
		(width 0.11684)
		(layer "In15.Cu")
		(net "PRSNT_CABLE_GPU_A2_ISO_N")
	)
	(segment
		(start 456.134978 -151.872442)
		(end 455.261218 -152.746202)
		(width 0.11684)
		(layer "In15.Cu")
		(net "PRSNT_CABLE_GPU_A2_ISO_N")
	)
	(segment
		(start 273.38274 -126.997714)
		(end 286.993584 -126.997714)
		(width 0.11684)
		(layer "In15.Cu")
		(net "PRSNT_CABLE_GPU_A2_ISO_N")
	)
	(segment
		(start 208.755996 -121.416826)
		(end 211.230972 -121.416826)
		(width 0.11684)
		(layer "In15.Cu")
		(net "PRSNT_CABLE_GPU_A2_ISO_N")
	)
	(segment
		(start 408.795474 -334.035146)
		(end 399.987516 -334.035146)
		(width 0.11684)
		(layer "In15.Cu")
		(net "PRSNT_CABLE_GPU_A2_ISO_N")
	)
	(segment
		(start 265.154918 -124.542804)
		(end 266.238228 -125.626114)
		(width 0.11684)
		(layer "In15.Cu")
		(net "PRSNT_CABLE_GPU_A2_ISO_N")
	)
	(segment
		(start 407.639774 -345.280234)
		(end 407.639774 -363.244384)
		(width 0.11684)
		(layer "In15.Cu")
		(net "PRSNT_CABLE_GPU_A2_ISO_N")
	)
	(segment
		(start 201.012806 -120.737376)
		(end 201.270616 -120.479566)
		(width 0.11684)
		(layer "In15.Cu")
		(net "PRSNT_CABLE_GPU_A2_ISO_N")
	)
	(segment
		(start 214.728806 -121.549414)
		(end 215.975184 -121.549414)
		(width 0.11684)
		(layer "In15.Cu")
		(net "PRSNT_CABLE_GPU_A2_ISO_N")
	)
	(segment
		(start 286.993584 -126.997714)
		(end 289.138868 -129.142998)
		(width 0.11684)
		(layer "In15.Cu")
		(net "PRSNT_CABLE_GPU_A2_ISO_N")
	)
	(segment
		(start 396.17142 -332.252066)
		(end 396.17142 -333.81188)
		(width 0.11684)
		(layer "In15.Cu")
		(net "PRSNT_CABLE_GPU_A2_ISO_N")
	)
	(segment
		(start 415.584132 -327.246488)
		(end 408.795474 -334.035146)
		(width 0.11684)
		(layer "In15.Cu")
		(net "PRSNT_CABLE_GPU_A2_ISO_N")
	)
	(segment
		(start 371.674644 -124.56414)
		(end 374.665494 -127.55499)
		(width 0.11684)
		(layer "In15.Cu")
		(net "PRSNT_CABLE_GPU_A2_ISO_N")
	)
	(segment
		(start 201.270616 -120.479566)
		(end 207.818736 -120.479566)
		(width 0.11684)
		(layer "In15.Cu")
		(net "PRSNT_CABLE_GPU_A2_ISO_N")
	)
	(segment
		(start 396.630906 -331.79258)
		(end 396.17142 -332.252066)
		(width 0.11684)
		(layer "In15.Cu")
		(net "PRSNT_CABLE_GPU_A2_ISO_N")
	)
	(segment
		(start 224.644458 -122.80138)
		(end 226.500944 -124.657866)
		(width 0.11684)
		(layer "In15.Cu")
		(net "PRSNT_CABLE_GPU_A2_ISO_N")
	)
	(segment
		(start 259.423662 -124.542804)
		(end 265.154918 -124.542804)
		(width 0.11684)
		(layer "In15.Cu")
		(net "PRSNT_CABLE_GPU_A2_ISO_N")
	)
	(segment
		(start 289.138868 -129.142998)
		(end 293.080186 -129.142998)
		(width 0.11684)
		(layer "In15.Cu")
		(net "PRSNT_CABLE_GPU_A2_ISO_N")
	)
	(segment
		(start 199.866758 -120.737376)
		(end 201.012806 -120.737376)
		(width 0.11684)
		(layer "In15.Cu")
		(net "PRSNT_CABLE_GPU_A2_ISO_N")
	)
	(segment
		(start 462.603088 -319.621662)
		(end 454.978262 -327.246488)
		(width 0.11684)
		(layer "In15.Cu")
		(net "PRSNT_CABLE_GPU_A2_ISO_N")
	)
	(segment
		(start 396.17142 -333.81188)
		(end 407.639774 -345.280234)
		(width 0.11684)
		(layer "In15.Cu")
		(net "PRSNT_CABLE_GPU_A2_ISO_N")
	)
	(segment
		(start 248.337832 -122.59183)
		(end 257.472688 -122.59183)
		(width 0.11684)
		(layer "In15.Cu")
		(net "PRSNT_CABLE_GPU_A2_ISO_N")
	)
	(segment
		(start 455.261218 -164.863272)
		(end 462.603088 -172.205142)
		(width 0.11684)
		(layer "In15.Cu")
		(net "PRSNT_CABLE_GPU_A2_ISO_N")
	)
	(segment
		(start 211.230972 -121.416826)
		(end 211.864702 -120.783096)
		(width 0.11684)
		(layer "In15.Cu")
		(net "PRSNT_CABLE_GPU_A2_ISO_N")
	)
	(segment
		(start 272.01114 -125.626114)
		(end 273.38274 -126.997714)
		(width 0.11684)
		(layer "In15.Cu")
		(net "PRSNT_CABLE_GPU_A2_ISO_N")
	)
	(segment
		(start 455.261218 -152.746202)
		(end 455.261218 -164.863272)
		(width 0.11684)
		(layer "In15.Cu")
		(net "PRSNT_CABLE_GPU_A2_ISO_N")
	)
	(segment
		(start 257.472688 -122.59183)
		(end 259.423662 -124.542804)
		(width 0.11684)
		(layer "In15.Cu")
		(net "PRSNT_CABLE_GPU_A2_ISO_N")
	)
	(segment
		(start 462.603088 -172.205142)
		(end 462.603088 -319.621662)
		(width 0.11684)
		(layer "In15.Cu")
		(net "PRSNT_CABLE_GPU_A2_ISO_N")
	)
	(segment
		(start 397.74495 -331.79258)
		(end 396.630906 -331.79258)
		(width 0.11684)
		(layer "In15.Cu")
		(net "PRSNT_CABLE_GPU_A2_ISO_N")
	)
	(segment
		(start 207.818736 -120.479566)
		(end 208.755996 -121.416826)
		(width 0.11684)
		(layer "In15.Cu")
		(net "PRSNT_CABLE_GPU_A2_ISO_N")
	)
	(segment
		(start 215.975184 -121.549414)
		(end 217.22715 -122.80138)
		(width 0.11684)
		(layer "In15.Cu")
		(net "PRSNT_CABLE_GPU_A2_ISO_N")
	)
	(segment
		(start 446.98666 -127.55499)
		(end 456.134978 -136.703308)
		(width 0.11684)
		(layer "In15.Cu")
		(net "PRSNT_CABLE_GPU_A2_ISO_N")
	)
	(segment
		(start 211.864702 -120.783096)
		(end 213.962488 -120.783096)
		(width 0.11684)
		(layer "In15.Cu")
		(net "PRSNT_CABLE_GPU_A2_ISO_N")
	)
	(segment
		(start 407.639774 -363.244384)
		(end 406.512268 -364.37189)
		(width 0.11684)
		(layer "In15.Cu")
		(net "PRSNT_CABLE_GPU_A2_ISO_N")
	)
	(segment
		(start 374.665494 -127.55499)
		(end 446.98666 -127.55499)
		(width 0.11684)
		(layer "In15.Cu")
		(net "PRSNT_CABLE_GPU_A2_ISO_N")
	)
	(segment
		(start 217.22715 -122.80138)
		(end 224.644458 -122.80138)
		(width 0.11684)
		(layer "In15.Cu")
		(net "PRSNT_CABLE_GPU_A2_ISO_N")
	)
	(segment
		(start 226.500944 -124.657866)
		(end 246.271796 -124.657866)
		(width 0.11684)
		(layer "In15.Cu")
		(net "PRSNT_CABLE_GPU_A2_ISO_N")
	)
	(segment
		(start 456.134978 -136.703308)
		(end 456.134978 -151.872442)
		(width 0.11684)
		(layer "In15.Cu")
		(net "PRSNT_CABLE_GPU_A2_ISO_N")
	)
	(segment
		(start 213.962488 -120.783096)
		(end 214.728806 -121.549414)
		(width 0.11684)
		(layer "In15.Cu")
		(net "PRSNT_CABLE_GPU_A2_ISO_N")
	)
	(segment
		(start 293.080186 -129.142998)
		(end 297.659044 -124.56414)
		(width 0.11684)
		(layer "In15.Cu")
		(net "PRSNT_CABLE_GPU_A2_ISO_N")
	)
	(segment
		(start 266.238228 -125.626114)
		(end 272.01114 -125.626114)
		(width 0.11684)
		(layer "In15.Cu")
		(net "PRSNT_CABLE_GPU_A2_ISO_N")
	)
	(segment
		(start 246.271796 -124.657866)
		(end 248.337832 -122.59183)
		(width 0.11684)
		(layer "In15.Cu")
		(net "PRSNT_CABLE_GPU_A2_ISO_N")
	)
	(segment
		(start 399.987516 -334.035146)
		(end 397.74495 -331.79258)
		(width 0.11684)
		(layer "In15.Cu")
		(net "PRSNT_CABLE_GPU_A2_ISO_N")
	)
	(segment
		(start 183.39181 -426.023532)
		(end 183.237632 -426.17771)
		(width 0.10668)
		(layer "F.Cu")
		(net "PRSNT_CABLE_GPU_A1_ISO_R1_N")
	)
	(segment
		(start 183.39181 -425.592494)
		(end 183.39181 -426.023532)
		(width 0.10668)
		(layer "F.Cu")
		(net "PRSNT_CABLE_GPU_A1_ISO_R1_N")
	)
	(segment
		(start 183.237632 -426.92193)
		(end 183.364886 -427.049184)
		(width 0.10668)
		(layer "F.Cu")
		(net "PRSNT_CABLE_GPU_A1_ISO_R1_N")
	)
	(segment
		(start 184.012078 -423.920412)
		(end 183.552338 -424.380152)
		(width 0.10668)
		(layer "F.Cu")
		(net "PRSNT_CABLE_GPU_A1_ISO_R1_N")
	)
	(segment
		(start 183.237632 -426.17771)
		(end 183.237632 -426.92193)
		(width 0.10668)
		(layer "F.Cu")
		(net "PRSNT_CABLE_GPU_A1_ISO_R1_N")
	)
	(segment
		(start 183.552338 -424.380152)
		(end 183.552338 -425.431966)
		(width 0.10668)
		(layer "F.Cu")
		(net "PRSNT_CABLE_GPU_A1_ISO_R1_N")
	)
	(segment
		(start 183.552338 -425.431966)
		(end 183.39181 -425.592494)
		(width 0.10668)
		(layer "F.Cu")
		(net "PRSNT_CABLE_GPU_A1_ISO_R1_N")
	)
	(segment
		(start 184.012078 -423.254932)
		(end 184.012078 -423.920412)
		(width 0.10668)
		(layer "F.Cu")
		(net "PRSNT_CABLE_GPU_A1_ISO_R1_N")
	)
	(via
		(at 183.237632 -426.17771)
		(size 0.762)
		(drill 0.381)
		(layers "F.Cu" "B.Cu")
		(net "PRSNT_CABLE_GPU_A1_ISO_R1_N")
	)
	(segment
		(start 210.110324 -121.633234)
		(end 210.831684 -120.911874)
		(width 0.10668)
		(layer "F.Cu")
		(net "PRSNT_CABLE_GPU_A1_ISO_N")
	)
	(segment
		(start 203.03998 -120.157748)
		(end 203.17968 -120.297448)
		(width 0.10668)
		(layer "F.Cu")
		(net "PRSNT_CABLE_GPU_A1_ISO_N")
	)
	(segment
		(start 203.17968 -120.297448)
		(end 206.768446 -120.297448)
		(width 0.10668)
		(layer "F.Cu")
		(net "PRSNT_CABLE_GPU_A1_ISO_N")
	)
	(segment
		(start 356.884732 -411.724094)
		(end 356.884732 -412.030418)
		(width 0.10668)
		(layer "F.Cu")
		(net "PRSNT_CABLE_GPU_A1_ISO_N")
	)
	(segment
		(start 356.884732 -413.046418)
		(end 356.884732 -414.062418)
		(width 0.10668)
		(layer "F.Cu")
		(net "PRSNT_CABLE_GPU_A1_ISO_N")
	)
	(segment
		(start 183.364886 -427.849284)
		(end 183.364886 -428.638462)
		(width 0.10668)
		(layer "F.Cu")
		(net "PRSNT_CABLE_GPU_A1_ISO_N")
	)
	(segment
		(start 356.884732 -412.030418)
		(end 356.884732 -413.046418)
		(width 0.10668)
		(layer "F.Cu")
		(net "PRSNT_CABLE_GPU_A1_ISO_N")
	)
	(segment
		(start 203.03998 -119.54002)
		(end 203.03998 -120.157748)
		(width 0.10668)
		(layer "F.Cu")
		(net "PRSNT_CABLE_GPU_A1_ISO_N")
	)
	(segment
		(start 183.364886 -428.638462)
		(end 183.687974 -428.96155)
		(width 0.10668)
		(layer "F.Cu")
		(net "PRSNT_CABLE_GPU_A1_ISO_N")
	)
	(segment
		(start 206.768446 -120.297448)
		(end 208.104232 -121.633234)
		(width 0.10668)
		(layer "F.Cu")
		(net "PRSNT_CABLE_GPU_A1_ISO_N")
	)
	(segment
		(start 356.884732 -415.195258)
		(end 356.884732 -414.062418)
		(width 0.10668)
		(layer "F.Cu")
		(net "PRSNT_CABLE_GPU_A1_ISO_N")
	)
	(segment
		(start 202.665076 -119.165116)
		(end 203.03998 -119.54002)
		(width 0.10668)
		(layer "F.Cu")
		(net "PRSNT_CABLE_GPU_A1_ISO_N")
	)
	(segment
		(start 201.395584 -118.782084)
		(end 201.778616 -119.165116)
		(width 0.10668)
		(layer "F.Cu")
		(net "PRSNT_CABLE_GPU_A1_ISO_N")
	)
	(segment
		(start 201.778616 -119.165116)
		(end 202.665076 -119.165116)
		(width 0.10668)
		(layer "F.Cu")
		(net "PRSNT_CABLE_GPU_A1_ISO_N")
	)
	(segment
		(start 208.104232 -121.633234)
		(end 210.110324 -121.633234)
		(width 0.10668)
		(layer "F.Cu")
		(net "PRSNT_CABLE_GPU_A1_ISO_N")
	)
	(segment
		(start 357.237538 -411.371288)
		(end 356.884732 -411.724094)
		(width 0.10668)
		(layer "F.Cu")
		(net "PRSNT_CABLE_GPU_A1_ISO_N")
	)
	(via
		(at 210.831684 -120.911874)
		(size 0.508)
		(drill 0.254)
		(layers "F.Cu" "B.Cu")
		(net "PRSNT_CABLE_GPU_A1_ISO_N")
	)
	(via
		(at 357.237538 -411.371288)
		(size 0.508)
		(drill 0.254)
		(layers "F.Cu" "B.Cu")
		(net "PRSNT_CABLE_GPU_A1_ISO_N")
	)
	(via
		(at 186.805062 -387.443472)
		(size 0.508)
		(drill 0.254)
		(layers "F.Cu" "B.Cu")
		(net "PRSNT_CABLE_GPU_A1_ISO_N")
	)
	(via
		(at 201.663554 -86.924896)
		(size 0.508)
		(drill 0.254)
		(layers "F.Cu" "B.Cu")
		(net "PRSNT_CABLE_GPU_A1_ISO_N")
	)
	(via
		(at 183.687974 -428.96155)
		(size 0.508)
		(drill 0.254)
		(layers "F.Cu" "B.Cu")
		(net "PRSNT_CABLE_GPU_A1_ISO_N")
	)
	(via
		(at 289.315398 -409.994862)
		(size 0.508)
		(drill 0.254)
		(layers "F.Cu" "B.Cu")
		(net "PRSNT_CABLE_GPU_A1_ISO_N")
	)
	(segment
		(start 187.093606 -384.0988)
		(end 187.093606 -381.249174)
		(width 0.10668)
		(layer "B.Cu")
		(net "PRSNT_CABLE_GPU_A1_ISO_N")
	)
	(segment
		(start 284.240224 -392.950192)
		(end 283.697426 -393.49299)
		(width 0.10668)
		(layer "B.Cu")
		(net "PRSNT_CABLE_GPU_A1_ISO_N")
	)
	(segment
		(start 187.093606 -381.249174)
		(end 194.340988 -374.001792)
		(width 0.10668)
		(layer "B.Cu")
		(net "PRSNT_CABLE_GPU_A1_ISO_N")
	)
	(segment
		(start 186.805062 -387.443472)
		(end 186.805062 -384.387344)
		(width 0.10668)
		(layer "B.Cu")
		(net "PRSNT_CABLE_GPU_A1_ISO_N")
	)
	(segment
		(start 281.668474 -384.602228)
		(end 284.240224 -387.173978)
		(width 0.10668)
		(layer "B.Cu")
		(net "PRSNT_CABLE_GPU_A1_ISO_N")
	)
	(segment
		(start 284.240224 -387.173978)
		(end 284.240224 -392.950192)
		(width 0.10668)
		(layer "B.Cu")
		(net "PRSNT_CABLE_GPU_A1_ISO_N")
	)
	(segment
		(start 186.805062 -384.387344)
		(end 187.093606 -384.0988)
		(width 0.10668)
		(layer "B.Cu")
		(net "PRSNT_CABLE_GPU_A1_ISO_N")
	)
	(segment
		(start 285.36646 -397.718788)
		(end 285.36646 -408.068526)
		(width 0.10668)
		(layer "B.Cu")
		(net "PRSNT_CABLE_GPU_A1_ISO_N")
	)
	(segment
		(start 194.340988 -374.001792)
		(end 278.805386 -374.001792)
		(width 0.10668)
		(layer "B.Cu")
		(net "PRSNT_CABLE_GPU_A1_ISO_N")
	)
	(segment
		(start 287.854898 -410.556964)
		(end 288.72053 -410.556964)
		(width 0.10668)
		(layer "B.Cu")
		(net "PRSNT_CABLE_GPU_A1_ISO_N")
	)
	(segment
		(start 288.72053 -410.556964)
		(end 289.282632 -409.994862)
		(width 0.10668)
		(layer "B.Cu")
		(net "PRSNT_CABLE_GPU_A1_ISO_N")
	)
	(segment
		(start 285.36646 -408.068526)
		(end 287.854898 -410.556964)
		(width 0.10668)
		(layer "B.Cu")
		(net "PRSNT_CABLE_GPU_A1_ISO_N")
	)
	(segment
		(start 281.668474 -376.86488)
		(end 281.668474 -384.602228)
		(width 0.10668)
		(layer "B.Cu")
		(net "PRSNT_CABLE_GPU_A1_ISO_N")
	)
	(segment
		(start 283.697426 -393.49299)
		(end 283.697426 -396.049754)
		(width 0.10668)
		(layer "B.Cu")
		(net "PRSNT_CABLE_GPU_A1_ISO_N")
	)
	(segment
		(start 278.805386 -374.001792)
		(end 281.668474 -376.86488)
		(width 0.10668)
		(layer "B.Cu")
		(net "PRSNT_CABLE_GPU_A1_ISO_N")
	)
	(segment
		(start 283.697426 -396.049754)
		(end 285.36646 -397.718788)
		(width 0.10668)
		(layer "B.Cu")
		(net "PRSNT_CABLE_GPU_A1_ISO_N")
	)
	(segment
		(start 289.282632 -409.994862)
		(end 289.315398 -409.994862)
		(width 0.10668)
		(layer "B.Cu")
		(net "PRSNT_CABLE_GPU_A1_ISO_N")
	)
	(segment
		(start 455.886058 -142.21968)
		(end 455.886058 -150.562056)
		(width 0.11684)
		(layer "In2.Cu")
		(net "PRSNT_CABLE_GPU_A1_ISO_N")
	)
	(segment
		(start 207.84693 -86.237572)
		(end 208.631282 -87.021924)
		(width 0.11684)
		(layer "In2.Cu")
		(net "PRSNT_CABLE_GPU_A1_ISO_N")
	)
	(segment
		(start 245.864126 -80.749902)
		(end 246.851678 -79.76235)
		(width 0.11684)
		(layer "In2.Cu")
		(net "PRSNT_CABLE_GPU_A1_ISO_N")
	)
	(segment
		(start 389.411464 -119.725948)
		(end 433.392326 -119.725948)
		(width 0.11684)
		(layer "In2.Cu")
		(net "PRSNT_CABLE_GPU_A1_ISO_N")
	)
	(segment
		(start 319.588388 -115.758976)
		(end 325.028814 -121.199402)
		(width 0.11684)
		(layer "In2.Cu")
		(net "PRSNT_CABLE_GPU_A1_ISO_N")
	)
	(segment
		(start 357.467408 -411.371288)
		(end 357.237538 -411.371288)
		(width 0.11684)
		(layer "In2.Cu")
		(net "PRSNT_CABLE_GPU_A1_ISO_N")
	)
	(segment
		(start 465.075016 -332.089506)
		(end 453.322436 -343.842086)
		(width 0.11684)
		(layer "In2.Cu")
		(net "PRSNT_CABLE_GPU_A1_ISO_N")
	)
	(segment
		(start 434.531008 -391.342626)
		(end 434.531008 -393.295378)
		(width 0.11684)
		(layer "In2.Cu")
		(net "PRSNT_CABLE_GPU_A1_ISO_N")
	)
	(segment
		(start 302.139858 -415.064702)
		(end 302.139858 -411.239716)
		(width 0.11684)
		(layer "In2.Cu")
		(net "PRSNT_CABLE_GPU_A1_ISO_N")
	)
	(segment
		(start 361.451906 -409.233878)
		(end 360.307636 -409.233878)
		(width 0.11684)
		(layer "In2.Cu")
		(net "PRSNT_CABLE_GPU_A1_ISO_N")
	)
	(segment
		(start 434.531008 -393.295378)
		(end 431.414174 -396.412212)
		(width 0.11684)
		(layer "In2.Cu")
		(net "PRSNT_CABLE_GPU_A1_ISO_N")
	)
	(segment
		(start 356.586282 -409.764738)
		(end 356.586282 -410.720032)
		(width 0.11684)
		(layer "In2.Cu")
		(net "PRSNT_CABLE_GPU_A1_ISO_N")
	)
	(segment
		(start 376.678952 -119.024908)
		(end 383.07518 -119.024908)
		(width 0.11684)
		(layer "In2.Cu")
		(net "PRSNT_CABLE_GPU_A1_ISO_N")
	)
	(segment
		(start 453.949308 -163.63823)
		(end 465.075016 -174.763938)
		(width 0.11684)
		(layer "In2.Cu")
		(net "PRSNT_CABLE_GPU_A1_ISO_N")
	)
	(segment
		(start 288.578036 -107.54868)
		(end 308.33822 -107.54868)
		(width 0.11684)
		(layer "In2.Cu")
		(net "PRSNT_CABLE_GPU_A1_ISO_N")
	)
	(segment
		(start 245.864126 -84.307426)
		(end 245.864126 -80.749902)
		(width 0.11684)
		(layer "In2.Cu")
		(net "PRSNT_CABLE_GPU_A1_ISO_N")
	)
	(segment
		(start 358.563672 -410.977842)
		(end 357.860854 -410.977842)
		(width 0.11684)
		(layer "In2.Cu")
		(net "PRSNT_CABLE_GPU_A1_ISO_N")
	)
	(segment
		(start 465.075016 -174.763938)
		(end 465.075016 -332.089506)
		(width 0.11684)
		(layer "In2.Cu")
		(net "PRSNT_CABLE_GPU_A1_ISO_N")
	)
	(segment
		(start 357.860854 -410.977842)
		(end 357.467408 -411.371288)
		(width 0.11684)
		(layer "In2.Cu")
		(net "PRSNT_CABLE_GPU_A1_ISO_N")
	)
	(segment
		(start 281.883866 -100.85451)
		(end 288.578036 -107.54868)
		(width 0.11684)
		(layer "In2.Cu")
		(net "PRSNT_CABLE_GPU_A1_ISO_N")
	)
	(segment
		(start 356.586282 -410.720032)
		(end 357.237538 -411.371288)
		(width 0.11684)
		(layer "In2.Cu")
		(net "PRSNT_CABLE_GPU_A1_ISO_N")
	)
	(segment
		(start 438.736232 -387.137402)
		(end 434.531008 -391.342626)
		(width 0.11684)
		(layer "In2.Cu")
		(net "PRSNT_CABLE_GPU_A1_ISO_N")
	)
	(segment
		(start 281.883866 -99.238562)
		(end 281.883866 -100.85451)
		(width 0.11684)
		(layer "In2.Cu")
		(net "PRSNT_CABLE_GPU_A1_ISO_N")
	)
	(segment
		(start 383.36474 -118.735348)
		(end 388.420864 -118.735348)
		(width 0.11684)
		(layer "In2.Cu")
		(net "PRSNT_CABLE_GPU_A1_ISO_N")
	)
	(segment
		(start 368.346228 -408.242262)
		(end 368.141758 -408.037792)
		(width 0.11684)
		(layer "In2.Cu")
		(net "PRSNT_CABLE_GPU_A1_ISO_N")
	)
	(segment
		(start 201.875644 -86.924896)
		(end 202.562968 -86.237572)
		(width 0.11684)
		(layer "In2.Cu")
		(net "PRSNT_CABLE_GPU_A1_ISO_N")
	)
	(segment
		(start 423.962068 -408.242262)
		(end 368.346228 -408.242262)
		(width 0.11684)
		(layer "In2.Cu")
		(net "PRSNT_CABLE_GPU_A1_ISO_N")
	)
	(segment
		(start 212.732112 -87.021924)
		(end 215.475312 -89.765124)
		(width 0.11684)
		(layer "In2.Cu")
		(net "PRSNT_CABLE_GPU_A1_ISO_N")
	)
	(segment
		(start 295.461944 -417.536122)
		(end 299.668438 -417.536122)
		(width 0.11684)
		(layer "In2.Cu")
		(net "PRSNT_CABLE_GPU_A1_ISO_N")
	)
	(segment
		(start 308.33822 -107.54868)
		(end 316.548516 -115.758976)
		(width 0.11684)
		(layer "In2.Cu")
		(net "PRSNT_CABLE_GPU_A1_ISO_N")
	)
	(segment
		(start 438.736232 -375.197116)
		(end 438.736232 -387.137402)
		(width 0.11684)
		(layer "In2.Cu")
		(net "PRSNT_CABLE_GPU_A1_ISO_N")
	)
	(segment
		(start 302.139858 -411.239716)
		(end 304.449734 -408.92984)
		(width 0.11684)
		(layer "In2.Cu")
		(net "PRSNT_CABLE_GPU_A1_ISO_N")
	)
	(segment
		(start 292.58895 -412.753556)
		(end 292.58895 -414.663128)
		(width 0.11684)
		(layer "In2.Cu")
		(net "PRSNT_CABLE_GPU_A1_ISO_N")
	)
	(segment
		(start 360.307636 -409.233878)
		(end 358.563672 -410.977842)
		(width 0.11684)
		(layer "In2.Cu")
		(net "PRSNT_CABLE_GPU_A1_ISO_N")
	)
	(segment
		(start 455.886058 -150.562056)
		(end 453.949308 -152.498806)
		(width 0.11684)
		(layer "In2.Cu")
		(net "PRSNT_CABLE_GPU_A1_ISO_N")
	)
	(segment
		(start 202.562968 -86.237572)
		(end 207.84693 -86.237572)
		(width 0.11684)
		(layer "In2.Cu")
		(net "PRSNT_CABLE_GPU_A1_ISO_N")
	)
	(segment
		(start 374.504458 -121.199402)
		(end 376.678952 -119.024908)
		(width 0.11684)
		(layer "In2.Cu")
		(net "PRSNT_CABLE_GPU_A1_ISO_N")
	)
	(segment
		(start 453.322436 -364.366556)
		(end 445.94653 -371.742462)
		(width 0.11684)
		(layer "In2.Cu")
		(net "PRSNT_CABLE_GPU_A1_ISO_N")
	)
	(segment
		(start 279.208738 -98.044508)
		(end 280.689812 -98.044508)
		(width 0.11684)
		(layer "In2.Cu")
		(net "PRSNT_CABLE_GPU_A1_ISO_N")
	)
	(segment
		(start 433.392326 -119.725948)
		(end 455.886058 -142.21968)
		(width 0.11684)
		(layer "In2.Cu")
		(net "PRSNT_CABLE_GPU_A1_ISO_N")
	)
	(segment
		(start 208.631282 -87.021924)
		(end 212.732112 -87.021924)
		(width 0.11684)
		(layer "In2.Cu")
		(net "PRSNT_CABLE_GPU_A1_ISO_N")
	)
	(segment
		(start 445.94653 -371.742462)
		(end 442.190886 -371.742462)
		(width 0.11684)
		(layer "In2.Cu")
		(net "PRSNT_CABLE_GPU_A1_ISO_N")
	)
	(segment
		(start 431.414174 -396.412212)
		(end 430.816004 -397.85671)
		(width 0.11684)
		(layer "In2.Cu")
		(net "PRSNT_CABLE_GPU_A1_ISO_N")
	)
	(segment
		(start 304.449734 -408.92984)
		(end 355.751384 -408.92984)
		(width 0.11684)
		(layer "In2.Cu")
		(net "PRSNT_CABLE_GPU_A1_ISO_N")
	)
	(segment
		(start 362.647992 -408.037792)
		(end 361.451906 -409.233878)
		(width 0.11684)
		(layer "In2.Cu")
		(net "PRSNT_CABLE_GPU_A1_ISO_N")
	)
	(segment
		(start 453.322436 -343.842086)
		(end 453.322436 -364.366556)
		(width 0.11684)
		(layer "In2.Cu")
		(net "PRSNT_CABLE_GPU_A1_ISO_N")
	)
	(segment
		(start 289.830256 -409.994862)
		(end 292.58895 -412.753556)
		(width 0.11684)
		(layer "In2.Cu")
		(net "PRSNT_CABLE_GPU_A1_ISO_N")
	)
	(segment
		(start 316.548516 -115.758976)
		(end 319.588388 -115.758976)
		(width 0.11684)
		(layer "In2.Cu")
		(net "PRSNT_CABLE_GPU_A1_ISO_N")
	)
	(segment
		(start 453.949308 -152.498806)
		(end 453.949308 -163.63823)
		(width 0.11684)
		(layer "In2.Cu")
		(net "PRSNT_CABLE_GPU_A1_ISO_N")
	)
	(segment
		(start 289.315398 -409.994862)
		(end 289.830256 -409.994862)
		(width 0.11684)
		(layer "In2.Cu")
		(net "PRSNT_CABLE_GPU_A1_ISO_N")
	)
	(segment
		(start 280.689812 -98.044508)
		(end 281.883866 -99.238562)
		(width 0.11684)
		(layer "In2.Cu")
		(net "PRSNT_CABLE_GPU_A1_ISO_N")
	)
	(segment
		(start 201.663554 -86.924896)
		(end 201.875644 -86.924896)
		(width 0.11684)
		(layer "In2.Cu")
		(net "PRSNT_CABLE_GPU_A1_ISO_N")
	)
	(segment
		(start 430.816004 -397.85671)
		(end 430.816004 -401.388326)
		(width 0.11684)
		(layer "In2.Cu")
		(net "PRSNT_CABLE_GPU_A1_ISO_N")
	)
	(segment
		(start 240.406428 -89.765124)
		(end 245.864126 -84.307426)
		(width 0.11684)
		(layer "In2.Cu")
		(net "PRSNT_CABLE_GPU_A1_ISO_N")
	)
	(segment
		(start 215.475312 -89.765124)
		(end 240.406428 -89.765124)
		(width 0.11684)
		(layer "In2.Cu")
		(net "PRSNT_CABLE_GPU_A1_ISO_N")
	)
	(segment
		(start 383.07518 -119.024908)
		(end 383.36474 -118.735348)
		(width 0.11684)
		(layer "In2.Cu")
		(net "PRSNT_CABLE_GPU_A1_ISO_N")
	)
	(segment
		(start 388.420864 -118.735348)
		(end 389.411464 -119.725948)
		(width 0.11684)
		(layer "In2.Cu")
		(net "PRSNT_CABLE_GPU_A1_ISO_N")
	)
	(segment
		(start 430.816004 -401.388326)
		(end 423.962068 -408.242262)
		(width 0.11684)
		(layer "In2.Cu")
		(net "PRSNT_CABLE_GPU_A1_ISO_N")
	)
	(segment
		(start 292.58895 -414.663128)
		(end 295.461944 -417.536122)
		(width 0.11684)
		(layer "In2.Cu")
		(net "PRSNT_CABLE_GPU_A1_ISO_N")
	)
	(segment
		(start 355.751384 -408.92984)
		(end 356.586282 -409.764738)
		(width 0.11684)
		(layer "In2.Cu")
		(net "PRSNT_CABLE_GPU_A1_ISO_N")
	)
	(segment
		(start 246.851678 -79.76235)
		(end 260.92658 -79.76235)
		(width 0.11684)
		(layer "In2.Cu")
		(net "PRSNT_CABLE_GPU_A1_ISO_N")
	)
	(segment
		(start 368.141758 -408.037792)
		(end 362.647992 -408.037792)
		(width 0.11684)
		(layer "In2.Cu")
		(net "PRSNT_CABLE_GPU_A1_ISO_N")
	)
	(segment
		(start 325.028814 -121.199402)
		(end 374.504458 -121.199402)
		(width 0.11684)
		(layer "In2.Cu")
		(net "PRSNT_CABLE_GPU_A1_ISO_N")
	)
	(segment
		(start 260.92658 -79.76235)
		(end 279.208738 -98.044508)
		(width 0.11684)
		(layer "In2.Cu")
		(net "PRSNT_CABLE_GPU_A1_ISO_N")
	)
	(segment
		(start 442.190886 -371.742462)
		(end 438.736232 -375.197116)
		(width 0.11684)
		(layer "In2.Cu")
		(net "PRSNT_CABLE_GPU_A1_ISO_N")
	)
	(segment
		(start 299.668438 -417.536122)
		(end 302.139858 -415.064702)
		(width 0.11684)
		(layer "In2.Cu")
		(net "PRSNT_CABLE_GPU_A1_ISO_N")
	)
	(segment
		(start 211.159344 -92.653612)
		(end 211.159344 -98.089466)
		(width 0.11684)
		(layer "In11.Cu")
		(net "PRSNT_CABLE_GPU_A1_ISO_N")
	)
	(segment
		(start 202.76185 -88.023192)
		(end 206.528924 -88.023192)
		(width 0.11684)
		(layer "In11.Cu")
		(net "PRSNT_CABLE_GPU_A1_ISO_N")
	)
	(segment
		(start 211.30133 -110.368842)
		(end 211.30133 -112.851184)
		(width 0.11684)
		(layer "In11.Cu")
		(net "PRSNT_CABLE_GPU_A1_ISO_N")
	)
	(segment
		(start 211.30133 -112.851184)
		(end 209.81289 -114.339624)
		(width 0.11684)
		(layer "In11.Cu")
		(net "PRSNT_CABLE_GPU_A1_ISO_N")
	)
	(segment
		(start 209.81289 -114.339624)
		(end 209.81289 -119.893588)
		(width 0.11684)
		(layer "In11.Cu")
		(net "PRSNT_CABLE_GPU_A1_ISO_N")
	)
	(segment
		(start 201.663554 -86.924896)
		(end 202.76185 -88.023192)
		(width 0.11684)
		(layer "In11.Cu")
		(net "PRSNT_CABLE_GPU_A1_ISO_N")
	)
	(segment
		(start 211.159344 -98.089466)
		(end 213.481666 -100.411788)
		(width 0.11684)
		(layer "In11.Cu")
		(net "PRSNT_CABLE_GPU_A1_ISO_N")
	)
	(segment
		(start 206.528924 -88.023192)
		(end 211.159344 -92.653612)
		(width 0.11684)
		(layer "In11.Cu")
		(net "PRSNT_CABLE_GPU_A1_ISO_N")
	)
	(segment
		(start 209.81289 -119.893588)
		(end 210.831176 -120.911874)
		(width 0.11684)
		(layer "In11.Cu")
		(net "PRSNT_CABLE_GPU_A1_ISO_N")
	)
	(segment
		(start 212.31225 -109.357922)
		(end 211.30133 -110.368842)
		(width 0.11684)
		(layer "In11.Cu")
		(net "PRSNT_CABLE_GPU_A1_ISO_N")
	)
	(segment
		(start 213.481666 -100.411788)
		(end 213.481666 -104.963722)
		(width 0.11684)
		(layer "In11.Cu")
		(net "PRSNT_CABLE_GPU_A1_ISO_N")
	)
	(segment
		(start 212.31225 -106.133138)
		(end 212.31225 -109.357922)
		(width 0.11684)
		(layer "In11.Cu")
		(net "PRSNT_CABLE_GPU_A1_ISO_N")
	)
	(segment
		(start 213.481666 -104.963722)
		(end 212.31225 -106.133138)
		(width 0.11684)
		(layer "In11.Cu")
		(net "PRSNT_CABLE_GPU_A1_ISO_N")
	)
	(segment
		(start 210.831176 -120.911874)
		(end 210.831684 -120.911874)
		(width 0.11684)
		(layer "In11.Cu")
		(net "PRSNT_CABLE_GPU_A1_ISO_N")
	)
	(segment
		(start 175.641254 -410.200348)
		(end 174.71009 -411.131512)
		(width 0.11684)
		(layer "In15.Cu")
		(net "PRSNT_CABLE_GPU_A1_ISO_N")
	)
	(segment
		(start 176.50841 -418.426392)
		(end 176.50841 -419.365176)
		(width 0.11684)
		(layer "In15.Cu")
		(net "PRSNT_CABLE_GPU_A1_ISO_N")
	)
	(segment
		(start 176.418748 -396.037816)
		(end 175.641254 -396.81531)
		(width 0.11684)
		(layer "In15.Cu")
		(net "PRSNT_CABLE_GPU_A1_ISO_N")
	)
	(segment
		(start 176.50841 -419.365176)
		(end 178.711352 -421.568118)
		(width 0.11684)
		(layer "In15.Cu")
		(net "PRSNT_CABLE_GPU_A1_ISO_N")
	)
	(segment
		(start 174.71009 -411.131512)
		(end 174.71009 -412.310834)
		(width 0.11684)
		(layer "In15.Cu")
		(net "PRSNT_CABLE_GPU_A1_ISO_N")
	)
	(segment
		(start 178.711352 -421.568118)
		(end 181.11978 -421.568118)
		(width 0.11684)
		(layer "In15.Cu")
		(net "PRSNT_CABLE_GPU_A1_ISO_N")
	)
	(segment
		(start 175.641254 -396.81531)
		(end 175.641254 -410.200348)
		(width 0.11684)
		(layer "In15.Cu")
		(net "PRSNT_CABLE_GPU_A1_ISO_N")
	)
	(segment
		(start 179.515262 -394.73886)
		(end 177.268378 -394.73886)
		(width 0.11684)
		(layer "In15.Cu")
		(net "PRSNT_CABLE_GPU_A1_ISO_N")
	)
	(segment
		(start 182.006494 -427.787054)
		(end 183.18099 -428.96155)
		(width 0.11684)
		(layer "In15.Cu")
		(net "PRSNT_CABLE_GPU_A1_ISO_N")
	)
	(segment
		(start 177.268378 -394.73886)
		(end 176.418748 -395.58849)
		(width 0.11684)
		(layer "In15.Cu")
		(net "PRSNT_CABLE_GPU_A1_ISO_N")
	)
	(segment
		(start 176.418748 -395.58849)
		(end 176.418748 -396.037816)
		(width 0.11684)
		(layer "In15.Cu")
		(net "PRSNT_CABLE_GPU_A1_ISO_N")
	)
	(segment
		(start 175.549052 -416.50285)
		(end 175.549052 -417.467034)
		(width 0.11684)
		(layer "In15.Cu")
		(net "PRSNT_CABLE_GPU_A1_ISO_N")
	)
	(segment
		(start 174.71009 -412.310834)
		(end 174.951898 -412.552642)
		(width 0.11684)
		(layer "In15.Cu")
		(net "PRSNT_CABLE_GPU_A1_ISO_N")
	)
	(segment
		(start 175.80864 -414.389062)
		(end 175.80864 -416.243262)
		(width 0.11684)
		(layer "In15.Cu")
		(net "PRSNT_CABLE_GPU_A1_ISO_N")
	)
	(segment
		(start 182.006494 -422.454832)
		(end 182.006494 -427.787054)
		(width 0.11684)
		(layer "In15.Cu")
		(net "PRSNT_CABLE_GPU_A1_ISO_N")
	)
	(segment
		(start 186.805062 -387.443472)
		(end 186.805062 -387.44906)
		(width 0.11684)
		(layer "In15.Cu")
		(net "PRSNT_CABLE_GPU_A1_ISO_N")
	)
	(segment
		(start 181.11978 -421.568118)
		(end 182.006494 -422.454832)
		(width 0.11684)
		(layer "In15.Cu")
		(net "PRSNT_CABLE_GPU_A1_ISO_N")
	)
	(segment
		(start 174.951898 -412.552642)
		(end 174.951898 -413.53232)
		(width 0.11684)
		(layer "In15.Cu")
		(net "PRSNT_CABLE_GPU_A1_ISO_N")
	)
	(segment
		(start 183.18099 -428.96155)
		(end 183.687974 -428.96155)
		(width 0.11684)
		(layer "In15.Cu")
		(net "PRSNT_CABLE_GPU_A1_ISO_N")
	)
	(segment
		(start 186.805062 -387.44906)
		(end 179.515262 -394.73886)
		(width 0.11684)
		(layer "In15.Cu")
		(net "PRSNT_CABLE_GPU_A1_ISO_N")
	)
	(segment
		(start 175.80864 -416.243262)
		(end 175.549052 -416.50285)
		(width 0.11684)
		(layer "In15.Cu")
		(net "PRSNT_CABLE_GPU_A1_ISO_N")
	)
	(segment
		(start 174.951898 -413.53232)
		(end 175.80864 -414.389062)
		(width 0.11684)
		(layer "In15.Cu")
		(net "PRSNT_CABLE_GPU_A1_ISO_N")
	)
	(segment
		(start 175.549052 -417.467034)
		(end 176.50841 -418.426392)
		(width 0.11684)
		(layer "In15.Cu")
		(net "PRSNT_CABLE_GPU_A1_ISO_N")
	)
	(via
		(at 125.418342 -387.693662)
		(size 0.4064)
		(drill 0.2032)
		(layers "F.Cu" "B.Cu")
		(net "P1V8_CPU1_RT3_1A_1D")
	)
	(via
		(at 137.362438 -384.10388)
		(size 0.508)
		(drill 0.254)
		(layers "F.Cu" "B.Cu")
		(net "P1V8_CPU1_RT3_1A_1D")
	)
	(via
		(at 137.362438 -385.09448)
		(size 0.508)
		(drill 0.254)
		(layers "F.Cu" "B.Cu")
		(net "P1V8_CPU1_RT3_1A_1D")
	)
	(via
		(at 125.278388 -387.084062)
		(size 0.4064)
		(drill 0.2032)
		(layers "F.Cu" "B.Cu")
		(net "P1V8_CPU1_RT3_1A_1D")
	)
	(via
		(at 136.59358 -386.04063)
		(size 0.508)
		(drill 0.254)
		(layers "F.Cu" "B.Cu")
		(net "P1V8_CPU1_RT3_1A")
	)
	(via
		(at 121.8184 -387.693662)
		(size 0.4064)
		(drill 0.2032)
		(layers "F.Cu" "B.Cu")
		(net "P1V8_CPU1_RT3_1A")
	)
	(via
		(at 135.462518 -384.671062)
		(size 0.508)
		(drill 0.254)
		(layers "F.Cu" "B.Cu")
		(net "P1V8_CPU1_RT3_1A")
	)
	(via
		(at 135.462518 -384.036062)
		(size 0.508)
		(drill 0.254)
		(layers "F.Cu" "B.Cu")
		(net "P1V8_CPU1_RT3_1A")
	)
	(via
		(at 135.462518 -385.306062)
		(size 0.508)
		(drill 0.254)
		(layers "F.Cu" "B.Cu")
		(net "P1V8_CPU1_RT3_1A")
	)
	(via
		(at 134.99973 -385.8895)
		(size 0.508)
		(drill 0.254)
		(layers "F.Cu" "B.Cu")
		(net "P1V8_CPU1_RT3_1A")
	)
	(via
		(at 123.01855 -387.693662)
		(size 0.4064)
		(drill 0.2032)
		(layers "F.Cu" "B.Cu")
		(net "P1V8_CPU1_RT3_1A")
	)
	(via
		(at 135.636508 -386.444744)
		(size 0.508)
		(drill 0.254)
		(layers "F.Cu" "B.Cu")
		(net "P1V8_CPU1_RT3_1A")
	)
	(via
		(at 134.33806 -385.56184)
		(size 0.6604)
		(drill 0.3302)
		(layers "F.Cu" "B.Cu")
		(net "P1V8_CPU1_RT3_1A")
	)
	(via
		(at 124.218446 -387.693662)
		(size 0.4064)
		(drill 0.2032)
		(layers "F.Cu" "B.Cu")
		(net "P1V8_CPU1_RT3_1A")
	)
	(via
		(at 136.562338 -385.09448)
		(size 0.508)
		(drill 0.254)
		(layers "F.Cu" "B.Cu")
		(net "P1V8_CPU1_RT3_1A")
	)
	(via
		(at 121.678446 -387.084062)
		(size 0.4064)
		(drill 0.2032)
		(layers "F.Cu" "B.Cu")
		(net "P1V8_CPU1_RT3_1A")
	)
	(via
		(at 124.078492 -387.084062)
		(size 0.4064)
		(drill 0.2032)
		(layers "F.Cu" "B.Cu")
		(net "P1V8_CPU1_RT3_1A")
	)
	(via
		(at 136.562338 -384.10388)
		(size 0.508)
		(drill 0.254)
		(layers "F.Cu" "B.Cu")
		(net "P1V8_CPU1_RT3_1A")
	)
	(via
		(at 122.878596 -387.084062)
		(size 0.4064)
		(drill 0.2032)
		(layers "F.Cu" "B.Cu")
		(net "P1V8_CPU1_RT3_1A")
	)
	(via
		(at 134.37235 -384.125724)
		(size 0.6604)
		(drill 0.3302)
		(layers "F.Cu" "B.Cu")
		(net "P1V8_CPU1_RT3_1A")
	)
	(via
		(at 170.86961 -388.753604)
		(size 0.508)
		(drill 0.254)
		(layers "F.Cu" "B.Cu")
		(net "P1V8_CPU1_RT2_1A_1D")
	)
	(via
		(at 157.94609 -387.693662)
		(size 0.4064)
		(drill 0.2032)
		(layers "F.Cu" "B.Cu")
		(net "P1V8_CPU1_RT2_1A_1D")
	)
	(via
		(at 157.806136 -387.084062)
		(size 0.4064)
		(drill 0.2032)
		(layers "F.Cu" "B.Cu")
		(net "P1V8_CPU1_RT2_1A_1D")
	)
	(via
		(at 170.86961 -387.763004)
		(size 0.508)
		(drill 0.254)
		(layers "F.Cu" "B.Cu")
		(net "P1V8_CPU1_RT2_1A_1D")
	)
	(via
		(at 170.143678 -388.239508)
		(size 0.6604)
		(drill 0.3302)
		(layers "F.Cu" "B.Cu")
		(net "P1V8_CPU1_RT2_1A_1D")
	)
	(via
		(at 168.44264 -386.520436)
		(size 0.508)
		(drill 0.254)
		(layers "F.Cu" "B.Cu")
		(net "P1V8_CPU1_RT2_1A")
	)
	(via
		(at 154.346148 -387.693662)
		(size 0.4064)
		(drill 0.2032)
		(layers "F.Cu" "B.Cu")
		(net "P1V8_CPU1_RT2_1A")
	)
	(via
		(at 155.406344 -387.084062)
		(size 0.4064)
		(drill 0.2032)
		(layers "F.Cu" "B.Cu")
		(net "P1V8_CPU1_RT2_1A")
	)
	(via
		(at 156.746194 -387.693662)
		(size 0.4064)
		(drill 0.2032)
		(layers "F.Cu" "B.Cu")
		(net "P1V8_CPU1_RT2_1A")
	)
	(via
		(at 154.206194 -387.084062)
		(size 0.4064)
		(drill 0.2032)
		(layers "F.Cu" "B.Cu")
		(net "P1V8_CPU1_RT2_1A")
	)
	(via
		(at 168.44264 -387.155436)
		(size 0.508)
		(drill 0.254)
		(layers "F.Cu" "B.Cu")
		(net "P1V8_CPU1_RT2_1A")
	)
	(via
		(at 167.80764 -385.885436)
		(size 0.508)
		(drill 0.254)
		(layers "F.Cu" "B.Cu")
		(net "P1V8_CPU1_RT2_1A")
	)
	(via
		(at 156.60624 -387.084062)
		(size 0.4064)
		(drill 0.2032)
		(layers "F.Cu" "B.Cu")
		(net "P1V8_CPU1_RT2_1A")
	)
	(via
		(at 169.121328 -387.96595)
		(size 0.508)
		(drill 0.254)
		(layers "F.Cu" "B.Cu")
		(net "P1V8_CPU1_RT2_1A")
	)
	(via
		(at 168.44264 -383.980436)
		(size 0.508)
		(drill 0.254)
		(layers "F.Cu" "B.Cu")
		(net "P1V8_CPU1_RT2_1A")
	)
	(via
		(at 168.07434 -384.593592)
		(size 0.508)
		(drill 0.254)
		(layers "F.Cu" "B.Cu")
		(net "P1V8_CPU1_RT2_1A")
	)
	(via
		(at 155.546298 -387.693662)
		(size 0.4064)
		(drill 0.2032)
		(layers "F.Cu" "B.Cu")
		(net "P1V8_CPU1_RT2_1A")
	)
	(via
		(at 168.44264 -385.250436)
		(size 0.508)
		(drill 0.254)
		(layers "F.Cu" "B.Cu")
		(net "P1V8_CPU1_RT2_1A")
	)
	(via
		(at 168.44264 -385.885436)
		(size 0.508)
		(drill 0.254)
		(layers "F.Cu" "B.Cu")
		(net "P1V8_CPU1_RT2_1A")
	)
	(via
		(at 119.418354 -387.693662)
		(size 0.4064)
		(drill 0.2032)
		(layers "F.Cu" "B.Cu")
		(net "P0V9_CPU1_RT3_2A_2D")
	)
	(via
		(at 108.36148 -394.168376)
		(size 0.508)
		(drill 0.254)
		(layers "F.Cu" "B.Cu")
		(net "P0V9_CPU1_RT3_2A_2D")
	)
	(via
		(at 119.2784 -387.084062)
		(size 0.4064)
		(drill 0.2032)
		(layers "F.Cu" "B.Cu")
		(net "P0V9_CPU1_RT3_2A_2D")
	)
	(via
		(at 107.72521 -393.979146)
		(size 0.508)
		(drill 0.254)
		(layers "F.Cu" "B.Cu")
		(net "P0V9_CPU1_RT3_2A_2D")
	)
	(via
		(at 107.72521 -393.242546)
		(size 0.508)
		(drill 0.254)
		(layers "F.Cu" "B.Cu")
		(net "P0V9_CPU1_RT3_2A_2D")
	)
	(via
		(at 127.818388 -387.693662)
		(size 0.4064)
		(drill 0.2032)
		(layers "F.Cu" "B.Cu")
		(net "P0V9_CPU1_RT3_2A_2D")
	)
	(via
		(at 107.723178 -394.699236)
		(size 0.6604)
		(drill 0.3302)
		(layers "F.Cu" "B.Cu")
		(net "P0V9_CPU1_RT3_2A_2D")
	)
	(via
		(at 127.678434 -387.084062)
		(size 0.4064)
		(drill 0.2032)
		(layers "F.Cu" "B.Cu")
		(net "P0V9_CPU1_RT3_2A_2D")
	)
	(via
		(at 107.111038 -394.168376)
		(size 0.508)
		(drill 0.254)
		(layers "F.Cu" "B.Cu")
		(net "P0V9_CPU1_RT3_2A_2D")
	)
	(via
		(at 118.218458 -387.693662)
		(size 0.4064)
		(drill 0.2032)
		(layers "F.Cu" "B.Cu")
		(net "P0V9_CPU1_RT3_2A")
	)
	(via
		(at 116.878608 -387.084062)
		(size 0.4064)
		(drill 0.2032)
		(layers "F.Cu" "B.Cu")
		(net "P0V9_CPU1_RT3_2A")
	)
	(via
		(at 114.478562 -387.084062)
		(size 0.4064)
		(drill 0.2032)
		(layers "F.Cu" "B.Cu")
		(net "P0V9_CPU1_RT3_2A")
	)
	(via
		(at 117.020848 -396.236444)
		(size 0.6604)
		(drill 0.3302)
		(layers "F.Cu" "B.Cu")
		(net "P0V9_CPU1_RT3_2A")
	)
	(via
		(at 132.478526 -387.084062)
		(size 0.4064)
		(drill 0.2032)
		(layers "F.Cu" "B.Cu")
		(net "P0V9_CPU1_RT3_2A")
	)
	(via
		(at 109.861858 -393.52093)
		(size 0.508)
		(drill 0.254)
		(layers "F.Cu" "B.Cu")
		(net "P0V9_CPU1_RT3_2A")
	)
	(via
		(at 109.226858 -392.25093)
		(size 0.508)
		(drill 0.254)
		(layers "F.Cu" "B.Cu")
		(net "P0V9_CPU1_RT3_2A")
	)
	(via
		(at 128.922526 -396.130018)
		(size 0.6604)
		(drill 0.3302)
		(layers "F.Cu" "B.Cu")
		(net "P0V9_CPU1_RT3_2A")
	)
	(via
		(at 129.018538 -387.693662)
		(size 0.4064)
		(drill 0.2032)
		(layers "F.Cu" "B.Cu")
		(net "P0V9_CPU1_RT3_2A")
	)
	(via
		(at 110.496858 -393.52093)
		(size 0.508)
		(drill 0.254)
		(layers "F.Cu" "B.Cu")
		(net "P0V9_CPU1_RT3_2A")
	)
	(via
		(at 132.61848 -387.693662)
		(size 0.4064)
		(drill 0.2032)
		(layers "F.Cu" "B.Cu")
		(net "P0V9_CPU1_RT3_2A")
	)
	(via
		(at 108.591858 -391.61593)
		(size 0.508)
		(drill 0.254)
		(layers "F.Cu" "B.Cu")
		(net "P0V9_CPU1_RT3_2A")
	)
	(via
		(at 115.678458 -387.084062)
		(size 0.4064)
		(drill 0.2032)
		(layers "F.Cu" "B.Cu")
		(net "P0V9_CPU1_RT3_2A")
	)
	(via
		(at 115.818412 -387.693662)
		(size 0.4064)
		(drill 0.2032)
		(layers "F.Cu" "B.Cu")
		(net "P0V9_CPU1_RT3_2A")
	)
	(via
		(at 118.078504 -387.084062)
		(size 0.4064)
		(drill 0.2032)
		(layers "F.Cu" "B.Cu")
		(net "P0V9_CPU1_RT3_2A")
	)
	(via
		(at 108.591858 -392.25093)
		(size 0.508)
		(drill 0.254)
		(layers "F.Cu" "B.Cu")
		(net "P0V9_CPU1_RT3_2A")
	)
	(via
		(at 131.418584 -387.693662)
		(size 0.4064)
		(drill 0.2032)
		(layers "F.Cu" "B.Cu")
		(net "P0V9_CPU1_RT3_2A")
	)
	(via
		(at 110.496858 -391.61593)
		(size 0.508)
		(drill 0.254)
		(layers "F.Cu" "B.Cu")
		(net "P0V9_CPU1_RT3_2A")
	)
	(via
		(at 109.226858 -392.88593)
		(size 0.508)
		(drill 0.254)
		(layers "F.Cu" "B.Cu")
		(net "P0V9_CPU1_RT3_2A")
	)
	(via
		(at 134.023354 -396.165578)
		(size 0.6604)
		(drill 0.3302)
		(layers "F.Cu" "B.Cu")
		(net "P0V9_CPU1_RT3_2A")
	)
	(via
		(at 111.955326 -395.421612)
		(size 0.6604)
		(drill 0.3302)
		(layers "F.Cu" "B.Cu")
		(net "P0V9_CPU1_RT3_2A")
	)
	(via
		(at 109.861858 -392.88593)
		(size 0.508)
		(drill 0.254)
		(layers "F.Cu" "B.Cu")
		(net "P0V9_CPU1_RT3_2A")
	)
	(via
		(at 117.018562 -387.693662)
		(size 0.4064)
		(drill 0.2032)
		(layers "F.Cu" "B.Cu")
		(net "P0V9_CPU1_RT3_2A")
	)
	(via
		(at 110.496858 -392.25093)
		(size 0.508)
		(drill 0.254)
		(layers "F.Cu" "B.Cu")
		(net "P0V9_CPU1_RT3_2A")
	)
	(via
		(at 109.861858 -391.61593)
		(size 0.508)
		(drill 0.254)
		(layers "F.Cu" "B.Cu")
		(net "P0V9_CPU1_RT3_2A")
	)
	(via
		(at 108.591858 -392.88593)
		(size 0.508)
		(drill 0.254)
		(layers "F.Cu" "B.Cu")
		(net "P0V9_CPU1_RT3_2A")
	)
	(via
		(at 109.226858 -391.61593)
		(size 0.508)
		(drill 0.254)
		(layers "F.Cu" "B.Cu")
		(net "P0V9_CPU1_RT3_2A")
	)
	(via
		(at 128.878584 -387.084062)
		(size 0.4064)
		(drill 0.2032)
		(layers "F.Cu" "B.Cu")
		(net "P0V9_CPU1_RT3_2A")
	)
	(via
		(at 131.27863 -387.084062)
		(size 0.4064)
		(drill 0.2032)
		(layers "F.Cu" "B.Cu")
		(net "P0V9_CPU1_RT3_2A")
	)
	(via
		(at 108.591858 -393.52093)
		(size 0.508)
		(drill 0.254)
		(layers "F.Cu" "B.Cu")
		(net "P0V9_CPU1_RT3_2A")
	)
	(via
		(at 130.07848 -387.084062)
		(size 0.4064)
		(drill 0.2032)
		(layers "F.Cu" "B.Cu")
		(net "P0V9_CPU1_RT3_2A")
	)
	(via
		(at 114.618516 -387.693662)
		(size 0.4064)
		(drill 0.2032)
		(layers "F.Cu" "B.Cu")
		(net "P0V9_CPU1_RT3_2A")
	)
	(via
		(at 109.861858 -392.25093)
		(size 0.508)
		(drill 0.254)
		(layers "F.Cu" "B.Cu")
		(net "P0V9_CPU1_RT3_2A")
	)
	(via
		(at 110.496858 -392.88593)
		(size 0.508)
		(drill 0.254)
		(layers "F.Cu" "B.Cu")
		(net "P0V9_CPU1_RT3_2A")
	)
	(via
		(at 109.226858 -393.52093)
		(size 0.508)
		(drill 0.254)
		(layers "F.Cu" "B.Cu")
		(net "P0V9_CPU1_RT3_2A")
	)
	(via
		(at 122.865388 -396.449042)
		(size 0.6604)
		(drill 0.3302)
		(layers "F.Cu" "B.Cu")
		(net "P0V9_CPU1_RT3_2A")
	)
	(via
		(at 130.218434 -387.693662)
		(size 0.4064)
		(drill 0.2032)
		(layers "F.Cu" "B.Cu")
		(net "P0V9_CPU1_RT3_2A")
	)
	(via
		(at 151.946102 -387.693662)
		(size 0.4064)
		(drill 0.2032)
		(layers "F.Cu" "B.Cu")
		(net "P0V9_CPU1_RT2_2A_2D")
	)
	(via
		(at 160.346136 -387.693662)
		(size 0.4064)
		(drill 0.2032)
		(layers "F.Cu" "B.Cu")
		(net "P0V9_CPU1_RT2_2A_2D")
	)
	(via
		(at 140.252958 -393.242546)
		(size 0.508)
		(drill 0.254)
		(layers "F.Cu" "B.Cu")
		(net "P0V9_CPU1_RT2_2A_2D")
	)
	(via
		(at 140.252958 -393.979146)
		(size 0.508)
		(drill 0.254)
		(layers "F.Cu" "B.Cu")
		(net "P0V9_CPU1_RT2_2A_2D")
	)
	(via
		(at 139.638786 -394.168376)
		(size 0.508)
		(drill 0.254)
		(layers "F.Cu" "B.Cu")
		(net "P0V9_CPU1_RT2_2A_2D")
	)
	(via
		(at 151.806148 -387.084062)
		(size 0.4064)
		(drill 0.2032)
		(layers "F.Cu" "B.Cu")
		(net "P0V9_CPU1_RT2_2A_2D")
	)
	(via
		(at 160.206182 -387.084062)
		(size 0.4064)
		(drill 0.2032)
		(layers "F.Cu" "B.Cu")
		(net "P0V9_CPU1_RT2_2A_2D")
	)
	(via
		(at 140.250926 -394.699236)
		(size 0.6604)
		(drill 0.3302)
		(layers "F.Cu" "B.Cu")
		(net "P0V9_CPU1_RT2_2A_2D")
	)
	(via
		(at 140.889228 -394.168376)
		(size 0.508)
		(drill 0.254)
		(layers "F.Cu" "B.Cu")
		(net "P0V9_CPU1_RT2_2A_2D")
	)
	(via
		(at 144.012412 -395.102588)
		(size 0.6604)
		(drill 0.3302)
		(layers "F.Cu" "B.Cu")
		(net "P0V9_CPU1_RT2_2A")
	)
	(via
		(at 162.746182 -387.693662)
		(size 0.4064)
		(drill 0.2032)
		(layers "F.Cu" "B.Cu")
		(net "P0V9_CPU1_RT2_2A")
	)
	(via
		(at 141.119606 -393.52093)
		(size 0.508)
		(drill 0.254)
		(layers "F.Cu" "B.Cu")
		(net "P0V9_CPU1_RT2_2A")
	)
	(via
		(at 168.435782 -390.840976)
		(size 0.508)
		(drill 0.254)
		(layers "F.Cu" "B.Cu")
		(net "P0V9_CPU1_RT2_2A")
	)
	(via
		(at 150.606252 -387.084062)
		(size 0.4064)
		(drill 0.2032)
		(layers "F.Cu" "B.Cu")
		(net "P0V9_CPU1_RT2_2A")
	)
	(via
		(at 168.435782 -392.110976)
		(size 0.508)
		(drill 0.254)
		(layers "F.Cu" "B.Cu")
		(net "P0V9_CPU1_RT2_2A")
	)
	(via
		(at 147.146264 -387.693662)
		(size 0.4064)
		(drill 0.2032)
		(layers "F.Cu" "B.Cu")
		(net "P0V9_CPU1_RT2_2A")
	)
	(via
		(at 141.754606 -392.25093)
		(size 0.508)
		(drill 0.254)
		(layers "F.Cu" "B.Cu")
		(net "P0V9_CPU1_RT2_2A")
	)
	(via
		(at 161.406332 -387.084062)
		(size 0.4064)
		(drill 0.2032)
		(layers "F.Cu" "B.Cu")
		(net "P0V9_CPU1_RT2_2A")
	)
	(via
		(at 142.389606 -393.52093)
		(size 0.508)
		(drill 0.254)
		(layers "F.Cu" "B.Cu")
		(net "P0V9_CPU1_RT2_2A")
	)
	(via
		(at 165.006274 -387.084062)
		(size 0.4064)
		(drill 0.2032)
		(layers "F.Cu" "B.Cu")
		(net "P0V9_CPU1_RT2_2A")
	)
	(via
		(at 167.882062 -391.794492)
		(size 0.508)
		(drill 0.254)
		(layers "F.Cu" "B.Cu")
		(net "P0V9_CPU1_RT2_2A")
	)
	(via
		(at 168.435782 -391.475976)
		(size 0.508)
		(drill 0.254)
		(layers "F.Cu" "B.Cu")
		(net "P0V9_CPU1_RT2_2A")
	)
	(via
		(at 143.024606 -392.88593)
		(size 0.508)
		(drill 0.254)
		(layers "F.Cu" "B.Cu")
		(net "P0V9_CPU1_RT2_2A")
	)
	(via
		(at 142.389606 -392.88593)
		(size 0.508)
		(drill 0.254)
		(layers "F.Cu" "B.Cu")
		(net "P0V9_CPU1_RT2_2A")
	)
	(via
		(at 141.754606 -392.88593)
		(size 0.508)
		(drill 0.254)
		(layers "F.Cu" "B.Cu")
		(net "P0V9_CPU1_RT2_2A")
	)
	(via
		(at 142.389606 -392.25093)
		(size 0.508)
		(drill 0.254)
		(layers "F.Cu" "B.Cu")
		(net "P0V9_CPU1_RT2_2A")
	)
	(via
		(at 161.546286 -387.693662)
		(size 0.4064)
		(drill 0.2032)
		(layers "F.Cu" "B.Cu")
		(net "P0V9_CPU1_RT2_2A")
	)
	(via
		(at 148.34616 -387.693662)
		(size 0.4064)
		(drill 0.2032)
		(layers "F.Cu" "B.Cu")
		(net "P0V9_CPU1_RT2_2A")
	)
	(via
		(at 162.606228 -387.084062)
		(size 0.4064)
		(drill 0.2032)
		(layers "F.Cu" "B.Cu")
		(net "P0V9_CPU1_RT2_2A")
	)
	(via
		(at 164.804852 -396.661386)
		(size 0.6604)
		(drill 0.3302)
		(layers "F.Cu" "B.Cu")
		(net "P0V9_CPU1_RT2_2A")
	)
	(via
		(at 141.119606 -391.61593)
		(size 0.508)
		(drill 0.254)
		(layers "F.Cu" "B.Cu")
		(net "P0V9_CPU1_RT2_2A")
	)
	(via
		(at 148.688044 -396.076678)
		(size 0.6604)
		(drill 0.3302)
		(layers "F.Cu" "B.Cu")
		(net "P0V9_CPU1_RT2_2A")
	)
	(via
		(at 141.119606 -392.88593)
		(size 0.508)
		(drill 0.254)
		(layers "F.Cu" "B.Cu")
		(net "P0V9_CPU1_RT2_2A")
	)
	(via
		(at 143.024606 -393.52093)
		(size 0.508)
		(drill 0.254)
		(layers "F.Cu" "B.Cu")
		(net "P0V9_CPU1_RT2_2A")
	)
	(via
		(at 165.146228 -387.693662)
		(size 0.4064)
		(drill 0.2032)
		(layers "F.Cu" "B.Cu")
		(net "P0V9_CPU1_RT2_2A")
	)
	(via
		(at 143.024606 -391.61593)
		(size 0.508)
		(drill 0.254)
		(layers "F.Cu" "B.Cu")
		(net "P0V9_CPU1_RT2_2A")
	)
	(via
		(at 163.806378 -387.084062)
		(size 0.4064)
		(drill 0.2032)
		(layers "F.Cu" "B.Cu")
		(net "P0V9_CPU1_RT2_2A")
	)
	(via
		(at 167.882062 -391.159492)
		(size 0.508)
		(drill 0.254)
		(layers "F.Cu" "B.Cu")
		(net "P0V9_CPU1_RT2_2A")
	)
	(via
		(at 159.916622 -396.377922)
		(size 0.6604)
		(drill 0.3302)
		(layers "F.Cu" "B.Cu")
		(net "P0V9_CPU1_RT2_2A")
	)
	(via
		(at 149.54631 -387.693662)
		(size 0.4064)
		(drill 0.2032)
		(layers "F.Cu" "B.Cu")
		(net "P0V9_CPU1_RT2_2A")
	)
	(via
		(at 148.206206 -387.084062)
		(size 0.4064)
		(drill 0.2032)
		(layers "F.Cu" "B.Cu")
		(net "P0V9_CPU1_RT2_2A")
	)
	(via
		(at 142.389606 -391.61593)
		(size 0.508)
		(drill 0.254)
		(layers "F.Cu" "B.Cu")
		(net "P0V9_CPU1_RT2_2A")
	)
	(via
		(at 150.746206 -387.693662)
		(size 0.4064)
		(drill 0.2032)
		(layers "F.Cu" "B.Cu")
		(net "P0V9_CPU1_RT2_2A")
	)
	(via
		(at 154.709622 -396.307056)
		(size 0.6604)
		(drill 0.3302)
		(layers "F.Cu" "B.Cu")
		(net "P0V9_CPU1_RT2_2A")
	)
	(via
		(at 141.754606 -393.52093)
		(size 0.508)
		(drill 0.254)
		(layers "F.Cu" "B.Cu")
		(net "P0V9_CPU1_RT2_2A")
	)
	(via
		(at 147.00631 -387.084062)
		(size 0.4064)
		(drill 0.2032)
		(layers "F.Cu" "B.Cu")
		(net "P0V9_CPU1_RT2_2A")
	)
	(via
		(at 141.754606 -391.61593)
		(size 0.508)
		(drill 0.254)
		(layers "F.Cu" "B.Cu")
		(net "P0V9_CPU1_RT2_2A")
	)
	(via
		(at 141.119606 -392.25093)
		(size 0.508)
		(drill 0.254)
		(layers "F.Cu" "B.Cu")
		(net "P0V9_CPU1_RT2_2A")
	)
	(via
		(at 163.946332 -387.693662)
		(size 0.4064)
		(drill 0.2032)
		(layers "F.Cu" "B.Cu")
		(net "P0V9_CPU1_RT2_2A")
	)
	(via
		(at 143.024606 -392.25093)
		(size 0.508)
		(drill 0.254)
		(layers "F.Cu" "B.Cu")
		(net "P0V9_CPU1_RT2_2A")
	)
	(via
		(at 149.406356 -387.084062)
		(size 0.4064)
		(drill 0.2032)
		(layers "F.Cu" "B.Cu")
		(net "P0V9_CPU1_RT2_2A")
	)
	(segment
		(start 112.560862 -391.240518)
		(end 112.560862 -391.09777)
		(width 0.254)
		(layer "F.Cu")
		(net "NCF_CPU1_P3_GND")
	)
	(segment
		(start 134.317994 -390.761474)
		(end 134.317994 -390.981184)
		(width 0.254)
		(layer "F.Cu")
		(net "NCF_CPU1_P3_GND")
	)
	(segment
		(start 134.01802 -383.402586)
		(end 133.983476 -383.368042)
		(width 0.254)
		(layer "F.Cu")
		(net "NCF_CPU1_P3_GND")
	)
	(segment
		(start 113.018062 -382.907286)
		(end 113.018062 -383.402586)
		(width 0.254)
		(layer "F.Cu")
		(net "NCF_CPU1_P3_GND")
	)
	(segment
		(start 134.800594 -390.819132)
		(end 134.375652 -390.819132)
		(width 0.254)
		(layer "F.Cu")
		(net "NCF_CPU1_P3_GND")
	)
	(segment
		(start 113.318036 -390.761474)
		(end 113.018062 -391.281158)
		(width 0.254)
		(layer "F.Cu")
		(net "NCF_CPU1_P3_GND")
	)
	(segment
		(start 112.717834 -383.92227)
		(end 112.459262 -383.663698)
		(width 0.254)
		(layer "F.Cu")
		(net "NCF_CPU1_P3_GND")
	)
	(segment
		(start 134.01802 -383.402586)
		(end 134.317994 -383.92227)
		(width 0.254)
		(layer "F.Cu")
		(net "NCF_CPU1_P3_GND")
	)
	(segment
		(start 134.317994 -390.981184)
		(end 134.01802 -391.281158)
		(width 0.254)
		(layer "F.Cu")
		(net "NCF_CPU1_P3_GND")
	)
	(segment
		(start 113.594896 -392.33475)
		(end 113.4364 -392.33475)
		(width 0.254)
		(layer "F.Cu")
		(net "NCF_CPU1_P3_GND")
	)
	(segment
		(start 134.516876 -383.301494)
		(end 134.617968 -383.402586)
		(width 0.254)
		(layer "F.Cu")
		(net "NCF_CPU1_P3_GND")
	)
	(segment
		(start 134.375652 -390.819132)
		(end 134.317994 -390.761474)
		(width 0.254)
		(layer "F.Cu")
		(net "NCF_CPU1_P3_GND")
	)
	(segment
		(start 134.516876 -382.86817)
		(end 134.516876 -383.301494)
		(width 0.254)
		(layer "F.Cu")
		(net "NCF_CPU1_P3_GND")
	)
	(segment
		(start 112.459262 -383.663698)
		(end 112.459262 -382.907286)
		(width 0.254)
		(layer "F.Cu")
		(net "NCF_CPU1_P3_GND")
	)
	(segment
		(start 113.318036 -383.92227)
		(end 112.717834 -383.92227)
		(width 0.254)
		(layer "F.Cu")
		(net "NCF_CPU1_P3_GND")
	)
	(segment
		(start 113.018062 -391.916412)
		(end 113.018062 -391.281158)
		(width 0.254)
		(layer "F.Cu")
		(net "NCF_CPU1_P3_GND")
	)
	(segment
		(start 112.717834 -390.940798)
		(end 112.717834 -390.761474)
		(width 0.254)
		(layer "F.Cu")
		(net "NCF_CPU1_P3_GND")
	)
	(segment
		(start 112.560862 -391.09777)
		(end 112.717834 -390.940798)
		(width 0.254)
		(layer "F.Cu")
		(net "NCF_CPU1_P3_GND")
	)
	(segment
		(start 113.4364 -392.33475)
		(end 113.018062 -391.916412)
		(width 0.254)
		(layer "F.Cu")
		(net "NCF_CPU1_P3_GND")
	)
	(segment
		(start 133.983476 -383.368042)
		(end 133.983476 -382.86817)
		(width 0.254)
		(layer "F.Cu")
		(net "NCF_CPU1_P3_GND")
	)
	(via
		(at 113.594896 -392.33475)
		(size 0.4064)
		(drill 0.2032)
		(layers "F.Cu" "B.Cu")
		(net "NCF_CPU1_P3_GND")
	)
	(via
		(at 112.560862 -391.240518)
		(size 0.4064)
		(drill 0.2032)
		(layers "F.Cu" "B.Cu")
		(net "NCF_CPU1_P3_GND")
	)
	(via
		(at 135.151114 -383.086864)
		(size 0.6604)
		(drill 0.3302)
		(layers "F.Cu" "B.Cu")
		(net "NCF_CPU1_P3_GND")
	)
	(via
		(at 134.516876 -382.86817)
		(size 0.4064)
		(drill 0.2032)
		(layers "F.Cu" "B.Cu")
		(net "NCF_CPU1_P3_GND")
	)
	(via
		(at 134.800594 -390.819132)
		(size 0.4064)
		(drill 0.2032)
		(layers "F.Cu" "B.Cu")
		(net "NCF_CPU1_P3_GND")
	)
	(via
		(at 112.459262 -382.907286)
		(size 0.4064)
		(drill 0.2032)
		(layers "F.Cu" "B.Cu")
		(net "NCF_CPU1_P3_GND")
	)
	(via
		(at 113.018062 -382.907286)
		(size 0.4064)
		(drill 0.2032)
		(layers "F.Cu" "B.Cu")
		(net "NCF_CPU1_P3_GND")
	)
	(via
		(at 133.983476 -382.86817)
		(size 0.4064)
		(drill 0.2032)
		(layers "F.Cu" "B.Cu")
		(net "NCF_CPU1_P3_GND")
	)
	(segment
		(start 145.08861 -391.240518)
		(end 145.08861 -391.09777)
		(width 0.254)
		(layer "F.Cu")
		(net "NCF_CPU1_P2_GND")
	)
	(segment
		(start 145.558764 -383.09804)
		(end 145.558764 -382.89484)
		(width 0.254)
		(layer "F.Cu")
		(net "NCF_CPU1_P2_GND")
	)
	(segment
		(start 166.511224 -383.368042)
		(end 166.511224 -382.86817)
		(width 0.254)
		(layer "F.Cu")
		(net "NCF_CPU1_P2_GND")
	)
	(segment
		(start 167.044624 -382.86817)
		(end 167.044624 -383.301494)
		(width 0.254)
		(layer "F.Cu")
		(net "NCF_CPU1_P2_GND")
	)
	(segment
		(start 167.044624 -383.301494)
		(end 167.145716 -383.402586)
		(width 0.254)
		(layer "F.Cu")
		(net "NCF_CPU1_P2_GND")
	)
	(segment
		(start 167.270684 -390.761474)
		(end 166.845742 -390.761474)
		(width 0.254)
		(layer "F.Cu")
		(net "NCF_CPU1_P2_GND")
	)
	(segment
		(start 146.122644 -392.33475)
		(end 145.964148 -392.33475)
		(width 0.254)
		(layer "F.Cu")
		(net "NCF_CPU1_P2_GND")
	)
	(segment
		(start 145.54581 -383.110994)
		(end 145.558764 -383.09804)
		(width 0.254)
		(layer "F.Cu")
		(net "NCF_CPU1_P2_GND")
	)
	(segment
		(start 145.08861 -391.09777)
		(end 145.245582 -390.940798)
		(width 0.254)
		(layer "F.Cu")
		(net "NCF_CPU1_P2_GND")
	)
	(segment
		(start 145.54581 -391.916412)
		(end 145.54581 -391.281158)
		(width 0.254)
		(layer "F.Cu")
		(net "NCF_CPU1_P2_GND")
	)
	(segment
		(start 166.845742 -390.981184)
		(end 166.545768 -391.281158)
		(width 0.254)
		(layer "F.Cu")
		(net "NCF_CPU1_P2_GND")
	)
	(segment
		(start 145.245582 -390.940798)
		(end 145.245582 -390.761474)
		(width 0.254)
		(layer "F.Cu")
		(net "NCF_CPU1_P2_GND")
	)
	(segment
		(start 144.98701 -383.663698)
		(end 144.98701 -382.907286)
		(width 0.254)
		(layer "F.Cu")
		(net "NCF_CPU1_P2_GND")
	)
	(segment
		(start 166.545768 -383.402586)
		(end 166.511224 -383.368042)
		(width 0.254)
		(layer "F.Cu")
		(net "NCF_CPU1_P2_GND")
	)
	(segment
		(start 145.845784 -390.761474)
		(end 145.54581 -391.281158)
		(width 0.254)
		(layer "F.Cu")
		(net "NCF_CPU1_P2_GND")
	)
	(segment
		(start 145.964148 -392.33475)
		(end 145.54581 -391.916412)
		(width 0.254)
		(layer "F.Cu")
		(net "NCF_CPU1_P2_GND")
	)
	(segment
		(start 145.845784 -383.92227)
		(end 145.245582 -383.92227)
		(width 0.254)
		(layer "F.Cu")
		(net "NCF_CPU1_P2_GND")
	)
	(segment
		(start 167.328342 -390.819132)
		(end 167.270684 -390.761474)
		(width 0.254)
		(layer "F.Cu")
		(net "NCF_CPU1_P2_GND")
	)
	(segment
		(start 166.545768 -383.402586)
		(end 166.845742 -383.92227)
		(width 0.254)
		(layer "F.Cu")
		(net "NCF_CPU1_P2_GND")
	)
	(segment
		(start 145.245582 -383.92227)
		(end 144.98701 -383.663698)
		(width 0.254)
		(layer "F.Cu")
		(net "NCF_CPU1_P2_GND")
	)
	(segment
		(start 145.54581 -383.402586)
		(end 145.54581 -383.110994)
		(width 0.254)
		(layer "F.Cu")
		(net "NCF_CPU1_P2_GND")
	)
	(segment
		(start 166.845742 -390.761474)
		(end 166.845742 -390.981184)
		(width 0.254)
		(layer "F.Cu")
		(net "NCF_CPU1_P2_GND")
	)
	(via
		(at 167.044624 -382.86817)
		(size 0.4064)
		(drill 0.2032)
		(layers "F.Cu" "B.Cu")
		(net "NCF_CPU1_P2_GND")
	)
	(via
		(at 145.558764 -382.89484)
		(size 0.4064)
		(drill 0.2032)
		(layers "F.Cu" "B.Cu")
		(net "NCF_CPU1_P2_GND")
	)
	(via
		(at 166.511224 -382.86817)
		(size 0.4064)
		(drill 0.2032)
		(layers "F.Cu" "B.Cu")
		(net "NCF_CPU1_P2_GND")
	)
	(via
		(at 146.122644 -392.33475)
		(size 0.4064)
		(drill 0.2032)
		(layers "F.Cu" "B.Cu")
		(net "NCF_CPU1_P2_GND")
	)
	(via
		(at 144.98701 -382.907286)
		(size 0.4064)
		(drill 0.2032)
		(layers "F.Cu" "B.Cu")
		(net "NCF_CPU1_P2_GND")
	)
	(via
		(at 167.678862 -383.086864)
		(size 0.6604)
		(drill 0.3302)
		(layers "F.Cu" "B.Cu")
		(net "NCF_CPU1_P2_GND")
	)
	(via
		(at 145.08861 -391.240518)
		(size 0.4064)
		(drill 0.2032)
		(layers "F.Cu" "B.Cu")
		(net "NCF_CPU1_P2_GND")
	)
	(via
		(at 167.328342 -390.819132)
		(size 0.4064)
		(drill 0.2032)
		(layers "F.Cu" "B.Cu")
		(net "NCF_CPU1_P2_GND")
	)
	(segment
		(start 134.58952 -397.3576)
		(end 136.26084 -395.68628)
		(width 0.10668)
		(layer "F.Cu")
		(net "NCF_A1_CPU1_P3_GND")
	)
	(segment
		(start 136.26084 -395.68628)
		(end 136.26084 -391.698226)
		(width 0.10668)
		(layer "F.Cu")
		(net "NCF_A1_CPU1_P3_GND")
	)
	(segment
		(start 135.597392 -391.051288)
		(end 135.367522 -391.281158)
		(width 0.10668)
		(layer "F.Cu")
		(net "NCF_A1_CPU1_P3_GND")
	)
	(segment
		(start 135.367522 -391.281158)
		(end 134.617968 -391.281158)
		(width 0.10668)
		(layer "F.Cu")
		(net "NCF_A1_CPU1_P3_GND")
	)
	(segment
		(start 136.26084 -391.698226)
		(end 136.536938 -391.422128)
		(width 0.10668)
		(layer "F.Cu")
		(net "NCF_A1_CPU1_P3_GND")
	)
	(segment
		(start 136.536938 -391.422128)
		(end 136.536938 -391.051288)
		(width 0.10668)
		(layer "F.Cu")
		(net "NCF_A1_CPU1_P3_GND")
	)
	(segment
		(start 136.536938 -391.051288)
		(end 135.597392 -391.051288)
		(width 0.10668)
		(layer "F.Cu")
		(net "NCF_A1_CPU1_P3_GND")
	)
	(segment
		(start 134.2263 -397.3576)
		(end 134.58952 -397.3576)
		(width 0.10668)
		(layer "F.Cu")
		(net "NCF_A1_CPU1_P3_GND")
	)
	(via
		(at 134.2263 -397.3576)
		(size 0.762)
		(drill 0.381)
		(layers "F.Cu" "B.Cu")
		(net "NCF_A1_CPU1_P3_GND")
	)
	(segment
		(start 169.187368 -393.621514)
		(end 169.187368 -394.6271)
		(width 0.10668)
		(layer "F.Cu")
		(net "NCF_A1_CPU1_P2_GND")
	)
	(segment
		(start 167.145716 -391.774426)
		(end 168.168574 -392.797284)
		(width 0.10668)
		(layer "F.Cu")
		(net "NCF_A1_CPU1_P2_GND")
	)
	(segment
		(start 168.168574 -392.797284)
		(end 168.500806 -392.934952)
		(width 0.10668)
		(layer "F.Cu")
		(net "NCF_A1_CPU1_P2_GND")
	)
	(segment
		(start 168.60901 -394.6271)
		(end 169.187368 -394.6271)
		(width 0.10668)
		(layer "F.Cu")
		(net "NCF_A1_CPU1_P2_GND")
	)
	(segment
		(start 168.500806 -392.934952)
		(end 169.187368 -393.621514)
		(width 0.10668)
		(layer "F.Cu")
		(net "NCF_A1_CPU1_P2_GND")
	)
	(segment
		(start 167.145716 -391.281158)
		(end 167.145716 -391.774426)
		(width 0.10668)
		(layer "F.Cu")
		(net "NCF_A1_CPU1_P2_GND")
	)
	(via
		(at 169.187368 -394.6271)
		(size 0.508)
		(drill 0.254)
		(layers "F.Cu" "B.Cu")
		(net "NCF_A1_CPU1_P2_GND")
	)
	(segment
		(start 111.74349 -389.2804)
		(end 111.38662 -389.63727)
		(width 0.10668)
		(layer "F.Cu")
		(net "MODE_RT_CPU1_P3")
	)
	(segment
		(start 112.72774 -394.75156)
		(end 112.72774 -394.433552)
		(width 0.10668)
		(layer "F.Cu")
		(net "MODE_RT_CPU1_P3")
	)
	(segment
		(start 111.38662 -389.63727)
		(end 111.38662 -391.576814)
		(width 0.10668)
		(layer "F.Cu")
		(net "MODE_RT_CPU1_P3")
	)
	(segment
		(start 113.151412 -395.175232)
		(end 112.72774 -394.75156)
		(width 0.10668)
		(layer "F.Cu")
		(net "MODE_RT_CPU1_P3")
	)
	(segment
		(start 113.34496 -395.175232)
		(end 113.151412 -395.175232)
		(width 0.10668)
		(layer "F.Cu")
		(net "MODE_RT_CPU1_P3")
	)
	(segment
		(start 113.138204 -393.328398)
		(end 113.138204 -394.192506)
		(width 0.10668)
		(layer "F.Cu")
		(net "MODE_RT_CPU1_P3")
	)
	(segment
		(start 112.897158 -394.433552)
		(end 112.72774 -394.433552)
		(width 0.10668)
		(layer "F.Cu")
		(net "MODE_RT_CPU1_P3")
	)
	(segment
		(start 111.74349 -389.2804)
		(end 111.992918 -389.030972)
		(width 0.10668)
		(layer "F.Cu")
		(net "MODE_RT_CPU1_P3")
	)
	(segment
		(start 111.992918 -389.030972)
		(end 112.68202 -389.030972)
		(width 0.10668)
		(layer "F.Cu")
		(net "MODE_RT_CPU1_P3")
	)
	(segment
		(start 111.38662 -391.576814)
		(end 113.138204 -393.328398)
		(width 0.10668)
		(layer "F.Cu")
		(net "MODE_RT_CPU1_P3")
	)
	(segment
		(start 113.138204 -394.192506)
		(end 112.897158 -394.433552)
		(width 0.10668)
		(layer "F.Cu")
		(net "MODE_RT_CPU1_P3")
	)
	(via
		(at 111.74349 -389.2804)
		(size 0.508)
		(drill 0.254)
		(layers "F.Cu" "B.Cu")
		(net "MODE_RT_CPU1_P3")
	)
	(segment
		(start 145.128488 -395.170152)
		(end 145.394934 -395.170152)
		(width 0.10668)
		(layer "F.Cu")
		(net "MODE_RT_CPU1_P2")
	)
	(segment
		(start 145.394934 -395.170152)
		(end 145.618962 -395.39418)
		(width 0.10668)
		(layer "F.Cu")
		(net "MODE_RT_CPU1_P2")
	)
	(segment
		(start 143.89608 -389.742426)
		(end 143.89608 -391.26287)
		(width 0.10668)
		(layer "F.Cu")
		(net "MODE_RT_CPU1_P2")
	)
	(segment
		(start 145.293842 -394.433552)
		(end 145.128488 -394.433552)
		(width 0.10668)
		(layer "F.Cu")
		(net "MODE_RT_CPU1_P2")
	)
	(segment
		(start 145.209768 -389.030972)
		(end 144.607534 -389.030972)
		(width 0.10668)
		(layer "F.Cu")
		(net "MODE_RT_CPU1_P2")
	)
	(segment
		(start 144.607534 -389.030972)
		(end 143.89608 -389.742426)
		(width 0.10668)
		(layer "F.Cu")
		(net "MODE_RT_CPU1_P2")
	)
	(segment
		(start 145.618962 -395.39418)
		(end 145.618962 -396.283434)
		(width 0.10668)
		(layer "F.Cu")
		(net "MODE_RT_CPU1_P2")
	)
	(segment
		(start 145.618962 -396.283434)
		(end 145.38833 -396.514066)
		(width 0.10668)
		(layer "F.Cu")
		(net "MODE_RT_CPU1_P2")
	)
	(segment
		(start 143.89608 -391.26287)
		(end 145.531586 -392.898376)
		(width 0.10668)
		(layer "F.Cu")
		(net "MODE_RT_CPU1_P2")
	)
	(segment
		(start 145.531586 -392.898376)
		(end 145.531586 -394.195808)
		(width 0.10668)
		(layer "F.Cu")
		(net "MODE_RT_CPU1_P2")
	)
	(segment
		(start 145.531586 -394.195808)
		(end 145.293842 -394.433552)
		(width 0.10668)
		(layer "F.Cu")
		(net "MODE_RT_CPU1_P2")
	)
	(segment
		(start 145.128488 -395.170152)
		(end 145.128488 -394.433552)
		(width 0.10668)
		(layer "F.Cu")
		(net "MODE_RT_CPU1_P2")
	)
	(via
		(at 145.38833 -396.514066)
		(size 0.762)
		(drill 0.381)
		(layers "F.Cu" "B.Cu")
		(net "MODE_RT_CPU1_P2")
	)
	(segment
		(start 111.749586 -389.971788)
		(end 112.390428 -389.330946)
		(width 0.10668)
		(layer "F.Cu")
		(net "JTAG_TEST_MODE_RT_CPU1_P3")
	)
	(segment
		(start 111.749586 -391.327894)
		(end 111.749586 -389.971788)
		(width 0.10668)
		(layer "F.Cu")
		(net "JTAG_TEST_MODE_RT_CPU1_P3")
	)
	(segment
		(start 114.456972 -394.349478)
		(end 114.456972 -394.03528)
		(width 0.10668)
		(layer "F.Cu")
		(net "JTAG_TEST_MODE_RT_CPU1_P3")
	)
	(segment
		(start 114.76736 -395.487906)
		(end 115.18138 -395.073886)
		(width 0.10668)
		(layer "F.Cu")
		(net "JTAG_TEST_MODE_RT_CPU1_P3")
	)
	(segment
		(start 115.18138 -395.073886)
		(end 114.456972 -394.349478)
		(width 0.10668)
		(layer "F.Cu")
		(net "JTAG_TEST_MODE_RT_CPU1_P3")
	)
	(segment
		(start 114.197638 -395.487906)
		(end 114.76736 -395.487906)
		(width 0.10668)
		(layer "F.Cu")
		(net "JTAG_TEST_MODE_RT_CPU1_P3")
	)
	(segment
		(start 114.456972 -394.03528)
		(end 111.749586 -391.327894)
		(width 0.10668)
		(layer "F.Cu")
		(net "JTAG_TEST_MODE_RT_CPU1_P3")
	)
	(segment
		(start 116.158518 -395.073886)
		(end 115.18138 -395.073886)
		(width 0.10668)
		(layer "F.Cu")
		(net "JTAG_TEST_MODE_RT_CPU1_P3")
	)
	(segment
		(start 112.390428 -389.330946)
		(end 113.201704 -389.330946)
		(width 0.10668)
		(layer "F.Cu")
		(net "JTAG_TEST_MODE_RT_CPU1_P3")
	)
	(via
		(at 115.18138 -395.073886)
		(size 0.762)
		(drill 0.381)
		(layers "F.Cu" "B.Cu")
		(net "JTAG_TEST_MODE_RT_CPU1_P3")
	)
	(segment
		(start 146.745706 -395.487906)
		(end 147.051776 -395.181836)
		(width 0.10668)
		(layer "F.Cu")
		(net "JTAG_TEST_MODE_RT_CPU1_P2")
	)
	(segment
		(start 144.850104 -389.330946)
		(end 144.277334 -389.903716)
		(width 0.10668)
		(layer "F.Cu")
		(net "JTAG_TEST_MODE_RT_CPU1_P2")
	)
	(segment
		(start 146.98472 -395.11478)
		(end 147.051776 -395.181836)
		(width 0.10668)
		(layer "F.Cu")
		(net "JTAG_TEST_MODE_RT_CPU1_P2")
	)
	(segment
		(start 146.98472 -393.88796)
		(end 146.98472 -395.11478)
		(width 0.10668)
		(layer "F.Cu")
		(net "JTAG_TEST_MODE_RT_CPU1_P2")
	)
	(segment
		(start 144.277334 -391.180574)
		(end 146.98472 -393.88796)
		(width 0.10668)
		(layer "F.Cu")
		(net "JTAG_TEST_MODE_RT_CPU1_P2")
	)
	(segment
		(start 145.729452 -389.330946)
		(end 144.850104 -389.330946)
		(width 0.10668)
		(layer "F.Cu")
		(net "JTAG_TEST_MODE_RT_CPU1_P2")
	)
	(segment
		(start 146.214846 -396.224506)
		(end 146.214846 -395.487906)
		(width 0.10668)
		(layer "F.Cu")
		(net "JTAG_TEST_MODE_RT_CPU1_P2")
	)
	(segment
		(start 146.214846 -395.487906)
		(end 146.745706 -395.487906)
		(width 0.10668)
		(layer "F.Cu")
		(net "JTAG_TEST_MODE_RT_CPU1_P2")
	)
	(segment
		(start 144.277334 -389.903716)
		(end 144.277334 -391.180574)
		(width 0.10668)
		(layer "F.Cu")
		(net "JTAG_TEST_MODE_RT_CPU1_P2")
	)
	(via
		(at 147.051776 -395.181836)
		(size 0.762)
		(drill 0.381)
		(layers "F.Cu" "B.Cu")
		(net "JTAG_TEST_MODE_RT_CPU1_P2")
	)
	(segment
		(start 186.111642 -414.04413)
		(end 186.111642 -414.397698)
		(width 0.10668)
		(layer "F.Cu")
		(net "GPU_PRSNT_N_ISO_R1")
	)
	(segment
		(start 186.111642 -414.397698)
		(end 185.99404 -414.5153)
		(width 0.10668)
		(layer "F.Cu")
		(net "GPU_PRSNT_N_ISO_R1")
	)
	(segment
		(start 185.99404 -414.5153)
		(end 185.99404 -414.932114)
		(width 0.10668)
		(layer "F.Cu")
		(net "GPU_PRSNT_N_ISO_R1")
	)
	(segment
		(start 185.99404 -415.891218)
		(end 185.96229 -415.922968)
		(width 0.10668)
		(layer "F.Cu")
		(net "GPU_PRSNT_N_ISO_R1")
	)
	(segment
		(start 185.99404 -414.932114)
		(end 185.99404 -415.891218)
		(width 0.10668)
		(layer "F.Cu")
		(net "GPU_PRSNT_N_ISO_R1")
	)
	(segment
		(start 185.96229 -415.922968)
		(end 185.96229 -417.404804)
		(width 0.10668)
		(layer "F.Cu")
		(net "GPU_PRSNT_N_ISO_R1")
	)
	(via
		(at 185.99404 -414.932114)
		(size 0.762)
		(drill 0.381)
		(layers "F.Cu" "B.Cu")
		(net "GPU_PRSNT_N_ISO_R1")
	)
	(segment
		(start 110.099094 -384.36042)
		(end 110.099094 -384.66268)
		(width 0.10668)
		(layer "F.Cu")
		(net "GPIO3_RT_CPU1_P3")
	)
	(segment
		(start 112.490504 -385.43103)
		(end 111.819436 -384.759962)
		(width 0.10668)
		(layer "F.Cu")
		(net "GPIO3_RT_CPU1_P3")
	)
	(segment
		(start 110.099094 -384.66268)
		(end 109.332014 -384.66268)
		(width 0.10668)
		(layer "F.Cu")
		(net "GPIO3_RT_CPU1_P3")
	)
	(segment
		(start 112.68202 -385.43103)
		(end 112.490504 -385.43103)
		(width 0.10668)
		(layer "F.Cu")
		(net "GPIO3_RT_CPU1_P3")
	)
	(segment
		(start 109.332014 -384.66268)
		(end 109.30509 -384.635756)
		(width 0.10668)
		(layer "F.Cu")
		(net "GPIO3_RT_CPU1_P3")
	)
	(segment
		(start 111.819436 -384.618992)
		(end 111.403384 -384.20294)
		(width 0.10668)
		(layer "F.Cu")
		(net "GPIO3_RT_CPU1_P3")
	)
	(segment
		(start 111.819436 -384.759962)
		(end 111.819436 -384.618992)
		(width 0.10668)
		(layer "F.Cu")
		(net "GPIO3_RT_CPU1_P3")
	)
	(segment
		(start 110.256574 -384.20294)
		(end 110.099094 -384.36042)
		(width 0.10668)
		(layer "F.Cu")
		(net "GPIO3_RT_CPU1_P3")
	)
	(segment
		(start 111.403384 -384.20294)
		(end 110.256574 -384.20294)
		(width 0.10668)
		(layer "F.Cu")
		(net "GPIO3_RT_CPU1_P3")
	)
	(via
		(at 109.30509 -384.635756)
		(size 0.762)
		(drill 0.381)
		(layers "F.Cu" "B.Cu")
		(net "GPIO3_RT_CPU1_P3")
	)
	(segment
		(start 142.784322 -384.20294)
		(end 143.89862 -384.20294)
		(width 0.10668)
		(layer "F.Cu")
		(net "GPIO3_RT_CPU1_P2")
	)
	(segment
		(start 142.626842 -384.66268)
		(end 142.626842 -384.36042)
		(width 0.10668)
		(layer "F.Cu")
		(net "GPIO3_RT_CPU1_P2")
	)
	(segment
		(start 145.018252 -385.43103)
		(end 145.209768 -385.43103)
		(width 0.10668)
		(layer "F.Cu")
		(net "GPIO3_RT_CPU1_P2")
	)
	(segment
		(start 142.626842 -384.66268)
		(end 141.859762 -384.66268)
		(width 0.10668)
		(layer "F.Cu")
		(net "GPIO3_RT_CPU1_P2")
	)
	(segment
		(start 142.626842 -384.36042)
		(end 142.784322 -384.20294)
		(width 0.10668)
		(layer "F.Cu")
		(net "GPIO3_RT_CPU1_P2")
	)
	(segment
		(start 143.89862 -384.20294)
		(end 144.347184 -384.651504)
		(width 0.10668)
		(layer "F.Cu")
		(net "GPIO3_RT_CPU1_P2")
	)
	(segment
		(start 141.859762 -384.66268)
		(end 141.832838 -384.635756)
		(width 0.10668)
		(layer "F.Cu")
		(net "GPIO3_RT_CPU1_P2")
	)
	(segment
		(start 144.347184 -384.651504)
		(end 144.347184 -384.759962)
		(width 0.10668)
		(layer "F.Cu")
		(net "GPIO3_RT_CPU1_P2")
	)
	(segment
		(start 144.347184 -384.759962)
		(end 145.018252 -385.43103)
		(width 0.10668)
		(layer "F.Cu")
		(net "GPIO3_RT_CPU1_P2")
	)
	(via
		(at 141.832838 -384.635756)
		(size 0.762)
		(drill 0.381)
		(layers "F.Cu" "B.Cu")
		(net "GPIO3_RT_CPU1_P2")
	)
	(segment
		(start 109.674152 -385.48056)
		(end 109.362494 -385.48056)
		(width 0.10668)
		(layer "F.Cu")
		(net "GPIO2_RT_CPU1_P3")
	)
	(segment
		(start 111.657384 -385.31927)
		(end 111.657384 -385.856734)
		(width 0.10668)
		(layer "F.Cu")
		(net "GPIO2_RT_CPU1_P3")
	)
	(segment
		(start 111.460534 -385.12242)
		(end 111.657384 -385.31927)
		(width 0.10668)
		(layer "F.Cu")
		(net "GPIO2_RT_CPU1_P3")
	)
	(segment
		(start 110.099094 -385.277106)
		(end 110.25378 -385.12242)
		(width 0.10668)
		(layer "F.Cu")
		(net "GPIO2_RT_CPU1_P3")
	)
	(segment
		(start 111.831628 -386.030978)
		(end 112.68202 -386.030978)
		(width 0.10668)
		(layer "F.Cu")
		(net "GPIO2_RT_CPU1_P3")
	)
	(segment
		(start 110.099094 -385.58216)
		(end 110.099094 -385.277106)
		(width 0.10668)
		(layer "F.Cu")
		(net "GPIO2_RT_CPU1_P3")
	)
	(segment
		(start 108.242354 -385.98348)
		(end 108.792264 -385.98348)
		(width 0.10668)
		(layer "F.Cu")
		(net "GPIO2_RT_CPU1_P3")
	)
	(segment
		(start 109.775752 -385.58216)
		(end 109.674152 -385.48056)
		(width 0.10668)
		(layer "F.Cu")
		(net "GPIO2_RT_CPU1_P3")
	)
	(segment
		(start 108.095034 -386.1308)
		(end 108.242354 -385.98348)
		(width 0.10668)
		(layer "F.Cu")
		(net "GPIO2_RT_CPU1_P3")
	)
	(segment
		(start 108.792264 -385.98348)
		(end 109.177328 -385.823968)
		(width 0.10668)
		(layer "F.Cu")
		(net "GPIO2_RT_CPU1_P3")
	)
	(segment
		(start 109.177328 -385.823968)
		(end 109.362494 -385.638802)
		(width 0.10668)
		(layer "F.Cu")
		(net "GPIO2_RT_CPU1_P3")
	)
	(segment
		(start 110.099094 -385.58216)
		(end 109.775752 -385.58216)
		(width 0.10668)
		(layer "F.Cu")
		(net "GPIO2_RT_CPU1_P3")
	)
	(segment
		(start 111.657384 -385.856734)
		(end 111.831628 -386.030978)
		(width 0.10668)
		(layer "F.Cu")
		(net "GPIO2_RT_CPU1_P3")
	)
	(segment
		(start 109.362494 -385.638802)
		(end 109.362494 -385.48056)
		(width 0.10668)
		(layer "F.Cu")
		(net "GPIO2_RT_CPU1_P3")
	)
	(segment
		(start 110.25378 -385.12242)
		(end 111.460534 -385.12242)
		(width 0.10668)
		(layer "F.Cu")
		(net "GPIO2_RT_CPU1_P3")
	)
	(via
		(at 108.095034 -386.1308)
		(size 0.762)
		(drill 0.381)
		(layers "F.Cu" "B.Cu")
		(net "GPIO2_RT_CPU1_P3")
	)
	(segment
		(start 143.905986 -385.12242)
		(end 142.781528 -385.12242)
		(width 0.10668)
		(layer "F.Cu")
		(net "GPIO2_RT_CPU1_P2")
	)
	(segment
		(start 142.781528 -385.12242)
		(end 142.626842 -385.277106)
		(width 0.10668)
		(layer "F.Cu")
		(net "GPIO2_RT_CPU1_P2")
	)
	(segment
		(start 141.890242 -385.48056)
		(end 141.890242 -385.823206)
		(width 0.10668)
		(layer "F.Cu")
		(net "GPIO2_RT_CPU1_P2")
	)
	(segment
		(start 142.305786 -385.58216)
		(end 142.626842 -385.58216)
		(width 0.10668)
		(layer "F.Cu")
		(net "GPIO2_RT_CPU1_P2")
	)
	(segment
		(start 141.890242 -385.48056)
		(end 142.204186 -385.48056)
		(width 0.10668)
		(layer "F.Cu")
		(net "GPIO2_RT_CPU1_P2")
	)
	(segment
		(start 142.626842 -385.277106)
		(end 142.626842 -385.58216)
		(width 0.10668)
		(layer "F.Cu")
		(net "GPIO2_RT_CPU1_P2")
	)
	(segment
		(start 140.770102 -385.98348)
		(end 140.622782 -386.1308)
		(width 0.10668)
		(layer "F.Cu")
		(net "GPIO2_RT_CPU1_P2")
	)
	(segment
		(start 141.729968 -385.98348)
		(end 140.770102 -385.98348)
		(width 0.10668)
		(layer "F.Cu")
		(net "GPIO2_RT_CPU1_P2")
	)
	(segment
		(start 142.204186 -385.48056)
		(end 142.305786 -385.58216)
		(width 0.10668)
		(layer "F.Cu")
		(net "GPIO2_RT_CPU1_P2")
	)
	(segment
		(start 144.185132 -385.401566)
		(end 143.905986 -385.12242)
		(width 0.10668)
		(layer "F.Cu")
		(net "GPIO2_RT_CPU1_P2")
	)
	(segment
		(start 141.890242 -385.823206)
		(end 141.729968 -385.98348)
		(width 0.10668)
		(layer "F.Cu")
		(net "GPIO2_RT_CPU1_P2")
	)
	(segment
		(start 144.185132 -385.856734)
		(end 144.185132 -385.401566)
		(width 0.10668)
		(layer "F.Cu")
		(net "GPIO2_RT_CPU1_P2")
	)
	(segment
		(start 144.359376 -386.030978)
		(end 144.185132 -385.856734)
		(width 0.10668)
		(layer "F.Cu")
		(net "GPIO2_RT_CPU1_P2")
	)
	(segment
		(start 145.209768 -386.030978)
		(end 144.359376 -386.030978)
		(width 0.10668)
		(layer "F.Cu")
		(net "GPIO2_RT_CPU1_P2")
	)
	(via
		(at 140.622782 -386.1308)
		(size 0.762)
		(drill 0.381)
		(layers "F.Cu" "B.Cu")
		(net "GPIO2_RT_CPU1_P2")
	)
	(segment
		(start 77.504036 -384.700272)
		(end 77.93482 -385.131056)
		(width 0.10668)
		(layer "F.Cu")
		(net "TEST2_RT_CPU1_P1")
	)
	(segment
		(start 75.5269 -383.7432)
		(end 75.5269 -383.418588)
		(width 0.10668)
		(layer "F.Cu")
		(net "TEST2_RT_CPU1_P1")
	)
	(segment
		(start 76.712064 -383.207514)
		(end 77.504036 -383.999486)
		(width 0.10668)
		(layer "F.Cu")
		(net "TEST2_RT_CPU1_P1")
	)
	(segment
		(start 75.737974 -383.207514)
		(end 76.712064 -383.207514)
		(width 0.10668)
		(layer "F.Cu")
		(net "TEST2_RT_CPU1_P1")
	)
	(segment
		(start 77.93482 -385.131056)
		(end 78.62951 -385.131056)
		(width 0.10668)
		(layer "F.Cu")
		(net "TEST2_RT_CPU1_P1")
	)
	(segment
		(start 74.5363 -383.82829)
		(end 73.728834 -384.635756)
		(width 0.10668)
		(layer "F.Cu")
		(net "TEST2_RT_CPU1_P1")
	)
	(segment
		(start 73.728834 -384.635756)
		(end 73.462896 -384.635756)
		(width 0.10668)
		(layer "F.Cu")
		(net "TEST2_RT_CPU1_P1")
	)
	(segment
		(start 74.5363 -383.7432)
		(end 75.5269 -383.7432)
		(width 0.10668)
		(layer "F.Cu")
		(net "TEST2_RT_CPU1_P1")
	)
	(segment
		(start 77.504036 -383.999486)
		(end 77.504036 -384.700272)
		(width 0.10668)
		(layer "F.Cu")
		(net "TEST2_RT_CPU1_P1")
	)
	(segment
		(start 74.5363 -383.7432)
		(end 74.5363 -383.82829)
		(width 0.10668)
		(layer "F.Cu")
		(net "TEST2_RT_CPU1_P1")
	)
	(segment
		(start 75.5269 -383.418588)
		(end 75.737974 -383.207514)
		(width 0.10668)
		(layer "F.Cu")
		(net "TEST2_RT_CPU1_P1")
	)
	(via
		(at 73.462896 -384.635756)
		(size 0.762)
		(drill 0.381)
		(layers "F.Cu" "B.Cu")
		(net "TEST2_RT_CPU1_P1")
	)
	(segment
		(start 77.888592 -385.731004)
		(end 78.62951 -385.731004)
		(width 0.10668)
		(layer "F.Cu")
		(net "TEST1_RT_CPU1_P1")
	)
	(segment
		(start 77.507592 -385.602734)
		(end 77.760322 -385.602734)
		(width 0.10668)
		(layer "F.Cu")
		(net "TEST1_RT_CPU1_P1")
	)
	(segment
		(start 77.760322 -385.602734)
		(end 77.888592 -385.731004)
		(width 0.10668)
		(layer "F.Cu")
		(net "TEST1_RT_CPU1_P1")
	)
	(via
		(at 77.507592 -384.885946)
		(size 0.6604)
		(drill 0.3302)
		(layers "F.Cu" "B.Cu")
		(net "TEST1_RT_CPU1_P1")
	)
	(via
		(at 77.507592 -385.602734)
		(size 0.4064)
		(drill 0.2032)
		(layers "F.Cu" "B.Cu")
		(net "TEST1_RT_CPU1_P1")
	)
	(segment
		(start 77.507592 -384.885946)
		(end 76.824586 -384.20294)
		(width 0.10668)
		(layer "B.Cu")
		(net "TEST1_RT_CPU1_P1")
	)
	(segment
		(start 77.507592 -385.602734)
		(end 77.507592 -384.885946)
		(width 0.10668)
		(layer "B.Cu")
		(net "TEST1_RT_CPU1_P1")
	)
	(segment
		(start 74.7903 -384.66268)
		(end 75.5269 -384.66268)
		(width 0.10668)
		(layer "B.Cu")
		(net "TEST1_RT_CPU1_P1")
	)
	(segment
		(start 75.695048 -384.20294)
		(end 75.5269 -384.371088)
		(width 0.10668)
		(layer "B.Cu")
		(net "TEST1_RT_CPU1_P1")
	)
	(segment
		(start 76.824586 -384.20294)
		(end 75.695048 -384.20294)
		(width 0.10668)
		(layer "B.Cu")
		(net "TEST1_RT_CPU1_P1")
	)
	(segment
		(start 75.5269 -384.371088)
		(end 75.5269 -384.66268)
		(width 0.10668)
		(layer "B.Cu")
		(net "TEST1_RT_CPU1_P1")
	)
	(segment
		(start 77.767942 -386.330952)
		(end 78.62951 -386.330952)
		(width 0.10668)
		(layer "F.Cu")
		(net "TEST0_RT_CPU1_P1")
	)
	(segment
		(start 77.609446 -386.489448)
		(end 77.767942 -386.330952)
		(width 0.10668)
		(layer "F.Cu")
		(net "TEST0_RT_CPU1_P1")
	)
	(via
		(at 77.055726 -386.129022)
		(size 0.6604)
		(drill 0.3302)
		(layers "F.Cu" "B.Cu")
		(net "TEST0_RT_CPU1_P1")
	)
	(via
		(at 77.609446 -386.489448)
		(size 0.4064)
		(drill 0.2032)
		(layers "F.Cu" "B.Cu")
		(net "TEST0_RT_CPU1_P1")
	)
	(segment
		(start 77.609446 -386.489448)
		(end 77.416152 -386.489448)
		(width 0.10668)
		(layer "B.Cu")
		(net "TEST0_RT_CPU1_P1")
	)
	(segment
		(start 77.055726 -385.336288)
		(end 76.841858 -385.12242)
		(width 0.10668)
		(layer "B.Cu")
		(net "TEST0_RT_CPU1_P1")
	)
	(segment
		(start 77.416152 -386.489448)
		(end 77.055726 -386.129022)
		(width 0.10668)
		(layer "B.Cu")
		(net "TEST0_RT_CPU1_P1")
	)
	(segment
		(start 76.841858 -385.12242)
		(end 75.695048 -385.12242)
		(width 0.10668)
		(layer "B.Cu")
		(net "TEST0_RT_CPU1_P1")
	)
	(segment
		(start 75.695048 -385.12242)
		(end 75.5269 -385.290568)
		(width 0.10668)
		(layer "B.Cu")
		(net "TEST0_RT_CPU1_P1")
	)
	(segment
		(start 75.5269 -385.290568)
		(end 75.5269 -385.58216)
		(width 0.10668)
		(layer "B.Cu")
		(net "TEST0_RT_CPU1_P1")
	)
	(segment
		(start 74.7903 -385.58216)
		(end 75.5269 -385.58216)
		(width 0.10668)
		(layer "B.Cu")
		(net "TEST0_RT_CPU1_P1")
	)
	(segment
		(start 77.055726 -386.129022)
		(end 77.055726 -385.336288)
		(width 0.10668)
		(layer "B.Cu")
		(net "TEST0_RT_CPU1_P1")
	)
	(via
		(at 219.71 -336.169)
		(size 0.6604)
		(drill 0.3302)
		(layers "F.Cu" "B.Cu")
		(net "SMB_RT_CPU1_P1_SDA")
	)
	(segment
		(start 219.202 -336.677)
		(end 219.71 -336.169)
		(width 0.10668)
		(layer "B.Cu")
		(net "SMB_RT_CPU1_P1_SDA")
	)
	(segment
		(start 221.510098 -336.521044)
		(end 220.062044 -336.521044)
		(width 0.10668)
		(layer "B.Cu")
		(net "SMB_RT_CPU1_P1_SDA")
	)
	(segment
		(start 220.062044 -336.521044)
		(end 219.71 -336.169)
		(width 0.10668)
		(layer "B.Cu")
		(net "SMB_RT_CPU1_P1_SDA")
	)
	(segment
		(start 218.3257 -336.296)
		(end 218.7067 -336.677)
		(width 0.10668)
		(layer "B.Cu")
		(net "SMB_RT_CPU1_P1_SDA")
	)
	(segment
		(start 218.7067 -336.677)
		(end 219.202 -336.677)
		(width 0.10668)
		(layer "B.Cu")
		(net "SMB_RT_CPU1_P1_SDA")
	)
	(via
		(at 219.71 -337.439)
		(size 0.6604)
		(drill 0.3302)
		(layers "F.Cu" "B.Cu")
		(net "SMB_RT_CPU1_P1_SCL")
	)
	(segment
		(start 218.5797 -337.058)
		(end 219.329 -337.058)
		(width 0.10668)
		(layer "B.Cu")
		(net "SMB_RT_CPU1_P1_SCL")
	)
	(segment
		(start 218.3257 -337.312)
		(end 218.5797 -337.058)
		(width 0.10668)
		(layer "B.Cu")
		(net "SMB_RT_CPU1_P1_SCL")
	)
	(segment
		(start 219.329 -337.058)
		(end 219.71 -337.439)
		(width 0.10668)
		(layer "B.Cu")
		(net "SMB_RT_CPU1_P1_SCL")
	)
	(segment
		(start 219.977716 -337.171284)
		(end 219.71 -337.439)
		(width 0.10668)
		(layer "B.Cu")
		(net "SMB_RT_CPU1_P1_SCL")
	)
	(segment
		(start 221.510098 -337.171284)
		(end 219.977716 -337.171284)
		(width 0.10668)
		(layer "B.Cu")
		(net "SMB_RT_CPU1_P1_SCL")
	)
	(via
		(at 216.081356 -336.166714)
		(size 0.6604)
		(drill 0.3302)
		(layers "F.Cu" "B.Cu")
		(net "SMB_RT_CPU1_P1_R_SDA")
	)
	(segment
		(start 216.350342 -336.4357)
		(end 216.916 -336.4357)
		(width 0.10668)
		(layer "B.Cu")
		(net "SMB_RT_CPU1_P1_R_SDA")
	)
	(segment
		(start 215.457786 -336.166714)
		(end 215.3285 -336.296)
		(width 0.10668)
		(layer "B.Cu")
		(net "SMB_RT_CPU1_P1_R_SDA")
	)
	(segment
		(start 216.916 -336.4357)
		(end 217.6526 -336.4357)
		(width 0.10668)
		(layer "B.Cu")
		(net "SMB_RT_CPU1_P1_R_SDA")
	)
	(segment
		(start 217.6526 -336.4357)
		(end 217.7923 -336.296)
		(width 0.10668)
		(layer "B.Cu")
		(net "SMB_RT_CPU1_P1_R_SDA")
	)
	(segment
		(start 216.081356 -336.166714)
		(end 216.350342 -336.4357)
		(width 0.10668)
		(layer "B.Cu")
		(net "SMB_RT_CPU1_P1_R_SDA")
	)
	(segment
		(start 216.081356 -336.166714)
		(end 215.457786 -336.166714)
		(width 0.10668)
		(layer "B.Cu")
		(net "SMB_RT_CPU1_P1_R_SDA")
	)
	(via
		(at 216.08542 -337.443826)
		(size 0.6604)
		(drill 0.3302)
		(layers "F.Cu" "B.Cu")
		(net "SMB_RT_CPU1_P1_R_SCL")
	)
	(segment
		(start 215.3285 -337.312)
		(end 215.953594 -337.312)
		(width 0.10668)
		(layer "B.Cu")
		(net "SMB_RT_CPU1_P1_R_SCL")
	)
	(segment
		(start 215.953594 -337.312)
		(end 216.08542 -337.443826)
		(width 0.10668)
		(layer "B.Cu")
		(net "SMB_RT_CPU1_P1_R_SCL")
	)
	(segment
		(start 216.916 -337.1723)
		(end 217.6526 -337.1723)
		(width 0.10668)
		(layer "B.Cu")
		(net "SMB_RT_CPU1_P1_R_SCL")
	)
	(segment
		(start 217.6526 -337.1723)
		(end 217.7923 -337.312)
		(width 0.10668)
		(layer "B.Cu")
		(net "SMB_RT_CPU1_P1_R_SCL")
	)
	(segment
		(start 216.08542 -337.443826)
		(end 216.356946 -337.1723)
		(width 0.10668)
		(layer "B.Cu")
		(net "SMB_RT_CPU1_P1_R_SCL")
	)
	(segment
		(start 216.356946 -337.1723)
		(end 216.916 -337.1723)
		(width 0.10668)
		(layer "B.Cu")
		(net "SMB_RT_CPU1_P1_R_SCL")
	)
	(segment
		(start 99.88169 -385.43103)
		(end 100.287836 -385.149344)
		(width 0.10668)
		(layer "F.Cu")
		(net "SMB_RT_CPU1_P1_R2_SDA")
	)
	(via
		(at 100.287836 -385.149344)
		(size 0.4064)
		(drill 0.2032)
		(layers "F.Cu" "B.Cu")
		(net "SMB_RT_CPU1_P1_R2_SDA")
	)
	(via
		(at 211.826602 -340.223856)
		(size 0.508)
		(drill 0.254)
		(layers "F.Cu" "B.Cu")
		(net "SMB_RT_CPU1_P1_R2_SDA")
	)
	(segment
		(start 212.714078 -337.36661)
		(end 212.714078 -339.33638)
		(width 0.10668)
		(layer "B.Cu")
		(net "SMB_RT_CPU1_P1_R2_SDA")
	)
	(segment
		(start 213.784688 -336.296)
		(end 212.714078 -337.36661)
		(width 0.10668)
		(layer "B.Cu")
		(net "SMB_RT_CPU1_P1_R2_SDA")
	)
	(segment
		(start 212.714078 -339.33638)
		(end 211.826602 -340.223856)
		(width 0.10668)
		(layer "B.Cu")
		(net "SMB_RT_CPU1_P1_R2_SDA")
	)
	(segment
		(start 214.7951 -336.296)
		(end 213.784688 -336.296)
		(width 0.10668)
		(layer "B.Cu")
		(net "SMB_RT_CPU1_P1_R2_SDA")
	)
	(segment
		(start 169.545762 -375.10974)
		(end 170.750738 -373.904764)
		(width 0.11684)
		(layer "In2.Cu")
		(net "SMB_RT_CPU1_P1_R2_SDA")
	)
	(segment
		(start 142.936976 -375.344436)
		(end 143.91894 -376.3264)
		(width 0.11684)
		(layer "In2.Cu")
		(net "SMB_RT_CPU1_P1_R2_SDA")
	)
	(segment
		(start 132.62737 -378.92482)
		(end 136.02462 -375.52757)
		(width 0.11684)
		(layer "In2.Cu")
		(net "SMB_RT_CPU1_P1_R2_SDA")
	)
	(segment
		(start 109.373924 -384.25882)
		(end 114.707924 -378.92482)
		(width 0.11684)
		(layer "In2.Cu")
		(net "SMB_RT_CPU1_P1_R2_SDA")
	)
	(segment
		(start 103.125524 -382.565656)
		(end 103.299006 -382.392174)
		(width 0.11684)
		(layer "In2.Cu")
		(net "SMB_RT_CPU1_P1_R2_SDA")
	)
	(segment
		(start 102.452424 -382.565656)
		(end 103.125524 -382.565656)
		(width 0.11684)
		(layer "In2.Cu")
		(net "SMB_RT_CPU1_P1_R2_SDA")
	)
	(segment
		(start 211.079842 -348.071694)
		(end 211.079842 -340.970616)
		(width 0.11684)
		(layer "In2.Cu")
		(net "SMB_RT_CPU1_P1_R2_SDA")
	)
	(segment
		(start 141.944344 -375.344436)
		(end 142.936976 -375.344436)
		(width 0.11684)
		(layer "In2.Cu")
		(net "SMB_RT_CPU1_P1_R2_SDA")
	)
	(segment
		(start 100.531422 -383.140966)
		(end 101.128576 -383.140966)
		(width 0.11684)
		(layer "In2.Cu")
		(net "SMB_RT_CPU1_P1_R2_SDA")
	)
	(segment
		(start 174.808642 -371.6909)
		(end 181.757066 -371.6909)
		(width 0.11684)
		(layer "In2.Cu")
		(net "SMB_RT_CPU1_P1_R2_SDA")
	)
	(segment
		(start 145.514568 -376.3264)
		(end 148.540724 -379.352556)
		(width 0.11684)
		(layer "In2.Cu")
		(net "SMB_RT_CPU1_P1_R2_SDA")
	)
	(segment
		(start 101.240844 -383.187448)
		(end 101.664008 -383.187448)
		(width 0.11684)
		(layer "In2.Cu")
		(net "SMB_RT_CPU1_P1_R2_SDA")
	)
	(segment
		(start 102.167944 -382.683512)
		(end 102.452424 -382.565656)
		(width 0.11684)
		(layer "In2.Cu")
		(net "SMB_RT_CPU1_P1_R2_SDA")
	)
	(segment
		(start 181.757066 -371.6909)
		(end 183.948832 -369.499134)
		(width 0.11684)
		(layer "In2.Cu")
		(net "SMB_RT_CPU1_P1_R2_SDA")
	)
	(segment
		(start 183.948832 -369.499134)
		(end 192.207896 -369.499134)
		(width 0.11684)
		(layer "In2.Cu")
		(net "SMB_RT_CPU1_P1_R2_SDA")
	)
	(segment
		(start 165.261036 -377.213876)
		(end 165.874192 -377.213876)
		(width 0.11684)
		(layer "In2.Cu")
		(net "SMB_RT_CPU1_P1_R2_SDA")
	)
	(segment
		(start 136.02462 -375.52757)
		(end 137.333736 -375.52757)
		(width 0.11684)
		(layer "In2.Cu")
		(net "SMB_RT_CPU1_P1_R2_SDA")
	)
	(segment
		(start 208.291684 -353.415346)
		(end 208.291684 -350.859852)
		(width 0.11684)
		(layer "In2.Cu")
		(net "SMB_RT_CPU1_P1_R2_SDA")
	)
	(segment
		(start 100.287836 -385.149344)
		(end 99.88042 -384.741928)
		(width 0.11684)
		(layer "In2.Cu")
		(net "SMB_RT_CPU1_P1_R2_SDA")
	)
	(segment
		(start 172.594778 -373.904764)
		(end 174.808642 -371.6909)
		(width 0.11684)
		(layer "In2.Cu")
		(net "SMB_RT_CPU1_P1_R2_SDA")
	)
	(segment
		(start 103.299006 -382.392174)
		(end 105.199434 -382.392174)
		(width 0.11684)
		(layer "In2.Cu")
		(net "SMB_RT_CPU1_P1_R2_SDA")
	)
	(segment
		(start 167.978328 -375.10974)
		(end 169.545762 -375.10974)
		(width 0.11684)
		(layer "In2.Cu")
		(net "SMB_RT_CPU1_P1_R2_SDA")
	)
	(segment
		(start 101.128576 -383.140966)
		(end 101.240844 -383.187448)
		(width 0.11684)
		(layer "In2.Cu")
		(net "SMB_RT_CPU1_P1_R2_SDA")
	)
	(segment
		(start 105.199434 -382.392174)
		(end 107.06608 -384.25882)
		(width 0.11684)
		(layer "In2.Cu")
		(net "SMB_RT_CPU1_P1_R2_SDA")
	)
	(segment
		(start 165.874192 -377.213876)
		(end 167.978328 -375.10974)
		(width 0.11684)
		(layer "In2.Cu")
		(net "SMB_RT_CPU1_P1_R2_SDA")
	)
	(segment
		(start 138.018266 -374.84304)
		(end 141.442948 -374.84304)
		(width 0.11684)
		(layer "In2.Cu")
		(net "SMB_RT_CPU1_P1_R2_SDA")
	)
	(segment
		(start 163.122356 -379.352556)
		(end 165.261036 -377.213876)
		(width 0.11684)
		(layer "In2.Cu")
		(net "SMB_RT_CPU1_P1_R2_SDA")
	)
	(segment
		(start 99.88042 -383.791968)
		(end 100.531422 -383.140966)
		(width 0.11684)
		(layer "In2.Cu")
		(net "SMB_RT_CPU1_P1_R2_SDA")
	)
	(segment
		(start 141.442948 -374.84304)
		(end 141.944344 -375.344436)
		(width 0.11684)
		(layer "In2.Cu")
		(net "SMB_RT_CPU1_P1_R2_SDA")
	)
	(segment
		(start 170.750738 -373.904764)
		(end 172.594778 -373.904764)
		(width 0.11684)
		(layer "In2.Cu")
		(net "SMB_RT_CPU1_P1_R2_SDA")
	)
	(segment
		(start 143.91894 -376.3264)
		(end 145.514568 -376.3264)
		(width 0.11684)
		(layer "In2.Cu")
		(net "SMB_RT_CPU1_P1_R2_SDA")
	)
	(segment
		(start 148.540724 -379.352556)
		(end 163.122356 -379.352556)
		(width 0.11684)
		(layer "In2.Cu")
		(net "SMB_RT_CPU1_P1_R2_SDA")
	)
	(segment
		(start 99.88042 -384.741928)
		(end 99.88042 -383.791968)
		(width 0.11684)
		(layer "In2.Cu")
		(net "SMB_RT_CPU1_P1_R2_SDA")
	)
	(segment
		(start 192.207896 -369.499134)
		(end 208.291684 -353.415346)
		(width 0.11684)
		(layer "In2.Cu")
		(net "SMB_RT_CPU1_P1_R2_SDA")
	)
	(segment
		(start 211.079842 -340.970616)
		(end 211.826602 -340.223856)
		(width 0.11684)
		(layer "In2.Cu")
		(net "SMB_RT_CPU1_P1_R2_SDA")
	)
	(segment
		(start 137.333736 -375.52757)
		(end 138.018266 -374.84304)
		(width 0.11684)
		(layer "In2.Cu")
		(net "SMB_RT_CPU1_P1_R2_SDA")
	)
	(segment
		(start 101.664008 -383.187448)
		(end 102.167944 -382.683512)
		(width 0.11684)
		(layer "In2.Cu")
		(net "SMB_RT_CPU1_P1_R2_SDA")
	)
	(segment
		(start 114.707924 -378.92482)
		(end 132.62737 -378.92482)
		(width 0.11684)
		(layer "In2.Cu")
		(net "SMB_RT_CPU1_P1_R2_SDA")
	)
	(segment
		(start 107.06608 -384.25882)
		(end 109.373924 -384.25882)
		(width 0.11684)
		(layer "In2.Cu")
		(net "SMB_RT_CPU1_P1_R2_SDA")
	)
	(segment
		(start 208.291684 -350.859852)
		(end 211.079842 -348.071694)
		(width 0.11684)
		(layer "In2.Cu")
		(net "SMB_RT_CPU1_P1_R2_SDA")
	)
	(segment
		(start 99.88169 -384.831082)
		(end 100.30206 -384.574542)
		(width 0.10668)
		(layer "F.Cu")
		(net "SMB_RT_CPU1_P1_R2_SCL")
	)
	(via
		(at 100.30206 -384.574542)
		(size 0.4064)
		(drill 0.2032)
		(layers "F.Cu" "B.Cu")
		(net "SMB_RT_CPU1_P1_R2_SCL")
	)
	(via
		(at 213.437724 -337.642962)
		(size 0.6604)
		(drill 0.3302)
		(layers "F.Cu" "B.Cu")
		(net "SMB_RT_CPU1_P1_R2_SCL")
	)
	(via
		(at 211.798662 -341.841582)
		(size 0.508)
		(drill 0.254)
		(layers "F.Cu" "B.Cu")
		(net "SMB_RT_CPU1_P1_R2_SCL")
	)
	(segment
		(start 213.437724 -337.642962)
		(end 213.080092 -338.000594)
		(width 0.10668)
		(layer "B.Cu")
		(net "SMB_RT_CPU1_P1_R2_SCL")
	)
	(segment
		(start 213.080092 -340.560152)
		(end 211.798662 -341.841582)
		(width 0.10668)
		(layer "B.Cu")
		(net "SMB_RT_CPU1_P1_R2_SCL")
	)
	(segment
		(start 213.768686 -337.312)
		(end 213.437724 -337.642962)
		(width 0.10668)
		(layer "B.Cu")
		(net "SMB_RT_CPU1_P1_R2_SCL")
	)
	(segment
		(start 213.080092 -338.000594)
		(end 213.080092 -340.560152)
		(width 0.10668)
		(layer "B.Cu")
		(net "SMB_RT_CPU1_P1_R2_SCL")
	)
	(segment
		(start 214.7951 -337.312)
		(end 213.768686 -337.312)
		(width 0.10668)
		(layer "B.Cu")
		(net "SMB_RT_CPU1_P1_R2_SCL")
	)
	(segment
		(start 104.912414 -382.889506)
		(end 106.703368 -384.68046)
		(width 0.11684)
		(layer "In2.Cu")
		(net "SMB_RT_CPU1_P1_R2_SCL")
	)
	(segment
		(start 102.553008 -382.987296)
		(end 103.358696 -382.987296)
		(width 0.11684)
		(layer "In2.Cu")
		(net "SMB_RT_CPU1_P1_R2_SCL")
	)
	(segment
		(start 103.456486 -382.889506)
		(end 104.912414 -382.889506)
		(width 0.11684)
		(layer "In2.Cu")
		(net "SMB_RT_CPU1_P1_R2_SCL")
	)
	(segment
		(start 181.907942 -372.136416)
		(end 184.123584 -369.920774)
		(width 0.11684)
		(layer "In2.Cu")
		(net "SMB_RT_CPU1_P1_R2_SCL")
	)
	(segment
		(start 100.697538 -383.571242)
		(end 101.044248 -383.571242)
		(width 0.11684)
		(layer "In2.Cu")
		(net "SMB_RT_CPU1_P1_R2_SCL")
	)
	(segment
		(start 170.991022 -374.326404)
		(end 172.76953 -374.326404)
		(width 0.11684)
		(layer "In2.Cu")
		(net "SMB_RT_CPU1_P1_R2_SCL")
	)
	(segment
		(start 172.76953 -374.326404)
		(end 174.959518 -372.136416)
		(width 0.11684)
		(layer "In2.Cu")
		(net "SMB_RT_CPU1_P1_R2_SCL")
	)
	(segment
		(start 101.044248 -383.571242)
		(end 101.165152 -383.62128)
		(width 0.11684)
		(layer "In2.Cu")
		(net "SMB_RT_CPU1_P1_R2_SCL")
	)
	(segment
		(start 100.30206 -383.96672)
		(end 100.697538 -383.571242)
		(width 0.11684)
		(layer "In2.Cu")
		(net "SMB_RT_CPU1_P1_R2_SCL")
	)
	(segment
		(start 211.52231 -348.379034)
		(end 211.52231 -342.117934)
		(width 0.11684)
		(layer "In2.Cu")
		(net "SMB_RT_CPU1_P1_R2_SCL")
	)
	(segment
		(start 100.30206 -384.574542)
		(end 100.30206 -383.96672)
		(width 0.11684)
		(layer "In2.Cu")
		(net "SMB_RT_CPU1_P1_R2_SCL")
	)
	(segment
		(start 101.826568 -383.62128)
		(end 102.395274 -383.052574)
		(width 0.11684)
		(layer "In2.Cu")
		(net "SMB_RT_CPU1_P1_R2_SCL")
	)
	(segment
		(start 166.480236 -377.635516)
		(end 168.524174 -375.591578)
		(width 0.11684)
		(layer "In2.Cu")
		(net "SMB_RT_CPU1_P1_R2_SCL")
	)
	(segment
		(start 211.52231 -342.117934)
		(end 211.798662 -341.841582)
		(width 0.11684)
		(layer "In2.Cu")
		(net "SMB_RT_CPU1_P1_R2_SCL")
	)
	(segment
		(start 143.172688 -379.774196)
		(end 163.297108 -379.774196)
		(width 0.11684)
		(layer "In2.Cu")
		(net "SMB_RT_CPU1_P1_R2_SCL")
	)
	(segment
		(start 114.889788 -379.34646)
		(end 133.171438 -379.34646)
		(width 0.11684)
		(layer "In2.Cu")
		(net "SMB_RT_CPU1_P1_R2_SCL")
	)
	(segment
		(start 102.395274 -383.052574)
		(end 102.553008 -382.987296)
		(width 0.11684)
		(layer "In2.Cu")
		(net "SMB_RT_CPU1_P1_R2_SCL")
	)
	(segment
		(start 106.703368 -384.68046)
		(end 109.555788 -384.68046)
		(width 0.11684)
		(layer "In2.Cu")
		(net "SMB_RT_CPU1_P1_R2_SCL")
	)
	(segment
		(start 163.297108 -379.774196)
		(end 165.435788 -377.635516)
		(width 0.11684)
		(layer "In2.Cu")
		(net "SMB_RT_CPU1_P1_R2_SCL")
	)
	(segment
		(start 141.645132 -378.24664)
		(end 143.172688 -379.774196)
		(width 0.11684)
		(layer "In2.Cu")
		(net "SMB_RT_CPU1_P1_R2_SCL")
	)
	(segment
		(start 103.358696 -382.987296)
		(end 103.456486 -382.889506)
		(width 0.11684)
		(layer "In2.Cu")
		(net "SMB_RT_CPU1_P1_R2_SCL")
	)
	(segment
		(start 101.165152 -383.62128)
		(end 101.826568 -383.62128)
		(width 0.11684)
		(layer "In2.Cu")
		(net "SMB_RT_CPU1_P1_R2_SCL")
	)
	(segment
		(start 168.524174 -375.591578)
		(end 169.725848 -375.591578)
		(width 0.11684)
		(layer "In2.Cu")
		(net "SMB_RT_CPU1_P1_R2_SCL")
	)
	(segment
		(start 109.555788 -384.68046)
		(end 114.889788 -379.34646)
		(width 0.11684)
		(layer "In2.Cu")
		(net "SMB_RT_CPU1_P1_R2_SCL")
	)
	(segment
		(start 192.382902 -369.920774)
		(end 208.713324 -353.590352)
		(width 0.11684)
		(layer "In2.Cu")
		(net "SMB_RT_CPU1_P1_R2_SCL")
	)
	(segment
		(start 134.271258 -378.24664)
		(end 141.645132 -378.24664)
		(width 0.11684)
		(layer "In2.Cu")
		(net "SMB_RT_CPU1_P1_R2_SCL")
	)
	(segment
		(start 169.725848 -375.591578)
		(end 170.991022 -374.326404)
		(width 0.11684)
		(layer "In2.Cu")
		(net "SMB_RT_CPU1_P1_R2_SCL")
	)
	(segment
		(start 184.123584 -369.920774)
		(end 192.382902 -369.920774)
		(width 0.11684)
		(layer "In2.Cu")
		(net "SMB_RT_CPU1_P1_R2_SCL")
	)
	(segment
		(start 165.435788 -377.635516)
		(end 166.480236 -377.635516)
		(width 0.11684)
		(layer "In2.Cu")
		(net "SMB_RT_CPU1_P1_R2_SCL")
	)
	(segment
		(start 208.713324 -351.18802)
		(end 211.52231 -348.379034)
		(width 0.11684)
		(layer "In2.Cu")
		(net "SMB_RT_CPU1_P1_R2_SCL")
	)
	(segment
		(start 133.171438 -379.34646)
		(end 134.271258 -378.24664)
		(width 0.11684)
		(layer "In2.Cu")
		(net "SMB_RT_CPU1_P1_R2_SCL")
	)
	(segment
		(start 174.959518 -372.136416)
		(end 181.907942 -372.136416)
		(width 0.11684)
		(layer "In2.Cu")
		(net "SMB_RT_CPU1_P1_R2_SCL")
	)
	(segment
		(start 208.713324 -353.590352)
		(end 208.713324 -351.18802)
		(width 0.11684)
		(layer "In2.Cu")
		(net "SMB_RT_CPU1_P1_R2_SCL")
	)
	(segment
		(start 98.845878 -391.281158)
		(end 98.845878 -392.14933)
		(width 0.10668)
		(layer "F.Cu")
		(net "RT_CPU1_P1_VQPS")
	)
	(segment
		(start 98.845878 -392.14933)
		(end 99.540568 -392.84402)
		(width 0.10668)
		(layer "F.Cu")
		(net "RT_CPU1_P1_VQPS")
	)
	(segment
		(start 99.540568 -394.381736)
		(end 99.295204 -394.6271)
		(width 0.10668)
		(layer "F.Cu")
		(net "RT_CPU1_P1_VQPS")
	)
	(segment
		(start 99.295204 -394.6271)
		(end 99.080828 -394.6271)
		(width 0.10668)
		(layer "F.Cu")
		(net "RT_CPU1_P1_VQPS")
	)
	(segment
		(start 99.080828 -394.6271)
		(end 99.080828 -395.3637)
		(width 0.10668)
		(layer "F.Cu")
		(net "RT_CPU1_P1_VQPS")
	)
	(segment
		(start 99.080828 -395.3637)
		(end 98.252788 -395.3637)
		(width 0.10668)
		(layer "F.Cu")
		(net "RT_CPU1_P1_VQPS")
	)
	(segment
		(start 99.540568 -392.84402)
		(end 99.540568 -394.381736)
		(width 0.10668)
		(layer "F.Cu")
		(net "RT_CPU1_P1_VQPS")
	)
	(via
		(at 98.252788 -395.3637)
		(size 0.762)
		(drill 0.381)
		(layers "F.Cu" "B.Cu")
		(net "RT_CPU1_P1_VQPS")
	)
	(segment
		(start 78.455774 -384.357372)
		(end 78.62951 -384.531108)
		(width 0.10668)
		(layer "F.Cu")
		(net "RT_CPU1_P1_SCAN_MODE")
	)
	(segment
		(start 77.928978 -384.357372)
		(end 78.455774 -384.357372)
		(width 0.10668)
		(layer "F.Cu")
		(net "RT_CPU1_P1_SCAN_MODE")
	)
	(via
		(at 77.34427 -383.361692)
		(size 0.6604)
		(drill 0.3302)
		(layers "F.Cu" "B.Cu")
		(net "RT_CPU1_P1_SCAN_MODE")
	)
	(via
		(at 77.928978 -384.357372)
		(size 0.4064)
		(drill 0.2032)
		(layers "F.Cu" "B.Cu")
		(net "RT_CPU1_P1_SCAN_MODE")
	)
	(segment
		(start 75.695048 -383.28346)
		(end 75.5269 -383.451608)
		(width 0.10668)
		(layer "B.Cu")
		(net "RT_CPU1_P1_SCAN_MODE")
	)
	(segment
		(start 77.928978 -384.357372)
		(end 77.928978 -383.9464)
		(width 0.10668)
		(layer "B.Cu")
		(net "RT_CPU1_P1_SCAN_MODE")
	)
	(segment
		(start 77.34427 -383.361692)
		(end 77.266038 -383.28346)
		(width 0.10668)
		(layer "B.Cu")
		(net "RT_CPU1_P1_SCAN_MODE")
	)
	(segment
		(start 77.266038 -383.28346)
		(end 75.695048 -383.28346)
		(width 0.10668)
		(layer "B.Cu")
		(net "RT_CPU1_P1_SCAN_MODE")
	)
	(segment
		(start 75.5269 -383.451608)
		(end 75.5269 -383.7432)
		(width 0.10668)
		(layer "B.Cu")
		(net "RT_CPU1_P1_SCAN_MODE")
	)
	(segment
		(start 77.928978 -383.9464)
		(end 77.34427 -383.361692)
		(width 0.10668)
		(layer "B.Cu")
		(net "RT_CPU1_P1_SCAN_MODE")
	)
	(segment
		(start 74.7903 -383.7432)
		(end 75.5269 -383.7432)
		(width 0.10668)
		(layer "B.Cu")
		(net "RT_CPU1_P1_SCAN_MODE")
	)
	(segment
		(start 104.276652 -386.52323)
		(end 104.034336 -386.762752)
		(width 0.10668)
		(layer "F.Cu")
		(net "RT_CPU1_P1_ADDR3")
	)
	(segment
		(start 102.810564 -387.846062)
		(end 102.4636 -387.499098)
		(width 0.10668)
		(layer "F.Cu")
		(net "RT_CPU1_P1_ADDR3")
	)
	(segment
		(start 100.252784 -386.402072)
		(end 99.88169 -386.030978)
		(width 0.10668)
		(layer "F.Cu")
		(net "RT_CPU1_P1_ADDR3")
	)
	(segment
		(start 104.034336 -387.099048)
		(end 103.892096 -387.241288)
		(width 0.10668)
		(layer "F.Cu")
		(net "RT_CPU1_P1_ADDR3")
	)
	(segment
		(start 103.330502 -387.473952)
		(end 103.182674 -387.473952)
		(width 0.10668)
		(layer "F.Cu")
		(net "RT_CPU1_P1_ADDR3")
	)
	(segment
		(start 102.4636 -387.499098)
		(end 101.066092 -387.499098)
		(width 0.10668)
		(layer "F.Cu")
		(net "RT_CPU1_P1_ADDR3")
	)
	(segment
		(start 101.066092 -387.499098)
		(end 100.252784 -386.68579)
		(width 0.10668)
		(layer "F.Cu")
		(net "RT_CPU1_P1_ADDR3")
	)
	(segment
		(start 100.252784 -386.68579)
		(end 100.252784 -386.402072)
		(width 0.10668)
		(layer "F.Cu")
		(net "RT_CPU1_P1_ADDR3")
	)
	(segment
		(start 103.892096 -387.241288)
		(end 103.330502 -387.473952)
		(width 0.10668)
		(layer "F.Cu")
		(net "RT_CPU1_P1_ADDR3")
	)
	(segment
		(start 104.409748 -386.5245)
		(end 104.276652 -386.52323)
		(width 0.10668)
		(layer "F.Cu")
		(net "RT_CPU1_P1_ADDR3")
	)
	(segment
		(start 104.034336 -386.762752)
		(end 104.034336 -387.099048)
		(width 0.10668)
		(layer "F.Cu")
		(net "RT_CPU1_P1_ADDR3")
	)
	(segment
		(start 104.409748 -385.7879)
		(end 104.409748 -386.5245)
		(width 0.10668)
		(layer "F.Cu")
		(net "RT_CPU1_P1_ADDR3")
	)
	(segment
		(start 103.182674 -387.473952)
		(end 102.810564 -387.846062)
		(width 0.10668)
		(layer "F.Cu")
		(net "RT_CPU1_P1_ADDR3")
	)
	(via
		(at 102.810564 -387.846062)
		(size 0.762)
		(drill 0.381)
		(layers "F.Cu" "B.Cu")
		(net "RT_CPU1_P1_ADDR3")
	)
	(segment
		(start 104.537256 -388.302754)
		(end 105.031286 -388.302754)
		(width 0.10668)
		(layer "F.Cu")
		(net "RT_CPU1_P1_ADDR2")
	)
	(segment
		(start 105.60431 -387.232652)
		(end 105.60431 -386.820918)
		(width 0.10668)
		(layer "F.Cu")
		(net "RT_CPU1_P1_ADDR2")
	)
	(segment
		(start 101.043232 -387.792468)
		(end 101.924104 -387.792468)
		(width 0.10668)
		(layer "F.Cu")
		(net "RT_CPU1_P1_ADDR2")
	)
	(segment
		(start 105.222548 -385.7879)
		(end 105.222548 -386.5245)
		(width 0.10668)
		(layer "F.Cu")
		(net "RT_CPU1_P1_ADDR2")
	)
	(segment
		(start 105.60431 -386.820918)
		(end 105.307892 -386.5245)
		(width 0.10668)
		(layer "F.Cu")
		(net "RT_CPU1_P1_ADDR2")
	)
	(segment
		(start 105.253028 -388.081012)
		(end 105.60431 -387.232652)
		(width 0.10668)
		(layer "F.Cu")
		(net "RT_CPU1_P1_ADDR2")
	)
	(segment
		(start 103.493824 -388.432802)
		(end 104.080564 -387.846062)
		(width 0.10668)
		(layer "F.Cu")
		(net "RT_CPU1_P1_ADDR2")
	)
	(segment
		(start 101.924104 -387.792468)
		(end 102.487222 -388.355586)
		(width 0.10668)
		(layer "F.Cu")
		(net "RT_CPU1_P1_ADDR2")
	)
	(segment
		(start 105.307892 -386.5245)
		(end 105.222548 -386.5245)
		(width 0.10668)
		(layer "F.Cu")
		(net "RT_CPU1_P1_ADDR2")
	)
	(segment
		(start 105.031286 -388.302754)
		(end 105.253028 -388.081012)
		(width 0.10668)
		(layer "F.Cu")
		(net "RT_CPU1_P1_ADDR2")
	)
	(segment
		(start 104.080564 -387.846062)
		(end 104.537256 -388.302754)
		(width 0.10668)
		(layer "F.Cu")
		(net "RT_CPU1_P1_ADDR2")
	)
	(segment
		(start 99.88169 -386.630926)
		(end 101.043232 -387.792468)
		(width 0.10668)
		(layer "F.Cu")
		(net "RT_CPU1_P1_ADDR2")
	)
	(segment
		(start 102.487222 -388.355586)
		(end 102.673658 -388.432802)
		(width 0.10668)
		(layer "F.Cu")
		(net "RT_CPU1_P1_ADDR2")
	)
	(segment
		(start 102.673658 -388.432802)
		(end 103.493824 -388.432802)
		(width 0.10668)
		(layer "F.Cu")
		(net "RT_CPU1_P1_ADDR2")
	)
	(via
		(at 104.080564 -387.846062)
		(size 0.762)
		(drill 0.381)
		(layers "F.Cu" "B.Cu")
		(net "RT_CPU1_P1_ADDR2")
	)
	(segment
		(start 103.228648 -382.575308)
		(end 103.533956 -382.27)
		(width 0.10668)
		(layer "F.Cu")
		(net "RT_CPU1_P1_ADDR1")
	)
	(segment
		(start 99.476306 -384.131312)
		(end 99.354894 -384.131312)
		(width 0.10668)
		(layer "F.Cu")
		(net "RT_CPU1_P1_ADDR1")
	)
	(segment
		(start 99.62896 -384.283966)
		(end 99.476306 -384.131312)
		(width 0.10668)
		(layer "F.Cu")
		(net "RT_CPU1_P1_ADDR1")
	)
	(segment
		(start 103.228648 -382.6764)
		(end 102.744778 -382.6764)
		(width 0.10668)
		(layer "F.Cu")
		(net "RT_CPU1_P1_ADDR1")
	)
	(segment
		(start 99.354894 -384.131312)
		(end 99.145852 -383.92227)
		(width 0.10668)
		(layer "F.Cu")
		(net "RT_CPU1_P1_ADDR1")
	)
	(segment
		(start 103.533956 -382.27)
		(end 104.549448 -382.27)
		(width 0.10668)
		(layer "F.Cu")
		(net "RT_CPU1_P1_ADDR1")
	)
	(segment
		(start 103.228648 -382.6764)
		(end 103.228648 -382.575308)
		(width 0.10668)
		(layer "F.Cu")
		(net "RT_CPU1_P1_ADDR1")
	)
	(segment
		(start 100.642166 -383.554478)
		(end 99.912678 -384.283966)
		(width 0.10668)
		(layer "F.Cu")
		(net "RT_CPU1_P1_ADDR1")
	)
	(segment
		(start 102.744778 -382.6764)
		(end 101.8667 -383.554478)
		(width 0.10668)
		(layer "F.Cu")
		(net "RT_CPU1_P1_ADDR1")
	)
	(segment
		(start 99.912678 -384.283966)
		(end 99.62896 -384.283966)
		(width 0.10668)
		(layer "F.Cu")
		(net "RT_CPU1_P1_ADDR1")
	)
	(segment
		(start 104.549448 -382.437386)
		(end 105.393236 -383.281174)
		(width 0.10668)
		(layer "F.Cu")
		(net "RT_CPU1_P1_ADDR1")
	)
	(segment
		(start 101.8667 -383.554478)
		(end 100.642166 -383.554478)
		(width 0.10668)
		(layer "F.Cu")
		(net "RT_CPU1_P1_ADDR1")
	)
	(segment
		(start 104.549448 -382.27)
		(end 104.549448 -382.437386)
		(width 0.10668)
		(layer "F.Cu")
		(net "RT_CPU1_P1_ADDR1")
	)
	(via
		(at 105.393236 -383.281174)
		(size 0.762)
		(drill 0.381)
		(layers "F.Cu" "B.Cu")
		(net "RT_CPU1_P1_ADDR1")
	)
	(segment
		(start 45.928026 -384.357372)
		(end 46.101762 -384.531108)
		(width 0.10668)
		(layer "F.Cu")
		(net "RT_CPU1_P0_SCAN_MODE")
	)
	(segment
		(start 45.40123 -384.357372)
		(end 45.928026 -384.357372)
		(width 0.10668)
		(layer "F.Cu")
		(net "RT_CPU1_P0_SCAN_MODE")
	)
	(via
		(at 45.40123 -384.357372)
		(size 0.4064)
		(drill 0.2032)
		(layers "F.Cu" "B.Cu")
		(net "RT_CPU1_P0_SCAN_MODE")
	)
	(via
		(at 44.83354 -383.35458)
		(size 0.6604)
		(drill 0.3302)
		(layers "F.Cu" "B.Cu")
		(net "RT_CPU1_P0_SCAN_MODE")
	)
	(segment
		(start 45.40123 -383.92227)
		(end 44.83354 -383.35458)
		(width 0.10668)
		(layer "B.Cu")
		(net "RT_CPU1_P0_SCAN_MODE")
	)
	(segment
		(start 44.83354 -383.214372)
		(end 44.305728 -382.68656)
		(width 0.10668)
		(layer "B.Cu")
		(net "RT_CPU1_P0_SCAN_MODE")
	)
	(segment
		(start 43.532552 -382.68656)
		(end 43.532552 -382.782572)
		(width 0.10668)
		(layer "B.Cu")
		(net "RT_CPU1_P0_SCAN_MODE")
	)
	(segment
		(start 42.999152 -383.315972)
		(end 42.999152 -383.49936)
		(width 0.10668)
		(layer "B.Cu")
		(net "RT_CPU1_P0_SCAN_MODE")
	)
	(segment
		(start 44.305728 -382.68656)
		(end 43.532552 -382.68656)
		(width 0.10668)
		(layer "B.Cu")
		(net "RT_CPU1_P0_SCAN_MODE")
	)
	(segment
		(start 45.40123 -384.357372)
		(end 45.40123 -383.92227)
		(width 0.10668)
		(layer "B.Cu")
		(net "RT_CPU1_P0_SCAN_MODE")
	)
	(segment
		(start 43.532552 -382.782572)
		(end 42.999152 -383.315972)
		(width 0.10668)
		(layer "B.Cu")
		(net "RT_CPU1_P0_SCAN_MODE")
	)
	(segment
		(start 44.83354 -383.35458)
		(end 44.83354 -383.214372)
		(width 0.10668)
		(layer "B.Cu")
		(net "RT_CPU1_P0_SCAN_MODE")
	)
	(segment
		(start 68.550536 -387.51129)
		(end 67.725036 -386.68579)
		(width 0.10668)
		(layer "F.Cu")
		(net "RT_CPU1_P0_ADDR3")
	)
	(segment
		(start 70.802754 -387.473952)
		(end 70.654926 -387.473952)
		(width 0.10668)
		(layer "F.Cu")
		(net "RT_CPU1_P0_ADDR3")
	)
	(segment
		(start 71.506588 -387.099048)
		(end 71.364348 -387.241288)
		(width 0.10668)
		(layer "F.Cu")
		(net "RT_CPU1_P0_ADDR3")
	)
	(segment
		(start 69.948044 -387.51129)
		(end 68.550536 -387.51129)
		(width 0.10668)
		(layer "F.Cu")
		(net "RT_CPU1_P0_ADDR3")
	)
	(segment
		(start 71.882 -386.5245)
		(end 71.748904 -386.52323)
		(width 0.10668)
		(layer "F.Cu")
		(net "RT_CPU1_P0_ADDR3")
	)
	(segment
		(start 71.748904 -386.52323)
		(end 71.506588 -386.762752)
		(width 0.10668)
		(layer "F.Cu")
		(net "RT_CPU1_P0_ADDR3")
	)
	(segment
		(start 67.725036 -386.402072)
		(end 67.353942 -386.030978)
		(width 0.10668)
		(layer "F.Cu")
		(net "RT_CPU1_P0_ADDR3")
	)
	(segment
		(start 71.506588 -386.762752)
		(end 71.506588 -387.099048)
		(width 0.10668)
		(layer "F.Cu")
		(net "RT_CPU1_P0_ADDR3")
	)
	(segment
		(start 70.654926 -387.473952)
		(end 70.282816 -387.846062)
		(width 0.10668)
		(layer "F.Cu")
		(net "RT_CPU1_P0_ADDR3")
	)
	(segment
		(start 71.364348 -387.241288)
		(end 70.802754 -387.473952)
		(width 0.10668)
		(layer "F.Cu")
		(net "RT_CPU1_P0_ADDR3")
	)
	(segment
		(start 71.882 -386.5245)
		(end 71.882 -385.7879)
		(width 0.10668)
		(layer "F.Cu")
		(net "RT_CPU1_P0_ADDR3")
	)
	(segment
		(start 70.282816 -387.846062)
		(end 69.948044 -387.51129)
		(width 0.10668)
		(layer "F.Cu")
		(net "RT_CPU1_P0_ADDR3")
	)
	(segment
		(start 67.725036 -386.68579)
		(end 67.725036 -386.402072)
		(width 0.10668)
		(layer "F.Cu")
		(net "RT_CPU1_P0_ADDR3")
	)
	(via
		(at 70.282816 -387.846062)
		(size 0.762)
		(drill 0.381)
		(layers "F.Cu" "B.Cu")
		(net "RT_CPU1_P0_ADDR3")
	)
	(segment
		(start 72.6948 -386.5245)
		(end 72.6948 -385.7879)
		(width 0.10668)
		(layer "F.Cu")
		(net "RT_CPU1_P0_ADDR2")
	)
	(segment
		(start 70.127876 -388.432802)
		(end 70.966076 -388.432802)
		(width 0.10668)
		(layer "F.Cu")
		(net "RT_CPU1_P0_ADDR2")
	)
	(segment
		(start 70.966076 -388.432802)
		(end 71.552816 -387.846062)
		(width 0.10668)
		(layer "F.Cu")
		(net "RT_CPU1_P0_ADDR2")
	)
	(segment
		(start 73.076562 -387.72973)
		(end 73.076562 -386.820918)
		(width 0.10668)
		(layer "F.Cu")
		(net "RT_CPU1_P0_ADDR2")
	)
	(segment
		(start 72.780144 -386.5245)
		(end 72.6948 -386.5245)
		(width 0.10668)
		(layer "F.Cu")
		(net "RT_CPU1_P0_ADDR2")
	)
	(segment
		(start 67.353942 -386.630926)
		(end 68.484496 -387.76148)
		(width 0.10668)
		(layer "F.Cu")
		(net "RT_CPU1_P0_ADDR2")
	)
	(segment
		(start 69.880226 -388.330186)
		(end 70.127876 -388.432802)
		(width 0.10668)
		(layer "F.Cu")
		(net "RT_CPU1_P0_ADDR2")
	)
	(segment
		(start 68.484496 -387.76148)
		(end 69.31152 -387.76148)
		(width 0.10668)
		(layer "F.Cu")
		(net "RT_CPU1_P0_ADDR2")
	)
	(segment
		(start 72.503538 -388.302754)
		(end 73.076562 -387.72973)
		(width 0.10668)
		(layer "F.Cu")
		(net "RT_CPU1_P0_ADDR2")
	)
	(segment
		(start 72.009508 -388.302754)
		(end 72.503538 -388.302754)
		(width 0.10668)
		(layer "F.Cu")
		(net "RT_CPU1_P0_ADDR2")
	)
	(segment
		(start 73.076562 -386.820918)
		(end 72.780144 -386.5245)
		(width 0.10668)
		(layer "F.Cu")
		(net "RT_CPU1_P0_ADDR2")
	)
	(segment
		(start 71.552816 -387.846062)
		(end 72.009508 -388.302754)
		(width 0.10668)
		(layer "F.Cu")
		(net "RT_CPU1_P0_ADDR2")
	)
	(segment
		(start 69.31152 -387.76148)
		(end 69.880226 -388.330186)
		(width 0.10668)
		(layer "F.Cu")
		(net "RT_CPU1_P0_ADDR2")
	)
	(via
		(at 71.552816 -387.846062)
		(size 0.762)
		(drill 0.381)
		(layers "F.Cu" "B.Cu")
		(net "RT_CPU1_P0_ADDR2")
	)
	(segment
		(start 70.7009 -382.575308)
		(end 71.006208 -382.27)
		(width 0.10668)
		(layer "F.Cu")
		(net "RT_CPU1_P0_ADDR1")
	)
	(segment
		(start 67.101212 -384.283966)
		(end 67.38493 -384.283966)
		(width 0.10668)
		(layer "F.Cu")
		(net "RT_CPU1_P0_ADDR1")
	)
	(segment
		(start 72.0217 -382.27)
		(end 72.0217 -382.437386)
		(width 0.10668)
		(layer "F.Cu")
		(net "RT_CPU1_P0_ADDR1")
	)
	(segment
		(start 66.948558 -384.131312)
		(end 67.101212 -384.283966)
		(width 0.10668)
		(layer "F.Cu")
		(net "RT_CPU1_P0_ADDR1")
	)
	(segment
		(start 70.21703 -382.6764)
		(end 70.7009 -382.6764)
		(width 0.10668)
		(layer "F.Cu")
		(net "RT_CPU1_P0_ADDR1")
	)
	(segment
		(start 71.006208 -382.27)
		(end 72.0217 -382.27)
		(width 0.10668)
		(layer "F.Cu")
		(net "RT_CPU1_P0_ADDR1")
	)
	(segment
		(start 66.618104 -383.92227)
		(end 66.827146 -384.131312)
		(width 0.10668)
		(layer "F.Cu")
		(net "RT_CPU1_P0_ADDR1")
	)
	(segment
		(start 66.827146 -384.131312)
		(end 66.948558 -384.131312)
		(width 0.10668)
		(layer "F.Cu")
		(net "RT_CPU1_P0_ADDR1")
	)
	(segment
		(start 68.097908 -383.570988)
		(end 69.322442 -383.570988)
		(width 0.10668)
		(layer "F.Cu")
		(net "RT_CPU1_P0_ADDR1")
	)
	(segment
		(start 67.38493 -384.283966)
		(end 68.097908 -383.570988)
		(width 0.10668)
		(layer "F.Cu")
		(net "RT_CPU1_P0_ADDR1")
	)
	(segment
		(start 72.0217 -382.437386)
		(end 72.865488 -383.281174)
		(width 0.10668)
		(layer "F.Cu")
		(net "RT_CPU1_P0_ADDR1")
	)
	(segment
		(start 69.322442 -383.570988)
		(end 70.21703 -382.6764)
		(width 0.10668)
		(layer "F.Cu")
		(net "RT_CPU1_P0_ADDR1")
	)
	(segment
		(start 70.7009 -382.6764)
		(end 70.7009 -382.575308)
		(width 0.10668)
		(layer "F.Cu")
		(net "RT_CPU1_P0_ADDR1")
	)
	(via
		(at 72.865488 -383.281174)
		(size 0.762)
		(drill 0.381)
		(layers "F.Cu" "B.Cu")
		(net "RT_CPU1_P0_ADDR1")
	)
	(segment
		(start 76.767182 -394.232384)
		(end 76.96835 -394.433552)
		(width 0.10668)
		(layer "F.Cu")
		(net "RST_RT_CPU1_P1_RESET_R_N")
	)
	(segment
		(start 180.382418 -136.83996)
		(end 180.87721 -137.334752)
		(width 0.10668)
		(layer "F.Cu")
		(net "RST_RT_CPU1_P1_RESET_R_N")
	)
	(segment
		(start 77.215746 -394.433552)
		(end 77.215746 -395.170152)
		(width 0.10668)
		(layer "F.Cu")
		(net "RST_RT_CPU1_P1_RESET_R_N")
	)
	(segment
		(start 179.961286 -133.83768)
		(end 180.4289 -134.305294)
		(width 0.10668)
		(layer "F.Cu")
		(net "RST_RT_CPU1_P1_RESET_R_N")
	)
	(segment
		(start 180.4289 -134.305294)
		(end 180.4289 -136.405112)
		(width 0.10668)
		(layer "F.Cu")
		(net "RST_RT_CPU1_P1_RESET_R_N")
	)
	(segment
		(start 76.972414 -392.251946)
		(end 76.767182 -392.457178)
		(width 0.10668)
		(layer "F.Cu")
		(net "RST_RT_CPU1_P1_RESET_R_N")
	)
	(segment
		(start 179.247038 -173.50867)
		(end 184.804304 -179.065936)
		(width 0.10668)
		(layer "F.Cu")
		(net "RST_RT_CPU1_P1_RESET_R_N")
	)
	(segment
		(start 184.804304 -179.065936)
		(end 184.804304 -187.136024)
		(width 0.10668)
		(layer "F.Cu")
		(net "RST_RT_CPU1_P1_RESET_R_N")
	)
	(segment
		(start 180.382418 -136.451594)
		(end 180.382418 -136.83996)
		(width 0.10668)
		(layer "F.Cu")
		(net "RST_RT_CPU1_P1_RESET_R_N")
	)
	(segment
		(start 76.250546 -395.170152)
		(end 77.215746 -395.170152)
		(width 0.10668)
		(layer "F.Cu")
		(net "RST_RT_CPU1_P1_RESET_R_N")
	)
	(segment
		(start 180.4289 -136.405112)
		(end 180.382418 -136.451594)
		(width 0.10668)
		(layer "F.Cu")
		(net "RST_RT_CPU1_P1_RESET_R_N")
	)
	(segment
		(start 76.96835 -394.433552)
		(end 77.215746 -394.433552)
		(width 0.10668)
		(layer "F.Cu")
		(net "RST_RT_CPU1_P1_RESET_R_N")
	)
	(segment
		(start 76.767182 -392.457178)
		(end 76.767182 -394.232384)
		(width 0.10668)
		(layer "F.Cu")
		(net "RST_RT_CPU1_P1_RESET_R_N")
	)
	(segment
		(start 179.247038 -172.601382)
		(end 179.247038 -173.50867)
		(width 0.10668)
		(layer "F.Cu")
		(net "RST_RT_CPU1_P1_RESET_R_N")
	)
	(segment
		(start 180.87721 -137.334752)
		(end 180.87721 -137.635488)
		(width 0.10668)
		(layer "F.Cu")
		(net "RST_RT_CPU1_P1_RESET_R_N")
	)
	(via
		(at 226.21748 -341.11946)
		(size 0.508)
		(drill 0.254)
		(layers "F.Cu" "B.Cu")
		(net "RST_RT_CPU1_P1_RESET_R_N")
	)
	(via
		(at 76.972414 -392.251946)
		(size 0.508)
		(drill 0.254)
		(layers "F.Cu" "B.Cu")
		(net "RST_RT_CPU1_P1_RESET_R_N")
	)
	(via
		(at 184.804304 -187.136024)
		(size 0.508)
		(drill 0.254)
		(layers "F.Cu" "B.Cu")
		(net "RST_RT_CPU1_P1_RESET_R_N")
	)
	(via
		(at 180.87721 -137.635488)
		(size 0.508)
		(drill 0.254)
		(layers "F.Cu" "B.Cu")
		(net "RST_RT_CPU1_P1_RESET_R_N")
	)
	(via
		(at 219.651072 -214.58301)
		(size 0.508)
		(drill 0.254)
		(layers "F.Cu" "B.Cu")
		(net "RST_RT_CPU1_P1_RESET_R_N")
	)
	(via
		(at 179.247038 -172.601382)
		(size 0.508)
		(drill 0.254)
		(layers "F.Cu" "B.Cu")
		(net "RST_RT_CPU1_P1_RESET_R_N")
	)
	(segment
		(start 219.651072 -214.58301)
		(end 218.692476 -214.58301)
		(width 0.10668)
		(layer "B.Cu")
		(net "RST_RT_CPU1_P1_RESET_R_N")
	)
	(segment
		(start 209.687414 -183.056784)
		(end 186.079638 -183.056784)
		(width 0.10668)
		(layer "B.Cu")
		(net "RST_RT_CPU1_P1_RESET_R_N")
	)
	(segment
		(start 217.094054 -190.463424)
		(end 209.687414 -183.056784)
		(width 0.10668)
		(layer "B.Cu")
		(net "RST_RT_CPU1_P1_RESET_R_N")
	)
	(segment
		(start 184.804304 -184.332118)
		(end 184.804304 -187.136024)
		(width 0.10668)
		(layer "B.Cu")
		(net "RST_RT_CPU1_P1_RESET_R_N")
	)
	(segment
		(start 217.094054 -212.984588)
		(end 217.094054 -190.463424)
		(width 0.10668)
		(layer "B.Cu")
		(net "RST_RT_CPU1_P1_RESET_R_N")
	)
	(segment
		(start 186.079638 -183.056784)
		(end 184.804304 -184.332118)
		(width 0.10668)
		(layer "B.Cu")
		(net "RST_RT_CPU1_P1_RESET_R_N")
	)
	(segment
		(start 218.692476 -214.58301)
		(end 217.094054 -212.984588)
		(width 0.10668)
		(layer "B.Cu")
		(net "RST_RT_CPU1_P1_RESET_R_N")
	)
	(segment
		(start 99.803458 -395.25956)
		(end 101.315266 -396.771368)
		(width 0.11684)
		(layer "In2.Cu")
		(net "RST_RT_CPU1_P1_RESET_R_N")
	)
	(segment
		(start 111.206534 -399.5166)
		(end 112.60074 -399.5166)
		(width 0.11684)
		(layer "In2.Cu")
		(net "RST_RT_CPU1_P1_RESET_R_N")
	)
	(segment
		(start 113.31448 -400.23034)
		(end 120.393968 -400.23034)
		(width 0.11684)
		(layer "In2.Cu")
		(net "RST_RT_CPU1_P1_RESET_R_N")
	)
	(segment
		(start 172.098716 -400.190462)
		(end 175.320198 -396.96898)
		(width 0.11684)
		(layer "In2.Cu")
		(net "RST_RT_CPU1_P1_RESET_R_N")
	)
	(segment
		(start 175.320198 -393.98702)
		(end 191.182244 -378.124974)
		(width 0.11684)
		(layer "In2.Cu")
		(net "RST_RT_CPU1_P1_RESET_R_N")
	)
	(segment
		(start 224.71126 -359.151174)
		(end 224.71126 -352.452178)
		(width 0.11684)
		(layer "In2.Cu")
		(net "RST_RT_CPU1_P1_RESET_R_N")
	)
	(segment
		(start 106.608626 -400.387312)
		(end 110.335822 -400.387312)
		(width 0.11684)
		(layer "In2.Cu")
		(net "RST_RT_CPU1_P1_RESET_R_N")
	)
	(segment
		(start 112.60074 -399.5166)
		(end 113.31448 -400.23034)
		(width 0.11684)
		(layer "In2.Cu")
		(net "RST_RT_CPU1_P1_RESET_R_N")
	)
	(segment
		(start 159.572198 -400.387312)
		(end 160.053274 -400.868388)
		(width 0.11684)
		(layer "In2.Cu")
		(net "RST_RT_CPU1_P1_RESET_R_N")
	)
	(segment
		(start 76.825094 -392.399266)
		(end 76.825094 -393.72794)
		(width 0.11684)
		(layer "In2.Cu")
		(net "RST_RT_CPU1_P1_RESET_R_N")
	)
	(segment
		(start 120.55094 -400.387312)
		(end 159.572198 -400.387312)
		(width 0.11684)
		(layer "In2.Cu")
		(net "RST_RT_CPU1_P1_RESET_R_N")
	)
	(segment
		(start 207.283558 -367.45418)
		(end 216.677494 -367.45418)
		(width 0.11684)
		(layer "In2.Cu")
		(net "RST_RT_CPU1_P1_RESET_R_N")
	)
	(segment
		(start 198.589138 -372.279672)
		(end 199.673464 -372.279672)
		(width 0.11684)
		(layer "In2.Cu")
		(net "RST_RT_CPU1_P1_RESET_R_N")
	)
	(segment
		(start 202.981306 -371.756432)
		(end 207.283558 -367.45418)
		(width 0.11684)
		(layer "In2.Cu")
		(net "RST_RT_CPU1_P1_RESET_R_N")
	)
	(segment
		(start 226.21748 -350.945958)
		(end 226.21748 -341.11946)
		(width 0.11684)
		(layer "In2.Cu")
		(net "RST_RT_CPU1_P1_RESET_R_N")
	)
	(segment
		(start 224.71126 -352.452178)
		(end 226.21748 -350.945958)
		(width 0.11684)
		(layer "In2.Cu")
		(net "RST_RT_CPU1_P1_RESET_R_N")
	)
	(segment
		(start 175.320198 -396.96898)
		(end 175.320198 -393.98702)
		(width 0.11684)
		(layer "In2.Cu")
		(net "RST_RT_CPU1_P1_RESET_R_N")
	)
	(segment
		(start 216.677494 -367.45418)
		(end 223.883982 -360.247692)
		(width 0.11684)
		(layer "In2.Cu")
		(net "RST_RT_CPU1_P1_RESET_R_N")
	)
	(segment
		(start 103.194612 -398.029684)
		(end 104.250998 -398.029684)
		(width 0.11684)
		(layer "In2.Cu")
		(net "RST_RT_CPU1_P1_RESET_R_N")
	)
	(segment
		(start 78.735936 -395.638782)
		(end 96.846898 -395.638782)
		(width 0.11684)
		(layer "In2.Cu")
		(net "RST_RT_CPU1_P1_RESET_R_N")
	)
	(segment
		(start 102.658164 -397.10868)
		(end 102.658164 -397.493236)
		(width 0.11684)
		(layer "In2.Cu")
		(net "RST_RT_CPU1_P1_RESET_R_N")
	)
	(segment
		(start 104.250998 -398.029684)
		(end 106.608626 -400.387312)
		(width 0.11684)
		(layer "In2.Cu")
		(net "RST_RT_CPU1_P1_RESET_R_N")
	)
	(segment
		(start 191.182244 -378.124974)
		(end 192.743836 -378.124974)
		(width 0.11684)
		(layer "In2.Cu")
		(net "RST_RT_CPU1_P1_RESET_R_N")
	)
	(segment
		(start 96.846898 -395.638782)
		(end 97.22612 -395.25956)
		(width 0.11684)
		(layer "In2.Cu")
		(net "RST_RT_CPU1_P1_RESET_R_N")
	)
	(segment
		(start 110.335822 -400.387312)
		(end 111.206534 -399.5166)
		(width 0.11684)
		(layer "In2.Cu")
		(net "RST_RT_CPU1_P1_RESET_R_N")
	)
	(segment
		(start 165.396164 -400.868388)
		(end 166.07409 -400.190462)
		(width 0.11684)
		(layer "In2.Cu")
		(net "RST_RT_CPU1_P1_RESET_R_N")
	)
	(segment
		(start 97.22612 -395.25956)
		(end 99.803458 -395.25956)
		(width 0.11684)
		(layer "In2.Cu")
		(net "RST_RT_CPU1_P1_RESET_R_N")
	)
	(segment
		(start 102.658164 -397.493236)
		(end 103.194612 -398.029684)
		(width 0.11684)
		(layer "In2.Cu")
		(net "RST_RT_CPU1_P1_RESET_R_N")
	)
	(segment
		(start 199.673464 -372.279672)
		(end 200.196704 -371.756432)
		(width 0.11684)
		(layer "In2.Cu")
		(net "RST_RT_CPU1_P1_RESET_R_N")
	)
	(segment
		(start 223.883982 -359.978452)
		(end 224.71126 -359.151174)
		(width 0.11684)
		(layer "In2.Cu")
		(net "RST_RT_CPU1_P1_RESET_R_N")
	)
	(segment
		(start 160.053274 -400.868388)
		(end 165.396164 -400.868388)
		(width 0.11684)
		(layer "In2.Cu")
		(net "RST_RT_CPU1_P1_RESET_R_N")
	)
	(segment
		(start 166.07409 -400.190462)
		(end 172.098716 -400.190462)
		(width 0.11684)
		(layer "In2.Cu")
		(net "RST_RT_CPU1_P1_RESET_R_N")
	)
	(segment
		(start 102.320852 -396.771368)
		(end 102.658164 -397.10868)
		(width 0.11684)
		(layer "In2.Cu")
		(net "RST_RT_CPU1_P1_RESET_R_N")
	)
	(segment
		(start 76.972414 -392.251946)
		(end 76.825094 -392.399266)
		(width 0.11684)
		(layer "In2.Cu")
		(net "RST_RT_CPU1_P1_RESET_R_N")
	)
	(segment
		(start 76.825094 -393.72794)
		(end 78.735936 -395.638782)
		(width 0.11684)
		(layer "In2.Cu")
		(net "RST_RT_CPU1_P1_RESET_R_N")
	)
	(segment
		(start 101.315266 -396.771368)
		(end 102.320852 -396.771368)
		(width 0.11684)
		(layer "In2.Cu")
		(net "RST_RT_CPU1_P1_RESET_R_N")
	)
	(segment
		(start 120.393968 -400.23034)
		(end 120.55094 -400.387312)
		(width 0.11684)
		(layer "In2.Cu")
		(net "RST_RT_CPU1_P1_RESET_R_N")
	)
	(segment
		(start 192.743836 -378.124974)
		(end 198.589138 -372.279672)
		(width 0.11684)
		(layer "In2.Cu")
		(net "RST_RT_CPU1_P1_RESET_R_N")
	)
	(segment
		(start 223.883982 -360.247692)
		(end 223.883982 -359.978452)
		(width 0.11684)
		(layer "In2.Cu")
		(net "RST_RT_CPU1_P1_RESET_R_N")
	)
	(segment
		(start 200.196704 -371.756432)
		(end 202.981306 -371.756432)
		(width 0.11684)
		(layer "In2.Cu")
		(net "RST_RT_CPU1_P1_RESET_R_N")
	)
	(segment
		(start 180.145944 -137.635488)
		(end 180.87721 -137.635488)
		(width 0.11684)
		(layer "In11.Cu")
		(net "RST_RT_CPU1_P1_RESET_R_N")
	)
	(segment
		(start 179.449984 -143.912082)
		(end 179.449984 -139.980416)
		(width 0.11684)
		(layer "In11.Cu")
		(net "RST_RT_CPU1_P1_RESET_R_N")
	)
	(segment
		(start 181.360572 -146.998182)
		(end 181.360572 -145.822924)
		(width 0.11684)
		(layer "In11.Cu")
		(net "RST_RT_CPU1_P1_RESET_R_N")
	)
	(segment
		(start 179.449984 -139.980416)
		(end 179.62753 -139.80287)
		(width 0.11684)
		(layer "In11.Cu")
		(net "RST_RT_CPU1_P1_RESET_R_N")
	)
	(segment
		(start 179.247038 -169.988484)
		(end 176.532794 -167.27424)
		(width 0.11684)
		(layer "In11.Cu")
		(net "RST_RT_CPU1_P1_RESET_R_N")
	)
	(segment
		(start 176.532794 -167.27424)
		(end 176.532794 -159.4104)
		(width 0.11684)
		(layer "In11.Cu")
		(net "RST_RT_CPU1_P1_RESET_R_N")
	)
	(segment
		(start 179.62753 -138.153902)
		(end 180.145944 -137.635488)
		(width 0.11684)
		(layer "In11.Cu")
		(net "RST_RT_CPU1_P1_RESET_R_N")
	)
	(segment
		(start 179.62753 -139.80287)
		(end 179.62753 -138.153902)
		(width 0.11684)
		(layer "In11.Cu")
		(net "RST_RT_CPU1_P1_RESET_R_N")
	)
	(segment
		(start 176.532794 -159.4104)
		(end 179.356512 -156.586682)
		(width 0.11684)
		(layer "In11.Cu")
		(net "RST_RT_CPU1_P1_RESET_R_N")
	)
	(segment
		(start 181.360572 -145.822924)
		(end 179.449984 -143.912082)
		(width 0.11684)
		(layer "In11.Cu")
		(net "RST_RT_CPU1_P1_RESET_R_N")
	)
	(segment
		(start 179.247038 -172.601382)
		(end 179.247038 -169.988484)
		(width 0.11684)
		(layer "In11.Cu")
		(net "RST_RT_CPU1_P1_RESET_R_N")
	)
	(segment
		(start 179.356512 -149.002242)
		(end 181.360572 -146.998182)
		(width 0.11684)
		(layer "In11.Cu")
		(net "RST_RT_CPU1_P1_RESET_R_N")
	)
	(segment
		(start 179.356512 -156.586682)
		(end 179.356512 -149.002242)
		(width 0.11684)
		(layer "In11.Cu")
		(net "RST_RT_CPU1_P1_RESET_R_N")
	)
	(segment
		(start 225.12782 -337.159854)
		(end 225.12782 -340.0298)
		(width 0.11684)
		(layer "In15.Cu")
		(net "RST_RT_CPU1_P1_RESET_R_N")
	)
	(segment
		(start 223.90354 -324.830948)
		(end 223.90354 -335.935574)
		(width 0.11684)
		(layer "In15.Cu")
		(net "RST_RT_CPU1_P1_RESET_R_N")
	)
	(segment
		(start 216.983818 -317.911226)
		(end 223.90354 -324.830948)
		(width 0.11684)
		(layer "In15.Cu")
		(net "RST_RT_CPU1_P1_RESET_R_N")
	)
	(segment
		(start 219.651072 -215.221058)
		(end 216.983818 -217.888312)
		(width 0.11684)
		(layer "In15.Cu")
		(net "RST_RT_CPU1_P1_RESET_R_N")
	)
	(segment
		(start 225.12782 -340.0298)
		(end 226.21748 -341.11946)
		(width 0.11684)
		(layer "In15.Cu")
		(net "RST_RT_CPU1_P1_RESET_R_N")
	)
	(segment
		(start 223.90354 -335.935574)
		(end 225.12782 -337.159854)
		(width 0.11684)
		(layer "In15.Cu")
		(net "RST_RT_CPU1_P1_RESET_R_N")
	)
	(segment
		(start 216.983818 -217.888312)
		(end 216.983818 -317.911226)
		(width 0.11684)
		(layer "In15.Cu")
		(net "RST_RT_CPU1_P1_RESET_R_N")
	)
	(segment
		(start 219.651072 -214.58301)
		(end 219.651072 -215.221058)
		(width 0.11684)
		(layer "In15.Cu")
		(net "RST_RT_CPU1_P1_RESET_R_N")
	)
	(segment
		(start 179.961286 -133.03758)
		(end 179.961286 -131.412234)
		(width 0.10668)
		(layer "F.Cu")
		(net "RST_RT_CPU1_P1_RESET_R2_N")
	)
	(segment
		(start 181.922166 -120.252744)
		(end 181.532276 -120.642634)
		(width 0.10668)
		(layer "F.Cu")
		(net "RST_RT_CPU1_P1_RESET_R2_N")
	)
	(segment
		(start 179.961286 -131.412234)
		(end 179.959 -131.409948)
		(width 0.10668)
		(layer "F.Cu")
		(net "RST_RT_CPU1_P1_RESET_R2_N")
	)
	(via
		(at 181.532276 -120.642634)
		(size 0.4572)
		(drill 0.254)
		(layers "F.Cu" "B.Cu")
		(net "RST_RT_CPU1_P1_RESET_R2_N")
	)
	(via
		(at 179.959 -131.409948)
		(size 0.508)
		(drill 0.254)
		(layers "F.Cu" "B.Cu")
		(net "RST_RT_CPU1_P1_RESET_R2_N")
	)
	(segment
		(start 179.269136 -130.720084)
		(end 179.269136 -129.764536)
		(width 0.11684)
		(layer "In11.Cu")
		(net "RST_RT_CPU1_P1_RESET_R2_N")
	)
	(segment
		(start 181.143148 -126.747016)
		(end 181.143148 -121.031762)
		(width 0.11684)
		(layer "In11.Cu")
		(net "RST_RT_CPU1_P1_RESET_R2_N")
	)
	(segment
		(start 179.473606 -128.416558)
		(end 181.143148 -126.747016)
		(width 0.11684)
		(layer "In11.Cu")
		(net "RST_RT_CPU1_P1_RESET_R2_N")
	)
	(segment
		(start 179.269136 -129.764536)
		(end 179.473606 -129.560066)
		(width 0.11684)
		(layer "In11.Cu")
		(net "RST_RT_CPU1_P1_RESET_R2_N")
	)
	(segment
		(start 179.959 -131.409948)
		(end 179.269136 -130.720084)
		(width 0.11684)
		(layer "In11.Cu")
		(net "RST_RT_CPU1_P1_RESET_R2_N")
	)
	(segment
		(start 179.473606 -129.560066)
		(end 179.473606 -128.416558)
		(width 0.11684)
		(layer "In11.Cu")
		(net "RST_RT_CPU1_P1_RESET_R2_N")
	)
	(segment
		(start 181.143148 -121.031762)
		(end 181.532276 -120.642634)
		(width 0.11684)
		(layer "In11.Cu")
		(net "RST_RT_CPU1_P1_RESET_R2_N")
	)
	(segment
		(start 76.250546 -393.980416)
		(end 76.250546 -394.636752)
		(width 0.10668)
		(layer "F.Cu")
		(net "RST_RT_CPU1_P1_RESET_N")
	)
	(segment
		(start 77.206602 -388.730998)
		(end 76.390754 -389.546846)
		(width 0.10668)
		(layer "F.Cu")
		(net "RST_RT_CPU1_P1_RESET_N")
	)
	(segment
		(start 78.62951 -388.730998)
		(end 77.206602 -388.730998)
		(width 0.10668)
		(layer "F.Cu")
		(net "RST_RT_CPU1_P1_RESET_N")
	)
	(segment
		(start 75.970892 -394.636752)
		(end 76.250546 -394.636752)
		(width 0.10668)
		(layer "F.Cu")
		(net "RST_RT_CPU1_P1_RESET_N")
	)
	(segment
		(start 75.823318 -396.693898)
		(end 75.823318 -394.784326)
		(width 0.10668)
		(layer "F.Cu")
		(net "RST_RT_CPU1_P1_RESET_N")
	)
	(segment
		(start 76.390754 -393.840208)
		(end 76.250546 -393.980416)
		(width 0.10668)
		(layer "F.Cu")
		(net "RST_RT_CPU1_P1_RESET_N")
	)
	(segment
		(start 75.823318 -394.784326)
		(end 75.970892 -394.636752)
		(width 0.10668)
		(layer "F.Cu")
		(net "RST_RT_CPU1_P1_RESET_N")
	)
	(segment
		(start 76.390754 -389.546846)
		(end 76.390754 -393.840208)
		(width 0.10668)
		(layer "F.Cu")
		(net "RST_RT_CPU1_P1_RESET_N")
	)
	(segment
		(start 79.42961 -400.30019)
		(end 75.823318 -396.693898)
		(width 0.10668)
		(layer "F.Cu")
		(net "RST_RT_CPU1_P1_RESET_N")
	)
	(via
		(at 79.42961 -400.30019)
		(size 0.762)
		(drill 0.381)
		(layers "F.Cu" "B.Cu")
		(net "RST_RT_CPU1_P1_RESET_N")
	)
	(segment
		(start 179.835048 -173.265084)
		(end 179.835048 -171.916344)
		(width 0.10668)
		(layer "F.Cu")
		(net "RST_RT_CPU1_P1_PERST_R_N")
	)
	(segment
		(start 185.265314 -186.47029)
		(end 185.265314 -178.69535)
		(width 0.10668)
		(layer "F.Cu")
		(net "RST_RT_CPU1_P1_PERST_R_N")
	)
	(segment
		(start 100.696268 -395.3637)
		(end 100.696268 -394.6271)
		(width 0.10668)
		(layer "F.Cu")
		(net "RST_RT_CPU1_P1_PERST_R_N")
	)
	(segment
		(start 100.261928 -392.975084)
		(end 100.421186 -392.815826)
		(width 0.10668)
		(layer "F.Cu")
		(net "RST_RT_CPU1_P1_PERST_R_N")
	)
	(segment
		(start 100.696268 -394.6271)
		(end 100.402136 -394.6271)
		(width 0.10668)
		(layer "F.Cu")
		(net "RST_RT_CPU1_P1_PERST_R_N")
	)
	(segment
		(start 100.402136 -394.6271)
		(end 100.261928 -394.486892)
		(width 0.10668)
		(layer "F.Cu")
		(net "RST_RT_CPU1_P1_PERST_R_N")
	)
	(segment
		(start 185.265314 -178.69535)
		(end 179.835048 -173.265084)
		(width 0.10668)
		(layer "F.Cu")
		(net "RST_RT_CPU1_P1_PERST_R_N")
	)
	(segment
		(start 100.261928 -394.486892)
		(end 100.261928 -392.975084)
		(width 0.10668)
		(layer "F.Cu")
		(net "RST_RT_CPU1_P1_PERST_R_N")
	)
	(segment
		(start 180.457856 -140.347192)
		(end 180.457856 -141.487144)
		(width 0.10668)
		(layer "F.Cu")
		(net "RST_RT_CPU1_P1_PERST_R_N")
	)
	(via
		(at 225.768916 -339.835744)
		(size 0.508)
		(drill 0.254)
		(layers "F.Cu" "B.Cu")
		(net "RST_RT_CPU1_P1_PERST_R_N")
	)
	(via
		(at 185.265314 -186.47029)
		(size 0.508)
		(drill 0.254)
		(layers "F.Cu" "B.Cu")
		(net "RST_RT_CPU1_P1_PERST_R_N")
	)
	(via
		(at 180.457856 -141.487144)
		(size 0.508)
		(drill 0.254)
		(layers "F.Cu" "B.Cu")
		(net "RST_RT_CPU1_P1_PERST_R_N")
	)
	(via
		(at 179.835048 -171.916344)
		(size 0.508)
		(drill 0.254)
		(layers "F.Cu" "B.Cu")
		(net "RST_RT_CPU1_P1_PERST_R_N")
	)
	(via
		(at 219.737686 -216.10193)
		(size 0.508)
		(drill 0.254)
		(layers "F.Cu" "B.Cu")
		(net "RST_RT_CPU1_P1_PERST_R_N")
	)
	(via
		(at 100.421186 -392.815826)
		(size 0.508)
		(drill 0.254)
		(layers "F.Cu" "B.Cu")
		(net "RST_RT_CPU1_P1_PERST_R_N")
	)
	(segment
		(start 186.403742 -183.417464)
		(end 185.265314 -184.555892)
		(width 0.10668)
		(layer "B.Cu")
		(net "RST_RT_CPU1_P1_PERST_R_N")
	)
	(segment
		(start 219.737686 -216.10193)
		(end 219.132912 -216.10193)
		(width 0.10668)
		(layer "B.Cu")
		(net "RST_RT_CPU1_P1_PERST_R_N")
	)
	(segment
		(start 219.132912 -216.10193)
		(end 216.715594 -213.684612)
		(width 0.10668)
		(layer "B.Cu")
		(net "RST_RT_CPU1_P1_PERST_R_N")
	)
	(segment
		(start 209.527902 -183.417464)
		(end 186.403742 -183.417464)
		(width 0.10668)
		(layer "B.Cu")
		(net "RST_RT_CPU1_P1_PERST_R_N")
	)
	(segment
		(start 185.265314 -184.555892)
		(end 185.265314 -186.47029)
		(width 0.10668)
		(layer "B.Cu")
		(net "RST_RT_CPU1_P1_PERST_R_N")
	)
	(segment
		(start 216.715594 -213.684612)
		(end 216.715594 -190.605156)
		(width 0.10668)
		(layer "B.Cu")
		(net "RST_RT_CPU1_P1_PERST_R_N")
	)
	(segment
		(start 216.715594 -190.605156)
		(end 209.527902 -183.417464)
		(width 0.10668)
		(layer "B.Cu")
		(net "RST_RT_CPU1_P1_PERST_R_N")
	)
	(segment
		(start 165.899338 -399.768822)
		(end 165.360858 -400.307302)
		(width 0.11684)
		(layer "In2.Cu")
		(net "RST_RT_CPU1_P1_PERST_R_N")
	)
	(segment
		(start 171.923964 -399.768822)
		(end 165.899338 -399.768822)
		(width 0.11684)
		(layer "In2.Cu")
		(net "RST_RT_CPU1_P1_PERST_R_N")
	)
	(segment
		(start 110.650528 -399.07972)
		(end 109.764576 -399.965672)
		(width 0.11684)
		(layer "In2.Cu")
		(net "RST_RT_CPU1_P1_PERST_R_N")
	)
	(segment
		(start 120.834658 -399.965672)
		(end 119.948706 -399.07972)
		(width 0.11684)
		(layer "In2.Cu")
		(net "RST_RT_CPU1_P1_PERST_R_N")
	)
	(segment
		(start 202.763882 -371.313456)
		(end 200.043288 -371.313456)
		(width 0.11684)
		(layer "In2.Cu")
		(net "RST_RT_CPU1_P1_PERST_R_N")
	)
	(segment
		(start 174.898558 -392.96594)
		(end 174.898558 -396.794228)
		(width 0.11684)
		(layer "In2.Cu")
		(net "RST_RT_CPU1_P1_PERST_R_N")
	)
	(segment
		(start 160.644586 -400.307302)
		(end 160.302956 -399.965672)
		(width 0.11684)
		(layer "In2.Cu")
		(net "RST_RT_CPU1_P1_PERST_R_N")
	)
	(segment
		(start 198.414132 -371.858032)
		(end 192.694814 -377.57735)
		(width 0.11684)
		(layer "In2.Cu")
		(net "RST_RT_CPU1_P1_PERST_R_N")
	)
	(segment
		(start 102.029006 -396.306802)
		(end 100.421186 -394.698982)
		(width 0.11684)
		(layer "In2.Cu")
		(net "RST_RT_CPU1_P1_PERST_R_N")
	)
	(segment
		(start 181.69636 -387.014466)
		(end 180.850032 -387.014466)
		(width 0.11684)
		(layer "In2.Cu")
		(net "RST_RT_CPU1_P1_PERST_R_N")
	)
	(segment
		(start 225.655886 -339.948774)
		(end 225.655886 -350.91116)
		(width 0.11684)
		(layer "In2.Cu")
		(net "RST_RT_CPU1_P1_PERST_R_N")
	)
	(segment
		(start 216.502742 -367.03254)
		(end 207.044798 -367.03254)
		(width 0.11684)
		(layer "In2.Cu")
		(net "RST_RT_CPU1_P1_PERST_R_N")
	)
	(segment
		(start 223.460564 -359.805224)
		(end 223.460564 -360.074718)
		(width 0.11684)
		(layer "In2.Cu")
		(net "RST_RT_CPU1_P1_PERST_R_N")
	)
	(segment
		(start 165.360858 -400.307302)
		(end 160.644586 -400.307302)
		(width 0.11684)
		(layer "In2.Cu")
		(net "RST_RT_CPU1_P1_PERST_R_N")
	)
	(segment
		(start 224.28962 -358.976168)
		(end 223.460564 -359.805224)
		(width 0.11684)
		(layer "In2.Cu")
		(net "RST_RT_CPU1_P1_PERST_R_N")
	)
	(segment
		(start 199.498712 -371.858032)
		(end 198.414132 -371.858032)
		(width 0.11684)
		(layer "In2.Cu")
		(net "RST_RT_CPU1_P1_PERST_R_N")
	)
	(segment
		(start 191.133476 -377.57735)
		(end 181.69636 -387.014466)
		(width 0.11684)
		(layer "In2.Cu")
		(net "RST_RT_CPU1_P1_PERST_R_N")
	)
	(segment
		(start 180.850032 -387.014466)
		(end 174.898558 -392.96594)
		(width 0.11684)
		(layer "In2.Cu")
		(net "RST_RT_CPU1_P1_PERST_R_N")
	)
	(segment
		(start 192.694814 -377.57735)
		(end 191.133476 -377.57735)
		(width 0.11684)
		(layer "In2.Cu")
		(net "RST_RT_CPU1_P1_PERST_R_N")
	)
	(segment
		(start 103.124508 -396.306802)
		(end 102.029006 -396.306802)
		(width 0.11684)
		(layer "In2.Cu")
		(net "RST_RT_CPU1_P1_PERST_R_N")
	)
	(segment
		(start 223.460564 -360.074718)
		(end 216.502742 -367.03254)
		(width 0.11684)
		(layer "In2.Cu")
		(net "RST_RT_CPU1_P1_PERST_R_N")
	)
	(segment
		(start 174.898558 -396.794228)
		(end 171.923964 -399.768822)
		(width 0.11684)
		(layer "In2.Cu")
		(net "RST_RT_CPU1_P1_PERST_R_N")
	)
	(segment
		(start 106.783378 -399.965672)
		(end 103.124508 -396.306802)
		(width 0.11684)
		(layer "In2.Cu")
		(net "RST_RT_CPU1_P1_PERST_R_N")
	)
	(segment
		(start 224.28962 -352.277426)
		(end 224.28962 -358.976168)
		(width 0.11684)
		(layer "In2.Cu")
		(net "RST_RT_CPU1_P1_PERST_R_N")
	)
	(segment
		(start 225.768916 -339.835744)
		(end 225.655886 -339.948774)
		(width 0.11684)
		(layer "In2.Cu")
		(net "RST_RT_CPU1_P1_PERST_R_N")
	)
	(segment
		(start 100.421186 -394.698982)
		(end 100.421186 -392.815826)
		(width 0.11684)
		(layer "In2.Cu")
		(net "RST_RT_CPU1_P1_PERST_R_N")
	)
	(segment
		(start 160.302956 -399.965672)
		(end 120.834658 -399.965672)
		(width 0.11684)
		(layer "In2.Cu")
		(net "RST_RT_CPU1_P1_PERST_R_N")
	)
	(segment
		(start 207.044798 -367.03254)
		(end 202.763882 -371.313456)
		(width 0.11684)
		(layer "In2.Cu")
		(net "RST_RT_CPU1_P1_PERST_R_N")
	)
	(segment
		(start 200.043288 -371.313456)
		(end 199.498712 -371.858032)
		(width 0.11684)
		(layer "In2.Cu")
		(net "RST_RT_CPU1_P1_PERST_R_N")
	)
	(segment
		(start 225.655886 -350.91116)
		(end 224.28962 -352.277426)
		(width 0.11684)
		(layer "In2.Cu")
		(net "RST_RT_CPU1_P1_PERST_R_N")
	)
	(segment
		(start 109.764576 -399.965672)
		(end 106.783378 -399.965672)
		(width 0.11684)
		(layer "In2.Cu")
		(net "RST_RT_CPU1_P1_PERST_R_N")
	)
	(segment
		(start 119.948706 -399.07972)
		(end 110.650528 -399.07972)
		(width 0.11684)
		(layer "In2.Cu")
		(net "RST_RT_CPU1_P1_PERST_R_N")
	)
	(segment
		(start 179.805076 -149.18817)
		(end 181.809136 -147.18411)
		(width 0.11684)
		(layer "In11.Cu")
		(net "RST_RT_CPU1_P1_PERST_R_N")
	)
	(segment
		(start 181.809136 -145.636996)
		(end 180.457856 -144.285716)
		(width 0.11684)
		(layer "In11.Cu")
		(net "RST_RT_CPU1_P1_PERST_R_N")
	)
	(segment
		(start 179.835048 -171.916344)
		(end 179.835048 -169.942002)
		(width 0.11684)
		(layer "In11.Cu")
		(net "RST_RT_CPU1_P1_PERST_R_N")
	)
	(segment
		(start 181.809136 -147.18411)
		(end 181.809136 -145.636996)
		(width 0.11684)
		(layer "In11.Cu")
		(net "RST_RT_CPU1_P1_PERST_R_N")
	)
	(segment
		(start 180.457856 -144.285716)
		(end 180.457856 -141.487144)
		(width 0.11684)
		(layer "In11.Cu")
		(net "RST_RT_CPU1_P1_PERST_R_N")
	)
	(segment
		(start 179.805076 -156.77261)
		(end 179.805076 -149.18817)
		(width 0.11684)
		(layer "In11.Cu")
		(net "RST_RT_CPU1_P1_PERST_R_N")
	)
	(segment
		(start 179.835048 -169.942002)
		(end 176.981358 -167.088312)
		(width 0.11684)
		(layer "In11.Cu")
		(net "RST_RT_CPU1_P1_PERST_R_N")
	)
	(segment
		(start 176.981358 -167.088312)
		(end 176.981358 -159.596328)
		(width 0.11684)
		(layer "In11.Cu")
		(net "RST_RT_CPU1_P1_PERST_R_N")
	)
	(segment
		(start 176.981358 -159.596328)
		(end 179.805076 -156.77261)
		(width 0.11684)
		(layer "In11.Cu")
		(net "RST_RT_CPU1_P1_PERST_R_N")
	)
	(segment
		(start 217.440256 -317.771272)
		(end 224.32518 -324.656196)
		(width 0.11684)
		(layer "In15.Cu")
		(net "RST_RT_CPU1_P1_PERST_R_N")
	)
	(segment
		(start 219.737686 -216.10193)
		(end 217.440256 -218.39936)
		(width 0.11684)
		(layer "In15.Cu")
		(net "RST_RT_CPU1_P1_PERST_R_N")
	)
	(segment
		(start 225.768916 -339.298534)
		(end 225.768916 -339.835744)
		(width 0.11684)
		(layer "In15.Cu")
		(net "RST_RT_CPU1_P1_PERST_R_N")
	)
	(segment
		(start 225.600768 -336.987134)
		(end 225.600768 -339.130386)
		(width 0.11684)
		(layer "In15.Cu")
		(net "RST_RT_CPU1_P1_PERST_R_N")
	)
	(segment
		(start 225.600768 -339.130386)
		(end 225.768916 -339.298534)
		(width 0.11684)
		(layer "In15.Cu")
		(net "RST_RT_CPU1_P1_PERST_R_N")
	)
	(segment
		(start 217.440256 -218.39936)
		(end 217.440256 -317.771272)
		(width 0.11684)
		(layer "In15.Cu")
		(net "RST_RT_CPU1_P1_PERST_R_N")
	)
	(segment
		(start 224.32518 -324.656196)
		(end 224.32518 -335.711546)
		(width 0.11684)
		(layer "In15.Cu")
		(net "RST_RT_CPU1_P1_PERST_R_N")
	)
	(segment
		(start 224.32518 -335.711546)
		(end 225.600768 -336.987134)
		(width 0.11684)
		(layer "In15.Cu")
		(net "RST_RT_CPU1_P1_PERST_R_N")
	)
	(segment
		(start 180.457856 -139.547092)
		(end 180.457856 -138.629898)
		(width 0.10668)
		(layer "F.Cu")
		(net "RST_RT_CPU1_P1_PERST_R2_N")
	)
	(segment
		(start 180.457856 -138.629898)
		(end 180.448966 -138.621008)
		(width 0.10668)
		(layer "F.Cu")
		(net "RST_RT_CPU1_P1_PERST_R2_N")
	)
	(segment
		(start 181.922166 -121.052844)
		(end 181.532276 -121.442734)
		(width 0.10668)
		(layer "F.Cu")
		(net "RST_RT_CPU1_P1_PERST_R2_N")
	)
	(via
		(at 181.532276 -121.442734)
		(size 0.4572)
		(drill 0.254)
		(layers "F.Cu" "B.Cu")
		(net "RST_RT_CPU1_P1_PERST_R2_N")
	)
	(via
		(at 180.448966 -138.621008)
		(size 0.508)
		(drill 0.254)
		(layers "F.Cu" "B.Cu")
		(net "RST_RT_CPU1_P1_PERST_R2_N")
	)
	(segment
		(start 180.211476 -130.91033)
		(end 180.211476 -129.749296)
		(width 0.11684)
		(layer "In11.Cu")
		(net "RST_RT_CPU1_P1_PERST_R2_N")
	)
	(segment
		(start 180.45303 -131.151884)
		(end 180.211476 -130.91033)
		(width 0.11684)
		(layer "In11.Cu")
		(net "RST_RT_CPU1_P1_PERST_R2_N")
	)
	(segment
		(start 181.928516 -121.838974)
		(end 181.532276 -121.442734)
		(width 0.11684)
		(layer "In11.Cu")
		(net "RST_RT_CPU1_P1_PERST_R2_N")
	)
	(segment
		(start 179.93614 -133.47319)
		(end 179.93614 -132.09778)
		(width 0.11684)
		(layer "In11.Cu")
		(net "RST_RT_CPU1_P1_PERST_R2_N")
	)
	(segment
		(start 180.952394 -127.721868)
		(end 181.928516 -126.745746)
		(width 0.11684)
		(layer "In11.Cu")
		(net "RST_RT_CPU1_P1_PERST_R2_N")
	)
	(segment
		(start 180.952394 -129.008378)
		(end 180.952394 -127.721868)
		(width 0.11684)
		(layer "In11.Cu")
		(net "RST_RT_CPU1_P1_PERST_R2_N")
	)
	(segment
		(start 181.361842 -134.898892)
		(end 179.93614 -133.47319)
		(width 0.11684)
		(layer "In11.Cu")
		(net "RST_RT_CPU1_P1_PERST_R2_N")
	)
	(segment
		(start 181.928516 -126.745746)
		(end 181.928516 -121.838974)
		(width 0.11684)
		(layer "In11.Cu")
		(net "RST_RT_CPU1_P1_PERST_R2_N")
	)
	(segment
		(start 181.234842 -138.621008)
		(end 181.361842 -138.494008)
		(width 0.11684)
		(layer "In11.Cu")
		(net "RST_RT_CPU1_P1_PERST_R2_N")
	)
	(segment
		(start 180.45303 -131.58089)
		(end 180.45303 -131.151884)
		(width 0.11684)
		(layer "In11.Cu")
		(net "RST_RT_CPU1_P1_PERST_R2_N")
	)
	(segment
		(start 179.93614 -132.09778)
		(end 180.45303 -131.58089)
		(width 0.11684)
		(layer "In11.Cu")
		(net "RST_RT_CPU1_P1_PERST_R2_N")
	)
	(segment
		(start 180.211476 -129.749296)
		(end 180.952394 -129.008378)
		(width 0.11684)
		(layer "In11.Cu")
		(net "RST_RT_CPU1_P1_PERST_R2_N")
	)
	(segment
		(start 181.361842 -138.494008)
		(end 181.361842 -134.898892)
		(width 0.11684)
		(layer "In11.Cu")
		(net "RST_RT_CPU1_P1_PERST_R2_N")
	)
	(segment
		(start 180.448966 -138.621008)
		(end 181.234842 -138.621008)
		(width 0.11684)
		(layer "In11.Cu")
		(net "RST_RT_CPU1_P1_PERST_R2_N")
	)
	(segment
		(start 100.152708 -395.8971)
		(end 99.901248 -395.64564)
		(width 0.10668)
		(layer "F.Cu")
		(net "RST_RT_CPU1_P1_PERST_N")
	)
	(segment
		(start 99.901248 -395.64564)
		(end 99.901248 -392.599672)
		(width 0.10668)
		(layer "F.Cu")
		(net "RST_RT_CPU1_P1_PERST_N")
	)
	(segment
		(start 99.145852 -391.844276)
		(end 99.145852 -390.761474)
		(width 0.10668)
		(layer "F.Cu")
		(net "RST_RT_CPU1_P1_PERST_N")
	)
	(segment
		(start 100.696268 -396.108936)
		(end 100.368354 -396.43685)
		(width 0.10668)
		(layer "F.Cu")
		(net "RST_RT_CPU1_P1_PERST_N")
	)
	(segment
		(start 100.368354 -396.43685)
		(end 99.888294 -396.43685)
		(width 0.10668)
		(layer "F.Cu")
		(net "RST_RT_CPU1_P1_PERST_N")
	)
	(segment
		(start 99.901248 -392.599672)
		(end 99.145852 -391.844276)
		(width 0.10668)
		(layer "F.Cu")
		(net "RST_RT_CPU1_P1_PERST_N")
	)
	(segment
		(start 100.696268 -395.8971)
		(end 100.696268 -396.108936)
		(width 0.10668)
		(layer "F.Cu")
		(net "RST_RT_CPU1_P1_PERST_N")
	)
	(segment
		(start 100.696268 -395.8971)
		(end 100.152708 -395.8971)
		(width 0.10668)
		(layer "F.Cu")
		(net "RST_RT_CPU1_P1_PERST_N")
	)
	(via
		(at 99.888294 -396.43685)
		(size 0.762)
		(drill 0.381)
		(layers "F.Cu" "B.Cu")
		(net "RST_RT_CPU1_P1_PERST_N")
	)
	(segment
		(start 41.005252 -389.0264)
		(end 41.2877 -389.0264)
		(width 0.10668)
		(layer "F.Cu")
		(net "RST_RT_CPU1_P0_RESET_R_N")
	)
	(segment
		(start 41.2877 -389.0264)
		(end 41.2877 -389.8392)
		(width 0.10668)
		(layer "F.Cu")
		(net "RST_RT_CPU1_P0_RESET_R_N")
	)
	(segment
		(start 40.738552 -388.7597)
		(end 41.005252 -389.0264)
		(width 0.10668)
		(layer "F.Cu")
		(net "RST_RT_CPU1_P0_RESET_R_N")
	)
	(segment
		(start 178.710336 -173.731174)
		(end 178.710336 -171.842176)
		(width 0.10668)
		(layer "F.Cu")
		(net "RST_RT_CPU1_P0_RESET_R_N")
	)
	(segment
		(start 184.330848 -186.47029)
		(end 184.330848 -179.351686)
		(width 0.10668)
		(layer "F.Cu")
		(net "RST_RT_CPU1_P0_RESET_R_N")
	)
	(segment
		(start 40.386 -388.7597)
		(end 40.386 -387.47192)
		(width 0.10668)
		(layer "F.Cu")
		(net "RST_RT_CPU1_P0_RESET_R_N")
	)
	(segment
		(start 40.386 -388.7597)
		(end 40.738552 -388.7597)
		(width 0.10668)
		(layer "F.Cu")
		(net "RST_RT_CPU1_P0_RESET_R_N")
	)
	(segment
		(start 184.330848 -179.351686)
		(end 178.710336 -173.731174)
		(width 0.10668)
		(layer "F.Cu")
		(net "RST_RT_CPU1_P0_RESET_R_N")
	)
	(via
		(at 40.386 -387.47192)
		(size 0.508)
		(drill 0.254)
		(layers "F.Cu" "B.Cu")
		(net "RST_RT_CPU1_P0_RESET_R_N")
	)
	(via
		(at 219.862654 -213.669626)
		(size 0.508)
		(drill 0.254)
		(layers "F.Cu" "B.Cu")
		(net "RST_RT_CPU1_P0_RESET_R_N")
	)
	(via
		(at 184.330848 -186.47029)
		(size 0.508)
		(drill 0.254)
		(layers "F.Cu" "B.Cu")
		(net "RST_RT_CPU1_P0_RESET_R_N")
	)
	(via
		(at 190.53937 -385.178554)
		(size 0.508)
		(drill 0.254)
		(layers "F.Cu" "B.Cu")
		(net "RST_RT_CPU1_P0_RESET_R_N")
	)
	(via
		(at 178.474878 -135.55853)
		(size 0.508)
		(drill 0.254)
		(layers "F.Cu" "B.Cu")
		(net "RST_RT_CPU1_P0_RESET_R_N")
	)
	(via
		(at 178.710336 -171.842176)
		(size 0.508)
		(drill 0.254)
		(layers "F.Cu" "B.Cu")
		(net "RST_RT_CPU1_P0_RESET_R_N")
	)
	(segment
		(start 179.275486 -133.371082)
		(end 178.474878 -134.17169)
		(width 0.10668)
		(layer "B.Cu")
		(net "RST_RT_CPU1_P0_RESET_R_N")
	)
	(segment
		(start 179.275486 -132.253736)
		(end 179.275486 -133.371082)
		(width 0.10668)
		(layer "B.Cu")
		(net "RST_RT_CPU1_P0_RESET_R_N")
	)
	(segment
		(start 178.474878 -134.17169)
		(end 178.474878 -135.55853)
		(width 0.10668)
		(layer "B.Cu")
		(net "RST_RT_CPU1_P0_RESET_R_N")
	)
	(segment
		(start 219.862654 -213.669626)
		(end 218.689428 -213.669626)
		(width 0.10668)
		(layer "B.Cu")
		(net "RST_RT_CPU1_P0_RESET_R_N")
	)
	(segment
		(start 178.123596 -131.101846)
		(end 179.275486 -132.253736)
		(width 0.10668)
		(layer "B.Cu")
		(net "RST_RT_CPU1_P0_RESET_R_N")
	)
	(segment
		(start 185.910474 -182.696104)
		(end 184.330848 -184.27573)
		(width 0.10668)
		(layer "B.Cu")
		(net "RST_RT_CPU1_P0_RESET_R_N")
	)
	(segment
		(start 209.856578 -182.696104)
		(end 185.910474 -182.696104)
		(width 0.10668)
		(layer "B.Cu")
		(net "RST_RT_CPU1_P0_RESET_R_N")
	)
	(segment
		(start 218.689428 -213.669626)
		(end 217.468704 -212.448902)
		(width 0.10668)
		(layer "B.Cu")
		(net "RST_RT_CPU1_P0_RESET_R_N")
	)
	(segment
		(start 217.468704 -190.30823)
		(end 209.856578 -182.696104)
		(width 0.10668)
		(layer "B.Cu")
		(net "RST_RT_CPU1_P0_RESET_R_N")
	)
	(segment
		(start 178.123596 -129.840482)
		(end 178.123596 -131.101846)
		(width 0.10668)
		(layer "B.Cu")
		(net "RST_RT_CPU1_P0_RESET_R_N")
	)
	(segment
		(start 178.981608 -127.233426)
		(end 178.981608 -128.98247)
		(width 0.10668)
		(layer "B.Cu")
		(net "RST_RT_CPU1_P0_RESET_R_N")
	)
	(segment
		(start 217.468704 -212.448902)
		(end 217.468704 -190.30823)
		(width 0.10668)
		(layer "B.Cu")
		(net "RST_RT_CPU1_P0_RESET_R_N")
	)
	(segment
		(start 178.981608 -128.98247)
		(end 178.123596 -129.840482)
		(width 0.10668)
		(layer "B.Cu")
		(net "RST_RT_CPU1_P0_RESET_R_N")
	)
	(segment
		(start 184.330848 -184.27573)
		(end 184.330848 -186.47029)
		(width 0.10668)
		(layer "B.Cu")
		(net "RST_RT_CPU1_P0_RESET_R_N")
	)
	(segment
		(start 182.500524 -392.16838)
		(end 176.19599 -398.472914)
		(width 0.11684)
		(layer "In2.Cu")
		(net "RST_RT_CPU1_P0_RESET_R_N")
	)
	(segment
		(start 112.048798 -401.18411)
		(end 111.975646 -401.257262)
		(width 0.11684)
		(layer "In2.Cu")
		(net "RST_RT_CPU1_P0_RESET_R_N")
	)
	(segment
		(start 174.241968 -409.838144)
		(end 168.884092 -409.838144)
		(width 0.11684)
		(layer "In2.Cu")
		(net "RST_RT_CPU1_P0_RESET_R_N")
	)
	(segment
		(start 99.19081 -397.44269)
		(end 98.86188 -397.11376)
		(width 0.11684)
		(layer "In2.Cu")
		(net "RST_RT_CPU1_P0_RESET_R_N")
	)
	(segment
		(start 106.285792 -401.257262)
		(end 103.901494 -398.872964)
		(width 0.11684)
		(layer "In2.Cu")
		(net "RST_RT_CPU1_P0_RESET_R_N")
	)
	(segment
		(start 120.051322 -401.257262)
		(end 119.97817 -401.18411)
		(width 0.11684)
		(layer "In2.Cu")
		(net "RST_RT_CPU1_P0_RESET_R_N")
	)
	(segment
		(start 158.915608 -401.257262)
		(end 120.051322 -401.257262)
		(width 0.11684)
		(layer "In2.Cu")
		(net "RST_RT_CPU1_P0_RESET_R_N")
	)
	(segment
		(start 100.46081 -397.44269)
		(end 99.19081 -397.44269)
		(width 0.11684)
		(layer "In2.Cu")
		(net "RST_RT_CPU1_P0_RESET_R_N")
	)
	(segment
		(start 48.668178 -395.665452)
		(end 42.499026 -389.4963)
		(width 0.11684)
		(layer "In2.Cu")
		(net "RST_RT_CPU1_P0_RESET_R_N")
	)
	(segment
		(start 101.891084 -398.872964)
		(end 100.46081 -397.44269)
		(width 0.11684)
		(layer "In2.Cu")
		(net "RST_RT_CPU1_P0_RESET_R_N")
	)
	(segment
		(start 64.342518 -395.665452)
		(end 48.668178 -395.665452)
		(width 0.11684)
		(layer "In2.Cu")
		(net "RST_RT_CPU1_P0_RESET_R_N")
	)
	(segment
		(start 103.901494 -398.872964)
		(end 101.891084 -398.872964)
		(width 0.11684)
		(layer "In2.Cu")
		(net "RST_RT_CPU1_P0_RESET_R_N")
	)
	(segment
		(start 42.499026 -389.4963)
		(end 42.065194 -389.4963)
		(width 0.11684)
		(layer "In2.Cu")
		(net "RST_RT_CPU1_P0_RESET_R_N")
	)
	(segment
		(start 65.297558 -396.620492)
		(end 64.342518 -395.665452)
		(width 0.11684)
		(layer "In2.Cu")
		(net "RST_RT_CPU1_P0_RESET_R_N")
	)
	(segment
		(start 98.86188 -397.11376)
		(end 97.475548 -397.11376)
		(width 0.11684)
		(layer "In2.Cu")
		(net "RST_RT_CPU1_P0_RESET_R_N")
	)
	(segment
		(start 176.19599 -407.884122)
		(end 174.241968 -409.838144)
		(width 0.11684)
		(layer "In2.Cu")
		(net "RST_RT_CPU1_P0_RESET_R_N")
	)
	(segment
		(start 190.53937 -385.178554)
		(end 183.549544 -392.16838)
		(width 0.11684)
		(layer "In2.Cu")
		(net "RST_RT_CPU1_P0_RESET_R_N")
	)
	(segment
		(start 176.19599 -398.472914)
		(end 176.19599 -407.884122)
		(width 0.11684)
		(layer "In2.Cu")
		(net "RST_RT_CPU1_P0_RESET_R_N")
	)
	(segment
		(start 97.475548 -397.11376)
		(end 96.98228 -396.620492)
		(width 0.11684)
		(layer "In2.Cu")
		(net "RST_RT_CPU1_P0_RESET_R_N")
	)
	(segment
		(start 168.884092 -409.838144)
		(end 166.248334 -407.202386)
		(width 0.11684)
		(layer "In2.Cu")
		(net "RST_RT_CPU1_P0_RESET_R_N")
	)
	(segment
		(start 183.549544 -392.16838)
		(end 182.500524 -392.16838)
		(width 0.11684)
		(layer "In2.Cu")
		(net "RST_RT_CPU1_P0_RESET_R_N")
	)
	(segment
		(start 166.248334 -407.202386)
		(end 166.248334 -403.638512)
		(width 0.11684)
		(layer "In2.Cu")
		(net "RST_RT_CPU1_P0_RESET_R_N")
	)
	(segment
		(start 119.97817 -401.18411)
		(end 112.048798 -401.18411)
		(width 0.11684)
		(layer "In2.Cu")
		(net "RST_RT_CPU1_P0_RESET_R_N")
	)
	(segment
		(start 42.065194 -389.4963)
		(end 40.386 -387.817106)
		(width 0.11684)
		(layer "In2.Cu")
		(net "RST_RT_CPU1_P0_RESET_R_N")
	)
	(segment
		(start 159.375856 -401.71751)
		(end 158.915608 -401.257262)
		(width 0.11684)
		(layer "In2.Cu")
		(net "RST_RT_CPU1_P0_RESET_R_N")
	)
	(segment
		(start 96.98228 -396.620492)
		(end 65.297558 -396.620492)
		(width 0.11684)
		(layer "In2.Cu")
		(net "RST_RT_CPU1_P0_RESET_R_N")
	)
	(segment
		(start 111.975646 -401.257262)
		(end 106.285792 -401.257262)
		(width 0.11684)
		(layer "In2.Cu")
		(net "RST_RT_CPU1_P0_RESET_R_N")
	)
	(segment
		(start 40.386 -387.817106)
		(end 40.386 -387.47192)
		(width 0.11684)
		(layer "In2.Cu")
		(net "RST_RT_CPU1_P0_RESET_R_N")
	)
	(segment
		(start 164.327332 -401.71751)
		(end 159.375856 -401.71751)
		(width 0.11684)
		(layer "In2.Cu")
		(net "RST_RT_CPU1_P0_RESET_R_N")
	)
	(segment
		(start 166.248334 -403.638512)
		(end 164.327332 -401.71751)
		(width 0.11684)
		(layer "In2.Cu")
		(net "RST_RT_CPU1_P0_RESET_R_N")
	)
	(segment
		(start 178.710336 -170.231816)
		(end 175.075596 -166.597076)
		(width 0.11684)
		(layer "In11.Cu")
		(net "RST_RT_CPU1_P0_RESET_R_N")
	)
	(segment
		(start 178.221386 -145.495264)
		(end 178.474878 -145.241772)
		(width 0.11684)
		(layer "In11.Cu")
		(net "RST_RT_CPU1_P0_RESET_R_N")
	)
	(segment
		(start 176.864264 -151.391874)
		(end 176.864264 -147.702016)
		(width 0.11684)
		(layer "In11.Cu")
		(net "RST_RT_CPU1_P0_RESET_R_N")
	)
	(segment
		(start 176.864264 -147.702016)
		(end 178.221386 -146.344894)
		(width 0.11684)
		(layer "In11.Cu")
		(net "RST_RT_CPU1_P0_RESET_R_N")
	)
	(segment
		(start 175.075596 -166.597076)
		(end 175.075596 -153.180542)
		(width 0.11684)
		(layer "In11.Cu")
		(net "RST_RT_CPU1_P0_RESET_R_N")
	)
	(segment
		(start 175.075596 -153.180542)
		(end 176.864264 -151.391874)
		(width 0.11684)
		(layer "In11.Cu")
		(net "RST_RT_CPU1_P0_RESET_R_N")
	)
	(segment
		(start 178.710336 -171.842176)
		(end 178.710336 -170.231816)
		(width 0.11684)
		(layer "In11.Cu")
		(net "RST_RT_CPU1_P0_RESET_R_N")
	)
	(segment
		(start 178.221386 -146.344894)
		(end 178.221386 -145.495264)
		(width 0.11684)
		(layer "In11.Cu")
		(net "RST_RT_CPU1_P0_RESET_R_N")
	)
	(segment
		(start 178.474878 -145.241772)
		(end 178.474878 -135.55853)
		(width 0.11684)
		(layer "In11.Cu")
		(net "RST_RT_CPU1_P0_RESET_R_N")
	)
	(segment
		(start 192.998598 -381.139446)
		(end 192.23101 -381.139446)
		(width 0.11684)
		(layer "In15.Cu")
		(net "RST_RT_CPU1_P0_RESET_R_N")
	)
	(segment
		(start 206.061056 -363.18825)
		(end 193.595752 -375.653554)
		(width 0.11684)
		(layer "In15.Cu")
		(net "RST_RT_CPU1_P0_RESET_R_N")
	)
	(segment
		(start 191.826642 -381.543814)
		(end 191.826642 -383.891282)
		(width 0.11684)
		(layer "In15.Cu")
		(net "RST_RT_CPU1_P0_RESET_R_N")
	)
	(segment
		(start 218.555062 -214.419434)
		(end 218.555062 -215.441784)
		(width 0.11684)
		(layer "In15.Cu")
		(net "RST_RT_CPU1_P0_RESET_R_N")
	)
	(segment
		(start 218.555062 -215.441784)
		(end 216.508076 -217.48877)
		(width 0.11684)
		(layer "In15.Cu")
		(net "RST_RT_CPU1_P0_RESET_R_N")
	)
	(segment
		(start 219.862654 -213.669626)
		(end 219.30487 -213.669626)
		(width 0.11684)
		(layer "In15.Cu")
		(net "RST_RT_CPU1_P0_RESET_R_N")
	)
	(segment
		(start 192.23101 -381.139446)
		(end 191.826642 -381.543814)
		(width 0.11684)
		(layer "In15.Cu")
		(net "RST_RT_CPU1_P0_RESET_R_N")
	)
	(segment
		(start 219.30487 -213.669626)
		(end 218.555062 -214.419434)
		(width 0.11684)
		(layer "In15.Cu")
		(net "RST_RT_CPU1_P0_RESET_R_N")
	)
	(segment
		(start 216.508076 -217.48877)
		(end 216.508076 -318.03213)
		(width 0.11684)
		(layer "In15.Cu")
		(net "RST_RT_CPU1_P0_RESET_R_N")
	)
	(segment
		(start 216.508076 -318.03213)
		(end 223.4819 -325.005954)
		(width 0.11684)
		(layer "In15.Cu")
		(net "RST_RT_CPU1_P0_RESET_R_N")
	)
	(segment
		(start 193.595752 -380.542292)
		(end 192.998598 -381.139446)
		(width 0.11684)
		(layer "In15.Cu")
		(net "RST_RT_CPU1_P0_RESET_R_N")
	)
	(segment
		(start 191.826642 -383.891282)
		(end 190.53937 -385.178554)
		(width 0.11684)
		(layer "In15.Cu")
		(net "RST_RT_CPU1_P0_RESET_R_N")
	)
	(segment
		(start 206.061056 -360.64444)
		(end 206.061056 -363.18825)
		(width 0.11684)
		(layer "In15.Cu")
		(net "RST_RT_CPU1_P0_RESET_R_N")
	)
	(segment
		(start 193.595752 -375.653554)
		(end 193.595752 -380.542292)
		(width 0.11684)
		(layer "In15.Cu")
		(net "RST_RT_CPU1_P0_RESET_R_N")
	)
	(segment
		(start 224.144332 -336.849212)
		(end 224.144332 -342.561164)
		(width 0.11684)
		(layer "In15.Cu")
		(net "RST_RT_CPU1_P0_RESET_R_N")
	)
	(segment
		(start 223.4819 -336.18678)
		(end 224.144332 -336.849212)
		(width 0.11684)
		(layer "In15.Cu")
		(net "RST_RT_CPU1_P0_RESET_R_N")
	)
	(segment
		(start 223.4819 -325.005954)
		(end 223.4819 -336.18678)
		(width 0.11684)
		(layer "In15.Cu")
		(net "RST_RT_CPU1_P0_RESET_R_N")
	)
	(segment
		(start 224.144332 -342.561164)
		(end 206.061056 -360.64444)
		(width 0.11684)
		(layer "In15.Cu")
		(net "RST_RT_CPU1_P0_RESET_R_N")
	)
	(segment
		(start 180.32222 -122.65279)
		(end 179.93233 -123.04268)
		(width 0.10668)
		(layer "F.Cu")
		(net "RST_RT_CPU1_P0_RESET_R2_N")
	)
	(via
		(at 179.93233 -123.04268)
		(size 0.4572)
		(drill 0.254)
		(layers "F.Cu" "B.Cu")
		(net "RST_RT_CPU1_P0_RESET_R2_N")
	)
	(segment
		(start 179.5526 -124.552456)
		(end 179.93233 -124.172726)
		(width 0.10668)
		(layer "B.Cu")
		(net "RST_RT_CPU1_P0_RESET_R2_N")
	)
	(segment
		(start 178.981608 -126.433326)
		(end 179.5526 -125.862334)
		(width 0.10668)
		(layer "B.Cu")
		(net "RST_RT_CPU1_P0_RESET_R2_N")
	)
	(segment
		(start 179.5526 -125.862334)
		(end 179.5526 -124.552456)
		(width 0.10668)
		(layer "B.Cu")
		(net "RST_RT_CPU1_P0_RESET_R2_N")
	)
	(segment
		(start 179.93233 -124.172726)
		(end 179.93233 -123.04268)
		(width 0.10668)
		(layer "B.Cu")
		(net "RST_RT_CPU1_P0_RESET_R2_N")
	)
	(segment
		(start 41.8211 -389.8392)
		(end 42.30497 -389.35533)
		(width 0.10668)
		(layer "F.Cu")
		(net "RST_RT_CPU1_P0_RESET_N")
	)
	(segment
		(start 42.947844 -388.921244)
		(end 42.6466 -388.62)
		(width 0.10668)
		(layer "F.Cu")
		(net "RST_RT_CPU1_P0_RESET_N")
	)
	(segment
		(start 46.101762 -388.730998)
		(end 44.676314 -388.730998)
		(width 0.10668)
		(layer "F.Cu")
		(net "RST_RT_CPU1_P0_RESET_N")
	)
	(segment
		(start 42.30497 -389.35533)
		(end 42.30497 -388.96163)
		(width 0.10668)
		(layer "F.Cu")
		(net "RST_RT_CPU1_P0_RESET_N")
	)
	(segment
		(start 44.676314 -388.730998)
		(end 44.486068 -388.921244)
		(width 0.10668)
		(layer "F.Cu")
		(net "RST_RT_CPU1_P0_RESET_N")
	)
	(segment
		(start 44.486068 -388.921244)
		(end 42.947844 -388.921244)
		(width 0.10668)
		(layer "F.Cu")
		(net "RST_RT_CPU1_P0_RESET_N")
	)
	(segment
		(start 42.30497 -388.96163)
		(end 42.6466 -388.62)
		(width 0.10668)
		(layer "F.Cu")
		(net "RST_RT_CPU1_P0_RESET_N")
	)
	(via
		(at 42.6466 -388.62)
		(size 0.762)
		(drill 0.381)
		(layers "F.Cu" "B.Cu")
		(net "RST_RT_CPU1_P0_RESET_N")
	)
	(segment
		(start 67.874388 -394.6271)
		(end 67.73418 -394.486892)
		(width 0.10668)
		(layer "F.Cu")
		(net "RST_RT_CPU1_P0_PERST_R_N")
	)
	(segment
		(start 178.198272 -131.0767)
		(end 177.917094 -131.357878)
		(width 0.10668)
		(layer "F.Cu")
		(net "RST_RT_CPU1_P0_PERST_R_N")
	)
	(segment
		(start 177.917094 -131.357878)
		(end 177.249582 -132.02539)
		(width 0.10668)
		(layer "F.Cu")
		(net "RST_RT_CPU1_P0_PERST_R_N")
	)
	(segment
		(start 178.985164 -129.766568)
		(end 178.67503 -129.766568)
		(width 0.10668)
		(layer "F.Cu")
		(net "RST_RT_CPU1_P0_PERST_R_N")
	)
	(segment
		(start 177.451512 -133.002274)
		(end 177.451512 -135.07847)
		(width 0.10668)
		(layer "F.Cu")
		(net "RST_RT_CPU1_P0_PERST_R_N")
	)
	(segment
		(start 178.67503 -129.766568)
		(end 178.198272 -130.243326)
		(width 0.10668)
		(layer "F.Cu")
		(net "RST_RT_CPU1_P0_PERST_R_N")
	)
	(segment
		(start 178.152044 -172.639482)
		(end 178.152044 -173.962568)
		(width 0.10668)
		(layer "F.Cu")
		(net "RST_RT_CPU1_P0_PERST_R_N")
	)
	(segment
		(start 183.848756 -179.65928)
		(end 183.848756 -187.142628)
		(width 0.10668)
		(layer "F.Cu")
		(net "RST_RT_CPU1_P0_PERST_R_N")
	)
	(segment
		(start 178.198272 -130.243326)
		(end 178.198272 -131.0767)
		(width 0.10668)
		(layer "F.Cu")
		(net "RST_RT_CPU1_P0_PERST_R_N")
	)
	(segment
		(start 177.249582 -132.02539)
		(end 177.249582 -132.800344)
		(width 0.10668)
		(layer "F.Cu")
		(net "RST_RT_CPU1_P0_PERST_R_N")
	)
	(segment
		(start 68.16852 -395.3637)
		(end 68.16852 -394.6271)
		(width 0.10668)
		(layer "F.Cu")
		(net "RST_RT_CPU1_P0_PERST_R_N")
	)
	(segment
		(start 67.73418 -394.486892)
		(end 67.73418 -392.873484)
		(width 0.10668)
		(layer "F.Cu")
		(net "RST_RT_CPU1_P0_PERST_R_N")
	)
	(segment
		(start 67.73418 -392.873484)
		(end 67.893438 -392.714226)
		(width 0.10668)
		(layer "F.Cu")
		(net "RST_RT_CPU1_P0_PERST_R_N")
	)
	(segment
		(start 177.451512 -135.07847)
		(end 176.994566 -135.535416)
		(width 0.10668)
		(layer "F.Cu")
		(net "RST_RT_CPU1_P0_PERST_R_N")
	)
	(segment
		(start 177.249582 -132.800344)
		(end 177.451512 -133.002274)
		(width 0.10668)
		(layer "F.Cu")
		(net "RST_RT_CPU1_P0_PERST_R_N")
	)
	(segment
		(start 178.152044 -173.962568)
		(end 183.848756 -179.65928)
		(width 0.10668)
		(layer "F.Cu")
		(net "RST_RT_CPU1_P0_PERST_R_N")
	)
	(segment
		(start 68.16852 -394.6271)
		(end 67.874388 -394.6271)
		(width 0.10668)
		(layer "F.Cu")
		(net "RST_RT_CPU1_P0_PERST_R_N")
	)
	(via
		(at 178.152044 -172.639482)
		(size 0.508)
		(drill 0.254)
		(layers "F.Cu" "B.Cu")
		(net "RST_RT_CPU1_P0_PERST_R_N")
	)
	(via
		(at 219.372434 -213.121748)
		(size 0.508)
		(drill 0.254)
		(layers "F.Cu" "B.Cu")
		(net "RST_RT_CPU1_P0_PERST_R_N")
	)
	(via
		(at 190.55207 -384.125978)
		(size 0.508)
		(drill 0.254)
		(layers "F.Cu" "B.Cu")
		(net "RST_RT_CPU1_P0_PERST_R_N")
	)
	(via
		(at 183.848756 -187.142628)
		(size 0.508)
		(drill 0.254)
		(layers "F.Cu" "B.Cu")
		(net "RST_RT_CPU1_P0_PERST_R_N")
	)
	(via
		(at 67.893438 -392.714226)
		(size 0.508)
		(drill 0.254)
		(layers "F.Cu" "B.Cu")
		(net "RST_RT_CPU1_P0_PERST_R_N")
	)
	(via
		(at 176.994566 -135.535416)
		(size 0.508)
		(drill 0.254)
		(layers "F.Cu" "B.Cu")
		(net "RST_RT_CPU1_P0_PERST_R_N")
	)
	(via
		(at 177.917094 -131.357878)
		(size 0.762)
		(drill 0.381)
		(layers "F.Cu" "B.Cu")
		(net "RST_RT_CPU1_P0_PERST_R_N")
	)
	(segment
		(start 217.829384 -211.578698)
		(end 217.829384 -190.155576)
		(width 0.10668)
		(layer "B.Cu")
		(net "RST_RT_CPU1_P0_PERST_R_N")
	)
	(segment
		(start 185.760868 -182.335424)
		(end 183.848756 -184.247536)
		(width 0.10668)
		(layer "B.Cu")
		(net "RST_RT_CPU1_P0_PERST_R_N")
	)
	(segment
		(start 210.009232 -182.335424)
		(end 185.760868 -182.335424)
		(width 0.10668)
		(layer "B.Cu")
		(net "RST_RT_CPU1_P0_PERST_R_N")
	)
	(segment
		(start 219.372434 -213.121748)
		(end 217.829384 -211.578698)
		(width 0.10668)
		(layer "B.Cu")
		(net "RST_RT_CPU1_P0_PERST_R_N")
	)
	(segment
		(start 183.848756 -184.247536)
		(end 183.848756 -187.142628)
		(width 0.10668)
		(layer "B.Cu")
		(net "RST_RT_CPU1_P0_PERST_R_N")
	)
	(segment
		(start 217.829384 -190.155576)
		(end 210.009232 -182.335424)
		(width 0.10668)
		(layer "B.Cu")
		(net "RST_RT_CPU1_P0_PERST_R_N")
	)
	(segment
		(start 120.248172 -400.808952)
		(end 159.112712 -400.808952)
		(width 0.11684)
		(layer "In2.Cu")
		(net "RST_RT_CPU1_P0_PERST_R_N")
	)
	(segment
		(start 175.77435 -398.268952)
		(end 176.412398 -397.630904)
		(width 0.11684)
		(layer "In2.Cu")
		(net "RST_RT_CPU1_P0_PERST_R_N")
	)
	(segment
		(start 164.500052 -401.293838)
		(end 166.669974 -403.46376)
		(width 0.11684)
		(layer "In2.Cu")
		(net "RST_RT_CPU1_P0_PERST_R_N")
	)
	(segment
		(start 173.806866 -409.327604)
		(end 175.77435 -407.36012)
		(width 0.11684)
		(layer "In2.Cu")
		(net "RST_RT_CPU1_P0_PERST_R_N")
	)
	(segment
		(start 111.457232 -399.97126)
		(end 112.303306 -399.97126)
		(width 0.11684)
		(layer "In2.Cu")
		(net "RST_RT_CPU1_P0_PERST_R_N")
	)
	(segment
		(start 106.433874 -400.808952)
		(end 110.61954 -400.808952)
		(width 0.11684)
		(layer "In2.Cu")
		(net "RST_RT_CPU1_P0_PERST_R_N")
	)
	(segment
		(start 97.198942 -396.096998)
		(end 97.48012 -395.81582)
		(width 0.11684)
		(layer "In2.Cu")
		(net "RST_RT_CPU1_P0_PERST_R_N")
	)
	(segment
		(start 166.669974 -406.970738)
		(end 169.02684 -409.327604)
		(width 0.11684)
		(layer "In2.Cu")
		(net "RST_RT_CPU1_P0_PERST_R_N")
	)
	(segment
		(start 187.75172 -384.125978)
		(end 190.55207 -384.125978)
		(width 0.11684)
		(layer "In2.Cu")
		(net "RST_RT_CPU1_P0_PERST_R_N")
	)
	(segment
		(start 67.893438 -393.967462)
		(end 70.022974 -396.096998)
		(width 0.11684)
		(layer "In2.Cu")
		(net "RST_RT_CPU1_P0_PERST_R_N")
	)
	(segment
		(start 113.054638 -400.722592)
		(end 120.161812 -400.722592)
		(width 0.11684)
		(layer "In2.Cu")
		(net "RST_RT_CPU1_P0_PERST_R_N")
	)
	(segment
		(start 99.459542 -395.81582)
		(end 102.095046 -398.451324)
		(width 0.11684)
		(layer "In2.Cu")
		(net "RST_RT_CPU1_P0_PERST_R_N")
	)
	(segment
		(start 102.095046 -398.451324)
		(end 104.076246 -398.451324)
		(width 0.11684)
		(layer "In2.Cu")
		(net "RST_RT_CPU1_P0_PERST_R_N")
	)
	(segment
		(start 176.412398 -395.4653)
		(end 187.75172 -384.125978)
		(width 0.11684)
		(layer "In2.Cu")
		(net "RST_RT_CPU1_P0_PERST_R_N")
	)
	(segment
		(start 159.597598 -401.293838)
		(end 164.500052 -401.293838)
		(width 0.11684)
		(layer "In2.Cu")
		(net "RST_RT_CPU1_P0_PERST_R_N")
	)
	(segment
		(start 97.48012 -395.81582)
		(end 99.459542 -395.81582)
		(width 0.11684)
		(layer "In2.Cu")
		(net "RST_RT_CPU1_P0_PERST_R_N")
	)
	(segment
		(start 169.02684 -409.327604)
		(end 173.806866 -409.327604)
		(width 0.11684)
		(layer "In2.Cu")
		(net "RST_RT_CPU1_P0_PERST_R_N")
	)
	(segment
		(start 159.112712 -400.808952)
		(end 159.597598 -401.293838)
		(width 0.11684)
		(layer "In2.Cu")
		(net "RST_RT_CPU1_P0_PERST_R_N")
	)
	(segment
		(start 112.303306 -399.97126)
		(end 113.054638 -400.722592)
		(width 0.11684)
		(layer "In2.Cu")
		(net "RST_RT_CPU1_P0_PERST_R_N")
	)
	(segment
		(start 110.61954 -400.808952)
		(end 111.457232 -399.97126)
		(width 0.11684)
		(layer "In2.Cu")
		(net "RST_RT_CPU1_P0_PERST_R_N")
	)
	(segment
		(start 67.893438 -392.714226)
		(end 67.893438 -393.967462)
		(width 0.11684)
		(layer "In2.Cu")
		(net "RST_RT_CPU1_P0_PERST_R_N")
	)
	(segment
		(start 120.161812 -400.722592)
		(end 120.248172 -400.808952)
		(width 0.11684)
		(layer "In2.Cu")
		(net "RST_RT_CPU1_P0_PERST_R_N")
	)
	(segment
		(start 175.77435 -407.36012)
		(end 175.77435 -398.268952)
		(width 0.11684)
		(layer "In2.Cu")
		(net "RST_RT_CPU1_P0_PERST_R_N")
	)
	(segment
		(start 104.076246 -398.451324)
		(end 106.433874 -400.808952)
		(width 0.11684)
		(layer "In2.Cu")
		(net "RST_RT_CPU1_P0_PERST_R_N")
	)
	(segment
		(start 166.669974 -403.46376)
		(end 166.669974 -406.970738)
		(width 0.11684)
		(layer "In2.Cu")
		(net "RST_RT_CPU1_P0_PERST_R_N")
	)
	(segment
		(start 176.412398 -397.630904)
		(end 176.412398 -395.4653)
		(width 0.11684)
		(layer "In2.Cu")
		(net "RST_RT_CPU1_P0_PERST_R_N")
	)
	(segment
		(start 70.022974 -396.096998)
		(end 97.198942 -396.096998)
		(width 0.11684)
		(layer "In2.Cu")
		(net "RST_RT_CPU1_P0_PERST_R_N")
	)
	(segment
		(start 177.53584 -136.07669)
		(end 176.994566 -135.535416)
		(width 0.11684)
		(layer "In11.Cu")
		(net "RST_RT_CPU1_P0_PERST_R_N")
	)
	(segment
		(start 178.152044 -172.639482)
		(end 178.152044 -170.283632)
		(width 0.11684)
		(layer "In11.Cu")
		(net "RST_RT_CPU1_P0_PERST_R_N")
	)
	(segment
		(start 178.152044 -170.283632)
		(end 174.644304 -166.775892)
		(width 0.11684)
		(layer "In11.Cu")
		(net "RST_RT_CPU1_P0_PERST_R_N")
	)
	(segment
		(start 177.358548 -145.393918)
		(end 177.358548 -137.872978)
		(width 0.11684)
		(layer "In11.Cu")
		(net "RST_RT_CPU1_P0_PERST_R_N")
	)
	(segment
		(start 174.644304 -166.775892)
		(end 174.644304 -153.001726)
		(width 0.11684)
		(layer "In11.Cu")
		(net "RST_RT_CPU1_P0_PERST_R_N")
	)
	(segment
		(start 177.00371 -146.852132)
		(end 177.00371 -145.748756)
		(width 0.11684)
		(layer "In11.Cu")
		(net "RST_RT_CPU1_P0_PERST_R_N")
	)
	(segment
		(start 176.432972 -147.42287)
		(end 177.00371 -146.852132)
		(width 0.11684)
		(layer "In11.Cu")
		(net "RST_RT_CPU1_P0_PERST_R_N")
	)
	(segment
		(start 176.432972 -151.213058)
		(end 176.432972 -147.42287)
		(width 0.11684)
		(layer "In11.Cu")
		(net "RST_RT_CPU1_P0_PERST_R_N")
	)
	(segment
		(start 177.00371 -145.748756)
		(end 177.358548 -145.393918)
		(width 0.11684)
		(layer "In11.Cu")
		(net "RST_RT_CPU1_P0_PERST_R_N")
	)
	(segment
		(start 174.644304 -153.001726)
		(end 176.432972 -151.213058)
		(width 0.11684)
		(layer "In11.Cu")
		(net "RST_RT_CPU1_P0_PERST_R_N")
	)
	(segment
		(start 177.53584 -137.695686)
		(end 177.53584 -136.07669)
		(width 0.11684)
		(layer "In11.Cu")
		(net "RST_RT_CPU1_P0_PERST_R_N")
	)
	(segment
		(start 177.358548 -137.872978)
		(end 177.53584 -137.695686)
		(width 0.11684)
		(layer "In11.Cu")
		(net "RST_RT_CPU1_P0_PERST_R_N")
	)
	(segment
		(start 205.51267 -362.810044)
		(end 193.174112 -375.148602)
		(width 0.11684)
		(layer "In15.Cu")
		(net "RST_RT_CPU1_P0_PERST_R_N")
	)
	(segment
		(start 193.174112 -379.794516)
		(end 192.777618 -380.19101)
		(width 0.11684)
		(layer "In15.Cu")
		(net "RST_RT_CPU1_P0_PERST_R_N")
	)
	(segment
		(start 192.777618 -380.19101)
		(end 192.038986 -380.19101)
		(width 0.11684)
		(layer "In15.Cu")
		(net "RST_RT_CPU1_P0_PERST_R_N")
	)
	(segment
		(start 216.085674 -318.20612)
		(end 222.530924 -324.65137)
		(width 0.11684)
		(layer "In15.Cu")
		(net "RST_RT_CPU1_P0_PERST_R_N")
	)
	(segment
		(start 191.399668 -383.27838)
		(end 190.55207 -384.125978)
		(width 0.11684)
		(layer "In15.Cu")
		(net "RST_RT_CPU1_P0_PERST_R_N")
	)
	(segment
		(start 223.390714 -336.691986)
		(end 223.390714 -342.700102)
		(width 0.11684)
		(layer "In15.Cu")
		(net "RST_RT_CPU1_P0_PERST_R_N")
	)
	(segment
		(start 192.038986 -380.19101)
		(end 191.399668 -380.830328)
		(width 0.11684)
		(layer "In15.Cu")
		(net "RST_RT_CPU1_P0_PERST_R_N")
	)
	(segment
		(start 223.390714 -342.700102)
		(end 205.51267 -360.578146)
		(width 0.11684)
		(layer "In15.Cu")
		(net "RST_RT_CPU1_P0_PERST_R_N")
	)
	(segment
		(start 191.399668 -380.830328)
		(end 191.399668 -383.27838)
		(width 0.11684)
		(layer "In15.Cu")
		(net "RST_RT_CPU1_P0_PERST_R_N")
	)
	(segment
		(start 218.026234 -214.082884)
		(end 218.026234 -215.226646)
		(width 0.11684)
		(layer "In15.Cu")
		(net "RST_RT_CPU1_P0_PERST_R_N")
	)
	(segment
		(start 219.372434 -213.121748)
		(end 218.98737 -213.121748)
		(width 0.11684)
		(layer "In15.Cu")
		(net "RST_RT_CPU1_P0_PERST_R_N")
	)
	(segment
		(start 222.530924 -324.65137)
		(end 222.530924 -335.832196)
		(width 0.11684)
		(layer "In15.Cu")
		(net "RST_RT_CPU1_P0_PERST_R_N")
	)
	(segment
		(start 218.98737 -213.121748)
		(end 218.026234 -214.082884)
		(width 0.11684)
		(layer "In15.Cu")
		(net "RST_RT_CPU1_P0_PERST_R_N")
	)
	(segment
		(start 216.085674 -217.167206)
		(end 216.085674 -318.20612)
		(width 0.11684)
		(layer "In15.Cu")
		(net "RST_RT_CPU1_P0_PERST_R_N")
	)
	(segment
		(start 218.026234 -215.226646)
		(end 216.085674 -217.167206)
		(width 0.11684)
		(layer "In15.Cu")
		(net "RST_RT_CPU1_P0_PERST_R_N")
	)
	(segment
		(start 222.530924 -335.832196)
		(end 223.390714 -336.691986)
		(width 0.11684)
		(layer "In15.Cu")
		(net "RST_RT_CPU1_P0_PERST_R_N")
	)
	(segment
		(start 205.51267 -360.578146)
		(end 205.51267 -362.810044)
		(width 0.11684)
		(layer "In15.Cu")
		(net "RST_RT_CPU1_P0_PERST_R_N")
	)
	(segment
		(start 193.174112 -375.148602)
		(end 193.174112 -379.794516)
		(width 0.11684)
		(layer "In15.Cu")
		(net "RST_RT_CPU1_P0_PERST_R_N")
	)
	(segment
		(start 180.32222 -123.45289)
		(end 180.32222 -123.897898)
		(width 0.10668)
		(layer "F.Cu")
		(net "RST_RT_CPU1_P0_PERST_R2_N")
	)
	(segment
		(start 179.59832 -124.621798)
		(end 179.59832 -126.76124)
		(width 0.10668)
		(layer "F.Cu")
		(net "RST_RT_CPU1_P0_PERST_R2_N")
	)
	(segment
		(start 178.985164 -127.374396)
		(end 179.334414 -127.025146)
		(width 0.10668)
		(layer "F.Cu")
		(net "RST_RT_CPU1_P0_PERST_R2_N")
	)
	(segment
		(start 178.985164 -128.966468)
		(end 178.985164 -127.374396)
		(width 0.10668)
		(layer "F.Cu")
		(net "RST_RT_CPU1_P0_PERST_R2_N")
	)
	(segment
		(start 180.32222 -123.897898)
		(end 179.59832 -124.621798)
		(width 0.10668)
		(layer "F.Cu")
		(net "RST_RT_CPU1_P0_PERST_R2_N")
	)
	(segment
		(start 179.59832 -126.76124)
		(end 179.334414 -127.025146)
		(width 0.10668)
		(layer "F.Cu")
		(net "RST_RT_CPU1_P0_PERST_R2_N")
	)
	(via
		(at 179.334414 -127.025146)
		(size 0.762)
		(drill 0.381)
		(layers "F.Cu" "B.Cu")
		(net "RST_RT_CPU1_P0_PERST_R2_N")
	)
	(segment
		(start 67.834256 -396.62608)
		(end 67.212718 -396.62608)
		(width 0.10668)
		(layer "F.Cu")
		(net "RST_RT_CPU1_P0_PERST_N")
	)
	(segment
		(start 67.3735 -395.64564)
		(end 67.3735 -392.599672)
		(width 0.10668)
		(layer "F.Cu")
		(net "RST_RT_CPU1_P0_PERST_N")
	)
	(segment
		(start 68.16852 -395.8971)
		(end 68.16852 -396.291816)
		(width 0.10668)
		(layer "F.Cu")
		(net "RST_RT_CPU1_P0_PERST_N")
	)
	(segment
		(start 66.618104 -391.844276)
		(end 66.618104 -390.761474)
		(width 0.10668)
		(layer "F.Cu")
		(net "RST_RT_CPU1_P0_PERST_N")
	)
	(segment
		(start 67.62496 -395.8971)
		(end 67.3735 -395.64564)
		(width 0.10668)
		(layer "F.Cu")
		(net "RST_RT_CPU1_P0_PERST_N")
	)
	(segment
		(start 67.3735 -392.599672)
		(end 66.618104 -391.844276)
		(width 0.10668)
		(layer "F.Cu")
		(net "RST_RT_CPU1_P0_PERST_N")
	)
	(segment
		(start 68.16852 -396.291816)
		(end 67.834256 -396.62608)
		(width 0.10668)
		(layer "F.Cu")
		(net "RST_RT_CPU1_P0_PERST_N")
	)
	(segment
		(start 68.16852 -395.8971)
		(end 67.62496 -395.8971)
		(width 0.10668)
		(layer "F.Cu")
		(net "RST_RT_CPU1_P0_PERST_N")
	)
	(via
		(at 67.212718 -396.62608)
		(size 0.762)
		(drill 0.381)
		(layers "F.Cu" "B.Cu")
		(net "RST_RT_CPU1_P0_PERST_N")
	)
	(segment
		(start 161.810954 -424.594528)
		(end 162.605212 -423.80027)
		(width 0.508)
		(layer "F.Cu")
		(net "P1V8_CPU1_RT_1D")
	)
	(segment
		(start 111.854996 -398.729962)
		(end 111.854996 -398.42821)
		(width 0.3048)
		(layer "F.Cu")
		(net "P1V8_CPU1_RT_1D")
	)
	(segment
		(start 221.513654 -315.014356)
		(end 221.513654 -296.584116)
		(width 0.508)
		(layer "F.Cu")
		(net "P1V8_CPU1_RT_1D")
	)
	(segment
		(start 105.008426 -396.6845)
		(end 105.207308 -396.485618)
		(width 0.3048)
		(layer "F.Cu")
		(net "P1V8_CPU1_RT_1D")
	)
	(segment
		(start 110.911132 -397.062452)
		(end 110.911132 -397.232378)
		(width 0.254)
		(layer "F.Cu")
		(net "P1V8_CPU1_RT_1D")
	)
	(segment
		(start 116.158518 -395.607286)
		(end 115.619784 -396.14602)
		(width 0.3048)
		(layer "F.Cu")
		(net "P1V8_CPU1_RT_1D")
	)
	(segment
		(start 113.34496 -395.708632)
		(end 112.53216 -395.708632)
		(width 0.3048)
		(layer "F.Cu")
		(net "P1V8_CPU1_RT_1D")
	)
	(segment
		(start 142.33652 -389.344154)
		(end 142.33652 -389.067294)
		(width 0.254)
		(layer "F.Cu")
		(net "P1V8_CPU1_RT_1D")
	)
	(segment
		(start 161.262568 -425.857924)
		(end 161.810954 -425.309538)
		(width 0.508)
		(layer "F.Cu")
		(net "P1V8_CPU1_RT_1D")
	)
	(segment
		(start 117.8433 -401.26285)
		(end 117.40261 -401.70354)
		(width 0.254)
		(layer "F.Cu")
		(net "P1V8_CPU1_RT_1D")
	)
	(segment
		(start 75.236578 -389.067294)
		(end 74.940668 -388.771384)
		(width 0.254)
		(layer "F.Cu")
		(net "P1V8_CPU1_RT_1D")
	)
	(segment
		(start 159.192976 -424.508676)
		(end 160.542224 -425.857924)
		(width 0.508)
		(layer "F.Cu")
		(net "P1V8_CPU1_RT_1D")
	)
	(segment
		(start 115.619784 -396.14602)
		(end 113.782348 -396.14602)
		(width 0.3048)
		(layer "F.Cu")
		(net "P1V8_CPU1_RT_1D")
	)
	(segment
		(start 103.145844 -394.106908)
		(end 103.145844 -394.42136)
		(width 0.381)
		(layer "F.Cu")
		(net "P1V8_CPU1_RT_1D")
	)
	(segment
		(start 162.605212 -423.80027)
		(end 163.340796 -423.80027)
		(width 0.508)
		(layer "F.Cu")
		(net "P1V8_CPU1_RT_1D")
	)
	(segment
		(start 169.963592 -416.662616)
		(end 170.090592 -416.789616)
		(width 0.3048)
		(layer "F.Cu")
		(net "P1V8_CPU1_RT_1D")
	)
	(segment
		(start 221.513654 -296.584116)
		(end 225.758502 -292.339268)
		(width 0.508)
		(layer "F.Cu")
		(net "P1V8_CPU1_RT_1D")
	)
	(segment
		(start 107.169458 -395.502384)
		(end 107.008676 -395.663166)
		(width 0.254)
		(layer "F.Cu")
		(net "P1V8_CPU1_RT_1D")
	)
	(segment
		(start 102.954074 -393.427712)
		(end 102.954074 -393.915138)
		(width 0.381)
		(layer "F.Cu")
		(net "P1V8_CPU1_RT_1D")
	)
	(segment
		(start 109.772704 -395.515338)
		(end 110.393226 -396.13586)
		(width 0.254)
		(layer "F.Cu")
		(net "P1V8_CPU1_RT_1D")
	)
	(segment
		(start 105.008426 -397.13408)
		(end 105.008426 -396.6845)
		(width 0.3048)
		(layer "F.Cu")
		(net "P1V8_CPU1_RT_1D")
	)
	(segment
		(start 102.954074 -393.915138)
		(end 103.145844 -394.106908)
		(width 0.381)
		(layer "F.Cu")
		(net "P1V8_CPU1_RT_1D")
	)
	(segment
		(start 94.4499 -401.9804)
		(end 95.105728 -401.9804)
		(width 0.254)
		(layer "F.Cu")
		(net "P1V8_CPU1_RT_1D")
	)
	(segment
		(start 113.782348 -396.14602)
		(end 113.34496 -395.708632)
		(width 0.3048)
		(layer "F.Cu")
		(net "P1V8_CPU1_RT_1D")
	)
	(segment
		(start 102.357682 -394.431266)
		(end 103.135938 -394.431266)
		(width 0.381)
		(layer "F.Cu")
		(net "P1V8_CPU1_RT_1D")
	)
	(segment
		(start 170.090592 -416.789616)
		(end 170.090592 -416.792918)
		(width 0.3048)
		(layer "F.Cu")
		(net "P1V8_CPU1_RT_1D")
	)
	(segment
		(start 169.349166 -416.662616)
		(end 169.963592 -416.662616)
		(width 0.3048)
		(layer "F.Cu")
		(net "P1V8_CPU1_RT_1D")
	)
	(segment
		(start 103.9241 -390.306052)
		(end 104.167432 -390.06272)
		(width 0.254)
		(layer "F.Cu")
		(net "P1V8_CPU1_RT_1D")
	)
	(segment
		(start 161.810954 -425.309538)
		(end 161.810954 -424.594528)
		(width 0.508)
		(layer "F.Cu")
		(net "P1V8_CPU1_RT_1D")
	)
	(segment
		(start 160.542224 -425.857924)
		(end 161.262568 -425.857924)
		(width 0.508)
		(layer "F.Cu")
		(net "P1V8_CPU1_RT_1D")
	)
	(segment
		(start 133.653022 -395.8971)
		(end 133.005322 -396.5448)
		(width 0.3048)
		(layer "F.Cu")
		(net "P1V8_CPU1_RT_1D")
	)
	(segment
		(start 75.236578 -389.344154)
		(end 75.236578 -389.067294)
		(width 0.254)
		(layer "F.Cu")
		(net "P1V8_CPU1_RT_1D")
	)
	(segment
		(start 112.53216 -395.708632)
		(end 112.036352 -395.708632)
		(width 0.3048)
		(layer "F.Cu")
		(net "P1V8_CPU1_RT_1D")
	)
	(segment
		(start 225.758502 -290.882832)
		(end 225.899472 -290.741862)
		(width 0.508)
		(layer "F.Cu")
		(net "P1V8_CPU1_RT_1D")
	)
	(segment
		(start 121.612406 -395.607286)
		(end 116.158518 -395.607286)
		(width 0.3048)
		(layer "F.Cu")
		(net "P1V8_CPU1_RT_1D")
	)
	(segment
		(start 103.135938 -394.431266)
		(end 103.145844 -394.42136)
		(width 0.381)
		(layer "F.Cu")
		(net "P1V8_CPU1_RT_1D")
	)
	(segment
		(start 117.8433 -400.3548)
		(end 117.8433 -401.1676)
		(width 0.254)
		(layer "F.Cu")
		(net "P1V8_CPU1_RT_1D")
	)
	(segment
		(start 103.9241 -390.652)
		(end 103.9241 -390.306052)
		(width 0.254)
		(layer "F.Cu")
		(net "P1V8_CPU1_RT_1D")
	)
	(segment
		(start 168.513506 -416.662616)
		(end 169.349166 -416.662616)
		(width 0.3048)
		(layer "F.Cu")
		(net "P1V8_CPU1_RT_1D")
	)
	(segment
		(start 109.210602 -395.515338)
		(end 108.432854 -395.515338)
		(width 0.254)
		(layer "F.Cu")
		(net "P1V8_CPU1_RT_1D")
	)
	(segment
		(start 66.42862 -393.7762)
		(end 66.42862 -394.51788)
		(width 0.254)
		(layer "F.Cu")
		(net "P1V8_CPU1_RT_1D")
	)
	(segment
		(start 110.393226 -396.13586)
		(end 110.393226 -396.544546)
		(width 0.254)
		(layer "F.Cu")
		(net "P1V8_CPU1_RT_1D")
	)
	(segment
		(start 110.393226 -396.544546)
		(end 110.911132 -397.062452)
		(width 0.254)
		(layer "F.Cu")
		(net "P1V8_CPU1_RT_1D")
	)
	(segment
		(start 155.942792 -419.164516)
		(end 159.192976 -422.4147)
		(width 0.508)
		(layer "F.Cu")
		(net "P1V8_CPU1_RT_1D")
	)
	(segment
		(start 105.506266 -398.729962)
		(end 105.506266 -397.63192)
		(width 0.3048)
		(layer "F.Cu")
		(net "P1V8_CPU1_RT_1D")
	)
	(segment
		(start 165.5699 -419.7096)
		(end 165.5699 -420.32301)
		(width 0.3048)
		(layer "F.Cu")
		(net "P1V8_CPU1_RT_1D")
	)
	(segment
		(start 133.005322 -396.5448)
		(end 122.54992 -396.5448)
		(width 0.3048)
		(layer "F.Cu")
		(net "P1V8_CPU1_RT_1D")
	)
	(segment
		(start 110.911132 -397.484346)
		(end 110.911132 -397.232378)
		(width 0.3048)
		(layer "F.Cu")
		(net "P1V8_CPU1_RT_1D")
	)
	(segment
		(start 166.188136 -420.941246)
		(end 166.188136 -421.216582)
		(width 0.3048)
		(layer "F.Cu")
		(net "P1V8_CPU1_RT_1D")
	)
	(segment
		(start 166.296848 -420.068502)
		(end 165.937946 -419.7096)
		(width 0.3048)
		(layer "F.Cu")
		(net "P1V8_CPU1_RT_1D")
	)
	(segment
		(start 94.4499 -401.1676)
		(end 94.4499 -401.9804)
		(width 0.254)
		(layer "F.Cu")
		(net "P1V8_CPU1_RT_1D")
	)
	(segment
		(start 105.207308 -396.485618)
		(end 105.207308 -396.086584)
		(width 0.3048)
		(layer "F.Cu")
		(net "P1V8_CPU1_RT_1D")
	)
	(segment
		(start 226.915472 -290.741862)
		(end 225.899472 -290.741862)
		(width 0.508)
		(layer "F.Cu")
		(net "P1V8_CPU1_RT_1D")
	)
	(segment
		(start 225.758502 -292.339268)
		(end 225.758502 -290.882832)
		(width 0.508)
		(layer "F.Cu")
		(net "P1V8_CPU1_RT_1D")
	)
	(segment
		(start 165.5699 -420.32301)
		(end 166.188136 -420.941246)
		(width 0.3048)
		(layer "F.Cu")
		(net "P1V8_CPU1_RT_1D")
	)
	(segment
		(start 222.054928 -315.55563)
		(end 221.513654 -315.014356)
		(width 0.508)
		(layer "F.Cu")
		(net "P1V8_CPU1_RT_1D")
	)
	(segment
		(start 222.738442 -315.55563)
		(end 222.054928 -315.55563)
		(width 0.508)
		(layer "F.Cu")
		(net "P1V8_CPU1_RT_1D")
	)
	(segment
		(start 122.54992 -396.5448)
		(end 121.612406 -395.607286)
		(width 0.3048)
		(layer "F.Cu")
		(net "P1V8_CPU1_RT_1D")
	)
	(segment
		(start 155.942792 -416.9664)
		(end 155.942792 -419.164516)
		(width 0.508)
		(layer "F.Cu")
		(net "P1V8_CPU1_RT_1D")
	)
	(segment
		(start 142.33652 -389.067294)
		(end 142.04061 -388.771384)
		(width 0.254)
		(layer "F.Cu")
		(net "P1V8_CPU1_RT_1D")
	)
	(segment
		(start 105.506266 -397.63192)
		(end 105.008426 -397.13408)
		(width 0.3048)
		(layer "F.Cu")
		(net "P1V8_CPU1_RT_1D")
	)
	(segment
		(start 159.192976 -422.4147)
		(end 159.192976 -424.508676)
		(width 0.508)
		(layer "F.Cu")
		(net "P1V8_CPU1_RT_1D")
	)
	(segment
		(start 111.22914 -394.90142)
		(end 111.22914 -394.69314)
		(width 0.3048)
		(layer "F.Cu")
		(net "P1V8_CPU1_RT_1D")
	)
	(segment
		(start 111.854996 -398.42821)
		(end 110.911132 -397.484346)
		(width 0.3048)
		(layer "F.Cu")
		(net "P1V8_CPU1_RT_1D")
	)
	(segment
		(start 109.210602 -395.515338)
		(end 109.772704 -395.515338)
		(width 0.254)
		(layer "F.Cu")
		(net "P1V8_CPU1_RT_1D")
	)
	(segment
		(start 108.432854 -395.515338)
		(end 108.4199 -395.502384)
		(width 0.254)
		(layer "F.Cu")
		(net "P1V8_CPU1_RT_1D")
	)
	(segment
		(start 165.937946 -419.7096)
		(end 165.5699 -419.7096)
		(width 0.3048)
		(layer "F.Cu")
		(net "P1V8_CPU1_RT_1D")
	)
	(segment
		(start 117.8433 -401.1676)
		(end 117.8433 -401.26285)
		(width 0.254)
		(layer "F.Cu")
		(net "P1V8_CPU1_RT_1D")
	)
	(segment
		(start 108.4199 -395.502384)
		(end 107.169458 -395.502384)
		(width 0.254)
		(layer "F.Cu")
		(net "P1V8_CPU1_RT_1D")
	)
	(segment
		(start 112.036352 -395.708632)
		(end 111.22914 -394.90142)
		(width 0.3048)
		(layer "F.Cu")
		(net "P1V8_CPU1_RT_1D")
	)
	(via
		(at 182.208932 -375.167652)
		(size 0.508)
		(drill 0.254)
		(layers "F.Cu" "B.Cu")
		(net "P1V8_CPU1_RT_1D")
	)
	(via
		(at 240.7031 -340.741)
		(size 0.508)
		(drill 0.254)
		(layers "F.Cu" "B.Cu")
		(net "P1V8_CPU1_RT_1D")
	)
	(via
		(at 138.092688 -386.04063)
		(size 0.508)
		(drill 0.254)
		(layers "F.Cu" "B.Cu")
		(net "P1V8_CPU1_RT_1D")
	)
	(via
		(at 181.134004 -373.332756)
		(size 0.508)
		(drill 0.254)
		(layers "F.Cu" "B.Cu")
		(net "P1V8_CPU1_RT_1D")
	)
	(via
		(at 240.7031 -341.884)
		(size 0.508)
		(drill 0.254)
		(layers "F.Cu" "B.Cu")
		(net "P1V8_CPU1_RT_1D")
	)
	(via
		(at 222.734378 -313.838844)
		(size 0.508)
		(drill 0.254)
		(layers "F.Cu" "B.Cu")
		(net "P1V8_CPU1_RT_1D")
	)
	(via
		(at 216.613994 -333.6163)
		(size 0.508)
		(drill 0.254)
		(layers "F.Cu" "B.Cu")
		(net "P1V8_CPU1_RT_1D")
	)
	(via
		(at 232.423462 -311.28208)
		(size 0.508)
		(drill 0.254)
		(layers "F.Cu" "B.Cu")
		(net "P1V8_CPU1_RT_1D")
	)
	(via
		(at 233.707178 -313.92368)
		(size 0.508)
		(drill 0.254)
		(layers "F.Cu" "B.Cu")
		(net "P1V8_CPU1_RT_1D")
	)
	(via
		(at 139.242038 -384.718814)
		(size 0.508)
		(drill 0.254)
		(layers "F.Cu" "B.Cu")
		(net "P1V8_CPU1_RT_1D")
	)
	(via
		(at 216.60612 -339.94471)
		(size 0.508)
		(drill 0.254)
		(layers "F.Cu" "B.Cu")
		(net "P1V8_CPU1_RT_1D")
	)
	(via
		(at 173.889162 -382.994154)
		(size 0.508)
		(drill 0.254)
		(layers "F.Cu" "B.Cu")
		(net "P1V8_CPU1_RT_1D")
	)
	(via
		(at 182.745634 -372.725188)
		(size 0.508)
		(drill 0.254)
		(layers "F.Cu" "B.Cu")
		(net "P1V8_CPU1_RT_1D")
	)
	(via
		(at 227.831396 -313.910726)
		(size 0.508)
		(drill 0.254)
		(layers "F.Cu" "B.Cu")
		(net "P1V8_CPU1_RT_1D")
	)
	(via
		(at 168.73601 -420.238936)
		(size 0.508)
		(drill 0.254)
		(layers "F.Cu" "B.Cu")
		(net "P1V8_CPU1_RT_1D")
	)
	(via
		(at 227.814378 -314.68568)
		(size 0.508)
		(drill 0.254)
		(layers "F.Cu" "B.Cu")
		(net "P1V8_CPU1_RT_1D")
	)
	(via
		(at 223.978978 -314.68568)
		(size 0.508)
		(drill 0.254)
		(layers "F.Cu" "B.Cu")
		(net "P1V8_CPU1_RT_1D")
	)
	(via
		(at 239.022382 -325.65721)
		(size 0.508)
		(drill 0.254)
		(layers "F.Cu" "B.Cu")
		(net "P1V8_CPU1_RT_1D")
	)
	(via
		(at 40.941752 -383.7432)
		(size 0.508)
		(drill 0.254)
		(layers "F.Cu" "B.Cu")
		(net "P1V8_CPU1_RT_1D")
	)
	(via
		(at 104.669844 -384.702304)
		(size 0.508)
		(drill 0.254)
		(layers "F.Cu" "B.Cu")
		(net "P1V8_CPU1_RT_1D")
	)
	(via
		(at 155.942792 -416.9664)
		(size 0.508)
		(drill 0.254)
		(layers "F.Cu" "B.Cu")
		(net "P1V8_CPU1_RT_1D")
	)
	(via
		(at 172.179234 -385.973066)
		(size 0.508)
		(drill 0.254)
		(layers "F.Cu" "B.Cu")
		(net "P1V8_CPU1_RT_1D")
	)
	(via
		(at 96.8629 -417.2966)
		(size 0.508)
		(drill 0.254)
		(layers "F.Cu" "B.Cu")
		(net "P1V8_CPU1_RT_1D")
	)
	(via
		(at 172.241718 -422.347898)
		(size 0.508)
		(drill 0.254)
		(layers "F.Cu" "B.Cu")
		(net "P1V8_CPU1_RT_1D")
	)
	(via
		(at 102.954074 -393.427712)
		(size 0.508)
		(drill 0.254)
		(layers "F.Cu" "B.Cu")
		(net "P1V8_CPU1_RT_1D")
	)
	(via
		(at 217.551 -337.947)
		(size 0.508)
		(drill 0.254)
		(layers "F.Cu" "B.Cu")
		(net "P1V8_CPU1_RT_1D")
	)
	(via
		(at 172.179234 -387.243066)
		(size 0.508)
		(drill 0.254)
		(layers "F.Cu" "B.Cu")
		(net "P1V8_CPU1_RT_1D")
	)
	(via
		(at 176.844198 -383.069846)
		(size 0.508)
		(drill 0.254)
		(layers "F.Cu" "B.Cu")
		(net "P1V8_CPU1_RT_1D")
	)
	(via
		(at 217.551 -342.519)
		(size 0.508)
		(drill 0.254)
		(layers "F.Cu" "B.Cu")
		(net "P1V8_CPU1_RT_1D")
	)
	(via
		(at 183.115204 -373.332756)
		(size 0.508)
		(drill 0.254)
		(layers "F.Cu" "B.Cu")
		(net "P1V8_CPU1_RT_1D")
	)
	(via
		(at 71.062596 -385.09448)
		(size 0.508)
		(drill 0.254)
		(layers "F.Cu" "B.Cu")
		(net "P1V8_CPU1_RT_1D")
	)
	(via
		(at 232.423462 -310.52008)
		(size 0.508)
		(drill 0.254)
		(layers "F.Cu" "B.Cu")
		(net "P1V8_CPU1_RT_1D")
	)
	(via
		(at 163.340796 -423.80027)
		(size 0.508)
		(drill 0.254)
		(layers "F.Cu" "B.Cu")
		(net "P1V8_CPU1_RT_1D")
	)
	(via
		(at 176.86782 -385.212336)
		(size 0.508)
		(drill 0.254)
		(layers "F.Cu" "B.Cu")
		(net "P1V8_CPU1_RT_1D")
	)
	(via
		(at 173.877478 -383.71399)
		(size 0.508)
		(drill 0.254)
		(layers "F.Cu" "B.Cu")
		(net "P1V8_CPU1_RT_1D")
	)
	(via
		(at 225.614738 -310.52008)
		(size 0.508)
		(drill 0.254)
		(layers "F.Cu" "B.Cu")
		(net "P1V8_CPU1_RT_1D")
	)
	(via
		(at 229.871778 -314.68568)
		(size 0.508)
		(drill 0.254)
		(layers "F.Cu" "B.Cu")
		(net "P1V8_CPU1_RT_1D")
	)
	(via
		(at 71.062596 -384.10388)
		(size 0.508)
		(drill 0.254)
		(layers "F.Cu" "B.Cu")
		(net "P1V8_CPU1_RT_1D")
	)
	(via
		(at 104.669844 -384.067304)
		(size 0.508)
		(drill 0.254)
		(layers "F.Cu" "B.Cu")
		(net "P1V8_CPU1_RT_1D")
	)
	(via
		(at 45.128688 -421.014652)
		(size 0.508)
		(drill 0.254)
		(layers "F.Cu" "B.Cu")
		(net "P1V8_CPU1_RT_1D")
	)
	(via
		(at 222.734378 -312.314844)
		(size 0.508)
		(drill 0.254)
		(layers "F.Cu" "B.Cu")
		(net "P1V8_CPU1_RT_1D")
	)
	(via
		(at 175.46828 -383.73177)
		(size 0.508)
		(drill 0.254)
		(layers "F.Cu" "B.Cu")
		(net "P1V8_CPU1_RT_1D")
	)
	(via
		(at 176.157128 -383.73177)
		(size 0.508)
		(drill 0.254)
		(layers "F.Cu" "B.Cu")
		(net "P1V8_CPU1_RT_1D")
	)
	(via
		(at 111.22914 -394.69314)
		(size 0.508)
		(drill 0.254)
		(layers "F.Cu" "B.Cu")
		(net "P1V8_CPU1_RT_1D")
	)
	(via
		(at 216.6874 -338.248752)
		(size 0.508)
		(drill 0.254)
		(layers "F.Cu" "B.Cu")
		(net "P1V8_CPU1_RT_1D")
	)
	(via
		(at 172.298106 -383.78384)
		(size 0.508)
		(drill 0.254)
		(layers "F.Cu" "B.Cu")
		(net "P1V8_CPU1_RT_1D")
	)
	(via
		(at 117.40261 -401.70354)
		(size 0.508)
		(drill 0.254)
		(layers "F.Cu" "B.Cu")
		(net "P1V8_CPU1_RT_1D")
	)
	(via
		(at 165.118796 -423.80027)
		(size 0.508)
		(drill 0.254)
		(layers "F.Cu" "B.Cu")
		(net "P1V8_CPU1_RT_1D")
	)
	(via
		(at 225.223578 -312.39968)
		(size 0.508)
		(drill 0.254)
		(layers "F.Cu" "B.Cu")
		(net "P1V8_CPU1_RT_1D")
	)
	(via
		(at 176.18837 -384.509772)
		(size 0.508)
		(drill 0.254)
		(layers "F.Cu" "B.Cu")
		(net "P1V8_CPU1_RT_1D")
	)
	(via
		(at 66.42862 -393.7762)
		(size 0.508)
		(drill 0.254)
		(layers "F.Cu" "B.Cu")
		(net "P1V8_CPU1_RT_1D")
	)
	(via
		(at 177.558446 -383.766568)
		(size 0.508)
		(drill 0.254)
		(layers "F.Cu" "B.Cu")
		(net "P1V8_CPU1_RT_1D")
	)
	(via
		(at 170.986196 -385.014724)
		(size 0.508)
		(drill 0.254)
		(layers "F.Cu" "B.Cu")
		(net "P1V8_CPU1_RT_1D")
	)
	(via
		(at 240.7031 -335.026)
		(size 0.508)
		(drill 0.254)
		(layers "F.Cu" "B.Cu")
		(net "P1V8_CPU1_RT_1D")
	)
	(via
		(at 138.162538 -384.10388)
		(size 0.508)
		(drill 0.254)
		(layers "F.Cu" "B.Cu")
		(net "P1V8_CPU1_RT_1D")
	)
	(via
		(at 233.707178 -313.16168)
		(size 0.508)
		(drill 0.254)
		(layers "F.Cu" "B.Cu")
		(net "P1V8_CPU1_RT_1D")
	)
	(via
		(at 233.707178 -312.39968)
		(size 0.508)
		(drill 0.254)
		(layers "F.Cu" "B.Cu")
		(net "P1V8_CPU1_RT_1D")
	)
	(via
		(at 240.7031 -339.598)
		(size 0.508)
		(drill 0.254)
		(layers "F.Cu" "B.Cu")
		(net "P1V8_CPU1_RT_1D")
	)
	(via
		(at 172.179234 -386.608066)
		(size 0.508)
		(drill 0.254)
		(layers "F.Cu" "B.Cu")
		(net "P1V8_CPU1_RT_1D")
	)
	(via
		(at 181.794404 -373.332756)
		(size 0.508)
		(drill 0.254)
		(layers "F.Cu" "B.Cu")
		(net "P1V8_CPU1_RT_1D")
	)
	(via
		(at 227.831396 -313.148726)
		(size 0.508)
		(drill 0.254)
		(layers "F.Cu" "B.Cu")
		(net "P1V8_CPU1_RT_1D")
	)
	(via
		(at 231.319578 -312.39968)
		(size 0.508)
		(drill 0.254)
		(layers "F.Cu" "B.Cu")
		(net "P1V8_CPU1_RT_1D")
	)
	(via
		(at 217.551 -340.233)
		(size 0.508)
		(drill 0.254)
		(layers "F.Cu" "B.Cu")
		(net "P1V8_CPU1_RT_1D")
	)
	(via
		(at 175.450754 -384.4925)
		(size 0.508)
		(drill 0.254)
		(layers "F.Cu" "B.Cu")
		(net "P1V8_CPU1_RT_1D")
	)
	(via
		(at 229.872032 -312.40476)
		(size 0.508)
		(drill 0.254)
		(layers "F.Cu" "B.Cu")
		(net "P1V8_CPU1_RT_1D")
	)
	(via
		(at 231.661462 -310.52008)
		(size 0.508)
		(drill 0.254)
		(layers "F.Cu" "B.Cu")
		(net "P1V8_CPU1_RT_1D")
	)
	(via
		(at 222.734378 -313.076844)
		(size 0.508)
		(drill 0.254)
		(layers "F.Cu" "B.Cu")
		(net "P1V8_CPU1_RT_1D")
	)
	(via
		(at 71.777352 -383.405126)
		(size 0.508)
		(drill 0.254)
		(layers "F.Cu" "B.Cu")
		(net "P1V8_CPU1_RT_1D")
	)
	(via
		(at 103.590344 -384.10388)
		(size 0.508)
		(drill 0.254)
		(layers "F.Cu" "B.Cu")
		(net "P1V8_CPU1_RT_1D")
	)
	(via
		(at 74.940668 -388.771384)
		(size 0.508)
		(drill 0.254)
		(layers "F.Cu" "B.Cu")
		(net "P1V8_CPU1_RT_1D")
	)
	(via
		(at 176.878996 -383.754884)
		(size 0.508)
		(drill 0.254)
		(layers "F.Cu" "B.Cu")
		(net "P1V8_CPU1_RT_1D")
	)
	(via
		(at 171.57827 -384.201924)
		(size 0.508)
		(drill 0.254)
		(layers "F.Cu" "B.Cu")
		(net "P1V8_CPU1_RT_1D")
	)
	(via
		(at 226.376738 -309.75808)
		(size 0.508)
		(drill 0.254)
		(layers "F.Cu" "B.Cu")
		(net "P1V8_CPU1_RT_1D")
	)
	(via
		(at 172.242734 -388.243064)
		(size 0.508)
		(drill 0.254)
		(layers "F.Cu" "B.Cu")
		(net "P1V8_CPU1_RT_1D")
	)
	(via
		(at 229.872032 -313.92876)
		(size 0.508)
		(drill 0.254)
		(layers "F.Cu" "B.Cu")
		(net "P1V8_CPU1_RT_1D")
	)
	(via
		(at 174.667164 -383.76098)
		(size 0.508)
		(drill 0.254)
		(layers "F.Cu" "B.Cu")
		(net "P1V8_CPU1_RT_1D")
	)
	(via
		(at 240.7031 -333.883)
		(size 0.508)
		(drill 0.254)
		(layers "F.Cu" "B.Cu")
		(net "P1V8_CPU1_RT_1D")
	)
	(via
		(at 176.14773 -385.90347)
		(size 0.508)
		(drill 0.254)
		(layers "F.Cu" "B.Cu")
		(net "P1V8_CPU1_RT_1D")
	)
	(via
		(at 41.195752 -385.58216)
		(size 0.508)
		(drill 0.254)
		(layers "F.Cu" "B.Cu")
		(net "P1V8_CPU1_RT_1D")
	)
	(via
		(at 137.36574 -386.444744)
		(size 0.508)
		(drill 0.254)
		(layers "F.Cu" "B.Cu")
		(net "P1V8_CPU1_RT_1D")
	)
	(via
		(at 172.29963 -385.316476)
		(size 0.508)
		(drill 0.254)
		(layers "F.Cu" "B.Cu")
		(net "P1V8_CPU1_RT_1D")
	)
	(via
		(at 181.881018 -374.597168)
		(size 0.508)
		(drill 0.254)
		(layers "F.Cu" "B.Cu")
		(net "P1V8_CPU1_RT_1D")
	)
	(via
		(at 222.738442 -314.83808)
		(size 0.508)
		(drill 0.254)
		(layers "F.Cu" "B.Cu")
		(net "P1V8_CPU1_RT_1D")
	)
	(via
		(at 70.265798 -386.444744)
		(size 0.508)
		(drill 0.254)
		(layers "F.Cu" "B.Cu")
		(net "P1V8_CPU1_RT_1D")
	)
	(via
		(at 172.310044 -383.02311)
		(size 0.508)
		(drill 0.254)
		(layers "F.Cu" "B.Cu")
		(net "P1V8_CPU1_RT_1D")
	)
	(via
		(at 103.520494 -386.04063)
		(size 0.508)
		(drill 0.254)
		(layers "F.Cu" "B.Cu")
		(net "P1V8_CPU1_RT_1D")
	)
	(via
		(at 107.475274 -385.353052)
		(size 0.508)
		(drill 0.254)
		(layers "F.Cu" "B.Cu")
		(net "P1V8_CPU1_RT_1D")
	)
	(via
		(at 164.483796 -423.80027)
		(size 0.508)
		(drill 0.254)
		(layers "F.Cu" "B.Cu")
		(net "P1V8_CPU1_RT_1D")
	)
	(via
		(at 102.793546 -386.444744)
		(size 0.508)
		(drill 0.254)
		(layers "F.Cu" "B.Cu")
		(net "P1V8_CPU1_RT_1D")
	)
	(via
		(at 183.201818 -374.597168)
		(size 0.508)
		(drill 0.254)
		(layers "F.Cu" "B.Cu")
		(net "P1V8_CPU1_RT_1D")
	)
	(via
		(at 104.3051 -383.405126)
		(size 0.508)
		(drill 0.254)
		(layers "F.Cu" "B.Cu")
		(net "P1V8_CPU1_RT_1D")
	)
	(via
		(at 138.162538 -385.09448)
		(size 0.508)
		(drill 0.254)
		(layers "F.Cu" "B.Cu")
		(net "P1V8_CPU1_RT_1D")
	)
	(via
		(at 216.65057 -335.36128)
		(size 0.508)
		(drill 0.254)
		(layers "F.Cu" "B.Cu")
		(net "P1V8_CPU1_RT_1D")
	)
	(via
		(at 177.58156 -384.498088)
		(size 0.508)
		(drill 0.254)
		(layers "F.Cu" "B.Cu")
		(net "P1V8_CPU1_RT_1D")
	)
	(via
		(at 107.337098 -383.719832)
		(size 0.508)
		(drill 0.254)
		(layers "F.Cu" "B.Cu")
		(net "P1V8_CPU1_RT_1D")
	)
	(via
		(at 181.614318 -373.960898)
		(size 0.508)
		(drill 0.254)
		(layers "F.Cu" "B.Cu")
		(net "P1V8_CPU1_RT_1D")
	)
	(via
		(at 225.614738 -311.28208)
		(size 0.508)
		(drill 0.254)
		(layers "F.Cu" "B.Cu")
		(net "P1V8_CPU1_RT_1D")
	)
	(via
		(at 176.171098 -385.18338)
		(size 0.508)
		(drill 0.254)
		(layers "F.Cu" "B.Cu")
		(net "P1V8_CPU1_RT_1D")
	)
	(via
		(at 142.04061 -388.771384)
		(size 0.508)
		(drill 0.254)
		(layers "F.Cu" "B.Cu")
		(net "P1V8_CPU1_RT_1D")
	)
	(via
		(at 182.935118 -373.960898)
		(size 0.508)
		(drill 0.254)
		(layers "F.Cu" "B.Cu")
		(net "P1V8_CPU1_RT_1D")
	)
	(via
		(at 45.127164 -418.902642)
		(size 0.508)
		(drill 0.254)
		(layers "F.Cu" "B.Cu")
		(net "P1V8_CPU1_RT_1D")
	)
	(via
		(at 181.424834 -372.725188)
		(size 0.508)
		(drill 0.254)
		(layers "F.Cu" "B.Cu")
		(net "P1V8_CPU1_RT_1D")
	)
	(via
		(at 70.992746 -386.04063)
		(size 0.508)
		(drill 0.254)
		(layers "F.Cu" "B.Cu")
		(net "P1V8_CPU1_RT_1D")
	)
	(via
		(at 231.319578 -313.92368)
		(size 0.508)
		(drill 0.254)
		(layers "F.Cu" "B.Cu")
		(net "P1V8_CPU1_RT_1D")
	)
	(via
		(at 182.869332 -375.167652)
		(size 0.508)
		(drill 0.254)
		(layers "F.Cu" "B.Cu")
		(net "P1V8_CPU1_RT_1D")
	)
	(via
		(at 223.978978 -315.44768)
		(size 0.508)
		(drill 0.254)
		(layers "F.Cu" "B.Cu")
		(net "P1V8_CPU1_RT_1D")
	)
	(via
		(at 174.678594 -384.457448)
		(size 0.508)
		(drill 0.254)
		(layers "F.Cu" "B.Cu")
		(net "P1V8_CPU1_RT_1D")
	)
	(via
		(at 182.454804 -373.332756)
		(size 0.508)
		(drill 0.254)
		(layers "F.Cu" "B.Cu")
		(net "P1V8_CPU1_RT_1D")
	)
	(via
		(at 229.872032 -313.16676)
		(size 0.508)
		(drill 0.254)
		(layers "F.Cu" "B.Cu")
		(net "P1V8_CPU1_RT_1D")
	)
	(via
		(at 231.661462 -309.75808)
		(size 0.508)
		(drill 0.254)
		(layers "F.Cu" "B.Cu")
		(net "P1V8_CPU1_RT_1D")
	)
	(via
		(at 104.167432 -390.06272)
		(size 0.508)
		(drill 0.254)
		(layers "F.Cu" "B.Cu")
		(net "P1V8_CPU1_RT_1D")
	)
	(via
		(at 166.296848 -420.068502)
		(size 0.508)
		(drill 0.254)
		(layers "F.Cu" "B.Cu")
		(net "P1V8_CPU1_RT_1D")
	)
	(via
		(at 233.707178 -314.68568)
		(size 0.508)
		(drill 0.254)
		(layers "F.Cu" "B.Cu")
		(net "P1V8_CPU1_RT_1D")
	)
	(via
		(at 173.651164 -384.858006)
		(size 0.508)
		(drill 0.254)
		(layers "F.Cu" "B.Cu")
		(net "P1V8_CPU1_RT_1D")
	)
	(via
		(at 108.110274 -385.353052)
		(size 0.508)
		(drill 0.254)
		(layers "F.Cu" "B.Cu")
		(net "P1V8_CPU1_RT_1D")
	)
	(via
		(at 240.7031 -336.169)
		(size 0.508)
		(drill 0.254)
		(layers "F.Cu" "B.Cu")
		(net "P1V8_CPU1_RT_1D")
	)
	(via
		(at 139.819634 -383.801874)
		(size 0.508)
		(drill 0.254)
		(layers "F.Cu" "B.Cu")
		(net "P1V8_CPU1_RT_1D")
	)
	(via
		(at 229.871778 -315.44768)
		(size 0.508)
		(drill 0.254)
		(layers "F.Cu" "B.Cu")
		(net "P1V8_CPU1_RT_1D")
	)
	(via
		(at 139.242038 -384.070352)
		(size 0.508)
		(drill 0.254)
		(layers "F.Cu" "B.Cu")
		(net "P1V8_CPU1_RT_1D")
	)
	(via
		(at 182.541418 -374.597168)
		(size 0.508)
		(drill 0.254)
		(layers "F.Cu" "B.Cu")
		(net "P1V8_CPU1_RT_1D")
	)
	(via
		(at 225.614738 -309.75808)
		(size 0.508)
		(drill 0.254)
		(layers "F.Cu" "B.Cu")
		(net "P1V8_CPU1_RT_1D")
	)
	(via
		(at 96.8629 -418.0332)
		(size 0.508)
		(drill 0.254)
		(layers "F.Cu" "B.Cu")
		(net "P1V8_CPU1_RT_1D")
	)
	(via
		(at 107.008676 -395.663166)
		(size 0.508)
		(drill 0.254)
		(layers "F.Cu" "B.Cu")
		(net "P1V8_CPU1_RT_1D")
	)
	(via
		(at 240.7031 -338.455)
		(size 0.508)
		(drill 0.254)
		(layers "F.Cu" "B.Cu")
		(net "P1V8_CPU1_RT_1D")
	)
	(via
		(at 182.085234 -372.725188)
		(size 0.508)
		(drill 0.254)
		(layers "F.Cu" "B.Cu")
		(net "P1V8_CPU1_RT_1D")
	)
	(via
		(at 225.223578 -313.16168)
		(size 0.508)
		(drill 0.254)
		(layers "F.Cu" "B.Cu")
		(net "P1V8_CPU1_RT_1D")
	)
	(via
		(at 173.117002 -383.719832)
		(size 0.508)
		(drill 0.254)
		(layers "F.Cu" "B.Cu")
		(net "P1V8_CPU1_RT_1D")
	)
	(via
		(at 174.632366 -383.075942)
		(size 0.508)
		(drill 0.254)
		(layers "F.Cu" "B.Cu")
		(net "P1V8_CPU1_RT_1D")
	)
	(via
		(at 240.7031 -337.312)
		(size 0.508)
		(drill 0.254)
		(layers "F.Cu" "B.Cu")
		(net "P1V8_CPU1_RT_1D")
	)
	(via
		(at 96.8629 -418.846)
		(size 0.508)
		(drill 0.254)
		(layers "F.Cu" "B.Cu")
		(net "P1V8_CPU1_RT_1D")
	)
	(via
		(at 103.590344 -385.09448)
		(size 0.508)
		(drill 0.254)
		(layers "F.Cu" "B.Cu")
		(net "P1V8_CPU1_RT_1D")
	)
	(via
		(at 232.423462 -309.75808)
		(size 0.508)
		(drill 0.254)
		(layers "F.Cu" "B.Cu")
		(net "P1V8_CPU1_RT_1D")
	)
	(via
		(at 72.142096 -384.067304)
		(size 0.508)
		(drill 0.254)
		(layers "F.Cu" "B.Cu")
		(net "P1V8_CPU1_RT_1D")
	)
	(via
		(at 223.950276 -313.121802)
		(size 0.508)
		(drill 0.254)
		(layers "F.Cu" "B.Cu")
		(net "P1V8_CPU1_RT_1D")
	)
	(via
		(at 231.661462 -311.28208)
		(size 0.508)
		(drill 0.254)
		(layers "F.Cu" "B.Cu")
		(net "P1V8_CPU1_RT_1D")
	)
	(via
		(at 180.764434 -372.725188)
		(size 0.508)
		(drill 0.254)
		(layers "F.Cu" "B.Cu")
		(net "P1V8_CPU1_RT_1D")
	)
	(via
		(at 223.950276 -312.359802)
		(size 0.508)
		(drill 0.254)
		(layers "F.Cu" "B.Cu")
		(net "P1V8_CPU1_RT_1D")
	)
	(via
		(at 95.105728 -401.9804)
		(size 0.508)
		(drill 0.254)
		(layers "F.Cu" "B.Cu")
		(net "P1V8_CPU1_RT_1D")
	)
	(via
		(at 176.12233 -383.046732)
		(size 0.508)
		(drill 0.254)
		(layers "F.Cu" "B.Cu")
		(net "P1V8_CPU1_RT_1D")
	)
	(via
		(at 217.551 -335.661)
		(size 0.508)
		(drill 0.254)
		(layers "F.Cu" "B.Cu")
		(net "P1V8_CPU1_RT_1D")
	)
	(via
		(at 225.223578 -313.92368)
		(size 0.508)
		(drill 0.254)
		(layers "F.Cu" "B.Cu")
		(net "P1V8_CPU1_RT_1D")
	)
	(via
		(at 98.87966 -396.5575)
		(size 0.508)
		(drill 0.254)
		(layers "F.Cu" "B.Cu")
		(net "P1V8_CPU1_RT_1D")
	)
	(via
		(at 226.376738 -311.28208)
		(size 0.508)
		(drill 0.254)
		(layers "F.Cu" "B.Cu")
		(net "P1V8_CPU1_RT_1D")
	)
	(via
		(at 227.814378 -315.44768)
		(size 0.508)
		(drill 0.254)
		(layers "F.Cu" "B.Cu")
		(net "P1V8_CPU1_RT_1D")
	)
	(via
		(at 175.433482 -383.046732)
		(size 0.508)
		(drill 0.254)
		(layers "F.Cu" "B.Cu")
		(net "P1V8_CPU1_RT_1D")
	)
	(via
		(at 173.105318 -383.040636)
		(size 0.508)
		(drill 0.254)
		(layers "F.Cu" "B.Cu")
		(net "P1V8_CPU1_RT_1D")
	)
	(via
		(at 231.319578 -313.16168)
		(size 0.508)
		(drill 0.254)
		(layers "F.Cu" "B.Cu")
		(net "P1V8_CPU1_RT_1D")
	)
	(via
		(at 170.090592 -416.792918)
		(size 0.508)
		(drill 0.254)
		(layers "F.Cu" "B.Cu")
		(net "P1V8_CPU1_RT_1D")
	)
	(via
		(at 172.902118 -384.376168)
		(size 0.508)
		(drill 0.254)
		(layers "F.Cu" "B.Cu")
		(net "P1V8_CPU1_RT_1D")
	)
	(via
		(at 139.819634 -384.450336)
		(size 0.508)
		(drill 0.254)
		(layers "F.Cu" "B.Cu")
		(net "P1V8_CPU1_RT_1D")
	)
	(via
		(at 227.831396 -312.386726)
		(size 0.508)
		(drill 0.254)
		(layers "F.Cu" "B.Cu")
		(net "P1V8_CPU1_RT_1D")
	)
	(via
		(at 72.142096 -384.702304)
		(size 0.508)
		(drill 0.254)
		(layers "F.Cu" "B.Cu")
		(net "P1V8_CPU1_RT_1D")
	)
	(via
		(at 233.707178 -315.44768)
		(size 0.508)
		(drill 0.254)
		(layers "F.Cu" "B.Cu")
		(net "P1V8_CPU1_RT_1D")
	)
	(via
		(at 182.274718 -373.960898)
		(size 0.508)
		(drill 0.254)
		(layers "F.Cu" "B.Cu")
		(net "P1V8_CPU1_RT_1D")
	)
	(via
		(at 107.972098 -383.719832)
		(size 0.508)
		(drill 0.254)
		(layers "F.Cu" "B.Cu")
		(net "P1V8_CPU1_RT_1D")
	)
	(via
		(at 223.950276 -313.883802)
		(size 0.508)
		(drill 0.254)
		(layers "F.Cu" "B.Cu")
		(net "P1V8_CPU1_RT_1D")
	)
	(via
		(at 105.207308 -396.086584)
		(size 0.508)
		(drill 0.254)
		(layers "F.Cu" "B.Cu")
		(net "P1V8_CPU1_RT_1D")
	)
	(via
		(at 45.087286 -420.07155)
		(size 0.508)
		(drill 0.254)
		(layers "F.Cu" "B.Cu")
		(net "P1V8_CPU1_RT_1D")
	)
	(via
		(at 175.451008 -385.195064)
		(size 0.508)
		(drill 0.254)
		(layers "F.Cu" "B.Cu")
		(net "P1V8_CPU1_RT_1D")
	)
	(via
		(at 103.6701 -383.405126)
		(size 0.508)
		(drill 0.254)
		(layers "F.Cu" "B.Cu")
		(net "P1V8_CPU1_RT_1D")
	)
	(via
		(at 71.142352 -383.405126)
		(size 0.508)
		(drill 0.254)
		(layers "F.Cu" "B.Cu")
		(net "P1V8_CPU1_RT_1D")
	)
	(via
		(at 177.608738 -383.047748)
		(size 0.508)
		(drill 0.254)
		(layers "F.Cu" "B.Cu")
		(net "P1V8_CPU1_RT_1D")
	)
	(via
		(at 226.376738 -310.52008)
		(size 0.508)
		(drill 0.254)
		(layers "F.Cu" "B.Cu")
		(net "P1V8_CPU1_RT_1D")
	)
	(via
		(at 176.867566 -384.509772)
		(size 0.508)
		(drill 0.254)
		(layers "F.Cu" "B.Cu")
		(net "P1V8_CPU1_RT_1D")
	)
	(segment
		(start 216.027 -338.1883)
		(end 216.626948 -338.1883)
		(width 0.254)
		(layer "B.Cu")
		(net "P1V8_CPU1_RT_1D")
	)
	(segment
		(start 240.1697 -340.741)
		(end 240.7031 -340.741)
		(width 0.254)
		(layer "B.Cu")
		(net "P1V8_CPU1_RT_1D")
	)
	(segment
		(start 168.3004 -420.674546)
		(end 168.73601 -420.238936)
		(width 0.254)
		(layer "B.Cu")
		(net "P1V8_CPU1_RT_1D")
	)
	(segment
		(start 217.3097 -335.9023)
		(end 217.551 -335.661)
		(width 0.254)
		(layer "B.Cu")
		(net "P1V8_CPU1_RT_1D")
	)
	(segment
		(start 165.543992 -420.068502)
		(end 166.296848 -420.068502)
		(width 0.3048)
		(layer "B.Cu")
		(net "P1V8_CPU1_RT_1D")
	)
	(segment
		(start 165.16096 -420.451534)
		(end 165.543992 -420.068502)
		(width 0.3048)
		(layer "B.Cu")
		(net "P1V8_CPU1_RT_1D")
	)
	(segment
		(start 240.1697 -339.598)
		(end 240.7031 -339.598)
		(width 0.254)
		(layer "B.Cu")
		(net "P1V8_CPU1_RT_1D")
	)
	(segment
		(start 240.1697 -333.883)
		(end 240.7031 -333.883)
		(width 0.254)
		(layer "B.Cu")
		(net "P1V8_CPU1_RT_1D")
	)
	(segment
		(start 240.1697 -338.455)
		(end 240.7031 -338.455)
		(width 0.254)
		(layer "B.Cu")
		(net "P1V8_CPU1_RT_1D")
	)
	(segment
		(start 156.9593 -416.1536)
		(end 156.9593 -416.9664)
		(width 0.254)
		(layer "B.Cu")
		(net "P1V8_CPU1_RT_1D")
	)
	(segment
		(start 168.986708 -420.783004)
		(end 169.2148 -421.011096)
		(width 0.254)
		(layer "B.Cu")
		(net "P1V8_CPU1_RT_1D")
	)
	(segment
		(start 217.3097 -340.4743)
		(end 217.551 -340.233)
		(width 0.254)
		(layer "B.Cu")
		(net "P1V8_CPU1_RT_1D")
	)
	(segment
		(start 164.107368 -420.451534)
		(end 164.900864 -420.451534)
		(width 0.3048)
		(layer "B.Cu")
		(net "P1V8_CPU1_RT_1D")
	)
	(segment
		(start 240.1697 -335.026)
		(end 240.7031 -335.026)
		(width 0.254)
		(layer "B.Cu")
		(net "P1V8_CPU1_RT_1D")
	)
	(segment
		(start 156.9593 -416.9664)
		(end 155.942792 -416.9664)
		(width 0.254)
		(layer "B.Cu")
		(net "P1V8_CPU1_RT_1D")
	)
	(segment
		(start 216.916 -337.7057)
		(end 217.3097 -337.7057)
		(width 0.254)
		(layer "B.Cu")
		(net "P1V8_CPU1_RT_1D")
	)
	(segment
		(start 216.59215 -335.4197)
		(end 216.65057 -335.36128)
		(width 0.254)
		(layer "B.Cu")
		(net "P1V8_CPU1_RT_1D")
	)
	(segment
		(start 240.1697 -336.169)
		(end 240.7031 -336.169)
		(width 0.254)
		(layer "B.Cu")
		(net "P1V8_CPU1_RT_1D")
	)
	(segment
		(start 216.65057 -335.36128)
		(end 216.916 -335.62671)
		(width 0.254)
		(layer "B.Cu")
		(net "P1V8_CPU1_RT_1D")
	)
	(segment
		(start 168.73601 -420.238936)
		(end 168.986708 -420.489634)
		(width 0.254)
		(layer "B.Cu")
		(net "P1V8_CPU1_RT_1D")
	)
	(segment
		(start 240.1697 -341.884)
		(end 240.7031 -341.884)
		(width 0.254)
		(layer "B.Cu")
		(net "P1V8_CPU1_RT_1D")
	)
	(segment
		(start 216.916 -335.9023)
		(end 217.3097 -335.9023)
		(width 0.254)
		(layer "B.Cu")
		(net "P1V8_CPU1_RT_1D")
	)
	(segment
		(start 238.305594 -325.65721)
		(end 239.022382 -325.65721)
		(width 0.381)
		(layer "B.Cu")
		(net "P1V8_CPU1_RT_1D")
	)
	(segment
		(start 216.027 -335.4197)
		(end 216.59215 -335.4197)
		(width 0.254)
		(layer "B.Cu")
		(net "P1V8_CPU1_RT_1D")
	)
	(segment
		(start 168.3004 -421.011096)
		(end 168.3004 -420.674546)
		(width 0.254)
		(layer "B.Cu")
		(net "P1V8_CPU1_RT_1D")
	)
	(segment
		(start 240.1697 -337.312)
		(end 240.7031 -337.312)
		(width 0.254)
		(layer "B.Cu")
		(net "P1V8_CPU1_RT_1D")
	)
	(segment
		(start 216.916 -338.020152)
		(end 216.6874 -338.248752)
		(width 0.254)
		(layer "B.Cu")
		(net "P1V8_CPU1_RT_1D")
	)
	(segment
		(start 216.916 -335.62671)
		(end 216.916 -335.9023)
		(width 0.254)
		(layer "B.Cu")
		(net "P1V8_CPU1_RT_1D")
	)
	(segment
		(start 216.916 -340.25459)
		(end 216.60612 -339.94471)
		(width 0.254)
		(layer "B.Cu")
		(net "P1V8_CPU1_RT_1D")
	)
	(segment
		(start 216.916 -337.7057)
		(end 216.916 -338.020152)
		(width 0.254)
		(layer "B.Cu")
		(net "P1V8_CPU1_RT_1D")
	)
	(segment
		(start 217.3097 -342.2777)
		(end 217.551 -342.519)
		(width 0.254)
		(layer "B.Cu")
		(net "P1V8_CPU1_RT_1D")
	)
	(segment
		(start 216.613994 -333.6163)
		(end 216.027 -333.6163)
		(width 0.254)
		(layer "B.Cu")
		(net "P1V8_CPU1_RT_1D")
	)
	(segment
		(start 216.916 -342.2777)
		(end 217.3097 -342.2777)
		(width 0.254)
		(layer "B.Cu")
		(net "P1V8_CPU1_RT_1D")
	)
	(segment
		(start 216.55913 -339.9917)
		(end 216.60612 -339.94471)
		(width 0.254)
		(layer "B.Cu")
		(net "P1V8_CPU1_RT_1D")
	)
	(segment
		(start 168.986708 -420.489634)
		(end 168.986708 -420.783004)
		(width 0.254)
		(layer "B.Cu")
		(net "P1V8_CPU1_RT_1D")
	)
	(segment
		(start 216.027 -339.9917)
		(end 216.55913 -339.9917)
		(width 0.254)
		(layer "B.Cu")
		(net "P1V8_CPU1_RT_1D")
	)
	(segment
		(start 216.626948 -338.1883)
		(end 216.6874 -338.248752)
		(width 0.254)
		(layer "B.Cu")
		(net "P1V8_CPU1_RT_1D")
	)
	(segment
		(start 217.3097 -337.7057)
		(end 217.551 -337.947)
		(width 0.254)
		(layer "B.Cu")
		(net "P1V8_CPU1_RT_1D")
	)
	(segment
		(start 164.900864 -420.451534)
		(end 165.16096 -420.451534)
		(width 0.3048)
		(layer "B.Cu")
		(net "P1V8_CPU1_RT_1D")
	)
	(segment
		(start 216.916 -340.4743)
		(end 216.916 -340.25459)
		(width 0.254)
		(layer "B.Cu")
		(net "P1V8_CPU1_RT_1D")
	)
	(segment
		(start 216.916 -340.4743)
		(end 217.3097 -340.4743)
		(width 0.254)
		(layer "B.Cu")
		(net "P1V8_CPU1_RT_1D")
	)
	(segment
		(start 236.646212 -325.6534)
		(end 236.650022 -325.65721)
		(width 0.508)
		(layer "In13.Cu")
		(net "P1V8_CPU1_RT_1D")
	)
	(segment
		(start 236.650022 -325.65721)
		(end 239.022382 -325.65721)
		(width 0.508)
		(layer "In13.Cu")
		(net "P1V8_CPU1_RT_1D")
	)
	(segment
		(start 98.1456 -396.5575)
		(end 95.105728 -399.597372)
		(width 0.508)
		(layer "In15.Cu")
		(net "P1V8_CPU1_RT_1D")
	)
	(segment
		(start 102.954074 -393.427712)
		(end 101.493066 -394.88872)
		(width 0.508)
		(layer "In15.Cu")
		(net "P1V8_CPU1_RT_1D")
	)
	(segment
		(start 98.87966 -396.5575)
		(end 98.1456 -396.5575)
		(width 0.508)
		(layer "In15.Cu")
		(net "P1V8_CPU1_RT_1D")
	)
	(segment
		(start 101.493066 -394.88872)
		(end 100.54844 -394.88872)
		(width 0.508)
		(layer "In15.Cu")
		(net "P1V8_CPU1_RT_1D")
	)
	(segment
		(start 95.105728 -399.597372)
		(end 95.105728 -401.9804)
		(width 0.508)
		(layer "In15.Cu")
		(net "P1V8_CPU1_RT_1D")
	)
	(segment
		(start 100.54844 -394.88872)
		(end 98.87966 -396.5575)
		(width 0.508)
		(layer "In15.Cu")
		(net "P1V8_CPU1_RT_1D")
	)
	(via
		(at 90.846148 -387.693662)
		(size 0.4064)
		(drill 0.2032)
		(layers "F.Cu" "B.Cu")
		(net "P1V8_CPU1_RT1_1A_1D")
	)
	(via
		(at 102.790244 -385.09448)
		(size 0.508)
		(drill 0.254)
		(layers "F.Cu" "B.Cu")
		(net "P1V8_CPU1_RT1_1A_1D")
	)
	(via
		(at 90.706194 -387.084062)
		(size 0.4064)
		(drill 0.2032)
		(layers "F.Cu" "B.Cu")
		(net "P1V8_CPU1_RT1_1A_1D")
	)
	(via
		(at 102.790244 -384.10388)
		(size 0.508)
		(drill 0.254)
		(layers "F.Cu" "B.Cu")
		(net "P1V8_CPU1_RT1_1A_1D")
	)
	(via
		(at 101.990144 -384.10388)
		(size 0.508)
		(drill 0.254)
		(layers "F.Cu" "B.Cu")
		(net "P1V8_CPU1_RT1_1A")
	)
	(via
		(at 87.106252 -387.084062)
		(size 0.4064)
		(drill 0.2032)
		(layers "F.Cu" "B.Cu")
		(net "P1V8_CPU1_RT1_1A")
	)
	(via
		(at 100.890324 -384.671062)
		(size 0.508)
		(drill 0.254)
		(layers "F.Cu" "B.Cu")
		(net "P1V8_CPU1_RT1_1A")
	)
	(via
		(at 102.021386 -386.04063)
		(size 0.508)
		(drill 0.254)
		(layers "F.Cu" "B.Cu")
		(net "P1V8_CPU1_RT1_1A")
	)
	(via
		(at 89.506298 -387.084062)
		(size 0.4064)
		(drill 0.2032)
		(layers "F.Cu" "B.Cu")
		(net "P1V8_CPU1_RT1_1A")
	)
	(via
		(at 87.246206 -387.693662)
		(size 0.4064)
		(drill 0.2032)
		(layers "F.Cu" "B.Cu")
		(net "P1V8_CPU1_RT1_1A")
	)
	(via
		(at 101.064314 -386.444744)
		(size 0.508)
		(drill 0.254)
		(layers "F.Cu" "B.Cu")
		(net "P1V8_CPU1_RT1_1A")
	)
	(via
		(at 99.77882 -385.57708)
		(size 0.6604)
		(drill 0.3302)
		(layers "F.Cu" "B.Cu")
		(net "P1V8_CPU1_RT1_1A")
	)
	(via
		(at 99.769168 -384.112008)
		(size 0.6604)
		(drill 0.3302)
		(layers "F.Cu" "B.Cu")
		(net "P1V8_CPU1_RT1_1A")
	)
	(via
		(at 101.990144 -385.09448)
		(size 0.508)
		(drill 0.254)
		(layers "F.Cu" "B.Cu")
		(net "P1V8_CPU1_RT1_1A")
	)
	(via
		(at 100.890324 -384.036062)
		(size 0.508)
		(drill 0.254)
		(layers "F.Cu" "B.Cu")
		(net "P1V8_CPU1_RT1_1A")
	)
	(via
		(at 100.427536 -385.8895)
		(size 0.508)
		(drill 0.254)
		(layers "F.Cu" "B.Cu")
		(net "P1V8_CPU1_RT1_1A")
	)
	(via
		(at 88.306402 -387.084062)
		(size 0.4064)
		(drill 0.2032)
		(layers "F.Cu" "B.Cu")
		(net "P1V8_CPU1_RT1_1A")
	)
	(via
		(at 100.890324 -385.306062)
		(size 0.508)
		(drill 0.254)
		(layers "F.Cu" "B.Cu")
		(net "P1V8_CPU1_RT1_1A")
	)
	(via
		(at 89.646252 -387.693662)
		(size 0.4064)
		(drill 0.2032)
		(layers "F.Cu" "B.Cu")
		(net "P1V8_CPU1_RT1_1A")
	)
	(via
		(at 88.446356 -387.693662)
		(size 0.4064)
		(drill 0.2032)
		(layers "F.Cu" "B.Cu")
		(net "P1V8_CPU1_RT1_1A")
	)
	(via
		(at 58.178446 -387.084062)
		(size 0.4064)
		(drill 0.2032)
		(layers "F.Cu" "B.Cu")
		(net "P1V8_CPU1_RT0_1A_1D")
	)
	(via
		(at 58.3184 -387.693662)
		(size 0.4064)
		(drill 0.2032)
		(layers "F.Cu" "B.Cu")
		(net "P1V8_CPU1_RT0_1A_1D")
	)
	(via
		(at 70.262496 -385.09448)
		(size 0.508)
		(drill 0.254)
		(layers "F.Cu" "B.Cu")
		(net "P1V8_CPU1_RT0_1A_1D")
	)
	(via
		(at 70.262496 -384.10388)
		(size 0.508)
		(drill 0.254)
		(layers "F.Cu" "B.Cu")
		(net "P1V8_CPU1_RT0_1A_1D")
	)
	(via
		(at 67.226434 -384.16738)
		(size 0.6604)
		(drill 0.3302)
		(layers "F.Cu" "B.Cu")
		(net "P1V8_CPU1_RT0_1A")
	)
	(via
		(at 56.97855 -387.084062)
		(size 0.4064)
		(drill 0.2032)
		(layers "F.Cu" "B.Cu")
		(net "P1V8_CPU1_RT0_1A")
	)
	(via
		(at 68.362576 -384.036062)
		(size 0.508)
		(drill 0.254)
		(layers "F.Cu" "B.Cu")
		(net "P1V8_CPU1_RT0_1A")
	)
	(via
		(at 69.462396 -384.10388)
		(size 0.508)
		(drill 0.254)
		(layers "F.Cu" "B.Cu")
		(net "P1V8_CPU1_RT0_1A")
	)
	(via
		(at 68.362576 -384.671062)
		(size 0.508)
		(drill 0.254)
		(layers "F.Cu" "B.Cu")
		(net "P1V8_CPU1_RT0_1A")
	)
	(via
		(at 69.462396 -385.09448)
		(size 0.508)
		(drill 0.254)
		(layers "F.Cu" "B.Cu")
		(net "P1V8_CPU1_RT0_1A")
	)
	(via
		(at 54.578504 -387.084062)
		(size 0.4064)
		(drill 0.2032)
		(layers "F.Cu" "B.Cu")
		(net "P1V8_CPU1_RT0_1A")
	)
	(via
		(at 55.918608 -387.693662)
		(size 0.4064)
		(drill 0.2032)
		(layers "F.Cu" "B.Cu")
		(net "P1V8_CPU1_RT0_1A")
	)
	(via
		(at 67.25158 -385.572)
		(size 0.6604)
		(drill 0.3302)
		(layers "F.Cu" "B.Cu")
		(net "P1V8_CPU1_RT0_1A")
	)
	(via
		(at 69.493638 -386.04063)
		(size 0.508)
		(drill 0.254)
		(layers "F.Cu" "B.Cu")
		(net "P1V8_CPU1_RT0_1A")
	)
	(via
		(at 67.899788 -385.8895)
		(size 0.508)
		(drill 0.254)
		(layers "F.Cu" "B.Cu")
		(net "P1V8_CPU1_RT0_1A")
	)
	(via
		(at 68.362576 -385.306062)
		(size 0.508)
		(drill 0.254)
		(layers "F.Cu" "B.Cu")
		(net "P1V8_CPU1_RT0_1A")
	)
	(via
		(at 57.118504 -387.693662)
		(size 0.4064)
		(drill 0.2032)
		(layers "F.Cu" "B.Cu")
		(net "P1V8_CPU1_RT0_1A")
	)
	(via
		(at 55.778654 -387.084062)
		(size 0.4064)
		(drill 0.2032)
		(layers "F.Cu" "B.Cu")
		(net "P1V8_CPU1_RT0_1A")
	)
	(via
		(at 68.536566 -386.444744)
		(size 0.508)
		(drill 0.254)
		(layers "F.Cu" "B.Cu")
		(net "P1V8_CPU1_RT0_1A")
	)
	(via
		(at 54.718458 -387.693662)
		(size 0.4064)
		(drill 0.2032)
		(layers "F.Cu" "B.Cu")
		(net "P1V8_CPU1_RT0_1A")
	)
	(segment
		(start 12.876784 -393.050776)
		(end 12.650978 -393.050776)
		(width 0.508)
		(layer "F.Cu")
		(net "P0V9_CPU1_RT_2D")
	)
	(segment
		(start 9.777984 -380.165356)
		(end 9.111234 -380.165356)
		(width 0.254)
		(layer "F.Cu")
		(net "P0V9_CPU1_RT_2D")
	)
	(segment
		(start 21.112734 -392.396726)
		(end 21.112734 -391.742676)
		(width 0.254)
		(layer "F.Cu")
		(net "P0V9_CPU1_RT_2D")
	)
	(segment
		(start 9.111234 -380.165356)
		(end 8.806434 -380.470156)
		(width 0.254)
		(layer "F.Cu")
		(net "P0V9_CPU1_RT_2D")
	)
	(segment
		(start 12.650978 -393.050776)
		(end 12.274296 -392.674094)
		(width 0.508)
		(layer "F.Cu")
		(net "P0V9_CPU1_RT_2D")
	)
	(via
		(at 26.30297 -375.698512)
		(size 0.508)
		(drill 0.254)
		(layers "F.Cu" "B.Cu")
		(net "P0V9_CPU1_RT_2D")
	)
	(via
		(at 10.50544 -380.738634)
		(size 0.508)
		(drill 0.254)
		(layers "F.Cu" "B.Cu")
		(net "P0V9_CPU1_RT_2D")
	)
	(via
		(at 106.211878 -393.52093)
		(size 0.508)
		(drill 0.254)
		(layers "F.Cu" "B.Cu")
		(net "P0V9_CPU1_RT_2D")
	)
	(via
		(at 14.675358 -378.60732)
		(size 0.508)
		(drill 0.254)
		(layers "F.Cu" "B.Cu")
		(net "P0V9_CPU1_RT_2D")
	)
	(via
		(at 53.518562 -387.693662)
		(size 0.4064)
		(drill 0.2032)
		(layers "F.Cu" "B.Cu")
		(net "P0V9_CPU1_RT_2D")
	)
	(via
		(at 20.782788 -375.17705)
		(size 0.508)
		(drill 0.254)
		(layers "F.Cu" "B.Cu")
		(net "P0V9_CPU1_RT_2D")
	)
	(via
		(at 20.556728 -380.14656)
		(size 0.508)
		(drill 0.254)
		(layers "F.Cu" "B.Cu")
		(net "P0V9_CPU1_RT_2D")
	)
	(via
		(at 105.576878 -393.52093)
		(size 0.508)
		(drill 0.254)
		(layers "F.Cu" "B.Cu")
		(net "P0V9_CPU1_RT_2D")
	)
	(via
		(at 71.004684 -393.52093)
		(size 0.508)
		(drill 0.254)
		(layers "F.Cu" "B.Cu")
		(net "P0V9_CPU1_RT_2D")
	)
	(via
		(at 42.587164 -398.175734)
		(size 0.508)
		(drill 0.254)
		(layers "F.Cu" "B.Cu")
		(net "P0V9_CPU1_RT_2D")
	)
	(via
		(at 14.686788 -376.628914)
		(size 0.508)
		(drill 0.254)
		(layers "F.Cu" "B.Cu")
		(net "P0V9_CPU1_RT_2D")
	)
	(via
		(at 26.785062 -377.924822)
		(size 0.508)
		(drill 0.254)
		(layers "F.Cu" "B.Cu")
		(net "P0V9_CPU1_RT_2D")
	)
	(via
		(at 20.782788 -377.46305)
		(size 0.508)
		(drill 0.254)
		(layers "F.Cu" "B.Cu")
		(net "P0V9_CPU1_RT_2D")
	)
	(via
		(at 41.317164 -398.175734)
		(size 0.508)
		(drill 0.254)
		(layers "F.Cu" "B.Cu")
		(net "P0V9_CPU1_RT_2D")
	)
	(via
		(at 41.952164 -397.540734)
		(size 0.508)
		(drill 0.254)
		(layers "F.Cu" "B.Cu")
		(net "P0V9_CPU1_RT_2D")
	)
	(via
		(at 92.046298 -387.693662)
		(size 0.4064)
		(drill 0.2032)
		(layers "F.Cu" "B.Cu")
		(net "P0V9_CPU1_RT_2D")
	)
	(via
		(at 72.274684 -392.25093)
		(size 0.508)
		(drill 0.254)
		(layers "F.Cu" "B.Cu")
		(net "P0V9_CPU1_RT_2D")
	)
	(via
		(at 138.739626 -393.52093)
		(size 0.508)
		(drill 0.254)
		(layers "F.Cu" "B.Cu")
		(net "P0V9_CPU1_RT_2D")
	)
	(via
		(at 139.374626 -392.88593)
		(size 0.508)
		(drill 0.254)
		(layers "F.Cu" "B.Cu")
		(net "P0V9_CPU1_RT_2D")
	)
	(via
		(at 14.686788 -375.93905)
		(size 0.508)
		(drill 0.254)
		(layers "F.Cu" "B.Cu")
		(net "P0V9_CPU1_RT_2D")
	)
	(via
		(at 26.30297 -376.460512)
		(size 0.508)
		(drill 0.254)
		(layers "F.Cu" "B.Cu")
		(net "P0V9_CPU1_RT_2D")
	)
	(via
		(at 107.329478 -390.54913)
		(size 0.508)
		(drill 0.254)
		(layers "F.Cu" "B.Cu")
		(net "P0V9_CPU1_RT_2D")
	)
	(via
		(at 21.333714 -379.48616)
		(size 0.508)
		(drill 0.254)
		(layers "F.Cu" "B.Cu")
		(net "P0V9_CPU1_RT_2D")
	)
	(via
		(at 25.802336 -378.788168)
		(size 0.508)
		(drill 0.254)
		(layers "F.Cu" "B.Cu")
		(net "P0V9_CPU1_RT_2D")
	)
	(via
		(at 43.171364 -398.810734)
		(size 0.508)
		(drill 0.254)
		(layers "F.Cu" "B.Cu")
		(net "P0V9_CPU1_RT_2D")
	)
	(via
		(at 42.587164 -396.905734)
		(size 0.508)
		(drill 0.254)
		(layers "F.Cu" "B.Cu")
		(net "P0V9_CPU1_RT_2D")
	)
	(via
		(at 139.374626 -391.61593)
		(size 0.508)
		(drill 0.254)
		(layers "F.Cu" "B.Cu")
		(net "P0V9_CPU1_RT_2D")
	)
	(via
		(at 16.94434 -376.510296)
		(size 0.508)
		(drill 0.254)
		(layers "F.Cu" "B.Cu")
		(net "P0V9_CPU1_RT_2D")
	)
	(via
		(at 10.492486 -380.027942)
		(size 0.508)
		(drill 0.254)
		(layers "F.Cu" "B.Cu")
		(net "P0V9_CPU1_RT_2D")
	)
	(via
		(at 71.004684 -392.88593)
		(size 0.508)
		(drill 0.254)
		(layers "F.Cu" "B.Cu")
		(net "P0V9_CPU1_RT_2D")
	)
	(via
		(at 136.834626 -393.52093)
		(size 0.508)
		(drill 0.254)
		(layers "F.Cu" "B.Cu")
		(net "P0V9_CPU1_RT_2D")
	)
	(via
		(at 12.51331 -379.3363)
		(size 0.508)
		(drill 0.254)
		(layers "F.Cu" "B.Cu")
		(net "P0V9_CPU1_RT_2D")
	)
	(via
		(at 10.876788 -376.70105)
		(size 0.508)
		(drill 0.254)
		(layers "F.Cu" "B.Cu")
		(net "P0V9_CPU1_RT_2D")
	)
	(via
		(at 106.211878 -392.25093)
		(size 0.508)
		(drill 0.254)
		(layers "F.Cu" "B.Cu")
		(net "P0V9_CPU1_RT_2D")
	)
	(via
		(at 105.576878 -392.25093)
		(size 0.508)
		(drill 0.254)
		(layers "F.Cu" "B.Cu")
		(net "P0V9_CPU1_RT_2D")
	)
	(via
		(at 43.222164 -398.175734)
		(size 0.508)
		(drill 0.254)
		(layers "F.Cu" "B.Cu")
		(net "P0V9_CPU1_RT_2D")
	)
	(via
		(at 27.228038 -381.446024)
		(size 0.508)
		(drill 0.254)
		(layers "F.Cu" "B.Cu")
		(net "P0V9_CPU1_RT_2D")
	)
	(via
		(at 27.872182 -378.807218)
		(size 0.508)
		(drill 0.254)
		(layers "F.Cu" "B.Cu")
		(net "P0V9_CPU1_RT_2D")
	)
	(via
		(at 106.846878 -392.25093)
		(size 0.508)
		(drill 0.254)
		(layers "F.Cu" "B.Cu")
		(net "P0V9_CPU1_RT_2D")
	)
	(via
		(at 27.866848 -380.795784)
		(size 0.508)
		(drill 0.254)
		(layers "F.Cu" "B.Cu")
		(net "P0V9_CPU1_RT_2D")
	)
	(via
		(at 12.274296 -392.674094)
		(size 0.508)
		(drill 0.254)
		(layers "F.Cu" "B.Cu")
		(net "P0V9_CPU1_RT_2D")
	)
	(via
		(at 22.535388 -375.854214)
		(size 0.508)
		(drill 0.254)
		(layers "F.Cu" "B.Cu")
		(net "P0V9_CPU1_RT_2D")
	)
	(via
		(at 159.14624 -387.693662)
		(size 0.4064)
		(drill 0.2032)
		(layers "F.Cu" "B.Cu")
		(net "P0V9_CPU1_RT_2D")
	)
	(via
		(at 72.774556 -390.825228)
		(size 0.508)
		(drill 0.254)
		(layers "F.Cu" "B.Cu")
		(net "P0V9_CPU1_RT_2D")
	)
	(via
		(at 18.388584 -378.78766)
		(size 0.508)
		(drill 0.254)
		(layers "F.Cu" "B.Cu")
		(net "P0V9_CPU1_RT_2D")
	)
	(via
		(at 72.274684 -392.88593)
		(size 0.508)
		(drill 0.254)
		(layers "F.Cu" "B.Cu")
		(net "P0V9_CPU1_RT_2D")
	)
	(via
		(at 20.531582 -380.80696)
		(size 0.508)
		(drill 0.254)
		(layers "F.Cu" "B.Cu")
		(net "P0V9_CPU1_RT_2D")
	)
	(via
		(at 20.782788 -376.70105)
		(size 0.508)
		(drill 0.254)
		(layers "F.Cu" "B.Cu")
		(net "P0V9_CPU1_RT_2D")
	)
	(via
		(at 72.139556 -390.825228)
		(size 0.508)
		(drill 0.254)
		(layers "F.Cu" "B.Cu")
		(net "P0V9_CPU1_RT_2D")
	)
	(via
		(at 106.211878 -391.61593)
		(size 0.508)
		(drill 0.254)
		(layers "F.Cu" "B.Cu")
		(net "P0V9_CPU1_RT_2D")
	)
	(via
		(at 42.587164 -397.540734)
		(size 0.508)
		(drill 0.254)
		(layers "F.Cu" "B.Cu")
		(net "P0V9_CPU1_RT_2D")
	)
	(via
		(at 20.782788 -375.93905)
		(size 0.508)
		(drill 0.254)
		(layers "F.Cu" "B.Cu")
		(net "P0V9_CPU1_RT_2D")
	)
	(via
		(at 16.26362 -380.13513)
		(size 0.508)
		(drill 0.254)
		(layers "F.Cu" "B.Cu")
		(net "P0V9_CPU1_RT_2D")
	)
	(via
		(at 22.616668 -378.080524)
		(size 0.508)
		(drill 0.254)
		(layers "F.Cu" "B.Cu")
		(net "P0V9_CPU1_RT_2D")
	)
	(via
		(at 16.94434 -377.272296)
		(size 0.508)
		(drill 0.254)
		(layers "F.Cu" "B.Cu")
		(net "P0V9_CPU1_RT_2D")
	)
	(via
		(at 70.369684 -392.88593)
		(size 0.508)
		(drill 0.254)
		(layers "F.Cu" "B.Cu")
		(net "P0V9_CPU1_RT_2D")
	)
	(via
		(at 43.222164 -397.540734)
		(size 0.508)
		(drill 0.254)
		(layers "F.Cu" "B.Cu")
		(net "P0V9_CPU1_RT_2D")
	)
	(via
		(at 20.536408 -378.114052)
		(size 0.508)
		(drill 0.254)
		(layers "F.Cu" "B.Cu")
		(net "P0V9_CPU1_RT_2D")
	)
	(via
		(at 138.739626 -392.25093)
		(size 0.508)
		(drill 0.254)
		(layers "F.Cu" "B.Cu")
		(net "P0V9_CPU1_RT_2D")
	)
	(via
		(at 16.26362 -381.40513)
		(size 0.508)
		(drill 0.254)
		(layers "F.Cu" "B.Cu")
		(net "P0V9_CPU1_RT_2D")
	)
	(via
		(at 140.009626 -391.61593)
		(size 0.508)
		(drill 0.254)
		(layers "F.Cu" "B.Cu")
		(net "P0V9_CPU1_RT_2D")
	)
	(via
		(at 26.462736 -378.788168)
		(size 0.508)
		(drill 0.254)
		(layers "F.Cu" "B.Cu")
		(net "P0V9_CPU1_RT_2D")
	)
	(via
		(at 27.678634 -376.473974)
		(size 0.508)
		(drill 0.254)
		(layers "F.Cu" "B.Cu")
		(net "P0V9_CPU1_RT_2D")
	)
	(via
		(at 26.572464 -381.459994)
		(size 0.508)
		(drill 0.254)
		(layers "F.Cu" "B.Cu")
		(net "P0V9_CPU1_RT_2D")
	)
	(via
		(at 12.490958 -380.053088)
		(size 0.508)
		(drill 0.254)
		(layers "F.Cu" "B.Cu")
		(net "P0V9_CPU1_RT_2D")
	)
	(via
		(at 41.952164 -398.175734)
		(size 0.508)
		(drill 0.254)
		(layers "F.Cu" "B.Cu")
		(net "P0V9_CPU1_RT_2D")
	)
	(via
		(at 86.93785 -392.885422)
		(size 0.6604)
		(drill 0.3302)
		(layers "F.Cu" "B.Cu")
		(net "P0V9_CPU1_RT_2D")
	)
	(via
		(at 106.211878 -392.88593)
		(size 0.508)
		(drill 0.254)
		(layers "F.Cu" "B.Cu")
		(net "P0V9_CPU1_RT_2D")
	)
	(via
		(at 71.639684 -393.52093)
		(size 0.508)
		(drill 0.254)
		(layers "F.Cu" "B.Cu")
		(net "P0V9_CPU1_RT_2D")
	)
	(via
		(at 20.556728 -378.82576)
		(size 0.508)
		(drill 0.254)
		(layers "F.Cu" "B.Cu")
		(net "P0V9_CPU1_RT_2D")
	)
	(via
		(at 25.789636 -380.807976)
		(size 0.508)
		(drill 0.254)
		(layers "F.Cu" "B.Cu")
		(net "P0V9_CPU1_RT_2D")
	)
	(via
		(at 20.556728 -379.48616)
		(size 0.508)
		(drill 0.254)
		(layers "F.Cu" "B.Cu")
		(net "P0V9_CPU1_RT_2D")
	)
	(via
		(at 72.274684 -391.61593)
		(size 0.508)
		(drill 0.254)
		(layers "F.Cu" "B.Cu")
		(net "P0V9_CPU1_RT_2D")
	)
	(via
		(at 10.876788 -375.93905)
		(size 0.508)
		(drill 0.254)
		(layers "F.Cu" "B.Cu")
		(net "P0V9_CPU1_RT_2D")
	)
	(via
		(at 42.536364 -398.810734)
		(size 0.508)
		(drill 0.254)
		(layers "F.Cu" "B.Cu")
		(net "P0V9_CPU1_RT_2D")
	)
	(via
		(at 19.782282 -380.14656)
		(size 0.508)
		(drill 0.254)
		(layers "F.Cu" "B.Cu")
		(net "P0V9_CPU1_RT_2D")
	)
	(via
		(at 14.686788 -375.17705)
		(size 0.508)
		(drill 0.254)
		(layers "F.Cu" "B.Cu")
		(net "P0V9_CPU1_RT_2D")
	)
	(via
		(at 21.333714 -380.12116)
		(size 0.508)
		(drill 0.254)
		(layers "F.Cu" "B.Cu")
		(net "P0V9_CPU1_RT_2D")
	)
	(via
		(at 26.462736 -379.448568)
		(size 0.508)
		(drill 0.254)
		(layers "F.Cu" "B.Cu")
		(net "P0V9_CPU1_RT_2D")
	)
	(via
		(at 8.590788 -376.70105)
		(size 0.508)
		(drill 0.254)
		(layers "F.Cu" "B.Cu")
		(net "P0V9_CPU1_RT_2D")
	)
	(via
		(at 27.024584 -377.218702)
		(size 0.508)
		(drill 0.254)
		(layers "F.Cu" "B.Cu")
		(net "P0V9_CPU1_RT_2D")
	)
	(via
		(at 106.846878 -393.52093)
		(size 0.508)
		(drill 0.254)
		(layers "F.Cu" "B.Cu")
		(net "P0V9_CPU1_RT_2D")
	)
	(via
		(at 45.159168 -401.977606)
		(size 0.508)
		(drill 0.254)
		(layers "F.Cu" "B.Cu")
		(net "P0V9_CPU1_RT_2D")
	)
	(via
		(at 153.146252 -387.693662)
		(size 0.4064)
		(drill 0.2032)
		(layers "F.Cu" "B.Cu")
		(net "P0V9_CPU1_RT_2D")
	)
	(via
		(at 120.618504 -387.693662)
		(size 0.4064)
		(drill 0.2032)
		(layers "F.Cu" "B.Cu")
		(net "P0V9_CPU1_RT_2D")
	)
	(via
		(at 16.26362 -378.86513)
		(size 0.508)
		(drill 0.254)
		(layers "F.Cu" "B.Cu")
		(net "P0V9_CPU1_RT_2D")
	)
	(via
		(at 27.909012 -381.477266)
		(size 0.508)
		(drill 0.254)
		(layers "F.Cu" "B.Cu")
		(net "P0V9_CPU1_RT_2D")
	)
	(via
		(at 72.274684 -393.52093)
		(size 0.508)
		(drill 0.254)
		(layers "F.Cu" "B.Cu")
		(net "P0V9_CPU1_RT_2D")
	)
	(via
		(at 25.815036 -379.473968)
		(size 0.508)
		(drill 0.254)
		(layers "F.Cu" "B.Cu")
		(net "P0V9_CPU1_RT_2D")
	)
	(via
		(at 14.686788 -377.264676)
		(size 0.508)
		(drill 0.254)
		(layers "F.Cu" "B.Cu")
		(net "P0V9_CPU1_RT_2D")
	)
	(via
		(at 71.639684 -392.25093)
		(size 0.508)
		(drill 0.254)
		(layers "F.Cu" "B.Cu")
		(net "P0V9_CPU1_RT_2D")
	)
	(via
		(at 138.739626 -391.61593)
		(size 0.508)
		(drill 0.254)
		(layers "F.Cu" "B.Cu")
		(net "P0V9_CPU1_RT_2D")
	)
	(via
		(at 22.629368 -378.740924)
		(size 0.508)
		(drill 0.254)
		(layers "F.Cu" "B.Cu")
		(net "P0V9_CPU1_RT_2D")
	)
	(via
		(at 53.378608 -387.084062)
		(size 0.4064)
		(drill 0.2032)
		(layers "F.Cu" "B.Cu")
		(net "P0V9_CPU1_RT_2D")
	)
	(via
		(at 19.782282 -378.82576)
		(size 0.508)
		(drill 0.254)
		(layers "F.Cu" "B.Cu")
		(net "P0V9_CPU1_RT_2D")
	)
	(via
		(at 26.30297 -377.222512)
		(size 0.508)
		(drill 0.254)
		(layers "F.Cu" "B.Cu")
		(net "P0V9_CPU1_RT_2D")
	)
	(via
		(at 21.112734 -391.742676)
		(size 0.508)
		(drill 0.254)
		(layers "F.Cu" "B.Cu")
		(net "P0V9_CPU1_RT_2D")
	)
	(via
		(at 90.53322 -392.867896)
		(size 0.6604)
		(drill 0.3302)
		(layers "F.Cu" "B.Cu")
		(net "P0V9_CPU1_RT_2D")
	)
	(via
		(at 69.734684 -393.52093)
		(size 0.508)
		(drill 0.254)
		(layers "F.Cu" "B.Cu")
		(net "P0V9_CPU1_RT_2D")
	)
	(via
		(at 27.018234 -376.473974)
		(size 0.508)
		(drill 0.254)
		(layers "F.Cu" "B.Cu")
		(net "P0V9_CPU1_RT_2D")
	)
	(via
		(at 27.684984 -377.218702)
		(size 0.508)
		(drill 0.254)
		(layers "F.Cu" "B.Cu")
		(net "P0V9_CPU1_RT_2D")
	)
	(via
		(at 139.617196 -390.87806)
		(size 0.508)
		(drill 0.254)
		(layers "F.Cu" "B.Cu")
		(net "P0V9_CPU1_RT_2D")
	)
	(via
		(at 126.618492 -387.693662)
		(size 0.4064)
		(drill 0.2032)
		(layers "F.Cu" "B.Cu")
		(net "P0V9_CPU1_RT_2D")
	)
	(via
		(at 16.96339 -375.71045)
		(size 0.508)
		(drill 0.254)
		(layers "F.Cu" "B.Cu")
		(net "P0V9_CPU1_RT_2D")
	)
	(via
		(at 18.38706 -380.799594)
		(size 0.508)
		(drill 0.254)
		(layers "F.Cu" "B.Cu")
		(net "P0V9_CPU1_RT_2D")
	)
	(via
		(at 19.11223 -380.80696)
		(size 0.508)
		(drill 0.254)
		(layers "F.Cu" "B.Cu")
		(net "P0V9_CPU1_RT_2D")
	)
	(via
		(at 105.942892 -390.883394)
		(size 0.508)
		(drill 0.254)
		(layers "F.Cu" "B.Cu")
		(net "P0V9_CPU1_RT_2D")
	)
	(via
		(at 137.469626 -392.88593)
		(size 0.508)
		(drill 0.254)
		(layers "F.Cu" "B.Cu")
		(net "P0V9_CPU1_RT_2D")
	)
	(via
		(at 17.02054 -374.978168)
		(size 0.508)
		(drill 0.254)
		(layers "F.Cu" "B.Cu")
		(net "P0V9_CPU1_RT_2D")
	)
	(via
		(at 72.909684 -392.25093)
		(size 0.508)
		(drill 0.254)
		(layers "F.Cu" "B.Cu")
		(net "P0V9_CPU1_RT_2D")
	)
	(via
		(at 25.86609 -381.473202)
		(size 0.508)
		(drill 0.254)
		(layers "F.Cu" "B.Cu")
		(net "P0V9_CPU1_RT_2D")
	)
	(via
		(at 123.901454 -392.86815)
		(size 0.6604)
		(drill 0.3302)
		(layers "F.Cu" "B.Cu")
		(net "P0V9_CPU1_RT_2D")
	)
	(via
		(at 156.443934 -392.86815)
		(size 0.6604)
		(drill 0.3302)
		(layers "F.Cu" "B.Cu")
		(net "P0V9_CPU1_RT_2D")
	)
	(via
		(at 153.006298 -387.084062)
		(size 0.4064)
		(drill 0.2032)
		(layers "F.Cu" "B.Cu")
		(net "P0V9_CPU1_RT_2D")
	)
	(via
		(at 16.26362 -379.50013)
		(size 0.508)
		(drill 0.254)
		(layers "F.Cu" "B.Cu")
		(net "P0V9_CPU1_RT_2D")
	)
	(via
		(at 9.8171 -380.828804)
		(size 0.508)
		(drill 0.254)
		(layers "F.Cu" "B.Cu")
		(net "P0V9_CPU1_RT_2D")
	)
	(via
		(at 10.876788 -377.46305)
		(size 0.508)
		(drill 0.254)
		(layers "F.Cu" "B.Cu")
		(net "P0V9_CPU1_RT_2D")
	)
	(via
		(at 41.901364 -398.810734)
		(size 0.508)
		(drill 0.254)
		(layers "F.Cu" "B.Cu")
		(net "P0V9_CPU1_RT_2D")
	)
	(via
		(at 106.846878 -392.88593)
		(size 0.508)
		(drill 0.254)
		(layers "F.Cu" "B.Cu")
		(net "P0V9_CPU1_RT_2D")
	)
	(via
		(at 19.11223 -380.14656)
		(size 0.508)
		(drill 0.254)
		(layers "F.Cu" "B.Cu")
		(net "P0V9_CPU1_RT_2D")
	)
	(via
		(at 106.694478 -390.54913)
		(size 0.508)
		(drill 0.254)
		(layers "F.Cu" "B.Cu")
		(net "P0V9_CPU1_RT_2D")
	)
	(via
		(at 159.006286 -387.084062)
		(size 0.4064)
		(drill 0.2032)
		(layers "F.Cu" "B.Cu")
		(net "P0V9_CPU1_RT_2D")
	)
	(via
		(at 59.51855 -387.693662)
		(size 0.4064)
		(drill 0.2032)
		(layers "F.Cu" "B.Cu")
		(net "P0V9_CPU1_RT_2D")
	)
	(via
		(at 71.639684 -392.88593)
		(size 0.508)
		(drill 0.254)
		(layers "F.Cu" "B.Cu")
		(net "P0V9_CPU1_RT_2D")
	)
	(via
		(at 12.51331 -378.7013)
		(size 0.508)
		(drill 0.254)
		(layers "F.Cu" "B.Cu")
		(net "P0V9_CPU1_RT_2D")
	)
	(via
		(at 107.481878 -392.25093)
		(size 0.508)
		(drill 0.254)
		(layers "F.Cu" "B.Cu")
		(net "P0V9_CPU1_RT_2D")
	)
	(via
		(at 105.942892 -390.248394)
		(size 0.508)
		(drill 0.254)
		(layers "F.Cu" "B.Cu")
		(net "P0V9_CPU1_RT_2D")
	)
	(via
		(at 140.009626 -392.25093)
		(size 0.508)
		(drill 0.254)
		(layers "F.Cu" "B.Cu")
		(net "P0V9_CPU1_RT_2D")
	)
	(via
		(at 8.590788 -375.17705)
		(size 0.508)
		(drill 0.254)
		(layers "F.Cu" "B.Cu")
		(net "P0V9_CPU1_RT_2D")
	)
	(via
		(at 27.872182 -379.467618)
		(size 0.508)
		(drill 0.254)
		(layers "F.Cu" "B.Cu")
		(net "P0V9_CPU1_RT_2D")
	)
	(via
		(at 41.952164 -396.905734)
		(size 0.508)
		(drill 0.254)
		(layers "F.Cu" "B.Cu")
		(net "P0V9_CPU1_RT_2D")
	)
	(via
		(at 120.47855 -387.084062)
		(size 0.4064)
		(drill 0.2032)
		(layers "F.Cu" "B.Cu")
		(net "P0V9_CPU1_RT_2D")
	)
	(via
		(at 137.469626 -393.52093)
		(size 0.508)
		(drill 0.254)
		(layers "F.Cu" "B.Cu")
		(net "P0V9_CPU1_RT_2D")
	)
	(via
		(at 19.782282 -380.80696)
		(size 0.508)
		(drill 0.254)
		(layers "F.Cu" "B.Cu")
		(net "P0V9_CPU1_RT_2D")
	)
	(via
		(at 41.317164 -397.540734)
		(size 0.508)
		(drill 0.254)
		(layers "F.Cu" "B.Cu")
		(net "P0V9_CPU1_RT_2D")
	)
	(via
		(at 126.478538 -387.084062)
		(size 0.4064)
		(drill 0.2032)
		(layers "F.Cu" "B.Cu")
		(net "P0V9_CPU1_RT_2D")
	)
	(via
		(at 21.333714 -378.82576)
		(size 0.508)
		(drill 0.254)
		(layers "F.Cu" "B.Cu")
		(net "P0V9_CPU1_RT_2D")
	)
	(via
		(at 21.308568 -378.16536)
		(size 0.508)
		(drill 0.254)
		(layers "F.Cu" "B.Cu")
		(net "P0V9_CPU1_RT_2D")
	)
	(via
		(at 41.317164 -396.905734)
		(size 0.508)
		(drill 0.254)
		(layers "F.Cu" "B.Cu")
		(net "P0V9_CPU1_RT_2D")
	)
	(via
		(at 45.794168 -401.977606)
		(size 0.508)
		(drill 0.254)
		(layers "F.Cu" "B.Cu")
		(net "P0V9_CPU1_RT_2D")
	)
	(via
		(at 69.734684 -392.88593)
		(size 0.508)
		(drill 0.254)
		(layers "F.Cu" "B.Cu")
		(net "P0V9_CPU1_RT_2D")
	)
	(via
		(at 22.535388 -375.092214)
		(size 0.508)
		(drill 0.254)
		(layers "F.Cu" "B.Cu")
		(net "P0V9_CPU1_RT_2D")
	)
	(via
		(at 27.206448 -380.795784)
		(size 0.508)
		(drill 0.254)
		(layers "F.Cu" "B.Cu")
		(net "P0V9_CPU1_RT_2D")
	)
	(via
		(at 19.11223 -379.48616)
		(size 0.508)
		(drill 0.254)
		(layers "F.Cu" "B.Cu")
		(net "P0V9_CPU1_RT_2D")
	)
	(via
		(at 27.123136 -380.108968)
		(size 0.508)
		(drill 0.254)
		(layers "F.Cu" "B.Cu")
		(net "P0V9_CPU1_RT_2D")
	)
	(via
		(at 10.876788 -375.17705)
		(size 0.508)
		(drill 0.254)
		(layers "F.Cu" "B.Cu")
		(net "P0V9_CPU1_RT_2D")
	)
	(via
		(at 136.834626 -392.88593)
		(size 0.508)
		(drill 0.254)
		(layers "F.Cu" "B.Cu")
		(net "P0V9_CPU1_RT_2D")
	)
	(via
		(at 27.872182 -380.128018)
		(size 0.508)
		(drill 0.254)
		(layers "F.Cu" "B.Cu")
		(net "P0V9_CPU1_RT_2D")
	)
	(via
		(at 138.104626 -392.88593)
		(size 0.508)
		(drill 0.254)
		(layers "F.Cu" "B.Cu")
		(net "P0V9_CPU1_RT_2D")
	)
	(via
		(at 139.374626 -392.25093)
		(size 0.508)
		(drill 0.254)
		(layers "F.Cu" "B.Cu")
		(net "P0V9_CPU1_RT_2D")
	)
	(via
		(at 21.348954 -381.42926)
		(size 0.508)
		(drill 0.254)
		(layers "F.Cu" "B.Cu")
		(net "P0V9_CPU1_RT_2D")
	)
	(via
		(at 85.906356 -387.084062)
		(size 0.4064)
		(drill 0.2032)
		(layers "F.Cu" "B.Cu")
		(net "P0V9_CPU1_RT_2D")
	)
	(via
		(at 19.11223 -378.82576)
		(size 0.508)
		(drill 0.254)
		(layers "F.Cu" "B.Cu")
		(net "P0V9_CPU1_RT_2D")
	)
	(via
		(at 139.374626 -393.52093)
		(size 0.508)
		(drill 0.254)
		(layers "F.Cu" "B.Cu")
		(net "P0V9_CPU1_RT_2D")
	)
	(via
		(at 105.576878 -391.61593)
		(size 0.508)
		(drill 0.254)
		(layers "F.Cu" "B.Cu")
		(net "P0V9_CPU1_RT_2D")
	)
	(via
		(at 12.493752 -380.791974)
		(size 0.508)
		(drill 0.254)
		(layers "F.Cu" "B.Cu")
		(net "P0V9_CPU1_RT_2D")
	)
	(via
		(at 22.535388 -376.616214)
		(size 0.508)
		(drill 0.254)
		(layers "F.Cu" "B.Cu")
		(net "P0V9_CPU1_RT_2D")
	)
	(via
		(at 8.590788 -375.93905)
		(size 0.508)
		(drill 0.254)
		(layers "F.Cu" "B.Cu")
		(net "P0V9_CPU1_RT_2D")
	)
	(via
		(at 105.576878 -392.88593)
		(size 0.508)
		(drill 0.254)
		(layers "F.Cu" "B.Cu")
		(net "P0V9_CPU1_RT_2D")
	)
	(via
		(at 22.535388 -377.378214)
		(size 0.508)
		(drill 0.254)
		(layers "F.Cu" "B.Cu")
		(net "P0V9_CPU1_RT_2D")
	)
	(via
		(at 106.846878 -391.61593)
		(size 0.508)
		(drill 0.254)
		(layers "F.Cu" "B.Cu")
		(net "P0V9_CPU1_RT_2D")
	)
	(via
		(at 59.378596 -387.084062)
		(size 0.4064)
		(drill 0.2032)
		(layers "F.Cu" "B.Cu")
		(net "P0V9_CPU1_RT_2D")
	)
	(via
		(at 21.308568 -380.78156)
		(size 0.508)
		(drill 0.254)
		(layers "F.Cu" "B.Cu")
		(net "P0V9_CPU1_RT_2D")
	)
	(via
		(at 107.481878 -391.61593)
		(size 0.508)
		(drill 0.254)
		(layers "F.Cu" "B.Cu")
		(net "P0V9_CPU1_RT_2D")
	)
	(via
		(at 28.09367 -377.925584)
		(size 0.508)
		(drill 0.254)
		(layers "F.Cu" "B.Cu")
		(net "P0V9_CPU1_RT_2D")
	)
	(via
		(at 43.222164 -396.905734)
		(size 0.508)
		(drill 0.254)
		(layers "F.Cu" "B.Cu")
		(net "P0V9_CPU1_RT_2D")
	)
	(via
		(at 26.546048 -380.795784)
		(size 0.508)
		(drill 0.254)
		(layers "F.Cu" "B.Cu")
		(net "P0V9_CPU1_RT_2D")
	)
	(via
		(at 138.104626 -393.52093)
		(size 0.508)
		(drill 0.254)
		(layers "F.Cu" "B.Cu")
		(net "P0V9_CPU1_RT_2D")
	)
	(via
		(at 16.940784 -377.95454)
		(size 0.508)
		(drill 0.254)
		(layers "F.Cu" "B.Cu")
		(net "P0V9_CPU1_RT_2D")
	)
	(via
		(at 26.307034 -375.02719)
		(size 0.508)
		(drill 0.254)
		(layers "F.Cu" "B.Cu")
		(net "P0V9_CPU1_RT_2D")
	)
	(via
		(at 26.462736 -380.108968)
		(size 0.508)
		(drill 0.254)
		(layers "F.Cu" "B.Cu")
		(net "P0V9_CPU1_RT_2D")
	)
	(via
		(at 8.590788 -377.46305)
		(size 0.508)
		(drill 0.254)
		(layers "F.Cu" "B.Cu")
		(net "P0V9_CPU1_RT_2D")
	)
	(via
		(at 18.388584 -380.10846)
		(size 0.508)
		(drill 0.254)
		(layers "F.Cu" "B.Cu")
		(net "P0V9_CPU1_RT_2D")
	)
	(via
		(at 72.909684 -391.61593)
		(size 0.508)
		(drill 0.254)
		(layers "F.Cu" "B.Cu")
		(net "P0V9_CPU1_RT_2D")
	)
	(via
		(at 139.938506 -390.308084)
		(size 0.508)
		(drill 0.254)
		(layers "F.Cu" "B.Cu")
		(net "P0V9_CPU1_RT_2D")
	)
	(via
		(at 71.639684 -391.61593)
		(size 0.508)
		(drill 0.254)
		(layers "F.Cu" "B.Cu")
		(net "P0V9_CPU1_RT_2D")
	)
	(via
		(at 27.123136 -379.448568)
		(size 0.508)
		(drill 0.254)
		(layers "F.Cu" "B.Cu")
		(net "P0V9_CPU1_RT_2D")
	)
	(via
		(at 25.815036 -380.108968)
		(size 0.508)
		(drill 0.254)
		(layers "F.Cu" "B.Cu")
		(net "P0V9_CPU1_RT_2D")
	)
	(via
		(at 41.266364 -398.810734)
		(size 0.508)
		(drill 0.254)
		(layers "F.Cu" "B.Cu")
		(net "P0V9_CPU1_RT_2D")
	)
	(via
		(at 70.369684 -393.52093)
		(size 0.508)
		(drill 0.254)
		(layers "F.Cu" "B.Cu")
		(net "P0V9_CPU1_RT_2D")
	)
	(via
		(at 16.26362 -380.77013)
		(size 0.508)
		(drill 0.254)
		(layers "F.Cu" "B.Cu")
		(net "P0V9_CPU1_RT_2D")
	)
	(via
		(at 86.04631 -387.693662)
		(size 0.4064)
		(drill 0.2032)
		(layers "F.Cu" "B.Cu")
		(net "P0V9_CPU1_RT_2D")
	)
	(via
		(at 91.906344 -387.084062)
		(size 0.4064)
		(drill 0.2032)
		(layers "F.Cu" "B.Cu")
		(net "P0V9_CPU1_RT_2D")
	)
	(via
		(at 56.812434 -392.88847)
		(size 0.6604)
		(drill 0.3302)
		(layers "F.Cu" "B.Cu")
		(net "P0V9_CPU1_RT_2D")
	)
	(via
		(at 27.445462 -377.924822)
		(size 0.508)
		(drill 0.254)
		(layers "F.Cu" "B.Cu")
		(net "P0V9_CPU1_RT_2D")
	)
	(via
		(at 26.144474 -377.976638)
		(size 0.508)
		(drill 0.254)
		(layers "F.Cu" "B.Cu")
		(net "P0V9_CPU1_RT_2D")
	)
	(via
		(at 18.388584 -379.44806)
		(size 0.508)
		(drill 0.254)
		(layers "F.Cu" "B.Cu")
		(net "P0V9_CPU1_RT_2D")
	)
	(via
		(at 19.782282 -379.48616)
		(size 0.508)
		(drill 0.254)
		(layers "F.Cu" "B.Cu")
		(net "P0V9_CPU1_RT_2D")
	)
	(via
		(at 14.67358 -377.963938)
		(size 0.508)
		(drill 0.254)
		(layers "F.Cu" "B.Cu")
		(net "P0V9_CPU1_RT_2D")
	)
	(via
		(at 27.123136 -378.788168)
		(size 0.508)
		(drill 0.254)
		(layers "F.Cu" "B.Cu")
		(net "P0V9_CPU1_RT_2D")
	)
	(via
		(at 138.739626 -392.88593)
		(size 0.508)
		(drill 0.254)
		(layers "F.Cu" "B.Cu")
		(net "P0V9_CPU1_RT_2D")
	)
	(segment
		(start 11.85926 -386.115814)
		(end 13.075158 -389.051038)
		(width 0.254)
		(layer "In15.Cu")
		(net "P0V9_CPU1_RT_2D")
	)
	(segment
		(start 21.92655 -386.432298)
		(end 23.140924 -385.217924)
		(width 0.254)
		(layer "In15.Cu")
		(net "P0V9_CPU1_RT_2D")
	)
	(segment
		(start 9.8171 -380.828804)
		(end 9.8171 -384.073654)
		(width 0.254)
		(layer "In15.Cu")
		(net "P0V9_CPU1_RT_2D")
	)
	(segment
		(start 139.409424 -389.81126)
		(end 138.30554 -389.81126)
		(width 0.254)
		(layer "In15.Cu")
		(net "P0V9_CPU1_RT_2D")
	)
	(segment
		(start 23.140924 -382.730502)
		(end 21.839682 -381.42926)
		(width 0.254)
		(layer "In15.Cu")
		(net "P0V9_CPU1_RT_2D")
	)
	(segment
		(start 21.92655 -388.700518)
		(end 21.92655 -386.432298)
		(width 0.254)
		(layer "In15.Cu")
		(net "P0V9_CPU1_RT_2D")
	)
	(segment
		(start 23.140924 -385.217924)
		(end 23.140924 -382.730502)
		(width 0.254)
		(layer "In15.Cu")
		(net "P0V9_CPU1_RT_2D")
	)
	(segment
		(start 13.075158 -391.873232)
		(end 12.274296 -392.674094)
		(width 0.254)
		(layer "In15.Cu")
		(net "P0V9_CPU1_RT_2D")
	)
	(segment
		(start 139.906248 -390.308084)
		(end 139.409424 -389.81126)
		(width 0.254)
		(layer "In15.Cu")
		(net "P0V9_CPU1_RT_2D")
	)
	(segment
		(start 21.112734 -391.742676)
		(end 21.353018 -391.742676)
		(width 0.254)
		(layer "In15.Cu")
		(net "P0V9_CPU1_RT_2D")
	)
	(segment
		(start 22.271228 -390.824466)
		(end 22.271228 -389.045196)
		(width 0.254)
		(layer "In15.Cu")
		(net "P0V9_CPU1_RT_2D")
	)
	(segment
		(start 22.271228 -389.045196)
		(end 21.92655 -388.700518)
		(width 0.254)
		(layer "In15.Cu")
		(net "P0V9_CPU1_RT_2D")
	)
	(segment
		(start 21.839682 -381.42926)
		(end 21.348954 -381.42926)
		(width 0.254)
		(layer "In15.Cu")
		(net "P0V9_CPU1_RT_2D")
	)
	(segment
		(start 13.075158 -389.051038)
		(end 13.075158 -391.873232)
		(width 0.254)
		(layer "In15.Cu")
		(net "P0V9_CPU1_RT_2D")
	)
	(segment
		(start 21.353018 -391.742676)
		(end 22.271228 -390.824466)
		(width 0.254)
		(layer "In15.Cu")
		(net "P0V9_CPU1_RT_2D")
	)
	(segment
		(start 9.8171 -384.073654)
		(end 11.85926 -386.115814)
		(width 0.254)
		(layer "In15.Cu")
		(net "P0V9_CPU1_RT_2D")
	)
	(segment
		(start 139.938506 -390.308084)
		(end 139.906248 -390.308084)
		(width 0.254)
		(layer "In15.Cu")
		(net "P0V9_CPU1_RT_2D")
	)
	(via
		(at 93.246194 -387.693662)
		(size 0.4064)
		(drill 0.2032)
		(layers "F.Cu" "B.Cu")
		(net "P0V9_CPU1_RT1_2A_2D")
	)
	(via
		(at 93.10624 -387.084062)
		(size 0.4064)
		(drill 0.2032)
		(layers "F.Cu" "B.Cu")
		(net "P0V9_CPU1_RT1_2A_2D")
	)
	(via
		(at 72.538844 -394.168376)
		(size 0.508)
		(drill 0.254)
		(layers "F.Cu" "B.Cu")
		(net "P0V9_CPU1_RT1_2A_2D")
	)
	(via
		(at 84.84616 -387.693662)
		(size 0.4064)
		(drill 0.2032)
		(layers "F.Cu" "B.Cu")
		(net "P0V9_CPU1_RT1_2A_2D")
	)
	(via
		(at 73.789286 -394.168376)
		(size 0.508)
		(drill 0.254)
		(layers "F.Cu" "B.Cu")
		(net "P0V9_CPU1_RT1_2A_2D")
	)
	(via
		(at 73.153016 -393.242546)
		(size 0.508)
		(drill 0.254)
		(layers "F.Cu" "B.Cu")
		(net "P0V9_CPU1_RT1_2A_2D")
	)
	(via
		(at 84.706206 -387.084062)
		(size 0.4064)
		(drill 0.2032)
		(layers "F.Cu" "B.Cu")
		(net "P0V9_CPU1_RT1_2A_2D")
	)
	(via
		(at 73.153016 -393.979146)
		(size 0.508)
		(drill 0.254)
		(layers "F.Cu" "B.Cu")
		(net "P0V9_CPU1_RT1_2A_2D")
	)
	(via
		(at 73.15073 -394.699236)
		(size 0.6604)
		(drill 0.3302)
		(layers "F.Cu" "B.Cu")
		(net "P0V9_CPU1_RT1_2A_2D")
	)
	(via
		(at 77.065124 -395.669008)
		(size 0.6604)
		(drill 0.3302)
		(layers "F.Cu" "B.Cu")
		(net "P0V9_CPU1_RT1_2A")
	)
	(via
		(at 81.106264 -387.084062)
		(size 0.4064)
		(drill 0.2032)
		(layers "F.Cu" "B.Cu")
		(net "P0V9_CPU1_RT1_2A")
	)
	(via
		(at 95.506286 -387.084062)
		(size 0.4064)
		(drill 0.2032)
		(layers "F.Cu" "B.Cu")
		(net "P0V9_CPU1_RT1_2A")
	)
	(via
		(at 95.64624 -387.693662)
		(size 0.4064)
		(drill 0.2032)
		(layers "F.Cu" "B.Cu")
		(net "P0V9_CPU1_RT1_2A")
	)
	(via
		(at 83.646264 -387.693662)
		(size 0.4064)
		(drill 0.2032)
		(layers "F.Cu" "B.Cu")
		(net "P0V9_CPU1_RT1_2A")
	)
	(via
		(at 74.654664 -393.52093)
		(size 0.508)
		(drill 0.254)
		(layers "F.Cu" "B.Cu")
		(net "P0V9_CPU1_RT1_2A")
	)
	(via
		(at 81.246218 -387.693662)
		(size 0.4064)
		(drill 0.2032)
		(layers "F.Cu" "B.Cu")
		(net "P0V9_CPU1_RT1_2A")
	)
	(via
		(at 94.988634 -396.12951)
		(size 0.6604)
		(drill 0.3302)
		(layers "F.Cu" "B.Cu")
		(net "P0V9_CPU1_RT1_2A")
	)
	(via
		(at 74.654664 -392.25093)
		(size 0.508)
		(drill 0.254)
		(layers "F.Cu" "B.Cu")
		(net "P0V9_CPU1_RT1_2A")
	)
	(via
		(at 75.924664 -392.88593)
		(size 0.508)
		(drill 0.254)
		(layers "F.Cu" "B.Cu")
		(net "P0V9_CPU1_RT1_2A")
	)
	(via
		(at 94.30639 -387.084062)
		(size 0.4064)
		(drill 0.2032)
		(layers "F.Cu" "B.Cu")
		(net "P0V9_CPU1_RT1_2A")
	)
	(via
		(at 79.906368 -387.084062)
		(size 0.4064)
		(drill 0.2032)
		(layers "F.Cu" "B.Cu")
		(net "P0V9_CPU1_RT1_2A")
	)
	(via
		(at 75.289664 -392.88593)
		(size 0.508)
		(drill 0.254)
		(layers "F.Cu" "B.Cu")
		(net "P0V9_CPU1_RT1_2A")
	)
	(via
		(at 75.924664 -393.52093)
		(size 0.508)
		(drill 0.254)
		(layers "F.Cu" "B.Cu")
		(net "P0V9_CPU1_RT1_2A")
	)
	(via
		(at 74.654664 -391.61593)
		(size 0.508)
		(drill 0.254)
		(layers "F.Cu" "B.Cu")
		(net "P0V9_CPU1_RT1_2A")
	)
	(via
		(at 82.446368 -387.693662)
		(size 0.4064)
		(drill 0.2032)
		(layers "F.Cu" "B.Cu")
		(net "P0V9_CPU1_RT1_2A")
	)
	(via
		(at 74.019664 -393.52093)
		(size 0.508)
		(drill 0.254)
		(layers "F.Cu" "B.Cu")
		(net "P0V9_CPU1_RT1_2A")
	)
	(via
		(at 75.924664 -392.25093)
		(size 0.508)
		(drill 0.254)
		(layers "F.Cu" "B.Cu")
		(net "P0V9_CPU1_RT1_2A")
	)
	(via
		(at 74.654664 -392.88593)
		(size 0.508)
		(drill 0.254)
		(layers "F.Cu" "B.Cu")
		(net "P0V9_CPU1_RT1_2A")
	)
	(via
		(at 74.019664 -392.88593)
		(size 0.508)
		(drill 0.254)
		(layers "F.Cu" "B.Cu")
		(net "P0V9_CPU1_RT1_2A")
	)
	(via
		(at 75.924664 -391.61593)
		(size 0.508)
		(drill 0.254)
		(layers "F.Cu" "B.Cu")
		(net "P0V9_CPU1_RT1_2A")
	)
	(via
		(at 83.50631 -387.084062)
		(size 0.4064)
		(drill 0.2032)
		(layers "F.Cu" "B.Cu")
		(net "P0V9_CPU1_RT1_2A")
	)
	(via
		(at 97.906332 -387.084062)
		(size 0.4064)
		(drill 0.2032)
		(layers "F.Cu" "B.Cu")
		(net "P0V9_CPU1_RT1_2A")
	)
	(via
		(at 99.805744 -395.562836)
		(size 0.6604)
		(drill 0.3302)
		(layers "F.Cu" "B.Cu")
		(net "P0V9_CPU1_RT1_2A")
	)
	(via
		(at 82.306414 -387.084062)
		(size 0.4064)
		(drill 0.2032)
		(layers "F.Cu" "B.Cu")
		(net "P0V9_CPU1_RT1_2A")
	)
	(via
		(at 96.84639 -387.693662)
		(size 0.4064)
		(drill 0.2032)
		(layers "F.Cu" "B.Cu")
		(net "P0V9_CPU1_RT1_2A")
	)
	(via
		(at 75.289664 -393.52093)
		(size 0.508)
		(drill 0.254)
		(layers "F.Cu" "B.Cu")
		(net "P0V9_CPU1_RT1_2A")
	)
	(via
		(at 94.446344 -387.693662)
		(size 0.4064)
		(drill 0.2032)
		(layers "F.Cu" "B.Cu")
		(net "P0V9_CPU1_RT1_2A")
	)
	(via
		(at 98.046286 -387.693662)
		(size 0.4064)
		(drill 0.2032)
		(layers "F.Cu" "B.Cu")
		(net "P0V9_CPU1_RT1_2A")
	)
	(via
		(at 74.019664 -392.25093)
		(size 0.508)
		(drill 0.254)
		(layers "F.Cu" "B.Cu")
		(net "P0V9_CPU1_RT1_2A")
	)
	(via
		(at 96.706436 -387.084062)
		(size 0.4064)
		(drill 0.2032)
		(layers "F.Cu" "B.Cu")
		(net "P0V9_CPU1_RT1_2A")
	)
	(via
		(at 80.046322 -387.693662)
		(size 0.4064)
		(drill 0.2032)
		(layers "F.Cu" "B.Cu")
		(net "P0V9_CPU1_RT1_2A")
	)
	(via
		(at 82.874358 -396.412974)
		(size 0.6604)
		(drill 0.3302)
		(layers "F.Cu" "B.Cu")
		(net "P0V9_CPU1_RT1_2A")
	)
	(via
		(at 75.289664 -392.25093)
		(size 0.508)
		(drill 0.254)
		(layers "F.Cu" "B.Cu")
		(net "P0V9_CPU1_RT1_2A")
	)
	(via
		(at 75.289664 -391.61593)
		(size 0.508)
		(drill 0.254)
		(layers "F.Cu" "B.Cu")
		(net "P0V9_CPU1_RT1_2A")
	)
	(via
		(at 74.019664 -391.61593)
		(size 0.508)
		(drill 0.254)
		(layers "F.Cu" "B.Cu")
		(net "P0V9_CPU1_RT1_2A")
	)
	(via
		(at 88.754204 -396.306548)
		(size 0.6604)
		(drill 0.3302)
		(layers "F.Cu" "B.Cu")
		(net "P0V9_CPU1_RT1_2A")
	)
	(via
		(at 60.578492 -387.084062)
		(size 0.4064)
		(drill 0.2032)
		(layers "F.Cu" "B.Cu")
		(net "P0V9_CPU1_RT0_2A_2D")
	)
	(via
		(at 45.359828 -398.67586)
		(size 0.508)
		(drill 0.254)
		(layers "F.Cu" "B.Cu")
		(net "P0V9_CPU1_RT0_2A_2D")
	)
	(via
		(at 46.25721 -399.35404)
		(size 0.6604)
		(drill 0.3302)
		(layers "F.Cu" "B.Cu")
		(net "P0V9_CPU1_RT0_2A_2D")
	)
	(via
		(at 45.996098 -400.33829)
		(size 0.508)
		(drill 0.254)
		(layers "F.Cu" "B.Cu")
		(net "P0V9_CPU1_RT0_2A_2D")
	)
	(via
		(at 45.359828 -400.14906)
		(size 0.508)
		(drill 0.254)
		(layers "F.Cu" "B.Cu")
		(net "P0V9_CPU1_RT0_2A_2D")
	)
	(via
		(at 52.178458 -387.084062)
		(size 0.4064)
		(drill 0.2032)
		(layers "F.Cu" "B.Cu")
		(net "P0V9_CPU1_RT0_2A_2D")
	)
	(via
		(at 45.359828 -399.41246)
		(size 0.508)
		(drill 0.254)
		(layers "F.Cu" "B.Cu")
		(net "P0V9_CPU1_RT0_2A_2D")
	)
	(via
		(at 60.718446 -387.693662)
		(size 0.4064)
		(drill 0.2032)
		(layers "F.Cu" "B.Cu")
		(net "P0V9_CPU1_RT0_2A_2D")
	)
	(via
		(at 52.318412 -387.693662)
		(size 0.4064)
		(drill 0.2032)
		(layers "F.Cu" "B.Cu")
		(net "P0V9_CPU1_RT0_2A_2D")
	)
	(via
		(at 48.578516 -387.084062)
		(size 0.4064)
		(drill 0.2032)
		(layers "F.Cu" "B.Cu")
		(net "P0V9_CPU1_RT0_2A")
	)
	(via
		(at 42.587164 -395.160754)
		(size 0.508)
		(drill 0.254)
		(layers "F.Cu" "B.Cu")
		(net "P0V9_CPU1_RT0_2A")
	)
	(via
		(at 47.518574 -387.693662)
		(size 0.4064)
		(drill 0.2032)
		(layers "F.Cu" "B.Cu")
		(net "P0V9_CPU1_RT0_2A")
	)
	(via
		(at 43.9547 -395.160754)
		(size 0.508)
		(drill 0.254)
		(layers "F.Cu" "B.Cu")
		(net "P0V9_CPU1_RT0_2A")
	)
	(via
		(at 48.71847 -387.693662)
		(size 0.4064)
		(drill 0.2032)
		(layers "F.Cu" "B.Cu")
		(net "P0V9_CPU1_RT0_2A")
	)
	(via
		(at 41.317164 -395.160754)
		(size 0.508)
		(drill 0.254)
		(layers "F.Cu" "B.Cu")
		(net "P0V9_CPU1_RT0_2A")
	)
	(via
		(at 47.37862 -387.084062)
		(size 0.4064)
		(drill 0.2032)
		(layers "F.Cu" "B.Cu")
		(net "P0V9_CPU1_RT0_2A")
	)
	(via
		(at 43.222164 -395.160754)
		(size 0.508)
		(drill 0.254)
		(layers "F.Cu" "B.Cu")
		(net "P0V9_CPU1_RT0_2A")
	)
	(via
		(at 63.817246 -396.377668)
		(size 0.6604)
		(drill 0.3302)
		(layers "F.Cu" "B.Cu")
		(net "P0V9_CPU1_RT0_2A")
	)
	(via
		(at 51.118516 -387.693662)
		(size 0.4064)
		(drill 0.2032)
		(layers "F.Cu" "B.Cu")
		(net "P0V9_CPU1_RT0_2A")
	)
	(via
		(at 41.952164 -394.525754)
		(size 0.508)
		(drill 0.254)
		(layers "F.Cu" "B.Cu")
		(net "P0V9_CPU1_RT0_2A")
	)
	(via
		(at 41.952164 -395.160754)
		(size 0.508)
		(drill 0.254)
		(layers "F.Cu" "B.Cu")
		(net "P0V9_CPU1_RT0_2A")
	)
	(via
		(at 49.778666 -387.084062)
		(size 0.4064)
		(drill 0.2032)
		(layers "F.Cu" "B.Cu")
		(net "P0V9_CPU1_RT0_2A")
	)
	(via
		(at 43.222164 -393.890754)
		(size 0.508)
		(drill 0.254)
		(layers "F.Cu" "B.Cu")
		(net "P0V9_CPU1_RT0_2A")
	)
	(via
		(at 41.952164 -393.890754)
		(size 0.508)
		(drill 0.254)
		(layers "F.Cu" "B.Cu")
		(net "P0V9_CPU1_RT0_2A")
	)
	(via
		(at 49.91862 -387.693662)
		(size 0.4064)
		(drill 0.2032)
		(layers "F.Cu" "B.Cu")
		(net "P0V9_CPU1_RT0_2A")
	)
	(via
		(at 62.978538 -387.084062)
		(size 0.4064)
		(drill 0.2032)
		(layers "F.Cu" "B.Cu")
		(net "P0V9_CPU1_RT0_2A")
	)
	(via
		(at 61.918596 -387.693662)
		(size 0.4064)
		(drill 0.2032)
		(layers "F.Cu" "B.Cu")
		(net "P0V9_CPU1_RT0_2A")
	)
	(via
		(at 50.978562 -387.084062)
		(size 0.4064)
		(drill 0.2032)
		(layers "F.Cu" "B.Cu")
		(net "P0V9_CPU1_RT0_2A")
	)
	(via
		(at 41.317164 -393.890754)
		(size 0.508)
		(drill 0.254)
		(layers "F.Cu" "B.Cu")
		(net "P0V9_CPU1_RT0_2A")
	)
	(via
		(at 41.317164 -394.525754)
		(size 0.508)
		(drill 0.254)
		(layers "F.Cu" "B.Cu")
		(net "P0V9_CPU1_RT0_2A")
	)
	(via
		(at 58.433208 -396.235936)
		(size 0.6604)
		(drill 0.3302)
		(layers "F.Cu" "B.Cu")
		(net "P0V9_CPU1_RT0_2A")
	)
	(via
		(at 50.923952 -395.562836)
		(size 0.6604)
		(drill 0.3302)
		(layers "F.Cu" "B.Cu")
		(net "P0V9_CPU1_RT0_2A")
	)
	(via
		(at 64.318642 -387.693662)
		(size 0.4064)
		(drill 0.2032)
		(layers "F.Cu" "B.Cu")
		(net "P0V9_CPU1_RT0_2A")
	)
	(via
		(at 45.752258 -394.146024)
		(size 0.6604)
		(drill 0.3302)
		(layers "F.Cu" "B.Cu")
		(net "P0V9_CPU1_RT0_2A")
	)
	(via
		(at 68.422012 -394.996162)
		(size 0.6604)
		(drill 0.3302)
		(layers "F.Cu" "B.Cu")
		(net "P0V9_CPU1_RT0_2A")
	)
	(via
		(at 42.587164 -393.890754)
		(size 0.508)
		(drill 0.254)
		(layers "F.Cu" "B.Cu")
		(net "P0V9_CPU1_RT0_2A")
	)
	(via
		(at 65.518538 -387.693662)
		(size 0.4064)
		(drill 0.2032)
		(layers "F.Cu" "B.Cu")
		(net "P0V9_CPU1_RT0_2A")
	)
	(via
		(at 43.222164 -394.525754)
		(size 0.508)
		(drill 0.254)
		(layers "F.Cu" "B.Cu")
		(net "P0V9_CPU1_RT0_2A")
	)
	(via
		(at 43.9547 -394.525754)
		(size 0.508)
		(drill 0.254)
		(layers "F.Cu" "B.Cu")
		(net "P0V9_CPU1_RT0_2A")
	)
	(via
		(at 64.178688 -387.084062)
		(size 0.4064)
		(drill 0.2032)
		(layers "F.Cu" "B.Cu")
		(net "P0V9_CPU1_RT0_2A")
	)
	(via
		(at 40.6781 -395.160754)
		(size 0.508)
		(drill 0.254)
		(layers "F.Cu" "B.Cu")
		(net "P0V9_CPU1_RT0_2A")
	)
	(via
		(at 40.6781 -394.525754)
		(size 0.508)
		(drill 0.254)
		(layers "F.Cu" "B.Cu")
		(net "P0V9_CPU1_RT0_2A")
	)
	(via
		(at 42.587164 -394.525754)
		(size 0.508)
		(drill 0.254)
		(layers "F.Cu" "B.Cu")
		(net "P0V9_CPU1_RT0_2A")
	)
	(via
		(at 61.778642 -387.084062)
		(size 0.4064)
		(drill 0.2032)
		(layers "F.Cu" "B.Cu")
		(net "P0V9_CPU1_RT0_2A")
	)
	(via
		(at 65.378584 -387.084062)
		(size 0.4064)
		(drill 0.2032)
		(layers "F.Cu" "B.Cu")
		(net "P0V9_CPU1_RT0_2A")
	)
	(via
		(at 63.118492 -387.693662)
		(size 0.4064)
		(drill 0.2032)
		(layers "F.Cu" "B.Cu")
		(net "P0V9_CPU1_RT0_2A")
	)
	(segment
		(start 78.14564 -383.92227)
		(end 77.900276 -383.676906)
		(width 0.254)
		(layer "F.Cu")
		(net "NCF_CPU1_P1_GND")
	)
	(segment
		(start 100.170742 -390.761474)
		(end 99.7458 -390.761474)
		(width 0.254)
		(layer "F.Cu")
		(net "NCF_CPU1_P1_GND")
	)
	(segment
		(start 77.988668 -391.09777)
		(end 78.14564 -390.940798)
		(width 0.254)
		(layer "F.Cu")
		(net "NCF_CPU1_P1_GND")
	)
	(segment
		(start 100.2284 -390.819132)
		(end 100.170742 -390.761474)
		(width 0.254)
		(layer "F.Cu")
		(net "NCF_CPU1_P1_GND")
	)
	(segment
		(start 78.895194 -392.33475)
		(end 79.022702 -392.33475)
		(width 0.254)
		(layer "F.Cu")
		(net "NCF_CPU1_P1_GND")
	)
	(segment
		(start 99.7458 -390.761474)
		(end 99.7458 -390.981184)
		(width 0.254)
		(layer "F.Cu")
		(net "NCF_CPU1_P1_GND")
	)
	(segment
		(start 78.445868 -391.281158)
		(end 78.445868 -391.885424)
		(width 0.254)
		(layer "F.Cu")
		(net "NCF_CPU1_P1_GND")
	)
	(segment
		(start 78.445868 -391.885424)
		(end 78.895194 -392.33475)
		(width 0.254)
		(layer "F.Cu")
		(net "NCF_CPU1_P1_GND")
	)
	(segment
		(start 78.745842 -383.92227)
		(end 78.14564 -383.92227)
		(width 0.254)
		(layer "F.Cu")
		(net "NCF_CPU1_P1_GND")
	)
	(segment
		(start 77.988668 -391.240518)
		(end 77.988668 -391.09777)
		(width 0.254)
		(layer "F.Cu")
		(net "NCF_CPU1_P1_GND")
	)
	(segment
		(start 99.411282 -383.368042)
		(end 99.411282 -382.86817)
		(width 0.254)
		(layer "F.Cu")
		(net "NCF_CPU1_P1_GND")
	)
	(segment
		(start 99.445826 -383.402586)
		(end 99.7458 -383.92227)
		(width 0.254)
		(layer "F.Cu")
		(net "NCF_CPU1_P1_GND")
	)
	(segment
		(start 99.445826 -383.402586)
		(end 99.411282 -383.368042)
		(width 0.254)
		(layer "F.Cu")
		(net "NCF_CPU1_P1_GND")
	)
	(segment
		(start 99.944682 -382.86817)
		(end 99.944682 -383.301494)
		(width 0.254)
		(layer "F.Cu")
		(net "NCF_CPU1_P1_GND")
	)
	(segment
		(start 78.14564 -390.940798)
		(end 78.14564 -390.761474)
		(width 0.254)
		(layer "F.Cu")
		(net "NCF_CPU1_P1_GND")
	)
	(segment
		(start 78.745842 -390.761474)
		(end 78.445868 -391.281158)
		(width 0.254)
		(layer "F.Cu")
		(net "NCF_CPU1_P1_GND")
	)
	(segment
		(start 99.944682 -383.301494)
		(end 100.045774 -383.402586)
		(width 0.254)
		(layer "F.Cu")
		(net "NCF_CPU1_P1_GND")
	)
	(segment
		(start 78.445868 -383.110994)
		(end 78.458822 -383.09804)
		(width 0.254)
		(layer "F.Cu")
		(net "NCF_CPU1_P1_GND")
	)
	(segment
		(start 77.900276 -383.676906)
		(end 77.900276 -382.848866)
		(width 0.254)
		(layer "F.Cu")
		(net "NCF_CPU1_P1_GND")
	)
	(segment
		(start 78.445868 -383.402586)
		(end 78.445868 -383.110994)
		(width 0.254)
		(layer "F.Cu")
		(net "NCF_CPU1_P1_GND")
	)
	(segment
		(start 78.458822 -383.09804)
		(end 78.458822 -382.89484)
		(width 0.254)
		(layer "F.Cu")
		(net "NCF_CPU1_P1_GND")
	)
	(segment
		(start 99.7458 -390.981184)
		(end 99.445826 -391.281158)
		(width 0.254)
		(layer "F.Cu")
		(net "NCF_CPU1_P1_GND")
	)
	(via
		(at 100.57892 -383.086864)
		(size 0.6604)
		(drill 0.3302)
		(layers "F.Cu" "B.Cu")
		(net "NCF_CPU1_P1_GND")
	)
	(via
		(at 99.411282 -382.86817)
		(size 0.4064)
		(drill 0.2032)
		(layers "F.Cu" "B.Cu")
		(net "NCF_CPU1_P1_GND")
	)
	(via
		(at 100.2284 -390.819132)
		(size 0.4064)
		(drill 0.2032)
		(layers "F.Cu" "B.Cu")
		(net "NCF_CPU1_P1_GND")
	)
	(via
		(at 78.458822 -382.89484)
		(size 0.4064)
		(drill 0.2032)
		(layers "F.Cu" "B.Cu")
		(net "NCF_CPU1_P1_GND")
	)
	(via
		(at 77.900276 -382.848866)
		(size 0.4064)
		(drill 0.2032)
		(layers "F.Cu" "B.Cu")
		(net "NCF_CPU1_P1_GND")
	)
	(via
		(at 99.944682 -382.86817)
		(size 0.4064)
		(drill 0.2032)
		(layers "F.Cu" "B.Cu")
		(net "NCF_CPU1_P1_GND")
	)
	(via
		(at 79.022702 -392.33475)
		(size 0.4064)
		(drill 0.2032)
		(layers "F.Cu" "B.Cu")
		(net "NCF_CPU1_P1_GND")
	)
	(via
		(at 77.988668 -391.240518)
		(size 0.4064)
		(drill 0.2032)
		(layers "F.Cu" "B.Cu")
		(net "NCF_CPU1_P1_GND")
	)
	(segment
		(start 101.509068 -394.6271)
		(end 101.14915 -394.987018)
		(width 0.10668)
		(layer "F.Cu")
		(net "NCF_A1_CPU1_P1_GND")
	)
	(segment
		(start 101.14915 -396.315184)
		(end 99.777804 -397.68653)
		(width 0.10668)
		(layer "F.Cu")
		(net "NCF_A1_CPU1_P1_GND")
	)
	(segment
		(start 99.777804 -397.68653)
		(end 99.35845 -397.68653)
		(width 0.10668)
		(layer "F.Cu")
		(net "NCF_A1_CPU1_P1_GND")
	)
	(segment
		(start 101.897434 -393.900152)
		(end 101.897434 -394.324078)
		(width 0.10668)
		(layer "F.Cu")
		(net "NCF_A1_CPU1_P1_GND")
	)
	(segment
		(start 101.897434 -394.324078)
		(end 101.594412 -394.6271)
		(width 0.10668)
		(layer "F.Cu")
		(net "NCF_A1_CPU1_P1_GND")
	)
	(segment
		(start 101.594412 -394.6271)
		(end 101.509068 -394.6271)
		(width 0.10668)
		(layer "F.Cu")
		(net "NCF_A1_CPU1_P1_GND")
	)
	(segment
		(start 101.14915 -394.987018)
		(end 101.14915 -396.315184)
		(width 0.10668)
		(layer "F.Cu")
		(net "NCF_A1_CPU1_P1_GND")
	)
	(segment
		(start 100.045774 -391.281158)
		(end 101.35489 -392.590274)
		(width 0.10668)
		(layer "F.Cu")
		(net "NCF_A1_CPU1_P1_GND")
	)
	(segment
		(start 101.35489 -392.590274)
		(end 101.897434 -393.900152)
		(width 0.10668)
		(layer "F.Cu")
		(net "NCF_A1_CPU1_P1_GND")
	)
	(via
		(at 99.35845 -397.68653)
		(size 0.762)
		(drill 0.381)
		(layers "F.Cu" "B.Cu")
		(net "NCF_A1_CPU1_P1_GND")
	)
	(segment
		(start 78.51902 -395.39418)
		(end 78.51902 -396.283434)
		(width 0.10668)
		(layer "F.Cu")
		(net "MODE_RT_CPU1_P1")
	)
	(segment
		(start 78.028546 -395.170152)
		(end 78.028546 -394.433552)
		(width 0.10668)
		(layer "F.Cu")
		(net "MODE_RT_CPU1_P1")
	)
	(segment
		(start 78.028546 -395.170152)
		(end 78.294992 -395.170152)
		(width 0.10668)
		(layer "F.Cu")
		(net "MODE_RT_CPU1_P1")
	)
	(segment
		(start 78.431644 -394.195808)
		(end 78.1939 -394.433552)
		(width 0.10668)
		(layer "F.Cu")
		(net "MODE_RT_CPU1_P1")
	)
	(segment
		(start 77.582268 -389.030972)
		(end 76.88072 -389.73252)
		(width 0.10668)
		(layer "F.Cu")
		(net "MODE_RT_CPU1_P1")
	)
	(segment
		(start 76.88072 -389.73252)
		(end 76.88072 -391.347452)
		(width 0.10668)
		(layer "F.Cu")
		(net "MODE_RT_CPU1_P1")
	)
	(segment
		(start 78.294992 -395.170152)
		(end 78.51902 -395.39418)
		(width 0.10668)
		(layer "F.Cu")
		(net "MODE_RT_CPU1_P1")
	)
	(segment
		(start 78.431644 -392.898376)
		(end 78.431644 -394.195808)
		(width 0.10668)
		(layer "F.Cu")
		(net "MODE_RT_CPU1_P1")
	)
	(segment
		(start 78.109826 -389.030972)
		(end 77.582268 -389.030972)
		(width 0.10668)
		(layer "F.Cu")
		(net "MODE_RT_CPU1_P1")
	)
	(segment
		(start 78.1939 -394.433552)
		(end 78.028546 -394.433552)
		(width 0.10668)
		(layer "F.Cu")
		(net "MODE_RT_CPU1_P1")
	)
	(segment
		(start 76.88072 -391.347452)
		(end 78.431644 -392.898376)
		(width 0.10668)
		(layer "F.Cu")
		(net "MODE_RT_CPU1_P1")
	)
	(segment
		(start 78.51902 -396.283434)
		(end 78.288388 -396.514066)
		(width 0.10668)
		(layer "F.Cu")
		(net "MODE_RT_CPU1_P1")
	)
	(via
		(at 78.288388 -396.514066)
		(size 0.762)
		(drill 0.381)
		(layers "F.Cu" "B.Cu")
		(net "MODE_RT_CPU1_P1")
	)
	(segment
		(start 77.750162 -389.330946)
		(end 77.177392 -389.903716)
		(width 0.10668)
		(layer "F.Cu")
		(net "JTAG_TEST_MODE_RT_CPU1_P1")
	)
	(segment
		(start 79.114904 -396.224506)
		(end 79.114904 -395.487906)
		(width 0.10668)
		(layer "F.Cu")
		(net "JTAG_TEST_MODE_RT_CPU1_P1")
	)
	(segment
		(start 77.177392 -391.189718)
		(end 79.884778 -393.897104)
		(width 0.10668)
		(layer "F.Cu")
		(net "JTAG_TEST_MODE_RT_CPU1_P1")
	)
	(segment
		(start 77.177392 -389.903716)
		(end 77.177392 -391.189718)
		(width 0.10668)
		(layer "F.Cu")
		(net "JTAG_TEST_MODE_RT_CPU1_P1")
	)
	(segment
		(start 79.645764 -395.487906)
		(end 79.951834 -395.181836)
		(width 0.10668)
		(layer "F.Cu")
		(net "JTAG_TEST_MODE_RT_CPU1_P1")
	)
	(segment
		(start 78.62951 -389.330946)
		(end 77.750162 -389.330946)
		(width 0.10668)
		(layer "F.Cu")
		(net "JTAG_TEST_MODE_RT_CPU1_P1")
	)
	(segment
		(start 79.884778 -395.11478)
		(end 79.951834 -395.181836)
		(width 0.10668)
		(layer "F.Cu")
		(net "JTAG_TEST_MODE_RT_CPU1_P1")
	)
	(segment
		(start 79.114904 -395.487906)
		(end 79.645764 -395.487906)
		(width 0.10668)
		(layer "F.Cu")
		(net "JTAG_TEST_MODE_RT_CPU1_P1")
	)
	(segment
		(start 79.884778 -393.897104)
		(end 79.884778 -395.11478)
		(width 0.10668)
		(layer "F.Cu")
		(net "JTAG_TEST_MODE_RT_CPU1_P1")
	)
	(via
		(at 79.951834 -395.181836)
		(size 0.762)
		(drill 0.381)
		(layers "F.Cu" "B.Cu")
		(net "JTAG_TEST_MODE_RT_CPU1_P1")
	)
	(segment
		(start 77.247242 -384.759962)
		(end 77.247242 -384.618992)
		(width 0.10668)
		(layer "F.Cu")
		(net "GPIO3_RT_CPU1_P1")
	)
	(segment
		(start 77.91831 -385.43103)
		(end 77.247242 -384.759962)
		(width 0.10668)
		(layer "F.Cu")
		(net "GPIO3_RT_CPU1_P1")
	)
	(segment
		(start 74.75982 -384.66268)
		(end 74.732896 -384.635756)
		(width 0.10668)
		(layer "F.Cu")
		(net "GPIO3_RT_CPU1_P1")
	)
	(segment
		(start 76.83119 -384.20294)
		(end 75.68438 -384.20294)
		(width 0.10668)
		(layer "F.Cu")
		(net "GPIO3_RT_CPU1_P1")
	)
	(segment
		(start 75.5269 -384.36042)
		(end 75.5269 -384.66268)
		(width 0.10668)
		(layer "F.Cu")
		(net "GPIO3_RT_CPU1_P1")
	)
	(segment
		(start 78.109826 -385.43103)
		(end 77.91831 -385.43103)
		(width 0.10668)
		(layer "F.Cu")
		(net "GPIO3_RT_CPU1_P1")
	)
	(segment
		(start 75.68438 -384.20294)
		(end 75.5269 -384.36042)
		(width 0.10668)
		(layer "F.Cu")
		(net "GPIO3_RT_CPU1_P1")
	)
	(segment
		(start 77.247242 -384.618992)
		(end 76.83119 -384.20294)
		(width 0.10668)
		(layer "F.Cu")
		(net "GPIO3_RT_CPU1_P1")
	)
	(segment
		(start 75.5269 -384.66268)
		(end 74.75982 -384.66268)
		(width 0.10668)
		(layer "F.Cu")
		(net "GPIO3_RT_CPU1_P1")
	)
	(via
		(at 74.732896 -384.635756)
		(size 0.762)
		(drill 0.381)
		(layers "F.Cu" "B.Cu")
		(net "GPIO3_RT_CPU1_P1")
	)
	(segment
		(start 77.08519 -385.856734)
		(end 77.259434 -386.030978)
		(width 0.10668)
		(layer "F.Cu")
		(net "GPIO2_RT_CPU1_P1")
	)
	(segment
		(start 74.7903 -385.48056)
		(end 75.068176 -385.48056)
		(width 0.10668)
		(layer "F.Cu")
		(net "GPIO2_RT_CPU1_P1")
	)
	(segment
		(start 75.169776 -385.58216)
		(end 75.5269 -385.58216)
		(width 0.10668)
		(layer "F.Cu")
		(net "GPIO2_RT_CPU1_P1")
	)
	(segment
		(start 73.67016 -385.98348)
		(end 73.52284 -386.1308)
		(width 0.10668)
		(layer "F.Cu")
		(net "GPIO2_RT_CPU1_P1")
	)
	(segment
		(start 75.5269 -385.58216)
		(end 75.5269 -385.277106)
		(width 0.10668)
		(layer "F.Cu")
		(net "GPIO2_RT_CPU1_P1")
	)
	(segment
		(start 75.068176 -385.48056)
		(end 75.169776 -385.58216)
		(width 0.10668)
		(layer "F.Cu")
		(net "GPIO2_RT_CPU1_P1")
	)
	(segment
		(start 77.259434 -386.030978)
		(end 78.109826 -386.030978)
		(width 0.10668)
		(layer "F.Cu")
		(net "GPIO2_RT_CPU1_P1")
	)
	(segment
		(start 75.681586 -385.12242)
		(end 76.88834 -385.12242)
		(width 0.10668)
		(layer "F.Cu")
		(net "GPIO2_RT_CPU1_P1")
	)
	(segment
		(start 75.5269 -385.277106)
		(end 75.681586 -385.12242)
		(width 0.10668)
		(layer "F.Cu")
		(net "GPIO2_RT_CPU1_P1")
	)
	(segment
		(start 77.08519 -385.31927)
		(end 77.08519 -385.856734)
		(width 0.10668)
		(layer "F.Cu")
		(net "GPIO2_RT_CPU1_P1")
	)
	(segment
		(start 74.630026 -385.98348)
		(end 73.67016 -385.98348)
		(width 0.10668)
		(layer "F.Cu")
		(net "GPIO2_RT_CPU1_P1")
	)
	(segment
		(start 74.7903 -385.48056)
		(end 74.7903 -385.823206)
		(width 0.10668)
		(layer "F.Cu")
		(net "GPIO2_RT_CPU1_P1")
	)
	(segment
		(start 74.7903 -385.823206)
		(end 74.630026 -385.98348)
		(width 0.10668)
		(layer "F.Cu")
		(net "GPIO2_RT_CPU1_P1")
	)
	(segment
		(start 76.88834 -385.12242)
		(end 77.08519 -385.31927)
		(width 0.10668)
		(layer "F.Cu")
		(net "GPIO2_RT_CPU1_P1")
	)
	(via
		(at 73.52284 -386.1308)
		(size 0.762)
		(drill 0.381)
		(layers "F.Cu" "B.Cu")
		(net "GPIO2_RT_CPU1_P1")
	)
	(segment
		(start 42.999152 -383.418588)
		(end 43.210226 -383.207514)
		(width 0.10668)
		(layer "F.Cu")
		(net "TEST2_RT_CPU1_P0")
	)
	(segment
		(start 42.008552 -383.7432)
		(end 42.008552 -383.82829)
		(width 0.10668)
		(layer "F.Cu")
		(net "TEST2_RT_CPU1_P0")
	)
	(segment
		(start 45.407072 -385.131056)
		(end 46.101762 -385.131056)
		(width 0.10668)
		(layer "F.Cu")
		(net "TEST2_RT_CPU1_P0")
	)
	(segment
		(start 44.184316 -383.207514)
		(end 44.976288 -383.999486)
		(width 0.10668)
		(layer "F.Cu")
		(net "TEST2_RT_CPU1_P0")
	)
	(segment
		(start 42.999152 -383.7432)
		(end 42.999152 -383.418588)
		(width 0.10668)
		(layer "F.Cu")
		(net "TEST2_RT_CPU1_P0")
	)
	(segment
		(start 44.976288 -383.999486)
		(end 44.976288 -384.700272)
		(width 0.10668)
		(layer "F.Cu")
		(net "TEST2_RT_CPU1_P0")
	)
	(segment
		(start 42.008552 -383.7432)
		(end 42.999152 -383.7432)
		(width 0.10668)
		(layer "F.Cu")
		(net "TEST2_RT_CPU1_P0")
	)
	(segment
		(start 44.976288 -384.700272)
		(end 45.407072 -385.131056)
		(width 0.10668)
		(layer "F.Cu")
		(net "TEST2_RT_CPU1_P0")
	)
	(segment
		(start 42.008552 -383.82829)
		(end 41.201086 -384.635756)
		(width 0.10668)
		(layer "F.Cu")
		(net "TEST2_RT_CPU1_P0")
	)
	(segment
		(start 43.210226 -383.207514)
		(end 44.184316 -383.207514)
		(width 0.10668)
		(layer "F.Cu")
		(net "TEST2_RT_CPU1_P0")
	)
	(segment
		(start 41.201086 -384.635756)
		(end 40.935148 -384.635756)
		(width 0.10668)
		(layer "F.Cu")
		(net "TEST2_RT_CPU1_P0")
	)
	(via
		(at 40.935148 -384.635756)
		(size 0.762)
		(drill 0.381)
		(layers "F.Cu" "B.Cu")
		(net "TEST2_RT_CPU1_P0")
	)
	(segment
		(start 44.979844 -385.602734)
		(end 45.232574 -385.602734)
		(width 0.10668)
		(layer "F.Cu")
		(net "TEST1_RT_CPU1_P0")
	)
	(segment
		(start 45.360844 -385.731004)
		(end 46.101762 -385.731004)
		(width 0.10668)
		(layer "F.Cu")
		(net "TEST1_RT_CPU1_P0")
	)
	(segment
		(start 45.232574 -385.602734)
		(end 45.360844 -385.731004)
		(width 0.10668)
		(layer "F.Cu")
		(net "TEST1_RT_CPU1_P0")
	)
	(via
		(at 44.979844 -385.602734)
		(size 0.4064)
		(drill 0.2032)
		(layers "F.Cu" "B.Cu")
		(net "TEST1_RT_CPU1_P0")
	)
	(via
		(at 44.77131 -384.943096)
		(size 0.6604)
		(drill 0.3302)
		(layers "F.Cu" "B.Cu")
		(net "TEST1_RT_CPU1_P0")
	)
	(segment
		(start 43.555412 -385.12242)
		(end 43.532552 -385.09956)
		(width 0.10668)
		(layer "B.Cu")
		(net "TEST1_RT_CPU1_P0")
	)
	(segment
		(start 42.999152 -384.28676)
		(end 42.999152 -384.468624)
		(width 0.10668)
		(layer "B.Cu")
		(net "TEST1_RT_CPU1_P0")
	)
	(segment
		(start 42.999152 -384.468624)
		(end 43.532552 -385.002024)
		(width 0.10668)
		(layer "B.Cu")
		(net "TEST1_RT_CPU1_P0")
	)
	(segment
		(start 44.979844 -385.602734)
		(end 44.979844 -385.15163)
		(width 0.10668)
		(layer "B.Cu")
		(net "TEST1_RT_CPU1_P0")
	)
	(segment
		(start 44.77131 -384.943096)
		(end 44.591986 -385.12242)
		(width 0.10668)
		(layer "B.Cu")
		(net "TEST1_RT_CPU1_P0")
	)
	(segment
		(start 44.979844 -385.15163)
		(end 44.77131 -384.943096)
		(width 0.10668)
		(layer "B.Cu")
		(net "TEST1_RT_CPU1_P0")
	)
	(segment
		(start 43.532552 -385.002024)
		(end 43.532552 -385.09956)
		(width 0.10668)
		(layer "B.Cu")
		(net "TEST1_RT_CPU1_P0")
	)
	(segment
		(start 44.591986 -385.12242)
		(end 43.555412 -385.12242)
		(width 0.10668)
		(layer "B.Cu")
		(net "TEST1_RT_CPU1_P0")
	)
	(segment
		(start 45.240194 -386.330952)
		(end 45.081698 -386.489448)
		(width 0.10668)
		(layer "F.Cu")
		(net "TEST0_RT_CPU1_P0")
	)
	(segment
		(start 46.101762 -386.330952)
		(end 45.240194 -386.330952)
		(width 0.10668)
		(layer "F.Cu")
		(net "TEST0_RT_CPU1_P0")
	)
	(via
		(at 45.081698 -386.489448)
		(size 0.4064)
		(drill 0.2032)
		(layers "F.Cu" "B.Cu")
		(net "TEST0_RT_CPU1_P0")
	)
	(via
		(at 44.35602 -386.72516)
		(size 0.6604)
		(drill 0.3302)
		(layers "F.Cu" "B.Cu")
		(net "TEST0_RT_CPU1_P0")
	)
	(segment
		(start 42.999152 -386.097272)
		(end 43.532552 -386.630672)
		(width 0.10668)
		(layer "B.Cu")
		(net "TEST0_RT_CPU1_P0")
	)
	(segment
		(start 44.591732 -386.489448)
		(end 44.35602 -386.72516)
		(width 0.10668)
		(layer "B.Cu")
		(net "TEST0_RT_CPU1_P0")
	)
	(segment
		(start 43.532552 -386.630672)
		(end 43.532552 -386.72516)
		(width 0.10668)
		(layer "B.Cu")
		(net "TEST0_RT_CPU1_P0")
	)
	(segment
		(start 45.081698 -386.489448)
		(end 44.591732 -386.489448)
		(width 0.10668)
		(layer "B.Cu")
		(net "TEST0_RT_CPU1_P0")
	)
	(segment
		(start 44.35602 -386.72516)
		(end 43.532552 -386.72516)
		(width 0.10668)
		(layer "B.Cu")
		(net "TEST0_RT_CPU1_P0")
	)
	(segment
		(start 42.999152 -385.91236)
		(end 42.999152 -386.097272)
		(width 0.10668)
		(layer "B.Cu")
		(net "TEST0_RT_CPU1_P0")
	)
	(segment
		(start 41.548304 -390.261602)
		(end 41.2877 -390.522206)
		(width 0.10668)
		(layer "F.Cu")
		(net "MODE_RT_CPU1_P0")
	)
	(segment
		(start 41.2877 -390.522206)
		(end 41.2877 -390.652)
		(width 0.10668)
		(layer "F.Cu")
		(net "MODE_RT_CPU1_P0")
	)
	(segment
		(start 45.582078 -389.030972)
		(end 45.089318 -389.030972)
		(width 0.10668)
		(layer "F.Cu")
		(net "MODE_RT_CPU1_P0")
	)
	(segment
		(start 44.23029 -389.89)
		(end 42.6466 -389.89)
		(width 0.10668)
		(layer "F.Cu")
		(net "MODE_RT_CPU1_P0")
	)
	(segment
		(start 45.089318 -389.030972)
		(end 44.23029 -389.89)
		(width 0.10668)
		(layer "F.Cu")
		(net "MODE_RT_CPU1_P0")
	)
	(segment
		(start 42.274998 -390.261602)
		(end 41.548304 -390.261602)
		(width 0.10668)
		(layer "F.Cu")
		(net "MODE_RT_CPU1_P0")
	)
	(segment
		(start 41.275 -390.6647)
		(end 41.2877 -390.652)
		(width 0.10668)
		(layer "F.Cu")
		(net "MODE_RT_CPU1_P0")
	)
	(segment
		(start 40.386 -390.6647)
		(end 41.275 -390.6647)
		(width 0.10668)
		(layer "F.Cu")
		(net "MODE_RT_CPU1_P0")
	)
	(segment
		(start 42.6466 -389.89)
		(end 42.274998 -390.261602)
		(width 0.10668)
		(layer "F.Cu")
		(net "MODE_RT_CPU1_P0")
	)
	(via
		(at 42.6466 -389.89)
		(size 0.762)
		(drill 0.381)
		(layers "F.Cu" "B.Cu")
		(net "MODE_RT_CPU1_P0")
	)
	(segment
		(start 40.9956 -391.5029)
		(end 41.2877 -391.795)
		(width 0.10668)
		(layer "F.Cu")
		(net "JTAG_TEST_MODE_RT_CPU1_P0")
	)
	(segment
		(start 44.359322 -390.219438)
		(end 43.587162 -390.219438)
		(width 0.10668)
		(layer "F.Cu")
		(net "JTAG_TEST_MODE_RT_CPU1_P0")
	)
	(segment
		(start 42.6466 -391.853674)
		(end 42.6466 -391.16)
		(width 0.10668)
		(layer "F.Cu")
		(net "JTAG_TEST_MODE_RT_CPU1_P0")
	)
	(segment
		(start 41.2877 -391.978388)
		(end 41.477692 -392.16838)
		(width 0.10668)
		(layer "F.Cu")
		(net "JTAG_TEST_MODE_RT_CPU1_P0")
	)
	(segment
		(start 43.587162 -390.219438)
		(end 42.6466 -391.16)
		(width 0.10668)
		(layer "F.Cu")
		(net "JTAG_TEST_MODE_RT_CPU1_P0")
	)
	(segment
		(start 45.247814 -389.330946)
		(end 44.359322 -390.219438)
		(width 0.10668)
		(layer "F.Cu")
		(net "JTAG_TEST_MODE_RT_CPU1_P0")
	)
	(segment
		(start 41.477692 -392.16838)
		(end 42.331894 -392.16838)
		(width 0.10668)
		(layer "F.Cu")
		(net "JTAG_TEST_MODE_RT_CPU1_P0")
	)
	(segment
		(start 42.331894 -392.16838)
		(end 42.6466 -391.853674)
		(width 0.10668)
		(layer "F.Cu")
		(net "JTAG_TEST_MODE_RT_CPU1_P0")
	)
	(segment
		(start 40.386 -391.5029)
		(end 40.9956 -391.5029)
		(width 0.10668)
		(layer "F.Cu")
		(net "JTAG_TEST_MODE_RT_CPU1_P0")
	)
	(segment
		(start 46.101762 -389.330946)
		(end 45.247814 -389.330946)
		(width 0.10668)
		(layer "F.Cu")
		(net "JTAG_TEST_MODE_RT_CPU1_P0")
	)
	(segment
		(start 41.2877 -391.795)
		(end 41.2877 -391.978388)
		(width 0.10668)
		(layer "F.Cu")
		(net "JTAG_TEST_MODE_RT_CPU1_P0")
	)
	(via
		(at 42.6466 -391.16)
		(size 0.762)
		(drill 0.381)
		(layers "F.Cu" "B.Cu")
		(net "JTAG_TEST_MODE_RT_CPU1_P0")
	)
	(segment
		(start 44.719494 -384.618992)
		(end 44.303442 -384.20294)
		(width 0.10668)
		(layer "F.Cu")
		(net "GPIO3_RT_CPU1_P0")
	)
	(segment
		(start 45.582078 -385.43103)
		(end 45.390562 -385.43103)
		(width 0.10668)
		(layer "F.Cu")
		(net "GPIO3_RT_CPU1_P0")
	)
	(segment
		(start 45.390562 -385.43103)
		(end 44.719494 -384.759962)
		(width 0.10668)
		(layer "F.Cu")
		(net "GPIO3_RT_CPU1_P0")
	)
	(segment
		(start 42.999152 -384.36042)
		(end 42.999152 -384.66268)
		(width 0.10668)
		(layer "F.Cu")
		(net "GPIO3_RT_CPU1_P0")
	)
	(segment
		(start 44.719494 -384.759962)
		(end 44.719494 -384.618992)
		(width 0.10668)
		(layer "F.Cu")
		(net "GPIO3_RT_CPU1_P0")
	)
	(segment
		(start 42.999152 -384.66268)
		(end 42.20972 -384.66268)
		(width 0.10668)
		(layer "F.Cu")
		(net "GPIO3_RT_CPU1_P0")
	)
	(segment
		(start 43.156632 -384.20294)
		(end 42.999152 -384.36042)
		(width 0.10668)
		(layer "F.Cu")
		(net "GPIO3_RT_CPU1_P0")
	)
	(segment
		(start 44.303442 -384.20294)
		(end 43.156632 -384.20294)
		(width 0.10668)
		(layer "F.Cu")
		(net "GPIO3_RT_CPU1_P0")
	)
	(via
		(at 42.20972 -384.66268)
		(size 0.762)
		(drill 0.381)
		(layers "F.Cu" "B.Cu")
		(net "GPIO3_RT_CPU1_P0")
	)
	(segment
		(start 41.745154 -386.005324)
		(end 40.97147 -386.325872)
		(width 0.10668)
		(layer "F.Cu")
		(net "GPIO2_RT_CPU1_P0")
	)
	(segment
		(start 44.557442 -385.856734)
		(end 44.731686 -386.030978)
		(width 0.10668)
		(layer "F.Cu")
		(net "GPIO2_RT_CPU1_P0")
	)
	(segment
		(start 42.262552 -385.58216)
		(end 42.262552 -385.822698)
		(width 0.10668)
		(layer "F.Cu")
		(net "GPIO2_RT_CPU1_P0")
	)
	(segment
		(start 42.262552 -385.58216)
		(end 42.999152 -385.58216)
		(width 0.10668)
		(layer "F.Cu")
		(net "GPIO2_RT_CPU1_P0")
	)
	(segment
		(start 44.360592 -385.12242)
		(end 44.557442 -385.31927)
		(width 0.10668)
		(layer "F.Cu")
		(net "GPIO2_RT_CPU1_P0")
	)
	(segment
		(start 42.999152 -385.58216)
		(end 42.999152 -385.277106)
		(width 0.10668)
		(layer "F.Cu")
		(net "GPIO2_RT_CPU1_P0")
	)
	(segment
		(start 40.97147 -386.325872)
		(end 40.112442 -386.325872)
		(width 0.10668)
		(layer "F.Cu")
		(net "GPIO2_RT_CPU1_P0")
	)
	(segment
		(start 43.153838 -385.12242)
		(end 44.360592 -385.12242)
		(width 0.10668)
		(layer "F.Cu")
		(net "GPIO2_RT_CPU1_P0")
	)
	(segment
		(start 44.731686 -386.030978)
		(end 45.582078 -386.030978)
		(width 0.10668)
		(layer "F.Cu")
		(net "GPIO2_RT_CPU1_P0")
	)
	(segment
		(start 42.999152 -385.277106)
		(end 43.153838 -385.12242)
		(width 0.10668)
		(layer "F.Cu")
		(net "GPIO2_RT_CPU1_P0")
	)
	(segment
		(start 42.262552 -385.822698)
		(end 42.079926 -386.005324)
		(width 0.10668)
		(layer "F.Cu")
		(net "GPIO2_RT_CPU1_P0")
	)
	(segment
		(start 44.557442 -385.31927)
		(end 44.557442 -385.856734)
		(width 0.10668)
		(layer "F.Cu")
		(net "GPIO2_RT_CPU1_P0")
	)
	(segment
		(start 42.079926 -386.005324)
		(end 41.745154 -386.005324)
		(width 0.10668)
		(layer "F.Cu")
		(net "GPIO2_RT_CPU1_P0")
	)
	(via
		(at 40.112442 -386.325872)
		(size 0.762)
		(drill 0.381)
		(layers "F.Cu" "B.Cu")
		(net "GPIO2_RT_CPU1_P0")
	)
	(via
		(at 20.238466 -407.743406)
		(size 0.6604)
		(drill 0.3302)
		(layers "F.Cu" "B.Cu")
		(net "TP_P0V9_RETIMER_CPU1_VRHOT")
	)
	(segment
		(start 19.834098 -407.743406)
		(end 19.727418 -407.850086)
		(width 0.10668)
		(layer "B.Cu")
		(net "TP_P0V9_RETIMER_CPU1_VRHOT")
	)
	(segment
		(start 20.238466 -407.743406)
		(end 19.834098 -407.743406)
		(width 0.10668)
		(layer "B.Cu")
		(net "TP_P0V9_RETIMER_CPU1_VRHOT")
	)
	(segment
		(start 19.727418 -407.850086)
		(end 19.727418 -408.64282)
		(width 0.10668)
		(layer "B.Cu")
		(net "TP_P0V9_RETIMER_CPU1_VRHOT")
	)
	(segment
		(start 20.743418 -408.248358)
		(end 20.238466 -407.743406)
		(width 0.10668)
		(layer "B.Cu")
		(net "TP_P0V9_RETIMER_CPU1_VRHOT")
	)
	(segment
		(start 20.743418 -408.64282)
		(end 20.743418 -408.248358)
		(width 0.10668)
		(layer "B.Cu")
		(net "TP_P0V9_RETIMER_CPU1_VRHOT")
	)
	(segment
		(start 19.14652 -412.909258)
		(end 17.95018 -411.712918)
		(width 0.13462)
		(layer "F.Cu")
		(net "TP_P0V9_RETIMER_CPU1_SVID_ALERT_N")
	)
	(segment
		(start 20.080732 -412.850584)
		(end 19.515328 -413.415988)
		(width 0.13462)
		(layer "F.Cu")
		(net "TP_P0V9_RETIMER_CPU1_SVID_ALERT_N")
	)
	(segment
		(start 17.95018 -411.712918)
		(end 17.580864 -411.712918)
		(width 0.13462)
		(layer "F.Cu")
		(net "TP_P0V9_RETIMER_CPU1_SVID_ALERT_N")
	)
	(segment
		(start 19.515328 -413.415988)
		(end 19.14652 -413.415988)
		(width 0.13462)
		(layer "F.Cu")
		(net "TP_P0V9_RETIMER_CPU1_SVID_ALERT_N")
	)
	(segment
		(start 19.14652 -413.415988)
		(end 19.14652 -412.909258)
		(width 0.13462)
		(layer "F.Cu")
		(net "TP_P0V9_RETIMER_CPU1_SVID_ALERT_N")
	)
	(via
		(at 19.14652 -413.415988)
		(size 0.508)
		(drill 0.254)
		(layers "F.Cu" "B.Cu")
		(net "TP_P0V9_RETIMER_CPU1_SVID_ALERT_N")
	)
	(segment
		(start 20.080732 -412.850584)
		(end 19.711924 -412.850584)
		(width 0.1524)
		(layer "B.Cu")
		(net "TP_P0V9_RETIMER_CPU1_SVID_ALERT_N")
	)
	(segment
		(start 19.711924 -412.850584)
		(end 19.14652 -413.415988)
		(width 0.1524)
		(layer "B.Cu")
		(net "TP_P0V9_RETIMER_CPU1_SVID_ALERT_N")
	)
	(via
		(at 441.78601 -426.070776)
		(size 0.6604)
		(drill 0.3302)
		(layers "F.Cu" "B.Cu")
		(net "TP_P0V9_RETIMER_CPU0_VRHOT")
	)
	(segment
		(start 441.78601 -426.15358)
		(end 441.51296 -426.42663)
		(width 0.10668)
		(layer "B.Cu")
		(net "TP_P0V9_RETIMER_CPU0_VRHOT")
	)
	(segment
		(start 440.328558 -425.584874)
		(end 440.444382 -425.700698)
		(width 0.10668)
		(layer "B.Cu")
		(net "TP_P0V9_RETIMER_CPU0_VRHOT")
	)
	(segment
		(start 440.194954 -426.277278)
		(end 439.995818 -426.476414)
		(width 0.10668)
		(layer "B.Cu")
		(net "TP_P0V9_RETIMER_CPU0_VRHOT")
	)
	(segment
		(start 438.766966 -426.349414)
		(end 438.766966 -425.584874)
		(width 0.10668)
		(layer "B.Cu")
		(net "TP_P0V9_RETIMER_CPU0_VRHOT")
	)
	(segment
		(start 441.78601 -425.827952)
		(end 441.78601 -426.070776)
		(width 0.10668)
		(layer "B.Cu")
		(net "TP_P0V9_RETIMER_CPU0_VRHOT")
	)
	(segment
		(start 440.906916 -426.277278)
		(end 440.194954 -426.277278)
		(width 0.10668)
		(layer "B.Cu")
		(net "TP_P0V9_RETIMER_CPU0_VRHOT")
	)
	(segment
		(start 441.056268 -426.42663)
		(end 440.906916 -426.277278)
		(width 0.10668)
		(layer "B.Cu")
		(net "TP_P0V9_RETIMER_CPU0_VRHOT")
	)
	(segment
		(start 441.78601 -426.070776)
		(end 441.78601 -426.15358)
		(width 0.10668)
		(layer "B.Cu")
		(net "TP_P0V9_RETIMER_CPU0_VRHOT")
	)
	(segment
		(start 441.658756 -425.700698)
		(end 441.78601 -425.827952)
		(width 0.10668)
		(layer "B.Cu")
		(net "TP_P0V9_RETIMER_CPU0_VRHOT")
	)
	(segment
		(start 439.995818 -426.476414)
		(end 438.893966 -426.476414)
		(width 0.10668)
		(layer "B.Cu")
		(net "TP_P0V9_RETIMER_CPU0_VRHOT")
	)
	(segment
		(start 439.782966 -425.584874)
		(end 440.328558 -425.584874)
		(width 0.10668)
		(layer "B.Cu")
		(net "TP_P0V9_RETIMER_CPU0_VRHOT")
	)
	(segment
		(start 440.444382 -425.700698)
		(end 441.658756 -425.700698)
		(width 0.10668)
		(layer "B.Cu")
		(net "TP_P0V9_RETIMER_CPU0_VRHOT")
	)
	(segment
		(start 438.893966 -426.476414)
		(end 438.766966 -426.349414)
		(width 0.10668)
		(layer "B.Cu")
		(net "TP_P0V9_RETIMER_CPU0_VRHOT")
	)
	(segment
		(start 441.51296 -426.42663)
		(end 441.056268 -426.42663)
		(width 0.10668)
		(layer "B.Cu")
		(net "TP_P0V9_RETIMER_CPU0_VRHOT")
	)
	(segment
		(start 440.563 -420.86911)
		(end 440.563 -421.517572)
		(width 0.13462)
		(layer "F.Cu")
		(net "TP_P0V9_RETIMER_CPU0_SVID_ALERT_N")
	)
	(segment
		(start 439.937652 -420.86911)
		(end 440.563 -420.86911)
		(width 0.13462)
		(layer "F.Cu")
		(net "TP_P0V9_RETIMER_CPU0_SVID_ALERT_N")
	)
	(segment
		(start 440.563 -421.517572)
		(end 441.560204 -422.514776)
		(width 0.13462)
		(layer "F.Cu")
		(net "TP_P0V9_RETIMER_CPU0_SVID_ALERT_N")
	)
	(segment
		(start 439.429652 -421.37711)
		(end 439.937652 -420.86911)
		(width 0.13462)
		(layer "F.Cu")
		(net "TP_P0V9_RETIMER_CPU0_SVID_ALERT_N")
	)
	(segment
		(start 441.560204 -422.514776)
		(end 441.92952 -422.514776)
		(width 0.13462)
		(layer "F.Cu")
		(net "TP_P0V9_RETIMER_CPU0_SVID_ALERT_N")
	)
	(via
		(at 440.563 -420.86911)
		(size 0.508)
		(drill 0.254)
		(layers "F.Cu" "B.Cu")
		(net "TP_P0V9_RETIMER_CPU0_SVID_ALERT_N")
	)
	(segment
		(start 439.429652 -421.37711)
		(end 440.055 -421.37711)
		(width 0.1524)
		(layer "B.Cu")
		(net "TP_P0V9_RETIMER_CPU0_SVID_ALERT_N")
	)
	(segment
		(start 440.055 -421.37711)
		(end 440.563 -420.86911)
		(width 0.1524)
		(layer "B.Cu")
		(net "TP_P0V9_RETIMER_CPU0_SVID_ALERT_N")
	)
	(via
		(at 218.69908 -333.883)
		(size 0.6604)
		(drill 0.3302)
		(layers "F.Cu" "B.Cu")
		(net "SMB_RT_CPU1_P0_SDA")
	)
	(segment
		(start 218.57208 -334.01)
		(end 218.69908 -333.883)
		(width 0.10668)
		(layer "B.Cu")
		(net "SMB_RT_CPU1_P0_SDA")
	)
	(segment
		(start 219.075 -333.883)
		(end 220.413072 -335.221072)
		(width 0.10668)
		(layer "B.Cu")
		(net "SMB_RT_CPU1_P0_SDA")
	)
	(segment
		(start 218.69908 -333.883)
		(end 219.075 -333.883)
		(width 0.10668)
		(layer "B.Cu")
		(net "SMB_RT_CPU1_P0_SDA")
	)
	(segment
		(start 220.413072 -335.221072)
		(end 221.510098 -335.221072)
		(width 0.10668)
		(layer "B.Cu")
		(net "SMB_RT_CPU1_P0_SDA")
	)
	(segment
		(start 217.9447 -334.01)
		(end 218.57208 -334.01)
		(width 0.10668)
		(layer "B.Cu")
		(net "SMB_RT_CPU1_P0_SDA")
	)
	(via
		(at 218.886278 -335.153)
		(size 0.6604)
		(drill 0.3302)
		(layers "F.Cu" "B.Cu")
		(net "SMB_RT_CPU1_P0_SCL")
	)
	(segment
		(start 218.44 -335.026)
		(end 217.9447 -335.026)
		(width 0.10668)
		(layer "B.Cu")
		(net "SMB_RT_CPU1_P0_SCL")
	)
	(segment
		(start 219.583 -335.153)
		(end 218.886278 -335.153)
		(width 0.10668)
		(layer "B.Cu")
		(net "SMB_RT_CPU1_P0_SCL")
	)
	(segment
		(start 220.301058 -335.871058)
		(end 219.583 -335.153)
		(width 0.10668)
		(layer "B.Cu")
		(net "SMB_RT_CPU1_P0_SCL")
	)
	(segment
		(start 218.567 -335.153)
		(end 218.44 -335.026)
		(width 0.10668)
		(layer "B.Cu")
		(net "SMB_RT_CPU1_P0_SCL")
	)
	(segment
		(start 218.886278 -335.153)
		(end 218.567 -335.153)
		(width 0.10668)
		(layer "B.Cu")
		(net "SMB_RT_CPU1_P0_SCL")
	)
	(segment
		(start 221.510098 -335.871058)
		(end 220.301058 -335.871058)
		(width 0.10668)
		(layer "B.Cu")
		(net "SMB_RT_CPU1_P0_SCL")
	)
	(via
		(at 215.129872 -333.722726)
		(size 0.6604)
		(drill 0.3302)
		(layers "F.Cu" "B.Cu")
		(net "SMB_RT_CPU1_P0_R_SDA")
	)
	(segment
		(start 216.027 -334.1497)
		(end 216.181432 -334.304132)
		(width 0.10668)
		(layer "B.Cu")
		(net "SMB_RT_CPU1_P0_R_SDA")
	)
	(segment
		(start 217.117168 -334.304132)
		(end 217.4113 -334.01)
		(width 0.10668)
		(layer "B.Cu")
		(net "SMB_RT_CPU1_P0_R_SDA")
	)
	(segment
		(start 215.556846 -334.1497)
		(end 216.027 -334.1497)
		(width 0.10668)
		(layer "B.Cu")
		(net "SMB_RT_CPU1_P0_R_SDA")
	)
	(segment
		(start 215.129872 -333.722726)
		(end 215.556846 -334.1497)
		(width 0.10668)
		(layer "B.Cu")
		(net "SMB_RT_CPU1_P0_R_SDA")
	)
	(segment
		(start 216.181432 -334.304132)
		(end 217.117168 -334.304132)
		(width 0.10668)
		(layer "B.Cu")
		(net "SMB_RT_CPU1_P0_R_SDA")
	)
	(segment
		(start 214.3887 -334.01)
		(end 214.675974 -333.722726)
		(width 0.10668)
		(layer "B.Cu")
		(net "SMB_RT_CPU1_P0_R_SDA")
	)
	(segment
		(start 214.675974 -333.722726)
		(end 215.129872 -333.722726)
		(width 0.10668)
		(layer "B.Cu")
		(net "SMB_RT_CPU1_P0_R_SDA")
	)
	(via
		(at 215.146382 -335.026)
		(size 0.6604)
		(drill 0.3302)
		(layers "F.Cu" "B.Cu")
		(net "SMB_RT_CPU1_P0_R_SCL")
	)
	(segment
		(start 217.071702 -334.686402)
		(end 217.4113 -335.026)
		(width 0.10668)
		(layer "B.Cu")
		(net "SMB_RT_CPU1_P0_R_SCL")
	)
	(segment
		(start 215.286082 -334.8863)
		(end 215.146382 -335.026)
		(width 0.10668)
		(layer "B.Cu")
		(net "SMB_RT_CPU1_P0_R_SCL")
	)
	(segment
		(start 215.146382 -335.026)
		(end 214.3887 -335.026)
		(width 0.10668)
		(layer "B.Cu")
		(net "SMB_RT_CPU1_P0_R_SCL")
	)
	(segment
		(start 216.027 -334.8863)
		(end 216.226898 -334.686402)
		(width 0.10668)
		(layer "B.Cu")
		(net "SMB_RT_CPU1_P0_R_SCL")
	)
	(segment
		(start 216.226898 -334.686402)
		(end 217.071702 -334.686402)
		(width 0.10668)
		(layer "B.Cu")
		(net "SMB_RT_CPU1_P0_R_SCL")
	)
	(segment
		(start 216.027 -334.8863)
		(end 215.286082 -334.8863)
		(width 0.10668)
		(layer "B.Cu")
		(net "SMB_RT_CPU1_P0_R_SCL")
	)
	(segment
		(start 67.353942 -385.43103)
		(end 67.760088 -385.149344)
		(width 0.10668)
		(layer "F.Cu")
		(net "SMB_RT_CPU1_P0_R2_SDA")
	)
	(via
		(at 211.774024 -337.859624)
		(size 0.508)
		(drill 0.254)
		(layers "F.Cu" "B.Cu")
		(net "SMB_RT_CPU1_P0_R2_SDA")
	)
	(via
		(at 67.760088 -385.149344)
		(size 0.4064)
		(drill 0.2032)
		(layers "F.Cu" "B.Cu")
		(net "SMB_RT_CPU1_P0_R2_SDA")
	)
	(segment
		(start 211.774024 -336.091276)
		(end 213.8553 -334.01)
		(width 0.10668)
		(layer "B.Cu")
		(net "SMB_RT_CPU1_P0_R2_SDA")
	)
	(segment
		(start 211.774024 -337.859624)
		(end 211.774024 -336.091276)
		(width 0.10668)
		(layer "B.Cu")
		(net "SMB_RT_CPU1_P0_R2_SDA")
	)
	(segment
		(start 69.030088 -383.200656)
		(end 69.49821 -382.732534)
		(width 0.11684)
		(layer "In2.Cu")
		(net "SMB_RT_CPU1_P0_R2_SDA")
	)
	(segment
		(start 160.16224 -375.563892)
		(end 160.16224 -373.599964)
		(width 0.11684)
		(layer "In2.Cu")
		(net "SMB_RT_CPU1_P0_R2_SDA")
	)
	(segment
		(start 161.803334 -371.95887)
		(end 161.803334 -371.124988)
		(width 0.11684)
		(layer "In2.Cu")
		(net "SMB_RT_CPU1_P0_R2_SDA")
	)
	(segment
		(start 164.224462 -367.600738)
		(end 169.38879 -367.600738)
		(width 0.11684)
		(layer "In2.Cu")
		(net "SMB_RT_CPU1_P0_R2_SDA")
	)
	(segment
		(start 140.632688 -372.754144)
		(end 142.283434 -374.40489)
		(width 0.11684)
		(layer "In2.Cu")
		(net "SMB_RT_CPU1_P0_R2_SDA")
	)
	(segment
		(start 160.16224 -373.599964)
		(end 161.803334 -371.95887)
		(width 0.11684)
		(layer "In2.Cu")
		(net "SMB_RT_CPU1_P0_R2_SDA")
	)
	(segment
		(start 68.74256 -383.200656)
		(end 69.030088 -383.200656)
		(width 0.11684)
		(layer "In2.Cu")
		(net "SMB_RT_CPU1_P0_R2_SDA")
	)
	(segment
		(start 169.38879 -367.600738)
		(end 174.181516 -370.80317)
		(width 0.11684)
		(layer "In2.Cu")
		(net "SMB_RT_CPU1_P0_R2_SDA")
	)
	(segment
		(start 77.70622 -381.166624)
		(end 93.792548 -381.166624)
		(width 0.11684)
		(layer "In2.Cu")
		(net "SMB_RT_CPU1_P0_R2_SDA")
	)
	(segment
		(start 134.388352 -374.521476)
		(end 134.388352 -373.392446)
		(width 0.11684)
		(layer "In2.Cu")
		(net "SMB_RT_CPU1_P0_R2_SDA")
	)
	(segment
		(start 102.324154 -375.224548)
		(end 103.645462 -373.90324)
		(width 0.11684)
		(layer "In2.Cu")
		(net "SMB_RT_CPU1_P0_R2_SDA")
	)
	(segment
		(start 93.792548 -381.166624)
		(end 99.734624 -375.224548)
		(width 0.11684)
		(layer "In2.Cu")
		(net "SMB_RT_CPU1_P0_R2_SDA")
	)
	(segment
		(start 163.417504 -368.407696)
		(end 164.224462 -367.600738)
		(width 0.11684)
		(layer "In2.Cu")
		(net "SMB_RT_CPU1_P0_R2_SDA")
	)
	(segment
		(start 134.388352 -373.392446)
		(end 135.026654 -372.754144)
		(width 0.11684)
		(layer "In2.Cu")
		(net "SMB_RT_CPU1_P0_R2_SDA")
	)
	(segment
		(start 144.322292 -375.460768)
		(end 145.84172 -375.460768)
		(width 0.11684)
		(layer "In2.Cu")
		(net "SMB_RT_CPU1_P0_R2_SDA")
	)
	(segment
		(start 67.07251 -384.700018)
		(end 67.07251 -384.019044)
		(width 0.11684)
		(layer "In2.Cu")
		(net "SMB_RT_CPU1_P0_R2_SDA")
	)
	(segment
		(start 67.760088 -385.149344)
		(end 67.521836 -385.149344)
		(width 0.11684)
		(layer "In2.Cu")
		(net "SMB_RT_CPU1_P0_R2_SDA")
	)
	(segment
		(start 183.59882 -368.655854)
		(end 191.857884 -368.655854)
		(width 0.11684)
		(layer "In2.Cu")
		(net "SMB_RT_CPU1_P0_R2_SDA")
	)
	(segment
		(start 73.538842 -383.588514)
		(end 75.28433 -383.588514)
		(width 0.11684)
		(layer "In2.Cu")
		(net "SMB_RT_CPU1_P0_R2_SDA")
	)
	(segment
		(start 161.803334 -371.124988)
		(end 163.417504 -369.510818)
		(width 0.11684)
		(layer "In2.Cu")
		(net "SMB_RT_CPU1_P0_R2_SDA")
	)
	(segment
		(start 68.492878 -383.097278)
		(end 68.74256 -383.200656)
		(width 0.11684)
		(layer "In2.Cu")
		(net "SMB_RT_CPU1_P0_R2_SDA")
	)
	(segment
		(start 67.994276 -383.097278)
		(end 68.492878 -383.097278)
		(width 0.11684)
		(layer "In2.Cu")
		(net "SMB_RT_CPU1_P0_R2_SDA")
	)
	(segment
		(start 109.699044 -373.90324)
		(end 112.04829 -376.252486)
		(width 0.11684)
		(layer "In2.Cu")
		(net "SMB_RT_CPU1_P0_R2_SDA")
	)
	(segment
		(start 147.000214 -376.619262)
		(end 159.10687 -376.619262)
		(width 0.11684)
		(layer "In2.Cu")
		(net "SMB_RT_CPU1_P0_R2_SDA")
	)
	(segment
		(start 69.49821 -382.732534)
		(end 70.340728 -382.383538)
		(width 0.11684)
		(layer "In2.Cu")
		(net "SMB_RT_CPU1_P0_R2_SDA")
	)
	(segment
		(start 70.340728 -382.383538)
		(end 72.333866 -382.383538)
		(width 0.11684)
		(layer "In2.Cu")
		(net "SMB_RT_CPU1_P0_R2_SDA")
	)
	(segment
		(start 159.10687 -376.619262)
		(end 160.16224 -375.563892)
		(width 0.11684)
		(layer "In2.Cu")
		(net "SMB_RT_CPU1_P0_R2_SDA")
	)
	(segment
		(start 181.451504 -370.80317)
		(end 183.59882 -368.655854)
		(width 0.11684)
		(layer "In2.Cu")
		(net "SMB_RT_CPU1_P0_R2_SDA")
	)
	(segment
		(start 132.657342 -376.252486)
		(end 134.388352 -374.521476)
		(width 0.11684)
		(layer "In2.Cu")
		(net "SMB_RT_CPU1_P0_R2_SDA")
	)
	(segment
		(start 135.026654 -372.754144)
		(end 140.632688 -372.754144)
		(width 0.11684)
		(layer "In2.Cu")
		(net "SMB_RT_CPU1_P0_R2_SDA")
	)
	(segment
		(start 174.181516 -370.80317)
		(end 181.451504 -370.80317)
		(width 0.11684)
		(layer "In2.Cu")
		(net "SMB_RT_CPU1_P0_R2_SDA")
	)
	(segment
		(start 142.283434 -374.40489)
		(end 143.266414 -374.40489)
		(width 0.11684)
		(layer "In2.Cu")
		(net "SMB_RT_CPU1_P0_R2_SDA")
	)
	(segment
		(start 99.734624 -375.224548)
		(end 102.324154 -375.224548)
		(width 0.11684)
		(layer "In2.Cu")
		(net "SMB_RT_CPU1_P0_R2_SDA")
	)
	(segment
		(start 210.180936 -339.452712)
		(end 211.774024 -337.859624)
		(width 0.11684)
		(layer "In2.Cu")
		(net "SMB_RT_CPU1_P0_R2_SDA")
	)
	(segment
		(start 207.448404 -350.183196)
		(end 210.180936 -347.450664)
		(width 0.11684)
		(layer "In2.Cu")
		(net "SMB_RT_CPU1_P0_R2_SDA")
	)
	(segment
		(start 207.448404 -353.065334)
		(end 207.448404 -350.183196)
		(width 0.11684)
		(layer "In2.Cu")
		(net "SMB_RT_CPU1_P0_R2_SDA")
	)
	(segment
		(start 67.07251 -384.019044)
		(end 67.994276 -383.097278)
		(width 0.11684)
		(layer "In2.Cu")
		(net "SMB_RT_CPU1_P0_R2_SDA")
	)
	(segment
		(start 103.645462 -373.90324)
		(end 109.699044 -373.90324)
		(width 0.11684)
		(layer "In2.Cu")
		(net "SMB_RT_CPU1_P0_R2_SDA")
	)
	(segment
		(start 210.180936 -347.450664)
		(end 210.180936 -339.452712)
		(width 0.11684)
		(layer "In2.Cu")
		(net "SMB_RT_CPU1_P0_R2_SDA")
	)
	(segment
		(start 163.417504 -369.510818)
		(end 163.417504 -368.407696)
		(width 0.11684)
		(layer "In2.Cu")
		(net "SMB_RT_CPU1_P0_R2_SDA")
	)
	(segment
		(start 191.857884 -368.655854)
		(end 207.448404 -353.065334)
		(width 0.11684)
		(layer "In2.Cu")
		(net "SMB_RT_CPU1_P0_R2_SDA")
	)
	(segment
		(start 112.04829 -376.252486)
		(end 132.657342 -376.252486)
		(width 0.11684)
		(layer "In2.Cu")
		(net "SMB_RT_CPU1_P0_R2_SDA")
	)
	(segment
		(start 143.266414 -374.40489)
		(end 144.322292 -375.460768)
		(width 0.11684)
		(layer "In2.Cu")
		(net "SMB_RT_CPU1_P0_R2_SDA")
	)
	(segment
		(start 67.521836 -385.149344)
		(end 67.07251 -384.700018)
		(width 0.11684)
		(layer "In2.Cu")
		(net "SMB_RT_CPU1_P0_R2_SDA")
	)
	(segment
		(start 145.84172 -375.460768)
		(end 147.000214 -376.619262)
		(width 0.11684)
		(layer "In2.Cu")
		(net "SMB_RT_CPU1_P0_R2_SDA")
	)
	(segment
		(start 75.28433 -383.588514)
		(end 77.70622 -381.166624)
		(width 0.11684)
		(layer "In2.Cu")
		(net "SMB_RT_CPU1_P0_R2_SDA")
	)
	(segment
		(start 72.333866 -382.383538)
		(end 73.538842 -383.588514)
		(width 0.11684)
		(layer "In2.Cu")
		(net "SMB_RT_CPU1_P0_R2_SDA")
	)
	(segment
		(start 67.353942 -384.831082)
		(end 67.774312 -384.574542)
		(width 0.10668)
		(layer "F.Cu")
		(net "SMB_RT_CPU1_P0_R2_SCL")
	)
	(via
		(at 211.840318 -339.408008)
		(size 0.508)
		(drill 0.254)
		(layers "F.Cu" "B.Cu")
		(net "SMB_RT_CPU1_P0_R2_SCL")
	)
	(via
		(at 212.73262 -336.14868)
		(size 0.6604)
		(drill 0.3302)
		(layers "F.Cu" "B.Cu")
		(net "SMB_RT_CPU1_P0_R2_SCL")
	)
	(via
		(at 67.774312 -384.574542)
		(size 0.4064)
		(drill 0.2032)
		(layers "F.Cu" "B.Cu")
		(net "SMB_RT_CPU1_P0_R2_SCL")
	)
	(segment
		(start 212.73262 -336.14868)
		(end 212.348572 -336.532728)
		(width 0.10668)
		(layer "B.Cu")
		(net "SMB_RT_CPU1_P0_R2_SCL")
	)
	(segment
		(start 212.348572 -336.532728)
		(end 212.348572 -338.899754)
		(width 0.10668)
		(layer "B.Cu")
		(net "SMB_RT_CPU1_P0_R2_SCL")
	)
	(segment
		(start 212.348572 -338.899754)
		(end 211.840318 -339.408008)
		(width 0.10668)
		(layer "B.Cu")
		(net "SMB_RT_CPU1_P0_R2_SCL")
	)
	(segment
		(start 213.8553 -335.026)
		(end 212.73262 -336.14868)
		(width 0.10668)
		(layer "B.Cu")
		(net "SMB_RT_CPU1_P0_R2_SCL")
	)
	(segment
		(start 207.870044 -350.518222)
		(end 210.637374 -347.750892)
		(width 0.11684)
		(layer "In2.Cu")
		(net "SMB_RT_CPU1_P0_R2_SCL")
	)
	(segment
		(start 73.342246 -384.163316)
		(end 75.309222 -384.163316)
		(width 0.11684)
		(layer "In2.Cu")
		(net "SMB_RT_CPU1_P0_R2_SCL")
	)
	(segment
		(start 77.731112 -381.741426)
		(end 93.814138 -381.741426)
		(width 0.11684)
		(layer "In2.Cu")
		(net "SMB_RT_CPU1_P0_R2_SCL")
	)
	(segment
		(start 172.804836 -372.752874)
		(end 174.325788 -371.231922)
		(width 0.11684)
		(layer "In2.Cu")
		(net "SMB_RT_CPU1_P0_R2_SCL")
	)
	(segment
		(start 150.435564 -377.982226)
		(end 150.552404 -377.865386)
		(width 0.11684)
		(layer "In2.Cu")
		(net "SMB_RT_CPU1_P0_R2_SCL")
	)
	(segment
		(start 75.309222 -384.163316)
		(end 77.731112 -381.741426)
		(width 0.11684)
		(layer "In2.Cu")
		(net "SMB_RT_CPU1_P0_R2_SCL")
	)
	(segment
		(start 174.325788 -371.231922)
		(end 181.619398 -371.231922)
		(width 0.11684)
		(layer "In2.Cu")
		(net "SMB_RT_CPU1_P0_R2_SCL")
	)
	(segment
		(start 148.715476 -378.930916)
		(end 150.318724 -378.930916)
		(width 0.11684)
		(layer "In2.Cu")
		(net "SMB_RT_CPU1_P0_R2_SCL")
	)
	(segment
		(start 151.400764 -377.865386)
		(end 151.591264 -377.865386)
		(width 0.11684)
		(layer "In2.Cu")
		(net "SMB_RT_CPU1_P0_R2_SCL")
	)
	(segment
		(start 142.108682 -374.82653)
		(end 143.091662 -374.82653)
		(width 0.11684)
		(layer "In2.Cu")
		(net "SMB_RT_CPU1_P0_R2_SCL")
	)
	(segment
		(start 69.791834 -383.06883)
		(end 70.329806 -382.846072)
		(width 0.11684)
		(layer "In2.Cu")
		(net "SMB_RT_CPU1_P0_R2_SCL")
	)
	(segment
		(start 68.495926 -383.558288)
		(end 68.6689 -383.629916)
		(width 0.11684)
		(layer "In2.Cu")
		(net "SMB_RT_CPU1_P0_R2_SCL")
	)
	(segment
		(start 144.14754 -375.882408)
		(end 145.666968 -375.882408)
		(width 0.11684)
		(layer "In2.Cu")
		(net "SMB_RT_CPU1_P0_R2_SCL")
	)
	(segment
		(start 165.33241 -376.792236)
		(end 166.87673 -375.247916)
		(width 0.11684)
		(layer "In2.Cu")
		(net "SMB_RT_CPU1_P0_R2_SCL")
	)
	(segment
		(start 99.909376 -375.646188)
		(end 102.715568 -375.646188)
		(width 0.11684)
		(layer "In2.Cu")
		(net "SMB_RT_CPU1_P0_R2_SCL")
	)
	(segment
		(start 111.810038 -376.827288)
		(end 133.904482 -376.827288)
		(width 0.11684)
		(layer "In2.Cu")
		(net "SMB_RT_CPU1_P0_R2_SCL")
	)
	(segment
		(start 135.849868 -375.10593)
		(end 137.07618 -375.10593)
		(width 0.11684)
		(layer "In2.Cu")
		(net "SMB_RT_CPU1_P0_R2_SCL")
	)
	(segment
		(start 151.708104 -378.814076)
		(end 151.824944 -378.930916)
		(width 0.11684)
		(layer "In2.Cu")
		(net "SMB_RT_CPU1_P0_R2_SCL")
	)
	(segment
		(start 70.329806 -382.846072)
		(end 72.025002 -382.846072)
		(width 0.11684)
		(layer "In2.Cu")
		(net "SMB_RT_CPU1_P0_R2_SCL")
	)
	(segment
		(start 151.824944 -378.930916)
		(end 162.947604 -378.930916)
		(width 0.11684)
		(layer "In2.Cu")
		(net "SMB_RT_CPU1_P0_R2_SCL")
	)
	(segment
		(start 137.898124 -374.283986)
		(end 141.566138 -374.283986)
		(width 0.11684)
		(layer "In2.Cu")
		(net "SMB_RT_CPU1_P0_R2_SCL")
	)
	(segment
		(start 145.666968 -375.882408)
		(end 148.715476 -378.930916)
		(width 0.11684)
		(layer "In2.Cu")
		(net "SMB_RT_CPU1_P0_R2_SCL")
	)
	(segment
		(start 150.859744 -377.982226)
		(end 150.859744 -378.814076)
		(width 0.11684)
		(layer "In2.Cu")
		(net "SMB_RT_CPU1_P0_R2_SCL")
	)
	(segment
		(start 151.591264 -377.865386)
		(end 151.708104 -377.982226)
		(width 0.11684)
		(layer "In2.Cu")
		(net "SMB_RT_CPU1_P0_R2_SCL")
	)
	(segment
		(start 165.086284 -376.792236)
		(end 165.33241 -376.792236)
		(width 0.11684)
		(layer "In2.Cu")
		(net "SMB_RT_CPU1_P0_R2_SCL")
	)
	(segment
		(start 109.460792 -374.478042)
		(end 111.810038 -376.827288)
		(width 0.11684)
		(layer "In2.Cu")
		(net "SMB_RT_CPU1_P0_R2_SCL")
	)
	(segment
		(start 210.637374 -340.610952)
		(end 211.840318 -339.408008)
		(width 0.11684)
		(layer "In2.Cu")
		(net "SMB_RT_CPU1_P0_R2_SCL")
	)
	(segment
		(start 167.668194 -372.752874)
		(end 172.804836 -372.752874)
		(width 0.11684)
		(layer "In2.Cu")
		(net "SMB_RT_CPU1_P0_R2_SCL")
	)
	(segment
		(start 133.904482 -376.827288)
		(end 135.4328 -375.29897)
		(width 0.11684)
		(layer "In2.Cu")
		(net "SMB_RT_CPU1_P0_R2_SCL")
	)
	(segment
		(start 135.656828 -375.29897)
		(end 135.849868 -375.10593)
		(width 0.11684)
		(layer "In2.Cu")
		(net "SMB_RT_CPU1_P0_R2_SCL")
	)
	(segment
		(start 69.230748 -383.629916)
		(end 69.791834 -383.06883)
		(width 0.11684)
		(layer "In2.Cu")
		(net "SMB_RT_CPU1_P0_R2_SCL")
	)
	(segment
		(start 137.07618 -375.10593)
		(end 137.898124 -374.283986)
		(width 0.11684)
		(layer "In2.Cu")
		(net "SMB_RT_CPU1_P0_R2_SCL")
	)
	(segment
		(start 141.566138 -374.283986)
		(end 142.108682 -374.82653)
		(width 0.11684)
		(layer "In2.Cu")
		(net "SMB_RT_CPU1_P0_R2_SCL")
	)
	(segment
		(start 150.742904 -377.865386)
		(end 150.859744 -377.982226)
		(width 0.11684)
		(layer "In2.Cu")
		(net "SMB_RT_CPU1_P0_R2_SCL")
	)
	(segment
		(start 150.435564 -378.814076)
		(end 150.435564 -377.982226)
		(width 0.11684)
		(layer "In2.Cu")
		(net "SMB_RT_CPU1_P0_R2_SCL")
	)
	(segment
		(start 150.552404 -377.865386)
		(end 150.742904 -377.865386)
		(width 0.11684)
		(layer "In2.Cu")
		(net "SMB_RT_CPU1_P0_R2_SCL")
	)
	(segment
		(start 143.091662 -374.82653)
		(end 144.14754 -375.882408)
		(width 0.11684)
		(layer "In2.Cu")
		(net "SMB_RT_CPU1_P0_R2_SCL")
	)
	(segment
		(start 67.774312 -384.574542)
		(end 67.774312 -383.93878)
		(width 0.11684)
		(layer "In2.Cu")
		(net "SMB_RT_CPU1_P0_R2_SCL")
	)
	(segment
		(start 135.4328 -375.29897)
		(end 135.656828 -375.29897)
		(width 0.11684)
		(layer "In2.Cu")
		(net "SMB_RT_CPU1_P0_R2_SCL")
	)
	(segment
		(start 151.283924 -378.814076)
		(end 151.283924 -377.982226)
		(width 0.11684)
		(layer "In2.Cu")
		(net "SMB_RT_CPU1_P0_R2_SCL")
	)
	(segment
		(start 183.773826 -369.077494)
		(end 192.03289 -369.077494)
		(width 0.11684)
		(layer "In2.Cu")
		(net "SMB_RT_CPU1_P0_R2_SCL")
	)
	(segment
		(start 68.154804 -383.558288)
		(end 68.495926 -383.558288)
		(width 0.11684)
		(layer "In2.Cu")
		(net "SMB_RT_CPU1_P0_R2_SCL")
	)
	(segment
		(start 68.6689 -383.629916)
		(end 69.230748 -383.629916)
		(width 0.11684)
		(layer "In2.Cu")
		(net "SMB_RT_CPU1_P0_R2_SCL")
	)
	(segment
		(start 72.025002 -382.846072)
		(end 73.342246 -384.163316)
		(width 0.11684)
		(layer "In2.Cu")
		(net "SMB_RT_CPU1_P0_R2_SCL")
	)
	(segment
		(start 93.814138 -381.741426)
		(end 99.909376 -375.646188)
		(width 0.11684)
		(layer "In2.Cu")
		(net "SMB_RT_CPU1_P0_R2_SCL")
	)
	(segment
		(start 166.87673 -375.247916)
		(end 166.87673 -373.544338)
		(width 0.11684)
		(layer "In2.Cu")
		(net "SMB_RT_CPU1_P0_R2_SCL")
	)
	(segment
		(start 207.870044 -353.24034)
		(end 207.870044 -350.518222)
		(width 0.11684)
		(layer "In2.Cu")
		(net "SMB_RT_CPU1_P0_R2_SCL")
	)
	(segment
		(start 103.883714 -374.478042)
		(end 109.460792 -374.478042)
		(width 0.11684)
		(layer "In2.Cu")
		(net "SMB_RT_CPU1_P0_R2_SCL")
	)
	(segment
		(start 150.318724 -378.930916)
		(end 150.435564 -378.814076)
		(width 0.11684)
		(layer "In2.Cu")
		(net "SMB_RT_CPU1_P0_R2_SCL")
	)
	(segment
		(start 151.708104 -377.982226)
		(end 151.708104 -378.814076)
		(width 0.11684)
		(layer "In2.Cu")
		(net "SMB_RT_CPU1_P0_R2_SCL")
	)
	(segment
		(start 67.774312 -383.93878)
		(end 68.154804 -383.558288)
		(width 0.11684)
		(layer "In2.Cu")
		(net "SMB_RT_CPU1_P0_R2_SCL")
	)
	(segment
		(start 192.03289 -369.077494)
		(end 207.870044 -353.24034)
		(width 0.11684)
		(layer "In2.Cu")
		(net "SMB_RT_CPU1_P0_R2_SCL")
	)
	(segment
		(start 150.859744 -378.814076)
		(end 150.976584 -378.930916)
		(width 0.11684)
		(layer "In2.Cu")
		(net "SMB_RT_CPU1_P0_R2_SCL")
	)
	(segment
		(start 166.87673 -373.544338)
		(end 167.668194 -372.752874)
		(width 0.11684)
		(layer "In2.Cu")
		(net "SMB_RT_CPU1_P0_R2_SCL")
	)
	(segment
		(start 162.947604 -378.930916)
		(end 165.086284 -376.792236)
		(width 0.11684)
		(layer "In2.Cu")
		(net "SMB_RT_CPU1_P0_R2_SCL")
	)
	(segment
		(start 181.619398 -371.231922)
		(end 183.773826 -369.077494)
		(width 0.11684)
		(layer "In2.Cu")
		(net "SMB_RT_CPU1_P0_R2_SCL")
	)
	(segment
		(start 151.283924 -377.982226)
		(end 151.400764 -377.865386)
		(width 0.11684)
		(layer "In2.Cu")
		(net "SMB_RT_CPU1_P0_R2_SCL")
	)
	(segment
		(start 210.637374 -347.750892)
		(end 210.637374 -340.610952)
		(width 0.11684)
		(layer "In2.Cu")
		(net "SMB_RT_CPU1_P0_R2_SCL")
	)
	(segment
		(start 150.976584 -378.930916)
		(end 151.167084 -378.930916)
		(width 0.11684)
		(layer "In2.Cu")
		(net "SMB_RT_CPU1_P0_R2_SCL")
	)
	(segment
		(start 102.715568 -375.646188)
		(end 103.883714 -374.478042)
		(width 0.11684)
		(layer "In2.Cu")
		(net "SMB_RT_CPU1_P0_R2_SCL")
	)
	(segment
		(start 151.167084 -378.930916)
		(end 151.283924 -378.814076)
		(width 0.11684)
		(layer "In2.Cu")
		(net "SMB_RT_CPU1_P0_R2_SCL")
	)
	(segment
		(start 13.188442 -394.028676)
		(end 12.495784 -394.028676)
		(width 0.254)
		(layer "F.Cu")
		(net "PV09_RETIMER_CPU1_VCCS")
	)
	(segment
		(start 13.206984 -394.047218)
		(end 13.188442 -394.028676)
		(width 0.254)
		(layer "F.Cu")
		(net "PV09_RETIMER_CPU1_VCCS")
	)
	(segment
		(start 22.547834 -394.217144)
		(end 22.481794 -394.283184)
		(width 0.2286)
		(layer "F.Cu")
		(net "PV09_RETIMER_CPU1_VCCS")
	)
	(segment
		(start 13.675868 -393.578334)
		(end 13.206984 -394.047218)
		(width 0.254)
		(layer "F.Cu")
		(net "PV09_RETIMER_CPU1_VCCS")
	)
	(segment
		(start 23.650702 -391.964164)
		(end 22.547834 -393.067032)
		(width 0.2286)
		(layer "F.Cu")
		(net "PV09_RETIMER_CPU1_VCCS")
	)
	(segment
		(start 22.547834 -393.539726)
		(end 22.547834 -394.217144)
		(width 0.2286)
		(layer "F.Cu")
		(net "PV09_RETIMER_CPU1_VCCS")
	)
	(segment
		(start 22.547834 -393.067032)
		(end 22.547834 -393.539726)
		(width 0.2286)
		(layer "F.Cu")
		(net "PV09_RETIMER_CPU1_VCCS")
	)
	(segment
		(start 14.57198 -391.935716)
		(end 13.675868 -392.831828)
		(width 0.254)
		(layer "F.Cu")
		(net "PV09_RETIMER_CPU1_VCCS")
	)
	(segment
		(start 13.675868 -392.831828)
		(end 13.675868 -393.578334)
		(width 0.254)
		(layer "F.Cu")
		(net "PV09_RETIMER_CPU1_VCCS")
	)
	(segment
		(start 23.650702 -391.754106)
		(end 23.650702 -391.964164)
		(width 0.2286)
		(layer "F.Cu")
		(net "PV09_RETIMER_CPU1_VCCS")
	)
	(segment
		(start 14.57198 -391.754106)
		(end 14.57198 -391.935716)
		(width 0.254)
		(layer "F.Cu")
		(net "PV09_RETIMER_CPU1_VCCS")
	)
	(via
		(at 12.098782 -406.627584)
		(size 0.508)
		(drill 0.254)
		(layers "F.Cu" "B.Cu")
		(net "PV09_RETIMER_CPU1_VCCS")
	)
	(via
		(at 12.495784 -394.028676)
		(size 0.508)
		(drill 0.254)
		(layers "F.Cu" "B.Cu")
		(net "PV09_RETIMER_CPU1_VCCS")
	)
	(via
		(at 22.481794 -394.283184)
		(size 0.508)
		(drill 0.254)
		(layers "F.Cu" "B.Cu")
		(net "PV09_RETIMER_CPU1_VCCS")
	)
	(segment
		(start 16.342614 -404.951438)
		(end 14.385798 -404.951438)
		(width 0.254)
		(layer "In15.Cu")
		(net "PV09_RETIMER_CPU1_VCCS")
	)
	(segment
		(start 14.385798 -404.951438)
		(end 13.301726 -403.867366)
		(width 0.254)
		(layer "In15.Cu")
		(net "PV09_RETIMER_CPU1_VCCS")
	)
	(segment
		(start 13.68298 -401.993608)
		(end 13.68298 -394.899134)
		(width 0.254)
		(layer "In15.Cu")
		(net "PV09_RETIMER_CPU1_VCCS")
	)
	(segment
		(start 13.301726 -402.374862)
		(end 13.68298 -401.993608)
		(width 0.254)
		(layer "In15.Cu")
		(net "PV09_RETIMER_CPU1_VCCS")
	)
	(segment
		(start 16.958818 -414.52927)
		(end 19.08937 -414.52927)
		(width 0.254)
		(layer "In15.Cu")
		(net "PV09_RETIMER_CPU1_VCCS")
	)
	(segment
		(start 20.012152 -407.99258)
		(end 18.441162 -406.42159)
		(width 0.254)
		(layer "In15.Cu")
		(net "PV09_RETIMER_CPU1_VCCS")
	)
	(segment
		(start 13.68298 -394.899134)
		(end 13.424662 -394.357606)
		(width 0.254)
		(layer "In15.Cu")
		(net "PV09_RETIMER_CPU1_VCCS")
	)
	(segment
		(start 20.012152 -413.606488)
		(end 20.012152 -407.99258)
		(width 0.254)
		(layer "In15.Cu")
		(net "PV09_RETIMER_CPU1_VCCS")
	)
	(segment
		(start 16.466566 -412.90367)
		(end 17.28089 -412.089346)
		(width 0.254)
		(layer "In15.Cu")
		(net "PV09_RETIMER_CPU1_VCCS")
	)
	(segment
		(start 13.301726 -403.867366)
		(end 13.301726 -402.374862)
		(width 0.254)
		(layer "In15.Cu")
		(net "PV09_RETIMER_CPU1_VCCS")
	)
	(segment
		(start 19.276568 -402.827998)
		(end 18.548858 -402.100288)
		(width 0.254)
		(layer "In15.Cu")
		(net "PV09_RETIMER_CPU1_VCCS")
	)
	(segment
		(start 19.47418 -399.769584)
		(end 21.741384 -399.769584)
		(width 0.254)
		(layer "In15.Cu")
		(net "PV09_RETIMER_CPU1_VCCS")
	)
	(segment
		(start 15.688818 -412.90367)
		(end 16.466566 -412.90367)
		(width 0.254)
		(layer "In15.Cu")
		(net "PV09_RETIMER_CPU1_VCCS")
	)
	(segment
		(start 22.634194 -398.876774)
		(end 22.634194 -395.920214)
		(width 0.254)
		(layer "In15.Cu")
		(net "PV09_RETIMER_CPU1_VCCS")
	)
	(segment
		(start 17.28089 -412.089346)
		(end 17.28089 -405.889714)
		(width 0.254)
		(layer "In15.Cu")
		(net "PV09_RETIMER_CPU1_VCCS")
	)
	(segment
		(start 21.741384 -399.769584)
		(end 22.634194 -398.876774)
		(width 0.254)
		(layer "In15.Cu")
		(net "PV09_RETIMER_CPU1_VCCS")
	)
	(segment
		(start 15.917418 -414.17367)
		(end 16.603218 -414.17367)
		(width 0.254)
		(layer "In15.Cu")
		(net "PV09_RETIMER_CPU1_VCCS")
	)
	(segment
		(start 18.548858 -402.100288)
		(end 18.548858 -400.694906)
		(width 0.254)
		(layer "In15.Cu")
		(net "PV09_RETIMER_CPU1_VCCS")
	)
	(segment
		(start 19.276568 -403.418294)
		(end 19.276568 -402.827998)
		(width 0.254)
		(layer "In15.Cu")
		(net "PV09_RETIMER_CPU1_VCCS")
	)
	(segment
		(start 17.28089 -405.889714)
		(end 16.342614 -404.951438)
		(width 0.254)
		(layer "In15.Cu")
		(net "PV09_RETIMER_CPU1_VCCS")
	)
	(segment
		(start 18.441162 -406.42159)
		(end 18.441162 -404.2537)
		(width 0.254)
		(layer "In15.Cu")
		(net "PV09_RETIMER_CPU1_VCCS")
	)
	(segment
		(start 16.603218 -414.17367)
		(end 16.958818 -414.52927)
		(width 0.254)
		(layer "In15.Cu")
		(net "PV09_RETIMER_CPU1_VCCS")
	)
	(segment
		(start 18.548858 -400.694906)
		(end 19.47418 -399.769584)
		(width 0.254)
		(layer "In15.Cu")
		(net "PV09_RETIMER_CPU1_VCCS")
	)
	(segment
		(start 13.424662 -394.357606)
		(end 12.495784 -394.028676)
		(width 0.254)
		(layer "In15.Cu")
		(net "PV09_RETIMER_CPU1_VCCS")
	)
	(segment
		(start 22.634194 -395.920214)
		(end 22.481794 -394.283184)
		(width 0.254)
		(layer "In15.Cu")
		(net "PV09_RETIMER_CPU1_VCCS")
	)
	(segment
		(start 18.441162 -404.2537)
		(end 19.276568 -403.418294)
		(width 0.254)
		(layer "In15.Cu")
		(net "PV09_RETIMER_CPU1_VCCS")
	)
	(segment
		(start 19.08937 -414.52927)
		(end 20.012152 -413.606488)
		(width 0.254)
		(layer "In15.Cu")
		(net "PV09_RETIMER_CPU1_VCCS")
	)
	(segment
		(start 442.970666 -400.526504)
		(end 443.141862 -400.355308)
		(width 0.2286)
		(layer "F.Cu")
		(net "PV09_RETIMER_CPU0_VCCS")
	)
	(segment
		(start 452.220584 -400.355308)
		(end 451.117716 -401.458176)
		(width 0.2286)
		(layer "F.Cu")
		(net "PV09_RETIMER_CPU0_VCCS")
	)
	(segment
		(start 441.758324 -402.41982)
		(end 441.776866 -402.438362)
		(width 0.254)
		(layer "F.Cu")
		(net "PV09_RETIMER_CPU0_VCCS")
	)
	(segment
		(start 451.117716 -401.93087)
		(end 451.117716 -402.608288)
		(width 0.2286)
		(layer "F.Cu")
		(net "PV09_RETIMER_CPU0_VCCS")
	)
	(segment
		(start 451.117716 -402.608288)
		(end 451.051676 -402.674328)
		(width 0.2286)
		(layer "F.Cu")
		(net "PV09_RETIMER_CPU0_VCCS")
	)
	(segment
		(start 443.141862 -400.355308)
		(end 443.141862 -400.14525)
		(width 0.2286)
		(layer "F.Cu")
		(net "PV09_RETIMER_CPU0_VCCS")
	)
	(segment
		(start 441.776866 -402.438362)
		(end 441.776866 -402.178012)
		(width 0.254)
		(layer "F.Cu")
		(net "PV09_RETIMER_CPU0_VCCS")
	)
	(segment
		(start 442.968126 -400.986752)
		(end 442.968126 -400.53895)
		(width 0.254)
		(layer "F.Cu")
		(net "PV09_RETIMER_CPU0_VCCS")
	)
	(segment
		(start 441.776866 -402.178012)
		(end 442.968126 -400.986752)
		(width 0.254)
		(layer "F.Cu")
		(net "PV09_RETIMER_CPU0_VCCS")
	)
	(segment
		(start 452.220584 -400.14525)
		(end 452.220584 -400.355308)
		(width 0.2286)
		(layer "F.Cu")
		(net "PV09_RETIMER_CPU0_VCCS")
	)
	(segment
		(start 442.968126 -400.53895)
		(end 442.970666 -400.53641)
		(width 0.254)
		(layer "F.Cu")
		(net "PV09_RETIMER_CPU0_VCCS")
	)
	(segment
		(start 451.117716 -401.458176)
		(end 451.117716 -401.93087)
		(width 0.2286)
		(layer "F.Cu")
		(net "PV09_RETIMER_CPU0_VCCS")
	)
	(segment
		(start 441.065666 -402.41982)
		(end 441.758324 -402.41982)
		(width 0.254)
		(layer "F.Cu")
		(net "PV09_RETIMER_CPU0_VCCS")
	)
	(segment
		(start 442.970666 -400.53641)
		(end 442.970666 -400.526504)
		(width 0.254)
		(layer "F.Cu")
		(net "PV09_RETIMER_CPU0_VCCS")
	)
	(via
		(at 441.065666 -402.41982)
		(size 0.508)
		(drill 0.254)
		(layers "F.Cu" "B.Cu")
		(net "PV09_RETIMER_CPU0_VCCS")
	)
	(via
		(at 451.051676 -402.674328)
		(size 0.508)
		(drill 0.254)
		(layers "F.Cu" "B.Cu")
		(net "PV09_RETIMER_CPU0_VCCS")
	)
	(via
		(at 447.411602 -427.60011)
		(size 0.508)
		(drill 0.254)
		(layers "F.Cu" "B.Cu")
		(net "PV09_RETIMER_CPU0_VCCS")
	)
	(segment
		(start 441.840874 -405.627078)
		(end 441.840874 -403.195028)
		(width 0.254)
		(layer "In15.Cu")
		(net "PV09_RETIMER_CPU0_VCCS")
	)
	(segment
		(start 441.840874 -403.195028)
		(end 441.065666 -402.41982)
		(width 0.254)
		(layer "In15.Cu")
		(net "PV09_RETIMER_CPU0_VCCS")
	)
	(segment
		(start 441.40374 -417.594542)
		(end 441.40374 -409.466288)
		(width 0.254)
		(layer "In15.Cu")
		(net "PV09_RETIMER_CPU0_VCCS")
	)
	(segment
		(start 441.40374 -409.466288)
		(end 441.773056 -409.096972)
		(width 0.254)
		(layer "In15.Cu")
		(net "PV09_RETIMER_CPU0_VCCS")
	)
	(segment
		(start 442.399166 -421.435784)
		(end 441.36945 -420.406068)
		(width 0.254)
		(layer "In15.Cu")
		(net "PV09_RETIMER_CPU0_VCCS")
	)
	(segment
		(start 441.773056 -409.096972)
		(end 450.086222 -409.096972)
		(width 0.254)
		(layer "In15.Cu")
		(net "PV09_RETIMER_CPU0_VCCS")
	)
	(segment
		(start 443.821566 -421.324024)
		(end 443.709806 -421.435784)
		(width 0.254)
		(layer "In15.Cu")
		(net "PV09_RETIMER_CPU0_VCCS")
	)
	(segment
		(start 441.36945 -420.406068)
		(end 441.36945 -419.371018)
		(width 0.254)
		(layer "In15.Cu")
		(net "PV09_RETIMER_CPU0_VCCS")
	)
	(segment
		(start 451.176136 -402.798788)
		(end 451.051676 -402.674328)
		(width 0.254)
		(layer "In15.Cu")
		(net "PV09_RETIMER_CPU0_VCCS")
	)
	(segment
		(start 439.433208 -408.034744)
		(end 441.840874 -405.627078)
		(width 0.254)
		(layer "In15.Cu")
		(net "PV09_RETIMER_CPU0_VCCS")
	)
	(segment
		(start 442.736478 -420.054024)
		(end 442.44895 -419.766496)
		(width 0.254)
		(layer "In15.Cu")
		(net "PV09_RETIMER_CPU0_VCCS")
	)
	(segment
		(start 439.05043 -415.645854)
		(end 439.433208 -415.263076)
		(width 0.254)
		(layer "In15.Cu")
		(net "PV09_RETIMER_CPU0_VCCS")
	)
	(segment
		(start 450.086222 -409.096972)
		(end 451.176136 -408.007058)
		(width 0.254)
		(layer "In15.Cu")
		(net "PV09_RETIMER_CPU0_VCCS")
	)
	(segment
		(start 442.44895 -418.639752)
		(end 441.40374 -417.594542)
		(width 0.254)
		(layer "In15.Cu")
		(net "PV09_RETIMER_CPU0_VCCS")
	)
	(segment
		(start 442.44895 -419.766496)
		(end 442.44895 -418.639752)
		(width 0.254)
		(layer "In15.Cu")
		(net "PV09_RETIMER_CPU0_VCCS")
	)
	(segment
		(start 439.05043 -417.051998)
		(end 439.05043 -415.645854)
		(width 0.254)
		(layer "In15.Cu")
		(net "PV09_RETIMER_CPU0_VCCS")
	)
	(segment
		(start 441.36945 -419.371018)
		(end 439.05043 -417.051998)
		(width 0.254)
		(layer "In15.Cu")
		(net "PV09_RETIMER_CPU0_VCCS")
	)
	(segment
		(start 443.592966 -420.054024)
		(end 442.736478 -420.054024)
		(width 0.254)
		(layer "In15.Cu")
		(net "PV09_RETIMER_CPU0_VCCS")
	)
	(segment
		(start 451.176136 -408.007058)
		(end 451.176136 -402.798788)
		(width 0.254)
		(layer "In15.Cu")
		(net "PV09_RETIMER_CPU0_VCCS")
	)
	(segment
		(start 439.433208 -415.263076)
		(end 439.433208 -408.034744)
		(width 0.254)
		(layer "In15.Cu")
		(net "PV09_RETIMER_CPU0_VCCS")
	)
	(segment
		(start 443.709806 -421.435784)
		(end 442.399166 -421.435784)
		(width 0.254)
		(layer "In15.Cu")
		(net "PV09_RETIMER_CPU0_VCCS")
	)
	(segment
		(start 18.13052 -409.712922)
		(end 17.580864 -409.712922)
		(width 0.13462)
		(layer "F.Cu")
		(net "P0V9_RETIMER_CPU1_VRHOT")
	)
	(segment
		(start 18.829782 -409.167584)
		(end 18.675858 -409.167584)
		(width 0.13462)
		(layer "F.Cu")
		(net "P0V9_RETIMER_CPU1_VRHOT")
	)
	(segment
		(start 18.675858 -409.167584)
		(end 18.13052 -409.712922)
		(width 0.13462)
		(layer "F.Cu")
		(net "P0V9_RETIMER_CPU1_VRHOT")
	)
	(via
		(at 18.829782 -409.167584)
		(size 0.508)
		(drill 0.254)
		(layers "F.Cu" "B.Cu")
		(net "P0V9_RETIMER_CPU1_VRHOT")
	)
	(segment
		(start 19.727418 -409.44292)
		(end 19.105118 -409.44292)
		(width 0.1524)
		(layer "B.Cu")
		(net "P0V9_RETIMER_CPU1_VRHOT")
	)
	(segment
		(start 19.105118 -409.44292)
		(end 18.829782 -409.167584)
		(width 0.1524)
		(layer "B.Cu")
		(net "P0V9_RETIMER_CPU1_VRHOT")
	)
	(segment
		(start 11.158982 -409.909772)
		(end 11.387582 -409.909772)
		(width 0.1778)
		(layer "F.Cu")
		(net "P0V9_RETIMER_CPU1_TEMP1_R")
	)
	(segment
		(start 11.590782 -410.112972)
		(end 12.780772 -410.112972)
		(width 0.1778)
		(layer "F.Cu")
		(net "P0V9_RETIMER_CPU1_TEMP1_R")
	)
	(segment
		(start 11.387582 -409.909772)
		(end 11.590782 -410.112972)
		(width 0.1778)
		(layer "F.Cu")
		(net "P0V9_RETIMER_CPU1_TEMP1_R")
	)
	(via
		(at 11.158982 -409.909772)
		(size 0.508)
		(drill 0.254)
		(layers "F.Cu" "B.Cu")
		(net "P0V9_RETIMER_CPU1_TEMP1_R")
	)
	(segment
		(start 11.121644 -409.872434)
		(end 11.158982 -409.909772)
		(width 0.2032)
		(layer "B.Cu")
		(net "P0V9_RETIMER_CPU1_TEMP1_R")
	)
	(segment
		(start 9.838182 -409.872434)
		(end 11.121644 -409.872434)
		(width 0.2032)
		(layer "B.Cu")
		(net "P0V9_RETIMER_CPU1_TEMP1_R")
	)
	(segment
		(start 18.830036 -411.834584)
		(end 18.30832 -411.312868)
		(width 0.13462)
		(layer "F.Cu")
		(net "P0V9_RETIMER_CPU1_SVID_SDA")
	)
	(segment
		(start 18.30832 -411.312868)
		(end 17.580864 -411.312868)
		(width 0.13462)
		(layer "F.Cu")
		(net "P0V9_RETIMER_CPU1_SVID_SDA")
	)
	(segment
		(start 20.080732 -411.707584)
		(end 18.957036 -411.707584)
		(width 0.1524)
		(layer "F.Cu")
		(net "P0V9_RETIMER_CPU1_SVID_SDA")
	)
	(segment
		(start 18.957036 -411.707584)
		(end 18.830036 -411.834584)
		(width 0.1524)
		(layer "F.Cu")
		(net "P0V9_RETIMER_CPU1_SVID_SDA")
	)
	(via
		(at 18.830036 -411.834584)
		(size 0.508)
		(drill 0.254)
		(layers "F.Cu" "B.Cu")
		(net "P0V9_RETIMER_CPU1_SVID_SDA")
	)
	(segment
		(start 20.080732 -411.707584)
		(end 18.957036 -411.707584)
		(width 0.1524)
		(layer "B.Cu")
		(net "P0V9_RETIMER_CPU1_SVID_SDA")
	)
	(segment
		(start 18.957036 -411.707584)
		(end 18.830036 -411.834584)
		(width 0.1524)
		(layer "B.Cu")
		(net "P0V9_RETIMER_CPU1_SVID_SDA")
	)
	(segment
		(start 18.35277 -410.64942)
		(end 18.089372 -410.912818)
		(width 0.13462)
		(layer "F.Cu")
		(net "P0V9_RETIMER_CPU1_SVID_CLK")
	)
	(segment
		(start 19.465036 -410.564584)
		(end 19.348958 -410.680662)
		(width 0.1524)
		(layer "F.Cu")
		(net "P0V9_RETIMER_CPU1_SVID_CLK")
	)
	(segment
		(start 20.080732 -410.564584)
		(end 19.465036 -410.564584)
		(width 0.1524)
		(layer "F.Cu")
		(net "P0V9_RETIMER_CPU1_SVID_CLK")
	)
	(segment
		(start 18.089372 -410.912818)
		(end 17.580864 -410.912818)
		(width 0.13462)
		(layer "F.Cu")
		(net "P0V9_RETIMER_CPU1_SVID_CLK")
	)
	(segment
		(start 18.384012 -410.680662)
		(end 18.35277 -410.64942)
		(width 0.1524)
		(layer "F.Cu")
		(net "P0V9_RETIMER_CPU1_SVID_CLK")
	)
	(segment
		(start 19.348958 -410.680662)
		(end 18.384012 -410.680662)
		(width 0.1524)
		(layer "F.Cu")
		(net "P0V9_RETIMER_CPU1_SVID_CLK")
	)
	(via
		(at 18.35277 -410.64942)
		(size 0.508)
		(drill 0.254)
		(layers "F.Cu" "B.Cu")
		(net "P0V9_RETIMER_CPU1_SVID_CLK")
	)
	(segment
		(start 19.465036 -410.564584)
		(end 19.3802 -410.64942)
		(width 0.1524)
		(layer "B.Cu")
		(net "P0V9_RETIMER_CPU1_SVID_CLK")
	)
	(segment
		(start 20.080732 -410.564584)
		(end 19.465036 -410.564584)
		(width 0.1524)
		(layer "B.Cu")
		(net "P0V9_RETIMER_CPU1_SVID_CLK")
	)
	(segment
		(start 19.3802 -410.64942)
		(end 18.35277 -410.64942)
		(width 0.1524)
		(layer "B.Cu")
		(net "P0V9_RETIMER_CPU1_SVID_CLK")
	)
	(segment
		(start 7.676642 -380.799848)
		(end 7.159498 -380.799848)
		(width 0.254)
		(layer "F.Cu")
		(net "P0V9_RETIMER_CPU1_SENSE_SH_P")
	)
	(segment
		(start 7.159498 -380.799848)
		(end 6.91007 -380.55042)
		(width 0.254)
		(layer "F.Cu")
		(net "P0V9_RETIMER_CPU1_SENSE_SH_P")
	)
	(segment
		(start 8.006334 -380.470156)
		(end 7.676642 -380.799848)
		(width 0.254)
		(layer "F.Cu")
		(net "P0V9_RETIMER_CPU1_SENSE_SH_P")
	)
	(segment
		(start 20.107656 -415.795968)
		(end 19.577558 -415.26587)
		(width 0.254)
		(layer "F.Cu")
		(net "P0V9_RETIMER_CPU1_SENSE_SH_P")
	)
	(segment
		(start 19.577558 -415.26587)
		(end 18.730468 -415.26587)
		(width 0.254)
		(layer "F.Cu")
		(net "P0V9_RETIMER_CPU1_SENSE_SH_P")
	)
	(via
		(at 103.86695 -400.50847)
		(size 0.508)
		(drill 0.254)
		(layers "F.Cu" "B.Cu")
		(net "P0V9_RETIMER_CPU1_SENSE_SH_P")
	)
	(via
		(at 20.107656 -415.795968)
		(size 0.508)
		(drill 0.254)
		(layers "F.Cu" "B.Cu")
		(net "P0V9_RETIMER_CPU1_SENSE_SH_P")
	)
	(via
		(at 6.91007 -380.55042)
		(size 0.508)
		(drill 0.254)
		(layers "F.Cu" "B.Cu")
		(net "P0V9_RETIMER_CPU1_SENSE_SH_P")
	)
	(via
		(at 32.186118 -415.516822)
		(size 0.508)
		(drill 0.254)
		(layers "F.Cu" "B.Cu")
		(net "P0V9_RETIMER_CPU1_SENSE_SH_P")
	)
	(segment
		(start 14.436852 -406.850088)
		(end 16.093948 -406.850088)
		(width 0.254)
		(layer "In2.Cu")
		(net "P0V9_RETIMER_CPU1_SENSE_SH_P")
	)
	(segment
		(start 20.302728 -407.749756)
		(end 20.302728 -414.164018)
		(width 0.254)
		(layer "In2.Cu")
		(net "P0V9_RETIMER_CPU1_SENSE_SH_P")
	)
	(segment
		(start 18.812256 -406.259284)
		(end 20.302728 -407.749756)
		(width 0.254)
		(layer "In2.Cu")
		(net "P0V9_RETIMER_CPU1_SENSE_SH_P")
	)
	(segment
		(start 10.770616 -383.681986)
		(end 10.770616 -399.061178)
		(width 0.254)
		(layer "In2.Cu")
		(net "P0V9_RETIMER_CPU1_SENSE_SH_P")
	)
	(segment
		(start 13.91285 -406.326086)
		(end 14.436852 -406.850088)
		(width 0.254)
		(layer "In2.Cu")
		(net "P0V9_RETIMER_CPU1_SENSE_SH_P")
	)
	(segment
		(start 19.854926 -415.543238)
		(end 20.107656 -415.795968)
		(width 0.254)
		(layer "In2.Cu")
		(net "P0V9_RETIMER_CPU1_SENSE_SH_P")
	)
	(segment
		(start 16.093948 -406.850088)
		(end 16.684752 -406.259284)
		(width 0.254)
		(layer "In2.Cu")
		(net "P0V9_RETIMER_CPU1_SENSE_SH_P")
	)
	(segment
		(start 13.91285 -402.203412)
		(end 13.91285 -406.326086)
		(width 0.254)
		(layer "In2.Cu")
		(net "P0V9_RETIMER_CPU1_SENSE_SH_P")
	)
	(segment
		(start 20.302728 -414.164018)
		(end 19.854926 -414.61182)
		(width 0.254)
		(layer "In2.Cu")
		(net "P0V9_RETIMER_CPU1_SENSE_SH_P")
	)
	(segment
		(start 7.130542 -380.770892)
		(end 7.859522 -380.770892)
		(width 0.254)
		(layer "In2.Cu")
		(net "P0V9_RETIMER_CPU1_SENSE_SH_P")
	)
	(segment
		(start 10.770616 -399.061178)
		(end 13.91285 -402.203412)
		(width 0.254)
		(layer "In2.Cu")
		(net "P0V9_RETIMER_CPU1_SENSE_SH_P")
	)
	(segment
		(start 19.854926 -414.61182)
		(end 19.854926 -415.543238)
		(width 0.254)
		(layer "In2.Cu")
		(net "P0V9_RETIMER_CPU1_SENSE_SH_P")
	)
	(segment
		(start 16.684752 -406.259284)
		(end 18.812256 -406.259284)
		(width 0.254)
		(layer "In2.Cu")
		(net "P0V9_RETIMER_CPU1_SENSE_SH_P")
	)
	(segment
		(start 6.91007 -380.55042)
		(end 7.130542 -380.770892)
		(width 0.254)
		(layer "In2.Cu")
		(net "P0V9_RETIMER_CPU1_SENSE_SH_P")
	)
	(segment
		(start 7.859522 -380.770892)
		(end 10.770616 -383.681986)
		(width 0.254)
		(layer "In2.Cu")
		(net "P0V9_RETIMER_CPU1_SENSE_SH_P")
	)
	(segment
		(start 103.683308 -400.324828)
		(end 103.86695 -400.50847)
		(width 0.254)
		(layer "In4.Cu")
		(net "P0V9_RETIMER_CPU1_SENSE_SH_P")
	)
	(segment
		(start 99.317556 -399.442432)
		(end 99.694492 -399.065496)
		(width 0.254)
		(layer "In4.Cu")
		(net "P0V9_RETIMER_CPU1_SENSE_SH_P")
	)
	(segment
		(start 36.274248 -401.840954)
		(end 40.102028 -398.013174)
		(width 0.254)
		(layer "In4.Cu")
		(net "P0V9_RETIMER_CPU1_SENSE_SH_P")
	)
	(segment
		(start 99.694492 -399.065496)
		(end 100.576126 -399.065496)
		(width 0.254)
		(layer "In4.Cu")
		(net "P0V9_RETIMER_CPU1_SENSE_SH_P")
	)
	(segment
		(start 100.576126 -399.065496)
		(end 101.835458 -400.324828)
		(width 0.254)
		(layer "In4.Cu")
		(net "P0V9_RETIMER_CPU1_SENSE_SH_P")
	)
	(segment
		(start 101.835458 -400.324828)
		(end 103.683308 -400.324828)
		(width 0.254)
		(layer "In4.Cu")
		(net "P0V9_RETIMER_CPU1_SENSE_SH_P")
	)
	(segment
		(start 32.679894 -414.680654)
		(end 34.827464 -414.680654)
		(width 0.254)
		(layer "In4.Cu")
		(net "P0V9_RETIMER_CPU1_SENSE_SH_P")
	)
	(segment
		(start 40.102028 -396.828772)
		(end 40.696642 -396.234158)
		(width 0.254)
		(layer "In4.Cu")
		(net "P0V9_RETIMER_CPU1_SENSE_SH_P")
	)
	(segment
		(start 32.186118 -415.17443)
		(end 32.679894 -414.680654)
		(width 0.254)
		(layer "In4.Cu")
		(net "P0V9_RETIMER_CPU1_SENSE_SH_P")
	)
	(segment
		(start 40.696642 -396.234158)
		(end 45.165518 -396.234158)
		(width 0.254)
		(layer "In4.Cu")
		(net "P0V9_RETIMER_CPU1_SENSE_SH_P")
	)
	(segment
		(start 40.102028 -398.013174)
		(end 40.102028 -396.828772)
		(width 0.254)
		(layer "In4.Cu")
		(net "P0V9_RETIMER_CPU1_SENSE_SH_P")
	)
	(segment
		(start 97.27819 -399.442432)
		(end 99.317556 -399.442432)
		(width 0.254)
		(layer "In4.Cu")
		(net "P0V9_RETIMER_CPU1_SENSE_SH_P")
	)
	(segment
		(start 32.186118 -415.516822)
		(end 32.186118 -415.17443)
		(width 0.254)
		(layer "In4.Cu")
		(net "P0V9_RETIMER_CPU1_SENSE_SH_P")
	)
	(segment
		(start 45.165518 -396.234158)
		(end 46.782482 -397.851122)
		(width 0.254)
		(layer "In4.Cu")
		(net "P0V9_RETIMER_CPU1_SENSE_SH_P")
	)
	(segment
		(start 95.68688 -397.851122)
		(end 97.27819 -399.442432)
		(width 0.254)
		(layer "In4.Cu")
		(net "P0V9_RETIMER_CPU1_SENSE_SH_P")
	)
	(segment
		(start 34.827464 -414.680654)
		(end 36.274248 -413.23387)
		(width 0.254)
		(layer "In4.Cu")
		(net "P0V9_RETIMER_CPU1_SENSE_SH_P")
	)
	(segment
		(start 46.782482 -397.851122)
		(end 95.68688 -397.851122)
		(width 0.254)
		(layer "In4.Cu")
		(net "P0V9_RETIMER_CPU1_SENSE_SH_P")
	)
	(segment
		(start 36.274248 -413.23387)
		(end 36.274248 -401.840954)
		(width 0.254)
		(layer "In4.Cu")
		(net "P0V9_RETIMER_CPU1_SENSE_SH_P")
	)
	(segment
		(start 30.294326 -404.321264)
		(end 30.294326 -408.425142)
		(width 0.254)
		(layer "In6.Cu")
		(net "P0V9_RETIMER_CPU1_SENSE_SH_P")
	)
	(segment
		(start 10.724642 -385.82346)
		(end 13.680186 -388.779004)
		(width 0.254)
		(layer "In6.Cu")
		(net "P0V9_RETIMER_CPU1_SENSE_SH_P")
	)
	(segment
		(start 13.680186 -390.903714)
		(end 14.29639 -391.519918)
		(width 0.254)
		(layer "In6.Cu")
		(net "P0V9_RETIMER_CPU1_SENSE_SH_P")
	)
	(segment
		(start 30.294326 -408.425142)
		(end 33.163002 -411.293818)
		(width 0.254)
		(layer "In6.Cu")
		(net "P0V9_RETIMER_CPU1_SENSE_SH_P")
	)
	(segment
		(start 19.776186 -402.470366)
		(end 28.443428 -402.470366)
		(width 0.254)
		(layer "In6.Cu")
		(net "P0V9_RETIMER_CPU1_SENSE_SH_P")
	)
	(segment
		(start 7.946898 -380.77648)
		(end 10.724642 -383.554224)
		(width 0.254)
		(layer "In6.Cu")
		(net "P0V9_RETIMER_CPU1_SENSE_SH_P")
	)
	(segment
		(start 33.163002 -414.181036)
		(end 32.186118 -415.15792)
		(width 0.254)
		(layer "In6.Cu")
		(net "P0V9_RETIMER_CPU1_SENSE_SH_P")
	)
	(segment
		(start 7.13613 -380.77648)
		(end 7.946898 -380.77648)
		(width 0.254)
		(layer "In6.Cu")
		(net "P0V9_RETIMER_CPU1_SENSE_SH_P")
	)
	(segment
		(start 6.91007 -380.55042)
		(end 7.13613 -380.77648)
		(width 0.254)
		(layer "In6.Cu")
		(net "P0V9_RETIMER_CPU1_SENSE_SH_P")
	)
	(segment
		(start 16.818356 -391.519918)
		(end 18.48739 -393.188952)
		(width 0.254)
		(layer "In6.Cu")
		(net "P0V9_RETIMER_CPU1_SENSE_SH_P")
	)
	(segment
		(start 28.443428 -402.470366)
		(end 30.294326 -404.321264)
		(width 0.254)
		(layer "In6.Cu")
		(net "P0V9_RETIMER_CPU1_SENSE_SH_P")
	)
	(segment
		(start 33.163002 -411.293818)
		(end 33.163002 -414.181036)
		(width 0.254)
		(layer "In6.Cu")
		(net "P0V9_RETIMER_CPU1_SENSE_SH_P")
	)
	(segment
		(start 18.48739 -401.18157)
		(end 19.776186 -402.470366)
		(width 0.254)
		(layer "In6.Cu")
		(net "P0V9_RETIMER_CPU1_SENSE_SH_P")
	)
	(segment
		(start 32.186118 -415.15792)
		(end 32.186118 -415.516822)
		(width 0.254)
		(layer "In6.Cu")
		(net "P0V9_RETIMER_CPU1_SENSE_SH_P")
	)
	(segment
		(start 10.724642 -383.554224)
		(end 10.724642 -385.82346)
		(width 0.254)
		(layer "In6.Cu")
		(net "P0V9_RETIMER_CPU1_SENSE_SH_P")
	)
	(segment
		(start 18.48739 -393.188952)
		(end 18.48739 -401.18157)
		(width 0.254)
		(layer "In6.Cu")
		(net "P0V9_RETIMER_CPU1_SENSE_SH_P")
	)
	(segment
		(start 14.29639 -391.519918)
		(end 16.818356 -391.519918)
		(width 0.254)
		(layer "In6.Cu")
		(net "P0V9_RETIMER_CPU1_SENSE_SH_P")
	)
	(segment
		(start 13.680186 -388.779004)
		(end 13.680186 -390.903714)
		(width 0.254)
		(layer "In6.Cu")
		(net "P0V9_RETIMER_CPU1_SENSE_SH_P")
	)
	(segment
		(start 138.17854 -389.81126)
		(end 136.758172 -389.81126)
		(width 0.254)
		(layer "In15.Cu")
		(net "P0V9_RETIMER_CPU1_SENSE_SH_P")
	)
	(segment
		(start 113.56848 -395.774926)
		(end 109.031278 -400.312128)
		(width 0.254)
		(layer "In15.Cu")
		(net "P0V9_RETIMER_CPU1_SENSE_SH_P")
	)
	(segment
		(start 109.031278 -400.312128)
		(end 104.063292 -400.312128)
		(width 0.254)
		(layer "In15.Cu")
		(net "P0V9_RETIMER_CPU1_SENSE_SH_P")
	)
	(segment
		(start 136.185402 -390.618472)
		(end 136.185402 -393.723622)
		(width 0.254)
		(layer "In15.Cu")
		(net "P0V9_RETIMER_CPU1_SENSE_SH_P")
	)
	(segment
		(start 134.134098 -395.774926)
		(end 113.56848 -395.774926)
		(width 0.254)
		(layer "In15.Cu")
		(net "P0V9_RETIMER_CPU1_SENSE_SH_P")
	)
	(segment
		(start 104.063292 -400.312128)
		(end 103.86695 -400.50847)
		(width 0.254)
		(layer "In15.Cu")
		(net "P0V9_RETIMER_CPU1_SENSE_SH_P")
	)
	(segment
		(start 136.351264 -390.218168)
		(end 136.185402 -390.618472)
		(width 0.254)
		(layer "In15.Cu")
		(net "P0V9_RETIMER_CPU1_SENSE_SH_P")
	)
	(segment
		(start 136.758172 -389.81126)
		(end 136.351264 -390.218168)
		(width 0.254)
		(layer "In15.Cu")
		(net "P0V9_RETIMER_CPU1_SENSE_SH_P")
	)
	(segment
		(start 136.185402 -393.723622)
		(end 134.134098 -395.774926)
		(width 0.254)
		(layer "In15.Cu")
		(net "P0V9_RETIMER_CPU1_SENSE_SH_P")
	)
	(segment
		(start 8.006334 -381.562356)
		(end 7.624826 -381.180848)
		(width 0.254)
		(layer "F.Cu")
		(net "P0V9_RETIMER_CPU1_SENSE_SH_N")
	)
	(segment
		(start 16.580866 -413.049466)
		(end 17.178782 -413.647382)
		(width 0.1778)
		(layer "F.Cu")
		(net "P0V9_RETIMER_CPU1_SENSE_SH_N")
	)
	(segment
		(start 17.178782 -413.974534)
		(end 17.032732 -414.120584)
		(width 0.1778)
		(layer "F.Cu")
		(net "P0V9_RETIMER_CPU1_SENSE_SH_N")
	)
	(segment
		(start 17.032732 -414.120584)
		(end 17.032732 -415.302192)
		(width 0.254)
		(layer "F.Cu")
		(net "P0V9_RETIMER_CPU1_SENSE_SH_N")
	)
	(segment
		(start 16.580866 -412.712916)
		(end 16.580866 -413.049466)
		(width 0.1778)
		(layer "F.Cu")
		(net "P0V9_RETIMER_CPU1_SENSE_SH_N")
	)
	(segment
		(start 17.032732 -415.302192)
		(end 17.526762 -415.796222)
		(width 0.254)
		(layer "F.Cu")
		(net "P0V9_RETIMER_CPU1_SENSE_SH_N")
	)
	(segment
		(start 17.178782 -413.647382)
		(end 17.178782 -413.974534)
		(width 0.1778)
		(layer "F.Cu")
		(net "P0V9_RETIMER_CPU1_SENSE_SH_N")
	)
	(segment
		(start 17.526762 -415.796222)
		(end 19.244056 -415.796222)
		(width 0.254)
		(layer "F.Cu")
		(net "P0V9_RETIMER_CPU1_SENSE_SH_N")
	)
	(segment
		(start 7.624826 -381.180848)
		(end 7.143242 -381.180848)
		(width 0.254)
		(layer "F.Cu")
		(net "P0V9_RETIMER_CPU1_SENSE_SH_N")
	)
	(segment
		(start 7.143242 -381.180848)
		(end 6.91007 -381.41402)
		(width 0.254)
		(layer "F.Cu")
		(net "P0V9_RETIMER_CPU1_SENSE_SH_N")
	)
	(via
		(at 31.575248 -414.905952)
		(size 0.508)
		(drill 0.254)
		(layers "F.Cu" "B.Cu")
		(net "P0V9_RETIMER_CPU1_SENSE_SH_N")
	)
	(via
		(at 6.91007 -381.41402)
		(size 0.508)
		(drill 0.254)
		(layers "F.Cu" "B.Cu")
		(net "P0V9_RETIMER_CPU1_SENSE_SH_N")
	)
	(via
		(at 19.244056 -415.796222)
		(size 0.508)
		(drill 0.254)
		(layers "F.Cu" "B.Cu")
		(net "P0V9_RETIMER_CPU1_SENSE_SH_N")
	)
	(via
		(at 103.86695 -399.74647)
		(size 0.508)
		(drill 0.254)
		(layers "F.Cu" "B.Cu")
		(net "P0V9_RETIMER_CPU1_SENSE_SH_N")
	)
	(segment
		(start 19.473926 -415.566352)
		(end 19.244056 -415.796222)
		(width 0.254)
		(layer "In2.Cu")
		(net "P0V9_RETIMER_CPU1_SENSE_SH_N")
	)
	(segment
		(start 19.921728 -407.907744)
		(end 19.921728 -414.00603)
		(width 0.254)
		(layer "In2.Cu")
		(net "P0V9_RETIMER_CPU1_SENSE_SH_N")
	)
	(segment
		(start 19.921728 -414.00603)
		(end 19.473926 -414.453832)
		(width 0.254)
		(layer "In2.Cu")
		(net "P0V9_RETIMER_CPU1_SENSE_SH_N")
	)
	(segment
		(start 16.251936 -407.231088)
		(end 16.84274 -406.640284)
		(width 0.254)
		(layer "In2.Cu")
		(net "P0V9_RETIMER_CPU1_SENSE_SH_N")
	)
	(segment
		(start 13.53185 -406.484074)
		(end 14.278864 -407.231088)
		(width 0.254)
		(layer "In2.Cu")
		(net "P0V9_RETIMER_CPU1_SENSE_SH_N")
	)
	(segment
		(start 13.53185 -402.3614)
		(end 13.53185 -406.484074)
		(width 0.254)
		(layer "In2.Cu")
		(net "P0V9_RETIMER_CPU1_SENSE_SH_N")
	)
	(segment
		(start 16.84274 -406.640284)
		(end 18.654268 -406.640284)
		(width 0.254)
		(layer "In2.Cu")
		(net "P0V9_RETIMER_CPU1_SENSE_SH_N")
	)
	(segment
		(start 6.91007 -381.41402)
		(end 7.172198 -381.151892)
		(width 0.254)
		(layer "In2.Cu")
		(net "P0V9_RETIMER_CPU1_SENSE_SH_N")
	)
	(segment
		(start 7.701534 -381.151892)
		(end 10.389616 -383.839974)
		(width 0.254)
		(layer "In2.Cu")
		(net "P0V9_RETIMER_CPU1_SENSE_SH_N")
	)
	(segment
		(start 10.389616 -399.219166)
		(end 13.53185 -402.3614)
		(width 0.254)
		(layer "In2.Cu")
		(net "P0V9_RETIMER_CPU1_SENSE_SH_N")
	)
	(segment
		(start 14.278864 -407.231088)
		(end 16.251936 -407.231088)
		(width 0.254)
		(layer "In2.Cu")
		(net "P0V9_RETIMER_CPU1_SENSE_SH_N")
	)
	(segment
		(start 10.389616 -383.839974)
		(end 10.389616 -399.219166)
		(width 0.254)
		(layer "In2.Cu")
		(net "P0V9_RETIMER_CPU1_SENSE_SH_N")
	)
	(segment
		(start 18.654268 -406.640284)
		(end 19.921728 -407.907744)
		(width 0.254)
		(layer "In2.Cu")
		(net "P0V9_RETIMER_CPU1_SENSE_SH_N")
	)
	(segment
		(start 7.172198 -381.151892)
		(end 7.701534 -381.151892)
		(width 0.254)
		(layer "In2.Cu")
		(net "P0V9_RETIMER_CPU1_SENSE_SH_N")
	)
	(segment
		(start 19.473926 -414.453832)
		(end 19.473926 -415.566352)
		(width 0.254)
		(layer "In2.Cu")
		(net "P0V9_RETIMER_CPU1_SENSE_SH_N")
	)
	(segment
		(start 100.734114 -398.684496)
		(end 101.993446 -399.943828)
		(width 0.254)
		(layer "In4.Cu")
		(net "P0V9_RETIMER_CPU1_SENSE_SH_N")
	)
	(segment
		(start 39.721028 -397.855186)
		(end 39.721028 -396.670784)
		(width 0.254)
		(layer "In4.Cu")
		(net "P0V9_RETIMER_CPU1_SENSE_SH_N")
	)
	(segment
		(start 46.94047 -397.470122)
		(end 95.844868 -397.470122)
		(width 0.254)
		(layer "In4.Cu")
		(net "P0V9_RETIMER_CPU1_SENSE_SH_N")
	)
	(segment
		(start 35.893248 -401.682966)
		(end 39.721028 -397.855186)
		(width 0.254)
		(layer "In4.Cu")
		(net "P0V9_RETIMER_CPU1_SENSE_SH_N")
	)
	(segment
		(start 101.993446 -399.943828)
		(end 103.669592 -399.943828)
		(width 0.254)
		(layer "In4.Cu")
		(net "P0V9_RETIMER_CPU1_SENSE_SH_N")
	)
	(segment
		(start 103.669592 -399.943828)
		(end 103.86695 -399.74647)
		(width 0.254)
		(layer "In4.Cu")
		(net "P0V9_RETIMER_CPU1_SENSE_SH_N")
	)
	(segment
		(start 39.721028 -396.670784)
		(end 40.538654 -395.853158)
		(width 0.254)
		(layer "In4.Cu")
		(net "P0V9_RETIMER_CPU1_SENSE_SH_N")
	)
	(segment
		(start 95.844868 -397.470122)
		(end 97.436178 -399.061432)
		(width 0.254)
		(layer "In4.Cu")
		(net "P0V9_RETIMER_CPU1_SENSE_SH_N")
	)
	(segment
		(start 32.521906 -414.299654)
		(end 34.669476 -414.299654)
		(width 0.254)
		(layer "In4.Cu")
		(net "P0V9_RETIMER_CPU1_SENSE_SH_N")
	)
	(segment
		(start 99.159568 -399.061432)
		(end 99.536504 -398.684496)
		(width 0.254)
		(layer "In4.Cu")
		(net "P0V9_RETIMER_CPU1_SENSE_SH_N")
	)
	(segment
		(start 40.538654 -395.853158)
		(end 45.323506 -395.853158)
		(width 0.254)
		(layer "In4.Cu")
		(net "P0V9_RETIMER_CPU1_SENSE_SH_N")
	)
	(segment
		(start 97.436178 -399.061432)
		(end 99.159568 -399.061432)
		(width 0.254)
		(layer "In4.Cu")
		(net "P0V9_RETIMER_CPU1_SENSE_SH_N")
	)
	(segment
		(start 99.536504 -398.684496)
		(end 100.734114 -398.684496)
		(width 0.254)
		(layer "In4.Cu")
		(net "P0V9_RETIMER_CPU1_SENSE_SH_N")
	)
	(segment
		(start 35.893248 -413.075882)
		(end 35.893248 -401.682966)
		(width 0.254)
		(layer "In4.Cu")
		(net "P0V9_RETIMER_CPU1_SENSE_SH_N")
	)
	(segment
		(start 31.575248 -414.905952)
		(end 31.915608 -414.905952)
		(width 0.254)
		(layer "In4.Cu")
		(net "P0V9_RETIMER_CPU1_SENSE_SH_N")
	)
	(segment
		(start 34.669476 -414.299654)
		(end 35.893248 -413.075882)
		(width 0.254)
		(layer "In4.Cu")
		(net "P0V9_RETIMER_CPU1_SENSE_SH_N")
	)
	(segment
		(start 45.323506 -395.853158)
		(end 46.94047 -397.470122)
		(width 0.254)
		(layer "In4.Cu")
		(net "P0V9_RETIMER_CPU1_SENSE_SH_N")
	)
	(segment
		(start 31.915608 -414.905952)
		(end 32.521906 -414.299654)
		(width 0.254)
		(layer "In4.Cu")
		(net "P0V9_RETIMER_CPU1_SENSE_SH_N")
	)
	(segment
		(start 13.299186 -391.061702)
		(end 14.138402 -391.900918)
		(width 0.254)
		(layer "In6.Cu")
		(net "P0V9_RETIMER_CPU1_SENSE_SH_N")
	)
	(segment
		(start 18.10639 -393.34694)
		(end 18.10639 -401.339558)
		(width 0.254)
		(layer "In6.Cu")
		(net "P0V9_RETIMER_CPU1_SENSE_SH_N")
	)
	(segment
		(start 10.343642 -385.981448)
		(end 13.299186 -388.936992)
		(width 0.254)
		(layer "In6.Cu")
		(net "P0V9_RETIMER_CPU1_SENSE_SH_N")
	)
	(segment
		(start 32.782002 -411.451806)
		(end 32.782002 -414.023048)
		(width 0.254)
		(layer "In6.Cu")
		(net "P0V9_RETIMER_CPU1_SENSE_SH_N")
	)
	(segment
		(start 31.899098 -414.905952)
		(end 31.575248 -414.905952)
		(width 0.254)
		(layer "In6.Cu")
		(net "P0V9_RETIMER_CPU1_SENSE_SH_N")
	)
	(segment
		(start 18.10639 -401.339558)
		(end 19.618198 -402.851366)
		(width 0.254)
		(layer "In6.Cu")
		(net "P0V9_RETIMER_CPU1_SENSE_SH_N")
	)
	(segment
		(start 14.138402 -391.900918)
		(end 16.660368 -391.900918)
		(width 0.254)
		(layer "In6.Cu")
		(net "P0V9_RETIMER_CPU1_SENSE_SH_N")
	)
	(segment
		(start 16.660368 -391.900918)
		(end 18.10639 -393.34694)
		(width 0.254)
		(layer "In6.Cu")
		(net "P0V9_RETIMER_CPU1_SENSE_SH_N")
	)
	(segment
		(start 29.913326 -404.479252)
		(end 29.913326 -408.58313)
		(width 0.254)
		(layer "In6.Cu")
		(net "P0V9_RETIMER_CPU1_SENSE_SH_N")
	)
	(segment
		(start 13.299186 -388.936992)
		(end 13.299186 -391.061702)
		(width 0.254)
		(layer "In6.Cu")
		(net "P0V9_RETIMER_CPU1_SENSE_SH_N")
	)
	(segment
		(start 6.91007 -381.41402)
		(end 7.16661 -381.15748)
		(width 0.254)
		(layer "In6.Cu")
		(net "P0V9_RETIMER_CPU1_SENSE_SH_N")
	)
	(segment
		(start 10.343642 -383.712212)
		(end 10.343642 -385.981448)
		(width 0.254)
		(layer "In6.Cu")
		(net "P0V9_RETIMER_CPU1_SENSE_SH_N")
	)
	(segment
		(start 29.913326 -408.58313)
		(end 32.782002 -411.451806)
		(width 0.254)
		(layer "In6.Cu")
		(net "P0V9_RETIMER_CPU1_SENSE_SH_N")
	)
	(segment
		(start 7.78891 -381.15748)
		(end 10.343642 -383.712212)
		(width 0.254)
		(layer "In6.Cu")
		(net "P0V9_RETIMER_CPU1_SENSE_SH_N")
	)
	(segment
		(start 32.782002 -414.023048)
		(end 31.899098 -414.905952)
		(width 0.254)
		(layer "In6.Cu")
		(net "P0V9_RETIMER_CPU1_SENSE_SH_N")
	)
	(segment
		(start 7.16661 -381.15748)
		(end 7.78891 -381.15748)
		(width 0.254)
		(layer "In6.Cu")
		(net "P0V9_RETIMER_CPU1_SENSE_SH_N")
	)
	(segment
		(start 28.28544 -402.851366)
		(end 29.913326 -404.479252)
		(width 0.254)
		(layer "In6.Cu")
		(net "P0V9_RETIMER_CPU1_SENSE_SH_N")
	)
	(segment
		(start 19.618198 -402.851366)
		(end 28.28544 -402.851366)
		(width 0.254)
		(layer "In6.Cu")
		(net "P0V9_RETIMER_CPU1_SENSE_SH_N")
	)
	(segment
		(start 136.600184 -389.43026)
		(end 136.028176 -390.002268)
		(width 0.254)
		(layer "In15.Cu")
		(net "P0V9_RETIMER_CPU1_SENSE_SH_N")
	)
	(segment
		(start 113.410492 -395.393926)
		(end 108.87329 -399.931128)
		(width 0.254)
		(layer "In15.Cu")
		(net "P0V9_RETIMER_CPU1_SENSE_SH_N")
	)
	(segment
		(start 138.17854 -389.43026)
		(end 136.600184 -389.43026)
		(width 0.254)
		(layer "In15.Cu")
		(net "P0V9_RETIMER_CPU1_SENSE_SH_N")
	)
	(segment
		(start 133.97611 -395.393926)
		(end 113.410492 -395.393926)
		(width 0.254)
		(layer "In15.Cu")
		(net "P0V9_RETIMER_CPU1_SENSE_SH_N")
	)
	(segment
		(start 108.87329 -399.931128)
		(end 104.051608 -399.931128)
		(width 0.254)
		(layer "In15.Cu")
		(net "P0V9_RETIMER_CPU1_SENSE_SH_N")
	)
	(segment
		(start 136.028176 -390.002268)
		(end 135.804402 -390.542526)
		(width 0.254)
		(layer "In15.Cu")
		(net "P0V9_RETIMER_CPU1_SENSE_SH_N")
	)
	(segment
		(start 135.804402 -390.542526)
		(end 135.804402 -393.565634)
		(width 0.254)
		(layer "In15.Cu")
		(net "P0V9_RETIMER_CPU1_SENSE_SH_N")
	)
	(segment
		(start 135.804402 -393.565634)
		(end 133.97611 -395.393926)
		(width 0.254)
		(layer "In15.Cu")
		(net "P0V9_RETIMER_CPU1_SENSE_SH_N")
	)
	(segment
		(start 104.051608 -399.931128)
		(end 103.86695 -399.74647)
		(width 0.254)
		(layer "In15.Cu")
		(net "P0V9_RETIMER_CPU1_SENSE_SH_N")
	)
	(segment
		(start 17.72285 -412.112968)
		(end 17.580864 -412.112968)
		(width 0.1524)
		(layer "F.Cu")
		(net "P0V9_RETIMER_CPU1_EN1_R")
	)
	(segment
		(start 17.924018 -412.314136)
		(end 17.72285 -412.112968)
		(width 0.10668)
		(layer "F.Cu")
		(net "P0V9_RETIMER_CPU1_EN1_R")
	)
	(segment
		(start 17.924018 -412.903162)
		(end 17.924018 -412.314136)
		(width 0.10668)
		(layer "F.Cu")
		(net "P0V9_RETIMER_CPU1_EN1_R")
	)
	(via
		(at 17.924018 -412.903162)
		(size 0.508)
		(drill 0.254)
		(layers "F.Cu" "B.Cu")
		(net "P0V9_RETIMER_CPU1_EN1_R")
	)
	(segment
		(start 17.924018 -413.501078)
		(end 17.924018 -412.903162)
		(width 0.10668)
		(layer "B.Cu")
		(net "P0V9_RETIMER_CPU1_EN1_R")
	)
	(segment
		(start 20.089368 -413.99587)
		(end 18.41881 -413.99587)
		(width 0.10668)
		(layer "B.Cu")
		(net "P0V9_RETIMER_CPU1_EN1_R")
	)
	(segment
		(start 18.41881 -413.99587)
		(end 17.924018 -413.501078)
		(width 0.10668)
		(layer "B.Cu")
		(net "P0V9_RETIMER_CPU1_EN1_R")
	)
	(segment
		(start 18.871692 -408.376628)
		(end 19.915124 -408.376628)
		(width 0.1524)
		(layer "F.Cu")
		(net "P0V9_RETIMER_CPU1_EN0_R")
	)
	(segment
		(start 18.855182 -408.393138)
		(end 18.871692 -408.376628)
		(width 0.1524)
		(layer "F.Cu")
		(net "P0V9_RETIMER_CPU1_EN0_R")
	)
	(segment
		(start 17.935448 -409.312872)
		(end 18.855182 -408.393138)
		(width 0.1524)
		(layer "F.Cu")
		(net "P0V9_RETIMER_CPU1_EN0_R")
	)
	(segment
		(start 17.580864 -409.312872)
		(end 17.935448 -409.312872)
		(width 0.1524)
		(layer "F.Cu")
		(net "P0V9_RETIMER_CPU1_EN0_R")
	)
	(segment
		(start 19.915124 -408.376628)
		(end 20.981924 -408.376628)
		(width 0.10668)
		(layer "F.Cu")
		(net "P0V9_RETIMER_CPU1_EN0_R")
	)
	(via
		(at 18.855182 -408.393138)
		(size 0.762)
		(drill 0.381)
		(layers "F.Cu" "B.Cu")
		(net "P0V9_RETIMER_CPU1_EN0_R")
	)
	(segment
		(start 12.780772 -411.312868)
		(end 11.985752 -411.312868)
		(width 0.1778)
		(layer "F.Cu")
		(net "P0V9_RETIMER_CPU1_CFP")
	)
	(segment
		(start 11.539982 -413.231584)
		(end 11.641582 -413.129984)
		(width 0.1778)
		(layer "F.Cu")
		(net "P0V9_RETIMER_CPU1_CFP")
	)
	(segment
		(start 11.472418 -411.826202)
		(end 11.472418 -412.472378)
		(width 0.1778)
		(layer "F.Cu")
		(net "P0V9_RETIMER_CPU1_CFP")
	)
	(segment
		(start 11.641582 -412.641542)
		(end 11.641582 -413.129984)
		(width 0.1778)
		(layer "F.Cu")
		(net "P0V9_RETIMER_CPU1_CFP")
	)
	(segment
		(start 11.985752 -411.312868)
		(end 11.472418 -411.826202)
		(width 0.1778)
		(layer "F.Cu")
		(net "P0V9_RETIMER_CPU1_CFP")
	)
	(segment
		(start 10.466832 -413.231584)
		(end 11.539982 -413.231584)
		(width 0.1778)
		(layer "F.Cu")
		(net "P0V9_RETIMER_CPU1_CFP")
	)
	(segment
		(start 11.472418 -412.472378)
		(end 11.641582 -412.641542)
		(width 0.1778)
		(layer "F.Cu")
		(net "P0V9_RETIMER_CPU1_CFP")
	)
	(via
		(at 11.641582 -413.129984)
		(size 0.762)
		(drill 0.381)
		(layers "F.Cu" "B.Cu")
		(net "P0V9_RETIMER_CPU1_CFP")
	)
	(segment
		(start 11.082782 -411.885384)
		(end 11.082782 -411.530038)
		(width 0.1778)
		(layer "F.Cu")
		(net "P0V9_RETIMER_CPU1_ADDR")
	)
	(segment
		(start 10.752582 -412.215584)
		(end 11.082782 -411.885384)
		(width 0.2032)
		(layer "F.Cu")
		(net "P0V9_RETIMER_CPU1_ADDR")
	)
	(segment
		(start 11.700002 -410.912818)
		(end 12.780772 -410.912818)
		(width 0.1778)
		(layer "F.Cu")
		(net "P0V9_RETIMER_CPU1_ADDR")
	)
	(segment
		(start 11.082782 -411.530038)
		(end 11.700002 -410.912818)
		(width 0.1778)
		(layer "F.Cu")
		(net "P0V9_RETIMER_CPU1_ADDR")
	)
	(segment
		(start 10.466832 -412.215584)
		(end 10.752582 -412.215584)
		(width 0.2032)
		(layer "F.Cu")
		(net "P0V9_RETIMER_CPU1_ADDR")
	)
	(segment
		(start 441.379864 -424.514772)
		(end 441.92952 -424.514772)
		(width 0.13462)
		(layer "F.Cu")
		(net "P0V9_RETIMER_CPU0_VRHOT")
	)
	(segment
		(start 440.680602 -425.06011)
		(end 440.834526 -425.06011)
		(width 0.13462)
		(layer "F.Cu")
		(net "P0V9_RETIMER_CPU0_VRHOT")
	)
	(segment
		(start 440.834526 -425.06011)
		(end 441.379864 -424.514772)
		(width 0.13462)
		(layer "F.Cu")
		(net "P0V9_RETIMER_CPU0_VRHOT")
	)
	(via
		(at 440.680602 -425.06011)
		(size 0.508)
		(drill 0.254)
		(layers "F.Cu" "B.Cu")
		(net "P0V9_RETIMER_CPU0_VRHOT")
	)
	(segment
		(start 440.405266 -424.784774)
		(end 440.680602 -425.06011)
		(width 0.1524)
		(layer "B.Cu")
		(net "P0V9_RETIMER_CPU0_VRHOT")
	)
	(segment
		(start 439.782966 -424.784774)
		(end 440.405266 -424.784774)
		(width 0.1524)
		(layer "B.Cu")
		(net "P0V9_RETIMER_CPU0_VRHOT")
	)
	(segment
		(start 448.351402 -424.317922)
		(end 448.122802 -424.317922)
		(width 0.1778)
		(layer "F.Cu")
		(net "P0V9_RETIMER_CPU0_TEMP1_R")
	)
	(segment
		(start 447.919602 -424.114722)
		(end 446.729612 -424.114722)
		(width 0.1778)
		(layer "F.Cu")
		(net "P0V9_RETIMER_CPU0_TEMP1_R")
	)
	(segment
		(start 448.122802 -424.317922)
		(end 447.919602 -424.114722)
		(width 0.1778)
		(layer "F.Cu")
		(net "P0V9_RETIMER_CPU0_TEMP1_R")
	)
	(via
		(at 448.351402 -424.317922)
		(size 0.508)
		(drill 0.254)
		(layers "F.Cu" "B.Cu")
		(net "P0V9_RETIMER_CPU0_TEMP1_R")
	)
	(segment
		(start 449.39966 -423.935398)
		(end 448.733926 -423.935398)
		(width 0.254)
		(layer "B.Cu")
		(net "P0V9_RETIMER_CPU0_TEMP1_R")
	)
	(segment
		(start 448.733926 -423.935398)
		(end 448.351402 -424.317922)
		(width 0.254)
		(layer "B.Cu")
		(net "P0V9_RETIMER_CPU0_TEMP1_R")
	)
	(segment
		(start 440.680348 -422.39311)
		(end 441.202064 -422.914826)
		(width 0.13462)
		(layer "F.Cu")
		(net "P0V9_RETIMER_CPU0_SVID_SDA")
	)
	(segment
		(start 441.202064 -422.914826)
		(end 441.92952 -422.914826)
		(width 0.13462)
		(layer "F.Cu")
		(net "P0V9_RETIMER_CPU0_SVID_SDA")
	)
	(segment
		(start 439.429652 -422.52011)
		(end 440.553348 -422.52011)
		(width 0.1524)
		(layer "F.Cu")
		(net "P0V9_RETIMER_CPU0_SVID_SDA")
	)
	(segment
		(start 440.553348 -422.52011)
		(end 440.680348 -422.39311)
		(width 0.1524)
		(layer "F.Cu")
		(net "P0V9_RETIMER_CPU0_SVID_SDA")
	)
	(via
		(at 440.680348 -422.39311)
		(size 0.508)
		(drill 0.254)
		(layers "F.Cu" "B.Cu")
		(net "P0V9_RETIMER_CPU0_SVID_SDA")
	)
	(segment
		(start 439.429652 -422.52011)
		(end 440.553348 -422.52011)
		(width 0.1524)
		(layer "B.Cu")
		(net "P0V9_RETIMER_CPU0_SVID_SDA")
	)
	(segment
		(start 440.553348 -422.52011)
		(end 440.680348 -422.39311)
		(width 0.1524)
		(layer "B.Cu")
		(net "P0V9_RETIMER_CPU0_SVID_SDA")
	)
	(segment
		(start 440.585606 -423.215562)
		(end 440.68492 -423.314876)
		(width 0.10668)
		(layer "F.Cu")
		(net "P0V9_RETIMER_CPU0_SVID_CLK")
	)
	(segment
		(start 440.045348 -423.66311)
		(end 440.492896 -423.215562)
		(width 0.10668)
		(layer "F.Cu")
		(net "P0V9_RETIMER_CPU0_SVID_CLK")
	)
	(segment
		(start 440.492896 -423.215562)
		(end 440.585606 -423.215562)
		(width 0.10668)
		(layer "F.Cu")
		(net "P0V9_RETIMER_CPU0_SVID_CLK")
	)
	(segment
		(start 439.429652 -423.66311)
		(end 440.045348 -423.66311)
		(width 0.1524)
		(layer "F.Cu")
		(net "P0V9_RETIMER_CPU0_SVID_CLK")
	)
	(segment
		(start 440.68492 -423.314876)
		(end 441.92952 -423.314876)
		(width 0.10668)
		(layer "F.Cu")
		(net "P0V9_RETIMER_CPU0_SVID_CLK")
	)
	(via
		(at 440.585606 -423.215562)
		(size 0.762)
		(drill 0.254)
		(layers "F.Cu" "B.Cu")
		(net "P0V9_RETIMER_CPU0_SVID_CLK")
	)
	(segment
		(start 440.045348 -423.66311)
		(end 439.429652 -423.66311)
		(width 0.1524)
		(layer "B.Cu")
		(net "P0V9_RETIMER_CPU0_SVID_CLK")
	)
	(segment
		(start 440.492896 -423.215562)
		(end 440.045348 -423.66311)
		(width 0.10668)
		(layer "B.Cu")
		(net "P0V9_RETIMER_CPU0_SVID_CLK")
	)
	(segment
		(start 440.585606 -423.215562)
		(end 440.492896 -423.215562)
		(width 0.10668)
		(layer "B.Cu")
		(net "P0V9_RETIMER_CPU0_SVID_CLK")
	)
	(segment
		(start 438.902094 -391.061702)
		(end 438.902094 -389.380222)
		(width 0.254)
		(layer "F.Cu")
		(net "P0V9_RETIMER_CPU0_SENSE_SH_P")
	)
	(segment
		(start 438.902094 -389.380222)
		(end 439.421016 -388.8613)
		(width 0.254)
		(layer "F.Cu")
		(net "P0V9_RETIMER_CPU0_SENSE_SH_P")
	)
	(segment
		(start 440.779916 -418.961824)
		(end 439.026554 -418.961824)
		(width 0.254)
		(layer "F.Cu")
		(net "P0V9_RETIMER_CPU0_SENSE_SH_P")
	)
	(segment
		(start 438.557416 -391.40638)
		(end 438.902094 -391.061702)
		(width 0.254)
		(layer "F.Cu")
		(net "P0V9_RETIMER_CPU0_SENSE_SH_P")
	)
	(segment
		(start 439.026554 -418.961824)
		(end 438.500774 -418.436044)
		(width 0.254)
		(layer "F.Cu")
		(net "P0V9_RETIMER_CPU0_SENSE_SH_P")
	)
	(via
		(at 438.557416 -391.40638)
		(size 0.508)
		(drill 0.254)
		(layers "F.Cu" "B.Cu")
		(net "P0V9_RETIMER_CPU0_SENSE_SH_P")
	)
	(via
		(at 438.500774 -418.436044)
		(size 0.508)
		(drill 0.254)
		(layers "F.Cu" "B.Cu")
		(net "P0V9_RETIMER_CPU0_SENSE_SH_P")
	)
	(segment
		(start 438.833006 -418.103812)
		(end 438.833006 -415.986214)
		(width 0.254)
		(layer "In2.Cu")
		(net "P0V9_RETIMER_CPU0_SENSE_SH_P")
	)
	(segment
		(start 438.833006 -415.986214)
		(end 440.411108 -414.408112)
		(width 0.254)
		(layer "In2.Cu")
		(net "P0V9_RETIMER_CPU0_SENSE_SH_P")
	)
	(segment
		(start 439.5851 -394.19784)
		(end 438.806082 -393.418822)
		(width 0.254)
		(layer "In2.Cu")
		(net "P0V9_RETIMER_CPU0_SENSE_SH_P")
	)
	(segment
		(start 439.5851 -405.63038)
		(end 439.5851 -394.19784)
		(width 0.254)
		(layer "In2.Cu")
		(net "P0V9_RETIMER_CPU0_SENSE_SH_P")
	)
	(segment
		(start 440.411108 -406.456388)
		(end 439.5851 -405.63038)
		(width 0.254)
		(layer "In2.Cu")
		(net "P0V9_RETIMER_CPU0_SENSE_SH_P")
	)
	(segment
		(start 438.806082 -392.420094)
		(end 438.805828 -392.313922)
		(width 0.254)
		(layer "In2.Cu")
		(net "P0V9_RETIMER_CPU0_SENSE_SH_P")
	)
	(segment
		(start 438.805828 -392.313922)
		(end 438.805828 -391.654284)
		(width 0.254)
		(layer "In2.Cu")
		(net "P0V9_RETIMER_CPU0_SENSE_SH_P")
	)
	(segment
		(start 438.805828 -391.654284)
		(end 438.557416 -391.40638)
		(width 0.254)
		(layer "In2.Cu")
		(net "P0V9_RETIMER_CPU0_SENSE_SH_P")
	)
	(segment
		(start 438.500774 -418.436044)
		(end 438.833006 -418.103812)
		(width 0.254)
		(layer "In2.Cu")
		(net "P0V9_RETIMER_CPU0_SENSE_SH_P")
	)
	(segment
		(start 440.411108 -414.408112)
		(end 440.411108 -406.456388)
		(width 0.254)
		(layer "In2.Cu")
		(net "P0V9_RETIMER_CPU0_SENSE_SH_P")
	)
	(segment
		(start 438.806082 -393.418822)
		(end 438.806082 -392.420094)
		(width 0.254)
		(layer "In2.Cu")
		(net "P0V9_RETIMER_CPU0_SENSE_SH_P")
	)
	(segment
		(start 304.055018 -408.979116)
		(end 304.819812 -408.214322)
		(width 0.254)
		(layer "In11.Cu")
		(net "P0V9_RETIMER_CPU0_SENSE_SH_P")
	)
	(segment
		(start 362.544868 -407.787602)
		(end 429.344074 -407.787602)
		(width 0.254)
		(layer "In11.Cu")
		(net "P0V9_RETIMER_CPU0_SENSE_SH_P")
	)
	(segment
		(start 438.794652 -392.313922)
		(end 438.794652 -391.643108)
		(width 0.254)
		(layer "In11.Cu")
		(net "P0V9_RETIMER_CPU0_SENSE_SH_P")
	)
	(segment
		(start 361.217718 -409.114752)
		(end 362.544868 -407.787602)
		(width 0.254)
		(layer "In11.Cu")
		(net "P0V9_RETIMER_CPU0_SENSE_SH_P")
	)
	(segment
		(start 431.847752 -396.64767)
		(end 435.061614 -393.433808)
		(width 0.254)
		(layer "In11.Cu")
		(net "P0V9_RETIMER_CPU0_SENSE_SH_P")
	)
	(segment
		(start 435.061614 -393.433808)
		(end 438.171336 -393.433808)
		(width 0.254)
		(layer "In11.Cu")
		(net "P0V9_RETIMER_CPU0_SENSE_SH_P")
	)
	(segment
		(start 438.794906 -392.810238)
		(end 438.794906 -392.483594)
		(width 0.254)
		(layer "In11.Cu")
		(net "P0V9_RETIMER_CPU0_SENSE_SH_P")
	)
	(segment
		(start 438.794652 -391.643108)
		(end 438.557416 -391.40638)
		(width 0.254)
		(layer "In11.Cu")
		(net "P0V9_RETIMER_CPU0_SENSE_SH_P")
	)
	(segment
		(start 431.847752 -405.283924)
		(end 431.847752 -396.64767)
		(width 0.254)
		(layer "In11.Cu")
		(net "P0V9_RETIMER_CPU0_SENSE_SH_P")
	)
	(segment
		(start 304.055018 -409.496514)
		(end 304.055018 -408.979116)
		(width 0.254)
		(layer "In11.Cu")
		(net "P0V9_RETIMER_CPU0_SENSE_SH_P")
	)
	(segment
		(start 310.09971 -408.214322)
		(end 311.00014 -409.114752)
		(width 0.254)
		(layer "In11.Cu")
		(net "P0V9_RETIMER_CPU0_SENSE_SH_P")
	)
	(segment
		(start 438.794906 -392.483594)
		(end 438.794652 -392.313922)
		(width 0.254)
		(layer "In11.Cu")
		(net "P0V9_RETIMER_CPU0_SENSE_SH_P")
	)
	(segment
		(start 438.171336 -393.433808)
		(end 438.794906 -392.810238)
		(width 0.254)
		(layer "In11.Cu")
		(net "P0V9_RETIMER_CPU0_SENSE_SH_P")
	)
	(segment
		(start 311.00014 -409.114752)
		(end 361.217718 -409.114752)
		(width 0.254)
		(layer "In11.Cu")
		(net "P0V9_RETIMER_CPU0_SENSE_SH_P")
	)
	(segment
		(start 429.344074 -407.787602)
		(end 431.847752 -405.283924)
		(width 0.254)
		(layer "In11.Cu")
		(net "P0V9_RETIMER_CPU0_SENSE_SH_P")
	)
	(segment
		(start 304.819812 -408.214322)
		(end 310.09971 -408.214322)
		(width 0.254)
		(layer "In11.Cu")
		(net "P0V9_RETIMER_CPU0_SENSE_SH_P")
	)
	(segment
		(start 439.421016 -391.405872)
		(end 439.421016 -389.9535)
		(width 0.254)
		(layer "F.Cu")
		(net "P0V9_RETIMER_CPU0_SENSE_SH_N")
	)
	(segment
		(start 442.331602 -420.580312)
		(end 442.929518 -421.178228)
		(width 0.1778)
		(layer "F.Cu")
		(net "P0V9_RETIMER_CPU0_SENSE_SH_N")
	)
	(segment
		(start 442.477652 -418.995098)
		(end 441.918598 -418.436044)
		(width 0.254)
		(layer "F.Cu")
		(net "P0V9_RETIMER_CPU0_SENSE_SH_N")
	)
	(segment
		(start 442.477652 -420.10711)
		(end 442.477652 -418.995098)
		(width 0.254)
		(layer "F.Cu")
		(net "P0V9_RETIMER_CPU0_SENSE_SH_N")
	)
	(segment
		(start 442.477652 -420.10711)
		(end 442.331602 -420.25316)
		(width 0.1778)
		(layer "F.Cu")
		(net "P0V9_RETIMER_CPU0_SENSE_SH_N")
	)
	(segment
		(start 441.918598 -418.436044)
		(end 439.516774 -418.436044)
		(width 0.254)
		(layer "F.Cu")
		(net "P0V9_RETIMER_CPU0_SENSE_SH_N")
	)
	(segment
		(start 442.331602 -420.25316)
		(end 442.331602 -420.580312)
		(width 0.1778)
		(layer "F.Cu")
		(net "P0V9_RETIMER_CPU0_SENSE_SH_N")
	)
	(segment
		(start 442.929518 -421.178228)
		(end 442.929518 -421.514778)
		(width 0.1778)
		(layer "F.Cu")
		(net "P0V9_RETIMER_CPU0_SENSE_SH_N")
	)
	(via
		(at 439.516774 -418.436044)
		(size 0.508)
		(drill 0.254)
		(layers "F.Cu" "B.Cu")
		(net "P0V9_RETIMER_CPU0_SENSE_SH_N")
	)
	(via
		(at 439.421016 -391.405872)
		(size 0.508)
		(drill 0.254)
		(layers "F.Cu" "B.Cu")
		(net "P0V9_RETIMER_CPU0_SENSE_SH_N")
	)
	(segment
		(start 439.186828 -391.64006)
		(end 439.421016 -391.405872)
		(width 0.254)
		(layer "In2.Cu")
		(net "P0V9_RETIMER_CPU0_SENSE_SH_N")
	)
	(segment
		(start 439.9661 -405.472392)
		(end 439.9661 -394.039852)
		(width 0.254)
		(layer "In2.Cu")
		(net "P0V9_RETIMER_CPU0_SENSE_SH_N")
	)
	(segment
		(start 440.792108 -406.2984)
		(end 439.9661 -405.472392)
		(width 0.254)
		(layer "In2.Cu")
		(net "P0V9_RETIMER_CPU0_SENSE_SH_N")
	)
	(segment
		(start 439.187082 -392.419332)
		(end 439.186828 -392.313414)
		(width 0.254)
		(layer "In2.Cu")
		(net "P0V9_RETIMER_CPU0_SENSE_SH_N")
	)
	(segment
		(start 439.516774 -418.436044)
		(end 439.214006 -418.133276)
		(width 0.254)
		(layer "In2.Cu")
		(net "P0V9_RETIMER_CPU0_SENSE_SH_N")
	)
	(segment
		(start 439.214006 -416.144202)
		(end 440.792108 -414.5661)
		(width 0.254)
		(layer "In2.Cu")
		(net "P0V9_RETIMER_CPU0_SENSE_SH_N")
	)
	(segment
		(start 439.186828 -392.313414)
		(end 439.186828 -391.64006)
		(width 0.254)
		(layer "In2.Cu")
		(net "P0V9_RETIMER_CPU0_SENSE_SH_N")
	)
	(segment
		(start 439.214006 -418.133276)
		(end 439.214006 -416.144202)
		(width 0.254)
		(layer "In2.Cu")
		(net "P0V9_RETIMER_CPU0_SENSE_SH_N")
	)
	(segment
		(start 439.187082 -393.260834)
		(end 439.187082 -392.419332)
		(width 0.254)
		(layer "In2.Cu")
		(net "P0V9_RETIMER_CPU0_SENSE_SH_N")
	)
	(segment
		(start 439.9661 -394.039852)
		(end 439.187082 -393.260834)
		(width 0.254)
		(layer "In2.Cu")
		(net "P0V9_RETIMER_CPU0_SENSE_SH_N")
	)
	(segment
		(start 440.792108 -414.5661)
		(end 440.792108 -406.2984)
		(width 0.254)
		(layer "In2.Cu")
		(net "P0V9_RETIMER_CPU0_SENSE_SH_N")
	)
	(segment
		(start 432.228752 -396.805658)
		(end 435.219602 -393.814808)
		(width 0.254)
		(layer "In11.Cu")
		(net "P0V9_RETIMER_CPU0_SENSE_SH_N")
	)
	(segment
		(start 362.702856 -408.168602)
		(end 429.502062 -408.168602)
		(width 0.254)
		(layer "In11.Cu")
		(net "P0V9_RETIMER_CPU0_SENSE_SH_N")
	)
	(segment
		(start 439.175652 -392.313414)
		(end 439.175652 -391.651236)
		(width 0.254)
		(layer "In11.Cu")
		(net "P0V9_RETIMER_CPU0_SENSE_SH_N")
	)
	(segment
		(start 309.941722 -408.595322)
		(end 310.842152 -409.495752)
		(width 0.254)
		(layer "In11.Cu")
		(net "P0V9_RETIMER_CPU0_SENSE_SH_N")
	)
	(segment
		(start 304.436018 -409.496514)
		(end 304.436018 -409.137104)
		(width 0.254)
		(layer "In11.Cu")
		(net "P0V9_RETIMER_CPU0_SENSE_SH_N")
	)
	(segment
		(start 304.9778 -408.595322)
		(end 309.941722 -408.595322)
		(width 0.254)
		(layer "In11.Cu")
		(net "P0V9_RETIMER_CPU0_SENSE_SH_N")
	)
	(segment
		(start 304.436018 -409.137104)
		(end 304.9778 -408.595322)
		(width 0.254)
		(layer "In11.Cu")
		(net "P0V9_RETIMER_CPU0_SENSE_SH_N")
	)
	(segment
		(start 361.375706 -409.495752)
		(end 362.702856 -408.168602)
		(width 0.254)
		(layer "In11.Cu")
		(net "P0V9_RETIMER_CPU0_SENSE_SH_N")
	)
	(segment
		(start 438.329324 -393.814808)
		(end 439.175906 -392.968226)
		(width 0.254)
		(layer "In11.Cu")
		(net "P0V9_RETIMER_CPU0_SENSE_SH_N")
	)
	(segment
		(start 432.228752 -405.441912)
		(end 432.228752 -396.805658)
		(width 0.254)
		(layer "In11.Cu")
		(net "P0V9_RETIMER_CPU0_SENSE_SH_N")
	)
	(segment
		(start 439.175906 -392.39825)
		(end 439.175652 -392.313414)
		(width 0.254)
		(layer "In11.Cu")
		(net "P0V9_RETIMER_CPU0_SENSE_SH_N")
	)
	(segment
		(start 439.175906 -392.968226)
		(end 439.175906 -392.39825)
		(width 0.254)
		(layer "In11.Cu")
		(net "P0V9_RETIMER_CPU0_SENSE_SH_N")
	)
	(segment
		(start 429.502062 -408.168602)
		(end 432.228752 -405.441912)
		(width 0.254)
		(layer "In11.Cu")
		(net "P0V9_RETIMER_CPU0_SENSE_SH_N")
	)
	(segment
		(start 435.219602 -393.814808)
		(end 438.329324 -393.814808)
		(width 0.254)
		(layer "In11.Cu")
		(net "P0V9_RETIMER_CPU0_SENSE_SH_N")
	)
	(segment
		(start 310.842152 -409.495752)
		(end 361.375706 -409.495752)
		(width 0.254)
		(layer "In11.Cu")
		(net "P0V9_RETIMER_CPU0_SENSE_SH_N")
	)
	(segment
		(start 439.175652 -391.651236)
		(end 439.421016 -391.405872)
		(width 0.254)
		(layer "In11.Cu")
		(net "P0V9_RETIMER_CPU0_SENSE_SH_N")
	)
	(segment
		(start 441.061602 -421.50411)
		(end 441.672218 -422.114726)
		(width 0.1524)
		(layer "F.Cu")
		(net "P0V9_RETIMER_CPU0_EN1_R")
	)
	(segment
		(start 440.807602 -419.59911)
		(end 441.061602 -419.85311)
		(width 0.1524)
		(layer "F.Cu")
		(net "P0V9_RETIMER_CPU0_EN1_R")
	)
	(segment
		(start 441.061602 -419.85311)
		(end 441.061602 -421.50411)
		(width 0.1524)
		(layer "F.Cu")
		(net "P0V9_RETIMER_CPU0_EN1_R")
	)
	(segment
		(start 441.672218 -422.114726)
		(end 441.92952 -422.114726)
		(width 0.1524)
		(layer "F.Cu")
		(net "P0V9_RETIMER_CPU0_EN1_R")
	)
	(via
		(at 440.807602 -419.59911)
		(size 0.508)
		(drill 0.254)
		(layers "F.Cu" "B.Cu")
		(net "P0V9_RETIMER_CPU0_EN1_R")
	)
	(segment
		(start 440.175396 -420.23157)
		(end 440.807602 -419.59911)
		(width 0.1524)
		(layer "B.Cu")
		(net "P0V9_RETIMER_CPU0_EN1_R")
	)
	(segment
		(start 439.421016 -420.231824)
		(end 440.175396 -420.23157)
		(width 0.1524)
		(layer "B.Cu")
		(net "P0V9_RETIMER_CPU0_EN1_R")
	)
	(segment
		(start 437.6166 -426.456856)
		(end 439.349896 -426.456856)
		(width 0.10668)
		(layer "F.Cu")
		(net "P0V9_RETIMER_CPU0_EN0_R")
	)
	(segment
		(start 441.574936 -424.914822)
		(end 440.655202 -425.834556)
		(width 0.10668)
		(layer "F.Cu")
		(net "P0V9_RETIMER_CPU0_EN0_R")
	)
	(segment
		(start 439.349896 -426.456856)
		(end 439.429652 -426.3771)
		(width 0.10668)
		(layer "F.Cu")
		(net "P0V9_RETIMER_CPU0_EN0_R")
	)
	(segment
		(start 441.92952 -424.914822)
		(end 441.574936 -424.914822)
		(width 0.10668)
		(layer "F.Cu")
		(net "P0V9_RETIMER_CPU0_EN0_R")
	)
	(segment
		(start 440.540648 -425.94911)
		(end 440.655202 -425.834556)
		(width 0.10668)
		(layer "F.Cu")
		(net "P0V9_RETIMER_CPU0_EN0_R")
	)
	(segment
		(start 439.429652 -425.94911)
		(end 440.540648 -425.94911)
		(width 0.10668)
		(layer "F.Cu")
		(net "P0V9_RETIMER_CPU0_EN0_R")
	)
	(segment
		(start 437.09463 -425.934886)
		(end 437.6166 -426.456856)
		(width 0.10668)
		(layer "F.Cu")
		(net "P0V9_RETIMER_CPU0_EN0_R")
	)
	(segment
		(start 439.429652 -426.3771)
		(end 439.429652 -425.94911)
		(width 0.10668)
		(layer "F.Cu")
		(net "P0V9_RETIMER_CPU0_EN0_R")
	)
	(via
		(at 440.655202 -425.834556)
		(size 0.762)
		(drill 0.381)
		(layers "F.Cu" "B.Cu")
		(net "P0V9_RETIMER_CPU0_EN0_R")
	)
	(segment
		(start 447.970402 -420.99611)
		(end 447.868802 -421.09771)
		(width 0.1778)
		(layer "F.Cu")
		(net "P0V9_RETIMER_CPU0_CFP")
	)
	(segment
		(start 447.868802 -421.586152)
		(end 447.868802 -421.09771)
		(width 0.1778)
		(layer "F.Cu")
		(net "P0V9_RETIMER_CPU0_CFP")
	)
	(segment
		(start 447.524632 -422.914826)
		(end 448.037966 -422.401492)
		(width 0.1778)
		(layer "F.Cu")
		(net "P0V9_RETIMER_CPU0_CFP")
	)
	(segment
		(start 446.729612 -422.914826)
		(end 447.524632 -422.914826)
		(width 0.1778)
		(layer "F.Cu")
		(net "P0V9_RETIMER_CPU0_CFP")
	)
	(segment
		(start 448.037966 -421.755316)
		(end 447.868802 -421.586152)
		(width 0.1778)
		(layer "F.Cu")
		(net "P0V9_RETIMER_CPU0_CFP")
	)
	(segment
		(start 449.043552 -420.99611)
		(end 447.970402 -420.99611)
		(width 0.1778)
		(layer "F.Cu")
		(net "P0V9_RETIMER_CPU0_CFP")
	)
	(segment
		(start 448.037966 -422.401492)
		(end 448.037966 -421.755316)
		(width 0.1778)
		(layer "F.Cu")
		(net "P0V9_RETIMER_CPU0_CFP")
	)
	(via
		(at 447.868802 -421.09771)
		(size 0.762)
		(drill 0.381)
		(layers "F.Cu" "B.Cu")
		(net "P0V9_RETIMER_CPU0_CFP")
	)
	(segment
		(start 448.427602 -422.697656)
		(end 447.810382 -423.314876)
		(width 0.1778)
		(layer "F.Cu")
		(net "P0V9_RETIMER_CPU0_ADDR")
	)
	(segment
		(start 449.043552 -422.01211)
		(end 448.757802 -422.01211)
		(width 0.2032)
		(layer "F.Cu")
		(net "P0V9_RETIMER_CPU0_ADDR")
	)
	(segment
		(start 447.810382 -423.314876)
		(end 446.729612 -423.314876)
		(width 0.1778)
		(layer "F.Cu")
		(net "P0V9_RETIMER_CPU0_ADDR")
	)
	(segment
		(start 448.427602 -422.34231)
		(end 448.427602 -422.697656)
		(width 0.1778)
		(layer "F.Cu")
		(net "P0V9_RETIMER_CPU0_ADDR")
	)
	(segment
		(start 448.757802 -422.01211)
		(end 448.427602 -422.34231)
		(width 0.2032)
		(layer "F.Cu")
		(net "P0V9_RETIMER_CPU0_ADDR")
	)
	(segment
		(start 67.01282 -392.84402)
		(end 66.31813 -392.14933)
		(width 0.10668)
		(layer "F.Cu")
		(net "RT_CPU1_P0_VQPS")
	)
	(segment
		(start 66.31813 -392.14933)
		(end 66.31813 -391.281158)
		(width 0.10668)
		(layer "F.Cu")
		(net "RT_CPU1_P0_VQPS")
	)
	(segment
		(start 67.01282 -394.82776)
		(end 67.01282 -392.84402)
		(width 0.10668)
		(layer "F.Cu")
		(net "RT_CPU1_P0_VQPS")
	)
	(segment
		(start 65.76568 -395.89964)
		(end 65.67424 -395.89964)
		(width 0.10668)
		(layer "F.Cu")
		(net "RT_CPU1_P0_VQPS")
	)
	(segment
		(start 65.47866 -395.89964)
		(end 65.67424 -395.89964)
		(width 0.10668)
		(layer "F.Cu")
		(net "RT_CPU1_P0_VQPS")
	)
	(segment
		(start 66.42862 -395.05128)
		(end 66.26225 -395.21765)
		(width 0.10668)
		(layer "F.Cu")
		(net "RT_CPU1_P0_VQPS")
	)
	(segment
		(start 66.7893 -395.05128)
		(end 67.01282 -394.82776)
		(width 0.10668)
		(layer "F.Cu")
		(net "RT_CPU1_P0_VQPS")
	)
	(segment
		(start 66.42862 -395.05128)
		(end 66.7893 -395.05128)
		(width 0.10668)
		(layer "F.Cu")
		(net "RT_CPU1_P0_VQPS")
	)
	(segment
		(start 66.26225 -395.21765)
		(end 66.26225 -395.40307)
		(width 0.10668)
		(layer "F.Cu")
		(net "RT_CPU1_P0_VQPS")
	)
	(segment
		(start 64.63538 -395.05636)
		(end 65.47866 -395.89964)
		(width 0.10668)
		(layer "F.Cu")
		(net "RT_CPU1_P0_VQPS")
	)
	(segment
		(start 66.26225 -395.40307)
		(end 65.76568 -395.89964)
		(width 0.10668)
		(layer "F.Cu")
		(net "RT_CPU1_P0_VQPS")
	)
	(via
		(at 65.67424 -395.89964)
		(size 0.762)
		(drill 0.381)
		(layers "F.Cu" "B.Cu")
		(net "RT_CPU1_P0_VQPS")
	)
	(segment
		(start 45.91812 -391.916412)
		(end 45.91812 -391.281158)
		(width 0.254)
		(layer "F.Cu")
		(net "NCF_CPU1_P0_GND")
	)
	(segment
		(start 45.46092 -391.09777)
		(end 45.617892 -390.940798)
		(width 0.254)
		(layer "F.Cu")
		(net "NCF_CPU1_P0_GND")
	)
	(segment
		(start 67.218052 -390.981184)
		(end 66.918078 -391.281158)
		(width 0.254)
		(layer "F.Cu")
		(net "NCF_CPU1_P0_GND")
	)
	(segment
		(start 66.918078 -383.402586)
		(end 67.218052 -383.92227)
		(width 0.254)
		(layer "F.Cu")
		(net "NCF_CPU1_P0_GND")
	)
	(segment
		(start 45.91812 -382.907286)
		(end 45.91812 -383.402586)
		(width 0.254)
		(layer "F.Cu")
		(net "NCF_CPU1_P0_GND")
	)
	(segment
		(start 66.883534 -383.368042)
		(end 66.883534 -382.86817)
		(width 0.254)
		(layer "F.Cu")
		(net "NCF_CPU1_P0_GND")
	)
	(segment
		(start 67.642994 -390.761474)
		(end 67.218052 -390.761474)
		(width 0.254)
		(layer "F.Cu")
		(net "NCF_CPU1_P0_GND")
	)
	(segment
		(start 45.46092 -391.240518)
		(end 45.46092 -391.09777)
		(width 0.254)
		(layer "F.Cu")
		(net "NCF_CPU1_P0_GND")
	)
	(segment
		(start 46.494954 -392.33475)
		(end 46.336458 -392.33475)
		(width 0.254)
		(layer "F.Cu")
		(net "NCF_CPU1_P0_GND")
	)
	(segment
		(start 66.918078 -383.402586)
		(end 66.883534 -383.368042)
		(width 0.254)
		(layer "F.Cu")
		(net "NCF_CPU1_P0_GND")
	)
	(segment
		(start 45.617892 -390.940798)
		(end 45.617892 -390.761474)
		(width 0.254)
		(layer "F.Cu")
		(net "NCF_CPU1_P0_GND")
	)
	(segment
		(start 46.336458 -392.33475)
		(end 45.91812 -391.916412)
		(width 0.254)
		(layer "F.Cu")
		(net "NCF_CPU1_P0_GND")
	)
	(segment
		(start 45.35932 -383.663698)
		(end 45.35932 -382.907286)
		(width 0.254)
		(layer "F.Cu")
		(net "NCF_CPU1_P0_GND")
	)
	(segment
		(start 67.416934 -382.86817)
		(end 67.416934 -383.301494)
		(width 0.254)
		(layer "F.Cu")
		(net "NCF_CPU1_P0_GND")
	)
	(segment
		(start 46.218094 -390.761474)
		(end 45.91812 -391.281158)
		(width 0.254)
		(layer "F.Cu")
		(net "NCF_CPU1_P0_GND")
	)
	(segment
		(start 67.218052 -390.761474)
		(end 67.218052 -390.981184)
		(width 0.254)
		(layer "F.Cu")
		(net "NCF_CPU1_P0_GND")
	)
	(segment
		(start 67.416934 -383.301494)
		(end 67.518026 -383.402586)
		(width 0.254)
		(layer "F.Cu")
		(net "NCF_CPU1_P0_GND")
	)
	(segment
		(start 46.218094 -383.92227)
		(end 45.617892 -383.92227)
		(width 0.254)
		(layer "F.Cu")
		(net "NCF_CPU1_P0_GND")
	)
	(segment
		(start 67.700652 -390.819132)
		(end 67.642994 -390.761474)
		(width 0.254)
		(layer "F.Cu")
		(net "NCF_CPU1_P0_GND")
	)
	(segment
		(start 45.617892 -383.92227)
		(end 45.35932 -383.663698)
		(width 0.254)
		(layer "F.Cu")
		(net "NCF_CPU1_P0_GND")
	)
	(via
		(at 46.494954 -392.33475)
		(size 0.4064)
		(drill 0.2032)
		(layers "F.Cu" "B.Cu")
		(net "NCF_CPU1_P0_GND")
	)
	(via
		(at 67.416934 -382.86817)
		(size 0.4064)
		(drill 0.2032)
		(layers "F.Cu" "B.Cu")
		(net "NCF_CPU1_P0_GND")
	)
	(via
		(at 45.46092 -391.240518)
		(size 0.4064)
		(drill 0.2032)
		(layers "F.Cu" "B.Cu")
		(net "NCF_CPU1_P0_GND")
	)
	(via
		(at 68.051172 -383.086864)
		(size 0.6604)
		(drill 0.3302)
		(layers "F.Cu" "B.Cu")
		(net "NCF_CPU1_P0_GND")
	)
	(via
		(at 66.883534 -382.86817)
		(size 0.4064)
		(drill 0.2032)
		(layers "F.Cu" "B.Cu")
		(net "NCF_CPU1_P0_GND")
	)
	(via
		(at 67.700652 -390.819132)
		(size 0.4064)
		(drill 0.2032)
		(layers "F.Cu" "B.Cu")
		(net "NCF_CPU1_P0_GND")
	)
	(via
		(at 45.35932 -382.907286)
		(size 0.4064)
		(drill 0.2032)
		(layers "F.Cu" "B.Cu")
		(net "NCF_CPU1_P0_GND")
	)
	(via
		(at 45.91812 -382.907286)
		(size 0.4064)
		(drill 0.2032)
		(layers "F.Cu" "B.Cu")
		(net "NCF_CPU1_P0_GND")
	)
	(segment
		(start 69.070728 -394.8049)
		(end 68.98132 -394.8049)
		(width 0.10668)
		(layer "F.Cu")
		(net "NCF_A1_CPU1_P0_GND")
	)
	(segment
		(start 69.369686 -394.108432)
		(end 69.369686 -394.505942)
		(width 0.10668)
		(layer "F.Cu")
		(net "NCF_A1_CPU1_P0_GND")
	)
	(segment
		(start 69.369686 -394.505942)
		(end 69.070728 -394.8049)
		(width 0.10668)
		(layer "F.Cu")
		(net "NCF_A1_CPU1_P0_GND")
	)
	(segment
		(start 67.570858 -397.53794)
		(end 68.98132 -396.127478)
		(width 0.10668)
		(layer "F.Cu")
		(net "NCF_A1_CPU1_P0_GND")
	)
	(segment
		(start 69.162168 -393.39901)
		(end 69.162168 -393.60729)
		(width 0.10668)
		(layer "F.Cu")
		(net "NCF_A1_CPU1_P0_GND")
	)
	(segment
		(start 65.91046 -397.53794)
		(end 67.570858 -397.53794)
		(width 0.10668)
		(layer "F.Cu")
		(net "NCF_A1_CPU1_P0_GND")
	)
	(segment
		(start 67.518026 -391.281158)
		(end 68.827142 -392.590274)
		(width 0.10668)
		(layer "F.Cu")
		(net "NCF_A1_CPU1_P0_GND")
	)
	(segment
		(start 68.827142 -392.590274)
		(end 69.162168 -393.39901)
		(width 0.10668)
		(layer "F.Cu")
		(net "NCF_A1_CPU1_P0_GND")
	)
	(segment
		(start 69.162168 -393.60729)
		(end 69.369686 -394.108432)
		(width 0.10668)
		(layer "F.Cu")
		(net "NCF_A1_CPU1_P0_GND")
	)
	(segment
		(start 68.98132 -396.127478)
		(end 68.98132 -394.8049)
		(width 0.10668)
		(layer "F.Cu")
		(net "NCF_A1_CPU1_P0_GND")
	)
	(via
		(at 65.91046 -397.53794)
		(size 0.762)
		(drill 0.381)
		(layers "F.Cu" "B.Cu")
		(net "NCF_A1_CPU1_P0_GND")
	)
	(segment
		(start 17.832832 -413.758888)
		(end 16.980916 -412.906972)
		(width 0.1778)
		(layer "F.Cu")
		(net "P0V9_RETIMER_CPU1_SENSE_R_P")
	)
	(segment
		(start 16.980916 -412.906972)
		(end 16.980916 -412.712916)
		(width 0.1778)
		(layer "F.Cu")
		(net "P0V9_RETIMER_CPU1_SENSE_R_P")
	)
	(segment
		(start 17.832832 -415.168334)
		(end 17.832832 -414.120584)
		(width 0.254)
		(layer "F.Cu")
		(net "P0V9_RETIMER_CPU1_SENSE_R_P")
	)
	(segment
		(start 17.832832 -414.120584)
		(end 17.832832 -413.758888)
		(width 0.1778)
		(layer "F.Cu")
		(net "P0V9_RETIMER_CPU1_SENSE_R_P")
	)
	(segment
		(start 17.930368 -415.26587)
		(end 17.832832 -415.168334)
		(width 0.254)
		(layer "F.Cu")
		(net "P0V9_RETIMER_CPU1_SENSE_R_P")
	)
	(segment
		(start 442.529468 -421.320722)
		(end 441.677552 -420.468806)
		(width 0.1778)
		(layer "F.Cu")
		(net "P0V9_RETIMER_CPU0_SENSE_R_P")
	)
	(segment
		(start 442.529468 -421.514778)
		(end 442.529468 -421.320722)
		(width 0.1778)
		(layer "F.Cu")
		(net "P0V9_RETIMER_CPU0_SENSE_R_P")
	)
	(segment
		(start 441.677552 -420.468806)
		(end 441.677552 -420.10711)
		(width 0.1778)
		(layer "F.Cu")
		(net "P0V9_RETIMER_CPU0_SENSE_R_P")
	)
	(segment
		(start 441.677552 -419.05936)
		(end 441.580016 -418.961824)
		(width 0.254)
		(layer "F.Cu")
		(net "P0V9_RETIMER_CPU0_SENSE_R_P")
	)
	(segment
		(start 441.677552 -420.10711)
		(end 441.677552 -419.05936)
		(width 0.254)
		(layer "F.Cu")
		(net "P0V9_RETIMER_CPU0_SENSE_R_P")
	)
	(segment
		(start 142.34795 -114.554)
		(end 142.34795 -115.497102)
		(width 0.10668)
		(layer "F.Cu")
		(net "UV_P2V5_COMP")
	)
	(segment
		(start 141.473174 -114.554)
		(end 142.34795 -114.554)
		(width 0.10668)
		(layer "F.Cu")
		(net "UV_P2V5_COMP")
	)
	(segment
		(start 140.60805 -114.554)
		(end 141.473174 -114.554)
		(width 0.10668)
		(layer "F.Cu")
		(net "UV_P2V5_COMP")
	)
	(segment
		(start 141.15796 -112.81791)
		(end 141.15796 -113.604294)
		(width 0.10668)
		(layer "F.Cu")
		(net "UV_P2V5_COMP")
	)
	(segment
		(start 143.375888 -116.52504)
		(end 143.71701 -116.52504)
		(width 0.10668)
		(layer "F.Cu")
		(net "UV_P2V5_COMP")
	)
	(segment
		(start 141.15796 -113.604294)
		(end 140.60805 -114.154204)
		(width 0.10668)
		(layer "F.Cu")
		(net "UV_P2V5_COMP")
	)
	(segment
		(start 142.34795 -115.497102)
		(end 143.375888 -116.52504)
		(width 0.10668)
		(layer "F.Cu")
		(net "UV_P2V5_COMP")
	)
	(segment
		(start 140.60805 -114.154204)
		(end 140.60805 -114.554)
		(width 0.10668)
		(layer "F.Cu")
		(net "UV_P2V5_COMP")
	)
	(via
		(at 141.473174 -114.554)
		(size 0.762)
		(drill 0.381)
		(layers "F.Cu" "B.Cu")
		(net "UV_P2V5_COMP")
	)
	(segment
		(start 128.397 -112.522)
		(end 129.09296 -113.21796)
		(width 0.10668)
		(layer "F.Cu")
		(net "UV_ADR_P2V5_COMP")
	)
	(segment
		(start 131.87299 -113.21796)
		(end 129.946654 -113.21796)
		(width 0.10668)
		(layer "F.Cu")
		(net "UV_ADR_P2V5_COMP")
	)
	(segment
		(start 127.381 -107.33405)
		(end 125.94082 -107.33405)
		(width 0.10668)
		(layer "F.Cu")
		(net "UV_ADR_P2V5_COMP")
	)
	(segment
		(start 127.381 -107.33405)
		(end 127.381 -108.31195)
		(width 0.10668)
		(layer "F.Cu")
		(net "UV_ADR_P2V5_COMP")
	)
	(segment
		(start 125.94082 -107.33405)
		(end 125.91796 -107.35691)
		(width 0.10668)
		(layer "F.Cu")
		(net "UV_ADR_P2V5_COMP")
	)
	(segment
		(start 129.09296 -113.21796)
		(end 129.946654 -113.21796)
		(width 0.10668)
		(layer "F.Cu")
		(net "UV_ADR_P2V5_COMP")
	)
	(segment
		(start 128.397 -109.32795)
		(end 128.397 -112.522)
		(width 0.10668)
		(layer "F.Cu")
		(net "UV_ADR_P2V5_COMP")
	)
	(segment
		(start 127.381 -108.31195)
		(end 128.397 -109.32795)
		(width 0.10668)
		(layer "F.Cu")
		(net "UV_ADR_P2V5_COMP")
	)
	(via
		(at 129.946654 -113.21796)
		(size 0.762)
		(drill 0.381)
		(layers "F.Cu" "B.Cu")
		(net "UV_ADR_P2V5_COMP")
	)
	(segment
		(start 16.162782 -403.941534)
		(end 16.162782 -403.220174)
		(width 0.10668)
		(layer "F.Cu")
		(net "P0V9_RETIMER_CPU1_PMSCL")
	)
	(via
		(at 16.162782 -403.220174)
		(size 0.508)
		(drill 0.254)
		(layers "F.Cu" "B.Cu")
		(net "P0V9_RETIMER_CPU1_PMSCL")
	)
	(segment
		(start 14.0589 -403.855174)
		(end 15.527782 -403.855174)
		(width 0.10668)
		(layer "B.Cu")
		(net "P0V9_RETIMER_CPU1_PMSCL")
	)
	(segment
		(start 15.527782 -403.855174)
		(end 16.162782 -403.220174)
		(width 0.10668)
		(layer "B.Cu")
		(net "P0V9_RETIMER_CPU1_PMSCL")
	)
	(segment
		(start 14.892782 -403.941534)
		(end 14.892782 -403.220174)
		(width 0.10668)
		(layer "F.Cu")
		(net "P0V9_RETIMER_CPU1_PMSDA")
	)
	(via
		(at 14.892782 -403.220174)
		(size 0.508)
		(drill 0.254)
		(layers "F.Cu" "B.Cu")
		(net "P0V9_RETIMER_CPU1_PMSDA")
	)
	(segment
		(start 14.4399 -403.220174)
		(end 14.892782 -403.220174)
		(width 0.10668)
		(layer "B.Cu")
		(net "P0V9_RETIMER_CPU1_PMSDA")
	)
	(segment
		(start 14.0589 -402.839174)
		(end 14.4399 -403.220174)
		(width 0.10668)
		(layer "B.Cu")
		(net "P0V9_RETIMER_CPU1_PMSDA")
	)
	(segment
		(start 442.077602 -430.889664)
		(end 441.691776 -431.27549)
		(width 0.10668)
		(layer "F.Cu")
		(net "P0V9_RETIMER_CPU0_PMSCL")
	)
	(segment
		(start 427.587918 -370.113814)
		(end 429.021748 -368.679984)
		(width 0.10668)
		(layer "F.Cu")
		(net "P0V9_RETIMER_CPU0_PMSCL")
	)
	(segment
		(start 420.017956 -369.675156)
		(end 420.456614 -370.113814)
		(width 0.10668)
		(layer "F.Cu")
		(net "P0V9_RETIMER_CPU0_PMSCL")
	)
	(segment
		(start 442.077602 -429.77816)
		(end 442.077602 -430.889664)
		(width 0.10668)
		(layer "F.Cu")
		(net "P0V9_RETIMER_CPU0_PMSCL")
	)
	(segment
		(start 420.456614 -370.113814)
		(end 427.587918 -370.113814)
		(width 0.10668)
		(layer "F.Cu")
		(net "P0V9_RETIMER_CPU0_PMSCL")
	)
	(segment
		(start 434.963062 -431.27549)
		(end 433.345844 -429.658272)
		(width 0.10668)
		(layer "F.Cu")
		(net "P0V9_RETIMER_CPU0_PMSCL")
	)
	(segment
		(start 441.691776 -431.27549)
		(end 434.963062 -431.27549)
		(width 0.10668)
		(layer "F.Cu")
		(net "P0V9_RETIMER_CPU0_PMSCL")
	)
	(via
		(at 429.021748 -368.679984)
		(size 0.508)
		(drill 0.254)
		(layers "F.Cu" "B.Cu")
		(net "P0V9_RETIMER_CPU0_PMSCL")
	)
	(via
		(at 433.345844 -429.658272)
		(size 0.508)
		(drill 0.254)
		(layers "F.Cu" "B.Cu")
		(net "P0V9_RETIMER_CPU0_PMSCL")
	)
	(segment
		(start 429.331882 -391.77341)
		(end 426.396912 -394.70838)
		(width 0.11684)
		(layer "In6.Cu")
		(net "P0V9_RETIMER_CPU0_PMSCL")
	)
	(segment
		(start 432.71821 -391.77341)
		(end 429.331882 -391.77341)
		(width 0.11684)
		(layer "In6.Cu")
		(net "P0V9_RETIMER_CPU0_PMSCL")
	)
	(segment
		(start 426.396912 -396.329916)
		(end 426.690028 -396.623032)
		(width 0.11684)
		(layer "In6.Cu")
		(net "P0V9_RETIMER_CPU0_PMSCL")
	)
	(segment
		(start 431.321972 -368.679984)
		(end 437.82107 -375.179082)
		(width 0.11684)
		(layer "In6.Cu")
		(net "P0V9_RETIMER_CPU0_PMSCL")
	)
	(segment
		(start 437.82107 -375.179082)
		(end 437.82107 -386.67055)
		(width 0.11684)
		(layer "In6.Cu")
		(net "P0V9_RETIMER_CPU0_PMSCL")
	)
	(segment
		(start 428.7647 -401.41652)
		(end 433.345844 -405.997664)
		(width 0.11684)
		(layer "In6.Cu")
		(net "P0V9_RETIMER_CPU0_PMSCL")
	)
	(segment
		(start 428.7647 -398.373092)
		(end 428.7647 -401.41652)
		(width 0.11684)
		(layer "In6.Cu")
		(net "P0V9_RETIMER_CPU0_PMSCL")
	)
	(segment
		(start 437.82107 -386.67055)
		(end 432.71821 -391.77341)
		(width 0.11684)
		(layer "In6.Cu")
		(net "P0V9_RETIMER_CPU0_PMSCL")
	)
	(segment
		(start 429.021748 -368.679984)
		(end 431.321972 -368.679984)
		(width 0.11684)
		(layer "In6.Cu")
		(net "P0V9_RETIMER_CPU0_PMSCL")
	)
	(segment
		(start 433.345844 -405.997664)
		(end 433.345844 -429.658272)
		(width 0.11684)
		(layer "In6.Cu")
		(net "P0V9_RETIMER_CPU0_PMSCL")
	)
	(segment
		(start 427.01464 -396.623032)
		(end 428.7647 -398.373092)
		(width 0.11684)
		(layer "In6.Cu")
		(net "P0V9_RETIMER_CPU0_PMSCL")
	)
	(segment
		(start 426.690028 -396.623032)
		(end 427.01464 -396.623032)
		(width 0.11684)
		(layer "In6.Cu")
		(net "P0V9_RETIMER_CPU0_PMSCL")
	)
	(segment
		(start 426.396912 -394.70838)
		(end 426.396912 -396.329916)
		(width 0.11684)
		(layer "In6.Cu")
		(net "P0V9_RETIMER_CPU0_PMSCL")
	)
	(segment
		(start 426.11675 -369.68049)
		(end 427.110652 -368.686588)
		(width 0.10668)
		(layer "F.Cu")
		(net "P0V9_RETIMER_CPU0_PMSDA")
	)
	(segment
		(start 442.638688 -431.677826)
		(end 433.345336 -431.677826)
		(width 0.10668)
		(layer "F.Cu")
		(net "P0V9_RETIMER_CPU0_PMSDA")
	)
	(segment
		(start 433.345336 -431.677826)
		(end 432.4985 -430.83099)
		(width 0.10668)
		(layer "F.Cu")
		(net "P0V9_RETIMER_CPU0_PMSDA")
	)
	(segment
		(start 443.347602 -430.968912)
		(end 442.638688 -431.677826)
		(width 0.10668)
		(layer "F.Cu")
		(net "P0V9_RETIMER_CPU0_PMSDA")
	)
	(segment
		(start 421.104568 -369.68049)
		(end 426.11675 -369.68049)
		(width 0.10668)
		(layer "F.Cu")
		(net "P0V9_RETIMER_CPU0_PMSDA")
	)
	(segment
		(start 443.347602 -429.77816)
		(end 443.347602 -430.968912)
		(width 0.10668)
		(layer "F.Cu")
		(net "P0V9_RETIMER_CPU0_PMSDA")
	)
	(via
		(at 432.4985 -430.83099)
		(size 0.508)
		(drill 0.254)
		(layers "F.Cu" "B.Cu")
		(net "P0V9_RETIMER_CPU0_PMSDA")
	)
	(via
		(at 427.110652 -368.686588)
		(size 0.508)
		(drill 0.254)
		(layers "F.Cu" "B.Cu")
		(net "P0V9_RETIMER_CPU0_PMSDA")
	)
	(segment
		(start 428.34306 -398.672812)
		(end 428.34306 -401.591272)
		(width 0.11684)
		(layer "In6.Cu")
		(net "P0V9_RETIMER_CPU0_PMSDA")
	)
	(segment
		(start 432.768756 -428.761906)
		(end 432.4985 -429.032162)
		(width 0.11684)
		(layer "In6.Cu")
		(net "P0V9_RETIMER_CPU0_PMSDA")
	)
	(segment
		(start 428.625254 -390.574276)
		(end 425.975272 -393.224258)
		(width 0.11684)
		(layer "In6.Cu")
		(net "P0V9_RETIMER_CPU0_PMSDA")
	)
	(segment
		(start 430.207928 -381.380238)
		(end 428.625254 -385.200144)
		(width 0.11684)
		(layer "In6.Cu")
		(net "P0V9_RETIMER_CPU0_PMSDA")
	)
	(segment
		(start 432.4985 -429.032162)
		(end 432.4985 -430.83099)
		(width 0.11684)
		(layer "In6.Cu")
		(net "P0V9_RETIMER_CPU0_PMSDA")
	)
	(segment
		(start 432.768756 -406.016968)
		(end 432.768756 -428.761906)
		(width 0.11684)
		(layer "In6.Cu")
		(net "P0V9_RETIMER_CPU0_PMSDA")
	)
	(segment
		(start 429.999394 -373.389652)
		(end 430.207928 -373.598186)
		(width 0.11684)
		(layer "In6.Cu")
		(net "P0V9_RETIMER_CPU0_PMSDA")
	)
	(segment
		(start 428.625254 -385.200144)
		(end 428.625254 -390.574276)
		(width 0.11684)
		(layer "In6.Cu")
		(net "P0V9_RETIMER_CPU0_PMSDA")
	)
	(segment
		(start 427.110652 -368.686588)
		(end 429.999394 -371.57533)
		(width 0.11684)
		(layer "In6.Cu")
		(net "P0V9_RETIMER_CPU0_PMSDA")
	)
	(segment
		(start 428.34306 -401.591272)
		(end 432.768756 -406.016968)
		(width 0.11684)
		(layer "In6.Cu")
		(net "P0V9_RETIMER_CPU0_PMSDA")
	)
	(segment
		(start 430.207928 -373.598186)
		(end 430.207928 -381.380238)
		(width 0.11684)
		(layer "In6.Cu")
		(net "P0V9_RETIMER_CPU0_PMSDA")
	)
	(segment
		(start 425.975272 -396.898876)
		(end 426.67682 -397.600424)
		(width 0.11684)
		(layer "In6.Cu")
		(net "P0V9_RETIMER_CPU0_PMSDA")
	)
	(segment
		(start 426.67682 -397.600424)
		(end 427.270672 -397.600424)
		(width 0.11684)
		(layer "In6.Cu")
		(net "P0V9_RETIMER_CPU0_PMSDA")
	)
	(segment
		(start 429.999394 -371.57533)
		(end 429.999394 -373.389652)
		(width 0.11684)
		(layer "In6.Cu")
		(net "P0V9_RETIMER_CPU0_PMSDA")
	)
	(segment
		(start 427.270672 -397.600424)
		(end 428.34306 -398.672812)
		(width 0.11684)
		(layer "In6.Cu")
		(net "P0V9_RETIMER_CPU0_PMSDA")
	)
	(segment
		(start 425.975272 -393.224258)
		(end 425.975272 -396.898876)
		(width 0.11684)
		(layer "In6.Cu")
		(net "P0V9_RETIMER_CPU0_PMSDA")
	)
	(via
		(at 427.331632 -57.997598)
		(size 0.508)
		(drill 0.254)
		(layers "F.Cu" "B.Cu")
		(net "U124_VCC")
	)
	(segment
		(start 139.34694 -13.599922)
		(end 139.34694 -12.212828)
		(width 0.10668)
		(layer "F.Cu")
		(net "TP_CHASI")
	)
	(via
		(at 139.34694 -12.212828)
		(size 0.508)
		(drill 0.254)
		(layers "F.Cu" "B.Cu")
		(net "TP_CHASI")
	)
	(segment
		(start 139.34694 -12.212828)
		(end 139.34694 -13.12164)
		(width 0.10668)
		(layer "B.Cu")
		(net "TP_CHASI")
	)
	(segment
		(start 146.194018 -78.130146)
		(end 146.186652 -78.137512)
		(width 0.254)
		(layer "F.Cu")
		(net "SW_P1V8_AUX_BT_R")
	)
	(segment
		(start 146.194018 -77.277722)
		(end 146.194018 -78.130146)
		(width 0.254)
		(layer "F.Cu")
		(net "SW_P1V8_AUX_BT_R")
	)
	(segment
		(start 124.090176 -75.849988)
		(end 124.088652 -75.851512)
		(width 0.254)
		(layer "F.Cu")
		(net "SW_P1V2_AUX_BT_R")
	)
	(segment
		(start 124.090176 -74.955146)
		(end 124.090176 -75.849988)
		(width 0.254)
		(layer "F.Cu")
		(net "SW_P1V2_AUX_BT_R")
	)
	(via
		(at 21.359622 -398.85239)
		(size 0.508)
		(drill 0.254)
		(layers "F.Cu" "B.Cu")
		(net "SW_P12V_AUX_P0V9_RETIMER_CPU1_FLT")
	)
	(via
		(at 27.515312 -390.892284)
		(size 0.4572)
		(drill 0.254)
		(layers "F.Cu" "B.Cu")
		(net "SW_P12V_AUX_P0V9_RETIMER_CPU1_FLT")
	)
	(via
		(at 24.075644 -399.84807)
		(size 0.508)
		(drill 0.254)
		(layers "F.Cu" "B.Cu")
		(net "SW_P12V_AUX_P0V9_RETIMER_CPU1_FLT")
	)
	(via
		(at 19.944588 -397.545814)
		(size 0.508)
		(drill 0.254)
		(layers "F.Cu" "B.Cu")
		(net "SW_P12V_AUX_P0V9_RETIMER_CPU1_FLT")
	)
	(via
		(at 29.11094 -392.567922)
		(size 0.508)
		(drill 0.254)
		(layers "F.Cu" "B.Cu")
		(net "SW_P12V_AUX_P0V9_RETIMER_CPU1_FLT")
	)
	(via
		(at 20.600162 -401.398994)
		(size 0.508)
		(drill 0.254)
		(layers "F.Cu" "B.Cu")
		(net "SW_P12V_AUX_P0V9_RETIMER_CPU1_FLT")
	)
	(via
		(at 24.761444 -400.48307)
		(size 0.508)
		(drill 0.254)
		(layers "F.Cu" "B.Cu")
		(net "SW_P12V_AUX_P0V9_RETIMER_CPU1_FLT")
	)
	(via
		(at 19.906488 -395.964664)
		(size 0.508)
		(drill 0.254)
		(layers "F.Cu" "B.Cu")
		(net "SW_P12V_AUX_P0V9_RETIMER_CPU1_FLT")
	)
	(via
		(at 19.944588 -396.910814)
		(size 0.508)
		(drill 0.254)
		(layers "F.Cu" "B.Cu")
		(net "SW_P12V_AUX_P0V9_RETIMER_CPU1_FLT")
	)
	(via
		(at 17.81937 -390.892284)
		(size 0.4572)
		(drill 0.254)
		(layers "F.Cu" "B.Cu")
		(net "SW_P12V_AUX_P0V9_RETIMER_CPU1_FLT")
	)
	(via
		(at 28.554172 -395.14272)
		(size 0.508)
		(drill 0.254)
		(layers "F.Cu" "B.Cu")
		(net "SW_P12V_AUX_P0V9_RETIMER_CPU1_FLT")
	)
	(via
		(at 26.898092 -390.892284)
		(size 0.4572)
		(drill 0.254)
		(layers "F.Cu" "B.Cu")
		(net "SW_P12V_AUX_P0V9_RETIMER_CPU1_FLT")
	)
	(via
		(at 21.235162 -401.398994)
		(size 0.508)
		(drill 0.254)
		(layers "F.Cu" "B.Cu")
		(net "SW_P12V_AUX_P0V9_RETIMER_CPU1_FLT")
	)
	(via
		(at 19.027648 -390.892284)
		(size 0.4572)
		(drill 0.254)
		(layers "F.Cu" "B.Cu")
		(net "SW_P12V_AUX_P0V9_RETIMER_CPU1_FLT")
	)
	(via
		(at 24.075644 -400.48307)
		(size 0.508)
		(drill 0.254)
		(layers "F.Cu" "B.Cu")
		(net "SW_P12V_AUX_P0V9_RETIMER_CPU1_FLT")
	)
	(via
		(at 19.944588 -398.878552)
		(size 0.508)
		(drill 0.254)
		(layers "F.Cu" "B.Cu")
		(net "SW_P12V_AUX_P0V9_RETIMER_CPU1_FLT")
	)
	(via
		(at 23.618952 -396.362174)
		(size 0.762)
		(drill 0.381)
		(layers "F.Cu" "B.Cu")
		(net "SW_P12V_AUX_P0V9_RETIMER_CPU1_FLT")
	)
	(via
		(at 19.906488 -395.329664)
		(size 0.508)
		(drill 0.254)
		(layers "F.Cu" "B.Cu")
		(net "SW_P12V_AUX_P0V9_RETIMER_CPU1_FLT")
	)
	(via
		(at 19.836384 -391.780776)
		(size 0.508)
		(drill 0.254)
		(layers "F.Cu" "B.Cu")
		(net "SW_P12V_AUX_P0V9_RETIMER_CPU1_FLT")
	)
	(via
		(at 28.422854 -392.567922)
		(size 0.508)
		(drill 0.254)
		(layers "F.Cu" "B.Cu")
		(net "SW_P12V_AUX_P0V9_RETIMER_CPU1_FLT")
	)
	(via
		(at 20.014184 -392.599926)
		(size 0.508)
		(drill 0.254)
		(layers "F.Cu" "B.Cu")
		(net "SW_P12V_AUX_P0V9_RETIMER_CPU1_FLT")
	)
	(via
		(at 26.280872 -390.892284)
		(size 0.4572)
		(drill 0.254)
		(layers "F.Cu" "B.Cu")
		(net "SW_P12V_AUX_P0V9_RETIMER_CPU1_FLT")
	)
	(via
		(at 19.79168 -390.71423)
		(size 0.508)
		(drill 0.254)
		(layers "F.Cu" "B.Cu")
		(net "SW_P12V_AUX_P0V9_RETIMER_CPU1_FLT")
	)
	(via
		(at 25.396444 -400.48307)
		(size 0.508)
		(drill 0.254)
		(layers "F.Cu" "B.Cu")
		(net "SW_P12V_AUX_P0V9_RETIMER_CPU1_FLT")
	)
	(via
		(at 27.229308 -395.760448)
		(size 0.762)
		(drill 0.381)
		(layers "F.Cu" "B.Cu")
		(net "SW_P12V_AUX_P0V9_RETIMER_CPU1_FLT")
	)
	(via
		(at 28.534106 -396.87881)
		(size 0.508)
		(drill 0.254)
		(layers "F.Cu" "B.Cu")
		(net "SW_P12V_AUX_P0V9_RETIMER_CPU1_FLT")
	)
	(via
		(at 19.914362 -401.398994)
		(size 0.508)
		(drill 0.254)
		(layers "F.Cu" "B.Cu")
		(net "SW_P12V_AUX_P0V9_RETIMER_CPU1_FLT")
	)
	(via
		(at 18.43659 -390.892284)
		(size 0.4572)
		(drill 0.254)
		(layers "F.Cu" "B.Cu")
		(net "SW_P12V_AUX_P0V9_RETIMER_CPU1_FLT")
	)
	(via
		(at 28.7274 -390.485884)
		(size 0.508)
		(drill 0.254)
		(layers "F.Cu" "B.Cu")
		(net "SW_P12V_AUX_P0V9_RETIMER_CPU1_FLT")
	)
	(via
		(at 28.554172 -395.77772)
		(size 0.508)
		(drill 0.254)
		(layers "F.Cu" "B.Cu")
		(net "SW_P12V_AUX_P0V9_RETIMER_CPU1_FLT")
	)
	(via
		(at 28.243784 -391.812526)
		(size 0.508)
		(drill 0.254)
		(layers "F.Cu" "B.Cu")
		(net "SW_P12V_AUX_P0V9_RETIMER_CPU1_FLT")
	)
	(via
		(at 28.96362 -391.774426)
		(size 0.508)
		(drill 0.254)
		(layers "F.Cu" "B.Cu")
		(net "SW_P12V_AUX_P0V9_RETIMER_CPU1_FLT")
	)
	(via
		(at 19.944588 -398.243552)
		(size 0.508)
		(drill 0.254)
		(layers "F.Cu" "B.Cu")
		(net "SW_P12V_AUX_P0V9_RETIMER_CPU1_FLT")
	)
	(via
		(at 20.692872 -398.85239)
		(size 0.508)
		(drill 0.254)
		(layers "F.Cu" "B.Cu")
		(net "SW_P12V_AUX_P0V9_RETIMER_CPU1_FLT")
	)
	(via
		(at 19.150584 -391.761726)
		(size 0.508)
		(drill 0.254)
		(layers "F.Cu" "B.Cu")
		(net "SW_P12V_AUX_P0V9_RETIMER_CPU1_FLT")
	)
	(via
		(at 27.57297 -400.675348)
		(size 0.508)
		(drill 0.254)
		(layers "F.Cu" "B.Cu")
		(net "SW_P12V_AUX_P0V9_RETIMER_CPU1_FLT")
	)
	(via
		(at 27.57297 -399.962878)
		(size 0.508)
		(drill 0.254)
		(layers "F.Cu" "B.Cu")
		(net "SW_P12V_AUX_P0V9_RETIMER_CPU1_FLT")
	)
	(via
		(at 28.534106 -397.51381)
		(size 0.508)
		(drill 0.254)
		(layers "F.Cu" "B.Cu")
		(net "SW_P12V_AUX_P0V9_RETIMER_CPU1_FLT")
	)
	(via
		(at 24.761444 -399.84807)
		(size 0.508)
		(drill 0.254)
		(layers "F.Cu" "B.Cu")
		(net "SW_P12V_AUX_P0V9_RETIMER_CPU1_FLT")
	)
	(via
		(at 25.396444 -399.84807)
		(size 0.508)
		(drill 0.254)
		(layers "F.Cu" "B.Cu")
		(net "SW_P12V_AUX_P0V9_RETIMER_CPU1_FLT")
	)
	(via
		(at 17.20215 -390.892284)
		(size 0.4572)
		(drill 0.254)
		(layers "F.Cu" "B.Cu")
		(net "SW_P12V_AUX_P0V9_RETIMER_CPU1_FLT")
	)
	(via
		(at 28.10637 -390.892284)
		(size 0.4572)
		(drill 0.254)
		(layers "F.Cu" "B.Cu")
		(net "SW_P12V_AUX_P0V9_RETIMER_CPU1_FLT")
	)
	(via
		(at 19.252184 -392.599926)
		(size 0.508)
		(drill 0.254)
		(layers "F.Cu" "B.Cu")
		(net "SW_P12V_AUX_P0V9_RETIMER_CPU1_FLT")
	)
	(via
		(at 457.448666 -402.178012)
		(size 0.762)
		(drill 0.381)
		(layers "F.Cu" "B.Cu")
		(net "SW_P12V_AUX_P0V9_RETIMER_CPU0_FLT")
	)
	(via
		(at 450.991732 -407.57348)
		(size 0.762)
		(drill 0.381)
		(layers "F.Cu" "B.Cu")
		(net "SW_P12V_AUX_P0V9_RETIMER_CPU0_FLT")
	)
	(via
		(at 447.720466 -400.15287)
		(size 0.508)
		(drill 0.254)
		(layers "F.Cu" "B.Cu")
		(net "SW_P12V_AUX_P0V9_RETIMER_CPU0_FLT")
	)
	(via
		(at 447.006472 -399.283428)
		(size 0.4572)
		(drill 0.254)
		(layers "F.Cu" "B.Cu")
		(net "SW_P12V_AUX_P0V9_RETIMER_CPU0_FLT")
	)
	(via
		(at 456.051666 -410.6037)
		(size 0.508)
		(drill 0.254)
		(layers "F.Cu" "B.Cu")
		(net "SW_P12V_AUX_P0V9_RETIMER_CPU0_FLT")
	)
	(via
		(at 451.473316 -410.902404)
		(size 0.508)
		(drill 0.254)
		(layers "F.Cu" "B.Cu")
		(net "SW_P12V_AUX_P0V9_RETIMER_CPU0_FLT")
	)
	(via
		(at 448.870324 -410.578554)
		(size 0.508)
		(drill 0.254)
		(layers "F.Cu" "B.Cu")
		(net "SW_P12V_AUX_P0V9_RETIMER_CPU0_FLT")
	)
	(via
		(at 457.677266 -401.04187)
		(size 0.508)
		(drill 0.254)
		(layers "F.Cu" "B.Cu")
		(net "SW_P12V_AUX_P0V9_RETIMER_CPU0_FLT")
	)
	(via
		(at 447.59753 -399.283428)
		(size 0.4572)
		(drill 0.254)
		(layers "F.Cu" "B.Cu")
		(net "SW_P12V_AUX_P0V9_RETIMER_CPU0_FLT")
	)
	(via
		(at 449.11772 -408.063446)
		(size 0.508)
		(drill 0.254)
		(layers "F.Cu" "B.Cu")
		(net "SW_P12V_AUX_P0V9_RETIMER_CPU0_FLT")
	)
	(via
		(at 456.915266 -401.04187)
		(size 0.508)
		(drill 0.254)
		(layers "F.Cu" "B.Cu")
		(net "SW_P12V_AUX_P0V9_RETIMER_CPU0_FLT")
	)
	(via
		(at 449.07962 -407.199846)
		(size 0.508)
		(drill 0.254)
		(layers "F.Cu" "B.Cu")
		(net "SW_P12V_AUX_P0V9_RETIMER_CPU0_FLT")
	)
	(via
		(at 448.584066 -400.99107)
		(size 0.508)
		(drill 0.254)
		(layers "F.Cu" "B.Cu")
		(net "SW_P12V_AUX_P0V9_RETIMER_CPU0_FLT")
	)
	(via
		(at 446.389252 -399.283428)
		(size 0.4572)
		(drill 0.254)
		(layers "F.Cu" "B.Cu")
		(net "SW_P12V_AUX_P0V9_RETIMER_CPU0_FLT")
	)
	(via
		(at 449.09867 -405.36495)
		(size 0.508)
		(drill 0.254)
		(layers "F.Cu" "B.Cu")
		(net "SW_P12V_AUX_P0V9_RETIMER_CPU0_FLT")
	)
	(via
		(at 447.092324 -410.578554)
		(size 0.508)
		(drill 0.254)
		(layers "F.Cu" "B.Cu")
		(net "SW_P12V_AUX_P0V9_RETIMER_CPU0_FLT")
	)
	(via
		(at 456.085194 -399.283428)
		(size 0.4572)
		(drill 0.254)
		(layers "F.Cu" "B.Cu")
		(net "SW_P12V_AUX_P0V9_RETIMER_CPU0_FLT")
	)
	(via
		(at 455.162666 -410.6037)
		(size 0.508)
		(drill 0.254)
		(layers "F.Cu" "B.Cu")
		(net "SW_P12V_AUX_P0V9_RETIMER_CPU0_FLT")
	)
	(via
		(at 447.822066 -400.99107)
		(size 0.508)
		(drill 0.254)
		(layers "F.Cu" "B.Cu")
		(net "SW_P12V_AUX_P0V9_RETIMER_CPU0_FLT")
	)
	(via
		(at 452.159116 -410.902404)
		(size 0.508)
		(drill 0.254)
		(layers "F.Cu" "B.Cu")
		(net "SW_P12V_AUX_P0V9_RETIMER_CPU0_FLT")
	)
	(via
		(at 445.772032 -399.283428)
		(size 0.4572)
		(drill 0.254)
		(layers "F.Cu" "B.Cu")
		(net "SW_P12V_AUX_P0V9_RETIMER_CPU0_FLT")
	)
	(via
		(at 448.228466 -399.31467)
		(size 0.508)
		(drill 0.254)
		(layers "F.Cu" "B.Cu")
		(net "SW_P12V_AUX_P0V9_RETIMER_CPU0_FLT")
	)
	(via
		(at 456.813666 -400.20367)
		(size 0.508)
		(drill 0.254)
		(layers "F.Cu" "B.Cu")
		(net "SW_P12V_AUX_P0V9_RETIMER_CPU0_FLT")
	)
	(via
		(at 456.457304 -407.330148)
		(size 0.508)
		(drill 0.254)
		(layers "F.Cu" "B.Cu")
		(net "SW_P12V_AUX_P0V9_RETIMER_CPU0_FLT")
	)
	(via
		(at 455.543666 -406.075642)
		(size 0.762)
		(drill 0.381)
		(layers "F.Cu" "B.Cu")
		(net "SW_P12V_AUX_P0V9_RETIMER_CPU0_FLT")
	)
	(via
		(at 456.474322 -408.181556)
		(size 0.508)
		(drill 0.254)
		(layers "F.Cu" "B.Cu")
		(net "SW_P12V_AUX_P0V9_RETIMER_CPU0_FLT")
	)
	(via
		(at 456.448922 -406.351994)
		(size 0.508)
		(drill 0.254)
		(layers "F.Cu" "B.Cu")
		(net "SW_P12V_AUX_P0V9_RETIMER_CPU0_FLT")
	)
	(via
		(at 454.850754 -399.283428)
		(size 0.4572)
		(drill 0.254)
		(layers "F.Cu" "B.Cu")
		(net "SW_P12V_AUX_P0V9_RETIMER_CPU0_FLT")
	)
	(via
		(at 457.321666 -399.36547)
		(size 0.508)
		(drill 0.254)
		(layers "F.Cu" "B.Cu")
		(net "SW_P12V_AUX_P0V9_RETIMER_CPU0_FLT")
	)
	(via
		(at 455.467974 -399.283428)
		(size 0.4572)
		(drill 0.254)
		(layers "F.Cu" "B.Cu")
		(net "SW_P12V_AUX_P0V9_RETIMER_CPU0_FLT")
	)
	(via
		(at 456.467972 -405.533352)
		(size 0.508)
		(drill 0.254)
		(layers "F.Cu" "B.Cu")
		(net "SW_P12V_AUX_P0V9_RETIMER_CPU0_FLT")
	)
	(via
		(at 457.575666 -400.20367)
		(size 0.508)
		(drill 0.254)
		(layers "F.Cu" "B.Cu")
		(net "SW_P12V_AUX_P0V9_RETIMER_CPU0_FLT")
	)
	(via
		(at 456.676252 -399.283428)
		(size 0.4572)
		(drill 0.254)
		(layers "F.Cu" "B.Cu")
		(net "SW_P12V_AUX_P0V9_RETIMER_CPU0_FLT")
	)
	(via
		(at 449.07962 -406.209246)
		(size 0.508)
		(drill 0.254)
		(layers "F.Cu" "B.Cu")
		(net "SW_P12V_AUX_P0V9_RETIMER_CPU0_FLT")
	)
	(via
		(at 452.159116 -410.216604)
		(size 0.508)
		(drill 0.254)
		(layers "F.Cu" "B.Cu")
		(net "SW_P12V_AUX_P0V9_RETIMER_CPU0_FLT")
	)
	(via
		(at 448.482466 -400.15287)
		(size 0.508)
		(drill 0.254)
		(layers "F.Cu" "B.Cu")
		(net "SW_P12V_AUX_P0V9_RETIMER_CPU0_FLT")
	)
	(via
		(at 453.446134 -407.790142)
		(size 0.762)
		(drill 0.381)
		(layers "F.Cu" "B.Cu")
		(net "SW_P12V_AUX_P0V9_RETIMER_CPU0_FLT")
	)
	(via
		(at 451.473316 -410.216604)
		(size 0.508)
		(drill 0.254)
		(layers "F.Cu" "B.Cu")
		(net "SW_P12V_AUX_P0V9_RETIMER_CPU0_FLT")
	)
	(via
		(at 447.981324 -410.578554)
		(size 0.508)
		(drill 0.254)
		(layers "F.Cu" "B.Cu")
		(net "SW_P12V_AUX_P0V9_RETIMER_CPU0_FLT")
	)
	(via
		(at 456.940666 -410.6037)
		(size 0.508)
		(drill 0.254)
		(layers "F.Cu" "B.Cu")
		(net "SW_P12V_AUX_P0V9_RETIMER_CPU0_FLT")
	)
	(via
		(at 452.794116 -410.902404)
		(size 0.508)
		(drill 0.254)
		(layers "F.Cu" "B.Cu")
		(net "SW_P12V_AUX_P0V9_RETIMER_CPU0_FLT")
	)
	(via
		(at 452.794116 -410.216604)
		(size 0.508)
		(drill 0.254)
		(layers "F.Cu" "B.Cu")
		(net "SW_P12V_AUX_P0V9_RETIMER_CPU0_FLT")
	)
	(segment
		(start 27.561794 -392.917934)
		(end 26.80081 -392.28395)
		(width 0.2032)
		(layer "F.Cu")
		(net "SW_P0V9_RETIMER_CPU1_PH2")
	)
	(segment
		(start 26.80081 -392.28395)
		(end 26.80081 -391.754106)
		(width 0.2032)
		(layer "F.Cu")
		(net "SW_P0V9_RETIMER_CPU1_PH2")
	)
	(segment
		(start 18.483072 -392.994134)
		(end 17.722088 -392.36015)
		(width 0.2032)
		(layer "F.Cu")
		(net "SW_P0V9_RETIMER_CPU1_PH1")
	)
	(segment
		(start 17.722088 -392.36015)
		(end 17.722088 -391.754106)
		(width 0.2032)
		(layer "F.Cu")
		(net "SW_P0V9_RETIMER_CPU1_PH1")
	)
	(segment
		(start 26.545794 -393.718034)
		(end 27.561794 -393.718034)
		(width 0.254)
		(layer "F.Cu")
		(net "SW_P0V9_RETIMER_CPU1_BOOT2_RC")
	)
	(segment
		(start 26.350722 -392.722862)
		(end 26.350722 -391.754106)
		(width 0.2032)
		(layer "F.Cu")
		(net "SW_P0V9_RETIMER_CPU1_BOOT2")
	)
	(segment
		(start 26.545794 -392.917934)
		(end 26.350722 -392.722862)
		(width 0.2032)
		(layer "F.Cu")
		(net "SW_P0V9_RETIMER_CPU1_BOOT2")
	)
	(segment
		(start 18.483072 -393.794234)
		(end 17.467072 -393.794234)
		(width 0.2286)
		(layer "F.Cu")
		(net "SW_P0V9_RETIMER_CPU1_BOOT1_RC")
	)
	(segment
		(start 17.272 -392.799062)
		(end 17.272 -391.754106)
		(width 0.2032)
		(layer "F.Cu")
		(net "SW_P0V9_RETIMER_CPU1_BOOT1")
	)
	(segment
		(start 17.467072 -392.994134)
		(end 17.272 -392.799062)
		(width 0.2032)
		(layer "F.Cu")
		(net "SW_P0V9_RETIMER_CPU1_BOOT1")
	)
	(segment
		(start 456.131676 -401.309078)
		(end 455.370692 -400.675094)
		(width 0.2032)
		(layer "F.Cu")
		(net "SW_P0V9_RETIMER_CPU0_PH2")
	)
	(segment
		(start 455.370692 -400.675094)
		(end 455.370692 -400.14525)
		(width 0.2032)
		(layer "F.Cu")
		(net "SW_P0V9_RETIMER_CPU0_PH2")
	)
	(segment
		(start 446.29197 -400.624294)
		(end 446.29197 -400.14525)
		(width 0.2032)
		(layer "F.Cu")
		(net "SW_P0V9_RETIMER_CPU0_PH1")
	)
	(segment
		(start 447.052954 -401.385278)
		(end 446.29197 -400.624294)
		(width 0.2032)
		(layer "F.Cu")
		(net "SW_P0V9_RETIMER_CPU0_PH1")
	)
	(segment
		(start 455.115676 -402.109178)
		(end 456.131676 -402.109178)
		(width 0.254)
		(layer "F.Cu")
		(net "SW_P0V9_RETIMER_CPU0_BOOT2_RC")
	)
	(segment
		(start 454.920604 -401.114006)
		(end 454.920604 -400.14525)
		(width 0.2032)
		(layer "F.Cu")
		(net "SW_P0V9_RETIMER_CPU0_BOOT2")
	)
	(segment
		(start 455.115676 -401.309078)
		(end 454.920604 -401.114006)
		(width 0.2032)
		(layer "F.Cu")
		(net "SW_P0V9_RETIMER_CPU0_BOOT2")
	)
	(segment
		(start 447.052954 -402.185378)
		(end 446.036954 -402.185378)
		(width 0.2286)
		(layer "F.Cu")
		(net "SW_P0V9_RETIMER_CPU0_BOOT1_RC")
	)
	(segment
		(start 445.841882 -401.190206)
		(end 445.841882 -400.14525)
		(width 0.2032)
		(layer "F.Cu")
		(net "SW_P0V9_RETIMER_CPU0_BOOT1")
	)
	(segment
		(start 446.036954 -401.385278)
		(end 445.841882 -401.190206)
		(width 0.2032)
		(layer "F.Cu")
		(net "SW_P0V9_RETIMER_CPU0_BOOT1")
	)
	(segment
		(start 25.676352 -361.572302)
		(end 25.676352 -361.678982)
		(width 0.10668)
		(layer "F.Cu")
		(net "SVID_PVDDCR_CPU1_P1_SVD_R1")
	)
	(segment
		(start 27.106372 -363.109002)
		(end 27.604974 -363.109002)
		(width 0.10668)
		(layer "F.Cu")
		(net "SVID_PVDDCR_CPU1_P1_SVD_R1")
	)
	(segment
		(start 25.16505 -361.061)
		(end 25.676352 -361.572302)
		(width 0.10668)
		(layer "F.Cu")
		(net "SVID_PVDDCR_CPU1_P1_SVD_R1")
	)
	(segment
		(start 25.676352 -361.678982)
		(end 27.106372 -363.109002)
		(width 0.10668)
		(layer "F.Cu")
		(net "SVID_PVDDCR_CPU1_P1_SVD_R1")
	)
	(segment
		(start 26.263854 -361.016804)
		(end 26.263854 -361.823254)
		(width 0.10668)
		(layer "F.Cu")
		(net "SVID_PVDDCR_CPU1_P1_SVC_R1")
	)
	(segment
		(start 27.149552 -362.708952)
		(end 27.604974 -362.708952)
		(width 0.10668)
		(layer "F.Cu")
		(net "SVID_PVDDCR_CPU1_P1_SVC_R1")
	)
	(segment
		(start 26.263854 -361.823254)
		(end 27.149552 -362.708952)
		(width 0.10668)
		(layer "F.Cu")
		(net "SVID_PVDDCR_CPU1_P1_SVC_R1")
	)
	(segment
		(start 25.16505 -359.918)
		(end 26.263854 -361.016804)
		(width 0.10668)
		(layer "F.Cu")
		(net "SVID_PVDDCR_CPU1_P1_SVC_R1")
	)
	(segment
		(start 306.272946 -359.3592)
		(end 306.593748 -359.680002)
		(width 0.10668)
		(layer "F.Cu")
		(net "SVID_PVDDCR_CPU1_P0_SVD_R1")
	)
	(segment
		(start 305.525678 -358.763316)
		(end 306.121562 -359.3592)
		(width 0.10668)
		(layer "F.Cu")
		(net "SVID_PVDDCR_CPU1_P0_SVD_R1")
	)
	(segment
		(start 306.593748 -359.680002)
		(end 307.258974 -359.680002)
		(width 0.10668)
		(layer "F.Cu")
		(net "SVID_PVDDCR_CPU1_P0_SVD_R1")
	)
	(segment
		(start 304.81905 -358.14)
		(end 304.902362 -358.14)
		(width 0.10668)
		(layer "F.Cu")
		(net "SVID_PVDDCR_CPU1_P0_SVD_R1")
	)
	(segment
		(start 304.902362 -358.14)
		(end 305.525678 -358.763316)
		(width 0.10668)
		(layer "F.Cu")
		(net "SVID_PVDDCR_CPU1_P0_SVD_R1")
	)
	(segment
		(start 306.121562 -359.3592)
		(end 306.272946 -359.3592)
		(width 0.10668)
		(layer "F.Cu")
		(net "SVID_PVDDCR_CPU1_P0_SVD_R1")
	)
	(via
		(at 305.525678 -358.763316)
		(size 0.508)
		(drill 0.254)
		(layers "F.Cu" "B.Cu")
		(net "SVID_PVDDCR_CPU1_P0_SVD_R1")
	)
	(segment
		(start 305.447192 -357.493062)
		(end 305.6636 -357.70947)
		(width 0.10668)
		(layer "F.Cu")
		(net "SVID_PVDDCR_CPU1_P0_SVC_R1")
	)
	(segment
		(start 304.95113 -356.997)
		(end 305.447192 -357.493062)
		(width 0.10668)
		(layer "F.Cu")
		(net "SVID_PVDDCR_CPU1_P0_SVC_R1")
	)
	(segment
		(start 304.81905 -356.997)
		(end 304.95113 -356.997)
		(width 0.10668)
		(layer "F.Cu")
		(net "SVID_PVDDCR_CPU1_P0_SVC_R1")
	)
	(segment
		(start 305.6636 -357.70947)
		(end 305.6636 -358.14)
		(width 0.10668)
		(layer "F.Cu")
		(net "SVID_PVDDCR_CPU1_P0_SVC_R1")
	)
	(segment
		(start 305.6636 -358.14)
		(end 306.803552 -359.279952)
		(width 0.10668)
		(layer "F.Cu")
		(net "SVID_PVDDCR_CPU1_P0_SVC_R1")
	)
	(segment
		(start 306.803552 -359.279952)
		(end 307.258974 -359.279952)
		(width 0.10668)
		(layer "F.Cu")
		(net "SVID_PVDDCR_CPU1_P0_SVC_R1")
	)
	(via
		(at 305.447192 -357.493062)
		(size 0.508)
		(drill 0.254)
		(layers "F.Cu" "B.Cu")
		(net "SVID_PVDDCR_CPU1_P0_SVC_R1")
	)
	(segment
		(start 88.53805 -146.939)
		(end 89.30005 -147.701)
		(width 0.10668)
		(layer "B.Cu")
		(net "SVID_PVDDCR_CPU0_P1_SVD_R1")
	)
	(segment
		(start 89.30005 -147.701)
		(end 90.22334 -147.701)
		(width 0.10668)
		(layer "B.Cu")
		(net "SVID_PVDDCR_CPU0_P1_SVD_R1")
	)
	(segment
		(start 90.22334 -147.701)
		(end 92.165932 -145.758408)
		(width 0.10668)
		(layer "B.Cu")
		(net "SVID_PVDDCR_CPU0_P1_SVD_R1")
	)
	(segment
		(start 92.165932 -145.758408)
		(end 92.795852 -145.758408)
		(width 0.10668)
		(layer "B.Cu")
		(net "SVID_PVDDCR_CPU0_P1_SVD_R1")
	)
	(segment
		(start 88.53805 -147.955)
		(end 88.790018 -147.955)
		(width 0.10668)
		(layer "B.Cu")
		(net "SVID_PVDDCR_CPU0_P1_SVC_R1")
	)
	(segment
		(start 92.41663 -146.158458)
		(end 92.795852 -146.158458)
		(width 0.10668)
		(layer "B.Cu")
		(net "SVID_PVDDCR_CPU0_P1_SVC_R1")
	)
	(segment
		(start 90.282776 -148.292312)
		(end 92.41663 -146.158458)
		(width 0.10668)
		(layer "B.Cu")
		(net "SVID_PVDDCR_CPU0_P1_SVC_R1")
	)
	(segment
		(start 89.12733 -148.292312)
		(end 90.282776 -148.292312)
		(width 0.10668)
		(layer "B.Cu")
		(net "SVID_PVDDCR_CPU0_P1_SVC_R1")
	)
	(segment
		(start 88.790018 -147.955)
		(end 89.12733 -148.292312)
		(width 0.10668)
		(layer "B.Cu")
		(net "SVID_PVDDCR_CPU0_P1_SVC_R1")
	)
	(via
		(at 374.292622 -144.132046)
		(size 0.6604)
		(drill 0.3302)
		(layers "F.Cu" "B.Cu")
		(net "SVID_PVDDCR_CPU0_P0_SVD_R1")
	)
	(segment
		(start 374.926352 -143.361156)
		(end 375.523252 -143.361156)
		(width 0.10668)
		(layer "B.Cu")
		(net "SVID_PVDDCR_CPU0_P0_SVD_R1")
	)
	(segment
		(start 374.292622 -143.994886)
		(end 374.926352 -143.361156)
		(width 0.10668)
		(layer "B.Cu")
		(net "SVID_PVDDCR_CPU0_P0_SVD_R1")
	)
	(segment
		(start 373.337328 -144.520158)
		(end 373.90451 -144.520158)
		(width 0.10668)
		(layer "B.Cu")
		(net "SVID_PVDDCR_CPU0_P0_SVD_R1")
	)
	(segment
		(start 373.90451 -144.520158)
		(end 374.292622 -144.132046)
		(width 0.10668)
		(layer "B.Cu")
		(net "SVID_PVDDCR_CPU0_P0_SVD_R1")
	)
	(segment
		(start 374.292622 -144.132046)
		(end 374.292622 -143.994886)
		(width 0.10668)
		(layer "B.Cu")
		(net "SVID_PVDDCR_CPU0_P0_SVD_R1")
	)
	(via
		(at 374.201436 -145.398998)
		(size 0.6604)
		(drill 0.3302)
		(layers "F.Cu" "B.Cu")
		(net "SVID_PVDDCR_CPU0_P0_SVC_R1")
	)
	(segment
		(start 374.868694 -144.136872)
		(end 374.726962 -144.478756)
		(width 0.10668)
		(layer "B.Cu")
		(net "SVID_PVDDCR_CPU0_P0_SVC_R1")
	)
	(segment
		(start 374.064276 -145.536158)
		(end 374.201436 -145.398998)
		(width 0.10668)
		(layer "B.Cu")
		(net "SVID_PVDDCR_CPU0_P0_SVC_R1")
	)
	(segment
		(start 373.337328 -145.536158)
		(end 374.064276 -145.536158)
		(width 0.10668)
		(layer "B.Cu")
		(net "SVID_PVDDCR_CPU0_P0_SVC_R1")
	)
	(segment
		(start 374.726962 -144.873472)
		(end 374.201436 -145.398998)
		(width 0.10668)
		(layer "B.Cu")
		(net "SVID_PVDDCR_CPU0_P0_SVC_R1")
	)
	(segment
		(start 375.24436 -143.761206)
		(end 374.868694 -144.136872)
		(width 0.10668)
		(layer "B.Cu")
		(net "SVID_PVDDCR_CPU0_P0_SVC_R1")
	)
	(segment
		(start 375.523252 -143.761206)
		(end 375.24436 -143.761206)
		(width 0.10668)
		(layer "B.Cu")
		(net "SVID_PVDDCR_CPU0_P0_SVC_R1")
	)
	(segment
		(start 374.726962 -144.478756)
		(end 374.726962 -144.873472)
		(width 0.10668)
		(layer "B.Cu")
		(net "SVID_PVDDCR_CPU0_P0_SVC_R1")
	)
	(segment
		(start 264.34415 -137.373868)
		(end 264.536174 -136.910826)
		(width 0.10668)
		(layer "F.Cu")
		(net "SPI_CPU0_R1_D3")
	)
	(segment
		(start 261.640066 -138.448796)
		(end 263.459214 -138.448796)
		(width 0.10668)
		(layer "F.Cu")
		(net "SPI_CPU0_R1_D3")
	)
	(segment
		(start 263.665716 -138.052302)
		(end 264.34415 -137.373868)
		(width 0.10668)
		(layer "F.Cu")
		(net "SPI_CPU0_R1_D3")
	)
	(segment
		(start 263.665716 -138.242294)
		(end 263.665716 -138.052302)
		(width 0.10668)
		(layer "F.Cu")
		(net "SPI_CPU0_R1_D3")
	)
	(segment
		(start 264.77595 -136.67105)
		(end 264.77595 -136.652)
		(width 0.10668)
		(layer "F.Cu")
		(net "SPI_CPU0_R1_D3")
	)
	(segment
		(start 264.536174 -136.910826)
		(end 264.77595 -136.67105)
		(width 0.10668)
		(layer "F.Cu")
		(net "SPI_CPU0_R1_D3")
	)
	(segment
		(start 263.459214 -138.448796)
		(end 263.665716 -138.242294)
		(width 0.10668)
		(layer "F.Cu")
		(net "SPI_CPU0_R1_D3")
	)
	(via
		(at 263.665716 -138.242294)
		(size 0.762)
		(drill 0.381)
		(layers "F.Cu" "B.Cu")
		(net "SPI_CPU0_R1_D3")
	)
	(segment
		(start 263.611614 -139.978892)
		(end 263.736582 -139.978892)
		(width 0.10668)
		(layer "F.Cu")
		(net "SPI_CPU0_R1_D2")
	)
	(segment
		(start 262.481568 -138.848846)
		(end 263.611614 -139.978892)
		(width 0.10668)
		(layer "F.Cu")
		(net "SPI_CPU0_R1_D2")
	)
	(segment
		(start 261.640066 -138.848846)
		(end 262.481568 -138.848846)
		(width 0.10668)
		(layer "F.Cu")
		(net "SPI_CPU0_R1_D2")
	)
	(segment
		(start 263.736582 -139.978892)
		(end 263.960102 -139.978892)
		(width 0.10668)
		(layer "F.Cu")
		(net "SPI_CPU0_R1_D2")
	)
	(segment
		(start 263.960102 -139.978892)
		(end 264.606024 -140.624814)
		(width 0.10668)
		(layer "F.Cu")
		(net "SPI_CPU0_R1_D2")
	)
	(via
		(at 263.736582 -139.978892)
		(size 0.762)
		(drill 0.381)
		(layers "F.Cu" "B.Cu")
		(net "SPI_CPU0_R1_D2")
	)
	(segment
		(start 262.001 -139.7762)
		(end 261.873746 -139.648946)
		(width 0.10668)
		(layer "F.Cu")
		(net "SPI_CPU0_R1_D1")
	)
	(segment
		(start 261.873746 -139.648946)
		(end 261.640066 -139.648946)
		(width 0.10668)
		(layer "F.Cu")
		(net "SPI_CPU0_R1_D1")
	)
	(segment
		(start 262.001 -140.010896)
		(end 262.001 -139.7762)
		(width 0.10668)
		(layer "F.Cu")
		(net "SPI_CPU0_R1_D1")
	)
	(segment
		(start 261.62 -140.391896)
		(end 262.001 -140.010896)
		(width 0.10668)
		(layer "F.Cu")
		(net "SPI_CPU0_R1_D1")
	)
	(segment
		(start 261.62 -140.843)
		(end 261.62 -140.391896)
		(width 0.10668)
		(layer "F.Cu")
		(net "SPI_CPU0_R1_D1")
	)
	(segment
		(start 261.62 -141.58595)
		(end 261.62 -140.843)
		(width 0.10668)
		(layer "F.Cu")
		(net "SPI_CPU0_R1_D1")
	)
	(via
		(at 261.62 -140.843)
		(size 0.508)
		(drill 0.254)
		(layers "F.Cu" "B.Cu")
		(net "SPI_CPU0_R1_D1")
	)
	(segment
		(start 262.763 -140.775436)
		(end 262.698484 -140.71092)
		(width 0.10668)
		(layer "F.Cu")
		(net "SPI_CPU0_R1_D0")
	)
	(segment
		(start 262.192008 -139.248896)
		(end 262.43661 -139.493498)
		(width 0.10668)
		(layer "F.Cu")
		(net "SPI_CPU0_R1_D0")
	)
	(segment
		(start 261.640066 -139.248896)
		(end 262.192008 -139.248896)
		(width 0.10668)
		(layer "F.Cu")
		(net "SPI_CPU0_R1_D0")
	)
	(segment
		(start 262.763 -141.33195)
		(end 262.763 -140.775436)
		(width 0.10668)
		(layer "F.Cu")
		(net "SPI_CPU0_R1_D0")
	)
	(segment
		(start 262.43661 -139.493498)
		(end 262.52043 -139.695936)
		(width 0.10668)
		(layer "F.Cu")
		(net "SPI_CPU0_R1_D0")
	)
	(segment
		(start 263.017 -141.58595)
		(end 262.763 -141.33195)
		(width 0.10668)
		(layer "F.Cu")
		(net "SPI_CPU0_R1_D0")
	)
	(segment
		(start 262.52043 -140.532866)
		(end 262.698484 -140.71092)
		(width 0.10668)
		(layer "F.Cu")
		(net "SPI_CPU0_R1_D0")
	)
	(segment
		(start 262.52043 -139.695936)
		(end 262.52043 -140.532866)
		(width 0.10668)
		(layer "F.Cu")
		(net "SPI_CPU0_R1_D0")
	)
	(via
		(at 262.698484 -140.71092)
		(size 0.762)
		(drill 0.381)
		(layers "F.Cu" "B.Cu")
		(net "SPI_CPU0_R1_D0")
	)
	(segment
		(start 168.402762 -418.136832)
		(end 168.402762 -418.8841)
		(width 0.10668)
		(layer "F.Cu")
		(net "SMB_RT_CPU1_P3_ROM_R_SDA")
	)
	(segment
		(start 168.513506 -417.196016)
		(end 168.513506 -417.920678)
		(width 0.10668)
		(layer "F.Cu")
		(net "SMB_RT_CPU1_P3_ROM_R_SDA")
	)
	(segment
		(start 168.511474 -417.92271)
		(end 168.511474 -418.02812)
		(width 0.10668)
		(layer "F.Cu")
		(net "SMB_RT_CPU1_P3_ROM_R_SDA")
	)
	(segment
		(start 168.511474 -418.02812)
		(end 168.402762 -418.136832)
		(width 0.10668)
		(layer "F.Cu")
		(net "SMB_RT_CPU1_P3_ROM_R_SDA")
	)
	(segment
		(start 168.513506 -417.920678)
		(end 168.511474 -417.92271)
		(width 0.10668)
		(layer "F.Cu")
		(net "SMB_RT_CPU1_P3_ROM_R_SDA")
	)
	(via
		(at 168.028112 -425.41571)
		(size 0.508)
		(drill 0.254)
		(layers "F.Cu" "B.Cu")
		(net "SMB_RT_CPU1_P3_ROM_R_SDA")
	)
	(via
		(at 168.511474 -418.02812)
		(size 0.762)
		(drill 0.254)
		(layers "F.Cu" "B.Cu")
		(net "SMB_RT_CPU1_P3_ROM_R_SDA")
	)
	(segment
		(start 168.196514 -425.247308)
		(end 168.028112 -425.41571)
		(width 0.10668)
		(layer "B.Cu")
		(net "SMB_RT_CPU1_P3_ROM_R_SDA")
	)
	(segment
		(start 168.196514 -424.757342)
		(end 168.196514 -425.247308)
		(width 0.10668)
		(layer "B.Cu")
		(net "SMB_RT_CPU1_P3_ROM_R_SDA")
	)
	(segment
		(start 168.22039 -420.570914)
		(end 168.692068 -421.042592)
		(width 0.11684)
		(layer "In11.Cu")
		(net "SMB_RT_CPU1_P3_ROM_R_SDA")
	)
	(segment
		(start 168.511474 -418.02812)
		(end 168.511474 -418.720016)
		(width 0.11684)
		(layer "In11.Cu")
		(net "SMB_RT_CPU1_P3_ROM_R_SDA")
	)
	(segment
		(start 168.692068 -423.962068)
		(end 168.028112 -424.626024)
		(width 0.11684)
		(layer "In11.Cu")
		(net "SMB_RT_CPU1_P3_ROM_R_SDA")
	)
	(segment
		(start 168.511474 -418.720016)
		(end 168.22039 -419.0111)
		(width 0.11684)
		(layer "In11.Cu")
		(net "SMB_RT_CPU1_P3_ROM_R_SDA")
	)
	(segment
		(start 168.028112 -424.626024)
		(end 168.028112 -425.41571)
		(width 0.11684)
		(layer "In11.Cu")
		(net "SMB_RT_CPU1_P3_ROM_R_SDA")
	)
	(segment
		(start 168.22039 -419.0111)
		(end 168.22039 -420.570914)
		(width 0.11684)
		(layer "In11.Cu")
		(net "SMB_RT_CPU1_P3_ROM_R_SDA")
	)
	(segment
		(start 168.692068 -421.042592)
		(end 168.692068 -423.962068)
		(width 0.11684)
		(layer "In11.Cu")
		(net "SMB_RT_CPU1_P3_ROM_R_SDA")
	)
	(segment
		(start 169.971212 -417.818062)
		(end 169.349166 -417.196016)
		(width 0.10668)
		(layer "F.Cu")
		(net "SMB_RT_CPU1_P3_ROM_R_SCL")
	)
	(segment
		(start 169.971212 -418.243258)
		(end 169.971212 -417.818062)
		(width 0.10668)
		(layer "F.Cu")
		(net "SMB_RT_CPU1_P3_ROM_R_SCL")
	)
	(segment
		(start 169.66819 -418.849556)
		(end 169.971212 -418.546534)
		(width 0.10668)
		(layer "F.Cu")
		(net "SMB_RT_CPU1_P3_ROM_R_SCL")
	)
	(segment
		(start 169.971212 -418.546534)
		(end 169.971212 -418.243258)
		(width 0.10668)
		(layer "F.Cu")
		(net "SMB_RT_CPU1_P3_ROM_R_SCL")
	)
	(via
		(at 169.971212 -418.243258)
		(size 0.508)
		(drill 0.254)
		(layers "F.Cu" "B.Cu")
		(net "SMB_RT_CPU1_P3_ROM_R_SCL")
	)
	(via
		(at 168.696386 -425.410376)
		(size 0.508)
		(drill 0.254)
		(layers "F.Cu" "B.Cu")
		(net "SMB_RT_CPU1_P3_ROM_R_SCL")
	)
	(segment
		(start 168.696386 -424.757342)
		(end 168.696386 -425.410376)
		(width 0.10668)
		(layer "B.Cu")
		(net "SMB_RT_CPU1_P3_ROM_R_SCL")
	)
	(segment
		(start 169.154602 -422.44899)
		(end 169.154602 -424.95216)
		(width 0.11684)
		(layer "In11.Cu")
		(net "SMB_RT_CPU1_P3_ROM_R_SCL")
	)
	(segment
		(start 170.10126 -418.243258)
		(end 171.050204 -419.192202)
		(width 0.11684)
		(layer "In11.Cu")
		(net "SMB_RT_CPU1_P3_ROM_R_SCL")
	)
	(segment
		(start 169.154602 -424.95216)
		(end 168.696386 -425.410376)
		(width 0.11684)
		(layer "In11.Cu")
		(net "SMB_RT_CPU1_P3_ROM_R_SCL")
	)
	(segment
		(start 169.971212 -418.243258)
		(end 170.10126 -418.243258)
		(width 0.11684)
		(layer "In11.Cu")
		(net "SMB_RT_CPU1_P3_ROM_R_SCL")
	)
	(segment
		(start 171.050204 -419.192202)
		(end 171.050204 -420.553388)
		(width 0.11684)
		(layer "In11.Cu")
		(net "SMB_RT_CPU1_P3_ROM_R_SCL")
	)
	(segment
		(start 171.050204 -420.553388)
		(end 169.154602 -422.44899)
		(width 0.11684)
		(layer "In11.Cu")
		(net "SMB_RT_CPU1_P3_ROM_R_SCL")
	)
	(segment
		(start 112.28705 -390.626092)
		(end 112.193324 -390.626092)
		(width 0.10668)
		(layer "F.Cu")
		(net "SMB_RT_CPU1_P3_ROM_MUX_1D_R_SDA")
	)
	(segment
		(start 112.68202 -390.231122)
		(end 112.28705 -390.626092)
		(width 0.10668)
		(layer "F.Cu")
		(net "SMB_RT_CPU1_P3_ROM_MUX_1D_R_SDA")
	)
	(via
		(at 112.193324 -390.626092)
		(size 0.4064)
		(drill 0.2032)
		(layers "F.Cu" "B.Cu")
		(net "SMB_RT_CPU1_P3_ROM_MUX_1D_R_SDA")
	)
	(via
		(at 111.75492 -406.22982)
		(size 0.6604)
		(drill 0.3302)
		(layers "F.Cu" "B.Cu")
		(net "SMB_RT_CPU1_P3_ROM_MUX_1D_R_SDA")
	)
	(via
		(at 112.13084 -405.38908)
		(size 0.508)
		(drill 0.254)
		(layers "F.Cu" "B.Cu")
		(net "SMB_RT_CPU1_P3_ROM_MUX_1D_R_SDA")
	)
	(segment
		(start 111.75492 -405.765)
		(end 112.13084 -405.38908)
		(width 0.10668)
		(layer "B.Cu")
		(net "SMB_RT_CPU1_P3_ROM_MUX_1D_R_SDA")
	)
	(segment
		(start 112.35436 -408.384756)
		(end 111.75492 -407.785316)
		(width 0.10668)
		(layer "B.Cu")
		(net "SMB_RT_CPU1_P3_ROM_MUX_1D_R_SDA")
	)
	(segment
		(start 111.75492 -407.785316)
		(end 111.75492 -406.22982)
		(width 0.10668)
		(layer "B.Cu")
		(net "SMB_RT_CPU1_P3_ROM_MUX_1D_R_SDA")
	)
	(segment
		(start 111.75492 -406.22982)
		(end 111.75492 -405.765)
		(width 0.10668)
		(layer "B.Cu")
		(net "SMB_RT_CPU1_P3_ROM_MUX_1D_R_SDA")
	)
	(segment
		(start 112.13084 -403.81936)
		(end 112.13084 -405.38908)
		(width 0.11684)
		(layer "In6.Cu")
		(net "SMB_RT_CPU1_P3_ROM_MUX_1D_R_SDA")
	)
	(segment
		(start 112.37976 -397.502634)
		(end 112.37976 -398.018)
		(width 0.11684)
		(layer "In6.Cu")
		(net "SMB_RT_CPU1_P3_ROM_MUX_1D_R_SDA")
	)
	(segment
		(start 112.974882 -391.032238)
		(end 112.974882 -396.907512)
		(width 0.11684)
		(layer "In6.Cu")
		(net "SMB_RT_CPU1_P3_ROM_MUX_1D_R_SDA")
	)
	(segment
		(start 112.974882 -398.613122)
		(end 112.974882 -398.925288)
		(width 0.11684)
		(layer "In6.Cu")
		(net "SMB_RT_CPU1_P3_ROM_MUX_1D_R_SDA")
	)
	(segment
		(start 112.934242 -398.965928)
		(end 112.934242 -403.015958)
		(width 0.11684)
		(layer "In6.Cu")
		(net "SMB_RT_CPU1_P3_ROM_MUX_1D_R_SDA")
	)
	(segment
		(start 112.934242 -403.015958)
		(end 112.13084 -403.81936)
		(width 0.11684)
		(layer "In6.Cu")
		(net "SMB_RT_CPU1_P3_ROM_MUX_1D_R_SDA")
	)
	(segment
		(start 112.37976 -398.018)
		(end 112.974882 -398.613122)
		(width 0.11684)
		(layer "In6.Cu")
		(net "SMB_RT_CPU1_P3_ROM_MUX_1D_R_SDA")
	)
	(segment
		(start 112.568736 -390.626092)
		(end 112.974882 -391.032238)
		(width 0.11684)
		(layer "In6.Cu")
		(net "SMB_RT_CPU1_P3_ROM_MUX_1D_R_SDA")
	)
	(segment
		(start 112.974882 -396.907512)
		(end 112.37976 -397.502634)
		(width 0.11684)
		(layer "In6.Cu")
		(net "SMB_RT_CPU1_P3_ROM_MUX_1D_R_SDA")
	)
	(segment
		(start 112.193324 -390.626092)
		(end 112.568736 -390.626092)
		(width 0.11684)
		(layer "In6.Cu")
		(net "SMB_RT_CPU1_P3_ROM_MUX_1D_R_SDA")
	)
	(segment
		(start 112.974882 -398.925288)
		(end 112.934242 -398.965928)
		(width 0.11684)
		(layer "In6.Cu")
		(net "SMB_RT_CPU1_P3_ROM_MUX_1D_R_SDA")
	)
	(segment
		(start 113.201704 -389.931148)
		(end 112.329468 -389.931148)
		(width 0.10668)
		(layer "F.Cu")
		(net "SMB_RT_CPU1_P3_ROM_MUX_1D_R_SCL")
	)
	(segment
		(start 112.329468 -389.931148)
		(end 112.193324 -390.067292)
		(width 0.10668)
		(layer "F.Cu")
		(net "SMB_RT_CPU1_P3_ROM_MUX_1D_R_SCL")
	)
	(via
		(at 112.67186 -404.84552)
		(size 0.508)
		(drill 0.254)
		(layers "F.Cu" "B.Cu")
		(net "SMB_RT_CPU1_P3_ROM_MUX_1D_R_SCL")
	)
	(via
		(at 113.251742 -405.425402)
		(size 0.6604)
		(drill 0.3302)
		(layers "F.Cu" "B.Cu")
		(net "SMB_RT_CPU1_P3_ROM_MUX_1D_R_SCL")
	)
	(via
		(at 112.193324 -390.067292)
		(size 0.4064)
		(drill 0.2032)
		(layers "F.Cu" "B.Cu")
		(net "SMB_RT_CPU1_P3_ROM_MUX_1D_R_SCL")
	)
	(segment
		(start 113.68786 -405.86152)
		(end 113.251742 -405.425402)
		(width 0.10668)
		(layer "B.Cu")
		(net "SMB_RT_CPU1_P3_ROM_MUX_1D_R_SCL")
	)
	(segment
		(start 113.251742 -405.425402)
		(end 112.67186 -404.84552)
		(width 0.10668)
		(layer "B.Cu")
		(net "SMB_RT_CPU1_P3_ROM_MUX_1D_R_SCL")
	)
	(segment
		(start 113.68786 -407.838656)
		(end 113.68786 -405.86152)
		(width 0.10668)
		(layer "B.Cu")
		(net "SMB_RT_CPU1_P3_ROM_MUX_1D_R_SCL")
	)
	(segment
		(start 113.17478 -408.351736)
		(end 113.68786 -407.838656)
		(width 0.10668)
		(layer "B.Cu")
		(net "SMB_RT_CPU1_P3_ROM_MUX_1D_R_SCL")
	)
	(segment
		(start 112.67186 -404.84552)
		(end 113.493296 -404.024084)
		(width 0.11684)
		(layer "In6.Cu")
		(net "SMB_RT_CPU1_P3_ROM_MUX_1D_R_SCL")
	)
	(segment
		(start 113.493296 -402.68779)
		(end 114.184938 -401.996148)
		(width 0.11684)
		(layer "In6.Cu")
		(net "SMB_RT_CPU1_P3_ROM_MUX_1D_R_SCL")
	)
	(segment
		(start 114.184938 -401.996148)
		(end 114.184938 -391.581894)
		(width 0.11684)
		(layer "In6.Cu")
		(net "SMB_RT_CPU1_P3_ROM_MUX_1D_R_SCL")
	)
	(segment
		(start 112.670336 -390.067292)
		(end 112.193324 -390.067292)
		(width 0.11684)
		(layer "In6.Cu")
		(net "SMB_RT_CPU1_P3_ROM_MUX_1D_R_SCL")
	)
	(segment
		(start 114.184938 -391.581894)
		(end 112.670336 -390.067292)
		(width 0.11684)
		(layer "In6.Cu")
		(net "SMB_RT_CPU1_P3_ROM_MUX_1D_R_SCL")
	)
	(segment
		(start 113.493296 -404.024084)
		(end 113.493296 -402.68779)
		(width 0.11684)
		(layer "In6.Cu")
		(net "SMB_RT_CPU1_P3_ROM_MUX_1D_R_SCL")
	)
	(segment
		(start 168.402762 -421.26281)
		(end 168.394634 -421.270938)
		(width 0.10668)
		(layer "F.Cu")
		(net "SMB_RT_CPU1_P3_ROM_SDA")
	)
	(segment
		(start 168.402762 -420.90213)
		(end 168.402762 -421.26281)
		(width 0.10668)
		(layer "F.Cu")
		(net "SMB_RT_CPU1_P3_ROM_SDA")
	)
	(segment
		(start 167.738806 -420.238174)
		(end 168.402762 -420.90213)
		(width 0.10668)
		(layer "F.Cu")
		(net "SMB_RT_CPU1_P3_ROM_SDA")
	)
	(segment
		(start 168.402762 -419.574218)
		(end 167.738806 -420.238174)
		(width 0.10668)
		(layer "F.Cu")
		(net "SMB_RT_CPU1_P3_ROM_SDA")
	)
	(segment
		(start 168.402762 -419.4175)
		(end 168.402762 -419.574218)
		(width 0.10668)
		(layer "F.Cu")
		(net "SMB_RT_CPU1_P3_ROM_SDA")
	)
	(via
		(at 167.738806 -420.238174)
		(size 0.508)
		(drill 0.254)
		(layers "F.Cu" "B.Cu")
		(net "SMB_RT_CPU1_P3_ROM_SDA")
	)
	(segment
		(start 169.66819 -419.382956)
		(end 169.664634 -419.386512)
		(width 0.10668)
		(layer "F.Cu")
		(net "SMB_RT_CPU1_P3_ROM_SCL")
	)
	(segment
		(start 169.664634 -420.218616)
		(end 169.664634 -421.270938)
		(width 0.10668)
		(layer "F.Cu")
		(net "SMB_RT_CPU1_P3_ROM_SCL")
	)
	(segment
		(start 169.664634 -419.386512)
		(end 169.664634 -420.218616)
		(width 0.10668)
		(layer "F.Cu")
		(net "SMB_RT_CPU1_P3_ROM_SCL")
	)
	(via
		(at 169.664634 -420.218616)
		(size 0.508)
		(drill 0.254)
		(layers "F.Cu" "B.Cu")
		(net "SMB_RT_CPU1_P3_ROM_SCL")
	)
	(segment
		(start 162.5092 -418.2491)
		(end 162.5092 -418.7825)
		(width 0.10668)
		(layer "F.Cu")
		(net "SMB_RT_CPU1_P2_ROM_R_SDA")
	)
	(via
		(at 162.5092 -418.2491)
		(size 0.508)
		(drill 0.254)
		(layers "F.Cu" "B.Cu")
		(net "SMB_RT_CPU1_P2_ROM_R_SDA")
	)
	(segment
		(start 164.107368 -419.918134)
		(end 163.820094 -419.63086)
		(width 0.10668)
		(layer "B.Cu")
		(net "SMB_RT_CPU1_P2_ROM_R_SDA")
	)
	(segment
		(start 160.743392 -417.754816)
		(end 161.178748 -417.754816)
		(width 0.10668)
		(layer "B.Cu")
		(net "SMB_RT_CPU1_P2_ROM_R_SDA")
	)
	(segment
		(start 161.673032 -418.2491)
		(end 162.5092 -418.2491)
		(width 0.10668)
		(layer "B.Cu")
		(net "SMB_RT_CPU1_P2_ROM_R_SDA")
	)
	(segment
		(start 162.941254 -418.2491)
		(end 162.5092 -418.2491)
		(width 0.10668)
		(layer "B.Cu")
		(net "SMB_RT_CPU1_P2_ROM_R_SDA")
	)
	(segment
		(start 161.178748 -417.754816)
		(end 161.673032 -418.2491)
		(width 0.10668)
		(layer "B.Cu")
		(net "SMB_RT_CPU1_P2_ROM_R_SDA")
	)
	(segment
		(start 163.820094 -419.63086)
		(end 163.820094 -419.12794)
		(width 0.10668)
		(layer "B.Cu")
		(net "SMB_RT_CPU1_P2_ROM_R_SDA")
	)
	(segment
		(start 163.820094 -419.12794)
		(end 162.941254 -418.2491)
		(width 0.10668)
		(layer "B.Cu")
		(net "SMB_RT_CPU1_P2_ROM_R_SDA")
	)
	(segment
		(start 163.715446 -418.299138)
		(end 163.80587 -418.208714)
		(width 0.10668)
		(layer "F.Cu")
		(net "SMB_RT_CPU1_P2_ROM_R_SCL")
	)
	(segment
		(start 163.715446 -418.7825)
		(end 163.715446 -418.299138)
		(width 0.10668)
		(layer "F.Cu")
		(net "SMB_RT_CPU1_P2_ROM_R_SCL")
	)
	(via
		(at 163.80587 -418.208714)
		(size 0.508)
		(drill 0.254)
		(layers "F.Cu" "B.Cu")
		(net "SMB_RT_CPU1_P2_ROM_R_SCL")
	)
	(segment
		(start 161.62147 -417.708842)
		(end 163.305998 -417.708842)
		(width 0.10668)
		(layer "B.Cu")
		(net "SMB_RT_CPU1_P2_ROM_R_SCL")
	)
	(segment
		(start 161.167572 -417.254944)
		(end 161.62147 -417.708842)
		(width 0.10668)
		(layer "B.Cu")
		(net "SMB_RT_CPU1_P2_ROM_R_SCL")
	)
	(segment
		(start 160.743392 -417.254944)
		(end 161.167572 -417.254944)
		(width 0.10668)
		(layer "B.Cu")
		(net "SMB_RT_CPU1_P2_ROM_R_SCL")
	)
	(segment
		(start 164.20592 -419.22319)
		(end 164.20592 -418.608764)
		(width 0.10668)
		(layer "B.Cu")
		(net "SMB_RT_CPU1_P2_ROM_R_SCL")
	)
	(segment
		(start 164.900864 -419.918134)
		(end 164.20592 -419.22319)
		(width 0.10668)
		(layer "B.Cu")
		(net "SMB_RT_CPU1_P2_ROM_R_SCL")
	)
	(segment
		(start 163.305998 -417.708842)
		(end 163.80587 -418.208714)
		(width 0.10668)
		(layer "B.Cu")
		(net "SMB_RT_CPU1_P2_ROM_R_SCL")
	)
	(segment
		(start 164.20592 -418.608764)
		(end 163.80587 -418.208714)
		(width 0.10668)
		(layer "B.Cu")
		(net "SMB_RT_CPU1_P2_ROM_R_SCL")
	)
	(segment
		(start 144.814798 -390.626092)
		(end 144.721072 -390.626092)
		(width 0.10668)
		(layer "F.Cu")
		(net "SMB_RT_CPU1_P2_ROM_MUX_1D_R_SDA")
	)
	(segment
		(start 145.209768 -390.231122)
		(end 144.814798 -390.626092)
		(width 0.10668)
		(layer "F.Cu")
		(net "SMB_RT_CPU1_P2_ROM_MUX_1D_R_SDA")
	)
	(via
		(at 144.721072 -390.626092)
		(size 0.4064)
		(drill 0.2032)
		(layers "F.Cu" "B.Cu")
		(net "SMB_RT_CPU1_P2_ROM_MUX_1D_R_SDA")
	)
	(via
		(at 164.921438 -412.28899)
		(size 0.508)
		(drill 0.254)
		(layers "F.Cu" "B.Cu")
		(net "SMB_RT_CPU1_P2_ROM_MUX_1D_R_SDA")
	)
	(via
		(at 164.216588 -411.94228)
		(size 0.6604)
		(drill 0.3302)
		(layers "F.Cu" "B.Cu")
		(net "SMB_RT_CPU1_P2_ROM_MUX_1D_R_SDA")
	)
	(segment
		(start 164.216588 -411.94228)
		(end 164.574728 -411.94228)
		(width 0.10668)
		(layer "B.Cu")
		(net "SMB_RT_CPU1_P2_ROM_MUX_1D_R_SDA")
	)
	(segment
		(start 164.196268 -411.92196)
		(end 164.216588 -411.94228)
		(width 0.10668)
		(layer "B.Cu")
		(net "SMB_RT_CPU1_P2_ROM_MUX_1D_R_SDA")
	)
	(segment
		(start 163.4236 -411.92196)
		(end 164.196268 -411.92196)
		(width 0.10668)
		(layer "B.Cu")
		(net "SMB_RT_CPU1_P2_ROM_MUX_1D_R_SDA")
	)
	(segment
		(start 164.574728 -411.94228)
		(end 164.921438 -412.28899)
		(width 0.10668)
		(layer "B.Cu")
		(net "SMB_RT_CPU1_P2_ROM_MUX_1D_R_SDA")
	)
	(segment
		(start 149.318726 -391.804906)
		(end 149.318726 -393.784328)
		(width 0.11684)
		(layer "In11.Cu")
		(net "SMB_RT_CPU1_P2_ROM_MUX_1D_R_SDA")
	)
	(segment
		(start 149.939756 -394.671804)
		(end 162.662108 -398.309338)
		(width 0.11684)
		(layer "In11.Cu")
		(net "SMB_RT_CPU1_P2_ROM_MUX_1D_R_SDA")
	)
	(segment
		(start 144.721072 -390.626092)
		(end 145.047716 -390.626092)
		(width 0.11684)
		(layer "In11.Cu")
		(net "SMB_RT_CPU1_P2_ROM_MUX_1D_R_SDA")
	)
	(segment
		(start 148.92528 -391.41146)
		(end 149.318726 -391.804906)
		(width 0.11684)
		(layer "In11.Cu")
		(net "SMB_RT_CPU1_P2_ROM_MUX_1D_R_SDA")
	)
	(segment
		(start 149.507194 -394.239242)
		(end 149.939756 -394.671804)
		(width 0.11684)
		(layer "In11.Cu")
		(net "SMB_RT_CPU1_P2_ROM_MUX_1D_R_SDA")
	)
	(segment
		(start 163.494974 -399.245836)
		(end 165.826694 -403.60854)
		(width 0.11684)
		(layer "In11.Cu")
		(net "SMB_RT_CPU1_P2_ROM_MUX_1D_R_SDA")
	)
	(segment
		(start 165.826694 -408.466036)
		(end 166.06774 -409.677108)
		(width 0.11684)
		(layer "In11.Cu")
		(net "SMB_RT_CPU1_P2_ROM_MUX_1D_R_SDA")
	)
	(segment
		(start 149.318726 -393.784328)
		(end 149.507194 -394.239242)
		(width 0.11684)
		(layer "In11.Cu")
		(net "SMB_RT_CPU1_P2_ROM_MUX_1D_R_SDA")
	)
	(segment
		(start 163.286186 -398.933416)
		(end 163.494974 -399.245836)
		(width 0.11684)
		(layer "In11.Cu")
		(net "SMB_RT_CPU1_P2_ROM_MUX_1D_R_SDA")
	)
	(segment
		(start 145.047716 -390.626092)
		(end 146.943826 -391.41146)
		(width 0.11684)
		(layer "In11.Cu")
		(net "SMB_RT_CPU1_P2_ROM_MUX_1D_R_SDA")
	)
	(segment
		(start 165.02507 -412.28899)
		(end 164.921438 -412.28899)
		(width 0.11684)
		(layer "In11.Cu")
		(net "SMB_RT_CPU1_P2_ROM_MUX_1D_R_SDA")
	)
	(segment
		(start 162.662108 -398.309338)
		(end 163.286186 -398.933416)
		(width 0.11684)
		(layer "In11.Cu")
		(net "SMB_RT_CPU1_P2_ROM_MUX_1D_R_SDA")
	)
	(segment
		(start 165.685216 -411.628844)
		(end 165.02507 -412.28899)
		(width 0.11684)
		(layer "In11.Cu")
		(net "SMB_RT_CPU1_P2_ROM_MUX_1D_R_SDA")
	)
	(segment
		(start 166.06774 -409.677108)
		(end 166.06774 -410.705046)
		(width 0.11684)
		(layer "In11.Cu")
		(net "SMB_RT_CPU1_P2_ROM_MUX_1D_R_SDA")
	)
	(segment
		(start 146.943826 -391.41146)
		(end 148.92528 -391.41146)
		(width 0.11684)
		(layer "In11.Cu")
		(net "SMB_RT_CPU1_P2_ROM_MUX_1D_R_SDA")
	)
	(segment
		(start 165.826694 -403.60854)
		(end 165.826694 -408.466036)
		(width 0.11684)
		(layer "In11.Cu")
		(net "SMB_RT_CPU1_P2_ROM_MUX_1D_R_SDA")
	)
	(segment
		(start 166.06774 -410.705046)
		(end 165.685216 -411.628844)
		(width 0.11684)
		(layer "In11.Cu")
		(net "SMB_RT_CPU1_P2_ROM_MUX_1D_R_SDA")
	)
	(segment
		(start 145.729452 -389.931148)
		(end 144.857216 -389.931148)
		(width 0.10668)
		(layer "F.Cu")
		(net "SMB_RT_CPU1_P2_ROM_MUX_1D_R_SCL")
	)
	(segment
		(start 144.857216 -389.931148)
		(end 144.721072 -390.067292)
		(width 0.10668)
		(layer "F.Cu")
		(net "SMB_RT_CPU1_P2_ROM_MUX_1D_R_SCL")
	)
	(via
		(at 144.721072 -390.067292)
		(size 0.4064)
		(drill 0.2032)
		(layers "F.Cu" "B.Cu")
		(net "SMB_RT_CPU1_P2_ROM_MUX_1D_R_SCL")
	)
	(via
		(at 164.24402 -413.25546)
		(size 0.6604)
		(drill 0.3302)
		(layers "F.Cu" "B.Cu")
		(net "SMB_RT_CPU1_P2_ROM_MUX_1D_R_SCL")
	)
	(via
		(at 164.884862 -412.934404)
		(size 0.508)
		(drill 0.254)
		(layers "F.Cu" "B.Cu")
		(net "SMB_RT_CPU1_P2_ROM_MUX_1D_R_SCL")
	)
	(segment
		(start 163.46932 -413.2707)
		(end 164.24402 -413.25546)
		(width 0.10668)
		(layer "B.Cu")
		(net "SMB_RT_CPU1_P2_ROM_MUX_1D_R_SCL")
	)
	(segment
		(start 164.563806 -413.25546)
		(end 164.24402 -413.25546)
		(width 0.10668)
		(layer "B.Cu")
		(net "SMB_RT_CPU1_P2_ROM_MUX_1D_R_SCL")
	)
	(segment
		(start 164.884862 -412.934404)
		(end 164.563806 -413.25546)
		(width 0.10668)
		(layer "B.Cu")
		(net "SMB_RT_CPU1_P2_ROM_MUX_1D_R_SCL")
	)
	(segment
		(start 165.03269 -412.934404)
		(end 164.884862 -412.934404)
		(width 0.11684)
		(layer "In11.Cu")
		(net "SMB_RT_CPU1_P2_ROM_MUX_1D_R_SCL")
	)
	(segment
		(start 166.248334 -401.355814)
		(end 166.248334 -407.888694)
		(width 0.11684)
		(layer "In11.Cu")
		(net "SMB_RT_CPU1_P2_ROM_MUX_1D_R_SCL")
	)
	(segment
		(start 163.108132 -397.968724)
		(end 163.648136 -398.508728)
		(width 0.11684)
		(layer "In11.Cu")
		(net "SMB_RT_CPU1_P2_ROM_MUX_1D_R_SCL")
	)
	(segment
		(start 147.031202 -390.846056)
		(end 148.767292 -390.846056)
		(width 0.11684)
		(layer "In11.Cu")
		(net "SMB_RT_CPU1_P2_ROM_MUX_1D_R_SCL")
	)
	(segment
		(start 145.151094 -390.067292)
		(end 147.031202 -390.846056)
		(width 0.11684)
		(layer "In11.Cu")
		(net "SMB_RT_CPU1_P2_ROM_MUX_1D_R_SCL")
	)
	(segment
		(start 166.5224 -409.525724)
		(end 166.5224 -410.71927)
		(width 0.11684)
		(layer "In11.Cu")
		(net "SMB_RT_CPU1_P2_ROM_MUX_1D_R_SCL")
	)
	(segment
		(start 150.592028 -393.996418)
		(end 150.937468 -394.341858)
		(width 0.11684)
		(layer "In11.Cu")
		(net "SMB_RT_CPU1_P2_ROM_MUX_1D_R_SCL")
	)
	(segment
		(start 163.648136 -398.508728)
		(end 163.9316 -399.03908)
		(width 0.11684)
		(layer "In11.Cu")
		(net "SMB_RT_CPU1_P2_ROM_MUX_1D_R_SCL")
	)
	(segment
		(start 150.256494 -391.632694)
		(end 150.469346 -392.146536)
		(width 0.11684)
		(layer "In11.Cu")
		(net "SMB_RT_CPU1_P2_ROM_MUX_1D_R_SCL")
	)
	(segment
		(start 166.009574 -411.95752)
		(end 165.03269 -412.934404)
		(width 0.11684)
		(layer "In11.Cu")
		(net "SMB_RT_CPU1_P2_ROM_MUX_1D_R_SCL")
	)
	(segment
		(start 166.51732 -409.50007)
		(end 166.5224 -409.525724)
		(width 0.11684)
		(layer "In11.Cu")
		(net "SMB_RT_CPU1_P2_ROM_MUX_1D_R_SCL")
	)
	(segment
		(start 150.469346 -393.700254)
		(end 150.592028 -393.996418)
		(width 0.11684)
		(layer "In11.Cu")
		(net "SMB_RT_CPU1_P2_ROM_MUX_1D_R_SCL")
	)
	(segment
		(start 149.96668 -391.34288)
		(end 150.256494 -391.632694)
		(width 0.11684)
		(layer "In11.Cu")
		(net "SMB_RT_CPU1_P2_ROM_MUX_1D_R_SCL")
	)
	(segment
		(start 150.937468 -394.341858)
		(end 163.108132 -397.968724)
		(width 0.11684)
		(layer "In11.Cu")
		(net "SMB_RT_CPU1_P2_ROM_MUX_1D_R_SCL")
	)
	(segment
		(start 163.9316 -399.03908)
		(end 166.248334 -401.355814)
		(width 0.11684)
		(layer "In11.Cu")
		(net "SMB_RT_CPU1_P2_ROM_MUX_1D_R_SCL")
	)
	(segment
		(start 166.5224 -410.71927)
		(end 166.009574 -411.95752)
		(width 0.11684)
		(layer "In11.Cu")
		(net "SMB_RT_CPU1_P2_ROM_MUX_1D_R_SCL")
	)
	(segment
		(start 166.248334 -407.888694)
		(end 166.51732 -408.15768)
		(width 0.11684)
		(layer "In11.Cu")
		(net "SMB_RT_CPU1_P2_ROM_MUX_1D_R_SCL")
	)
	(segment
		(start 148.767292 -390.846056)
		(end 149.96668 -391.34288)
		(width 0.11684)
		(layer "In11.Cu")
		(net "SMB_RT_CPU1_P2_ROM_MUX_1D_R_SCL")
	)
	(segment
		(start 150.469346 -392.146536)
		(end 150.469346 -393.700254)
		(width 0.11684)
		(layer "In11.Cu")
		(net "SMB_RT_CPU1_P2_ROM_MUX_1D_R_SCL")
	)
	(segment
		(start 166.51732 -408.15768)
		(end 166.51732 -409.50007)
		(width 0.11684)
		(layer "In11.Cu")
		(net "SMB_RT_CPU1_P2_ROM_MUX_1D_R_SCL")
	)
	(segment
		(start 144.721072 -390.067292)
		(end 145.151094 -390.067292)
		(width 0.11684)
		(layer "In11.Cu")
		(net "SMB_RT_CPU1_P2_ROM_MUX_1D_R_SCL")
	)
	(segment
		(start 162.378136 -420.674038)
		(end 161.853372 -420.149274)
		(width 0.10668)
		(layer "F.Cu")
		(net "SMB_RT_CPU1_P2_ROM_SDA")
	)
	(segment
		(start 162.5092 -419.95852)
		(end 162.318446 -420.149274)
		(width 0.10668)
		(layer "F.Cu")
		(net "SMB_RT_CPU1_P2_ROM_SDA")
	)
	(segment
		(start 162.318446 -420.149274)
		(end 161.853372 -420.149274)
		(width 0.10668)
		(layer "F.Cu")
		(net "SMB_RT_CPU1_P2_ROM_SDA")
	)
	(segment
		(start 162.5092 -419.3159)
		(end 162.5092 -419.95852)
		(width 0.10668)
		(layer "F.Cu")
		(net "SMB_RT_CPU1_P2_ROM_SDA")
	)
	(segment
		(start 162.378136 -421.216582)
		(end 162.378136 -420.674038)
		(width 0.10668)
		(layer "F.Cu")
		(net "SMB_RT_CPU1_P2_ROM_SDA")
	)
	(via
		(at 161.853372 -420.149274)
		(size 0.508)
		(drill 0.254)
		(layers "F.Cu" "B.Cu")
		(net "SMB_RT_CPU1_P2_ROM_SDA")
	)
	(segment
		(start 163.648136 -420.498778)
		(end 163.249864 -420.100506)
		(width 0.10668)
		(layer "F.Cu")
		(net "SMB_RT_CPU1_P2_ROM_SCL")
	)
	(segment
		(start 163.715446 -419.634924)
		(end 163.715446 -419.3159)
		(width 0.10668)
		(layer "F.Cu")
		(net "SMB_RT_CPU1_P2_ROM_SCL")
	)
	(segment
		(start 163.648136 -421.216582)
		(end 163.648136 -420.498778)
		(width 0.10668)
		(layer "F.Cu")
		(net "SMB_RT_CPU1_P2_ROM_SCL")
	)
	(segment
		(start 163.249864 -420.100506)
		(end 163.715446 -419.634924)
		(width 0.10668)
		(layer "F.Cu")
		(net "SMB_RT_CPU1_P2_ROM_SCL")
	)
	(via
		(at 163.249864 -420.100506)
		(size 0.508)
		(drill 0.254)
		(layers "F.Cu" "B.Cu")
		(net "SMB_RT_CPU1_P2_ROM_SCL")
	)
	(segment
		(start 114.749072 -401.603718)
		(end 114.54384 -401.603718)
		(width 0.10668)
		(layer "F.Cu")
		(net "SMB_RT_CPU1_P1_ROM_R_SDA")
	)
	(segment
		(start 107.852464 -396.261844)
		(end 108.3564 -396.76578)
		(width 0.10668)
		(layer "F.Cu")
		(net "SMB_RT_CPU1_P1_ROM_R_SDA")
	)
	(segment
		(start 108.078524 -396.035784)
		(end 107.852464 -396.261844)
		(width 0.10668)
		(layer "F.Cu")
		(net "SMB_RT_CPU1_P1_ROM_R_SDA")
	)
	(segment
		(start 114.54384 -401.603718)
		(end 114.114072 -402.033486)
		(width 0.10668)
		(layer "F.Cu")
		(net "SMB_RT_CPU1_P1_ROM_R_SDA")
	)
	(segment
		(start 114.114072 -402.033486)
		(end 113.175542 -402.033486)
		(width 0.10668)
		(layer "F.Cu")
		(net "SMB_RT_CPU1_P1_ROM_R_SDA")
	)
	(segment
		(start 112.45342 -402.755608)
		(end 109.502702 -402.755608)
		(width 0.10668)
		(layer "F.Cu")
		(net "SMB_RT_CPU1_P1_ROM_R_SDA")
	)
	(segment
		(start 109.502702 -402.755608)
		(end 108.478574 -401.73148)
		(width 0.10668)
		(layer "F.Cu")
		(net "SMB_RT_CPU1_P1_ROM_R_SDA")
	)
	(segment
		(start 113.175542 -402.033486)
		(end 112.45342 -402.755608)
		(width 0.10668)
		(layer "F.Cu")
		(net "SMB_RT_CPU1_P1_ROM_R_SDA")
	)
	(segment
		(start 108.4199 -396.035784)
		(end 108.078524 -396.035784)
		(width 0.10668)
		(layer "F.Cu")
		(net "SMB_RT_CPU1_P1_ROM_R_SDA")
	)
	(via
		(at 108.478574 -401.73148)
		(size 0.508)
		(drill 0.254)
		(layers "F.Cu" "B.Cu")
		(net "SMB_RT_CPU1_P1_ROM_R_SDA")
	)
	(via
		(at 107.852464 -396.261844)
		(size 0.508)
		(drill 0.254)
		(layers "F.Cu" "B.Cu")
		(net "SMB_RT_CPU1_P1_ROM_R_SDA")
	)
	(segment
		(start 108.478574 -396.887954)
		(end 107.852464 -396.261844)
		(width 0.11684)
		(layer "In6.Cu")
		(net "SMB_RT_CPU1_P1_ROM_R_SDA")
	)
	(segment
		(start 108.478574 -401.73148)
		(end 108.478574 -396.887954)
		(width 0.11684)
		(layer "In6.Cu")
		(net "SMB_RT_CPU1_P1_ROM_R_SDA")
	)
	(segment
		(start 112.401604 -402.30044)
		(end 110.6424 -402.30044)
		(width 0.10668)
		(layer "F.Cu")
		(net "SMB_RT_CPU1_P1_ROM_R_SCL")
	)
	(segment
		(start 114.496088 -401.103846)
		(end 113.918492 -401.681442)
		(width 0.10668)
		(layer "F.Cu")
		(net "SMB_RT_CPU1_P1_ROM_R_SCL")
	)
	(segment
		(start 114.749072 -401.103846)
		(end 114.496088 -401.103846)
		(width 0.10668)
		(layer "F.Cu")
		(net "SMB_RT_CPU1_P1_ROM_R_SCL")
	)
	(segment
		(start 109.376464 -396.76578)
		(end 109.22 -396.76578)
		(width 0.10668)
		(layer "F.Cu")
		(net "SMB_RT_CPU1_P1_ROM_R_SCL")
	)
	(segment
		(start 113.918492 -401.681442)
		(end 113.020602 -401.681442)
		(width 0.10668)
		(layer "F.Cu")
		(net "SMB_RT_CPU1_P1_ROM_R_SCL")
	)
	(segment
		(start 110.6424 -402.30044)
		(end 110.09376 -401.7518)
		(width 0.10668)
		(layer "F.Cu")
		(net "SMB_RT_CPU1_P1_ROM_R_SCL")
	)
	(segment
		(start 109.388402 -396.048738)
		(end 109.740954 -396.40129)
		(width 0.10668)
		(layer "F.Cu")
		(net "SMB_RT_CPU1_P1_ROM_R_SCL")
	)
	(segment
		(start 109.210602 -396.048738)
		(end 109.388402 -396.048738)
		(width 0.10668)
		(layer "F.Cu")
		(net "SMB_RT_CPU1_P1_ROM_R_SCL")
	)
	(segment
		(start 109.740954 -396.40129)
		(end 109.376464 -396.76578)
		(width 0.10668)
		(layer "F.Cu")
		(net "SMB_RT_CPU1_P1_ROM_R_SCL")
	)
	(segment
		(start 113.020602 -401.681442)
		(end 112.401604 -402.30044)
		(width 0.10668)
		(layer "F.Cu")
		(net "SMB_RT_CPU1_P1_ROM_R_SCL")
	)
	(via
		(at 109.740954 -396.40129)
		(size 0.508)
		(drill 0.254)
		(layers "F.Cu" "B.Cu")
		(net "SMB_RT_CPU1_P1_ROM_R_SCL")
	)
	(via
		(at 110.09376 -401.7518)
		(size 0.508)
		(drill 0.254)
		(layers "F.Cu" "B.Cu")
		(net "SMB_RT_CPU1_P1_ROM_R_SCL")
	)
	(segment
		(start 110.09376 -401.059396)
		(end 109.06379 -400.029426)
		(width 0.11684)
		(layer "In6.Cu")
		(net "SMB_RT_CPU1_P1_ROM_R_SCL")
	)
	(segment
		(start 110.09376 -401.7518)
		(end 110.09376 -401.059396)
		(width 0.11684)
		(layer "In6.Cu")
		(net "SMB_RT_CPU1_P1_ROM_R_SCL")
	)
	(segment
		(start 109.06379 -397.078454)
		(end 109.740954 -396.40129)
		(width 0.11684)
		(layer "In6.Cu")
		(net "SMB_RT_CPU1_P1_ROM_R_SCL")
	)
	(segment
		(start 109.06379 -400.029426)
		(end 109.06379 -397.078454)
		(width 0.11684)
		(layer "In6.Cu")
		(net "SMB_RT_CPU1_P1_ROM_R_SCL")
	)
	(segment
		(start 77.714856 -390.626092)
		(end 77.62113 -390.626092)
		(width 0.10668)
		(layer "F.Cu")
		(net "SMB_RT_CPU1_P1_ROM_MUX_1D_R_SDA")
	)
	(segment
		(start 104.47528 -394.5001)
		(end 103.984806 -394.5001)
		(width 0.10668)
		(layer "F.Cu")
		(net "SMB_RT_CPU1_P1_ROM_MUX_1D_R_SDA")
	)
	(segment
		(start 103.984806 -394.5001)
		(end 103.85933 -394.625576)
		(width 0.10668)
		(layer "F.Cu")
		(net "SMB_RT_CPU1_P1_ROM_MUX_1D_R_SDA")
	)
	(segment
		(start 78.109826 -390.231122)
		(end 77.714856 -390.626092)
		(width 0.10668)
		(layer "F.Cu")
		(net "SMB_RT_CPU1_P1_ROM_MUX_1D_R_SDA")
	)
	(via
		(at 77.62113 -390.626092)
		(size 0.4064)
		(drill 0.2032)
		(layers "F.Cu" "B.Cu")
		(net "SMB_RT_CPU1_P1_ROM_MUX_1D_R_SDA")
	)
	(via
		(at 103.85933 -394.625576)
		(size 0.508)
		(drill 0.254)
		(layers "F.Cu" "B.Cu")
		(net "SMB_RT_CPU1_P1_ROM_MUX_1D_R_SDA")
	)
	(segment
		(start 103.85933 -394.625576)
		(end 103.647494 -394.837412)
		(width 0.11684)
		(layer "In4.Cu")
		(net "SMB_RT_CPU1_P1_ROM_MUX_1D_R_SDA")
	)
	(segment
		(start 101.090476 -394.837412)
		(end 100.277422 -395.650466)
		(width 0.11684)
		(layer "In4.Cu")
		(net "SMB_RT_CPU1_P1_ROM_MUX_1D_R_SDA")
	)
	(segment
		(start 100.277422 -395.650466)
		(end 79.000858 -395.650466)
		(width 0.11684)
		(layer "In4.Cu")
		(net "SMB_RT_CPU1_P1_ROM_MUX_1D_R_SDA")
	)
	(segment
		(start 79.000858 -395.650466)
		(end 77.838808 -394.488416)
		(width 0.11684)
		(layer "In4.Cu")
		(net "SMB_RT_CPU1_P1_ROM_MUX_1D_R_SDA")
	)
	(segment
		(start 77.387958 -390.859264)
		(end 77.62113 -390.626092)
		(width 0.11684)
		(layer "In4.Cu")
		(net "SMB_RT_CPU1_P1_ROM_MUX_1D_R_SDA")
	)
	(segment
		(start 77.838808 -392.01979)
		(end 77.387958 -391.56894)
		(width 0.11684)
		(layer "In4.Cu")
		(net "SMB_RT_CPU1_P1_ROM_MUX_1D_R_SDA")
	)
	(segment
		(start 77.387958 -391.56894)
		(end 77.387958 -390.859264)
		(width 0.11684)
		(layer "In4.Cu")
		(net "SMB_RT_CPU1_P1_ROM_MUX_1D_R_SDA")
	)
	(segment
		(start 103.647494 -394.837412)
		(end 101.090476 -394.837412)
		(width 0.11684)
		(layer "In4.Cu")
		(net "SMB_RT_CPU1_P1_ROM_MUX_1D_R_SDA")
	)
	(segment
		(start 77.838808 -394.488416)
		(end 77.838808 -392.01979)
		(width 0.11684)
		(layer "In4.Cu")
		(net "SMB_RT_CPU1_P1_ROM_MUX_1D_R_SDA")
	)
	(segment
		(start 105.66146 -395.55674)
		(end 105.492804 -395.388084)
		(width 0.10668)
		(layer "F.Cu")
		(net "SMB_RT_CPU1_P1_ROM_MUX_1D_R_SCL")
	)
	(segment
		(start 78.62951 -389.931148)
		(end 77.757274 -389.931148)
		(width 0.10668)
		(layer "F.Cu")
		(net "SMB_RT_CPU1_P1_ROM_MUX_1D_R_SCL")
	)
	(segment
		(start 105.492804 -395.388084)
		(end 105.03916 -395.388084)
		(width 0.10668)
		(layer "F.Cu")
		(net "SMB_RT_CPU1_P1_ROM_MUX_1D_R_SCL")
	)
	(segment
		(start 77.757274 -389.931148)
		(end 77.62113 -390.067292)
		(width 0.10668)
		(layer "F.Cu")
		(net "SMB_RT_CPU1_P1_ROM_MUX_1D_R_SCL")
	)
	(via
		(at 77.62113 -390.067292)
		(size 0.4064)
		(drill 0.2032)
		(layers "F.Cu" "B.Cu")
		(net "SMB_RT_CPU1_P1_ROM_MUX_1D_R_SCL")
	)
	(via
		(at 105.03916 -395.388084)
		(size 0.508)
		(drill 0.254)
		(layers "F.Cu" "B.Cu")
		(net "SMB_RT_CPU1_P1_ROM_MUX_1D_R_SCL")
	)
	(segment
		(start 103.378254 -394.4112)
		(end 100.920296 -394.4112)
		(width 0.11684)
		(layer "In4.Cu")
		(net "SMB_RT_CPU1_P1_ROM_MUX_1D_R_SCL")
	)
	(segment
		(start 104.150668 -394.1572)
		(end 103.632254 -394.1572)
		(width 0.11684)
		(layer "In4.Cu")
		(net "SMB_RT_CPU1_P1_ROM_MUX_1D_R_SCL")
	)
	(segment
		(start 105.03916 -395.045692)
		(end 104.150668 -394.1572)
		(width 0.11684)
		(layer "In4.Cu")
		(net "SMB_RT_CPU1_P1_ROM_MUX_1D_R_SCL")
	)
	(segment
		(start 105.03916 -395.388084)
		(end 105.03916 -395.045692)
		(width 0.11684)
		(layer "In4.Cu")
		(net "SMB_RT_CPU1_P1_ROM_MUX_1D_R_SCL")
	)
	(segment
		(start 78.45806 -394.511276)
		(end 78.45806 -390.58215)
		(width 0.11684)
		(layer "In4.Cu")
		(net "SMB_RT_CPU1_P1_ROM_MUX_1D_R_SCL")
	)
	(segment
		(start 103.632254 -394.1572)
		(end 103.378254 -394.4112)
		(width 0.11684)
		(layer "In4.Cu")
		(net "SMB_RT_CPU1_P1_ROM_MUX_1D_R_SCL")
	)
	(segment
		(start 78.45806 -390.58215)
		(end 77.943202 -390.067292)
		(width 0.11684)
		(layer "In4.Cu")
		(net "SMB_RT_CPU1_P1_ROM_MUX_1D_R_SCL")
	)
	(segment
		(start 100.10267 -395.228826)
		(end 79.17561 -395.228826)
		(width 0.11684)
		(layer "In4.Cu")
		(net "SMB_RT_CPU1_P1_ROM_MUX_1D_R_SCL")
	)
	(segment
		(start 77.943202 -390.067292)
		(end 77.62113 -390.067292)
		(width 0.11684)
		(layer "In4.Cu")
		(net "SMB_RT_CPU1_P1_ROM_MUX_1D_R_SCL")
	)
	(segment
		(start 100.920296 -394.4112)
		(end 100.10267 -395.228826)
		(width 0.11684)
		(layer "In4.Cu")
		(net "SMB_RT_CPU1_P1_ROM_MUX_1D_R_SCL")
	)
	(segment
		(start 79.17561 -395.228826)
		(end 78.45806 -394.511276)
		(width 0.11684)
		(layer "In4.Cu")
		(net "SMB_RT_CPU1_P1_ROM_MUX_1D_R_SCL")
	)
	(segment
		(start 108.132372 -397.29918)
		(end 108.3564 -397.29918)
		(width 0.10668)
		(layer "F.Cu")
		(net "SMB_RT_CPU1_P1_ROM_SDA")
	)
	(segment
		(start 107.819952 -397.6116)
		(end 108.132372 -397.29918)
		(width 0.10668)
		(layer "F.Cu")
		(net "SMB_RT_CPU1_P1_ROM_SDA")
	)
	(segment
		(start 108.044996 -398.729962)
		(end 107.819952 -398.504918)
		(width 0.10668)
		(layer "F.Cu")
		(net "SMB_RT_CPU1_P1_ROM_SDA")
	)
	(segment
		(start 107.819952 -398.504918)
		(end 107.819952 -397.6116)
		(width 0.10668)
		(layer "F.Cu")
		(net "SMB_RT_CPU1_P1_ROM_SDA")
	)
	(via
		(at 107.819952 -397.6116)
		(size 0.508)
		(drill 0.254)
		(layers "F.Cu" "B.Cu")
		(net "SMB_RT_CPU1_P1_ROM_SDA")
	)
	(segment
		(start 109.296962 -397.29918)
		(end 109.22 -397.29918)
		(width 0.10668)
		(layer "F.Cu")
		(net "SMB_RT_CPU1_P1_ROM_SCL")
	)
	(segment
		(start 109.314996 -398.729962)
		(end 109.314996 -398.104106)
		(width 0.10668)
		(layer "F.Cu")
		(net "SMB_RT_CPU1_P1_ROM_SCL")
	)
	(segment
		(start 109.314996 -398.104106)
		(end 109.708442 -397.71066)
		(width 0.10668)
		(layer "F.Cu")
		(net "SMB_RT_CPU1_P1_ROM_SCL")
	)
	(segment
		(start 109.708442 -397.71066)
		(end 109.296962 -397.29918)
		(width 0.10668)
		(layer "F.Cu")
		(net "SMB_RT_CPU1_P1_ROM_SCL")
	)
	(via
		(at 109.708442 -397.71066)
		(size 0.508)
		(drill 0.254)
		(layers "F.Cu" "B.Cu")
		(net "SMB_RT_CPU1_P1_ROM_SCL")
	)
	(segment
		(start 102.357682 -395.71676)
		(end 102.339648 -395.734794)
		(width 0.10668)
		(layer "F.Cu")
		(net "SMB_RT_CPU1_P0_ROM_R_SDA")
	)
	(segment
		(start 102.357682 -394.964666)
		(end 102.357682 -395.71676)
		(width 0.10668)
		(layer "F.Cu")
		(net "SMB_RT_CPU1_P0_ROM_R_SDA")
	)
	(segment
		(start 98.3869 -402.14169)
		(end 97.870518 -402.14169)
		(width 0.10668)
		(layer "F.Cu")
		(net "SMB_RT_CPU1_P0_ROM_R_SDA")
	)
	(segment
		(start 102.6668 -396.061946)
		(end 102.339648 -395.734794)
		(width 0.10668)
		(layer "F.Cu")
		(net "SMB_RT_CPU1_P0_ROM_R_SDA")
	)
	(segment
		(start 98.751136 -401.777454)
		(end 98.3869 -402.14169)
		(width 0.10668)
		(layer "F.Cu")
		(net "SMB_RT_CPU1_P0_ROM_R_SDA")
	)
	(segment
		(start 102.6668 -396.4305)
		(end 102.6668 -396.061946)
		(width 0.10668)
		(layer "F.Cu")
		(net "SMB_RT_CPU1_P0_ROM_R_SDA")
	)
	(via
		(at 102.339648 -395.734794)
		(size 0.508)
		(drill 0.254)
		(layers "F.Cu" "B.Cu")
		(net "SMB_RT_CPU1_P0_ROM_R_SDA")
	)
	(via
		(at 98.751136 -401.777454)
		(size 0.508)
		(drill 0.254)
		(layers "F.Cu" "B.Cu")
		(net "SMB_RT_CPU1_P0_ROM_R_SDA")
	)
	(segment
		(start 99.29114 -399.43024)
		(end 99.29114 -401.23745)
		(width 0.11684)
		(layer "In15.Cu")
		(net "SMB_RT_CPU1_P0_ROM_R_SDA")
	)
	(segment
		(start 99.91852 -398.80286)
		(end 99.29114 -399.43024)
		(width 0.11684)
		(layer "In15.Cu")
		(net "SMB_RT_CPU1_P0_ROM_R_SDA")
	)
	(segment
		(start 99.91852 -398.45742)
		(end 99.91852 -398.80286)
		(width 0.11684)
		(layer "In15.Cu")
		(net "SMB_RT_CPU1_P0_ROM_R_SDA")
	)
	(segment
		(start 102.339648 -395.734794)
		(end 101.48062 -396.593822)
		(width 0.11684)
		(layer "In15.Cu")
		(net "SMB_RT_CPU1_P0_ROM_R_SDA")
	)
	(segment
		(start 99.29114 -401.23745)
		(end 98.751136 -401.777454)
		(width 0.11684)
		(layer "In15.Cu")
		(net "SMB_RT_CPU1_P0_ROM_R_SDA")
	)
	(segment
		(start 101.48062 -396.89532)
		(end 99.91852 -398.45742)
		(width 0.11684)
		(layer "In15.Cu")
		(net "SMB_RT_CPU1_P0_ROM_R_SDA")
	)
	(segment
		(start 101.48062 -396.593822)
		(end 101.48062 -396.89532)
		(width 0.11684)
		(layer "In15.Cu")
		(net "SMB_RT_CPU1_P0_ROM_R_SDA")
	)
	(segment
		(start 103.145844 -394.95476)
		(end 103.145844 -395.623288)
		(width 0.10668)
		(layer "F.Cu")
		(net "SMB_RT_CPU1_P0_ROM_R_SCL")
	)
	(segment
		(start 103.062532 -395.7066)
		(end 103.5304 -396.174468)
		(width 0.10668)
		(layer "F.Cu")
		(net "SMB_RT_CPU1_P0_ROM_R_SCL")
	)
	(segment
		(start 97.870518 -402.641562)
		(end 98.4885 -402.641562)
		(width 0.10668)
		(layer "F.Cu")
		(net "SMB_RT_CPU1_P0_ROM_R_SCL")
	)
	(segment
		(start 103.5304 -396.174468)
		(end 103.5304 -396.4305)
		(width 0.10668)
		(layer "F.Cu")
		(net "SMB_RT_CPU1_P0_ROM_R_SCL")
	)
	(segment
		(start 98.4885 -402.641562)
		(end 98.66503 -402.818092)
		(width 0.10668)
		(layer "F.Cu")
		(net "SMB_RT_CPU1_P0_ROM_R_SCL")
	)
	(segment
		(start 103.145844 -395.623288)
		(end 103.062532 -395.7066)
		(width 0.10668)
		(layer "F.Cu")
		(net "SMB_RT_CPU1_P0_ROM_R_SCL")
	)
	(via
		(at 98.66503 -402.818092)
		(size 0.508)
		(drill 0.254)
		(layers "F.Cu" "B.Cu")
		(net "SMB_RT_CPU1_P0_ROM_R_SCL")
	)
	(via
		(at 103.062532 -395.7066)
		(size 0.508)
		(drill 0.254)
		(layers "F.Cu" "B.Cu")
		(net "SMB_RT_CPU1_P0_ROM_R_SCL")
	)
	(segment
		(start 98.267012 -402.420074)
		(end 98.66503 -402.818092)
		(width 0.11684)
		(layer "In15.Cu")
		(net "SMB_RT_CPU1_P0_ROM_R_SCL")
	)
	(segment
		(start 98.267012 -399.786348)
		(end 98.267012 -402.420074)
		(width 0.11684)
		(layer "In15.Cu")
		(net "SMB_RT_CPU1_P0_ROM_R_SCL")
	)
	(segment
		(start 102.599998 -395.244066)
		(end 102.016052 -395.244066)
		(width 0.11684)
		(layer "In15.Cu")
		(net "SMB_RT_CPU1_P0_ROM_R_SCL")
	)
	(segment
		(start 99.35718 -397.902938)
		(end 99.35718 -398.69618)
		(width 0.11684)
		(layer "In15.Cu")
		(net "SMB_RT_CPU1_P0_ROM_R_SCL")
	)
	(segment
		(start 103.062532 -395.7066)
		(end 102.599998 -395.244066)
		(width 0.11684)
		(layer "In15.Cu")
		(net "SMB_RT_CPU1_P0_ROM_R_SCL")
	)
	(segment
		(start 102.016052 -395.244066)
		(end 99.35718 -397.902938)
		(width 0.11684)
		(layer "In15.Cu")
		(net "SMB_RT_CPU1_P0_ROM_R_SCL")
	)
	(segment
		(start 99.35718 -398.69618)
		(end 98.267012 -399.786348)
		(width 0.11684)
		(layer "In15.Cu")
		(net "SMB_RT_CPU1_P0_ROM_R_SCL")
	)
	(segment
		(start 45.187108 -390.626092)
		(end 45.093382 -390.626092)
		(width 0.10668)
		(layer "F.Cu")
		(net "SMB_RT_CPU1_P0_ROM_MUX_1D_R_SDA")
	)
	(segment
		(start 42.60596 -379.56236)
		(end 43.39844 -379.56236)
		(width 0.10668)
		(layer "F.Cu")
		(net "SMB_RT_CPU1_P0_ROM_MUX_1D_R_SDA")
	)
	(segment
		(start 45.582078 -390.231122)
		(end 45.187108 -390.626092)
		(width 0.10668)
		(layer "F.Cu")
		(net "SMB_RT_CPU1_P0_ROM_MUX_1D_R_SDA")
	)
	(segment
		(start 43.39844 -379.56236)
		(end 43.70578 -379.8697)
		(width 0.10668)
		(layer "F.Cu")
		(net "SMB_RT_CPU1_P0_ROM_MUX_1D_R_SDA")
	)
	(via
		(at 43.70578 -379.8697)
		(size 0.508)
		(drill 0.254)
		(layers "F.Cu" "B.Cu")
		(net "SMB_RT_CPU1_P0_ROM_MUX_1D_R_SDA")
	)
	(via
		(at 45.093382 -390.626092)
		(size 0.4064)
		(drill 0.2032)
		(layers "F.Cu" "B.Cu")
		(net "SMB_RT_CPU1_P0_ROM_MUX_1D_R_SDA")
	)
	(segment
		(start 42.7482 -386.080508)
		(end 42.7482 -389.006588)
		(width 0.11684)
		(layer "In13.Cu")
		(net "SMB_RT_CPU1_P0_ROM_MUX_1D_R_SDA")
	)
	(segment
		(start 42.38752 -385.719828)
		(end 42.7482 -386.080508)
		(width 0.11684)
		(layer "In13.Cu")
		(net "SMB_RT_CPU1_P0_ROM_MUX_1D_R_SDA")
	)
	(segment
		(start 42.38752 -383.359152)
		(end 42.38752 -385.719828)
		(width 0.11684)
		(layer "In13.Cu")
		(net "SMB_RT_CPU1_P0_ROM_MUX_1D_R_SDA")
	)
	(segment
		(start 44.367704 -390.626092)
		(end 45.093382 -390.626092)
		(width 0.11684)
		(layer "In13.Cu")
		(net "SMB_RT_CPU1_P0_ROM_MUX_1D_R_SDA")
	)
	(segment
		(start 43.70578 -379.8697)
		(end 42.95394 -380.62154)
		(width 0.11684)
		(layer "In13.Cu")
		(net "SMB_RT_CPU1_P0_ROM_MUX_1D_R_SDA")
	)
	(segment
		(start 42.95394 -382.792732)
		(end 42.38752 -383.359152)
		(width 0.11684)
		(layer "In13.Cu")
		(net "SMB_RT_CPU1_P0_ROM_MUX_1D_R_SDA")
	)
	(segment
		(start 42.7482 -389.006588)
		(end 44.367704 -390.626092)
		(width 0.11684)
		(layer "In13.Cu")
		(net "SMB_RT_CPU1_P0_ROM_MUX_1D_R_SDA")
	)
	(segment
		(start 42.95394 -380.62154)
		(end 42.95394 -382.792732)
		(width 0.11684)
		(layer "In13.Cu")
		(net "SMB_RT_CPU1_P0_ROM_MUX_1D_R_SDA")
	)
	(segment
		(start 42.6339 -378.71654)
		(end 43.53052 -378.71654)
		(width 0.10668)
		(layer "F.Cu")
		(net "SMB_RT_CPU1_P0_ROM_MUX_1D_R_SCL")
	)
	(segment
		(start 46.101762 -389.931148)
		(end 45.229526 -389.931148)
		(width 0.10668)
		(layer "F.Cu")
		(net "SMB_RT_CPU1_P0_ROM_MUX_1D_R_SCL")
	)
	(segment
		(start 45.229526 -389.931148)
		(end 45.093382 -390.067292)
		(width 0.10668)
		(layer "F.Cu")
		(net "SMB_RT_CPU1_P0_ROM_MUX_1D_R_SCL")
	)
	(segment
		(start 43.53052 -378.71654)
		(end 43.73372 -378.51334)
		(width 0.10668)
		(layer "F.Cu")
		(net "SMB_RT_CPU1_P0_ROM_MUX_1D_R_SCL")
	)
	(via
		(at 43.73372 -378.51334)
		(size 0.508)
		(drill 0.254)
		(layers "F.Cu" "B.Cu")
		(net "SMB_RT_CPU1_P0_ROM_MUX_1D_R_SCL")
	)
	(via
		(at 45.093382 -390.067292)
		(size 0.4064)
		(drill 0.2032)
		(layers "F.Cu" "B.Cu")
		(net "SMB_RT_CPU1_P0_ROM_MUX_1D_R_SCL")
	)
	(segment
		(start 43.54957 -380.92507)
		(end 43.54957 -382.98755)
		(width 0.11684)
		(layer "In13.Cu")
		(net "SMB_RT_CPU1_P0_ROM_MUX_1D_R_SCL")
	)
	(segment
		(start 44.34078 -380.13386)
		(end 43.54957 -380.92507)
		(width 0.11684)
		(layer "In13.Cu")
		(net "SMB_RT_CPU1_P0_ROM_MUX_1D_R_SCL")
	)
	(segment
		(start 42.94632 -385.48818)
		(end 43.307 -385.84886)
		(width 0.11684)
		(layer "In13.Cu")
		(net "SMB_RT_CPU1_P0_ROM_MUX_1D_R_SCL")
	)
	(segment
		(start 44.599352 -390.067292)
		(end 45.093382 -390.067292)
		(width 0.11684)
		(layer "In13.Cu")
		(net "SMB_RT_CPU1_P0_ROM_MUX_1D_R_SCL")
	)
	(segment
		(start 43.307 -385.84886)
		(end 43.307 -388.77494)
		(width 0.11684)
		(layer "In13.Cu")
		(net "SMB_RT_CPU1_P0_ROM_MUX_1D_R_SCL")
	)
	(segment
		(start 42.94632 -383.5908)
		(end 42.94632 -385.48818)
		(width 0.11684)
		(layer "In13.Cu")
		(net "SMB_RT_CPU1_P0_ROM_MUX_1D_R_SCL")
	)
	(segment
		(start 43.73372 -378.51334)
		(end 44.34078 -379.1204)
		(width 0.11684)
		(layer "In13.Cu")
		(net "SMB_RT_CPU1_P0_ROM_MUX_1D_R_SCL")
	)
	(segment
		(start 44.34078 -379.1204)
		(end 44.34078 -380.13386)
		(width 0.11684)
		(layer "In13.Cu")
		(net "SMB_RT_CPU1_P0_ROM_MUX_1D_R_SCL")
	)
	(segment
		(start 43.54957 -382.98755)
		(end 42.94632 -383.5908)
		(width 0.11684)
		(layer "In13.Cu")
		(net "SMB_RT_CPU1_P0_ROM_MUX_1D_R_SCL")
	)
	(segment
		(start 43.307 -388.77494)
		(end 44.599352 -390.067292)
		(width 0.11684)
		(layer "In13.Cu")
		(net "SMB_RT_CPU1_P0_ROM_MUX_1D_R_SCL")
	)
	(segment
		(start 102.6668 -396.9639)
		(end 102.267512 -397.363188)
		(width 0.10668)
		(layer "F.Cu")
		(net "SMB_RT_CPU1_P0_ROM_SDA")
	)
	(segment
		(start 101.917246 -397.363188)
		(end 101.917246 -397.760952)
		(width 0.10668)
		(layer "F.Cu")
		(net "SMB_RT_CPU1_P0_ROM_SDA")
	)
	(segment
		(start 101.696266 -397.981932)
		(end 101.696266 -398.729962)
		(width 0.10668)
		(layer "F.Cu")
		(net "SMB_RT_CPU1_P0_ROM_SDA")
	)
	(segment
		(start 101.917246 -397.760952)
		(end 101.696266 -397.981932)
		(width 0.10668)
		(layer "F.Cu")
		(net "SMB_RT_CPU1_P0_ROM_SDA")
	)
	(segment
		(start 102.267512 -397.363188)
		(end 101.917246 -397.363188)
		(width 0.10668)
		(layer "F.Cu")
		(net "SMB_RT_CPU1_P0_ROM_SDA")
	)
	(via
		(at 101.917246 -397.363188)
		(size 0.508)
		(drill 0.254)
		(layers "F.Cu" "B.Cu")
		(net "SMB_RT_CPU1_P0_ROM_SDA")
	)
	(segment
		(start 103.428292 -397.50746)
		(end 103.5304 -397.405352)
		(width 0.10668)
		(layer "F.Cu")
		(net "SMB_RT_CPU1_P0_ROM_SCL")
	)
	(segment
		(start 102.966266 -397.969486)
		(end 103.428292 -397.50746)
		(width 0.10668)
		(layer "F.Cu")
		(net "SMB_RT_CPU1_P0_ROM_SCL")
	)
	(segment
		(start 102.966266 -398.729962)
		(end 102.966266 -397.969486)
		(width 0.10668)
		(layer "F.Cu")
		(net "SMB_RT_CPU1_P0_ROM_SCL")
	)
	(segment
		(start 103.5304 -397.405352)
		(end 103.5304 -396.9639)
		(width 0.10668)
		(layer "F.Cu")
		(net "SMB_RT_CPU1_P0_ROM_SCL")
	)
	(via
		(at 103.428292 -397.50746)
		(size 0.508)
		(drill 0.254)
		(layers "F.Cu" "B.Cu")
		(net "SMB_RT_CPU1_P0_ROM_SCL")
	)
	(segment
		(start 373.88165 -425.635166)
		(end 373.275352 -425.028868)
		(width 0.10668)
		(layer "F.Cu")
		(net "SMB_RT_CPU0_P3_ROM_R_SDA")
	)
	(segment
		(start 373.88165 -425.927774)
		(end 373.88165 -425.635166)
		(width 0.10668)
		(layer "F.Cu")
		(net "SMB_RT_CPU0_P3_ROM_R_SDA")
	)
	(via
		(at 365.271812 -424.177968)
		(size 0.508)
		(drill 0.254)
		(layers "F.Cu" "B.Cu")
		(net "SMB_RT_CPU0_P3_ROM_R_SDA")
	)
	(via
		(at 373.275352 -425.028868)
		(size 0.508)
		(drill 0.254)
		(layers "F.Cu" "B.Cu")
		(net "SMB_RT_CPU0_P3_ROM_R_SDA")
	)
	(segment
		(start 366.633506 -424.149012)
		(end 366.834928 -423.94759)
		(width 0.10668)
		(layer "B.Cu")
		(net "SMB_RT_CPU0_P3_ROM_R_SDA")
	)
	(segment
		(start 365.395002 -424.301158)
		(end 365.892334 -424.301158)
		(width 0.10668)
		(layer "B.Cu")
		(net "SMB_RT_CPU0_P3_ROM_R_SDA")
	)
	(segment
		(start 366.651794 -423.022776)
		(end 366.113568 -423.022776)
		(width 0.10668)
		(layer "B.Cu")
		(net "SMB_RT_CPU0_P3_ROM_R_SDA")
	)
	(segment
		(start 366.834928 -423.20591)
		(end 366.651794 -423.022776)
		(width 0.10668)
		(layer "B.Cu")
		(net "SMB_RT_CPU0_P3_ROM_R_SDA")
	)
	(segment
		(start 366.04448 -424.149012)
		(end 366.633506 -424.149012)
		(width 0.10668)
		(layer "B.Cu")
		(net "SMB_RT_CPU0_P3_ROM_R_SDA")
	)
	(segment
		(start 366.834928 -423.57675)
		(end 366.834928 -423.20591)
		(width 0.10668)
		(layer "B.Cu")
		(net "SMB_RT_CPU0_P3_ROM_R_SDA")
	)
	(segment
		(start 366.834928 -423.94759)
		(end 366.834928 -423.57675)
		(width 0.10668)
		(layer "B.Cu")
		(net "SMB_RT_CPU0_P3_ROM_R_SDA")
	)
	(segment
		(start 365.271812 -424.177968)
		(end 365.395002 -424.301158)
		(width 0.10668)
		(layer "B.Cu")
		(net "SMB_RT_CPU0_P3_ROM_R_SDA")
	)
	(segment
		(start 365.892334 -424.301158)
		(end 366.04448 -424.149012)
		(width 0.10668)
		(layer "B.Cu")
		(net "SMB_RT_CPU0_P3_ROM_R_SDA")
	)
	(segment
		(start 373.275352 -425.028868)
		(end 373.275352 -425.494704)
		(width 0.11684)
		(layer "In11.Cu")
		(net "SMB_RT_CPU0_P3_ROM_R_SDA")
	)
	(segment
		(start 373.275352 -425.494704)
		(end 372.705884 -426.064172)
		(width 0.11684)
		(layer "In11.Cu")
		(net "SMB_RT_CPU0_P3_ROM_R_SDA")
	)
	(segment
		(start 372.705884 -426.064172)
		(end 372.02364 -426.064172)
		(width 0.11684)
		(layer "In11.Cu")
		(net "SMB_RT_CPU0_P3_ROM_R_SDA")
	)
	(segment
		(start 368.37112 -427.039786)
		(end 366.084104 -427.039786)
		(width 0.11684)
		(layer "In11.Cu")
		(net "SMB_RT_CPU0_P3_ROM_R_SDA")
	)
	(segment
		(start 366.084104 -427.039786)
		(end 364.967774 -425.923456)
		(width 0.11684)
		(layer "In11.Cu")
		(net "SMB_RT_CPU0_P3_ROM_R_SDA")
	)
	(segment
		(start 368.804698 -426.606208)
		(end 368.37112 -427.039786)
		(width 0.11684)
		(layer "In11.Cu")
		(net "SMB_RT_CPU0_P3_ROM_R_SDA")
	)
	(segment
		(start 371.481604 -426.606208)
		(end 368.804698 -426.606208)
		(width 0.11684)
		(layer "In11.Cu")
		(net "SMB_RT_CPU0_P3_ROM_R_SDA")
	)
	(segment
		(start 364.967774 -425.923456)
		(end 364.967774 -424.482006)
		(width 0.11684)
		(layer "In11.Cu")
		(net "SMB_RT_CPU0_P3_ROM_R_SDA")
	)
	(segment
		(start 372.02364 -426.064172)
		(end 371.481604 -426.606208)
		(width 0.11684)
		(layer "In11.Cu")
		(net "SMB_RT_CPU0_P3_ROM_R_SDA")
	)
	(segment
		(start 364.967774 -424.482006)
		(end 365.271812 -424.177968)
		(width 0.11684)
		(layer "In11.Cu")
		(net "SMB_RT_CPU0_P3_ROM_R_SDA")
	)
	(segment
		(start 373.28983 -424.387518)
		(end 372.897908 -424.387518)
		(width 0.10668)
		(layer "F.Cu")
		(net "SMB_RT_CPU0_P3_ROM_R_SCL")
	)
	(segment
		(start 374.381522 -425.927774)
		(end 374.381522 -425.47921)
		(width 0.10668)
		(layer "F.Cu")
		(net "SMB_RT_CPU0_P3_ROM_R_SCL")
	)
	(segment
		(start 374.381522 -425.47921)
		(end 373.28983 -424.387518)
		(width 0.10668)
		(layer "F.Cu")
		(net "SMB_RT_CPU0_P3_ROM_R_SCL")
	)
	(via
		(at 365.586264 -425.47032)
		(size 0.508)
		(drill 0.254)
		(layers "F.Cu" "B.Cu")
		(net "SMB_RT_CPU0_P3_ROM_R_SCL")
	)
	(via
		(at 372.897908 -424.387518)
		(size 0.508)
		(drill 0.254)
		(layers "F.Cu" "B.Cu")
		(net "SMB_RT_CPU0_P3_ROM_R_SCL")
	)
	(segment
		(start 368.54892 -425.509182)
		(end 368.54892 -425.389802)
		(width 0.10668)
		(layer "B.Cu")
		(net "SMB_RT_CPU0_P3_ROM_R_SCL")
	)
	(segment
		(start 366.184688 -424.522392)
		(end 365.586264 -425.120816)
		(width 0.10668)
		(layer "B.Cu")
		(net "SMB_RT_CPU0_P3_ROM_R_SCL")
	)
	(segment
		(start 365.586264 -425.120816)
		(end 365.586264 -425.47032)
		(width 0.10668)
		(layer "B.Cu")
		(net "SMB_RT_CPU0_P3_ROM_R_SCL")
	)
	(segment
		(start 368.214402 -425.055284)
		(end 368.214402 -424.88993)
		(width 0.10668)
		(layer "B.Cu")
		(net "SMB_RT_CPU0_P3_ROM_R_SCL")
	)
	(segment
		(start 368.54892 -425.389802)
		(end 368.214402 -425.055284)
		(width 0.10668)
		(layer "B.Cu")
		(net "SMB_RT_CPU0_P3_ROM_R_SCL")
	)
	(segment
		(start 367.03762 -424.522392)
		(end 366.184688 -424.522392)
		(width 0.10668)
		(layer "B.Cu")
		(net "SMB_RT_CPU0_P3_ROM_R_SCL")
	)
	(segment
		(start 368.068098 -424.372786)
		(end 367.735358 -424.372786)
		(width 0.10668)
		(layer "B.Cu")
		(net "SMB_RT_CPU0_P3_ROM_R_SCL")
	)
	(segment
		(start 367.735358 -424.372786)
		(end 367.660428 -424.297856)
		(width 0.10668)
		(layer "B.Cu")
		(net "SMB_RT_CPU0_P3_ROM_R_SCL")
	)
	(segment
		(start 368.068098 -424.743626)
		(end 368.068098 -424.372786)
		(width 0.10668)
		(layer "B.Cu")
		(net "SMB_RT_CPU0_P3_ROM_R_SCL")
	)
	(segment
		(start 367.262156 -424.297856)
		(end 367.03762 -424.522392)
		(width 0.10668)
		(layer "B.Cu")
		(net "SMB_RT_CPU0_P3_ROM_R_SCL")
	)
	(segment
		(start 367.660428 -424.297856)
		(end 367.262156 -424.297856)
		(width 0.10668)
		(layer "B.Cu")
		(net "SMB_RT_CPU0_P3_ROM_R_SCL")
	)
	(segment
		(start 368.214402 -424.88993)
		(end 368.068098 -424.743626)
		(width 0.10668)
		(layer "B.Cu")
		(net "SMB_RT_CPU0_P3_ROM_R_SCL")
	)
	(segment
		(start 365.586264 -425.805092)
		(end 365.586264 -425.47032)
		(width 0.11684)
		(layer "In11.Cu")
		(net "SMB_RT_CPU0_P3_ROM_R_SCL")
	)
	(segment
		(start 372.383558 -424.387518)
		(end 370.609368 -426.161708)
		(width 0.11684)
		(layer "In11.Cu")
		(net "SMB_RT_CPU0_P3_ROM_R_SCL")
	)
	(segment
		(start 372.897908 -424.387518)
		(end 372.383558 -424.387518)
		(width 0.11684)
		(layer "In11.Cu")
		(net "SMB_RT_CPU0_P3_ROM_R_SCL")
	)
	(segment
		(start 368.652806 -426.161708)
		(end 368.381788 -426.432726)
		(width 0.11684)
		(layer "In11.Cu")
		(net "SMB_RT_CPU0_P3_ROM_R_SCL")
	)
	(segment
		(start 370.609368 -426.161708)
		(end 368.652806 -426.161708)
		(width 0.11684)
		(layer "In11.Cu")
		(net "SMB_RT_CPU0_P3_ROM_R_SCL")
	)
	(segment
		(start 368.381788 -426.432726)
		(end 366.213898 -426.432726)
		(width 0.11684)
		(layer "In11.Cu")
		(net "SMB_RT_CPU0_P3_ROM_R_SCL")
	)
	(segment
		(start 366.213898 -426.432726)
		(end 365.586264 -425.805092)
		(width 0.11684)
		(layer "In11.Cu")
		(net "SMB_RT_CPU0_P3_ROM_R_SCL")
	)
	(segment
		(start 364.102142 -422.705022)
		(end 364.856522 -421.950642)
		(width 0.10668)
		(layer "F.Cu")
		(net "SMB_RT_CPU0_P3_ROM_MUX_1D_R_SDA")
	)
	(segment
		(start 368.287046 -399.008092)
		(end 368.19332 -399.008092)
		(width 0.10668)
		(layer "F.Cu")
		(net "SMB_RT_CPU0_P3_ROM_MUX_1D_R_SDA")
	)
	(segment
		(start 364.987332 -427.39691)
		(end 364.102142 -426.51172)
		(width 0.10668)
		(layer "F.Cu")
		(net "SMB_RT_CPU0_P3_ROM_MUX_1D_R_SDA")
	)
	(segment
		(start 364.068868 -419.602158)
		(end 364.021878 -419.602158)
		(width 0.10668)
		(layer "F.Cu")
		(net "SMB_RT_CPU0_P3_ROM_MUX_1D_R_SDA")
	)
	(segment
		(start 364.856522 -420.389812)
		(end 364.068868 -419.602158)
		(width 0.10668)
		(layer "F.Cu")
		(net "SMB_RT_CPU0_P3_ROM_MUX_1D_R_SDA")
	)
	(segment
		(start 368.682016 -398.613122)
		(end 368.287046 -399.008092)
		(width 0.10668)
		(layer "F.Cu")
		(net "SMB_RT_CPU0_P3_ROM_MUX_1D_R_SDA")
	)
	(segment
		(start 364.102142 -426.51172)
		(end 364.102142 -422.705022)
		(width 0.10668)
		(layer "F.Cu")
		(net "SMB_RT_CPU0_P3_ROM_MUX_1D_R_SDA")
	)
	(segment
		(start 364.856522 -421.950642)
		(end 364.856522 -420.389812)
		(width 0.10668)
		(layer "F.Cu")
		(net "SMB_RT_CPU0_P3_ROM_MUX_1D_R_SDA")
	)
	(segment
		(start 365.528098 -427.39691)
		(end 364.987332 -427.39691)
		(width 0.10668)
		(layer "F.Cu")
		(net "SMB_RT_CPU0_P3_ROM_MUX_1D_R_SDA")
	)
	(via
		(at 364.021878 -419.602158)
		(size 0.508)
		(drill 0.254)
		(layers "F.Cu" "B.Cu")
		(net "SMB_RT_CPU0_P3_ROM_MUX_1D_R_SDA")
	)
	(via
		(at 368.19332 -399.008092)
		(size 0.4064)
		(drill 0.2032)
		(layers "F.Cu" "B.Cu")
		(net "SMB_RT_CPU0_P3_ROM_MUX_1D_R_SDA")
	)
	(segment
		(start 369.557808 -408.662886)
		(end 368.300254 -407.405332)
		(width 0.11684)
		(layer "In4.Cu")
		(net "SMB_RT_CPU0_P3_ROM_MUX_1D_R_SDA")
	)
	(segment
		(start 366.154462 -407.16708)
		(end 366.154462 -404.728426)
		(width 0.11684)
		(layer "In4.Cu")
		(net "SMB_RT_CPU0_P3_ROM_MUX_1D_R_SDA")
	)
	(segment
		(start 364.473744 -419.602158)
		(end 365.006382 -419.06952)
		(width 0.11684)
		(layer "In4.Cu")
		(net "SMB_RT_CPU0_P3_ROM_MUX_1D_R_SDA")
	)
	(segment
		(start 365.006382 -415.90214)
		(end 365.417862 -415.49066)
		(width 0.11684)
		(layer "In4.Cu")
		(net "SMB_RT_CPU0_P3_ROM_MUX_1D_R_SDA")
	)
	(segment
		(start 369.557808 -413.908494)
		(end 369.557808 -408.662886)
		(width 0.11684)
		(layer "In4.Cu")
		(net "SMB_RT_CPU0_P3_ROM_MUX_1D_R_SDA")
	)
	(segment
		(start 367.97107 -399.701512)
		(end 367.97107 -399.230342)
		(width 0.11684)
		(layer "In4.Cu")
		(net "SMB_RT_CPU0_P3_ROM_MUX_1D_R_SDA")
	)
	(segment
		(start 367.975642 -415.49066)
		(end 369.557808 -413.908494)
		(width 0.11684)
		(layer "In4.Cu")
		(net "SMB_RT_CPU0_P3_ROM_MUX_1D_R_SDA")
	)
	(segment
		(start 366.392714 -407.405332)
		(end 366.154462 -407.16708)
		(width 0.11684)
		(layer "In4.Cu")
		(net "SMB_RT_CPU0_P3_ROM_MUX_1D_R_SDA")
	)
	(segment
		(start 368.877596 -400.608038)
		(end 367.97107 -399.701512)
		(width 0.11684)
		(layer "In4.Cu")
		(net "SMB_RT_CPU0_P3_ROM_MUX_1D_R_SDA")
	)
	(segment
		(start 365.417862 -415.49066)
		(end 367.975642 -415.49066)
		(width 0.11684)
		(layer "In4.Cu")
		(net "SMB_RT_CPU0_P3_ROM_MUX_1D_R_SDA")
	)
	(segment
		(start 365.006382 -419.06952)
		(end 365.006382 -415.90214)
		(width 0.11684)
		(layer "In4.Cu")
		(net "SMB_RT_CPU0_P3_ROM_MUX_1D_R_SDA")
	)
	(segment
		(start 367.97107 -399.230342)
		(end 368.19332 -399.008092)
		(width 0.11684)
		(layer "In4.Cu")
		(net "SMB_RT_CPU0_P3_ROM_MUX_1D_R_SDA")
	)
	(segment
		(start 368.300254 -407.405332)
		(end 366.392714 -407.405332)
		(width 0.11684)
		(layer "In4.Cu")
		(net "SMB_RT_CPU0_P3_ROM_MUX_1D_R_SDA")
	)
	(segment
		(start 368.877596 -402.005292)
		(end 368.877596 -400.608038)
		(width 0.11684)
		(layer "In4.Cu")
		(net "SMB_RT_CPU0_P3_ROM_MUX_1D_R_SDA")
	)
	(segment
		(start 366.154462 -404.728426)
		(end 368.877596 -402.005292)
		(width 0.11684)
		(layer "In4.Cu")
		(net "SMB_RT_CPU0_P3_ROM_MUX_1D_R_SDA")
	)
	(segment
		(start 364.021878 -419.602158)
		(end 364.473744 -419.602158)
		(width 0.11684)
		(layer "In4.Cu")
		(net "SMB_RT_CPU0_P3_ROM_MUX_1D_R_SDA")
	)
	(segment
		(start 365.364522 -428.28591)
		(end 363.761782 -426.68317)
		(width 0.10668)
		(layer "F.Cu")
		(net "SMB_RT_CPU0_P3_ROM_MUX_1D_R_SCL")
	)
	(segment
		(start 365.528098 -428.28591)
		(end 365.364522 -428.28591)
		(width 0.10668)
		(layer "F.Cu")
		(net "SMB_RT_CPU0_P3_ROM_MUX_1D_R_SCL")
	)
	(segment
		(start 369.2017 -398.313148)
		(end 368.329464 -398.313148)
		(width 0.10668)
		(layer "F.Cu")
		(net "SMB_RT_CPU0_P3_ROM_MUX_1D_R_SCL")
	)
	(segment
		(start 368.329464 -398.313148)
		(end 368.19332 -398.449292)
		(width 0.10668)
		(layer "F.Cu")
		(net "SMB_RT_CPU0_P3_ROM_MUX_1D_R_SCL")
	)
	(segment
		(start 363.761782 -421.847264)
		(end 364.138972 -421.470074)
		(width 0.10668)
		(layer "F.Cu")
		(net "SMB_RT_CPU0_P3_ROM_MUX_1D_R_SCL")
	)
	(segment
		(start 363.761782 -426.68317)
		(end 363.761782 -421.847264)
		(width 0.10668)
		(layer "F.Cu")
		(net "SMB_RT_CPU0_P3_ROM_MUX_1D_R_SCL")
	)
	(via
		(at 364.138972 -421.470074)
		(size 0.508)
		(drill 0.254)
		(layers "F.Cu" "B.Cu")
		(net "SMB_RT_CPU0_P3_ROM_MUX_1D_R_SCL")
	)
	(via
		(at 368.19332 -398.449292)
		(size 0.4064)
		(drill 0.2032)
		(layers "F.Cu" "B.Cu")
		(net "SMB_RT_CPU0_P3_ROM_MUX_1D_R_SCL")
	)
	(segment
		(start 368.066574 -407.968958)
		(end 366.159034 -407.968958)
		(width 0.11684)
		(layer "In4.Cu")
		(net "SMB_RT_CPU0_P3_ROM_MUX_1D_R_SCL")
	)
	(segment
		(start 364.138972 -421.412416)
		(end 363.332014 -420.605458)
		(width 0.11684)
		(layer "In4.Cu")
		(net "SMB_RT_CPU0_P3_ROM_MUX_1D_R_SCL")
	)
	(segment
		(start 365.590836 -404.494746)
		(end 368.428016 -401.657566)
		(width 0.11684)
		(layer "In4.Cu")
		(net "SMB_RT_CPU0_P3_ROM_MUX_1D_R_SCL")
	)
	(segment
		(start 364.138972 -421.470074)
		(end 364.138972 -421.412416)
		(width 0.11684)
		(layer "In4.Cu")
		(net "SMB_RT_CPU0_P3_ROM_MUX_1D_R_SCL")
	)
	(segment
		(start 368.428016 -400.825462)
		(end 367.548922 -399.946368)
		(width 0.11684)
		(layer "In4.Cu")
		(net "SMB_RT_CPU0_P3_ROM_MUX_1D_R_SCL")
	)
	(segment
		(start 366.159034 -407.968958)
		(end 365.590836 -407.40076)
		(width 0.11684)
		(layer "In4.Cu")
		(net "SMB_RT_CPU0_P3_ROM_MUX_1D_R_SCL")
	)
	(segment
		(start 367.548922 -399.946368)
		(end 367.548922 -398.954498)
		(width 0.11684)
		(layer "In4.Cu")
		(net "SMB_RT_CPU0_P3_ROM_MUX_1D_R_SCL")
	)
	(segment
		(start 365.590836 -407.40076)
		(end 365.590836 -404.494746)
		(width 0.11684)
		(layer "In4.Cu")
		(net "SMB_RT_CPU0_P3_ROM_MUX_1D_R_SCL")
	)
	(segment
		(start 367.548922 -398.954498)
		(end 368.054128 -398.449292)
		(width 0.11684)
		(layer "In4.Cu")
		(net "SMB_RT_CPU0_P3_ROM_MUX_1D_R_SCL")
	)
	(segment
		(start 365.184182 -414.927034)
		(end 367.741962 -414.927034)
		(width 0.11684)
		(layer "In4.Cu")
		(net "SMB_RT_CPU0_P3_ROM_MUX_1D_R_SCL")
	)
	(segment
		(start 367.741962 -414.927034)
		(end 368.994182 -413.674814)
		(width 0.11684)
		(layer "In4.Cu")
		(net "SMB_RT_CPU0_P3_ROM_MUX_1D_R_SCL")
	)
	(segment
		(start 363.332014 -419.19906)
		(end 363.546136 -418.984938)
		(width 0.11684)
		(layer "In4.Cu")
		(net "SMB_RT_CPU0_P3_ROM_MUX_1D_R_SCL")
	)
	(segment
		(start 368.994182 -413.674814)
		(end 368.994182 -408.896566)
		(width 0.11684)
		(layer "In4.Cu")
		(net "SMB_RT_CPU0_P3_ROM_MUX_1D_R_SCL")
	)
	(segment
		(start 363.332014 -420.605458)
		(end 363.332014 -419.19906)
		(width 0.11684)
		(layer "In4.Cu")
		(net "SMB_RT_CPU0_P3_ROM_MUX_1D_R_SCL")
	)
	(segment
		(start 363.546136 -418.984938)
		(end 363.546136 -416.56508)
		(width 0.11684)
		(layer "In4.Cu")
		(net "SMB_RT_CPU0_P3_ROM_MUX_1D_R_SCL")
	)
	(segment
		(start 368.054128 -398.449292)
		(end 368.19332 -398.449292)
		(width 0.11684)
		(layer "In4.Cu")
		(net "SMB_RT_CPU0_P3_ROM_MUX_1D_R_SCL")
	)
	(segment
		(start 368.428016 -401.657566)
		(end 368.428016 -400.825462)
		(width 0.11684)
		(layer "In4.Cu")
		(net "SMB_RT_CPU0_P3_ROM_MUX_1D_R_SCL")
	)
	(segment
		(start 363.546136 -416.56508)
		(end 365.184182 -414.927034)
		(width 0.11684)
		(layer "In4.Cu")
		(net "SMB_RT_CPU0_P3_ROM_MUX_1D_R_SCL")
	)
	(segment
		(start 368.994182 -408.896566)
		(end 368.066574 -407.968958)
		(width 0.11684)
		(layer "In4.Cu")
		(net "SMB_RT_CPU0_P3_ROM_MUX_1D_R_SCL")
	)
	(via
		(at 368.185954 -423.144442)
		(size 0.6604)
		(drill 0.3302)
		(layers "F.Cu" "B.Cu")
		(net "SMB_RT_CPU0_P3_ROM_SDA")
	)
	(segment
		(start 371.004084 -422.618916)
		(end 369.979194 -423.643806)
		(width 0.10668)
		(layer "B.Cu")
		(net "SMB_RT_CPU0_P3_ROM_SDA")
	)
	(segment
		(start 368.981482 -423.643806)
		(end 368.482118 -423.144442)
		(width 0.10668)
		(layer "B.Cu")
		(net "SMB_RT_CPU0_P3_ROM_SDA")
	)
	(segment
		(start 369.979194 -423.643806)
		(end 368.981482 -423.643806)
		(width 0.10668)
		(layer "B.Cu")
		(net "SMB_RT_CPU0_P3_ROM_SDA")
	)
	(segment
		(start 368.482118 -423.144442)
		(end 368.185954 -423.144442)
		(width 0.10668)
		(layer "B.Cu")
		(net "SMB_RT_CPU0_P3_ROM_SDA")
	)
	(segment
		(start 371.376702 -422.618916)
		(end 371.004084 -422.618916)
		(width 0.10668)
		(layer "B.Cu")
		(net "SMB_RT_CPU0_P3_ROM_SDA")
	)
	(segment
		(start 367.483136 -423.091102)
		(end 367.368328 -423.20591)
		(width 0.10668)
		(layer "B.Cu")
		(net "SMB_RT_CPU0_P3_ROM_SDA")
	)
	(segment
		(start 367.368328 -423.20591)
		(end 367.368328 -423.57675)
		(width 0.10668)
		(layer "B.Cu")
		(net "SMB_RT_CPU0_P3_ROM_SDA")
	)
	(segment
		(start 368.132614 -423.091102)
		(end 367.483136 -423.091102)
		(width 0.10668)
		(layer "B.Cu")
		(net "SMB_RT_CPU0_P3_ROM_SDA")
	)
	(segment
		(start 368.185954 -423.144442)
		(end 368.132614 -423.091102)
		(width 0.10668)
		(layer "B.Cu")
		(net "SMB_RT_CPU0_P3_ROM_SDA")
	)
	(via
		(at 369.49507 -424.501818)
		(size 0.6604)
		(drill 0.3302)
		(layers "F.Cu" "B.Cu")
		(net "SMB_RT_CPU0_P3_ROM_SCL")
	)
	(segment
		(start 370.491766 -424.053)
		(end 371.212618 -424.053)
		(width 0.10668)
		(layer "B.Cu")
		(net "SMB_RT_CPU0_P3_ROM_SCL")
	)
	(segment
		(start 369.991894 -424.552872)
		(end 370.491766 -424.053)
		(width 0.10668)
		(layer "B.Cu")
		(net "SMB_RT_CPU0_P3_ROM_SCL")
	)
	(segment
		(start 369.49507 -424.501818)
		(end 369.546124 -424.552872)
		(width 0.10668)
		(layer "B.Cu")
		(net "SMB_RT_CPU0_P3_ROM_SCL")
	)
	(segment
		(start 371.212618 -424.053)
		(end 371.376702 -423.888916)
		(width 0.10668)
		(layer "B.Cu")
		(net "SMB_RT_CPU0_P3_ROM_SCL")
	)
	(segment
		(start 369.546124 -424.552872)
		(end 369.991894 -424.552872)
		(width 0.10668)
		(layer "B.Cu")
		(net "SMB_RT_CPU0_P3_ROM_SCL")
	)
	(segment
		(start 368.601498 -424.372786)
		(end 369.366038 -424.372786)
		(width 0.10668)
		(layer "B.Cu")
		(net "SMB_RT_CPU0_P3_ROM_SCL")
	)
	(segment
		(start 369.366038 -424.372786)
		(end 369.49507 -424.501818)
		(width 0.10668)
		(layer "B.Cu")
		(net "SMB_RT_CPU0_P3_ROM_SCL")
	)
	(segment
		(start 419.391084 -423.510964)
		(end 419.391084 -423.061638)
		(width 0.10668)
		(layer "F.Cu")
		(net "SMB_RT_CPU0_P2_ROM_R_SDA")
	)
	(segment
		(start 419.391084 -423.061638)
		(end 419.531292 -422.92143)
		(width 0.10668)
		(layer "F.Cu")
		(net "SMB_RT_CPU0_P2_ROM_R_SDA")
	)
	(via
		(at 419.531292 -422.92143)
		(size 0.508)
		(drill 0.254)
		(layers "F.Cu" "B.Cu")
		(net "SMB_RT_CPU0_P2_ROM_R_SDA")
	)
	(segment
		(start 419.06317 -426.291756)
		(end 418.402008 -426.291756)
		(width 0.10668)
		(layer "B.Cu")
		(net "SMB_RT_CPU0_P2_ROM_R_SDA")
	)
	(segment
		(start 418.402008 -426.291756)
		(end 417.984686 -425.874434)
		(width 0.10668)
		(layer "B.Cu")
		(net "SMB_RT_CPU0_P2_ROM_R_SDA")
	)
	(segment
		(start 417.984686 -424.468036)
		(end 419.531292 -422.92143)
		(width 0.10668)
		(layer "B.Cu")
		(net "SMB_RT_CPU0_P2_ROM_R_SDA")
	)
	(segment
		(start 417.984686 -425.874434)
		(end 417.984686 -424.468036)
		(width 0.10668)
		(layer "B.Cu")
		(net "SMB_RT_CPU0_P2_ROM_R_SDA")
	)
	(segment
		(start 419.396164 -426.799248)
		(end 419.396164 -426.62475)
		(width 0.10668)
		(layer "B.Cu")
		(net "SMB_RT_CPU0_P2_ROM_R_SDA")
	)
	(segment
		(start 419.660832 -426.799248)
		(end 419.396164 -426.799248)
		(width 0.10668)
		(layer "B.Cu")
		(net "SMB_RT_CPU0_P2_ROM_R_SDA")
	)
	(segment
		(start 421.26281 -426.516038)
		(end 419.944042 -426.516038)
		(width 0.10668)
		(layer "B.Cu")
		(net "SMB_RT_CPU0_P2_ROM_R_SDA")
	)
	(segment
		(start 419.396164 -426.62475)
		(end 419.06317 -426.291756)
		(width 0.10668)
		(layer "B.Cu")
		(net "SMB_RT_CPU0_P2_ROM_R_SDA")
	)
	(segment
		(start 419.944042 -426.516038)
		(end 419.660832 -426.799248)
		(width 0.10668)
		(layer "B.Cu")
		(net "SMB_RT_CPU0_P2_ROM_R_SDA")
	)
	(segment
		(start 420.839646 -422.897046)
		(end 420.839646 -423.296842)
		(width 0.10668)
		(layer "F.Cu")
		(net "SMB_RT_CPU0_P2_ROM_R_SCL")
	)
	(segment
		(start 420.839646 -423.296842)
		(end 420.658544 -423.477944)
		(width 0.10668)
		(layer "F.Cu")
		(net "SMB_RT_CPU0_P2_ROM_R_SCL")
	)
	(via
		(at 417.917122 -423.600372)
		(size 0.6604)
		(drill 0.3302)
		(layers "F.Cu" "B.Cu")
		(net "SMB_RT_CPU0_P2_ROM_R_SCL")
	)
	(via
		(at 420.839646 -422.897046)
		(size 0.508)
		(drill 0.254)
		(layers "F.Cu" "B.Cu")
		(net "SMB_RT_CPU0_P2_ROM_R_SCL")
	)
	(segment
		(start 419.985698 -427.01591)
		(end 419.407594 -427.594014)
		(width 0.10668)
		(layer "B.Cu")
		(net "SMB_RT_CPU0_P2_ROM_R_SCL")
	)
	(segment
		(start 419.861238 -422.373298)
		(end 419.144196 -422.373298)
		(width 0.10668)
		(layer "B.Cu")
		(net "SMB_RT_CPU0_P2_ROM_R_SCL")
	)
	(segment
		(start 417.616132 -423.901362)
		(end 417.616132 -427.92269)
		(width 0.10668)
		(layer "B.Cu")
		(net "SMB_RT_CPU0_P2_ROM_R_SCL")
	)
	(segment
		(start 417.917122 -423.600372)
		(end 417.616132 -423.901362)
		(width 0.10668)
		(layer "B.Cu")
		(net "SMB_RT_CPU0_P2_ROM_R_SCL")
	)
	(segment
		(start 419.407594 -427.952154)
		(end 419.407594 -427.594014)
		(width 0.10668)
		(layer "B.Cu")
		(net "SMB_RT_CPU0_P2_ROM_R_SCL")
	)
	(segment
		(start 419.144196 -422.373298)
		(end 417.917122 -423.600372)
		(width 0.10668)
		(layer "B.Cu")
		(net "SMB_RT_CPU0_P2_ROM_R_SCL")
	)
	(segment
		(start 420.839646 -422.897046)
		(end 420.384986 -422.897046)
		(width 0.10668)
		(layer "B.Cu")
		(net "SMB_RT_CPU0_P2_ROM_R_SCL")
	)
	(segment
		(start 420.384986 -422.897046)
		(end 419.861238 -422.373298)
		(width 0.10668)
		(layer "B.Cu")
		(net "SMB_RT_CPU0_P2_ROM_R_SCL")
	)
	(segment
		(start 417.616132 -427.92269)
		(end 417.822126 -428.128684)
		(width 0.10668)
		(layer "B.Cu")
		(net "SMB_RT_CPU0_P2_ROM_R_SCL")
	)
	(segment
		(start 419.231064 -428.128684)
		(end 419.407594 -427.952154)
		(width 0.10668)
		(layer "B.Cu")
		(net "SMB_RT_CPU0_P2_ROM_R_SCL")
	)
	(segment
		(start 417.822126 -428.128684)
		(end 419.231064 -428.128684)
		(width 0.10668)
		(layer "B.Cu")
		(net "SMB_RT_CPU0_P2_ROM_R_SCL")
	)
	(segment
		(start 421.26281 -427.01591)
		(end 419.985698 -427.01591)
		(width 0.10668)
		(layer "B.Cu")
		(net "SMB_RT_CPU0_P2_ROM_R_SCL")
	)
	(segment
		(start 401.209764 -398.613122)
		(end 400.814794 -399.008092)
		(width 0.10668)
		(layer "F.Cu")
		(net "SMB_RT_CPU0_P2_ROM_MUX_1D_R_SDA")
	)
	(segment
		(start 400.814794 -399.008092)
		(end 400.721068 -399.008092)
		(width 0.10668)
		(layer "F.Cu")
		(net "SMB_RT_CPU0_P2_ROM_MUX_1D_R_SDA")
	)
	(via
		(at 400.721068 -399.008092)
		(size 0.4064)
		(drill 0.2032)
		(layers "F.Cu" "B.Cu")
		(net "SMB_RT_CPU0_P2_ROM_MUX_1D_R_SDA")
	)
	(via
		(at 420.66972 -421.44188)
		(size 0.508)
		(drill 0.254)
		(layers "F.Cu" "B.Cu")
		(net "SMB_RT_CPU0_P2_ROM_MUX_1D_R_SDA")
	)
	(via
		(at 420.90975 -422.12133)
		(size 0.6604)
		(drill 0.3302)
		(layers "F.Cu" "B.Cu")
		(net "SMB_RT_CPU0_P2_ROM_MUX_1D_R_SDA")
	)
	(segment
		(start 420.66972 -421.8813)
		(end 420.90975 -422.12133)
		(width 0.10668)
		(layer "B.Cu")
		(net "SMB_RT_CPU0_P2_ROM_MUX_1D_R_SDA")
	)
	(segment
		(start 420.90975 -422.12133)
		(end 421.07739 -422.28897)
		(width 0.10668)
		(layer "B.Cu")
		(net "SMB_RT_CPU0_P2_ROM_MUX_1D_R_SDA")
	)
	(segment
		(start 421.07739 -422.28897)
		(end 421.69207 -422.28897)
		(width 0.10668)
		(layer "B.Cu")
		(net "SMB_RT_CPU0_P2_ROM_MUX_1D_R_SDA")
	)
	(segment
		(start 420.66972 -421.44188)
		(end 420.66972 -421.8813)
		(width 0.10668)
		(layer "B.Cu")
		(net "SMB_RT_CPU0_P2_ROM_MUX_1D_R_SDA")
	)
	(segment
		(start 404.964392 -403.94763)
		(end 419.271958 -409.873958)
		(width 0.11684)
		(layer "In6.Cu")
		(net "SMB_RT_CPU0_P2_ROM_MUX_1D_R_SDA")
	)
	(segment
		(start 420.66972 -412.439866)
		(end 420.66972 -421.44188)
		(width 0.11684)
		(layer "In6.Cu")
		(net "SMB_RT_CPU0_P2_ROM_MUX_1D_R_SDA")
	)
	(segment
		(start 419.843712 -410.445712)
		(end 420.66972 -412.439866)
		(width 0.11684)
		(layer "In6.Cu")
		(net "SMB_RT_CPU0_P2_ROM_MUX_1D_R_SDA")
	)
	(segment
		(start 401.51431 -402.786088)
		(end 402.199094 -403.470872)
		(width 0.11684)
		(layer "In6.Cu")
		(net "SMB_RT_CPU0_P2_ROM_MUX_1D_R_SDA")
	)
	(segment
		(start 400.604228 -399.124932)
		(end 400.604228 -399.818098)
		(width 0.11684)
		(layer "In6.Cu")
		(net "SMB_RT_CPU0_P2_ROM_MUX_1D_R_SDA")
	)
	(segment
		(start 419.271958 -409.873958)
		(end 419.843712 -410.445712)
		(width 0.11684)
		(layer "In6.Cu")
		(net "SMB_RT_CPU0_P2_ROM_MUX_1D_R_SDA")
	)
	(segment
		(start 401.51431 -400.72818)
		(end 401.51431 -402.786088)
		(width 0.11684)
		(layer "In6.Cu")
		(net "SMB_RT_CPU0_P2_ROM_MUX_1D_R_SDA")
	)
	(segment
		(start 402.56841 -403.470872)
		(end 404.964392 -403.94763)
		(width 0.11684)
		(layer "In6.Cu")
		(net "SMB_RT_CPU0_P2_ROM_MUX_1D_R_SDA")
	)
	(segment
		(start 402.199094 -403.470872)
		(end 402.56841 -403.470872)
		(width 0.11684)
		(layer "In6.Cu")
		(net "SMB_RT_CPU0_P2_ROM_MUX_1D_R_SDA")
	)
	(segment
		(start 400.721068 -399.008092)
		(end 400.604228 -399.124932)
		(width 0.11684)
		(layer "In6.Cu")
		(net "SMB_RT_CPU0_P2_ROM_MUX_1D_R_SDA")
	)
	(segment
		(start 400.604228 -399.818098)
		(end 401.51431 -400.72818)
		(width 0.11684)
		(layer "In6.Cu")
		(net "SMB_RT_CPU0_P2_ROM_MUX_1D_R_SDA")
	)
	(segment
		(start 400.857212 -398.313148)
		(end 400.721068 -398.449292)
		(width 0.10668)
		(layer "F.Cu")
		(net "SMB_RT_CPU0_P2_ROM_MUX_1D_R_SCL")
	)
	(segment
		(start 401.729448 -398.313148)
		(end 400.857212 -398.313148)
		(width 0.10668)
		(layer "F.Cu")
		(net "SMB_RT_CPU0_P2_ROM_MUX_1D_R_SCL")
	)
	(via
		(at 400.721068 -398.449292)
		(size 0.4064)
		(drill 0.2032)
		(layers "F.Cu" "B.Cu")
		(net "SMB_RT_CPU0_P2_ROM_MUX_1D_R_SCL")
	)
	(via
		(at 419.95852 -421.0939)
		(size 0.6604)
		(drill 0.3302)
		(layers "F.Cu" "B.Cu")
		(net "SMB_RT_CPU0_P2_ROM_MUX_1D_R_SCL")
	)
	(via
		(at 420.09822 -421.80256)
		(size 0.508)
		(drill 0.254)
		(layers "F.Cu" "B.Cu")
		(net "SMB_RT_CPU0_P2_ROM_MUX_1D_R_SCL")
	)
	(segment
		(start 420.701724 -420.534592)
		(end 419.95852 -421.0939)
		(width 0.10668)
		(layer "B.Cu")
		(net "SMB_RT_CPU0_P2_ROM_MUX_1D_R_SCL")
	)
	(segment
		(start 420.09822 -421.80256)
		(end 419.95852 -421.66286)
		(width 0.10668)
		(layer "B.Cu")
		(net "SMB_RT_CPU0_P2_ROM_MUX_1D_R_SCL")
	)
	(segment
		(start 419.95852 -421.66286)
		(end 419.95852 -421.0939)
		(width 0.10668)
		(layer "B.Cu")
		(net "SMB_RT_CPU0_P2_ROM_MUX_1D_R_SCL")
	)
	(segment
		(start 418.71138 -410.105606)
		(end 419.520116 -410.914342)
		(width 0.11684)
		(layer "In6.Cu")
		(net "SMB_RT_CPU0_P2_ROM_MUX_1D_R_SCL")
	)
	(segment
		(start 402.015706 -403.91334)
		(end 402.525484 -403.91334)
		(width 0.11684)
		(layer "In6.Cu")
		(net "SMB_RT_CPU0_P2_ROM_MUX_1D_R_SCL")
	)
	(segment
		(start 400.17192 -398.90446)
		(end 400.17192 -400.011646)
		(width 0.11684)
		(layer "In6.Cu")
		(net "SMB_RT_CPU0_P2_ROM_MUX_1D_R_SCL")
	)
	(segment
		(start 420.09822 -421.30726)
		(end 420.09822 -421.80256)
		(width 0.11684)
		(layer "In6.Cu")
		(net "SMB_RT_CPU0_P2_ROM_MUX_1D_R_SCL")
	)
	(segment
		(start 404.904194 -404.386542)
		(end 418.71138 -410.105606)
		(width 0.11684)
		(layer "In6.Cu")
		(net "SMB_RT_CPU0_P2_ROM_MUX_1D_R_SCL")
	)
	(segment
		(start 400.721068 -398.449292)
		(end 400.627088 -398.449292)
		(width 0.11684)
		(layer "In6.Cu")
		(net "SMB_RT_CPU0_P2_ROM_MUX_1D_R_SCL")
	)
	(segment
		(start 401.071842 -402.969476)
		(end 402.015706 -403.91334)
		(width 0.11684)
		(layer "In6.Cu")
		(net "SMB_RT_CPU0_P2_ROM_MUX_1D_R_SCL")
	)
	(segment
		(start 401.071842 -400.911568)
		(end 401.071842 -402.969476)
		(width 0.11684)
		(layer "In6.Cu")
		(net "SMB_RT_CPU0_P2_ROM_MUX_1D_R_SCL")
	)
	(segment
		(start 419.520116 -410.914342)
		(end 420.24808 -412.671768)
		(width 0.11684)
		(layer "In6.Cu")
		(net "SMB_RT_CPU0_P2_ROM_MUX_1D_R_SCL")
	)
	(segment
		(start 402.525484 -403.91334)
		(end 404.904194 -404.386542)
		(width 0.11684)
		(layer "In6.Cu")
		(net "SMB_RT_CPU0_P2_ROM_MUX_1D_R_SCL")
	)
	(segment
		(start 420.24808 -412.671768)
		(end 420.24808 -421.1574)
		(width 0.11684)
		(layer "In6.Cu")
		(net "SMB_RT_CPU0_P2_ROM_MUX_1D_R_SCL")
	)
	(segment
		(start 400.627088 -398.449292)
		(end 400.17192 -398.90446)
		(width 0.11684)
		(layer "In6.Cu")
		(net "SMB_RT_CPU0_P2_ROM_MUX_1D_R_SCL")
	)
	(segment
		(start 400.17192 -400.011646)
		(end 401.071842 -400.911568)
		(width 0.11684)
		(layer "In6.Cu")
		(net "SMB_RT_CPU0_P2_ROM_MUX_1D_R_SCL")
	)
	(segment
		(start 420.24808 -421.1574)
		(end 420.09822 -421.30726)
		(width 0.11684)
		(layer "In6.Cu")
		(net "SMB_RT_CPU0_P2_ROM_MUX_1D_R_SCL")
	)
	(segment
		(start 419.391084 -424.044364)
		(end 419.391084 -424.634152)
		(width 0.10668)
		(layer "F.Cu")
		(net "SMB_RT_CPU0_P2_ROM_SDA")
	)
	(segment
		(start 419.391084 -424.634152)
		(end 419.379654 -424.645582)
		(width 0.10668)
		(layer "F.Cu")
		(net "SMB_RT_CPU0_P2_ROM_SDA")
	)
	(segment
		(start 419.379654 -424.645582)
		(end 419.379654 -425.685458)
		(width 0.10668)
		(layer "F.Cu")
		(net "SMB_RT_CPU0_P2_ROM_SDA")
	)
	(via
		(at 419.379654 -424.645582)
		(size 0.508)
		(drill 0.254)
		(layers "F.Cu" "B.Cu")
		(net "SMB_RT_CPU0_P2_ROM_SDA")
	)
	(segment
		(start 420.649654 -424.61688)
		(end 420.649654 -425.685458)
		(width 0.10668)
		(layer "F.Cu")
		(net "SMB_RT_CPU0_P2_ROM_SCL")
	)
	(segment
		(start 420.658544 -424.60799)
		(end 420.649654 -424.61688)
		(width 0.10668)
		(layer "F.Cu")
		(net "SMB_RT_CPU0_P2_ROM_SCL")
	)
	(segment
		(start 420.658544 -424.011344)
		(end 420.658544 -424.60799)
		(width 0.10668)
		(layer "F.Cu")
		(net "SMB_RT_CPU0_P2_ROM_SCL")
	)
	(via
		(at 420.649654 -424.61688)
		(size 0.508)
		(drill 0.254)
		(layers "F.Cu" "B.Cu")
		(net "SMB_RT_CPU0_P2_ROM_SCL")
	)
	(segment
		(start 291.243258 -397.25854)
		(end 291.544756 -396.957042)
		(width 0.10668)
		(layer "F.Cu")
		(net "SMB_RT_CPU0_P1_ROM_R_SDA")
	)
	(segment
		(start 291.243258 -397.59001)
		(end 291.243258 -397.25854)
		(width 0.10668)
		(layer "F.Cu")
		(net "SMB_RT_CPU0_P1_ROM_R_SDA")
	)
	(segment
		(start 291.544756 -396.957042)
		(end 291.140134 -396.55242)
		(width 0.10668)
		(layer "F.Cu")
		(net "SMB_RT_CPU0_P1_ROM_R_SDA")
	)
	(segment
		(start 291.259006 -398.34185)
		(end 291.259006 -397.605758)
		(width 0.10668)
		(layer "F.Cu")
		(net "SMB_RT_CPU0_P1_ROM_R_SDA")
	)
	(segment
		(start 291.140134 -396.55242)
		(end 291.140134 -395.871446)
		(width 0.10668)
		(layer "F.Cu")
		(net "SMB_RT_CPU0_P1_ROM_R_SDA")
	)
	(segment
		(start 291.259006 -397.605758)
		(end 291.243258 -397.59001)
		(width 0.10668)
		(layer "F.Cu")
		(net "SMB_RT_CPU0_P1_ROM_R_SDA")
	)
	(via
		(at 291.544756 -396.957042)
		(size 0.508)
		(drill 0.254)
		(layers "F.Cu" "B.Cu")
		(net "SMB_RT_CPU0_P1_ROM_R_SDA")
	)
	(segment
		(start 290.42614 -397.589248)
		(end 290.42614 -398.232122)
		(width 0.10668)
		(layer "F.Cu")
		(net "SMB_RT_CPU0_P1_ROM_R_SCL")
	)
	(segment
		(start 290.42614 -397.14424)
		(end 290.42614 -397.589248)
		(width 0.10668)
		(layer "F.Cu")
		(net "SMB_RT_CPU0_P1_ROM_R_SCL")
	)
	(segment
		(start 290.640262 -396.53845)
		(end 290.230306 -396.948406)
		(width 0.10668)
		(layer "F.Cu")
		(net "SMB_RT_CPU0_P1_ROM_R_SCL")
	)
	(segment
		(start 290.42614 -398.232122)
		(end 290.311586 -398.346676)
		(width 0.10668)
		(layer "F.Cu")
		(net "SMB_RT_CPU0_P1_ROM_R_SCL")
	)
	(segment
		(start 290.230306 -396.948406)
		(end 290.42614 -397.14424)
		(width 0.10668)
		(layer "F.Cu")
		(net "SMB_RT_CPU0_P1_ROM_R_SCL")
	)
	(segment
		(start 290.640262 -395.871446)
		(end 290.640262 -396.53845)
		(width 0.10668)
		(layer "F.Cu")
		(net "SMB_RT_CPU0_P1_ROM_R_SCL")
	)
	(via
		(at 290.230306 -396.948406)
		(size 0.508)
		(drill 0.254)
		(layers "F.Cu" "B.Cu")
		(net "SMB_RT_CPU0_P1_ROM_R_SCL")
	)
	(segment
		(start 331.199236 -388.337044)
		(end 331.199236 -388.149338)
		(width 0.10668)
		(layer "F.Cu")
		(net "SMB_RT_CPU0_P1_ROM_MUX_1D_R_SDA")
	)
	(segment
		(start 333.714598 -399.008092)
		(end 333.620872 -399.008092)
		(width 0.10668)
		(layer "F.Cu")
		(net "SMB_RT_CPU0_P1_ROM_MUX_1D_R_SDA")
	)
	(segment
		(start 334.109568 -398.613122)
		(end 333.714598 -399.008092)
		(width 0.10668)
		(layer "F.Cu")
		(net "SMB_RT_CPU0_P1_ROM_MUX_1D_R_SDA")
	)
	(segment
		(start 330.80706 -388.72922)
		(end 331.199236 -388.337044)
		(width 0.10668)
		(layer "F.Cu")
		(net "SMB_RT_CPU0_P1_ROM_MUX_1D_R_SDA")
	)
	(via
		(at 333.620872 -399.008092)
		(size 0.4064)
		(drill 0.2032)
		(layers "F.Cu" "B.Cu")
		(net "SMB_RT_CPU0_P1_ROM_MUX_1D_R_SDA")
	)
	(via
		(at 330.80706 -388.72922)
		(size 0.508)
		(drill 0.254)
		(layers "F.Cu" "B.Cu")
		(net "SMB_RT_CPU0_P1_ROM_MUX_1D_R_SDA")
	)
	(segment
		(start 330.82484 -388.747)
		(end 332.35392 -388.747)
		(width 0.11684)
		(layer "In2.Cu")
		(net "SMB_RT_CPU0_P1_ROM_MUX_1D_R_SDA")
	)
	(segment
		(start 332.9051 -389.29818)
		(end 332.9051 -390.45388)
		(width 0.11684)
		(layer "In2.Cu")
		(net "SMB_RT_CPU0_P1_ROM_MUX_1D_R_SDA")
	)
	(segment
		(start 330.80706 -388.72922)
		(end 330.82484 -388.747)
		(width 0.11684)
		(layer "In2.Cu")
		(net "SMB_RT_CPU0_P1_ROM_MUX_1D_R_SDA")
	)
	(segment
		(start 332.35392 -388.747)
		(end 332.9051 -389.29818)
		(width 0.11684)
		(layer "In2.Cu")
		(net "SMB_RT_CPU0_P1_ROM_MUX_1D_R_SDA")
	)
	(segment
		(start 332.550262 -399.008092)
		(end 333.620872 -399.008092)
		(width 0.11684)
		(layer "In2.Cu")
		(net "SMB_RT_CPU0_P1_ROM_MUX_1D_R_SDA")
	)
	(segment
		(start 331.532738 -394.862304)
		(end 331.532738 -397.990568)
		(width 0.11684)
		(layer "In2.Cu")
		(net "SMB_RT_CPU0_P1_ROM_MUX_1D_R_SDA")
	)
	(segment
		(start 331.06233 -392.29665)
		(end 331.06233 -394.391896)
		(width 0.11684)
		(layer "In2.Cu")
		(net "SMB_RT_CPU0_P1_ROM_MUX_1D_R_SDA")
	)
	(segment
		(start 332.9051 -390.45388)
		(end 331.06233 -392.29665)
		(width 0.11684)
		(layer "In2.Cu")
		(net "SMB_RT_CPU0_P1_ROM_MUX_1D_R_SDA")
	)
	(segment
		(start 331.06233 -394.391896)
		(end 331.532738 -394.862304)
		(width 0.11684)
		(layer "In2.Cu")
		(net "SMB_RT_CPU0_P1_ROM_MUX_1D_R_SDA")
	)
	(segment
		(start 331.532738 -397.990568)
		(end 332.550262 -399.008092)
		(width 0.11684)
		(layer "In2.Cu")
		(net "SMB_RT_CPU0_P1_ROM_MUX_1D_R_SDA")
	)
	(segment
		(start 334.629252 -398.313148)
		(end 333.757016 -398.313148)
		(width 0.10668)
		(layer "F.Cu")
		(net "SMB_RT_CPU0_P1_ROM_MUX_1D_R_SCL")
	)
	(segment
		(start 332.331314 -387.350254)
		(end 331.199236 -387.350254)
		(width 0.10668)
		(layer "F.Cu")
		(net "SMB_RT_CPU0_P1_ROM_MUX_1D_R_SCL")
	)
	(segment
		(start 333.757016 -398.313148)
		(end 333.620872 -398.449292)
		(width 0.10668)
		(layer "F.Cu")
		(net "SMB_RT_CPU0_P1_ROM_MUX_1D_R_SCL")
	)
	(segment
		(start 332.4606 -387.47954)
		(end 332.331314 -387.350254)
		(width 0.10668)
		(layer "F.Cu")
		(net "SMB_RT_CPU0_P1_ROM_MUX_1D_R_SCL")
	)
	(via
		(at 333.620872 -398.449292)
		(size 0.4064)
		(drill 0.2032)
		(layers "F.Cu" "B.Cu")
		(net "SMB_RT_CPU0_P1_ROM_MUX_1D_R_SCL")
	)
	(via
		(at 332.4606 -387.47954)
		(size 0.508)
		(drill 0.254)
		(layers "F.Cu" "B.Cu")
		(net "SMB_RT_CPU0_P1_ROM_MUX_1D_R_SCL")
	)
	(segment
		(start 333.50708 -390.53262)
		(end 331.688186 -392.351514)
		(width 0.11684)
		(layer "In2.Cu")
		(net "SMB_RT_CPU0_P1_ROM_MUX_1D_R_SCL")
	)
	(segment
		(start 333.50708 -388.52602)
		(end 333.50708 -390.53262)
		(width 0.11684)
		(layer "In2.Cu")
		(net "SMB_RT_CPU0_P1_ROM_MUX_1D_R_SCL")
	)
	(segment
		(start 332.78191 -398.449292)
		(end 333.620872 -398.449292)
		(width 0.11684)
		(layer "In2.Cu")
		(net "SMB_RT_CPU0_P1_ROM_MUX_1D_R_SCL")
	)
	(segment
		(start 331.688186 -394.40866)
		(end 332.091538 -394.812012)
		(width 0.11684)
		(layer "In2.Cu")
		(net "SMB_RT_CPU0_P1_ROM_MUX_1D_R_SCL")
	)
	(segment
		(start 331.688186 -392.351514)
		(end 331.688186 -394.40866)
		(width 0.11684)
		(layer "In2.Cu")
		(net "SMB_RT_CPU0_P1_ROM_MUX_1D_R_SCL")
	)
	(segment
		(start 332.091538 -394.812012)
		(end 332.091538 -397.75892)
		(width 0.11684)
		(layer "In2.Cu")
		(net "SMB_RT_CPU0_P1_ROM_MUX_1D_R_SCL")
	)
	(segment
		(start 332.091538 -397.75892)
		(end 332.78191 -398.449292)
		(width 0.11684)
		(layer "In2.Cu")
		(net "SMB_RT_CPU0_P1_ROM_MUX_1D_R_SCL")
	)
	(segment
		(start 332.4606 -387.47954)
		(end 333.50708 -388.52602)
		(width 0.11684)
		(layer "In2.Cu")
		(net "SMB_RT_CPU0_P1_ROM_MUX_1D_R_SCL")
	)
	(segment
		(start 291.259006 -398.87525)
		(end 291.259006 -399.32737)
		(width 0.10668)
		(layer "F.Cu")
		(net "SMB_RT_CPU0_P1_ROM_SDA")
	)
	(segment
		(start 291.947346 -401.181062)
		(end 292.999668 -401.181062)
		(width 0.10668)
		(layer "F.Cu")
		(net "SMB_RT_CPU0_P1_ROM_SDA")
	)
	(segment
		(start 291.614606 -400.848322)
		(end 291.947346 -401.181062)
		(width 0.10668)
		(layer "F.Cu")
		(net "SMB_RT_CPU0_P1_ROM_SDA")
	)
	(segment
		(start 291.614606 -399.68297)
		(end 291.614606 -400.848322)
		(width 0.10668)
		(layer "F.Cu")
		(net "SMB_RT_CPU0_P1_ROM_SDA")
	)
	(segment
		(start 291.259006 -399.32737)
		(end 291.614606 -399.68297)
		(width 0.10668)
		(layer "F.Cu")
		(net "SMB_RT_CPU0_P1_ROM_SDA")
	)
	(via
		(at 291.614606 -399.68297)
		(size 0.762)
		(drill 0.381)
		(layers "F.Cu" "B.Cu")
		(net "SMB_RT_CPU0_P1_ROM_SDA")
	)
	(segment
		(start 290.878006 -401.102068)
		(end 292.227 -402.451062)
		(width 0.10668)
		(layer "F.Cu")
		(net "SMB_RT_CPU0_P1_ROM_SCL")
	)
	(segment
		(start 292.227 -402.451062)
		(end 292.999668 -402.451062)
		(width 0.10668)
		(layer "F.Cu")
		(net "SMB_RT_CPU0_P1_ROM_SCL")
	)
	(segment
		(start 290.311586 -399.428716)
		(end 290.046664 -399.693638)
		(width 0.10668)
		(layer "F.Cu")
		(net "SMB_RT_CPU0_P1_ROM_SCL")
	)
	(segment
		(start 290.878006 -400.52498)
		(end 290.878006 -401.102068)
		(width 0.10668)
		(layer "F.Cu")
		(net "SMB_RT_CPU0_P1_ROM_SCL")
	)
	(segment
		(start 290.046664 -399.693638)
		(end 290.878006 -400.52498)
		(width 0.10668)
		(layer "F.Cu")
		(net "SMB_RT_CPU0_P1_ROM_SCL")
	)
	(segment
		(start 290.311586 -398.880076)
		(end 290.311586 -399.428716)
		(width 0.10668)
		(layer "F.Cu")
		(net "SMB_RT_CPU0_P1_ROM_SCL")
	)
	(via
		(at 290.046664 -399.693638)
		(size 0.762)
		(drill 0.381)
		(layers "F.Cu" "B.Cu")
		(net "SMB_RT_CPU0_P1_ROM_SCL")
	)
	(segment
		(start 295.576752 -421.907208)
		(end 296.114724 -421.369236)
		(width 0.10668)
		(layer "F.Cu")
		(net "SMB_RT_CPU0_P0_ROM_R_SDA")
	)
	(via
		(at 296.114724 -421.369236)
		(size 0.508)
		(drill 0.254)
		(layers "F.Cu" "B.Cu")
		(net "SMB_RT_CPU0_P0_ROM_R_SDA")
	)
	(segment
		(start 295.6687 -425.1833)
		(end 295.336976 -425.515024)
		(width 0.10668)
		(layer "B.Cu")
		(net "SMB_RT_CPU0_P0_ROM_R_SDA")
	)
	(segment
		(start 293.951914 -422.709086)
		(end 294.259 -422.402)
		(width 0.10668)
		(layer "B.Cu")
		(net "SMB_RT_CPU0_P0_ROM_R_SDA")
	)
	(segment
		(start 294.324024 -425.515024)
		(end 293.951914 -425.142914)
		(width 0.10668)
		(layer "B.Cu")
		(net "SMB_RT_CPU0_P0_ROM_R_SDA")
	)
	(segment
		(start 295.6687 -424.942)
		(end 295.6687 -425.1833)
		(width 0.10668)
		(layer "B.Cu")
		(net "SMB_RT_CPU0_P0_ROM_R_SDA")
	)
	(segment
		(start 295.336976 -425.515024)
		(end 294.324024 -425.515024)
		(width 0.10668)
		(layer "B.Cu")
		(net "SMB_RT_CPU0_P0_ROM_R_SDA")
	)
	(segment
		(start 294.259 -422.402)
		(end 295.08196 -422.402)
		(width 0.10668)
		(layer "B.Cu")
		(net "SMB_RT_CPU0_P0_ROM_R_SDA")
	)
	(segment
		(start 295.940988 -424.942)
		(end 296.038016 -425.039028)
		(width 0.10668)
		(layer "B.Cu")
		(net "SMB_RT_CPU0_P0_ROM_R_SDA")
	)
	(segment
		(start 296.038016 -425.039028)
		(end 297.925236 -425.039028)
		(width 0.10668)
		(layer "B.Cu")
		(net "SMB_RT_CPU0_P0_ROM_R_SDA")
	)
	(segment
		(start 295.08196 -422.402)
		(end 296.114724 -421.369236)
		(width 0.10668)
		(layer "B.Cu")
		(net "SMB_RT_CPU0_P0_ROM_R_SDA")
	)
	(segment
		(start 295.6687 -424.942)
		(end 295.940988 -424.942)
		(width 0.10668)
		(layer "B.Cu")
		(net "SMB_RT_CPU0_P0_ROM_R_SDA")
	)
	(segment
		(start 293.951914 -425.142914)
		(end 293.951914 -422.709086)
		(width 0.10668)
		(layer "B.Cu")
		(net "SMB_RT_CPU0_P0_ROM_R_SDA")
	)
	(segment
		(start 294.560752 -421.907208)
		(end 294.560752 -421.604186)
		(width 0.10668)
		(layer "F.Cu")
		(net "SMB_RT_CPU0_P0_ROM_R_SCL")
	)
	(segment
		(start 294.560752 -421.604186)
		(end 294.219122 -421.262556)
		(width 0.10668)
		(layer "F.Cu")
		(net "SMB_RT_CPU0_P0_ROM_R_SCL")
	)
	(via
		(at 294.219122 -421.262556)
		(size 0.508)
		(drill 0.254)
		(layers "F.Cu" "B.Cu")
		(net "SMB_RT_CPU0_P0_ROM_R_SCL")
	)
	(segment
		(start 295.6687 -426.0977)
		(end 295.467024 -425.896024)
		(width 0.10668)
		(layer "B.Cu")
		(net "SMB_RT_CPU0_P0_ROM_R_SCL")
	)
	(segment
		(start 296.164 -426.339)
		(end 295.6687 -426.339)
		(width 0.10668)
		(layer "B.Cu")
		(net "SMB_RT_CPU0_P0_ROM_R_SCL")
	)
	(segment
		(start 296.9641 -425.5389)
		(end 296.164 -426.339)
		(width 0.10668)
		(layer "B.Cu")
		(net "SMB_RT_CPU0_P0_ROM_R_SCL")
	)
	(segment
		(start 294.070024 -425.896024)
		(end 293.570914 -425.396914)
		(width 0.10668)
		(layer "B.Cu")
		(net "SMB_RT_CPU0_P0_ROM_R_SCL")
	)
	(segment
		(start 293.570914 -422.551098)
		(end 294.219122 -421.90289)
		(width 0.10668)
		(layer "B.Cu")
		(net "SMB_RT_CPU0_P0_ROM_R_SCL")
	)
	(segment
		(start 297.925236 -425.5389)
		(end 296.9641 -425.5389)
		(width 0.10668)
		(layer "B.Cu")
		(net "SMB_RT_CPU0_P0_ROM_R_SCL")
	)
	(segment
		(start 295.467024 -425.896024)
		(end 294.070024 -425.896024)
		(width 0.10668)
		(layer "B.Cu")
		(net "SMB_RT_CPU0_P0_ROM_R_SCL")
	)
	(segment
		(start 294.219122 -421.90289)
		(end 294.219122 -421.262556)
		(width 0.10668)
		(layer "B.Cu")
		(net "SMB_RT_CPU0_P0_ROM_R_SCL")
	)
	(segment
		(start 295.6687 -426.339)
		(end 295.6687 -426.0977)
		(width 0.10668)
		(layer "B.Cu")
		(net "SMB_RT_CPU0_P0_ROM_R_SCL")
	)
	(segment
		(start 293.570914 -425.396914)
		(end 293.570914 -422.551098)
		(width 0.10668)
		(layer "B.Cu")
		(net "SMB_RT_CPU0_P0_ROM_R_SCL")
	)
	(segment
		(start 301.58182 -398.613122)
		(end 301.18685 -399.008092)
		(width 0.10668)
		(layer "F.Cu")
		(net "SMB_RT_CPU0_P0_ROM_MUX_1D_R_SDA")
	)
	(segment
		(start 301.18685 -399.008092)
		(end 301.093124 -399.008092)
		(width 0.10668)
		(layer "F.Cu")
		(net "SMB_RT_CPU0_P0_ROM_MUX_1D_R_SDA")
	)
	(via
		(at 301.093124 -399.008092)
		(size 0.4064)
		(drill 0.2032)
		(layers "F.Cu" "B.Cu")
		(net "SMB_RT_CPU0_P0_ROM_MUX_1D_R_SDA")
	)
	(via
		(at 302.47082 -425.63034)
		(size 0.508)
		(drill 0.254)
		(layers "F.Cu" "B.Cu")
		(net "SMB_RT_CPU0_P0_ROM_MUX_1D_R_SDA")
	)
	(segment
		(start 302.339248 -425.498768)
		(end 301.654972 -425.498768)
		(width 0.10668)
		(layer "B.Cu")
		(net "SMB_RT_CPU0_P0_ROM_MUX_1D_R_SDA")
	)
	(segment
		(start 302.47082 -425.63034)
		(end 302.339248 -425.498768)
		(width 0.10668)
		(layer "B.Cu")
		(net "SMB_RT_CPU0_P0_ROM_MUX_1D_R_SDA")
	)
	(segment
		(start 302.614076 -421.555672)
		(end 302.614076 -412.680658)
		(width 0.11684)
		(layer "In4.Cu")
		(net "SMB_RT_CPU0_P0_ROM_MUX_1D_R_SDA")
	)
	(segment
		(start 302.614076 -412.680658)
		(end 301.341028 -409.607258)
		(width 0.11684)
		(layer "In4.Cu")
		(net "SMB_RT_CPU0_P0_ROM_MUX_1D_R_SDA")
	)
	(segment
		(start 301.341028 -409.607258)
		(end 300.77156 -409.03779)
		(width 0.11684)
		(layer "In4.Cu")
		(net "SMB_RT_CPU0_P0_ROM_MUX_1D_R_SDA")
	)
	(segment
		(start 303.550574 -422.49217)
		(end 302.614076 -421.555672)
		(width 0.11684)
		(layer "In4.Cu")
		(net "SMB_RT_CPU0_P0_ROM_MUX_1D_R_SDA")
	)
	(segment
		(start 300.77156 -409.03779)
		(end 300.77156 -406.748234)
		(width 0.11684)
		(layer "In4.Cu")
		(net "SMB_RT_CPU0_P0_ROM_MUX_1D_R_SDA")
	)
	(segment
		(start 301.64024 -402.125942)
		(end 300.816518 -401.30222)
		(width 0.11684)
		(layer "In4.Cu")
		(net "SMB_RT_CPU0_P0_ROM_MUX_1D_R_SDA")
	)
	(segment
		(start 300.77156 -406.748234)
		(end 301.64024 -405.879554)
		(width 0.11684)
		(layer "In4.Cu")
		(net "SMB_RT_CPU0_P0_ROM_MUX_1D_R_SDA")
	)
	(segment
		(start 300.816518 -399.284698)
		(end 301.093124 -399.008092)
		(width 0.11684)
		(layer "In4.Cu")
		(net "SMB_RT_CPU0_P0_ROM_MUX_1D_R_SDA")
	)
	(segment
		(start 302.47082 -425.550838)
		(end 303.550574 -424.471084)
		(width 0.11684)
		(layer "In4.Cu")
		(net "SMB_RT_CPU0_P0_ROM_MUX_1D_R_SDA")
	)
	(segment
		(start 302.47082 -425.63034)
		(end 302.47082 -425.550838)
		(width 0.11684)
		(layer "In4.Cu")
		(net "SMB_RT_CPU0_P0_ROM_MUX_1D_R_SDA")
	)
	(segment
		(start 303.550574 -424.471084)
		(end 303.550574 -422.49217)
		(width 0.11684)
		(layer "In4.Cu")
		(net "SMB_RT_CPU0_P0_ROM_MUX_1D_R_SDA")
	)
	(segment
		(start 301.64024 -405.879554)
		(end 301.64024 -402.125942)
		(width 0.11684)
		(layer "In4.Cu")
		(net "SMB_RT_CPU0_P0_ROM_MUX_1D_R_SDA")
	)
	(segment
		(start 300.816518 -401.30222)
		(end 300.816518 -399.284698)
		(width 0.11684)
		(layer "In4.Cu")
		(net "SMB_RT_CPU0_P0_ROM_MUX_1D_R_SDA")
	)
	(segment
		(start 301.229268 -398.313148)
		(end 301.093124 -398.449292)
		(width 0.10668)
		(layer "F.Cu")
		(net "SMB_RT_CPU0_P0_ROM_MUX_1D_R_SCL")
	)
	(segment
		(start 302.101504 -398.313148)
		(end 301.229268 -398.313148)
		(width 0.10668)
		(layer "F.Cu")
		(net "SMB_RT_CPU0_P0_ROM_MUX_1D_R_SCL")
	)
	(via
		(at 302.072802 -427.367954)
		(size 0.508)
		(drill 0.254)
		(layers "F.Cu" "B.Cu")
		(net "SMB_RT_CPU0_P0_ROM_MUX_1D_R_SCL")
	)
	(via
		(at 301.093124 -398.449292)
		(size 0.4064)
		(drill 0.2032)
		(layers "F.Cu" "B.Cu")
		(net "SMB_RT_CPU0_P0_ROM_MUX_1D_R_SCL")
	)
	(segment
		(start 302.072802 -427.367954)
		(end 302.072802 -426.753782)
		(width 0.10668)
		(layer "B.Cu")
		(net "SMB_RT_CPU0_P0_ROM_MUX_1D_R_SCL")
	)
	(segment
		(start 301.817532 -426.498512)
		(end 301.644304 -426.498512)
		(width 0.10668)
		(layer "B.Cu")
		(net "SMB_RT_CPU0_P0_ROM_MUX_1D_R_SCL")
	)
	(segment
		(start 302.072802 -426.753782)
		(end 301.817532 -426.498512)
		(width 0.10668)
		(layer "B.Cu")
		(net "SMB_RT_CPU0_P0_ROM_MUX_1D_R_SCL")
	)
	(segment
		(start 301.11065 -410.167328)
		(end 302.055276 -412.44774)
		(width 0.11684)
		(layer "In4.Cu")
		(net "SMB_RT_CPU0_P0_ROM_MUX_1D_R_SCL")
	)
	(segment
		(start 300.861476 -398.449292)
		(end 300.257718 -399.05305)
		(width 0.11684)
		(layer "In4.Cu")
		(net "SMB_RT_CPU0_P0_ROM_MUX_1D_R_SCL")
	)
	(segment
		(start 302.055276 -412.44774)
		(end 302.055276 -420.942516)
		(width 0.11684)
		(layer "In4.Cu")
		(net "SMB_RT_CPU0_P0_ROM_MUX_1D_R_SCL")
	)
	(segment
		(start 301.093124 -398.449292)
		(end 300.861476 -398.449292)
		(width 0.11684)
		(layer "In4.Cu")
		(net "SMB_RT_CPU0_P0_ROM_MUX_1D_R_SCL")
	)
	(segment
		(start 301.08144 -402.35759)
		(end 301.08144 -405.647906)
		(width 0.11684)
		(layer "In4.Cu")
		(net "SMB_RT_CPU0_P0_ROM_MUX_1D_R_SCL")
	)
	(segment
		(start 302.072802 -426.753782)
		(end 302.072802 -427.367954)
		(width 0.11684)
		(layer "In4.Cu")
		(net "SMB_RT_CPU0_P0_ROM_MUX_1D_R_SCL")
	)
	(segment
		(start 300.257718 -401.533868)
		(end 301.08144 -402.35759)
		(width 0.11684)
		(layer "In4.Cu")
		(net "SMB_RT_CPU0_P0_ROM_MUX_1D_R_SCL")
	)
	(segment
		(start 301.64024 -426.32122)
		(end 302.072802 -426.753782)
		(width 0.11684)
		(layer "In4.Cu")
		(net "SMB_RT_CPU0_P0_ROM_MUX_1D_R_SCL")
	)
	(segment
		(start 302.055276 -420.942516)
		(end 301.686722 -421.31107)
		(width 0.11684)
		(layer "In4.Cu")
		(net "SMB_RT_CPU0_P0_ROM_MUX_1D_R_SCL")
	)
	(segment
		(start 301.686722 -423.357802)
		(end 301.64024 -423.404284)
		(width 0.11684)
		(layer "In4.Cu")
		(net "SMB_RT_CPU0_P0_ROM_MUX_1D_R_SCL")
	)
	(segment
		(start 300.21276 -406.516586)
		(end 300.21276 -409.269438)
		(width 0.11684)
		(layer "In4.Cu")
		(net "SMB_RT_CPU0_P0_ROM_MUX_1D_R_SCL")
	)
	(segment
		(start 300.257718 -399.05305)
		(end 300.257718 -401.533868)
		(width 0.11684)
		(layer "In4.Cu")
		(net "SMB_RT_CPU0_P0_ROM_MUX_1D_R_SCL")
	)
	(segment
		(start 300.21276 -409.269438)
		(end 301.11065 -410.167328)
		(width 0.11684)
		(layer "In4.Cu")
		(net "SMB_RT_CPU0_P0_ROM_MUX_1D_R_SCL")
	)
	(segment
		(start 301.686722 -421.31107)
		(end 301.686722 -423.357802)
		(width 0.11684)
		(layer "In4.Cu")
		(net "SMB_RT_CPU0_P0_ROM_MUX_1D_R_SCL")
	)
	(segment
		(start 301.64024 -423.404284)
		(end 301.64024 -426.32122)
		(width 0.11684)
		(layer "In4.Cu")
		(net "SMB_RT_CPU0_P0_ROM_MUX_1D_R_SCL")
	)
	(segment
		(start 301.08144 -405.647906)
		(end 300.21276 -406.516586)
		(width 0.11684)
		(layer "In4.Cu")
		(net "SMB_RT_CPU0_P0_ROM_MUX_1D_R_SCL")
	)
	(segment
		(start 295.576752 -422.440608)
		(end 295.30294 -422.440608)
		(width 0.10668)
		(layer "F.Cu")
		(net "SMB_RT_CPU0_P0_ROM_SDA")
	)
	(segment
		(start 296.950892 -422.210992)
		(end 296.973498 -422.188386)
		(width 0.10668)
		(layer "F.Cu")
		(net "SMB_RT_CPU0_P0_ROM_SDA")
	)
	(segment
		(start 295.30294 -422.440608)
		(end 295.175686 -422.567862)
		(width 0.10668)
		(layer "F.Cu")
		(net "SMB_RT_CPU0_P0_ROM_SDA")
	)
	(segment
		(start 295.369996 -423.234612)
		(end 296.950892 -423.234612)
		(width 0.10668)
		(layer "F.Cu")
		(net "SMB_RT_CPU0_P0_ROM_SDA")
	)
	(segment
		(start 296.950892 -423.234612)
		(end 296.950892 -422.210992)
		(width 0.10668)
		(layer "F.Cu")
		(net "SMB_RT_CPU0_P0_ROM_SDA")
	)
	(segment
		(start 295.175686 -423.040302)
		(end 295.369996 -423.234612)
		(width 0.10668)
		(layer "F.Cu")
		(net "SMB_RT_CPU0_P0_ROM_SDA")
	)
	(segment
		(start 295.175686 -422.567862)
		(end 295.175686 -423.040302)
		(width 0.10668)
		(layer "F.Cu")
		(net "SMB_RT_CPU0_P0_ROM_SDA")
	)
	(via
		(at 296.950892 -423.234612)
		(size 0.508)
		(drill 0.254)
		(layers "F.Cu" "B.Cu")
		(net "SMB_RT_CPU0_P0_ROM_SDA")
	)
	(segment
		(start 294.560752 -423.018458)
		(end 294.560752 -422.440608)
		(width 0.10668)
		(layer "F.Cu")
		(net "SMB_RT_CPU0_P0_ROM_SCL")
	)
	(segment
		(start 295.23817 -423.695876)
		(end 294.560752 -423.018458)
		(width 0.10668)
		(layer "F.Cu")
		(net "SMB_RT_CPU0_P0_ROM_SCL")
	)
	(segment
		(start 297.248326 -423.695876)
		(end 295.23817 -423.695876)
		(width 0.10668)
		(layer "F.Cu")
		(net "SMB_RT_CPU0_P0_ROM_SCL")
	)
	(segment
		(start 298.243498 -422.188386)
		(end 298.243498 -422.700704)
		(width 0.10668)
		(layer "F.Cu")
		(net "SMB_RT_CPU0_P0_ROM_SCL")
	)
	(segment
		(start 298.243498 -422.700704)
		(end 297.248326 -423.695876)
		(width 0.10668)
		(layer "F.Cu")
		(net "SMB_RT_CPU0_P0_ROM_SCL")
	)
	(via
		(at 294.560752 -423.018458)
		(size 0.508)
		(drill 0.254)
		(layers "F.Cu" "B.Cu")
		(net "SMB_RT_CPU0_P0_ROM_SCL")
	)
	(segment
		(start 229.230428 -289.701732)
		(end 229.5906 -290.061904)
		(width 0.1524)
		(layer "F.Cu")
		(net "PWRGD_P1V8_RETIMER_CPU1")
	)
	(segment
		(start 229.5906 -290.061904)
		(end 230.026972 -290.061904)
		(width 0.1524)
		(layer "F.Cu")
		(net "PWRGD_P1V8_RETIMER_CPU1")
	)
	(via
		(at 229.230428 -289.701732)
		(size 0.508)
		(drill 0.254)
		(layers "F.Cu" "B.Cu")
		(net "PWRGD_P1V8_RETIMER_CPU1")
	)
	(via
		(at 227.64115 -289.72129)
		(size 0.6604)
		(drill 0.3302)
		(layers "F.Cu" "B.Cu")
		(net "PWRGD_P1V8_RETIMER_CPU1")
	)
	(segment
		(start 228.525578 -289.466782)
		(end 228.760528 -289.701732)
		(width 0.1524)
		(layer "B.Cu")
		(net "PWRGD_P1V8_RETIMER_CPU1")
	)
	(segment
		(start 227.161344 -290.450016)
		(end 226.766628 -290.844732)
		(width 0.1524)
		(layer "B.Cu")
		(net "PWRGD_P1V8_RETIMER_CPU1")
	)
	(segment
		(start 227.64115 -289.72129)
		(end 227.161344 -290.201096)
		(width 0.1524)
		(layer "B.Cu")
		(net "PWRGD_P1V8_RETIMER_CPU1")
	)
	(segment
		(start 227.161344 -290.201096)
		(end 227.161344 -290.450016)
		(width 0.1524)
		(layer "B.Cu")
		(net "PWRGD_P1V8_RETIMER_CPU1")
	)
	(segment
		(start 228.525578 -289.466782)
		(end 227.895658 -289.466782)
		(width 0.1524)
		(layer "B.Cu")
		(net "PWRGD_P1V8_RETIMER_CPU1")
	)
	(segment
		(start 228.760528 -289.701732)
		(end 229.230428 -289.701732)
		(width 0.1524)
		(layer "B.Cu")
		(net "PWRGD_P1V8_RETIMER_CPU1")
	)
	(segment
		(start 227.895658 -289.466782)
		(end 227.64115 -289.72129)
		(width 0.1524)
		(layer "B.Cu")
		(net "PWRGD_P1V8_RETIMER_CPU1")
	)
	(segment
		(start 19.508724 -406.268428)
		(end 18.45564 -405.215344)
		(width 0.1524)
		(layer "F.Cu")
		(net "PWRGD_P0V9_RETIMER_CPU1_R")
	)
	(segment
		(start 18.25244 -408.582876)
		(end 17.922494 -408.912822)
		(width 0.1524)
		(layer "F.Cu")
		(net "PWRGD_P0V9_RETIMER_CPU1_R")
	)
	(segment
		(start 18.25244 -407.63952)
		(end 18.25244 -408.582876)
		(width 0.1524)
		(layer "F.Cu")
		(net "PWRGD_P0V9_RETIMER_CPU1_R")
	)
	(segment
		(start 19.508724 -406.383236)
		(end 18.38325 -407.50871)
		(width 0.1524)
		(layer "F.Cu")
		(net "PWRGD_P0V9_RETIMER_CPU1_R")
	)
	(segment
		(start 17.922494 -408.912822)
		(end 17.580864 -408.912822)
		(width 0.1524)
		(layer "F.Cu")
		(net "PWRGD_P0V9_RETIMER_CPU1_R")
	)
	(segment
		(start 18.45564 -405.215344)
		(end 18.45564 -404.741634)
		(width 0.1524)
		(layer "F.Cu")
		(net "PWRGD_P0V9_RETIMER_CPU1_R")
	)
	(segment
		(start 18.38325 -407.50871)
		(end 18.25244 -407.63952)
		(width 0.1524)
		(layer "F.Cu")
		(net "PWRGD_P0V9_RETIMER_CPU1_R")
	)
	(segment
		(start 19.508724 -406.268428)
		(end 19.508724 -406.383236)
		(width 0.1524)
		(layer "F.Cu")
		(net "PWRGD_P0V9_RETIMER_CPU1_R")
	)
	(segment
		(start 20.575524 -406.268428)
		(end 19.508724 -406.268428)
		(width 0.1524)
		(layer "F.Cu")
		(net "PWRGD_P0V9_RETIMER_CPU1_R")
	)
	(via
		(at 18.38325 -407.50871)
		(size 0.508)
		(drill 0.254)
		(layers "F.Cu" "B.Cu")
		(net "PWRGD_P0V9_RETIMER_CPU1_R")
	)
	(segment
		(start 18.38325 -407.50871)
		(end 16.985234 -407.50871)
		(width 0.1524)
		(layer "B.Cu")
		(net "PWRGD_P0V9_RETIMER_CPU1_R")
	)
	(segment
		(start 18.45564 -403.941534)
		(end 18.45564 -403.19071)
		(width 0.10668)
		(layer "F.Cu")
		(net "PWRGD_P0V9_RETIMER_CPU1")
	)
	(segment
		(start 176.855882 -138.140948)
		(end 176.855882 -138.81862)
		(width 0.1524)
		(layer "F.Cu")
		(net "PWRGD_P0V9_RETIMER_CPU1")
	)
	(via
		(at 18.45564 -403.19071)
		(size 0.508)
		(drill 0.254)
		(layers "F.Cu" "B.Cu")
		(net "PWRGD_P0V9_RETIMER_CPU1")
	)
	(via
		(at 176.855882 -138.81862)
		(size 0.508)
		(drill 0.254)
		(layers "F.Cu" "B.Cu")
		(net "PWRGD_P0V9_RETIMER_CPU1")
	)
	(via
		(at 73.081642 -139.318746)
		(size 0.508)
		(drill 0.254)
		(layers "F.Cu" "B.Cu")
		(net "PWRGD_P0V9_RETIMER_CPU1")
	)
	(via
		(at 37.889434 -410.656786)
		(size 0.508)
		(drill 0.254)
		(layers "F.Cu" "B.Cu")
		(net "PWRGD_P0V9_RETIMER_CPU1")
	)
	(segment
		(start 19.178524 -406.343612)
		(end 18.45564 -405.620728)
		(width 0.1524)
		(layer "B.Cu")
		(net "PWRGD_P0V9_RETIMER_CPU1")
	)
	(segment
		(start 37.889434 -410.656786)
		(end 37.889434 -409.77693)
		(width 0.1524)
		(layer "B.Cu")
		(net "PWRGD_P0V9_RETIMER_CPU1")
	)
	(segment
		(start 20.555458 -406.343612)
		(end 19.178524 -406.343612)
		(width 0.1524)
		(layer "B.Cu")
		(net "PWRGD_P0V9_RETIMER_CPU1")
	)
	(segment
		(start 37.333428 -409.220924)
		(end 22.33422 -409.220924)
		(width 0.1524)
		(layer "B.Cu")
		(net "PWRGD_P0V9_RETIMER_CPU1")
	)
	(segment
		(start 20.9042 -406.692354)
		(end 20.555458 -406.343612)
		(width 0.1524)
		(layer "B.Cu")
		(net "PWRGD_P0V9_RETIMER_CPU1")
	)
	(segment
		(start 20.9042 -407.790904)
		(end 20.9042 -406.692354)
		(width 0.1524)
		(layer "B.Cu")
		(net "PWRGD_P0V9_RETIMER_CPU1")
	)
	(segment
		(start 37.889434 -409.77693)
		(end 37.333428 -409.220924)
		(width 0.1524)
		(layer "B.Cu")
		(net "PWRGD_P0V9_RETIMER_CPU1")
	)
	(segment
		(start 18.45564 -405.620728)
		(end 18.45564 -403.19071)
		(width 0.1524)
		(layer "B.Cu")
		(net "PWRGD_P0V9_RETIMER_CPU1")
	)
	(segment
		(start 22.33422 -409.220924)
		(end 20.9042 -407.790904)
		(width 0.1524)
		(layer "B.Cu")
		(net "PWRGD_P0V9_RETIMER_CPU1")
	)
	(segment
		(start 176.12868 -138.622278)
		(end 176.325022 -138.81862)
		(width 0.1524)
		(layer "In6.Cu")
		(net "PWRGD_P0V9_RETIMER_CPU1")
	)
	(segment
		(start 171.943268 -138.622278)
		(end 176.12868 -138.622278)
		(width 0.1524)
		(layer "In6.Cu")
		(net "PWRGD_P0V9_RETIMER_CPU1")
	)
	(segment
		(start 165.09873 -135.9154)
		(end 169.23639 -135.9154)
		(width 0.1524)
		(layer "In6.Cu")
		(net "PWRGD_P0V9_RETIMER_CPU1")
	)
	(segment
		(start 78.75016 -128.0414)
		(end 107.716066 -128.0414)
		(width 0.1524)
		(layer "In6.Cu")
		(net "PWRGD_P0V9_RETIMER_CPU1")
	)
	(segment
		(start 73.081642 -133.709918)
		(end 78.75016 -128.0414)
		(width 0.1524)
		(layer "In6.Cu")
		(net "PWRGD_P0V9_RETIMER_CPU1")
	)
	(segment
		(start 119.398542 -133.294882)
		(end 154.961336 -133.294882)
		(width 0.1524)
		(layer "In6.Cu")
		(net "PWRGD_P0V9_RETIMER_CPU1")
	)
	(segment
		(start 118.86311 -133.830314)
		(end 119.398542 -133.294882)
		(width 0.1524)
		(layer "In6.Cu")
		(net "PWRGD_P0V9_RETIMER_CPU1")
	)
	(segment
		(start 169.23639 -135.9154)
		(end 171.943268 -138.622278)
		(width 0.1524)
		(layer "In6.Cu")
		(net "PWRGD_P0V9_RETIMER_CPU1")
	)
	(segment
		(start 73.081642 -139.318746)
		(end 73.081642 -133.709918)
		(width 0.1524)
		(layer "In6.Cu")
		(net "PWRGD_P0V9_RETIMER_CPU1")
	)
	(segment
		(start 116.228368 -132.026406)
		(end 118.032276 -133.830314)
		(width 0.1524)
		(layer "In6.Cu")
		(net "PWRGD_P0V9_RETIMER_CPU1")
	)
	(segment
		(start 158.235396 -136.568942)
		(end 164.445188 -136.568942)
		(width 0.1524)
		(layer "In6.Cu")
		(net "PWRGD_P0V9_RETIMER_CPU1")
	)
	(segment
		(start 176.325022 -138.81862)
		(end 176.855882 -138.81862)
		(width 0.1524)
		(layer "In6.Cu")
		(net "PWRGD_P0V9_RETIMER_CPU1")
	)
	(segment
		(start 164.445188 -136.568942)
		(end 165.09873 -135.9154)
		(width 0.1524)
		(layer "In6.Cu")
		(net "PWRGD_P0V9_RETIMER_CPU1")
	)
	(segment
		(start 154.961336 -133.294882)
		(end 158.235396 -136.568942)
		(width 0.1524)
		(layer "In6.Cu")
		(net "PWRGD_P0V9_RETIMER_CPU1")
	)
	(segment
		(start 111.701072 -132.026406)
		(end 116.228368 -132.026406)
		(width 0.1524)
		(layer "In6.Cu")
		(net "PWRGD_P0V9_RETIMER_CPU1")
	)
	(segment
		(start 118.032276 -133.830314)
		(end 118.86311 -133.830314)
		(width 0.1524)
		(layer "In6.Cu")
		(net "PWRGD_P0V9_RETIMER_CPU1")
	)
	(segment
		(start 107.716066 -128.0414)
		(end 111.701072 -132.026406)
		(width 0.1524)
		(layer "In6.Cu")
		(net "PWRGD_P0V9_RETIMER_CPU1")
	)
	(segment
		(start 31.203646 -139.318746)
		(end 73.081642 -139.318746)
		(width 0.1524)
		(layer "In13.Cu")
		(net "PWRGD_P0V9_RETIMER_CPU1")
	)
	(segment
		(start 37.889434 -410.656786)
		(end 37.889434 -409.889706)
		(width 0.1524)
		(layer "In13.Cu")
		(net "PWRGD_P0V9_RETIMER_CPU1")
	)
	(segment
		(start 17.874742 -344.264742)
		(end 13.258292 -339.648292)
		(width 0.1524)
		(layer "In13.Cu")
		(net "PWRGD_P0V9_RETIMER_CPU1")
	)
	(segment
		(start 40.493188 -391.560812)
		(end 39.400226 -390.46785)
		(width 0.1524)
		(layer "In13.Cu")
		(net "PWRGD_P0V9_RETIMER_CPU1")
	)
	(segment
		(start 23.607268 -349.337884)
		(end 23.607268 -346.395548)
		(width 0.1524)
		(layer "In13.Cu")
		(net "PWRGD_P0V9_RETIMER_CPU1")
	)
	(segment
		(start 27.419554 -371.446552)
		(end 24.708612 -368.73561)
		(width 0.1524)
		(layer "In13.Cu")
		(net "PWRGD_P0V9_RETIMER_CPU1")
	)
	(segment
		(start 20.51812 -367.770918)
		(end 20.51812 -366.356392)
		(width 0.1524)
		(layer "In13.Cu")
		(net "PWRGD_P0V9_RETIMER_CPU1")
	)
	(segment
		(start 7.91845 -186.435492)
		(end 19.61261 -174.741332)
		(width 0.1524)
		(layer "In13.Cu")
		(net "PWRGD_P0V9_RETIMER_CPU1")
	)
	(segment
		(start 13.258292 -339.648292)
		(end 11.863324 -339.648292)
		(width 0.1524)
		(layer "In13.Cu")
		(net "PWRGD_P0V9_RETIMER_CPU1")
	)
	(segment
		(start 40.493188 -393.496292)
		(end 40.493188 -391.560812)
		(width 0.1524)
		(layer "In13.Cu")
		(net "PWRGD_P0V9_RETIMER_CPU1")
	)
	(segment
		(start 30.712918 -379.080268)
		(end 30.712918 -374.439942)
		(width 0.1524)
		(layer "In13.Cu")
		(net "PWRGD_P0V9_RETIMER_CPU1")
	)
	(segment
		(start 19.61261 -174.741332)
		(end 19.61261 -150.909782)
		(width 0.1524)
		(layer "In13.Cu")
		(net "PWRGD_P0V9_RETIMER_CPU1")
	)
	(segment
		(start 37.192458 -409.19273)
		(end 37.192458 -399.06194)
		(width 0.1524)
		(layer "In13.Cu")
		(net "PWRGD_P0V9_RETIMER_CPU1")
	)
	(segment
		(start 7.91845 -335.703418)
		(end 7.91845 -186.435492)
		(width 0.1524)
		(layer "In13.Cu")
		(net "PWRGD_P0V9_RETIMER_CPU1")
	)
	(segment
		(start 38.156896 -395.832584)
		(end 40.493188 -393.496292)
		(width 0.1524)
		(layer "In13.Cu")
		(net "PWRGD_P0V9_RETIMER_CPU1")
	)
	(segment
		(start 37.889434 -409.889706)
		(end 37.192458 -409.19273)
		(width 0.1524)
		(layer "In13.Cu")
		(net "PWRGD_P0V9_RETIMER_CPU1")
	)
	(segment
		(start 24.708612 -368.73561)
		(end 21.482812 -368.73561)
		(width 0.1524)
		(layer "In13.Cu")
		(net "PWRGD_P0V9_RETIMER_CPU1")
	)
	(segment
		(start 39.400226 -390.46785)
		(end 39.400226 -387.767576)
		(width 0.1524)
		(layer "In13.Cu")
		(net "PWRGD_P0V9_RETIMER_CPU1")
	)
	(segment
		(start 28.941268 -371.446552)
		(end 27.419554 -371.446552)
		(width 0.1524)
		(layer "In13.Cu")
		(net "PWRGD_P0V9_RETIMER_CPU1")
	)
	(segment
		(start 21.482812 -368.73561)
		(end 20.51812 -367.770918)
		(width 0.1524)
		(layer "In13.Cu")
		(net "PWRGD_P0V9_RETIMER_CPU1")
	)
	(segment
		(start 21.476462 -344.264742)
		(end 17.874742 -344.264742)
		(width 0.1524)
		(layer "In13.Cu")
		(net "PWRGD_P0V9_RETIMER_CPU1")
	)
	(segment
		(start 11.863324 -339.648292)
		(end 7.91845 -335.703418)
		(width 0.1524)
		(layer "In13.Cu")
		(net "PWRGD_P0V9_RETIMER_CPU1")
	)
	(segment
		(start 20.51812 -366.356392)
		(end 18.685764 -364.524036)
		(width 0.1524)
		(layer "In13.Cu")
		(net "PWRGD_P0V9_RETIMER_CPU1")
	)
	(segment
		(start 18.685764 -364.524036)
		(end 18.685764 -354.259388)
		(width 0.1524)
		(layer "In13.Cu")
		(net "PWRGD_P0V9_RETIMER_CPU1")
	)
	(segment
		(start 29.969968 -373.696992)
		(end 29.969968 -372.475252)
		(width 0.1524)
		(layer "In13.Cu")
		(net "PWRGD_P0V9_RETIMER_CPU1")
	)
	(segment
		(start 19.61261 -150.909782)
		(end 31.203646 -139.318746)
		(width 0.1524)
		(layer "In13.Cu")
		(net "PWRGD_P0V9_RETIMER_CPU1")
	)
	(segment
		(start 37.192458 -399.06194)
		(end 38.156896 -398.097502)
		(width 0.1524)
		(layer "In13.Cu")
		(net "PWRGD_P0V9_RETIMER_CPU1")
	)
	(segment
		(start 38.156896 -398.097502)
		(end 38.156896 -395.832584)
		(width 0.1524)
		(layer "In13.Cu")
		(net "PWRGD_P0V9_RETIMER_CPU1")
	)
	(segment
		(start 30.712918 -374.439942)
		(end 29.969968 -373.696992)
		(width 0.1524)
		(layer "In13.Cu")
		(net "PWRGD_P0V9_RETIMER_CPU1")
	)
	(segment
		(start 18.685764 -354.259388)
		(end 23.607268 -349.337884)
		(width 0.1524)
		(layer "In13.Cu")
		(net "PWRGD_P0V9_RETIMER_CPU1")
	)
	(segment
		(start 29.969968 -372.475252)
		(end 28.941268 -371.446552)
		(width 0.1524)
		(layer "In13.Cu")
		(net "PWRGD_P0V9_RETIMER_CPU1")
	)
	(segment
		(start 39.400226 -387.767576)
		(end 30.712918 -379.080268)
		(width 0.1524)
		(layer "In13.Cu")
		(net "PWRGD_P0V9_RETIMER_CPU1")
	)
	(segment
		(start 23.607268 -346.395548)
		(end 21.476462 -344.264742)
		(width 0.1524)
		(layer "In13.Cu")
		(net "PWRGD_P0V9_RETIMER_CPU1")
	)
	(segment
		(start 439.274458 -428.518574)
		(end 438.257442 -428.518574)
		(width 0.1524)
		(layer "F.Cu")
		(net "PWRGD_P0V9_RETIMER_CPU0_R")
	)
	(segment
		(start 439.276744 -428.52086)
		(end 439.274458 -428.518574)
		(width 0.1524)
		(layer "F.Cu")
		(net "PWRGD_P0V9_RETIMER_CPU0_R")
	)
	(segment
		(start 439.429652 -427.09211)
		(end 439.429652 -427.824138)
		(width 0.1524)
		(layer "F.Cu")
		(net "PWRGD_P0V9_RETIMER_CPU0_R")
	)
	(segment
		(start 439.429652 -427.824138)
		(end 439.276744 -427.977046)
		(width 0.1524)
		(layer "F.Cu")
		(net "PWRGD_P0V9_RETIMER_CPU0_R")
	)
	(segment
		(start 440.375802 -427.09211)
		(end 439.429652 -427.09211)
		(width 0.1524)
		(layer "F.Cu")
		(net "PWRGD_P0V9_RETIMER_CPU0_R")
	)
	(segment
		(start 439.276744 -427.977046)
		(end 439.276744 -428.52086)
		(width 0.1524)
		(layer "F.Cu")
		(net "PWRGD_P0V9_RETIMER_CPU0_R")
	)
	(segment
		(start 441.257944 -425.644818)
		(end 441.58789 -425.314872)
		(width 0.1524)
		(layer "F.Cu")
		(net "PWRGD_P0V9_RETIMER_CPU0_R")
	)
	(segment
		(start 440.629802 -426.83811)
		(end 440.375802 -427.09211)
		(width 0.1524)
		(layer "F.Cu")
		(net "PWRGD_P0V9_RETIMER_CPU0_R")
	)
	(segment
		(start 441.257944 -426.209968)
		(end 441.257944 -425.644818)
		(width 0.1524)
		(layer "F.Cu")
		(net "PWRGD_P0V9_RETIMER_CPU0_R")
	)
	(segment
		(start 441.58789 -425.314872)
		(end 441.92952 -425.314872)
		(width 0.1524)
		(layer "F.Cu")
		(net "PWRGD_P0V9_RETIMER_CPU0_R")
	)
	(segment
		(start 440.629802 -426.83811)
		(end 441.257944 -426.209968)
		(width 0.1524)
		(layer "F.Cu")
		(net "PWRGD_P0V9_RETIMER_CPU0_R")
	)
	(via
		(at 440.629802 -426.83811)
		(size 0.508)
		(drill 0.254)
		(layers "F.Cu" "B.Cu")
		(net "PWRGD_P0V9_RETIMER_CPU0_R")
	)
	(segment
		(start 439.421016 -427.089824)
		(end 440.378088 -427.089824)
		(width 0.1524)
		(layer "B.Cu")
		(net "PWRGD_P0V9_RETIMER_CPU0_R")
	)
	(segment
		(start 440.378088 -427.089824)
		(end 440.629802 -426.83811)
		(width 0.1524)
		(layer "B.Cu")
		(net "PWRGD_P0V9_RETIMER_CPU0_R")
	)
	(segment
		(start 439.892694 -429.32096)
		(end 439.911744 -429.30191)
		(width 0.13462)
		(layer "F.Cu")
		(net "PWRGD_P0V9_RETIMER_CPU0")
	)
	(segment
		(start 439.276744 -429.32096)
		(end 439.892694 -429.32096)
		(width 0.13462)
		(layer "F.Cu")
		(net "PWRGD_P0V9_RETIMER_CPU0")
	)
	(via
		(at 204.556614 -146.826986)
		(size 0.508)
		(drill 0.254)
		(layers "F.Cu" "B.Cu")
		(net "PWRGD_P0V9_RETIMER_CPU0")
	)
	(via
		(at 175.151796 -145.507964)
		(size 0.508)
		(drill 0.254)
		(layers "F.Cu" "B.Cu")
		(net "PWRGD_P0V9_RETIMER_CPU0")
	)
	(via
		(at 216.484962 -85.721952)
		(size 0.508)
		(drill 0.254)
		(layers "F.Cu" "B.Cu")
		(net "PWRGD_P0V9_RETIMER_CPU0")
	)
	(via
		(at 439.911744 -429.30191)
		(size 0.508)
		(drill 0.254)
		(layers "F.Cu" "B.Cu")
		(net "PWRGD_P0V9_RETIMER_CPU0")
	)
	(segment
		(start 175.437292 -132.350002)
		(end 173.947074 -130.859784)
		(width 0.1524)
		(layer "B.Cu")
		(net "PWRGD_P0V9_RETIMER_CPU0")
	)
	(segment
		(start 173.947074 -126.598172)
		(end 174.307246 -126.238)
		(width 0.1524)
		(layer "B.Cu")
		(net "PWRGD_P0V9_RETIMER_CPU0")
	)
	(segment
		(start 174.307246 -126.238)
		(end 174.73295 -126.238)
		(width 0.1524)
		(layer "B.Cu")
		(net "PWRGD_P0V9_RETIMER_CPU0")
	)
	(segment
		(start 173.947074 -130.859784)
		(end 173.947074 -126.598172)
		(width 0.1524)
		(layer "B.Cu")
		(net "PWRGD_P0V9_RETIMER_CPU0")
	)
	(segment
		(start 175.437292 -141.849602)
		(end 175.437292 -132.350002)
		(width 0.1524)
		(layer "B.Cu")
		(net "PWRGD_P0V9_RETIMER_CPU0")
	)
	(segment
		(start 175.151796 -142.135098)
		(end 175.437292 -141.849602)
		(width 0.1524)
		(layer "B.Cu")
		(net "PWRGD_P0V9_RETIMER_CPU0")
	)
	(segment
		(start 175.151796 -145.507964)
		(end 175.151796 -142.135098)
		(width 0.1524)
		(layer "B.Cu")
		(net "PWRGD_P0V9_RETIMER_CPU0")
	)
	(segment
		(start 433.605178 -117.162072)
		(end 457.827126 -141.38402)
		(width 0.1524)
		(layer "In2.Cu")
		(net "PWRGD_P0V9_RETIMER_CPU0")
	)
	(segment
		(start 456.609196 -354.56495)
		(end 456.609196 -368.964464)
		(width 0.1524)
		(layer "In2.Cu")
		(net "PWRGD_P0V9_RETIMER_CPU0")
	)
	(segment
		(start 463.325464 -168.298622)
		(end 466.357716 -171.330874)
		(width 0.1524)
		(layer "In2.Cu")
		(net "PWRGD_P0V9_RETIMER_CPU0")
	)
	(segment
		(start 452.088758 -373.484902)
		(end 442.731906 -373.484902)
		(width 0.1524)
		(layer "In2.Cu")
		(net "PWRGD_P0V9_RETIMER_CPU0")
	)
	(segment
		(start 442.731906 -373.484902)
		(end 440.229752 -375.987056)
		(width 0.1524)
		(layer "In2.Cu")
		(net "PWRGD_P0V9_RETIMER_CPU0")
	)
	(segment
		(start 432.098704 -398.25549)
		(end 432.098704 -408.911298)
		(width 0.1524)
		(layer "In2.Cu")
		(net "PWRGD_P0V9_RETIMER_CPU0")
	)
	(segment
		(start 435.719728 -412.532322)
		(end 435.719728 -427.98746)
		(width 0.1524)
		(layer "In2.Cu")
		(net "PWRGD_P0V9_RETIMER_CPU0")
	)
	(segment
		(start 460.799688 -168.298622)
		(end 463.325464 -168.298622)
		(width 0.1524)
		(layer "In2.Cu")
		(net "PWRGD_P0V9_RETIMER_CPU0")
	)
	(segment
		(start 437.034178 -429.30191)
		(end 439.911744 -429.30191)
		(width 0.1524)
		(layer "In2.Cu")
		(net "PWRGD_P0V9_RETIMER_CPU0")
	)
	(segment
		(start 440.229752 -375.987056)
		(end 440.229752 -387.56844)
		(width 0.1524)
		(layer "In2.Cu")
		(net "PWRGD_P0V9_RETIMER_CPU0")
	)
	(segment
		(start 455.423778 -344.437716)
		(end 455.423778 -353.379532)
		(width 0.1524)
		(layer "In2.Cu")
		(net "PWRGD_P0V9_RETIMER_CPU0")
	)
	(segment
		(start 455.555604 -163.054538)
		(end 460.799688 -168.298622)
		(width 0.1524)
		(layer "In2.Cu")
		(net "PWRGD_P0V9_RETIMER_CPU0")
	)
	(segment
		(start 457.827126 -141.38402)
		(end 457.827126 -150.888954)
		(width 0.1524)
		(layer "In2.Cu")
		(net "PWRGD_P0V9_RETIMER_CPU0")
	)
	(segment
		(start 373.454422 -119.877078)
		(end 376.514868 -116.816632)
		(width 0.1524)
		(layer "In2.Cu")
		(net "PWRGD_P0V9_RETIMER_CPU0")
	)
	(segment
		(start 329.36688 -119.877078)
		(end 373.454422 -119.877078)
		(width 0.1524)
		(layer "In2.Cu")
		(net "PWRGD_P0V9_RETIMER_CPU0")
	)
	(segment
		(start 456.609196 -368.964464)
		(end 452.088758 -373.484902)
		(width 0.1524)
		(layer "In2.Cu")
		(net "PWRGD_P0V9_RETIMER_CPU0")
	)
	(segment
		(start 265.836908 -80.996282)
		(end 290.711636 -105.87101)
		(width 0.1524)
		(layer "In2.Cu")
		(net "PWRGD_P0V9_RETIMER_CPU0")
	)
	(segment
		(start 246.114062 -78.19009)
		(end 264.5791 -78.19009)
		(width 0.1524)
		(layer "In2.Cu")
		(net "PWRGD_P0V9_RETIMER_CPU0")
	)
	(segment
		(start 382.623568 -116.816632)
		(end 382.969008 -117.162072)
		(width 0.1524)
		(layer "In2.Cu")
		(net "PWRGD_P0V9_RETIMER_CPU0")
	)
	(segment
		(start 290.711636 -105.87101)
		(end 309.739792 -105.87101)
		(width 0.1524)
		(layer "In2.Cu")
		(net "PWRGD_P0V9_RETIMER_CPU0")
	)
	(segment
		(start 466.357716 -333.503778)
		(end 455.423778 -344.437716)
		(width 0.1524)
		(layer "In2.Cu")
		(net "PWRGD_P0V9_RETIMER_CPU0")
	)
	(segment
		(start 455.555604 -153.160476)
		(end 455.555604 -163.054538)
		(width 0.1524)
		(layer "In2.Cu")
		(net "PWRGD_P0V9_RETIMER_CPU0")
	)
	(segment
		(start 244.250464 -80.053688)
		(end 246.114062 -78.19009)
		(width 0.1524)
		(layer "In2.Cu")
		(net "PWRGD_P0V9_RETIMER_CPU0")
	)
	(segment
		(start 309.739792 -105.87101)
		(end 311.868566 -107.999784)
		(width 0.1524)
		(layer "In2.Cu")
		(net "PWRGD_P0V9_RETIMER_CPU0")
	)
	(segment
		(start 435.814216 -393.827)
		(end 432.603656 -397.03756)
		(width 0.1524)
		(layer "In2.Cu")
		(net "PWRGD_P0V9_RETIMER_CPU0")
	)
	(segment
		(start 432.603656 -397.03756)
		(end 432.098704 -398.25549)
		(width 0.1524)
		(layer "In2.Cu")
		(net "PWRGD_P0V9_RETIMER_CPU0")
	)
	(segment
		(start 265.836908 -79.447898)
		(end 265.836908 -80.996282)
		(width 0.1524)
		(layer "In2.Cu")
		(net "PWRGD_P0V9_RETIMER_CPU0")
	)
	(segment
		(start 219.04071 -85.721952)
		(end 221.18193 -87.863172)
		(width 0.1524)
		(layer "In2.Cu")
		(net "PWRGD_P0V9_RETIMER_CPU0")
	)
	(segment
		(start 440.229752 -387.56844)
		(end 435.814216 -391.983976)
		(width 0.1524)
		(layer "In2.Cu")
		(net "PWRGD_P0V9_RETIMER_CPU0")
	)
	(segment
		(start 466.357716 -171.330874)
		(end 466.357716 -333.503778)
		(width 0.1524)
		(layer "In2.Cu")
		(net "PWRGD_P0V9_RETIMER_CPU0")
	)
	(segment
		(start 244.250464 -83.058)
		(end 244.250464 -80.053688)
		(width 0.1524)
		(layer "In2.Cu")
		(net "PWRGD_P0V9_RETIMER_CPU0")
	)
	(segment
		(start 317.489586 -107.999784)
		(end 329.36688 -119.877078)
		(width 0.1524)
		(layer "In2.Cu")
		(net "PWRGD_P0V9_RETIMER_CPU0")
	)
	(segment
		(start 311.868566 -107.999784)
		(end 317.489586 -107.999784)
		(width 0.1524)
		(layer "In2.Cu")
		(net "PWRGD_P0V9_RETIMER_CPU0")
	)
	(segment
		(start 376.514868 -116.816632)
		(end 382.623568 -116.816632)
		(width 0.1524)
		(layer "In2.Cu")
		(net "PWRGD_P0V9_RETIMER_CPU0")
	)
	(segment
		(start 435.719728 -427.98746)
		(end 437.034178 -429.30191)
		(width 0.1524)
		(layer "In2.Cu")
		(net "PWRGD_P0V9_RETIMER_CPU0")
	)
	(segment
		(start 455.423778 -353.379532)
		(end 456.609196 -354.56495)
		(width 0.1524)
		(layer "In2.Cu")
		(net "PWRGD_P0V9_RETIMER_CPU0")
	)
	(segment
		(start 382.969008 -117.162072)
		(end 433.605178 -117.162072)
		(width 0.1524)
		(layer "In2.Cu")
		(net "PWRGD_P0V9_RETIMER_CPU0")
	)
	(segment
		(start 435.814216 -391.983976)
		(end 435.814216 -393.827)
		(width 0.1524)
		(layer "In2.Cu")
		(net "PWRGD_P0V9_RETIMER_CPU0")
	)
	(segment
		(start 264.5791 -78.19009)
		(end 265.836908 -79.447898)
		(width 0.1524)
		(layer "In2.Cu")
		(net "PWRGD_P0V9_RETIMER_CPU0")
	)
	(segment
		(start 221.18193 -87.863172)
		(end 239.445292 -87.863172)
		(width 0.1524)
		(layer "In2.Cu")
		(net "PWRGD_P0V9_RETIMER_CPU0")
	)
	(segment
		(start 239.445292 -87.863172)
		(end 244.250464 -83.058)
		(width 0.1524)
		(layer "In2.Cu")
		(net "PWRGD_P0V9_RETIMER_CPU0")
	)
	(segment
		(start 216.484962 -85.721952)
		(end 219.04071 -85.721952)
		(width 0.1524)
		(layer "In2.Cu")
		(net "PWRGD_P0V9_RETIMER_CPU0")
	)
	(segment
		(start 432.098704 -408.911298)
		(end 435.719728 -412.532322)
		(width 0.1524)
		(layer "In2.Cu")
		(net "PWRGD_P0V9_RETIMER_CPU0")
	)
	(segment
		(start 457.827126 -150.888954)
		(end 455.555604 -153.160476)
		(width 0.1524)
		(layer "In2.Cu")
		(net "PWRGD_P0V9_RETIMER_CPU0")
	)
	(segment
		(start 220.238828 -126.788418)
		(end 217.246962 -129.780284)
		(width 0.1524)
		(layer "In11.Cu")
		(net "PWRGD_P0V9_RETIMER_CPU0")
	)
	(segment
		(start 220.570044 -105.470706)
		(end 220.238828 -105.801922)
		(width 0.1524)
		(layer "In11.Cu")
		(net "PWRGD_P0V9_RETIMER_CPU0")
	)
	(segment
		(start 209.483706 -132.178552)
		(end 209.483706 -135.628634)
		(width 0.1524)
		(layer "In11.Cu")
		(net "PWRGD_P0V9_RETIMER_CPU0")
	)
	(segment
		(start 204.556614 -140.555726)
		(end 204.556614 -146.826986)
		(width 0.1524)
		(layer "In11.Cu")
		(net "PWRGD_P0V9_RETIMER_CPU0")
	)
	(segment
		(start 216.9541 -87.697818)
		(end 220.570044 -91.313762)
		(width 0.1524)
		(layer "In11.Cu")
		(net "PWRGD_P0V9_RETIMER_CPU0")
	)
	(segment
		(start 216.484962 -85.721952)
		(end 216.9541 -86.19109)
		(width 0.1524)
		(layer "In11.Cu")
		(net "PWRGD_P0V9_RETIMER_CPU0")
	)
	(segment
		(start 217.246962 -129.780284)
		(end 210.715606 -129.780284)
		(width 0.1524)
		(layer "In11.Cu")
		(net "PWRGD_P0V9_RETIMER_CPU0")
	)
	(segment
		(start 209.965544 -130.530346)
		(end 209.965544 -131.696714)
		(width 0.1524)
		(layer "In11.Cu")
		(net "PWRGD_P0V9_RETIMER_CPU0")
	)
	(segment
		(start 210.715606 -129.780284)
		(end 209.965544 -130.530346)
		(width 0.1524)
		(layer "In11.Cu")
		(net "PWRGD_P0V9_RETIMER_CPU0")
	)
	(segment
		(start 220.238828 -105.801922)
		(end 220.238828 -126.788418)
		(width 0.1524)
		(layer "In11.Cu")
		(net "PWRGD_P0V9_RETIMER_CPU0")
	)
	(segment
		(start 209.483706 -135.628634)
		(end 204.556614 -140.555726)
		(width 0.1524)
		(layer "In11.Cu")
		(net "PWRGD_P0V9_RETIMER_CPU0")
	)
	(segment
		(start 220.570044 -91.313762)
		(end 220.570044 -105.470706)
		(width 0.1524)
		(layer "In11.Cu")
		(net "PWRGD_P0V9_RETIMER_CPU0")
	)
	(segment
		(start 216.9541 -86.19109)
		(end 216.9541 -87.697818)
		(width 0.1524)
		(layer "In11.Cu")
		(net "PWRGD_P0V9_RETIMER_CPU0")
	)
	(segment
		(start 209.965544 -131.696714)
		(end 209.483706 -132.178552)
		(width 0.1524)
		(layer "In11.Cu")
		(net "PWRGD_P0V9_RETIMER_CPU0")
	)
	(segment
		(start 196.180456 -145.178018)
		(end 191.08166 -145.178018)
		(width 0.1524)
		(layer "In13.Cu")
		(net "PWRGD_P0V9_RETIMER_CPU0")
	)
	(segment
		(start 197.829424 -146.826986)
		(end 196.180456 -145.178018)
		(width 0.1524)
		(layer "In13.Cu")
		(net "PWRGD_P0V9_RETIMER_CPU0")
	)
	(segment
		(start 191.08166 -145.178018)
		(end 190.751714 -145.507964)
		(width 0.1524)
		(layer "In13.Cu")
		(net "PWRGD_P0V9_RETIMER_CPU0")
	)
	(segment
		(start 190.751714 -145.507964)
		(end 175.151796 -145.507964)
		(width 0.1524)
		(layer "In13.Cu")
		(net "PWRGD_P0V9_RETIMER_CPU0")
	)
	(segment
		(start 204.556614 -146.826986)
		(end 197.829424 -146.826986)
		(width 0.1524)
		(layer "In13.Cu")
		(net "PWRGD_P0V9_RETIMER_CPU0")
	)
	(segment
		(start 197.84695 -93.345)
		(end 195.199 -93.345)
		(width 0.10668)
		(layer "F.Cu")
		(net "PWRGD_CHGL_CPU1_R2")
	)
	(segment
		(start 192.238376 -92.202)
		(end 191.74587 -92.202)
		(width 0.10668)
		(layer "F.Cu")
		(net "PWRGD_CHGL_CPU1_R2")
	)
	(segment
		(start 191.74587 -92.202)
		(end 191.243204 -91.699334)
		(width 0.10668)
		(layer "F.Cu")
		(net "PWRGD_CHGL_CPU1_R2")
	)
	(segment
		(start 192.619376 -91.821)
		(end 192.238376 -92.202)
		(width 0.10668)
		(layer "F.Cu")
		(net "PWRGD_CHGL_CPU1_R2")
	)
	(segment
		(start 189.12205 -110.652814)
		(end 189.51194 -110.262924)
		(width 0.10668)
		(layer "F.Cu")
		(net "PWRGD_CHGL_CPU1_R2")
	)
	(segment
		(start 193.675 -91.821)
		(end 192.619376 -91.821)
		(width 0.10668)
		(layer "F.Cu")
		(net "PWRGD_CHGL_CPU1_R2")
	)
	(segment
		(start 195.199 -93.345)
		(end 193.675 -91.821)
		(width 0.10668)
		(layer "F.Cu")
		(net "PWRGD_CHGL_CPU1_R2")
	)
	(via
		(at 189.51194 -110.262924)
		(size 0.4572)
		(drill 0.254)
		(layers "F.Cu" "B.Cu")
		(net "PWRGD_CHGL_CPU1_R2")
	)
	(via
		(at 191.243204 -91.699334)
		(size 0.508)
		(drill 0.254)
		(layers "F.Cu" "B.Cu")
		(net "PWRGD_CHGL_CPU1_R2")
	)
	(segment
		(start 190.524892 -104.41686)
		(end 190.524892 -100.25888)
		(width 0.11684)
		(layer "In4.Cu")
		(net "PWRGD_CHGL_CPU1_R2")
	)
	(segment
		(start 190.524892 -100.25888)
		(end 190.344806 -100.078794)
		(width 0.11684)
		(layer "In4.Cu")
		(net "PWRGD_CHGL_CPU1_R2")
	)
	(segment
		(start 189.107572 -110.021878)
		(end 189.107572 -105.83418)
		(width 0.11684)
		(layer "In4.Cu")
		(net "PWRGD_CHGL_CPU1_R2")
	)
	(segment
		(start 190.344806 -100.078794)
		(end 190.344806 -92.597732)
		(width 0.11684)
		(layer "In4.Cu")
		(net "PWRGD_CHGL_CPU1_R2")
	)
	(segment
		(start 189.51194 -110.262924)
		(end 189.348618 -110.262924)
		(width 0.11684)
		(layer "In4.Cu")
		(net "PWRGD_CHGL_CPU1_R2")
	)
	(segment
		(start 189.107572 -105.83418)
		(end 190.524892 -104.41686)
		(width 0.11684)
		(layer "In4.Cu")
		(net "PWRGD_CHGL_CPU1_R2")
	)
	(segment
		(start 189.348618 -110.262924)
		(end 189.107572 -110.021878)
		(width 0.11684)
		(layer "In4.Cu")
		(net "PWRGD_CHGL_CPU1_R2")
	)
	(segment
		(start 190.344806 -92.597732)
		(end 191.243204 -91.699334)
		(width 0.11684)
		(layer "In4.Cu")
		(net "PWRGD_CHGL_CPU1_R2")
	)
	(segment
		(start 198.64705 -93.345)
		(end 198.64705 -94.234)
		(width 0.10668)
		(layer "F.Cu")
		(net "PWRGD_CHGL_CPU1_R1")
	)
	(segment
		(start 198.64705 -93.345)
		(end 199.263 -93.345)
		(width 0.10668)
		(layer "F.Cu")
		(net "PWRGD_CHGL_CPU1_R1")
	)
	(segment
		(start 198.64705 -92.456)
		(end 198.64705 -93.345)
		(width 0.10668)
		(layer "F.Cu")
		(net "PWRGD_CHGL_CPU1_R1")
	)
	(segment
		(start 200.476104 -92.964)
		(end 199.644 -92.964)
		(width 0.10668)
		(layer "F.Cu")
		(net "PWRGD_CHGL_CPU1_R1")
	)
	(segment
		(start 199.644 -92.964)
		(end 199.263 -93.345)
		(width 0.10668)
		(layer "F.Cu")
		(net "PWRGD_CHGL_CPU1_R1")
	)
	(via
		(at 199.263 -93.345)
		(size 0.508)
		(drill 0.254)
		(layers "F.Cu" "B.Cu")
		(net "PWRGD_CHGL_CPU1_R1")
	)
	(segment
		(start 195.620386 -104.205278)
		(end 195.799964 -104.384856)
		(width 0.10668)
		(layer "F.Cu")
		(net "PWRGD_CHGL_CPU0_R2")
	)
	(segment
		(start 200.51395 -102.362)
		(end 199.904604 -102.362)
		(width 0.10668)
		(layer "F.Cu")
		(net "PWRGD_CHGL_CPU0_R2")
	)
	(segment
		(start 197.370954 -104.384856)
		(end 197.933564 -103.822246)
		(width 0.10668)
		(layer "F.Cu")
		(net "PWRGD_CHGL_CPU0_R2")
	)
	(segment
		(start 199.904604 -102.362)
		(end 199.789034 -102.47757)
		(width 0.10668)
		(layer "F.Cu")
		(net "PWRGD_CHGL_CPU0_R2")
	)
	(segment
		(start 197.933564 -103.56723)
		(end 198.65594 -102.844854)
		(width 0.10668)
		(layer "F.Cu")
		(net "PWRGD_CHGL_CPU0_R2")
	)
	(segment
		(start 197.933564 -103.822246)
		(end 197.933564 -103.56723)
		(width 0.10668)
		(layer "F.Cu")
		(net "PWRGD_CHGL_CPU0_R2")
	)
	(segment
		(start 195.799964 -104.384856)
		(end 197.370954 -104.384856)
		(width 0.10668)
		(layer "F.Cu")
		(net "PWRGD_CHGL_CPU0_R2")
	)
	(segment
		(start 199.42175 -102.844854)
		(end 199.789034 -102.47757)
		(width 0.10668)
		(layer "F.Cu")
		(net "PWRGD_CHGL_CPU0_R2")
	)
	(segment
		(start 192.322196 -106.652822)
		(end 192.712086 -106.262932)
		(width 0.10668)
		(layer "F.Cu")
		(net "PWRGD_CHGL_CPU0_R2")
	)
	(segment
		(start 198.65594 -102.844854)
		(end 199.42175 -102.844854)
		(width 0.10668)
		(layer "F.Cu")
		(net "PWRGD_CHGL_CPU0_R2")
	)
	(via
		(at 192.712086 -106.262932)
		(size 0.4572)
		(drill 0.254)
		(layers "F.Cu" "B.Cu")
		(net "PWRGD_CHGL_CPU0_R2")
	)
	(via
		(at 199.789034 -102.47757)
		(size 0.508)
		(drill 0.254)
		(layers "F.Cu" "B.Cu")
		(net "PWRGD_CHGL_CPU0_R2")
	)
	(via
		(at 195.620386 -104.205278)
		(size 0.508)
		(drill 0.254)
		(layers "F.Cu" "B.Cu")
		(net "PWRGD_CHGL_CPU0_R2")
	)
	(segment
		(start 195.620386 -104.205278)
		(end 195.490084 -104.33558)
		(width 0.11684)
		(layer "In2.Cu")
		(net "PWRGD_CHGL_CPU0_R2")
	)
	(segment
		(start 194.530726 -104.33558)
		(end 192.712086 -106.15422)
		(width 0.11684)
		(layer "In2.Cu")
		(net "PWRGD_CHGL_CPU0_R2")
	)
	(segment
		(start 195.490084 -104.33558)
		(end 194.530726 -104.33558)
		(width 0.11684)
		(layer "In2.Cu")
		(net "PWRGD_CHGL_CPU0_R2")
	)
	(segment
		(start 192.712086 -106.15422)
		(end 192.712086 -106.262932)
		(width 0.11684)
		(layer "In2.Cu")
		(net "PWRGD_CHGL_CPU0_R2")
	)
	(segment
		(start 203.60005 -99.695)
		(end 204.57795 -99.695)
		(width 0.10668)
		(layer "F.Cu")
		(net "PWRGD_CHGL_CPU0_R1")
	)
	(segment
		(start 203.955904 -101.473)
		(end 204.57795 -100.850954)
		(width 0.10668)
		(layer "F.Cu")
		(net "PWRGD_CHGL_CPU0_R1")
	)
	(segment
		(start 204.57795 -99.695)
		(end 204.57795 -100.457508)
		(width 0.10668)
		(layer "F.Cu")
		(net "PWRGD_CHGL_CPU0_R1")
	)
	(segment
		(start 202.20305 -101.473)
		(end 203.651104 -101.473)
		(width 0.10668)
		(layer "F.Cu")
		(net "PWRGD_CHGL_CPU0_R1")
	)
	(segment
		(start 203.651104 -101.473)
		(end 203.955904 -101.473)
		(width 0.10668)
		(layer "F.Cu")
		(net "PWRGD_CHGL_CPU0_R1")
	)
	(segment
		(start 201.31405 -102.362)
		(end 202.20305 -101.473)
		(width 0.10668)
		(layer "F.Cu")
		(net "PWRGD_CHGL_CPU0_R1")
	)
	(segment
		(start 204.57795 -100.850954)
		(end 204.57795 -100.457508)
		(width 0.10668)
		(layer "F.Cu")
		(net "PWRGD_CHGL_CPU0_R1")
	)
	(via
		(at 204.57795 -100.457508)
		(size 0.508)
		(drill 0.254)
		(layers "F.Cu" "B.Cu")
		(net "PWRGD_CHGL_CPU0_R1")
	)
	(segment
		(start 188.322204 -110.652814)
		(end 188.712094 -110.262924)
		(width 0.10668)
		(layer "F.Cu")
		(net "PWRGD_CHAF_CPU1_R2")
	)
	(segment
		(start 151.65705 -125.349)
		(end 152.019 -124.98705)
		(width 0.10668)
		(layer "F.Cu")
		(net "PWRGD_CHAF_CPU1_R2")
	)
	(segment
		(start 152.019 -124.98705)
		(end 152.019 -123.063)
		(width 0.10668)
		(layer "F.Cu")
		(net "PWRGD_CHAF_CPU1_R2")
	)
	(segment
		(start 152.019 -123.063)
		(end 151.765 -122.809)
		(width 0.10668)
		(layer "F.Cu")
		(net "PWRGD_CHAF_CPU1_R2")
	)
	(via
		(at 188.712094 -110.262924)
		(size 0.4572)
		(drill 0.254)
		(layers "F.Cu" "B.Cu")
		(net "PWRGD_CHAF_CPU1_R2")
	)
	(via
		(at 151.765 -122.809)
		(size 0.508)
		(drill 0.254)
		(layers "F.Cu" "B.Cu")
		(net "PWRGD_CHAF_CPU1_R2")
	)
	(via
		(at 168.817036 -114.287808)
		(size 0.4572)
		(drill 0.254)
		(layers "F.Cu" "B.Cu")
		(net "PWRGD_CHAF_CPU1_R2")
	)
	(segment
		(start 175.61433 -107.513628)
		(end 177.138076 -109.037374)
		(width 0.11684)
		(layer "In2.Cu")
		(net "PWRGD_CHAF_CPU1_R2")
	)
	(segment
		(start 167.324786 -112.01527)
		(end 167.52189 -111.818166)
		(width 0.11684)
		(layer "In2.Cu")
		(net "PWRGD_CHAF_CPU1_R2")
	)
	(segment
		(start 185.85434 -110.914688)
		(end 185.85434 -109.33684)
		(width 0.11684)
		(layer "In2.Cu")
		(net "PWRGD_CHAF_CPU1_R2")
	)
	(segment
		(start 167.371014 -109.088682)
		(end 168.946068 -107.513628)
		(width 0.11684)
		(layer "In2.Cu")
		(net "PWRGD_CHAF_CPU1_R2")
	)
	(segment
		(start 179.52847 -110.866936)
		(end 179.52847 -111.322612)
		(width 0.11684)
		(layer "In2.Cu")
		(net "PWRGD_CHAF_CPU1_R2")
	)
	(segment
		(start 185.593736 -111.814356)
		(end 185.593736 -111.175292)
		(width 0.11684)
		(layer "In2.Cu")
		(net "PWRGD_CHAF_CPU1_R2")
	)
	(segment
		(start 185.593736 -111.175292)
		(end 185.85434 -110.914688)
		(width 0.11684)
		(layer "In2.Cu")
		(net "PWRGD_CHAF_CPU1_R2")
	)
	(segment
		(start 188.312044 -109.292644)
		(end 188.312044 -109.862874)
		(width 0.11684)
		(layer "In2.Cu")
		(net "PWRGD_CHAF_CPU1_R2")
	)
	(segment
		(start 177.921158 -110.65637)
		(end 179.317904 -110.65637)
		(width 0.11684)
		(layer "In2.Cu")
		(net "PWRGD_CHAF_CPU1_R2")
	)
	(segment
		(start 167.684196 -113.638076)
		(end 167.324786 -113.278666)
		(width 0.11684)
		(layer "In2.Cu")
		(net "PWRGD_CHAF_CPU1_R2")
	)
	(segment
		(start 185.85434 -109.33684)
		(end 186.1185 -109.07268)
		(width 0.11684)
		(layer "In2.Cu")
		(net "PWRGD_CHAF_CPU1_R2")
	)
	(segment
		(start 168.266872 -113.638076)
		(end 167.684196 -113.638076)
		(width 0.11684)
		(layer "In2.Cu")
		(net "PWRGD_CHAF_CPU1_R2")
	)
	(segment
		(start 177.138076 -109.873288)
		(end 177.921158 -110.65637)
		(width 0.11684)
		(layer "In2.Cu")
		(net "PWRGD_CHAF_CPU1_R2")
	)
	(segment
		(start 188.09208 -109.07268)
		(end 188.312044 -109.292644)
		(width 0.11684)
		(layer "In2.Cu")
		(net "PWRGD_CHAF_CPU1_R2")
	)
	(segment
		(start 167.324786 -113.278666)
		(end 167.324786 -112.01527)
		(width 0.11684)
		(layer "In2.Cu")
		(net "PWRGD_CHAF_CPU1_R2")
	)
	(segment
		(start 177.138076 -109.037374)
		(end 177.138076 -109.873288)
		(width 0.11684)
		(layer "In2.Cu")
		(net "PWRGD_CHAF_CPU1_R2")
	)
	(segment
		(start 167.52189 -111.818166)
		(end 167.52189 -110.668308)
		(width 0.11684)
		(layer "In2.Cu")
		(net "PWRGD_CHAF_CPU1_R2")
	)
	(segment
		(start 180.571394 -112.254792)
		(end 185.1533 -112.254792)
		(width 0.11684)
		(layer "In2.Cu")
		(net "PWRGD_CHAF_CPU1_R2")
	)
	(segment
		(start 188.312044 -109.862874)
		(end 188.712094 -110.262924)
		(width 0.11684)
		(layer "In2.Cu")
		(net "PWRGD_CHAF_CPU1_R2")
	)
	(segment
		(start 186.1185 -109.07268)
		(end 188.09208 -109.07268)
		(width 0.11684)
		(layer "In2.Cu")
		(net "PWRGD_CHAF_CPU1_R2")
	)
	(segment
		(start 168.946068 -107.513628)
		(end 175.61433 -107.513628)
		(width 0.11684)
		(layer "In2.Cu")
		(net "PWRGD_CHAF_CPU1_R2")
	)
	(segment
		(start 168.817036 -114.287808)
		(end 168.817036 -114.18824)
		(width 0.11684)
		(layer "In2.Cu")
		(net "PWRGD_CHAF_CPU1_R2")
	)
	(segment
		(start 185.1533 -112.254792)
		(end 185.593736 -111.814356)
		(width 0.11684)
		(layer "In2.Cu")
		(net "PWRGD_CHAF_CPU1_R2")
	)
	(segment
		(start 180.211222 -111.471202)
		(end 180.32857 -111.58855)
		(width 0.11684)
		(layer "In2.Cu")
		(net "PWRGD_CHAF_CPU1_R2")
	)
	(segment
		(start 167.371014 -110.517432)
		(end 167.371014 -109.088682)
		(width 0.11684)
		(layer "In2.Cu")
		(net "PWRGD_CHAF_CPU1_R2")
	)
	(segment
		(start 179.317904 -110.65637)
		(end 179.52847 -110.866936)
		(width 0.11684)
		(layer "In2.Cu")
		(net "PWRGD_CHAF_CPU1_R2")
	)
	(segment
		(start 180.32857 -111.58855)
		(end 180.32857 -112.011968)
		(width 0.11684)
		(layer "In2.Cu")
		(net "PWRGD_CHAF_CPU1_R2")
	)
	(segment
		(start 168.817036 -114.18824)
		(end 168.266872 -113.638076)
		(width 0.11684)
		(layer "In2.Cu")
		(net "PWRGD_CHAF_CPU1_R2")
	)
	(segment
		(start 179.67706 -111.471202)
		(end 180.211222 -111.471202)
		(width 0.11684)
		(layer "In2.Cu")
		(net "PWRGD_CHAF_CPU1_R2")
	)
	(segment
		(start 167.52189 -110.668308)
		(end 167.371014 -110.517432)
		(width 0.11684)
		(layer "In2.Cu")
		(net "PWRGD_CHAF_CPU1_R2")
	)
	(segment
		(start 180.32857 -112.011968)
		(end 180.571394 -112.254792)
		(width 0.11684)
		(layer "In2.Cu")
		(net "PWRGD_CHAF_CPU1_R2")
	)
	(segment
		(start 179.52847 -111.322612)
		(end 179.67706 -111.471202)
		(width 0.11684)
		(layer "In2.Cu")
		(net "PWRGD_CHAF_CPU1_R2")
	)
	(segment
		(start 166.031926 -113.669826)
		(end 165.384734 -114.317018)
		(width 0.11684)
		(layer "In6.Cu")
		(net "PWRGD_CHAF_CPU1_R2")
	)
	(segment
		(start 168.817036 -114.040666)
		(end 168.446196 -113.669826)
		(width 0.11684)
		(layer "In6.Cu")
		(net "PWRGD_CHAF_CPU1_R2")
	)
	(segment
		(start 163.412932 -115.92941)
		(end 163.412932 -116.865654)
		(width 0.11684)
		(layer "In6.Cu")
		(net "PWRGD_CHAF_CPU1_R2")
	)
	(segment
		(start 160.5915 -118.524782)
		(end 156.307282 -122.809)
		(width 0.11684)
		(layer "In6.Cu")
		(net "PWRGD_CHAF_CPU1_R2")
	)
	(segment
		(start 161.753804 -118.524782)
		(end 160.5915 -118.524782)
		(width 0.11684)
		(layer "In6.Cu")
		(net "PWRGD_CHAF_CPU1_R2")
	)
	(segment
		(start 168.817036 -114.287808)
		(end 168.817036 -114.040666)
		(width 0.11684)
		(layer "In6.Cu")
		(net "PWRGD_CHAF_CPU1_R2")
	)
	(segment
		(start 156.307282 -122.809)
		(end 151.765 -122.809)
		(width 0.11684)
		(layer "In6.Cu")
		(net "PWRGD_CHAF_CPU1_R2")
	)
	(segment
		(start 168.446196 -113.669826)
		(end 166.031926 -113.669826)
		(width 0.11684)
		(layer "In6.Cu")
		(net "PWRGD_CHAF_CPU1_R2")
	)
	(segment
		(start 163.412932 -116.865654)
		(end 161.753804 -118.524782)
		(width 0.11684)
		(layer "In6.Cu")
		(net "PWRGD_CHAF_CPU1_R2")
	)
	(segment
		(start 165.384734 -114.317018)
		(end 165.025324 -114.317018)
		(width 0.11684)
		(layer "In6.Cu")
		(net "PWRGD_CHAF_CPU1_R2")
	)
	(segment
		(start 165.025324 -114.317018)
		(end 163.412932 -115.92941)
		(width 0.11684)
		(layer "In6.Cu")
		(net "PWRGD_CHAF_CPU1_R2")
	)
	(segment
		(start 150.805896 -123.444)
		(end 150.622 -123.444)
		(width 0.10668)
		(layer "F.Cu")
		(net "PWRGD_CHAF_CPU1_R1")
	)
	(segment
		(start 147.33905 -121.793)
		(end 148.337778 -121.793)
		(width 0.10668)
		(layer "F.Cu")
		(net "PWRGD_CHAF_CPU1_R1")
	)
	(segment
		(start 147.33905 -120.777)
		(end 147.33905 -121.793)
		(width 0.10668)
		(layer "F.Cu")
		(net "PWRGD_CHAF_CPU1_R1")
	)
	(segment
		(start 150.85695 -125.349)
		(end 150.805896 -125.297946)
		(width 0.10668)
		(layer "F.Cu")
		(net "PWRGD_CHAF_CPU1_R1")
	)
	(segment
		(start 150.805896 -125.297946)
		(end 150.805896 -123.444)
		(width 0.10668)
		(layer "F.Cu")
		(net "PWRGD_CHAF_CPU1_R1")
	)
	(segment
		(start 148.972778 -122.428)
		(end 148.37791 -121.833132)
		(width 0.10668)
		(layer "F.Cu")
		(net "PWRGD_CHAF_CPU1_R1")
	)
	(segment
		(start 150.622 -123.444)
		(end 149.606 -122.428)
		(width 0.10668)
		(layer "F.Cu")
		(net "PWRGD_CHAF_CPU1_R1")
	)
	(segment
		(start 148.337778 -121.793)
		(end 148.37791 -121.833132)
		(width 0.10668)
		(layer "F.Cu")
		(net "PWRGD_CHAF_CPU1_R1")
	)
	(segment
		(start 149.606 -122.428)
		(end 148.972778 -122.428)
		(width 0.10668)
		(layer "F.Cu")
		(net "PWRGD_CHAF_CPU1_R1")
	)
	(via
		(at 148.37791 -121.833132)
		(size 0.762)
		(drill 0.381)
		(layers "F.Cu" "B.Cu")
		(net "PWRGD_CHAF_CPU1_R1")
	)
	(segment
		(start 199.009 -104.14)
		(end 199.009 -104.034336)
		(width 0.10668)
		(layer "F.Cu")
		(net "PWRGD_CHAF_CPU0_R2")
	)
	(segment
		(start 200.51395 -104.521)
		(end 199.39 -104.521)
		(width 0.10668)
		(layer "F.Cu")
		(net "PWRGD_CHAF_CPU0_R2")
	)
	(segment
		(start 191.522096 -106.652822)
		(end 191.911986 -106.262932)
		(width 0.10668)
		(layer "F.Cu")
		(net "PWRGD_CHAF_CPU0_R2")
	)
	(segment
		(start 199.39 -104.521)
		(end 199.009 -104.14)
		(width 0.10668)
		(layer "F.Cu")
		(net "PWRGD_CHAF_CPU0_R2")
	)
	(segment
		(start 199.009 -104.034336)
		(end 198.947024 -103.97236)
		(width 0.10668)
		(layer "F.Cu")
		(net "PWRGD_CHAF_CPU0_R2")
	)
	(via
		(at 198.947024 -103.97236)
		(size 0.508)
		(drill 0.254)
		(layers "F.Cu" "B.Cu")
		(net "PWRGD_CHAF_CPU0_R2")
	)
	(via
		(at 191.911986 -106.262932)
		(size 0.4572)
		(drill 0.254)
		(layers "F.Cu" "B.Cu")
		(net "PWRGD_CHAF_CPU0_R2")
	)
	(segment
		(start 198.393304 -103.41864)
		(end 198.947024 -103.97236)
		(width 0.11684)
		(layer "In2.Cu")
		(net "PWRGD_CHAF_CPU0_R2")
	)
	(segment
		(start 195.04406 -103.91394)
		(end 195.53936 -103.41864)
		(width 0.11684)
		(layer "In2.Cu")
		(net "PWRGD_CHAF_CPU0_R2")
	)
	(segment
		(start 195.53936 -103.41864)
		(end 198.393304 -103.41864)
		(width 0.11684)
		(layer "In2.Cu")
		(net "PWRGD_CHAF_CPU0_R2")
	)
	(segment
		(start 191.911986 -106.262932)
		(end 191.991488 -106.262932)
		(width 0.11684)
		(layer "In2.Cu")
		(net "PWRGD_CHAF_CPU0_R2")
	)
	(segment
		(start 191.991488 -106.262932)
		(end 194.34048 -103.91394)
		(width 0.11684)
		(layer "In2.Cu")
		(net "PWRGD_CHAF_CPU0_R2")
	)
	(segment
		(start 194.34048 -103.91394)
		(end 195.04406 -103.91394)
		(width 0.11684)
		(layer "In2.Cu")
		(net "PWRGD_CHAF_CPU0_R2")
	)
	(segment
		(start 207.453738 -104.741218)
		(end 204.944218 -104.741218)
		(width 0.10668)
		(layer "F.Cu")
		(net "PWRGD_CHAF_CPU0_R1")
	)
	(segment
		(start 204.944218 -104.741218)
		(end 204.216 -104.013)
		(width 0.10668)
		(layer "F.Cu")
		(net "PWRGD_CHAF_CPU0_R1")
	)
	(segment
		(start 207.532732 -104.741218)
		(end 207.453738 -104.741218)
		(width 0.10668)
		(layer "F.Cu")
		(net "PWRGD_CHAF_CPU0_R1")
	)
	(segment
		(start 204.216 -104.013)
		(end 203.397104 -104.013)
		(width 0.10668)
		(layer "F.Cu")
		(net "PWRGD_CHAF_CPU0_R1")
	)
	(segment
		(start 202.539854 -104.013)
		(end 202.031854 -103.505)
		(width 0.10668)
		(layer "F.Cu")
		(net "PWRGD_CHAF_CPU0_R1")
	)
	(segment
		(start 201.31405 -103.505)
		(end 201.31405 -104.521)
		(width 0.10668)
		(layer "F.Cu")
		(net "PWRGD_CHAF_CPU0_R1")
	)
	(segment
		(start 202.031854 -103.505)
		(end 201.31405 -103.505)
		(width 0.10668)
		(layer "F.Cu")
		(net "PWRGD_CHAF_CPU0_R1")
	)
	(segment
		(start 203.397104 -104.013)
		(end 202.539854 -104.013)
		(width 0.10668)
		(layer "F.Cu")
		(net "PWRGD_CHAF_CPU0_R1")
	)
	(segment
		(start 208.26095 -104.013)
		(end 207.532732 -104.741218)
		(width 0.10668)
		(layer "F.Cu")
		(net "PWRGD_CHAF_CPU0_R1")
	)
	(via
		(at 207.453738 -104.741218)
		(size 0.762)
		(drill 0.381)
		(layers "F.Cu" "B.Cu")
		(net "PWRGD_CHAF_CPU0_R1")
	)
	(segment
		(start 199.262492 -100.673662)
		(end 198.209154 -101.727)
		(width 0.10668)
		(layer "F.Cu")
		(net "PRSNT_SWB_ISO_R_N")
	)
	(segment
		(start 200.51395 -101.346)
		(end 199.841612 -100.673662)
		(width 0.10668)
		(layer "F.Cu")
		(net "PRSNT_SWB_ISO_R_N")
	)
	(segment
		(start 197.012814 -103.313484)
		(end 196.401182 -103.925116)
		(width 0.10668)
		(layer "F.Cu")
		(net "PRSNT_SWB_ISO_R_N")
	)
	(segment
		(start 193.922142 -109.052868)
		(end 194.312032 -108.662978)
		(width 0.10668)
		(layer "F.Cu")
		(net "PRSNT_SWB_ISO_R_N")
	)
	(segment
		(start 198.209154 -101.727)
		(end 197.408292 -101.727)
		(width 0.10668)
		(layer "F.Cu")
		(net "PRSNT_SWB_ISO_R_N")
	)
	(segment
		(start 197.012814 -102.122478)
		(end 197.012814 -103.313484)
		(width 0.10668)
		(layer "F.Cu")
		(net "PRSNT_SWB_ISO_R_N")
	)
	(segment
		(start 197.408292 -101.727)
		(end 197.012814 -102.122478)
		(width 0.10668)
		(layer "F.Cu")
		(net "PRSNT_SWB_ISO_R_N")
	)
	(segment
		(start 199.841612 -100.673662)
		(end 199.262492 -100.673662)
		(width 0.10668)
		(layer "F.Cu")
		(net "PRSNT_SWB_ISO_R_N")
	)
	(via
		(at 194.312032 -108.662978)
		(size 0.4572)
		(drill 0.254)
		(layers "F.Cu" "B.Cu")
		(net "PRSNT_SWB_ISO_R_N")
	)
	(via
		(at 196.401182 -103.925116)
		(size 0.508)
		(drill 0.254)
		(layers "F.Cu" "B.Cu")
		(net "PRSNT_SWB_ISO_R_N")
	)
	(via
		(at 199.262492 -100.673662)
		(size 0.508)
		(drill 0.254)
		(layers "F.Cu" "B.Cu")
		(net "PRSNT_SWB_ISO_R_N")
	)
	(segment
		(start 196.342 -104.59212)
		(end 195.58 -105.35412)
		(width 0.11684)
		(layer "In15.Cu")
		(net "PRSNT_SWB_ISO_R_N")
	)
	(segment
		(start 196.342 -103.984298)
		(end 196.342 -104.59212)
		(width 0.11684)
		(layer "In15.Cu")
		(net "PRSNT_SWB_ISO_R_N")
	)
	(segment
		(start 195.072 -106.934)
		(end 195.072 -108.331)
		(width 0.11684)
		(layer "In15.Cu")
		(net "PRSNT_SWB_ISO_R_N")
	)
	(segment
		(start 195.58 -105.35412)
		(end 195.58 -106.426)
		(width 0.11684)
		(layer "In15.Cu")
		(net "PRSNT_SWB_ISO_R_N")
	)
	(segment
		(start 195.072 -108.331)
		(end 194.740022 -108.662978)
		(width 0.11684)
		(layer "In15.Cu")
		(net "PRSNT_SWB_ISO_R_N")
	)
	(segment
		(start 195.58 -106.426)
		(end 195.072 -106.934)
		(width 0.11684)
		(layer "In15.Cu")
		(net "PRSNT_SWB_ISO_R_N")
	)
	(segment
		(start 196.401182 -103.925116)
		(end 196.342 -103.984298)
		(width 0.11684)
		(layer "In15.Cu")
		(net "PRSNT_SWB_ISO_R_N")
	)
	(segment
		(start 194.740022 -108.662978)
		(end 194.312032 -108.662978)
		(width 0.11684)
		(layer "In15.Cu")
		(net "PRSNT_SWB_ISO_R_N")
	)
	(segment
		(start 184.84977 -415.680906)
		(end 184.84977 -416.051238)
		(width 0.10668)
		(layer "F.Cu")
		(net "PRSNT_SWB_ISO_R1_N")
	)
	(segment
		(start 185.312304 -416.513772)
		(end 185.312304 -417.404804)
		(width 0.10668)
		(layer "F.Cu")
		(net "PRSNT_SWB_ISO_R1_N")
	)
	(segment
		(start 184.84977 -416.051238)
		(end 185.312304 -416.513772)
		(width 0.10668)
		(layer "F.Cu")
		(net "PRSNT_SWB_ISO_R1_N")
	)
	(segment
		(start 184.84977 -415.238946)
		(end 184.84977 -415.680906)
		(width 0.10668)
		(layer "F.Cu")
		(net "PRSNT_SWB_ISO_R1_N")
	)
	(segment
		(start 185.095642 -414.993074)
		(end 184.84977 -415.238946)
		(width 0.10668)
		(layer "F.Cu")
		(net "PRSNT_SWB_ISO_R1_N")
	)
	(segment
		(start 185.095642 -414.04413)
		(end 185.095642 -414.993074)
		(width 0.10668)
		(layer "F.Cu")
		(net "PRSNT_SWB_ISO_R1_N")
	)
	(via
		(at 184.84977 -415.680906)
		(size 0.762)
		(drill 0.381)
		(layers "F.Cu" "B.Cu")
		(net "PRSNT_SWB_ISO_R1_N")
	)
	(segment
		(start 223.983042 -201.745088)
		(end 223.983042 -199.661272)
		(width 0.10668)
		(layer "F.Cu")
		(net "PRSNT_SWB_ISO_N")
	)
	(segment
		(start 201.31405 -100.190554)
		(end 201.31405 -101.346)
		(width 0.10668)
		(layer "F.Cu")
		(net "PRSNT_SWB_ISO_N")
	)
	(segment
		(start 223.268032 -364.075218)
		(end 225.337624 -364.075218)
		(width 0.10668)
		(layer "F.Cu")
		(net "PRSNT_SWB_ISO_N")
	)
	(segment
		(start 223.233234 -166.606728)
		(end 223.233234 -164.10051)
		(width 0.10668)
		(layer "F.Cu")
		(net "PRSNT_SWB_ISO_N")
	)
	(segment
		(start 221.746064 -144.190466)
		(end 221.746064 -137.38225)
		(width 0.10668)
		(layer "F.Cu")
		(net "PRSNT_SWB_ISO_N")
	)
	(segment
		(start 222.414846 -206.042768)
		(end 222.414846 -203.313284)
		(width 0.10668)
		(layer "F.Cu")
		(net "PRSNT_SWB_ISO_N")
	)
	(segment
		(start 219.66428 -107.0864)
		(end 218.57462 -105.99674)
		(width 0.10668)
		(layer "F.Cu")
		(net "PRSNT_SWB_ISO_N")
	)
	(segment
		(start 223.983042 -199.661272)
		(end 224.52203 -199.122284)
		(width 0.10668)
		(layer "F.Cu")
		(net "PRSNT_SWB_ISO_N")
	)
	(segment
		(start 217.860372 -322.455032)
		(end 217.860372 -209.298794)
		(width 0.10668)
		(layer "F.Cu")
		(net "PRSNT_SWB_ISO_N")
	)
	(segment
		(start 202.317604 -99.187)
		(end 201.31405 -100.190554)
		(width 0.10668)
		(layer "F.Cu")
		(net "PRSNT_SWB_ISO_N")
	)
	(segment
		(start 222.302578 -136.825736)
		(end 222.302578 -125.473968)
		(width 0.10668)
		(layer "F.Cu")
		(net "PRSNT_SWB_ISO_N")
	)
	(segment
		(start 217.860372 -209.298794)
		(end 218.305888 -208.853278)
		(width 0.10668)
		(layer "F.Cu")
		(net "PRSNT_SWB_ISO_N")
	)
	(segment
		(start 226.67722 -335.843372)
		(end 225.24974 -334.415892)
		(width 0.10668)
		(layer "F.Cu")
		(net "PRSNT_SWB_ISO_N")
	)
	(segment
		(start 221.649544 -112.964976)
		(end 221.649544 -107.349544)
		(width 0.10668)
		(layer "F.Cu")
		(net "PRSNT_SWB_ISO_N")
	)
	(segment
		(start 225.24974 -334.415892)
		(end 225.24974 -329.8444)
		(width 0.10668)
		(layer "F.Cu")
		(net "PRSNT_SWB_ISO_N")
	)
	(segment
		(start 219.944442 -145.992088)
		(end 221.746064 -144.190466)
		(width 0.10668)
		(layer "F.Cu")
		(net "PRSNT_SWB_ISO_N")
	)
	(segment
		(start 207.899 -99.187)
		(end 202.317604 -99.187)
		(width 0.10668)
		(layer "F.Cu")
		(net "PRSNT_SWB_ISO_N")
	)
	(segment
		(start 201.883772 -370.253514)
		(end 217.75547 -370.253514)
		(width 0.10668)
		(layer "F.Cu")
		(net "PRSNT_SWB_ISO_N")
	)
	(segment
		(start 225.24974 -329.8444)
		(end 217.860372 -322.455032)
		(width 0.10668)
		(layer "F.Cu")
		(net "PRSNT_SWB_ISO_N")
	)
	(segment
		(start 185.095642 -413.24403)
		(end 185.095642 -412.775654)
		(width 0.10668)
		(layer "F.Cu")
		(net "PRSNT_SWB_ISO_N")
	)
	(segment
		(start 221.746064 -137.38225)
		(end 222.302578 -136.825736)
		(width 0.10668)
		(layer "F.Cu")
		(net "PRSNT_SWB_ISO_N")
	)
	(segment
		(start 221.435676 -365.907574)
		(end 223.268032 -364.075218)
		(width 0.10668)
		(layer "F.Cu")
		(net "PRSNT_SWB_ISO_N")
	)
	(segment
		(start 223.233234 -164.10051)
		(end 219.944442 -160.811718)
		(width 0.10668)
		(layer "F.Cu")
		(net "PRSNT_SWB_ISO_N")
	)
	(segment
		(start 216.408 -103.632)
		(end 213.487 -100.711)
		(width 0.10668)
		(layer "F.Cu")
		(net "PRSNT_SWB_ISO_N")
	)
	(segment
		(start 225.337624 -364.075218)
		(end 226.67722 -362.735622)
		(width 0.10668)
		(layer "F.Cu")
		(net "PRSNT_SWB_ISO_N")
	)
	(segment
		(start 224.52203 -199.122284)
		(end 224.52203 -167.895524)
		(width 0.10668)
		(layer "F.Cu")
		(net "PRSNT_SWB_ISO_N")
	)
	(segment
		(start 218.57462 -105.99674)
		(end 218.57462 -105.29824)
		(width 0.10668)
		(layer "F.Cu")
		(net "PRSNT_SWB_ISO_N")
	)
	(segment
		(start 180.829966 -368.773964)
		(end 200.404222 -368.773964)
		(width 0.10668)
		(layer "F.Cu")
		(net "PRSNT_SWB_ISO_N")
	)
	(segment
		(start 200.404222 -368.773964)
		(end 201.883772 -370.253514)
		(width 0.10668)
		(layer "F.Cu")
		(net "PRSNT_SWB_ISO_N")
	)
	(segment
		(start 221.649544 -107.349544)
		(end 221.3864 -107.0864)
		(width 0.10668)
		(layer "F.Cu")
		(net "PRSNT_SWB_ISO_N")
	)
	(segment
		(start 224.52203 -167.895524)
		(end 223.233234 -166.606728)
		(width 0.10668)
		(layer "F.Cu")
		(net "PRSNT_SWB_ISO_N")
	)
	(segment
		(start 216.90838 -103.632)
		(end 216.408 -103.632)
		(width 0.10668)
		(layer "F.Cu")
		(net "PRSNT_SWB_ISO_N")
	)
	(segment
		(start 218.57462 -105.29824)
		(end 216.90838 -103.632)
		(width 0.10668)
		(layer "F.Cu")
		(net "PRSNT_SWB_ISO_N")
	)
	(segment
		(start 185.095642 -412.775654)
		(end 184.73928 -412.419292)
		(width 0.10668)
		(layer "F.Cu")
		(net "PRSNT_SWB_ISO_N")
	)
	(segment
		(start 219.248736 -122.420126)
		(end 219.248736 -115.365784)
		(width 0.10668)
		(layer "F.Cu")
		(net "PRSNT_SWB_ISO_N")
	)
	(segment
		(start 226.67722 -362.735622)
		(end 226.67722 -335.843372)
		(width 0.10668)
		(layer "F.Cu")
		(net "PRSNT_SWB_ISO_N")
	)
	(segment
		(start 218.305888 -208.853278)
		(end 219.604336 -208.853278)
		(width 0.10668)
		(layer "F.Cu")
		(net "PRSNT_SWB_ISO_N")
	)
	(segment
		(start 221.435676 -366.573308)
		(end 221.435676 -365.907574)
		(width 0.10668)
		(layer "F.Cu")
		(net "PRSNT_SWB_ISO_N")
	)
	(segment
		(start 222.414846 -203.313284)
		(end 223.983042 -201.745088)
		(width 0.10668)
		(layer "F.Cu")
		(net "PRSNT_SWB_ISO_N")
	)
	(segment
		(start 219.604336 -208.853278)
		(end 222.414846 -206.042768)
		(width 0.10668)
		(layer "F.Cu")
		(net "PRSNT_SWB_ISO_N")
	)
	(segment
		(start 219.248736 -115.365784)
		(end 221.649544 -112.964976)
		(width 0.10668)
		(layer "F.Cu")
		(net "PRSNT_SWB_ISO_N")
	)
	(segment
		(start 176.152302 -366.571784)
		(end 178.627786 -366.571784)
		(width 0.10668)
		(layer "F.Cu")
		(net "PRSNT_SWB_ISO_N")
	)
	(segment
		(start 219.944442 -160.811718)
		(end 219.944442 -145.992088)
		(width 0.10668)
		(layer "F.Cu")
		(net "PRSNT_SWB_ISO_N")
	)
	(segment
		(start 217.75547 -370.253514)
		(end 221.435676 -366.573308)
		(width 0.10668)
		(layer "F.Cu")
		(net "PRSNT_SWB_ISO_N")
	)
	(segment
		(start 175.753522 -366.173004)
		(end 176.152302 -366.571784)
		(width 0.10668)
		(layer "F.Cu")
		(net "PRSNT_SWB_ISO_N")
	)
	(segment
		(start 209.423 -100.711)
		(end 207.899 -99.187)
		(width 0.10668)
		(layer "F.Cu")
		(net "PRSNT_SWB_ISO_N")
	)
	(segment
		(start 178.627786 -366.571784)
		(end 180.829966 -368.773964)
		(width 0.10668)
		(layer "F.Cu")
		(net "PRSNT_SWB_ISO_N")
	)
	(segment
		(start 221.3864 -107.0864)
		(end 219.66428 -107.0864)
		(width 0.10668)
		(layer "F.Cu")
		(net "PRSNT_SWB_ISO_N")
	)
	(segment
		(start 213.487 -100.711)
		(end 209.423 -100.711)
		(width 0.10668)
		(layer "F.Cu")
		(net "PRSNT_SWB_ISO_N")
	)
	(segment
		(start 222.302578 -125.473968)
		(end 219.248736 -122.420126)
		(width 0.10668)
		(layer "F.Cu")
		(net "PRSNT_SWB_ISO_N")
	)
	(via
		(at 175.753522 -366.173004)
		(size 0.508)
		(drill 0.254)
		(layers "F.Cu" "B.Cu")
		(net "PRSNT_SWB_ISO_N")
	)
	(via
		(at 216.408 -103.632)
		(size 0.762)
		(drill 0.381)
		(layers "F.Cu" "B.Cu")
		(net "PRSNT_SWB_ISO_N")
	)
	(via
		(at 97.807272 -427.609508)
		(size 0.508)
		(drill 0.254)
		(layers "F.Cu" "B.Cu")
		(net "PRSNT_SWB_ISO_N")
	)
	(via
		(at 171.127166 -395.419072)
		(size 0.508)
		(drill 0.254)
		(layers "F.Cu" "B.Cu")
		(net "PRSNT_SWB_ISO_N")
	)
	(via
		(at 178.410108 -419.219126)
		(size 0.508)
		(drill 0.254)
		(layers "F.Cu" "B.Cu")
		(net "PRSNT_SWB_ISO_N")
	)
	(via
		(at 184.73928 -412.419292)
		(size 0.508)
		(drill 0.254)
		(layers "F.Cu" "B.Cu")
		(net "PRSNT_SWB_ISO_N")
	)
	(segment
		(start 169.450766 -399.81886)
		(end 171.197778 -398.071848)
		(width 0.10668)
		(layer "B.Cu")
		(net "PRSNT_SWB_ISO_N")
	)
	(segment
		(start 164.505132 -411.048962)
		(end 164.505132 -400.801332)
		(width 0.10668)
		(layer "B.Cu")
		(net "PRSNT_SWB_ISO_N")
	)
	(segment
		(start 175.450754 -412.402528)
		(end 174.876968 -412.402528)
		(width 0.10668)
		(layer "B.Cu")
		(net "PRSNT_SWB_ISO_N")
	)
	(segment
		(start 171.288456 -412.456122)
		(end 169.966132 -413.778446)
		(width 0.10668)
		(layer "B.Cu")
		(net "PRSNT_SWB_ISO_N")
	)
	(segment
		(start 167.836088 -413.778446)
		(end 167.456612 -413.39897)
		(width 0.10668)
		(layer "B.Cu")
		(net "PRSNT_SWB_ISO_N")
	)
	(segment
		(start 97.807272 -427.609508)
		(end 97.807272 -426.561758)
		(width 0.10668)
		(layer "B.Cu")
		(net "PRSNT_SWB_ISO_N")
	)
	(segment
		(start 171.197778 -396.237714)
		(end 171.127166 -396.167102)
		(width 0.10668)
		(layer "B.Cu")
		(net "PRSNT_SWB_ISO_N")
	)
	(segment
		(start 99.478592 -426.179996)
		(end 100.123244 -425.535344)
		(width 0.10668)
		(layer "B.Cu")
		(net "PRSNT_SWB_ISO_N")
	)
	(segment
		(start 165.487604 -399.81886)
		(end 169.450766 -399.81886)
		(width 0.10668)
		(layer "B.Cu")
		(net "PRSNT_SWB_ISO_N")
	)
	(segment
		(start 97.991168 -426.179996)
		(end 99.478592 -426.179996)
		(width 0.10668)
		(layer "B.Cu")
		(net "PRSNT_SWB_ISO_N")
	)
	(segment
		(start 184.73928 -412.419292)
		(end 183.285638 -410.96565)
		(width 0.10668)
		(layer "B.Cu")
		(net "PRSNT_SWB_ISO_N")
	)
	(segment
		(start 174.13859 -412.293308)
		(end 173.975776 -412.456122)
		(width 0.10668)
		(layer "B.Cu")
		(net "PRSNT_SWB_ISO_N")
	)
	(segment
		(start 174.876968 -412.402528)
		(end 174.767748 -412.293308)
		(width 0.10668)
		(layer "B.Cu")
		(net "PRSNT_SWB_ISO_N")
	)
	(segment
		(start 97.807272 -426.561758)
		(end 97.991168 -426.377862)
		(width 0.10668)
		(layer "B.Cu")
		(net "PRSNT_SWB_ISO_N")
	)
	(segment
		(start 181.281578 -410.96565)
		(end 180.857906 -411.389322)
		(width 0.10668)
		(layer "B.Cu")
		(net "PRSNT_SWB_ISO_N")
	)
	(segment
		(start 167.456612 -413.39897)
		(end 167.456612 -412.599378)
		(width 0.10668)
		(layer "B.Cu")
		(net "PRSNT_SWB_ISO_N")
	)
	(segment
		(start 164.505132 -400.801332)
		(end 165.487604 -399.81886)
		(width 0.10668)
		(layer "B.Cu")
		(net "PRSNT_SWB_ISO_N")
	)
	(segment
		(start 179.261008 -411.681676)
		(end 176.52619 -411.681676)
		(width 0.10668)
		(layer "B.Cu")
		(net "PRSNT_SWB_ISO_N")
	)
	(segment
		(start 167.313356 -412.456122)
		(end 165.912292 -412.456122)
		(width 0.10668)
		(layer "B.Cu")
		(net "PRSNT_SWB_ISO_N")
	)
	(segment
		(start 176.52619 -411.681676)
		(end 175.914558 -412.293308)
		(width 0.10668)
		(layer "B.Cu")
		(net "PRSNT_SWB_ISO_N")
	)
	(segment
		(start 180.644292 -411.389322)
		(end 180.480208 -411.553406)
		(width 0.10668)
		(layer "B.Cu")
		(net "PRSNT_SWB_ISO_N")
	)
	(segment
		(start 171.197778 -398.071848)
		(end 171.197778 -396.237714)
		(width 0.10668)
		(layer "B.Cu")
		(net "PRSNT_SWB_ISO_N")
	)
	(segment
		(start 179.389278 -411.553406)
		(end 179.261008 -411.681676)
		(width 0.10668)
		(layer "B.Cu")
		(net "PRSNT_SWB_ISO_N")
	)
	(segment
		(start 171.127166 -396.167102)
		(end 171.127166 -395.419072)
		(width 0.10668)
		(layer "B.Cu")
		(net "PRSNT_SWB_ISO_N")
	)
	(segment
		(start 175.914558 -412.293308)
		(end 175.559974 -412.293308)
		(width 0.10668)
		(layer "B.Cu")
		(net "PRSNT_SWB_ISO_N")
	)
	(segment
		(start 169.966132 -413.778446)
		(end 167.836088 -413.778446)
		(width 0.10668)
		(layer "B.Cu")
		(net "PRSNT_SWB_ISO_N")
	)
	(segment
		(start 165.912292 -412.456122)
		(end 164.505132 -411.048962)
		(width 0.10668)
		(layer "B.Cu")
		(net "PRSNT_SWB_ISO_N")
	)
	(segment
		(start 175.559974 -412.293308)
		(end 175.450754 -412.402528)
		(width 0.10668)
		(layer "B.Cu")
		(net "PRSNT_SWB_ISO_N")
	)
	(segment
		(start 173.975776 -412.456122)
		(end 171.288456 -412.456122)
		(width 0.10668)
		(layer "B.Cu")
		(net "PRSNT_SWB_ISO_N")
	)
	(segment
		(start 167.456612 -412.599378)
		(end 167.313356 -412.456122)
		(width 0.10668)
		(layer "B.Cu")
		(net "PRSNT_SWB_ISO_N")
	)
	(segment
		(start 180.480208 -411.553406)
		(end 179.389278 -411.553406)
		(width 0.10668)
		(layer "B.Cu")
		(net "PRSNT_SWB_ISO_N")
	)
	(segment
		(start 97.991168 -425.19219)
		(end 97.991168 -426.179996)
		(width 0.10668)
		(layer "B.Cu")
		(net "PRSNT_SWB_ISO_N")
	)
	(segment
		(start 97.991168 -426.377862)
		(end 97.991168 -426.179996)
		(width 0.10668)
		(layer "B.Cu")
		(net "PRSNT_SWB_ISO_N")
	)
	(segment
		(start 180.857906 -411.389322)
		(end 180.644292 -411.389322)
		(width 0.10668)
		(layer "B.Cu")
		(net "PRSNT_SWB_ISO_N")
	)
	(segment
		(start 183.285638 -410.96565)
		(end 181.281578 -410.96565)
		(width 0.10668)
		(layer "B.Cu")
		(net "PRSNT_SWB_ISO_N")
	)
	(segment
		(start 174.767748 -412.293308)
		(end 174.13859 -412.293308)
		(width 0.10668)
		(layer "B.Cu")
		(net "PRSNT_SWB_ISO_N")
	)
	(segment
		(start 169.30116 -418.535612)
		(end 169.545508 -418.77996)
		(width 0.11684)
		(layer "In2.Cu")
		(net "PRSNT_SWB_ISO_N")
	)
	(segment
		(start 118.29034 -420.16172)
		(end 119.936514 -420.16172)
		(width 0.11684)
		(layer "In2.Cu")
		(net "PRSNT_SWB_ISO_N")
	)
	(segment
		(start 97.807272 -427.609508)
		(end 97.807272 -426.575728)
		(width 0.11684)
		(layer "In2.Cu")
		(net "PRSNT_SWB_ISO_N")
	)
	(segment
		(start 162.779456 -418.71392)
		(end 162.868102 -418.625274)
		(width 0.11684)
		(layer "In2.Cu")
		(net "PRSNT_SWB_ISO_N")
	)
	(segment
		(start 163.41979 -418.625274)
		(end 163.46805 -418.673534)
		(width 0.11684)
		(layer "In2.Cu")
		(net "PRSNT_SWB_ISO_N")
	)
	(segment
		(start 108.94314 -420.022274)
		(end 118.150894 -420.022274)
		(width 0.11684)
		(layer "In2.Cu")
		(net "PRSNT_SWB_ISO_N")
	)
	(segment
		(start 164.639244 -418.14242)
		(end 167.805608 -418.14242)
		(width 0.11684)
		(layer "In2.Cu")
		(net "PRSNT_SWB_ISO_N")
	)
	(segment
		(start 119.936514 -420.16172)
		(end 122.251216 -417.847018)
		(width 0.11684)
		(layer "In2.Cu")
		(net "PRSNT_SWB_ISO_N")
	)
	(segment
		(start 162.868102 -418.625274)
		(end 163.41979 -418.625274)
		(width 0.11684)
		(layer "In2.Cu")
		(net "PRSNT_SWB_ISO_N")
	)
	(segment
		(start 162.274504 -418.71392)
		(end 162.779456 -418.71392)
		(width 0.11684)
		(layer "In2.Cu")
		(net "PRSNT_SWB_ISO_N")
	)
	(segment
		(start 97.807272 -426.575728)
		(end 99.93757 -424.44543)
		(width 0.11684)
		(layer "In2.Cu")
		(net "PRSNT_SWB_ISO_N")
	)
	(segment
		(start 167.805608 -418.14242)
		(end 168.1988 -418.535612)
		(width 0.11684)
		(layer "In2.Cu")
		(net "PRSNT_SWB_ISO_N")
	)
	(segment
		(start 177.145696 -419.219126)
		(end 178.410108 -419.219126)
		(width 0.11684)
		(layer "In2.Cu")
		(net "PRSNT_SWB_ISO_N")
	)
	(segment
		(start 169.545508 -418.77996)
		(end 170.794934 -418.77996)
		(width 0.11684)
		(layer "In2.Cu")
		(net "PRSNT_SWB_ISO_N")
	)
	(segment
		(start 106.661204 -422.12895)
		(end 106.836464 -422.12895)
		(width 0.11684)
		(layer "In2.Cu")
		(net "PRSNT_SWB_ISO_N")
	)
	(segment
		(start 168.1988 -418.535612)
		(end 169.30116 -418.535612)
		(width 0.11684)
		(layer "In2.Cu")
		(net "PRSNT_SWB_ISO_N")
	)
	(segment
		(start 164.10813 -418.673534)
		(end 164.639244 -418.14242)
		(width 0.11684)
		(layer "In2.Cu")
		(net "PRSNT_SWB_ISO_N")
	)
	(segment
		(start 170.794934 -418.77996)
		(end 171.247054 -419.23208)
		(width 0.11684)
		(layer "In2.Cu")
		(net "PRSNT_SWB_ISO_N")
	)
	(segment
		(start 171.247054 -419.23208)
		(end 177.132742 -419.23208)
		(width 0.11684)
		(layer "In2.Cu")
		(net "PRSNT_SWB_ISO_N")
	)
	(segment
		(start 122.251216 -417.847018)
		(end 161.407602 -417.847018)
		(width 0.11684)
		(layer "In2.Cu")
		(net "PRSNT_SWB_ISO_N")
	)
	(segment
		(start 104.344724 -424.44543)
		(end 106.661204 -422.12895)
		(width 0.11684)
		(layer "In2.Cu")
		(net "PRSNT_SWB_ISO_N")
	)
	(segment
		(start 177.132742 -419.23208)
		(end 177.145696 -419.219126)
		(width 0.11684)
		(layer "In2.Cu")
		(net "PRSNT_SWB_ISO_N")
	)
	(segment
		(start 99.93757 -424.44543)
		(end 104.344724 -424.44543)
		(width 0.11684)
		(layer "In2.Cu")
		(net "PRSNT_SWB_ISO_N")
	)
	(segment
		(start 118.150894 -420.022274)
		(end 118.29034 -420.16172)
		(width 0.11684)
		(layer "In2.Cu")
		(net "PRSNT_SWB_ISO_N")
	)
	(segment
		(start 161.407602 -417.847018)
		(end 162.274504 -418.71392)
		(width 0.11684)
		(layer "In2.Cu")
		(net "PRSNT_SWB_ISO_N")
	)
	(segment
		(start 106.836464 -422.12895)
		(end 108.94314 -420.022274)
		(width 0.11684)
		(layer "In2.Cu")
		(net "PRSNT_SWB_ISO_N")
	)
	(segment
		(start 163.46805 -418.673534)
		(end 164.10813 -418.673534)
		(width 0.11684)
		(layer "In2.Cu")
		(net "PRSNT_SWB_ISO_N")
	)
	(segment
		(start 171.127166 -394.508482)
		(end 170.084242 -393.465558)
		(width 0.11684)
		(layer "In15.Cu")
		(net "PRSNT_SWB_ISO_N")
	)
	(segment
		(start 170.084242 -392.250168)
		(end 172.498004 -389.836406)
		(width 0.11684)
		(layer "In15.Cu")
		(net "PRSNT_SWB_ISO_N")
	)
	(segment
		(start 183.821578 -417.90112)
		(end 179.728114 -417.90112)
		(width 0.11684)
		(layer "In15.Cu")
		(net "PRSNT_SWB_ISO_N")
	)
	(segment
		(start 184.104788 -379.339348)
		(end 184.104788 -372.57355)
		(width 0.11684)
		(layer "In15.Cu")
		(net "PRSNT_SWB_ISO_N")
	)
	(segment
		(start 184.73928 -412.419292)
		(end 184.73928 -416.983418)
		(width 0.11684)
		(layer "In15.Cu")
		(net "PRSNT_SWB_ISO_N")
	)
	(segment
		(start 173.60773 -389.836406)
		(end 184.104788 -379.339348)
		(width 0.11684)
		(layer "In15.Cu")
		(net "PRSNT_SWB_ISO_N")
	)
	(segment
		(start 184.104788 -372.57355)
		(end 178.60137 -367.070132)
		(width 0.11684)
		(layer "In15.Cu")
		(net "PRSNT_SWB_ISO_N")
	)
	(segment
		(start 170.084242 -393.465558)
		(end 170.084242 -392.250168)
		(width 0.11684)
		(layer "In15.Cu")
		(net "PRSNT_SWB_ISO_N")
	)
	(segment
		(start 184.73928 -416.983418)
		(end 183.821578 -417.90112)
		(width 0.11684)
		(layer "In15.Cu")
		(net "PRSNT_SWB_ISO_N")
	)
	(segment
		(start 172.498004 -389.836406)
		(end 173.60773 -389.836406)
		(width 0.11684)
		(layer "In15.Cu")
		(net "PRSNT_SWB_ISO_N")
	)
	(segment
		(start 179.728114 -417.90112)
		(end 178.410108 -419.219126)
		(width 0.11684)
		(layer "In15.Cu")
		(net "PRSNT_SWB_ISO_N")
	)
	(segment
		(start 176.65065 -367.070132)
		(end 175.753522 -366.173004)
		(width 0.11684)
		(layer "In15.Cu")
		(net "PRSNT_SWB_ISO_N")
	)
	(segment
		(start 178.60137 -367.070132)
		(end 176.65065 -367.070132)
		(width 0.11684)
		(layer "In15.Cu")
		(net "PRSNT_SWB_ISO_N")
	)
	(segment
		(start 171.127166 -395.419072)
		(end 171.127166 -394.508482)
		(width 0.11684)
		(layer "In15.Cu")
		(net "PRSNT_SWB_ISO_N")
	)
	(via
		(at 103.251 -424.815)
		(size 0.6604)
		(drill 0.3302)
		(layers "F.Cu" "B.Cu")
		(net "PRSNT_SWB")
	)
	(segment
		(start 101.473 -424.758358)
		(end 101.473 -424.41368)
		(width 0.10668)
		(layer "B.Cu")
		(net "PRSNT_SWB")
	)
	(segment
		(start 103.180642 -424.885358)
		(end 103.251 -424.815)
		(width 0.10668)
		(layer "B.Cu")
		(net "PRSNT_SWB")
	)
	(segment
		(start 103.251 -424.815)
		(end 104.12095 -424.815)
		(width 0.10668)
		(layer "B.Cu")
		(net "PRSNT_SWB")
	)
	(segment
		(start 101.473 -424.41368)
		(end 101.651308 -424.235372)
		(width 0.10668)
		(layer "B.Cu")
		(net "PRSNT_SWB")
	)
	(segment
		(start 102.023164 -424.885358)
		(end 103.180642 -424.885358)
		(width 0.10668)
		(layer "B.Cu")
		(net "PRSNT_SWB")
	)
	(segment
		(start 101.651308 -424.235372)
		(end 102.023164 -424.235372)
		(width 0.10668)
		(layer "B.Cu")
		(net "PRSNT_SWB")
	)
	(segment
		(start 102.023164 -424.885358)
		(end 101.6 -424.885358)
		(width 0.10668)
		(layer "B.Cu")
		(net "PRSNT_SWB")
	)
	(segment
		(start 101.6 -424.885358)
		(end 101.473 -424.758358)
		(width 0.10668)
		(layer "B.Cu")
		(net "PRSNT_SWB")
	)
	(segment
		(start 222.82404 -81.46796)
		(end 222.25 -82.042)
		(width 0.10668)
		(layer "F.Cu")
		(net "P3V3_E1S_PWRGD_0_R1")
	)
	(segment
		(start 221.259146 -81.273904)
		(end 221.361 -81.17205)
		(width 0.10668)
		(layer "F.Cu")
		(net "P3V3_E1S_PWRGD_0_R1")
	)
	(segment
		(start 223.66605 -81.42605)
		(end 223.527112 -81.287112)
		(width 0.10668)
		(layer "F.Cu")
		(net "P3V3_E1S_PWRGD_0_R1")
	)
	(segment
		(start 222.82404 -81.287112)
		(end 222.82404 -81.46796)
		(width 0.10668)
		(layer "F.Cu")
		(net "P3V3_E1S_PWRGD_0_R1")
	)
	(segment
		(start 221.259146 -82.042)
		(end 221.259146 -81.273904)
		(width 0.10668)
		(layer "F.Cu")
		(net "P3V3_E1S_PWRGD_0_R1")
	)
	(segment
		(start 224.77095 -82.804)
		(end 223.66605 -82.804)
		(width 0.10668)
		(layer "F.Cu")
		(net "P3V3_E1S_PWRGD_0_R1")
	)
	(segment
		(start 223.66605 -82.804)
		(end 223.66605 -81.42605)
		(width 0.10668)
		(layer "F.Cu")
		(net "P3V3_E1S_PWRGD_0_R1")
	)
	(segment
		(start 222.25 -82.042)
		(end 221.259146 -82.042)
		(width 0.10668)
		(layer "F.Cu")
		(net "P3V3_E1S_PWRGD_0_R1")
	)
	(segment
		(start 223.527112 -81.287112)
		(end 222.82404 -81.287112)
		(width 0.10668)
		(layer "F.Cu")
		(net "P3V3_E1S_PWRGD_0_R1")
	)
	(via
		(at 221.259146 -82.042)
		(size 0.508)
		(drill 0.254)
		(layers "F.Cu" "B.Cu")
		(net "P3V3_E1S_PWRGD_0_R1")
	)
	(segment
		(start 107.496356 -412.778956)
		(end 107.496356 -412.00705)
		(width 0.254)
		(layer "F.Cu")
		(net "P3V3_9ZXL045_P1_VDDR")
	)
	(segment
		(start 107.95 -413.2326)
		(end 107.496356 -412.778956)
		(width 0.254)
		(layer "F.Cu")
		(net "P3V3_9ZXL045_P1_VDDR")
	)
	(via
		(at 107.95 -413.2326)
		(size 0.762)
		(drill 0.381)
		(layers "F.Cu" "B.Cu")
		(net "P3V3_9ZXL045_P1_VDDR")
	)
	(via
		(at 110.871 -411.1498)
		(size 0.762)
		(drill 0.381)
		(layers "F.Cu" "B.Cu")
		(net "P3V3_9ZXL045_P1_VDDA")
	)
	(segment
		(start 103.71455 -407.88209)
		(end 103.301038 -407.468578)
		(width 0.254)
		(layer "F.Cu")
		(net "P3V3_9ZXL045_P1_VDD")
	)
	(segment
		(start 103.871522 -407.88209)
		(end 103.71455 -407.88209)
		(width 0.254)
		(layer "F.Cu")
		(net "P3V3_9ZXL045_P1_VDD")
	)
	(segment
		(start 103.871522 -409.882086)
		(end 103.246174 -409.882086)
		(width 0.254)
		(layer "F.Cu")
		(net "P3V3_9ZXL045_P1_VDD")
	)
	(segment
		(start 108.621322 -409.882086)
		(end 109.347 -409.882086)
		(width 0.254)
		(layer "F.Cu")
		(net "P3V3_9ZXL045_P1_VDD")
	)
	(segment
		(start 106.496358 -407.25725)
		(end 106.496358 -406.58415)
		(width 0.254)
		(layer "F.Cu")
		(net "P3V3_9ZXL045_P1_VDD")
	)
	(segment
		(start 103.246174 -409.882086)
		(end 103.211122 -409.917138)
		(width 0.254)
		(layer "F.Cu")
		(net "P3V3_9ZXL045_P1_VDD")
	)
	(segment
		(start 108.621322 -407.88209)
		(end 109.347 -407.88209)
		(width 0.254)
		(layer "F.Cu")
		(net "P3V3_9ZXL045_P1_VDD")
	)
	(via
		(at 109.347 -407.88209)
		(size 0.508)
		(drill 0.254)
		(layers "F.Cu" "B.Cu")
		(net "P3V3_9ZXL045_P1_VDD")
	)
	(via
		(at 101.459538 -409.602686)
		(size 0.508)
		(drill 0.254)
		(layers "F.Cu" "B.Cu")
		(net "P3V3_9ZXL045_P1_VDD")
	)
	(via
		(at 101.549454 -408.019504)
		(size 0.508)
		(drill 0.254)
		(layers "F.Cu" "B.Cu")
		(net "P3V3_9ZXL045_P1_VDD")
	)
	(via
		(at 106.496358 -406.58415)
		(size 0.508)
		(drill 0.254)
		(layers "F.Cu" "B.Cu")
		(net "P3V3_9ZXL045_P1_VDD")
	)
	(via
		(at 102.023418 -407.069544)
		(size 0.6604)
		(drill 0.3302)
		(layers "F.Cu" "B.Cu")
		(net "P3V3_9ZXL045_P1_VDD")
	)
	(via
		(at 107.992164 -407.00071)
		(size 0.6604)
		(drill 0.3302)
		(layers "F.Cu" "B.Cu")
		(net "P3V3_9ZXL045_P1_VDD")
	)
	(via
		(at 103.211122 -409.917138)
		(size 0.508)
		(drill 0.254)
		(layers "F.Cu" "B.Cu")
		(net "P3V3_9ZXL045_P1_VDD")
	)
	(via
		(at 109.347 -409.882086)
		(size 0.508)
		(drill 0.254)
		(layers "F.Cu" "B.Cu")
		(net "P3V3_9ZXL045_P1_VDD")
	)
	(via
		(at 103.301038 -407.468578)
		(size 0.508)
		(drill 0.254)
		(layers "F.Cu" "B.Cu")
		(net "P3V3_9ZXL045_P1_VDD")
	)
	(via
		(at 110.30712 -417.780978)
		(size 0.762)
		(drill 0.381)
		(layers "F.Cu" "B.Cu")
		(net "P3V3_9ZXL045_P1")
	)
	(segment
		(start 281.60345 -425.81195)
		(end 281.94 -425.4754)
		(width 0.508)
		(layer "F.Cu")
		(net "P3V3_9ZXL045_P0_VDDR")
	)
	(segment
		(start 283.506164 -419.572948)
		(end 282.82646 -419.572948)
		(width 0.2286)
		(layer "F.Cu")
		(net "P3V3_9ZXL045_P0_VDDR")
	)
	(segment
		(start 280.67 -421.729408)
		(end 280.67 -425.81195)
		(width 0.508)
		(layer "F.Cu")
		(net "P3V3_9ZXL045_P0_VDDR")
	)
	(segment
		(start 280.67 -425.81195)
		(end 281.60345 -425.81195)
		(width 0.508)
		(layer "F.Cu")
		(net "P3V3_9ZXL045_P0_VDDR")
	)
	(segment
		(start 282.177744 -420.221664)
		(end 280.67 -421.729408)
		(width 0.508)
		(layer "F.Cu")
		(net "P3V3_9ZXL045_P0_VDDR")
	)
	(segment
		(start 282.177744 -420.221664)
		(end 282.82646 -419.572948)
		(width 0.508)
		(layer "F.Cu")
		(net "P3V3_9ZXL045_P0_VDDR")
	)
	(via
		(at 282.82646 -419.572948)
		(size 0.508)
		(drill 0.254)
		(layers "F.Cu" "B.Cu")
		(net "P3V3_9ZXL045_P0_VDDR")
	)
	(via
		(at 282.177744 -420.221664)
		(size 0.762)
		(drill 0.381)
		(layers "F.Cu" "B.Cu")
		(net "P3V3_9ZXL045_P0_VDDR")
	)
	(segment
		(start 283.245306 -419.154102)
		(end 282.82646 -419.572948)
		(width 0.381)
		(layer "B.Cu")
		(net "P3V3_9ZXL045_P0_VDDR")
	)
	(segment
		(start 283.245306 -418.976302)
		(end 283.245306 -419.154102)
		(width 0.381)
		(layer "B.Cu")
		(net "P3V3_9ZXL045_P0_VDDR")
	)
	(segment
		(start 283.591508 -425.79544)
		(end 283.265118 -425.46905)
		(width 0.508)
		(layer "F.Cu")
		(net "P3V3_9ZXL045_P0_VDDA")
	)
	(segment
		(start 284.556962 -425.79544)
		(end 283.591508 -425.79544)
		(width 0.508)
		(layer "F.Cu")
		(net "P3V3_9ZXL045_P0_VDDA")
	)
	(segment
		(start 284.63113 -420.697914)
		(end 284.63113 -421.377618)
		(width 0.2286)
		(layer "F.Cu")
		(net "P3V3_9ZXL045_P0_VDDA")
	)
	(segment
		(start 284.556962 -421.451786)
		(end 284.556962 -424.208956)
		(width 0.508)
		(layer "F.Cu")
		(net "P3V3_9ZXL045_P0_VDDA")
	)
	(segment
		(start 284.63113 -421.377618)
		(end 284.556962 -421.451786)
		(width 0.508)
		(layer "F.Cu")
		(net "P3V3_9ZXL045_P0_VDDA")
	)
	(segment
		(start 284.556962 -424.208956)
		(end 284.556962 -425.79544)
		(width 0.508)
		(layer "F.Cu")
		(net "P3V3_9ZXL045_P0_VDDA")
	)
	(via
		(at 284.63113 -421.377618)
		(size 0.508)
		(drill 0.254)
		(layers "F.Cu" "B.Cu")
		(net "P3V3_9ZXL045_P0_VDDA")
	)
	(via
		(at 284.556962 -424.208956)
		(size 0.762)
		(drill 0.381)
		(layers "F.Cu" "B.Cu")
		(net "P3V3_9ZXL045_P0_VDDA")
	)
	(segment
		(start 284.074108 -420.891462)
		(end 284.144974 -420.891462)
		(width 0.381)
		(layer "B.Cu")
		(net "P3V3_9ZXL045_P0_VDDA")
	)
	(segment
		(start 284.144974 -420.891462)
		(end 284.63113 -421.377618)
		(width 0.381)
		(layer "B.Cu")
		(net "P3V3_9ZXL045_P0_VDDA")
	)
	(segment
		(start 287.631124 -415.316924)
		(end 287.777174 -415.170874)
		(width 0.2286)
		(layer "F.Cu")
		(net "P3V3_9ZXL045_P0_VDD")
	)
	(segment
		(start 285.631128 -415.948114)
		(end 285.631128 -415.26841)
		(width 0.2286)
		(layer "F.Cu")
		(net "P3V3_9ZXL045_P0_VDD")
	)
	(segment
		(start 285.631128 -420.697914)
		(end 285.631128 -421.342566)
		(width 0.2286)
		(layer "F.Cu")
		(net "P3V3_9ZXL045_P0_VDD")
	)
	(segment
		(start 287.631124 -420.697914)
		(end 287.631124 -421.377618)
		(width 0.2286)
		(layer "F.Cu")
		(net "P3V3_9ZXL045_P0_VDD")
	)
	(segment
		(start 287.631124 -415.948114)
		(end 287.631124 -415.316924)
		(width 0.2286)
		(layer "F.Cu")
		(net "P3V3_9ZXL045_P0_VDD")
	)
	(segment
		(start 285.631128 -421.342566)
		(end 285.596076 -421.377618)
		(width 0.2286)
		(layer "F.Cu")
		(net "P3V3_9ZXL045_P0_VDD")
	)
	(segment
		(start 288.255964 -418.57295)
		(end 288.935668 -418.57295)
		(width 0.2286)
		(layer "F.Cu")
		(net "P3V3_9ZXL045_P0_VDD")
	)
	(via
		(at 285.596076 -421.377618)
		(size 0.508)
		(drill 0.254)
		(layers "F.Cu" "B.Cu")
		(net "P3V3_9ZXL045_P0_VDD")
	)
	(via
		(at 287.631124 -421.377618)
		(size 0.508)
		(drill 0.254)
		(layers "F.Cu" "B.Cu")
		(net "P3V3_9ZXL045_P0_VDD")
	)
	(via
		(at 288.935668 -418.57295)
		(size 0.508)
		(drill 0.254)
		(layers "F.Cu" "B.Cu")
		(net "P3V3_9ZXL045_P0_VDD")
	)
	(via
		(at 287.777174 -415.170874)
		(size 0.508)
		(drill 0.254)
		(layers "F.Cu" "B.Cu")
		(net "P3V3_9ZXL045_P0_VDD")
	)
	(via
		(at 283.752544 -414.132014)
		(size 0.508)
		(drill 0.254)
		(layers "F.Cu" "B.Cu")
		(net "P3V3_9ZXL045_P0_VDD")
	)
	(via
		(at 285.631128 -415.26841)
		(size 0.508)
		(drill 0.254)
		(layers "F.Cu" "B.Cu")
		(net "P3V3_9ZXL045_P0_VDD")
	)
	(via
		(at 283.028644 -414.148778)
		(size 0.508)
		(drill 0.254)
		(layers "F.Cu" "B.Cu")
		(net "P3V3_9ZXL045_P0_VDD")
	)
	(segment
		(start 288.200846 -420.807896)
		(end 287.631124 -421.377618)
		(width 0.381)
		(layer "B.Cu")
		(net "P3V3_9ZXL045_P0_VDD")
	)
	(segment
		(start 288.387028 -419.04285)
		(end 288.465768 -419.04285)
		(width 0.381)
		(layer "B.Cu")
		(net "P3V3_9ZXL045_P0_VDD")
	)
	(segment
		(start 285.23311 -415.855912)
		(end 285.23311 -415.666428)
		(width 0.381)
		(layer "B.Cu")
		(net "P3V3_9ZXL045_P0_VDD")
	)
	(segment
		(start 285.299912 -421.046402)
		(end 285.596076 -421.342566)
		(width 0.381)
		(layer "B.Cu")
		(net "P3V3_9ZXL045_P0_VDD")
	)
	(segment
		(start 286.893 -415.39795)
		(end 287.550098 -415.39795)
		(width 0.3556)
		(layer "B.Cu")
		(net "P3V3_9ZXL045_P0_VDD")
	)
	(segment
		(start 288.200846 -420.78148)
		(end 288.200846 -420.807896)
		(width 0.381)
		(layer "B.Cu")
		(net "P3V3_9ZXL045_P0_VDD")
	)
	(segment
		(start 288.465768 -419.04285)
		(end 288.935668 -418.57295)
		(width 0.381)
		(layer "B.Cu")
		(net "P3V3_9ZXL045_P0_VDD")
	)
	(segment
		(start 285.23311 -415.666428)
		(end 285.631128 -415.26841)
		(width 0.381)
		(layer "B.Cu")
		(net "P3V3_9ZXL045_P0_VDD")
	)
	(segment
		(start 285.299912 -420.750492)
		(end 285.299912 -421.046402)
		(width 0.381)
		(layer "B.Cu")
		(net "P3V3_9ZXL045_P0_VDD")
	)
	(segment
		(start 287.550098 -415.39795)
		(end 287.777174 -415.170874)
		(width 0.3556)
		(layer "B.Cu")
		(net "P3V3_9ZXL045_P0_VDD")
	)
	(segment
		(start 285.596076 -421.342566)
		(end 285.596076 -421.377618)
		(width 0.381)
		(layer "B.Cu")
		(net "P3V3_9ZXL045_P0_VDD")
	)
	(via
		(at 283.3243 -427.992794)
		(size 0.762)
		(drill 0.381)
		(layers "F.Cu" "B.Cu")
		(net "P3V3_9ZXL045_P0")
	)
	(segment
		(start 233.548682 -293.461948)
		(end 233.623866 -293.537132)
		(width 0.254)
		(layer "F.Cu")
		(net "P1V8_RETIMER_CPU1_VCC")
	)
	(segment
		(start 234.301538 -293.5351)
		(end 233.625898 -293.5351)
		(width 0.254)
		(layer "F.Cu")
		(net "P1V8_RETIMER_CPU1_VCC")
	)
	(segment
		(start 232.827068 -293.461948)
		(end 233.548682 -293.461948)
		(width 0.254)
		(layer "F.Cu")
		(net "P1V8_RETIMER_CPU1_VCC")
	)
	(segment
		(start 233.625898 -293.5351)
		(end 233.623866 -293.537132)
		(width 0.254)
		(layer "F.Cu")
		(net "P1V8_RETIMER_CPU1_VCC")
	)
	(via
		(at 233.623866 -293.537132)
		(size 0.508)
		(drill 0.254)
		(layers "F.Cu" "B.Cu")
		(net "P1V8_RETIMER_CPU1_VCC")
	)
	(segment
		(start 231.162098 -292.312852)
		(end 232.386378 -293.537132)
		(width 0.254)
		(layer "B.Cu")
		(net "P1V8_RETIMER_CPU1_VCC")
	)
	(segment
		(start 229.993698 -289.933888)
		(end 231.162098 -291.102288)
		(width 0.254)
		(layer "B.Cu")
		(net "P1V8_RETIMER_CPU1_VCC")
	)
	(segment
		(start 231.162098 -291.102288)
		(end 231.162098 -292.312852)
		(width 0.254)
		(layer "B.Cu")
		(net "P1V8_RETIMER_CPU1_VCC")
	)
	(segment
		(start 232.386378 -293.537132)
		(end 233.623866 -293.537132)
		(width 0.254)
		(layer "B.Cu")
		(net "P1V8_RETIMER_CPU1_VCC")
	)
	(segment
		(start 227.99167 -291.863526)
		(end 228.09327 -291.761926)
		(width 0.1778)
		(layer "F.Cu")
		(net "P1V8_RETIMER_CPU1_REF")
	)
	(segment
		(start 228.09327 -291.761926)
		(end 230.026972 -291.761926)
		(width 0.1778)
		(layer "F.Cu")
		(net "P1V8_RETIMER_CPU1_REF")
	)
	(segment
		(start 228.67112 -292.295326)
		(end 228.80447 -292.161976)
		(width 0.1778)
		(layer "F.Cu")
		(net "P1V8_RETIMER_CPU1_MODE")
	)
	(segment
		(start 228.80447 -292.161976)
		(end 230.026972 -292.161976)
		(width 0.1778)
		(layer "F.Cu")
		(net "P1V8_RETIMER_CPU1_MODE")
	)
	(via
		(at 228.67112 -292.295326)
		(size 0.508)
		(drill 0.254)
		(layers "F.Cu" "B.Cu")
		(net "P1V8_RETIMER_CPU1_MODE")
	)
	(segment
		(start 227.983542 -290.564062)
		(end 227.983542 -291.607748)
		(width 0.10668)
		(layer "B.Cu")
		(net "P1V8_RETIMER_CPU1_MODE")
	)
	(segment
		(start 227.983542 -291.607748)
		(end 228.67112 -292.295326)
		(width 0.10668)
		(layer "B.Cu")
		(net "P1V8_RETIMER_CPU1_MODE")
	)
	(segment
		(start 229.480618 -290.961826)
		(end 230.026972 -290.961826)
		(width 0.1778)
		(layer "F.Cu")
		(net "P1V8_RETIMER_CPU1_FB")
	)
	(segment
		(start 226.915472 -289.941762)
		(end 225.899472 -289.941762)
		(width 0.254)
		(layer "F.Cu")
		(net "P1V8_RETIMER_CPU1_FB")
	)
	(segment
		(start 229.030022 -290.688522)
		(end 229.480618 -290.961826)
		(width 0.1778)
		(layer "F.Cu")
		(net "P1V8_RETIMER_CPU1_FB")
	)
	(segment
		(start 228.29647 -290.181792)
		(end 227.948998 -289.941762)
		(width 0.254)
		(layer "F.Cu")
		(net "P1V8_RETIMER_CPU1_FB")
	)
	(segment
		(start 228.66096 -290.43884)
		(end 228.29647 -290.181792)
		(width 0.254)
		(layer "F.Cu")
		(net "P1V8_RETIMER_CPU1_FB")
	)
	(segment
		(start 228.66096 -290.43884)
		(end 229.030022 -290.688522)
		(width 0.254)
		(layer "F.Cu")
		(net "P1V8_RETIMER_CPU1_FB")
	)
	(segment
		(start 226.915472 -289.941762)
		(end 227.948998 -289.941762)
		(width 0.254)
		(layer "F.Cu")
		(net "P1V8_RETIMER_CPU1_FB")
	)
	(via
		(at 228.66096 -290.43884)
		(size 0.4064)
		(drill 0.2032)
		(layers "F.Cu" "B.Cu")
		(net "P1V8_RETIMER_CPU1_FB")
	)
	(segment
		(start 229.4382 -290.56203)
		(end 230.026972 -290.56203)
		(width 0.10668)
		(layer "F.Cu")
		(net "P1V8_RETIMER_CPU1_EN")
	)
	(segment
		(start 177.129186 -183.814212)
		(end 177.129186 -172.449236)
		(width 0.1524)
		(layer "F.Cu")
		(net "P1V8_RETIMER_CPU1_EN")
	)
	(segment
		(start 178.448462 -185.133488)
		(end 177.129186 -183.814212)
		(width 0.1524)
		(layer "F.Cu")
		(net "P1V8_RETIMER_CPU1_EN")
	)
	(segment
		(start 178.448462 -186.895994)
		(end 178.448462 -185.133488)
		(width 0.1524)
		(layer "F.Cu")
		(net "P1V8_RETIMER_CPU1_EN")
	)
	(segment
		(start 225.875342 -288.15538)
		(end 227.03155 -288.15538)
		(width 0.10668)
		(layer "F.Cu")
		(net "P1V8_RETIMER_CPU1_EN")
	)
	(segment
		(start 227.888292 -289.012122)
		(end 229.4382 -290.56203)
		(width 0.10668)
		(layer "F.Cu")
		(net "P1V8_RETIMER_CPU1_EN")
	)
	(segment
		(start 169.344594 -128.24333)
		(end 168.844214 -128.74371)
		(width 0.1524)
		(layer "F.Cu")
		(net "P1V8_RETIMER_CPU1_EN")
	)
	(segment
		(start 177.129186 -172.449236)
		(end 176.488598 -171.808648)
		(width 0.1524)
		(layer "F.Cu")
		(net "P1V8_RETIMER_CPU1_EN")
	)
	(segment
		(start 227.03155 -288.15538)
		(end 227.888292 -289.012122)
		(width 0.10668)
		(layer "F.Cu")
		(net "P1V8_RETIMER_CPU1_EN")
	)
	(via
		(at 178.448462 -186.895994)
		(size 0.508)
		(drill 0.254)
		(layers "F.Cu" "B.Cu")
		(net "P1V8_RETIMER_CPU1_EN")
	)
	(via
		(at 225.875342 -288.15538)
		(size 0.508)
		(drill 0.254)
		(layers "F.Cu" "B.Cu")
		(net "P1V8_RETIMER_CPU1_EN")
	)
	(via
		(at 185.34888 -188.671454)
		(size 0.6604)
		(drill 0.3302)
		(layers "F.Cu" "B.Cu")
		(net "P1V8_RETIMER_CPU1_EN")
	)
	(via
		(at 168.844214 -128.74371)
		(size 0.508)
		(drill 0.254)
		(layers "F.Cu" "B.Cu")
		(net "P1V8_RETIMER_CPU1_EN")
	)
	(via
		(at 176.488598 -171.808648)
		(size 0.508)
		(drill 0.254)
		(layers "F.Cu" "B.Cu")
		(net "P1V8_RETIMER_CPU1_EN")
	)
	(segment
		(start 180.223922 -188.671454)
		(end 185.34888 -188.671454)
		(width 0.1524)
		(layer "B.Cu")
		(net "P1V8_RETIMER_CPU1_EN")
	)
	(segment
		(start 190.986664 -185.437526)
		(end 192.259966 -186.710828)
		(width 0.1524)
		(layer "B.Cu")
		(net "P1V8_RETIMER_CPU1_EN")
	)
	(segment
		(start 186.248294 -187.77204)
		(end 186.248294 -186.464702)
		(width 0.1524)
		(layer "B.Cu")
		(net "P1V8_RETIMER_CPU1_EN")
	)
	(segment
		(start 212.736176 -191.901826)
		(end 212.736176 -277.842472)
		(width 0.1524)
		(layer "B.Cu")
		(net "P1V8_RETIMER_CPU1_EN")
	)
	(segment
		(start 222.015812 -287.122108)
		(end 224.84207 -287.122108)
		(width 0.1524)
		(layer "B.Cu")
		(net "P1V8_RETIMER_CPU1_EN")
	)
	(segment
		(start 209.210402 -188.376052)
		(end 212.736176 -191.901826)
		(width 0.1524)
		(layer "B.Cu")
		(net "P1V8_RETIMER_CPU1_EN")
	)
	(segment
		(start 187.27547 -185.437526)
		(end 190.986664 -185.437526)
		(width 0.1524)
		(layer "B.Cu")
		(net "P1V8_RETIMER_CPU1_EN")
	)
	(segment
		(start 224.84207 -287.122108)
		(end 225.875342 -288.15538)
		(width 0.1524)
		(layer "B.Cu")
		(net "P1V8_RETIMER_CPU1_EN")
	)
	(segment
		(start 192.259966 -187.630816)
		(end 193.005202 -188.376052)
		(width 0.1524)
		(layer "B.Cu")
		(net "P1V8_RETIMER_CPU1_EN")
	)
	(segment
		(start 193.005202 -188.376052)
		(end 209.210402 -188.376052)
		(width 0.1524)
		(layer "B.Cu")
		(net "P1V8_RETIMER_CPU1_EN")
	)
	(segment
		(start 185.34888 -188.671454)
		(end 186.248294 -187.77204)
		(width 0.1524)
		(layer "B.Cu")
		(net "P1V8_RETIMER_CPU1_EN")
	)
	(segment
		(start 192.259966 -186.710828)
		(end 192.259966 -187.630816)
		(width 0.1524)
		(layer "B.Cu")
		(net "P1V8_RETIMER_CPU1_EN")
	)
	(segment
		(start 212.736176 -277.842472)
		(end 222.015812 -287.122108)
		(width 0.1524)
		(layer "B.Cu")
		(net "P1V8_RETIMER_CPU1_EN")
	)
	(segment
		(start 178.448462 -186.895994)
		(end 180.223922 -188.671454)
		(width 0.1524)
		(layer "B.Cu")
		(net "P1V8_RETIMER_CPU1_EN")
	)
	(segment
		(start 186.248294 -186.464702)
		(end 187.27547 -185.437526)
		(width 0.1524)
		(layer "B.Cu")
		(net "P1V8_RETIMER_CPU1_EN")
	)
	(segment
		(start 173.330616 -167.319706)
		(end 173.330616 -139.919456)
		(width 0.1524)
		(layer "In11.Cu")
		(net "P1V8_RETIMER_CPU1_EN")
	)
	(segment
		(start 169.427398 -136.016492)
		(end 169.427398 -129.326894)
		(width 0.1524)
		(layer "In11.Cu")
		(net "P1V8_RETIMER_CPU1_EN")
	)
	(segment
		(start 176.488598 -171.808648)
		(end 176.488598 -170.477688)
		(width 0.1524)
		(layer "In11.Cu")
		(net "P1V8_RETIMER_CPU1_EN")
	)
	(segment
		(start 173.330616 -139.919456)
		(end 169.427398 -136.016492)
		(width 0.1524)
		(layer "In11.Cu")
		(net "P1V8_RETIMER_CPU1_EN")
	)
	(segment
		(start 169.427398 -129.326894)
		(end 168.844214 -128.74371)
		(width 0.1524)
		(layer "In11.Cu")
		(net "P1V8_RETIMER_CPU1_EN")
	)
	(segment
		(start 176.488598 -170.477688)
		(end 173.330616 -167.319706)
		(width 0.1524)
		(layer "In11.Cu")
		(net "P1V8_RETIMER_CPU1_EN")
	)
	(segment
		(start 228.593904 -292.988238)
		(end 229.42931 -292.562026)
		(width 0.1778)
		(layer "F.Cu")
		(net "P1V8_RETIMER_CPU1_CS")
	)
	(segment
		(start 229.42931 -292.562026)
		(end 230.026972 -292.562026)
		(width 0.1778)
		(layer "F.Cu")
		(net "P1V8_RETIMER_CPU1_CS")
	)
	(segment
		(start 227.99167 -292.988238)
		(end 228.593904 -292.988238)
		(width 0.1778)
		(layer "F.Cu")
		(net "P1V8_RETIMER_CPU1_CS")
	)
	(segment
		(start 171.478194 -31.102808)
		(end 173.484794 -31.102808)
		(width 0.10668)
		(layer "F.Cu")
		(net "P12V_SCM_FLTB_N")
	)
	(segment
		(start 171.160694 -30.785308)
		(end 171.478194 -31.102808)
		(width 0.10668)
		(layer "F.Cu")
		(net "P12V_SCM_FLTB_N")
	)
	(segment
		(start 186.817 -37.719)
		(end 186.817 -36.322)
		(width 0.10668)
		(layer "F.Cu")
		(net "P12V_SCM_FLTB_N")
	)
	(segment
		(start 187.96 -45.085)
		(end 187.96 -38.862)
		(width 0.10668)
		(layer "F.Cu")
		(net "P12V_SCM_FLTB_N")
	)
	(segment
		(start 189.357 -46.482)
		(end 187.96 -45.085)
		(width 0.10668)
		(layer "F.Cu")
		(net "P12V_SCM_FLTB_N")
	)
	(segment
		(start 189.357 -50.65395)
		(end 189.357 -46.482)
		(width 0.10668)
		(layer "F.Cu")
		(net "P12V_SCM_FLTB_N")
	)
	(segment
		(start 173.484794 -31.102808)
		(end 173.616366 -30.971236)
		(width 0.10668)
		(layer "F.Cu")
		(net "P12V_SCM_FLTB_N")
	)
	(segment
		(start 173.616366 -30.971236)
		(end 173.616366 -30.446472)
		(width 0.10668)
		(layer "F.Cu")
		(net "P12V_SCM_FLTB_N")
	)
	(segment
		(start 187.96 -38.862)
		(end 186.817 -37.719)
		(width 0.10668)
		(layer "F.Cu")
		(net "P12V_SCM_FLTB_N")
	)
	(via
		(at 186.817 -36.322)
		(size 0.508)
		(drill 0.254)
		(layers "F.Cu" "B.Cu")
		(net "P12V_SCM_FLTB_N")
	)
	(via
		(at 174.498 -30.353)
		(size 0.508)
		(drill 0.254)
		(layers "F.Cu" "B.Cu")
		(net "P12V_SCM_FLTB_N")
	)
	(via
		(at 171.160694 -30.785308)
		(size 0.762)
		(drill 0.381)
		(layers "F.Cu" "B.Cu")
		(net "P12V_SCM_FLTB_N")
	)
	(segment
		(start 175.895 -30.353)
		(end 176.432718 -30.890718)
		(width 0.11684)
		(layer "In15.Cu")
		(net "P12V_SCM_FLTB_N")
	)
	(segment
		(start 176.432718 -32.014922)
		(end 179.723796 -35.306)
		(width 0.11684)
		(layer "In15.Cu")
		(net "P12V_SCM_FLTB_N")
	)
	(segment
		(start 174.498 -30.353)
		(end 175.895 -30.353)
		(width 0.11684)
		(layer "In15.Cu")
		(net "P12V_SCM_FLTB_N")
	)
	(segment
		(start 185.801 -35.306)
		(end 186.817 -36.322)
		(width 0.11684)
		(layer "In15.Cu")
		(net "P12V_SCM_FLTB_N")
	)
	(segment
		(start 176.432718 -30.890718)
		(end 176.432718 -32.014922)
		(width 0.11684)
		(layer "In15.Cu")
		(net "P12V_SCM_FLTB_N")
	)
	(segment
		(start 179.723796 -35.306)
		(end 185.801 -35.306)
		(width 0.11684)
		(layer "In15.Cu")
		(net "P12V_SCM_FLTB_N")
	)
	(segment
		(start 189.972696 -51.45405)
		(end 190.246 -51.180746)
		(width 0.10668)
		(layer "F.Cu")
		(net "P12V_SCM_FAULT_R_N")
	)
	(segment
		(start 190.754 -53.848)
		(end 189.611 -52.705)
		(width 0.10668)
		(layer "F.Cu")
		(net "P12V_SCM_FAULT_R_N")
	)
	(segment
		(start 190.246 -48.566324)
		(end 191.703198 -47.109126)
		(width 0.10668)
		(layer "F.Cu")
		(net "P12V_SCM_FAULT_R_N")
	)
	(segment
		(start 189.357 -51.45405)
		(end 189.972696 -51.45405)
		(width 0.10668)
		(layer "F.Cu")
		(net "P12V_SCM_FAULT_R_N")
	)
	(segment
		(start 189.611 -52.705)
		(end 189.357 -52.451)
		(width 0.10668)
		(layer "F.Cu")
		(net "P12V_SCM_FAULT_R_N")
	)
	(segment
		(start 190.246 -51.180746)
		(end 190.246 -48.566324)
		(width 0.10668)
		(layer "F.Cu")
		(net "P12V_SCM_FAULT_R_N")
	)
	(segment
		(start 189.357 -52.451)
		(end 189.357 -51.45405)
		(width 0.10668)
		(layer "F.Cu")
		(net "P12V_SCM_FAULT_R_N")
	)
	(segment
		(start 193.167 -27.79395)
		(end 193.167 -27.128978)
		(width 0.10668)
		(layer "F.Cu")
		(net "P12V_SCM_FAULT_R_N")
	)
	(segment
		(start 193.089022 -26.365962)
		(end 193.089022 -27.051)
		(width 0.10668)
		(layer "F.Cu")
		(net "P12V_SCM_FAULT_R_N")
	)
	(segment
		(start 193.167 -27.128978)
		(end 193.089022 -27.051)
		(width 0.10668)
		(layer "F.Cu")
		(net "P12V_SCM_FAULT_R_N")
	)
	(segment
		(start 190.754 -54.04104)
		(end 190.754 -53.848)
		(width 0.10668)
		(layer "F.Cu")
		(net "P12V_SCM_FAULT_R_N")
	)
	(via
		(at 189.611 -52.705)
		(size 0.762)
		(drill 0.381)
		(layers "F.Cu" "B.Cu")
		(net "P12V_SCM_FAULT_R_N")
	)
	(via
		(at 193.089022 -27.051)
		(size 0.508)
		(drill 0.254)
		(layers "F.Cu" "B.Cu")
		(net "P12V_SCM_FAULT_R_N")
	)
	(via
		(at 191.703198 -47.109126)
		(size 0.508)
		(drill 0.254)
		(layers "F.Cu" "B.Cu")
		(net "P12V_SCM_FAULT_R_N")
	)
	(segment
		(start 193.089022 -31.04388)
		(end 193.089022 -45.723302)
		(width 0.11684)
		(layer "In11.Cu")
		(net "P12V_SCM_FAULT_R_N")
	)
	(segment
		(start 193.089022 -45.723302)
		(end 191.703198 -47.109126)
		(width 0.11684)
		(layer "In11.Cu")
		(net "P12V_SCM_FAULT_R_N")
	)
	(segment
		(start 193.089022 -27.051)
		(end 191.90462 -28.235402)
		(width 0.11684)
		(layer "In11.Cu")
		(net "P12V_SCM_FAULT_R_N")
	)
	(segment
		(start 191.90462 -29.859478)
		(end 193.089022 -31.04388)
		(width 0.11684)
		(layer "In11.Cu")
		(net "P12V_SCM_FAULT_R_N")
	)
	(segment
		(start 191.90462 -28.235402)
		(end 191.90462 -29.859478)
		(width 0.11684)
		(layer "In11.Cu")
		(net "P12V_SCM_FAULT_R_N")
	)
	(segment
		(start 192.278 -28.447746)
		(end 192.424304 -28.59405)
		(width 0.10668)
		(layer "F.Cu")
		(net "P12V_SCM_FAULT_N")
	)
	(segment
		(start 192.424304 -28.59405)
		(end 193.167 -28.59405)
		(width 0.10668)
		(layer "F.Cu")
		(net "P12V_SCM_FAULT_N")
	)
	(segment
		(start 191.509396 -25.393396)
		(end 192.278 -26.162)
		(width 0.10668)
		(layer "F.Cu")
		(net "P12V_SCM_FAULT_N")
	)
	(segment
		(start 191.238886 -25.393396)
		(end 191.509396 -25.393396)
		(width 0.10668)
		(layer "F.Cu")
		(net "P12V_SCM_FAULT_N")
	)
	(segment
		(start 192.278 -26.162)
		(end 192.278 -28.447746)
		(width 0.10668)
		(layer "F.Cu")
		(net "P12V_SCM_FAULT_N")
	)
	(via
		(at 192.424304 -28.59405)
		(size 0.508)
		(drill 0.254)
		(layers "F.Cu" "B.Cu")
		(net "P12V_SCM_FAULT_N")
	)
	(segment
		(start 145.26895 -117.348)
		(end 145.26895 -118.364)
		(width 0.10668)
		(layer "F.Cu")
		(net "P12V_AUX_UV_TRIGGER")
	)
	(segment
		(start 145.26895 -116.444522)
		(end 145.26895 -115.443)
		(width 0.10668)
		(layer "F.Cu")
		(net "P12V_AUX_UV_TRIGGER")
	)
	(segment
		(start 142.76705 -119.106696)
		(end 143.448786 -118.42496)
		(width 0.10668)
		(layer "F.Cu")
		(net "P12V_AUX_UV_TRIGGER")
	)
	(segment
		(start 145.26895 -118.364)
		(end 145.20799 -118.42496)
		(width 0.10668)
		(layer "F.Cu")
		(net "P12V_AUX_UV_TRIGGER")
	)
	(segment
		(start 145.26895 -117.348)
		(end 145.26895 -116.444522)
		(width 0.10668)
		(layer "F.Cu")
		(net "P12V_AUX_UV_TRIGGER")
	)
	(segment
		(start 142.76705 -120.269)
		(end 142.76705 -119.106696)
		(width 0.10668)
		(layer "F.Cu")
		(net "P12V_AUX_UV_TRIGGER")
	)
	(segment
		(start 145.20799 -118.42496)
		(end 143.71701 -118.42496)
		(width 0.10668)
		(layer "F.Cu")
		(net "P12V_AUX_UV_TRIGGER")
	)
	(segment
		(start 143.448786 -118.42496)
		(end 143.71701 -118.42496)
		(width 0.10668)
		(layer "F.Cu")
		(net "P12V_AUX_UV_TRIGGER")
	)
	(via
		(at 145.26895 -116.444522)
		(size 0.762)
		(drill 0.381)
		(layers "F.Cu" "B.Cu")
		(net "P12V_AUX_UV_TRIGGER")
	)
	(segment
		(start 130.70205 -111.31804)
		(end 131.87299 -111.31804)
		(width 0.10668)
		(layer "F.Cu")
		(net "P12V_AUX_UV_ADR_TRIGGER")
	)
	(segment
		(start 132.715 -109.87405)
		(end 131.699 -109.87405)
		(width 0.10668)
		(layer "F.Cu")
		(net "P12V_AUX_UV_ADR_TRIGGER")
	)
	(segment
		(start 132.73405 -109.855)
		(end 133.71195 -109.855)
		(width 0.10668)
		(layer "F.Cu")
		(net "P12V_AUX_UV_ADR_TRIGGER")
	)
	(segment
		(start 131.699 -109.87405)
		(end 130.048 -109.87405)
		(width 0.10668)
		(layer "F.Cu")
		(net "P12V_AUX_UV_ADR_TRIGGER")
	)
	(segment
		(start 130.351022 -110.967012)
		(end 130.70205 -111.31804)
		(width 0.10668)
		(layer "F.Cu")
		(net "P12V_AUX_UV_ADR_TRIGGER")
	)
	(segment
		(start 130.048 -110.66399)
		(end 130.351022 -110.967012)
		(width 0.10668)
		(layer "F.Cu")
		(net "P12V_AUX_UV_ADR_TRIGGER")
	)
	(segment
		(start 132.715 -109.87405)
		(end 132.73405 -109.855)
		(width 0.10668)
		(layer "F.Cu")
		(net "P12V_AUX_UV_ADR_TRIGGER")
	)
	(segment
		(start 130.048 -109.87405)
		(end 130.048 -110.66399)
		(width 0.10668)
		(layer "F.Cu")
		(net "P12V_AUX_UV_ADR_TRIGGER")
	)
	(via
		(at 130.351022 -110.967012)
		(size 0.762)
		(drill 0.381)
		(layers "F.Cu" "B.Cu")
		(net "P12V_AUX_UV_ADR_TRIGGER")
	)
	(segment
		(start 22.274784 -392.396726)
		(end 22.630384 -392.041126)
		(width 0.2032)
		(layer "F.Cu")
		(net "P0V9_RETIMER_CPU1_VOS2")
	)
	(segment
		(start 21.912834 -392.396726)
		(end 22.274784 -392.396726)
		(width 0.2032)
		(layer "F.Cu")
		(net "P0V9_RETIMER_CPU1_VOS2")
	)
	(segment
		(start 22.983444 -391.129266)
		(end 23.240746 -391.129266)
		(width 0.2032)
		(layer "F.Cu")
		(net "P0V9_RETIMER_CPU1_VOS2")
	)
	(segment
		(start 22.630384 -392.041126)
		(end 22.630384 -391.482326)
		(width 0.2032)
		(layer "F.Cu")
		(net "P0V9_RETIMER_CPU1_VOS2")
	)
	(segment
		(start 22.630384 -391.482326)
		(end 22.983444 -391.129266)
		(width 0.2032)
		(layer "F.Cu")
		(net "P0V9_RETIMER_CPU1_VOS2")
	)
	(segment
		(start 13.511784 -391.431526)
		(end 13.814044 -391.129266)
		(width 0.2286)
		(layer "F.Cu")
		(net "P0V9_RETIMER_CPU1_VOS1")
	)
	(segment
		(start 13.814044 -391.129266)
		(end 14.162024 -391.129266)
		(width 0.2286)
		(layer "F.Cu")
		(net "P0V9_RETIMER_CPU1_VOS1")
	)
	(segment
		(start 13.511784 -391.615676)
		(end 13.511784 -391.431526)
		(width 0.2286)
		(layer "F.Cu")
		(net "P0V9_RETIMER_CPU1_VOS1")
	)
	(segment
		(start 12.876784 -392.250676)
		(end 13.511784 -391.615676)
		(width 0.2286)
		(layer "F.Cu")
		(net "P0V9_RETIMER_CPU1_VOS1")
	)
	(segment
		(start 10.847832 -409.294584)
		(end 11.590782 -409.294584)
		(width 0.1778)
		(layer "F.Cu")
		(net "P0V9_RETIMER_CPU1_VMON")
	)
	(segment
		(start 11.590782 -409.294584)
		(end 11.895582 -409.599384)
		(width 0.1778)
		(layer "F.Cu")
		(net "P0V9_RETIMER_CPU1_VMON")
	)
	(segment
		(start 11.895582 -409.599384)
		(end 12.00912 -409.712922)
		(width 0.1778)
		(layer "F.Cu")
		(net "P0V9_RETIMER_CPU1_VMON")
	)
	(segment
		(start 10.466832 -409.675584)
		(end 10.847832 -409.294584)
		(width 0.1778)
		(layer "F.Cu")
		(net "P0V9_RETIMER_CPU1_VMON")
	)
	(segment
		(start 12.00912 -409.712922)
		(end 12.780772 -409.712922)
		(width 0.1778)
		(layer "F.Cu")
		(net "P0V9_RETIMER_CPU1_VMON")
	)
	(via
		(at 11.895582 -409.599384)
		(size 0.508)
		(drill 0.254)
		(layers "F.Cu" "B.Cu")
		(net "P0V9_RETIMER_CPU1_VMON")
	)
	(segment
		(start 11.895582 -409.599384)
		(end 11.920982 -409.624784)
		(width 0.254)
		(layer "B.Cu")
		(net "P0V9_RETIMER_CPU1_VMON")
	)
	(segment
		(start 12.234418 -413.488124)
		(end 12.253468 -413.469074)
		(width 0.254)
		(layer "B.Cu")
		(net "P0V9_RETIMER_CPU1_VMON")
	)
	(segment
		(start 12.841732 -409.624784)
		(end 12.841732 -412.264606)
		(width 0.254)
		(layer "B.Cu")
		(net "P0V9_RETIMER_CPU1_VMON")
	)
	(segment
		(start 12.841732 -412.264606)
		(end 12.253468 -412.85287)
		(width 0.254)
		(layer "B.Cu")
		(net "P0V9_RETIMER_CPU1_VMON")
	)
	(segment
		(start 12.253468 -413.469074)
		(end 12.253468 -412.85287)
		(width 0.254)
		(layer "B.Cu")
		(net "P0V9_RETIMER_CPU1_VMON")
	)
	(segment
		(start 11.920982 -409.624784)
		(end 12.841732 -409.624784)
		(width 0.254)
		(layer "B.Cu")
		(net "P0V9_RETIMER_CPU1_VMON")
	)
	(segment
		(start 12.234418 -413.97682)
		(end 12.234418 -413.488124)
		(width 0.254)
		(layer "B.Cu")
		(net "P0V9_RETIMER_CPU1_VMON")
	)
	(segment
		(start 10.720832 -408.151584)
		(end 10.466832 -408.405584)
		(width 0.381)
		(layer "F.Cu")
		(net "P0V9_RETIMER_CPU1_VINSEN")
	)
	(segment
		(start 11.801094 -408.786584)
		(end 12.327382 -409.312872)
		(width 0.1778)
		(layer "F.Cu")
		(net "P0V9_RETIMER_CPU1_VINSEN")
	)
	(segment
		(start 12.327382 -409.312872)
		(end 12.780772 -409.312872)
		(width 0.1778)
		(layer "F.Cu")
		(net "P0V9_RETIMER_CPU1_VINSEN")
	)
	(segment
		(start 11.082782 -408.151584)
		(end 10.720832 -408.151584)
		(width 0.381)
		(layer "F.Cu")
		(net "P0V9_RETIMER_CPU1_VINSEN")
	)
	(segment
		(start 10.466832 -408.551888)
		(end 10.701528 -408.786584)
		(width 0.1778)
		(layer "F.Cu")
		(net "P0V9_RETIMER_CPU1_VINSEN")
	)
	(segment
		(start 10.466832 -408.405584)
		(end 10.466832 -408.551888)
		(width 0.1778)
		(layer "F.Cu")
		(net "P0V9_RETIMER_CPU1_VINSEN")
	)
	(segment
		(start 10.701528 -408.786584)
		(end 11.801094 -408.786584)
		(width 0.1778)
		(layer "F.Cu")
		(net "P0V9_RETIMER_CPU1_VINSEN")
	)
	(via
		(at 11.082782 -408.151584)
		(size 0.508)
		(drill 0.254)
		(layers "F.Cu" "B.Cu")
		(net "P0V9_RETIMER_CPU1_VINSEN")
	)
	(segment
		(start 10.466832 -406.119584)
		(end 10.466832 -407.262584)
		(width 0.254)
		(layer "B.Cu")
		(net "P0V9_RETIMER_CPU1_VINSEN")
	)
	(segment
		(start 10.466832 -407.262584)
		(end 10.466832 -407.535634)
		(width 0.254)
		(layer "B.Cu")
		(net "P0V9_RETIMER_CPU1_VINSEN")
	)
	(segment
		(start 10.466832 -407.535634)
		(end 11.082782 -408.151584)
		(width 0.254)
		(layer "B.Cu")
		(net "P0V9_RETIMER_CPU1_VINSEN")
	)
	(segment
		(start 19.490182 -409.421584)
		(end 18.855182 -410.056584)
		(width 0.1524)
		(layer "F.Cu")
		(net "P0V9_RETIMER_CPU1_INALERT")
	)
	(segment
		(start 18.798794 -410.112972)
		(end 17.580864 -410.112972)
		(width 0.1524)
		(layer "F.Cu")
		(net "P0V9_RETIMER_CPU1_INALERT")
	)
	(segment
		(start 18.855182 -410.056584)
		(end 18.798794 -410.112972)
		(width 0.1524)
		(layer "F.Cu")
		(net "P0V9_RETIMER_CPU1_INALERT")
	)
	(segment
		(start 20.080732 -409.421584)
		(end 19.490182 -409.421584)
		(width 0.1524)
		(layer "F.Cu")
		(net "P0V9_RETIMER_CPU1_INALERT")
	)
	(via
		(at 18.855182 -410.056584)
		(size 0.762)
		(drill 0.381)
		(layers "F.Cu" "B.Cu")
		(net "P0V9_RETIMER_CPU1_INALERT")
	)
	(segment
		(start 25.353772 -392.759184)
		(end 25.353772 -392.563096)
		(width 0.1778)
		(layer "F.Cu")
		(net "P0V9_RETIMER_CPU1_VCC2")
	)
	(segment
		(start 21.938996 -390.549384)
		(end 21.364194 -390.549384)
		(width 0.381)
		(layer "F.Cu")
		(net "P0V9_RETIMER_CPU1_VCC2")
	)
	(segment
		(start 23.240746 -390.22909)
		(end 22.25929 -390.22909)
		(width 0.1778)
		(layer "F.Cu")
		(net "P0V9_RETIMER_CPU1_VCC2")
	)
	(segment
		(start 25.353772 -392.563096)
		(end 25.4508 -392.466068)
		(width 0.1778)
		(layer "F.Cu")
		(net "P0V9_RETIMER_CPU1_VCC2")
	)
	(segment
		(start 22.25929 -390.22909)
		(end 21.938996 -390.549384)
		(width 0.1778)
		(layer "F.Cu")
		(net "P0V9_RETIMER_CPU1_VCC2")
	)
	(segment
		(start 21.364194 -390.549384)
		(end 21.287994 -390.473184)
		(width 0.381)
		(layer "F.Cu")
		(net "P0V9_RETIMER_CPU1_VCC2")
	)
	(segment
		(start 25.4508 -392.466068)
		(end 25.4508 -391.754106)
		(width 0.1778)
		(layer "F.Cu")
		(net "P0V9_RETIMER_CPU1_VCC2")
	)
	(via
		(at 21.287994 -390.473184)
		(size 0.508)
		(drill 0.254)
		(layers "F.Cu" "B.Cu")
		(net "P0V9_RETIMER_CPU1_VCC2")
	)
	(via
		(at 25.353772 -392.759184)
		(size 0.508)
		(drill 0.254)
		(layers "F.Cu" "B.Cu")
		(net "P0V9_RETIMER_CPU1_VCC2")
	)
	(via
		(at 23.702772 -391.703814)
		(size 0.6604)
		(drill 0.3302)
		(layers "F.Cu" "B.Cu")
		(net "P0V9_RETIMER_CPU1_VCC2")
	)
	(segment
		(start 24.636984 -391.703814)
		(end 25.353772 -392.420602)
		(width 0.381)
		(layer "B.Cu")
		(net "P0V9_RETIMER_CPU1_VCC2")
	)
	(segment
		(start 21.834602 -389.926576)
		(end 22.096984 -389.926576)
		(width 0.381)
		(layer "B.Cu")
		(net "P0V9_RETIMER_CPU1_VCC2")
	)
	(segment
		(start 25.353772 -392.420602)
		(end 25.353772 -392.759184)
		(width 0.381)
		(layer "B.Cu")
		(net "P0V9_RETIMER_CPU1_VCC2")
	)
	(segment
		(start 22.096984 -390.764268)
		(end 23.03653 -391.703814)
		(width 0.381)
		(layer "B.Cu")
		(net "P0V9_RETIMER_CPU1_VCC2")
	)
	(segment
		(start 23.702772 -391.703814)
		(end 24.636984 -391.703814)
		(width 0.381)
		(layer "B.Cu")
		(net "P0V9_RETIMER_CPU1_VCC2")
	)
	(segment
		(start 21.287994 -390.473184)
		(end 21.834602 -389.926576)
		(width 0.381)
		(layer "B.Cu")
		(net "P0V9_RETIMER_CPU1_VCC2")
	)
	(segment
		(start 22.096984 -389.926576)
		(end 22.096984 -390.764268)
		(width 0.381)
		(layer "B.Cu")
		(net "P0V9_RETIMER_CPU1_VCC2")
	)
	(segment
		(start 23.03653 -391.703814)
		(end 23.702772 -391.703814)
		(width 0.381)
		(layer "B.Cu")
		(net "P0V9_RETIMER_CPU1_VCC2")
	)
	(segment
		(start 16.32585 -392.512296)
		(end 16.32585 -392.759184)
		(width 0.1778)
		(layer "F.Cu")
		(net "P0V9_RETIMER_CPU1_VCC1")
	)
	(segment
		(start 16.372078 -391.754106)
		(end 16.372078 -392.466068)
		(width 0.1778)
		(layer "F.Cu")
		(net "P0V9_RETIMER_CPU1_VCC1")
	)
	(segment
		(start 13.411708 -390.22909)
		(end 13.218414 -390.422384)
		(width 0.2032)
		(layer "F.Cu")
		(net "P0V9_RETIMER_CPU1_VCC1")
	)
	(segment
		(start 13.218414 -390.422384)
		(end 12.860274 -390.422384)
		(width 0.2032)
		(layer "F.Cu")
		(net "P0V9_RETIMER_CPU1_VCC1")
	)
	(segment
		(start 12.435078 -390.422384)
		(end 12.231878 -390.219184)
		(width 0.381)
		(layer "F.Cu")
		(net "P0V9_RETIMER_CPU1_VCC1")
	)
	(segment
		(start 12.860274 -390.422384)
		(end 12.435078 -390.422384)
		(width 0.381)
		(layer "F.Cu")
		(net "P0V9_RETIMER_CPU1_VCC1")
	)
	(segment
		(start 14.162024 -390.22909)
		(end 13.411708 -390.22909)
		(width 0.2032)
		(layer "F.Cu")
		(net "P0V9_RETIMER_CPU1_VCC1")
	)
	(segment
		(start 16.372078 -392.466068)
		(end 16.32585 -392.512296)
		(width 0.1778)
		(layer "F.Cu")
		(net "P0V9_RETIMER_CPU1_VCC1")
	)
	(via
		(at 16.32585 -392.759184)
		(size 0.508)
		(drill 0.254)
		(layers "F.Cu" "B.Cu")
		(net "P0V9_RETIMER_CPU1_VCC1")
	)
	(via
		(at 12.231878 -390.219184)
		(size 0.508)
		(drill 0.254)
		(layers "F.Cu" "B.Cu")
		(net "P0V9_RETIMER_CPU1_VCC1")
	)
	(via
		(at 14.6939 -391.703814)
		(size 0.6604)
		(drill 0.3302)
		(layers "F.Cu" "B.Cu")
		(net "P0V9_RETIMER_CPU1_VCC1")
	)
	(segment
		(start 12.524486 -389.926576)
		(end 12.231878 -390.219184)
		(width 0.381)
		(layer "B.Cu")
		(net "P0V9_RETIMER_CPU1_VCC1")
	)
	(segment
		(start 16.32585 -392.471402)
		(end 15.558262 -391.703814)
		(width 0.381)
		(layer "B.Cu")
		(net "P0V9_RETIMER_CPU1_VCC1")
	)
	(segment
		(start 14.6939 -391.703814)
		(end 13.957808 -391.703814)
		(width 0.381)
		(layer "B.Cu")
		(net "P0V9_RETIMER_CPU1_VCC1")
	)
	(segment
		(start 15.558262 -391.703814)
		(end 14.6939 -391.703814)
		(width 0.381)
		(layer "B.Cu")
		(net "P0V9_RETIMER_CPU1_VCC1")
	)
	(segment
		(start 13.957808 -391.703814)
		(end 13.018262 -390.764268)
		(width 0.381)
		(layer "B.Cu")
		(net "P0V9_RETIMER_CPU1_VCC1")
	)
	(segment
		(start 13.018262 -389.926576)
		(end 12.524486 -389.926576)
		(width 0.381)
		(layer "B.Cu")
		(net "P0V9_RETIMER_CPU1_VCC1")
	)
	(segment
		(start 13.018262 -390.764268)
		(end 13.018262 -389.926576)
		(width 0.381)
		(layer "B.Cu")
		(net "P0V9_RETIMER_CPU1_VCC1")
	)
	(segment
		(start 16.32585 -392.759184)
		(end 16.32585 -392.471402)
		(width 0.381)
		(layer "B.Cu")
		(net "P0V9_RETIMER_CPU1_VCC1")
	)
	(segment
		(start 10.466832 -406.119584)
		(end 10.466832 -404.976584)
		(width 0.254)
		(layer "F.Cu")
		(net "P0V9_RETIMER_CPU1_VCC")
	)
	(segment
		(start 12.780772 -408.912822)
		(end 12.435332 -408.912822)
		(width 0.1778)
		(layer "F.Cu")
		(net "P0V9_RETIMER_CPU1_VCC")
	)
	(segment
		(start 12.435332 -408.912822)
		(end 11.907774 -408.385264)
		(width 0.1778)
		(layer "F.Cu")
		(net "P0V9_RETIMER_CPU1_VCC")
	)
	(segment
		(start 11.46048 -407.262584)
		(end 10.466832 -407.262584)
		(width 0.254)
		(layer "F.Cu")
		(net "P0V9_RETIMER_CPU1_VCC")
	)
	(segment
		(start 11.907774 -408.385264)
		(end 11.907774 -407.709878)
		(width 0.1778)
		(layer "F.Cu")
		(net "P0V9_RETIMER_CPU1_VCC")
	)
	(segment
		(start 11.907774 -407.709878)
		(end 11.46048 -407.262584)
		(width 0.1778)
		(layer "F.Cu")
		(net "P0V9_RETIMER_CPU1_VCC")
	)
	(segment
		(start 10.466832 -407.262584)
		(end 10.466832 -406.119584)
		(width 0.254)
		(layer "F.Cu")
		(net "P0V9_RETIMER_CPU1_VCC")
	)
	(via
		(at 11.46048 -407.262584)
		(size 0.762)
		(drill 0.381)
		(layers "F.Cu" "B.Cu")
		(net "P0V9_RETIMER_CPU1_VCC")
	)
	(segment
		(start 11.286744 -410.512768)
		(end 10.980928 -410.818584)
		(width 0.1778)
		(layer "F.Cu")
		(net "P0V9_RETIMER_CPU1_TEMP0")
	)
	(segment
		(start 10.980928 -410.818584)
		(end 10.466832 -410.818584)
		(width 0.1778)
		(layer "F.Cu")
		(net "P0V9_RETIMER_CPU1_TEMP0")
	)
	(segment
		(start 24.642572 -392.57605)
		(end 24.642572 -392.768074)
		(width 0.254)
		(layer "F.Cu")
		(net "P0V9_RETIMER_CPU1_TEMP0")
	)
	(segment
		(start 15.92199 -392.323066)
		(end 15.92199 -391.754106)
		(width 0.2286)
		(layer "F.Cu")
		(net "P0V9_RETIMER_CPU1_TEMP0")
	)
	(segment
		(start 15.64767 -392.895582)
		(end 15.64767 -392.597386)
		(width 0.2286)
		(layer "F.Cu")
		(net "P0V9_RETIMER_CPU1_TEMP0")
	)
	(segment
		(start 25.000712 -392.21791)
		(end 24.642572 -392.57605)
		(width 0.254)
		(layer "F.Cu")
		(net "P0V9_RETIMER_CPU1_TEMP0")
	)
	(segment
		(start 25.000712 -391.754106)
		(end 25.000712 -392.21791)
		(width 0.2286)
		(layer "F.Cu")
		(net "P0V9_RETIMER_CPU1_TEMP0")
	)
	(segment
		(start 12.780772 -410.512768)
		(end 11.286744 -410.512768)
		(width 0.1778)
		(layer "F.Cu")
		(net "P0V9_RETIMER_CPU1_TEMP0")
	)
	(segment
		(start 15.64767 -392.597386)
		(end 15.92199 -392.323066)
		(width 0.2286)
		(layer "F.Cu")
		(net "P0V9_RETIMER_CPU1_TEMP0")
	)
	(segment
		(start 10.466832 -410.818584)
		(end 10.466832 -411.453584)
		(width 0.381)
		(layer "F.Cu")
		(net "P0V9_RETIMER_CPU1_TEMP0")
	)
	(via
		(at 24.642572 -392.768074)
		(size 0.508)
		(drill 0.254)
		(layers "F.Cu" "B.Cu")
		(net "P0V9_RETIMER_CPU1_TEMP0")
	)
	(via
		(at 15.64767 -392.895582)
		(size 0.508)
		(drill 0.254)
		(layers "F.Cu" "B.Cu")
		(net "P0V9_RETIMER_CPU1_TEMP0")
	)
	(via
		(at 10.466832 -411.453584)
		(size 0.508)
		(drill 0.254)
		(layers "F.Cu" "B.Cu")
		(net "P0V9_RETIMER_CPU1_TEMP0")
	)
	(segment
		(start 10.466832 -412.291784)
		(end 10.466832 -411.453584)
		(width 0.254)
		(layer "B.Cu")
		(net "P0V9_RETIMER_CPU1_TEMP0")
	)
	(segment
		(start 21.661882 -400.027648)
		(end 14.473936 -400.027648)
		(width 0.254)
		(layer "In2.Cu")
		(net "P0V9_RETIMER_CPU1_TEMP0")
	)
	(segment
		(start 24.642572 -397.046958)
		(end 21.906738 -399.782792)
		(width 0.254)
		(layer "In2.Cu")
		(net "P0V9_RETIMER_CPU1_TEMP0")
	)
	(segment
		(start 12.711684 -414.241488)
		(end 11.37031 -412.900114)
		(width 0.254)
		(layer "In2.Cu")
		(net "P0V9_RETIMER_CPU1_TEMP0")
	)
	(segment
		(start 21.479002 -407.138124)
		(end 24.520398 -410.17952)
		(width 0.254)
		(layer "In2.Cu")
		(net "P0V9_RETIMER_CPU1_TEMP0")
	)
	(segment
		(start 13.97508 -399.528792)
		(end 13.97508 -398.70761)
		(width 0.254)
		(layer "In2.Cu")
		(net "P0V9_RETIMER_CPU1_TEMP0")
	)
	(segment
		(start 21.906738 -399.782792)
		(end 21.661882 -400.027648)
		(width 0.254)
		(layer "In2.Cu")
		(net "P0V9_RETIMER_CPU1_TEMP0")
	)
	(segment
		(start 24.642572 -392.768074)
		(end 24.642572 -397.046958)
		(width 0.254)
		(layer "In2.Cu")
		(net "P0V9_RETIMER_CPU1_TEMP0")
	)
	(segment
		(start 11.37031 -412.357062)
		(end 10.466832 -411.453584)
		(width 0.254)
		(layer "In2.Cu")
		(net "P0V9_RETIMER_CPU1_TEMP0")
	)
	(segment
		(start 14.970252 -397.712438)
		(end 14.970252 -393.573)
		(width 0.254)
		(layer "In2.Cu")
		(net "P0V9_RETIMER_CPU1_TEMP0")
	)
	(segment
		(start 20.56003 -417.063174)
		(end 17.930114 -417.063174)
		(width 0.254)
		(layer "In2.Cu")
		(net "P0V9_RETIMER_CPU1_TEMP0")
	)
	(segment
		(start 12.711684 -414.606232)
		(end 12.711684 -414.241488)
		(width 0.254)
		(layer "In2.Cu")
		(net "P0V9_RETIMER_CPU1_TEMP0")
	)
	(segment
		(start 16.88465 -416.01771)
		(end 14.123162 -416.01771)
		(width 0.254)
		(layer "In2.Cu")
		(net "P0V9_RETIMER_CPU1_TEMP0")
	)
	(segment
		(start 24.520398 -410.17952)
		(end 24.520398 -413.102806)
		(width 0.254)
		(layer "In2.Cu")
		(net "P0V9_RETIMER_CPU1_TEMP0")
	)
	(segment
		(start 22.794976 -402.78177)
		(end 21.479002 -404.097744)
		(width 0.254)
		(layer "In2.Cu")
		(net "P0V9_RETIMER_CPU1_TEMP0")
	)
	(segment
		(start 21.479002 -404.097744)
		(end 21.479002 -407.138124)
		(width 0.254)
		(layer "In2.Cu")
		(net "P0V9_RETIMER_CPU1_TEMP0")
	)
	(segment
		(start 13.97508 -398.70761)
		(end 14.970252 -397.712438)
		(width 0.254)
		(layer "In2.Cu")
		(net "P0V9_RETIMER_CPU1_TEMP0")
	)
	(segment
		(start 22.794976 -400.67103)
		(end 22.794976 -402.78177)
		(width 0.254)
		(layer "In2.Cu")
		(net "P0V9_RETIMER_CPU1_TEMP0")
	)
	(segment
		(start 24.520398 -413.102806)
		(end 20.56003 -417.063174)
		(width 0.254)
		(layer "In2.Cu")
		(net "P0V9_RETIMER_CPU1_TEMP0")
	)
	(segment
		(start 14.970252 -393.573)
		(end 15.64767 -392.895582)
		(width 0.254)
		(layer "In2.Cu")
		(net "P0V9_RETIMER_CPU1_TEMP0")
	)
	(segment
		(start 17.930114 -417.063174)
		(end 16.88465 -416.01771)
		(width 0.254)
		(layer "In2.Cu")
		(net "P0V9_RETIMER_CPU1_TEMP0")
	)
	(segment
		(start 21.906738 -399.782792)
		(end 22.794976 -400.67103)
		(width 0.254)
		(layer "In2.Cu")
		(net "P0V9_RETIMER_CPU1_TEMP0")
	)
	(segment
		(start 11.37031 -412.900114)
		(end 11.37031 -412.357062)
		(width 0.254)
		(layer "In2.Cu")
		(net "P0V9_RETIMER_CPU1_TEMP0")
	)
	(segment
		(start 14.473936 -400.027648)
		(end 13.97508 -399.528792)
		(width 0.254)
		(layer "In2.Cu")
		(net "P0V9_RETIMER_CPU1_TEMP0")
	)
	(segment
		(start 14.123162 -416.01771)
		(end 12.711684 -414.606232)
		(width 0.254)
		(layer "In2.Cu")
		(net "P0V9_RETIMER_CPU1_TEMP0")
	)
	(segment
		(start 25.900888 -393.729972)
		(end 25.900888 -391.754106)
		(width 0.1524)
		(layer "F.Cu")
		(net "P0V9_RETIMER_CPU1_PWM2")
	)
	(segment
		(start 15.780766 -407.515568)
		(end 15.780766 -407.912824)
		(width 0.1524)
		(layer "F.Cu")
		(net "P0V9_RETIMER_CPU1_PWM2")
	)
	(segment
		(start 14.683994 -405.907494)
		(end 14.683994 -406.418796)
		(width 0.1524)
		(layer "F.Cu")
		(net "P0V9_RETIMER_CPU1_PWM2")
	)
	(segment
		(start 14.683994 -406.418796)
		(end 15.780766 -407.515568)
		(width 0.1524)
		(layer "F.Cu")
		(net "P0V9_RETIMER_CPU1_PWM2")
	)
	(segment
		(start 25.910794 -393.761468)
		(end 25.932384 -393.761468)
		(width 0.1524)
		(layer "F.Cu")
		(net "P0V9_RETIMER_CPU1_PWM2")
	)
	(segment
		(start 25.932384 -393.761468)
		(end 25.900888 -393.729972)
		(width 0.1524)
		(layer "F.Cu")
		(net "P0V9_RETIMER_CPU1_PWM2")
	)
	(via
		(at 14.683994 -405.907494)
		(size 0.508)
		(drill 0.254)
		(layers "F.Cu" "B.Cu")
		(net "P0V9_RETIMER_CPU1_PWM2")
	)
	(via
		(at 25.910794 -393.761468)
		(size 0.508)
		(drill 0.254)
		(layers "F.Cu" "B.Cu")
		(net "P0V9_RETIMER_CPU1_PWM2")
	)
	(segment
		(start 15.22349 -405.19731)
		(end 14.683994 -405.736806)
		(width 0.254)
		(layer "In4.Cu")
		(net "P0V9_RETIMER_CPU1_PWM2")
	)
	(segment
		(start 22.86381 -402.711666)
		(end 21.291296 -404.28418)
		(width 0.254)
		(layer "In4.Cu")
		(net "P0V9_RETIMER_CPU1_PWM2")
	)
	(segment
		(start 16.47825 -405.42591)
		(end 16.24965 -405.19731)
		(width 0.254)
		(layer "In4.Cu")
		(net "P0V9_RETIMER_CPU1_PWM2")
	)
	(segment
		(start 21.291296 -404.28418)
		(end 21.291296 -404.905972)
		(width 0.254)
		(layer "In4.Cu")
		(net "P0V9_RETIMER_CPU1_PWM2")
	)
	(segment
		(start 25.545796 -393.761468)
		(end 22.86381 -396.443454)
		(width 0.254)
		(layer "In4.Cu")
		(net "P0V9_RETIMER_CPU1_PWM2")
	)
	(segment
		(start 14.683994 -405.736806)
		(end 14.683994 -405.907494)
		(width 0.254)
		(layer "In4.Cu")
		(net "P0V9_RETIMER_CPU1_PWM2")
	)
	(segment
		(start 21.291296 -404.905972)
		(end 20.771358 -405.42591)
		(width 0.254)
		(layer "In4.Cu")
		(net "P0V9_RETIMER_CPU1_PWM2")
	)
	(segment
		(start 25.910794 -393.761468)
		(end 25.545796 -393.761468)
		(width 0.254)
		(layer "In4.Cu")
		(net "P0V9_RETIMER_CPU1_PWM2")
	)
	(segment
		(start 16.24965 -405.19731)
		(end 15.22349 -405.19731)
		(width 0.254)
		(layer "In4.Cu")
		(net "P0V9_RETIMER_CPU1_PWM2")
	)
	(segment
		(start 20.771358 -405.42591)
		(end 16.47825 -405.42591)
		(width 0.254)
		(layer "In4.Cu")
		(net "P0V9_RETIMER_CPU1_PWM2")
	)
	(segment
		(start 22.86381 -396.443454)
		(end 22.86381 -402.711666)
		(width 0.254)
		(layer "In4.Cu")
		(net "P0V9_RETIMER_CPU1_PWM2")
	)
	(segment
		(start 16.822166 -393.582144)
		(end 16.822166 -391.754106)
		(width 0.1524)
		(layer "F.Cu")
		(net "P0V9_RETIMER_CPU1_PWM1")
	)
	(segment
		(start 15.52194 -406.748742)
		(end 16.180816 -407.407618)
		(width 0.1524)
		(layer "F.Cu")
		(net "P0V9_RETIMER_CPU1_PWM1")
	)
	(segment
		(start 16.180816 -407.407618)
		(end 16.180816 -407.912824)
		(width 0.1524)
		(layer "F.Cu")
		(net "P0V9_RETIMER_CPU1_PWM1")
	)
	(segment
		(start 15.52194 -405.929084)
		(end 15.52194 -406.748742)
		(width 0.1524)
		(layer "F.Cu")
		(net "P0V9_RETIMER_CPU1_PWM1")
	)
	(via
		(at 16.822166 -393.582144)
		(size 0.508)
		(drill 0.254)
		(layers "F.Cu" "B.Cu")
		(net "P0V9_RETIMER_CPU1_PWM1")
	)
	(via
		(at 15.52194 -405.929084)
		(size 0.508)
		(drill 0.254)
		(layers "F.Cu" "B.Cu")
		(net "P0V9_RETIMER_CPU1_PWM1")
	)
	(segment
		(start 13.701522 -405.929846)
		(end 14.404848 -406.633172)
		(width 0.254)
		(layer "In4.Cu")
		(net "P0V9_RETIMER_CPU1_PWM1")
	)
	(segment
		(start 13.701522 -396.932912)
		(end 13.701522 -405.929846)
		(width 0.254)
		(layer "In4.Cu")
		(net "P0V9_RETIMER_CPU1_PWM1")
	)
	(segment
		(start 16.822166 -393.812268)
		(end 13.701522 -396.932912)
		(width 0.254)
		(layer "In4.Cu")
		(net "P0V9_RETIMER_CPU1_PWM1")
	)
	(segment
		(start 15.06728 -406.633172)
		(end 15.52194 -406.178512)
		(width 0.254)
		(layer "In4.Cu")
		(net "P0V9_RETIMER_CPU1_PWM1")
	)
	(segment
		(start 16.822166 -393.582144)
		(end 16.822166 -393.812268)
		(width 0.254)
		(layer "In4.Cu")
		(net "P0V9_RETIMER_CPU1_PWM1")
	)
	(segment
		(start 15.52194 -406.178512)
		(end 15.52194 -405.929084)
		(width 0.254)
		(layer "In4.Cu")
		(net "P0V9_RETIMER_CPU1_PWM1")
	)
	(segment
		(start 14.404848 -406.633172)
		(end 15.06728 -406.633172)
		(width 0.254)
		(layer "In4.Cu")
		(net "P0V9_RETIMER_CPU1_PWM1")
	)
	(segment
		(start 10.7061 -390.811512)
		(end 10.7061 -392.884914)
		(width 0.254)
		(layer "F.Cu")
		(net "P0V9_RETIMER_CPU1_PVCC")
	)
	(segment
		(start 14.162024 -389.779256)
		(end 13.466318 -389.779256)
		(width 0.2032)
		(layer "F.Cu")
		(net "P0V9_RETIMER_CPU1_PVCC")
	)
	(segment
		(start 12.505436 -389.444484)
		(end 12.289282 -389.22833)
		(width 0.4572)
		(layer "F.Cu")
		(net "P0V9_RETIMER_CPU1_PVCC")
	)
	(segment
		(start 10.7061 -393.82827)
		(end 11.7221 -393.82827)
		(width 0.254)
		(layer "F.Cu")
		(net "P0V9_RETIMER_CPU1_PVCC")
	)
	(segment
		(start 13.131546 -389.444484)
		(end 12.860274 -389.444484)
		(width 0.2032)
		(layer "F.Cu")
		(net "P0V9_RETIMER_CPU1_PVCC")
	)
	(segment
		(start 22.549612 -389.779256)
		(end 23.240746 -389.779256)
		(width 0.2286)
		(layer "F.Cu")
		(net "P0V9_RETIMER_CPU1_PVCC")
	)
	(segment
		(start 21.284184 -389.571484)
		(end 21.938996 -389.571484)
		(width 0.381)
		(layer "F.Cu")
		(net "P0V9_RETIMER_CPU1_PVCC")
	)
	(segment
		(start 12.860274 -389.444484)
		(end 12.505436 -389.444484)
		(width 0.4572)
		(layer "F.Cu")
		(net "P0V9_RETIMER_CPU1_PVCC")
	)
	(segment
		(start 13.466318 -389.779256)
		(end 13.131546 -389.444484)
		(width 0.2032)
		(layer "F.Cu")
		(net "P0V9_RETIMER_CPU1_PVCC")
	)
	(segment
		(start 21.938996 -389.571484)
		(end 22.34184 -389.571484)
		(width 0.2286)
		(layer "F.Cu")
		(net "P0V9_RETIMER_CPU1_PVCC")
	)
	(segment
		(start 12.289282 -389.22833)
		(end 10.7061 -390.811512)
		(width 0.254)
		(layer "F.Cu")
		(net "P0V9_RETIMER_CPU1_PVCC")
	)
	(segment
		(start 10.7061 -392.884914)
		(end 10.7061 -393.82827)
		(width 0.254)
		(layer "F.Cu")
		(net "P0V9_RETIMER_CPU1_PVCC")
	)
	(segment
		(start 22.34184 -389.571484)
		(end 22.549612 -389.779256)
		(width 0.2286)
		(layer "F.Cu")
		(net "P0V9_RETIMER_CPU1_PVCC")
	)
	(via
		(at 12.289282 -389.22833)
		(size 0.508)
		(drill 0.254)
		(layers "F.Cu" "B.Cu")
		(net "P0V9_RETIMER_CPU1_PVCC")
	)
	(via
		(at 21.284184 -389.571484)
		(size 0.508)
		(drill 0.254)
		(layers "F.Cu" "B.Cu")
		(net "P0V9_RETIMER_CPU1_PVCC")
	)
	(via
		(at 10.7061 -392.884914)
		(size 0.762)
		(drill 0.381)
		(layers "F.Cu" "B.Cu")
		(net "P0V9_RETIMER_CPU1_PVCC")
	)
	(segment
		(start 12.916408 -389.22833)
		(end 12.289282 -389.22833)
		(width 0.381)
		(layer "B.Cu")
		(net "P0V9_RETIMER_CPU1_PVCC")
	)
	(segment
		(start 21.729192 -389.126476)
		(end 21.284184 -389.571484)
		(width 0.381)
		(layer "B.Cu")
		(net "P0V9_RETIMER_CPU1_PVCC")
	)
	(segment
		(start 13.018262 -389.126476)
		(end 12.916408 -389.22833)
		(width 0.381)
		(layer "B.Cu")
		(net "P0V9_RETIMER_CPU1_PVCC")
	)
	(segment
		(start 22.096984 -389.126476)
		(end 21.729192 -389.126476)
		(width 0.381)
		(layer "B.Cu")
		(net "P0V9_RETIMER_CPU1_PVCC")
	)
	(segment
		(start 14.79677 -391.706354)
		(end 16.482822 -391.706354)
		(width 0.508)
		(layer "In2.Cu")
		(net "P0V9_RETIMER_CPU1_PVCC")
	)
	(segment
		(start 22.515068 -390.207754)
		(end 21.878798 -389.571484)
		(width 0.508)
		(layer "In2.Cu")
		(net "P0V9_RETIMER_CPU1_PVCC")
	)
	(segment
		(start 17.110964 -391.96645)
		(end 18.679668 -393.535154)
		(width 0.508)
		(layer "In2.Cu")
		(net "P0V9_RETIMER_CPU1_PVCC")
	)
	(segment
		(start 18.679668 -393.535154)
		(end 20.914868 -393.535154)
		(width 0.508)
		(layer "In2.Cu")
		(net "P0V9_RETIMER_CPU1_PVCC")
	)
	(segment
		(start 12.318746 -389.22833)
		(end 14.79677 -391.706354)
		(width 0.508)
		(layer "In2.Cu")
		(net "P0V9_RETIMER_CPU1_PVCC")
	)
	(segment
		(start 16.482822 -391.706354)
		(end 17.110964 -391.96645)
		(width 0.508)
		(layer "In2.Cu")
		(net "P0V9_RETIMER_CPU1_PVCC")
	)
	(segment
		(start 12.289282 -389.22833)
		(end 12.318746 -389.22833)
		(width 0.508)
		(layer "In2.Cu")
		(net "P0V9_RETIMER_CPU1_PVCC")
	)
	(segment
		(start 21.878798 -389.571484)
		(end 21.284184 -389.571484)
		(width 0.508)
		(layer "In2.Cu")
		(net "P0V9_RETIMER_CPU1_PVCC")
	)
	(segment
		(start 22.515068 -391.934954)
		(end 22.515068 -390.207754)
		(width 0.508)
		(layer "In2.Cu")
		(net "P0V9_RETIMER_CPU1_PVCC")
	)
	(segment
		(start 20.914868 -393.535154)
		(end 22.515068 -391.934954)
		(width 0.508)
		(layer "In2.Cu")
		(net "P0V9_RETIMER_CPU1_PVCC")
	)
	(segment
		(start 16.18742 -406.71623)
		(end 16.18742 -405.82088)
		(width 0.10668)
		(layer "F.Cu")
		(net "P0V9_RETIMER_CPU1_PMSDA_R")
	)
	(segment
		(start 15.450058 -405.29891)
		(end 14.892782 -404.741634)
		(width 0.10668)
		(layer "F.Cu")
		(net "P0V9_RETIMER_CPU1_PMSDA_R")
	)
	(segment
		(start 16.18742 -405.82088)
		(end 15.66545 -405.29891)
		(width 0.10668)
		(layer "F.Cu")
		(net "P0V9_RETIMER_CPU1_PMSDA_R")
	)
	(segment
		(start 16.580866 -407.912824)
		(end 16.580866 -407.109676)
		(width 0.10668)
		(layer "F.Cu")
		(net "P0V9_RETIMER_CPU1_PMSDA_R")
	)
	(segment
		(start 15.66545 -405.29891)
		(end 15.450058 -405.29891)
		(width 0.10668)
		(layer "F.Cu")
		(net "P0V9_RETIMER_CPU1_PMSDA_R")
	)
	(segment
		(start 16.580866 -407.109676)
		(end 16.18742 -406.71623)
		(width 0.10668)
		(layer "F.Cu")
		(net "P0V9_RETIMER_CPU1_PMSDA_R")
	)
	(segment
		(start 16.162782 -404.741634)
		(end 16.980916 -405.559768)
		(width 0.10668)
		(layer "F.Cu")
		(net "P0V9_RETIMER_CPU1_PMSCL_R")
	)
	(segment
		(start 16.980916 -405.559768)
		(end 16.980916 -405.67991)
		(width 0.10668)
		(layer "F.Cu")
		(net "P0V9_RETIMER_CPU1_PMSCL_R")
	)
	(segment
		(start 16.980916 -407.912824)
		(end 16.980916 -405.67991)
		(width 0.10668)
		(layer "F.Cu")
		(net "P0V9_RETIMER_CPU1_PMSCL_R")
	)
	(via
		(at 16.980916 -405.67991)
		(size 0.762)
		(drill 0.381)
		(layers "F.Cu" "B.Cu")
		(net "P0V9_RETIMER_CPU1_PMSCL_R")
	)
	(segment
		(start 17.89684 -408.44851)
		(end 17.89684 -406.56891)
		(width 0.13462)
		(layer "F.Cu")
		(net "TP_P0V9_RETIMER_CPU1_PMALERT")
	)
	(segment
		(start 17.832578 -408.512772)
		(end 17.89684 -408.44851)
		(width 0.13462)
		(layer "F.Cu")
		(net "TP_P0V9_RETIMER_CPU1_PMALERT")
	)
	(segment
		(start 17.89684 -405.332692)
		(end 17.89684 -406.56891)
		(width 0.13462)
		(layer "F.Cu")
		(net "TP_P0V9_RETIMER_CPU1_PMALERT")
	)
	(segment
		(start 17.305782 -404.741634)
		(end 17.89684 -405.332692)
		(width 0.13462)
		(layer "F.Cu")
		(net "TP_P0V9_RETIMER_CPU1_PMALERT")
	)
	(segment
		(start 17.580864 -408.512772)
		(end 17.832578 -408.512772)
		(width 0.13462)
		(layer "F.Cu")
		(net "TP_P0V9_RETIMER_CPU1_PMALERT")
	)
	(via
		(at 17.89684 -406.56891)
		(size 0.762)
		(drill 0.381)
		(layers "F.Cu" "B.Cu")
		(net "TP_P0V9_RETIMER_CPU1_PMALERT")
	)
	(segment
		(start 24.550878 -392.120374)
		(end 24.550878 -391.754106)
		(width 0.1524)
		(layer "F.Cu")
		(net "P0V9_RETIMER_CPU1_LSET2")
	)
	(segment
		(start 24.018748 -392.652504)
		(end 24.550878 -392.120374)
		(width 0.1524)
		(layer "F.Cu")
		(net "P0V9_RETIMER_CPU1_LSET2")
	)
	(segment
		(start 24.240744 -394.410184)
		(end 23.697184 -393.866624)
		(width 0.1524)
		(layer "F.Cu")
		(net "P0V9_RETIMER_CPU1_LSET2")
	)
	(segment
		(start 23.697184 -393.866624)
		(end 23.697184 -393.482068)
		(width 0.1524)
		(layer "F.Cu")
		(net "P0V9_RETIMER_CPU1_LSET2")
	)
	(segment
		(start 23.697184 -393.482068)
		(end 24.018748 -393.160504)
		(width 0.1524)
		(layer "F.Cu")
		(net "P0V9_RETIMER_CPU1_LSET2")
	)
	(segment
		(start 24.018748 -393.160504)
		(end 24.018748 -392.652504)
		(width 0.1524)
		(layer "F.Cu")
		(net "P0V9_RETIMER_CPU1_LSET2")
	)
	(via
		(at 23.697184 -393.482068)
		(size 0.508)
		(drill 0.254)
		(layers "F.Cu" "B.Cu")
		(net "P0V9_RETIMER_CPU1_LSET2")
	)
	(segment
		(start 14.995906 -393.609576)
		(end 14.995906 -392.743182)
		(width 0.1524)
		(layer "F.Cu")
		(net "P0V9_RETIMER_CPU1_LSET1")
	)
	(segment
		(start 15.472156 -392.266932)
		(end 15.472156 -391.754106)
		(width 0.1524)
		(layer "F.Cu")
		(net "P0V9_RETIMER_CPU1_LSET1")
	)
	(segment
		(start 14.995906 -392.743182)
		(end 15.472156 -392.266932)
		(width 0.1524)
		(layer "F.Cu")
		(net "P0V9_RETIMER_CPU1_LSET1")
	)
	(segment
		(start 14.995906 -393.772898)
		(end 14.995906 -393.609576)
		(width 0.1524)
		(layer "F.Cu")
		(net "P0V9_RETIMER_CPU1_LSET1")
	)
	(segment
		(start 15.651734 -394.428726)
		(end 14.995906 -393.772898)
		(width 0.1524)
		(layer "F.Cu")
		(net "P0V9_RETIMER_CPU1_LSET1")
	)
	(via
		(at 14.995906 -393.609576)
		(size 0.762)
		(drill 0.381)
		(layers "F.Cu" "B.Cu")
		(net "P0V9_RETIMER_CPU1_LSET1")
	)
	(segment
		(start 23.097998 -394.137388)
		(end 23.097998 -393.067286)
		(width 0.2286)
		(layer "F.Cu")
		(net "P0V9_RETIMER_CPU1_IMON2")
	)
	(segment
		(start 15.780766 -413.687768)
		(end 15.780766 -412.712916)
		(width 0.1778)
		(layer "F.Cu")
		(net "P0V9_RETIMER_CPU1_IMON2")
	)
	(segment
		(start 24.10079 -392.064494)
		(end 24.10079 -391.754106)
		(width 0.2286)
		(layer "F.Cu")
		(net "P0V9_RETIMER_CPU1_IMON2")
	)
	(segment
		(start 23.243794 -394.283184)
		(end 23.097998 -394.137388)
		(width 0.2286)
		(layer "F.Cu")
		(net "P0V9_RETIMER_CPU1_IMON2")
	)
	(segment
		(start 23.097998 -393.067286)
		(end 24.10079 -392.064494)
		(width 0.2286)
		(layer "F.Cu")
		(net "P0V9_RETIMER_CPU1_IMON2")
	)
	(segment
		(start 16.416782 -414.755584)
		(end 16.416782 -414.323784)
		(width 0.1778)
		(layer "F.Cu")
		(net "P0V9_RETIMER_CPU1_IMON2")
	)
	(segment
		(start 16.416782 -414.323784)
		(end 15.780766 -413.687768)
		(width 0.1778)
		(layer "F.Cu")
		(net "P0V9_RETIMER_CPU1_IMON2")
	)
	(via
		(at 16.416782 -414.755584)
		(size 0.508)
		(drill 0.254)
		(layers "F.Cu" "B.Cu")
		(net "P0V9_RETIMER_CPU1_IMON2")
	)
	(via
		(at 23.243794 -394.283184)
		(size 0.508)
		(drill 0.254)
		(layers "F.Cu" "B.Cu")
		(net "P0V9_RETIMER_CPU1_IMON2")
	)
	(segment
		(start 19.2405 -414.917128)
		(end 16.578326 -414.917128)
		(width 0.254)
		(layer "In15.Cu")
		(net "P0V9_RETIMER_CPU1_IMON2")
	)
	(segment
		(start 21.930868 -400.226784)
		(end 19.663664 -400.226784)
		(width 0.254)
		(layer "In15.Cu")
		(net "P0V9_RETIMER_CPU1_IMON2")
	)
	(segment
		(start 19.657568 -402.67001)
		(end 19.657568 -403.576282)
		(width 0.254)
		(layer "In15.Cu")
		(net "P0V9_RETIMER_CPU1_IMON2")
	)
	(segment
		(start 19.663664 -400.226784)
		(end 18.929858 -400.96059)
		(width 0.254)
		(layer "In15.Cu")
		(net "P0V9_RETIMER_CPU1_IMON2")
	)
	(segment
		(start 18.929858 -400.96059)
		(end 18.929858 -401.9423)
		(width 0.254)
		(layer "In15.Cu")
		(net "P0V9_RETIMER_CPU1_IMON2")
	)
	(segment
		(start 23.243794 -394.283184)
		(end 23.091394 -395.920214)
		(width 0.254)
		(layer "In15.Cu")
		(net "P0V9_RETIMER_CPU1_IMON2")
	)
	(segment
		(start 23.091394 -395.920214)
		(end 23.091394 -399.066258)
		(width 0.254)
		(layer "In15.Cu")
		(net "P0V9_RETIMER_CPU1_IMON2")
	)
	(segment
		(start 18.929858 -401.9423)
		(end 19.657568 -402.67001)
		(width 0.254)
		(layer "In15.Cu")
		(net "P0V9_RETIMER_CPU1_IMON2")
	)
	(segment
		(start 20.393152 -407.834592)
		(end 20.393152 -413.764476)
		(width 0.254)
		(layer "In15.Cu")
		(net "P0V9_RETIMER_CPU1_IMON2")
	)
	(segment
		(start 20.393152 -413.764476)
		(end 19.2405 -414.917128)
		(width 0.254)
		(layer "In15.Cu")
		(net "P0V9_RETIMER_CPU1_IMON2")
	)
	(segment
		(start 18.822162 -404.411688)
		(end 18.822162 -406.263602)
		(width 0.254)
		(layer "In15.Cu")
		(net "P0V9_RETIMER_CPU1_IMON2")
	)
	(segment
		(start 18.822162 -406.263602)
		(end 20.393152 -407.834592)
		(width 0.254)
		(layer "In15.Cu")
		(net "P0V9_RETIMER_CPU1_IMON2")
	)
	(segment
		(start 16.578326 -414.917128)
		(end 16.416782 -414.755584)
		(width 0.254)
		(layer "In15.Cu")
		(net "P0V9_RETIMER_CPU1_IMON2")
	)
	(segment
		(start 19.657568 -403.576282)
		(end 18.822162 -404.411688)
		(width 0.254)
		(layer "In15.Cu")
		(net "P0V9_RETIMER_CPU1_IMON2")
	)
	(segment
		(start 23.091394 -399.066258)
		(end 21.930868 -400.226784)
		(width 0.254)
		(layer "In15.Cu")
		(net "P0V9_RETIMER_CPU1_IMON2")
	)
	(segment
		(start 15.00632 -392.127232)
		(end 15.022068 -392.111484)
		(width 0.2286)
		(layer "F.Cu")
		(net "P0V9_RETIMER_CPU1_IMON1")
	)
	(segment
		(start 15.022068 -392.111484)
		(end 15.022068 -391.754106)
		(width 0.2286)
		(layer "F.Cu")
		(net "P0V9_RETIMER_CPU1_IMON1")
	)
	(segment
		(start 14.06398 -394.043154)
		(end 14.06398 -393.08659)
		(width 0.2286)
		(layer "F.Cu")
		(net "P0V9_RETIMER_CPU1_IMON1")
	)
	(segment
		(start 16.289782 -413.485584)
		(end 16.180816 -413.376618)
		(width 0.1778)
		(layer "F.Cu")
		(net "P0V9_RETIMER_CPU1_IMON1")
	)
	(segment
		(start 16.180816 -413.376618)
		(end 16.180816 -412.712916)
		(width 0.1778)
		(layer "F.Cu")
		(net "P0V9_RETIMER_CPU1_IMON1")
	)
	(segment
		(start 14.06398 -393.08659)
		(end 15.00632 -392.14425)
		(width 0.2286)
		(layer "F.Cu")
		(net "P0V9_RETIMER_CPU1_IMON1")
	)
	(segment
		(start 15.00632 -392.14425)
		(end 15.00632 -392.127232)
		(width 0.2286)
		(layer "F.Cu")
		(net "P0V9_RETIMER_CPU1_IMON1")
	)
	(via
		(at 14.06398 -394.043154)
		(size 0.508)
		(drill 0.254)
		(layers "F.Cu" "B.Cu")
		(net "P0V9_RETIMER_CPU1_IMON1")
	)
	(via
		(at 16.289782 -413.485584)
		(size 0.508)
		(drill 0.254)
		(layers "F.Cu" "B.Cu")
		(net "P0V9_RETIMER_CPU1_IMON1")
	)
	(segment
		(start 14.06398 -402.151596)
		(end 14.06398 -394.043154)
		(width 0.254)
		(layer "In15.Cu")
		(net "P0V9_RETIMER_CPU1_IMON1")
	)
	(segment
		(start 17.66189 -405.731726)
		(end 16.500602 -404.570438)
		(width 0.254)
		(layer "In15.Cu")
		(net "P0V9_RETIMER_CPU1_IMON1")
	)
	(segment
		(start 14.543786 -404.570438)
		(end 13.682726 -403.709378)
		(width 0.254)
		(layer "In15.Cu")
		(net "P0V9_RETIMER_CPU1_IMON1")
	)
	(segment
		(start 16.423894 -413.485584)
		(end 17.66189 -412.247588)
		(width 0.254)
		(layer "In15.Cu")
		(net "P0V9_RETIMER_CPU1_IMON1")
	)
	(segment
		(start 17.66189 -412.247588)
		(end 17.66189 -405.731726)
		(width 0.254)
		(layer "In15.Cu")
		(net "P0V9_RETIMER_CPU1_IMON1")
	)
	(segment
		(start 13.682726 -402.53285)
		(end 14.06398 -402.151596)
		(width 0.254)
		(layer "In15.Cu")
		(net "P0V9_RETIMER_CPU1_IMON1")
	)
	(segment
		(start 16.289782 -413.485584)
		(end 16.423894 -413.485584)
		(width 0.254)
		(layer "In15.Cu")
		(net "P0V9_RETIMER_CPU1_IMON1")
	)
	(segment
		(start 16.500602 -404.570438)
		(end 14.543786 -404.570438)
		(width 0.254)
		(layer "In15.Cu")
		(net "P0V9_RETIMER_CPU1_IMON1")
	)
	(segment
		(start 13.682726 -403.709378)
		(end 13.682726 -402.53285)
		(width 0.254)
		(layer "In15.Cu")
		(net "P0V9_RETIMER_CPU1_IMON1")
	)
	(segment
		(start 20.981924 -407.576528)
		(end 23.226522 -409.821126)
		(width 0.1524)
		(layer "F.Cu")
		(net "P0V9_RETIMER_CPU1_EN")
	)
	(segment
		(start 23.226522 -409.821126)
		(end 35.853116 -409.821126)
		(width 0.1524)
		(layer "F.Cu")
		(net "P0V9_RETIMER_CPU1_EN")
	)
	(segment
		(start 195.2498 -138.06805)
		(end 195.2498 -141.907768)
		(width 0.1524)
		(layer "F.Cu")
		(net "P0V9_RETIMER_CPU1_EN")
	)
	(segment
		(start 35.853116 -409.821126)
		(end 36.211256 -410.179266)
		(width 0.1524)
		(layer "F.Cu")
		(net "P0V9_RETIMER_CPU1_EN")
	)
	(segment
		(start 195.2498 -141.907768)
		(end 196.459602 -143.11757)
		(width 0.1524)
		(layer "F.Cu")
		(net "P0V9_RETIMER_CPU1_EN")
	)
	(segment
		(start 36.211256 -410.179266)
		(end 37.199062 -410.179266)
		(width 0.1524)
		(layer "F.Cu")
		(net "P0V9_RETIMER_CPU1_EN")
	)
	(via
		(at 196.459602 -143.11757)
		(size 0.508)
		(drill 0.254)
		(layers "F.Cu" "B.Cu")
		(net "P0V9_RETIMER_CPU1_EN")
	)
	(via
		(at 37.199062 -410.179266)
		(size 0.508)
		(drill 0.254)
		(layers "F.Cu" "B.Cu")
		(net "P0V9_RETIMER_CPU1_EN")
	)
	(segment
		(start 30.255718 -374.699784)
		(end 30.255718 -379.34011)
		(width 0.1524)
		(layer "In13.Cu")
		(net "P0V9_RETIMER_CPU1_EN")
	)
	(segment
		(start 16.553942 -354.18776)
		(end 18.17878 -355.812598)
		(width 0.1524)
		(layer "In13.Cu")
		(net "P0V9_RETIMER_CPU1_EN")
	)
	(segment
		(start 38.893242 -387.977634)
		(end 38.893242 -390.677908)
		(width 0.1524)
		(layer "In13.Cu")
		(net "P0V9_RETIMER_CPU1_EN")
	)
	(segment
		(start 96.2787 -137.530332)
		(end 95.593408 -138.215624)
		(width 0.1524)
		(layer "In13.Cu")
		(net "P0V9_RETIMER_CPU1_EN")
	)
	(segment
		(start 93.0021 -137.13968)
		(end 79.915512 -137.13968)
		(width 0.1524)
		(layer "In13.Cu")
		(net "P0V9_RETIMER_CPU1_EN")
	)
	(segment
		(start 189.607952 -144.254474)
		(end 188.8363 -145.026126)
		(width 0.1524)
		(layer "In13.Cu")
		(net "P0V9_RETIMER_CPU1_EN")
	)
	(segment
		(start 20.011136 -366.56645)
		(end 20.011136 -367.980976)
		(width 0.1524)
		(layer "In13.Cu")
		(net "P0V9_RETIMER_CPU1_EN")
	)
	(segment
		(start 20.011136 -367.980976)
		(end 21.272754 -369.242594)
		(width 0.1524)
		(layer "In13.Cu")
		(net "P0V9_RETIMER_CPU1_EN")
	)
	(segment
		(start 36.685474 -409.665678)
		(end 37.199062 -410.179266)
		(width 0.1524)
		(layer "In13.Cu")
		(net "P0V9_RETIMER_CPU1_EN")
	)
	(segment
		(start 28.73121 -371.953536)
		(end 29.462984 -372.68531)
		(width 0.1524)
		(layer "In13.Cu")
		(net "P0V9_RETIMER_CPU1_EN")
	)
	(segment
		(start 176.585372 -145.026126)
		(end 175.989234 -144.429988)
		(width 0.1524)
		(layer "In13.Cu")
		(net "P0V9_RETIMER_CPU1_EN")
	)
	(segment
		(start 24.498554 -369.242594)
		(end 27.209496 -371.953536)
		(width 0.1524)
		(layer "In13.Cu")
		(net "P0V9_RETIMER_CPU1_EN")
	)
	(segment
		(start 196.459602 -143.11757)
		(end 195.322698 -144.254474)
		(width 0.1524)
		(layer "In13.Cu")
		(net "P0V9_RETIMER_CPU1_EN")
	)
	(segment
		(start 16.553942 -345.074494)
		(end 16.553942 -354.18776)
		(width 0.1524)
		(layer "In13.Cu")
		(net "P0V9_RETIMER_CPU1_EN")
	)
	(segment
		(start 157.104842 -144.429988)
		(end 150.205186 -137.530332)
		(width 0.1524)
		(layer "In13.Cu")
		(net "P0V9_RETIMER_CPU1_EN")
	)
	(segment
		(start 37.649912 -394.573506)
		(end 37.649912 -397.887444)
		(width 0.1524)
		(layer "In13.Cu")
		(net "P0V9_RETIMER_CPU1_EN")
	)
	(segment
		(start 30.255718 -379.34011)
		(end 38.893242 -387.977634)
		(width 0.1524)
		(layer "In13.Cu")
		(net "P0V9_RETIMER_CPU1_EN")
	)
	(segment
		(start 27.209496 -371.953536)
		(end 28.73121 -371.953536)
		(width 0.1524)
		(layer "In13.Cu")
		(net "P0V9_RETIMER_CPU1_EN")
	)
	(segment
		(start 39.986204 -392.237214)
		(end 37.649912 -394.573506)
		(width 0.1524)
		(layer "In13.Cu")
		(net "P0V9_RETIMER_CPU1_EN")
	)
	(segment
		(start 195.322698 -144.254474)
		(end 189.607952 -144.254474)
		(width 0.1524)
		(layer "In13.Cu")
		(net "P0V9_RETIMER_CPU1_EN")
	)
	(segment
		(start 188.8363 -145.026126)
		(end 176.585372 -145.026126)
		(width 0.1524)
		(layer "In13.Cu")
		(net "P0V9_RETIMER_CPU1_EN")
	)
	(segment
		(start 31.114492 -138.761216)
		(end 19.15541 -150.720298)
		(width 0.1524)
		(layer "In13.Cu")
		(net "P0V9_RETIMER_CPU1_EN")
	)
	(segment
		(start 39.986204 -391.77087)
		(end 39.986204 -392.237214)
		(width 0.1524)
		(layer "In13.Cu")
		(net "P0V9_RETIMER_CPU1_EN")
	)
	(segment
		(start 150.205186 -137.530332)
		(end 96.2787 -137.530332)
		(width 0.1524)
		(layer "In13.Cu")
		(net "P0V9_RETIMER_CPU1_EN")
	)
	(segment
		(start 19.15541 -174.551594)
		(end 7.436612 -186.270392)
		(width 0.1524)
		(layer "In13.Cu")
		(net "P0V9_RETIMER_CPU1_EN")
	)
	(segment
		(start 18.17878 -355.812598)
		(end 18.17878 -364.734094)
		(width 0.1524)
		(layer "In13.Cu")
		(net "P0V9_RETIMER_CPU1_EN")
	)
	(segment
		(start 18.17878 -364.734094)
		(end 20.011136 -366.56645)
		(width 0.1524)
		(layer "In13.Cu")
		(net "P0V9_RETIMER_CPU1_EN")
	)
	(segment
		(start 7.436612 -186.270392)
		(end 7.436612 -335.957164)
		(width 0.1524)
		(layer "In13.Cu")
		(net "P0V9_RETIMER_CPU1_EN")
	)
	(segment
		(start 7.436612 -335.957164)
		(end 16.553942 -345.074494)
		(width 0.1524)
		(layer "In13.Cu")
		(net "P0V9_RETIMER_CPU1_EN")
	)
	(segment
		(start 29.462984 -373.90705)
		(end 30.255718 -374.699784)
		(width 0.1524)
		(layer "In13.Cu")
		(net "P0V9_RETIMER_CPU1_EN")
	)
	(segment
		(start 95.593408 -138.215624)
		(end 94.078044 -138.215624)
		(width 0.1524)
		(layer "In13.Cu")
		(net "P0V9_RETIMER_CPU1_EN")
	)
	(segment
		(start 94.078044 -138.215624)
		(end 93.0021 -137.13968)
		(width 0.1524)
		(layer "In13.Cu")
		(net "P0V9_RETIMER_CPU1_EN")
	)
	(segment
		(start 38.893242 -390.677908)
		(end 39.986204 -391.77087)
		(width 0.1524)
		(layer "In13.Cu")
		(net "P0V9_RETIMER_CPU1_EN")
	)
	(segment
		(start 175.989234 -144.429988)
		(end 157.104842 -144.429988)
		(width 0.1524)
		(layer "In13.Cu")
		(net "P0V9_RETIMER_CPU1_EN")
	)
	(segment
		(start 29.462984 -372.68531)
		(end 29.462984 -373.90705)
		(width 0.1524)
		(layer "In13.Cu")
		(net "P0V9_RETIMER_CPU1_EN")
	)
	(segment
		(start 78.293976 -138.761216)
		(end 31.114492 -138.761216)
		(width 0.1524)
		(layer "In13.Cu")
		(net "P0V9_RETIMER_CPU1_EN")
	)
	(segment
		(start 37.649912 -397.887444)
		(end 36.685474 -398.851882)
		(width 0.1524)
		(layer "In13.Cu")
		(net "P0V9_RETIMER_CPU1_EN")
	)
	(segment
		(start 36.685474 -398.851882)
		(end 36.685474 -409.665678)
		(width 0.1524)
		(layer "In13.Cu")
		(net "P0V9_RETIMER_CPU1_EN")
	)
	(segment
		(start 79.915512 -137.13968)
		(end 78.293976 -138.761216)
		(width 0.1524)
		(layer "In13.Cu")
		(net "P0V9_RETIMER_CPU1_EN")
	)
	(segment
		(start 21.272754 -369.242594)
		(end 24.498554 -369.242594)
		(width 0.1524)
		(layer "In13.Cu")
		(net "P0V9_RETIMER_CPU1_EN")
	)
	(segment
		(start 19.15541 -150.720298)
		(end 19.15541 -174.551594)
		(width 0.1524)
		(layer "In13.Cu")
		(net "P0V9_RETIMER_CPU1_EN")
	)
	(segment
		(start 451.200266 -400.43227)
		(end 451.200266 -399.87347)
		(width 0.2032)
		(layer "F.Cu")
		(net "P0V9_RETIMER_CPU0_VOS2")
	)
	(segment
		(start 450.844666 -400.78787)
		(end 451.200266 -400.43227)
		(width 0.2032)
		(layer "F.Cu")
		(net "P0V9_RETIMER_CPU0_VOS2")
	)
	(segment
		(start 451.200266 -399.87347)
		(end 451.553326 -399.52041)
		(width 0.2032)
		(layer "F.Cu")
		(net "P0V9_RETIMER_CPU0_VOS2")
	)
	(segment
		(start 450.482716 -400.78787)
		(end 450.844666 -400.78787)
		(width 0.2032)
		(layer "F.Cu")
		(net "P0V9_RETIMER_CPU0_VOS2")
	)
	(segment
		(start 451.553326 -399.52041)
		(end 451.810628 -399.52041)
		(width 0.2032)
		(layer "F.Cu")
		(net "P0V9_RETIMER_CPU0_VOS2")
	)
	(segment
		(start 441.446666 -400.64182)
		(end 442.081666 -400.00682)
		(width 0.2286)
		(layer "F.Cu")
		(net "P0V9_RETIMER_CPU0_VOS1")
	)
	(segment
		(start 442.081666 -399.82267)
		(end 442.383926 -399.52041)
		(width 0.2286)
		(layer "F.Cu")
		(net "P0V9_RETIMER_CPU0_VOS1")
	)
	(segment
		(start 442.383926 -399.52041)
		(end 442.731906 -399.52041)
		(width 0.2286)
		(layer "F.Cu")
		(net "P0V9_RETIMER_CPU0_VOS1")
	)
	(segment
		(start 442.081666 -400.00682)
		(end 442.081666 -399.82267)
		(width 0.2286)
		(layer "F.Cu")
		(net "P0V9_RETIMER_CPU0_VOS1")
	)
	(segment
		(start 449.131182 -425.210478)
		(end 448.853814 -424.93311)
		(width 0.1778)
		(layer "F.Cu")
		(net "P0V9_RETIMER_CPU0_VMON")
	)
	(segment
		(start 447.501264 -424.514772)
		(end 446.729612 -424.514772)
		(width 0.1778)
		(layer "F.Cu")
		(net "P0V9_RETIMER_CPU0_VMON")
	)
	(segment
		(start 447.919602 -424.93311)
		(end 447.614802 -424.62831)
		(width 0.1778)
		(layer "F.Cu")
		(net "P0V9_RETIMER_CPU0_VMON")
	)
	(segment
		(start 448.853814 -424.93311)
		(end 447.919602 -424.93311)
		(width 0.1778)
		(layer "F.Cu")
		(net "P0V9_RETIMER_CPU0_VMON")
	)
	(segment
		(start 449.131182 -425.210478)
		(end 449.131182 -424.33113)
		(width 0.254)
		(layer "F.Cu")
		(net "P0V9_RETIMER_CPU0_VMON")
	)
	(segment
		(start 447.614802 -424.62831)
		(end 447.501264 -424.514772)
		(width 0.1778)
		(layer "F.Cu")
		(net "P0V9_RETIMER_CPU0_VMON")
	)
	(segment
		(start 449.131182 -424.33113)
		(end 449.151756 -424.310556)
		(width 0.254)
		(layer "F.Cu")
		(net "P0V9_RETIMER_CPU0_VMON")
	)
	(via
		(at 447.614802 -424.62831)
		(size 0.508)
		(drill 0.254)
		(layers "F.Cu" "B.Cu")
		(net "P0V9_RETIMER_CPU0_VMON")
	)
	(segment
		(start 447.275966 -421.355774)
		(end 447.256916 -421.374824)
		(width 0.254)
		(layer "B.Cu")
		(net "P0V9_RETIMER_CPU0_VMON")
	)
	(segment
		(start 447.614802 -424.62831)
		(end 446.668652 -423.68216)
		(width 0.254)
		(layer "B.Cu")
		(net "P0V9_RETIMER_CPU0_VMON")
	)
	(segment
		(start 446.668652 -423.68216)
		(end 446.668652 -421.963088)
		(width 0.254)
		(layer "B.Cu")
		(net "P0V9_RETIMER_CPU0_VMON")
	)
	(segment
		(start 446.668652 -421.963088)
		(end 447.256916 -421.374824)
		(width 0.254)
		(layer "B.Cu")
		(net "P0V9_RETIMER_CPU0_VMON")
	)
	(segment
		(start 447.275966 -420.250874)
		(end 447.275966 -421.355774)
		(width 0.254)
		(layer "B.Cu")
		(net "P0V9_RETIMER_CPU0_VMON")
	)
	(segment
		(start 449.075048 -426.224192)
		(end 449.075048 -425.965366)
		(width 0.1778)
		(layer "F.Cu")
		(net "P0V9_RETIMER_CPU0_VINSEN")
	)
	(segment
		(start 448.550792 -425.44111)
		(end 447.70929 -425.44111)
		(width 0.1778)
		(layer "F.Cu")
		(net "P0V9_RETIMER_CPU0_VINSEN")
	)
	(segment
		(start 447.70929 -425.44111)
		(end 447.183002 -424.914822)
		(width 0.1778)
		(layer "F.Cu")
		(net "P0V9_RETIMER_CPU0_VINSEN")
	)
	(segment
		(start 449.075048 -425.965366)
		(end 448.550792 -425.44111)
		(width 0.1778)
		(layer "F.Cu")
		(net "P0V9_RETIMER_CPU0_VINSEN")
	)
	(segment
		(start 449.043552 -426.255688)
		(end 448.60718 -426.255688)
		(width 0.254)
		(layer "F.Cu")
		(net "P0V9_RETIMER_CPU0_VINSEN")
	)
	(segment
		(start 449.043552 -426.255688)
		(end 449.075048 -426.224192)
		(width 0.1778)
		(layer "F.Cu")
		(net "P0V9_RETIMER_CPU0_VINSEN")
	)
	(segment
		(start 448.60718 -426.255688)
		(end 448.427602 -426.07611)
		(width 0.254)
		(layer "F.Cu")
		(net "P0V9_RETIMER_CPU0_VINSEN")
	)
	(segment
		(start 447.183002 -424.914822)
		(end 446.729612 -424.914822)
		(width 0.1778)
		(layer "F.Cu")
		(net "P0V9_RETIMER_CPU0_VINSEN")
	)
	(via
		(at 448.427602 -426.07611)
		(size 0.508)
		(drill 0.254)
		(layers "F.Cu" "B.Cu")
		(net "P0V9_RETIMER_CPU0_VINSEN")
	)
	(segment
		(start 449.246752 -425.92371)
		(end 449.246752 -425.58081)
		(width 0.254)
		(layer "B.Cu")
		(net "P0V9_RETIMER_CPU0_VINSEN")
	)
	(segment
		(start 449.246752 -425.58081)
		(end 449.094352 -425.42841)
		(width 0.254)
		(layer "B.Cu")
		(net "P0V9_RETIMER_CPU0_VINSEN")
	)
	(segment
		(start 449.094352 -425.42841)
		(end 449.094352 -424.93311)
		(width 0.254)
		(layer "B.Cu")
		(net "P0V9_RETIMER_CPU0_VINSEN")
	)
	(segment
		(start 448.580002 -425.92371)
		(end 448.427602 -426.07611)
		(width 0.254)
		(layer "B.Cu")
		(net "P0V9_RETIMER_CPU0_VINSEN")
	)
	(segment
		(start 449.246752 -425.92371)
		(end 448.580002 -425.92371)
		(width 0.254)
		(layer "B.Cu")
		(net "P0V9_RETIMER_CPU0_VINSEN")
	)
	(segment
		(start 439.429652 -424.80611)
		(end 440.020202 -424.80611)
		(width 0.1524)
		(layer "F.Cu")
		(net "P0V9_RETIMER_CPU0_INALERT")
	)
	(segment
		(start 440.020202 -424.80611)
		(end 440.71159 -424.114722)
		(width 0.1524)
		(layer "F.Cu")
		(net "P0V9_RETIMER_CPU0_INALERT")
	)
	(segment
		(start 440.71159 -424.114722)
		(end 441.92952 -424.114722)
		(width 0.1524)
		(layer "F.Cu")
		(net "P0V9_RETIMER_CPU0_INALERT")
	)
	(segment
		(start 454.020682 -400.14525)
		(end 454.020682 -400.857212)
		(width 0.1778)
		(layer "F.Cu")
		(net "P0V9_RETIMER_CPU0_VCC2")
	)
	(segment
		(start 450.508878 -398.940528)
		(end 450.829172 -398.620234)
		(width 0.1778)
		(layer "F.Cu")
		(net "P0V9_RETIMER_CPU0_VCC2")
	)
	(segment
		(start 449.934076 -398.940528)
		(end 450.508878 -398.940528)
		(width 0.381)
		(layer "F.Cu")
		(net "P0V9_RETIMER_CPU0_VCC2")
	)
	(segment
		(start 450.829172 -398.620234)
		(end 451.810628 -398.620234)
		(width 0.1778)
		(layer "F.Cu")
		(net "P0V9_RETIMER_CPU0_VCC2")
	)
	(segment
		(start 454.020682 -400.857212)
		(end 453.923654 -400.95424)
		(width 0.1778)
		(layer "F.Cu")
		(net "P0V9_RETIMER_CPU0_VCC2")
	)
	(segment
		(start 453.923654 -400.95424)
		(end 453.923654 -401.134072)
		(width 0.1778)
		(layer "F.Cu")
		(net "P0V9_RETIMER_CPU0_VCC2")
	)
	(segment
		(start 449.857876 -398.864328)
		(end 449.934076 -398.940528)
		(width 0.381)
		(layer "F.Cu")
		(net "P0V9_RETIMER_CPU0_VCC2")
	)
	(segment
		(start 453.923654 -401.134072)
		(end 453.958706 -401.169124)
		(width 0.1778)
		(layer "F.Cu")
		(net "P0V9_RETIMER_CPU0_VCC2")
	)
	(via
		(at 449.857876 -398.864328)
		(size 0.508)
		(drill 0.254)
		(layers "F.Cu" "B.Cu")
		(net "P0V9_RETIMER_CPU0_VCC2")
	)
	(via
		(at 451.30339 -399.765266)
		(size 0.6604)
		(drill 0.3302)
		(layers "F.Cu" "B.Cu")
		(net "P0V9_RETIMER_CPU0_VCC2")
	)
	(via
		(at 453.958706 -401.169124)
		(size 0.508)
		(drill 0.254)
		(layers "F.Cu" "B.Cu")
		(net "P0V9_RETIMER_CPU0_VCC2")
	)
	(segment
		(start 453.958706 -401.169124)
		(end 453.958706 -400.691858)
		(width 0.381)
		(layer "B.Cu")
		(net "P0V9_RETIMER_CPU0_VCC2")
	)
	(segment
		(start 451.30339 -399.765266)
		(end 450.666866 -399.128742)
		(width 0.381)
		(layer "B.Cu")
		(net "P0V9_RETIMER_CPU0_VCC2")
	)
	(segment
		(start 450.404484 -398.31772)
		(end 449.857876 -398.864328)
		(width 0.381)
		(layer "B.Cu")
		(net "P0V9_RETIMER_CPU0_VCC2")
	)
	(segment
		(start 450.666866 -398.31772)
		(end 450.404484 -398.31772)
		(width 0.381)
		(layer "B.Cu")
		(net "P0V9_RETIMER_CPU0_VCC2")
	)
	(segment
		(start 453.958706 -400.691858)
		(end 453.361806 -400.094958)
		(width 0.381)
		(layer "B.Cu")
		(net "P0V9_RETIMER_CPU0_VCC2")
	)
	(segment
		(start 450.666866 -399.128742)
		(end 450.666866 -398.31772)
		(width 0.381)
		(layer "B.Cu")
		(net "P0V9_RETIMER_CPU0_VCC2")
	)
	(segment
		(start 453.361806 -400.094958)
		(end 451.633082 -400.094958)
		(width 0.381)
		(layer "B.Cu")
		(net "P0V9_RETIMER_CPU0_VCC2")
	)
	(segment
		(start 451.633082 -400.094958)
		(end 451.30339 -399.765266)
		(width 0.381)
		(layer "B.Cu")
		(net "P0V9_RETIMER_CPU0_VCC2")
	)
	(segment
		(start 444.895732 -401.150328)
		(end 444.895732 -400.90344)
		(width 0.1778)
		(layer "F.Cu")
		(net "P0V9_RETIMER_CPU0_VCC1")
	)
	(segment
		(start 440.779154 -398.737328)
		(end 440.855354 -398.813528)
		(width 0.381)
		(layer "F.Cu")
		(net "P0V9_RETIMER_CPU0_VCC1")
	)
	(segment
		(start 444.94196 -400.857212)
		(end 444.94196 -400.14525)
		(width 0.1778)
		(layer "F.Cu")
		(net "P0V9_RETIMER_CPU0_VCC1")
	)
	(segment
		(start 441.788296 -398.813528)
		(end 441.98159 -398.620234)
		(width 0.2032)
		(layer "F.Cu")
		(net "P0V9_RETIMER_CPU0_VCC1")
	)
	(segment
		(start 440.855354 -398.813528)
		(end 441.430156 -398.813528)
		(width 0.381)
		(layer "F.Cu")
		(net "P0V9_RETIMER_CPU0_VCC1")
	)
	(segment
		(start 441.98159 -398.620234)
		(end 442.731906 -398.620234)
		(width 0.2032)
		(layer "F.Cu")
		(net "P0V9_RETIMER_CPU0_VCC1")
	)
	(segment
		(start 444.895732 -400.90344)
		(end 444.94196 -400.857212)
		(width 0.1778)
		(layer "F.Cu")
		(net "P0V9_RETIMER_CPU0_VCC1")
	)
	(segment
		(start 441.430156 -398.813528)
		(end 441.788296 -398.813528)
		(width 0.2032)
		(layer "F.Cu")
		(net "P0V9_RETIMER_CPU0_VCC1")
	)
	(via
		(at 440.779154 -398.737328)
		(size 0.508)
		(drill 0.254)
		(layers "F.Cu" "B.Cu")
		(net "P0V9_RETIMER_CPU0_VCC1")
	)
	(via
		(at 444.895732 -401.150328)
		(size 0.508)
		(drill 0.254)
		(layers "F.Cu" "B.Cu")
		(net "P0V9_RETIMER_CPU0_VCC1")
	)
	(segment
		(start 443.709044 -399.96364)
		(end 444.895732 -401.150328)
		(width 0.381)
		(layer "B.Cu")
		(net "P0V9_RETIMER_CPU0_VCC1")
	)
	(segment
		(start 442.345826 -399.96364)
		(end 443.709044 -399.96364)
		(width 0.381)
		(layer "B.Cu")
		(net "P0V9_RETIMER_CPU0_VCC1")
	)
	(segment
		(start 442.005466 -399.96364)
		(end 440.779154 -398.737328)
		(width 0.381)
		(layer "B.Cu")
		(net "P0V9_RETIMER_CPU0_VCC1")
	)
	(segment
		(start 442.345826 -399.96364)
		(end 442.005466 -399.96364)
		(width 0.381)
		(layer "B.Cu")
		(net "P0V9_RETIMER_CPU0_VCC1")
	)
	(segment
		(start 447.843402 -426.71111)
		(end 448.097402 -426.96511)
		(width 0.254)
		(layer "F.Cu")
		(net "P0V9_RETIMER_CPU0_VCC")
	)
	(segment
		(start 447.729102 -425.968922)
		(end 447.729102 -426.59681)
		(width 0.1778)
		(layer "F.Cu")
		(net "P0V9_RETIMER_CPU0_VCC")
	)
	(segment
		(start 447.075052 -425.314872)
		(end 447.729102 -425.968922)
		(width 0.1778)
		(layer "F.Cu")
		(net "P0V9_RETIMER_CPU0_VCC")
	)
	(segment
		(start 447.729102 -426.59681)
		(end 447.843402 -426.71111)
		(width 0.1778)
		(layer "F.Cu")
		(net "P0V9_RETIMER_CPU0_VCC")
	)
	(segment
		(start 446.729612 -425.314872)
		(end 447.075052 -425.314872)
		(width 0.1778)
		(layer "F.Cu")
		(net "P0V9_RETIMER_CPU0_VCC")
	)
	(segment
		(start 449.043552 -426.96511)
		(end 449.043552 -427.152308)
		(width 0.254)
		(layer "F.Cu")
		(net "P0V9_RETIMER_CPU0_VCC")
	)
	(segment
		(start 449.043552 -428.10811)
		(end 449.043552 -429.25111)
		(width 0.254)
		(layer "F.Cu")
		(net "P0V9_RETIMER_CPU0_VCC")
	)
	(segment
		(start 448.097402 -426.96511)
		(end 449.043552 -426.96511)
		(width 0.254)
		(layer "F.Cu")
		(net "P0V9_RETIMER_CPU0_VCC")
	)
	(segment
		(start 449.043552 -427.152308)
		(end 449.043552 -428.10811)
		(width 0.254)
		(layer "F.Cu")
		(net "P0V9_RETIMER_CPU0_VCC")
	)
	(via
		(at 447.843402 -426.71111)
		(size 0.762)
		(drill 0.381)
		(layers "F.Cu" "B.Cu")
		(net "P0V9_RETIMER_CPU0_VCC")
	)
	(segment
		(start 449.043552 -422.77411)
		(end 449.161662 -422.89222)
		(width 0.254)
		(layer "F.Cu")
		(net "P0V9_RETIMER_CPU0_TEMP0")
	)
	(segment
		(start 444.268352 -400.93773)
		(end 444.491872 -400.71421)
		(width 0.2286)
		(layer "F.Cu")
		(net "P0V9_RETIMER_CPU0_TEMP0")
	)
	(segment
		(start 453.288654 -401.057618)
		(end 453.288654 -400.974814)
		(width 0.254)
		(layer "F.Cu")
		(net "P0V9_RETIMER_CPU0_TEMP0")
	)
	(segment
		(start 444.491872 -400.71421)
		(end 444.491872 -400.14525)
		(width 0.2286)
		(layer "F.Cu")
		(net "P0V9_RETIMER_CPU0_TEMP0")
	)
	(segment
		(start 443.681866 -402.178012)
		(end 444.268352 -401.591526)
		(width 0.2286)
		(layer "F.Cu")
		(net "P0V9_RETIMER_CPU0_TEMP0")
	)
	(segment
		(start 453.570594 -400.692874)
		(end 453.570594 -400.14525)
		(width 0.2286)
		(layer "F.Cu")
		(net "P0V9_RETIMER_CPU0_TEMP0")
	)
	(segment
		(start 449.161662 -423.413936)
		(end 448.860672 -423.714926)
		(width 0.1778)
		(layer "F.Cu")
		(net "P0V9_RETIMER_CPU0_TEMP0")
	)
	(segment
		(start 448.860672 -423.714926)
		(end 446.729612 -423.714926)
		(width 0.1778)
		(layer "F.Cu")
		(net "P0V9_RETIMER_CPU0_TEMP0")
	)
	(segment
		(start 449.161662 -422.89222)
		(end 449.161662 -423.413936)
		(width 0.254)
		(layer "F.Cu")
		(net "P0V9_RETIMER_CPU0_TEMP0")
	)
	(segment
		(start 453.288654 -400.974814)
		(end 453.570594 -400.692874)
		(width 0.254)
		(layer "F.Cu")
		(net "P0V9_RETIMER_CPU0_TEMP0")
	)
	(segment
		(start 444.268352 -401.591526)
		(end 444.268352 -400.93773)
		(width 0.2286)
		(layer "F.Cu")
		(net "P0V9_RETIMER_CPU0_TEMP0")
	)
	(via
		(at 449.043552 -422.77411)
		(size 0.508)
		(drill 0.254)
		(layers "F.Cu" "B.Cu")
		(net "P0V9_RETIMER_CPU0_TEMP0")
	)
	(via
		(at 453.288654 -401.057618)
		(size 0.508)
		(drill 0.254)
		(layers "F.Cu" "B.Cu")
		(net "P0V9_RETIMER_CPU0_TEMP0")
	)
	(via
		(at 443.681866 -402.178012)
		(size 0.508)
		(drill 0.254)
		(layers "F.Cu" "B.Cu")
		(net "P0V9_RETIMER_CPU0_TEMP0")
	)
	(segment
		(start 449.043552 -422.01211)
		(end 449.043552 -422.77411)
		(width 0.254)
		(layer "B.Cu")
		(net "P0V9_RETIMER_CPU0_TEMP0")
	)
	(segment
		(start 444.52286 -416.768788)
		(end 441.792868 -414.038796)
		(width 0.254)
		(layer "In2.Cu")
		(net "P0V9_RETIMER_CPU0_TEMP0")
	)
	(segment
		(start 444.52286 -417.530026)
		(end 444.52286 -416.768788)
		(width 0.254)
		(layer "In2.Cu")
		(net "P0V9_RETIMER_CPU0_TEMP0")
	)
	(segment
		(start 449.043552 -422.050718)
		(end 444.52286 -417.530026)
		(width 0.254)
		(layer "In2.Cu")
		(net "P0V9_RETIMER_CPU0_TEMP0")
	)
	(segment
		(start 442.615066 -402.870416)
		(end 443.30747 -402.178012)
		(width 0.254)
		(layer "In2.Cu")
		(net "P0V9_RETIMER_CPU0_TEMP0")
	)
	(segment
		(start 452.29526 -403.607778)
		(end 452.71182 -403.191218)
		(width 0.254)
		(layer "In2.Cu")
		(net "P0V9_RETIMER_CPU0_TEMP0")
	)
	(segment
		(start 441.792868 -405.533098)
		(end 442.615066 -404.7109)
		(width 0.254)
		(layer "In2.Cu")
		(net "P0V9_RETIMER_CPU0_TEMP0")
	)
	(segment
		(start 443.681866 -402.178012)
		(end 445.111632 -403.607778)
		(width 0.254)
		(layer "In2.Cu")
		(net "P0V9_RETIMER_CPU0_TEMP0")
	)
	(segment
		(start 441.792868 -414.038796)
		(end 441.792868 -405.533098)
		(width 0.254)
		(layer "In2.Cu")
		(net "P0V9_RETIMER_CPU0_TEMP0")
	)
	(segment
		(start 443.30747 -402.178012)
		(end 443.681866 -402.178012)
		(width 0.254)
		(layer "In2.Cu")
		(net "P0V9_RETIMER_CPU0_TEMP0")
	)
	(segment
		(start 442.615066 -404.7109)
		(end 442.615066 -402.870416)
		(width 0.254)
		(layer "In2.Cu")
		(net "P0V9_RETIMER_CPU0_TEMP0")
	)
	(segment
		(start 452.71182 -403.191218)
		(end 453.288654 -401.79879)
		(width 0.254)
		(layer "In2.Cu")
		(net "P0V9_RETIMER_CPU0_TEMP0")
	)
	(segment
		(start 453.288654 -401.79879)
		(end 453.288654 -401.057618)
		(width 0.254)
		(layer "In2.Cu")
		(net "P0V9_RETIMER_CPU0_TEMP0")
	)
	(segment
		(start 449.043552 -422.77411)
		(end 449.043552 -422.050718)
		(width 0.254)
		(layer "In2.Cu")
		(net "P0V9_RETIMER_CPU0_TEMP0")
	)
	(segment
		(start 445.111632 -403.607778)
		(end 452.29526 -403.607778)
		(width 0.254)
		(layer "In2.Cu")
		(net "P0V9_RETIMER_CPU0_TEMP0")
	)
	(segment
		(start 454.47077 -400.14525)
		(end 454.47077 -402.121116)
		(width 0.1524)
		(layer "F.Cu")
		(net "P0V9_RETIMER_CPU0_PWM2")
	)
	(segment
		(start 454.502266 -402.152612)
		(end 454.480676 -402.152612)
		(width 0.1524)
		(layer "F.Cu")
		(net "P0V9_RETIMER_CPU0_PWM2")
	)
	(segment
		(start 443.729618 -426.712126)
		(end 443.729618 -426.31487)
		(width 0.1524)
		(layer "F.Cu")
		(net "P0V9_RETIMER_CPU0_PWM2")
	)
	(segment
		(start 444.84036 -428.27956)
		(end 444.84036 -427.822868)
		(width 0.1524)
		(layer "F.Cu")
		(net "P0V9_RETIMER_CPU0_PWM2")
	)
	(segment
		(start 454.47077 -402.121116)
		(end 454.502266 -402.152612)
		(width 0.1524)
		(layer "F.Cu")
		(net "P0V9_RETIMER_CPU0_PWM2")
	)
	(segment
		(start 444.84036 -427.822868)
		(end 443.729618 -426.712126)
		(width 0.1524)
		(layer "F.Cu")
		(net "P0V9_RETIMER_CPU0_PWM2")
	)
	(via
		(at 444.84036 -428.27956)
		(size 0.508)
		(drill 0.254)
		(layers "F.Cu" "B.Cu")
		(net "P0V9_RETIMER_CPU0_PWM2")
	)
	(via
		(at 454.480676 -402.152612)
		(size 0.508)
		(drill 0.254)
		(layers "F.Cu" "B.Cu")
		(net "P0V9_RETIMER_CPU0_PWM2")
	)
	(segment
		(start 453.787256 -405.17191)
		(end 449.631054 -409.328112)
		(width 0.254)
		(layer "In4.Cu")
		(net "P0V9_RETIMER_CPU0_PWM2")
	)
	(segment
		(start 449.631054 -409.328112)
		(end 446.61328 -409.328112)
		(width 0.254)
		(layer "In4.Cu")
		(net "P0V9_RETIMER_CPU0_PWM2")
	)
	(segment
		(start 441.700158 -416.297618)
		(end 441.700158 -425.60875)
		(width 0.254)
		(layer "In4.Cu")
		(net "P0V9_RETIMER_CPU0_PWM2")
	)
	(segment
		(start 442.823854 -415.173922)
		(end 441.700158 -416.297618)
		(width 0.254)
		(layer "In4.Cu")
		(net "P0V9_RETIMER_CPU0_PWM2")
	)
	(segment
		(start 446.61328 -409.328112)
		(end 445.546988 -410.394404)
		(width 0.254)
		(layer "In4.Cu")
		(net "P0V9_RETIMER_CPU0_PWM2")
	)
	(segment
		(start 445.546988 -410.394404)
		(end 445.546988 -414.046162)
		(width 0.254)
		(layer "In4.Cu")
		(net "P0V9_RETIMER_CPU0_PWM2")
	)
	(segment
		(start 441.700158 -425.60875)
		(end 442.385704 -426.294296)
		(width 0.254)
		(layer "In4.Cu")
		(net "P0V9_RETIMER_CPU0_PWM2")
	)
	(segment
		(start 453.787256 -402.720048)
		(end 453.787256 -405.17191)
		(width 0.254)
		(layer "In4.Cu")
		(net "P0V9_RETIMER_CPU0_PWM2")
	)
	(segment
		(start 443.19571 -426.294296)
		(end 444.84036 -427.938946)
		(width 0.254)
		(layer "In4.Cu")
		(net "P0V9_RETIMER_CPU0_PWM2")
	)
	(segment
		(start 445.546988 -414.046162)
		(end 442.823854 -415.173922)
		(width 0.254)
		(layer "In4.Cu")
		(net "P0V9_RETIMER_CPU0_PWM2")
	)
	(segment
		(start 453.893682 -402.463254)
		(end 453.787256 -402.720048)
		(width 0.254)
		(layer "In4.Cu")
		(net "P0V9_RETIMER_CPU0_PWM2")
	)
	(segment
		(start 454.204324 -402.152612)
		(end 453.893682 -402.463254)
		(width 0.254)
		(layer "In4.Cu")
		(net "P0V9_RETIMER_CPU0_PWM2")
	)
	(segment
		(start 442.385704 -426.294296)
		(end 443.19571 -426.294296)
		(width 0.254)
		(layer "In4.Cu")
		(net "P0V9_RETIMER_CPU0_PWM2")
	)
	(segment
		(start 454.480676 -402.152612)
		(end 454.204324 -402.152612)
		(width 0.254)
		(layer "In4.Cu")
		(net "P0V9_RETIMER_CPU0_PWM2")
	)
	(segment
		(start 444.84036 -427.938946)
		(end 444.84036 -428.27956)
		(width 0.254)
		(layer "In4.Cu")
		(net "P0V9_RETIMER_CPU0_PWM2")
	)
	(segment
		(start 445.392048 -402.203412)
		(end 445.392048 -400.14525)
		(width 0.1524)
		(layer "F.Cu")
		(net "P0V9_RETIMER_CPU0_PWM1")
	)
	(segment
		(start 443.329568 -426.820076)
		(end 443.329568 -426.31487)
		(width 0.1524)
		(layer "F.Cu")
		(net "P0V9_RETIMER_CPU0_PWM1")
	)
	(segment
		(start 443.988444 -427.478952)
		(end 443.329568 -426.820076)
		(width 0.1524)
		(layer "F.Cu")
		(net "P0V9_RETIMER_CPU0_PWM1")
	)
	(segment
		(start 443.988444 -428.29861)
		(end 443.988444 -427.478952)
		(width 0.1524)
		(layer "F.Cu")
		(net "P0V9_RETIMER_CPU0_PWM1")
	)
	(via
		(at 443.988444 -428.29861)
		(size 0.508)
		(drill 0.254)
		(layers "F.Cu" "B.Cu")
		(net "P0V9_RETIMER_CPU0_PWM1")
	)
	(via
		(at 445.392048 -402.203412)
		(size 0.508)
		(drill 0.254)
		(layers "F.Cu" "B.Cu")
		(net "P0V9_RETIMER_CPU0_PWM1")
	)
	(segment
		(start 443.879478 -428.189644)
		(end 443.988444 -428.29861)
		(width 0.254)
		(layer "In4.Cu")
		(net "P0V9_RETIMER_CPU0_PWM1")
	)
	(segment
		(start 444.697866 -404.29307)
		(end 436.082948 -412.907988)
		(width 0.254)
		(layer "In4.Cu")
		(net "P0V9_RETIMER_CPU0_PWM1")
	)
	(segment
		(start 444.697866 -402.897594)
		(end 444.697866 -404.29307)
		(width 0.254)
		(layer "In4.Cu")
		(net "P0V9_RETIMER_CPU0_PWM1")
	)
	(segment
		(start 445.392048 -402.203412)
		(end 444.697866 -402.897594)
		(width 0.254)
		(layer "In4.Cu")
		(net "P0V9_RETIMER_CPU0_PWM1")
	)
	(segment
		(start 437.768746 -428.189644)
		(end 443.879478 -428.189644)
		(width 0.254)
		(layer "In4.Cu")
		(net "P0V9_RETIMER_CPU0_PWM1")
	)
	(segment
		(start 436.082948 -426.503846)
		(end 437.768746 -428.189644)
		(width 0.254)
		(layer "In4.Cu")
		(net "P0V9_RETIMER_CPU0_PWM1")
	)
	(segment
		(start 436.082948 -412.907988)
		(end 436.082948 -426.503846)
		(width 0.254)
		(layer "In4.Cu")
		(net "P0V9_RETIMER_CPU0_PWM1")
	)
	(segment
		(start 439.471308 -405.388572)
		(end 439.471308 -401.136358)
		(width 0.4572)
		(layer "F.Cu")
		(net "P0V9_RETIMER_CPU0_PVCC")
	)
	(segment
		(start 438.455308 -405.388572)
		(end 439.471308 -405.388572)
		(width 0.4572)
		(layer "F.Cu")
		(net "P0V9_RETIMER_CPU0_PVCC")
	)
	(segment
		(start 440.479434 -397.839184)
		(end 440.78271 -397.839184)
		(width 0.4572)
		(layer "F.Cu")
		(net "P0V9_RETIMER_CPU0_PVCC")
	)
	(segment
		(start 442.0362 -398.1704)
		(end 442.731906 -398.1704)
		(width 0.2032)
		(layer "F.Cu")
		(net "P0V9_RETIMER_CPU0_PVCC")
	)
	(segment
		(start 451.810628 -398.1704)
		(end 451.119494 -398.1704)
		(width 0.2286)
		(layer "F.Cu")
		(net "P0V9_RETIMER_CPU0_PVCC")
	)
	(segment
		(start 450.911722 -397.962628)
		(end 450.508878 -397.962628)
		(width 0.2286)
		(layer "F.Cu")
		(net "P0V9_RETIMER_CPU0_PVCC")
	)
	(segment
		(start 451.119494 -398.1704)
		(end 450.911722 -397.962628)
		(width 0.2286)
		(layer "F.Cu")
		(net "P0V9_RETIMER_CPU0_PVCC")
	)
	(segment
		(start 439.471308 -398.84731)
		(end 440.479434 -397.839184)
		(width 0.4572)
		(layer "F.Cu")
		(net "P0V9_RETIMER_CPU0_PVCC")
	)
	(segment
		(start 439.471308 -401.136358)
		(end 439.471308 -398.84731)
		(width 0.4572)
		(layer "F.Cu")
		(net "P0V9_RETIMER_CPU0_PVCC")
	)
	(segment
		(start 441.701428 -397.835628)
		(end 442.0362 -398.1704)
		(width 0.2032)
		(layer "F.Cu")
		(net "P0V9_RETIMER_CPU0_PVCC")
	)
	(segment
		(start 450.508878 -397.962628)
		(end 449.854066 -397.962628)
		(width 0.381)
		(layer "F.Cu")
		(net "P0V9_RETIMER_CPU0_PVCC")
	)
	(segment
		(start 440.786266 -397.835628)
		(end 441.430156 -397.835628)
		(width 0.4572)
		(layer "F.Cu")
		(net "P0V9_RETIMER_CPU0_PVCC")
	)
	(segment
		(start 440.78271 -397.839184)
		(end 440.786266 -397.835628)
		(width 0.4572)
		(layer "F.Cu")
		(net "P0V9_RETIMER_CPU0_PVCC")
	)
	(segment
		(start 441.430156 -397.835628)
		(end 441.701428 -397.835628)
		(width 0.2032)
		(layer "F.Cu")
		(net "P0V9_RETIMER_CPU0_PVCC")
	)
	(via
		(at 440.786266 -397.835628)
		(size 0.508)
		(drill 0.254)
		(layers "F.Cu" "B.Cu")
		(net "P0V9_RETIMER_CPU0_PVCC")
	)
	(via
		(at 439.471308 -401.136358)
		(size 0.762)
		(drill 0.381)
		(layers "F.Cu" "B.Cu")
		(net "P0V9_RETIMER_CPU0_PVCC")
	)
	(via
		(at 449.854066 -397.962628)
		(size 0.508)
		(drill 0.254)
		(layers "F.Cu" "B.Cu")
		(net "P0V9_RETIMER_CPU0_PVCC")
	)
	(segment
		(start 440.865514 -397.835628)
		(end 442.193426 -399.16354)
		(width 0.381)
		(layer "B.Cu")
		(net "P0V9_RETIMER_CPU0_PVCC")
	)
	(segment
		(start 450.299074 -397.51762)
		(end 449.854066 -397.962628)
		(width 0.381)
		(layer "B.Cu")
		(net "P0V9_RETIMER_CPU0_PVCC")
	)
	(segment
		(start 450.666866 -397.51762)
		(end 450.299074 -397.51762)
		(width 0.381)
		(layer "B.Cu")
		(net "P0V9_RETIMER_CPU0_PVCC")
	)
	(segment
		(start 440.786266 -397.835628)
		(end 440.865514 -397.835628)
		(width 0.381)
		(layer "B.Cu")
		(net "P0V9_RETIMER_CPU0_PVCC")
	)
	(segment
		(start 442.193426 -399.16354)
		(end 442.345826 -399.16354)
		(width 0.381)
		(layer "B.Cu")
		(net "P0V9_RETIMER_CPU0_PVCC")
	)
	(segment
		(start 445.595502 -400.293332)
		(end 443.48273 -400.293332)
		(width 0.508)
		(layer "In2.Cu")
		(net "P0V9_RETIMER_CPU0_PVCC")
	)
	(segment
		(start 447.392552 -402.090382)
		(end 445.595502 -400.293332)
		(width 0.508)
		(layer "In2.Cu")
		(net "P0V9_RETIMER_CPU0_PVCC")
	)
	(segment
		(start 450.67601 -400.699732)
		(end 449.28536 -402.090382)
		(width 0.508)
		(layer "In2.Cu")
		(net "P0V9_RETIMER_CPU0_PVCC")
	)
	(segment
		(start 449.854066 -397.962628)
		(end 450.330062 -397.962628)
		(width 0.508)
		(layer "In2.Cu")
		(net "P0V9_RETIMER_CPU0_PVCC")
	)
	(segment
		(start 450.330062 -397.962628)
		(end 450.67601 -398.308576)
		(width 0.508)
		(layer "In2.Cu")
		(net "P0V9_RETIMER_CPU0_PVCC")
	)
	(segment
		(start 441.025026 -397.835628)
		(end 440.786266 -397.835628)
		(width 0.508)
		(layer "In2.Cu")
		(net "P0V9_RETIMER_CPU0_PVCC")
	)
	(segment
		(start 450.67601 -398.308576)
		(end 450.67601 -400.699732)
		(width 0.508)
		(layer "In2.Cu")
		(net "P0V9_RETIMER_CPU0_PVCC")
	)
	(segment
		(start 449.28536 -402.090382)
		(end 447.392552 -402.090382)
		(width 0.508)
		(layer "In2.Cu")
		(net "P0V9_RETIMER_CPU0_PVCC")
	)
	(segment
		(start 443.48273 -400.293332)
		(end 441.025026 -397.835628)
		(width 0.508)
		(layer "In2.Cu")
		(net "P0V9_RETIMER_CPU0_PVCC")
	)
	(segment
		(start 442.929518 -426.31487)
		(end 442.929518 -427.359826)
		(width 0.10668)
		(layer "F.Cu")
		(net "P0V9_RETIMER_CPU0_PMSDA_R")
	)
	(segment
		(start 442.929518 -427.359826)
		(end 443.347602 -427.77791)
		(width 0.10668)
		(layer "F.Cu")
		(net "P0V9_RETIMER_CPU0_PMSDA_R")
	)
	(segment
		(start 443.347602 -427.77791)
		(end 443.347602 -428.97806)
		(width 0.10668)
		(layer "F.Cu")
		(net "P0V9_RETIMER_CPU0_PMSDA_R")
	)
	(via
		(at 443.347602 -427.77791)
		(size 0.762)
		(drill 0.381)
		(layers "F.Cu" "B.Cu")
		(net "P0V9_RETIMER_CPU0_PMSDA_R")
	)
	(segment
		(start 442.077602 -428.97806)
		(end 442.077602 -427.77791)
		(width 0.10668)
		(layer "F.Cu")
		(net "P0V9_RETIMER_CPU0_PMSCL_R")
	)
	(segment
		(start 442.077602 -427.77791)
		(end 442.529468 -427.326044)
		(width 0.10668)
		(layer "F.Cu")
		(net "P0V9_RETIMER_CPU0_PMSCL_R")
	)
	(segment
		(start 442.529468 -427.326044)
		(end 442.529468 -426.31487)
		(width 0.10668)
		(layer "F.Cu")
		(net "P0V9_RETIMER_CPU0_PMSCL_R")
	)
	(via
		(at 442.077602 -427.77791)
		(size 0.762)
		(drill 0.381)
		(layers "F.Cu" "B.Cu")
		(net "P0V9_RETIMER_CPU0_PMSCL_R")
	)
	(segment
		(start 440.807602 -427.77791)
		(end 440.807602 -428.97806)
		(width 0.13462)
		(layer "F.Cu")
		(net "TP_P0V9_RETIMER_CPU0_PMALERT")
	)
	(segment
		(start 441.677806 -425.714922)
		(end 441.92952 -425.714922)
		(width 0.13462)
		(layer "F.Cu")
		(net "TP_P0V9_RETIMER_CPU0_PMALERT")
	)
	(segment
		(start 441.613544 -426.971968)
		(end 441.613544 -425.779184)
		(width 0.13462)
		(layer "F.Cu")
		(net "TP_P0V9_RETIMER_CPU0_PMALERT")
	)
	(segment
		(start 441.613544 -425.779184)
		(end 441.677806 -425.714922)
		(width 0.13462)
		(layer "F.Cu")
		(net "TP_P0V9_RETIMER_CPU0_PMALERT")
	)
	(segment
		(start 440.807602 -427.77791)
		(end 441.613544 -426.971968)
		(width 0.13462)
		(layer "F.Cu")
		(net "TP_P0V9_RETIMER_CPU0_PMALERT")
	)
	(via
		(at 440.807602 -427.77791)
		(size 0.762)
		(drill 0.381)
		(layers "F.Cu" "B.Cu")
		(net "TP_P0V9_RETIMER_CPU0_PMALERT")
	)
	(segment
		(start 452.267066 -401.873212)
		(end 452.267066 -402.257768)
		(width 0.1524)
		(layer "F.Cu")
		(net "P0V9_RETIMER_CPU0_LSET2")
	)
	(segment
		(start 452.267066 -402.257768)
		(end 452.810626 -402.801328)
		(width 0.1524)
		(layer "F.Cu")
		(net "P0V9_RETIMER_CPU0_LSET2")
	)
	(segment
		(start 453.12076 -400.57451)
		(end 452.58863 -401.10664)
		(width 0.1524)
		(layer "F.Cu")
		(net "P0V9_RETIMER_CPU0_LSET2")
	)
	(segment
		(start 453.12076 -400.14525)
		(end 453.12076 -400.57451)
		(width 0.1524)
		(layer "F.Cu")
		(net "P0V9_RETIMER_CPU0_LSET2")
	)
	(segment
		(start 452.58863 -401.10664)
		(end 452.58863 -401.551648)
		(width 0.1524)
		(layer "F.Cu")
		(net "P0V9_RETIMER_CPU0_LSET2")
	)
	(segment
		(start 452.58863 -401.551648)
		(end 452.267066 -401.873212)
		(width 0.1524)
		(layer "F.Cu")
		(net "P0V9_RETIMER_CPU0_LSET2")
	)
	(via
		(at 452.267066 -401.873212)
		(size 0.508)
		(drill 0.254)
		(layers "F.Cu" "B.Cu")
		(net "P0V9_RETIMER_CPU0_LSET2")
	)
	(segment
		(start 443.199266 -402.692616)
		(end 443.072266 -402.565616)
		(width 0.1524)
		(layer "F.Cu")
		(net "P0V9_RETIMER_CPU0_LSET1")
	)
	(segment
		(start 443.811406 -400.888708)
		(end 444.042038 -400.658076)
		(width 0.1524)
		(layer "F.Cu")
		(net "P0V9_RETIMER_CPU0_LSET1")
	)
	(segment
		(start 444.221616 -402.81987)
		(end 444.094362 -402.692616)
		(width 0.1524)
		(layer "F.Cu")
		(net "P0V9_RETIMER_CPU0_LSET1")
	)
	(segment
		(start 443.072266 -402.075904)
		(end 443.811406 -401.336764)
		(width 0.1524)
		(layer "F.Cu")
		(net "P0V9_RETIMER_CPU0_LSET1")
	)
	(segment
		(start 443.811406 -401.336764)
		(end 443.811406 -400.888708)
		(width 0.1524)
		(layer "F.Cu")
		(net "P0V9_RETIMER_CPU0_LSET1")
	)
	(segment
		(start 444.094362 -402.692616)
		(end 443.199266 -402.692616)
		(width 0.1524)
		(layer "F.Cu")
		(net "P0V9_RETIMER_CPU0_LSET1")
	)
	(segment
		(start 443.072266 -402.565616)
		(end 443.072266 -402.075904)
		(width 0.1524)
		(layer "F.Cu")
		(net "P0V9_RETIMER_CPU0_LSET1")
	)
	(segment
		(start 444.042038 -400.658076)
		(end 444.042038 -400.14525)
		(width 0.1524)
		(layer "F.Cu")
		(net "P0V9_RETIMER_CPU0_LSET1")
	)
	(segment
		(start 451.66788 -401.45843)
		(end 451.66788 -402.528532)
		(width 0.2286)
		(layer "F.Cu")
		(net "P0V9_RETIMER_CPU0_IMON2")
	)
	(segment
		(start 443.093602 -419.412166)
		(end 443.093602 -419.90391)
		(width 0.254)
		(layer "F.Cu")
		(net "P0V9_RETIMER_CPU0_IMON2")
	)
	(segment
		(start 452.670672 -400.14525)
		(end 452.670672 -400.455638)
		(width 0.2286)
		(layer "F.Cu")
		(net "P0V9_RETIMER_CPU0_IMON2")
	)
	(segment
		(start 451.66788 -402.528532)
		(end 451.813676 -402.674328)
		(width 0.2286)
		(layer "F.Cu")
		(net "P0V9_RETIMER_CPU0_IMON2")
	)
	(segment
		(start 443.729618 -420.539926)
		(end 443.729618 -421.514778)
		(width 0.1778)
		(layer "F.Cu")
		(net "P0V9_RETIMER_CPU0_IMON2")
	)
	(segment
		(start 452.670672 -400.455638)
		(end 451.66788 -401.45843)
		(width 0.2286)
		(layer "F.Cu")
		(net "P0V9_RETIMER_CPU0_IMON2")
	)
	(segment
		(start 443.093602 -419.90391)
		(end 443.729618 -420.539926)
		(width 0.1778)
		(layer "F.Cu")
		(net "P0V9_RETIMER_CPU0_IMON2")
	)
	(via
		(at 443.093602 -419.412166)
		(size 0.508)
		(drill 0.254)
		(layers "F.Cu" "B.Cu")
		(net "P0V9_RETIMER_CPU0_IMON2")
	)
	(via
		(at 451.813676 -402.674328)
		(size 0.508)
		(drill 0.254)
		(layers "F.Cu" "B.Cu")
		(net "P0V9_RETIMER_CPU0_IMON2")
	)
	(segment
		(start 450.347842 -409.616148)
		(end 451.69455 -408.26944)
		(width 0.254)
		(layer "In15.Cu")
		(net "P0V9_RETIMER_CPU0_IMON2")
	)
	(segment
		(start 441.940442 -417.404804)
		(end 441.940442 -409.89504)
		(width 0.254)
		(layer "In15.Cu")
		(net "P0V9_RETIMER_CPU0_IMON2")
	)
	(segment
		(start 451.69455 -408.26944)
		(end 451.69455 -402.793454)
		(width 0.254)
		(layer "In15.Cu")
		(net "P0V9_RETIMER_CPU0_IMON2")
	)
	(segment
		(start 443.093602 -418.557964)
		(end 441.940442 -417.404804)
		(width 0.254)
		(layer "In15.Cu")
		(net "P0V9_RETIMER_CPU0_IMON2")
	)
	(segment
		(start 441.940442 -409.89504)
		(end 441.941712 -409.89377)
		(width 0.254)
		(layer "In15.Cu")
		(net "P0V9_RETIMER_CPU0_IMON2")
	)
	(segment
		(start 451.69455 -402.793454)
		(end 451.813676 -402.674328)
		(width 0.254)
		(layer "In15.Cu")
		(net "P0V9_RETIMER_CPU0_IMON2")
	)
	(segment
		(start 442.068712 -409.616148)
		(end 450.347842 -409.616148)
		(width 0.254)
		(layer "In15.Cu")
		(net "P0V9_RETIMER_CPU0_IMON2")
	)
	(segment
		(start 441.941712 -409.89377)
		(end 441.941712 -409.743148)
		(width 0.254)
		(layer "In15.Cu")
		(net "P0V9_RETIMER_CPU0_IMON2")
	)
	(segment
		(start 441.941712 -409.743148)
		(end 442.068712 -409.616148)
		(width 0.254)
		(layer "In15.Cu")
		(net "P0V9_RETIMER_CPU0_IMON2")
	)
	(segment
		(start 443.093602 -419.412166)
		(end 443.093602 -418.557964)
		(width 0.254)
		(layer "In15.Cu")
		(net "P0V9_RETIMER_CPU0_IMON2")
	)
	(segment
		(start 443.576202 -400.535394)
		(end 443.415166 -400.69643)
		(width 0.2286)
		(layer "F.Cu")
		(net "P0V9_RETIMER_CPU0_IMON1")
	)
	(segment
		(start 442.538866 -402.899118)
		(end 442.916818 -403.27707)
		(width 0.254)
		(layer "F.Cu")
		(net "P0V9_RETIMER_CPU0_IMON1")
	)
	(segment
		(start 443.415166 -400.69643)
		(end 443.415166 -401.172172)
		(width 0.2286)
		(layer "F.Cu")
		(net "P0V9_RETIMER_CPU0_IMON1")
	)
	(segment
		(start 443.59195 -400.14525)
		(end 443.59195 -400.502628)
		(width 0.2286)
		(layer "F.Cu")
		(net "P0V9_RETIMER_CPU0_IMON1")
	)
	(segment
		(start 443.59195 -400.502628)
		(end 443.576202 -400.518376)
		(width 0.2286)
		(layer "F.Cu")
		(net "P0V9_RETIMER_CPU0_IMON1")
	)
	(segment
		(start 443.415166 -401.172172)
		(end 442.538866 -402.048472)
		(width 0.2286)
		(layer "F.Cu")
		(net "P0V9_RETIMER_CPU0_IMON1")
	)
	(segment
		(start 442.916818 -403.27707)
		(end 443.504066 -403.27707)
		(width 0.254)
		(layer "F.Cu")
		(net "P0V9_RETIMER_CPU0_IMON1")
	)
	(segment
		(start 443.576202 -400.518376)
		(end 443.576202 -400.535394)
		(width 0.2286)
		(layer "F.Cu")
		(net "P0V9_RETIMER_CPU0_IMON1")
	)
	(segment
		(start 443.220602 -420.74211)
		(end 443.329568 -420.851076)
		(width 0.1778)
		(layer "F.Cu")
		(net "P0V9_RETIMER_CPU0_IMON1")
	)
	(segment
		(start 443.329568 -420.851076)
		(end 443.329568 -421.514778)
		(width 0.1778)
		(layer "F.Cu")
		(net "P0V9_RETIMER_CPU0_IMON1")
	)
	(segment
		(start 442.538866 -402.048472)
		(end 442.538866 -402.899118)
		(width 0.254)
		(layer "F.Cu")
		(net "P0V9_RETIMER_CPU0_IMON1")
	)
	(via
		(at 443.220602 -420.74211)
		(size 0.508)
		(drill 0.254)
		(layers "F.Cu" "B.Cu")
		(net "P0V9_RETIMER_CPU0_IMON1")
	)
	(via
		(at 443.504066 -403.27707)
		(size 0.508)
		(drill 0.254)
		(layers "F.Cu" "B.Cu")
		(net "P0V9_RETIMER_CPU0_IMON1")
	)
	(segment
		(start 439.573924 -415.92627)
		(end 439.947558 -415.552636)
		(width 0.254)
		(layer "In15.Cu")
		(net "P0V9_RETIMER_CPU0_IMON1")
	)
	(segment
		(start 439.947558 -415.552636)
		(end 439.947558 -408.300174)
		(width 0.254)
		(layer "In15.Cu")
		(net "P0V9_RETIMER_CPU0_IMON1")
	)
	(segment
		(start 442.467746 -420.74211)
		(end 441.938156 -420.21252)
		(width 0.254)
		(layer "In15.Cu")
		(net "P0V9_RETIMER_CPU0_IMON1")
	)
	(segment
		(start 442.355224 -404.425912)
		(end 443.504066 -403.27707)
		(width 0.254)
		(layer "In15.Cu")
		(net "P0V9_RETIMER_CPU0_IMON1")
	)
	(segment
		(start 441.938156 -419.213284)
		(end 439.573924 -416.849052)
		(width 0.254)
		(layer "In15.Cu")
		(net "P0V9_RETIMER_CPU0_IMON1")
	)
	(segment
		(start 439.947558 -408.300174)
		(end 442.355224 -405.892508)
		(width 0.254)
		(layer "In15.Cu")
		(net "P0V9_RETIMER_CPU0_IMON1")
	)
	(segment
		(start 439.573924 -416.849052)
		(end 439.573924 -415.92627)
		(width 0.254)
		(layer "In15.Cu")
		(net "P0V9_RETIMER_CPU0_IMON1")
	)
	(segment
		(start 443.220602 -420.74211)
		(end 442.467746 -420.74211)
		(width 0.254)
		(layer "In15.Cu")
		(net "P0V9_RETIMER_CPU0_IMON1")
	)
	(segment
		(start 441.938156 -420.21252)
		(end 441.938156 -419.213284)
		(width 0.254)
		(layer "In15.Cu")
		(net "P0V9_RETIMER_CPU0_IMON1")
	)
	(segment
		(start 442.355224 -405.892508)
		(end 442.355224 -404.425912)
		(width 0.254)
		(layer "In15.Cu")
		(net "P0V9_RETIMER_CPU0_IMON1")
	)
	(segment
		(start 437.09463 -425.134786)
		(end 437.09463 -423.798492)
		(width 0.1524)
		(layer "F.Cu")
		(net "P0V9_RETIMER_CPU0_EN")
	)
	(via
		(at 218.577414 -113.306606)
		(size 0.508)
		(drill 0.254)
		(layers "F.Cu" "B.Cu")
		(net "P0V9_RETIMER_CPU0_EN")
	)
	(via
		(at 215.93937 -85.100668)
		(size 0.508)
		(drill 0.254)
		(layers "F.Cu" "B.Cu")
		(net "P0V9_RETIMER_CPU0_EN")
	)
	(via
		(at 437.09463 -423.798492)
		(size 0.508)
		(drill 0.254)
		(layers "F.Cu" "B.Cu")
		(net "P0V9_RETIMER_CPU0_EN")
	)
	(segment
		(start 199.484234 -111.519208)
		(end 200.568814 -111.519208)
		(width 0.1524)
		(layer "B.Cu")
		(net "P0V9_RETIMER_CPU0_EN")
	)
	(segment
		(start 198.063104 -111.962946)
		(end 199.040496 -111.962946)
		(width 0.1524)
		(layer "B.Cu")
		(net "P0V9_RETIMER_CPU0_EN")
	)
	(segment
		(start 202.166982 -113.117376)
		(end 203.016358 -113.117376)
		(width 0.1524)
		(layer "B.Cu")
		(net "P0V9_RETIMER_CPU0_EN")
	)
	(segment
		(start 200.568814 -111.519208)
		(end 202.166982 -113.117376)
		(width 0.1524)
		(layer "B.Cu")
		(net "P0V9_RETIMER_CPU0_EN")
	)
	(segment
		(start 199.040496 -111.962946)
		(end 199.484234 -111.519208)
		(width 0.1524)
		(layer "B.Cu")
		(net "P0V9_RETIMER_CPU0_EN")
	)
	(segment
		(start 207.513682 -113.307622)
		(end 209.530442 -111.290862)
		(width 0.1524)
		(layer "B.Cu")
		(net "P0V9_RETIMER_CPU0_EN")
	)
	(segment
		(start 203.016358 -113.117376)
		(end 203.206604 -113.307622)
		(width 0.1524)
		(layer "B.Cu")
		(net "P0V9_RETIMER_CPU0_EN")
	)
	(segment
		(start 203.206604 -113.307622)
		(end 207.513682 -113.307622)
		(width 0.1524)
		(layer "B.Cu")
		(net "P0V9_RETIMER_CPU0_EN")
	)
	(segment
		(start 210.525614 -110.961424)
		(end 216.232232 -110.961424)
		(width 0.1524)
		(layer "B.Cu")
		(net "P0V9_RETIMER_CPU0_EN")
	)
	(segment
		(start 197.37705 -112.395)
		(end 197.63105 -112.395)
		(width 0.1524)
		(layer "B.Cu")
		(net "P0V9_RETIMER_CPU0_EN")
	)
	(segment
		(start 209.530442 -111.290862)
		(end 210.196176 -111.290862)
		(width 0.1524)
		(layer "B.Cu")
		(net "P0V9_RETIMER_CPU0_EN")
	)
	(segment
		(start 216.232232 -110.961424)
		(end 218.577414 -113.306606)
		(width 0.1524)
		(layer "B.Cu")
		(net "P0V9_RETIMER_CPU0_EN")
	)
	(segment
		(start 210.196176 -111.290862)
		(end 210.525614 -110.961424)
		(width 0.1524)
		(layer "B.Cu")
		(net "P0V9_RETIMER_CPU0_EN")
	)
	(segment
		(start 197.63105 -112.395)
		(end 198.063104 -111.962946)
		(width 0.1524)
		(layer "B.Cu")
		(net "P0V9_RETIMER_CPU0_EN")
	)
	(segment
		(start 265.02741 -77.73289)
		(end 245.919244 -77.73289)
		(width 0.1524)
		(layer "In2.Cu")
		(net "P0V9_RETIMER_CPU0_EN")
	)
	(segment
		(start 436.390542 -423.094404)
		(end 436.390542 -414.066228)
		(width 0.1524)
		(layer "In2.Cu")
		(net "P0V9_RETIMER_CPU0_EN")
	)
	(segment
		(start 458.288136 -141.193012)
		(end 433.796186 -116.701062)
		(width 0.1524)
		(layer "In2.Cu")
		(net "P0V9_RETIMER_CPU0_EN")
	)
	(segment
		(start 456.056492 -153.311606)
		(end 458.288136 -151.079962)
		(width 0.1524)
		(layer "In2.Cu")
		(net "P0V9_RETIMER_CPU0_EN")
	)
	(segment
		(start 329.557888 -119.416068)
		(end 317.680594 -107.538774)
		(width 0.1524)
		(layer "In2.Cu")
		(net "P0V9_RETIMER_CPU0_EN")
	)
	(segment
		(start 373.263414 -119.416068)
		(end 329.557888 -119.416068)
		(width 0.1524)
		(layer "In2.Cu")
		(net "P0V9_RETIMER_CPU0_EN")
	)
	(segment
		(start 376.32386 -116.355622)
		(end 373.263414 -119.416068)
		(width 0.1524)
		(layer "In2.Cu")
		(net "P0V9_RETIMER_CPU0_EN")
	)
	(segment
		(start 438.441592 -402.87829)
		(end 438.441592 -397.021558)
		(width 0.1524)
		(layer "In2.Cu")
		(net "P0V9_RETIMER_CPU0_EN")
	)
	(segment
		(start 440.770772 -387.700774)
		(end 440.770772 -376.16003)
		(width 0.1524)
		(layer "In2.Cu")
		(net "P0V9_RETIMER_CPU0_EN")
	)
	(segment
		(start 455.884788 -353.188524)
		(end 455.884788 -344.628724)
		(width 0.1524)
		(layer "In2.Cu")
		(net "P0V9_RETIMER_CPU0_EN")
	)
	(segment
		(start 438.441592 -397.021558)
		(end 436.292244 -394.87221)
		(width 0.1524)
		(layer "In2.Cu")
		(net "P0V9_RETIMER_CPU0_EN")
	)
	(segment
		(start 312.059574 -107.538774)
		(end 309.9308 -105.41)
		(width 0.1524)
		(layer "In2.Cu")
		(net "P0V9_RETIMER_CPU0_EN")
	)
	(segment
		(start 457.070206 -354.373942)
		(end 455.884788 -353.188524)
		(width 0.1524)
		(layer "In2.Cu")
		(net "P0V9_RETIMER_CPU0_EN")
	)
	(segment
		(start 458.288136 -151.079962)
		(end 458.288136 -141.193012)
		(width 0.1524)
		(layer "In2.Cu")
		(net "P0V9_RETIMER_CPU0_EN")
	)
	(segment
		(start 456.056492 -162.908488)
		(end 456.056492 -153.311606)
		(width 0.1524)
		(layer "In2.Cu")
		(net "P0V9_RETIMER_CPU0_EN")
	)
	(segment
		(start 243.789454 -82.866992)
		(end 239.254284 -87.402162)
		(width 0.1524)
		(layer "In2.Cu")
		(net "P0V9_RETIMER_CPU0_EN")
	)
	(segment
		(start 442.98489 -373.945912)
		(end 452.279766 -373.945912)
		(width 0.1524)
		(layer "In2.Cu")
		(net "P0V9_RETIMER_CPU0_EN")
	)
	(segment
		(start 440.770772 -376.16003)
		(end 442.98489 -373.945912)
		(width 0.1524)
		(layer "In2.Cu")
		(net "P0V9_RETIMER_CPU0_EN")
	)
	(segment
		(start 437.364632 -403.95525)
		(end 438.441592 -402.87829)
		(width 0.1524)
		(layer "In2.Cu")
		(net "P0V9_RETIMER_CPU0_EN")
	)
	(segment
		(start 437.09463 -423.798492)
		(end 436.390542 -423.094404)
		(width 0.1524)
		(layer "In2.Cu")
		(net "P0V9_RETIMER_CPU0_EN")
	)
	(segment
		(start 243.789454 -79.86268)
		(end 243.789454 -82.866992)
		(width 0.1524)
		(layer "In2.Cu")
		(net "P0V9_RETIMER_CPU0_EN")
	)
	(segment
		(start 245.919244 -77.73289)
		(end 243.789454 -79.86268)
		(width 0.1524)
		(layer "In2.Cu")
		(net "P0V9_RETIMER_CPU0_EN")
	)
	(segment
		(start 436.292244 -392.179302)
		(end 440.770772 -387.700774)
		(width 0.1524)
		(layer "In2.Cu")
		(net "P0V9_RETIMER_CPU0_EN")
	)
	(segment
		(start 216.872058 -85.100668)
		(end 215.93937 -85.100668)
		(width 0.1524)
		(layer "In2.Cu")
		(net "P0V9_RETIMER_CPU0_EN")
	)
	(segment
		(start 436.390542 -414.066228)
		(end 437.364632 -413.092138)
		(width 0.1524)
		(layer "In2.Cu")
		(net "P0V9_RETIMER_CPU0_EN")
	)
	(segment
		(start 455.884788 -344.628724)
		(end 466.814916 -333.698596)
		(width 0.1524)
		(layer "In2.Cu")
		(net "P0V9_RETIMER_CPU0_EN")
	)
	(segment
		(start 437.364632 -413.092138)
		(end 437.364632 -403.95525)
		(width 0.1524)
		(layer "In2.Cu")
		(net "P0V9_RETIMER_CPU0_EN")
	)
	(segment
		(start 460.985616 -167.837612)
		(end 456.056492 -162.908488)
		(width 0.1524)
		(layer "In2.Cu")
		(net "P0V9_RETIMER_CPU0_EN")
	)
	(segment
		(start 452.279766 -373.945912)
		(end 457.070206 -369.155472)
		(width 0.1524)
		(layer "In2.Cu")
		(net "P0V9_RETIMER_CPU0_EN")
	)
	(segment
		(start 317.680594 -107.538774)
		(end 312.059574 -107.538774)
		(width 0.1524)
		(layer "In2.Cu")
		(net "P0V9_RETIMER_CPU0_EN")
	)
	(segment
		(start 221.367604 -87.402162)
		(end 219.230194 -85.264752)
		(width 0.1524)
		(layer "In2.Cu")
		(net "P0V9_RETIMER_CPU0_EN")
	)
	(segment
		(start 457.070206 -369.155472)
		(end 457.070206 -354.373942)
		(width 0.1524)
		(layer "In2.Cu")
		(net "P0V9_RETIMER_CPU0_EN")
	)
	(segment
		(start 219.230194 -85.264752)
		(end 217.036142 -85.264752)
		(width 0.1524)
		(layer "In2.Cu")
		(net "P0V9_RETIMER_CPU0_EN")
	)
	(segment
		(start 436.292244 -394.87221)
		(end 436.292244 -392.179302)
		(width 0.1524)
		(layer "In2.Cu")
		(net "P0V9_RETIMER_CPU0_EN")
	)
	(segment
		(start 239.254284 -87.402162)
		(end 221.367604 -87.402162)
		(width 0.1524)
		(layer "In2.Cu")
		(net "P0V9_RETIMER_CPU0_EN")
	)
	(segment
		(start 433.796186 -116.701062)
		(end 383.160016 -116.701062)
		(width 0.1524)
		(layer "In2.Cu")
		(net "P0V9_RETIMER_CPU0_EN")
	)
	(segment
		(start 217.036142 -85.264752)
		(end 216.872058 -85.100668)
		(width 0.1524)
		(layer "In2.Cu")
		(net "P0V9_RETIMER_CPU0_EN")
	)
	(segment
		(start 466.814916 -333.698596)
		(end 466.814916 -171.136056)
		(width 0.1524)
		(layer "In2.Cu")
		(net "P0V9_RETIMER_CPU0_EN")
	)
	(segment
		(start 383.160016 -116.701062)
		(end 382.814576 -116.355622)
		(width 0.1524)
		(layer "In2.Cu")
		(net "P0V9_RETIMER_CPU0_EN")
	)
	(segment
		(start 309.9308 -105.41)
		(end 292.70452 -105.41)
		(width 0.1524)
		(layer "In2.Cu")
		(net "P0V9_RETIMER_CPU0_EN")
	)
	(segment
		(start 466.814916 -171.136056)
		(end 463.516472 -167.837612)
		(width 0.1524)
		(layer "In2.Cu")
		(net "P0V9_RETIMER_CPU0_EN")
	)
	(segment
		(start 382.814576 -116.355622)
		(end 376.32386 -116.355622)
		(width 0.1524)
		(layer "In2.Cu")
		(net "P0V9_RETIMER_CPU0_EN")
	)
	(segment
		(start 463.516472 -167.837612)
		(end 460.985616 -167.837612)
		(width 0.1524)
		(layer "In2.Cu")
		(net "P0V9_RETIMER_CPU0_EN")
	)
	(segment
		(start 292.70452 -105.41)
		(end 265.02741 -77.73289)
		(width 0.1524)
		(layer "In2.Cu")
		(net "P0V9_RETIMER_CPU0_EN")
	)
	(segment
		(start 218.80576 -113.07826)
		(end 218.80576 -108.601256)
		(width 0.1524)
		(layer "In11.Cu")
		(net "P0V9_RETIMER_CPU0_EN")
	)
	(segment
		(start 219.44965 -96.24568)
		(end 219.060268 -95.856298)
		(width 0.1524)
		(layer "In11.Cu")
		(net "P0V9_RETIMER_CPU0_EN")
	)
	(segment
		(start 218.577414 -113.306606)
		(end 218.80576 -113.07826)
		(width 0.1524)
		(layer "In11.Cu")
		(net "P0V9_RETIMER_CPU0_EN")
	)
	(segment
		(start 219.060268 -95.856298)
		(end 219.060268 -91.110054)
		(width 0.1524)
		(layer "In11.Cu")
		(net "P0V9_RETIMER_CPU0_EN")
	)
	(segment
		(start 218.80576 -108.601256)
		(end 219.183204 -108.223812)
		(width 0.1524)
		(layer "In11.Cu")
		(net "P0V9_RETIMER_CPU0_EN")
	)
	(segment
		(start 219.060268 -91.110054)
		(end 215.93937 -87.989156)
		(width 0.1524)
		(layer "In11.Cu")
		(net "P0V9_RETIMER_CPU0_EN")
	)
	(segment
		(start 219.183204 -103.729282)
		(end 219.44965 -103.462836)
		(width 0.1524)
		(layer "In11.Cu")
		(net "P0V9_RETIMER_CPU0_EN")
	)
	(segment
		(start 215.93937 -87.989156)
		(end 215.93937 -85.100668)
		(width 0.1524)
		(layer "In11.Cu")
		(net "P0V9_RETIMER_CPU0_EN")
	)
	(segment
		(start 219.44965 -103.462836)
		(end 219.44965 -96.24568)
		(width 0.1524)
		(layer "In11.Cu")
		(net "P0V9_RETIMER_CPU0_EN")
	)
	(segment
		(start 219.183204 -108.223812)
		(end 219.183204 -103.729282)
		(width 0.1524)
		(layer "In11.Cu")
		(net "P0V9_RETIMER_CPU0_EN")
	)
	(segment
		(start 440.887866 -388.8613)
		(end 440.221116 -388.8613)
		(width 0.254)
		(layer "F.Cu")
		(net "P0V9_CPU0_RT_2D")
	)
	(segment
		(start 449.682616 -400.78787)
		(end 449.682616 -400.13382)
		(width 0.254)
		(layer "F.Cu")
		(net "P0V9_CPU0_RT_2D")
	)
	(segment
		(start 441.192666 -388.5565)
		(end 440.887866 -388.8613)
		(width 0.254)
		(layer "F.Cu")
		(net "P0V9_CPU0_RT_2D")
	)
	(segment
		(start 441.446666 -401.44192)
		(end 440.779916 -401.44192)
		(width 0.254)
		(layer "F.Cu")
		(net "P0V9_CPU0_RT_2D")
	)
	(via
		(at 463.206846 -387.386576)
		(size 0.508)
		(drill 0.254)
		(layers "F.Cu" "B.Cu")
		(net "P0V9_CPU0_RT_2D")
	)
	(via
		(at 396.009622 -400.63293)
		(size 0.508)
		(drill 0.254)
		(layers "F.Cu" "B.Cu")
		(net "P0V9_CPU0_RT_2D")
	)
	(via
		(at 446.107566 -381.86487)
		(size 0.508)
		(drill 0.254)
		(layers "F.Cu" "B.Cu")
		(net "P0V9_CPU0_RT_2D")
	)
	(via
		(at 449.134484 -387.096254)
		(size 0.508)
		(drill 0.254)
		(layers "F.Cu" "B.Cu")
		(net "P0V9_CPU0_RT_2D")
	)
	(via
		(at 457.969366 -381.86487)
		(size 0.508)
		(drill 0.254)
		(layers "F.Cu" "B.Cu")
		(net "P0V9_CPU0_RT_2D")
	)
	(via
		(at 328.274426 -401.90293)
		(size 0.508)
		(drill 0.254)
		(layers "F.Cu" "B.Cu")
		(net "P0V9_CPU0_RT_2D")
	)
	(via
		(at 361.853734 -399.265394)
		(size 0.508)
		(drill 0.254)
		(layers "F.Cu" "B.Cu")
		(net "P0V9_CPU0_RT_2D")
	)
	(via
		(at 455.74331 -385.638548)
		(size 0.508)
		(drill 0.254)
		(layers "F.Cu" "B.Cu")
		(net "P0V9_CPU0_RT_2D")
	)
	(via
		(at 444.787528 -388.428992)
		(size 0.508)
		(drill 0.254)
		(layers "F.Cu" "B.Cu")
		(net "P0V9_CPU0_RT_2D")
	)
	(via
		(at 448.063366 -381.86487)
		(size 0.508)
		(drill 0.254)
		(layers "F.Cu" "B.Cu")
		(net "P0V9_CPU0_RT_2D")
	)
	(via
		(at 442.660532 -386.394706)
		(size 0.508)
		(drill 0.254)
		(layers "F.Cu" "B.Cu")
		(net "P0V9_CPU0_RT_2D")
	)
	(via
		(at 441.84951 -388.13867)
		(size 0.508)
		(drill 0.254)
		(layers "F.Cu" "B.Cu")
		(net "P0V9_CPU0_RT_2D")
	)
	(via
		(at 451.873366 -383.38887)
		(size 0.508)
		(drill 0.254)
		(layers "F.Cu" "B.Cu")
		(net "P0V9_CPU0_RT_2D")
	)
	(via
		(at 297.316906 -405.287734)
		(size 0.508)
		(drill 0.254)
		(layers "F.Cu" "B.Cu")
		(net "P0V9_CPU0_RT_2D")
	)
	(via
		(at 457.969366 -383.38887)
		(size 0.508)
		(drill 0.254)
		(layers "F.Cu" "B.Cu")
		(net "P0V9_CPU0_RT_2D")
	)
	(via
		(at 448.372484 -387.096254)
		(size 0.508)
		(drill 0.254)
		(layers "F.Cu" "B.Cu")
		(net "P0V9_CPU0_RT_2D")
	)
	(via
		(at 361.853734 -398.630394)
		(size 0.508)
		(drill 0.254)
		(layers "F.Cu" "B.Cu")
		(net "P0V9_CPU0_RT_2D")
	)
	(via
		(at 442.297566 -381.86487)
		(size 0.508)
		(drill 0.254)
		(layers "F.Cu" "B.Cu")
		(net "P0V9_CPU0_RT_2D")
	)
	(via
		(at 394.739622 -401.26793)
		(size 0.508)
		(drill 0.254)
		(layers "F.Cu" "B.Cu")
		(net "P0V9_CPU0_RT_2D")
	)
	(via
		(at 452.123048 -385.071874)
		(size 0.508)
		(drill 0.254)
		(layers "F.Cu" "B.Cu")
		(net "P0V9_CPU0_RT_2D")
	)
	(via
		(at 440.779916 -401.44192)
		(size 0.508)
		(drill 0.254)
		(layers "F.Cu" "B.Cu")
		(net "P0V9_CPU0_RT_2D")
	)
	(via
		(at 382.478534 -395.466062)
		(size 0.4064)
		(drill 0.2032)
		(layers "F.Cu" "B.Cu")
		(net "P0V9_CPU0_RT_2D")
	)
	(via
		(at 454.159366 -384.15087)
		(size 0.508)
		(drill 0.254)
		(layers "F.Cu" "B.Cu")
		(net "P0V9_CPU0_RT_2D")
	)
	(via
		(at 409.146248 -396.075662)
		(size 0.4064)
		(drill 0.2032)
		(layers "F.Cu" "B.Cu")
		(net "P0V9_CPU0_RT_2D")
	)
	(via
		(at 448.063366 -383.38887)
		(size 0.508)
		(drill 0.254)
		(layers "F.Cu" "B.Cu")
		(net "P0V9_CPU0_RT_2D")
	)
	(via
		(at 460.255366 -381.86487)
		(size 0.508)
		(drill 0.254)
		(layers "F.Cu" "B.Cu")
		(net "P0V9_CPU0_RT_2D")
	)
	(via
		(at 361.576874 -400.63293)
		(size 0.508)
		(drill 0.254)
		(layers "F.Cu" "B.Cu")
		(net "P0V9_CPU0_RT_2D")
	)
	(via
		(at 309.37835 -395.466062)
		(size 0.4064)
		(drill 0.2032)
		(layers "F.Cu" "B.Cu")
		(net "P0V9_CPU0_RT_2D")
	)
	(via
		(at 449.144644 -385.691634)
		(size 0.508)
		(drill 0.254)
		(layers "F.Cu" "B.Cu")
		(net "P0V9_CPU0_RT_2D")
	)
	(via
		(at 451.873366 -384.15087)
		(size 0.508)
		(drill 0.254)
		(layers "F.Cu" "B.Cu")
		(net "P0V9_CPU0_RT_2D")
	)
	(via
		(at 376.6185 -396.075662)
		(size 0.4064)
		(drill 0.2032)
		(layers "F.Cu" "B.Cu")
		(net "P0V9_CPU0_RT_2D")
	)
	(via
		(at 328.274426 -399.99793)
		(size 0.508)
		(drill 0.254)
		(layers "F.Cu" "B.Cu")
		(net "P0V9_CPU0_RT_2D")
	)
	(via
		(at 327.004426 -401.26793)
		(size 0.508)
		(drill 0.254)
		(layers "F.Cu" "B.Cu")
		(net "P0V9_CPU0_RT_2D")
	)
	(via
		(at 362.846874 -399.99793)
		(size 0.508)
		(drill 0.254)
		(layers "F.Cu" "B.Cu")
		(net "P0V9_CPU0_RT_2D")
	)
	(via
		(at 448.382644 -386.35813)
		(size 0.508)
		(drill 0.254)
		(layers "F.Cu" "B.Cu")
		(net "P0V9_CPU0_RT_2D")
	)
	(via
		(at 459.71206 -387.231128)
		(size 0.508)
		(drill 0.254)
		(layers "F.Cu" "B.Cu")
		(net "P0V9_CPU0_RT_2D")
	)
	(via
		(at 328.774298 -399.207228)
		(size 0.508)
		(drill 0.254)
		(layers "F.Cu" "B.Cu")
		(net "P0V9_CPU0_RT_2D")
	)
	(via
		(at 456.5523 -388.307072)
		(size 0.508)
		(drill 0.254)
		(layers "F.Cu" "B.Cu")
		(net "P0V9_CPU0_RT_2D")
	)
	(via
		(at 328.909426 -399.99793)
		(size 0.508)
		(drill 0.254)
		(layers "F.Cu" "B.Cu")
		(net "P0V9_CPU0_RT_2D")
	)
	(via
		(at 455.74331 -386.298948)
		(size 0.508)
		(drill 0.254)
		(layers "F.Cu" "B.Cu")
		(net "P0V9_CPU0_RT_2D")
	)
	(via
		(at 363.481874 -400.63293)
		(size 0.508)
		(drill 0.254)
		(layers "F.Cu" "B.Cu")
		(net "P0V9_CPU0_RT_2D")
	)
	(via
		(at 458.228446 -388.119874)
		(size 0.508)
		(drill 0.254)
		(layers "F.Cu" "B.Cu")
		(net "P0V9_CPU0_RT_2D")
	)
	(via
		(at 326.369426 -401.26793)
		(size 0.508)
		(drill 0.254)
		(layers "F.Cu" "B.Cu")
		(net "P0V9_CPU0_RT_2D")
	)
	(via
		(at 362.211874 -401.90293)
		(size 0.508)
		(drill 0.254)
		(layers "F.Cu" "B.Cu")
		(net "P0V9_CPU0_RT_2D")
	)
	(via
		(at 361.576874 -401.90293)
		(size 0.508)
		(drill 0.254)
		(layers "F.Cu" "B.Cu")
		(net "P0V9_CPU0_RT_2D")
	)
	(via
		(at 299.221906 -405.287734)
		(size 0.508)
		(drill 0.254)
		(layers "F.Cu" "B.Cu")
		(net "P0V9_CPU0_RT_2D")
	)
	(via
		(at 449.682616 -400.13382)
		(size 0.508)
		(drill 0.254)
		(layers "F.Cu" "B.Cu")
		(net "P0V9_CPU0_RT_2D")
	)
	(via
		(at 312.82005 -401.25396)
		(size 0.6604)
		(drill 0.3302)
		(layers "F.Cu" "B.Cu")
		(net "P0V9_CPU0_RT_2D")
	)
	(via
		(at 409.006294 -395.466062)
		(size 0.4064)
		(drill 0.2032)
		(layers "F.Cu" "B.Cu")
		(net "P0V9_CPU0_RT_2D")
	)
	(via
		(at 455.74331 -386.959348)
		(size 0.508)
		(drill 0.254)
		(layers "F.Cu" "B.Cu")
		(net "P0V9_CPU0_RT_2D")
	)
	(via
		(at 362.846874 -401.26793)
		(size 0.508)
		(drill 0.254)
		(layers "F.Cu" "B.Cu")
		(net "P0V9_CPU0_RT_2D")
	)
	(via
		(at 460.255366 -384.15087)
		(size 0.508)
		(drill 0.254)
		(layers "F.Cu" "B.Cu")
		(net "P0V9_CPU0_RT_2D")
	)
	(via
		(at 449.777104 -385.039108)
		(size 0.508)
		(drill 0.254)
		(layers "F.Cu" "B.Cu")
		(net "P0V9_CPU0_RT_2D")
	)
	(via
		(at 297.316906 -405.922734)
		(size 0.508)
		(drill 0.254)
		(layers "F.Cu" "B.Cu")
		(net "P0V9_CPU0_RT_2D")
	)
	(via
		(at 448.394836 -388.452868)
		(size 0.508)
		(drill 0.254)
		(layers "F.Cu" "B.Cu")
		(net "P0V9_CPU0_RT_2D")
	)
	(via
		(at 451.873366 -382.62687)
		(size 0.508)
		(drill 0.254)
		(layers "F.Cu" "B.Cu")
		(net "P0V9_CPU0_RT_2D")
	)
	(via
		(at 457.969366 -382.62687)
		(size 0.508)
		(drill 0.254)
		(layers "F.Cu" "B.Cu")
		(net "P0V9_CPU0_RT_2D")
	)
	(via
		(at 444.776098 -385.750816)
		(size 0.508)
		(drill 0.254)
		(layers "F.Cu" "B.Cu")
		(net "P0V9_CPU0_RT_2D")
	)
	(via
		(at 449.805044 -386.35813)
		(size 0.508)
		(drill 0.254)
		(layers "F.Cu" "B.Cu")
		(net "P0V9_CPU0_RT_2D")
	)
	(via
		(at 460.255366 -382.62687)
		(size 0.508)
		(drill 0.254)
		(layers "F.Cu" "B.Cu")
		(net "P0V9_CPU0_RT_2D")
	)
	(via
		(at 448.354704 -385.039108)
		(size 0.508)
		(drill 0.254)
		(layers "F.Cu" "B.Cu")
		(net "P0V9_CPU0_RT_2D")
	)
	(via
		(at 457.170028 -385.651248)
		(size 0.508)
		(drill 0.254)
		(layers "F.Cu" "B.Cu")
		(net "P0V9_CPU0_RT_2D")
	)
	(via
		(at 460.255366 -383.38887)
		(size 0.508)
		(drill 0.254)
		(layers "F.Cu" "B.Cu")
		(net "P0V9_CPU0_RT_2D")
	)
	(via
		(at 315.518292 -396.075662)
		(size 0.4064)
		(drill 0.2032)
		(layers "F.Cu" "B.Cu")
		(net "P0V9_CPU0_RT_2D")
	)
	(via
		(at 451.396608 -386.392674)
		(size 0.508)
		(drill 0.254)
		(layers "F.Cu" "B.Cu")
		(net "P0V9_CPU0_RT_2D")
	)
	(via
		(at 449.144644 -386.35813)
		(size 0.508)
		(drill 0.254)
		(layers "F.Cu" "B.Cu")
		(net "P0V9_CPU0_RT_2D")
	)
	(via
		(at 362.846874 -400.63293)
		(size 0.508)
		(drill 0.254)
		(layers "F.Cu" "B.Cu")
		(net "P0V9_CPU0_RT_2D")
	)
	(via
		(at 327.639426 -401.26793)
		(size 0.508)
		(drill 0.254)
		(layers "F.Cu" "B.Cu")
		(net "P0V9_CPU0_RT_2D")
	)
	(via
		(at 347.906086 -395.466062)
		(size 0.4064)
		(drill 0.2032)
		(layers "F.Cu" "B.Cu")
		(net "P0V9_CPU0_RT_2D")
	)
	(via
		(at 442.297566 -383.38887)
		(size 0.508)
		(drill 0.254)
		(layers "F.Cu" "B.Cu")
		(net "P0V9_CPU0_RT_2D")
	)
	(via
		(at 297.951906 -405.922734)
		(size 0.508)
		(drill 0.254)
		(layers "F.Cu" "B.Cu")
		(net "P0V9_CPU0_RT_2D")
	)
	(via
		(at 449.156836 -388.452868)
		(size 0.508)
		(drill 0.254)
		(layers "F.Cu" "B.Cu")
		(net "P0V9_CPU0_RT_2D")
	)
	(via
		(at 442.67374 -387.231636)
		(size 0.508)
		(drill 0.254)
		(layers "F.Cu" "B.Cu")
		(net "P0V9_CPU0_RT_2D")
	)
	(via
		(at 328.274426 -401.26793)
		(size 0.508)
		(drill 0.254)
		(layers "F.Cu" "B.Cu")
		(net "P0V9_CPU0_RT_2D")
	)
	(via
		(at 327.004426 -401.90293)
		(size 0.508)
		(drill 0.254)
		(layers "F.Cu" "B.Cu")
		(net "P0V9_CPU0_RT_2D")
	)
	(via
		(at 326.369426 -401.90293)
		(size 0.508)
		(drill 0.254)
		(layers "F.Cu" "B.Cu")
		(net "P0V9_CPU0_RT_2D")
	)
	(via
		(at 464.065366 -381.86487)
		(size 0.508)
		(drill 0.254)
		(layers "F.Cu" "B.Cu")
		(net "P0V9_CPU0_RT_2D")
	)
	(via
		(at 454.159366 -383.38887)
		(size 0.508)
		(drill 0.254)
		(layers "F.Cu" "B.Cu")
		(net "P0V9_CPU0_RT_2D")
	)
	(via
		(at 298.536106 -407.192734)
		(size 0.508)
		(drill 0.254)
		(layers "F.Cu" "B.Cu")
		(net "P0V9_CPU0_RT_2D")
	)
	(via
		(at 395.374622 -400.63293)
		(size 0.508)
		(drill 0.254)
		(layers "F.Cu" "B.Cu")
		(net "P0V9_CPU0_RT_2D")
	)
	(via
		(at 457.969366 -384.15087)
		(size 0.508)
		(drill 0.254)
		(layers "F.Cu" "B.Cu")
		(net "P0V9_CPU0_RT_2D")
	)
	(via
		(at 415.146236 -396.075662)
		(size 0.4064)
		(drill 0.2032)
		(layers "F.Cu" "B.Cu")
		(net "P0V9_CPU0_RT_2D")
	)
	(via
		(at 451.396608 -385.071874)
		(size 0.508)
		(drill 0.254)
		(layers "F.Cu" "B.Cu")
		(net "P0V9_CPU0_RT_2D")
	)
	(via
		(at 361.576874 -401.26793)
		(size 0.508)
		(drill 0.254)
		(layers "F.Cu" "B.Cu")
		(net "P0V9_CPU0_RT_2D")
	)
	(via
		(at 451.403466 -387.69544)
		(size 0.508)
		(drill 0.254)
		(layers "F.Cu" "B.Cu")
		(net "P0V9_CPU0_RT_2D")
	)
	(via
		(at 456.529948 -386.970016)
		(size 0.508)
		(drill 0.254)
		(layers "F.Cu" "B.Cu")
		(net "P0V9_CPU0_RT_2D")
	)
	(via
		(at 448.372484 -387.756654)
		(size 0.508)
		(drill 0.254)
		(layers "F.Cu" "B.Cu")
		(net "P0V9_CPU0_RT_2D")
	)
	(via
		(at 446.107566 -383.38887)
		(size 0.508)
		(drill 0.254)
		(layers "F.Cu" "B.Cu")
		(net "P0V9_CPU0_RT_2D")
	)
	(via
		(at 448.063366 -382.62687)
		(size 0.508)
		(drill 0.254)
		(layers "F.Cu" "B.Cu")
		(net "P0V9_CPU0_RT_2D")
	)
	(via
		(at 449.116704 -385.039108)
		(size 0.508)
		(drill 0.254)
		(layers "F.Cu" "B.Cu")
		(net "P0V9_CPU0_RT_2D")
	)
	(via
		(at 444.787528 -387.158992)
		(size 0.508)
		(drill 0.254)
		(layers "F.Cu" "B.Cu")
		(net "P0V9_CPU0_RT_2D")
	)
	(via
		(at 444.082932 -388.428992)
		(size 0.508)
		(drill 0.254)
		(layers "F.Cu" "B.Cu")
		(net "P0V9_CPU0_RT_2D")
	)
	(via
		(at 450.743066 -387.06044)
		(size 0.508)
		(drill 0.254)
		(layers "F.Cu" "B.Cu")
		(net "P0V9_CPU0_RT_2D")
	)
	(via
		(at 297.901106 -407.192734)
		(size 0.508)
		(drill 0.254)
		(layers "F.Cu" "B.Cu")
		(net "P0V9_CPU0_RT_2D")
	)
	(via
		(at 442.297566 -384.15087)
		(size 0.508)
		(drill 0.254)
		(layers "F.Cu" "B.Cu")
		(net "P0V9_CPU0_RT_2D")
	)
	(via
		(at 362.846874 -401.90293)
		(size 0.508)
		(drill 0.254)
		(layers "F.Cu" "B.Cu")
		(net "P0V9_CPU0_RT_2D")
	)
	(via
		(at 452.123048 -386.392674)
		(size 0.508)
		(drill 0.254)
		(layers "F.Cu" "B.Cu")
		(net "P0V9_CPU0_RT_2D")
	)
	(via
		(at 395.374622 -399.99793)
		(size 0.508)
		(drill 0.254)
		(layers "F.Cu" "B.Cu")
		(net "P0V9_CPU0_RT_2D")
	)
	(via
		(at 299.221906 -406.557734)
		(size 0.508)
		(drill 0.254)
		(layers "F.Cu" "B.Cu")
		(net "P0V9_CPU0_RT_2D")
	)
	(via
		(at 395.374622 -401.26793)
		(size 0.508)
		(drill 0.254)
		(layers "F.Cu" "B.Cu")
		(net "P0V9_CPU0_RT_2D")
	)
	(via
		(at 328.909426 -400.63293)
		(size 0.508)
		(drill 0.254)
		(layers "F.Cu" "B.Cu")
		(net "P0V9_CPU0_RT_2D")
	)
	(via
		(at 325.734426 -401.90293)
		(size 0.508)
		(drill 0.254)
		(layers "F.Cu" "B.Cu")
		(net "P0V9_CPU0_RT_2D")
	)
	(via
		(at 327.639426 -399.99793)
		(size 0.508)
		(drill 0.254)
		(layers "F.Cu" "B.Cu")
		(net "P0V9_CPU0_RT_2D")
	)
	(via
		(at 341.906098 -395.466062)
		(size 0.4064)
		(drill 0.2032)
		(layers "F.Cu" "B.Cu")
		(net "P0V9_CPU0_RT_2D")
	)
	(via
		(at 444.071502 -385.750816)
		(size 0.508)
		(drill 0.254)
		(layers "F.Cu" "B.Cu")
		(net "P0V9_CPU0_RT_2D")
	)
	(via
		(at 443.33414 -387.231636)
		(size 0.508)
		(drill 0.254)
		(layers "F.Cu" "B.Cu")
		(net "P0V9_CPU0_RT_2D")
	)
	(via
		(at 394.739622 -401.90293)
		(size 0.508)
		(drill 0.254)
		(layers "F.Cu" "B.Cu")
		(net "P0V9_CPU0_RT_2D")
	)
	(via
		(at 457.170028 -387.632448)
		(size 0.508)
		(drill 0.254)
		(layers "F.Cu" "B.Cu")
		(net "P0V9_CPU0_RT_2D")
	)
	(via
		(at 412.447994 -401.25396)
		(size 0.6604)
		(drill 0.3302)
		(layers "F.Cu" "B.Cu")
		(net "P0V9_CPU0_RT_2D")
	)
	(via
		(at 298.586906 -405.922734)
		(size 0.508)
		(drill 0.254)
		(layers "F.Cu" "B.Cu")
		(net "P0V9_CPU0_RT_2D")
	)
	(via
		(at 362.211874 -400.63293)
		(size 0.508)
		(drill 0.254)
		(layers "F.Cu" "B.Cu")
		(net "P0V9_CPU0_RT_2D")
	)
	(via
		(at 328.274426 -400.63293)
		(size 0.508)
		(drill 0.254)
		(layers "F.Cu" "B.Cu")
		(net "P0V9_CPU0_RT_2D")
	)
	(via
		(at 444.082932 -387.793992)
		(size 0.508)
		(drill 0.254)
		(layers "F.Cu" "B.Cu")
		(net "P0V9_CPU0_RT_2D")
	)
	(via
		(at 450.736208 -385.071874)
		(size 0.508)
		(drill 0.254)
		(layers "F.Cu" "B.Cu")
		(net "P0V9_CPU0_RT_2D")
	)
	(via
		(at 327.639426 -401.90293)
		(size 0.508)
		(drill 0.254)
		(layers "F.Cu" "B.Cu")
		(net "P0V9_CPU0_RT_2D")
	)
	(via
		(at 347.756226 -401.26285)
		(size 0.6604)
		(drill 0.3302)
		(layers "F.Cu" "B.Cu")
		(net "P0V9_CPU0_RT_2D")
	)
	(via
		(at 464.065366 -384.15087)
		(size 0.508)
		(drill 0.254)
		(layers "F.Cu" "B.Cu")
		(net "P0V9_CPU0_RT_2D")
	)
	(via
		(at 461.23225 -387.269228)
		(size 0.508)
		(drill 0.254)
		(layers "F.Cu" "B.Cu")
		(net "P0V9_CPU0_RT_2D")
	)
	(via
		(at 342.046052 -396.075662)
		(size 0.4064)
		(drill 0.2032)
		(layers "F.Cu" "B.Cu")
		(net "P0V9_CPU0_RT_2D")
	)
	(via
		(at 457.198476 -388.283196)
		(size 0.508)
		(drill 0.254)
		(layers "F.Cu" "B.Cu")
		(net "P0V9_CPU0_RT_2D")
	)
	(via
		(at 415.006282 -395.466062)
		(size 0.4064)
		(drill 0.2032)
		(layers "F.Cu" "B.Cu")
		(net "P0V9_CPU0_RT_2D")
	)
	(via
		(at 444.787528 -387.793992)
		(size 0.508)
		(drill 0.254)
		(layers "F.Cu" "B.Cu")
		(net "P0V9_CPU0_RT_2D")
	)
	(via
		(at 363.481874 -399.99793)
		(size 0.508)
		(drill 0.254)
		(layers "F.Cu" "B.Cu")
		(net "P0V9_CPU0_RT_2D")
	)
	(via
		(at 448.382644 -385.691634)
		(size 0.508)
		(drill 0.254)
		(layers "F.Cu" "B.Cu")
		(net "P0V9_CPU0_RT_2D")
	)
	(via
		(at 395.87424 -399.207228)
		(size 0.508)
		(drill 0.254)
		(layers "F.Cu" "B.Cu")
		(net "P0V9_CPU0_RT_2D")
	)
	(via
		(at 449.134484 -387.756654)
		(size 0.508)
		(drill 0.254)
		(layers "F.Cu" "B.Cu")
		(net "P0V9_CPU0_RT_2D")
	)
	(via
		(at 452.119238 -388.337552)
		(size 0.508)
		(drill 0.254)
		(layers "F.Cu" "B.Cu")
		(net "P0V9_CPU0_RT_2D")
	)
	(via
		(at 456.529948 -387.630416)
		(size 0.508)
		(drill 0.254)
		(layers "F.Cu" "B.Cu")
		(net "P0V9_CPU0_RT_2D")
	)
	(via
		(at 444.082932 -387.158992)
		(size 0.508)
		(drill 0.254)
		(layers "F.Cu" "B.Cu")
		(net "P0V9_CPU0_RT_2D")
	)
	(via
		(at 297.951906 -406.557734)
		(size 0.508)
		(drill 0.254)
		(layers "F.Cu" "B.Cu")
		(net "P0V9_CPU0_RT_2D")
	)
	(via
		(at 395.374622 -401.90293)
		(size 0.508)
		(drill 0.254)
		(layers "F.Cu" "B.Cu")
		(net "P0V9_CPU0_RT_2D")
	)
	(via
		(at 297.316906 -406.557734)
		(size 0.508)
		(drill 0.254)
		(layers "F.Cu" "B.Cu")
		(net "P0V9_CPU0_RT_2D")
	)
	(via
		(at 298.586906 -406.557734)
		(size 0.508)
		(drill 0.254)
		(layers "F.Cu" "B.Cu")
		(net "P0V9_CPU0_RT_2D")
	)
	(via
		(at 444.079884 -386.390642)
		(size 0.508)
		(drill 0.254)
		(layers "F.Cu" "B.Cu")
		(net "P0V9_CPU0_RT_2D")
	)
	(via
		(at 297.951906 -405.287734)
		(size 0.508)
		(drill 0.254)
		(layers "F.Cu" "B.Cu")
		(net "P0V9_CPU0_RT_2D")
	)
	(via
		(at 442.297566 -382.62687)
		(size 0.508)
		(drill 0.254)
		(layers "F.Cu" "B.Cu")
		(net "P0V9_CPU0_RT_2D")
	)
	(via
		(at 464.065366 -383.38887)
		(size 0.508)
		(drill 0.254)
		(layers "F.Cu" "B.Cu")
		(net "P0V9_CPU0_RT_2D")
	)
	(via
		(at 459.05166 -387.231128)
		(size 0.508)
		(drill 0.254)
		(layers "F.Cu" "B.Cu")
		(net "P0V9_CPU0_RT_2D")
	)
	(via
		(at 394.104622 -401.90293)
		(size 0.508)
		(drill 0.254)
		(layers "F.Cu" "B.Cu")
		(net "P0V9_CPU0_RT_2D")
	)
	(via
		(at 446.107566 -382.62687)
		(size 0.508)
		(drill 0.254)
		(layers "F.Cu" "B.Cu")
		(net "P0V9_CPU0_RT_2D")
	)
	(via
		(at 362.694474 -398.93113)
		(size 0.508)
		(drill 0.254)
		(layers "F.Cu" "B.Cu")
		(net "P0V9_CPU0_RT_2D")
	)
	(via
		(at 297.266106 -407.192734)
		(size 0.508)
		(drill 0.254)
		(layers "F.Cu" "B.Cu")
		(net "P0V9_CPU0_RT_2D")
	)
	(via
		(at 448.063366 -384.15087)
		(size 0.508)
		(drill 0.254)
		(layers "F.Cu" "B.Cu")
		(net "P0V9_CPU0_RT_2D")
	)
	(via
		(at 450.736208 -385.732274)
		(size 0.508)
		(drill 0.254)
		(layers "F.Cu" "B.Cu")
		(net "P0V9_CPU0_RT_2D")
	)
	(via
		(at 450.736208 -386.392674)
		(size 0.508)
		(drill 0.254)
		(layers "F.Cu" "B.Cu")
		(net "P0V9_CPU0_RT_2D")
	)
	(via
		(at 443.419484 -386.394706)
		(size 0.508)
		(drill 0.254)
		(layers "F.Cu" "B.Cu")
		(net "P0V9_CPU0_RT_2D")
	)
	(via
		(at 325.734426 -401.26793)
		(size 0.508)
		(drill 0.254)
		(layers "F.Cu" "B.Cu")
		(net "P0V9_CPU0_RT_2D")
	)
	(via
		(at 395.23924 -399.207228)
		(size 0.508)
		(drill 0.254)
		(layers "F.Cu" "B.Cu")
		(net "P0V9_CPU0_RT_2D")
	)
	(via
		(at 392.834622 -401.26793)
		(size 0.508)
		(drill 0.254)
		(layers "F.Cu" "B.Cu")
		(net "P0V9_CPU0_RT_2D")
	)
	(via
		(at 449.805044 -385.691634)
		(size 0.508)
		(drill 0.254)
		(layers "F.Cu" "B.Cu")
		(net "P0V9_CPU0_RT_2D")
	)
	(via
		(at 451.873366 -381.86487)
		(size 0.508)
		(drill 0.254)
		(layers "F.Cu" "B.Cu")
		(net "P0V9_CPU0_RT_2D")
	)
	(via
		(at 450.743066 -387.69544)
		(size 0.508)
		(drill 0.254)
		(layers "F.Cu" "B.Cu")
		(net "P0V9_CPU0_RT_2D")
	)
	(via
		(at 449.794884 -387.756654)
		(size 0.508)
		(drill 0.254)
		(layers "F.Cu" "B.Cu")
		(net "P0V9_CPU0_RT_2D")
	)
	(via
		(at 327.639426 -400.63293)
		(size 0.508)
		(drill 0.254)
		(layers "F.Cu" "B.Cu")
		(net "P0V9_CPU0_RT_2D")
	)
	(via
		(at 363.329474 -398.93113)
		(size 0.508)
		(drill 0.254)
		(layers "F.Cu" "B.Cu")
		(net "P0V9_CPU0_RT_2D")
	)
	(via
		(at 348.04604 -396.075662)
		(size 0.4064)
		(drill 0.2032)
		(layers "F.Cu" "B.Cu")
		(net "P0V9_CPU0_RT_2D")
	)
	(via
		(at 456.529948 -385.649216)
		(size 0.508)
		(drill 0.254)
		(layers "F.Cu" "B.Cu")
		(net "P0V9_CPU0_RT_2D")
	)
	(via
		(at 457.170028 -386.972048)
		(size 0.508)
		(drill 0.254)
		(layers "F.Cu" "B.Cu")
		(net "P0V9_CPU0_RT_2D")
	)
	(via
		(at 444.78448 -386.390642)
		(size 0.508)
		(drill 0.254)
		(layers "F.Cu" "B.Cu")
		(net "P0V9_CPU0_RT_2D")
	)
	(via
		(at 392.834622 -401.90293)
		(size 0.508)
		(drill 0.254)
		(layers "F.Cu" "B.Cu")
		(net "P0V9_CPU0_RT_2D")
	)
	(via
		(at 451.396608 -385.732274)
		(size 0.508)
		(drill 0.254)
		(layers "F.Cu" "B.Cu")
		(net "P0V9_CPU0_RT_2D")
	)
	(via
		(at 298.586906 -405.287734)
		(size 0.508)
		(drill 0.254)
		(layers "F.Cu" "B.Cu")
		(net "P0V9_CPU0_RT_2D")
	)
	(via
		(at 446.107566 -384.15087)
		(size 0.508)
		(drill 0.254)
		(layers "F.Cu" "B.Cu")
		(net "P0V9_CPU0_RT_2D")
	)
	(via
		(at 328.139298 -399.207228)
		(size 0.508)
		(drill 0.254)
		(layers "F.Cu" "B.Cu")
		(net "P0V9_CPU0_RT_2D")
	)
	(via
		(at 461.89265 -387.269228)
		(size 0.508)
		(drill 0.254)
		(layers "F.Cu" "B.Cu")
		(net "P0V9_CPU0_RT_2D")
	)
	(via
		(at 454.159366 -382.62687)
		(size 0.508)
		(drill 0.254)
		(layers "F.Cu" "B.Cu")
		(net "P0V9_CPU0_RT_2D")
	)
	(via
		(at 451.403466 -387.06044)
		(size 0.508)
		(drill 0.254)
		(layers "F.Cu" "B.Cu")
		(net "P0V9_CPU0_RT_2D")
	)
	(via
		(at 443.367922 -385.744212)
		(size 0.508)
		(drill 0.254)
		(layers "F.Cu" "B.Cu")
		(net "P0V9_CPU0_RT_2D")
	)
	(via
		(at 449.794884 -387.096254)
		(size 0.508)
		(drill 0.254)
		(layers "F.Cu" "B.Cu")
		(net "P0V9_CPU0_RT_2D")
	)
	(via
		(at 315.378338 -395.466062)
		(size 0.4064)
		(drill 0.2032)
		(layers "F.Cu" "B.Cu")
		(net "P0V9_CPU0_RT_2D")
	)
	(via
		(at 299.171106 -407.192734)
		(size 0.508)
		(drill 0.254)
		(layers "F.Cu" "B.Cu")
		(net "P0V9_CPU0_RT_2D")
	)
	(via
		(at 382.618488 -396.075662)
		(size 0.4064)
		(drill 0.2032)
		(layers "F.Cu" "B.Cu")
		(net "P0V9_CPU0_RT_2D")
	)
	(via
		(at 309.518304 -396.075662)
		(size 0.4064)
		(drill 0.2032)
		(layers "F.Cu" "B.Cu")
		(net "P0V9_CPU0_RT_2D")
	)
	(via
		(at 394.739622 -399.99793)
		(size 0.508)
		(drill 0.254)
		(layers "F.Cu" "B.Cu")
		(net "P0V9_CPU0_RT_2D")
	)
	(via
		(at 393.469622 -401.90293)
		(size 0.508)
		(drill 0.254)
		(layers "F.Cu" "B.Cu")
		(net "P0V9_CPU0_RT_2D")
	)
	(via
		(at 452.123048 -385.732274)
		(size 0.508)
		(drill 0.254)
		(layers "F.Cu" "B.Cu")
		(net "P0V9_CPU0_RT_2D")
	)
	(via
		(at 299.221906 -405.922734)
		(size 0.508)
		(drill 0.254)
		(layers "F.Cu" "B.Cu")
		(net "P0V9_CPU0_RT_2D")
	)
	(via
		(at 457.170028 -386.311648)
		(size 0.508)
		(drill 0.254)
		(layers "F.Cu" "B.Cu")
		(net "P0V9_CPU0_RT_2D")
	)
	(via
		(at 362.211874 -399.99793)
		(size 0.508)
		(drill 0.254)
		(layers "F.Cu" "B.Cu")
		(net "P0V9_CPU0_RT_2D")
	)
	(via
		(at 394.739622 -400.63293)
		(size 0.508)
		(drill 0.254)
		(layers "F.Cu" "B.Cu")
		(net "P0V9_CPU0_RT_2D")
	)
	(via
		(at 379.920246 -401.25396)
		(size 0.6604)
		(drill 0.3302)
		(layers "F.Cu" "B.Cu")
		(net "P0V9_CPU0_RT_2D")
	)
	(via
		(at 393.469622 -401.26793)
		(size 0.508)
		(drill 0.254)
		(layers "F.Cu" "B.Cu")
		(net "P0V9_CPU0_RT_2D")
	)
	(via
		(at 342.947752 -401.25396)
		(size 0.6604)
		(drill 0.3302)
		(layers "F.Cu" "B.Cu")
		(net "P0V9_CPU0_RT_2D")
	)
	(via
		(at 452.129906 -387.69544)
		(size 0.508)
		(drill 0.254)
		(layers "F.Cu" "B.Cu")
		(net "P0V9_CPU0_RT_2D")
	)
	(via
		(at 455.74331 -387.619748)
		(size 0.508)
		(drill 0.254)
		(layers "F.Cu" "B.Cu")
		(net "P0V9_CPU0_RT_2D")
	)
	(via
		(at 464.065366 -382.62687)
		(size 0.508)
		(drill 0.254)
		(layers "F.Cu" "B.Cu")
		(net "P0V9_CPU0_RT_2D")
	)
	(via
		(at 454.159366 -381.86487)
		(size 0.508)
		(drill 0.254)
		(layers "F.Cu" "B.Cu")
		(net "P0V9_CPU0_RT_2D")
	)
	(via
		(at 455.744072 -388.29488)
		(size 0.508)
		(drill 0.254)
		(layers "F.Cu" "B.Cu")
		(net "P0V9_CPU0_RT_2D")
	)
	(via
		(at 452.129906 -387.06044)
		(size 0.508)
		(drill 0.254)
		(layers "F.Cu" "B.Cu")
		(net "P0V9_CPU0_RT_2D")
	)
	(via
		(at 362.211874 -401.26793)
		(size 0.508)
		(drill 0.254)
		(layers "F.Cu" "B.Cu")
		(net "P0V9_CPU0_RT_2D")
	)
	(via
		(at 302.304196 -410.316172)
		(size 0.508)
		(drill 0.254)
		(layers "F.Cu" "B.Cu")
		(net "P0V9_CPU0_RT_2D")
	)
	(via
		(at 394.104622 -401.26793)
		(size 0.508)
		(drill 0.254)
		(layers "F.Cu" "B.Cu")
		(net "P0V9_CPU0_RT_2D")
	)
	(via
		(at 396.009622 -399.99793)
		(size 0.508)
		(drill 0.254)
		(layers "F.Cu" "B.Cu")
		(net "P0V9_CPU0_RT_2D")
	)
	(via
		(at 361.576874 -399.99793)
		(size 0.508)
		(drill 0.254)
		(layers "F.Cu" "B.Cu")
		(net "P0V9_CPU0_RT_2D")
	)
	(via
		(at 376.478546 -395.466062)
		(size 0.4064)
		(drill 0.2032)
		(layers "F.Cu" "B.Cu")
		(net "P0V9_CPU0_RT_2D")
	)
	(via
		(at 456.529948 -386.309616)
		(size 0.508)
		(drill 0.254)
		(layers "F.Cu" "B.Cu")
		(net "P0V9_CPU0_RT_2D")
	)
	(segment
		(start 304.055018 -409.996386)
		(end 304.055018 -409.623514)
		(width 0.254)
		(layer "In11.Cu")
		(net "P0V9_CPU0_RT_2D")
	)
	(segment
		(start 302.304196 -410.316172)
		(end 303.735232 -410.316172)
		(width 0.254)
		(layer "In11.Cu")
		(net "P0V9_CPU0_RT_2D")
	)
	(segment
		(start 303.735232 -410.316172)
		(end 304.055018 -409.996386)
		(width 0.254)
		(layer "In11.Cu")
		(net "P0V9_CPU0_RT_2D")
	)
	(segment
		(start 440.779916 -401.42668)
		(end 440.779916 -401.44192)
		(width 0.254)
		(layer "In15.Cu")
		(net "P0V9_CPU0_RT_2D")
	)
	(segment
		(start 441.84951 -388.13867)
		(end 440.762898 -389.225282)
		(width 0.254)
		(layer "In15.Cu")
		(net "P0V9_CPU0_RT_2D")
	)
	(segment
		(start 451.698868 -398.408906)
		(end 451.698868 -390.9949)
		(width 0.254)
		(layer "In15.Cu")
		(net "P0V9_CPU0_RT_2D")
	)
	(segment
		(start 440.762898 -389.225282)
		(end 440.762898 -395.975586)
		(width 0.254)
		(layer "In15.Cu")
		(net "P0V9_CPU0_RT_2D")
	)
	(segment
		(start 449.973954 -400.13382)
		(end 451.698868 -398.408906)
		(width 0.254)
		(layer "In15.Cu")
		(net "P0V9_CPU0_RT_2D")
	)
	(segment
		(start 441.669424 -396.882112)
		(end 441.669424 -400.537172)
		(width 0.254)
		(layer "In15.Cu")
		(net "P0V9_CPU0_RT_2D")
	)
	(segment
		(start 441.669424 -400.537172)
		(end 440.779916 -401.42668)
		(width 0.254)
		(layer "In15.Cu")
		(net "P0V9_CPU0_RT_2D")
	)
	(segment
		(start 451.698868 -390.9949)
		(end 449.156836 -388.452868)
		(width 0.254)
		(layer "In15.Cu")
		(net "P0V9_CPU0_RT_2D")
	)
	(segment
		(start 449.682616 -400.13382)
		(end 449.973954 -400.13382)
		(width 0.254)
		(layer "In15.Cu")
		(net "P0V9_CPU0_RT_2D")
	)
	(segment
		(start 440.762898 -395.975586)
		(end 441.669424 -396.882112)
		(width 0.254)
		(layer "In15.Cu")
		(net "P0V9_CPU0_RT_2D")
	)
	(via
		(at 188.44895 -423.246804)
		(size 0.6604)
		(drill 0.3302)
		(layers "F.Cu" "B.Cu")
		(net "OC_P2V5_COMP")
	)
	(segment
		(start 188.27496 -423.678096)
		(end 188.27496 -424.86199)
		(width 0.10668)
		(layer "B.Cu")
		(net "OC_P2V5_COMP")
	)
	(segment
		(start 187.47105 -421.103552)
		(end 187.01004 -420.642542)
		(width 0.10668)
		(layer "B.Cu")
		(net "OC_P2V5_COMP")
	)
	(segment
		(start 188.44895 -423.504106)
		(end 188.27496 -423.678096)
		(width 0.10668)
		(layer "B.Cu")
		(net "OC_P2V5_COMP")
	)
	(segment
		(start 188.44895 -422.402)
		(end 188.44895 -423.246804)
		(width 0.10668)
		(layer "B.Cu")
		(net "OC_P2V5_COMP")
	)
	(segment
		(start 188.44895 -422.402)
		(end 187.47105 -422.402)
		(width 0.10668)
		(layer "B.Cu")
		(net "OC_P2V5_COMP")
	)
	(segment
		(start 188.44895 -423.246804)
		(end 188.44895 -423.504106)
		(width 0.10668)
		(layer "B.Cu")
		(net "OC_P2V5_COMP")
	)
	(segment
		(start 187.01004 -420.642542)
		(end 187.01004 -420.03091)
		(width 0.10668)
		(layer "B.Cu")
		(net "OC_P2V5_COMP")
	)
	(segment
		(start 187.47105 -422.402)
		(end 187.47105 -421.103552)
		(width 0.10668)
		(layer "B.Cu")
		(net "OC_P2V5_COMP")
	)
	(segment
		(start 13.743432 -74.394568)
		(end 14.034516 -74.394568)
		(width 0.10668)
		(layer "F.Cu")
		(net "OCP_V3_2_PRSNT23_R1_N")
	)
	(segment
		(start 12.93495 -77.089)
		(end 12.93495 -75.20305)
		(width 0.10668)
		(layer "F.Cu")
		(net "OCP_V3_2_PRSNT23_R1_N")
	)
	(segment
		(start 12.93495 -75.20305)
		(end 13.743432 -74.394568)
		(width 0.10668)
		(layer "F.Cu")
		(net "OCP_V3_2_PRSNT23_R1_N")
	)
	(segment
		(start 14.034516 -74.394568)
		(end 14.901672 -74.394568)
		(width 0.10668)
		(layer "F.Cu")
		(net "OCP_V3_2_PRSNT23_R1_N")
	)
	(segment
		(start 11.95705 -77.089)
		(end 12.93495 -77.089)
		(width 0.10668)
		(layer "F.Cu")
		(net "OCP_V3_2_PRSNT23_R1_N")
	)
	(via
		(at 14.034516 -74.394568)
		(size 0.508)
		(drill 0.254)
		(layers "F.Cu" "B.Cu")
		(net "OCP_V3_2_PRSNT23_R1_N")
	)
	(segment
		(start 16.329152 -73.694798)
		(end 14.901672 -73.694798)
		(width 0.10668)
		(layer "F.Cu")
		(net "OCP_V3_2_PRSNT01_R1_N")
	)
	(segment
		(start 16.129 -72.771)
		(end 16.36395 -73.00595)
		(width 0.10668)
		(layer "F.Cu")
		(net "OCP_V3_2_PRSNT01_R1_N")
	)
	(segment
		(start 16.36395 -73.00595)
		(end 16.36395 -73.66)
		(width 0.10668)
		(layer "F.Cu")
		(net "OCP_V3_2_PRSNT01_R1_N")
	)
	(segment
		(start 10.795 -72.771)
		(end 16.129 -72.771)
		(width 0.10668)
		(layer "F.Cu")
		(net "OCP_V3_2_PRSNT01_R1_N")
	)
	(segment
		(start 9.67105 -73.279)
		(end 10.287 -73.279)
		(width 0.10668)
		(layer "F.Cu")
		(net "OCP_V3_2_PRSNT01_R1_N")
	)
	(segment
		(start 16.36395 -73.66)
		(end 16.329152 -73.694798)
		(width 0.10668)
		(layer "F.Cu")
		(net "OCP_V3_2_PRSNT01_R1_N")
	)
	(segment
		(start 10.287 -73.279)
		(end 10.795 -72.771)
		(width 0.10668)
		(layer "F.Cu")
		(net "OCP_V3_2_PRSNT01_R1_N")
	)
	(via
		(at 10.287 -73.279)
		(size 0.508)
		(drill 0.254)
		(layers "F.Cu" "B.Cu")
		(net "OCP_V3_2_PRSNT01_R1_N")
	)
	(segment
		(start 79.26705 -66.802)
		(end 79.26705 -65.746122)
		(width 0.10668)
		(layer "F.Cu")
		(net "OCP_V3_2_P3V3_R1_PWRGD")
	)
	(segment
		(start 76.835 -64.40805)
		(end 76.835 -64.897)
		(width 0.10668)
		(layer "F.Cu")
		(net "OCP_V3_2_P3V3_R1_PWRGD")
	)
	(segment
		(start 76.835 -64.897)
		(end 77.096112 -65.158112)
		(width 0.10668)
		(layer "F.Cu")
		(net "OCP_V3_2_P3V3_R1_PWRGD")
	)
	(segment
		(start 77.858112 -65.158112)
		(end 78.67904 -65.158112)
		(width 0.10668)
		(layer "F.Cu")
		(net "OCP_V3_2_P3V3_R1_PWRGD")
	)
	(segment
		(start 80.24495 -66.802)
		(end 79.26705 -66.802)
		(width 0.10668)
		(layer "F.Cu")
		(net "OCP_V3_2_P3V3_R1_PWRGD")
	)
	(segment
		(start 79.26705 -65.746122)
		(end 78.67904 -65.158112)
		(width 0.10668)
		(layer "F.Cu")
		(net "OCP_V3_2_P3V3_R1_PWRGD")
	)
	(segment
		(start 77.096112 -65.158112)
		(end 77.858112 -65.158112)
		(width 0.10668)
		(layer "F.Cu")
		(net "OCP_V3_2_P3V3_R1_PWRGD")
	)
	(via
		(at 77.858112 -65.158112)
		(size 0.508)
		(drill 0.254)
		(layers "F.Cu" "B.Cu")
		(net "OCP_V3_2_P3V3_R1_PWRGD")
	)
	(segment
		(start 413.766 -98.82505)
		(end 412.75 -98.82505)
		(width 0.10668)
		(layer "F.Cu")
		(net "OCP_V3_1_P3V3_R1_PWRGD")
	)
	(segment
		(start 413.766 -99.80295)
		(end 414.440878 -99.80295)
		(width 0.10668)
		(layer "F.Cu")
		(net "OCP_V3_1_P3V3_R1_PWRGD")
	)
	(segment
		(start 414.440878 -99.80295)
		(end 415.22904 -100.591112)
		(width 0.10668)
		(layer "F.Cu")
		(net "OCP_V3_1_P3V3_R1_PWRGD")
	)
	(segment
		(start 413.766 -99.80295)
		(end 413.766 -98.82505)
		(width 0.10668)
		(layer "F.Cu")
		(net "OCP_V3_1_P3V3_R1_PWRGD")
	)
	(via
		(at 414.440878 -99.80295)
		(size 0.508)
		(drill 0.254)
		(layers "F.Cu" "B.Cu")
		(net "OCP_V3_1_P3V3_R1_PWRGD")
	)
	(segment
		(start 11.351768 -75.044808)
		(end 12.164568 -75.044808)
		(width 0.10668)
		(layer "F.Cu")
		(net "OCP_SFF_PRSNT23_R1_N")
	)
	(via
		(at 12.164568 -75.044808)
		(size 0.508)
		(drill 0.254)
		(layers "F.Cu" "B.Cu")
		(net "OCP_SFF_PRSNT23_R1_N")
	)
	(segment
		(start 9.652 -75.87361)
		(end 10.480802 -75.044808)
		(width 0.10668)
		(layer "B.Cu")
		(net "OCP_SFF_PRSNT23_R1_N")
	)
	(segment
		(start 10.480802 -75.044808)
		(end 12.164568 -75.044808)
		(width 0.10668)
		(layer "B.Cu")
		(net "OCP_SFF_PRSNT23_R1_N")
	)
	(segment
		(start 8.382 -80.75295)
		(end 9.271 -80.75295)
		(width 0.10668)
		(layer "B.Cu")
		(net "OCP_SFF_PRSNT23_R1_N")
	)
	(segment
		(start 9.271 -80.75295)
		(end 9.652 -80.37195)
		(width 0.10668)
		(layer "B.Cu")
		(net "OCP_SFF_PRSNT23_R1_N")
	)
	(segment
		(start 9.652 -80.37195)
		(end 9.652 -75.87361)
		(width 0.10668)
		(layer "B.Cu")
		(net "OCP_SFF_PRSNT23_R1_N")
	)
	(segment
		(start 11.351768 -75.744578)
		(end 10.538968 -75.744578)
		(width 0.10668)
		(layer "F.Cu")
		(net "OCP_SFF_PRSNT01_R1_N")
	)
	(via
		(at 10.538968 -75.744578)
		(size 0.508)
		(drill 0.254)
		(layers "F.Cu" "B.Cu")
		(net "OCP_SFF_PRSNT01_R1_N")
	)
	(segment
		(start 10.084308 -76.199238)
		(end 10.538968 -75.744578)
		(width 0.10668)
		(layer "B.Cu")
		(net "OCP_SFF_PRSNT01_R1_N")
	)
	(segment
		(start 10.084308 -80.677258)
		(end 10.084308 -76.199238)
		(width 0.10668)
		(layer "B.Cu")
		(net "OCP_SFF_PRSNT01_R1_N")
	)
	(segment
		(start 10.16 -80.75295)
		(end 10.084308 -80.677258)
		(width 0.10668)
		(layer "B.Cu")
		(net "OCP_SFF_PRSNT01_R1_N")
	)
	(segment
		(start 11.049 -80.75295)
		(end 10.16 -80.75295)
		(width 0.10668)
		(layer "B.Cu")
		(net "OCP_SFF_PRSNT01_R1_N")
	)
	(via
		(at 203.019406 -139.51204)
		(size 0.6604)
		(drill 0.3302)
		(layers "F.Cu" "B.Cu")
		(net "NC_U8004_2Y")
	)
	(segment
		(start 201.690986 -139.51204)
		(end 203.019406 -139.51204)
		(width 0.10668)
		(layer "B.Cu")
		(net "NC_U8004_2Y")
	)
	(segment
		(start 13.38072 -412.931102)
		(end 13.38072 -412.712916)
		(width 0.1778)
		(layer "F.Cu")
		(net "NC_P0V9_RETIMER_CPU1_IMON8")
	)
	(segment
		(start 11.717782 -414.863534)
		(end 11.717782 -414.59404)
		(width 0.254)
		(layer "F.Cu")
		(net "NC_P0V9_RETIMER_CPU1_IMON8")
	)
	(segment
		(start 11.717782 -414.59404)
		(end 12.013438 -414.298384)
		(width 0.254)
		(layer "F.Cu")
		(net "NC_P0V9_RETIMER_CPU1_IMON8")
	)
	(segment
		(start 12.013438 -414.298384)
		(end 13.38072 -412.931102)
		(width 0.1778)
		(layer "F.Cu")
		(net "NC_P0V9_RETIMER_CPU1_IMON8")
	)
	(segment
		(start 13.78077 -413.073596)
		(end 13.78077 -412.712916)
		(width 0.1778)
		(layer "F.Cu")
		(net "NC_P0V9_RETIMER_CPU1_IMON7")
	)
	(segment
		(start 12.987782 -414.476184)
		(end 12.987782 -413.866584)
		(width 0.1778)
		(layer "F.Cu")
		(net "NC_P0V9_RETIMER_CPU1_IMON7")
	)
	(segment
		(start 12.987782 -413.866584)
		(end 13.78077 -413.073596)
		(width 0.1778)
		(layer "F.Cu")
		(net "NC_P0V9_RETIMER_CPU1_IMON7")
	)
	(segment
		(start 12.987782 -414.863534)
		(end 12.987782 -414.476184)
		(width 0.254)
		(layer "F.Cu")
		(net "NC_P0V9_RETIMER_CPU1_IMON7")
	)
	(segment
		(start 14.18082 -413.371284)
		(end 14.18082 -412.712916)
		(width 0.1778)
		(layer "F.Cu")
		(net "NC_P0V9_RETIMER_CPU1_IMON6")
	)
	(segment
		(start 13.622782 -413.929322)
		(end 14.18082 -413.371284)
		(width 0.1778)
		(layer "F.Cu")
		(net "NC_P0V9_RETIMER_CPU1_IMON6")
	)
	(segment
		(start 13.622782 -413.993584)
		(end 13.622782 -413.929322)
		(width 0.1778)
		(layer "F.Cu")
		(net "NC_P0V9_RETIMER_CPU1_IMON6")
	)
	(via
		(at 13.622782 -413.993584)
		(size 0.508)
		(drill 0.254)
		(layers "F.Cu" "B.Cu")
		(net "NC_P0V9_RETIMER_CPU1_IMON6")
	)
	(segment
		(start 13.622782 -415.244534)
		(end 13.622782 -413.993584)
		(width 0.254)
		(layer "B.Cu")
		(net "NC_P0V9_RETIMER_CPU1_IMON6")
	)
	(segment
		(start 14.58087 -413.513778)
		(end 14.58087 -412.712916)
		(width 0.1778)
		(layer "F.Cu")
		(net "NC_P0V9_RETIMER_CPU1_IMON5")
	)
	(segment
		(start 14.257782 -415.650934)
		(end 14.257782 -414.450784)
		(width 0.254)
		(layer "F.Cu")
		(net "NC_P0V9_RETIMER_CPU1_IMON5")
	)
	(segment
		(start 14.257782 -414.450784)
		(end 14.384782 -414.196784)
		(width 0.1778)
		(layer "F.Cu")
		(net "NC_P0V9_RETIMER_CPU1_IMON5")
	)
	(segment
		(start 14.384782 -414.196784)
		(end 14.384782 -413.709866)
		(width 0.1778)
		(layer "F.Cu")
		(net "NC_P0V9_RETIMER_CPU1_IMON5")
	)
	(segment
		(start 14.384782 -413.709866)
		(end 14.58087 -413.513778)
		(width 0.1778)
		(layer "F.Cu")
		(net "NC_P0V9_RETIMER_CPU1_IMON5")
	)
	(via
		(at 14.257782 -414.450784)
		(size 0.762)
		(drill 0.381)
		(layers "F.Cu" "B.Cu")
		(net "NC_P0V9_RETIMER_CPU1_IMON5")
	)
	(segment
		(start 14.98092 -412.712916)
		(end 14.98092 -413.905446)
		(width 0.1778)
		(layer "F.Cu")
		(net "NC_P0V9_RETIMER_CPU1_IMON4")
	)
	(segment
		(start 14.98092 -413.905446)
		(end 14.892782 -413.993584)
		(width 0.1778)
		(layer "F.Cu")
		(net "NC_P0V9_RETIMER_CPU1_IMON4")
	)
	(via
		(at 14.892782 -413.993584)
		(size 0.508)
		(drill 0.254)
		(layers "F.Cu" "B.Cu")
		(net "NC_P0V9_RETIMER_CPU1_IMON4")
	)
	(segment
		(start 14.892782 -413.993584)
		(end 14.892782 -415.244534)
		(width 0.254)
		(layer "B.Cu")
		(net "NC_P0V9_RETIMER_CPU1_IMON4")
	)
	(segment
		(start 15.527782 -414.476184)
		(end 15.527782 -413.993584)
		(width 0.1778)
		(layer "F.Cu")
		(net "NC_P0V9_RETIMER_CPU1_IMON3")
	)
	(segment
		(start 15.527782 -413.993584)
		(end 15.380716 -413.846518)
		(width 0.1778)
		(layer "F.Cu")
		(net "NC_P0V9_RETIMER_CPU1_IMON3")
	)
	(segment
		(start 15.527782 -415.650934)
		(end 15.527782 -414.476184)
		(width 0.254)
		(layer "F.Cu")
		(net "NC_P0V9_RETIMER_CPU1_IMON3")
	)
	(segment
		(start 15.380716 -413.846518)
		(end 15.380716 -412.712916)
		(width 0.1778)
		(layer "F.Cu")
		(net "NC_P0V9_RETIMER_CPU1_IMON3")
	)
	(via
		(at 15.527782 -414.476184)
		(size 0.762)
		(drill 0.381)
		(layers "F.Cu" "B.Cu")
		(net "NC_P0V9_RETIMER_CPU1_IMON3")
	)
	(segment
		(start 446.129664 -421.296592)
		(end 446.129664 -421.514778)
		(width 0.1778)
		(layer "F.Cu")
		(net "NC_P0V9_RETIMER_CPU0_IMON8")
	)
	(segment
		(start 447.792602 -419.633654)
		(end 447.496946 -419.92931)
		(width 0.254)
		(layer "F.Cu")
		(net "NC_P0V9_RETIMER_CPU0_IMON8")
	)
	(segment
		(start 447.792602 -419.36416)
		(end 447.792602 -419.633654)
		(width 0.254)
		(layer "F.Cu")
		(net "NC_P0V9_RETIMER_CPU0_IMON8")
	)
	(segment
		(start 447.496946 -419.92931)
		(end 446.129664 -421.296592)
		(width 0.1778)
		(layer "F.Cu")
		(net "NC_P0V9_RETIMER_CPU0_IMON8")
	)
	(segment
		(start 446.522602 -419.36416)
		(end 446.522602 -419.75151)
		(width 0.254)
		(layer "F.Cu")
		(net "NC_P0V9_RETIMER_CPU0_IMON7")
	)
	(segment
		(start 446.522602 -419.75151)
		(end 446.522602 -420.36111)
		(width 0.1778)
		(layer "F.Cu")
		(net "NC_P0V9_RETIMER_CPU0_IMON7")
	)
	(segment
		(start 446.522602 -420.36111)
		(end 445.729614 -421.154098)
		(width 0.1778)
		(layer "F.Cu")
		(net "NC_P0V9_RETIMER_CPU0_IMON7")
	)
	(segment
		(start 445.729614 -421.154098)
		(end 445.729614 -421.514778)
		(width 0.1778)
		(layer "F.Cu")
		(net "NC_P0V9_RETIMER_CPU0_IMON7")
	)
	(segment
		(start 445.887602 -420.23411)
		(end 445.887602 -420.298372)
		(width 0.1778)
		(layer "F.Cu")
		(net "NC_P0V9_RETIMER_CPU0_IMON6")
	)
	(segment
		(start 445.887602 -420.298372)
		(end 445.329564 -420.85641)
		(width 0.1778)
		(layer "F.Cu")
		(net "NC_P0V9_RETIMER_CPU0_IMON6")
	)
	(segment
		(start 445.329564 -420.85641)
		(end 445.329564 -421.514778)
		(width 0.1778)
		(layer "F.Cu")
		(net "NC_P0V9_RETIMER_CPU0_IMON6")
	)
	(via
		(at 445.887602 -420.23411)
		(size 0.508)
		(drill 0.254)
		(layers "F.Cu" "B.Cu")
		(net "NC_P0V9_RETIMER_CPU0_IMON6")
	)
	(segment
		(start 445.887602 -418.98316)
		(end 445.887602 -420.23411)
		(width 0.254)
		(layer "B.Cu")
		(net "NC_P0V9_RETIMER_CPU0_IMON6")
	)
	(segment
		(start 444.929514 -420.713916)
		(end 444.929514 -421.514778)
		(width 0.1778)
		(layer "F.Cu")
		(net "NC_P0V9_RETIMER_CPU0_IMON5")
	)
	(segment
		(start 445.252602 -419.77691)
		(end 445.125602 -420.03091)
		(width 0.1778)
		(layer "F.Cu")
		(net "NC_P0V9_RETIMER_CPU0_IMON5")
	)
	(segment
		(start 445.252602 -418.57676)
		(end 445.252602 -419.77691)
		(width 0.254)
		(layer "F.Cu")
		(net "NC_P0V9_RETIMER_CPU0_IMON5")
	)
	(segment
		(start 445.125602 -420.517828)
		(end 444.929514 -420.713916)
		(width 0.1778)
		(layer "F.Cu")
		(net "NC_P0V9_RETIMER_CPU0_IMON5")
	)
	(segment
		(start 445.125602 -420.03091)
		(end 445.125602 -420.517828)
		(width 0.1778)
		(layer "F.Cu")
		(net "NC_P0V9_RETIMER_CPU0_IMON5")
	)
	(via
		(at 445.252602 -419.77691)
		(size 0.762)
		(drill 0.381)
		(layers "F.Cu" "B.Cu")
		(net "NC_P0V9_RETIMER_CPU0_IMON5")
	)
	(segment
		(start 444.529464 -421.514778)
		(end 444.529464 -420.322248)
		(width 0.1778)
		(layer "F.Cu")
		(net "NC_P0V9_RETIMER_CPU0_IMON4")
	)
	(segment
		(start 444.529464 -420.322248)
		(end 444.617602 -420.23411)
		(width 0.1778)
		(layer "F.Cu")
		(net "NC_P0V9_RETIMER_CPU0_IMON4")
	)
	(via
		(at 444.617602 -420.23411)
		(size 0.508)
		(drill 0.254)
		(layers "F.Cu" "B.Cu")
		(net "NC_P0V9_RETIMER_CPU0_IMON4")
	)
	(segment
		(start 444.617602 -420.23411)
		(end 444.617602 -418.98316)
		(width 0.254)
		(layer "B.Cu")
		(net "NC_P0V9_RETIMER_CPU0_IMON4")
	)
	(segment
		(start 443.982602 -420.23411)
		(end 444.129668 -420.381176)
		(width 0.1778)
		(layer "F.Cu")
		(net "NC_P0V9_RETIMER_CPU0_IMON3")
	)
	(segment
		(start 444.129668 -420.381176)
		(end 444.129668 -421.514778)
		(width 0.1778)
		(layer "F.Cu")
		(net "NC_P0V9_RETIMER_CPU0_IMON3")
	)
	(segment
		(start 443.982602 -419.75151)
		(end 443.982602 -420.23411)
		(width 0.1778)
		(layer "F.Cu")
		(net "NC_P0V9_RETIMER_CPU0_IMON3")
	)
	(segment
		(start 443.982602 -418.57676)
		(end 443.982602 -419.75151)
		(width 0.254)
		(layer "F.Cu")
		(net "NC_P0V9_RETIMER_CPU0_IMON3")
	)
	(via
		(at 443.982602 -419.75151)
		(size 0.762)
		(drill 0.381)
		(layers "F.Cu" "B.Cu")
		(net "NC_P0V9_RETIMER_CPU0_IMON3")
	)
	(segment
		(start 191.389 -52.832)
		(end 191.389 -54.026054)
		(width 0.10668)
		(layer "F.Cu")
		(net "LED_P12V_SCM_FAULT_D2")
	)
	(segment
		(start 191.389 -54.026054)
		(end 191.403986 -54.04104)
		(width 0.10668)
		(layer "F.Cu")
		(net "LED_P12V_SCM_FAULT_D2")
	)
	(segment
		(start 191.389 -51.423062)
		(end 191.389 -52.832)
		(width 0.10668)
		(layer "F.Cu")
		(net "LED_P12V_SCM_FAULT_D2")
	)
	(via
		(at 191.389 -52.832)
		(size 0.762)
		(drill 0.381)
		(layers "F.Cu" "B.Cu")
		(net "LED_P12V_SCM_FAULT_D2")
	)
	(segment
		(start 190.104014 -55.94096)
		(end 190.104014 -57.008014)
		(width 0.10668)
		(layer "F.Cu")
		(net "LED_P12V_SCM_FAULT_D1")
	)
	(segment
		(start 191.637666 -57.963054)
		(end 191.567054 -57.963054)
		(width 0.10668)
		(layer "F.Cu")
		(net "LED_P12V_SCM_FAULT_D1")
	)
	(segment
		(start 190.754 -55.94096)
		(end 190.754 -57.15)
		(width 0.10668)
		(layer "F.Cu")
		(net "LED_P12V_SCM_FAULT_D1")
	)
	(segment
		(start 190.246 -57.15)
		(end 190.754 -57.15)
		(width 0.10668)
		(layer "F.Cu")
		(net "LED_P12V_SCM_FAULT_D1")
	)
	(segment
		(start 190.104014 -57.008014)
		(end 190.246 -57.15)
		(width 0.10668)
		(layer "F.Cu")
		(net "LED_P12V_SCM_FAULT_D1")
	)
	(segment
		(start 191.567054 -57.963054)
		(end 190.754 -57.15)
		(width 0.10668)
		(layer "F.Cu")
		(net "LED_P12V_SCM_FAULT_D1")
	)
	(via
		(at 190.754 -57.15)
		(size 0.762)
		(drill 0.381)
		(layers "F.Cu" "B.Cu")
		(net "LED_P12V_SCM_FAULT_D1")
	)
	(segment
		(start 193.294 -53.95595)
		(end 193.294 -50.546)
		(width 0.10668)
		(layer "F.Cu")
		(net "LED_P12V_SCM_FAULT")
	)
	(segment
		(start 193.294 -50.546)
		(end 192.659 -49.911)
		(width 0.10668)
		(layer "F.Cu")
		(net "LED_P12V_SCM_FAULT")
	)
	(segment
		(start 191.400938 -49.911)
		(end 191.389 -49.922938)
		(width 0.10668)
		(layer "F.Cu")
		(net "LED_P12V_SCM_FAULT")
	)
	(segment
		(start 192.659 -49.911)
		(end 191.400938 -49.911)
		(width 0.10668)
		(layer "F.Cu")
		(net "LED_P12V_SCM_FAULT")
	)
	(via
		(at 193.294 -50.546)
		(size 0.762)
		(drill 0.381)
		(layers "F.Cu" "B.Cu")
		(net "LED_P12V_SCM_FAULT")
	)
	(segment
		(start 27.696414 -372.781576)
		(end 28.354274 -373.439436)
		(width 0.10668)
		(layer "F.Cu")
		(net "LED_P12V_PSU_R3")
	)
	(segment
		(start 28.354274 -373.439436)
		(end 30.940248 -373.439436)
		(width 0.10668)
		(layer "F.Cu")
		(net "LED_P12V_PSU_R3")
	)
	(segment
		(start 56.469788 -135.45947)
		(end 43.323002 -135.45947)
		(width 0.10668)
		(layer "F.Cu")
		(net "LED_P12V_PSU_R3")
	)
	(segment
		(start 6.080506 -182.95112)
		(end 6.080506 -334.790542)
		(width 0.10668)
		(layer "F.Cu")
		(net "LED_P12V_PSU_R3")
	)
	(segment
		(start 182.777384 -410.144722)
		(end 182.176166 -409.543504)
		(width 0.10668)
		(layer "F.Cu")
		(net "LED_P12V_PSU_R3")
	)
	(segment
		(start 33.618424 -371.907054)
		(end 38.82263 -371.907054)
		(width 0.10668)
		(layer "F.Cu")
		(net "LED_P12V_PSU_R3")
	)
	(segment
		(start 51.074066 -90.37574)
		(end 51.074066 -123.745244)
		(width 0.10668)
		(layer "F.Cu")
		(net "LED_P12V_PSU_R3")
	)
	(segment
		(start 4.439666 -368.530632)
		(end 26.271982 -368.530632)
		(width 0.10668)
		(layer "F.Cu")
		(net "LED_P12V_PSU_R3")
	)
	(segment
		(start 35.64001 -88.735916)
		(end 49.434242 -88.735916)
		(width 0.10668)
		(layer "F.Cu")
		(net "LED_P12V_PSU_R3")
	)
	(segment
		(start 49.434242 -88.735916)
		(end 51.074066 -90.37574)
		(width 0.10668)
		(layer "F.Cu")
		(net "LED_P12V_PSU_R3")
	)
	(segment
		(start 33.986216 -87.082122)
		(end 35.64001 -88.735916)
		(width 0.10668)
		(layer "F.Cu")
		(net "LED_P12V_PSU_R3")
	)
	(segment
		(start 30.940248 -373.439436)
		(end 31.952184 -373.020336)
		(width 0.10668)
		(layer "F.Cu")
		(net "LED_P12V_PSU_R3")
	)
	(segment
		(start 33.986216 -57.135522)
		(end 33.986216 -87.082122)
		(width 0.10668)
		(layer "F.Cu")
		(net "LED_P12V_PSU_R3")
	)
	(segment
		(start 35.04057 -143.741902)
		(end 24.571452 -143.741902)
		(width 0.10668)
		(layer "F.Cu")
		(net "LED_P12V_PSU_R3")
	)
	(segment
		(start 51.074066 -123.745244)
		(end 58.826654 -131.497832)
		(width 0.10668)
		(layer "F.Cu")
		(net "LED_P12V_PSU_R3")
	)
	(segment
		(start 3.691636 -367.782602)
		(end 4.439666 -368.530632)
		(width 0.10668)
		(layer "F.Cu")
		(net "LED_P12V_PSU_R3")
	)
	(segment
		(start 184.222644 -410.144722)
		(end 182.777384 -410.144722)
		(width 0.10668)
		(layer "F.Cu")
		(net "LED_P12V_PSU_R3")
	)
	(segment
		(start 43.323002 -135.45947)
		(end 35.04057 -143.741902)
		(width 0.10668)
		(layer "F.Cu")
		(net "LED_P12V_PSU_R3")
	)
	(segment
		(start 38.180772 -53.437282)
		(end 37.684456 -53.437282)
		(width 0.10668)
		(layer "F.Cu")
		(net "LED_P12V_PSU_R3")
	)
	(segment
		(start 58.826654 -133.102604)
		(end 56.469788 -135.45947)
		(width 0.10668)
		(layer "F.Cu")
		(net "LED_P12V_PSU_R3")
	)
	(segment
		(start 16.058388 -172.973238)
		(end 6.080506 -182.95112)
		(width 0.10668)
		(layer "F.Cu")
		(net "LED_P12V_PSU_R3")
	)
	(segment
		(start 38.82263 -371.907054)
		(end 41.439592 -374.524016)
		(width 0.10668)
		(layer "F.Cu")
		(net "LED_P12V_PSU_R3")
	)
	(segment
		(start 31.952184 -373.020336)
		(end 33.618424 -371.907054)
		(width 0.10668)
		(layer "F.Cu")
		(net "LED_P12V_PSU_R3")
	)
	(segment
		(start 37.684456 -53.437282)
		(end 33.986216 -57.135522)
		(width 0.10668)
		(layer "F.Cu")
		(net "LED_P12V_PSU_R3")
	)
	(segment
		(start 26.271982 -368.530632)
		(end 27.696414 -369.955064)
		(width 0.10668)
		(layer "F.Cu")
		(net "LED_P12V_PSU_R3")
	)
	(segment
		(start 24.571452 -143.741902)
		(end 16.058388 -152.254966)
		(width 0.10668)
		(layer "F.Cu")
		(net "LED_P12V_PSU_R3")
	)
	(segment
		(start 6.080506 -334.790542)
		(end 3.691636 -337.179412)
		(width 0.10668)
		(layer "F.Cu")
		(net "LED_P12V_PSU_R3")
	)
	(segment
		(start 27.696414 -369.955064)
		(end 27.696414 -372.781576)
		(width 0.10668)
		(layer "F.Cu")
		(net "LED_P12V_PSU_R3")
	)
	(segment
		(start 16.058388 -152.254966)
		(end 16.058388 -172.973238)
		(width 0.10668)
		(layer "F.Cu")
		(net "LED_P12V_PSU_R3")
	)
	(segment
		(start 3.691636 -337.179412)
		(end 3.691636 -367.782602)
		(width 0.10668)
		(layer "F.Cu")
		(net "LED_P12V_PSU_R3")
	)
	(segment
		(start 58.826654 -131.497832)
		(end 58.826654 -133.102604)
		(width 0.10668)
		(layer "F.Cu")
		(net "LED_P12V_PSU_R3")
	)
	(via
		(at 41.439592 -374.524016)
		(size 0.508)
		(drill 0.254)
		(layers "F.Cu" "B.Cu")
		(net "LED_P12V_PSU_R3")
	)
	(via
		(at 190.745872 -376.516646)
		(size 0.508)
		(drill 0.254)
		(layers "F.Cu" "B.Cu")
		(net "LED_P12V_PSU_R3")
	)
	(via
		(at 182.176166 -409.543504)
		(size 0.508)
		(drill 0.254)
		(layers "F.Cu" "B.Cu")
		(net "LED_P12V_PSU_R3")
	)
	(segment
		(start 40.705532 -370.153184)
		(end 44.142914 -366.715802)
		(width 0.10668)
		(layer "B.Cu")
		(net "LED_P12V_PSU_R3")
	)
	(segment
		(start 40.705532 -373.789956)
		(end 40.705532 -370.153184)
		(width 0.10668)
		(layer "B.Cu")
		(net "LED_P12V_PSU_R3")
	)
	(segment
		(start 179.157122 -371.207538)
		(end 180.112162 -372.162578)
		(width 0.10668)
		(layer "B.Cu")
		(net "LED_P12V_PSU_R3")
	)
	(segment
		(start 180.112162 -372.162578)
		(end 186.391804 -372.162578)
		(width 0.10668)
		(layer "B.Cu")
		(net "LED_P12V_PSU_R3")
	)
	(segment
		(start 170.449748 -366.715802)
		(end 174.941484 -371.207538)
		(width 0.10668)
		(layer "B.Cu")
		(net "LED_P12V_PSU_R3")
	)
	(segment
		(start 44.142914 -366.715802)
		(end 170.449748 -366.715802)
		(width 0.10668)
		(layer "B.Cu")
		(net "LED_P12V_PSU_R3")
	)
	(segment
		(start 186.391804 -372.162578)
		(end 190.745872 -376.516646)
		(width 0.10668)
		(layer "B.Cu")
		(net "LED_P12V_PSU_R3")
	)
	(segment
		(start 41.439592 -374.524016)
		(end 40.705532 -373.789956)
		(width 0.10668)
		(layer "B.Cu")
		(net "LED_P12V_PSU_R3")
	)
	(segment
		(start 174.941484 -371.207538)
		(end 179.157122 -371.207538)
		(width 0.10668)
		(layer "B.Cu")
		(net "LED_P12V_PSU_R3")
	)
	(segment
		(start 185.733182 -381.010414)
		(end 185.733182 -389.055102)
		(width 0.11684)
		(layer "In6.Cu")
		(net "LED_P12V_PSU_R3")
	)
	(segment
		(start 190.745872 -376.516646)
		(end 190.227204 -376.516646)
		(width 0.11684)
		(layer "In6.Cu")
		(net "LED_P12V_PSU_R3")
	)
	(segment
		(start 180.12664 -409.543504)
		(end 182.176166 -409.543504)
		(width 0.11684)
		(layer "In6.Cu")
		(net "LED_P12V_PSU_R3")
	)
	(segment
		(start 179.492656 -408.90952)
		(end 180.12664 -409.543504)
		(width 0.11684)
		(layer "In6.Cu")
		(net "LED_P12V_PSU_R3")
	)
	(segment
		(start 178.420776 -395.91107)
		(end 178.420776 -399.707608)
		(width 0.11684)
		(layer "In6.Cu")
		(net "LED_P12V_PSU_R3")
	)
	(segment
		(start 178.95062 -405.562308)
		(end 179.291488 -405.903176)
		(width 0.11684)
		(layer "In6.Cu")
		(net "LED_P12V_PSU_R3")
	)
	(segment
		(start 190.227204 -376.516646)
		(end 185.733182 -381.010414)
		(width 0.11684)
		(layer "In6.Cu")
		(net "LED_P12V_PSU_R3")
	)
	(segment
		(start 185.733182 -389.055102)
		(end 182.805324 -391.98296)
		(width 0.11684)
		(layer "In6.Cu")
		(net "LED_P12V_PSU_R3")
	)
	(segment
		(start 179.291488 -407.349706)
		(end 179.492656 -407.550874)
		(width 0.11684)
		(layer "In6.Cu")
		(net "LED_P12V_PSU_R3")
	)
	(segment
		(start 182.348886 -391.98296)
		(end 178.420776 -395.91107)
		(width 0.11684)
		(layer "In6.Cu")
		(net "LED_P12V_PSU_R3")
	)
	(segment
		(start 179.291488 -405.903176)
		(end 179.291488 -407.349706)
		(width 0.11684)
		(layer "In6.Cu")
		(net "LED_P12V_PSU_R3")
	)
	(segment
		(start 178.420776 -399.707608)
		(end 178.95062 -400.237452)
		(width 0.11684)
		(layer "In6.Cu")
		(net "LED_P12V_PSU_R3")
	)
	(segment
		(start 178.95062 -400.237452)
		(end 178.95062 -405.562308)
		(width 0.11684)
		(layer "In6.Cu")
		(net "LED_P12V_PSU_R3")
	)
	(segment
		(start 182.805324 -391.98296)
		(end 182.348886 -391.98296)
		(width 0.11684)
		(layer "In6.Cu")
		(net "LED_P12V_PSU_R3")
	)
	(segment
		(start 179.492656 -407.550874)
		(end 179.492656 -408.90952)
		(width 0.11684)
		(layer "In6.Cu")
		(net "LED_P12V_PSU_R3")
	)
	(segment
		(start 38.180772 -55.469282)
		(end 37.777166 -55.469282)
		(width 0.10668)
		(layer "F.Cu")
		(net "LED_P12V_PSU_R2")
	)
	(segment
		(start 37.649912 -54.367176)
		(end 37.649912 -54.893972)
		(width 0.10668)
		(layer "F.Cu")
		(net "LED_P12V_PSU_R2")
	)
	(segment
		(start 37.777166 -55.469282)
		(end 37.649912 -55.342028)
		(width 0.10668)
		(layer "F.Cu")
		(net "LED_P12V_PSU_R2")
	)
	(segment
		(start 37.779706 -54.237382)
		(end 37.649912 -54.367176)
		(width 0.10668)
		(layer "F.Cu")
		(net "LED_P12V_PSU_R2")
	)
	(segment
		(start 38.180772 -54.237382)
		(end 37.779706 -54.237382)
		(width 0.10668)
		(layer "F.Cu")
		(net "LED_P12V_PSU_R2")
	)
	(segment
		(start 37.649912 -55.342028)
		(end 37.649912 -54.893972)
		(width 0.10668)
		(layer "F.Cu")
		(net "LED_P12V_PSU_R2")
	)
	(via
		(at 37.649912 -54.893972)
		(size 0.508)
		(drill 0.254)
		(layers "F.Cu" "B.Cu")
		(net "LED_P12V_PSU_R2")
	)
	(segment
		(start 38.180772 -57.680352)
		(end 37.904674 -57.404254)
		(width 0.10668)
		(layer "F.Cu")
		(net "LED_P12V_PSU_R1")
	)
	(segment
		(start 37.904674 -57.404254)
		(end 37.904674 -56.947816)
		(width 0.10668)
		(layer "F.Cu")
		(net "LED_P12V_PSU_R1")
	)
	(segment
		(start 38.180772 -56.269382)
		(end 37.904674 -56.54548)
		(width 0.10668)
		(layer "F.Cu")
		(net "LED_P12V_PSU_R1")
	)
	(segment
		(start 37.904674 -56.54548)
		(end 37.904674 -56.947816)
		(width 0.10668)
		(layer "F.Cu")
		(net "LED_P12V_PSU_R1")
	)
	(via
		(at 37.904674 -56.947816)
		(size 0.508)
		(drill 0.254)
		(layers "F.Cu" "B.Cu")
		(net "LED_P12V_PSU_R1")
	)
	(segment
		(start 367.841276 -62.0903)
		(end 367.841276 -62.47384)
		(width 0.10668)
		(layer "F.Cu")
		(net "LED_P12V_AUX_R3")
	)
	(segment
		(start 359.168954 -62.962536)
		(end 358.3305 -62.124082)
		(width 0.10668)
		(layer "F.Cu")
		(net "LED_P12V_AUX_R3")
	)
	(segment
		(start 367.841276 -62.47384)
		(end 367.35258 -62.962536)
		(width 0.10668)
		(layer "F.Cu")
		(net "LED_P12V_AUX_R3")
	)
	(segment
		(start 191.415924 -45.092874)
		(end 191.415924 -46.284134)
		(width 0.10668)
		(layer "F.Cu")
		(net "LED_P12V_AUX_R3")
	)
	(segment
		(start 367.35258 -62.962536)
		(end 359.168954 -62.962536)
		(width 0.10668)
		(layer "F.Cu")
		(net "LED_P12V_AUX_R3")
	)
	(segment
		(start 190.90005 -44.577)
		(end 191.415924 -45.092874)
		(width 0.10668)
		(layer "F.Cu")
		(net "LED_P12V_AUX_R3")
	)
	(segment
		(start 191.415924 -46.284134)
		(end 190.90005 -46.800008)
		(width 0.10668)
		(layer "F.Cu")
		(net "LED_P12V_AUX_R3")
	)
	(via
		(at 358.3305 -62.124082)
		(size 0.508)
		(drill 0.254)
		(layers "F.Cu" "B.Cu")
		(net "LED_P12V_AUX_R3")
	)
	(via
		(at 190.90005 -46.800008)
		(size 0.508)
		(drill 0.254)
		(layers "F.Cu" "B.Cu")
		(net "LED_P12V_AUX_R3")
	)
	(segment
		(start 285.515558 -58.740548)
		(end 275.134578 -69.121528)
		(width 0.11684)
		(layer "In2.Cu")
		(net "LED_P12V_AUX_R3")
	)
	(segment
		(start 192.023238 -45.67682)
		(end 190.90005 -46.800008)
		(width 0.11684)
		(layer "In2.Cu")
		(net "LED_P12V_AUX_R3")
	)
	(segment
		(start 209.51825 -41.157906)
		(end 201.435716 -41.157906)
		(width 0.11684)
		(layer "In2.Cu")
		(net "LED_P12V_AUX_R3")
	)
	(segment
		(start 273.715734 -69.121528)
		(end 269.407132 -64.812926)
		(width 0.11684)
		(layer "In2.Cu")
		(net "LED_P12V_AUX_R3")
	)
	(segment
		(start 353.211892 -58.740548)
		(end 285.515558 -58.740548)
		(width 0.11684)
		(layer "In2.Cu")
		(net "LED_P12V_AUX_R3")
	)
	(segment
		(start 210.36407 -46.110144)
		(end 210.36407 -42.003726)
		(width 0.11684)
		(layer "In2.Cu")
		(net "LED_P12V_AUX_R3")
	)
	(segment
		(start 358.3305 -62.124082)
		(end 356.595426 -62.124082)
		(width 0.11684)
		(layer "In2.Cu")
		(net "LED_P12V_AUX_R3")
	)
	(segment
		(start 269.407132 -64.812926)
		(end 229.066852 -64.812926)
		(width 0.11684)
		(layer "In2.Cu")
		(net "LED_P12V_AUX_R3")
	)
	(segment
		(start 196.916802 -45.67682)
		(end 192.023238 -45.67682)
		(width 0.11684)
		(layer "In2.Cu")
		(net "LED_P12V_AUX_R3")
	)
	(segment
		(start 201.435716 -41.157906)
		(end 196.916802 -45.67682)
		(width 0.11684)
		(layer "In2.Cu")
		(net "LED_P12V_AUX_R3")
	)
	(segment
		(start 356.595426 -62.124082)
		(end 353.211892 -58.740548)
		(width 0.11684)
		(layer "In2.Cu")
		(net "LED_P12V_AUX_R3")
	)
	(segment
		(start 210.36407 -42.003726)
		(end 209.51825 -41.157906)
		(width 0.11684)
		(layer "In2.Cu")
		(net "LED_P12V_AUX_R3")
	)
	(segment
		(start 275.134578 -69.121528)
		(end 273.715734 -69.121528)
		(width 0.11684)
		(layer "In2.Cu")
		(net "LED_P12V_AUX_R3")
	)
	(segment
		(start 229.066852 -64.812926)
		(end 210.36407 -46.110144)
		(width 0.11684)
		(layer "In2.Cu")
		(net "LED_P12V_AUX_R3")
	)
	(segment
		(start 367.041176 -62.0903)
		(end 365.790226 -62.0903)
		(width 0.10668)
		(layer "F.Cu")
		(net "LED_P12V_AUX_R2")
	)
	(segment
		(start 364.539276 -62.0903)
		(end 365.790226 -62.0903)
		(width 0.10668)
		(layer "F.Cu")
		(net "LED_P12V_AUX_R2")
	)
	(via
		(at 365.790226 -62.0903)
		(size 0.762)
		(drill 0.381)
		(layers "F.Cu" "B.Cu")
		(net "LED_P12V_AUX_R2")
	)
	(segment
		(start 362.488226 -62.0903)
		(end 363.739176 -62.0903)
		(width 0.10668)
		(layer "F.Cu")
		(net "LED_P12V_AUX_R1")
	)
	(segment
		(start 361.185206 -62.0903)
		(end 362.488226 -62.0903)
		(width 0.10668)
		(layer "F.Cu")
		(net "LED_P12V_AUX_R1")
	)
	(via
		(at 362.488226 -62.0903)
		(size 0.762)
		(drill 0.381)
		(layers "F.Cu" "B.Cu")
		(net "LED_P12V_AUX_R1")
	)
	(segment
		(start 141.01699 -118.42496)
		(end 140.688822 -118.42496)
		(width 0.10668)
		(layer "F.Cu")
		(net "IRQ_UV_DETECT_R2_N")
	)
	(segment
		(start 140.688822 -118.42496)
		(end 140.24864 -118.865142)
		(width 0.10668)
		(layer "F.Cu")
		(net "IRQ_UV_DETECT_R2_N")
	)
	(segment
		(start 141.96695 -121.285)
		(end 141.96695 -120.269)
		(width 0.10668)
		(layer "F.Cu")
		(net "IRQ_UV_DETECT_R2_N")
	)
	(segment
		(start 140.773404 -120.269)
		(end 140.476732 -119.972328)
		(width 0.10668)
		(layer "F.Cu")
		(net "IRQ_UV_DETECT_R2_N")
	)
	(segment
		(start 140.24864 -119.744236)
		(end 140.476732 -119.972328)
		(width 0.10668)
		(layer "F.Cu")
		(net "IRQ_UV_DETECT_R2_N")
	)
	(segment
		(start 141.96695 -120.269)
		(end 140.773404 -120.269)
		(width 0.10668)
		(layer "F.Cu")
		(net "IRQ_UV_DETECT_R2_N")
	)
	(segment
		(start 140.24864 -118.865142)
		(end 140.24864 -119.744236)
		(width 0.10668)
		(layer "F.Cu")
		(net "IRQ_UV_DETECT_R2_N")
	)
	(via
		(at 140.476732 -119.972328)
		(size 0.762)
		(drill 0.381)
		(layers "F.Cu" "B.Cu")
		(net "IRQ_UV_DETECT_R2_N")
	)
	(via
		(at 186.37504 -423.394124)
		(size 0.6604)
		(drill 0.3302)
		(layers "F.Cu" "B.Cu")
		(net "HSC_OC_VOL")
	)
	(segment
		(start 185.066686 -425.067476)
		(end 185.430414 -425.431204)
		(width 0.10668)
		(layer "B.Cu")
		(net "HSC_OC_VOL")
	)
	(segment
		(start 183.55056 -422.608502)
		(end 183.54802 -422.611042)
		(width 0.10668)
		(layer "B.Cu")
		(net "HSC_OC_VOL")
	)
	(segment
		(start 186.37504 -425.071794)
		(end 186.37504 -424.86199)
		(width 0.10668)
		(layer "B.Cu")
		(net "HSC_OC_VOL")
	)
	(segment
		(start 186.37504 -423.101262)
		(end 185.88228 -422.608502)
		(width 0.10668)
		(layer "B.Cu")
		(net "HSC_OC_VOL")
	)
	(segment
		(start 185.430414 -425.431204)
		(end 186.01563 -425.431204)
		(width 0.10668)
		(layer "B.Cu")
		(net "HSC_OC_VOL")
	)
	(segment
		(start 185.496708 -422.608502)
		(end 184.480708 -422.608502)
		(width 0.10668)
		(layer "B.Cu")
		(net "HSC_OC_VOL")
	)
	(segment
		(start 186.37504 -423.394124)
		(end 186.37504 -423.101262)
		(width 0.10668)
		(layer "B.Cu")
		(net "HSC_OC_VOL")
	)
	(segment
		(start 186.37504 -424.86199)
		(end 186.37504 -423.394124)
		(width 0.10668)
		(layer "B.Cu")
		(net "HSC_OC_VOL")
	)
	(segment
		(start 186.01563 -425.431204)
		(end 186.37504 -425.071794)
		(width 0.10668)
		(layer "B.Cu")
		(net "HSC_OC_VOL")
	)
	(segment
		(start 185.88228 -422.608502)
		(end 185.496708 -422.608502)
		(width 0.10668)
		(layer "B.Cu")
		(net "HSC_OC_VOL")
	)
	(segment
		(start 184.719468 -425.067476)
		(end 185.066686 -425.067476)
		(width 0.10668)
		(layer "B.Cu")
		(net "HSC_OC_VOL")
	)
	(segment
		(start 184.480708 -422.608502)
		(end 183.55056 -422.608502)
		(width 0.10668)
		(layer "B.Cu")
		(net "HSC_OC_VOL")
	)
	(via
		(at 184.719468 -426.697902)
		(size 0.6604)
		(drill 0.3302)
		(layers "F.Cu" "B.Cu")
		(net "HSC_D_OC_R2")
	)
	(segment
		(start 184.789318 -427.442884)
		(end 185.088022 -427.741588)
		(width 0.10668)
		(layer "B.Cu")
		(net "HSC_D_OC_R2")
	)
	(segment
		(start 184.719468 -425.867576)
		(end 184.719468 -426.697902)
		(width 0.10668)
		(layer "B.Cu")
		(net "HSC_D_OC_R2")
	)
	(segment
		(start 185.088022 -427.741588)
		(end 185.088022 -428.15764)
		(width 0.10668)
		(layer "B.Cu")
		(net "HSC_D_OC_R2")
	)
	(segment
		(start 186.002676 -425.867576)
		(end 184.719468 -425.867576)
		(width 0.10668)
		(layer "B.Cu")
		(net "HSC_D_OC_R2")
	)
	(segment
		(start 186.37504 -426.23994)
		(end 186.002676 -425.867576)
		(width 0.10668)
		(layer "B.Cu")
		(net "HSC_D_OC_R2")
	)
	(segment
		(start 184.789318 -426.767752)
		(end 184.789318 -427.442884)
		(width 0.10668)
		(layer "B.Cu")
		(net "HSC_D_OC_R2")
	)
	(segment
		(start 184.719468 -426.697902)
		(end 184.789318 -426.767752)
		(width 0.10668)
		(layer "B.Cu")
		(net "HSC_D_OC_R2")
	)
	(segment
		(start 186.37504 -427.56201)
		(end 186.37504 -426.23994)
		(width 0.10668)
		(layer "B.Cu")
		(net "HSC_D_OC_R2")
	)
	(segment
		(start 175.294036 -29.437584)
		(end 174.477426 -29.437584)
		(width 0.10668)
		(layer "F.Cu")
		(net "HP_LVC3_SCM_HSC_PWRGD_R")
	)
	(segment
		(start 174.477426 -29.437584)
		(end 174.470314 -29.430472)
		(width 0.10668)
		(layer "F.Cu")
		(net "HP_LVC3_SCM_HSC_PWRGD_R")
	)
	(segment
		(start 174.470314 -29.430472)
		(end 173.616112 -29.430472)
		(width 0.10668)
		(layer "F.Cu")
		(net "HP_LVC3_SCM_HSC_PWRGD_R")
	)
	(via
		(at 174.470314 -29.430472)
		(size 0.508)
		(drill 0.254)
		(layers "F.Cu" "B.Cu")
		(net "HP_LVC3_SCM_HSC_PWRGD_R")
	)
	(segment
		(start 173.369478 -29.430472)
		(end 174.470314 -29.430472)
		(width 0.10668)
		(layer "B.Cu")
		(net "HP_LVC3_SCM_HSC_PWRGD_R")
	)
	(segment
		(start 173.101 -29.69895)
		(end 173.369478 -29.430472)
		(width 0.10668)
		(layer "B.Cu")
		(net "HP_LVC3_SCM_HSC_PWRGD_R")
	)
	(segment
		(start 134.51205 -111.25708)
		(end 134.51205 -109.855)
		(width 0.10668)
		(layer "F.Cu")
		(net "FM_UV_ADR_TRIGGER_N_R2")
	)
	(segment
		(start 148.242274 -115.377468)
		(end 148.242274 -114.07902)
		(width 0.10668)
		(layer "F.Cu")
		(net "FM_UV_ADR_TRIGGER_N_R2")
	)
	(segment
		(start 141.859 -111.379)
		(end 141.859 -110.88624)
		(width 0.10668)
		(layer "F.Cu")
		(net "FM_UV_ADR_TRIGGER_N_R2")
	)
	(segment
		(start 136.061958 -109.855)
		(end 134.51205 -109.855)
		(width 0.10668)
		(layer "F.Cu")
		(net "FM_UV_ADR_TRIGGER_N_R2")
	)
	(segment
		(start 136.915906 -109.001052)
		(end 136.500108 -109.41685)
		(width 0.10668)
		(layer "F.Cu")
		(net "FM_UV_ADR_TRIGGER_N_R2")
	)
	(segment
		(start 141.859 -110.88624)
		(end 139.973812 -109.001052)
		(width 0.10668)
		(layer "F.Cu")
		(net "FM_UV_ADR_TRIGGER_N_R2")
	)
	(segment
		(start 134.57301 -111.31804)
		(end 134.51205 -111.25708)
		(width 0.10668)
		(layer "F.Cu")
		(net "FM_UV_ADR_TRIGGER_N_R2")
	)
	(segment
		(start 148.242274 -114.07902)
		(end 147.320254 -113.157)
		(width 0.10668)
		(layer "F.Cu")
		(net "FM_UV_ADR_TRIGGER_N_R2")
	)
	(segment
		(start 139.973812 -109.001052)
		(end 136.915906 -109.001052)
		(width 0.10668)
		(layer "F.Cu")
		(net "FM_UV_ADR_TRIGGER_N_R2")
	)
	(segment
		(start 147.320254 -113.157)
		(end 143.637 -113.157)
		(width 0.10668)
		(layer "F.Cu")
		(net "FM_UV_ADR_TRIGGER_N_R2")
	)
	(segment
		(start 143.637 -113.157)
		(end 141.859 -111.379)
		(width 0.10668)
		(layer "F.Cu")
		(net "FM_UV_ADR_TRIGGER_N_R2")
	)
	(segment
		(start 136.500108 -109.41685)
		(end 136.061958 -109.855)
		(width 0.10668)
		(layer "F.Cu")
		(net "FM_UV_ADR_TRIGGER_N_R2")
	)
	(via
		(at 136.500108 -109.41685)
		(size 0.762)
		(drill 0.381)
		(layers "F.Cu" "B.Cu")
		(net "FM_UV_ADR_TRIGGER_N_R2")
	)
	(segment
		(start 198.576946 -183.636412)
		(end 196.027548 -183.636412)
		(width 0.1524)
		(layer "F.Cu")
		(net "FM_PWRGD_P1V8_RETIMER_CPU1")
	)
	(segment
		(start 201.455274 -186.51474)
		(end 198.576946 -183.636412)
		(width 0.1524)
		(layer "F.Cu")
		(net "FM_PWRGD_P1V8_RETIMER_CPU1")
	)
	(segment
		(start 185.132218 -172.741082)
		(end 185.132218 -171.03471)
		(width 0.1524)
		(layer "F.Cu")
		(net "FM_PWRGD_P1V8_RETIMER_CPU1")
	)
	(segment
		(start 196.027548 -183.636412)
		(end 185.132218 -172.741082)
		(width 0.1524)
		(layer "F.Cu")
		(net "FM_PWRGD_P1V8_RETIMER_CPU1")
	)
	(segment
		(start 189.92215 -113.05286)
		(end 190.31204 -112.66297)
		(width 0.10668)
		(layer "F.Cu")
		(net "FM_PWRGD_P1V8_RETIMER_CPU1")
	)
	(segment
		(start 185.132218 -171.03471)
		(end 191.384682 -164.782246)
		(width 0.1524)
		(layer "F.Cu")
		(net "FM_PWRGD_P1V8_RETIMER_CPU1")
	)
	(via
		(at 191.384682 -164.782246)
		(size 0.508)
		(drill 0.254)
		(layers "F.Cu" "B.Cu")
		(net "FM_PWRGD_P1V8_RETIMER_CPU1")
	)
	(via
		(at 190.31204 -112.66297)
		(size 0.4572)
		(drill 0.254)
		(layers "F.Cu" "B.Cu")
		(net "FM_PWRGD_P1V8_RETIMER_CPU1")
	)
	(via
		(at 201.455274 -186.51474)
		(size 0.508)
		(drill 0.254)
		(layers "F.Cu" "B.Cu")
		(net "FM_PWRGD_P1V8_RETIMER_CPU1")
	)
	(segment
		(start 227.43668 -289.030156)
		(end 228.162104 -289.030156)
		(width 0.1524)
		(layer "B.Cu")
		(net "FM_PWRGD_P1V8_RETIMER_CPU1")
	)
	(segment
		(start 222.223584 -286.61995)
		(end 225.308414 -286.61995)
		(width 0.1524)
		(layer "B.Cu")
		(net "FM_PWRGD_P1V8_RETIMER_CPU1")
	)
	(segment
		(start 226.766628 -289.828732)
		(end 226.766628 -289.700208)
		(width 0.1524)
		(layer "B.Cu")
		(net "FM_PWRGD_P1V8_RETIMER_CPU1")
	)
	(segment
		(start 209.198464 -187.98286)
		(end 213.068916 -191.853312)
		(width 0.1524)
		(layer "B.Cu")
		(net "FM_PWRGD_P1V8_RETIMER_CPU1")
	)
	(segment
		(start 201.455274 -186.51474)
		(end 202.923394 -187.98286)
		(width 0.1524)
		(layer "B.Cu")
		(net "FM_PWRGD_P1V8_RETIMER_CPU1")
	)
	(segment
		(start 213.068916 -191.853312)
		(end 213.068916 -277.465282)
		(width 0.1524)
		(layer "B.Cu")
		(net "FM_PWRGD_P1V8_RETIMER_CPU1")
	)
	(segment
		(start 226.766628 -289.700208)
		(end 227.43668 -289.030156)
		(width 0.1524)
		(layer "B.Cu")
		(net "FM_PWRGD_P1V8_RETIMER_CPU1")
	)
	(segment
		(start 226.980496 -288.292032)
		(end 228.150928 -288.292032)
		(width 0.1524)
		(layer "B.Cu")
		(net "FM_PWRGD_P1V8_RETIMER_CPU1")
	)
	(segment
		(start 228.162104 -289.030156)
		(end 228.525578 -288.666682)
		(width 0.1524)
		(layer "B.Cu")
		(net "FM_PWRGD_P1V8_RETIMER_CPU1")
	)
	(segment
		(start 213.068916 -277.465282)
		(end 222.223584 -286.61995)
		(width 0.1524)
		(layer "B.Cu")
		(net "FM_PWRGD_P1V8_RETIMER_CPU1")
	)
	(segment
		(start 202.923394 -187.98286)
		(end 209.198464 -187.98286)
		(width 0.1524)
		(layer "B.Cu")
		(net "FM_PWRGD_P1V8_RETIMER_CPU1")
	)
	(segment
		(start 228.150928 -288.292032)
		(end 228.525578 -288.666682)
		(width 0.1524)
		(layer "B.Cu")
		(net "FM_PWRGD_P1V8_RETIMER_CPU1")
	)
	(segment
		(start 225.308414 -286.61995)
		(end 226.980496 -288.292032)
		(width 0.1524)
		(layer "B.Cu")
		(net "FM_PWRGD_P1V8_RETIMER_CPU1")
	)
	(segment
		(start 191.74079 -124.429266)
		(end 191.74079 -123.655836)
		(width 0.1524)
		(layer "In4.Cu")
		(net "FM_PWRGD_P1V8_RETIMER_CPU1")
	)
	(segment
		(start 191.509396 -119.597424)
		(end 191.353694 -119.441722)
		(width 0.11684)
		(layer "In4.Cu")
		(net "FM_PWRGD_P1V8_RETIMER_CPU1")
	)
	(segment
		(start 190.712344 -115.358926)
		(end 189.918848 -114.56543)
		(width 0.11684)
		(layer "In4.Cu")
		(net "FM_PWRGD_P1V8_RETIMER_CPU1")
	)
	(segment
		(start 189.918848 -113.056162)
		(end 190.31204 -112.66297)
		(width 0.11684)
		(layer "In4.Cu")
		(net "FM_PWRGD_P1V8_RETIMER_CPU1")
	)
	(segment
		(start 191.524382 -162.145726)
		(end 200.265284 -162.145726)
		(width 0.1524)
		(layer "In4.Cu")
		(net "FM_PWRGD_P1V8_RETIMER_CPU1")
	)
	(segment
		(start 199.19823 -146.75104)
		(end 199.19823 -144.353534)
		(width 0.1524)
		(layer "In4.Cu")
		(net "FM_PWRGD_P1V8_RETIMER_CPU1")
	)
	(segment
		(start 191.353694 -119.441722)
		(end 190.92545 -119.441722)
		(width 0.11684)
		(layer "In4.Cu")
		(net "FM_PWRGD_P1V8_RETIMER_CPU1")
	)
	(segment
		(start 191.509396 -123.424442)
		(end 191.509396 -119.597424)
		(width 0.11684)
		(layer "In4.Cu")
		(net "FM_PWRGD_P1V8_RETIMER_CPU1")
	)
	(segment
		(start 191.384682 -162.285426)
		(end 191.524382 -162.145726)
		(width 0.1524)
		(layer "In4.Cu")
		(net "FM_PWRGD_P1V8_RETIMER_CPU1")
	)
	(segment
		(start 189.918848 -114.56543)
		(end 189.918848 -113.056162)
		(width 0.11684)
		(layer "In4.Cu")
		(net "FM_PWRGD_P1V8_RETIMER_CPU1")
	)
	(segment
		(start 202.191112 -149.743922)
		(end 199.19823 -146.75104)
		(width 0.1524)
		(layer "In4.Cu")
		(net "FM_PWRGD_P1V8_RETIMER_CPU1")
	)
	(segment
		(start 194.980052 -127.668528)
		(end 191.74079 -124.429266)
		(width 0.1524)
		(layer "In4.Cu")
		(net "FM_PWRGD_P1V8_RETIMER_CPU1")
	)
	(segment
		(start 191.384682 -164.782246)
		(end 191.384682 -162.285426)
		(width 0.1524)
		(layer "In4.Cu")
		(net "FM_PWRGD_P1V8_RETIMER_CPU1")
	)
	(segment
		(start 190.712344 -119.228616)
		(end 190.712344 -115.358926)
		(width 0.11684)
		(layer "In4.Cu")
		(net "FM_PWRGD_P1V8_RETIMER_CPU1")
	)
	(segment
		(start 197.035928 -140.936218)
		(end 197.898258 -140.073888)
		(width 0.1524)
		(layer "In4.Cu")
		(net "FM_PWRGD_P1V8_RETIMER_CPU1")
	)
	(segment
		(start 199.19823 -144.353534)
		(end 197.035928 -142.191232)
		(width 0.1524)
		(layer "In4.Cu")
		(net "FM_PWRGD_P1V8_RETIMER_CPU1")
	)
	(segment
		(start 197.035928 -142.191232)
		(end 197.035928 -140.936218)
		(width 0.1524)
		(layer "In4.Cu")
		(net "FM_PWRGD_P1V8_RETIMER_CPU1")
	)
	(segment
		(start 191.74079 -123.655836)
		(end 191.509396 -123.424442)
		(width 0.11684)
		(layer "In4.Cu")
		(net "FM_PWRGD_P1V8_RETIMER_CPU1")
	)
	(segment
		(start 190.92545 -119.441722)
		(end 190.712344 -119.228616)
		(width 0.11684)
		(layer "In4.Cu")
		(net "FM_PWRGD_P1V8_RETIMER_CPU1")
	)
	(segment
		(start 197.898258 -132.755386)
		(end 194.980052 -129.83718)
		(width 0.1524)
		(layer "In4.Cu")
		(net "FM_PWRGD_P1V8_RETIMER_CPU1")
	)
	(segment
		(start 202.191112 -160.219898)
		(end 202.191112 -149.743922)
		(width 0.1524)
		(layer "In4.Cu")
		(net "FM_PWRGD_P1V8_RETIMER_CPU1")
	)
	(segment
		(start 194.980052 -129.83718)
		(end 194.980052 -127.668528)
		(width 0.1524)
		(layer "In4.Cu")
		(net "FM_PWRGD_P1V8_RETIMER_CPU1")
	)
	(segment
		(start 200.265284 -162.145726)
		(end 202.191112 -160.219898)
		(width 0.1524)
		(layer "In4.Cu")
		(net "FM_PWRGD_P1V8_RETIMER_CPU1")
	)
	(segment
		(start 197.898258 -140.073888)
		(end 197.898258 -132.755386)
		(width 0.1524)
		(layer "In4.Cu")
		(net "FM_PWRGD_P1V8_RETIMER_CPU1")
	)
	(segment
		(start 202.383644 -129.320798)
		(end 203.0603 -129.997454)
		(width 0.10668)
		(layer "F.Cu")
		(net "FM_JTAG_BMC_R_OE")
	)
	(segment
		(start 201.983848 -129.320798)
		(end 202.383644 -129.320798)
		(width 0.10668)
		(layer "F.Cu")
		(net "FM_JTAG_BMC_R_OE")
	)
	(segment
		(start 423.827448 -57.047638)
		(end 422.129712 -57.047638)
		(width 0.10668)
		(layer "F.Cu")
		(net "FM_JTAG_BMC_R_OE")
	)
	(segment
		(start 422.148 -57.02935)
		(end 422.129712 -57.047638)
		(width 0.10668)
		(layer "F.Cu")
		(net "FM_JTAG_BMC_R_OE")
	)
	(segment
		(start 201.44105 -128.778)
		(end 201.983848 -129.320798)
		(width 0.10668)
		(layer "F.Cu")
		(net "FM_JTAG_BMC_R_OE")
	)
	(segment
		(start 422.148 -56.15305)
		(end 422.148 -57.02935)
		(width 0.10668)
		(layer "F.Cu")
		(net "FM_JTAG_BMC_R_OE")
	)
	(segment
		(start 422.129712 -57.047638)
		(end 421.492426 -57.047638)
		(width 0.10668)
		(layer "F.Cu")
		(net "FM_JTAG_BMC_R_OE")
	)
	(via
		(at 421.492426 -57.047638)
		(size 0.508)
		(drill 0.254)
		(layers "F.Cu" "B.Cu")
		(net "FM_JTAG_BMC_R_OE")
	)
	(via
		(at 252.86462 -127.008636)
		(size 0.508)
		(drill 0.254)
		(layers "F.Cu" "B.Cu")
		(net "FM_JTAG_BMC_R_OE")
	)
	(via
		(at 203.0603 -129.997454)
		(size 0.508)
		(drill 0.254)
		(layers "F.Cu" "B.Cu")
		(net "FM_JTAG_BMC_R_OE")
	)
	(via
		(at 249.178826 -88.744298)
		(size 0.508)
		(drill 0.254)
		(layers "F.Cu" "B.Cu")
		(net "FM_JTAG_BMC_R_OE")
	)
	(segment
		(start 308.155848 -59.122818)
		(end 309.171086 -58.10758)
		(width 0.11684)
		(layer "In6.Cu")
		(net "FM_JTAG_BMC_R_OE")
	)
	(segment
		(start 281.81808 -75.466702)
		(end 281.81808 -66.360548)
		(width 0.11684)
		(layer "In6.Cu")
		(net "FM_JTAG_BMC_R_OE")
	)
	(segment
		(start 289.05581 -59.122818)
		(end 308.155848 -59.122818)
		(width 0.11684)
		(layer "In6.Cu")
		(net "FM_JTAG_BMC_R_OE")
	)
	(segment
		(start 419.349936 -54.905148)
		(end 421.492426 -57.047638)
		(width 0.11684)
		(layer "In6.Cu")
		(net "FM_JTAG_BMC_R_OE")
	)
	(segment
		(start 249.178826 -88.744298)
		(end 249.178826 -88.373712)
		(width 0.11684)
		(layer "In6.Cu")
		(net "FM_JTAG_BMC_R_OE")
	)
	(segment
		(start 390.779 -54.905148)
		(end 419.349936 -54.905148)
		(width 0.11684)
		(layer "In6.Cu")
		(net "FM_JTAG_BMC_R_OE")
	)
	(segment
		(start 272.28927 -84.995512)
		(end 281.81808 -75.466702)
		(width 0.11684)
		(layer "In6.Cu")
		(net "FM_JTAG_BMC_R_OE")
	)
	(segment
		(start 249.178826 -88.373712)
		(end 252.557026 -84.995512)
		(width 0.11684)
		(layer "In6.Cu")
		(net "FM_JTAG_BMC_R_OE")
	)
	(segment
		(start 309.171086 -58.10758)
		(end 387.576568 -58.10758)
		(width 0.11684)
		(layer "In6.Cu")
		(net "FM_JTAG_BMC_R_OE")
	)
	(segment
		(start 252.557026 -84.995512)
		(end 272.28927 -84.995512)
		(width 0.11684)
		(layer "In6.Cu")
		(net "FM_JTAG_BMC_R_OE")
	)
	(segment
		(start 387.576568 -58.10758)
		(end 390.779 -54.905148)
		(width 0.11684)
		(layer "In6.Cu")
		(net "FM_JTAG_BMC_R_OE")
	)
	(segment
		(start 281.81808 -66.360548)
		(end 289.05581 -59.122818)
		(width 0.11684)
		(layer "In6.Cu")
		(net "FM_JTAG_BMC_R_OE")
	)
	(segment
		(start 248.266712 -88.744298)
		(end 247.804178 -89.206832)
		(width 0.11684)
		(layer "In11.Cu")
		(net "FM_JTAG_BMC_R_OE")
	)
	(segment
		(start 246.623078 -108.014262)
		(end 247.863868 -109.255052)
		(width 0.11684)
		(layer "In11.Cu")
		(net "FM_JTAG_BMC_R_OE")
	)
	(segment
		(start 247.804178 -89.206832)
		(end 247.804178 -90.273886)
		(width 0.11684)
		(layer "In11.Cu")
		(net "FM_JTAG_BMC_R_OE")
	)
	(segment
		(start 246.623078 -91.454986)
		(end 246.623078 -108.014262)
		(width 0.11684)
		(layer "In11.Cu")
		(net "FM_JTAG_BMC_R_OE")
	)
	(segment
		(start 249.178826 -88.744298)
		(end 248.266712 -88.744298)
		(width 0.11684)
		(layer "In11.Cu")
		(net "FM_JTAG_BMC_R_OE")
	)
	(segment
		(start 247.863868 -126.499366)
		(end 248.912126 -127.547624)
		(width 0.11684)
		(layer "In11.Cu")
		(net "FM_JTAG_BMC_R_OE")
	)
	(segment
		(start 248.912126 -127.547624)
		(end 252.325632 -127.547624)
		(width 0.11684)
		(layer "In11.Cu")
		(net "FM_JTAG_BMC_R_OE")
	)
	(segment
		(start 252.325632 -127.547624)
		(end 252.86462 -127.008636)
		(width 0.11684)
		(layer "In11.Cu")
		(net "FM_JTAG_BMC_R_OE")
	)
	(segment
		(start 247.804178 -90.273886)
		(end 246.623078 -91.454986)
		(width 0.11684)
		(layer "In11.Cu")
		(net "FM_JTAG_BMC_R_OE")
	)
	(segment
		(start 247.863868 -109.255052)
		(end 247.863868 -126.499366)
		(width 0.11684)
		(layer "In11.Cu")
		(net "FM_JTAG_BMC_R_OE")
	)
	(segment
		(start 239.367568 -131.574032)
		(end 218.378786 -131.574032)
		(width 0.11684)
		(layer "In15.Cu")
		(net "FM_JTAG_BMC_R_OE")
	)
	(segment
		(start 212.720936 -132.033264)
		(end 208.909158 -132.033264)
		(width 0.11684)
		(layer "In15.Cu")
		(net "FM_JTAG_BMC_R_OE")
	)
	(segment
		(start 248.56948 -128.729994)
		(end 247.788938 -129.510536)
		(width 0.11684)
		(layer "In15.Cu")
		(net "FM_JTAG_BMC_R_OE")
	)
	(segment
		(start 208.909158 -132.033264)
		(end 206.873348 -129.997454)
		(width 0.11684)
		(layer "In15.Cu")
		(net "FM_JTAG_BMC_R_OE")
	)
	(segment
		(start 252.86462 -127.008636)
		(end 251.143262 -128.729994)
		(width 0.11684)
		(layer "In15.Cu")
		(net "FM_JTAG_BMC_R_OE")
	)
	(segment
		(start 251.143262 -128.729994)
		(end 248.56948 -128.729994)
		(width 0.11684)
		(layer "In15.Cu")
		(net "FM_JTAG_BMC_R_OE")
	)
	(segment
		(start 213.943946 -130.810254)
		(end 212.720936 -132.033264)
		(width 0.11684)
		(layer "In15.Cu")
		(net "FM_JTAG_BMC_R_OE")
	)
	(segment
		(start 218.378786 -131.574032)
		(end 217.615008 -130.810254)
		(width 0.11684)
		(layer "In15.Cu")
		(net "FM_JTAG_BMC_R_OE")
	)
	(segment
		(start 206.873348 -129.997454)
		(end 203.0603 -129.997454)
		(width 0.11684)
		(layer "In15.Cu")
		(net "FM_JTAG_BMC_R_OE")
	)
	(segment
		(start 247.788938 -129.510536)
		(end 241.431064 -129.510536)
		(width 0.11684)
		(layer "In15.Cu")
		(net "FM_JTAG_BMC_R_OE")
	)
	(segment
		(start 241.431064 -129.510536)
		(end 239.367568 -131.574032)
		(width 0.11684)
		(layer "In15.Cu")
		(net "FM_JTAG_BMC_R_OE")
	)
	(segment
		(start 217.615008 -130.810254)
		(end 213.943946 -130.810254)
		(width 0.11684)
		(layer "In15.Cu")
		(net "FM_JTAG_BMC_R_OE")
	)
	(segment
		(start 186.722004 -119.452898)
		(end 187.111894 -119.842788)
		(width 0.10668)
		(layer "F.Cu")
		(net "FM_ESPI_CPU0_ALERT_SEL")
	)
	(segment
		(start 186.055 -137.26795)
		(end 186.58078 -136.74217)
		(width 0.10668)
		(layer "F.Cu")
		(net "FM_ESPI_CPU0_ALERT_SEL")
	)
	(segment
		(start 186.58078 -135.089646)
		(end 187.108338 -134.562088)
		(width 0.10668)
		(layer "F.Cu")
		(net "FM_ESPI_CPU0_ALERT_SEL")
	)
	(segment
		(start 186.58078 -136.74217)
		(end 186.58078 -135.089646)
		(width 0.10668)
		(layer "F.Cu")
		(net "FM_ESPI_CPU0_ALERT_SEL")
	)
	(via
		(at 187.111894 -119.842788)
		(size 0.4572)
		(drill 0.254)
		(layers "F.Cu" "B.Cu")
		(net "FM_ESPI_CPU0_ALERT_SEL")
	)
	(via
		(at 187.108338 -134.562088)
		(size 0.508)
		(drill 0.254)
		(layers "F.Cu" "B.Cu")
		(net "FM_ESPI_CPU0_ALERT_SEL")
	)
	(segment
		(start 187.430664 -129.878328)
		(end 187.430664 -130.720084)
		(width 0.11684)
		(layer "In4.Cu")
		(net "FM_ESPI_CPU0_ALERT_SEL")
	)
	(segment
		(start 187.111894 -119.842788)
		(end 187.518802 -120.249696)
		(width 0.11684)
		(layer "In4.Cu")
		(net "FM_ESPI_CPU0_ALERT_SEL")
	)
	(segment
		(start 188.42863 -133.241796)
		(end 187.108338 -134.562088)
		(width 0.11684)
		(layer "In4.Cu")
		(net "FM_ESPI_CPU0_ALERT_SEL")
	)
	(segment
		(start 188.266578 -125.421136)
		(end 188.266578 -129.042414)
		(width 0.11684)
		(layer "In4.Cu")
		(net "FM_ESPI_CPU0_ALERT_SEL")
	)
	(segment
		(start 187.518802 -120.249696)
		(end 187.518802 -124.67336)
		(width 0.11684)
		(layer "In4.Cu")
		(net "FM_ESPI_CPU0_ALERT_SEL")
	)
	(segment
		(start 188.42863 -131.71805)
		(end 188.42863 -133.241796)
		(width 0.11684)
		(layer "In4.Cu")
		(net "FM_ESPI_CPU0_ALERT_SEL")
	)
	(segment
		(start 187.430664 -130.720084)
		(end 188.42863 -131.71805)
		(width 0.11684)
		(layer "In4.Cu")
		(net "FM_ESPI_CPU0_ALERT_SEL")
	)
	(segment
		(start 188.266578 -129.042414)
		(end 187.430664 -129.878328)
		(width 0.11684)
		(layer "In4.Cu")
		(net "FM_ESPI_CPU0_ALERT_SEL")
	)
	(segment
		(start 187.518802 -124.67336)
		(end 188.266578 -125.421136)
		(width 0.11684)
		(layer "In4.Cu")
		(net "FM_ESPI_CPU0_ALERT_SEL")
	)
	(segment
		(start 186.055 -138.06805)
		(end 186.394344 -138.06805)
		(width 0.10668)
		(layer "F.Cu")
		(net "FM_ESPI_CPU0_ALERT_R_SEL")
	)
	(segment
		(start 186.62142 -139.236196)
		(end 185.093356 -140.76426)
		(width 0.10668)
		(layer "F.Cu")
		(net "FM_ESPI_CPU0_ALERT_R_SEL")
	)
	(segment
		(start 186.394344 -138.06805)
		(end 186.62142 -138.295126)
		(width 0.10668)
		(layer "F.Cu")
		(net "FM_ESPI_CPU0_ALERT_R_SEL")
	)
	(segment
		(start 186.62142 -138.295126)
		(end 186.62142 -139.236196)
		(width 0.10668)
		(layer "F.Cu")
		(net "FM_ESPI_CPU0_ALERT_R_SEL")
	)
	(via
		(at 185.093356 -140.76426)
		(size 0.508)
		(drill 0.254)
		(layers "F.Cu" "B.Cu")
		(net "FM_ESPI_CPU0_ALERT_R_SEL")
	)
	(segment
		(start 186.424824 -142.406878)
		(end 187.458858 -142.406878)
		(width 0.10668)
		(layer "B.Cu")
		(net "FM_ESPI_CPU0_ALERT_R_SEL")
	)
	(segment
		(start 186.878214 -143.256)
		(end 186.3852 -143.749014)
		(width 0.10668)
		(layer "B.Cu")
		(net "FM_ESPI_CPU0_ALERT_R_SEL")
	)
	(segment
		(start 185.093356 -140.76426)
		(end 185.093356 -141.07541)
		(width 0.10668)
		(layer "B.Cu")
		(net "FM_ESPI_CPU0_ALERT_R_SEL")
	)
	(segment
		(start 186.3852 -143.749014)
		(end 185.73496 -143.749014)
		(width 0.10668)
		(layer "B.Cu")
		(net "FM_ESPI_CPU0_ALERT_R_SEL")
	)
	(segment
		(start 187.68695 -142.63497)
		(end 187.68695 -143.256)
		(width 0.10668)
		(layer "B.Cu")
		(net "FM_ESPI_CPU0_ALERT_R_SEL")
	)
	(segment
		(start 185.093356 -141.07541)
		(end 186.424824 -142.406878)
		(width 0.10668)
		(layer "B.Cu")
		(net "FM_ESPI_CPU0_ALERT_R_SEL")
	)
	(segment
		(start 187.458858 -142.406878)
		(end 187.68695 -142.63497)
		(width 0.10668)
		(layer "B.Cu")
		(net "FM_ESPI_CPU0_ALERT_R_SEL")
	)
	(segment
		(start 187.68695 -143.256)
		(end 186.878214 -143.256)
		(width 0.10668)
		(layer "B.Cu")
		(net "FM_ESPI_CPU0_ALERT_R_SEL")
	)
	(segment
		(start 222.84563 -197.05193)
		(end 222.84563 -170.542458)
		(width 0.10668)
		(layer "F.Cu")
		(net "FM_AC_PWR_BTN_R_N")
	)
	(segment
		(start 217.535506 -370.029994)
		(end 221.090744 -366.474756)
		(width 0.10668)
		(layer "F.Cu")
		(net "FM_AC_PWR_BTN_R_N")
	)
	(segment
		(start 220.150944 -206.059024)
		(end 220.725746 -205.484222)
		(width 0.10668)
		(layer "F.Cu")
		(net "FM_AC_PWR_BTN_R_N")
	)
	(segment
		(start 222.536004 -334.13446)
		(end 222.536004 -329.172062)
		(width 0.10668)
		(layer "F.Cu")
		(net "FM_AC_PWR_BTN_R_N")
	)
	(segment
		(start 146.927316 -21.898356)
		(end 146.927316 -22.587204)
		(width 0.10668)
		(layer "F.Cu")
		(net "FM_AC_PWR_BTN_R_N")
	)
	(segment
		(start 218.638628 -206.059024)
		(end 220.150944 -206.059024)
		(width 0.10668)
		(layer "F.Cu")
		(net "FM_AC_PWR_BTN_R_N")
	)
	(segment
		(start 220.725746 -201.782934)
		(end 221.848172 -200.660508)
		(width 0.10668)
		(layer "F.Cu")
		(net "FM_AC_PWR_BTN_R_N")
	)
	(segment
		(start 178.536854 -366.1029)
		(end 180.984398 -368.550444)
		(width 0.10668)
		(layer "F.Cu")
		(net "FM_AC_PWR_BTN_R_N")
	)
	(segment
		(start 194.026536 -418.85489)
		(end 193.759074 -418.587428)
		(width 0.10668)
		(layer "F.Cu")
		(net "FM_AC_PWR_BTN_R_N")
	)
	(segment
		(start 217.537284 -165.234112)
		(end 217.537284 -163.41979)
		(width 0.10668)
		(layer "F.Cu")
		(net "FM_AC_PWR_BTN_R_N")
	)
	(segment
		(start 202.00366 -370.029994)
		(end 217.535506 -370.029994)
		(width 0.10668)
		(layer "F.Cu")
		(net "FM_AC_PWR_BTN_R_N")
	)
	(segment
		(start 221.848172 -200.660508)
		(end 221.848172 -198.049388)
		(width 0.10668)
		(layer "F.Cu")
		(net "FM_AC_PWR_BTN_R_N")
	)
	(segment
		(start 222.536004 -329.172062)
		(end 216.268554 -322.904612)
		(width 0.10668)
		(layer "F.Cu")
		(net "FM_AC_PWR_BTN_R_N")
	)
	(segment
		(start 180.984398 -368.550444)
		(end 200.52411 -368.550444)
		(width 0.10668)
		(layer "F.Cu")
		(net "FM_AC_PWR_BTN_R_N")
	)
	(segment
		(start 194.911472 -422.271698)
		(end 194.527424 -422.271698)
		(width 0.10668)
		(layer "F.Cu")
		(net "FM_AC_PWR_BTN_R_N")
	)
	(segment
		(start 200.52411 -368.550444)
		(end 202.00366 -370.029994)
		(width 0.10668)
		(layer "F.Cu")
		(net "FM_AC_PWR_BTN_R_N")
	)
	(segment
		(start 201.366628 -145.410428)
		(end 201.366628 -143.592042)
		(width 0.10668)
		(layer "F.Cu")
		(net "FM_AC_PWR_BTN_R_N")
	)
	(segment
		(start 194.527424 -422.271698)
		(end 194.026536 -421.77081)
		(width 0.10668)
		(layer "F.Cu")
		(net "FM_AC_PWR_BTN_R_N")
	)
	(segment
		(start 194.026536 -421.77081)
		(end 194.026536 -418.85489)
		(width 0.10668)
		(layer "F.Cu")
		(net "FM_AC_PWR_BTN_R_N")
	)
	(segment
		(start 193.759074 -418.587428)
		(end 188.669168 -418.587428)
		(width 0.10668)
		(layer "F.Cu")
		(net "FM_AC_PWR_BTN_R_N")
	)
	(segment
		(start 221.090744 -365.089948)
		(end 223.835214 -362.345478)
		(width 0.10668)
		(layer "F.Cu")
		(net "FM_AC_PWR_BTN_R_N")
	)
	(segment
		(start 221.090744 -366.474756)
		(end 221.090744 -365.089948)
		(width 0.10668)
		(layer "F.Cu")
		(net "FM_AC_PWR_BTN_R_N")
	)
	(segment
		(start 221.848172 -198.049388)
		(end 222.84563 -197.05193)
		(width 0.10668)
		(layer "F.Cu")
		(net "FM_AC_PWR_BTN_R_N")
	)
	(segment
		(start 176.571148 -366.1029)
		(end 178.536854 -366.1029)
		(width 0.10668)
		(layer "F.Cu")
		(net "FM_AC_PWR_BTN_R_N")
	)
	(segment
		(start 223.835214 -335.43367)
		(end 222.536004 -334.13446)
		(width 0.10668)
		(layer "F.Cu")
		(net "FM_AC_PWR_BTN_R_N")
	)
	(segment
		(start 216.268554 -208.429098)
		(end 218.638628 -206.059024)
		(width 0.10668)
		(layer "F.Cu")
		(net "FM_AC_PWR_BTN_R_N")
	)
	(segment
		(start 206.035402 -150.079202)
		(end 201.366628 -145.410428)
		(width 0.10668)
		(layer "F.Cu")
		(net "FM_AC_PWR_BTN_R_N")
	)
	(segment
		(start 223.835214 -362.345478)
		(end 223.835214 -335.43367)
		(width 0.10668)
		(layer "F.Cu")
		(net "FM_AC_PWR_BTN_R_N")
	)
	(segment
		(start 222.84563 -170.542458)
		(end 217.537284 -165.234112)
		(width 0.10668)
		(layer "F.Cu")
		(net "FM_AC_PWR_BTN_R_N")
	)
	(segment
		(start 220.725746 -205.484222)
		(end 220.725746 -201.782934)
		(width 0.10668)
		(layer "F.Cu")
		(net "FM_AC_PWR_BTN_R_N")
	)
	(segment
		(start 216.268554 -322.904612)
		(end 216.268554 -208.429098)
		(width 0.10668)
		(layer "F.Cu")
		(net "FM_AC_PWR_BTN_R_N")
	)
	(segment
		(start 217.537284 -163.41979)
		(end 206.035402 -151.917908)
		(width 0.10668)
		(layer "F.Cu")
		(net "FM_AC_PWR_BTN_R_N")
	)
	(segment
		(start 206.035402 -151.917908)
		(end 206.035402 -150.079202)
		(width 0.10668)
		(layer "F.Cu")
		(net "FM_AC_PWR_BTN_R_N")
	)
	(via
		(at 188.860938 -37.516562)
		(size 0.508)
		(drill 0.254)
		(layers "F.Cu" "B.Cu")
		(net "FM_AC_PWR_BTN_R_N")
	)
	(via
		(at 146.927316 -22.587204)
		(size 0.508)
		(drill 0.254)
		(layers "F.Cu" "B.Cu")
		(net "FM_AC_PWR_BTN_R_N")
	)
	(via
		(at 162.339528 -399.574258)
		(size 0.508)
		(drill 0.254)
		(layers "F.Cu" "B.Cu")
		(net "FM_AC_PWR_BTN_R_N")
	)
	(via
		(at 188.669168 -418.587428)
		(size 0.508)
		(drill 0.254)
		(layers "F.Cu" "B.Cu")
		(net "FM_AC_PWR_BTN_R_N")
	)
	(via
		(at 165.291262 -410.441648)
		(size 0.508)
		(drill 0.254)
		(layers "F.Cu" "B.Cu")
		(net "FM_AC_PWR_BTN_R_N")
	)
	(via
		(at 176.571148 -366.1029)
		(size 0.508)
		(drill 0.254)
		(layers "F.Cu" "B.Cu")
		(net "FM_AC_PWR_BTN_R_N")
	)
	(via
		(at 201.366628 -143.592042)
		(size 0.508)
		(drill 0.254)
		(layers "F.Cu" "B.Cu")
		(net "FM_AC_PWR_BTN_R_N")
	)
	(segment
		(start 200.8251 -144.67205)
		(end 201.366628 -144.130522)
		(width 0.10668)
		(layer "B.Cu")
		(net "FM_AC_PWR_BTN_R_N")
	)
	(segment
		(start 200.406 -144.67205)
		(end 199.39 -144.67205)
		(width 0.10668)
		(layer "B.Cu")
		(net "FM_AC_PWR_BTN_R_N")
	)
	(segment
		(start 200.406 -144.67205)
		(end 200.8251 -144.67205)
		(width 0.10668)
		(layer "B.Cu")
		(net "FM_AC_PWR_BTN_R_N")
	)
	(segment
		(start 201.366628 -144.130522)
		(end 201.366628 -143.592042)
		(width 0.10668)
		(layer "B.Cu")
		(net "FM_AC_PWR_BTN_R_N")
	)
	(segment
		(start 199.39 -144.67205)
		(end 198.374 -144.67205)
		(width 0.10668)
		(layer "B.Cu")
		(net "FM_AC_PWR_BTN_R_N")
	)
	(segment
		(start 175.542448 -417.616894)
		(end 177.452528 -417.616894)
		(width 0.11684)
		(layer "In4.Cu")
		(net "FM_AC_PWR_BTN_R_N")
	)
	(segment
		(start 174.867316 -416.941762)
		(end 175.542448 -417.616894)
		(width 0.11684)
		(layer "In4.Cu")
		(net "FM_AC_PWR_BTN_R_N")
	)
	(segment
		(start 165.968172 -410.441648)
		(end 168.475152 -412.948628)
		(width 0.11684)
		(layer "In4.Cu")
		(net "FM_AC_PWR_BTN_R_N")
	)
	(segment
		(start 183.514492 -418.220398)
		(end 184.204102 -417.530788)
		(width 0.11684)
		(layer "In4.Cu")
		(net "FM_AC_PWR_BTN_R_N")
	)
	(segment
		(start 177.452528 -417.616894)
		(end 178.056032 -418.220398)
		(width 0.11684)
		(layer "In4.Cu")
		(net "FM_AC_PWR_BTN_R_N")
	)
	(segment
		(start 173.732444 -417.473384)
		(end 174.264066 -416.941762)
		(width 0.11684)
		(layer "In4.Cu")
		(net "FM_AC_PWR_BTN_R_N")
	)
	(segment
		(start 171.290742 -415.56305)
		(end 173.201076 -417.473384)
		(width 0.11684)
		(layer "In4.Cu")
		(net "FM_AC_PWR_BTN_R_N")
	)
	(segment
		(start 187.612528 -417.530788)
		(end 188.669168 -418.587428)
		(width 0.11684)
		(layer "In4.Cu")
		(net "FM_AC_PWR_BTN_R_N")
	)
	(segment
		(start 168.475152 -413.236156)
		(end 170.802046 -415.56305)
		(width 0.11684)
		(layer "In4.Cu")
		(net "FM_AC_PWR_BTN_R_N")
	)
	(segment
		(start 174.264066 -416.941762)
		(end 174.867316 -416.941762)
		(width 0.11684)
		(layer "In4.Cu")
		(net "FM_AC_PWR_BTN_R_N")
	)
	(segment
		(start 168.475152 -412.948628)
		(end 168.475152 -413.236156)
		(width 0.11684)
		(layer "In4.Cu")
		(net "FM_AC_PWR_BTN_R_N")
	)
	(segment
		(start 173.201076 -417.473384)
		(end 173.732444 -417.473384)
		(width 0.11684)
		(layer "In4.Cu")
		(net "FM_AC_PWR_BTN_R_N")
	)
	(segment
		(start 184.204102 -417.530788)
		(end 187.612528 -417.530788)
		(width 0.11684)
		(layer "In4.Cu")
		(net "FM_AC_PWR_BTN_R_N")
	)
	(segment
		(start 165.291262 -410.441648)
		(end 165.968172 -410.441648)
		(width 0.11684)
		(layer "In4.Cu")
		(net "FM_AC_PWR_BTN_R_N")
	)
	(segment
		(start 170.802046 -415.56305)
		(end 171.290742 -415.56305)
		(width 0.11684)
		(layer "In4.Cu")
		(net "FM_AC_PWR_BTN_R_N")
	)
	(segment
		(start 178.056032 -418.220398)
		(end 183.514492 -418.220398)
		(width 0.11684)
		(layer "In4.Cu")
		(net "FM_AC_PWR_BTN_R_N")
	)
	(segment
		(start 163.382198 -398.869916)
		(end 162.677856 -399.574258)
		(width 0.11684)
		(layer "In6.Cu")
		(net "FM_AC_PWR_BTN_R_N")
	)
	(segment
		(start 179.10683 -371.114066)
		(end 178.729132 -371.491764)
		(width 0.11684)
		(layer "In6.Cu")
		(net "FM_AC_PWR_BTN_R_N")
	)
	(segment
		(start 172.578776 -381.09906)
		(end 170.082718 -383.595118)
		(width 0.11684)
		(layer "In6.Cu")
		(net "FM_AC_PWR_BTN_R_N")
	)
	(segment
		(start 176.571148 -366.1029)
		(end 176.571148 -367.034572)
		(width 0.11684)
		(layer "In6.Cu")
		(net "FM_AC_PWR_BTN_R_N")
	)
	(segment
		(start 176.28235 -371.491764)
		(end 172.578776 -375.195338)
		(width 0.11684)
		(layer "In6.Cu")
		(net "FM_AC_PWR_BTN_R_N")
	)
	(segment
		(start 172.578776 -375.195338)
		(end 172.578776 -381.09906)
		(width 0.11684)
		(layer "In6.Cu")
		(net "FM_AC_PWR_BTN_R_N")
	)
	(segment
		(start 178.729132 -371.491764)
		(end 176.28235 -371.491764)
		(width 0.11684)
		(layer "In6.Cu")
		(net "FM_AC_PWR_BTN_R_N")
	)
	(segment
		(start 168.473374 -394.433806)
		(end 166.748968 -394.433806)
		(width 0.11684)
		(layer "In6.Cu")
		(net "FM_AC_PWR_BTN_R_N")
	)
	(segment
		(start 163.382198 -397.800576)
		(end 163.382198 -398.869916)
		(width 0.11684)
		(layer "In6.Cu")
		(net "FM_AC_PWR_BTN_R_N")
	)
	(segment
		(start 166.748968 -394.433806)
		(end 163.382198 -397.800576)
		(width 0.11684)
		(layer "In6.Cu")
		(net "FM_AC_PWR_BTN_R_N")
	)
	(segment
		(start 179.10683 -369.570254)
		(end 179.10683 -371.114066)
		(width 0.11684)
		(layer "In6.Cu")
		(net "FM_AC_PWR_BTN_R_N")
	)
	(segment
		(start 170.082718 -392.824462)
		(end 168.473374 -394.433806)
		(width 0.11684)
		(layer "In6.Cu")
		(net "FM_AC_PWR_BTN_R_N")
	)
	(segment
		(start 176.571148 -367.034572)
		(end 179.10683 -369.570254)
		(width 0.11684)
		(layer "In6.Cu")
		(net "FM_AC_PWR_BTN_R_N")
	)
	(segment
		(start 170.082718 -383.595118)
		(end 170.082718 -392.824462)
		(width 0.11684)
		(layer "In6.Cu")
		(net "FM_AC_PWR_BTN_R_N")
	)
	(segment
		(start 162.677856 -399.574258)
		(end 162.339528 -399.574258)
		(width 0.11684)
		(layer "In6.Cu")
		(net "FM_AC_PWR_BTN_R_N")
	)
	(segment
		(start 201.00036 -91.603322)
		(end 202.195176 -92.686124)
		(width 0.11684)
		(layer "In11.Cu")
		(net "FM_AC_PWR_BTN_R_N")
	)
	(segment
		(start 207.513682 -113.298986)
		(end 206.729076 -113.298986)
		(width 0.11684)
		(layer "In11.Cu")
		(net "FM_AC_PWR_BTN_R_N")
	)
	(segment
		(start 202.26782 -143.326104)
		(end 202.001882 -143.592042)
		(width 0.11684)
		(layer "In11.Cu")
		(net "FM_AC_PWR_BTN_R_N")
	)
	(segment
		(start 162.340036 -399.574766)
		(end 162.339528 -399.574258)
		(width 0.11684)
		(layer "In11.Cu")
		(net "FM_AC_PWR_BTN_R_N")
	)
	(segment
		(start 202.001882 -143.592042)
		(end 201.366628 -143.592042)
		(width 0.11684)
		(layer "In11.Cu")
		(net "FM_AC_PWR_BTN_R_N")
	)
	(segment
		(start 164.983414 -410.1338)
		(end 164.983414 -404.106634)
		(width 0.11684)
		(layer "In11.Cu")
		(net "FM_AC_PWR_BTN_R_N")
	)
	(segment
		(start 202.26782 -139.568936)
		(end 202.26782 -143.326104)
		(width 0.11684)
		(layer "In11.Cu")
		(net "FM_AC_PWR_BTN_R_N")
	)
	(segment
		(start 206.299308 -130.27406)
		(end 206.299308 -135.537448)
		(width 0.11684)
		(layer "In11.Cu")
		(net "FM_AC_PWR_BTN_R_N")
	)
	(segment
		(start 188.839856 -73.475088)
		(end 190.550292 -76.673202)
		(width 0.11684)
		(layer "In11.Cu")
		(net "FM_AC_PWR_BTN_R_N")
	)
	(segment
		(start 196.694552 -87.097616)
		(end 200.08596 -90.489024)
		(width 0.11684)
		(layer "In11.Cu")
		(net "FM_AC_PWR_BTN_R_N")
	)
	(segment
		(start 205.269338 -97.230946)
		(end 205.269338 -101.65715)
		(width 0.11684)
		(layer "In11.Cu")
		(net "FM_AC_PWR_BTN_R_N")
	)
	(segment
		(start 204.703426 -95.194374)
		(end 204.703426 -96.665034)
		(width 0.11684)
		(layer "In11.Cu")
		(net "FM_AC_PWR_BTN_R_N")
	)
	(segment
		(start 164.983414 -404.106634)
		(end 162.340036 -401.463256)
		(width 0.11684)
		(layer "In11.Cu")
		(net "FM_AC_PWR_BTN_R_N")
	)
	(segment
		(start 200.08596 -90.489024)
		(end 201.00036 -91.603322)
		(width 0.11684)
		(layer "In11.Cu")
		(net "FM_AC_PWR_BTN_R_N")
	)
	(segment
		(start 196.694552 -84.515452)
		(end 196.694552 -87.097616)
		(width 0.11684)
		(layer "In11.Cu")
		(net "FM_AC_PWR_BTN_R_N")
	)
	(segment
		(start 191.014096 -43.961812)
		(end 188.839856 -46.136052)
		(width 0.11684)
		(layer "In11.Cu")
		(net "FM_AC_PWR_BTN_R_N")
	)
	(segment
		(start 204.703426 -96.665034)
		(end 205.269338 -97.230946)
		(width 0.11684)
		(layer "In11.Cu")
		(net "FM_AC_PWR_BTN_R_N")
	)
	(segment
		(start 205.726538 -102.512368)
		(end 208.44129 -105.22712)
		(width 0.11684)
		(layer "In11.Cu")
		(net "FM_AC_PWR_BTN_R_N")
	)
	(segment
		(start 188.860938 -37.516562)
		(end 191.014096 -39.66972)
		(width 0.11684)
		(layer "In11.Cu")
		(net "FM_AC_PWR_BTN_R_N")
	)
	(segment
		(start 195.787772 -81.910682)
		(end 195.787772 -83.608672)
		(width 0.11684)
		(layer "In11.Cu")
		(net "FM_AC_PWR_BTN_R_N")
	)
	(segment
		(start 206.729076 -113.298986)
		(end 205.674214 -114.353848)
		(width 0.11684)
		(layer "In11.Cu")
		(net "FM_AC_PWR_BTN_R_N")
	)
	(segment
		(start 205.695296 -129.670048)
		(end 206.299308 -130.27406)
		(width 0.11684)
		(layer "In11.Cu")
		(net "FM_AC_PWR_BTN_R_N")
	)
	(segment
		(start 195.787772 -83.608672)
		(end 196.694552 -84.515452)
		(width 0.11684)
		(layer "In11.Cu")
		(net "FM_AC_PWR_BTN_R_N")
	)
	(segment
		(start 208.44129 -105.22712)
		(end 208.44129 -112.371378)
		(width 0.11684)
		(layer "In11.Cu")
		(net "FM_AC_PWR_BTN_R_N")
	)
	(segment
		(start 205.674214 -115.929664)
		(end 205.695296 -115.950746)
		(width 0.11684)
		(layer "In11.Cu")
		(net "FM_AC_PWR_BTN_R_N")
	)
	(segment
		(start 205.674214 -114.353848)
		(end 205.674214 -115.929664)
		(width 0.11684)
		(layer "In11.Cu")
		(net "FM_AC_PWR_BTN_R_N")
	)
	(segment
		(start 165.291262 -410.441648)
		(end 164.983414 -410.1338)
		(width 0.11684)
		(layer "In11.Cu")
		(net "FM_AC_PWR_BTN_R_N")
	)
	(segment
		(start 208.44129 -112.371378)
		(end 207.513682 -113.298986)
		(width 0.11684)
		(layer "In11.Cu")
		(net "FM_AC_PWR_BTN_R_N")
	)
	(segment
		(start 191.014096 -39.66972)
		(end 191.014096 -43.961812)
		(width 0.11684)
		(layer "In11.Cu")
		(net "FM_AC_PWR_BTN_R_N")
	)
	(segment
		(start 202.195176 -92.686124)
		(end 204.703426 -95.194374)
		(width 0.11684)
		(layer "In11.Cu")
		(net "FM_AC_PWR_BTN_R_N")
	)
	(segment
		(start 190.550292 -76.673202)
		(end 195.787772 -81.910682)
		(width 0.11684)
		(layer "In11.Cu")
		(net "FM_AC_PWR_BTN_R_N")
	)
	(segment
		(start 188.839856 -46.136052)
		(end 188.839856 -73.475088)
		(width 0.11684)
		(layer "In11.Cu")
		(net "FM_AC_PWR_BTN_R_N")
	)
	(segment
		(start 162.340036 -401.463256)
		(end 162.340036 -399.574766)
		(width 0.11684)
		(layer "In11.Cu")
		(net "FM_AC_PWR_BTN_R_N")
	)
	(segment
		(start 206.299308 -135.537448)
		(end 202.26782 -139.568936)
		(width 0.11684)
		(layer "In11.Cu")
		(net "FM_AC_PWR_BTN_R_N")
	)
	(segment
		(start 205.269338 -101.65715)
		(end 205.726538 -102.512368)
		(width 0.11684)
		(layer "In11.Cu")
		(net "FM_AC_PWR_BTN_R_N")
	)
	(segment
		(start 205.695296 -115.950746)
		(end 205.695296 -129.670048)
		(width 0.11684)
		(layer "In11.Cu")
		(net "FM_AC_PWR_BTN_R_N")
	)
	(segment
		(start 174.087028 -32.445452)
		(end 173.180502 -31.538926)
		(width 0.11684)
		(layer "In15.Cu")
		(net "FM_AC_PWR_BTN_R_N")
	)
	(segment
		(start 185.829702 -36.935918)
		(end 179.937664 -36.935918)
		(width 0.11684)
		(layer "In15.Cu")
		(net "FM_AC_PWR_BTN_R_N")
	)
	(segment
		(start 173.180502 -31.538926)
		(end 173.180502 -29.584142)
		(width 0.11684)
		(layer "In15.Cu")
		(net "FM_AC_PWR_BTN_R_N")
	)
	(segment
		(start 156.97581 -19.980656)
		(end 148.080222 -19.980656)
		(width 0.11684)
		(layer "In15.Cu")
		(net "FM_AC_PWR_BTN_R_N")
	)
	(segment
		(start 163.519866 -26.524712)
		(end 156.97581 -19.980656)
		(width 0.11684)
		(layer "In15.Cu")
		(net "FM_AC_PWR_BTN_R_N")
	)
	(segment
		(start 146.927316 -21.133562)
		(end 146.927316 -22.587204)
		(width 0.11684)
		(layer "In15.Cu")
		(net "FM_AC_PWR_BTN_R_N")
	)
	(segment
		(start 179.937664 -36.935918)
		(end 175.447198 -32.445452)
		(width 0.11684)
		(layer "In15.Cu")
		(net "FM_AC_PWR_BTN_R_N")
	)
	(segment
		(start 173.180502 -29.584142)
		(end 170.121072 -26.524712)
		(width 0.11684)
		(layer "In15.Cu")
		(net "FM_AC_PWR_BTN_R_N")
	)
	(segment
		(start 170.121072 -26.524712)
		(end 163.519866 -26.524712)
		(width 0.11684)
		(layer "In15.Cu")
		(net "FM_AC_PWR_BTN_R_N")
	)
	(segment
		(start 186.410346 -37.516562)
		(end 185.829702 -36.935918)
		(width 0.11684)
		(layer "In15.Cu")
		(net "FM_AC_PWR_BTN_R_N")
	)
	(segment
		(start 148.080222 -19.980656)
		(end 146.927316 -21.133562)
		(width 0.11684)
		(layer "In15.Cu")
		(net "FM_AC_PWR_BTN_R_N")
	)
	(segment
		(start 175.447198 -32.445452)
		(end 174.087028 -32.445452)
		(width 0.11684)
		(layer "In15.Cu")
		(net "FM_AC_PWR_BTN_R_N")
	)
	(segment
		(start 188.860938 -37.516562)
		(end 186.410346 -37.516562)
		(width 0.11684)
		(layer "In15.Cu")
		(net "FM_AC_PWR_BTN_R_N")
	)
	(via
		(at 200.391014 -142.733014)
		(size 0.6604)
		(drill 0.3302)
		(layers "F.Cu" "B.Cu")
		(net "FM_AC_PWR_BTN_PLD_N")
	)
	(segment
		(start 200.391014 -141.41196)
		(end 200.391014 -142.733014)
		(width 0.10668)
		(layer "B.Cu")
		(net "FM_AC_PWR_BTN_PLD_N")
	)
	(segment
		(start 200.406 -142.748)
		(end 200.391014 -142.733014)
		(width 0.10668)
		(layer "B.Cu")
		(net "FM_AC_PWR_BTN_PLD_N")
	)
	(segment
		(start 200.406 -143.87195)
		(end 200.406 -142.748)
		(width 0.10668)
		(layer "B.Cu")
		(net "FM_AC_PWR_BTN_PLD_N")
	)
	(via
		(at 199.517 -138.176)
		(size 0.6604)
		(drill 0.3302)
		(layers "F.Cu" "B.Cu")
		(net "FM_AC_PWR_BTN_PLD_ISO_R_N")
	)
	(segment
		(start 200.391014 -139.050014)
		(end 199.517 -138.176)
		(width 0.10668)
		(layer "B.Cu")
		(net "FM_AC_PWR_BTN_PLD_ISO_R_N")
	)
	(segment
		(start 200.391014 -139.51204)
		(end 200.391014 -139.050014)
		(width 0.10668)
		(layer "B.Cu")
		(net "FM_AC_PWR_BTN_PLD_ISO_R_N")
	)
	(segment
		(start 199.517 -138.176)
		(end 199.517 -137.05205)
		(width 0.10668)
		(layer "B.Cu")
		(net "FM_AC_PWR_BTN_PLD_ISO_R_N")
	)
	(segment
		(start 191.522096 -120.252744)
		(end 191.911986 -120.642634)
		(width 0.10668)
		(layer "F.Cu")
		(net "FM_AC_PWR_BTN_PLD_ISO_N")
	)
	(via
		(at 191.911986 -120.642634)
		(size 0.4572)
		(drill 0.254)
		(layers "F.Cu" "B.Cu")
		(net "FM_AC_PWR_BTN_PLD_ISO_N")
	)
	(via
		(at 198.551546 -136.25195)
		(size 0.508)
		(drill 0.254)
		(layers "F.Cu" "B.Cu")
		(net "FM_AC_PWR_BTN_PLD_ISO_N")
	)
	(segment
		(start 198.551546 -136.25195)
		(end 199.517 -136.25195)
		(width 0.10668)
		(layer "B.Cu")
		(net "FM_AC_PWR_BTN_PLD_ISO_N")
	)
	(segment
		(start 199.517 -136.25195)
		(end 199.517 -135.27405)
		(width 0.10668)
		(layer "B.Cu")
		(net "FM_AC_PWR_BTN_PLD_ISO_N")
	)
	(segment
		(start 192.310258 -122.728482)
		(end 195.317872 -125.736096)
		(width 0.11684)
		(layer "In4.Cu")
		(net "FM_AC_PWR_BTN_PLD_ISO_N")
	)
	(segment
		(start 198.551546 -130.314954)
		(end 198.551546 -136.25195)
		(width 0.11684)
		(layer "In4.Cu")
		(net "FM_AC_PWR_BTN_PLD_ISO_N")
	)
	(segment
		(start 192.310258 -121.040906)
		(end 192.310258 -122.728482)
		(width 0.11684)
		(layer "In4.Cu")
		(net "FM_AC_PWR_BTN_PLD_ISO_N")
	)
	(segment
		(start 191.911986 -120.642634)
		(end 192.310258 -121.040906)
		(width 0.11684)
		(layer "In4.Cu")
		(net "FM_AC_PWR_BTN_PLD_ISO_N")
	)
	(segment
		(start 195.317872 -125.736096)
		(end 195.317872 -127.08128)
		(width 0.11684)
		(layer "In4.Cu")
		(net "FM_AC_PWR_BTN_PLD_ISO_N")
	)
	(segment
		(start 195.317872 -127.08128)
		(end 198.551546 -130.314954)
		(width 0.11684)
		(layer "In4.Cu")
		(net "FM_AC_PWR_BTN_PLD_ISO_N")
	)
	(segment
		(start 194.914774 -424.222164)
		(end 194.911472 -424.218862)
		(width 0.10668)
		(layer "F.Cu")
		(net "FM_AC_PWR_BTN_PDB_N")
	)
	(segment
		(start 194.911472 -424.218862)
		(end 194.911472 -423.071798)
		(width 0.10668)
		(layer "F.Cu")
		(net "FM_AC_PWR_BTN_PDB_N")
	)
	(segment
		(start 195.66255 -429.994822)
		(end 195.66255 -424.96994)
		(width 0.10668)
		(layer "F.Cu")
		(net "FM_AC_PWR_BTN_PDB_N")
	)
	(segment
		(start 195.66255 -424.96994)
		(end 194.914774 -424.222164)
		(width 0.10668)
		(layer "F.Cu")
		(net "FM_AC_PWR_BTN_PDB_N")
	)
	(segment
		(start 195.258182 -430.39919)
		(end 195.66255 -429.994822)
		(width 0.10668)
		(layer "F.Cu")
		(net "FM_AC_PWR_BTN_PDB_N")
	)
	(via
		(at 195.258182 -430.39919)
		(size 0.508)
		(drill 0.254)
		(layers "F.Cu" "B.Cu")
		(net "FM_AC_PWR_BTN_PDB_N")
	)
	(segment
		(start 235.91012 -435.58206)
		(end 233.02214 -438.47004)
		(width 0.11684)
		(layer "In2.Cu")
		(net "FM_AC_PWR_BTN_PDB_N")
	)
	(segment
		(start 233.02214 -438.47004)
		(end 198.952104 -438.47004)
		(width 0.11684)
		(layer "In2.Cu")
		(net "FM_AC_PWR_BTN_PDB_N")
	)
	(segment
		(start 195.258182 -434.776118)
		(end 195.258182 -430.39919)
		(width 0.11684)
		(layer "In2.Cu")
		(net "FM_AC_PWR_BTN_PDB_N")
	)
	(segment
		(start 198.952104 -438.47004)
		(end 195.258182 -434.776118)
		(width 0.11684)
		(layer "In2.Cu")
		(net "FM_AC_PWR_BTN_PDB_N")
	)
	(segment
		(start 150.85695 -17.360646)
		(end 150.85695 -16.549878)
		(width 0.10668)
		(layer "F.Cu")
		(net "FM_AC_PWR_BTN_N")
	)
	(segment
		(start 149.421596 -18.796)
		(end 150.85695 -17.360646)
		(width 0.10668)
		(layer "F.Cu")
		(net "FM_AC_PWR_BTN_N")
	)
	(segment
		(start 148.08962 -18.796)
		(end 149.421596 -18.796)
		(width 0.10668)
		(layer "F.Cu")
		(net "FM_AC_PWR_BTN_N")
	)
	(segment
		(start 147.054316 -19.80438)
		(end 147.08124 -19.80438)
		(width 0.10668)
		(layer "F.Cu")
		(net "FM_AC_PWR_BTN_N")
	)
	(segment
		(start 146.927316 -19.93138)
		(end 147.054316 -19.80438)
		(width 0.10668)
		(layer "F.Cu")
		(net "FM_AC_PWR_BTN_N")
	)
	(segment
		(start 147.08124 -19.80438)
		(end 148.08962 -18.796)
		(width 0.10668)
		(layer "F.Cu")
		(net "FM_AC_PWR_BTN_N")
	)
	(segment
		(start 146.927316 -21.098256)
		(end 146.927316 -19.93138)
		(width 0.10668)
		(layer "F.Cu")
		(net "FM_AC_PWR_BTN_N")
	)
	(via
		(at 147.08124 -19.80438)
		(size 0.762)
		(drill 0.381)
		(layers "F.Cu" "B.Cu")
		(net "FM_AC_PWR_BTN_N")
	)
	(segment
		(start 108.839 -415.01695)
		(end 108.839 -414.147)
		(width 0.10668)
		(layer "F.Cu")
		(net "FM_9ZXL045_P1_DEV_EN")
	)
	(segment
		(start 108.839 -414.147)
		(end 108.839 -412.9532)
		(width 0.10668)
		(layer "F.Cu")
		(net "FM_9ZXL045_P1_DEV_EN")
	)
	(segment
		(start 107.996482 -412.110682)
		(end 107.996482 -412.00705)
		(width 0.10668)
		(layer "F.Cu")
		(net "FM_9ZXL045_P1_DEV_EN")
	)
	(segment
		(start 108.839 -412.9532)
		(end 107.996482 -412.110682)
		(width 0.10668)
		(layer "F.Cu")
		(net "FM_9ZXL045_P1_DEV_EN")
	)
	(via
		(at 108.839 -414.147)
		(size 0.762)
		(drill 0.381)
		(layers "F.Cu" "B.Cu")
		(net "FM_9ZXL045_P1_DEV_EN")
	)
	(segment
		(start 111.35995 -407.4668)
		(end 110.781846 -407.4668)
		(width 0.10668)
		(layer "F.Cu")
		(net "FM_9ZXL045_P1_3_OE_N")
	)
	(segment
		(start 110.18393 -408.064716)
		(end 109.86643 -408.382216)
		(width 0.10668)
		(layer "F.Cu")
		(net "FM_9ZXL045_P1_3_OE_N")
	)
	(segment
		(start 110.781846 -407.4668)
		(end 110.18393 -408.064716)
		(width 0.10668)
		(layer "F.Cu")
		(net "FM_9ZXL045_P1_3_OE_N")
	)
	(segment
		(start 109.86643 -408.382216)
		(end 108.621322 -408.382216)
		(width 0.10668)
		(layer "F.Cu")
		(net "FM_9ZXL045_P1_3_OE_N")
	)
	(via
		(at 110.18393 -408.064716)
		(size 0.762)
		(drill 0.381)
		(layers "F.Cu" "B.Cu")
		(net "FM_9ZXL045_P1_3_OE_N")
	)
	(segment
		(start 109.647228 -406.824434)
		(end 110.986316 -406.824434)
		(width 0.10668)
		(layer "F.Cu")
		(net "FM_9ZXL045_P1_2_OE_N")
	)
	(segment
		(start 107.996482 -407.115518)
		(end 108.287566 -406.824434)
		(width 0.10668)
		(layer "F.Cu")
		(net "FM_9ZXL045_P1_2_OE_N")
	)
	(segment
		(start 110.986316 -406.824434)
		(end 111.35995 -406.4508)
		(width 0.10668)
		(layer "F.Cu")
		(net "FM_9ZXL045_P1_2_OE_N")
	)
	(segment
		(start 107.996482 -407.25725)
		(end 107.996482 -407.115518)
		(width 0.10668)
		(layer "F.Cu")
		(net "FM_9ZXL045_P1_2_OE_N")
	)
	(segment
		(start 108.287566 -406.824434)
		(end 109.647228 -406.824434)
		(width 0.10668)
		(layer "F.Cu")
		(net "FM_9ZXL045_P1_2_OE_N")
	)
	(via
		(at 109.647228 -406.824434)
		(size 0.762)
		(drill 0.381)
		(layers "F.Cu" "B.Cu")
		(net "FM_9ZXL045_P1_2_OE_N")
	)
	(segment
		(start 100.88372 -406.151588)
		(end 101.305614 -406.573482)
		(width 0.10668)
		(layer "F.Cu")
		(net "FM_9ZXL045_P1_1_OE_N")
	)
	(segment
		(start 103.533194 -406.151588)
		(end 104.157018 -406.775412)
		(width 0.10668)
		(layer "F.Cu")
		(net "FM_9ZXL045_P1_1_OE_N")
	)
	(segment
		(start 104.996488 -407.02992)
		(end 104.996488 -407.25725)
		(width 0.10668)
		(layer "F.Cu")
		(net "FM_9ZXL045_P1_1_OE_N")
	)
	(segment
		(start 101.305614 -406.573482)
		(end 103.1113 -406.573482)
		(width 0.10668)
		(layer "F.Cu")
		(net "FM_9ZXL045_P1_1_OE_N")
	)
	(segment
		(start 104.157018 -406.775412)
		(end 104.74198 -406.775412)
		(width 0.10668)
		(layer "F.Cu")
		(net "FM_9ZXL045_P1_1_OE_N")
	)
	(segment
		(start 103.1113 -406.573482)
		(end 103.533194 -406.151588)
		(width 0.10668)
		(layer "F.Cu")
		(net "FM_9ZXL045_P1_1_OE_N")
	)
	(segment
		(start 104.74198 -406.775412)
		(end 104.996488 -407.02992)
		(width 0.10668)
		(layer "F.Cu")
		(net "FM_9ZXL045_P1_1_OE_N")
	)
	(via
		(at 103.533194 -406.151588)
		(size 0.762)
		(drill 0.381)
		(layers "F.Cu" "B.Cu")
		(net "FM_9ZXL045_P1_1_OE_N")
	)
	(segment
		(start 103.547418 -408.382216)
		(end 103.871522 -408.382216)
		(width 0.10668)
		(layer "F.Cu")
		(net "FM_9ZXL045_P1_0_OE_N")
	)
	(segment
		(start 101.992938 -407.167588)
		(end 102.33279 -407.167588)
		(width 0.10668)
		(layer "F.Cu")
		(net "FM_9ZXL045_P1_0_OE_N")
	)
	(segment
		(start 102.33279 -407.167588)
		(end 103.547418 -408.382216)
		(width 0.10668)
		(layer "F.Cu")
		(net "FM_9ZXL045_P1_0_OE_N")
	)
	(segment
		(start 100.88372 -407.167588)
		(end 101.992938 -407.167588)
		(width 0.10668)
		(layer "F.Cu")
		(net "FM_9ZXL045_P1_0_OE_N")
	)
	(via
		(at 101.992938 -407.167588)
		(size 0.762)
		(drill 0.381)
		(layers "F.Cu" "B.Cu")
		(net "FM_9ZXL045_P1_0_OE_N")
	)
	(segment
		(start 283.295852 -420.073074)
		(end 283.506164 -420.073074)
		(width 0.10668)
		(layer "F.Cu")
		(net "FM_9ZXL045_P0_DEV_EN")
	)
	(segment
		(start 281.817826 -421.87495)
		(end 282.292298 -421.400478)
		(width 0.10668)
		(layer "F.Cu")
		(net "FM_9ZXL045_P0_DEV_EN")
	)
	(segment
		(start 282.292298 -421.400478)
		(end 282.292298 -421.076628)
		(width 0.10668)
		(layer "F.Cu")
		(net "FM_9ZXL045_P0_DEV_EN")
	)
	(segment
		(start 281.686 -423.01795)
		(end 281.686 -422.006776)
		(width 0.10668)
		(layer "F.Cu")
		(net "FM_9ZXL045_P0_DEV_EN")
	)
	(segment
		(start 282.292298 -421.076628)
		(end 283.295852 -420.073074)
		(width 0.10668)
		(layer "F.Cu")
		(net "FM_9ZXL045_P0_DEV_EN")
	)
	(segment
		(start 281.686 -422.006776)
		(end 281.817826 -421.87495)
		(width 0.10668)
		(layer "F.Cu")
		(net "FM_9ZXL045_P0_DEV_EN")
	)
	(via
		(at 281.817826 -421.87495)
		(size 0.762)
		(drill 0.381)
		(layers "F.Cu" "B.Cu")
		(net "FM_9ZXL045_P0_DEV_EN")
	)
	(segment
		(start 289.589718 -423.056558)
		(end 289.1282 -422.59504)
		(width 0.10668)
		(layer "F.Cu")
		(net "FM_9ZXL045_P0_3_OE_N")
	)
	(segment
		(start 289.1282 -422.59504)
		(end 288.391092 -422.59504)
		(width 0.10668)
		(layer "F.Cu")
		(net "FM_9ZXL045_P0_3_OE_N")
	)
	(segment
		(start 288.391092 -422.59504)
		(end 288.154618 -422.59504)
		(width 0.10668)
		(layer "F.Cu")
		(net "FM_9ZXL045_P0_3_OE_N")
	)
	(segment
		(start 288.154618 -422.59504)
		(end 287.130998 -421.57142)
		(width 0.10668)
		(layer "F.Cu")
		(net "FM_9ZXL045_P0_3_OE_N")
	)
	(segment
		(start 287.130998 -421.57142)
		(end 287.130998 -420.697914)
		(width 0.10668)
		(layer "F.Cu")
		(net "FM_9ZXL045_P0_3_OE_N")
	)
	(via
		(at 288.391092 -422.59504)
		(size 0.762)
		(drill 0.381)
		(layers "F.Cu" "B.Cu")
		(net "FM_9ZXL045_P0_3_OE_N")
	)
	(segment
		(start 290.1569 -421.529256)
		(end 288.700718 -420.073074)
		(width 0.10668)
		(layer "F.Cu")
		(net "FM_9ZXL045_P0_2_OE_N")
	)
	(segment
		(start 288.700718 -420.073074)
		(end 288.255964 -420.073074)
		(width 0.10668)
		(layer "F.Cu")
		(net "FM_9ZXL045_P0_2_OE_N")
	)
	(segment
		(start 290.603178 -423.034714)
		(end 290.603178 -421.975534)
		(width 0.10668)
		(layer "F.Cu")
		(net "FM_9ZXL045_P0_2_OE_N")
	)
	(segment
		(start 290.603178 -421.975534)
		(end 290.1569 -421.529256)
		(width 0.10668)
		(layer "F.Cu")
		(net "FM_9ZXL045_P0_2_OE_N")
	)
	(via
		(at 290.1569 -421.529256)
		(size 0.762)
		(drill 0.381)
		(layers "F.Cu" "B.Cu")
		(net "FM_9ZXL045_P0_2_OE_N")
	)
	(segment
		(start 288.568638 -413.141922)
		(end 288.568638 -413.682434)
		(width 0.10668)
		(layer "F.Cu")
		(net "FM_9ZXL045_P0_1_OE_N")
	)
	(segment
		(start 288.726118 -417.07308)
		(end 288.255964 -417.07308)
		(width 0.10668)
		(layer "F.Cu")
		(net "FM_9ZXL045_P0_1_OE_N")
	)
	(segment
		(start 288.568638 -413.682434)
		(end 289.167824 -414.28162)
		(width 0.10668)
		(layer "F.Cu")
		(net "FM_9ZXL045_P0_1_OE_N")
	)
	(segment
		(start 289.167824 -416.631374)
		(end 288.726118 -417.07308)
		(width 0.10668)
		(layer "F.Cu")
		(net "FM_9ZXL045_P0_1_OE_N")
	)
	(segment
		(start 289.167824 -414.59912)
		(end 289.167824 -416.631374)
		(width 0.10668)
		(layer "F.Cu")
		(net "FM_9ZXL045_P0_1_OE_N")
	)
	(segment
		(start 289.167824 -414.28162)
		(end 289.167824 -414.59912)
		(width 0.10668)
		(layer "F.Cu")
		(net "FM_9ZXL045_P0_1_OE_N")
	)
	(via
		(at 289.167824 -414.59912)
		(size 0.762)
		(drill 0.381)
		(layers "F.Cu" "B.Cu")
		(net "FM_9ZXL045_P0_1_OE_N")
	)
	(segment
		(start 287.570672 -414.161478)
		(end 287.130998 -414.601152)
		(width 0.10668)
		(layer "F.Cu")
		(net "FM_9ZXL045_P0_0_OE_N")
	)
	(segment
		(start 287.130998 -414.601152)
		(end 287.130998 -415.948114)
		(width 0.10668)
		(layer "F.Cu")
		(net "FM_9ZXL045_P0_0_OE_N")
	)
	(segment
		(start 287.570672 -413.14116)
		(end 287.570672 -414.161478)
		(width 0.10668)
		(layer "F.Cu")
		(net "FM_9ZXL045_P0_0_OE_N")
	)
	(via
		(at 287.570672 -414.161478)
		(size 0.762)
		(drill 0.381)
		(layers "F.Cu" "B.Cu")
		(net "FM_9ZXL045_P0_0_OE_N")
	)
	(via
		(at 185.280808 -146.426428)
		(size 0.6604)
		(drill 0.3302)
		(layers "F.Cu" "B.Cu")
		(net "ESPI_CPU0_ALERT_R1_N")
	)
	(segment
		(start 185.102246 -144.182084)
		(end 184.669176 -143.749014)
		(width 0.10668)
		(layer "B.Cu")
		(net "ESPI_CPU0_ALERT_R1_N")
	)
	(segment
		(start 185.102246 -145.726404)
		(end 185.102246 -144.182084)
		(width 0.10668)
		(layer "B.Cu")
		(net "ESPI_CPU0_ALERT_R1_N")
	)
	(segment
		(start 184.669176 -143.749014)
		(end 183.83504 -143.749014)
		(width 0.10668)
		(layer "B.Cu")
		(net "ESPI_CPU0_ALERT_R1_N")
	)
	(segment
		(start 185.280808 -146.426428)
		(end 185.280808 -145.904966)
		(width 0.10668)
		(layer "B.Cu")
		(net "ESPI_CPU0_ALERT_R1_N")
	)
	(segment
		(start 185.280808 -147.837144)
		(end 185.280808 -146.426428)
		(width 0.10668)
		(layer "B.Cu")
		(net "ESPI_CPU0_ALERT_R1_N")
	)
	(segment
		(start 185.280808 -145.904966)
		(end 185.102246 -145.726404)
		(width 0.10668)
		(layer "B.Cu")
		(net "ESPI_CPU0_ALERT_R1_N")
	)
	(segment
		(start 183.967374 -140.280136)
		(end 184.894982 -139.352528)
		(width 0.10668)
		(layer "F.Cu")
		(net "ESPI_CPU0_ALERT_PLD_N")
	)
	(segment
		(start 185.304684 -138.032998)
		(end 185.039 -138.032998)
		(width 0.10668)
		(layer "F.Cu")
		(net "ESPI_CPU0_ALERT_PLD_N")
	)
	(segment
		(start 185.543698 -138.846052)
		(end 185.543698 -138.272012)
		(width 0.10668)
		(layer "F.Cu")
		(net "ESPI_CPU0_ALERT_PLD_N")
	)
	(segment
		(start 185.543698 -138.272012)
		(end 185.304684 -138.032998)
		(width 0.10668)
		(layer "F.Cu")
		(net "ESPI_CPU0_ALERT_PLD_N")
	)
	(segment
		(start 184.894982 -139.352528)
		(end 185.037222 -139.352528)
		(width 0.10668)
		(layer "F.Cu")
		(net "ESPI_CPU0_ALERT_PLD_N")
	)
	(segment
		(start 183.967374 -140.573252)
		(end 183.967374 -140.280136)
		(width 0.10668)
		(layer "F.Cu")
		(net "ESPI_CPU0_ALERT_PLD_N")
	)
	(segment
		(start 185.037222 -139.352528)
		(end 185.543698 -138.846052)
		(width 0.10668)
		(layer "F.Cu")
		(net "ESPI_CPU0_ALERT_PLD_N")
	)
	(via
		(at 182.499 -143.951706)
		(size 0.6604)
		(drill 0.3302)
		(layers "F.Cu" "B.Cu")
		(net "ESPI_CPU0_ALERT_PLD_N")
	)
	(via
		(at 183.967374 -140.573252)
		(size 0.508)
		(drill 0.254)
		(layers "F.Cu" "B.Cu")
		(net "ESPI_CPU0_ALERT_PLD_N")
	)
	(segment
		(start 183.967374 -140.573252)
		(end 183.967374 -141.818614)
		(width 0.10668)
		(layer "B.Cu")
		(net "ESPI_CPU0_ALERT_PLD_N")
	)
	(segment
		(start 183.83504 -145.048986)
		(end 183.223154 -145.048986)
		(width 0.10668)
		(layer "B.Cu")
		(net "ESPI_CPU0_ALERT_PLD_N")
	)
	(segment
		(start 183.223154 -145.048986)
		(end 183.13019 -145.14195)
		(width 0.10668)
		(layer "B.Cu")
		(net "ESPI_CPU0_ALERT_PLD_N")
	)
	(segment
		(start 183.13019 -145.14195)
		(end 182.499 -145.14195)
		(width 0.10668)
		(layer "B.Cu")
		(net "ESPI_CPU0_ALERT_PLD_N")
	)
	(segment
		(start 182.499 -143.286988)
		(end 182.499 -143.951706)
		(width 0.10668)
		(layer "B.Cu")
		(net "ESPI_CPU0_ALERT_PLD_N")
	)
	(segment
		(start 183.967374 -141.818614)
		(end 182.499 -143.286988)
		(width 0.10668)
		(layer "B.Cu")
		(net "ESPI_CPU0_ALERT_PLD_N")
	)
	(segment
		(start 182.499 -145.14195)
		(end 182.499 -143.951706)
		(width 0.10668)
		(layer "B.Cu")
		(net "ESPI_CPU0_ALERT_PLD_N")
	)
	(segment
		(start 220.123766 -204.237336)
		(end 220.32722 -204.44079)
		(width 0.10668)
		(layer "F.Cu")
		(net "ESPI_CPU0_ALERT_P0_N")
	)
	(segment
		(start 223.282002 -361.620562)
		(end 223.373696 -361.712256)
		(width 0.10668)
		(layer "F.Cu")
		(net "ESPI_CPU0_ALERT_P0_N")
	)
	(segment
		(start 406.49398 -324.414896)
		(end 406.49398 -327.077832)
		(width 0.10668)
		(layer "F.Cu")
		(net "ESPI_CPU0_ALERT_P0_N")
	)
	(segment
		(start 216.492328 -201.235818)
		(end 219.493846 -204.237336)
		(width 0.10668)
		(layer "F.Cu")
		(net "ESPI_CPU0_ALERT_P0_N")
	)
	(segment
		(start 405.453342 -322.953888)
		(end 405.453342 -323.374258)
		(width 0.10668)
		(layer "F.Cu")
		(net "ESPI_CPU0_ALERT_P0_N")
	)
	(segment
		(start 406.002744 -327.569068)
		(end 406.002744 -329.725274)
		(width 0.10668)
		(layer "F.Cu")
		(net "ESPI_CPU0_ALERT_P0_N")
	)
	(segment
		(start 222.312484 -329.264772)
		(end 222.312484 -334.24241)
		(width 0.10668)
		(layer "F.Cu")
		(net "ESPI_CPU0_ALERT_P0_N")
	)
	(segment
		(start 362.177076 -360.634026)
		(end 348.68104 -374.130062)
		(width 0.10668)
		(layer "F.Cu")
		(net "ESPI_CPU0_ALERT_P0_N")
	)
	(segment
		(start 406.806654 -345.774264)
		(end 406.806654 -351.32137)
		(width 0.10668)
		(layer "F.Cu")
		(net "ESPI_CPU0_ALERT_P0_N")
	)
	(segment
		(start 248.233946 -371.714014)
		(end 244.870478 -368.350546)
		(width 0.10668)
		(layer "F.Cu")
		(net "ESPI_CPU0_ALERT_P0_N")
	)
	(segment
		(start 282.95727 -376.054366)
		(end 278.616918 -371.714014)
		(width 0.10668)
		(layer "F.Cu")
		(net "ESPI_CPU0_ALERT_P0_N")
	)
	(segment
		(start 220.053662 -205.832202)
		(end 218.37015 -205.832202)
		(width 0.10668)
		(layer "F.Cu")
		(net "ESPI_CPU0_ALERT_P0_N")
	)
	(segment
		(start 219.493846 -204.237336)
		(end 220.123766 -204.237336)
		(width 0.10668)
		(layer "F.Cu")
		(net "ESPI_CPU0_ALERT_P0_N")
	)
	(segment
		(start 215.975438 -322.927726)
		(end 222.312484 -329.264772)
		(width 0.10668)
		(layer "F.Cu")
		(net "ESPI_CPU0_ALERT_P0_N")
	)
	(segment
		(start 215.975438 -208.226914)
		(end 215.975438 -322.927726)
		(width 0.10668)
		(layer "F.Cu")
		(net "ESPI_CPU0_ALERT_P0_N")
	)
	(segment
		(start 216.492328 -186.744864)
		(end 216.492328 -201.235818)
		(width 0.10668)
		(layer "F.Cu")
		(net "ESPI_CPU0_ALERT_P0_N")
	)
	(segment
		(start 298.286932 -374.130062)
		(end 296.362628 -376.054366)
		(width 0.10668)
		(layer "F.Cu")
		(net "ESPI_CPU0_ALERT_P0_N")
	)
	(segment
		(start 397.493998 -360.634026)
		(end 362.177076 -360.634026)
		(width 0.10668)
		(layer "F.Cu")
		(net "ESPI_CPU0_ALERT_P0_N")
	)
	(segment
		(start 231.366822 -368.350546)
		(end 231.006142 -367.989866)
		(width 0.10668)
		(layer "F.Cu")
		(net "ESPI_CPU0_ALERT_P0_N")
	)
	(segment
		(start 405.097234 -344.064844)
		(end 406.806654 -345.774264)
		(width 0.10668)
		(layer "F.Cu")
		(net "ESPI_CPU0_ALERT_P0_N")
	)
	(segment
		(start 220.32722 -204.44079)
		(end 220.32722 -205.558644)
		(width 0.10668)
		(layer "F.Cu")
		(net "ESPI_CPU0_ALERT_P0_N")
	)
	(segment
		(start 187.078112 -147.22221)
		(end 187.078112 -155.318968)
		(width 0.10668)
		(layer "F.Cu")
		(net "ESPI_CPU0_ALERT_P0_N")
	)
	(segment
		(start 222.312484 -334.24241)
		(end 223.282002 -335.211928)
		(width 0.10668)
		(layer "F.Cu")
		(net "ESPI_CPU0_ALERT_P0_N")
	)
	(segment
		(start 405.097234 -330.630784)
		(end 405.097234 -344.064844)
		(width 0.10668)
		(layer "F.Cu")
		(net "ESPI_CPU0_ALERT_P0_N")
	)
	(segment
		(start 406.49398 -327.077832)
		(end 406.002744 -327.569068)
		(width 0.10668)
		(layer "F.Cu")
		(net "ESPI_CPU0_ALERT_P0_N")
	)
	(segment
		(start 220.32722 -205.558644)
		(end 220.053662 -205.832202)
		(width 0.10668)
		(layer "F.Cu")
		(net "ESPI_CPU0_ALERT_P0_N")
	)
	(segment
		(start 223.282002 -335.211928)
		(end 223.282002 -361.620562)
		(width 0.10668)
		(layer "F.Cu")
		(net "ESPI_CPU0_ALERT_P0_N")
	)
	(segment
		(start 406.806654 -351.32137)
		(end 397.493998 -360.634026)
		(width 0.10668)
		(layer "F.Cu")
		(net "ESPI_CPU0_ALERT_P0_N")
	)
	(segment
		(start 207.78343 -166.368984)
		(end 208.241646 -166.8272)
		(width 0.10668)
		(layer "F.Cu")
		(net "ESPI_CPU0_ALERT_P0_N")
	)
	(segment
		(start 348.68104 -374.130062)
		(end 298.286932 -374.130062)
		(width 0.10668)
		(layer "F.Cu")
		(net "ESPI_CPU0_ALERT_P0_N")
	)
	(segment
		(start 296.362628 -376.054366)
		(end 282.95727 -376.054366)
		(width 0.10668)
		(layer "F.Cu")
		(net "ESPI_CPU0_ALERT_P0_N")
	)
	(segment
		(start 218.37015 -205.832202)
		(end 215.975438 -208.226914)
		(width 0.10668)
		(layer "F.Cu")
		(net "ESPI_CPU0_ALERT_P0_N")
	)
	(segment
		(start 223.373696 -361.712256)
		(end 223.373696 -361.950254)
		(width 0.10668)
		(layer "F.Cu")
		(net "ESPI_CPU0_ALERT_P0_N")
	)
	(segment
		(start 405.453342 -323.374258)
		(end 406.49398 -324.414896)
		(width 0.10668)
		(layer "F.Cu")
		(net "ESPI_CPU0_ALERT_P0_N")
	)
	(segment
		(start 208.241646 -166.8272)
		(end 216.492328 -186.744864)
		(width 0.10668)
		(layer "F.Cu")
		(net "ESPI_CPU0_ALERT_P0_N")
	)
	(segment
		(start 406.002744 -329.725274)
		(end 405.097234 -330.630784)
		(width 0.10668)
		(layer "F.Cu")
		(net "ESPI_CPU0_ALERT_P0_N")
	)
	(segment
		(start 244.870478 -368.350546)
		(end 231.366822 -368.350546)
		(width 0.10668)
		(layer "F.Cu")
		(net "ESPI_CPU0_ALERT_P0_N")
	)
	(segment
		(start 187.078112 -155.318968)
		(end 191.299846 -159.540702)
		(width 0.10668)
		(layer "F.Cu")
		(net "ESPI_CPU0_ALERT_P0_N")
	)
	(segment
		(start 191.299846 -159.540702)
		(end 207.78343 -166.368984)
		(width 0.10668)
		(layer "F.Cu")
		(net "ESPI_CPU0_ALERT_P0_N")
	)
	(segment
		(start 278.616918 -371.714014)
		(end 248.233946 -371.714014)
		(width 0.10668)
		(layer "F.Cu")
		(net "ESPI_CPU0_ALERT_P0_N")
	)
	(via
		(at 405.453342 -322.953888)
		(size 0.508)
		(drill 0.254)
		(layers "F.Cu" "B.Cu")
		(net "ESPI_CPU0_ALERT_P0_N")
	)
	(via
		(at 187.078112 -147.22221)
		(size 0.508)
		(drill 0.254)
		(layers "F.Cu" "B.Cu")
		(net "ESPI_CPU0_ALERT_P0_N")
	)
	(via
		(at 231.006142 -367.989866)
		(size 0.508)
		(drill 0.254)
		(layers "F.Cu" "B.Cu")
		(net "ESPI_CPU0_ALERT_P0_N")
	)
	(via
		(at 223.373696 -361.950254)
		(size 0.508)
		(drill 0.254)
		(layers "F.Cu" "B.Cu")
		(net "ESPI_CPU0_ALERT_P0_N")
	)
	(segment
		(start 187.078112 -147.07743)
		(end 187.701174 -146.454368)
		(width 0.10668)
		(layer "B.Cu")
		(net "ESPI_CPU0_ALERT_P0_N")
	)
	(segment
		(start 231.006142 -367.989866)
		(end 227.274374 -367.989866)
		(width 0.10668)
		(layer "B.Cu")
		(net "ESPI_CPU0_ALERT_P0_N")
	)
	(segment
		(start 185.73496 -145.048986)
		(end 186.378088 -145.048986)
		(width 0.10668)
		(layer "B.Cu")
		(net "ESPI_CPU0_ALERT_P0_N")
	)
	(segment
		(start 403.715728 -323.657468)
		(end 403.963124 -323.410072)
		(width 0.10668)
		(layer "B.Cu")
		(net "ESPI_CPU0_ALERT_P0_N")
	)
	(segment
		(start 225.221292 -361.950254)
		(end 223.373696 -361.950254)
		(width 0.10668)
		(layer "B.Cu")
		(net "ESPI_CPU0_ALERT_P0_N")
	)
	(segment
		(start 187.078112 -147.22221)
		(end 187.078112 -147.07743)
		(width 0.10668)
		(layer "B.Cu")
		(net "ESPI_CPU0_ALERT_P0_N")
	)
	(segment
		(start 187.701174 -146.454368)
		(end 187.701174 -145.585434)
		(width 0.10668)
		(layer "B.Cu")
		(net "ESPI_CPU0_ALERT_P0_N")
	)
	(segment
		(start 403.715728 -323.892672)
		(end 403.715728 -323.657468)
		(width 0.10668)
		(layer "B.Cu")
		(net "ESPI_CPU0_ALERT_P0_N")
	)
	(segment
		(start 186.914536 -145.585434)
		(end 187.701174 -145.585434)
		(width 0.10668)
		(layer "B.Cu")
		(net "ESPI_CPU0_ALERT_P0_N")
	)
	(segment
		(start 227.274374 -367.989866)
		(end 226.157282 -366.872774)
		(width 0.10668)
		(layer "B.Cu")
		(net "ESPI_CPU0_ALERT_P0_N")
	)
	(segment
		(start 226.157282 -362.886244)
		(end 225.221292 -361.950254)
		(width 0.10668)
		(layer "B.Cu")
		(net "ESPI_CPU0_ALERT_P0_N")
	)
	(segment
		(start 405.093678 -323.410072)
		(end 405.530558 -323.846952)
		(width 0.10668)
		(layer "B.Cu")
		(net "ESPI_CPU0_ALERT_P0_N")
	)
	(segment
		(start 405.530558 -323.846952)
		(end 406.298908 -323.846952)
		(width 0.10668)
		(layer "B.Cu")
		(net "ESPI_CPU0_ALERT_P0_N")
	)
	(segment
		(start 226.157282 -366.872774)
		(end 226.157282 -362.886244)
		(width 0.10668)
		(layer "B.Cu")
		(net "ESPI_CPU0_ALERT_P0_N")
	)
	(segment
		(start 406.298908 -323.799454)
		(end 406.298908 -323.846952)
		(width 0.10668)
		(layer "B.Cu")
		(net "ESPI_CPU0_ALERT_P0_N")
	)
	(segment
		(start 405.453342 -322.953888)
		(end 406.298908 -323.799454)
		(width 0.10668)
		(layer "B.Cu")
		(net "ESPI_CPU0_ALERT_P0_N")
	)
	(segment
		(start 186.378088 -145.048986)
		(end 186.914536 -145.585434)
		(width 0.10668)
		(layer "B.Cu")
		(net "ESPI_CPU0_ALERT_P0_N")
	)
	(segment
		(start 403.963124 -323.410072)
		(end 405.093678 -323.410072)
		(width 0.10668)
		(layer "B.Cu")
		(net "ESPI_CPU0_ALERT_P0_N")
	)
	(segment
		(start 104.977946 -414.887918)
		(end 105.386378 -414.479486)
		(width 0.10668)
		(layer "F.Cu")
		(net "CLK_9ZXL045_P1_SADR0")
	)
	(segment
		(start 104.66705 -415.198814)
		(end 104.977946 -414.887918)
		(width 0.10668)
		(layer "F.Cu")
		(net "CLK_9ZXL045_P1_SADR0")
	)
	(segment
		(start 104.66705 -416.814)
		(end 104.66705 -415.798)
		(width 0.10668)
		(layer "F.Cu")
		(net "CLK_9ZXL045_P1_SADR0")
	)
	(segment
		(start 105.386378 -414.479486)
		(end 105.386378 -412.962852)
		(width 0.10668)
		(layer "F.Cu")
		(net "CLK_9ZXL045_P1_SADR0")
	)
	(segment
		(start 105.996486 -412.352744)
		(end 105.996486 -412.00705)
		(width 0.10668)
		(layer "F.Cu")
		(net "CLK_9ZXL045_P1_SADR0")
	)
	(segment
		(start 105.386378 -412.962852)
		(end 105.996486 -412.352744)
		(width 0.10668)
		(layer "F.Cu")
		(net "CLK_9ZXL045_P1_SADR0")
	)
	(segment
		(start 104.66705 -415.798)
		(end 104.66705 -415.198814)
		(width 0.10668)
		(layer "F.Cu")
		(net "CLK_9ZXL045_P1_SADR0")
	)
	(via
		(at 104.977946 -414.887918)
		(size 0.762)
		(drill 0.381)
		(layers "F.Cu" "B.Cu")
		(net "CLK_9ZXL045_P1_SADR0")
	)
	(segment
		(start 109.47781 -411.38221)
		(end 109.985048 -411.889448)
		(width 0.10668)
		(layer "F.Cu")
		(net "CLK_9ZXL045_P1_HIBW")
	)
	(segment
		(start 108.621322 -411.38221)
		(end 109.47781 -411.38221)
		(width 0.10668)
		(layer "F.Cu")
		(net "CLK_9ZXL045_P1_HIBW")
	)
	(via
		(at 109.985048 -411.889448)
		(size 0.508)
		(drill 0.254)
		(layers "F.Cu" "B.Cu")
		(net "CLK_9ZXL045_P1_HIBW")
	)
	(segment
		(start 111.48695 -413.512)
		(end 111.52505 -413.4739)
		(width 0.10668)
		(layer "B.Cu")
		(net "CLK_9ZXL045_P1_HIBW")
	)
	(segment
		(start 111.48695 -414.02)
		(end 111.48695 -413.512)
		(width 0.10668)
		(layer "B.Cu")
		(net "CLK_9ZXL045_P1_HIBW")
	)
	(segment
		(start 111.52505 -413.4739)
		(end 111.52505 -413.004)
		(width 0.10668)
		(layer "B.Cu")
		(net "CLK_9ZXL045_P1_HIBW")
	)
	(segment
		(start 110.772194 -411.889448)
		(end 109.985048 -411.889448)
		(width 0.10668)
		(layer "B.Cu")
		(net "CLK_9ZXL045_P1_HIBW")
	)
	(segment
		(start 111.52505 -413.004)
		(end 111.52505 -412.642304)
		(width 0.10668)
		(layer "B.Cu")
		(net "CLK_9ZXL045_P1_HIBW")
	)
	(segment
		(start 111.52505 -412.642304)
		(end 110.772194 -411.889448)
		(width 0.10668)
		(layer "B.Cu")
		(net "CLK_9ZXL045_P1_HIBW")
	)
	(segment
		(start 281.697938 -417.714684)
		(end 282.056332 -418.073078)
		(width 0.10668)
		(layer "F.Cu")
		(net "CLK_9ZXL045_P0_SADR0")
	)
	(segment
		(start 282.056332 -418.073078)
		(end 283.506164 -418.073078)
		(width 0.10668)
		(layer "F.Cu")
		(net "CLK_9ZXL045_P0_SADR0")
	)
	(segment
		(start 279.92705 -417.195)
		(end 280.543 -417.195)
		(width 0.10668)
		(layer "F.Cu")
		(net "CLK_9ZXL045_P0_SADR0")
	)
	(segment
		(start 281.062684 -417.714684)
		(end 281.697938 -417.714684)
		(width 0.10668)
		(layer "F.Cu")
		(net "CLK_9ZXL045_P0_SADR0")
	)
	(segment
		(start 279.92705 -416.306)
		(end 279.92705 -417.195)
		(width 0.10668)
		(layer "F.Cu")
		(net "CLK_9ZXL045_P0_SADR0")
	)
	(segment
		(start 280.543 -417.195)
		(end 280.797 -417.449)
		(width 0.10668)
		(layer "F.Cu")
		(net "CLK_9ZXL045_P0_SADR0")
	)
	(segment
		(start 280.797 -417.449)
		(end 281.062684 -417.714684)
		(width 0.10668)
		(layer "F.Cu")
		(net "CLK_9ZXL045_P0_SADR0")
	)
	(via
		(at 280.797 -417.449)
		(size 0.762)
		(drill 0.381)
		(layers "F.Cu" "B.Cu")
		(net "CLK_9ZXL045_P0_SADR0")
	)
	(segment
		(start 283.586174 -422.054274)
		(end 283.586174 -421.68445)
		(width 0.10668)
		(layer "F.Cu")
		(net "CLK_9ZXL045_P0_HIBW")
	)
	(segment
		(start 284.131004 -421.13962)
		(end 284.131004 -420.697914)
		(width 0.10668)
		(layer "F.Cu")
		(net "CLK_9ZXL045_P0_HIBW")
	)
	(segment
		(start 283.464 -423.01795)
		(end 283.586174 -422.895776)
		(width 0.10668)
		(layer "F.Cu")
		(net "CLK_9ZXL045_P0_HIBW")
	)
	(segment
		(start 283.586174 -421.68445)
		(end 284.131004 -421.13962)
		(width 0.10668)
		(layer "F.Cu")
		(net "CLK_9ZXL045_P0_HIBW")
	)
	(segment
		(start 283.586174 -422.895776)
		(end 283.586174 -422.054274)
		(width 0.10668)
		(layer "F.Cu")
		(net "CLK_9ZXL045_P0_HIBW")
	)
	(segment
		(start 282.575 -423.01795)
		(end 283.464 -423.01795)
		(width 0.10668)
		(layer "F.Cu")
		(net "CLK_9ZXL045_P0_HIBW")
	)
	(via
		(at 283.586174 -422.054274)
		(size 0.762)
		(drill 0.381)
		(layers "F.Cu" "B.Cu")
		(net "CLK_9ZXL045_P0_HIBW")
	)
	(segment
		(start 108.382816 -387.789674)
		(end 108.653326 -387.519164)
		(width 0.12954)
		(layer "F.Cu")
		(net "CLK_100M_RETIMER_CPU1_P3_R_DP")
	)
	(segment
		(start 108.82884 -408.882088)
		(end 108.917486 -408.970734)
		(width 0.12954)
		(layer "F.Cu")
		(net "CLK_100M_RETIMER_CPU1_P3_R_DP")
	)
	(segment
		(start 108.653326 -387.519164)
		(end 109.116114 -387.519164)
		(width 0.12954)
		(layer "F.Cu")
		(net "CLK_100M_RETIMER_CPU1_P3_R_DP")
	)
	(segment
		(start 110.126526 -409.310586)
		(end 110.670594 -409.310586)
		(width 0.12954)
		(layer "F.Cu")
		(net "CLK_100M_RETIMER_CPU1_P3_R_DP")
	)
	(segment
		(start 109.116114 -387.519164)
		(end 109.361224 -387.764274)
		(width 0.12954)
		(layer "F.Cu")
		(net "CLK_100M_RETIMER_CPU1_P3_R_DP")
	)
	(segment
		(start 110.670594 -409.310586)
		(end 110.941104 -409.040076)
		(width 0.12954)
		(layer "F.Cu")
		(net "CLK_100M_RETIMER_CPU1_P3_R_DP")
	)
	(segment
		(start 109.786674 -408.970734)
		(end 110.126526 -409.310586)
		(width 0.12954)
		(layer "F.Cu")
		(net "CLK_100M_RETIMER_CPU1_P3_R_DP")
	)
	(segment
		(start 108.917486 -408.970734)
		(end 109.786674 -408.970734)
		(width 0.12954)
		(layer "F.Cu")
		(net "CLK_100M_RETIMER_CPU1_P3_R_DP")
	)
	(segment
		(start 108.621322 -408.882088)
		(end 108.82884 -408.882088)
		(width 0.12954)
		(layer "F.Cu")
		(net "CLK_100M_RETIMER_CPU1_P3_R_DP")
	)
	(via
		(at 108.382816 -387.789674)
		(size 0.508)
		(drill 0.254)
		(layers "F.Cu" "B.Cu")
		(net "CLK_100M_RETIMER_CPU1_P3_R_DP")
	)
	(via
		(at 110.941104 -409.040076)
		(size 0.508)
		(drill 0.254)
		(layers "F.Cu" "B.Cu")
		(net "CLK_100M_RETIMER_CPU1_P3_R_DP")
	)
	(segment
		(start 111.781844 -393.89431)
		(end 111.781844 -394.32103)
		(width 0.14224)
		(layer "In6.Cu")
		(net "CLK_100M_RETIMER_CPU1_P3_R_DP")
	)
	(segment
		(start 110.885224 -390.225026)
		(end 111.048546 -390.619488)
		(width 0.14224)
		(layer "In6.Cu")
		(net "CLK_100M_RETIMER_CPU1_P3_R_DP")
	)
	(segment
		(start 111.781844 -395.54277)
		(end 111.919004 -395.67993)
		(width 0.14224)
		(layer "In6.Cu")
		(net "CLK_100M_RETIMER_CPU1_P3_R_DP")
	)
	(segment
		(start 111.919004 -395.67993)
		(end 111.919004 -396.65275)
		(width 0.14224)
		(layer "In6.Cu")
		(net "CLK_100M_RETIMER_CPU1_P3_R_DP")
	)
	(segment
		(start 110.796324 -389.651748)
		(end 110.959392 -390.045956)
		(width 0.14224)
		(layer "In6.Cu")
		(net "CLK_100M_RETIMER_CPU1_P3_R_DP")
	)
	(segment
		(start 110.957868 -402.884894)
		(end 110.957868 -403.311614)
		(width 0.14224)
		(layer "In6.Cu")
		(net "CLK_100M_RETIMER_CPU1_P3_R_DP")
	)
	(segment
		(start 111.755428 -396.816326)
		(end 111.561372 -396.816326)
		(width 0.14224)
		(layer "In6.Cu")
		(net "CLK_100M_RETIMER_CPU1_P3_R_DP")
	)
	(segment
		(start 110.820708 -403.875494)
		(end 110.957868 -404.012654)
		(width 0.14224)
		(layer "In6.Cu")
		(net "CLK_100M_RETIMER_CPU1_P3_R_DP")
	)
	(segment
		(start 111.781844 -394.32103)
		(end 111.919004 -394.45819)
		(width 0.14224)
		(layer "In6.Cu")
		(net "CLK_100M_RETIMER_CPU1_P3_R_DP")
	)
	(segment
		(start 111.919004 -394.97889)
		(end 111.781844 -395.11605)
		(width 0.14224)
		(layer "In6.Cu")
		(net "CLK_100M_RETIMER_CPU1_P3_R_DP")
	)
	(segment
		(start 110.957868 -401.056094)
		(end 110.820708 -401.193254)
		(width 0.14224)
		(layer "In6.Cu")
		(net "CLK_100M_RETIMER_CPU1_P3_R_DP")
	)
	(segment
		(start 110.820708 -399.364454)
		(end 110.957868 -399.501614)
		(width 0.14224)
		(layer "In6.Cu")
		(net "CLK_100M_RETIMER_CPU1_P3_R_DP")
	)
	(segment
		(start 110.453424 -389.182864)
		(end 110.616746 -389.577326)
		(width 0.14224)
		(layer "In6.Cu")
		(net "CLK_100M_RETIMER_CPU1_P3_R_DP")
	)
	(segment
		(start 110.527592 -389.003794)
		(end 110.453424 -389.182864)
		(width 0.14224)
		(layer "In6.Cu")
		(net "CLK_100M_RETIMER_CPU1_P3_R_DP")
	)
	(segment
		(start 109.55528 -387.800342)
		(end 109.55528 -387.994398)
		(width 0.14224)
		(layer "In6.Cu")
		(net "CLK_100M_RETIMER_CPU1_P3_R_DP")
	)
	(segment
		(start 111.919004 -392.36269)
		(end 111.919004 -393.75715)
		(width 0.14224)
		(layer "In6.Cu")
		(net "CLK_100M_RETIMER_CPU1_P3_R_DP")
	)
	(segment
		(start 110.957868 -401.757134)
		(end 110.957868 -402.183854)
		(width 0.14224)
		(layer "In6.Cu")
		(net "CLK_100M_RETIMER_CPU1_P3_R_DP")
	)
	(segment
		(start 110.957868 -406.90927)
		(end 112.2553 -408.206702)
		(width 0.14224)
		(layer "In6.Cu")
		(net "CLK_100M_RETIMER_CPU1_P3_R_DP")
	)
	(segment
		(start 110.957868 -404.012654)
		(end 110.957868 -406.90927)
		(width 0.14224)
		(layer "In6.Cu")
		(net "CLK_100M_RETIMER_CPU1_P3_R_DP")
	)
	(segment
		(start 110.957868 -398.800574)
		(end 110.820708 -398.937734)
		(width 0.14224)
		(layer "In6.Cu")
		(net "CLK_100M_RETIMER_CPU1_P3_R_DP")
	)
	(segment
		(start 111.22787 -390.69391)
		(end 111.390938 -391.088118)
		(width 0.14224)
		(layer "In6.Cu")
		(net "CLK_100M_RETIMER_CPU1_P3_R_DP")
	)
	(segment
		(start 111.31677 -391.267188)
		(end 111.480092 -391.66165)
		(width 0.14224)
		(layer "In6.Cu")
		(net "CLK_100M_RETIMER_CPU1_P3_R_DP")
	)
	(segment
		(start 110.820708 -401.193254)
		(end 110.820708 -401.619974)
		(width 0.14224)
		(layer "In6.Cu")
		(net "CLK_100M_RETIMER_CPU1_P3_R_DP")
	)
	(segment
		(start 111.659416 -391.736072)
		(end 111.919004 -392.36269)
		(width 0.14224)
		(layer "In6.Cu")
		(net "CLK_100M_RETIMER_CPU1_P3_R_DP")
	)
	(segment
		(start 110.957868 -402.183854)
		(end 110.820708 -402.321014)
		(width 0.14224)
		(layer "In6.Cu")
		(net "CLK_100M_RETIMER_CPU1_P3_R_DP")
	)
	(segment
		(start 109.857286 -388.296404)
		(end 110.051342 -388.296404)
		(width 0.14224)
		(layer "In6.Cu")
		(net "CLK_100M_RETIMER_CPU1_P3_R_DP")
	)
	(segment
		(start 109.55528 -387.994398)
		(end 109.857286 -388.296404)
		(width 0.14224)
		(layer "In6.Cu")
		(net "CLK_100M_RETIMER_CPU1_P3_R_DP")
	)
	(segment
		(start 111.048546 -390.619488)
		(end 111.22787 -390.69391)
		(width 0.14224)
		(layer "In6.Cu")
		(net "CLK_100M_RETIMER_CPU1_P3_R_DP")
	)
	(segment
		(start 110.820708 -402.747734)
		(end 110.957868 -402.884894)
		(width 0.14224)
		(layer "In6.Cu")
		(net "CLK_100M_RETIMER_CPU1_P3_R_DP")
	)
	(segment
		(start 111.561372 -396.816326)
		(end 111.259366 -397.118332)
		(width 0.14224)
		(layer "In6.Cu")
		(net "CLK_100M_RETIMER_CPU1_P3_R_DP")
	)
	(segment
		(start 110.820708 -401.619974)
		(end 110.957868 -401.757134)
		(width 0.14224)
		(layer "In6.Cu")
		(net "CLK_100M_RETIMER_CPU1_P3_R_DP")
	)
	(segment
		(start 111.919004 -393.75715)
		(end 111.781844 -393.89431)
		(width 0.14224)
		(layer "In6.Cu")
		(net "CLK_100M_RETIMER_CPU1_P3_R_DP")
	)
	(segment
		(start 108.382816 -387.789674)
		(end 108.673646 -387.498844)
		(width 0.14224)
		(layer "In6.Cu")
		(net "CLK_100M_RETIMER_CPU1_P3_R_DP")
	)
	(segment
		(start 111.259366 -397.118332)
		(end 111.259366 -397.312388)
		(width 0.14224)
		(layer "In6.Cu")
		(net "CLK_100M_RETIMER_CPU1_P3_R_DP")
	)
	(segment
		(start 110.957868 -403.311614)
		(end 110.820708 -403.448774)
		(width 0.14224)
		(layer "In6.Cu")
		(net "CLK_100M_RETIMER_CPU1_P3_R_DP")
	)
	(segment
		(start 109.253782 -387.498844)
		(end 109.55528 -387.800342)
		(width 0.14224)
		(layer "In6.Cu")
		(net "CLK_100M_RETIMER_CPU1_P3_R_DP")
	)
	(segment
		(start 110.820708 -400.065494)
		(end 110.820708 -400.492214)
		(width 0.14224)
		(layer "In6.Cu")
		(net "CLK_100M_RETIMER_CPU1_P3_R_DP")
	)
	(segment
		(start 110.957868 -399.928334)
		(end 110.820708 -400.065494)
		(width 0.14224)
		(layer "In6.Cu")
		(net "CLK_100M_RETIMER_CPU1_P3_R_DP")
	)
	(segment
		(start 110.820708 -400.492214)
		(end 110.957868 -400.629374)
		(width 0.14224)
		(layer "In6.Cu")
		(net "CLK_100M_RETIMER_CPU1_P3_R_DP")
	)
	(segment
		(start 110.616746 -389.577326)
		(end 110.796324 -389.651748)
		(width 0.14224)
		(layer "In6.Cu")
		(net "CLK_100M_RETIMER_CPU1_P3_R_DP")
	)
	(segment
		(start 110.957868 -399.501614)
		(end 110.957868 -399.928334)
		(width 0.14224)
		(layer "In6.Cu")
		(net "CLK_100M_RETIMER_CPU1_P3_R_DP")
	)
	(segment
		(start 112.2553 -408.942286)
		(end 111.86668 -409.330906)
		(width 0.14224)
		(layer "In6.Cu")
		(net "CLK_100M_RETIMER_CPU1_P3_R_DP")
	)
	(segment
		(start 110.820708 -402.321014)
		(end 110.820708 -402.747734)
		(width 0.14224)
		(layer "In6.Cu")
		(net "CLK_100M_RETIMER_CPU1_P3_R_DP")
	)
	(segment
		(start 111.480092 -391.66165)
		(end 111.659416 -391.736072)
		(width 0.14224)
		(layer "In6.Cu")
		(net "CLK_100M_RETIMER_CPU1_P3_R_DP")
	)
	(segment
		(start 111.259366 -397.312388)
		(end 110.957868 -397.613886)
		(width 0.14224)
		(layer "In6.Cu")
		(net "CLK_100M_RETIMER_CPU1_P3_R_DP")
	)
	(segment
		(start 110.959392 -390.045956)
		(end 110.885224 -390.225026)
		(width 0.14224)
		(layer "In6.Cu")
		(net "CLK_100M_RETIMER_CPU1_P3_R_DP")
	)
	(segment
		(start 108.673646 -387.498844)
		(end 109.253782 -387.498844)
		(width 0.14224)
		(layer "In6.Cu")
		(net "CLK_100M_RETIMER_CPU1_P3_R_DP")
	)
	(segment
		(start 111.919004 -396.65275)
		(end 111.755428 -396.816326)
		(width 0.14224)
		(layer "In6.Cu")
		(net "CLK_100M_RETIMER_CPU1_P3_R_DP")
	)
	(segment
		(start 110.051342 -388.296404)
		(end 110.364524 -388.609586)
		(width 0.14224)
		(layer "In6.Cu")
		(net "CLK_100M_RETIMER_CPU1_P3_R_DP")
	)
	(segment
		(start 111.919004 -394.45819)
		(end 111.919004 -394.97889)
		(width 0.14224)
		(layer "In6.Cu")
		(net "CLK_100M_RETIMER_CPU1_P3_R_DP")
	)
	(segment
		(start 110.820708 -398.937734)
		(end 110.820708 -399.364454)
		(width 0.14224)
		(layer "In6.Cu")
		(net "CLK_100M_RETIMER_CPU1_P3_R_DP")
	)
	(segment
		(start 111.86668 -409.330906)
		(end 111.231934 -409.330906)
		(width 0.14224)
		(layer "In6.Cu")
		(net "CLK_100M_RETIMER_CPU1_P3_R_DP")
	)
	(segment
		(start 110.957868 -397.613886)
		(end 110.957868 -398.800574)
		(width 0.14224)
		(layer "In6.Cu")
		(net "CLK_100M_RETIMER_CPU1_P3_R_DP")
	)
	(segment
		(start 110.957868 -400.629374)
		(end 110.957868 -401.056094)
		(width 0.14224)
		(layer "In6.Cu")
		(net "CLK_100M_RETIMER_CPU1_P3_R_DP")
	)
	(segment
		(start 110.364524 -388.609586)
		(end 110.527592 -389.003794)
		(width 0.14224)
		(layer "In6.Cu")
		(net "CLK_100M_RETIMER_CPU1_P3_R_DP")
	)
	(segment
		(start 111.781844 -395.11605)
		(end 111.781844 -395.54277)
		(width 0.14224)
		(layer "In6.Cu")
		(net "CLK_100M_RETIMER_CPU1_P3_R_DP")
	)
	(segment
		(start 111.231934 -409.330906)
		(end 110.941104 -409.040076)
		(width 0.14224)
		(layer "In6.Cu")
		(net "CLK_100M_RETIMER_CPU1_P3_R_DP")
	)
	(segment
		(start 111.390938 -391.088118)
		(end 111.31677 -391.267188)
		(width 0.14224)
		(layer "In6.Cu")
		(net "CLK_100M_RETIMER_CPU1_P3_R_DP")
	)
	(segment
		(start 110.820708 -403.448774)
		(end 110.820708 -403.875494)
		(width 0.14224)
		(layer "In6.Cu")
		(net "CLK_100M_RETIMER_CPU1_P3_R_DP")
	)
	(segment
		(start 112.2553 -408.206702)
		(end 112.2553 -408.942286)
		(width 0.14224)
		(layer "In6.Cu")
		(net "CLK_100M_RETIMER_CPU1_P3_R_DP")
	)
	(segment
		(start 109.116114 -387.196584)
		(end 109.361224 -386.951474)
		(width 0.12954)
		(layer "F.Cu")
		(net "CLK_100M_RETIMER_CPU1_P3_R_DN")
	)
	(segment
		(start 108.839762 -409.382214)
		(end 108.928662 -409.293314)
		(width 0.12954)
		(layer "F.Cu")
		(net "CLK_100M_RETIMER_CPU1_P3_R_DN")
	)
	(segment
		(start 108.928662 -409.293314)
		(end 109.652816 -409.293314)
		(width 0.12954)
		(layer "F.Cu")
		(net "CLK_100M_RETIMER_CPU1_P3_R_DN")
	)
	(segment
		(start 108.621322 -409.382214)
		(end 108.839762 -409.382214)
		(width 0.12954)
		(layer "F.Cu")
		(net "CLK_100M_RETIMER_CPU1_P3_R_DN")
	)
	(segment
		(start 108.382816 -386.926074)
		(end 108.653326 -387.196584)
		(width 0.12954)
		(layer "F.Cu")
		(net "CLK_100M_RETIMER_CPU1_P3_R_DN")
	)
	(segment
		(start 109.992668 -409.633166)
		(end 110.670594 -409.633166)
		(width 0.12954)
		(layer "F.Cu")
		(net "CLK_100M_RETIMER_CPU1_P3_R_DN")
	)
	(segment
		(start 110.670594 -409.633166)
		(end 110.941104 -409.903676)
		(width 0.12954)
		(layer "F.Cu")
		(net "CLK_100M_RETIMER_CPU1_P3_R_DN")
	)
	(segment
		(start 108.653326 -387.196584)
		(end 109.116114 -387.196584)
		(width 0.12954)
		(layer "F.Cu")
		(net "CLK_100M_RETIMER_CPU1_P3_R_DN")
	)
	(segment
		(start 109.652816 -409.293314)
		(end 109.992668 -409.633166)
		(width 0.12954)
		(layer "F.Cu")
		(net "CLK_100M_RETIMER_CPU1_P3_R_DN")
	)
	(via
		(at 108.382816 -386.926074)
		(size 0.508)
		(drill 0.254)
		(layers "F.Cu" "B.Cu")
		(net "CLK_100M_RETIMER_CPU1_P3_R_DN")
	)
	(via
		(at 110.941104 -409.903676)
		(size 0.508)
		(drill 0.254)
		(layers "F.Cu" "B.Cu")
		(net "CLK_100M_RETIMER_CPU1_P3_R_DN")
	)
	(segment
		(start 111.239808 -397.730726)
		(end 111.239808 -406.79243)
		(width 0.14224)
		(layer "In6.Cu")
		(net "CLK_100M_RETIMER_CPU1_P3_R_DN")
	)
	(segment
		(start 112.53724 -409.059126)
		(end 111.98352 -409.612846)
		(width 0.14224)
		(layer "In6.Cu")
		(net "CLK_100M_RETIMER_CPU1_P3_R_DN")
	)
	(segment
		(start 112.200944 -392.306556)
		(end 112.200944 -396.76959)
		(width 0.14224)
		(layer "In6.Cu")
		(net "CLK_100M_RETIMER_CPU1_P3_R_DN")
	)
	(segment
		(start 111.98352 -409.612846)
		(end 111.231934 -409.612846)
		(width 0.14224)
		(layer "In6.Cu")
		(net "CLK_100M_RETIMER_CPU1_P3_R_DN")
	)
	(segment
		(start 109.370622 -387.216904)
		(end 110.603538 -388.44982)
		(width 0.14224)
		(layer "In6.Cu")
		(net "CLK_100M_RETIMER_CPU1_P3_R_DN")
	)
	(segment
		(start 111.239808 -406.79243)
		(end 112.53724 -408.089862)
		(width 0.14224)
		(layer "In6.Cu")
		(net "CLK_100M_RETIMER_CPU1_P3_R_DN")
	)
	(segment
		(start 111.231934 -409.612846)
		(end 110.941104 -409.903676)
		(width 0.14224)
		(layer "In6.Cu")
		(net "CLK_100M_RETIMER_CPU1_P3_R_DN")
	)
	(segment
		(start 112.53724 -408.089862)
		(end 112.53724 -409.059126)
		(width 0.14224)
		(layer "In6.Cu")
		(net "CLK_100M_RETIMER_CPU1_P3_R_DN")
	)
	(segment
		(start 112.200944 -396.76959)
		(end 111.239808 -397.730726)
		(width 0.14224)
		(layer "In6.Cu")
		(net "CLK_100M_RETIMER_CPU1_P3_R_DN")
	)
	(segment
		(start 108.673646 -387.216904)
		(end 109.370622 -387.216904)
		(width 0.14224)
		(layer "In6.Cu")
		(net "CLK_100M_RETIMER_CPU1_P3_R_DN")
	)
	(segment
		(start 108.382816 -386.926074)
		(end 108.673646 -387.216904)
		(width 0.14224)
		(layer "In6.Cu")
		(net "CLK_100M_RETIMER_CPU1_P3_R_DN")
	)
	(segment
		(start 110.603538 -388.44982)
		(end 112.200944 -392.306556)
		(width 0.14224)
		(layer "In6.Cu")
		(net "CLK_100M_RETIMER_CPU1_P3_R_DN")
	)
	(segment
		(start 111.268256 -387.506972)
		(end 111.577374 -387.81609)
		(width 0.12954)
		(layer "F.Cu")
		(net "CLK_100M_RETIMER_CPU1_P3_DP")
	)
	(segment
		(start 110.901226 -387.506972)
		(end 111.268256 -387.506972)
		(width 0.12954)
		(layer "F.Cu")
		(net "CLK_100M_RETIMER_CPU1_P3_DP")
	)
	(segment
		(start 112.597946 -387.747002)
		(end 112.68202 -387.831076)
		(width 0.1016)
		(layer "F.Cu")
		(net "CLK_100M_RETIMER_CPU1_P3_DP")
	)
	(segment
		(start 110.643924 -387.764274)
		(end 110.901226 -387.506972)
		(width 0.12954)
		(layer "F.Cu")
		(net "CLK_100M_RETIMER_CPU1_P3_DP")
	)
	(segment
		(start 112.392206 -387.747002)
		(end 112.597946 -387.747002)
		(width 0.1016)
		(layer "F.Cu")
		(net "CLK_100M_RETIMER_CPU1_P3_DP")
	)
	(segment
		(start 112.323118 -387.81609)
		(end 112.392206 -387.747002)
		(width 0.1016)
		(layer "F.Cu")
		(net "CLK_100M_RETIMER_CPU1_P3_DP")
	)
	(segment
		(start 110.398052 -387.518402)
		(end 110.643924 -387.764274)
		(width 0.12954)
		(layer "F.Cu")
		(net "CLK_100M_RETIMER_CPU1_P3_DP")
	)
	(segment
		(start 111.577374 -387.81609)
		(end 112.323118 -387.81609)
		(width 0.12954)
		(layer "F.Cu")
		(net "CLK_100M_RETIMER_CPU1_P3_DP")
	)
	(segment
		(start 109.894624 -387.764274)
		(end 110.140496 -387.518402)
		(width 0.12954)
		(layer "F.Cu")
		(net "CLK_100M_RETIMER_CPU1_P3_DP")
	)
	(segment
		(start 110.140496 -387.518402)
		(end 110.398052 -387.518402)
		(width 0.12954)
		(layer "F.Cu")
		(net "CLK_100M_RETIMER_CPU1_P3_DP")
	)
	(segment
		(start 111.711232 -387.49351)
		(end 112.304068 -387.49351)
		(width 0.12954)
		(layer "F.Cu")
		(net "CLK_100M_RETIMER_CPU1_P3_DN")
	)
	(segment
		(start 110.399576 -387.195822)
		(end 110.643924 -386.951474)
		(width 0.12954)
		(layer "F.Cu")
		(net "CLK_100M_RETIMER_CPU1_P3_DN")
	)
	(segment
		(start 110.643924 -386.951474)
		(end 110.876842 -387.184392)
		(width 0.12954)
		(layer "F.Cu")
		(net "CLK_100M_RETIMER_CPU1_P3_DN")
	)
	(segment
		(start 111.402114 -387.184392)
		(end 111.711232 -387.49351)
		(width 0.12954)
		(layer "F.Cu")
		(net "CLK_100M_RETIMER_CPU1_P3_DN")
	)
	(segment
		(start 110.876842 -387.184392)
		(end 111.402114 -387.184392)
		(width 0.12954)
		(layer "F.Cu")
		(net "CLK_100M_RETIMER_CPU1_P3_DN")
	)
	(segment
		(start 109.894624 -386.951474)
		(end 110.138972 -387.195822)
		(width 0.12954)
		(layer "F.Cu")
		(net "CLK_100M_RETIMER_CPU1_P3_DN")
	)
	(segment
		(start 110.138972 -387.195822)
		(end 110.399576 -387.195822)
		(width 0.12954)
		(layer "F.Cu")
		(net "CLK_100M_RETIMER_CPU1_P3_DN")
	)
	(segment
		(start 112.304068 -387.49351)
		(end 112.34166 -387.531102)
		(width 0.1016)
		(layer "F.Cu")
		(net "CLK_100M_RETIMER_CPU1_P3_DN")
	)
	(segment
		(start 112.34166 -387.531102)
		(end 113.201704 -387.531102)
		(width 0.1016)
		(layer "F.Cu")
		(net "CLK_100M_RETIMER_CPU1_P3_DN")
	)
	(segment
		(start 141.643862 -387.519164)
		(end 141.888972 -387.764274)
		(width 0.12954)
		(layer "F.Cu")
		(net "CLK_100M_RETIMER_CPU1_P2_R_DP")
	)
	(segment
		(start 106.996484 -407.25725)
		(end 106.996484 -407.07437)
		(width 0.12954)
		(layer "F.Cu")
		(net "CLK_100M_RETIMER_CPU1_P2_R_DP")
	)
	(segment
		(start 107.476036 -405.510492)
		(end 107.205526 -405.239982)
		(width 0.12954)
		(layer "F.Cu")
		(net "CLK_100M_RETIMER_CPU1_P2_R_DP")
	)
	(segment
		(start 107.476036 -406.232614)
		(end 107.476036 -405.510492)
		(width 0.12954)
		(layer "F.Cu")
		(net "CLK_100M_RETIMER_CPU1_P2_R_DP")
	)
	(segment
		(start 107.08513 -406.985724)
		(end 107.08513 -406.62352)
		(width 0.12954)
		(layer "F.Cu")
		(net "CLK_100M_RETIMER_CPU1_P2_R_DP")
	)
	(segment
		(start 106.996484 -407.07437)
		(end 107.08513 -406.985724)
		(width 0.12954)
		(layer "F.Cu")
		(net "CLK_100M_RETIMER_CPU1_P2_R_DP")
	)
	(segment
		(start 141.181074 -387.519164)
		(end 141.643862 -387.519164)
		(width 0.12954)
		(layer "F.Cu")
		(net "CLK_100M_RETIMER_CPU1_P2_R_DP")
	)
	(segment
		(start 107.08513 -406.62352)
		(end 107.476036 -406.232614)
		(width 0.12954)
		(layer "F.Cu")
		(net "CLK_100M_RETIMER_CPU1_P2_R_DP")
	)
	(segment
		(start 140.910564 -387.789674)
		(end 141.181074 -387.519164)
		(width 0.12954)
		(layer "F.Cu")
		(net "CLK_100M_RETIMER_CPU1_P2_R_DP")
	)
	(via
		(at 140.910564 -387.789674)
		(size 0.508)
		(drill 0.254)
		(layers "F.Cu" "B.Cu")
		(net "CLK_100M_RETIMER_CPU1_P2_R_DP")
	)
	(via
		(at 107.205526 -405.239982)
		(size 0.508)
		(drill 0.254)
		(layers "F.Cu" "B.Cu")
		(net "CLK_100M_RETIMER_CPU1_P2_R_DP")
	)
	(segment
		(start 132.156454 -383.106676)
		(end 132.156454 -382.55448)
		(width 0.14224)
		(layer "In6.Cu")
		(net "CLK_100M_RETIMER_CPU1_P2_R_DP")
	)
	(segment
		(start 110.12932 -404.293324)
		(end 110.12932 -405.548592)
		(width 0.14224)
		(layer "In6.Cu")
		(net "CLK_100M_RETIMER_CPU1_P2_R_DP")
	)
	(segment
		(start 140.910564 -387.789674)
		(end 140.619734 -387.498844)
		(width 0.14224)
		(layer "In6.Cu")
		(net "CLK_100M_RETIMER_CPU1_P2_R_DP")
	)
	(segment
		(start 136.445498 -387.864096)
		(end 135.417052 -387.864096)
		(width 0.14224)
		(layer "In6.Cu")
		(net "CLK_100M_RETIMER_CPU1_P2_R_DP")
	)
	(segment
		(start 105.761536 -399.92554)
		(end 110.12932 -404.293324)
		(width 0.14224)
		(layer "In6.Cu")
		(net "CLK_100M_RETIMER_CPU1_P2_R_DP")
	)
	(segment
		(start 136.582658 -388.001256)
		(end 136.445498 -387.864096)
		(width 0.14224)
		(layer "In6.Cu")
		(net "CLK_100M_RETIMER_CPU1_P2_R_DP")
	)
	(segment
		(start 106.13009 -396.937992)
		(end 105.761536 -397.306546)
		(width 0.14224)
		(layer "In6.Cu")
		(net "CLK_100M_RETIMER_CPU1_P2_R_DP")
	)
	(segment
		(start 125.42266 -382.12649)
		(end 112.649254 -382.12649)
		(width 0.14224)
		(layer "In6.Cu")
		(net "CLK_100M_RETIMER_CPU1_P2_R_DP")
	)
	(segment
		(start 137.146538 -387.864096)
		(end 137.009378 -388.001256)
		(width 0.14224)
		(layer "In6.Cu")
		(net "CLK_100M_RETIMER_CPU1_P2_R_DP")
	)
	(segment
		(start 128.999234 -382.12649)
		(end 128.862074 -382.26365)
		(width 0.14224)
		(layer "In6.Cu")
		(net "CLK_100M_RETIMER_CPU1_P2_R_DP")
	)
	(segment
		(start 110.11535 -384.137916)
		(end 110.11535 -385.053586)
		(width 0.14224)
		(layer "In6.Cu")
		(net "CLK_100M_RETIMER_CPU1_P2_R_DP")
	)
	(segment
		(start 111.53394 -383.241804)
		(end 111.011462 -383.241804)
		(width 0.14224)
		(layer "In6.Cu")
		(net "CLK_100M_RETIMER_CPU1_P2_R_DP")
	)
	(segment
		(start 107.310428 -386.442966)
		(end 106.825796 -386.927598)
		(width 0.14224)
		(layer "In6.Cu")
		(net "CLK_100M_RETIMER_CPU1_P2_R_DP")
	)
	(segment
		(start 127.25146 -382.12649)
		(end 127.1143 -382.26365)
		(width 0.14224)
		(layer "In6.Cu")
		(net "CLK_100M_RETIMER_CPU1_P2_R_DP")
	)
	(segment
		(start 140.349478 -387.498844)
		(end 140.144246 -387.293612)
		(width 0.14224)
		(layer "In6.Cu")
		(net "CLK_100M_RETIMER_CPU1_P2_R_DP")
	)
	(segment
		(start 107.496356 -405.530812)
		(end 107.205526 -405.239982)
		(width 0.14224)
		(layer "In6.Cu")
		(net "CLK_100M_RETIMER_CPU1_P2_R_DP")
	)
	(segment
		(start 104.92359 -393.79906)
		(end 106.13009 -395.00556)
		(width 0.14224)
		(layer "In6.Cu")
		(net "CLK_100M_RETIMER_CPU1_P2_R_DP")
	)
	(segment
		(start 131.728464 -382.12649)
		(end 128.999234 -382.12649)
		(width 0.14224)
		(layer "In6.Cu")
		(net "CLK_100M_RETIMER_CPU1_P2_R_DP")
	)
	(segment
		(start 106.825796 -387.345936)
		(end 105.193084 -388.978648)
		(width 0.14224)
		(layer "In6.Cu")
		(net "CLK_100M_RETIMER_CPU1_P2_R_DP")
	)
	(segment
		(start 110.11535 -385.053586)
		(end 109.31017 -385.858766)
		(width 0.14224)
		(layer "In6.Cu")
		(net "CLK_100M_RETIMER_CPU1_P2_R_DP")
	)
	(segment
		(start 112.649254 -382.12649)
		(end 111.53394 -383.241804)
		(width 0.14224)
		(layer "In6.Cu")
		(net "CLK_100M_RETIMER_CPU1_P2_R_DP")
	)
	(segment
		(start 111.011462 -383.241804)
		(end 110.11535 -384.137916)
		(width 0.14224)
		(layer "In6.Cu")
		(net "CLK_100M_RETIMER_CPU1_P2_R_DP")
	)
	(segment
		(start 128.862074 -382.26365)
		(end 128.435354 -382.26365)
		(width 0.14224)
		(layer "In6.Cu")
		(net "CLK_100M_RETIMER_CPU1_P2_R_DP")
	)
	(segment
		(start 127.1143 -382.26365)
		(end 126.68758 -382.26365)
		(width 0.14224)
		(layer "In6.Cu")
		(net "CLK_100M_RETIMER_CPU1_P2_R_DP")
	)
	(segment
		(start 104.92359 -390.986518)
		(end 104.92359 -393.79906)
		(width 0.14224)
		(layer "In6.Cu")
		(net "CLK_100M_RETIMER_CPU1_P2_R_DP")
	)
	(segment
		(start 132.156454 -382.55448)
		(end 131.728464 -382.12649)
		(width 0.14224)
		(layer "In6.Cu")
		(net "CLK_100M_RETIMER_CPU1_P2_R_DP")
	)
	(segment
		(start 140.144246 -387.293612)
		(end 138.661902 -387.293612)
		(width 0.14224)
		(layer "In6.Cu")
		(net "CLK_100M_RETIMER_CPU1_P2_R_DP")
	)
	(segment
		(start 107.496356 -406.082246)
		(end 107.496356 -405.530812)
		(width 0.14224)
		(layer "In6.Cu")
		(net "CLK_100M_RETIMER_CPU1_P2_R_DP")
	)
	(segment
		(start 135.417052 -387.864096)
		(end 134.331202 -386.778246)
		(width 0.14224)
		(layer "In6.Cu")
		(net "CLK_100M_RETIMER_CPU1_P2_R_DP")
	)
	(segment
		(start 110.12932 -405.548592)
		(end 109.008164 -406.669748)
		(width 0.14224)
		(layer "In6.Cu")
		(net "CLK_100M_RETIMER_CPU1_P2_R_DP")
	)
	(segment
		(start 106.13009 -395.00556)
		(end 106.13009 -396.937992)
		(width 0.14224)
		(layer "In6.Cu")
		(net "CLK_100M_RETIMER_CPU1_P2_R_DP")
	)
	(segment
		(start 105.193084 -388.978648)
		(end 105.193084 -390.717024)
		(width 0.14224)
		(layer "In6.Cu")
		(net "CLK_100M_RETIMER_CPU1_P2_R_DP")
	)
	(segment
		(start 109.31017 -385.858766)
		(end 107.899708 -386.442966)
		(width 0.14224)
		(layer "In6.Cu")
		(net "CLK_100M_RETIMER_CPU1_P2_R_DP")
	)
	(segment
		(start 105.761536 -397.306546)
		(end 105.761536 -399.92554)
		(width 0.14224)
		(layer "In6.Cu")
		(net "CLK_100M_RETIMER_CPU1_P2_R_DP")
	)
	(segment
		(start 108.083858 -406.669748)
		(end 107.496356 -406.082246)
		(width 0.14224)
		(layer "In6.Cu")
		(net "CLK_100M_RETIMER_CPU1_P2_R_DP")
	)
	(segment
		(start 138.091418 -387.864096)
		(end 137.146538 -387.864096)
		(width 0.14224)
		(layer "In6.Cu")
		(net "CLK_100M_RETIMER_CPU1_P2_R_DP")
	)
	(segment
		(start 134.331202 -386.778246)
		(end 133.27253 -384.222752)
		(width 0.14224)
		(layer "In6.Cu")
		(net "CLK_100M_RETIMER_CPU1_P2_R_DP")
	)
	(segment
		(start 125.55982 -382.26365)
		(end 125.42266 -382.12649)
		(width 0.14224)
		(layer "In6.Cu")
		(net "CLK_100M_RETIMER_CPU1_P2_R_DP")
	)
	(segment
		(start 125.98654 -382.26365)
		(end 125.55982 -382.26365)
		(width 0.14224)
		(layer "In6.Cu")
		(net "CLK_100M_RETIMER_CPU1_P2_R_DP")
	)
	(segment
		(start 126.68758 -382.26365)
		(end 126.55042 -382.12649)
		(width 0.14224)
		(layer "In6.Cu")
		(net "CLK_100M_RETIMER_CPU1_P2_R_DP")
	)
	(segment
		(start 126.55042 -382.12649)
		(end 126.1237 -382.12649)
		(width 0.14224)
		(layer "In6.Cu")
		(net "CLK_100M_RETIMER_CPU1_P2_R_DP")
	)
	(segment
		(start 138.661902 -387.293612)
		(end 138.091418 -387.864096)
		(width 0.14224)
		(layer "In6.Cu")
		(net "CLK_100M_RETIMER_CPU1_P2_R_DP")
	)
	(segment
		(start 105.193084 -390.717024)
		(end 104.92359 -390.986518)
		(width 0.14224)
		(layer "In6.Cu")
		(net "CLK_100M_RETIMER_CPU1_P2_R_DP")
	)
	(segment
		(start 133.27253 -384.222752)
		(end 132.156454 -383.106676)
		(width 0.14224)
		(layer "In6.Cu")
		(net "CLK_100M_RETIMER_CPU1_P2_R_DP")
	)
	(segment
		(start 128.298194 -382.12649)
		(end 127.25146 -382.12649)
		(width 0.14224)
		(layer "In6.Cu")
		(net "CLK_100M_RETIMER_CPU1_P2_R_DP")
	)
	(segment
		(start 126.1237 -382.12649)
		(end 125.98654 -382.26365)
		(width 0.14224)
		(layer "In6.Cu")
		(net "CLK_100M_RETIMER_CPU1_P2_R_DP")
	)
	(segment
		(start 109.008164 -406.669748)
		(end 108.083858 -406.669748)
		(width 0.14224)
		(layer "In6.Cu")
		(net "CLK_100M_RETIMER_CPU1_P2_R_DP")
	)
	(segment
		(start 107.899708 -386.442966)
		(end 107.310428 -386.442966)
		(width 0.14224)
		(layer "In6.Cu")
		(net "CLK_100M_RETIMER_CPU1_P2_R_DP")
	)
	(segment
		(start 106.825796 -386.927598)
		(end 106.825796 -387.345936)
		(width 0.14224)
		(layer "In6.Cu")
		(net "CLK_100M_RETIMER_CPU1_P2_R_DP")
	)
	(segment
		(start 128.435354 -382.26365)
		(end 128.298194 -382.12649)
		(width 0.14224)
		(layer "In6.Cu")
		(net "CLK_100M_RETIMER_CPU1_P2_R_DP")
	)
	(segment
		(start 137.009378 -388.001256)
		(end 136.582658 -388.001256)
		(width 0.14224)
		(layer "In6.Cu")
		(net "CLK_100M_RETIMER_CPU1_P2_R_DP")
	)
	(segment
		(start 140.619734 -387.498844)
		(end 140.349478 -387.498844)
		(width 0.14224)
		(layer "In6.Cu")
		(net "CLK_100M_RETIMER_CPU1_P2_R_DP")
	)
	(segment
		(start 107.496356 -407.25725)
		(end 107.496356 -407.06421)
		(width 0.12954)
		(layer "F.Cu")
		(net "CLK_100M_RETIMER_CPU1_P2_R_DN")
	)
	(segment
		(start 107.496356 -407.06421)
		(end 107.40771 -406.975564)
		(width 0.12954)
		(layer "F.Cu")
		(net "CLK_100M_RETIMER_CPU1_P2_R_DN")
	)
	(segment
		(start 140.910564 -386.926074)
		(end 141.181074 -387.196584)
		(width 0.12954)
		(layer "F.Cu")
		(net "CLK_100M_RETIMER_CPU1_P2_R_DN")
	)
	(segment
		(start 107.798616 -405.510492)
		(end 108.069126 -405.239982)
		(width 0.12954)
		(layer "F.Cu")
		(net "CLK_100M_RETIMER_CPU1_P2_R_DN")
	)
	(segment
		(start 141.643862 -387.196584)
		(end 141.888972 -386.951474)
		(width 0.12954)
		(layer "F.Cu")
		(net "CLK_100M_RETIMER_CPU1_P2_R_DN")
	)
	(segment
		(start 107.798616 -406.366472)
		(end 107.798616 -405.510492)
		(width 0.12954)
		(layer "F.Cu")
		(net "CLK_100M_RETIMER_CPU1_P2_R_DN")
	)
	(segment
		(start 107.40771 -406.975564)
		(end 107.40771 -406.757378)
		(width 0.12954)
		(layer "F.Cu")
		(net "CLK_100M_RETIMER_CPU1_P2_R_DN")
	)
	(segment
		(start 141.181074 -387.196584)
		(end 141.643862 -387.196584)
		(width 0.12954)
		(layer "F.Cu")
		(net "CLK_100M_RETIMER_CPU1_P2_R_DN")
	)
	(segment
		(start 107.40771 -406.757378)
		(end 107.798616 -406.366472)
		(width 0.12954)
		(layer "F.Cu")
		(net "CLK_100M_RETIMER_CPU1_P2_R_DN")
	)
	(via
		(at 140.910564 -386.926074)
		(size 0.508)
		(drill 0.254)
		(layers "F.Cu" "B.Cu")
		(net "CLK_100M_RETIMER_CPU1_P2_R_DN")
	)
	(via
		(at 108.069126 -405.239982)
		(size 0.508)
		(drill 0.254)
		(layers "F.Cu" "B.Cu")
		(net "CLK_100M_RETIMER_CPU1_P2_R_DN")
	)
	(segment
		(start 104.64165 -391.51687)
		(end 104.53243 -391.62609)
		(width 0.14224)
		(layer "In6.Cu")
		(net "CLK_100M_RETIMER_CPU1_P2_R_DN")
	)
	(segment
		(start 104.911144 -388.861808)
		(end 104.911144 -390.600184)
		(width 0.14224)
		(layer "In6.Cu")
		(net "CLK_100M_RETIMER_CPU1_P2_R_DN")
	)
	(segment
		(start 105.84815 -395.1224)
		(end 105.84815 -396.821152)
		(width 0.14224)
		(layer "In6.Cu")
		(net "CLK_100M_RETIMER_CPU1_P2_R_DN")
	)
	(segment
		(start 105.84815 -396.821152)
		(end 105.479596 -397.189706)
		(width 0.14224)
		(layer "In6.Cu")
		(net "CLK_100M_RETIMER_CPU1_P2_R_DN")
	)
	(segment
		(start 112.532414 -381.84455)
		(end 111.4171 -382.959864)
		(width 0.14224)
		(layer "In6.Cu")
		(net "CLK_100M_RETIMER_CPU1_P2_R_DN")
	)
	(segment
		(start 104.911144 -390.600184)
		(end 104.64165 -390.869678)
		(width 0.14224)
		(layer "In6.Cu")
		(net "CLK_100M_RETIMER_CPU1_P2_R_DN")
	)
	(segment
		(start 134.570216 -386.61848)
		(end 133.511544 -384.062986)
		(width 0.14224)
		(layer "In6.Cu")
		(net "CLK_100M_RETIMER_CPU1_P2_R_DN")
	)
	(segment
		(start 109.83341 -384.936746)
		(end 109.150404 -385.619752)
		(width 0.14224)
		(layer "In6.Cu")
		(net "CLK_100M_RETIMER_CPU1_P2_R_DN")
	)
	(segment
		(start 104.64165 -392.632184)
		(end 104.523794 -392.75004)
		(width 0.14224)
		(layer "In6.Cu")
		(net "CLK_100M_RETIMER_CPU1_P2_R_DN")
	)
	(segment
		(start 132.438394 -382.989836)
		(end 132.438394 -382.43764)
		(width 0.14224)
		(layer "In6.Cu")
		(net "CLK_100M_RETIMER_CPU1_P2_R_DN")
	)
	(segment
		(start 106.543856 -387.229096)
		(end 104.911144 -388.861808)
		(width 0.14224)
		(layer "In6.Cu")
		(net "CLK_100M_RETIMER_CPU1_P2_R_DN")
	)
	(segment
		(start 105.342436 -399.05178)
		(end 105.342436 -399.4785)
		(width 0.14224)
		(layer "In6.Cu")
		(net "CLK_100M_RETIMER_CPU1_P2_R_DN")
	)
	(segment
		(start 109.150404 -385.619752)
		(end 107.843574 -386.161026)
		(width 0.14224)
		(layer "In6.Cu")
		(net "CLK_100M_RETIMER_CPU1_P2_R_DN")
	)
	(segment
		(start 108.200698 -406.387808)
		(end 107.778296 -405.965406)
		(width 0.14224)
		(layer "In6.Cu")
		(net "CLK_100M_RETIMER_CPU1_P2_R_DN")
	)
	(segment
		(start 138.545062 -387.011672)
		(end 137.974578 -387.582156)
		(width 0.14224)
		(layer "In6.Cu")
		(net "CLK_100M_RETIMER_CPU1_P2_R_DN")
	)
	(segment
		(start 109.84738 -405.431752)
		(end 108.891324 -406.387808)
		(width 0.14224)
		(layer "In6.Cu")
		(net "CLK_100M_RETIMER_CPU1_P2_R_DN")
	)
	(segment
		(start 140.619734 -387.216904)
		(end 140.466318 -387.216904)
		(width 0.14224)
		(layer "In6.Cu")
		(net "CLK_100M_RETIMER_CPU1_P2_R_DN")
	)
	(segment
		(start 106.543856 -386.810758)
		(end 106.543856 -387.229096)
		(width 0.14224)
		(layer "In6.Cu")
		(net "CLK_100M_RETIMER_CPU1_P2_R_DN")
	)
	(segment
		(start 104.64165 -393.294616)
		(end 104.64165 -393.9159)
		(width 0.14224)
		(layer "In6.Cu")
		(net "CLK_100M_RETIMER_CPU1_P2_R_DN")
	)
	(segment
		(start 105.479596 -399.61566)
		(end 105.479596 -400.04238)
		(width 0.14224)
		(layer "In6.Cu")
		(net "CLK_100M_RETIMER_CPU1_P2_R_DN")
	)
	(segment
		(start 105.479596 -397.189706)
		(end 105.479596 -397.78686)
		(width 0.14224)
		(layer "In6.Cu")
		(net "CLK_100M_RETIMER_CPU1_P2_R_DN")
	)
	(segment
		(start 137.974578 -387.582156)
		(end 135.533892 -387.582156)
		(width 0.14224)
		(layer "In6.Cu")
		(net "CLK_100M_RETIMER_CPU1_P2_R_DN")
	)
	(segment
		(start 104.523794 -393.17676)
		(end 104.64165 -393.294616)
		(width 0.14224)
		(layer "In6.Cu")
		(net "CLK_100M_RETIMER_CPU1_P2_R_DN")
	)
	(segment
		(start 107.778296 -405.530812)
		(end 108.069126 -405.239982)
		(width 0.14224)
		(layer "In6.Cu")
		(net "CLK_100M_RETIMER_CPU1_P2_R_DN")
	)
	(segment
		(start 109.83341 -384.021076)
		(end 109.83341 -384.936746)
		(width 0.14224)
		(layer "In6.Cu")
		(net "CLK_100M_RETIMER_CPU1_P2_R_DN")
	)
	(segment
		(start 140.466318 -387.216904)
		(end 140.261086 -387.011672)
		(width 0.14224)
		(layer "In6.Cu")
		(net "CLK_100M_RETIMER_CPU1_P2_R_DN")
	)
	(segment
		(start 105.479596 -398.4879)
		(end 105.479596 -398.91462)
		(width 0.14224)
		(layer "In6.Cu")
		(net "CLK_100M_RETIMER_CPU1_P2_R_DN")
	)
	(segment
		(start 135.533892 -387.582156)
		(end 134.570216 -386.61848)
		(width 0.14224)
		(layer "In6.Cu")
		(net "CLK_100M_RETIMER_CPU1_P2_R_DN")
	)
	(segment
		(start 108.891324 -406.387808)
		(end 108.200698 -406.387808)
		(width 0.14224)
		(layer "In6.Cu")
		(net "CLK_100M_RETIMER_CPU1_P2_R_DN")
	)
	(segment
		(start 110.894622 -382.959864)
		(end 109.83341 -384.021076)
		(width 0.14224)
		(layer "In6.Cu")
		(net "CLK_100M_RETIMER_CPU1_P2_R_DN")
	)
	(segment
		(start 105.342436 -397.92402)
		(end 105.342436 -398.35074)
		(width 0.14224)
		(layer "In6.Cu")
		(net "CLK_100M_RETIMER_CPU1_P2_R_DN")
	)
	(segment
		(start 104.64165 -393.9159)
		(end 105.84815 -395.1224)
		(width 0.14224)
		(layer "In6.Cu")
		(net "CLK_100M_RETIMER_CPU1_P2_R_DN")
	)
	(segment
		(start 107.778296 -405.965406)
		(end 107.778296 -405.530812)
		(width 0.14224)
		(layer "In6.Cu")
		(net "CLK_100M_RETIMER_CPU1_P2_R_DN")
	)
	(segment
		(start 140.910564 -386.926074)
		(end 140.619734 -387.216904)
		(width 0.14224)
		(layer "In6.Cu")
		(net "CLK_100M_RETIMER_CPU1_P2_R_DN")
	)
	(segment
		(start 105.479596 -398.91462)
		(end 105.342436 -399.05178)
		(width 0.14224)
		(layer "In6.Cu")
		(net "CLK_100M_RETIMER_CPU1_P2_R_DN")
	)
	(segment
		(start 105.342436 -398.35074)
		(end 105.479596 -398.4879)
		(width 0.14224)
		(layer "In6.Cu")
		(net "CLK_100M_RETIMER_CPU1_P2_R_DN")
	)
	(segment
		(start 104.64165 -392.16203)
		(end 104.64165 -392.632184)
		(width 0.14224)
		(layer "In6.Cu")
		(net "CLK_100M_RETIMER_CPU1_P2_R_DN")
	)
	(segment
		(start 111.4171 -382.959864)
		(end 110.894622 -382.959864)
		(width 0.14224)
		(layer "In6.Cu")
		(net "CLK_100M_RETIMER_CPU1_P2_R_DN")
	)
	(segment
		(start 104.64165 -390.869678)
		(end 104.64165 -391.51687)
		(width 0.14224)
		(layer "In6.Cu")
		(net "CLK_100M_RETIMER_CPU1_P2_R_DN")
	)
	(segment
		(start 104.53243 -392.05281)
		(end 104.64165 -392.16203)
		(width 0.14224)
		(layer "In6.Cu")
		(net "CLK_100M_RETIMER_CPU1_P2_R_DN")
	)
	(segment
		(start 104.53243 -391.62609)
		(end 104.53243 -392.05281)
		(width 0.14224)
		(layer "In6.Cu")
		(net "CLK_100M_RETIMER_CPU1_P2_R_DN")
	)
	(segment
		(start 131.845304 -381.84455)
		(end 112.532414 -381.84455)
		(width 0.14224)
		(layer "In6.Cu")
		(net "CLK_100M_RETIMER_CPU1_P2_R_DN")
	)
	(segment
		(start 107.193588 -386.161026)
		(end 106.543856 -386.810758)
		(width 0.14224)
		(layer "In6.Cu")
		(net "CLK_100M_RETIMER_CPU1_P2_R_DN")
	)
	(segment
		(start 104.523794 -392.75004)
		(end 104.523794 -393.17676)
		(width 0.14224)
		(layer "In6.Cu")
		(net "CLK_100M_RETIMER_CPU1_P2_R_DN")
	)
	(segment
		(start 105.342436 -399.4785)
		(end 105.479596 -399.61566)
		(width 0.14224)
		(layer "In6.Cu")
		(net "CLK_100M_RETIMER_CPU1_P2_R_DN")
	)
	(segment
		(start 109.84738 -404.410164)
		(end 109.84738 -405.431752)
		(width 0.14224)
		(layer "In6.Cu")
		(net "CLK_100M_RETIMER_CPU1_P2_R_DN")
	)
	(segment
		(start 132.438394 -382.43764)
		(end 131.845304 -381.84455)
		(width 0.14224)
		(layer "In6.Cu")
		(net "CLK_100M_RETIMER_CPU1_P2_R_DN")
	)
	(segment
		(start 140.261086 -387.011672)
		(end 138.545062 -387.011672)
		(width 0.14224)
		(layer "In6.Cu")
		(net "CLK_100M_RETIMER_CPU1_P2_R_DN")
	)
	(segment
		(start 133.511544 -384.062986)
		(end 132.438394 -382.989836)
		(width 0.14224)
		(layer "In6.Cu")
		(net "CLK_100M_RETIMER_CPU1_P2_R_DN")
	)
	(segment
		(start 107.843574 -386.161026)
		(end 107.193588 -386.161026)
		(width 0.14224)
		(layer "In6.Cu")
		(net "CLK_100M_RETIMER_CPU1_P2_R_DN")
	)
	(segment
		(start 105.479596 -397.78686)
		(end 105.342436 -397.92402)
		(width 0.14224)
		(layer "In6.Cu")
		(net "CLK_100M_RETIMER_CPU1_P2_R_DN")
	)
	(segment
		(start 105.479596 -400.04238)
		(end 109.84738 -404.410164)
		(width 0.14224)
		(layer "In6.Cu")
		(net "CLK_100M_RETIMER_CPU1_P2_R_DN")
	)
	(segment
		(start 144.919954 -387.747002)
		(end 145.125694 -387.747002)
		(width 0.1016)
		(layer "F.Cu")
		(net "CLK_100M_RETIMER_CPU1_P2_DP")
	)
	(segment
		(start 145.125694 -387.747002)
		(end 145.209768 -387.831076)
		(width 0.1016)
		(layer "F.Cu")
		(net "CLK_100M_RETIMER_CPU1_P2_DP")
	)
	(segment
		(start 143.796004 -387.506972)
		(end 144.105122 -387.81609)
		(width 0.12954)
		(layer "F.Cu")
		(net "CLK_100M_RETIMER_CPU1_P2_DP")
	)
	(segment
		(start 142.422372 -387.764274)
		(end 142.668244 -387.518402)
		(width 0.12954)
		(layer "F.Cu")
		(net "CLK_100M_RETIMER_CPU1_P2_DP")
	)
	(segment
		(start 143.171672 -387.764274)
		(end 143.428974 -387.506972)
		(width 0.12954)
		(layer "F.Cu")
		(net "CLK_100M_RETIMER_CPU1_P2_DP")
	)
	(segment
		(start 142.668244 -387.518402)
		(end 142.9258 -387.518402)
		(width 0.12954)
		(layer "F.Cu")
		(net "CLK_100M_RETIMER_CPU1_P2_DP")
	)
	(segment
		(start 142.9258 -387.518402)
		(end 143.171672 -387.764274)
		(width 0.12954)
		(layer "F.Cu")
		(net "CLK_100M_RETIMER_CPU1_P2_DP")
	)
	(segment
		(start 144.850866 -387.81609)
		(end 144.919954 -387.747002)
		(width 0.1016)
		(layer "F.Cu")
		(net "CLK_100M_RETIMER_CPU1_P2_DP")
	)
	(segment
		(start 144.105122 -387.81609)
		(end 144.850866 -387.81609)
		(width 0.12954)
		(layer "F.Cu")
		(net "CLK_100M_RETIMER_CPU1_P2_DP")
	)
	(segment
		(start 143.428974 -387.506972)
		(end 143.796004 -387.506972)
		(width 0.12954)
		(layer "F.Cu")
		(net "CLK_100M_RETIMER_CPU1_P2_DP")
	)
	(segment
		(start 142.927324 -387.195822)
		(end 143.171672 -386.951474)
		(width 0.12954)
		(layer "F.Cu")
		(net "CLK_100M_RETIMER_CPU1_P2_DN")
	)
	(segment
		(start 143.929862 -387.184392)
		(end 144.23898 -387.49351)
		(width 0.12954)
		(layer "F.Cu")
		(net "CLK_100M_RETIMER_CPU1_P2_DN")
	)
	(segment
		(start 144.23898 -387.49351)
		(end 144.831816 -387.49351)
		(width 0.12954)
		(layer "F.Cu")
		(net "CLK_100M_RETIMER_CPU1_P2_DN")
	)
	(segment
		(start 143.171672 -386.951474)
		(end 143.40459 -387.184392)
		(width 0.12954)
		(layer "F.Cu")
		(net "CLK_100M_RETIMER_CPU1_P2_DN")
	)
	(segment
		(start 142.66672 -387.195822)
		(end 142.927324 -387.195822)
		(width 0.12954)
		(layer "F.Cu")
		(net "CLK_100M_RETIMER_CPU1_P2_DN")
	)
	(segment
		(start 142.422372 -386.951474)
		(end 142.66672 -387.195822)
		(width 0.12954)
		(layer "F.Cu")
		(net "CLK_100M_RETIMER_CPU1_P2_DN")
	)
	(segment
		(start 144.869408 -387.531102)
		(end 145.729452 -387.531102)
		(width 0.1016)
		(layer "F.Cu")
		(net "CLK_100M_RETIMER_CPU1_P2_DN")
	)
	(segment
		(start 143.40459 -387.184392)
		(end 143.929862 -387.184392)
		(width 0.12954)
		(layer "F.Cu")
		(net "CLK_100M_RETIMER_CPU1_P2_DN")
	)
	(segment
		(start 144.831816 -387.49351)
		(end 144.869408 -387.531102)
		(width 0.1016)
		(layer "F.Cu")
		(net "CLK_100M_RETIMER_CPU1_P2_DN")
	)
	(segment
		(start 73.810622 -387.789674)
		(end 74.081132 -387.519164)
		(width 0.12954)
		(layer "F.Cu")
		(net "CLK_100M_RETIMER_CPU1_P1_R_DP")
	)
	(segment
		(start 74.081132 -387.519164)
		(end 74.54392 -387.519164)
		(width 0.12954)
		(layer "F.Cu")
		(net "CLK_100M_RETIMER_CPU1_P1_R_DP")
	)
	(segment
		(start 105.49636 -407.100786)
		(end 105.585006 -407.01214)
		(width 0.12954)
		(layer "F.Cu")
		(net "CLK_100M_RETIMER_CPU1_P1_R_DP")
	)
	(segment
		(start 104.775 -405.638508)
		(end 104.391714 -405.638508)
		(width 0.12954)
		(layer "F.Cu")
		(net "CLK_100M_RETIMER_CPU1_P1_R_DP")
	)
	(segment
		(start 105.372408 -406.626822)
		(end 105.372408 -406.235916)
		(width 0.12954)
		(layer "F.Cu")
		(net "CLK_100M_RETIMER_CPU1_P1_R_DP")
	)
	(segment
		(start 74.54392 -387.519164)
		(end 74.78903 -387.764274)
		(width 0.12954)
		(layer "F.Cu")
		(net "CLK_100M_RETIMER_CPU1_P1_R_DP")
	)
	(segment
		(start 105.49636 -407.25725)
		(end 105.49636 -407.100786)
		(width 0.12954)
		(layer "F.Cu")
		(net "CLK_100M_RETIMER_CPU1_P1_R_DP")
	)
	(segment
		(start 105.372408 -406.235916)
		(end 104.775 -405.638508)
		(width 0.12954)
		(layer "F.Cu")
		(net "CLK_100M_RETIMER_CPU1_P1_R_DP")
	)
	(segment
		(start 105.585006 -406.83942)
		(end 105.372408 -406.626822)
		(width 0.12954)
		(layer "F.Cu")
		(net "CLK_100M_RETIMER_CPU1_P1_R_DP")
	)
	(segment
		(start 105.585006 -407.01214)
		(end 105.585006 -406.83942)
		(width 0.12954)
		(layer "F.Cu")
		(net "CLK_100M_RETIMER_CPU1_P1_R_DP")
	)
	(via
		(at 73.810622 -387.789674)
		(size 0.508)
		(drill 0.254)
		(layers "F.Cu" "B.Cu")
		(net "CLK_100M_RETIMER_CPU1_P1_R_DP")
	)
	(via
		(at 104.391714 -405.638508)
		(size 0.508)
		(drill 0.254)
		(layers "F.Cu" "B.Cu")
		(net "CLK_100M_RETIMER_CPU1_P1_R_DP")
	)
	(segment
		(start 75.208638 -387.498844)
		(end 75.345798 -387.636004)
		(width 0.14224)
		(layer "In6.Cu")
		(net "CLK_100M_RETIMER_CPU1_P1_R_DP")
	)
	(segment
		(start 96.130364 -400.137884)
		(end 98.755454 -400.137884)
		(width 0.14224)
		(layer "In6.Cu")
		(net "CLK_100M_RETIMER_CPU1_P1_R_DP")
	)
	(segment
		(start 104.391714 -405.225504)
		(end 104.391714 -405.638508)
		(width 0.14224)
		(layer "In6.Cu")
		(net "CLK_100M_RETIMER_CPU1_P1_R_DP")
	)
	(segment
		(start 78.682596 -388.95782)
		(end 78.545436 -389.09498)
		(width 0.14224)
		(layer "In6.Cu")
		(net "CLK_100M_RETIMER_CPU1_P1_R_DP")
	)
	(segment
		(start 86.115906 -394.798804)
		(end 86.542626 -394.798804)
		(width 0.14224)
		(layer "In6.Cu")
		(net "CLK_100M_RETIMER_CPU1_P1_R_DP")
	)
	(segment
		(start 99.056952 -400.633438)
		(end 99.358958 -400.935444)
		(width 0.14224)
		(layer "In6.Cu")
		(net "CLK_100M_RETIMER_CPU1_P1_R_DP")
	)
	(segment
		(start 82.031586 -394.798804)
		(end 82.168746 -394.661644)
		(width 0.14224)
		(layer "In6.Cu")
		(net "CLK_100M_RETIMER_CPU1_P1_R_DP")
	)
	(segment
		(start 78.682596 -388.325868)
		(end 78.682596 -388.95782)
		(width 0.14224)
		(layer "In6.Cu")
		(net "CLK_100M_RETIMER_CPU1_P1_R_DP")
	)
	(segment
		(start 83.296506 -394.661644)
		(end 83.723226 -394.661644)
		(width 0.14224)
		(layer "In6.Cu")
		(net "CLK_100M_RETIMER_CPU1_P1_R_DP")
	)
	(segment
		(start 80.060038 -394.661644)
		(end 81.467706 -394.661644)
		(width 0.14224)
		(layer "In6.Cu")
		(net "CLK_100M_RETIMER_CPU1_P1_R_DP")
	)
	(segment
		(start 82.732626 -394.798804)
		(end 83.159346 -394.798804)
		(width 0.14224)
		(layer "In6.Cu")
		(net "CLK_100M_RETIMER_CPU1_P1_R_DP")
	)
	(segment
		(start 98.755454 -400.137884)
		(end 99.056952 -400.439382)
		(width 0.14224)
		(layer "In6.Cu")
		(net "CLK_100M_RETIMER_CPU1_P1_R_DP")
	)
	(segment
		(start 79.508096 -391.823194)
		(end 79.437992 -391.893298)
		(width 0.14224)
		(layer "In6.Cu")
		(net "CLK_100M_RETIMER_CPU1_P1_R_DP")
	)
	(segment
		(start 100.712778 -402.095208)
		(end 100.712778 -402.28901)
		(width 0.14224)
		(layer "In6.Cu")
		(net "CLK_100M_RETIMER_CPU1_P1_R_DP")
	)
	(segment
		(start 86.679786 -394.661644)
		(end 90.654124 -394.661644)
		(width 0.14224)
		(layer "In6.Cu")
		(net "CLK_100M_RETIMER_CPU1_P1_R_DP")
	)
	(segment
		(start 102.438708 -403.272498)
		(end 104.391714 -405.225504)
		(width 0.14224)
		(layer "In6.Cu")
		(net "CLK_100M_RETIMER_CPU1_P1_R_DP")
	)
	(segment
		(start 84.287106 -394.798804)
		(end 84.424266 -394.661644)
		(width 0.14224)
		(layer "In6.Cu")
		(net "CLK_100M_RETIMER_CPU1_P1_R_DP")
	)
	(segment
		(start 99.553014 -400.935444)
		(end 100.712778 -402.095208)
		(width 0.14224)
		(layer "In6.Cu")
		(net "CLK_100M_RETIMER_CPU1_P1_R_DP")
	)
	(segment
		(start 83.860386 -394.798804)
		(end 84.287106 -394.798804)
		(width 0.14224)
		(layer "In6.Cu")
		(net "CLK_100M_RETIMER_CPU1_P1_R_DP")
	)
	(segment
		(start 82.168746 -394.661644)
		(end 82.595466 -394.661644)
		(width 0.14224)
		(layer "In6.Cu")
		(net "CLK_100M_RETIMER_CPU1_P1_R_DP")
	)
	(segment
		(start 79.508096 -391.138156)
		(end 79.508096 -391.823194)
		(width 0.14224)
		(layer "In6.Cu")
		(net "CLK_100M_RETIMER_CPU1_P1_R_DP")
	)
	(segment
		(start 78.545436 -389.09498)
		(end 78.545436 -389.5217)
		(width 0.14224)
		(layer "In6.Cu")
		(net "CLK_100M_RETIMER_CPU1_P1_R_DP")
	)
	(segment
		(start 78.122526 -387.765798)
		(end 78.682596 -388.325868)
		(width 0.14224)
		(layer "In6.Cu")
		(net "CLK_100M_RETIMER_CPU1_P1_R_DP")
	)
	(segment
		(start 84.988146 -394.798804)
		(end 85.414866 -394.798804)
		(width 0.14224)
		(layer "In6.Cu")
		(net "CLK_100M_RETIMER_CPU1_P1_R_DP")
	)
	(segment
		(start 75.772518 -387.636004)
		(end 75.909678 -387.498844)
		(width 0.14224)
		(layer "In6.Cu")
		(net "CLK_100M_RETIMER_CPU1_P1_R_DP")
	)
	(segment
		(start 84.424266 -394.661644)
		(end 84.850986 -394.661644)
		(width 0.14224)
		(layer "In6.Cu")
		(net "CLK_100M_RETIMER_CPU1_P1_R_DP")
	)
	(segment
		(start 100.712778 -402.28901)
		(end 101.014784 -402.591016)
		(width 0.14224)
		(layer "In6.Cu")
		(net "CLK_100M_RETIMER_CPU1_P1_R_DP")
	)
	(segment
		(start 76.91501 -387.765798)
		(end 78.122526 -387.765798)
		(width 0.14224)
		(layer "In6.Cu")
		(net "CLK_100M_RETIMER_CPU1_P1_R_DP")
	)
	(segment
		(start 79.679546 -394.281152)
		(end 80.060038 -394.661644)
		(width 0.14224)
		(layer "In6.Cu")
		(net "CLK_100M_RETIMER_CPU1_P1_R_DP")
	)
	(segment
		(start 101.208586 -402.591016)
		(end 101.890068 -403.272498)
		(width 0.14224)
		(layer "In6.Cu")
		(net "CLK_100M_RETIMER_CPU1_P1_R_DP")
	)
	(segment
		(start 78.545436 -389.5217)
		(end 78.682596 -389.65886)
		(width 0.14224)
		(layer "In6.Cu")
		(net "CLK_100M_RETIMER_CPU1_P1_R_DP")
	)
	(segment
		(start 81.604866 -394.798804)
		(end 82.031586 -394.798804)
		(width 0.14224)
		(layer "In6.Cu")
		(net "CLK_100M_RETIMER_CPU1_P1_R_DP")
	)
	(segment
		(start 75.345798 -387.636004)
		(end 75.772518 -387.636004)
		(width 0.14224)
		(layer "In6.Cu")
		(net "CLK_100M_RETIMER_CPU1_P1_R_DP")
	)
	(segment
		(start 78.682596 -390.312656)
		(end 79.508096 -391.138156)
		(width 0.14224)
		(layer "In6.Cu")
		(net "CLK_100M_RETIMER_CPU1_P1_R_DP")
	)
	(segment
		(start 81.467706 -394.661644)
		(end 81.604866 -394.798804)
		(width 0.14224)
		(layer "In6.Cu")
		(net "CLK_100M_RETIMER_CPU1_P1_R_DP")
	)
	(segment
		(start 85.978746 -394.661644)
		(end 86.115906 -394.798804)
		(width 0.14224)
		(layer "In6.Cu")
		(net "CLK_100M_RETIMER_CPU1_P1_R_DP")
	)
	(segment
		(start 101.890068 -403.272498)
		(end 102.438708 -403.272498)
		(width 0.14224)
		(layer "In6.Cu")
		(net "CLK_100M_RETIMER_CPU1_P1_R_DP")
	)
	(segment
		(start 84.850986 -394.661644)
		(end 84.988146 -394.798804)
		(width 0.14224)
		(layer "In6.Cu")
		(net "CLK_100M_RETIMER_CPU1_P1_R_DP")
	)
	(segment
		(start 79.437992 -391.893298)
		(end 79.437992 -393.697968)
		(width 0.14224)
		(layer "In6.Cu")
		(net "CLK_100M_RETIMER_CPU1_P1_R_DP")
	)
	(segment
		(start 86.542626 -394.798804)
		(end 86.679786 -394.661644)
		(width 0.14224)
		(layer "In6.Cu")
		(net "CLK_100M_RETIMER_CPU1_P1_R_DP")
	)
	(segment
		(start 101.014784 -402.591016)
		(end 101.208586 -402.591016)
		(width 0.14224)
		(layer "In6.Cu")
		(net "CLK_100M_RETIMER_CPU1_P1_R_DP")
	)
	(segment
		(start 85.552026 -394.661644)
		(end 85.978746 -394.661644)
		(width 0.14224)
		(layer "In6.Cu")
		(net "CLK_100M_RETIMER_CPU1_P1_R_DP")
	)
	(segment
		(start 83.723226 -394.661644)
		(end 83.860386 -394.798804)
		(width 0.14224)
		(layer "In6.Cu")
		(net "CLK_100M_RETIMER_CPU1_P1_R_DP")
	)
	(segment
		(start 82.595466 -394.661644)
		(end 82.732626 -394.798804)
		(width 0.14224)
		(layer "In6.Cu")
		(net "CLK_100M_RETIMER_CPU1_P1_R_DP")
	)
	(segment
		(start 78.682596 -389.65886)
		(end 78.682596 -390.312656)
		(width 0.14224)
		(layer "In6.Cu")
		(net "CLK_100M_RETIMER_CPU1_P1_R_DP")
	)
	(segment
		(start 79.437992 -393.697968)
		(end 79.679546 -394.281152)
		(width 0.14224)
		(layer "In6.Cu")
		(net "CLK_100M_RETIMER_CPU1_P1_R_DP")
	)
	(segment
		(start 76.648056 -387.498844)
		(end 76.91501 -387.765798)
		(width 0.14224)
		(layer "In6.Cu")
		(net "CLK_100M_RETIMER_CPU1_P1_R_DP")
	)
	(segment
		(start 99.056952 -400.439382)
		(end 99.056952 -400.633438)
		(width 0.14224)
		(layer "In6.Cu")
		(net "CLK_100M_RETIMER_CPU1_P1_R_DP")
	)
	(segment
		(start 74.101452 -387.498844)
		(end 75.208638 -387.498844)
		(width 0.14224)
		(layer "In6.Cu")
		(net "CLK_100M_RETIMER_CPU1_P1_R_DP")
	)
	(segment
		(start 75.909678 -387.498844)
		(end 76.648056 -387.498844)
		(width 0.14224)
		(layer "In6.Cu")
		(net "CLK_100M_RETIMER_CPU1_P1_R_DP")
	)
	(segment
		(start 73.810622 -387.789674)
		(end 74.101452 -387.498844)
		(width 0.14224)
		(layer "In6.Cu")
		(net "CLK_100M_RETIMER_CPU1_P1_R_DP")
	)
	(segment
		(start 85.414866 -394.798804)
		(end 85.552026 -394.661644)
		(width 0.14224)
		(layer "In6.Cu")
		(net "CLK_100M_RETIMER_CPU1_P1_R_DP")
	)
	(segment
		(start 90.654124 -394.661644)
		(end 96.130364 -400.137884)
		(width 0.14224)
		(layer "In6.Cu")
		(net "CLK_100M_RETIMER_CPU1_P1_R_DP")
	)
	(segment
		(start 99.358958 -400.935444)
		(end 99.553014 -400.935444)
		(width 0.14224)
		(layer "In6.Cu")
		(net "CLK_100M_RETIMER_CPU1_P1_R_DP")
	)
	(segment
		(start 83.159346 -394.798804)
		(end 83.296506 -394.661644)
		(width 0.14224)
		(layer "In6.Cu")
		(net "CLK_100M_RETIMER_CPU1_P1_R_DP")
	)
	(segment
		(start 105.002584 -405.409654)
		(end 105.002584 -405.027638)
		(width 0.12954)
		(layer "F.Cu")
		(net "CLK_100M_RETIMER_CPU1_P1_R_DN")
	)
	(segment
		(start 105.907586 -406.705562)
		(end 105.694988 -406.492964)
		(width 0.12954)
		(layer "F.Cu")
		(net "CLK_100M_RETIMER_CPU1_P1_R_DN")
	)
	(segment
		(start 105.996486 -407.25725)
		(end 105.996486 -407.087832)
		(width 0.12954)
		(layer "F.Cu")
		(net "CLK_100M_RETIMER_CPU1_P1_R_DN")
	)
	(segment
		(start 73.810622 -386.926074)
		(end 74.081132 -387.196584)
		(width 0.12954)
		(layer "F.Cu")
		(net "CLK_100M_RETIMER_CPU1_P1_R_DN")
	)
	(segment
		(start 105.907586 -406.998932)
		(end 105.907586 -406.705562)
		(width 0.12954)
		(layer "F.Cu")
		(net "CLK_100M_RETIMER_CPU1_P1_R_DN")
	)
	(segment
		(start 105.694988 -406.492964)
		(end 105.694988 -406.102058)
		(width 0.12954)
		(layer "F.Cu")
		(net "CLK_100M_RETIMER_CPU1_P1_R_DN")
	)
	(segment
		(start 105.996486 -407.087832)
		(end 105.907586 -406.998932)
		(width 0.12954)
		(layer "F.Cu")
		(net "CLK_100M_RETIMER_CPU1_P1_R_DN")
	)
	(segment
		(start 74.081132 -387.196584)
		(end 74.54392 -387.196584)
		(width 0.12954)
		(layer "F.Cu")
		(net "CLK_100M_RETIMER_CPU1_P1_R_DN")
	)
	(segment
		(start 74.54392 -387.196584)
		(end 74.78903 -386.951474)
		(width 0.12954)
		(layer "F.Cu")
		(net "CLK_100M_RETIMER_CPU1_P1_R_DN")
	)
	(segment
		(start 105.694988 -406.102058)
		(end 105.002584 -405.409654)
		(width 0.12954)
		(layer "F.Cu")
		(net "CLK_100M_RETIMER_CPU1_P1_R_DN")
	)
	(via
		(at 105.002584 -405.027638)
		(size 0.508)
		(drill 0.254)
		(layers "F.Cu" "B.Cu")
		(net "CLK_100M_RETIMER_CPU1_P1_R_DN")
	)
	(via
		(at 73.810622 -386.926074)
		(size 0.508)
		(drill 0.254)
		(layers "F.Cu" "B.Cu")
		(net "CLK_100M_RETIMER_CPU1_P1_R_DN")
	)
	(segment
		(start 90.770964 -394.379704)
		(end 96.247204 -399.855944)
		(width 0.14224)
		(layer "In6.Cu")
		(net "CLK_100M_RETIMER_CPU1_P1_R_DN")
	)
	(segment
		(start 80.176878 -394.379704)
		(end 90.770964 -394.379704)
		(width 0.14224)
		(layer "In6.Cu")
		(net "CLK_100M_RETIMER_CPU1_P1_R_DN")
	)
	(segment
		(start 79.719932 -393.641834)
		(end 79.91856 -394.121386)
		(width 0.14224)
		(layer "In6.Cu")
		(net "CLK_100M_RETIMER_CPU1_P1_R_DN")
	)
	(segment
		(start 79.91856 -394.121386)
		(end 80.176878 -394.379704)
		(width 0.14224)
		(layer "In6.Cu")
		(net "CLK_100M_RETIMER_CPU1_P1_R_DN")
	)
	(segment
		(start 76.764896 -387.216904)
		(end 77.03185 -387.483858)
		(width 0.14224)
		(layer "In6.Cu")
		(net "CLK_100M_RETIMER_CPU1_P1_R_DN")
	)
	(segment
		(start 102.555548 -402.990558)
		(end 104.592628 -405.027638)
		(width 0.14224)
		(layer "In6.Cu")
		(net "CLK_100M_RETIMER_CPU1_P1_R_DN")
	)
	(segment
		(start 79.790036 -391.021316)
		(end 79.790036 -391.940034)
		(width 0.14224)
		(layer "In6.Cu")
		(net "CLK_100M_RETIMER_CPU1_P1_R_DN")
	)
	(segment
		(start 96.247204 -399.855944)
		(end 98.872294 -399.855944)
		(width 0.14224)
		(layer "In6.Cu")
		(net "CLK_100M_RETIMER_CPU1_P1_R_DN")
	)
	(segment
		(start 73.810622 -386.926074)
		(end 74.101452 -387.216904)
		(width 0.14224)
		(layer "In6.Cu")
		(net "CLK_100M_RETIMER_CPU1_P1_R_DN")
	)
	(segment
		(start 79.719932 -392.010138)
		(end 79.719932 -393.641834)
		(width 0.14224)
		(layer "In6.Cu")
		(net "CLK_100M_RETIMER_CPU1_P1_R_DN")
	)
	(segment
		(start 74.101452 -387.216904)
		(end 76.764896 -387.216904)
		(width 0.14224)
		(layer "In6.Cu")
		(net "CLK_100M_RETIMER_CPU1_P1_R_DN")
	)
	(segment
		(start 98.872294 -399.855944)
		(end 102.006908 -402.990558)
		(width 0.14224)
		(layer "In6.Cu")
		(net "CLK_100M_RETIMER_CPU1_P1_R_DN")
	)
	(segment
		(start 79.790036 -391.940034)
		(end 79.719932 -392.010138)
		(width 0.14224)
		(layer "In6.Cu")
		(net "CLK_100M_RETIMER_CPU1_P1_R_DN")
	)
	(segment
		(start 78.964536 -390.195816)
		(end 79.790036 -391.021316)
		(width 0.14224)
		(layer "In6.Cu")
		(net "CLK_100M_RETIMER_CPU1_P1_R_DN")
	)
	(segment
		(start 77.03185 -387.483858)
		(end 78.239366 -387.483858)
		(width 0.14224)
		(layer "In6.Cu")
		(net "CLK_100M_RETIMER_CPU1_P1_R_DN")
	)
	(segment
		(start 78.964536 -388.209028)
		(end 78.964536 -390.195816)
		(width 0.14224)
		(layer "In6.Cu")
		(net "CLK_100M_RETIMER_CPU1_P1_R_DN")
	)
	(segment
		(start 78.239366 -387.483858)
		(end 78.964536 -388.209028)
		(width 0.14224)
		(layer "In6.Cu")
		(net "CLK_100M_RETIMER_CPU1_P1_R_DN")
	)
	(segment
		(start 102.006908 -402.990558)
		(end 102.555548 -402.990558)
		(width 0.14224)
		(layer "In6.Cu")
		(net "CLK_100M_RETIMER_CPU1_P1_R_DN")
	)
	(segment
		(start 104.592628 -405.027638)
		(end 105.002584 -405.027638)
		(width 0.14224)
		(layer "In6.Cu")
		(net "CLK_100M_RETIMER_CPU1_P1_R_DN")
	)
	(segment
		(start 76.696062 -387.506972)
		(end 77.00518 -387.81609)
		(width 0.12954)
		(layer "F.Cu")
		(net "CLK_100M_RETIMER_CPU1_P1_DP")
	)
	(segment
		(start 76.329032 -387.506972)
		(end 76.696062 -387.506972)
		(width 0.12954)
		(layer "F.Cu")
		(net "CLK_100M_RETIMER_CPU1_P1_DP")
	)
	(segment
		(start 75.32243 -387.764274)
		(end 75.568302 -387.518402)
		(width 0.12954)
		(layer "F.Cu")
		(net "CLK_100M_RETIMER_CPU1_P1_DP")
	)
	(segment
		(start 77.00518 -387.81609)
		(end 77.750924 -387.81609)
		(width 0.12954)
		(layer "F.Cu")
		(net "CLK_100M_RETIMER_CPU1_P1_DP")
	)
	(segment
		(start 78.025752 -387.747002)
		(end 78.109826 -387.831076)
		(width 0.1016)
		(layer "F.Cu")
		(net "CLK_100M_RETIMER_CPU1_P1_DP")
	)
	(segment
		(start 76.07173 -387.764274)
		(end 76.329032 -387.506972)
		(width 0.12954)
		(layer "F.Cu")
		(net "CLK_100M_RETIMER_CPU1_P1_DP")
	)
	(segment
		(start 75.825858 -387.518402)
		(end 76.07173 -387.764274)
		(width 0.12954)
		(layer "F.Cu")
		(net "CLK_100M_RETIMER_CPU1_P1_DP")
	)
	(segment
		(start 75.568302 -387.518402)
		(end 75.825858 -387.518402)
		(width 0.12954)
		(layer "F.Cu")
		(net "CLK_100M_RETIMER_CPU1_P1_DP")
	)
	(segment
		(start 77.820012 -387.747002)
		(end 78.025752 -387.747002)
		(width 0.1016)
		(layer "F.Cu")
		(net "CLK_100M_RETIMER_CPU1_P1_DP")
	)
	(segment
		(start 77.750924 -387.81609)
		(end 77.820012 -387.747002)
		(width 0.1016)
		(layer "F.Cu")
		(net "CLK_100M_RETIMER_CPU1_P1_DP")
	)
	(segment
		(start 77.769466 -387.531102)
		(end 78.62951 -387.531102)
		(width 0.1016)
		(layer "F.Cu")
		(net "CLK_100M_RETIMER_CPU1_P1_DN")
	)
	(segment
		(start 75.827382 -387.195822)
		(end 76.07173 -386.951474)
		(width 0.12954)
		(layer "F.Cu")
		(net "CLK_100M_RETIMER_CPU1_P1_DN")
	)
	(segment
		(start 77.139038 -387.49351)
		(end 77.731874 -387.49351)
		(width 0.12954)
		(layer "F.Cu")
		(net "CLK_100M_RETIMER_CPU1_P1_DN")
	)
	(segment
		(start 76.82992 -387.184392)
		(end 77.139038 -387.49351)
		(width 0.12954)
		(layer "F.Cu")
		(net "CLK_100M_RETIMER_CPU1_P1_DN")
	)
	(segment
		(start 77.731874 -387.49351)
		(end 77.769466 -387.531102)
		(width 0.1016)
		(layer "F.Cu")
		(net "CLK_100M_RETIMER_CPU1_P1_DN")
	)
	(segment
		(start 75.566778 -387.195822)
		(end 75.827382 -387.195822)
		(width 0.12954)
		(layer "F.Cu")
		(net "CLK_100M_RETIMER_CPU1_P1_DN")
	)
	(segment
		(start 75.32243 -386.951474)
		(end 75.566778 -387.195822)
		(width 0.12954)
		(layer "F.Cu")
		(net "CLK_100M_RETIMER_CPU1_P1_DN")
	)
	(segment
		(start 76.07173 -386.951474)
		(end 76.304648 -387.184392)
		(width 0.12954)
		(layer "F.Cu")
		(net "CLK_100M_RETIMER_CPU1_P1_DN")
	)
	(segment
		(start 76.304648 -387.184392)
		(end 76.82992 -387.184392)
		(width 0.12954)
		(layer "F.Cu")
		(net "CLK_100M_RETIMER_CPU1_P1_DN")
	)
	(segment
		(start 41.553384 -387.519164)
		(end 42.016172 -387.519164)
		(width 0.12954)
		(layer "F.Cu")
		(net "CLK_100M_RETIMER_CPU1_P0_R_DP")
	)
	(segment
		(start 42.016172 -387.519164)
		(end 42.261282 -387.764274)
		(width 0.12954)
		(layer "F.Cu")
		(net "CLK_100M_RETIMER_CPU1_P0_R_DP")
	)
	(segment
		(start 103.871522 -409.382214)
		(end 103.668576 -409.382214)
		(width 0.12954)
		(layer "F.Cu")
		(net "CLK_100M_RETIMER_CPU1_P0_R_DP")
	)
	(segment
		(start 41.282874 -387.789674)
		(end 41.553384 -387.519164)
		(width 0.12954)
		(layer "F.Cu")
		(net "CLK_100M_RETIMER_CPU1_P0_R_DP")
	)
	(segment
		(start 102.845108 -409.293314)
		(end 102.574598 -409.563824)
		(width 0.12954)
		(layer "F.Cu")
		(net "CLK_100M_RETIMER_CPU1_P0_R_DP")
	)
	(segment
		(start 103.579676 -409.293314)
		(end 102.845108 -409.293314)
		(width 0.12954)
		(layer "F.Cu")
		(net "CLK_100M_RETIMER_CPU1_P0_R_DP")
	)
	(segment
		(start 103.668576 -409.382214)
		(end 103.579676 -409.293314)
		(width 0.12954)
		(layer "F.Cu")
		(net "CLK_100M_RETIMER_CPU1_P0_R_DP")
	)
	(via
		(at 102.574598 -409.563824)
		(size 0.508)
		(drill 0.254)
		(layers "F.Cu" "B.Cu")
		(net "CLK_100M_RETIMER_CPU1_P0_R_DP")
	)
	(via
		(at 41.282874 -387.789674)
		(size 0.508)
		(drill 0.254)
		(layers "F.Cu" "B.Cu")
		(net "CLK_100M_RETIMER_CPU1_P0_R_DP")
	)
	(segment
		(start 100.497894 -408.478736)
		(end 100.497894 -406.650952)
		(width 0.14224)
		(layer "In6.Cu")
		(net "CLK_100M_RETIMER_CPU1_P0_R_DP")
	)
	(segment
		(start 100.497894 -406.650952)
		(end 97.733866 -403.886924)
		(width 0.14224)
		(layer "In6.Cu")
		(net "CLK_100M_RETIMER_CPU1_P0_R_DP")
	)
	(segment
		(start 66.421762 -384.78587)
		(end 65.491868 -383.855976)
		(width 0.14224)
		(layer "In6.Cu")
		(net "CLK_100M_RETIMER_CPU1_P0_R_DP")
	)
	(segment
		(start 67.075558 -386.36448)
		(end 66.421762 -384.78587)
		(width 0.14224)
		(layer "In6.Cu")
		(net "CLK_100M_RETIMER_CPU1_P0_R_DP")
	)
	(segment
		(start 78.112112 -394.507212)
		(end 78.112112 -392.371834)
		(width 0.14224)
		(layer "In6.Cu")
		(net "CLK_100M_RETIMER_CPU1_P0_R_DP")
	)
	(segment
		(start 82.166968 -395.781784)
		(end 80.176116 -395.781784)
		(width 0.14224)
		(layer "In6.Cu")
		(net "CLK_100M_RETIMER_CPU1_P0_R_DP")
	)
	(segment
		(start 82.304128 -395.918944)
		(end 82.166968 -395.781784)
		(width 0.14224)
		(layer "In6.Cu")
		(net "CLK_100M_RETIMER_CPU1_P0_R_DP")
	)
	(segment
		(start 101.703632 -408.954478)
		(end 100.973636 -408.954478)
		(width 0.14224)
		(layer "In6.Cu")
		(net "CLK_100M_RETIMER_CPU1_P0_R_DP")
	)
	(segment
		(start 47.182532 -383.855976)
		(end 46.236128 -384.80238)
		(width 0.14224)
		(layer "In6.Cu")
		(net "CLK_100M_RETIMER_CPU1_P0_R_DP")
	)
	(segment
		(start 83.858608 -395.918944)
		(end 83.431888 -395.918944)
		(width 0.14224)
		(layer "In6.Cu")
		(net "CLK_100M_RETIMER_CPU1_P0_R_DP")
	)
	(segment
		(start 75.579986 -389.839708)
		(end 71.86549 -389.839708)
		(width 0.14224)
		(layer "In6.Cu")
		(net "CLK_100M_RETIMER_CPU1_P0_R_DP")
	)
	(segment
		(start 45.550328 -387.78561)
		(end 43.873166 -387.78561)
		(width 0.14224)
		(layer "In6.Cu")
		(net "CLK_100M_RETIMER_CPU1_P0_R_DP")
	)
	(segment
		(start 46.236128 -385.97205)
		(end 46.373288 -386.10921)
		(width 0.14224)
		(layer "In6.Cu")
		(net "CLK_100M_RETIMER_CPU1_P0_R_DP")
	)
	(segment
		(start 69.94652 -387.920738)
		(end 68.631816 -387.920738)
		(width 0.14224)
		(layer "In6.Cu")
		(net "CLK_100M_RETIMER_CPU1_P0_R_DP")
	)
	(segment
		(start 65.491868 -383.855976)
		(end 47.182532 -383.855976)
		(width 0.14224)
		(layer "In6.Cu")
		(net "CLK_100M_RETIMER_CPU1_P0_R_DP")
	)
	(segment
		(start 42.222674 -387.636004)
		(end 42.085514 -387.498844)
		(width 0.14224)
		(layer "In6.Cu")
		(net "CLK_100M_RETIMER_CPU1_P0_R_DP")
	)
	(segment
		(start 46.373288 -386.10921)
		(end 46.373288 -386.53593)
		(width 0.14224)
		(layer "In6.Cu")
		(net "CLK_100M_RETIMER_CPU1_P0_R_DP")
	)
	(segment
		(start 46.236128 -384.80238)
		(end 46.236128 -385.97205)
		(width 0.14224)
		(layer "In6.Cu")
		(net "CLK_100M_RETIMER_CPU1_P0_R_DP")
	)
	(segment
		(start 78.112112 -392.371834)
		(end 75.579986 -389.839708)
		(width 0.14224)
		(layer "In6.Cu")
		(net "CLK_100M_RETIMER_CPU1_P0_R_DP")
	)
	(segment
		(start 43.873166 -387.78561)
		(end 43.5864 -387.498844)
		(width 0.14224)
		(layer "In6.Cu")
		(net "CLK_100M_RETIMER_CPU1_P0_R_DP")
	)
	(segment
		(start 68.631816 -387.920738)
		(end 67.075558 -386.36448)
		(width 0.14224)
		(layer "In6.Cu")
		(net "CLK_100M_RETIMER_CPU1_P0_R_DP")
	)
	(segment
		(start 80.176116 -395.781784)
		(end 78.828392 -395.223492)
		(width 0.14224)
		(layer "In6.Cu")
		(net "CLK_100M_RETIMER_CPU1_P0_R_DP")
	)
	(segment
		(start 100.973636 -408.954478)
		(end 100.497894 -408.478736)
		(width 0.14224)
		(layer "In6.Cu")
		(net "CLK_100M_RETIMER_CPU1_P0_R_DP")
	)
	(segment
		(start 83.294728 -395.781784)
		(end 82.868008 -395.781784)
		(width 0.14224)
		(layer "In6.Cu")
		(net "CLK_100M_RETIMER_CPU1_P0_R_DP")
	)
	(segment
		(start 90.198956 -395.781784)
		(end 83.995768 -395.781784)
		(width 0.14224)
		(layer "In6.Cu")
		(net "CLK_100M_RETIMER_CPU1_P0_R_DP")
	)
	(segment
		(start 46.373288 -386.53593)
		(end 46.236128 -386.67309)
		(width 0.14224)
		(layer "In6.Cu")
		(net "CLK_100M_RETIMER_CPU1_P0_R_DP")
	)
	(segment
		(start 102.283768 -409.272994)
		(end 102.022148 -409.272994)
		(width 0.14224)
		(layer "In6.Cu")
		(net "CLK_100M_RETIMER_CPU1_P0_R_DP")
	)
	(segment
		(start 42.786554 -387.498844)
		(end 42.649394 -387.636004)
		(width 0.14224)
		(layer "In6.Cu")
		(net "CLK_100M_RETIMER_CPU1_P0_R_DP")
	)
	(segment
		(start 97.733866 -403.316694)
		(end 90.198956 -395.781784)
		(width 0.14224)
		(layer "In6.Cu")
		(net "CLK_100M_RETIMER_CPU1_P0_R_DP")
	)
	(segment
		(start 102.574598 -409.563824)
		(end 102.283768 -409.272994)
		(width 0.14224)
		(layer "In6.Cu")
		(net "CLK_100M_RETIMER_CPU1_P0_R_DP")
	)
	(segment
		(start 43.5864 -387.498844)
		(end 42.786554 -387.498844)
		(width 0.14224)
		(layer "In6.Cu")
		(net "CLK_100M_RETIMER_CPU1_P0_R_DP")
	)
	(segment
		(start 102.022148 -409.272994)
		(end 101.703632 -408.954478)
		(width 0.14224)
		(layer "In6.Cu")
		(net "CLK_100M_RETIMER_CPU1_P0_R_DP")
	)
	(segment
		(start 83.431888 -395.918944)
		(end 83.294728 -395.781784)
		(width 0.14224)
		(layer "In6.Cu")
		(net "CLK_100M_RETIMER_CPU1_P0_R_DP")
	)
	(segment
		(start 42.649394 -387.636004)
		(end 42.222674 -387.636004)
		(width 0.14224)
		(layer "In6.Cu")
		(net "CLK_100M_RETIMER_CPU1_P0_R_DP")
	)
	(segment
		(start 46.236128 -387.09981)
		(end 45.550328 -387.78561)
		(width 0.14224)
		(layer "In6.Cu")
		(net "CLK_100M_RETIMER_CPU1_P0_R_DP")
	)
	(segment
		(start 83.995768 -395.781784)
		(end 83.858608 -395.918944)
		(width 0.14224)
		(layer "In6.Cu")
		(net "CLK_100M_RETIMER_CPU1_P0_R_DP")
	)
	(segment
		(start 41.573704 -387.498844)
		(end 41.282874 -387.789674)
		(width 0.14224)
		(layer "In6.Cu")
		(net "CLK_100M_RETIMER_CPU1_P0_R_DP")
	)
	(segment
		(start 82.730848 -395.918944)
		(end 82.304128 -395.918944)
		(width 0.14224)
		(layer "In6.Cu")
		(net "CLK_100M_RETIMER_CPU1_P0_R_DP")
	)
	(segment
		(start 78.828392 -395.223492)
		(end 78.112112 -394.507212)
		(width 0.14224)
		(layer "In6.Cu")
		(net "CLK_100M_RETIMER_CPU1_P0_R_DP")
	)
	(segment
		(start 71.86549 -389.839708)
		(end 69.94652 -387.920738)
		(width 0.14224)
		(layer "In6.Cu")
		(net "CLK_100M_RETIMER_CPU1_P0_R_DP")
	)
	(segment
		(start 46.236128 -386.67309)
		(end 46.236128 -387.09981)
		(width 0.14224)
		(layer "In6.Cu")
		(net "CLK_100M_RETIMER_CPU1_P0_R_DP")
	)
	(segment
		(start 82.868008 -395.781784)
		(end 82.730848 -395.918944)
		(width 0.14224)
		(layer "In6.Cu")
		(net "CLK_100M_RETIMER_CPU1_P0_R_DP")
	)
	(segment
		(start 97.733866 -403.886924)
		(end 97.733866 -403.316694)
		(width 0.14224)
		(layer "In6.Cu")
		(net "CLK_100M_RETIMER_CPU1_P0_R_DP")
	)
	(segment
		(start 42.085514 -387.498844)
		(end 41.573704 -387.498844)
		(width 0.14224)
		(layer "In6.Cu")
		(net "CLK_100M_RETIMER_CPU1_P0_R_DP")
	)
	(segment
		(start 102.845108 -408.970734)
		(end 102.574598 -408.700224)
		(width 0.12954)
		(layer "F.Cu")
		(net "CLK_100M_RETIMER_CPU1_P0_R_DN")
	)
	(segment
		(start 103.871522 -408.882088)
		(end 103.681022 -408.882088)
		(width 0.12954)
		(layer "F.Cu")
		(net "CLK_100M_RETIMER_CPU1_P0_R_DN")
	)
	(segment
		(start 41.282874 -386.926074)
		(end 41.553384 -387.196584)
		(width 0.12954)
		(layer "F.Cu")
		(net "CLK_100M_RETIMER_CPU1_P0_R_DN")
	)
	(segment
		(start 103.681022 -408.882088)
		(end 103.592376 -408.970734)
		(width 0.12954)
		(layer "F.Cu")
		(net "CLK_100M_RETIMER_CPU1_P0_R_DN")
	)
	(segment
		(start 103.592376 -408.970734)
		(end 102.845108 -408.970734)
		(width 0.12954)
		(layer "F.Cu")
		(net "CLK_100M_RETIMER_CPU1_P0_R_DN")
	)
	(segment
		(start 41.553384 -387.196584)
		(end 42.016172 -387.196584)
		(width 0.12954)
		(layer "F.Cu")
		(net "CLK_100M_RETIMER_CPU1_P0_R_DN")
	)
	(segment
		(start 42.016172 -387.196584)
		(end 42.261282 -386.951474)
		(width 0.12954)
		(layer "F.Cu")
		(net "CLK_100M_RETIMER_CPU1_P0_R_DN")
	)
	(via
		(at 41.282874 -386.926074)
		(size 0.508)
		(drill 0.254)
		(layers "F.Cu" "B.Cu")
		(net "CLK_100M_RETIMER_CPU1_P0_R_DN")
	)
	(via
		(at 102.574598 -408.700224)
		(size 0.508)
		(drill 0.254)
		(layers "F.Cu" "B.Cu")
		(net "CLK_100M_RETIMER_CPU1_P0_R_DN")
	)
	(segment
		(start 102.138988 -408.991054)
		(end 101.820472 -408.672538)
		(width 0.14224)
		(layer "In6.Cu")
		(net "CLK_100M_RETIMER_CPU1_P0_R_DN")
	)
	(segment
		(start 68.748656 -387.638798)
		(end 67.314572 -386.204714)
		(width 0.14224)
		(layer "In6.Cu")
		(net "CLK_100M_RETIMER_CPU1_P0_R_DN")
	)
	(segment
		(start 45.954188 -386.98297)
		(end 45.433488 -387.50367)
		(width 0.14224)
		(layer "In6.Cu")
		(net "CLK_100M_RETIMER_CPU1_P0_R_DN")
	)
	(segment
		(start 41.573704 -387.216904)
		(end 41.282874 -386.926074)
		(width 0.14224)
		(layer "In6.Cu")
		(net "CLK_100M_RETIMER_CPU1_P0_R_DN")
	)
	(segment
		(start 75.696826 -389.557768)
		(end 71.98233 -389.557768)
		(width 0.14224)
		(layer "In6.Cu")
		(net "CLK_100M_RETIMER_CPU1_P0_R_DN")
	)
	(segment
		(start 102.574598 -408.700224)
		(end 102.283768 -408.991054)
		(width 0.14224)
		(layer "In6.Cu")
		(net "CLK_100M_RETIMER_CPU1_P0_R_DN")
	)
	(segment
		(start 70.06336 -387.638798)
		(end 68.748656 -387.638798)
		(width 0.14224)
		(layer "In6.Cu")
		(net "CLK_100M_RETIMER_CPU1_P0_R_DN")
	)
	(segment
		(start 45.954188 -384.68554)
		(end 45.954188 -386.98297)
		(width 0.14224)
		(layer "In6.Cu")
		(net "CLK_100M_RETIMER_CPU1_P0_R_DN")
	)
	(segment
		(start 100.779834 -406.534112)
		(end 98.015806 -403.770084)
		(width 0.14224)
		(layer "In6.Cu")
		(net "CLK_100M_RETIMER_CPU1_P0_R_DN")
	)
	(segment
		(start 71.98233 -389.557768)
		(end 70.06336 -387.638798)
		(width 0.14224)
		(layer "In6.Cu")
		(net "CLK_100M_RETIMER_CPU1_P0_R_DN")
	)
	(segment
		(start 101.820472 -408.672538)
		(end 101.090476 -408.672538)
		(width 0.14224)
		(layer "In6.Cu")
		(net "CLK_100M_RETIMER_CPU1_P0_R_DN")
	)
	(segment
		(start 101.090476 -408.672538)
		(end 100.779834 -408.361896)
		(width 0.14224)
		(layer "In6.Cu")
		(net "CLK_100M_RETIMER_CPU1_P0_R_DN")
	)
	(segment
		(start 45.433488 -387.50367)
		(end 43.990006 -387.50367)
		(width 0.14224)
		(layer "In6.Cu")
		(net "CLK_100M_RETIMER_CPU1_P0_R_DN")
	)
	(segment
		(start 90.315796 -395.499844)
		(end 80.23225 -395.499844)
		(width 0.14224)
		(layer "In6.Cu")
		(net "CLK_100M_RETIMER_CPU1_P0_R_DN")
	)
	(segment
		(start 100.779834 -408.361896)
		(end 100.779834 -406.534112)
		(width 0.14224)
		(layer "In6.Cu")
		(net "CLK_100M_RETIMER_CPU1_P0_R_DN")
	)
	(segment
		(start 65.608708 -383.574036)
		(end 47.065692 -383.574036)
		(width 0.14224)
		(layer "In6.Cu")
		(net "CLK_100M_RETIMER_CPU1_P0_R_DN")
	)
	(segment
		(start 78.394052 -394.390372)
		(end 78.394052 -392.254994)
		(width 0.14224)
		(layer "In6.Cu")
		(net "CLK_100M_RETIMER_CPU1_P0_R_DN")
	)
	(segment
		(start 78.988158 -394.984478)
		(end 78.394052 -394.390372)
		(width 0.14224)
		(layer "In6.Cu")
		(net "CLK_100M_RETIMER_CPU1_P0_R_DN")
	)
	(segment
		(start 43.990006 -387.50367)
		(end 43.70324 -387.216904)
		(width 0.14224)
		(layer "In6.Cu")
		(net "CLK_100M_RETIMER_CPU1_P0_R_DN")
	)
	(segment
		(start 98.015806 -403.770084)
		(end 98.015806 -403.199854)
		(width 0.14224)
		(layer "In6.Cu")
		(net "CLK_100M_RETIMER_CPU1_P0_R_DN")
	)
	(segment
		(start 98.015806 -403.199854)
		(end 90.315796 -395.499844)
		(width 0.14224)
		(layer "In6.Cu")
		(net "CLK_100M_RETIMER_CPU1_P0_R_DN")
	)
	(segment
		(start 78.394052 -392.254994)
		(end 75.696826 -389.557768)
		(width 0.14224)
		(layer "In6.Cu")
		(net "CLK_100M_RETIMER_CPU1_P0_R_DN")
	)
	(segment
		(start 66.660776 -384.626104)
		(end 65.608708 -383.574036)
		(width 0.14224)
		(layer "In6.Cu")
		(net "CLK_100M_RETIMER_CPU1_P0_R_DN")
	)
	(segment
		(start 67.314572 -386.204714)
		(end 66.660776 -384.626104)
		(width 0.14224)
		(layer "In6.Cu")
		(net "CLK_100M_RETIMER_CPU1_P0_R_DN")
	)
	(segment
		(start 47.065692 -383.574036)
		(end 45.954188 -384.68554)
		(width 0.14224)
		(layer "In6.Cu")
		(net "CLK_100M_RETIMER_CPU1_P0_R_DN")
	)
	(segment
		(start 80.23225 -395.499844)
		(end 78.988158 -394.984478)
		(width 0.14224)
		(layer "In6.Cu")
		(net "CLK_100M_RETIMER_CPU1_P0_R_DN")
	)
	(segment
		(start 102.283768 -408.991054)
		(end 102.138988 -408.991054)
		(width 0.14224)
		(layer "In6.Cu")
		(net "CLK_100M_RETIMER_CPU1_P0_R_DN")
	)
	(segment
		(start 43.70324 -387.216904)
		(end 41.573704 -387.216904)
		(width 0.14224)
		(layer "In6.Cu")
		(net "CLK_100M_RETIMER_CPU1_P0_R_DN")
	)
	(segment
		(start 43.040554 -387.518402)
		(end 43.29811 -387.518402)
		(width 0.12954)
		(layer "F.Cu")
		(net "CLK_100M_RETIMER_CPU1_P0_DP")
	)
	(segment
		(start 43.801284 -387.506972)
		(end 44.168314 -387.506972)
		(width 0.12954)
		(layer "F.Cu")
		(net "CLK_100M_RETIMER_CPU1_P0_DP")
	)
	(segment
		(start 44.477432 -387.81609)
		(end 45.223176 -387.81609)
		(width 0.12954)
		(layer "F.Cu")
		(net "CLK_100M_RETIMER_CPU1_P0_DP")
	)
	(segment
		(start 43.543982 -387.764274)
		(end 43.801284 -387.506972)
		(width 0.12954)
		(layer "F.Cu")
		(net "CLK_100M_RETIMER_CPU1_P0_DP")
	)
	(segment
		(start 42.794682 -387.764274)
		(end 43.040554 -387.518402)
		(width 0.12954)
		(layer "F.Cu")
		(net "CLK_100M_RETIMER_CPU1_P0_DP")
	)
	(segment
		(start 45.223176 -387.81609)
		(end 45.292264 -387.747002)
		(width 0.1016)
		(layer "F.Cu")
		(net "CLK_100M_RETIMER_CPU1_P0_DP")
	)
	(segment
		(start 43.29811 -387.518402)
		(end 43.543982 -387.764274)
		(width 0.12954)
		(layer "F.Cu")
		(net "CLK_100M_RETIMER_CPU1_P0_DP")
	)
	(segment
		(start 45.292264 -387.747002)
		(end 45.498004 -387.747002)
		(width 0.1016)
		(layer "F.Cu")
		(net "CLK_100M_RETIMER_CPU1_P0_DP")
	)
	(segment
		(start 44.168314 -387.506972)
		(end 44.477432 -387.81609)
		(width 0.12954)
		(layer "F.Cu")
		(net "CLK_100M_RETIMER_CPU1_P0_DP")
	)
	(segment
		(start 45.498004 -387.747002)
		(end 45.582078 -387.831076)
		(width 0.1016)
		(layer "F.Cu")
		(net "CLK_100M_RETIMER_CPU1_P0_DP")
	)
	(segment
		(start 43.7769 -387.184392)
		(end 44.302172 -387.184392)
		(width 0.12954)
		(layer "F.Cu")
		(net "CLK_100M_RETIMER_CPU1_P0_DN")
	)
	(segment
		(start 44.61129 -387.49351)
		(end 45.204126 -387.49351)
		(width 0.12954)
		(layer "F.Cu")
		(net "CLK_100M_RETIMER_CPU1_P0_DN")
	)
	(segment
		(start 43.543982 -386.951474)
		(end 43.7769 -387.184392)
		(width 0.12954)
		(layer "F.Cu")
		(net "CLK_100M_RETIMER_CPU1_P0_DN")
	)
	(segment
		(start 43.03903 -387.195822)
		(end 43.299634 -387.195822)
		(width 0.12954)
		(layer "F.Cu")
		(net "CLK_100M_RETIMER_CPU1_P0_DN")
	)
	(segment
		(start 43.299634 -387.195822)
		(end 43.543982 -386.951474)
		(width 0.12954)
		(layer "F.Cu")
		(net "CLK_100M_RETIMER_CPU1_P0_DN")
	)
	(segment
		(start 45.241718 -387.531102)
		(end 46.101762 -387.531102)
		(width 0.1016)
		(layer "F.Cu")
		(net "CLK_100M_RETIMER_CPU1_P0_DN")
	)
	(segment
		(start 44.302172 -387.184392)
		(end 44.61129 -387.49351)
		(width 0.12954)
		(layer "F.Cu")
		(net "CLK_100M_RETIMER_CPU1_P0_DN")
	)
	(segment
		(start 42.794682 -386.951474)
		(end 43.03903 -387.195822)
		(width 0.12954)
		(layer "F.Cu")
		(net "CLK_100M_RETIMER_CPU1_P0_DN")
	)
	(segment
		(start 45.204126 -387.49351)
		(end 45.241718 -387.531102)
		(width 0.1016)
		(layer "F.Cu")
		(net "CLK_100M_RETIMER_CPU1_P0_DN")
	)
	(segment
		(start 364.382812 -396.171674)
		(end 364.653322 -395.901164)
		(width 0.12954)
		(layer "F.Cu")
		(net "CLK_100M_RETIMER_CPU0_P3_R_DP")
	)
	(segment
		(start 364.653322 -395.901164)
		(end 365.11611 -395.901164)
		(width 0.12954)
		(layer "F.Cu")
		(net "CLK_100M_RETIMER_CPU0_P3_R_DP")
	)
	(segment
		(start 286.631126 -420.942516)
		(end 286.542226 -421.031416)
		(width 0.12954)
		(layer "F.Cu")
		(net "CLK_100M_RETIMER_CPU0_P3_R_DP")
	)
	(segment
		(start 286.631126 -420.697914)
		(end 286.631126 -420.942516)
		(width 0.12954)
		(layer "F.Cu")
		(net "CLK_100M_RETIMER_CPU0_P3_R_DP")
	)
	(segment
		(start 286.542226 -421.031416)
		(end 286.542226 -422.05656)
		(width 0.12954)
		(layer "F.Cu")
		(net "CLK_100M_RETIMER_CPU0_P3_R_DP")
	)
	(segment
		(start 365.11611 -395.901164)
		(end 365.36122 -396.146274)
		(width 0.12954)
		(layer "F.Cu")
		(net "CLK_100M_RETIMER_CPU0_P3_R_DP")
	)
	(segment
		(start 286.542226 -422.05656)
		(end 286.812736 -422.32707)
		(width 0.12954)
		(layer "F.Cu")
		(net "CLK_100M_RETIMER_CPU0_P3_R_DP")
	)
	(via
		(at 284.005782 -404.215092)
		(size 0.508)
		(drill 0.254)
		(layers "F.Cu" "B.Cu")
		(net "CLK_100M_RETIMER_CPU0_P3_R_DP")
	)
	(via
		(at 364.382812 -396.171674)
		(size 0.508)
		(drill 0.254)
		(layers "F.Cu" "B.Cu")
		(net "CLK_100M_RETIMER_CPU0_P3_R_DP")
	)
	(via
		(at 286.812736 -422.32707)
		(size 0.508)
		(drill 0.254)
		(layers "F.Cu" "B.Cu")
		(net "CLK_100M_RETIMER_CPU0_P3_R_DP")
	)
	(segment
		(start 287.360614 -404.64232)
		(end 287.497774 -404.50516)
		(width 0.14224)
		(layer "In2.Cu")
		(net "CLK_100M_RETIMER_CPU0_P3_R_DP")
	)
	(segment
		(start 359.189782 -399.593054)
		(end 359.189782 -398.522444)
		(width 0.14224)
		(layer "In2.Cu")
		(net "CLK_100M_RETIMER_CPU0_P3_R_DP")
	)
	(segment
		(start 288.671254 -404.64232)
		(end 288.808414 -404.50516)
		(width 0.14224)
		(layer "In2.Cu")
		(net "CLK_100M_RETIMER_CPU0_P3_R_DP")
	)
	(segment
		(start 285.789116 -403.924262)
		(end 286.370014 -404.50516)
		(width 0.14224)
		(layer "In2.Cu")
		(net "CLK_100M_RETIMER_CPU0_P3_R_DP")
	)
	(segment
		(start 359.189782 -401.119086)
		(end 359.189782 -400.294094)
		(width 0.14224)
		(layer "In2.Cu")
		(net "CLK_100M_RETIMER_CPU0_P3_R_DP")
	)
	(segment
		(start 286.370014 -404.50516)
		(end 286.796734 -404.50516)
		(width 0.14224)
		(layer "In2.Cu")
		(net "CLK_100M_RETIMER_CPU0_P3_R_DP")
	)
	(segment
		(start 355.624892 -402.649944)
		(end 357.658924 -402.649944)
		(width 0.14224)
		(layer "In2.Cu")
		(net "CLK_100M_RETIMER_CPU0_P3_R_DP")
	)
	(segment
		(start 359.326942 -400.156934)
		(end 359.326942 -399.730214)
		(width 0.14224)
		(layer "In2.Cu")
		(net "CLK_100M_RETIMER_CPU0_P3_R_DP")
	)
	(segment
		(start 284.296612 -403.924262)
		(end 285.789116 -403.924262)
		(width 0.14224)
		(layer "In2.Cu")
		(net "CLK_100M_RETIMER_CPU0_P3_R_DP")
	)
	(segment
		(start 360.859832 -397.711422)
		(end 362.69041 -395.880844)
		(width 0.14224)
		(layer "In2.Cu")
		(net "CLK_100M_RETIMER_CPU0_P3_R_DP")
	)
	(segment
		(start 359.326942 -399.730214)
		(end 359.189782 -399.593054)
		(width 0.14224)
		(layer "In2.Cu")
		(net "CLK_100M_RETIMER_CPU0_P3_R_DP")
	)
	(segment
		(start 299.560234 -401.564602)
		(end 300.499018 -402.503386)
		(width 0.14224)
		(layer "In2.Cu")
		(net "CLK_100M_RETIMER_CPU0_P3_R_DP")
	)
	(segment
		(start 358.14127 -402.167598)
		(end 358.335326 -402.167598)
		(width 0.14224)
		(layer "In2.Cu")
		(net "CLK_100M_RETIMER_CPU0_P3_R_DP")
	)
	(segment
		(start 359.189782 -398.522444)
		(end 360.000804 -397.711422)
		(width 0.14224)
		(layer "In2.Cu")
		(net "CLK_100M_RETIMER_CPU0_P3_R_DP")
	)
	(segment
		(start 288.244534 -404.64232)
		(end 288.671254 -404.64232)
		(width 0.14224)
		(layer "In2.Cu")
		(net "CLK_100M_RETIMER_CPU0_P3_R_DP")
	)
	(segment
		(start 288.107374 -404.50516)
		(end 288.244534 -404.64232)
		(width 0.14224)
		(layer "In2.Cu")
		(net "CLK_100M_RETIMER_CPU0_P3_R_DP")
	)
	(segment
		(start 300.695868 -402.97862)
		(end 302.006 -404.288752)
		(width 0.14224)
		(layer "In2.Cu")
		(net "CLK_100M_RETIMER_CPU0_P3_R_DP")
	)
	(segment
		(start 286.933894 -404.64232)
		(end 287.360614 -404.64232)
		(width 0.14224)
		(layer "In2.Cu")
		(net "CLK_100M_RETIMER_CPU0_P3_R_DP")
	)
	(segment
		(start 292.210998 -404.50516)
		(end 295.151556 -401.564602)
		(width 0.14224)
		(layer "In2.Cu")
		(net "CLK_100M_RETIMER_CPU0_P3_R_DP")
	)
	(segment
		(start 300.499018 -402.503386)
		(end 300.695868 -402.97862)
		(width 0.14224)
		(layer "In2.Cu")
		(net "CLK_100M_RETIMER_CPU0_P3_R_DP")
	)
	(segment
		(start 362.69041 -395.880844)
		(end 364.091982 -395.880844)
		(width 0.14224)
		(layer "In2.Cu")
		(net "CLK_100M_RETIMER_CPU0_P3_R_DP")
	)
	(segment
		(start 295.151556 -401.564602)
		(end 299.560234 -401.564602)
		(width 0.14224)
		(layer "In2.Cu")
		(net "CLK_100M_RETIMER_CPU0_P3_R_DP")
	)
	(segment
		(start 302.006 -404.288752)
		(end 353.986084 -404.288752)
		(width 0.14224)
		(layer "In2.Cu")
		(net "CLK_100M_RETIMER_CPU0_P3_R_DP")
	)
	(segment
		(start 353.986084 -404.288752)
		(end 355.624892 -402.649944)
		(width 0.14224)
		(layer "In2.Cu")
		(net "CLK_100M_RETIMER_CPU0_P3_R_DP")
	)
	(segment
		(start 359.189782 -400.294094)
		(end 359.326942 -400.156934)
		(width 0.14224)
		(layer "In2.Cu")
		(net "CLK_100M_RETIMER_CPU0_P3_R_DP")
	)
	(segment
		(start 364.091982 -395.880844)
		(end 364.382812 -396.171674)
		(width 0.14224)
		(layer "In2.Cu")
		(net "CLK_100M_RETIMER_CPU0_P3_R_DP")
	)
	(segment
		(start 358.335326 -402.167598)
		(end 358.637332 -401.865592)
		(width 0.14224)
		(layer "In2.Cu")
		(net "CLK_100M_RETIMER_CPU0_P3_R_DP")
	)
	(segment
		(start 358.637332 -401.671536)
		(end 359.189782 -401.119086)
		(width 0.14224)
		(layer "In2.Cu")
		(net "CLK_100M_RETIMER_CPU0_P3_R_DP")
	)
	(segment
		(start 284.005782 -404.215092)
		(end 284.296612 -403.924262)
		(width 0.14224)
		(layer "In2.Cu")
		(net "CLK_100M_RETIMER_CPU0_P3_R_DP")
	)
	(segment
		(start 286.796734 -404.50516)
		(end 286.933894 -404.64232)
		(width 0.14224)
		(layer "In2.Cu")
		(net "CLK_100M_RETIMER_CPU0_P3_R_DP")
	)
	(segment
		(start 358.637332 -401.865592)
		(end 358.637332 -401.671536)
		(width 0.14224)
		(layer "In2.Cu")
		(net "CLK_100M_RETIMER_CPU0_P3_R_DP")
	)
	(segment
		(start 360.000804 -397.711422)
		(end 360.859832 -397.711422)
		(width 0.14224)
		(layer "In2.Cu")
		(net "CLK_100M_RETIMER_CPU0_P3_R_DP")
	)
	(segment
		(start 287.497774 -404.50516)
		(end 288.107374 -404.50516)
		(width 0.14224)
		(layer "In2.Cu")
		(net "CLK_100M_RETIMER_CPU0_P3_R_DP")
	)
	(segment
		(start 288.808414 -404.50516)
		(end 292.210998 -404.50516)
		(width 0.14224)
		(layer "In2.Cu")
		(net "CLK_100M_RETIMER_CPU0_P3_R_DP")
	)
	(segment
		(start 357.658924 -402.649944)
		(end 358.14127 -402.167598)
		(width 0.14224)
		(layer "In2.Cu")
		(net "CLK_100M_RETIMER_CPU0_P3_R_DP")
	)
	(segment
		(start 284.044898 -415.74466)
		(end 284.764734 -415.024824)
		(width 0.14224)
		(layer "In13.Cu")
		(net "CLK_100M_RETIMER_CPU0_P3_R_DP")
	)
	(segment
		(start 284.901894 -413.333184)
		(end 284.901894 -412.906464)
		(width 0.14224)
		(layer "In13.Cu")
		(net "CLK_100M_RETIMER_CPU0_P3_R_DP")
	)
	(segment
		(start 284.901894 -410.650944)
		(end 284.764734 -410.513784)
		(width 0.14224)
		(layer "In13.Cu")
		(net "CLK_100M_RETIMER_CPU0_P3_R_DP")
	)
	(segment
		(start 283.449522 -403.924262)
		(end 283.714952 -403.924262)
		(width 0.14224)
		(layer "In13.Cu")
		(net "CLK_100M_RETIMER_CPU0_P3_R_DP")
	)
	(segment
		(start 286.521906 -420.785798)
		(end 286.137858 -420.40175)
		(width 0.14224)
		(layer "In13.Cu")
		(net "CLK_100M_RETIMER_CPU0_P3_R_DP")
	)
	(segment
		(start 284.764734 -412.342584)
		(end 284.901894 -412.205424)
		(width 0.14224)
		(layer "In13.Cu")
		(net "CLK_100M_RETIMER_CPU0_P3_R_DP")
	)
	(segment
		(start 284.764734 -413.897064)
		(end 284.764734 -413.470344)
		(width 0.14224)
		(layer "In13.Cu")
		(net "CLK_100M_RETIMER_CPU0_P3_R_DP")
	)
	(segment
		(start 284.901894 -411.778704)
		(end 284.764734 -411.641544)
		(width 0.14224)
		(layer "In13.Cu")
		(net "CLK_100M_RETIMER_CPU0_P3_R_DP")
	)
	(segment
		(start 284.321504 -420.40175)
		(end 284.044898 -420.125144)
		(width 0.14224)
		(layer "In13.Cu")
		(net "CLK_100M_RETIMER_CPU0_P3_R_DP")
	)
	(segment
		(start 284.901894 -412.906464)
		(end 284.764734 -412.769304)
		(width 0.14224)
		(layer "In13.Cu")
		(net "CLK_100M_RETIMER_CPU0_P3_R_DP")
	)
	(segment
		(start 284.764734 -410.513784)
		(end 284.764734 -406.27046)
		(width 0.14224)
		(layer "In13.Cu")
		(net "CLK_100M_RETIMER_CPU0_P3_R_DP")
	)
	(segment
		(start 286.812736 -422.32707)
		(end 286.521906 -422.03624)
		(width 0.14224)
		(layer "In13.Cu")
		(net "CLK_100M_RETIMER_CPU0_P3_R_DP")
	)
	(segment
		(start 283.322522 -404.051262)
		(end 283.449522 -403.924262)
		(width 0.14224)
		(layer "In13.Cu")
		(net "CLK_100M_RETIMER_CPU0_P3_R_DP")
	)
	(segment
		(start 284.901894 -414.460944)
		(end 284.901894 -414.034224)
		(width 0.14224)
		(layer "In13.Cu")
		(net "CLK_100M_RETIMER_CPU0_P3_R_DP")
	)
	(segment
		(start 284.764734 -415.024824)
		(end 284.764734 -414.598104)
		(width 0.14224)
		(layer "In13.Cu")
		(net "CLK_100M_RETIMER_CPU0_P3_R_DP")
	)
	(segment
		(start 284.764734 -411.641544)
		(end 284.764734 -411.214824)
		(width 0.14224)
		(layer "In13.Cu")
		(net "CLK_100M_RETIMER_CPU0_P3_R_DP")
	)
	(segment
		(start 284.764734 -414.598104)
		(end 284.901894 -414.460944)
		(width 0.14224)
		(layer "In13.Cu")
		(net "CLK_100M_RETIMER_CPU0_P3_R_DP")
	)
	(segment
		(start 284.764734 -412.769304)
		(end 284.764734 -412.342584)
		(width 0.14224)
		(layer "In13.Cu")
		(net "CLK_100M_RETIMER_CPU0_P3_R_DP")
	)
	(segment
		(start 284.901894 -414.034224)
		(end 284.764734 -413.897064)
		(width 0.14224)
		(layer "In13.Cu")
		(net "CLK_100M_RETIMER_CPU0_P3_R_DP")
	)
	(segment
		(start 284.044898 -420.125144)
		(end 284.044898 -415.74466)
		(width 0.14224)
		(layer "In13.Cu")
		(net "CLK_100M_RETIMER_CPU0_P3_R_DP")
	)
	(segment
		(start 283.714952 -403.924262)
		(end 284.005782 -404.215092)
		(width 0.14224)
		(layer "In13.Cu")
		(net "CLK_100M_RETIMER_CPU0_P3_R_DP")
	)
	(segment
		(start 286.521906 -422.03624)
		(end 286.521906 -420.785798)
		(width 0.14224)
		(layer "In13.Cu")
		(net "CLK_100M_RETIMER_CPU0_P3_R_DP")
	)
	(segment
		(start 284.764734 -411.214824)
		(end 284.901894 -411.077664)
		(width 0.14224)
		(layer "In13.Cu")
		(net "CLK_100M_RETIMER_CPU0_P3_R_DP")
	)
	(segment
		(start 284.901894 -411.077664)
		(end 284.901894 -410.650944)
		(width 0.14224)
		(layer "In13.Cu")
		(net "CLK_100M_RETIMER_CPU0_P3_R_DP")
	)
	(segment
		(start 284.901894 -412.205424)
		(end 284.901894 -411.778704)
		(width 0.14224)
		(layer "In13.Cu")
		(net "CLK_100M_RETIMER_CPU0_P3_R_DP")
	)
	(segment
		(start 284.764734 -413.470344)
		(end 284.901894 -413.333184)
		(width 0.14224)
		(layer "In13.Cu")
		(net "CLK_100M_RETIMER_CPU0_P3_R_DP")
	)
	(segment
		(start 284.764734 -406.27046)
		(end 283.322522 -404.828248)
		(width 0.14224)
		(layer "In13.Cu")
		(net "CLK_100M_RETIMER_CPU0_P3_R_DP")
	)
	(segment
		(start 286.137858 -420.40175)
		(end 284.321504 -420.40175)
		(width 0.14224)
		(layer "In13.Cu")
		(net "CLK_100M_RETIMER_CPU0_P3_R_DP")
	)
	(segment
		(start 283.322522 -404.828248)
		(end 283.322522 -404.051262)
		(width 0.14224)
		(layer "In13.Cu")
		(net "CLK_100M_RETIMER_CPU0_P3_R_DP")
	)
	(segment
		(start 286.219646 -421.029384)
		(end 286.219646 -422.05656)
		(width 0.12954)
		(layer "F.Cu")
		(net "CLK_100M_RETIMER_CPU0_P3_R_DN")
	)
	(segment
		(start 365.11611 -395.578584)
		(end 365.36122 -395.333474)
		(width 0.12954)
		(layer "F.Cu")
		(net "CLK_100M_RETIMER_CPU0_P3_R_DN")
	)
	(segment
		(start 286.131 -420.940738)
		(end 286.219646 -421.029384)
		(width 0.12954)
		(layer "F.Cu")
		(net "CLK_100M_RETIMER_CPU0_P3_R_DN")
	)
	(segment
		(start 364.653322 -395.578584)
		(end 365.11611 -395.578584)
		(width 0.12954)
		(layer "F.Cu")
		(net "CLK_100M_RETIMER_CPU0_P3_R_DN")
	)
	(segment
		(start 286.131 -420.697914)
		(end 286.131 -420.940738)
		(width 0.12954)
		(layer "F.Cu")
		(net "CLK_100M_RETIMER_CPU0_P3_R_DN")
	)
	(segment
		(start 286.219646 -422.05656)
		(end 285.949136 -422.32707)
		(width 0.12954)
		(layer "F.Cu")
		(net "CLK_100M_RETIMER_CPU0_P3_R_DN")
	)
	(segment
		(start 364.382812 -395.308074)
		(end 364.653322 -395.578584)
		(width 0.12954)
		(layer "F.Cu")
		(net "CLK_100M_RETIMER_CPU0_P3_R_DN")
	)
	(via
		(at 364.382812 -395.308074)
		(size 0.508)
		(drill 0.254)
		(layers "F.Cu" "B.Cu")
		(net "CLK_100M_RETIMER_CPU0_P3_R_DN")
	)
	(via
		(at 285.949136 -422.32707)
		(size 0.508)
		(drill 0.254)
		(layers "F.Cu" "B.Cu")
		(net "CLK_100M_RETIMER_CPU0_P3_R_DN")
	)
	(via
		(at 284.005782 -403.351492)
		(size 0.508)
		(drill 0.254)
		(layers "F.Cu" "B.Cu")
		(net "CLK_100M_RETIMER_CPU0_P3_R_DN")
	)
	(segment
		(start 292.094158 -404.22322)
		(end 295.034716 -401.282662)
		(width 0.14224)
		(layer "In2.Cu")
		(net "CLK_100M_RETIMER_CPU0_P3_R_DN")
	)
	(segment
		(start 300.738032 -402.34362)
		(end 300.934882 -402.818854)
		(width 0.14224)
		(layer "In2.Cu")
		(net "CLK_100M_RETIMER_CPU0_P3_R_DN")
	)
	(segment
		(start 362.57357 -395.598904)
		(end 364.091982 -395.598904)
		(width 0.14224)
		(layer "In2.Cu")
		(net "CLK_100M_RETIMER_CPU0_P3_R_DN")
	)
	(segment
		(start 302.12284 -404.006812)
		(end 353.869244 -404.006812)
		(width 0.14224)
		(layer "In2.Cu")
		(net "CLK_100M_RETIMER_CPU0_P3_R_DN")
	)
	(segment
		(start 359.883964 -397.429482)
		(end 360.742992 -397.429482)
		(width 0.14224)
		(layer "In2.Cu")
		(net "CLK_100M_RETIMER_CPU0_P3_R_DN")
	)
	(segment
		(start 284.005782 -403.351492)
		(end 284.296612 -403.642322)
		(width 0.14224)
		(layer "In2.Cu")
		(net "CLK_100M_RETIMER_CPU0_P3_R_DN")
	)
	(segment
		(start 284.296612 -403.642322)
		(end 285.905956 -403.642322)
		(width 0.14224)
		(layer "In2.Cu")
		(net "CLK_100M_RETIMER_CPU0_P3_R_DN")
	)
	(segment
		(start 355.508052 -402.368004)
		(end 357.542084 -402.368004)
		(width 0.14224)
		(layer "In2.Cu")
		(net "CLK_100M_RETIMER_CPU0_P3_R_DN")
	)
	(segment
		(start 295.034716 -401.282662)
		(end 299.677074 -401.282662)
		(width 0.14224)
		(layer "In2.Cu")
		(net "CLK_100M_RETIMER_CPU0_P3_R_DN")
	)
	(segment
		(start 285.905956 -403.642322)
		(end 286.486854 -404.22322)
		(width 0.14224)
		(layer "In2.Cu")
		(net "CLK_100M_RETIMER_CPU0_P3_R_DN")
	)
	(segment
		(start 353.869244 -404.006812)
		(end 355.508052 -402.368004)
		(width 0.14224)
		(layer "In2.Cu")
		(net "CLK_100M_RETIMER_CPU0_P3_R_DN")
	)
	(segment
		(start 358.907842 -398.405604)
		(end 359.883964 -397.429482)
		(width 0.14224)
		(layer "In2.Cu")
		(net "CLK_100M_RETIMER_CPU0_P3_R_DN")
	)
	(segment
		(start 358.907842 -401.002246)
		(end 358.907842 -398.405604)
		(width 0.14224)
		(layer "In2.Cu")
		(net "CLK_100M_RETIMER_CPU0_P3_R_DN")
	)
	(segment
		(start 300.934882 -402.818854)
		(end 302.12284 -404.006812)
		(width 0.14224)
		(layer "In2.Cu")
		(net "CLK_100M_RETIMER_CPU0_P3_R_DN")
	)
	(segment
		(start 299.677074 -401.282662)
		(end 300.738032 -402.34362)
		(width 0.14224)
		(layer "In2.Cu")
		(net "CLK_100M_RETIMER_CPU0_P3_R_DN")
	)
	(segment
		(start 364.091982 -395.598904)
		(end 364.382812 -395.308074)
		(width 0.14224)
		(layer "In2.Cu")
		(net "CLK_100M_RETIMER_CPU0_P3_R_DN")
	)
	(segment
		(start 286.486854 -404.22322)
		(end 292.094158 -404.22322)
		(width 0.14224)
		(layer "In2.Cu")
		(net "CLK_100M_RETIMER_CPU0_P3_R_DN")
	)
	(segment
		(start 357.542084 -402.368004)
		(end 358.907842 -401.002246)
		(width 0.14224)
		(layer "In2.Cu")
		(net "CLK_100M_RETIMER_CPU0_P3_R_DN")
	)
	(segment
		(start 360.742992 -397.429482)
		(end 362.57357 -395.598904)
		(width 0.14224)
		(layer "In2.Cu")
		(net "CLK_100M_RETIMER_CPU0_P3_R_DN")
	)
	(segment
		(start 284.482794 -406.3873)
		(end 283.040582 -404.945088)
		(width 0.14224)
		(layer "In13.Cu")
		(net "CLK_100M_RETIMER_CPU0_P3_R_DN")
	)
	(segment
		(start 283.762958 -420.241984)
		(end 283.762958 -415.62782)
		(width 0.14224)
		(layer "In13.Cu")
		(net "CLK_100M_RETIMER_CPU0_P3_R_DN")
	)
	(segment
		(start 285.949136 -422.32707)
		(end 286.239966 -422.03624)
		(width 0.14224)
		(layer "In13.Cu")
		(net "CLK_100M_RETIMER_CPU0_P3_R_DN")
	)
	(segment
		(start 283.332682 -403.642322)
		(end 283.714952 -403.642322)
		(width 0.14224)
		(layer "In13.Cu")
		(net "CLK_100M_RETIMER_CPU0_P3_R_DN")
	)
	(segment
		(start 286.021018 -420.68369)
		(end 284.204664 -420.68369)
		(width 0.14224)
		(layer "In13.Cu")
		(net "CLK_100M_RETIMER_CPU0_P3_R_DN")
	)
	(segment
		(start 283.762958 -415.62782)
		(end 284.482794 -414.907984)
		(width 0.14224)
		(layer "In13.Cu")
		(net "CLK_100M_RETIMER_CPU0_P3_R_DN")
	)
	(segment
		(start 283.040582 -404.945088)
		(end 283.040582 -403.934422)
		(width 0.14224)
		(layer "In13.Cu")
		(net "CLK_100M_RETIMER_CPU0_P3_R_DN")
	)
	(segment
		(start 283.040582 -403.934422)
		(end 283.332682 -403.642322)
		(width 0.14224)
		(layer "In13.Cu")
		(net "CLK_100M_RETIMER_CPU0_P3_R_DN")
	)
	(segment
		(start 284.482794 -414.907984)
		(end 284.482794 -406.3873)
		(width 0.14224)
		(layer "In13.Cu")
		(net "CLK_100M_RETIMER_CPU0_P3_R_DN")
	)
	(segment
		(start 284.204664 -420.68369)
		(end 283.762958 -420.241984)
		(width 0.14224)
		(layer "In13.Cu")
		(net "CLK_100M_RETIMER_CPU0_P3_R_DN")
	)
	(segment
		(start 286.239966 -422.03624)
		(end 286.239966 -420.902638)
		(width 0.14224)
		(layer "In13.Cu")
		(net "CLK_100M_RETIMER_CPU0_P3_R_DN")
	)
	(segment
		(start 283.714952 -403.642322)
		(end 284.005782 -403.351492)
		(width 0.14224)
		(layer "In13.Cu")
		(net "CLK_100M_RETIMER_CPU0_P3_R_DN")
	)
	(segment
		(start 286.239966 -420.902638)
		(end 286.021018 -420.68369)
		(width 0.14224)
		(layer "In13.Cu")
		(net "CLK_100M_RETIMER_CPU0_P3_R_DN")
	)
	(segment
		(start 366.140492 -395.900402)
		(end 366.398048 -395.900402)
		(width 0.12954)
		(layer "F.Cu")
		(net "CLK_100M_RETIMER_CPU0_P3_DP")
	)
	(segment
		(start 366.398048 -395.900402)
		(end 366.64392 -396.146274)
		(width 0.12954)
		(layer "F.Cu")
		(net "CLK_100M_RETIMER_CPU0_P3_DP")
	)
	(segment
		(start 366.64392 -396.146274)
		(end 366.901222 -395.888972)
		(width 0.12954)
		(layer "F.Cu")
		(net "CLK_100M_RETIMER_CPU0_P3_DP")
	)
	(segment
		(start 368.323114 -396.19809)
		(end 368.392202 -396.129002)
		(width 0.1016)
		(layer "F.Cu")
		(net "CLK_100M_RETIMER_CPU0_P3_DP")
	)
	(segment
		(start 367.268252 -395.888972)
		(end 367.57737 -396.19809)
		(width 0.12954)
		(layer "F.Cu")
		(net "CLK_100M_RETIMER_CPU0_P3_DP")
	)
	(segment
		(start 365.89462 -396.146274)
		(end 366.140492 -395.900402)
		(width 0.12954)
		(layer "F.Cu")
		(net "CLK_100M_RETIMER_CPU0_P3_DP")
	)
	(segment
		(start 367.57737 -396.19809)
		(end 368.323114 -396.19809)
		(width 0.12954)
		(layer "F.Cu")
		(net "CLK_100M_RETIMER_CPU0_P3_DP")
	)
	(segment
		(start 368.392202 -396.129002)
		(end 368.597942 -396.129002)
		(width 0.1016)
		(layer "F.Cu")
		(net "CLK_100M_RETIMER_CPU0_P3_DP")
	)
	(segment
		(start 368.597942 -396.129002)
		(end 368.682016 -396.213076)
		(width 0.1016)
		(layer "F.Cu")
		(net "CLK_100M_RETIMER_CPU0_P3_DP")
	)
	(segment
		(start 366.901222 -395.888972)
		(end 367.268252 -395.888972)
		(width 0.12954)
		(layer "F.Cu")
		(net "CLK_100M_RETIMER_CPU0_P3_DP")
	)
	(segment
		(start 366.399572 -395.577822)
		(end 366.64392 -395.333474)
		(width 0.12954)
		(layer "F.Cu")
		(net "CLK_100M_RETIMER_CPU0_P3_DN")
	)
	(segment
		(start 366.138968 -395.577822)
		(end 366.399572 -395.577822)
		(width 0.12954)
		(layer "F.Cu")
		(net "CLK_100M_RETIMER_CPU0_P3_DN")
	)
	(segment
		(start 366.876838 -395.566392)
		(end 367.40211 -395.566392)
		(width 0.12954)
		(layer "F.Cu")
		(net "CLK_100M_RETIMER_CPU0_P3_DN")
	)
	(segment
		(start 367.711228 -395.87551)
		(end 368.304064 -395.87551)
		(width 0.12954)
		(layer "F.Cu")
		(net "CLK_100M_RETIMER_CPU0_P3_DN")
	)
	(segment
		(start 366.64392 -395.333474)
		(end 366.876838 -395.566392)
		(width 0.12954)
		(layer "F.Cu")
		(net "CLK_100M_RETIMER_CPU0_P3_DN")
	)
	(segment
		(start 368.341656 -395.913102)
		(end 369.2017 -395.913102)
		(width 0.1016)
		(layer "F.Cu")
		(net "CLK_100M_RETIMER_CPU0_P3_DN")
	)
	(segment
		(start 365.89462 -395.333474)
		(end 366.138968 -395.577822)
		(width 0.12954)
		(layer "F.Cu")
		(net "CLK_100M_RETIMER_CPU0_P3_DN")
	)
	(segment
		(start 368.304064 -395.87551)
		(end 368.341656 -395.913102)
		(width 0.1016)
		(layer "F.Cu")
		(net "CLK_100M_RETIMER_CPU0_P3_DN")
	)
	(segment
		(start 367.40211 -395.566392)
		(end 367.711228 -395.87551)
		(width 0.12954)
		(layer "F.Cu")
		(net "CLK_100M_RETIMER_CPU0_P3_DN")
	)
	(segment
		(start 288.589466 -419.161976)
		(end 289.146234 -419.161976)
		(width 0.12954)
		(layer "F.Cu")
		(net "CLK_100M_RETIMER_CPU0_P2_R_DP")
	)
	(segment
		(start 289.146234 -419.161976)
		(end 289.9156 -419.931342)
		(width 0.12954)
		(layer "F.Cu")
		(net "CLK_100M_RETIMER_CPU0_P2_R_DP")
	)
	(segment
		(start 396.91056 -396.171674)
		(end 397.18107 -395.901164)
		(width 0.12954)
		(layer "F.Cu")
		(net "CLK_100M_RETIMER_CPU0_P2_R_DP")
	)
	(segment
		(start 290.940744 -419.931342)
		(end 291.211254 -419.660832)
		(width 0.12954)
		(layer "F.Cu")
		(net "CLK_100M_RETIMER_CPU0_P2_R_DP")
	)
	(segment
		(start 288.500566 -419.073076)
		(end 288.589466 -419.161976)
		(width 0.12954)
		(layer "F.Cu")
		(net "CLK_100M_RETIMER_CPU0_P2_R_DP")
	)
	(segment
		(start 289.9156 -419.931342)
		(end 290.940744 -419.931342)
		(width 0.12954)
		(layer "F.Cu")
		(net "CLK_100M_RETIMER_CPU0_P2_R_DP")
	)
	(segment
		(start 397.18107 -395.901164)
		(end 397.643858 -395.901164)
		(width 0.12954)
		(layer "F.Cu")
		(net "CLK_100M_RETIMER_CPU0_P2_R_DP")
	)
	(segment
		(start 288.255964 -419.073076)
		(end 288.500566 -419.073076)
		(width 0.12954)
		(layer "F.Cu")
		(net "CLK_100M_RETIMER_CPU0_P2_R_DP")
	)
	(segment
		(start 397.643858 -395.901164)
		(end 397.888968 -396.146274)
		(width 0.12954)
		(layer "F.Cu")
		(net "CLK_100M_RETIMER_CPU0_P2_R_DP")
	)
	(via
		(at 291.211254 -419.660832)
		(size 0.508)
		(drill 0.254)
		(layers "F.Cu" "B.Cu")
		(net "CLK_100M_RETIMER_CPU0_P2_R_DP")
	)
	(via
		(at 287.483296 -407.414222)
		(size 0.508)
		(drill 0.254)
		(layers "F.Cu" "B.Cu")
		(net "CLK_100M_RETIMER_CPU0_P2_R_DP")
	)
	(via
		(at 396.91056 -396.171674)
		(size 0.508)
		(drill 0.254)
		(layers "F.Cu" "B.Cu")
		(net "CLK_100M_RETIMER_CPU0_P2_R_DP")
	)
	(segment
		(start 359.786428 -403.899878)
		(end 359.786682 -403.899624)
		(width 0.14224)
		(layer "In2.Cu")
		(net "CLK_100M_RETIMER_CPU0_P2_R_DP")
	)
	(segment
		(start 291.747448 -406.227026)
		(end 291.747448 -406.033224)
		(width 0.14224)
		(layer "In2.Cu")
		(net "CLK_100M_RETIMER_CPU0_P2_R_DP")
	)
	(segment
		(start 291.445442 -406.529032)
		(end 291.747448 -406.227026)
		(width 0.14224)
		(layer "In2.Cu")
		(net "CLK_100M_RETIMER_CPU0_P2_R_DP")
	)
	(segment
		(start 395.094206 -395.427454)
		(end 395.489176 -395.427454)
		(width 0.14224)
		(layer "In2.Cu")
		(net "CLK_100M_RETIMER_CPU0_P2_R_DP")
	)
	(segment
		(start 396.61973 -395.880844)
		(end 396.91056 -396.171674)
		(width 0.14224)
		(layer "In2.Cu")
		(net "CLK_100M_RETIMER_CPU0_P2_R_DP")
	)
	(segment
		(start 392.709146 -398.757648)
		(end 394.28801 -397.178784)
		(width 0.14224)
		(layer "In2.Cu")
		(net "CLK_100M_RETIMER_CPU0_P2_R_DP")
	)
	(segment
		(start 390.271254 -400.979386)
		(end 390.786112 -400.464528)
		(width 0.14224)
		(layer "In2.Cu")
		(net "CLK_100M_RETIMER_CPU0_P2_R_DP")
	)
	(segment
		(start 288.750502 -407.260552)
		(end 289.177222 -407.260552)
		(width 0.14224)
		(layer "In2.Cu")
		(net "CLK_100M_RETIMER_CPU0_P2_R_DP")
	)
	(segment
		(start 392.40714 -399.25371)
		(end 392.709146 -398.951704)
		(width 0.14224)
		(layer "In2.Cu")
		(net "CLK_100M_RETIMER_CPU0_P2_R_DP")
	)
	(segment
		(start 296.35323 -404.627588)
		(end 299.582332 -404.627588)
		(width 0.14224)
		(layer "In2.Cu")
		(net "CLK_100M_RETIMER_CPU0_P2_R_DP")
	)
	(segment
		(start 394.28801 -397.178784)
		(end 394.28801 -396.23365)
		(width 0.14224)
		(layer "In2.Cu")
		(net "CLK_100M_RETIMER_CPU0_P2_R_DP")
	)
	(segment
		(start 392.709146 -398.951704)
		(end 392.709146 -398.757648)
		(width 0.14224)
		(layer "In2.Cu")
		(net "CLK_100M_RETIMER_CPU0_P2_R_DP")
	)
	(segment
		(start 289.314382 -407.123392)
		(end 290.65728 -407.123392)
		(width 0.14224)
		(layer "In2.Cu")
		(net "CLK_100M_RETIMER_CPU0_P2_R_DP")
	)
	(segment
		(start 394.28801 -396.23365)
		(end 395.094206 -395.427454)
		(width 0.14224)
		(layer "In2.Cu")
		(net "CLK_100M_RETIMER_CPU0_P2_R_DP")
	)
	(segment
		(start 354.822252 -405.9555)
		(end 359.786428 -403.899878)
		(width 0.14224)
		(layer "In2.Cu")
		(net "CLK_100M_RETIMER_CPU0_P2_R_DP")
	)
	(segment
		(start 391.60958 -400.051016)
		(end 391.911586 -399.74901)
		(width 0.14224)
		(layer "In2.Cu")
		(net "CLK_100M_RETIMER_CPU0_P2_R_DP")
	)
	(segment
		(start 390.633204 -402.867876)
		(end 390.633204 -402.281644)
		(width 0.14224)
		(layer "In2.Cu")
		(net "CLK_100M_RETIMER_CPU0_P2_R_DP")
	)
	(segment
		(start 291.25164 -406.529032)
		(end 291.445442 -406.529032)
		(width 0.14224)
		(layer "In2.Cu")
		(net "CLK_100M_RETIMER_CPU0_P2_R_DP")
	)
	(segment
		(start 395.942566 -395.880844)
		(end 396.61973 -395.880844)
		(width 0.14224)
		(layer "In2.Cu")
		(net "CLK_100M_RETIMER_CPU0_P2_R_DP")
	)
	(segment
		(start 287.483296 -407.414222)
		(end 287.774126 -407.123392)
		(width 0.14224)
		(layer "In2.Cu")
		(net "CLK_100M_RETIMER_CPU0_P2_R_DP")
	)
	(segment
		(start 295.526714 -405.454104)
		(end 296.35323 -404.627588)
		(width 0.14224)
		(layer "In2.Cu")
		(net "CLK_100M_RETIMER_CPU0_P2_R_DP")
	)
	(segment
		(start 292.326568 -405.454104)
		(end 295.526714 -405.454104)
		(width 0.14224)
		(layer "In2.Cu")
		(net "CLK_100M_RETIMER_CPU0_P2_R_DP")
	)
	(segment
		(start 389.601456 -403.899624)
		(end 390.633204 -402.867876)
		(width 0.14224)
		(layer "In2.Cu")
		(net "CLK_100M_RETIMER_CPU0_P2_R_DP")
	)
	(segment
		(start 390.633204 -402.281644)
		(end 390.271254 -401.40763)
		(width 0.14224)
		(layer "In2.Cu")
		(net "CLK_100M_RETIMER_CPU0_P2_R_DP")
	)
	(segment
		(start 390.271254 -401.40763)
		(end 390.271254 -400.979386)
		(width 0.14224)
		(layer "In2.Cu")
		(net "CLK_100M_RETIMER_CPU0_P2_R_DP")
	)
	(segment
		(start 391.415778 -400.051016)
		(end 391.60958 -400.051016)
		(width 0.14224)
		(layer "In2.Cu")
		(net "CLK_100M_RETIMER_CPU0_P2_R_DP")
	)
	(segment
		(start 390.786112 -400.464528)
		(end 391.002266 -400.464528)
		(width 0.14224)
		(layer "In2.Cu")
		(net "CLK_100M_RETIMER_CPU0_P2_R_DP")
	)
	(segment
		(start 392.213084 -399.25371)
		(end 392.40714 -399.25371)
		(width 0.14224)
		(layer "In2.Cu")
		(net "CLK_100M_RETIMER_CPU0_P2_R_DP")
	)
	(segment
		(start 287.774126 -407.123392)
		(end 288.613342 -407.123392)
		(width 0.14224)
		(layer "In2.Cu")
		(net "CLK_100M_RETIMER_CPU0_P2_R_DP")
	)
	(segment
		(start 395.489176 -395.427454)
		(end 395.942566 -395.880844)
		(width 0.14224)
		(layer "In2.Cu")
		(net "CLK_100M_RETIMER_CPU0_P2_R_DP")
	)
	(segment
		(start 300.910244 -405.9555)
		(end 354.822252 -405.9555)
		(width 0.14224)
		(layer "In2.Cu")
		(net "CLK_100M_RETIMER_CPU0_P2_R_DP")
	)
	(segment
		(start 290.65728 -407.123392)
		(end 291.25164 -406.529032)
		(width 0.14224)
		(layer "In2.Cu")
		(net "CLK_100M_RETIMER_CPU0_P2_R_DP")
	)
	(segment
		(start 391.911586 -399.555208)
		(end 392.213084 -399.25371)
		(width 0.14224)
		(layer "In2.Cu")
		(net "CLK_100M_RETIMER_CPU0_P2_R_DP")
	)
	(segment
		(start 288.613342 -407.123392)
		(end 288.750502 -407.260552)
		(width 0.14224)
		(layer "In2.Cu")
		(net "CLK_100M_RETIMER_CPU0_P2_R_DP")
	)
	(segment
		(start 359.786682 -403.899624)
		(end 389.601456 -403.899624)
		(width 0.14224)
		(layer "In2.Cu")
		(net "CLK_100M_RETIMER_CPU0_P2_R_DP")
	)
	(segment
		(start 391.911586 -399.74901)
		(end 391.911586 -399.555208)
		(width 0.14224)
		(layer "In2.Cu")
		(net "CLK_100M_RETIMER_CPU0_P2_R_DP")
	)
	(segment
		(start 291.747448 -406.033224)
		(end 292.326568 -405.454104)
		(width 0.14224)
		(layer "In2.Cu")
		(net "CLK_100M_RETIMER_CPU0_P2_R_DP")
	)
	(segment
		(start 289.177222 -407.260552)
		(end 289.314382 -407.123392)
		(width 0.14224)
		(layer "In2.Cu")
		(net "CLK_100M_RETIMER_CPU0_P2_R_DP")
	)
	(segment
		(start 299.582332 -404.627588)
		(end 300.910244 -405.9555)
		(width 0.14224)
		(layer "In2.Cu")
		(net "CLK_100M_RETIMER_CPU0_P2_R_DP")
	)
	(segment
		(start 391.002266 -400.464528)
		(end 391.415778 -400.051016)
		(width 0.14224)
		(layer "In2.Cu")
		(net "CLK_100M_RETIMER_CPU0_P2_R_DP")
	)
	(segment
		(start 286.842708 -414.305496)
		(end 286.705548 -414.168336)
		(width 0.14224)
		(layer "In13.Cu")
		(net "CLK_100M_RETIMER_CPU0_P2_R_DP")
	)
	(segment
		(start 288.119566 -419.31336)
		(end 288.256726 -419.1762)
		(width 0.14224)
		(layer "In13.Cu")
		(net "CLK_100M_RETIMER_CPU0_P2_R_DP")
	)
	(segment
		(start 286.705548 -410.785056)
		(end 286.705548 -410.358336)
		(width 0.14224)
		(layer "In13.Cu")
		(net "CLK_100M_RETIMER_CPU0_P2_R_DP")
	)
	(segment
		(start 286.705548 -409.230576)
		(end 286.842708 -409.093416)
		(width 0.14224)
		(layer "In13.Cu")
		(net "CLK_100M_RETIMER_CPU0_P2_R_DP")
	)
	(segment
		(start 286.705548 -412.613856)
		(end 286.842708 -412.476696)
		(width 0.14224)
		(layer "In13.Cu")
		(net "CLK_100M_RETIMER_CPU0_P2_R_DP")
	)
	(segment
		(start 286.842708 -411.348936)
		(end 286.842708 -410.922216)
		(width 0.14224)
		(layer "In13.Cu")
		(net "CLK_100M_RETIMER_CPU0_P2_R_DP")
	)
	(segment
		(start 286.705548 -410.358336)
		(end 286.842708 -410.221176)
		(width 0.14224)
		(layer "In13.Cu")
		(net "CLK_100M_RETIMER_CPU0_P2_R_DP")
	)
	(segment
		(start 286.842708 -410.221176)
		(end 286.842708 -409.794456)
		(width 0.14224)
		(layer "In13.Cu")
		(net "CLK_100M_RETIMER_CPU0_P2_R_DP")
	)
	(segment
		(start 290.356544 -419.814502)
		(end 289.929824 -419.814502)
		(width 0.14224)
		(layer "In13.Cu")
		(net "CLK_100M_RETIMER_CPU0_P2_R_DP")
	)
	(segment
		(start 290.493704 -419.951662)
		(end 290.356544 -419.814502)
		(width 0.14224)
		(layer "In13.Cu")
		(net "CLK_100M_RETIMER_CPU0_P2_R_DP")
	)
	(segment
		(start 288.119566 -416.710114)
		(end 286.705548 -415.296096)
		(width 0.14224)
		(layer "In13.Cu")
		(net "CLK_100M_RETIMER_CPU0_P2_R_DP")
	)
	(segment
		(start 287.192466 -407.123392)
		(end 287.483296 -407.414222)
		(width 0.14224)
		(layer "In13.Cu")
		(net "CLK_100M_RETIMER_CPU0_P2_R_DP")
	)
	(segment
		(start 288.119566 -419.74008)
		(end 288.119566 -419.31336)
		(width 0.14224)
		(layer "In13.Cu")
		(net "CLK_100M_RETIMER_CPU0_P2_R_DP")
	)
	(segment
		(start 286.705548 -411.486096)
		(end 286.842708 -411.348936)
		(width 0.14224)
		(layer "In13.Cu")
		(net "CLK_100M_RETIMER_CPU0_P2_R_DP")
	)
	(segment
		(start 288.256726 -418.74948)
		(end 288.119566 -418.61232)
		(width 0.14224)
		(layer "In13.Cu")
		(net "CLK_100M_RETIMER_CPU0_P2_R_DP")
	)
	(segment
		(start 286.842708 -413.604456)
		(end 286.842708 -413.177736)
		(width 0.14224)
		(layer "In13.Cu")
		(net "CLK_100M_RETIMER_CPU0_P2_R_DP")
	)
	(segment
		(start 286.705548 -414.168336)
		(end 286.705548 -413.741616)
		(width 0.14224)
		(layer "In13.Cu")
		(net "CLK_100M_RETIMER_CPU0_P2_R_DP")
	)
	(segment
		(start 288.256726 -419.1762)
		(end 288.256726 -418.74948)
		(width 0.14224)
		(layer "In13.Cu")
		(net "CLK_100M_RETIMER_CPU0_P2_R_DP")
	)
	(segment
		(start 289.792664 -419.951662)
		(end 288.331148 -419.951662)
		(width 0.14224)
		(layer "In13.Cu")
		(net "CLK_100M_RETIMER_CPU0_P2_R_DP")
	)
	(segment
		(start 286.705548 -415.296096)
		(end 286.705548 -414.869376)
		(width 0.14224)
		(layer "In13.Cu")
		(net "CLK_100M_RETIMER_CPU0_P2_R_DP")
	)
	(segment
		(start 286.705548 -409.657296)
		(end 286.705548 -409.230576)
		(width 0.14224)
		(layer "In13.Cu")
		(net "CLK_100M_RETIMER_CPU0_P2_R_DP")
	)
	(segment
		(start 286.842708 -409.093416)
		(end 286.842708 -408.666696)
		(width 0.14224)
		(layer "In13.Cu")
		(net "CLK_100M_RETIMER_CPU0_P2_R_DP")
	)
	(segment
		(start 286.842708 -414.732216)
		(end 286.842708 -414.305496)
		(width 0.14224)
		(layer "In13.Cu")
		(net "CLK_100M_RETIMER_CPU0_P2_R_DP")
	)
	(segment
		(start 286.705548 -413.040576)
		(end 286.705548 -412.613856)
		(width 0.14224)
		(layer "In13.Cu")
		(net "CLK_100M_RETIMER_CPU0_P2_R_DP")
	)
	(segment
		(start 286.842708 -408.666696)
		(end 286.705548 -408.529536)
		(width 0.14224)
		(layer "In13.Cu")
		(net "CLK_100M_RETIMER_CPU0_P2_R_DP")
	)
	(segment
		(start 286.705548 -414.869376)
		(end 286.842708 -414.732216)
		(width 0.14224)
		(layer "In13.Cu")
		(net "CLK_100M_RETIMER_CPU0_P2_R_DP")
	)
	(segment
		(start 286.705548 -413.741616)
		(end 286.842708 -413.604456)
		(width 0.14224)
		(layer "In13.Cu")
		(net "CLK_100M_RETIMER_CPU0_P2_R_DP")
	)
	(segment
		(start 286.705548 -408.529536)
		(end 286.705548 -407.291286)
		(width 0.14224)
		(layer "In13.Cu")
		(net "CLK_100M_RETIMER_CPU0_P2_R_DP")
	)
	(segment
		(start 286.705548 -411.912816)
		(end 286.705548 -411.486096)
		(width 0.14224)
		(layer "In13.Cu")
		(net "CLK_100M_RETIMER_CPU0_P2_R_DP")
	)
	(segment
		(start 286.842708 -409.794456)
		(end 286.705548 -409.657296)
		(width 0.14224)
		(layer "In13.Cu")
		(net "CLK_100M_RETIMER_CPU0_P2_R_DP")
	)
	(segment
		(start 290.920424 -419.951662)
		(end 290.493704 -419.951662)
		(width 0.14224)
		(layer "In13.Cu")
		(net "CLK_100M_RETIMER_CPU0_P2_R_DP")
	)
	(segment
		(start 289.929824 -419.814502)
		(end 289.792664 -419.951662)
		(width 0.14224)
		(layer "In13.Cu")
		(net "CLK_100M_RETIMER_CPU0_P2_R_DP")
	)
	(segment
		(start 286.842708 -413.177736)
		(end 286.705548 -413.040576)
		(width 0.14224)
		(layer "In13.Cu")
		(net "CLK_100M_RETIMER_CPU0_P2_R_DP")
	)
	(segment
		(start 286.842708 -410.922216)
		(end 286.705548 -410.785056)
		(width 0.14224)
		(layer "In13.Cu")
		(net "CLK_100M_RETIMER_CPU0_P2_R_DP")
	)
	(segment
		(start 291.211254 -419.660832)
		(end 290.920424 -419.951662)
		(width 0.14224)
		(layer "In13.Cu")
		(net "CLK_100M_RETIMER_CPU0_P2_R_DP")
	)
	(segment
		(start 286.842708 -412.476696)
		(end 286.842708 -412.049976)
		(width 0.14224)
		(layer "In13.Cu")
		(net "CLK_100M_RETIMER_CPU0_P2_R_DP")
	)
	(segment
		(start 288.119566 -418.61232)
		(end 288.119566 -416.710114)
		(width 0.14224)
		(layer "In13.Cu")
		(net "CLK_100M_RETIMER_CPU0_P2_R_DP")
	)
	(segment
		(start 286.842708 -412.049976)
		(end 286.705548 -411.912816)
		(width 0.14224)
		(layer "In13.Cu")
		(net "CLK_100M_RETIMER_CPU0_P2_R_DP")
	)
	(segment
		(start 286.705548 -407.291286)
		(end 286.873442 -407.123392)
		(width 0.14224)
		(layer "In13.Cu")
		(net "CLK_100M_RETIMER_CPU0_P2_R_DP")
	)
	(segment
		(start 286.873442 -407.123392)
		(end 287.192466 -407.123392)
		(width 0.14224)
		(layer "In13.Cu")
		(net "CLK_100M_RETIMER_CPU0_P2_R_DP")
	)
	(segment
		(start 288.331148 -419.951662)
		(end 288.119566 -419.74008)
		(width 0.14224)
		(layer "In13.Cu")
		(net "CLK_100M_RETIMER_CPU0_P2_R_DP")
	)
	(segment
		(start 289.012376 -419.484556)
		(end 289.781742 -420.253922)
		(width 0.12954)
		(layer "F.Cu")
		(net "CLK_100M_RETIMER_CPU0_P2_R_DN")
	)
	(segment
		(start 288.587434 -419.484556)
		(end 289.012376 -419.484556)
		(width 0.12954)
		(layer "F.Cu")
		(net "CLK_100M_RETIMER_CPU0_P2_R_DN")
	)
	(segment
		(start 397.643858 -395.578584)
		(end 397.888968 -395.333474)
		(width 0.12954)
		(layer "F.Cu")
		(net "CLK_100M_RETIMER_CPU0_P2_R_DN")
	)
	(segment
		(start 396.91056 -395.308074)
		(end 397.18107 -395.578584)
		(width 0.12954)
		(layer "F.Cu")
		(net "CLK_100M_RETIMER_CPU0_P2_R_DN")
	)
	(segment
		(start 397.18107 -395.578584)
		(end 397.643858 -395.578584)
		(width 0.12954)
		(layer "F.Cu")
		(net "CLK_100M_RETIMER_CPU0_P2_R_DN")
	)
	(segment
		(start 288.499042 -419.572948)
		(end 288.587434 -419.484556)
		(width 0.12954)
		(layer "F.Cu")
		(net "CLK_100M_RETIMER_CPU0_P2_R_DN")
	)
	(segment
		(start 289.781742 -420.253922)
		(end 290.940744 -420.253922)
		(width 0.12954)
		(layer "F.Cu")
		(net "CLK_100M_RETIMER_CPU0_P2_R_DN")
	)
	(segment
		(start 288.255964 -419.572948)
		(end 288.499042 -419.572948)
		(width 0.12954)
		(layer "F.Cu")
		(net "CLK_100M_RETIMER_CPU0_P2_R_DN")
	)
	(segment
		(start 290.940744 -420.253922)
		(end 291.211254 -420.524432)
		(width 0.12954)
		(layer "F.Cu")
		(net "CLK_100M_RETIMER_CPU0_P2_R_DN")
	)
	(via
		(at 396.91056 -395.308074)
		(size 0.508)
		(drill 0.254)
		(layers "F.Cu" "B.Cu")
		(net "CLK_100M_RETIMER_CPU0_P2_R_DN")
	)
	(via
		(at 287.483296 -406.550622)
		(size 0.508)
		(drill 0.254)
		(layers "F.Cu" "B.Cu")
		(net "CLK_100M_RETIMER_CPU0_P2_R_DN")
	)
	(via
		(at 291.211254 -420.524432)
		(size 0.508)
		(drill 0.254)
		(layers "F.Cu" "B.Cu")
		(net "CLK_100M_RETIMER_CPU0_P2_R_DN")
	)
	(segment
		(start 389.989314 -401.463764)
		(end 389.989314 -400.862546)
		(width 0.14224)
		(layer "In2.Cu")
		(net "CLK_100M_RETIMER_CPU0_P2_R_DN")
	)
	(segment
		(start 395.606016 -395.145514)
		(end 396.059406 -395.598904)
		(width 0.14224)
		(layer "In2.Cu")
		(net "CLK_100M_RETIMER_CPU0_P2_R_DN")
	)
	(segment
		(start 389.484616 -403.617684)
		(end 390.351264 -402.751036)
		(width 0.14224)
		(layer "In2.Cu")
		(net "CLK_100M_RETIMER_CPU0_P2_R_DN")
	)
	(segment
		(start 389.989314 -400.862546)
		(end 390.669272 -400.182588)
		(width 0.14224)
		(layer "In2.Cu")
		(net "CLK_100M_RETIMER_CPU0_P2_R_DN")
	)
	(segment
		(start 287.774126 -406.841452)
		(end 290.54044 -406.841452)
		(width 0.14224)
		(layer "In2.Cu")
		(net "CLK_100M_RETIMER_CPU0_P2_R_DN")
	)
	(segment
		(start 295.409874 -405.172164)
		(end 296.23639 -404.345648)
		(width 0.14224)
		(layer "In2.Cu")
		(net "CLK_100M_RETIMER_CPU0_P2_R_DN")
	)
	(segment
		(start 394.00607 -396.11681)
		(end 394.977366 -395.145514)
		(width 0.14224)
		(layer "In2.Cu")
		(net "CLK_100M_RETIMER_CPU0_P2_R_DN")
	)
	(segment
		(start 396.61973 -395.598904)
		(end 396.91056 -395.308074)
		(width 0.14224)
		(layer "In2.Cu")
		(net "CLK_100M_RETIMER_CPU0_P2_R_DN")
	)
	(segment
		(start 292.209728 -405.172164)
		(end 295.409874 -405.172164)
		(width 0.14224)
		(layer "In2.Cu")
		(net "CLK_100M_RETIMER_CPU0_P2_R_DN")
	)
	(segment
		(start 301.027084 -405.67356)
		(end 354.766118 -405.67356)
		(width 0.14224)
		(layer "In2.Cu")
		(net "CLK_100M_RETIMER_CPU0_P2_R_DN")
	)
	(segment
		(start 396.059406 -395.598904)
		(end 396.61973 -395.598904)
		(width 0.14224)
		(layer "In2.Cu")
		(net "CLK_100M_RETIMER_CPU0_P2_R_DN")
	)
	(segment
		(start 299.699172 -404.345648)
		(end 301.027084 -405.67356)
		(width 0.14224)
		(layer "In2.Cu")
		(net "CLK_100M_RETIMER_CPU0_P2_R_DN")
	)
	(segment
		(start 390.885426 -400.182588)
		(end 394.00607 -397.061944)
		(width 0.14224)
		(layer "In2.Cu")
		(net "CLK_100M_RETIMER_CPU0_P2_R_DN")
	)
	(segment
		(start 390.351264 -402.751036)
		(end 390.351264 -402.337778)
		(width 0.14224)
		(layer "In2.Cu")
		(net "CLK_100M_RETIMER_CPU0_P2_R_DN")
	)
	(segment
		(start 287.483296 -406.550622)
		(end 287.774126 -406.841452)
		(width 0.14224)
		(layer "In2.Cu")
		(net "CLK_100M_RETIMER_CPU0_P2_R_DN")
	)
	(segment
		(start 390.669272 -400.182588)
		(end 390.885426 -400.182588)
		(width 0.14224)
		(layer "In2.Cu")
		(net "CLK_100M_RETIMER_CPU0_P2_R_DN")
	)
	(segment
		(start 390.351264 -402.337778)
		(end 389.989314 -401.463764)
		(width 0.14224)
		(layer "In2.Cu")
		(net "CLK_100M_RETIMER_CPU0_P2_R_DN")
	)
	(segment
		(start 290.54044 -406.841452)
		(end 292.209728 -405.172164)
		(width 0.14224)
		(layer "In2.Cu")
		(net "CLK_100M_RETIMER_CPU0_P2_R_DN")
	)
	(segment
		(start 394.00607 -397.061944)
		(end 394.00607 -396.11681)
		(width 0.14224)
		(layer "In2.Cu")
		(net "CLK_100M_RETIMER_CPU0_P2_R_DN")
	)
	(segment
		(start 296.23639 -404.345648)
		(end 299.699172 -404.345648)
		(width 0.14224)
		(layer "In2.Cu")
		(net "CLK_100M_RETIMER_CPU0_P2_R_DN")
	)
	(segment
		(start 354.766118 -405.67356)
		(end 359.730294 -403.617684)
		(width 0.14224)
		(layer "In2.Cu")
		(net "CLK_100M_RETIMER_CPU0_P2_R_DN")
	)
	(segment
		(start 359.730294 -403.617684)
		(end 389.484616 -403.617684)
		(width 0.14224)
		(layer "In2.Cu")
		(net "CLK_100M_RETIMER_CPU0_P2_R_DN")
	)
	(segment
		(start 394.977366 -395.145514)
		(end 395.606016 -395.145514)
		(width 0.14224)
		(layer "In2.Cu")
		(net "CLK_100M_RETIMER_CPU0_P2_R_DN")
	)
	(segment
		(start 287.192466 -406.841452)
		(end 287.483296 -406.550622)
		(width 0.14224)
		(layer "In13.Cu")
		(net "CLK_100M_RETIMER_CPU0_P2_R_DN")
	)
	(segment
		(start 287.837626 -419.85692)
		(end 287.837626 -416.826954)
		(width 0.14224)
		(layer "In13.Cu")
		(net "CLK_100M_RETIMER_CPU0_P2_R_DN")
	)
	(segment
		(start 291.211254 -420.524432)
		(end 290.920424 -420.233602)
		(width 0.14224)
		(layer "In13.Cu")
		(net "CLK_100M_RETIMER_CPU0_P2_R_DN")
	)
	(segment
		(start 286.756602 -406.841452)
		(end 287.192466 -406.841452)
		(width 0.14224)
		(layer "In13.Cu")
		(net "CLK_100M_RETIMER_CPU0_P2_R_DN")
	)
	(segment
		(start 288.214308 -420.233602)
		(end 287.837626 -419.85692)
		(width 0.14224)
		(layer "In13.Cu")
		(net "CLK_100M_RETIMER_CPU0_P2_R_DN")
	)
	(segment
		(start 290.920424 -420.233602)
		(end 288.214308 -420.233602)
		(width 0.14224)
		(layer "In13.Cu")
		(net "CLK_100M_RETIMER_CPU0_P2_R_DN")
	)
	(segment
		(start 286.423608 -407.174446)
		(end 286.756602 -406.841452)
		(width 0.14224)
		(layer "In13.Cu")
		(net "CLK_100M_RETIMER_CPU0_P2_R_DN")
	)
	(segment
		(start 287.837626 -416.826954)
		(end 286.423608 -415.412936)
		(width 0.14224)
		(layer "In13.Cu")
		(net "CLK_100M_RETIMER_CPU0_P2_R_DN")
	)
	(segment
		(start 286.423608 -415.412936)
		(end 286.423608 -407.174446)
		(width 0.14224)
		(layer "In13.Cu")
		(net "CLK_100M_RETIMER_CPU0_P2_R_DN")
	)
	(segment
		(start 398.422368 -396.146274)
		(end 398.66824 -395.900402)
		(width 0.12954)
		(layer "F.Cu")
		(net "CLK_100M_RETIMER_CPU0_P2_DP")
	)
	(segment
		(start 401.12569 -396.129002)
		(end 401.209764 -396.213076)
		(width 0.1016)
		(layer "F.Cu")
		(net "CLK_100M_RETIMER_CPU0_P2_DP")
	)
	(segment
		(start 398.66824 -395.900402)
		(end 398.925796 -395.900402)
		(width 0.12954)
		(layer "F.Cu")
		(net "CLK_100M_RETIMER_CPU0_P2_DP")
	)
	(segment
		(start 400.91995 -396.129002)
		(end 401.12569 -396.129002)
		(width 0.1016)
		(layer "F.Cu")
		(net "CLK_100M_RETIMER_CPU0_P2_DP")
	)
	(segment
		(start 400.850862 -396.19809)
		(end 400.91995 -396.129002)
		(width 0.1016)
		(layer "F.Cu")
		(net "CLK_100M_RETIMER_CPU0_P2_DP")
	)
	(segment
		(start 399.42897 -395.888972)
		(end 399.796 -395.888972)
		(width 0.12954)
		(layer "F.Cu")
		(net "CLK_100M_RETIMER_CPU0_P2_DP")
	)
	(segment
		(start 399.796 -395.888972)
		(end 400.105118 -396.19809)
		(width 0.12954)
		(layer "F.Cu")
		(net "CLK_100M_RETIMER_CPU0_P2_DP")
	)
	(segment
		(start 400.105118 -396.19809)
		(end 400.850862 -396.19809)
		(width 0.12954)
		(layer "F.Cu")
		(net "CLK_100M_RETIMER_CPU0_P2_DP")
	)
	(segment
		(start 398.925796 -395.900402)
		(end 399.171668 -396.146274)
		(width 0.12954)
		(layer "F.Cu")
		(net "CLK_100M_RETIMER_CPU0_P2_DP")
	)
	(segment
		(start 399.171668 -396.146274)
		(end 399.42897 -395.888972)
		(width 0.12954)
		(layer "F.Cu")
		(net "CLK_100M_RETIMER_CPU0_P2_DP")
	)
	(segment
		(start 399.171668 -395.333474)
		(end 399.404586 -395.566392)
		(width 0.12954)
		(layer "F.Cu")
		(net "CLK_100M_RETIMER_CPU0_P2_DN")
	)
	(segment
		(start 398.666716 -395.577822)
		(end 398.92732 -395.577822)
		(width 0.12954)
		(layer "F.Cu")
		(net "CLK_100M_RETIMER_CPU0_P2_DN")
	)
	(segment
		(start 400.238976 -395.87551)
		(end 400.831812 -395.87551)
		(width 0.12954)
		(layer "F.Cu")
		(net "CLK_100M_RETIMER_CPU0_P2_DN")
	)
	(segment
		(start 399.929858 -395.566392)
		(end 400.238976 -395.87551)
		(width 0.12954)
		(layer "F.Cu")
		(net "CLK_100M_RETIMER_CPU0_P2_DN")
	)
	(segment
		(start 398.422368 -395.333474)
		(end 398.666716 -395.577822)
		(width 0.12954)
		(layer "F.Cu")
		(net "CLK_100M_RETIMER_CPU0_P2_DN")
	)
	(segment
		(start 399.404586 -395.566392)
		(end 399.929858 -395.566392)
		(width 0.12954)
		(layer "F.Cu")
		(net "CLK_100M_RETIMER_CPU0_P2_DN")
	)
	(segment
		(start 400.869404 -395.913102)
		(end 401.729448 -395.913102)
		(width 0.1016)
		(layer "F.Cu")
		(net "CLK_100M_RETIMER_CPU0_P2_DN")
	)
	(segment
		(start 398.92732 -395.577822)
		(end 399.171668 -395.333474)
		(width 0.12954)
		(layer "F.Cu")
		(net "CLK_100M_RETIMER_CPU0_P2_DN")
	)
	(segment
		(start 400.831812 -395.87551)
		(end 400.869404 -395.913102)
		(width 0.1016)
		(layer "F.Cu")
		(net "CLK_100M_RETIMER_CPU0_P2_DN")
	)
	(segment
		(start 288.539682 -417.661598)
		(end 289.564826 -417.661598)
		(width 0.12954)
		(layer "F.Cu")
		(net "CLK_100M_RETIMER_CPU0_P1_R_DP")
	)
	(segment
		(start 289.564826 -417.661598)
		(end 289.835336 -417.391088)
		(width 0.12954)
		(layer "F.Cu")
		(net "CLK_100M_RETIMER_CPU0_P1_R_DP")
	)
	(segment
		(start 330.080874 -395.901164)
		(end 330.543662 -395.901164)
		(width 0.12954)
		(layer "F.Cu")
		(net "CLK_100M_RETIMER_CPU0_P1_R_DP")
	)
	(segment
		(start 329.810364 -396.171674)
		(end 330.080874 -395.901164)
		(width 0.12954)
		(layer "F.Cu")
		(net "CLK_100M_RETIMER_CPU0_P1_R_DP")
	)
	(segment
		(start 330.543662 -395.901164)
		(end 330.788772 -396.146274)
		(width 0.12954)
		(layer "F.Cu")
		(net "CLK_100M_RETIMER_CPU0_P1_R_DP")
	)
	(segment
		(start 288.451036 -417.572952)
		(end 288.539682 -417.661598)
		(width 0.12954)
		(layer "F.Cu")
		(net "CLK_100M_RETIMER_CPU0_P1_R_DP")
	)
	(segment
		(start 288.255964 -417.572952)
		(end 288.451036 -417.572952)
		(width 0.12954)
		(layer "F.Cu")
		(net "CLK_100M_RETIMER_CPU0_P1_R_DP")
	)
	(via
		(at 289.835336 -417.391088)
		(size 0.508)
		(drill 0.254)
		(layers "F.Cu" "B.Cu")
		(net "CLK_100M_RETIMER_CPU0_P1_R_DP")
	)
	(via
		(at 290.300918 -403.025356)
		(size 0.508)
		(drill 0.254)
		(layers "F.Cu" "B.Cu")
		(net "CLK_100M_RETIMER_CPU0_P1_R_DP")
	)
	(via
		(at 329.810364 -396.171674)
		(size 0.508)
		(drill 0.254)
		(layers "F.Cu" "B.Cu")
		(net "CLK_100M_RETIMER_CPU0_P1_R_DP")
	)
	(segment
		(start 304.914554 -403.086062)
		(end 304.487834 -403.086062)
		(width 0.14224)
		(layer "In2.Cu")
		(net "CLK_100M_RETIMER_CPU0_P1_R_DP")
	)
	(segment
		(start 293.374826 -401.635468)
		(end 293.18077 -401.635468)
		(width 0.14224)
		(layer "In2.Cu")
		(net "CLK_100M_RETIMER_CPU0_P1_R_DP")
	)
	(segment
		(start 300.155864 -400.536664)
		(end 294.279574 -400.536664)
		(width 0.14224)
		(layer "In2.Cu")
		(net "CLK_100M_RETIMER_CPU0_P1_R_DP")
	)
	(segment
		(start 290.591748 -402.734526)
		(end 290.300918 -403.025356)
		(width 0.14224)
		(layer "In2.Cu")
		(net "CLK_100M_RETIMER_CPU0_P1_R_DP")
	)
	(segment
		(start 292.879272 -401.936966)
		(end 292.879272 -402.131022)
		(width 0.14224)
		(layer "In2.Cu")
		(net "CLK_100M_RETIMER_CPU0_P1_R_DP")
	)
	(segment
		(start 302.242728 -403.086062)
		(end 301.562516 -402.40585)
		(width 0.14224)
		(layer "In2.Cu")
		(net "CLK_100M_RETIMER_CPU0_P1_R_DP")
	)
	(segment
		(start 325.516748 -398.818354)
		(end 325.214742 -399.12036)
		(width 0.14224)
		(layer "In2.Cu")
		(net "CLK_100M_RETIMER_CPU0_P1_R_DP")
	)
	(segment
		(start 305.051714 -403.223222)
		(end 304.914554 -403.086062)
		(width 0.14224)
		(layer "In2.Cu")
		(net "CLK_100M_RETIMER_CPU0_P1_R_DP")
	)
	(segment
		(start 323.3293 -402.50618)
		(end 322.749418 -403.086062)
		(width 0.14224)
		(layer "In2.Cu")
		(net "CLK_100M_RETIMER_CPU0_P1_R_DP")
	)
	(segment
		(start 327.397618 -396.480284)
		(end 327.051416 -397.315944)
		(width 0.14224)
		(layer "In2.Cu")
		(net "CLK_100M_RETIMER_CPU0_P1_R_DP")
	)
	(segment
		(start 327.051416 -397.315944)
		(end 326.888602 -397.55953)
		(width 0.14224)
		(layer "In2.Cu")
		(net "CLK_100M_RETIMER_CPU0_P1_R_DP")
	)
	(segment
		(start 301.235364 -401.616164)
		(end 300.155864 -400.536664)
		(width 0.14224)
		(layer "In2.Cu")
		(net "CLK_100M_RETIMER_CPU0_P1_R_DP")
	)
	(segment
		(start 305.478434 -403.223222)
		(end 305.051714 -403.223222)
		(width 0.14224)
		(layer "In2.Cu")
		(net "CLK_100M_RETIMER_CPU0_P1_R_DP")
	)
	(segment
		(start 325.020686 -399.12036)
		(end 323.215 -400.926046)
		(width 0.14224)
		(layer "In2.Cu")
		(net "CLK_100M_RETIMER_CPU0_P1_R_DP")
	)
	(segment
		(start 329.519534 -395.880844)
		(end 328.84237 -395.880844)
		(width 0.14224)
		(layer "In2.Cu")
		(net "CLK_100M_RETIMER_CPU0_P1_R_DP")
	)
	(segment
		(start 293.18077 -401.635468)
		(end 292.879272 -401.936966)
		(width 0.14224)
		(layer "In2.Cu")
		(net "CLK_100M_RETIMER_CPU0_P1_R_DP")
	)
	(segment
		(start 326.321674 -398.126458)
		(end 326.014588 -398.126458)
		(width 0.14224)
		(layer "In2.Cu")
		(net "CLK_100M_RETIMER_CPU0_P1_R_DP")
	)
	(segment
		(start 329.810364 -396.171674)
		(end 329.519534 -395.880844)
		(width 0.14224)
		(layer "In2.Cu")
		(net "CLK_100M_RETIMER_CPU0_P1_R_DP")
	)
	(segment
		(start 326.888602 -397.55953)
		(end 326.321674 -398.126458)
		(width 0.14224)
		(layer "In2.Cu")
		(net "CLK_100M_RETIMER_CPU0_P1_R_DP")
	)
	(segment
		(start 325.214742 -399.12036)
		(end 325.020686 -399.12036)
		(width 0.14224)
		(layer "In2.Cu")
		(net "CLK_100M_RETIMER_CPU0_P1_R_DP")
	)
	(segment
		(start 293.676832 -401.139406)
		(end 293.676832 -401.333462)
		(width 0.14224)
		(layer "In2.Cu")
		(net "CLK_100M_RETIMER_CPU0_P1_R_DP")
	)
	(segment
		(start 303.923954 -403.223222)
		(end 303.786794 -403.086062)
		(width 0.14224)
		(layer "In2.Cu")
		(net "CLK_100M_RETIMER_CPU0_P1_R_DP")
	)
	(segment
		(start 305.615594 -403.086062)
		(end 305.478434 -403.223222)
		(width 0.14224)
		(layer "In2.Cu")
		(net "CLK_100M_RETIMER_CPU0_P1_R_DP")
	)
	(segment
		(start 323.3293 -401.539456)
		(end 323.3293 -402.50618)
		(width 0.14224)
		(layer "In2.Cu")
		(net "CLK_100M_RETIMER_CPU0_P1_R_DP")
	)
	(segment
		(start 292.577266 -402.433028)
		(end 292.38321 -402.433028)
		(width 0.14224)
		(layer "In2.Cu")
		(net "CLK_100M_RETIMER_CPU0_P1_R_DP")
	)
	(segment
		(start 328.149458 -395.679422)
		(end 327.49617 -396.33271)
		(width 0.14224)
		(layer "In2.Cu")
		(net "CLK_100M_RETIMER_CPU0_P1_R_DP")
	)
	(segment
		(start 292.38321 -402.433028)
		(end 292.081712 -402.734526)
		(width 0.14224)
		(layer "In2.Cu")
		(net "CLK_100M_RETIMER_CPU0_P1_R_DP")
	)
	(segment
		(start 328.640948 -395.679422)
		(end 328.149458 -395.679422)
		(width 0.14224)
		(layer "In2.Cu")
		(net "CLK_100M_RETIMER_CPU0_P1_R_DP")
	)
	(segment
		(start 304.350674 -403.223222)
		(end 303.923954 -403.223222)
		(width 0.14224)
		(layer "In2.Cu")
		(net "CLK_100M_RETIMER_CPU0_P1_R_DP")
	)
	(segment
		(start 326.014588 -398.126458)
		(end 325.516748 -398.624298)
		(width 0.14224)
		(layer "In2.Cu")
		(net "CLK_100M_RETIMER_CPU0_P1_R_DP")
	)
	(segment
		(start 304.487834 -403.086062)
		(end 304.350674 -403.223222)
		(width 0.14224)
		(layer "In2.Cu")
		(net "CLK_100M_RETIMER_CPU0_P1_R_DP")
	)
	(segment
		(start 294.279574 -400.536664)
		(end 293.676832 -401.139406)
		(width 0.14224)
		(layer "In2.Cu")
		(net "CLK_100M_RETIMER_CPU0_P1_R_DP")
	)
	(segment
		(start 323.215 -401.425156)
		(end 323.3293 -401.539456)
		(width 0.14224)
		(layer "In2.Cu")
		(net "CLK_100M_RETIMER_CPU0_P1_R_DP")
	)
	(segment
		(start 323.215 -400.926046)
		(end 323.215 -401.425156)
		(width 0.14224)
		(layer "In2.Cu")
		(net "CLK_100M_RETIMER_CPU0_P1_R_DP")
	)
	(segment
		(start 292.879272 -402.131022)
		(end 292.577266 -402.433028)
		(width 0.14224)
		(layer "In2.Cu")
		(net "CLK_100M_RETIMER_CPU0_P1_R_DP")
	)
	(segment
		(start 328.84237 -395.880844)
		(end 328.640948 -395.679422)
		(width 0.14224)
		(layer "In2.Cu")
		(net "CLK_100M_RETIMER_CPU0_P1_R_DP")
	)
	(segment
		(start 301.562516 -402.40585)
		(end 301.235364 -401.616164)
		(width 0.14224)
		(layer "In2.Cu")
		(net "CLK_100M_RETIMER_CPU0_P1_R_DP")
	)
	(segment
		(start 327.49617 -396.33271)
		(end 327.397618 -396.480284)
		(width 0.14224)
		(layer "In2.Cu")
		(net "CLK_100M_RETIMER_CPU0_P1_R_DP")
	)
	(segment
		(start 293.676832 -401.333462)
		(end 293.374826 -401.635468)
		(width 0.14224)
		(layer "In2.Cu")
		(net "CLK_100M_RETIMER_CPU0_P1_R_DP")
	)
	(segment
		(start 322.749418 -403.086062)
		(end 305.615594 -403.086062)
		(width 0.14224)
		(layer "In2.Cu")
		(net "CLK_100M_RETIMER_CPU0_P1_R_DP")
	)
	(segment
		(start 303.786794 -403.086062)
		(end 302.242728 -403.086062)
		(width 0.14224)
		(layer "In2.Cu")
		(net "CLK_100M_RETIMER_CPU0_P1_R_DP")
	)
	(segment
		(start 292.081712 -402.734526)
		(end 290.591748 -402.734526)
		(width 0.14224)
		(layer "In2.Cu")
		(net "CLK_100M_RETIMER_CPU0_P1_R_DP")
	)
	(segment
		(start 325.516748 -398.624298)
		(end 325.516748 -398.818354)
		(width 0.14224)
		(layer "In2.Cu")
		(net "CLK_100M_RETIMER_CPU0_P1_R_DP")
	)
	(segment
		(start 289.06851 -416.998658)
		(end 289.20567 -416.861498)
		(width 0.14224)
		(layer "In13.Cu")
		(net "CLK_100M_RETIMER_CPU0_P1_R_DP")
	)
	(segment
		(start 289.06851 -416.297618)
		(end 289.06851 -415.870898)
		(width 0.14224)
		(layer "In13.Cu")
		(net "CLK_100M_RETIMER_CPU0_P1_R_DP")
	)
	(segment
		(start 289.06851 -414.743138)
		(end 289.20567 -414.605978)
		(width 0.14224)
		(layer "In13.Cu")
		(net "CLK_100M_RETIMER_CPU0_P1_R_DP")
	)
	(segment
		(start 289.835336 -417.391088)
		(end 289.544506 -417.681918)
		(width 0.14224)
		(layer "In13.Cu")
		(net "CLK_100M_RETIMER_CPU0_P1_R_DP")
	)
	(segment
		(start 289.06851 -414.042098)
		(end 289.06851 -413.596582)
		(width 0.14224)
		(layer "In13.Cu")
		(net "CLK_100M_RETIMER_CPU0_P1_R_DP")
	)
	(segment
		(start 288.448242 -409.166314)
		(end 288.585402 -409.029154)
		(width 0.14224)
		(layer "In13.Cu")
		(net "CLK_100M_RETIMER_CPU0_P1_R_DP")
	)
	(segment
		(start 288.585402 -407.901394)
		(end 288.585402 -407.474674)
		(width 0.14224)
		(layer "In13.Cu")
		(net "CLK_100M_RETIMER_CPU0_P1_R_DP")
	)
	(segment
		(start 289.06851 -415.870898)
		(end 289.20567 -415.733738)
		(width 0.14224)
		(layer "In13.Cu")
		(net "CLK_100M_RETIMER_CPU0_P1_R_DP")
	)
	(segment
		(start 289.20567 -416.861498)
		(end 289.20567 -416.434778)
		(width 0.14224)
		(layer "In13.Cu")
		(net "CLK_100M_RETIMER_CPU0_P1_R_DP")
	)
	(segment
		(start 288.585402 -410.857954)
		(end 288.448242 -410.720794)
		(width 0.14224)
		(layer "In13.Cu")
		(net "CLK_100M_RETIMER_CPU0_P1_R_DP")
	)
	(segment
		(start 288.448242 -412.549594)
		(end 288.585402 -412.412434)
		(width 0.14224)
		(layer "In13.Cu")
		(net "CLK_100M_RETIMER_CPU0_P1_R_DP")
	)
	(segment
		(start 288.448242 -411.421834)
		(end 288.585402 -411.284674)
		(width 0.14224)
		(layer "In13.Cu")
		(net "CLK_100M_RETIMER_CPU0_P1_R_DP")
	)
	(segment
		(start 290.010088 -402.734526)
		(end 290.300918 -403.025356)
		(width 0.14224)
		(layer "In13.Cu")
		(net "CLK_100M_RETIMER_CPU0_P1_R_DP")
	)
	(segment
		(start 288.448242 -410.720794)
		(end 288.448242 -410.294074)
		(width 0.14224)
		(layer "In13.Cu")
		(net "CLK_100M_RETIMER_CPU0_P1_R_DP")
	)
	(segment
		(start 289.06851 -417.425378)
		(end 289.06851 -416.998658)
		(width 0.14224)
		(layer "In13.Cu")
		(net "CLK_100M_RETIMER_CPU0_P1_R_DP")
	)
	(segment
		(start 288.575242 -402.734526)
		(end 290.010088 -402.734526)
		(width 0.14224)
		(layer "In13.Cu")
		(net "CLK_100M_RETIMER_CPU0_P1_R_DP")
	)
	(segment
		(start 289.32505 -417.681918)
		(end 289.06851 -417.425378)
		(width 0.14224)
		(layer "In13.Cu")
		(net "CLK_100M_RETIMER_CPU0_P1_R_DP")
	)
	(segment
		(start 288.448242 -409.593034)
		(end 288.448242 -409.166314)
		(width 0.14224)
		(layer "In13.Cu")
		(net "CLK_100M_RETIMER_CPU0_P1_R_DP")
	)
	(segment
		(start 288.448242 -411.848554)
		(end 288.448242 -411.421834)
		(width 0.14224)
		(layer "In13.Cu")
		(net "CLK_100M_RETIMER_CPU0_P1_R_DP")
	)
	(segment
		(start 288.448242 -408.465274)
		(end 288.448242 -408.038554)
		(width 0.14224)
		(layer "In13.Cu")
		(net "CLK_100M_RETIMER_CPU0_P1_R_DP")
	)
	(segment
		(start 289.06851 -415.169858)
		(end 289.06851 -414.743138)
		(width 0.14224)
		(layer "In13.Cu")
		(net "CLK_100M_RETIMER_CPU0_P1_R_DP")
	)
	(segment
		(start 289.06851 -413.596582)
		(end 288.448242 -412.976314)
		(width 0.14224)
		(layer "In13.Cu")
		(net "CLK_100M_RETIMER_CPU0_P1_R_DP")
	)
	(segment
		(start 288.448242 -407.337514)
		(end 288.448242 -402.861526)
		(width 0.14224)
		(layer "In13.Cu")
		(net "CLK_100M_RETIMER_CPU0_P1_R_DP")
	)
	(segment
		(start 289.20567 -414.179258)
		(end 289.06851 -414.042098)
		(width 0.14224)
		(layer "In13.Cu")
		(net "CLK_100M_RETIMER_CPU0_P1_R_DP")
	)
	(segment
		(start 288.585402 -411.284674)
		(end 288.585402 -410.857954)
		(width 0.14224)
		(layer "In13.Cu")
		(net "CLK_100M_RETIMER_CPU0_P1_R_DP")
	)
	(segment
		(start 288.585402 -412.412434)
		(end 288.585402 -411.985714)
		(width 0.14224)
		(layer "In13.Cu")
		(net "CLK_100M_RETIMER_CPU0_P1_R_DP")
	)
	(segment
		(start 288.585402 -407.474674)
		(end 288.448242 -407.337514)
		(width 0.14224)
		(layer "In13.Cu")
		(net "CLK_100M_RETIMER_CPU0_P1_R_DP")
	)
	(segment
		(start 289.20567 -415.733738)
		(end 289.20567 -415.307018)
		(width 0.14224)
		(layer "In13.Cu")
		(net "CLK_100M_RETIMER_CPU0_P1_R_DP")
	)
	(segment
		(start 289.544506 -417.681918)
		(end 289.32505 -417.681918)
		(width 0.14224)
		(layer "In13.Cu")
		(net "CLK_100M_RETIMER_CPU0_P1_R_DP")
	)
	(segment
		(start 289.20567 -416.434778)
		(end 289.06851 -416.297618)
		(width 0.14224)
		(layer "In13.Cu")
		(net "CLK_100M_RETIMER_CPU0_P1_R_DP")
	)
	(segment
		(start 288.585402 -411.985714)
		(end 288.448242 -411.848554)
		(width 0.14224)
		(layer "In13.Cu")
		(net "CLK_100M_RETIMER_CPU0_P1_R_DP")
	)
	(segment
		(start 288.448242 -412.976314)
		(end 288.448242 -412.549594)
		(width 0.14224)
		(layer "In13.Cu")
		(net "CLK_100M_RETIMER_CPU0_P1_R_DP")
	)
	(segment
		(start 288.448242 -402.861526)
		(end 288.575242 -402.734526)
		(width 0.14224)
		(layer "In13.Cu")
		(net "CLK_100M_RETIMER_CPU0_P1_R_DP")
	)
	(segment
		(start 288.585402 -408.602434)
		(end 288.448242 -408.465274)
		(width 0.14224)
		(layer "In13.Cu")
		(net "CLK_100M_RETIMER_CPU0_P1_R_DP")
	)
	(segment
		(start 289.20567 -415.307018)
		(end 289.06851 -415.169858)
		(width 0.14224)
		(layer "In13.Cu")
		(net "CLK_100M_RETIMER_CPU0_P1_R_DP")
	)
	(segment
		(start 288.585402 -409.730194)
		(end 288.448242 -409.593034)
		(width 0.14224)
		(layer "In13.Cu")
		(net "CLK_100M_RETIMER_CPU0_P1_R_DP")
	)
	(segment
		(start 289.20567 -414.605978)
		(end 289.20567 -414.179258)
		(width 0.14224)
		(layer "In13.Cu")
		(net "CLK_100M_RETIMER_CPU0_P1_R_DP")
	)
	(segment
		(start 288.448242 -410.294074)
		(end 288.585402 -410.156914)
		(width 0.14224)
		(layer "In13.Cu")
		(net "CLK_100M_RETIMER_CPU0_P1_R_DP")
	)
	(segment
		(start 288.585402 -409.029154)
		(end 288.585402 -408.602434)
		(width 0.14224)
		(layer "In13.Cu")
		(net "CLK_100M_RETIMER_CPU0_P1_R_DP")
	)
	(segment
		(start 288.585402 -410.156914)
		(end 288.585402 -409.730194)
		(width 0.14224)
		(layer "In13.Cu")
		(net "CLK_100M_RETIMER_CPU0_P1_R_DP")
	)
	(segment
		(start 288.448242 -408.038554)
		(end 288.585402 -407.901394)
		(width 0.14224)
		(layer "In13.Cu")
		(net "CLK_100M_RETIMER_CPU0_P1_R_DP")
	)
	(segment
		(start 288.538666 -417.984178)
		(end 289.564826 -417.984178)
		(width 0.12954)
		(layer "F.Cu")
		(net "CLK_100M_RETIMER_CPU0_P1_R_DN")
	)
	(segment
		(start 289.564826 -417.984178)
		(end 289.835336 -418.254688)
		(width 0.12954)
		(layer "F.Cu")
		(net "CLK_100M_RETIMER_CPU0_P1_R_DN")
	)
	(segment
		(start 330.543662 -395.578584)
		(end 330.788772 -395.333474)
		(width 0.12954)
		(layer "F.Cu")
		(net "CLK_100M_RETIMER_CPU0_P1_R_DN")
	)
	(segment
		(start 288.449766 -418.073078)
		(end 288.538666 -417.984178)
		(width 0.12954)
		(layer "F.Cu")
		(net "CLK_100M_RETIMER_CPU0_P1_R_DN")
	)
	(segment
		(start 330.080874 -395.578584)
		(end 330.543662 -395.578584)
		(width 0.12954)
		(layer "F.Cu")
		(net "CLK_100M_RETIMER_CPU0_P1_R_DN")
	)
	(segment
		(start 329.810364 -395.308074)
		(end 330.080874 -395.578584)
		(width 0.12954)
		(layer "F.Cu")
		(net "CLK_100M_RETIMER_CPU0_P1_R_DN")
	)
	(segment
		(start 288.255964 -418.073078)
		(end 288.449766 -418.073078)
		(width 0.12954)
		(layer "F.Cu")
		(net "CLK_100M_RETIMER_CPU0_P1_R_DN")
	)
	(via
		(at 290.300918 -402.161756)
		(size 0.508)
		(drill 0.254)
		(layers "F.Cu" "B.Cu")
		(net "CLK_100M_RETIMER_CPU0_P1_R_DN")
	)
	(via
		(at 329.810364 -395.308074)
		(size 0.508)
		(drill 0.254)
		(layers "F.Cu" "B.Cu")
		(net "CLK_100M_RETIMER_CPU0_P1_R_DN")
	)
	(via
		(at 289.835336 -418.254688)
		(size 0.508)
		(drill 0.254)
		(layers "F.Cu" "B.Cu")
		(net "CLK_100M_RETIMER_CPU0_P1_R_DN")
	)
	(segment
		(start 328.757788 -395.397482)
		(end 328.032618 -395.397482)
		(width 0.14224)
		(layer "In2.Cu")
		(net "CLK_100M_RETIMER_CPU0_P1_R_DN")
	)
	(segment
		(start 322.93306 -401.541996)
		(end 323.04736 -401.656296)
		(width 0.14224)
		(layer "In2.Cu")
		(net "CLK_100M_RETIMER_CPU0_P1_R_DN")
	)
	(segment
		(start 329.519534 -395.598904)
		(end 328.95921 -395.598904)
		(width 0.14224)
		(layer "In2.Cu")
		(net "CLK_100M_RETIMER_CPU0_P1_R_DN")
	)
	(segment
		(start 327.276968 -396.152878)
		(end 327.147682 -396.34668)
		(width 0.14224)
		(layer "In2.Cu")
		(net "CLK_100M_RETIMER_CPU0_P1_R_DN")
	)
	(segment
		(start 326.204834 -397.844518)
		(end 325.897748 -397.844518)
		(width 0.14224)
		(layer "In2.Cu")
		(net "CLK_100M_RETIMER_CPU0_P1_R_DN")
	)
	(segment
		(start 328.95921 -395.598904)
		(end 328.757788 -395.397482)
		(width 0.14224)
		(layer "In2.Cu")
		(net "CLK_100M_RETIMER_CPU0_P1_R_DN")
	)
	(segment
		(start 301.474378 -401.456398)
		(end 300.272704 -400.254724)
		(width 0.14224)
		(layer "In2.Cu")
		(net "CLK_100M_RETIMER_CPU0_P1_R_DN")
	)
	(segment
		(start 323.04736 -401.656296)
		(end 323.04736 -402.38934)
		(width 0.14224)
		(layer "In2.Cu")
		(net "CLK_100M_RETIMER_CPU0_P1_R_DN")
	)
	(segment
		(start 329.810364 -395.308074)
		(end 329.519534 -395.598904)
		(width 0.14224)
		(layer "In2.Cu")
		(net "CLK_100M_RETIMER_CPU0_P1_R_DN")
	)
	(segment
		(start 323.04736 -402.38934)
		(end 322.632578 -402.804122)
		(width 0.14224)
		(layer "In2.Cu")
		(net "CLK_100M_RETIMER_CPU0_P1_R_DN")
	)
	(segment
		(start 328.032618 -395.397482)
		(end 327.949814 -395.480032)
		(width 0.14224)
		(layer "In2.Cu")
		(net "CLK_100M_RETIMER_CPU0_P1_R_DN")
	)
	(segment
		(start 325.897748 -397.844518)
		(end 322.93306 -400.809206)
		(width 0.14224)
		(layer "In2.Cu")
		(net "CLK_100M_RETIMER_CPU0_P1_R_DN")
	)
	(segment
		(start 327.950068 -395.480032)
		(end 327.276968 -396.152878)
		(width 0.14224)
		(layer "In2.Cu")
		(net "CLK_100M_RETIMER_CPU0_P1_R_DN")
	)
	(segment
		(start 300.272704 -400.254724)
		(end 294.162734 -400.254724)
		(width 0.14224)
		(layer "In2.Cu")
		(net "CLK_100M_RETIMER_CPU0_P1_R_DN")
	)
	(segment
		(start 326.80148 -397.18234)
		(end 326.669654 -397.379698)
		(width 0.14224)
		(layer "In2.Cu")
		(net "CLK_100M_RETIMER_CPU0_P1_R_DN")
	)
	(segment
		(start 291.964872 -402.452586)
		(end 290.591748 -402.452586)
		(width 0.14224)
		(layer "In2.Cu")
		(net "CLK_100M_RETIMER_CPU0_P1_R_DN")
	)
	(segment
		(start 322.632578 -402.804122)
		(end 302.359568 -402.804122)
		(width 0.14224)
		(layer "In2.Cu")
		(net "CLK_100M_RETIMER_CPU0_P1_R_DN")
	)
	(segment
		(start 322.93306 -400.809206)
		(end 322.93306 -401.541996)
		(width 0.14224)
		(layer "In2.Cu")
		(net "CLK_100M_RETIMER_CPU0_P1_R_DN")
	)
	(segment
		(start 327.949814 -395.480032)
		(end 327.950068 -395.480032)
		(width 0.14224)
		(layer "In2.Cu")
		(net "CLK_100M_RETIMER_CPU0_P1_R_DN")
	)
	(segment
		(start 326.669654 -397.379698)
		(end 326.204834 -397.844518)
		(width 0.14224)
		(layer "In2.Cu")
		(net "CLK_100M_RETIMER_CPU0_P1_R_DN")
	)
	(segment
		(start 294.162734 -400.254724)
		(end 291.964872 -402.452586)
		(width 0.14224)
		(layer "In2.Cu")
		(net "CLK_100M_RETIMER_CPU0_P1_R_DN")
	)
	(segment
		(start 302.359568 -402.804122)
		(end 301.80153 -402.246084)
		(width 0.14224)
		(layer "In2.Cu")
		(net "CLK_100M_RETIMER_CPU0_P1_R_DN")
	)
	(segment
		(start 327.147682 -396.34668)
		(end 326.80148 -397.18234)
		(width 0.14224)
		(layer "In2.Cu")
		(net "CLK_100M_RETIMER_CPU0_P1_R_DN")
	)
	(segment
		(start 290.591748 -402.452586)
		(end 290.300918 -402.161756)
		(width 0.14224)
		(layer "In2.Cu")
		(net "CLK_100M_RETIMER_CPU0_P1_R_DN")
	)
	(segment
		(start 301.80153 -402.246084)
		(end 301.474378 -401.456398)
		(width 0.14224)
		(layer "In2.Cu")
		(net "CLK_100M_RETIMER_CPU0_P1_R_DN")
	)
	(segment
		(start 288.458402 -402.452586)
		(end 290.010088 -402.452586)
		(width 0.14224)
		(layer "In13.Cu")
		(net "CLK_100M_RETIMER_CPU0_P1_R_DN")
	)
	(segment
		(start 288.78657 -413.713422)
		(end 288.166302 -413.093154)
		(width 0.14224)
		(layer "In13.Cu")
		(net "CLK_100M_RETIMER_CPU0_P1_R_DN")
	)
	(segment
		(start 289.835336 -418.254688)
		(end 289.544506 -417.963858)
		(width 0.14224)
		(layer "In13.Cu")
		(net "CLK_100M_RETIMER_CPU0_P1_R_DN")
	)
	(segment
		(start 290.010088 -402.452586)
		(end 290.300918 -402.161756)
		(width 0.14224)
		(layer "In13.Cu")
		(net "CLK_100M_RETIMER_CPU0_P1_R_DN")
	)
	(segment
		(start 288.166302 -402.744686)
		(end 288.458402 -402.452586)
		(width 0.14224)
		(layer "In13.Cu")
		(net "CLK_100M_RETIMER_CPU0_P1_R_DN")
	)
	(segment
		(start 288.166302 -413.093154)
		(end 288.166302 -402.744686)
		(width 0.14224)
		(layer "In13.Cu")
		(net "CLK_100M_RETIMER_CPU0_P1_R_DN")
	)
	(segment
		(start 289.20821 -417.963858)
		(end 288.78657 -417.542218)
		(width 0.14224)
		(layer "In13.Cu")
		(net "CLK_100M_RETIMER_CPU0_P1_R_DN")
	)
	(segment
		(start 288.78657 -417.542218)
		(end 288.78657 -413.713422)
		(width 0.14224)
		(layer "In13.Cu")
		(net "CLK_100M_RETIMER_CPU0_P1_R_DN")
	)
	(segment
		(start 289.544506 -417.963858)
		(end 289.20821 -417.963858)
		(width 0.14224)
		(layer "In13.Cu")
		(net "CLK_100M_RETIMER_CPU0_P1_R_DN")
	)
	(segment
		(start 331.568044 -395.900402)
		(end 331.8256 -395.900402)
		(width 0.12954)
		(layer "F.Cu")
		(net "CLK_100M_RETIMER_CPU0_P1_DP")
	)
	(segment
		(start 331.8256 -395.900402)
		(end 332.071472 -396.146274)
		(width 0.12954)
		(layer "F.Cu")
		(net "CLK_100M_RETIMER_CPU0_P1_DP")
	)
	(segment
		(start 333.819754 -396.129002)
		(end 334.025494 -396.129002)
		(width 0.1016)
		(layer "F.Cu")
		(net "CLK_100M_RETIMER_CPU0_P1_DP")
	)
	(segment
		(start 333.750666 -396.19809)
		(end 333.819754 -396.129002)
		(width 0.1016)
		(layer "F.Cu")
		(net "CLK_100M_RETIMER_CPU0_P1_DP")
	)
	(segment
		(start 332.328774 -395.888972)
		(end 332.695804 -395.888972)
		(width 0.12954)
		(layer "F.Cu")
		(net "CLK_100M_RETIMER_CPU0_P1_DP")
	)
	(segment
		(start 333.004922 -396.19809)
		(end 333.750666 -396.19809)
		(width 0.12954)
		(layer "F.Cu")
		(net "CLK_100M_RETIMER_CPU0_P1_DP")
	)
	(segment
		(start 334.025494 -396.129002)
		(end 334.109568 -396.213076)
		(width 0.1016)
		(layer "F.Cu")
		(net "CLK_100M_RETIMER_CPU0_P1_DP")
	)
	(segment
		(start 332.071472 -396.146274)
		(end 332.328774 -395.888972)
		(width 0.12954)
		(layer "F.Cu")
		(net "CLK_100M_RETIMER_CPU0_P1_DP")
	)
	(segment
		(start 331.322172 -396.146274)
		(end 331.568044 -395.900402)
		(width 0.12954)
		(layer "F.Cu")
		(net "CLK_100M_RETIMER_CPU0_P1_DP")
	)
	(segment
		(start 332.695804 -395.888972)
		(end 333.004922 -396.19809)
		(width 0.12954)
		(layer "F.Cu")
		(net "CLK_100M_RETIMER_CPU0_P1_DP")
	)
	(segment
		(start 331.322172 -395.333474)
		(end 331.56652 -395.577822)
		(width 0.12954)
		(layer "F.Cu")
		(net "CLK_100M_RETIMER_CPU0_P1_DN")
	)
	(segment
		(start 333.731616 -395.87551)
		(end 333.769208 -395.913102)
		(width 0.1016)
		(layer "F.Cu")
		(net "CLK_100M_RETIMER_CPU0_P1_DN")
	)
	(segment
		(start 331.827124 -395.577822)
		(end 332.071472 -395.333474)
		(width 0.12954)
		(layer "F.Cu")
		(net "CLK_100M_RETIMER_CPU0_P1_DN")
	)
	(segment
		(start 333.13878 -395.87551)
		(end 333.731616 -395.87551)
		(width 0.12954)
		(layer "F.Cu")
		(net "CLK_100M_RETIMER_CPU0_P1_DN")
	)
	(segment
		(start 333.769208 -395.913102)
		(end 334.629252 -395.913102)
		(width 0.1016)
		(layer "F.Cu")
		(net "CLK_100M_RETIMER_CPU0_P1_DN")
	)
	(segment
		(start 332.071472 -395.333474)
		(end 332.30439 -395.566392)
		(width 0.12954)
		(layer "F.Cu")
		(net "CLK_100M_RETIMER_CPU0_P1_DN")
	)
	(segment
		(start 331.56652 -395.577822)
		(end 331.827124 -395.577822)
		(width 0.12954)
		(layer "F.Cu")
		(net "CLK_100M_RETIMER_CPU0_P1_DN")
	)
	(segment
		(start 332.829662 -395.566392)
		(end 333.13878 -395.87551)
		(width 0.12954)
		(layer "F.Cu")
		(net "CLK_100M_RETIMER_CPU0_P1_DN")
	)
	(segment
		(start 332.30439 -395.566392)
		(end 332.829662 -395.566392)
		(width 0.12954)
		(layer "F.Cu")
		(net "CLK_100M_RETIMER_CPU0_P1_DN")
	)
	(segment
		(start 297.282616 -396.171674)
		(end 297.553126 -395.901164)
		(width 0.12954)
		(layer "F.Cu")
		(net "CLK_100M_RETIMER_CPU0_P0_R_DP")
	)
	(segment
		(start 298.015914 -395.901164)
		(end 298.261024 -396.146274)
		(width 0.12954)
		(layer "F.Cu")
		(net "CLK_100M_RETIMER_CPU0_P0_R_DP")
	)
	(segment
		(start 286.2199 -415.614612)
		(end 286.2199 -413.607758)
		(width 0.12954)
		(layer "F.Cu")
		(net "CLK_100M_RETIMER_CPU0_P0_R_DP")
	)
	(segment
		(start 286.131 -415.948114)
		(end 286.131 -415.703512)
		(width 0.12954)
		(layer "F.Cu")
		(net "CLK_100M_RETIMER_CPU0_P0_R_DP")
	)
	(segment
		(start 283.187648 -410.575506)
		(end 283.187648 -407.827226)
		(width 0.12954)
		(layer "F.Cu")
		(net "CLK_100M_RETIMER_CPU0_P0_R_DP")
	)
	(segment
		(start 286.131 -415.703512)
		(end 286.2199 -415.614612)
		(width 0.12954)
		(layer "F.Cu")
		(net "CLK_100M_RETIMER_CPU0_P0_R_DP")
	)
	(segment
		(start 286.2199 -413.607758)
		(end 283.187648 -410.575506)
		(width 0.12954)
		(layer "F.Cu")
		(net "CLK_100M_RETIMER_CPU0_P0_R_DP")
	)
	(segment
		(start 297.553126 -395.901164)
		(end 298.015914 -395.901164)
		(width 0.12954)
		(layer "F.Cu")
		(net "CLK_100M_RETIMER_CPU0_P0_R_DP")
	)
	(segment
		(start 283.187648 -407.827226)
		(end 282.917138 -407.556716)
		(width 0.12954)
		(layer "F.Cu")
		(net "CLK_100M_RETIMER_CPU0_P0_R_DP")
	)
	(via
		(at 297.282616 -396.171674)
		(size 0.508)
		(drill 0.254)
		(layers "F.Cu" "B.Cu")
		(net "CLK_100M_RETIMER_CPU0_P0_R_DP")
	)
	(via
		(at 282.917138 -407.556716)
		(size 0.508)
		(drill 0.254)
		(layers "F.Cu" "B.Cu")
		(net "CLK_100M_RETIMER_CPU0_P0_R_DP")
	)
	(segment
		(start 293.318692 -398.021048)
		(end 293.455852 -397.883888)
		(width 0.14224)
		(layer "In2.Cu")
		(net "CLK_100M_RETIMER_CPU0_P0_R_DP")
	)
	(segment
		(start 281.487118 -401.914106)
		(end 281.681174 -401.914106)
		(width 0.14224)
		(layer "In2.Cu")
		(net "CLK_100M_RETIMER_CPU0_P0_R_DP")
	)
	(segment
		(start 283.082238 -400.318986)
		(end 283.276294 -400.318986)
		(width 0.14224)
		(layer "In2.Cu")
		(net "CLK_100M_RETIMER_CPU0_P0_R_DP")
	)
	(segment
		(start 281.98318 -401.6121)
		(end 281.98318 -401.418044)
		(width 0.14224)
		(layer "In2.Cu")
		(net "CLK_100M_RETIMER_CPU0_P0_R_DP")
	)
	(segment
		(start 281.18562 -405.68118)
		(end 281.32278 -405.54402)
		(width 0.14224)
		(layer "In2.Cu")
		(net "CLK_100M_RETIMER_CPU0_P0_R_DP")
	)
	(segment
		(start 284.37586 -399.025364)
		(end 284.677358 -398.723866)
		(width 0.14224)
		(layer "In2.Cu")
		(net "CLK_100M_RETIMER_CPU0_P0_R_DP")
	)
	(segment
		(start 295.885616 -395.880844)
		(end 296.991786 -395.880844)
		(width 0.14224)
		(layer "In2.Cu")
		(net "CLK_100M_RETIMER_CPU0_P0_R_DP")
	)
	(segment
		(start 282.478734 -401.116546)
		(end 282.78074 -400.81454)
		(width 0.14224)
		(layer "In2.Cu")
		(net "CLK_100M_RETIMER_CPU0_P0_R_DP")
	)
	(segment
		(start 294.378126 -397.58239)
		(end 294.680132 -397.280384)
		(width 0.14224)
		(layer "In2.Cu")
		(net "CLK_100M_RETIMER_CPU0_P0_R_DP")
	)
	(segment
		(start 286.92475 -397.883888)
		(end 287.06191 -398.021048)
		(width 0.14224)
		(layer "In2.Cu")
		(net "CLK_100M_RETIMER_CPU0_P0_R_DP")
	)
	(segment
		(start 284.073854 -399.521426)
		(end 284.37586 -399.21942)
		(width 0.14224)
		(layer "In2.Cu")
		(net "CLK_100M_RETIMER_CPU0_P0_R_DP")
	)
	(segment
		(start 286.36087 -398.021048)
		(end 286.49803 -397.883888)
		(width 0.14224)
		(layer "In2.Cu")
		(net "CLK_100M_RETIMER_CPU0_P0_R_DP")
	)
	(segment
		(start 285.517336 -397.883888)
		(end 285.79699 -397.883888)
		(width 0.14224)
		(layer "In2.Cu")
		(net "CLK_100M_RETIMER_CPU0_P0_R_DP")
	)
	(segment
		(start 287.48863 -398.021048)
		(end 287.62579 -397.883888)
		(width 0.14224)
		(layer "In2.Cu")
		(net "CLK_100M_RETIMER_CPU0_P0_R_DP")
	)
	(segment
		(start 281.681174 -401.914106)
		(end 281.98318 -401.6121)
		(width 0.14224)
		(layer "In2.Cu")
		(net "CLK_100M_RETIMER_CPU0_P0_R_DP")
	)
	(segment
		(start 290.451032 -397.883888)
		(end 290.588192 -398.021048)
		(width 0.14224)
		(layer "In2.Cu")
		(net "CLK_100M_RETIMER_CPU0_P0_R_DP")
	)
	(segment
		(start 287.62579 -397.883888)
		(end 290.451032 -397.883888)
		(width 0.14224)
		(layer "In2.Cu")
		(net "CLK_100M_RETIMER_CPU0_P0_R_DP")
	)
	(segment
		(start 285.17342 -398.42186)
		(end 285.17342 -398.227804)
		(width 0.14224)
		(layer "In2.Cu")
		(net "CLK_100M_RETIMER_CPU0_P0_R_DP")
	)
	(segment
		(start 296.991786 -395.880844)
		(end 297.282616 -396.171674)
		(width 0.14224)
		(layer "In2.Cu")
		(net "CLK_100M_RETIMER_CPU0_P0_R_DP")
	)
	(segment
		(start 281.32278 -407.79954)
		(end 281.32278 -407.37282)
		(width 0.14224)
		(layer "In2.Cu")
		(net "CLK_100M_RETIMER_CPU0_P0_R_DP")
	)
	(segment
		(start 291.014912 -398.021048)
		(end 291.152072 -397.883888)
		(width 0.14224)
		(layer "In2.Cu")
		(net "CLK_100M_RETIMER_CPU0_P0_R_DP")
	)
	(segment
		(start 281.18562 -406.80894)
		(end 281.32278 -406.67178)
		(width 0.14224)
		(layer "In2.Cu")
		(net "CLK_100M_RETIMER_CPU0_P0_R_DP")
	)
	(segment
		(start 281.98318 -401.418044)
		(end 282.284678 -401.116546)
		(width 0.14224)
		(layer "In2.Cu")
		(net "CLK_100M_RETIMER_CPU0_P0_R_DP")
	)
	(segment
		(start 285.79699 -397.883888)
		(end 285.93415 -398.021048)
		(width 0.14224)
		(layer "In2.Cu")
		(net "CLK_100M_RETIMER_CPU0_P0_R_DP")
	)
	(segment
		(start 281.32278 -402.86178)
		(end 281.18562 -402.72462)
		(width 0.14224)
		(layer "In2.Cu")
		(net "CLK_100M_RETIMER_CPU0_P0_R_DP")
	)
	(segment
		(start 295.477692 -396.288768)
		(end 295.885616 -395.880844)
		(width 0.14224)
		(layer "In2.Cu")
		(net "CLK_100M_RETIMER_CPU0_P0_R_DP")
	)
	(segment
		(start 281.18562 -407.23566)
		(end 281.18562 -406.80894)
		(width 0.14224)
		(layer "In2.Cu")
		(net "CLK_100M_RETIMER_CPU0_P0_R_DP")
	)
	(segment
		(start 281.18562 -407.9367)
		(end 281.32278 -407.79954)
		(width 0.14224)
		(layer "In2.Cu")
		(net "CLK_100M_RETIMER_CPU0_P0_R_DP")
	)
	(segment
		(start 281.32278 -403.98954)
		(end 281.18562 -403.85238)
		(width 0.14224)
		(layer "In2.Cu")
		(net "CLK_100M_RETIMER_CPU0_P0_R_DP")
	)
	(segment
		(start 282.284678 -401.116546)
		(end 282.478734 -401.116546)
		(width 0.14224)
		(layer "In2.Cu")
		(net "CLK_100M_RETIMER_CPU0_P0_R_DP")
	)
	(segment
		(start 284.677358 -398.723866)
		(end 284.871414 -398.723866)
		(width 0.14224)
		(layer "In2.Cu")
		(net "CLK_100M_RETIMER_CPU0_P0_R_DP")
	)
	(segment
		(start 281.88031 -408.35326)
		(end 281.74315 -408.49042)
		(width 0.14224)
		(layer "In2.Cu")
		(net "CLK_100M_RETIMER_CPU0_P0_R_DP")
	)
	(segment
		(start 281.18562 -403.85238)
		(end 281.18562 -403.42566)
		(width 0.14224)
		(layer "In2.Cu")
		(net "CLK_100M_RETIMER_CPU0_P0_R_DP")
	)
	(segment
		(start 292.891972 -398.021048)
		(end 293.318692 -398.021048)
		(width 0.14224)
		(layer "In2.Cu")
		(net "CLK_100M_RETIMER_CPU0_P0_R_DP")
	)
	(segment
		(start 292.754812 -397.883888)
		(end 292.891972 -398.021048)
		(width 0.14224)
		(layer "In2.Cu")
		(net "CLK_100M_RETIMER_CPU0_P0_R_DP")
	)
	(segment
		(start 290.588192 -398.021048)
		(end 291.014912 -398.021048)
		(width 0.14224)
		(layer "In2.Cu")
		(net "CLK_100M_RETIMER_CPU0_P0_R_DP")
	)
	(segment
		(start 295.477692 -396.482824)
		(end 295.477692 -396.288768)
		(width 0.14224)
		(layer "In2.Cu")
		(net "CLK_100M_RETIMER_CPU0_P0_R_DP")
	)
	(segment
		(start 294.680132 -397.280384)
		(end 294.680132 -397.086328)
		(width 0.14224)
		(layer "In2.Cu")
		(net "CLK_100M_RETIMER_CPU0_P0_R_DP")
	)
	(segment
		(start 281.32278 -405.54402)
		(end 281.32278 -405.1173)
		(width 0.14224)
		(layer "In2.Cu")
		(net "CLK_100M_RETIMER_CPU0_P0_R_DP")
	)
	(segment
		(start 282.880816 -408.49042)
		(end 282.44419 -408.49042)
		(width 0.14224)
		(layer "In2.Cu")
		(net "CLK_100M_RETIMER_CPU0_P0_R_DP")
	)
	(segment
		(start 281.32278 -406.67178)
		(end 281.32278 -406.24506)
		(width 0.14224)
		(layer "In2.Cu")
		(net "CLK_100M_RETIMER_CPU0_P0_R_DP")
	)
	(segment
		(start 281.18562 -404.55342)
		(end 281.32278 -404.41626)
		(width 0.14224)
		(layer "In2.Cu")
		(net "CLK_100M_RETIMER_CPU0_P0_R_DP")
	)
	(segment
		(start 284.37586 -399.21942)
		(end 284.37586 -399.025364)
		(width 0.14224)
		(layer "In2.Cu")
		(net "CLK_100M_RETIMER_CPU0_P0_R_DP")
	)
	(segment
		(start 281.18562 -406.1079)
		(end 281.18562 -405.68118)
		(width 0.14224)
		(layer "In2.Cu")
		(net "CLK_100M_RETIMER_CPU0_P0_R_DP")
	)
	(segment
		(start 283.276294 -400.318986)
		(end 283.5783 -400.01698)
		(width 0.14224)
		(layer "In2.Cu")
		(net "CLK_100M_RETIMER_CPU0_P0_R_DP")
	)
	(segment
		(start 281.32278 -406.24506)
		(end 281.18562 -406.1079)
		(width 0.14224)
		(layer "In2.Cu")
		(net "CLK_100M_RETIMER_CPU0_P0_R_DP")
	)
	(segment
		(start 281.32278 -403.2885)
		(end 281.32278 -402.86178)
		(width 0.14224)
		(layer "In2.Cu")
		(net "CLK_100M_RETIMER_CPU0_P0_R_DP")
	)
	(segment
		(start 281.32278 -404.41626)
		(end 281.32278 -403.98954)
		(width 0.14224)
		(layer "In2.Cu")
		(net "CLK_100M_RETIMER_CPU0_P0_R_DP")
	)
	(segment
		(start 281.31262 -408.49042)
		(end 281.18562 -408.36342)
		(width 0.14224)
		(layer "In2.Cu")
		(net "CLK_100M_RETIMER_CPU0_P0_R_DP")
	)
	(segment
		(start 285.17342 -398.227804)
		(end 285.517336 -397.883888)
		(width 0.14224)
		(layer "In2.Cu")
		(net "CLK_100M_RETIMER_CPU0_P0_R_DP")
	)
	(segment
		(start 291.152072 -397.883888)
		(end 292.754812 -397.883888)
		(width 0.14224)
		(layer "In2.Cu")
		(net "CLK_100M_RETIMER_CPU0_P0_R_DP")
	)
	(segment
		(start 294.680132 -397.086328)
		(end 294.98163 -396.78483)
		(width 0.14224)
		(layer "In2.Cu")
		(net "CLK_100M_RETIMER_CPU0_P0_R_DP")
	)
	(segment
		(start 283.207968 -408.163268)
		(end 282.880816 -408.49042)
		(width 0.14224)
		(layer "In2.Cu")
		(net "CLK_100M_RETIMER_CPU0_P0_R_DP")
	)
	(segment
		(start 287.06191 -398.021048)
		(end 287.48863 -398.021048)
		(width 0.14224)
		(layer "In2.Cu")
		(net "CLK_100M_RETIMER_CPU0_P0_R_DP")
	)
	(segment
		(start 281.32278 -407.37282)
		(end 281.18562 -407.23566)
		(width 0.14224)
		(layer "In2.Cu")
		(net "CLK_100M_RETIMER_CPU0_P0_R_DP")
	)
	(segment
		(start 293.882572 -397.883888)
		(end 294.18407 -397.58239)
		(width 0.14224)
		(layer "In2.Cu")
		(net "CLK_100M_RETIMER_CPU0_P0_R_DP")
	)
	(segment
		(start 293.455852 -397.883888)
		(end 293.882572 -397.883888)
		(width 0.14224)
		(layer "In2.Cu")
		(net "CLK_100M_RETIMER_CPU0_P0_R_DP")
	)
	(segment
		(start 284.871414 -398.723866)
		(end 285.17342 -398.42186)
		(width 0.14224)
		(layer "In2.Cu")
		(net "CLK_100M_RETIMER_CPU0_P0_R_DP")
	)
	(segment
		(start 282.44419 -408.49042)
		(end 282.30703 -408.35326)
		(width 0.14224)
		(layer "In2.Cu")
		(net "CLK_100M_RETIMER_CPU0_P0_R_DP")
	)
	(segment
		(start 283.5783 -400.01698)
		(end 283.5783 -399.822924)
		(width 0.14224)
		(layer "In2.Cu")
		(net "CLK_100M_RETIMER_CPU0_P0_R_DP")
	)
	(segment
		(start 282.917138 -407.556716)
		(end 283.207968 -407.847546)
		(width 0.14224)
		(layer "In2.Cu")
		(net "CLK_100M_RETIMER_CPU0_P0_R_DP")
	)
	(segment
		(start 283.5783 -399.822924)
		(end 283.879798 -399.521426)
		(width 0.14224)
		(layer "In2.Cu")
		(net "CLK_100M_RETIMER_CPU0_P0_R_DP")
	)
	(segment
		(start 281.18562 -408.36342)
		(end 281.18562 -407.9367)
		(width 0.14224)
		(layer "In2.Cu")
		(net "CLK_100M_RETIMER_CPU0_P0_R_DP")
	)
	(segment
		(start 282.30703 -408.35326)
		(end 281.88031 -408.35326)
		(width 0.14224)
		(layer "In2.Cu")
		(net "CLK_100M_RETIMER_CPU0_P0_R_DP")
	)
	(segment
		(start 283.207968 -407.847546)
		(end 283.207968 -408.163268)
		(width 0.14224)
		(layer "In2.Cu")
		(net "CLK_100M_RETIMER_CPU0_P0_R_DP")
	)
	(segment
		(start 281.74315 -408.49042)
		(end 281.31262 -408.49042)
		(width 0.14224)
		(layer "In2.Cu")
		(net "CLK_100M_RETIMER_CPU0_P0_R_DP")
	)
	(segment
		(start 281.18562 -403.42566)
		(end 281.32278 -403.2885)
		(width 0.14224)
		(layer "In2.Cu")
		(net "CLK_100M_RETIMER_CPU0_P0_R_DP")
	)
	(segment
		(start 294.98163 -396.78483)
		(end 295.175686 -396.78483)
		(width 0.14224)
		(layer "In2.Cu")
		(net "CLK_100M_RETIMER_CPU0_P0_R_DP")
	)
	(segment
		(start 281.32278 -405.1173)
		(end 281.18562 -404.98014)
		(width 0.14224)
		(layer "In2.Cu")
		(net "CLK_100M_RETIMER_CPU0_P0_R_DP")
	)
	(segment
		(start 281.18562 -402.72462)
		(end 281.18562 -402.215604)
		(width 0.14224)
		(layer "In2.Cu")
		(net "CLK_100M_RETIMER_CPU0_P0_R_DP")
	)
	(segment
		(start 285.93415 -398.021048)
		(end 286.36087 -398.021048)
		(width 0.14224)
		(layer "In2.Cu")
		(net "CLK_100M_RETIMER_CPU0_P0_R_DP")
	)
	(segment
		(start 282.78074 -400.620484)
		(end 283.082238 -400.318986)
		(width 0.14224)
		(layer "In2.Cu")
		(net "CLK_100M_RETIMER_CPU0_P0_R_DP")
	)
	(segment
		(start 286.49803 -397.883888)
		(end 286.92475 -397.883888)
		(width 0.14224)
		(layer "In2.Cu")
		(net "CLK_100M_RETIMER_CPU0_P0_R_DP")
	)
	(segment
		(start 281.18562 -404.98014)
		(end 281.18562 -404.55342)
		(width 0.14224)
		(layer "In2.Cu")
		(net "CLK_100M_RETIMER_CPU0_P0_R_DP")
	)
	(segment
		(start 281.18562 -402.215604)
		(end 281.487118 -401.914106)
		(width 0.14224)
		(layer "In2.Cu")
		(net "CLK_100M_RETIMER_CPU0_P0_R_DP")
	)
	(segment
		(start 283.879798 -399.521426)
		(end 284.073854 -399.521426)
		(width 0.14224)
		(layer "In2.Cu")
		(net "CLK_100M_RETIMER_CPU0_P0_R_DP")
	)
	(segment
		(start 282.78074 -400.81454)
		(end 282.78074 -400.620484)
		(width 0.14224)
		(layer "In2.Cu")
		(net "CLK_100M_RETIMER_CPU0_P0_R_DP")
	)
	(segment
		(start 295.175686 -396.78483)
		(end 295.477692 -396.482824)
		(width 0.14224)
		(layer "In2.Cu")
		(net "CLK_100M_RETIMER_CPU0_P0_R_DP")
	)
	(segment
		(start 294.18407 -397.58239)
		(end 294.378126 -397.58239)
		(width 0.14224)
		(layer "In2.Cu")
		(net "CLK_100M_RETIMER_CPU0_P0_R_DP")
	)
	(segment
		(start 286.54248 -415.616644)
		(end 286.54248 -413.4739)
		(width 0.12954)
		(layer "F.Cu")
		(net "CLK_100M_RETIMER_CPU0_P0_R_DN")
	)
	(segment
		(start 283.510228 -410.441648)
		(end 283.510228 -407.827226)
		(width 0.12954)
		(layer "F.Cu")
		(net "CLK_100M_RETIMER_CPU0_P0_R_DN")
	)
	(segment
		(start 297.282616 -395.308074)
		(end 297.553126 -395.578584)
		(width 0.12954)
		(layer "F.Cu")
		(net "CLK_100M_RETIMER_CPU0_P0_R_DN")
	)
	(segment
		(start 286.631126 -415.70529)
		(end 286.54248 -415.616644)
		(width 0.12954)
		(layer "F.Cu")
		(net "CLK_100M_RETIMER_CPU0_P0_R_DN")
	)
	(segment
		(start 298.015914 -395.578584)
		(end 298.261024 -395.333474)
		(width 0.12954)
		(layer "F.Cu")
		(net "CLK_100M_RETIMER_CPU0_P0_R_DN")
	)
	(segment
		(start 286.631126 -415.948114)
		(end 286.631126 -415.70529)
		(width 0.12954)
		(layer "F.Cu")
		(net "CLK_100M_RETIMER_CPU0_P0_R_DN")
	)
	(segment
		(start 283.510228 -407.827226)
		(end 283.780738 -407.556716)
		(width 0.12954)
		(layer "F.Cu")
		(net "CLK_100M_RETIMER_CPU0_P0_R_DN")
	)
	(segment
		(start 286.54248 -413.4739)
		(end 283.510228 -410.441648)
		(width 0.12954)
		(layer "F.Cu")
		(net "CLK_100M_RETIMER_CPU0_P0_R_DN")
	)
	(segment
		(start 297.553126 -395.578584)
		(end 298.015914 -395.578584)
		(width 0.12954)
		(layer "F.Cu")
		(net "CLK_100M_RETIMER_CPU0_P0_R_DN")
	)
	(via
		(at 283.780738 -407.556716)
		(size 0.508)
		(drill 0.254)
		(layers "F.Cu" "B.Cu")
		(net "CLK_100M_RETIMER_CPU0_P0_R_DN")
	)
	(via
		(at 297.282616 -395.308074)
		(size 0.508)
		(drill 0.254)
		(layers "F.Cu" "B.Cu")
		(net "CLK_100M_RETIMER_CPU0_P0_R_DN")
	)
	(segment
		(start 280.90368 -402.098764)
		(end 285.400496 -397.601948)
		(width 0.14224)
		(layer "In2.Cu")
		(net "CLK_100M_RETIMER_CPU0_P0_R_DN")
	)
	(segment
		(start 280.90368 -408.48026)
		(end 280.90368 -402.098764)
		(width 0.14224)
		(layer "In2.Cu")
		(net "CLK_100M_RETIMER_CPU0_P0_R_DN")
	)
	(segment
		(start 293.765732 -397.601948)
		(end 295.768776 -395.598904)
		(width 0.14224)
		(layer "In2.Cu")
		(net "CLK_100M_RETIMER_CPU0_P0_R_DN")
	)
	(segment
		(start 283.489908 -407.847546)
		(end 283.489908 -408.280108)
		(width 0.14224)
		(layer "In2.Cu")
		(net "CLK_100M_RETIMER_CPU0_P0_R_DN")
	)
	(segment
		(start 281.19578 -408.77236)
		(end 280.90368 -408.48026)
		(width 0.14224)
		(layer "In2.Cu")
		(net "CLK_100M_RETIMER_CPU0_P0_R_DN")
	)
	(segment
		(start 282.997656 -408.77236)
		(end 281.19578 -408.77236)
		(width 0.14224)
		(layer "In2.Cu")
		(net "CLK_100M_RETIMER_CPU0_P0_R_DN")
	)
	(segment
		(start 296.991786 -395.598904)
		(end 297.282616 -395.308074)
		(width 0.14224)
		(layer "In2.Cu")
		(net "CLK_100M_RETIMER_CPU0_P0_R_DN")
	)
	(segment
		(start 285.400496 -397.601948)
		(end 293.765732 -397.601948)
		(width 0.14224)
		(layer "In2.Cu")
		(net "CLK_100M_RETIMER_CPU0_P0_R_DN")
	)
	(segment
		(start 283.780738 -407.556716)
		(end 283.489908 -407.847546)
		(width 0.14224)
		(layer "In2.Cu")
		(net "CLK_100M_RETIMER_CPU0_P0_R_DN")
	)
	(segment
		(start 295.768776 -395.598904)
		(end 296.991786 -395.598904)
		(width 0.14224)
		(layer "In2.Cu")
		(net "CLK_100M_RETIMER_CPU0_P0_R_DN")
	)
	(segment
		(start 283.489908 -408.280108)
		(end 282.997656 -408.77236)
		(width 0.14224)
		(layer "In2.Cu")
		(net "CLK_100M_RETIMER_CPU0_P0_R_DN")
	)
	(segment
		(start 298.794424 -396.146274)
		(end 299.040296 -395.900402)
		(width 0.12954)
		(layer "F.Cu")
		(net "CLK_100M_RETIMER_CPU0_P0_DP")
	)
	(segment
		(start 299.040296 -395.900402)
		(end 299.297852 -395.900402)
		(width 0.12954)
		(layer "F.Cu")
		(net "CLK_100M_RETIMER_CPU0_P0_DP")
	)
	(segment
		(start 299.543724 -396.146274)
		(end 299.801026 -395.888972)
		(width 0.12954)
		(layer "F.Cu")
		(net "CLK_100M_RETIMER_CPU0_P0_DP")
	)
	(segment
		(start 300.477174 -396.19809)
		(end 301.222918 -396.19809)
		(width 0.12954)
		(layer "F.Cu")
		(net "CLK_100M_RETIMER_CPU0_P0_DP")
	)
	(segment
		(start 299.297852 -395.900402)
		(end 299.543724 -396.146274)
		(width 0.12954)
		(layer "F.Cu")
		(net "CLK_100M_RETIMER_CPU0_P0_DP")
	)
	(segment
		(start 299.801026 -395.888972)
		(end 300.168056 -395.888972)
		(width 0.12954)
		(layer "F.Cu")
		(net "CLK_100M_RETIMER_CPU0_P0_DP")
	)
	(segment
		(start 301.497746 -396.129002)
		(end 301.58182 -396.213076)
		(width 0.1016)
		(layer "F.Cu")
		(net "CLK_100M_RETIMER_CPU0_P0_DP")
	)
	(segment
		(start 301.222918 -396.19809)
		(end 301.292006 -396.129002)
		(width 0.1016)
		(layer "F.Cu")
		(net "CLK_100M_RETIMER_CPU0_P0_DP")
	)
	(segment
		(start 300.168056 -395.888972)
		(end 300.477174 -396.19809)
		(width 0.12954)
		(layer "F.Cu")
		(net "CLK_100M_RETIMER_CPU0_P0_DP")
	)
	(segment
		(start 301.292006 -396.129002)
		(end 301.497746 -396.129002)
		(width 0.1016)
		(layer "F.Cu")
		(net "CLK_100M_RETIMER_CPU0_P0_DP")
	)
	(segment
		(start 299.038772 -395.577822)
		(end 299.299376 -395.577822)
		(width 0.12954)
		(layer "F.Cu")
		(net "CLK_100M_RETIMER_CPU0_P0_DN")
	)
	(segment
		(start 300.611032 -395.87551)
		(end 301.203868 -395.87551)
		(width 0.12954)
		(layer "F.Cu")
		(net "CLK_100M_RETIMER_CPU0_P0_DN")
	)
	(segment
		(start 300.301914 -395.566392)
		(end 300.611032 -395.87551)
		(width 0.12954)
		(layer "F.Cu")
		(net "CLK_100M_RETIMER_CPU0_P0_DN")
	)
	(segment
		(start 299.543724 -395.333474)
		(end 299.776642 -395.566392)
		(width 0.12954)
		(layer "F.Cu")
		(net "CLK_100M_RETIMER_CPU0_P0_DN")
	)
	(segment
		(start 299.299376 -395.577822)
		(end 299.543724 -395.333474)
		(width 0.12954)
		(layer "F.Cu")
		(net "CLK_100M_RETIMER_CPU0_P0_DN")
	)
	(segment
		(start 298.794424 -395.333474)
		(end 299.038772 -395.577822)
		(width 0.12954)
		(layer "F.Cu")
		(net "CLK_100M_RETIMER_CPU0_P0_DN")
	)
	(segment
		(start 301.24146 -395.913102)
		(end 302.101504 -395.913102)
		(width 0.1016)
		(layer "F.Cu")
		(net "CLK_100M_RETIMER_CPU0_P0_DN")
	)
	(segment
		(start 301.203868 -395.87551)
		(end 301.24146 -395.913102)
		(width 0.1016)
		(layer "F.Cu")
		(net "CLK_100M_RETIMER_CPU0_P0_DN")
	)
	(segment
		(start 299.776642 -395.566392)
		(end 300.301914 -395.566392)
		(width 0.12954)
		(layer "F.Cu")
		(net "CLK_100M_RETIMER_CPU0_P0_DN")
	)
	(segment
		(start 121.19229 -320.94424)
		(end 121.19229 -320.12128)
		(width 0.12954)
		(layer "F.Cu")
		(net "CLK_100M_CPU1_CLK13_R_DP")
	)
	(segment
		(start 98.138996 -295.999154)
		(end 98.44786 -295.69029)
		(width 0.12954)
		(layer "F.Cu")
		(net "CLK_100M_CPU1_CLK13_R_DP")
	)
	(segment
		(start 98.138996 -297.067986)
		(end 98.138996 -295.999154)
		(width 0.12954)
		(layer "F.Cu")
		(net "CLK_100M_CPU1_CLK13_R_DP")
	)
	(segment
		(start 121.539 -321.29095)
		(end 121.19229 -320.94424)
		(width 0.12954)
		(layer "F.Cu")
		(net "CLK_100M_CPU1_CLK13_R_DP")
	)
	(segment
		(start 121.19229 -320.12128)
		(end 98.138996 -297.067986)
		(width 0.12954)
		(layer "F.Cu")
		(net "CLK_100M_CPU1_CLK13_R_DP")
	)
	(segment
		(start 120.86971 -320.94424)
		(end 120.86971 -320.255138)
		(width 0.12954)
		(layer "F.Cu")
		(net "CLK_100M_CPU1_CLK13_R_DN")
	)
	(segment
		(start 120.86971 -320.255138)
		(end 97.816416 -297.201844)
		(width 0.12954)
		(layer "F.Cu")
		(net "CLK_100M_CPU1_CLK13_R_DN")
	)
	(segment
		(start 97.816416 -297.201844)
		(end 97.816416 -295.9989)
		(width 0.12954)
		(layer "F.Cu")
		(net "CLK_100M_CPU1_CLK13_R_DN")
	)
	(segment
		(start 120.523 -321.29095)
		(end 120.86971 -320.94424)
		(width 0.12954)
		(layer "F.Cu")
		(net "CLK_100M_CPU1_CLK13_R_DN")
	)
	(segment
		(start 97.816416 -295.9989)
		(end 97.507806 -295.69029)
		(width 0.12954)
		(layer "F.Cu")
		(net "CLK_100M_CPU1_CLK13_R_DN")
	)
	(segment
		(start 139.68603 -369.51412)
		(end 139.298172 -369.901978)
		(width 0.12954)
		(layer "F.Cu")
		(net "CLK_100M_CPU1_CLK13_DP")
	)
	(segment
		(start 106.87431 -413.43453)
		(end 106.6038 -413.16402)
		(width 0.12954)
		(layer "F.Cu")
		(net "CLK_100M_CPU1_CLK13_DP")
	)
	(segment
		(start 106.907584 -412.624016)
		(end 106.907584 -412.29407)
		(width 0.12954)
		(layer "F.Cu")
		(net "CLK_100M_CPU1_CLK13_DP")
	)
	(segment
		(start 121.19229 -348.40799)
		(end 121.19229 -349.134684)
		(width 0.12954)
		(layer "F.Cu")
		(net "CLK_100M_CPU1_CLK13_DP")
	)
	(segment
		(start 106.6038 -412.9278)
		(end 106.907584 -412.624016)
		(width 0.12954)
		(layer "F.Cu")
		(net "CLK_100M_CPU1_CLK13_DP")
	)
	(segment
		(start 139.298172 -369.901978)
		(end 139.053062 -369.901978)
		(width 0.12954)
		(layer "F.Cu")
		(net "CLK_100M_CPU1_CLK13_DP")
	)
	(segment
		(start 106.996484 -412.20517)
		(end 106.996484 -412.00705)
		(width 0.12954)
		(layer "F.Cu")
		(net "CLK_100M_CPU1_CLK13_DP")
	)
	(segment
		(start 139.68603 -367.628424)
		(end 139.68603 -369.51412)
		(width 0.12954)
		(layer "F.Cu")
		(net "CLK_100M_CPU1_CLK13_DP")
	)
	(segment
		(start 121.19229 -322.43776)
		(end 121.19229 -348.40799)
		(width 0.12954)
		(layer "F.Cu")
		(net "CLK_100M_CPU1_CLK13_DP")
	)
	(segment
		(start 121.539 -322.09105)
		(end 121.19229 -322.43776)
		(width 0.12954)
		(layer "F.Cu")
		(net "CLK_100M_CPU1_CLK13_DP")
	)
	(segment
		(start 121.19229 -349.134684)
		(end 139.68603 -367.628424)
		(width 0.12954)
		(layer "F.Cu")
		(net "CLK_100M_CPU1_CLK13_DP")
	)
	(segment
		(start 139.053062 -369.901978)
		(end 138.748262 -370.206778)
		(width 0.12954)
		(layer "F.Cu")
		(net "CLK_100M_CPU1_CLK13_DP")
	)
	(segment
		(start 106.6038 -413.16402)
		(end 106.6038 -412.9278)
		(width 0.12954)
		(layer "F.Cu")
		(net "CLK_100M_CPU1_CLK13_DP")
	)
	(segment
		(start 106.907584 -412.29407)
		(end 106.996484 -412.20517)
		(width 0.12954)
		(layer "F.Cu")
		(net "CLK_100M_CPU1_CLK13_DP")
	)
	(via
		(at 106.87431 -413.43453)
		(size 0.508)
		(drill 0.254)
		(layers "F.Cu" "B.Cu")
		(net "CLK_100M_CPU1_CLK13_DP")
	)
	(via
		(at 138.748262 -370.206778)
		(size 0.508)
		(drill 0.254)
		(layers "F.Cu" "B.Cu")
		(net "CLK_100M_CPU1_CLK13_DP")
	)
	(via
		(at 121.19229 -348.40799)
		(size 0.4064)
		(drill 0.2032)
		(layers "F.Cu" "B.Cu")
		(net "CLK_100M_CPU1_CLK13_DP")
	)
	(segment
		(start 136.225788 -370.995448)
		(end 136.225788 -372.028974)
		(width 0.14224)
		(layer "In6.Cu")
		(net "CLK_100M_CPU1_CLK13_DP")
	)
	(segment
		(start 138.457432 -369.915948)
		(end 137.632948 -369.915948)
		(width 0.14224)
		(layer "In6.Cu")
		(net "CLK_100M_CPU1_CLK13_DP")
	)
	(segment
		(start 112.169448 -380.655322)
		(end 108.98886 -383.83591)
		(width 0.14224)
		(layer "In6.Cu")
		(net "CLK_100M_CPU1_CLK13_DP")
	)
	(segment
		(start 107.186222 -412.138876)
		(end 106.58348 -412.741618)
		(width 0.14224)
		(layer "In6.Cu")
		(net "CLK_100M_CPU1_CLK13_DP")
	)
	(segment
		(start 129.84988 -380.655322)
		(end 112.169448 -380.655322)
		(width 0.14224)
		(layer "In6.Cu")
		(net "CLK_100M_CPU1_CLK13_DP")
	)
	(segment
		(start 106.115866 -407.336244)
		(end 107.83824 -407.336244)
		(width 0.14224)
		(layer "In6.Cu")
		(net "CLK_100M_CPU1_CLK13_DP")
	)
	(segment
		(start 106.58348 -412.741618)
		(end 106.58348 -413.1437)
		(width 0.14224)
		(layer "In6.Cu")
		(net "CLK_100M_CPU1_CLK13_DP")
	)
	(segment
		(start 105.856024 -406.190958)
		(end 105.856024 -407.076402)
		(width 0.14224)
		(layer "In6.Cu")
		(net "CLK_100M_CPU1_CLK13_DP")
	)
	(segment
		(start 132.24256 -378.456698)
		(end 131.940554 -378.758704)
		(width 0.14224)
		(layer "In6.Cu")
		(net "CLK_100M_CPU1_CLK13_DP")
	)
	(segment
		(start 131.142994 -379.556264)
		(end 130.948938 -379.556264)
		(width 0.14224)
		(layer "In6.Cu")
		(net "CLK_100M_CPU1_CLK13_DP")
	)
	(segment
		(start 137.632948 -369.915948)
		(end 137.225532 -370.323364)
		(width 0.14224)
		(layer "In6.Cu")
		(net "CLK_100M_CPU1_CLK13_DP")
	)
	(segment
		(start 132.738114 -377.961144)
		(end 132.544058 -377.961144)
		(width 0.14224)
		(layer "In6.Cu")
		(net "CLK_100M_CPU1_CLK13_DP")
	)
	(segment
		(start 103.451406 -391.049764)
		(end 102.242366 -392.258804)
		(width 0.14224)
		(layer "In6.Cu")
		(net "CLK_100M_CPU1_CLK13_DP")
	)
	(segment
		(start 106.478578 -405.568404)
		(end 105.856024 -406.190958)
		(width 0.14224)
		(layer "In6.Cu")
		(net "CLK_100M_CPU1_CLK13_DP")
	)
	(segment
		(start 101.262434 -395.831822)
		(end 101.262434 -397.97863)
		(width 0.14224)
		(layer "In6.Cu")
		(net "CLK_100M_CPU1_CLK13_DP")
	)
	(segment
		(start 106.58348 -413.1437)
		(end 106.87431 -413.43453)
		(width 0.14224)
		(layer "In6.Cu")
		(net "CLK_100M_CPU1_CLK13_DP")
	)
	(segment
		(start 108.684568 -411.846776)
		(end 108.392468 -412.138876)
		(width 0.14224)
		(layer "In6.Cu")
		(net "CLK_100M_CPU1_CLK13_DP")
	)
	(segment
		(start 130.345434 -380.353824)
		(end 130.151378 -380.353824)
		(width 0.14224)
		(layer "In6.Cu")
		(net "CLK_100M_CPU1_CLK13_DP")
	)
	(segment
		(start 105.856024 -407.076402)
		(end 106.115866 -407.336244)
		(width 0.14224)
		(layer "In6.Cu")
		(net "CLK_100M_CPU1_CLK13_DP")
	)
	(segment
		(start 108.684568 -408.182572)
		(end 108.684568 -411.846776)
		(width 0.14224)
		(layer "In6.Cu")
		(net "CLK_100M_CPU1_CLK13_DP")
	)
	(segment
		(start 131.940554 -378.758704)
		(end 131.746498 -378.758704)
		(width 0.14224)
		(layer "In6.Cu")
		(net "CLK_100M_CPU1_CLK13_DP")
	)
	(segment
		(start 102.242366 -392.258804)
		(end 102.242366 -394.85189)
		(width 0.14224)
		(layer "In6.Cu")
		(net "CLK_100M_CPU1_CLK13_DP")
	)
	(segment
		(start 134.49681 -373.547894)
		(end 134.49681 -376.008392)
		(width 0.14224)
		(layer "In6.Cu")
		(net "CLK_100M_CPU1_CLK13_DP")
	)
	(segment
		(start 131.746498 -378.758704)
		(end 131.445 -379.060202)
		(width 0.14224)
		(layer "In6.Cu")
		(net "CLK_100M_CPU1_CLK13_DP")
	)
	(segment
		(start 108.98886 -384.056382)
		(end 108.330746 -384.714496)
		(width 0.14224)
		(layer "In6.Cu")
		(net "CLK_100M_CPU1_CLK13_DP")
	)
	(segment
		(start 107.83824 -407.336244)
		(end 108.684568 -408.182572)
		(width 0.14224)
		(layer "In6.Cu")
		(net "CLK_100M_CPU1_CLK13_DP")
	)
	(segment
		(start 135.125206 -372.919498)
		(end 134.49681 -373.547894)
		(width 0.14224)
		(layer "In6.Cu")
		(net "CLK_100M_CPU1_CLK13_DP")
	)
	(segment
		(start 133.04012 -377.659138)
		(end 132.738114 -377.961144)
		(width 0.14224)
		(layer "In6.Cu")
		(net "CLK_100M_CPU1_CLK13_DP")
	)
	(segment
		(start 138.748262 -370.206778)
		(end 138.457432 -369.915948)
		(width 0.14224)
		(layer "In6.Cu")
		(net "CLK_100M_CPU1_CLK13_DP")
	)
	(segment
		(start 136.666224 -370.555012)
		(end 136.225788 -370.995448)
		(width 0.14224)
		(layer "In6.Cu")
		(net "CLK_100M_CPU1_CLK13_DP")
	)
	(segment
		(start 108.392468 -412.138876)
		(end 107.186222 -412.138876)
		(width 0.14224)
		(layer "In6.Cu")
		(net "CLK_100M_CPU1_CLK13_DP")
	)
	(segment
		(start 135.483854 -372.770908)
		(end 135.125206 -372.919498)
		(width 0.14224)
		(layer "In6.Cu")
		(net "CLK_100M_CPU1_CLK13_DP")
	)
	(segment
		(start 131.445 -379.254258)
		(end 131.142994 -379.556264)
		(width 0.14224)
		(layer "In6.Cu")
		(net "CLK_100M_CPU1_CLK13_DP")
	)
	(segment
		(start 105.83672 -385.202684)
		(end 105.83672 -385.693666)
		(width 0.14224)
		(layer "In6.Cu")
		(net "CLK_100M_CPU1_CLK13_DP")
	)
	(segment
		(start 106.324908 -384.714496)
		(end 105.83672 -385.202684)
		(width 0.14224)
		(layer "In6.Cu")
		(net "CLK_100M_CPU1_CLK13_DP")
	)
	(segment
		(start 133.04012 -377.465082)
		(end 133.04012 -377.659138)
		(width 0.14224)
		(layer "In6.Cu")
		(net "CLK_100M_CPU1_CLK13_DP")
	)
	(segment
		(start 130.64744 -379.857762)
		(end 130.64744 -380.051818)
		(width 0.14224)
		(layer "In6.Cu")
		(net "CLK_100M_CPU1_CLK13_DP")
	)
	(segment
		(start 105.83672 -385.693666)
		(end 103.451406 -388.07898)
		(width 0.14224)
		(layer "In6.Cu")
		(net "CLK_100M_CPU1_CLK13_DP")
	)
	(segment
		(start 130.948938 -379.556264)
		(end 130.64744 -379.857762)
		(width 0.14224)
		(layer "In6.Cu")
		(net "CLK_100M_CPU1_CLK13_DP")
	)
	(segment
		(start 132.24256 -378.262642)
		(end 132.24256 -378.456698)
		(width 0.14224)
		(layer "In6.Cu")
		(net "CLK_100M_CPU1_CLK13_DP")
	)
	(segment
		(start 103.634286 -401.656296)
		(end 106.478578 -404.500588)
		(width 0.14224)
		(layer "In6.Cu")
		(net "CLK_100M_CPU1_CLK13_DP")
	)
	(segment
		(start 108.98886 -383.83591)
		(end 108.98886 -384.056382)
		(width 0.14224)
		(layer "In6.Cu")
		(net "CLK_100M_CPU1_CLK13_DP")
	)
	(segment
		(start 106.478578 -404.500588)
		(end 106.478578 -405.568404)
		(width 0.14224)
		(layer "In6.Cu")
		(net "CLK_100M_CPU1_CLK13_DP")
	)
	(segment
		(start 108.330746 -384.714496)
		(end 106.324908 -384.714496)
		(width 0.14224)
		(layer "In6.Cu")
		(net "CLK_100M_CPU1_CLK13_DP")
	)
	(segment
		(start 101.262434 -397.97863)
		(end 102.710742 -399.426938)
		(width 0.14224)
		(layer "In6.Cu")
		(net "CLK_100M_CPU1_CLK13_DP")
	)
	(segment
		(start 136.225788 -372.028974)
		(end 135.483854 -372.770908)
		(width 0.14224)
		(layer "In6.Cu")
		(net "CLK_100M_CPU1_CLK13_DP")
	)
	(segment
		(start 134.49681 -376.008392)
		(end 133.04012 -377.465082)
		(width 0.14224)
		(layer "In6.Cu")
		(net "CLK_100M_CPU1_CLK13_DP")
	)
	(segment
		(start 130.151378 -380.353824)
		(end 129.84988 -380.655322)
		(width 0.14224)
		(layer "In6.Cu")
		(net "CLK_100M_CPU1_CLK13_DP")
	)
	(segment
		(start 102.710742 -399.426938)
		(end 103.634286 -401.656296)
		(width 0.14224)
		(layer "In6.Cu")
		(net "CLK_100M_CPU1_CLK13_DP")
	)
	(segment
		(start 130.64744 -380.051818)
		(end 130.345434 -380.353824)
		(width 0.14224)
		(layer "In6.Cu")
		(net "CLK_100M_CPU1_CLK13_DP")
	)
	(segment
		(start 131.445 -379.060202)
		(end 131.445 -379.254258)
		(width 0.14224)
		(layer "In6.Cu")
		(net "CLK_100M_CPU1_CLK13_DP")
	)
	(segment
		(start 102.242366 -394.85189)
		(end 101.262434 -395.831822)
		(width 0.14224)
		(layer "In6.Cu")
		(net "CLK_100M_CPU1_CLK13_DP")
	)
	(segment
		(start 137.225532 -370.323364)
		(end 136.666224 -370.555012)
		(width 0.14224)
		(layer "In6.Cu")
		(net "CLK_100M_CPU1_CLK13_DP")
	)
	(segment
		(start 132.544058 -377.961144)
		(end 132.24256 -378.262642)
		(width 0.14224)
		(layer "In6.Cu")
		(net "CLK_100M_CPU1_CLK13_DP")
	)
	(segment
		(start 103.451406 -388.07898)
		(end 103.451406 -391.049764)
		(width 0.14224)
		(layer "In6.Cu")
		(net "CLK_100M_CPU1_CLK13_DP")
	)
	(segment
		(start 137.600944 -366.26927)
		(end 137.876026 -366.544352)
		(width 0.12954)
		(layer "F.Cu")
		(net "CLK_100M_CPU1_CLK13_DN")
	)
	(segment
		(start 138.420094 -367.088166)
		(end 138.695176 -367.363248)
		(width 0.12954)
		(layer "F.Cu")
		(net "CLK_100M_CPU1_CLK13_DN")
	)
	(segment
		(start 106.585004 -412.490158)
		(end 106.585004 -412.29915)
		(width 0.12954)
		(layer "F.Cu")
		(net "CLK_100M_CPU1_CLK13_DN")
	)
	(segment
		(start 138.14552 -366.544352)
		(end 138.420094 -366.818926)
		(width 0.12954)
		(layer "F.Cu")
		(net "CLK_100M_CPU1_CLK13_DN")
	)
	(segment
		(start 106.28122 -412.793942)
		(end 106.585004 -412.490158)
		(width 0.12954)
		(layer "F.Cu")
		(net "CLK_100M_CPU1_CLK13_DN")
	)
	(segment
		(start 106.28122 -413.16402)
		(end 106.28122 -412.793942)
		(width 0.12954)
		(layer "F.Cu")
		(net "CLK_100M_CPU1_CLK13_DN")
	)
	(segment
		(start 120.86971 -322.43776)
		(end 120.523 -322.09105)
		(width 0.12954)
		(layer "F.Cu")
		(net "CLK_100M_CPU1_CLK13_DN")
	)
	(segment
		(start 139.36345 -369.380262)
		(end 139.164314 -369.579398)
		(width 0.12954)
		(layer "F.Cu")
		(net "CLK_100M_CPU1_CLK13_DN")
	)
	(segment
		(start 106.01071 -413.43453)
		(end 106.28122 -413.16402)
		(width 0.12954)
		(layer "F.Cu")
		(net "CLK_100M_CPU1_CLK13_DN")
	)
	(segment
		(start 106.585004 -412.29915)
		(end 106.496358 -412.210504)
		(width 0.12954)
		(layer "F.Cu")
		(net "CLK_100M_CPU1_CLK13_DN")
	)
	(segment
		(start 138.420094 -366.818926)
		(end 138.420094 -367.088166)
		(width 0.12954)
		(layer "F.Cu")
		(net "CLK_100M_CPU1_CLK13_DN")
	)
	(segment
		(start 120.86971 -345.73972)
		(end 120.86971 -349.268542)
		(width 0.12954)
		(layer "F.Cu")
		(net "CLK_100M_CPU1_CLK13_DN")
	)
	(segment
		(start 136.781794 -365.45012)
		(end 137.056876 -365.725202)
		(width 0.12954)
		(layer "F.Cu")
		(net "CLK_100M_CPU1_CLK13_DN")
	)
	(segment
		(start 138.984482 -369.579398)
		(end 138.748262 -369.343178)
		(width 0.12954)
		(layer "F.Cu")
		(net "CLK_100M_CPU1_CLK13_DN")
	)
	(segment
		(start 136.781794 -365.180626)
		(end 136.781794 -365.45012)
		(width 0.12954)
		(layer "F.Cu")
		(net "CLK_100M_CPU1_CLK13_DN")
	)
	(segment
		(start 139.164314 -369.579398)
		(end 138.984482 -369.579398)
		(width 0.12954)
		(layer "F.Cu")
		(net "CLK_100M_CPU1_CLK13_DN")
	)
	(segment
		(start 106.496358 -412.210504)
		(end 106.496358 -412.00705)
		(width 0.12954)
		(layer "F.Cu")
		(net "CLK_100M_CPU1_CLK13_DN")
	)
	(segment
		(start 120.86971 -345.73972)
		(end 120.86971 -322.43776)
		(width 0.12954)
		(layer "F.Cu")
		(net "CLK_100M_CPU1_CLK13_DN")
	)
	(segment
		(start 139.36345 -367.762282)
		(end 139.36345 -369.380262)
		(width 0.12954)
		(layer "F.Cu")
		(net "CLK_100M_CPU1_CLK13_DN")
	)
	(segment
		(start 137.876026 -366.544352)
		(end 138.14552 -366.544352)
		(width 0.12954)
		(layer "F.Cu")
		(net "CLK_100M_CPU1_CLK13_DN")
	)
	(segment
		(start 138.695176 -367.363248)
		(end 138.964416 -367.363248)
		(width 0.12954)
		(layer "F.Cu")
		(net "CLK_100M_CPU1_CLK13_DN")
	)
	(segment
		(start 120.86971 -349.268542)
		(end 136.781794 -365.180626)
		(width 0.12954)
		(layer "F.Cu")
		(net "CLK_100M_CPU1_CLK13_DN")
	)
	(segment
		(start 138.964416 -367.363248)
		(end 139.36345 -367.762282)
		(width 0.12954)
		(layer "F.Cu")
		(net "CLK_100M_CPU1_CLK13_DN")
	)
	(segment
		(start 137.056876 -365.725202)
		(end 137.32637 -365.725202)
		(width 0.12954)
		(layer "F.Cu")
		(net "CLK_100M_CPU1_CLK13_DN")
	)
	(segment
		(start 137.600944 -365.999776)
		(end 137.600944 -366.26927)
		(width 0.12954)
		(layer "F.Cu")
		(net "CLK_100M_CPU1_CLK13_DN")
	)
	(segment
		(start 137.32637 -365.725202)
		(end 137.600944 -365.999776)
		(width 0.12954)
		(layer "F.Cu")
		(net "CLK_100M_CPU1_CLK13_DN")
	)
	(via
		(at 120.86971 -345.73972)
		(size 0.4064)
		(drill 0.2032)
		(layers "F.Cu" "B.Cu")
		(net "CLK_100M_CPU1_CLK13_DN")
	)
	(via
		(at 106.01071 -413.43453)
		(size 0.508)
		(drill 0.254)
		(layers "F.Cu" "B.Cu")
		(net "CLK_100M_CPU1_CLK13_DN")
	)
	(via
		(at 138.748262 -369.343178)
		(size 0.508)
		(drill 0.254)
		(layers "F.Cu" "B.Cu")
		(net "CLK_100M_CPU1_CLK13_DN")
	)
	(segment
		(start 135.943848 -371.912134)
		(end 135.324088 -372.531894)
		(width 0.14224)
		(layer "In6.Cu")
		(net "CLK_100M_CPU1_CLK13_DN")
	)
	(segment
		(start 137.516108 -369.634008)
		(end 137.065766 -370.08435)
		(width 0.14224)
		(layer "In6.Cu")
		(net "CLK_100M_CPU1_CLK13_DN")
	)
	(segment
		(start 108.213906 -384.432556)
		(end 106.208068 -384.432556)
		(width 0.14224)
		(layer "In6.Cu")
		(net "CLK_100M_CPU1_CLK13_DN")
	)
	(segment
		(start 136.506458 -370.315998)
		(end 135.943848 -370.878608)
		(width 0.14224)
		(layer "In6.Cu")
		(net "CLK_100M_CPU1_CLK13_DN")
	)
	(segment
		(start 134.96544 -372.680484)
		(end 134.21487 -373.431054)
		(width 0.14224)
		(layer "In6.Cu")
		(net "CLK_100M_CPU1_CLK13_DN")
	)
	(segment
		(start 100.980494 -395.714982)
		(end 100.980494 -398.09547)
		(width 0.14224)
		(layer "In6.Cu")
		(net "CLK_100M_CPU1_CLK13_DN")
	)
	(segment
		(start 103.395272 -401.816062)
		(end 106.196638 -404.617428)
		(width 0.14224)
		(layer "In6.Cu")
		(net "CLK_100M_CPU1_CLK13_DN")
	)
	(segment
		(start 107.069382 -411.856936)
		(end 106.30154 -412.624778)
		(width 0.14224)
		(layer "In6.Cu")
		(net "CLK_100M_CPU1_CLK13_DN")
	)
	(segment
		(start 106.196638 -404.617428)
		(end 106.196638 -405.451564)
		(width 0.14224)
		(layer "In6.Cu")
		(net "CLK_100M_CPU1_CLK13_DN")
	)
	(segment
		(start 106.30154 -413.1437)
		(end 106.01071 -413.43453)
		(width 0.14224)
		(layer "In6.Cu")
		(net "CLK_100M_CPU1_CLK13_DN")
	)
	(segment
		(start 105.55478 -385.576826)
		(end 103.169466 -387.96214)
		(width 0.14224)
		(layer "In6.Cu")
		(net "CLK_100M_CPU1_CLK13_DN")
	)
	(segment
		(start 137.065766 -370.08435)
		(end 136.506458 -370.315998)
		(width 0.14224)
		(layer "In6.Cu")
		(net "CLK_100M_CPU1_CLK13_DN")
	)
	(segment
		(start 105.574084 -406.074118)
		(end 105.574084 -407.193242)
		(width 0.14224)
		(layer "In6.Cu")
		(net "CLK_100M_CPU1_CLK13_DN")
	)
	(segment
		(start 103.169466 -390.932924)
		(end 101.960426 -392.141964)
		(width 0.14224)
		(layer "In6.Cu")
		(net "CLK_100M_CPU1_CLK13_DN")
	)
	(segment
		(start 101.960426 -392.141964)
		(end 101.960426 -394.73505)
		(width 0.14224)
		(layer "In6.Cu")
		(net "CLK_100M_CPU1_CLK13_DN")
	)
	(segment
		(start 138.748262 -369.343178)
		(end 138.457432 -369.634008)
		(width 0.14224)
		(layer "In6.Cu")
		(net "CLK_100M_CPU1_CLK13_DN")
	)
	(segment
		(start 108.402628 -411.729936)
		(end 108.275628 -411.856936)
		(width 0.14224)
		(layer "In6.Cu")
		(net "CLK_100M_CPU1_CLK13_DN")
	)
	(segment
		(start 108.70692 -383.939542)
		(end 108.213906 -384.432556)
		(width 0.14224)
		(layer "In6.Cu")
		(net "CLK_100M_CPU1_CLK13_DN")
	)
	(segment
		(start 134.21487 -375.891552)
		(end 129.73304 -380.373382)
		(width 0.14224)
		(layer "In6.Cu")
		(net "CLK_100M_CPU1_CLK13_DN")
	)
	(segment
		(start 101.960426 -394.73505)
		(end 100.980494 -395.714982)
		(width 0.14224)
		(layer "In6.Cu")
		(net "CLK_100M_CPU1_CLK13_DN")
	)
	(segment
		(start 106.30154 -412.624778)
		(end 106.30154 -413.1437)
		(width 0.14224)
		(layer "In6.Cu")
		(net "CLK_100M_CPU1_CLK13_DN")
	)
	(segment
		(start 105.999026 -407.618184)
		(end 107.7214 -407.618184)
		(width 0.14224)
		(layer "In6.Cu")
		(net "CLK_100M_CPU1_CLK13_DN")
	)
	(segment
		(start 105.574084 -407.193242)
		(end 105.999026 -407.618184)
		(width 0.14224)
		(layer "In6.Cu")
		(net "CLK_100M_CPU1_CLK13_DN")
	)
	(segment
		(start 106.208068 -384.432556)
		(end 105.55478 -385.085844)
		(width 0.14224)
		(layer "In6.Cu")
		(net "CLK_100M_CPU1_CLK13_DN")
	)
	(segment
		(start 105.55478 -385.085844)
		(end 105.55478 -385.576826)
		(width 0.14224)
		(layer "In6.Cu")
		(net "CLK_100M_CPU1_CLK13_DN")
	)
	(segment
		(start 108.275628 -411.856936)
		(end 107.069382 -411.856936)
		(width 0.14224)
		(layer "In6.Cu")
		(net "CLK_100M_CPU1_CLK13_DN")
	)
	(segment
		(start 102.471728 -399.586704)
		(end 103.395272 -401.816062)
		(width 0.14224)
		(layer "In6.Cu")
		(net "CLK_100M_CPU1_CLK13_DN")
	)
	(segment
		(start 135.943848 -370.878608)
		(end 135.943848 -371.912134)
		(width 0.14224)
		(layer "In6.Cu")
		(net "CLK_100M_CPU1_CLK13_DN")
	)
	(segment
		(start 106.196638 -405.451564)
		(end 105.574084 -406.074118)
		(width 0.14224)
		(layer "In6.Cu")
		(net "CLK_100M_CPU1_CLK13_DN")
	)
	(segment
		(start 108.70692 -383.71907)
		(end 108.70692 -383.939542)
		(width 0.14224)
		(layer "In6.Cu")
		(net "CLK_100M_CPU1_CLK13_DN")
	)
	(segment
		(start 135.324088 -372.531894)
		(end 134.96544 -372.680484)
		(width 0.14224)
		(layer "In6.Cu")
		(net "CLK_100M_CPU1_CLK13_DN")
	)
	(segment
		(start 138.457432 -369.634008)
		(end 137.516108 -369.634008)
		(width 0.14224)
		(layer "In6.Cu")
		(net "CLK_100M_CPU1_CLK13_DN")
	)
	(segment
		(start 100.980494 -398.09547)
		(end 102.471728 -399.586704)
		(width 0.14224)
		(layer "In6.Cu")
		(net "CLK_100M_CPU1_CLK13_DN")
	)
	(segment
		(start 129.73304 -380.373382)
		(end 112.052608 -380.373382)
		(width 0.14224)
		(layer "In6.Cu")
		(net "CLK_100M_CPU1_CLK13_DN")
	)
	(segment
		(start 108.402628 -408.299412)
		(end 108.402628 -411.729936)
		(width 0.14224)
		(layer "In6.Cu")
		(net "CLK_100M_CPU1_CLK13_DN")
	)
	(segment
		(start 103.169466 -387.96214)
		(end 103.169466 -390.932924)
		(width 0.14224)
		(layer "In6.Cu")
		(net "CLK_100M_CPU1_CLK13_DN")
	)
	(segment
		(start 134.21487 -373.431054)
		(end 134.21487 -375.891552)
		(width 0.14224)
		(layer "In6.Cu")
		(net "CLK_100M_CPU1_CLK13_DN")
	)
	(segment
		(start 107.7214 -407.618184)
		(end 108.402628 -408.299412)
		(width 0.14224)
		(layer "In6.Cu")
		(net "CLK_100M_CPU1_CLK13_DN")
	)
	(segment
		(start 112.052608 -380.373382)
		(end 108.70692 -383.71907)
		(width 0.14224)
		(layer "In6.Cu")
		(net "CLK_100M_CPU1_CLK13_DN")
	)
	(segment
		(start 360.987594 -319.732914)
		(end 360.704384 -319.449704)
		(width 0.12954)
		(layer "F.Cu")
		(net "CLK_100M_CPU0_CLK13_R_DP")
	)
	(segment
		(start 346.079318 -296.922952)
		(end 346.079318 -295.998646)
		(width 0.12954)
		(layer "F.Cu")
		(net "CLK_100M_CPU0_CLK13_R_DP")
	)
	(segment
		(start 355.504496 -313.327288)
		(end 343.574116 -313.327288)
		(width 0.12954)
		(layer "F.Cu")
		(net "CLK_100M_CPU0_CLK13_R_DP")
	)
	(segment
		(start 360.704384 -319.449704)
		(end 360.704384 -318.527176)
		(width 0.12954)
		(layer "F.Cu")
		(net "CLK_100M_CPU0_CLK13_R_DP")
	)
	(segment
		(start 338.585048 -299.091604)
		(end 339.480652 -298.196)
		(width 0.12954)
		(layer "F.Cu")
		(net "CLK_100M_CPU0_CLK13_R_DP")
	)
	(segment
		(start 339.480652 -298.196)
		(end 344.80627 -298.196)
		(width 0.12954)
		(layer "F.Cu")
		(net "CLK_100M_CPU0_CLK13_R_DP")
	)
	(segment
		(start 339.085428 -306.281836)
		(end 338.585048 -305.071526)
		(width 0.12954)
		(layer "F.Cu")
		(net "CLK_100M_CPU0_CLK13_R_DP")
	)
	(segment
		(start 360.704384 -318.527176)
		(end 355.504496 -313.327288)
		(width 0.12954)
		(layer "F.Cu")
		(net "CLK_100M_CPU0_CLK13_R_DP")
	)
	(segment
		(start 343.574116 -313.327288)
		(end 339.085428 -308.8386)
		(width 0.12954)
		(layer "F.Cu")
		(net "CLK_100M_CPU0_CLK13_R_DP")
	)
	(segment
		(start 338.585048 -305.071526)
		(end 338.585048 -299.091604)
		(width 0.12954)
		(layer "F.Cu")
		(net "CLK_100M_CPU0_CLK13_R_DP")
	)
	(segment
		(start 346.079318 -295.998646)
		(end 346.387928 -295.690036)
		(width 0.12954)
		(layer "F.Cu")
		(net "CLK_100M_CPU0_CLK13_R_DP")
	)
	(segment
		(start 339.085428 -308.8386)
		(end 339.085428 -306.281836)
		(width 0.12954)
		(layer "F.Cu")
		(net "CLK_100M_CPU0_CLK13_R_DP")
	)
	(segment
		(start 344.80627 -298.196)
		(end 346.079318 -296.922952)
		(width 0.12954)
		(layer "F.Cu")
		(net "CLK_100M_CPU0_CLK13_R_DP")
	)
	(segment
		(start 343.440258 -313.649868)
		(end 338.762848 -308.972458)
		(width 0.12954)
		(layer "F.Cu")
		(net "CLK_100M_CPU0_CLK13_R_DN")
	)
	(segment
		(start 338.762848 -306.346098)
		(end 338.262468 -305.135788)
		(width 0.12954)
		(layer "F.Cu")
		(net "CLK_100M_CPU0_CLK13_R_DN")
	)
	(segment
		(start 345.756738 -295.9989)
		(end 345.447874 -295.690036)
		(width 0.12954)
		(layer "F.Cu")
		(net "CLK_100M_CPU0_CLK13_R_DN")
	)
	(segment
		(start 360.381804 -318.661034)
		(end 355.370638 -313.649868)
		(width 0.12954)
		(layer "F.Cu")
		(net "CLK_100M_CPU0_CLK13_R_DN")
	)
	(segment
		(start 355.370638 -313.649868)
		(end 343.440258 -313.649868)
		(width 0.12954)
		(layer "F.Cu")
		(net "CLK_100M_CPU0_CLK13_R_DN")
	)
	(segment
		(start 344.672412 -297.87342)
		(end 345.756738 -296.789094)
		(width 0.12954)
		(layer "F.Cu")
		(net "CLK_100M_CPU0_CLK13_R_DN")
	)
	(segment
		(start 338.762848 -308.972458)
		(end 338.762848 -306.346098)
		(width 0.12954)
		(layer "F.Cu")
		(net "CLK_100M_CPU0_CLK13_R_DN")
	)
	(segment
		(start 339.346794 -297.87342)
		(end 344.672412 -297.87342)
		(width 0.12954)
		(layer "F.Cu")
		(net "CLK_100M_CPU0_CLK13_R_DN")
	)
	(segment
		(start 345.756738 -296.789094)
		(end 345.756738 -295.9989)
		(width 0.12954)
		(layer "F.Cu")
		(net "CLK_100M_CPU0_CLK13_R_DN")
	)
	(segment
		(start 360.098594 -319.732914)
		(end 360.381804 -319.449704)
		(width 0.12954)
		(layer "F.Cu")
		(net "CLK_100M_CPU0_CLK13_R_DN")
	)
	(segment
		(start 338.262468 -305.135788)
		(end 338.262468 -298.957746)
		(width 0.12954)
		(layer "F.Cu")
		(net "CLK_100M_CPU0_CLK13_R_DN")
	)
	(segment
		(start 360.381804 -319.449704)
		(end 360.381804 -318.661034)
		(width 0.12954)
		(layer "F.Cu")
		(net "CLK_100M_CPU0_CLK13_R_DN")
	)
	(segment
		(start 338.262468 -298.957746)
		(end 339.346794 -297.87342)
		(width 0.12954)
		(layer "F.Cu")
		(net "CLK_100M_CPU0_CLK13_R_DN")
	)
	(segment
		(start 297.30319 -372.465092)
		(end 295.131744 -374.636538)
		(width 0.12954)
		(layer "F.Cu")
		(net "CLK_100M_CPU0_CLK13_DP")
	)
	(segment
		(start 295.131744 -374.636538)
		(end 292.613842 -374.636538)
		(width 0.12954)
		(layer "F.Cu")
		(net "CLK_100M_CPU0_CLK13_DP")
	)
	(segment
		(start 281.686508 -418.984176)
		(end 283.172662 -418.984176)
		(width 0.12954)
		(layer "F.Cu")
		(net "CLK_100M_CPU0_CLK13_DP")
	)
	(segment
		(start 281.519122 -418.81679)
		(end 281.686508 -418.984176)
		(width 0.12954)
		(layer "F.Cu")
		(net "CLK_100M_CPU0_CLK13_DP")
	)
	(segment
		(start 277.368254 -418.81679)
		(end 281.519122 -418.81679)
		(width 0.12954)
		(layer "F.Cu")
		(net "CLK_100M_CPU0_CLK13_DP")
	)
	(segment
		(start 365.689642 -327.448418)
		(end 365.689642 -353.482148)
		(width 0.12954)
		(layer "F.Cu")
		(net "CLK_100M_CPU0_CLK13_DP")
	)
	(segment
		(start 299.399198 -372.465092)
		(end 297.30319 -372.465092)
		(width 0.12954)
		(layer "F.Cu")
		(net "CLK_100M_CPU0_CLK13_DP")
	)
	(segment
		(start 277.103332 -419.081712)
		(end 277.368254 -418.81679)
		(width 0.12954)
		(layer "F.Cu")
		(net "CLK_100M_CPU0_CLK13_DP")
	)
	(segment
		(start 360.704384 -320.816224)
		(end 360.704384 -322.46316)
		(width 0.12954)
		(layer "F.Cu")
		(net "CLK_100M_CPU0_CLK13_DP")
	)
	(segment
		(start 365.689642 -353.482148)
		(end 346.706698 -372.465092)
		(width 0.12954)
		(layer "F.Cu")
		(net "CLK_100M_CPU0_CLK13_DP")
	)
	(segment
		(start 346.706698 -372.465092)
		(end 299.399198 -372.465092)
		(width 0.12954)
		(layer "F.Cu")
		(net "CLK_100M_CPU0_CLK13_DP")
	)
	(segment
		(start 292.613842 -374.636538)
		(end 291.663628 -373.686324)
		(width 0.12954)
		(layer "F.Cu")
		(net "CLK_100M_CPU0_CLK13_DP")
	)
	(segment
		(start 283.172662 -418.984176)
		(end 283.261562 -419.073076)
		(width 0.12954)
		(layer "F.Cu")
		(net "CLK_100M_CPU0_CLK13_DP")
	)
	(segment
		(start 291.663628 -373.686324)
		(end 283.505402 -373.686324)
		(width 0.12954)
		(layer "F.Cu")
		(net "CLK_100M_CPU0_CLK13_DP")
	)
	(segment
		(start 360.987594 -320.533014)
		(end 360.704384 -320.816224)
		(width 0.12954)
		(layer "F.Cu")
		(net "CLK_100M_CPU0_CLK13_DP")
	)
	(segment
		(start 360.704384 -322.46316)
		(end 365.689642 -327.448418)
		(width 0.12954)
		(layer "F.Cu")
		(net "CLK_100M_CPU0_CLK13_DP")
	)
	(segment
		(start 283.505402 -373.686324)
		(end 283.234892 -373.956834)
		(width 0.12954)
		(layer "F.Cu")
		(net "CLK_100M_CPU0_CLK13_DP")
	)
	(segment
		(start 283.261562 -419.073076)
		(end 283.506164 -419.073076)
		(width 0.12954)
		(layer "F.Cu")
		(net "CLK_100M_CPU0_CLK13_DP")
	)
	(via
		(at 283.234892 -373.956834)
		(size 0.508)
		(drill 0.254)
		(layers "F.Cu" "B.Cu")
		(net "CLK_100M_CPU0_CLK13_DP")
	)
	(via
		(at 277.103332 -419.081712)
		(size 0.508)
		(drill 0.254)
		(layers "F.Cu" "B.Cu")
		(net "CLK_100M_CPU0_CLK13_DP")
	)
	(via
		(at 299.399198 -372.465092)
		(size 0.4064)
		(drill 0.2032)
		(layers "F.Cu" "B.Cu")
		(net "CLK_100M_CPU0_CLK13_DP")
	)
	(segment
		(start 282.33624 -412.932626)
		(end 281.010614 -414.258252)
		(width 0.14224)
		(layer "In4.Cu")
		(net "CLK_100M_CPU0_CLK13_DP")
	)
	(segment
		(start 277.394162 -418.790882)
		(end 277.103332 -419.081712)
		(width 0.14224)
		(layer "In4.Cu")
		(net "CLK_100M_CPU0_CLK13_DP")
	)
	(segment
		(start 281.010614 -414.258252)
		(end 281.010614 -417.077144)
		(width 0.14224)
		(layer "In4.Cu")
		(net "CLK_100M_CPU0_CLK13_DP")
	)
	(segment
		(start 282.255468 -397.380968)
		(end 282.255468 -408.688032)
		(width 0.14224)
		(layer "In4.Cu")
		(net "CLK_100M_CPU0_CLK13_DP")
	)
	(segment
		(start 282.944824 -411.128464)
		(end 282.33624 -411.737048)
		(width 0.14224)
		(layer "In4.Cu")
		(net "CLK_100M_CPU0_CLK13_DP")
	)
	(segment
		(start 283.538422 -396.098014)
		(end 282.255468 -397.380968)
		(width 0.14224)
		(layer "In4.Cu")
		(net "CLK_100M_CPU0_CLK13_DP")
	)
	(segment
		(start 282.29941 -373.666004)
		(end 281.75331 -374.212104)
		(width 0.14224)
		(layer "In4.Cu")
		(net "CLK_100M_CPU0_CLK13_DP")
	)
	(segment
		(start 282.104846 -389.882634)
		(end 284.028134 -391.805922)
		(width 0.14224)
		(layer "In4.Cu")
		(net "CLK_100M_CPU0_CLK13_DP")
	)
	(segment
		(start 282.944062 -373.666004)
		(end 282.29941 -373.666004)
		(width 0.14224)
		(layer "In4.Cu")
		(net "CLK_100M_CPU0_CLK13_DP")
	)
	(segment
		(start 281.75331 -374.212104)
		(end 281.75331 -386.522214)
		(width 0.14224)
		(layer "In4.Cu")
		(net "CLK_100M_CPU0_CLK13_DP")
	)
	(segment
		(start 281.010614 -417.077144)
		(end 279.296876 -418.790882)
		(width 0.14224)
		(layer "In4.Cu")
		(net "CLK_100M_CPU0_CLK13_DP")
	)
	(segment
		(start 284.028134 -393.155932)
		(end 283.538422 -393.645644)
		(width 0.14224)
		(layer "In4.Cu")
		(net "CLK_100M_CPU0_CLK13_DP")
	)
	(segment
		(start 282.255468 -408.688032)
		(end 282.944824 -409.377388)
		(width 0.14224)
		(layer "In4.Cu")
		(net "CLK_100M_CPU0_CLK13_DP")
	)
	(segment
		(start 283.538422 -393.645644)
		(end 283.538422 -396.098014)
		(width 0.14224)
		(layer "In4.Cu")
		(net "CLK_100M_CPU0_CLK13_DP")
	)
	(segment
		(start 284.028134 -391.805922)
		(end 284.028134 -393.155932)
		(width 0.14224)
		(layer "In4.Cu")
		(net "CLK_100M_CPU0_CLK13_DP")
	)
	(segment
		(start 282.33624 -411.737048)
		(end 282.33624 -412.932626)
		(width 0.14224)
		(layer "In4.Cu")
		(net "CLK_100M_CPU0_CLK13_DP")
	)
	(segment
		(start 281.75331 -386.522214)
		(end 282.104846 -386.87375)
		(width 0.14224)
		(layer "In4.Cu")
		(net "CLK_100M_CPU0_CLK13_DP")
	)
	(segment
		(start 283.234892 -373.956834)
		(end 282.944062 -373.666004)
		(width 0.14224)
		(layer "In4.Cu")
		(net "CLK_100M_CPU0_CLK13_DP")
	)
	(segment
		(start 282.944824 -409.377388)
		(end 282.944824 -411.128464)
		(width 0.14224)
		(layer "In4.Cu")
		(net "CLK_100M_CPU0_CLK13_DP")
	)
	(segment
		(start 282.104846 -386.87375)
		(end 282.104846 -389.882634)
		(width 0.14224)
		(layer "In4.Cu")
		(net "CLK_100M_CPU0_CLK13_DP")
	)
	(segment
		(start 279.296876 -418.790882)
		(end 277.394162 -418.790882)
		(width 0.14224)
		(layer "In4.Cu")
		(net "CLK_100M_CPU0_CLK13_DP")
	)
	(segment
		(start 365.367062 -327.582276)
		(end 365.367062 -353.34829)
		(width 0.12954)
		(layer "F.Cu")
		(net "CLK_100M_CPU0_CLK13_DN")
	)
	(segment
		(start 360.098594 -320.533014)
		(end 360.381804 -320.816224)
		(width 0.12954)
		(layer "F.Cu")
		(net "CLK_100M_CPU0_CLK13_DN")
	)
	(segment
		(start 345.435174 -371.952012)
		(end 345.244674 -372.142512)
		(width 0.12954)
		(layer "F.Cu")
		(net "CLK_100M_CPU0_CLK13_DN")
	)
	(segment
		(start 346.57284 -372.142512)
		(end 346.014294 -372.142512)
		(width 0.12954)
		(layer "F.Cu")
		(net "CLK_100M_CPU0_CLK13_DN")
	)
	(segment
		(start 346.014294 -372.142512)
		(end 345.823794 -371.952012)
		(width 0.12954)
		(layer "F.Cu")
		(net "CLK_100M_CPU0_CLK13_DN")
	)
	(segment
		(start 360.381804 -322.597018)
		(end 365.367062 -327.582276)
		(width 0.12954)
		(layer "F.Cu")
		(net "CLK_100M_CPU0_CLK13_DN")
	)
	(segment
		(start 345.244674 -372.142512)
		(end 344.856054 -372.142512)
		(width 0.12954)
		(layer "F.Cu")
		(net "CLK_100M_CPU0_CLK13_DN")
	)
	(segment
		(start 283.505402 -373.363744)
		(end 283.234892 -373.093234)
		(width 0.12954)
		(layer "F.Cu")
		(net "CLK_100M_CPU0_CLK13_DN")
	)
	(segment
		(start 294.997886 -374.313958)
		(end 292.7477 -374.313958)
		(width 0.12954)
		(layer "F.Cu")
		(net "CLK_100M_CPU0_CLK13_DN")
	)
	(segment
		(start 342.928194 -372.142512)
		(end 302.067468 -372.142512)
		(width 0.12954)
		(layer "F.Cu")
		(net "CLK_100M_CPU0_CLK13_DN")
	)
	(segment
		(start 343.507314 -371.952012)
		(end 343.118694 -371.952012)
		(width 0.12954)
		(layer "F.Cu")
		(net "CLK_100M_CPU0_CLK13_DN")
	)
	(segment
		(start 343.697814 -372.142512)
		(end 343.507314 -371.952012)
		(width 0.12954)
		(layer "F.Cu")
		(net "CLK_100M_CPU0_CLK13_DN")
	)
	(segment
		(start 344.276934 -371.952012)
		(end 344.086434 -372.142512)
		(width 0.12954)
		(layer "F.Cu")
		(net "CLK_100M_CPU0_CLK13_DN")
	)
	(segment
		(start 292.7477 -374.313958)
		(end 291.797486 -373.363744)
		(width 0.12954)
		(layer "F.Cu")
		(net "CLK_100M_CPU0_CLK13_DN")
	)
	(segment
		(start 344.665554 -371.952012)
		(end 344.276934 -371.952012)
		(width 0.12954)
		(layer "F.Cu")
		(net "CLK_100M_CPU0_CLK13_DN")
	)
	(segment
		(start 344.856054 -372.142512)
		(end 344.665554 -371.952012)
		(width 0.12954)
		(layer "F.Cu")
		(net "CLK_100M_CPU0_CLK13_DN")
	)
	(segment
		(start 344.086434 -372.142512)
		(end 343.697814 -372.142512)
		(width 0.12954)
		(layer "F.Cu")
		(net "CLK_100M_CPU0_CLK13_DN")
	)
	(segment
		(start 281.820366 -418.661596)
		(end 283.174694 -418.661596)
		(width 0.12954)
		(layer "F.Cu")
		(net "CLK_100M_CPU0_CLK13_DN")
	)
	(segment
		(start 360.381804 -320.816224)
		(end 360.381804 -322.597018)
		(width 0.12954)
		(layer "F.Cu")
		(net "CLK_100M_CPU0_CLK13_DN")
	)
	(segment
		(start 281.65298 -418.49421)
		(end 281.820366 -418.661596)
		(width 0.12954)
		(layer "F.Cu")
		(net "CLK_100M_CPU0_CLK13_DN")
	)
	(segment
		(start 277.37943 -418.49421)
		(end 281.65298 -418.49421)
		(width 0.12954)
		(layer "F.Cu")
		(net "CLK_100M_CPU0_CLK13_DN")
	)
	(segment
		(start 283.174694 -418.661596)
		(end 283.26334 -418.57295)
		(width 0.12954)
		(layer "F.Cu")
		(net "CLK_100M_CPU0_CLK13_DN")
	)
	(segment
		(start 345.823794 -371.952012)
		(end 345.435174 -371.952012)
		(width 0.12954)
		(layer "F.Cu")
		(net "CLK_100M_CPU0_CLK13_DN")
	)
	(segment
		(start 343.118694 -371.952012)
		(end 342.928194 -372.142512)
		(width 0.12954)
		(layer "F.Cu")
		(net "CLK_100M_CPU0_CLK13_DN")
	)
	(segment
		(start 291.797486 -373.363744)
		(end 283.505402 -373.363744)
		(width 0.12954)
		(layer "F.Cu")
		(net "CLK_100M_CPU0_CLK13_DN")
	)
	(segment
		(start 297.169332 -372.142512)
		(end 294.997886 -374.313958)
		(width 0.12954)
		(layer "F.Cu")
		(net "CLK_100M_CPU0_CLK13_DN")
	)
	(segment
		(start 283.26334 -418.57295)
		(end 283.506164 -418.57295)
		(width 0.12954)
		(layer "F.Cu")
		(net "CLK_100M_CPU0_CLK13_DN")
	)
	(segment
		(start 277.103332 -418.218112)
		(end 277.37943 -418.49421)
		(width 0.12954)
		(layer "F.Cu")
		(net "CLK_100M_CPU0_CLK13_DN")
	)
	(segment
		(start 365.367062 -353.34829)
		(end 346.57284 -372.142512)
		(width 0.12954)
		(layer "F.Cu")
		(net "CLK_100M_CPU0_CLK13_DN")
	)
	(segment
		(start 302.067468 -372.142512)
		(end 297.169332 -372.142512)
		(width 0.12954)
		(layer "F.Cu")
		(net "CLK_100M_CPU0_CLK13_DN")
	)
	(via
		(at 277.103332 -418.218112)
		(size 0.508)
		(drill 0.254)
		(layers "F.Cu" "B.Cu")
		(net "CLK_100M_CPU0_CLK13_DN")
	)
	(via
		(at 302.067468 -372.142512)
		(size 0.4064)
		(drill 0.2032)
		(layers "F.Cu" "B.Cu")
		(net "CLK_100M_CPU0_CLK13_DN")
	)
	(via
		(at 283.234892 -373.093234)
		(size 0.508)
		(drill 0.254)
		(layers "F.Cu" "B.Cu")
		(net "CLK_100M_CPU0_CLK13_DN")
	)
	(segment
		(start 283.256482 -393.528804)
		(end 283.256482 -395.981174)
		(width 0.14224)
		(layer "In4.Cu")
		(net "CLK_100M_CPU0_CLK13_DN")
	)
	(segment
		(start 283.746194 -391.922762)
		(end 283.746194 -393.039092)
		(width 0.14224)
		(layer "In4.Cu")
		(net "CLK_100M_CPU0_CLK13_DN")
	)
	(segment
		(start 282.662884 -409.494228)
		(end 282.662884 -411.011624)
		(width 0.14224)
		(layer "In4.Cu")
		(net "CLK_100M_CPU0_CLK13_DN")
	)
	(segment
		(start 282.18257 -373.384064)
		(end 281.47137 -374.095264)
		(width 0.14224)
		(layer "In4.Cu")
		(net "CLK_100M_CPU0_CLK13_DN")
	)
	(segment
		(start 282.0543 -412.815786)
		(end 280.728674 -414.141412)
		(width 0.14224)
		(layer "In4.Cu")
		(net "CLK_100M_CPU0_CLK13_DN")
	)
	(segment
		(start 281.47137 -386.639054)
		(end 281.822906 -386.99059)
		(width 0.14224)
		(layer "In4.Cu")
		(net "CLK_100M_CPU0_CLK13_DN")
	)
	(segment
		(start 277.394162 -418.508942)
		(end 277.103332 -418.218112)
		(width 0.14224)
		(layer "In4.Cu")
		(net "CLK_100M_CPU0_CLK13_DN")
	)
	(segment
		(start 280.728674 -414.141412)
		(end 280.728674 -416.960304)
		(width 0.14224)
		(layer "In4.Cu")
		(net "CLK_100M_CPU0_CLK13_DN")
	)
	(segment
		(start 281.822906 -389.999474)
		(end 283.746194 -391.922762)
		(width 0.14224)
		(layer "In4.Cu")
		(net "CLK_100M_CPU0_CLK13_DN")
	)
	(segment
		(start 282.662884 -411.011624)
		(end 282.0543 -411.620208)
		(width 0.14224)
		(layer "In4.Cu")
		(net "CLK_100M_CPU0_CLK13_DN")
	)
	(segment
		(start 279.180036 -418.508942)
		(end 277.394162 -418.508942)
		(width 0.14224)
		(layer "In4.Cu")
		(net "CLK_100M_CPU0_CLK13_DN")
	)
	(segment
		(start 281.47137 -374.095264)
		(end 281.47137 -386.639054)
		(width 0.14224)
		(layer "In4.Cu")
		(net "CLK_100M_CPU0_CLK13_DN")
	)
	(segment
		(start 281.822906 -386.99059)
		(end 281.822906 -389.999474)
		(width 0.14224)
		(layer "In4.Cu")
		(net "CLK_100M_CPU0_CLK13_DN")
	)
	(segment
		(start 282.944062 -373.384064)
		(end 282.18257 -373.384064)
		(width 0.14224)
		(layer "In4.Cu")
		(net "CLK_100M_CPU0_CLK13_DN")
	)
	(segment
		(start 283.234892 -373.093234)
		(end 282.944062 -373.384064)
		(width 0.14224)
		(layer "In4.Cu")
		(net "CLK_100M_CPU0_CLK13_DN")
	)
	(segment
		(start 282.0543 -411.620208)
		(end 282.0543 -412.815786)
		(width 0.14224)
		(layer "In4.Cu")
		(net "CLK_100M_CPU0_CLK13_DN")
	)
	(segment
		(start 281.973528 -408.804872)
		(end 282.662884 -409.494228)
		(width 0.14224)
		(layer "In4.Cu")
		(net "CLK_100M_CPU0_CLK13_DN")
	)
	(segment
		(start 280.728674 -416.960304)
		(end 279.180036 -418.508942)
		(width 0.14224)
		(layer "In4.Cu")
		(net "CLK_100M_CPU0_CLK13_DN")
	)
	(segment
		(start 283.746194 -393.039092)
		(end 283.256482 -393.528804)
		(width 0.14224)
		(layer "In4.Cu")
		(net "CLK_100M_CPU0_CLK13_DN")
	)
	(segment
		(start 281.973528 -397.264128)
		(end 281.973528 -408.804872)
		(width 0.14224)
		(layer "In4.Cu")
		(net "CLK_100M_CPU0_CLK13_DN")
	)
	(segment
		(start 283.256482 -395.981174)
		(end 281.973528 -397.264128)
		(width 0.14224)
		(layer "In4.Cu")
		(net "CLK_100M_CPU0_CLK13_DN")
	)
	(segment
		(start 241.53495 -290.061904)
		(end 241.971322 -290.061904)
		(width 0.1524)
		(layer "F.Cu")
		(net "PWRGD_P1V8_RETIMER_CPU0")
	)
	(segment
		(start 241.174778 -289.701732)
		(end 241.53495 -290.061904)
		(width 0.1524)
		(layer "F.Cu")
		(net "PWRGD_P1V8_RETIMER_CPU0")
	)
	(via
		(at 239.631474 -289.7378)
		(size 0.6604)
		(drill 0.3302)
		(layers "F.Cu" "B.Cu")
		(net "PWRGD_P1V8_RETIMER_CPU0")
	)
	(via
		(at 241.174778 -289.701732)
		(size 0.508)
		(drill 0.254)
		(layers "F.Cu" "B.Cu")
		(net "PWRGD_P1V8_RETIMER_CPU0")
	)
	(segment
		(start 239.132872 -290.422838)
		(end 239.132872 -290.236402)
		(width 0.1524)
		(layer "B.Cu")
		(net "PWRGD_P1V8_RETIMER_CPU0")
	)
	(segment
		(start 239.902492 -289.466782)
		(end 240.469928 -289.466782)
		(width 0.1524)
		(layer "B.Cu")
		(net "PWRGD_P1V8_RETIMER_CPU0")
	)
	(segment
		(start 239.631474 -289.7378)
		(end 239.902492 -289.466782)
		(width 0.1524)
		(layer "B.Cu")
		(net "PWRGD_P1V8_RETIMER_CPU0")
	)
	(segment
		(start 239.132872 -290.236402)
		(end 239.631474 -289.7378)
		(width 0.1524)
		(layer "B.Cu")
		(net "PWRGD_P1V8_RETIMER_CPU0")
	)
	(segment
		(start 240.469928 -289.466782)
		(end 240.704878 -289.701732)
		(width 0.1524)
		(layer "B.Cu")
		(net "PWRGD_P1V8_RETIMER_CPU0")
	)
	(segment
		(start 238.710978 -290.844732)
		(end 239.132872 -290.422838)
		(width 0.1524)
		(layer "B.Cu")
		(net "PWRGD_P1V8_RETIMER_CPU0")
	)
	(segment
		(start 240.704878 -289.701732)
		(end 241.174778 -289.701732)
		(width 0.1524)
		(layer "B.Cu")
		(net "PWRGD_P1V8_RETIMER_CPU0")
	)
	(segment
		(start 245.570248 -293.5351)
		(end 246.245888 -293.5351)
		(width 0.254)
		(layer "F.Cu")
		(net "P1V8_RETIMER_CPU0_VCC")
	)
	(segment
		(start 245.568216 -293.537132)
		(end 245.570248 -293.5351)
		(width 0.254)
		(layer "F.Cu")
		(net "P1V8_RETIMER_CPU0_VCC")
	)
	(segment
		(start 245.493032 -293.461948)
		(end 245.568216 -293.537132)
		(width 0.254)
		(layer "F.Cu")
		(net "P1V8_RETIMER_CPU0_VCC")
	)
	(segment
		(start 244.771418 -293.461948)
		(end 245.493032 -293.461948)
		(width 0.254)
		(layer "F.Cu")
		(net "P1V8_RETIMER_CPU0_VCC")
	)
	(via
		(at 242.762532 -290.758372)
		(size 0.6604)
		(drill 0.3302)
		(layers "F.Cu" "B.Cu")
		(net "P1V8_RETIMER_CPU0_VCC")
	)
	(via
		(at 245.568216 -293.537132)
		(size 0.508)
		(drill 0.254)
		(layers "F.Cu" "B.Cu")
		(net "P1V8_RETIMER_CPU0_VCC")
	)
	(segment
		(start 242.762532 -290.758372)
		(end 241.938048 -289.933888)
		(width 0.254)
		(layer "B.Cu")
		(net "P1V8_RETIMER_CPU0_VCC")
	)
	(segment
		(start 243.106448 -291.102288)
		(end 242.762532 -290.758372)
		(width 0.254)
		(layer "B.Cu")
		(net "P1V8_RETIMER_CPU0_VCC")
	)
	(segment
		(start 244.330728 -293.537132)
		(end 243.106448 -292.312852)
		(width 0.254)
		(layer "B.Cu")
		(net "P1V8_RETIMER_CPU0_VCC")
	)
	(segment
		(start 243.106448 -292.312852)
		(end 243.106448 -291.102288)
		(width 0.254)
		(layer "B.Cu")
		(net "P1V8_RETIMER_CPU0_VCC")
	)
	(segment
		(start 245.568216 -293.537132)
		(end 244.330728 -293.537132)
		(width 0.254)
		(layer "B.Cu")
		(net "P1V8_RETIMER_CPU0_VCC")
	)
	(segment
		(start 240.343944 -291.863526)
		(end 240.445544 -291.761926)
		(width 0.1778)
		(layer "F.Cu")
		(net "P1V8_RETIMER_CPU0_REF")
	)
	(segment
		(start 239.93602 -291.863526)
		(end 240.343944 -291.863526)
		(width 0.1778)
		(layer "F.Cu")
		(net "P1V8_RETIMER_CPU0_REF")
	)
	(segment
		(start 240.445544 -291.761926)
		(end 241.971322 -291.761926)
		(width 0.1778)
		(layer "F.Cu")
		(net "P1V8_RETIMER_CPU0_REF")
	)
	(segment
		(start 240.61547 -292.295326)
		(end 240.74882 -292.161976)
		(width 0.2032)
		(layer "F.Cu")
		(net "P1V8_RETIMER_CPU0_MODE")
	)
	(segment
		(start 240.74882 -292.161976)
		(end 241.971322 -292.161976)
		(width 0.1778)
		(layer "F.Cu")
		(net "P1V8_RETIMER_CPU0_MODE")
	)
	(via
		(at 240.61547 -292.295326)
		(size 0.508)
		(drill 0.254)
		(layers "F.Cu" "B.Cu")
		(net "P1V8_RETIMER_CPU0_MODE")
	)
	(segment
		(start 239.927892 -291.607748)
		(end 240.61547 -292.295326)
		(width 0.10668)
		(layer "B.Cu")
		(net "P1V8_RETIMER_CPU0_MODE")
	)
	(segment
		(start 239.927892 -290.564062)
		(end 239.927892 -291.607748)
		(width 0.10668)
		(layer "B.Cu")
		(net "P1V8_RETIMER_CPU0_MODE")
	)
	(segment
		(start 239.893348 -289.941762)
		(end 238.859822 -289.941762)
		(width 0.254)
		(layer "F.Cu")
		(net "P1V8_RETIMER_CPU0_FB")
	)
	(segment
		(start 240.60531 -290.43884)
		(end 240.24082 -290.181792)
		(width 0.254)
		(layer "F.Cu")
		(net "P1V8_RETIMER_CPU0_FB")
	)
	(segment
		(start 241.424968 -290.961826)
		(end 241.971322 -290.961826)
		(width 0.1778)
		(layer "F.Cu")
		(net "P1V8_RETIMER_CPU0_FB")
	)
	(segment
		(start 240.24082 -290.181792)
		(end 239.893348 -289.941762)
		(width 0.254)
		(layer "F.Cu")
		(net "P1V8_RETIMER_CPU0_FB")
	)
	(segment
		(start 238.859822 -289.941762)
		(end 237.843822 -289.941762)
		(width 0.254)
		(layer "F.Cu")
		(net "P1V8_RETIMER_CPU0_FB")
	)
	(segment
		(start 240.60531 -290.43884)
		(end 240.974372 -290.688522)
		(width 0.254)
		(layer "F.Cu")
		(net "P1V8_RETIMER_CPU0_FB")
	)
	(segment
		(start 240.974372 -290.688522)
		(end 241.424968 -290.961826)
		(width 0.1778)
		(layer "F.Cu")
		(net "P1V8_RETIMER_CPU0_FB")
	)
	(via
		(at 240.60531 -290.43884)
		(size 0.4064)
		(drill 0.2032)
		(layers "F.Cu" "B.Cu")
		(net "P1V8_RETIMER_CPU0_FB")
	)
	(segment
		(start 177.484024 -183.533796)
		(end 177.484024 -171.802552)
		(width 0.1524)
		(layer "F.Cu")
		(net "P1V8_RETIMER_CPU0_EN")
	)
	(segment
		(start 239.832642 -289.051492)
		(end 239.832642 -289.012122)
		(width 0.10668)
		(layer "F.Cu")
		(net "P1V8_RETIMER_CPU0_EN")
	)
	(segment
		(start 239.832642 -289.012122)
		(end 241.38255 -290.56203)
		(width 0.10668)
		(layer "F.Cu")
		(net "P1V8_RETIMER_CPU0_EN")
	)
	(segment
		(start 238.035592 -288.123122)
		(end 237.819692 -288.339022)
		(width 0.10668)
		(layer "F.Cu")
		(net "P1V8_RETIMER_CPU0_EN")
	)
	(segment
		(start 238.109252 -289.471862)
		(end 239.412272 -289.471862)
		(width 0.10668)
		(layer "F.Cu")
		(net "P1V8_RETIMER_CPU0_EN")
	)
	(segment
		(start 178.967892 -185.017664)
		(end 177.484024 -183.533796)
		(width 0.1524)
		(layer "F.Cu")
		(net "P1V8_RETIMER_CPU0_EN")
	)
	(segment
		(start 239.412272 -289.471862)
		(end 239.832642 -289.051492)
		(width 0.10668)
		(layer "F.Cu")
		(net "P1V8_RETIMER_CPU0_EN")
	)
	(segment
		(start 237.819692 -289.182302)
		(end 238.109252 -289.471862)
		(width 0.10668)
		(layer "F.Cu")
		(net "P1V8_RETIMER_CPU0_EN")
	)
	(segment
		(start 171.376594 -128.24333)
		(end 170.865546 -128.754378)
		(width 0.1524)
		(layer "F.Cu")
		(net "P1V8_RETIMER_CPU0_EN")
	)
	(segment
		(start 241.38255 -290.56203)
		(end 241.971322 -290.56203)
		(width 0.10668)
		(layer "F.Cu")
		(net "P1V8_RETIMER_CPU0_EN")
	)
	(segment
		(start 178.967892 -186.001152)
		(end 178.967892 -185.017664)
		(width 0.1524)
		(layer "F.Cu")
		(net "P1V8_RETIMER_CPU0_EN")
	)
	(segment
		(start 237.819692 -288.339022)
		(end 237.819692 -289.182302)
		(width 0.10668)
		(layer "F.Cu")
		(net "P1V8_RETIMER_CPU0_EN")
	)
	(via
		(at 177.484024 -171.802552)
		(size 0.508)
		(drill 0.254)
		(layers "F.Cu" "B.Cu")
		(net "P1V8_RETIMER_CPU0_EN")
	)
	(via
		(at 170.865546 -128.754378)
		(size 0.508)
		(drill 0.254)
		(layers "F.Cu" "B.Cu")
		(net "P1V8_RETIMER_CPU0_EN")
	)
	(via
		(at 238.035592 -288.123122)
		(size 0.508)
		(drill 0.254)
		(layers "F.Cu" "B.Cu")
		(net "P1V8_RETIMER_CPU0_EN")
	)
	(via
		(at 178.967892 -186.001152)
		(size 0.508)
		(drill 0.254)
		(layers "F.Cu" "B.Cu")
		(net "P1V8_RETIMER_CPU0_EN")
	)
	(segment
		(start 238.035592 -288.123122)
		(end 237.62843 -287.71596)
		(width 0.1524)
		(layer "B.Cu")
		(net "P1V8_RETIMER_CPU0_EN")
	)
	(segment
		(start 201.670666 -185.512964)
		(end 200.871836 -186.311794)
		(width 0.1524)
		(layer "B.Cu")
		(net "P1V8_RETIMER_CPU0_EN")
	)
	(segment
		(start 191.125094 -185.005472)
		(end 187.212986 -185.005472)
		(width 0.1524)
		(layer "B.Cu")
		(net "P1V8_RETIMER_CPU0_EN")
	)
	(segment
		(start 213.644734 -191.733932)
		(end 207.423766 -185.512964)
		(width 0.1524)
		(layer "B.Cu")
		(net "P1V8_RETIMER_CPU0_EN")
	)
	(segment
		(start 187.212986 -185.005472)
		(end 185.892948 -186.32551)
		(width 0.1524)
		(layer "B.Cu")
		(net "P1V8_RETIMER_CPU0_EN")
	)
	(segment
		(start 192.621408 -187.43422)
		(end 192.621408 -186.501786)
		(width 0.1524)
		(layer "B.Cu")
		(net "P1V8_RETIMER_CPU0_EN")
	)
	(segment
		(start 193.224658 -188.03747)
		(end 192.621408 -187.43422)
		(width 0.1524)
		(layer "B.Cu")
		(net "P1V8_RETIMER_CPU0_EN")
	)
	(segment
		(start 185.094118 -187.89777)
		(end 180.185822 -187.89777)
		(width 0.1524)
		(layer "B.Cu")
		(net "P1V8_RETIMER_CPU0_EN")
	)
	(segment
		(start 185.892948 -186.32551)
		(end 185.892948 -187.09894)
		(width 0.1524)
		(layer "B.Cu")
		(net "P1V8_RETIMER_CPU0_EN")
	)
	(segment
		(start 230.547418 -264.577576)
		(end 213.644734 -247.674892)
		(width 0.1524)
		(layer "B.Cu")
		(net "P1V8_RETIMER_CPU0_EN")
	)
	(segment
		(start 237.62843 -287.71596)
		(end 237.62843 -282.657042)
		(width 0.1524)
		(layer "B.Cu")
		(net "P1V8_RETIMER_CPU0_EN")
	)
	(segment
		(start 200.871836 -186.311794)
		(end 200.871836 -187.35167)
		(width 0.1524)
		(layer "B.Cu")
		(net "P1V8_RETIMER_CPU0_EN")
	)
	(segment
		(start 180.185822 -187.89777)
		(end 178.967892 -186.67984)
		(width 0.1524)
		(layer "B.Cu")
		(net "P1V8_RETIMER_CPU0_EN")
	)
	(segment
		(start 213.644734 -247.674892)
		(end 213.644734 -191.733932)
		(width 0.1524)
		(layer "B.Cu")
		(net "P1V8_RETIMER_CPU0_EN")
	)
	(segment
		(start 178.967892 -186.67984)
		(end 178.967892 -186.001152)
		(width 0.1524)
		(layer "B.Cu")
		(net "P1V8_RETIMER_CPU0_EN")
	)
	(segment
		(start 237.62843 -282.657042)
		(end 230.547418 -275.57603)
		(width 0.1524)
		(layer "B.Cu")
		(net "P1V8_RETIMER_CPU0_EN")
	)
	(segment
		(start 230.547418 -275.57603)
		(end 230.547418 -264.577576)
		(width 0.1524)
		(layer "B.Cu")
		(net "P1V8_RETIMER_CPU0_EN")
	)
	(segment
		(start 200.186036 -188.03747)
		(end 193.224658 -188.03747)
		(width 0.1524)
		(layer "B.Cu")
		(net "P1V8_RETIMER_CPU0_EN")
	)
	(segment
		(start 207.423766 -185.512964)
		(end 201.670666 -185.512964)
		(width 0.1524)
		(layer "B.Cu")
		(net "P1V8_RETIMER_CPU0_EN")
	)
	(segment
		(start 185.892948 -187.09894)
		(end 185.094118 -187.89777)
		(width 0.1524)
		(layer "B.Cu")
		(net "P1V8_RETIMER_CPU0_EN")
	)
	(segment
		(start 192.621408 -186.501786)
		(end 191.125094 -185.005472)
		(width 0.1524)
		(layer "B.Cu")
		(net "P1V8_RETIMER_CPU0_EN")
	)
	(segment
		(start 200.871836 -187.35167)
		(end 200.186036 -188.03747)
		(width 0.1524)
		(layer "B.Cu")
		(net "P1V8_RETIMER_CPU0_EN")
	)
	(segment
		(start 173.832774 -167.11168)
		(end 173.832774 -139.71143)
		(width 0.1524)
		(layer "In11.Cu")
		(net "P1V8_RETIMER_CPU0_EN")
	)
	(segment
		(start 169.970958 -129.648966)
		(end 170.865546 -128.754378)
		(width 0.1524)
		(layer "In11.Cu")
		(net "P1V8_RETIMER_CPU0_EN")
	)
	(segment
		(start 177.484024 -171.802552)
		(end 177.484024 -170.76293)
		(width 0.1524)
		(layer "In11.Cu")
		(net "P1V8_RETIMER_CPU0_EN")
	)
	(segment
		(start 169.970958 -135.849614)
		(end 169.970958 -129.648966)
		(width 0.1524)
		(layer "In11.Cu")
		(net "P1V8_RETIMER_CPU0_EN")
	)
	(segment
		(start 173.832774 -139.71143)
		(end 169.970958 -135.849614)
		(width 0.1524)
		(layer "In11.Cu")
		(net "P1V8_RETIMER_CPU0_EN")
	)
	(segment
		(start 177.484024 -170.76293)
		(end 173.832774 -167.11168)
		(width 0.1524)
		(layer "In11.Cu")
		(net "P1V8_RETIMER_CPU0_EN")
	)
	(segment
		(start 240.538254 -292.988238)
		(end 241.37366 -292.562026)
		(width 0.1778)
		(layer "F.Cu")
		(net "P1V8_RETIMER_CPU0_CS")
	)
	(segment
		(start 239.93602 -292.988238)
		(end 240.538254 -292.988238)
		(width 0.1778)
		(layer "F.Cu")
		(net "P1V8_RETIMER_CPU0_CS")
	)
	(segment
		(start 241.37366 -292.562026)
		(end 241.971322 -292.562026)
		(width 0.1778)
		(layer "F.Cu")
		(net "P1V8_RETIMER_CPU0_CS")
	)
	(segment
		(start 365.283496 -426.604176)
		(end 364.619032 -425.939712)
		(width 0.254)
		(layer "F.Cu")
		(net "P1V8_CPU0_RT_1D")
	)
	(segment
		(start 237.843822 -291.614098)
		(end 237.843822 -290.741862)
		(width 0.508)
		(layer "F.Cu")
		(net "P1V8_CPU0_RT_1D")
	)
	(segment
		(start 295.026588 -391.81405)
		(end 295.026588 -392.32205)
		(width 0.254)
		(layer "F.Cu")
		(net "P1V8_CPU0_RT_1D")
	)
	(segment
		(start 398.336262 -397.726154)
		(end 398.336262 -397.44904)
		(width 0.254)
		(layer "F.Cu")
		(net "P1V8_CPU0_RT_1D")
	)
	(segment
		(start 322.40474 -402.908262)
		(end 322.40474 -402.12518)
		(width 0.254)
		(layer "F.Cu")
		(net "P1V8_CPU0_RT_1D")
	)
	(segment
		(start 359.923842 -399.034)
		(end 359.923842 -398.688052)
		(width 0.254)
		(layer "F.Cu")
		(net "P1V8_CPU0_RT_1D")
	)
	(segment
		(start 289.89274 -398.047718)
		(end 289.72637 -398.214088)
		(width 0.254)
		(layer "F.Cu")
		(net "P1V8_CPU0_RT_1D")
	)
	(segment
		(start 331.23632 -397.726154)
		(end 331.23632 -397.449294)
		(width 0.254)
		(layer "F.Cu")
		(net "P1V8_CPU0_RT_1D")
	)
	(segment
		(start 423.206672 -424.217846)
		(end 423.206672 -423.592752)
		(width 0.254)
		(layer "F.Cu")
		(net "P1V8_CPU0_RT_1D")
	)
	(segment
		(start 365.523018 -429.557688)
		(end 364.719616 -430.36109)
		(width 0.254)
		(layer "F.Cu")
		(net "P1V8_CPU0_RT_1D")
	)
	(segment
		(start 295.072816 -395.390624)
		(end 294.847772 -395.16558)
		(width 0.254)
		(layer "F.Cu")
		(net "P1V8_CPU0_RT_1D")
	)
	(segment
		(start 359.923842 -398.688052)
		(end 360.167174 -398.44472)
		(width 0.254)
		(layer "F.Cu")
		(net "P1V8_CPU0_RT_1D")
	)
	(segment
		(start 331.23632 -397.449294)
		(end 330.94041 -397.153384)
		(width 0.254)
		(layer "F.Cu")
		(net "P1V8_CPU0_RT_1D")
	)
	(segment
		(start 365.523018 -429.075342)
		(end 365.523018 -429.557688)
		(width 0.254)
		(layer "F.Cu")
		(net "P1V8_CPU0_RT_1D")
	)
	(segment
		(start 238.859822 -290.741862)
		(end 237.843822 -290.741862)
		(width 0.508)
		(layer "F.Cu")
		(net "P1V8_CPU0_RT_1D")
	)
	(segment
		(start 295.194736 -391.645902)
		(end 295.026588 -391.81405)
		(width 0.254)
		(layer "F.Cu")
		(net "P1V8_CPU0_RT_1D")
	)
	(segment
		(start 364.822994 -423.520616)
		(end 364.822994 -423.150792)
		(width 0.254)
		(layer "F.Cu")
		(net "P1V8_CPU0_RT_1D")
	)
	(segment
		(start 294.847772 -395.16558)
		(end 294.847772 -394.721842)
		(width 0.254)
		(layer "F.Cu")
		(net "P1V8_CPU0_RT_1D")
	)
	(segment
		(start 289.72637 -398.214088)
		(end 289.72637 -398.591024)
		(width 0.254)
		(layer "F.Cu")
		(net "P1V8_CPU0_RT_1D")
	)
	(segment
		(start 364.619032 -423.724578)
		(end 364.822994 -423.520616)
		(width 0.254)
		(layer "F.Cu")
		(net "P1V8_CPU0_RT_1D")
	)
	(segment
		(start 423.189654 -425.685458)
		(end 423.189654 -424.234864)
		(width 0.254)
		(layer "F.Cu")
		(net "P1V8_CPU0_RT_1D")
	)
	(segment
		(start 322.364862 -402.94814)
		(end 322.40474 -402.908262)
		(width 0.254)
		(layer "F.Cu")
		(net "P1V8_CPU0_RT_1D")
	)
	(segment
		(start 398.336262 -397.44904)
		(end 398.040606 -397.153384)
		(width 0.254)
		(layer "F.Cu")
		(net "P1V8_CPU0_RT_1D")
	)
	(segment
		(start 423.189654 -424.234864)
		(end 423.206672 -424.217846)
		(width 0.254)
		(layer "F.Cu")
		(net "P1V8_CPU0_RT_1D")
	)
	(segment
		(start 364.619032 -425.939712)
		(end 364.619032 -423.724578)
		(width 0.254)
		(layer "F.Cu")
		(net "P1V8_CPU0_RT_1D")
	)
	(segment
		(start 291.776658 -398.334992)
		(end 291.964618 -398.522952)
		(width 0.254)
		(layer "F.Cu")
		(net "P1V8_CPU0_RT_1D")
	)
	(segment
		(start 365.5187 -426.604176)
		(end 365.283496 -426.604176)
		(width 0.254)
		(layer "F.Cu")
		(net "P1V8_CPU0_RT_1D")
	)
	(segment
		(start 291.776658 -397.59001)
		(end 291.776658 -398.334992)
		(width 0.254)
		(layer "F.Cu")
		(net "P1V8_CPU0_RT_1D")
	)
	(segment
		(start 289.89274 -397.589248)
		(end 289.89274 -398.047718)
		(width 0.254)
		(layer "F.Cu")
		(net "P1V8_CPU0_RT_1D")
	)
	(via
		(at 290.46043 -390.512808)
		(size 0.508)
		(drill 0.254)
		(layers "F.Cu" "B.Cu")
		(net "P1V8_CPU0_RT_1D")
	)
	(via
		(at 395.65326 -391.836148)
		(size 0.6604)
		(drill 0.3302)
		(layers "F.Cu" "B.Cu")
		(net "P1V8_CPU0_RT_1D")
	)
	(via
		(at 330.94041 -397.153384)
		(size 0.508)
		(drill 0.254)
		(layers "F.Cu" "B.Cu")
		(net "P1V8_CPU0_RT_1D")
	)
	(via
		(at 359.520236 -394.42263)
		(size 0.508)
		(drill 0.254)
		(layers "F.Cu" "B.Cu")
		(net "P1V8_CPU0_RT_1D")
	)
	(via
		(at 291.73043 -392.417808)
		(size 0.508)
		(drill 0.254)
		(layers "F.Cu" "B.Cu")
		(net "P1V8_CPU0_RT_1D")
	)
	(via
		(at 418.307266 -427.161452)
		(size 0.508)
		(drill 0.254)
		(layers "F.Cu" "B.Cu")
		(net "P1V8_CPU0_RT_1D")
	)
	(via
		(at 239.547654 -311.28208)
		(size 0.508)
		(drill 0.254)
		(layers "F.Cu" "B.Cu")
		(net "P1V8_CPU0_RT_1D")
	)
	(via
		(at 360.304842 -391.787126)
		(size 0.508)
		(drill 0.254)
		(layers "F.Cu" "B.Cu")
		(net "P1V8_CPU0_RT_1D")
	)
	(via
		(at 328.141838 -393.084304)
		(size 0.508)
		(drill 0.254)
		(layers "F.Cu" "B.Cu")
		(net "P1V8_CPU0_RT_1D")
	)
	(via
		(at 394.24229 -391.787126)
		(size 0.508)
		(drill 0.254)
		(layers "F.Cu" "B.Cu")
		(net "P1V8_CPU0_RT_1D")
	)
	(via
		(at 240.309654 -310.52008)
		(size 0.508)
		(drill 0.254)
		(layers "F.Cu" "B.Cu")
		(net "P1V8_CPU0_RT_1D")
	)
	(via
		(at 246.301514 -313.92368)
		(size 0.508)
		(drill 0.254)
		(layers "F.Cu" "B.Cu")
		(net "P1V8_CPU0_RT_1D")
	)
	(via
		(at 367.792 -425.704)
		(size 0.508)
		(drill 0.254)
		(layers "F.Cu" "B.Cu")
		(net "P1V8_CPU0_RT_1D")
	)
	(via
		(at 233.172 -337.947)
		(size 0.508)
		(drill 0.254)
		(layers "F.Cu" "B.Cu")
		(net "P1V8_CPU0_RT_1D")
	)
	(via
		(at 289.80384 -378.951236)
		(size 0.508)
		(drill 0.254)
		(layers "F.Cu" "B.Cu")
		(net "P1V8_CPU0_RT_1D")
	)
	(via
		(at 245.594378 -309.75808)
		(size 0.508)
		(drill 0.254)
		(layers "F.Cu" "B.Cu")
		(net "P1V8_CPU0_RT_1D")
	)
	(via
		(at 233.172 -335.661)
		(size 0.508)
		(drill 0.254)
		(layers "F.Cu" "B.Cu")
		(net "P1V8_CPU0_RT_1D")
	)
	(via
		(at 238.932212 -312.359802)
		(size 0.508)
		(drill 0.254)
		(layers "F.Cu" "B.Cu")
		(net "P1V8_CPU0_RT_1D")
	)
	(via
		(at 246.356378 -309.75808)
		(size 0.508)
		(drill 0.254)
		(layers "F.Cu" "B.Cu")
		(net "P1V8_CPU0_RT_1D")
	)
	(via
		(at 296.941494 -392.1252)
		(size 0.508)
		(drill 0.254)
		(layers "F.Cu" "B.Cu")
		(net "P1V8_CPU0_RT_1D")
	)
	(via
		(at 239.547654 -310.52008)
		(size 0.508)
		(drill 0.254)
		(layers "F.Cu" "B.Cu")
		(net "P1V8_CPU0_RT_1D")
	)
	(via
		(at 428.17923 -394.355066)
		(size 0.508)
		(drill 0.254)
		(layers "F.Cu" "B.Cu")
		(net "P1V8_CPU0_RT_1D")
	)
	(via
		(at 291.09543 -389.877808)
		(size 0.508)
		(drill 0.254)
		(layers "F.Cu" "B.Cu")
		(net "P1V8_CPU0_RT_1D")
	)
	(via
		(at 253.8349 -335.13268)
		(size 0.508)
		(drill 0.254)
		(layers "F.Cu" "B.Cu")
		(net "P1V8_CPU0_RT_1D")
	)
	(via
		(at 293.00043 -392.417808)
		(size 0.508)
		(drill 0.254)
		(layers "F.Cu" "B.Cu")
		(net "P1V8_CPU0_RT_1D")
	)
	(via
		(at 238.932212 -313.883802)
		(size 0.508)
		(drill 0.254)
		(layers "F.Cu" "B.Cu")
		(net "P1V8_CPU0_RT_1D")
	)
	(via
		(at 240.205514 -313.16168)
		(size 0.508)
		(drill 0.254)
		(layers "F.Cu" "B.Cu")
		(net "P1V8_CPU0_RT_1D")
	)
	(via
		(at 240.309654 -309.75808)
		(size 0.508)
		(drill 0.254)
		(layers "F.Cu" "B.Cu")
		(net "P1V8_CPU0_RT_1D")
	)
	(via
		(at 328.141838 -392.449304)
		(size 0.508)
		(drill 0.254)
		(layers "F.Cu" "B.Cu")
		(net "P1V8_CPU0_RT_1D")
	)
	(via
		(at 367.807494 -404.63597)
		(size 0.508)
		(drill 0.254)
		(layers "F.Cu" "B.Cu")
		(net "P1V8_CPU0_RT_1D")
	)
	(via
		(at 292.97884 -378.951236)
		(size 0.508)
		(drill 0.254)
		(layers "F.Cu" "B.Cu")
		(net "P1V8_CPU0_RT_1D")
	)
	(via
		(at 289.80384 -378.316236)
		(size 0.508)
		(drill 0.254)
		(layers "F.Cu" "B.Cu")
		(net "P1V8_CPU0_RT_1D")
	)
	(via
		(at 327.777094 -391.787126)
		(size 0.508)
		(drill 0.254)
		(layers "F.Cu" "B.Cu")
		(net "P1V8_CPU0_RT_1D")
	)
	(via
		(at 244.853968 -312.40476)
		(size 0.508)
		(drill 0.254)
		(layers "F.Cu" "B.Cu")
		(net "P1V8_CPU0_RT_1D")
	)
	(via
		(at 294.564562 -424.942)
		(size 0.508)
		(drill 0.254)
		(layers "F.Cu" "B.Cu")
		(net "P1V8_CPU0_RT_1D")
	)
	(via
		(at 233.172 -340.233)
		(size 0.508)
		(drill 0.254)
		(layers "F.Cu" "B.Cu")
		(net "P1V8_CPU0_RT_1D")
	)
	(via
		(at 293.00043 -391.782808)
		(size 0.508)
		(drill 0.254)
		(layers "F.Cu" "B.Cu")
		(net "P1V8_CPU0_RT_1D")
	)
	(via
		(at 358.793288 -394.826744)
		(size 0.508)
		(drill 0.254)
		(layers "F.Cu" "B.Cu")
		(net "P1V8_CPU0_RT_1D")
	)
	(via
		(at 290.46043 -389.877808)
		(size 0.508)
		(drill 0.254)
		(layers "F.Cu" "B.Cu")
		(net "P1V8_CPU0_RT_1D")
	)
	(via
		(at 326.26554 -394.826744)
		(size 0.508)
		(drill 0.254)
		(layers "F.Cu" "B.Cu")
		(net "P1V8_CPU0_RT_1D")
	)
	(via
		(at 248.689114 -313.92368)
		(size 0.508)
		(drill 0.254)
		(layers "F.Cu" "B.Cu")
		(net "P1V8_CPU0_RT_1D")
	)
	(via
		(at 292.97884 -378.316236)
		(size 0.508)
		(drill 0.254)
		(layers "F.Cu" "B.Cu")
		(net "P1V8_CPU0_RT_1D")
	)
	(via
		(at 425.281852 -426.169328)
		(size 0.508)
		(drill 0.254)
		(layers "F.Cu" "B.Cu")
		(net "P1V8_CPU0_RT_1D")
	)
	(via
		(at 253.8349 -340.76132)
		(size 0.508)
		(drill 0.254)
		(layers "F.Cu" "B.Cu")
		(net "P1V8_CPU0_RT_1D")
	)
	(via
		(at 424.473624 -420.72687)
		(size 0.508)
		(drill 0.254)
		(layers "F.Cu" "B.Cu")
		(net "P1V8_CPU0_RT_1D")
	)
	(via
		(at 395.242034 -393.084304)
		(size 0.508)
		(drill 0.254)
		(layers "F.Cu" "B.Cu")
		(net "P1V8_CPU0_RT_1D")
	)
	(via
		(at 291.09543 -390.512808)
		(size 0.508)
		(drill 0.254)
		(layers "F.Cu" "B.Cu")
		(net "P1V8_CPU0_RT_1D")
	)
	(via
		(at 363.40669 -392.1252)
		(size 0.508)
		(drill 0.254)
		(layers "F.Cu" "B.Cu")
		(net "P1V8_CPU0_RT_1D")
	)
	(via
		(at 246.301514 -312.39968)
		(size 0.508)
		(drill 0.254)
		(layers "F.Cu" "B.Cu")
		(net "P1V8_CPU0_RT_1D")
	)
	(via
		(at 238.960914 -315.44768)
		(size 0.508)
		(drill 0.254)
		(layers "F.Cu" "B.Cu")
		(net "P1V8_CPU0_RT_1D")
	)
	(via
		(at 322.40474 -402.12518)
		(size 0.508)
		(drill 0.254)
		(layers "F.Cu" "B.Cu")
		(net "P1V8_CPU0_RT_1D")
	)
	(via
		(at 354.84562 -404.89124)
		(size 0.508)
		(drill 0.254)
		(layers "F.Cu" "B.Cu")
		(net "P1V8_CPU0_RT_1D")
	)
	(via
		(at 295.790112 -397.656812)
		(size 0.508)
		(drill 0.254)
		(layers "F.Cu" "B.Cu")
		(net "P1V8_CPU0_RT_1D")
	)
	(via
		(at 428.299626 -393.698476)
		(size 0.508)
		(drill 0.254)
		(layers "F.Cu" "B.Cu")
		(net "P1V8_CPU0_RT_1D")
	)
	(via
		(at 253.8349 -337.37804)
		(size 0.508)
		(drill 0.254)
		(layers "F.Cu" "B.Cu")
		(net "P1V8_CPU0_RT_1D")
	)
	(via
		(at 393.365736 -394.826744)
		(size 0.508)
		(drill 0.254)
		(layers "F.Cu" "B.Cu")
		(net "P1V8_CPU0_RT_1D")
	)
	(via
		(at 363.66069 -393.76096)
		(size 0.508)
		(drill 0.254)
		(layers "F.Cu" "B.Cu")
		(net "P1V8_CPU0_RT_1D")
	)
	(via
		(at 304.621946 -425.581318)
		(size 0.508)
		(drill 0.254)
		(layers "F.Cu" "B.Cu")
		(net "P1V8_CPU0_RT_1D")
	)
	(via
		(at 246.301514 -313.16168)
		(size 0.508)
		(drill 0.254)
		(layers "F.Cu" "B.Cu")
		(net "P1V8_CPU0_RT_1D")
	)
	(via
		(at 291.09543 -391.782808)
		(size 0.508)
		(drill 0.254)
		(layers "F.Cu" "B.Cu")
		(net "P1V8_CPU0_RT_1D")
	)
	(via
		(at 291.09543 -392.417808)
		(size 0.508)
		(drill 0.254)
		(layers "F.Cu" "B.Cu")
		(net "P1V8_CPU0_RT_1D")
	)
	(via
		(at 232.240582 -335.9658)
		(size 0.508)
		(drill 0.254)
		(layers "F.Cu" "B.Cu")
		(net "P1V8_CPU0_RT_1D")
	)
	(via
		(at 240.309654 -311.28208)
		(size 0.508)
		(drill 0.254)
		(layers "F.Cu" "B.Cu")
		(net "P1V8_CPU0_RT_1D")
	)
	(via
		(at 360.669586 -392.449304)
		(size 0.508)
		(drill 0.254)
		(layers "F.Cu" "B.Cu")
		(net "P1V8_CPU0_RT_1D")
	)
	(via
		(at 239.547654 -309.75808)
		(size 0.508)
		(drill 0.254)
		(layers "F.Cu" "B.Cu")
		(net "P1V8_CPU0_RT_1D")
	)
	(via
		(at 237.716314 -312.314844)
		(size 0.508)
		(drill 0.254)
		(layers "F.Cu" "B.Cu")
		(net "P1V8_CPU0_RT_1D")
	)
	(via
		(at 428.17923 -395.625066)
		(size 0.508)
		(drill 0.254)
		(layers "F.Cu" "B.Cu")
		(net "P1V8_CPU0_RT_1D")
	)
	(via
		(at 289.82543 -389.877808)
		(size 0.508)
		(drill 0.254)
		(layers "F.Cu" "B.Cu")
		(net "P1V8_CPU0_RT_1D")
	)
	(via
		(at 289.82543 -392.417808)
		(size 0.508)
		(drill 0.254)
		(layers "F.Cu" "B.Cu")
		(net "P1V8_CPU0_RT_1D")
	)
	(via
		(at 242.813332 -313.910726)
		(size 0.508)
		(drill 0.254)
		(layers "F.Cu" "B.Cu")
		(net "P1V8_CPU0_RT_1D")
	)
	(via
		(at 245.594378 -310.52008)
		(size 0.508)
		(drill 0.254)
		(layers "F.Cu" "B.Cu")
		(net "P1V8_CPU0_RT_1D")
	)
	(via
		(at 326.992488 -394.42263)
		(size 0.508)
		(drill 0.254)
		(layers "F.Cu" "B.Cu")
		(net "P1V8_CPU0_RT_1D")
	)
	(via
		(at 290.43884 -378.951236)
		(size 0.508)
		(drill 0.254)
		(layers "F.Cu" "B.Cu")
		(net "P1V8_CPU0_RT_1D")
	)
	(via
		(at 398.040606 -397.153384)
		(size 0.508)
		(drill 0.254)
		(layers "F.Cu" "B.Cu")
		(net "P1V8_CPU0_RT_1D")
	)
	(via
		(at 242.796314 -315.44768)
		(size 0.508)
		(drill 0.254)
		(layers "F.Cu" "B.Cu")
		(net "P1V8_CPU0_RT_1D")
	)
	(via
		(at 304.227484 -426.952156)
		(size 0.508)
		(drill 0.254)
		(layers "F.Cu" "B.Cu")
		(net "P1V8_CPU0_RT_1D")
	)
	(via
		(at 245.594378 -311.28208)
		(size 0.508)
		(drill 0.254)
		(layers "F.Cu" "B.Cu")
		(net "P1V8_CPU0_RT_1D")
	)
	(via
		(at 421.63365 -404.603966)
		(size 0.508)
		(drill 0.254)
		(layers "F.Cu" "B.Cu")
		(net "P1V8_CPU0_RT_1D")
	)
	(via
		(at 238.932212 -313.121802)
		(size 0.508)
		(drill 0.254)
		(layers "F.Cu" "B.Cu")
		(net "P1V8_CPU0_RT_1D")
	)
	(via
		(at 244.853714 -315.44768)
		(size 0.508)
		(drill 0.254)
		(layers "F.Cu" "B.Cu")
		(net "P1V8_CPU0_RT_1D")
	)
	(via
		(at 292.34384 -378.316236)
		(size 0.508)
		(drill 0.254)
		(layers "F.Cu" "B.Cu")
		(net "P1V8_CPU0_RT_1D")
	)
	(via
		(at 291.70884 -378.951236)
		(size 0.508)
		(drill 0.254)
		(layers "F.Cu" "B.Cu")
		(net "P1V8_CPU0_RT_1D")
	)
	(via
		(at 293.61384 -378.951236)
		(size 0.508)
		(drill 0.254)
		(layers "F.Cu" "B.Cu")
		(net "P1V8_CPU0_RT_1D")
	)
	(via
		(at 253.8349 -336.25536)
		(size 0.508)
		(drill 0.254)
		(layers "F.Cu" "B.Cu")
		(net "P1V8_CPU0_RT_1D")
	)
	(via
		(at 253.8349 -341.884)
		(size 0.508)
		(drill 0.254)
		(layers "F.Cu" "B.Cu")
		(net "P1V8_CPU0_RT_1D")
	)
	(via
		(at 428.24273 -396.625064)
		(size 0.508)
		(drill 0.254)
		(layers "F.Cu" "B.Cu")
		(net "P1V8_CPU0_RT_1D")
	)
	(via
		(at 327.062338 -392.48588)
		(size 0.508)
		(drill 0.254)
		(layers "F.Cu" "B.Cu")
		(net "P1V8_CPU0_RT_1D")
	)
	(via
		(at 292.36543 -390.512808)
		(size 0.508)
		(drill 0.254)
		(layers "F.Cu" "B.Cu")
		(net "P1V8_CPU0_RT_1D")
	)
	(via
		(at 428.17923 -394.990066)
		(size 0.508)
		(drill 0.254)
		(layers "F.Cu" "B.Cu")
		(net "P1V8_CPU0_RT_1D")
	)
	(via
		(at 293.00043 -389.877808)
		(size 0.508)
		(drill 0.254)
		(layers "F.Cu" "B.Cu")
		(net "P1V8_CPU0_RT_1D")
	)
	(via
		(at 292.36543 -391.147808)
		(size 0.508)
		(drill 0.254)
		(layers "F.Cu" "B.Cu")
		(net "P1V8_CPU0_RT_1D")
	)
	(via
		(at 360.669586 -393.084304)
		(size 0.508)
		(drill 0.254)
		(layers "F.Cu" "B.Cu")
		(net "P1V8_CPU0_RT_1D")
	)
	(via
		(at 291.09543 -391.147808)
		(size 0.508)
		(drill 0.254)
		(layers "F.Cu" "B.Cu")
		(net "P1V8_CPU0_RT_1D")
	)
	(via
		(at 291.73043 -390.512808)
		(size 0.508)
		(drill 0.254)
		(layers "F.Cu" "B.Cu")
		(net "P1V8_CPU0_RT_1D")
	)
	(via
		(at 291.964618 -398.522952)
		(size 0.508)
		(drill 0.254)
		(layers "F.Cu" "B.Cu")
		(net "P1V8_CPU0_RT_1D")
	)
	(via
		(at 253.8349 -334.01)
		(size 0.508)
		(drill 0.254)
		(layers "F.Cu" "B.Cu")
		(net "P1V8_CPU0_RT_1D")
	)
	(via
		(at 248.689114 -312.39968)
		(size 0.508)
		(drill 0.254)
		(layers "F.Cu" "B.Cu")
		(net "P1V8_CPU0_RT_1D")
	)
	(via
		(at 394.092684 -394.42263)
		(size 0.508)
		(drill 0.254)
		(layers "F.Cu" "B.Cu")
		(net "P1V8_CPU0_RT_1D")
	)
	(via
		(at 244.853968 -313.92876)
		(size 0.508)
		(drill 0.254)
		(layers "F.Cu" "B.Cu")
		(net "P1V8_CPU0_RT_1D")
	)
	(via
		(at 423.206672 -423.592752)
		(size 0.508)
		(drill 0.254)
		(layers "F.Cu" "B.Cu")
		(net "P1V8_CPU0_RT_1D")
	)
	(via
		(at 394.162534 -392.48588)
		(size 0.508)
		(drill 0.254)
		(layers "F.Cu" "B.Cu")
		(net "P1V8_CPU0_RT_1D")
	)
	(via
		(at 242.813332 -312.386726)
		(size 0.508)
		(drill 0.254)
		(layers "F.Cu" "B.Cu")
		(net "P1V8_CPU0_RT_1D")
	)
	(via
		(at 237.720378 -314.83808)
		(size 0.508)
		(drill 0.254)
		(layers "F.Cu" "B.Cu")
		(net "P1V8_CPU0_RT_1D")
	)
	(via
		(at 244.853968 -313.16676)
		(size 0.508)
		(drill 0.254)
		(layers "F.Cu" "B.Cu")
		(net "P1V8_CPU0_RT_1D")
	)
	(via
		(at 237.716314 -313.838844)
		(size 0.508)
		(drill 0.254)
		(layers "F.Cu" "B.Cu")
		(net "P1V8_CPU0_RT_1D")
	)
	(via
		(at 244.853714 -314.68568)
		(size 0.508)
		(drill 0.254)
		(layers "F.Cu" "B.Cu")
		(net "P1V8_CPU0_RT_1D")
	)
	(via
		(at 289.82543 -391.782808)
		(size 0.508)
		(drill 0.254)
		(layers "F.Cu" "B.Cu")
		(net "P1V8_CPU0_RT_1D")
	)
	(via
		(at 291.07384 -378.951236)
		(size 0.508)
		(drill 0.254)
		(layers "F.Cu" "B.Cu")
		(net "P1V8_CPU0_RT_1D")
	)
	(via
		(at 248.689114 -315.44768)
		(size 0.508)
		(drill 0.254)
		(layers "F.Cu" "B.Cu")
		(net "P1V8_CPU0_RT_1D")
	)
	(via
		(at 302.339756 -422.05402)
		(size 0.508)
		(drill 0.254)
		(layers "F.Cu" "B.Cu")
		(net "P1V8_CPU0_RT_1D")
	)
	(via
		(at 232.24617 -340.544404)
		(size 0.508)
		(drill 0.254)
		(layers "F.Cu" "B.Cu")
		(net "P1V8_CPU0_RT_1D")
	)
	(via
		(at 291.73043 -389.877808)
		(size 0.508)
		(drill 0.254)
		(layers "F.Cu" "B.Cu")
		(net "P1V8_CPU0_RT_1D")
	)
	(via
		(at 289.82543 -391.147808)
		(size 0.508)
		(drill 0.254)
		(layers "F.Cu" "B.Cu")
		(net "P1V8_CPU0_RT_1D")
	)
	(via
		(at 394.162534 -393.47648)
		(size 0.508)
		(drill 0.254)
		(layers "F.Cu" "B.Cu")
		(net "P1V8_CPU0_RT_1D")
	)
	(via
		(at 291.07384 -378.316236)
		(size 0.508)
		(drill 0.254)
		(layers "F.Cu" "B.Cu")
		(net "P1V8_CPU0_RT_1D")
	)
	(via
		(at 292.36543 -391.782808)
		(size 0.508)
		(drill 0.254)
		(layers "F.Cu" "B.Cu")
		(net "P1V8_CPU0_RT_1D")
	)
	(via
		(at 246.356378 -310.52008)
		(size 0.508)
		(drill 0.254)
		(layers "F.Cu" "B.Cu")
		(net "P1V8_CPU0_RT_1D")
	)
	(via
		(at 292.34384 -378.951236)
		(size 0.508)
		(drill 0.254)
		(layers "F.Cu" "B.Cu")
		(net "P1V8_CPU0_RT_1D")
	)
	(via
		(at 359.590086 -393.47648)
		(size 0.508)
		(drill 0.254)
		(layers "F.Cu" "B.Cu")
		(net "P1V8_CPU0_RT_1D")
	)
	(via
		(at 364.719616 -430.36109)
		(size 0.508)
		(drill 0.254)
		(layers "F.Cu" "B.Cu")
		(net "P1V8_CPU0_RT_1D")
	)
	(via
		(at 237.716314 -313.076844)
		(size 0.508)
		(drill 0.254)
		(layers "F.Cu" "B.Cu")
		(net "P1V8_CPU0_RT_1D")
	)
	(via
		(at 289.82543 -390.512808)
		(size 0.508)
		(drill 0.254)
		(layers "F.Cu" "B.Cu")
		(net "P1V8_CPU0_RT_1D")
	)
	(via
		(at 364.04169 -392.1252)
		(size 0.508)
		(drill 0.254)
		(layers "F.Cu" "B.Cu")
		(net "P1V8_CPU0_RT_1D")
	)
	(via
		(at 395.242034 -392.449304)
		(size 0.508)
		(drill 0.254)
		(layers "F.Cu" "B.Cu")
		(net "P1V8_CPU0_RT_1D")
	)
	(via
		(at 294.513 -426.466)
		(size 0.508)
		(drill 0.254)
		(layers "F.Cu" "B.Cu")
		(net "P1V8_CPU0_RT_1D")
	)
	(via
		(at 359.590086 -392.48588)
		(size 0.508)
		(drill 0.254)
		(layers "F.Cu" "B.Cu")
		(net "P1V8_CPU0_RT_1D")
	)
	(via
		(at 293.00043 -391.147808)
		(size 0.508)
		(drill 0.254)
		(layers "F.Cu" "B.Cu")
		(net "P1V8_CPU0_RT_1D")
	)
	(via
		(at 240.205514 -312.39968)
		(size 0.508)
		(drill 0.254)
		(layers "F.Cu" "B.Cu")
		(net "P1V8_CPU0_RT_1D")
	)
	(via
		(at 289.72637 -398.591024)
		(size 0.508)
		(drill 0.254)
		(layers "F.Cu" "B.Cu")
		(net "P1V8_CPU0_RT_1D")
	)
	(via
		(at 290.43884 -378.316236)
		(size 0.508)
		(drill 0.254)
		(layers "F.Cu" "B.Cu")
		(net "P1V8_CPU0_RT_1D")
	)
	(via
		(at 242.813332 -313.148726)
		(size 0.508)
		(drill 0.254)
		(layers "F.Cu" "B.Cu")
		(net "P1V8_CPU0_RT_1D")
	)
	(via
		(at 424.376342 -428.962058)
		(size 0.508)
		(drill 0.254)
		(layers "F.Cu" "B.Cu")
		(net "P1V8_CPU0_RT_1D")
	)
	(via
		(at 253.8349 -338.51596)
		(size 0.508)
		(drill 0.254)
		(layers "F.Cu" "B.Cu")
		(net "P1V8_CPU0_RT_1D")
	)
	(via
		(at 232.273348 -337.655154)
		(size 0.508)
		(drill 0.254)
		(layers "F.Cu" "B.Cu")
		(net "P1V8_CPU0_RT_1D")
	)
	(via
		(at 233.172 -333.375)
		(size 0.508)
		(drill 0.254)
		(layers "F.Cu" "B.Cu")
		(net "P1V8_CPU0_RT_1D")
	)
	(via
		(at 426.89653 -420.701978)
		(size 0.508)
		(drill 0.254)
		(layers "F.Cu" "B.Cu")
		(net "P1V8_CPU0_RT_1D")
	)
	(via
		(at 396.582392 -392.993118)
		(size 0.6604)
		(drill 0.3302)
		(layers "F.Cu" "B.Cu")
		(net "P1V8_CPU0_RT_1D")
	)
	(via
		(at 290.46043 -392.417808)
		(size 0.508)
		(drill 0.254)
		(layers "F.Cu" "B.Cu")
		(net "P1V8_CPU0_RT_1D")
	)
	(via
		(at 425.286424 -420.72687)
		(size 0.508)
		(drill 0.254)
		(layers "F.Cu" "B.Cu")
		(net "P1V8_CPU0_RT_1D")
	)
	(via
		(at 294.24884 -378.951236)
		(size 0.508)
		(drill 0.254)
		(layers "F.Cu" "B.Cu")
		(net "P1V8_CPU0_RT_1D")
	)
	(via
		(at 364.29569 -393.76096)
		(size 0.508)
		(drill 0.254)
		(layers "F.Cu" "B.Cu")
		(net "P1V8_CPU0_RT_1D")
	)
	(via
		(at 290.46043 -391.782808)
		(size 0.508)
		(drill 0.254)
		(layers "F.Cu" "B.Cu")
		(net "P1V8_CPU0_RT_1D")
	)
	(via
		(at 246.356378 -311.28208)
		(size 0.508)
		(drill 0.254)
		(layers "F.Cu" "B.Cu")
		(net "P1V8_CPU0_RT_1D")
	)
	(via
		(at 327.142094 -391.787126)
		(size 0.508)
		(drill 0.254)
		(layers "F.Cu" "B.Cu")
		(net "P1V8_CPU0_RT_1D")
	)
	(via
		(at 294.24884 -378.316236)
		(size 0.508)
		(drill 0.254)
		(layers "F.Cu" "B.Cu")
		(net "P1V8_CPU0_RT_1D")
	)
	(via
		(at 237.843822 -291.614098)
		(size 0.508)
		(drill 0.254)
		(layers "F.Cu" "B.Cu")
		(net "P1V8_CPU0_RT_1D")
	)
	(via
		(at 232.226104 -342.2777)
		(size 0.508)
		(drill 0.254)
		(layers "F.Cu" "B.Cu")
		(net "P1V8_CPU0_RT_1D")
	)
	(via
		(at 293.00043 -390.512808)
		(size 0.508)
		(drill 0.254)
		(layers "F.Cu" "B.Cu")
		(net "P1V8_CPU0_RT_1D")
	)
	(via
		(at 394.87729 -391.787126)
		(size 0.508)
		(drill 0.254)
		(layers "F.Cu" "B.Cu")
		(net "P1V8_CPU0_RT_1D")
	)
	(via
		(at 240.205514 -313.92368)
		(size 0.508)
		(drill 0.254)
		(layers "F.Cu" "B.Cu")
		(net "P1V8_CPU0_RT_1D")
	)
	(via
		(at 253.8349 -339.63864)
		(size 0.508)
		(drill 0.254)
		(layers "F.Cu" "B.Cu")
		(net "P1V8_CPU0_RT_1D")
	)
	(via
		(at 364.822994 -423.150792)
		(size 0.508)
		(drill 0.254)
		(layers "F.Cu" "B.Cu")
		(net "P1V8_CPU0_RT_1D")
	)
	(via
		(at 242.796314 -314.68568)
		(size 0.508)
		(drill 0.254)
		(layers "F.Cu" "B.Cu")
		(net "P1V8_CPU0_RT_1D")
	)
	(via
		(at 297.195494 -393.96416)
		(size 0.508)
		(drill 0.254)
		(layers "F.Cu" "B.Cu")
		(net "P1V8_CPU0_RT_1D")
	)
	(via
		(at 395.619478 -393.845796)
		(size 0.6604)
		(drill 0.3302)
		(layers "F.Cu" "B.Cu")
		(net "P1V8_CPU0_RT_1D")
	)
	(via
		(at 291.73043 -391.147808)
		(size 0.508)
		(drill 0.254)
		(layers "F.Cu" "B.Cu")
		(net "P1V8_CPU0_RT_1D")
	)
	(via
		(at 426.099224 -420.72687)
		(size 0.508)
		(drill 0.254)
		(layers "F.Cu" "B.Cu")
		(net "P1V8_CPU0_RT_1D")
	)
	(via
		(at 292.36543 -389.877808)
		(size 0.508)
		(drill 0.254)
		(layers "F.Cu" "B.Cu")
		(net "P1V8_CPU0_RT_1D")
	)
	(via
		(at 248.689114 -313.16168)
		(size 0.508)
		(drill 0.254)
		(layers "F.Cu" "B.Cu")
		(net "P1V8_CPU0_RT_1D")
	)
	(via
		(at 238.960914 -314.68568)
		(size 0.508)
		(drill 0.254)
		(layers "F.Cu" "B.Cu")
		(net "P1V8_CPU0_RT_1D")
	)
	(via
		(at 248.689114 -314.68568)
		(size 0.508)
		(drill 0.254)
		(layers "F.Cu" "B.Cu")
		(net "P1V8_CPU0_RT_1D")
	)
	(via
		(at 293.61384 -378.316236)
		(size 0.508)
		(drill 0.254)
		(layers "F.Cu" "B.Cu")
		(net "P1V8_CPU0_RT_1D")
	)
	(via
		(at 359.669842 -391.787126)
		(size 0.508)
		(drill 0.254)
		(layers "F.Cu" "B.Cu")
		(net "P1V8_CPU0_RT_1D")
	)
	(via
		(at 360.167174 -398.44472)
		(size 0.508)
		(drill 0.254)
		(layers "F.Cu" "B.Cu")
		(net "P1V8_CPU0_RT_1D")
	)
	(via
		(at 291.73043 -391.782808)
		(size 0.508)
		(drill 0.254)
		(layers "F.Cu" "B.Cu")
		(net "P1V8_CPU0_RT_1D")
	)
	(via
		(at 327.062338 -393.47648)
		(size 0.508)
		(drill 0.254)
		(layers "F.Cu" "B.Cu")
		(net "P1V8_CPU0_RT_1D")
	)
	(via
		(at 291.70884 -378.316236)
		(size 0.508)
		(drill 0.254)
		(layers "F.Cu" "B.Cu")
		(net "P1V8_CPU0_RT_1D")
	)
	(via
		(at 304.615088 -427.48835)
		(size 0.508)
		(drill 0.254)
		(layers "F.Cu" "B.Cu")
		(net "P1V8_CPU0_RT_1D")
	)
	(via
		(at 292.36543 -392.417808)
		(size 0.508)
		(drill 0.254)
		(layers "F.Cu" "B.Cu")
		(net "P1V8_CPU0_RT_1D")
	)
	(via
		(at 239.141 -324.626986)
		(size 0.508)
		(drill 0.254)
		(layers "F.Cu" "B.Cu")
		(net "P1V8_CPU0_RT_1D")
	)
	(via
		(at 290.46043 -391.147808)
		(size 0.508)
		(drill 0.254)
		(layers "F.Cu" "B.Cu")
		(net "P1V8_CPU0_RT_1D")
	)
	(segment
		(start 254.3683 -338.51596)
		(end 253.8349 -338.51596)
		(width 0.254)
		(layer "B.Cu")
		(net "P1V8_CPU0_RT_1D")
	)
	(segment
		(start 365.192818 -423.150792)
		(end 364.822994 -423.150792)
		(width 0.254)
		(layer "B.Cu")
		(net "P1V8_CPU0_RT_1D")
	)
	(segment
		(start 424.684444 -426.451522)
		(end 424.999658 -426.451522)
		(width 0.254)
		(layer "B.Cu")
		(net "P1V8_CPU0_RT_1D")
	)
	(segment
		(start 295.1353 -426.339)
		(end 294.64 -426.339)
		(width 0.254)
		(layer "B.Cu")
		(net "P1V8_CPU0_RT_1D")
	)
	(segment
		(start 371.376702 -426.428916)
		(end 369.873784 -426.428916)
		(width 0.254)
		(layer "B.Cu")
		(net "P1V8_CPU0_RT_1D")
	)
	(segment
		(start 294.64 -426.339)
		(end 294.513 -426.466)
		(width 0.254)
		(layer "B.Cu")
		(net "P1V8_CPU0_RT_1D")
	)
	(segment
		(start 254.3683 -334.01)
		(end 253.8349 -334.01)
		(width 0.254)
		(layer "B.Cu")
		(net "P1V8_CPU0_RT_1D")
	)
	(segment
		(start 232.176066 -340.4743)
		(end 232.24617 -340.544404)
		(width 0.254)
		(layer "B.Cu")
		(net "P1V8_CPU0_RT_1D")
	)
	(segment
		(start 232.177082 -335.9023)
		(end 232.240582 -335.9658)
		(width 0.254)
		(layer "B.Cu")
		(net "P1V8_CPU0_RT_1D")
	)
	(segment
		(start 232.9307 -338.1883)
		(end 233.172 -337.947)
		(width 0.254)
		(layer "B.Cu")
		(net "P1V8_CPU0_RT_1D")
	)
	(segment
		(start 254.3683 -340.76132)
		(end 253.8349 -340.76132)
		(width 0.254)
		(layer "B.Cu")
		(net "P1V8_CPU0_RT_1D")
	)
	(segment
		(start 369.8367 -426.122846)
		(end 369.7097 -425.995846)
		(width 0.254)
		(layer "B.Cu")
		(net "P1V8_CPU0_RT_1D")
	)
	(segment
		(start 232.9307 -333.6163)
		(end 233.172 -333.375)
		(width 0.254)
		(layer "B.Cu")
		(net "P1V8_CPU0_RT_1D")
	)
	(segment
		(start 424.664124 -428.385224)
		(end 424.664124 -428.674276)
		(width 0.254)
		(layer "B.Cu")
		(net "P1V8_CPU0_RT_1D")
	)
	(segment
		(start 254.3683 -336.25536)
		(end 253.8349 -336.25536)
		(width 0.254)
		(layer "B.Cu")
		(net "P1V8_CPU0_RT_1D")
	)
	(segment
		(start 254.3683 -339.63864)
		(end 253.8349 -339.63864)
		(width 0.254)
		(layer "B.Cu")
		(net "P1V8_CPU0_RT_1D")
	)
	(segment
		(start 232.222802 -337.7057)
		(end 232.273348 -337.655154)
		(width 0.254)
		(layer "B.Cu")
		(net "P1V8_CPU0_RT_1D")
	)
	(segment
		(start 232.273348 -337.655154)
		(end 232.537 -337.918806)
		(width 0.254)
		(layer "B.Cu")
		(net "P1V8_CPU0_RT_1D")
	)
	(segment
		(start 369.873784 -426.428916)
		(end 369.8367 -426.466)
		(width 0.254)
		(layer "B.Cu")
		(net "P1V8_CPU0_RT_1D")
	)
	(segment
		(start 424.664124 -428.674276)
		(end 424.376342 -428.962058)
		(width 0.254)
		(layer "B.Cu")
		(net "P1V8_CPU0_RT_1D")
	)
	(segment
		(start 232.240582 -335.9658)
		(end 232.480612 -335.72577)
		(width 0.254)
		(layer "B.Cu")
		(net "P1V8_CPU0_RT_1D")
	)
	(segment
		(start 232.480612 -335.72577)
		(end 232.480612 -335.725516)
		(width 0.254)
		(layer "B.Cu")
		(net "P1V8_CPU0_RT_1D")
	)
	(segment
		(start 232.537 -335.4197)
		(end 232.9307 -335.4197)
		(width 0.254)
		(layer "B.Cu")
		(net "P1V8_CPU0_RT_1D")
	)
	(segment
		(start 232.537 -338.1883)
		(end 232.9307 -338.1883)
		(width 0.254)
		(layer "B.Cu")
		(net "P1V8_CPU0_RT_1D")
	)
	(segment
		(start 238.317532 -324.626986)
		(end 239.141 -324.626986)
		(width 0.508)
		(layer "B.Cu")
		(net "P1V8_CPU0_RT_1D")
	)
	(segment
		(start 231.648 -340.4743)
		(end 232.176066 -340.4743)
		(width 0.254)
		(layer "B.Cu")
		(net "P1V8_CPU0_RT_1D")
	)
	(segment
		(start 301.575724 -428.428658)
		(end 303.67478 -428.428658)
		(width 0.254)
		(layer "B.Cu")
		(net "P1V8_CPU0_RT_1D")
	)
	(segment
		(start 231.648 -337.7057)
		(end 232.222802 -337.7057)
		(width 0.254)
		(layer "B.Cu")
		(net "P1V8_CPU0_RT_1D")
	)
	(segment
		(start 232.537 -335.669128)
		(end 232.537 -335.4197)
		(width 0.254)
		(layer "B.Cu")
		(net "P1V8_CPU0_RT_1D")
	)
	(segment
		(start 237.843822 -291.614098)
		(end 236.728 -292.72992)
		(width 0.508)
		(layer "B.Cu")
		(net "P1V8_CPU0_RT_1D")
	)
	(segment
		(start 368.595656 -425.995846)
		(end 368.54892 -426.042582)
		(width 0.254)
		(layer "B.Cu")
		(net "P1V8_CPU0_RT_1D")
	)
	(segment
		(start 232.537 -339.9917)
		(end 232.9307 -339.9917)
		(width 0.254)
		(layer "B.Cu")
		(net "P1V8_CPU0_RT_1D")
	)
	(segment
		(start 295.1353 -424.942)
		(end 294.564562 -424.942)
		(width 0.254)
		(layer "B.Cu")
		(net "P1V8_CPU0_RT_1D")
	)
	(segment
		(start 369.7097 -425.995846)
		(end 368.595656 -425.995846)
		(width 0.254)
		(layer "B.Cu")
		(net "P1V8_CPU0_RT_1D")
	)
	(segment
		(start 232.9307 -339.9917)
		(end 233.172 -340.233)
		(width 0.254)
		(layer "B.Cu")
		(net "P1V8_CPU0_RT_1D")
	)
	(segment
		(start 236.728 -292.72992)
		(end 236.728 -314.454286)
		(width 0.508)
		(layer "B.Cu")
		(net "P1V8_CPU0_RT_1D")
	)
	(segment
		(start 302.339756 -422.05402)
		(end 301.535338 -422.858438)
		(width 0.254)
		(layer "B.Cu")
		(net "P1V8_CPU0_RT_1D")
	)
	(segment
		(start 301.535338 -422.858438)
		(end 301.535338 -424.183048)
		(width 0.254)
		(layer "B.Cu")
		(net "P1V8_CPU0_RT_1D")
	)
	(segment
		(start 232.537 -333.6163)
		(end 232.9307 -333.6163)
		(width 0.254)
		(layer "B.Cu")
		(net "P1V8_CPU0_RT_1D")
	)
	(segment
		(start 231.648 -335.9023)
		(end 232.177082 -335.9023)
		(width 0.254)
		(layer "B.Cu")
		(net "P1V8_CPU0_RT_1D")
	)
	(segment
		(start 418.66947 -426.799248)
		(end 418.307266 -427.161452)
		(width 0.254)
		(layer "B.Cu")
		(net "P1V8_CPU0_RT_1D")
	)
	(segment
		(start 232.480612 -335.725516)
		(end 232.537 -335.669128)
		(width 0.254)
		(layer "B.Cu")
		(net "P1V8_CPU0_RT_1D")
	)
	(segment
		(start 232.537 -337.918806)
		(end 232.537 -338.1883)
		(width 0.254)
		(layer "B.Cu")
		(net "P1V8_CPU0_RT_1D")
	)
	(segment
		(start 232.537 -340.253574)
		(end 232.537 -339.9917)
		(width 0.254)
		(layer "B.Cu")
		(net "P1V8_CPU0_RT_1D")
	)
	(segment
		(start 254.3683 -337.37804)
		(end 253.8349 -337.37804)
		(width 0.254)
		(layer "B.Cu")
		(net "P1V8_CPU0_RT_1D")
	)
	(segment
		(start 303.67478 -428.428658)
		(end 304.615088 -427.48835)
		(width 0.254)
		(layer "B.Cu")
		(net "P1V8_CPU0_RT_1D")
	)
	(segment
		(start 368.130582 -426.042582)
		(end 368.54892 -426.042582)
		(width 0.254)
		(layer "B.Cu")
		(net "P1V8_CPU0_RT_1D")
	)
	(segment
		(start 231.648 -342.2777)
		(end 232.226104 -342.2777)
		(width 0.254)
		(layer "B.Cu")
		(net "P1V8_CPU0_RT_1D")
	)
	(segment
		(start 365.580168 -423.022776)
		(end 365.320834 -423.022776)
		(width 0.254)
		(layer "B.Cu")
		(net "P1V8_CPU0_RT_1D")
	)
	(segment
		(start 237.111794 -314.83808)
		(end 237.720378 -314.83808)
		(width 0.508)
		(layer "B.Cu")
		(net "P1V8_CPU0_RT_1D")
	)
	(segment
		(start 232.9307 -335.4197)
		(end 233.172 -335.661)
		(width 0.254)
		(layer "B.Cu")
		(net "P1V8_CPU0_RT_1D")
	)
	(segment
		(start 236.728 -314.454286)
		(end 237.111794 -314.83808)
		(width 0.508)
		(layer "B.Cu")
		(net "P1V8_CPU0_RT_1D")
	)
	(segment
		(start 367.792 -425.704)
		(end 368.130582 -426.042582)
		(width 0.254)
		(layer "B.Cu")
		(net "P1V8_CPU0_RT_1D")
	)
	(segment
		(start 301.082202 -427.935136)
		(end 301.575724 -428.428658)
		(width 0.254)
		(layer "B.Cu")
		(net "P1V8_CPU0_RT_1D")
	)
	(segment
		(start 369.8367 -426.466)
		(end 369.8367 -426.122846)
		(width 0.254)
		(layer "B.Cu")
		(net "P1V8_CPU0_RT_1D")
	)
	(segment
		(start 424.999658 -426.451522)
		(end 425.281852 -426.169328)
		(width 0.254)
		(layer "B.Cu")
		(net "P1V8_CPU0_RT_1D")
	)
	(segment
		(start 232.24617 -340.544404)
		(end 232.537 -340.253574)
		(width 0.254)
		(layer "B.Cu")
		(net "P1V8_CPU0_RT_1D")
	)
	(segment
		(start 365.320834 -423.022776)
		(end 365.192818 -423.150792)
		(width 0.254)
		(layer "B.Cu")
		(net "P1V8_CPU0_RT_1D")
	)
	(segment
		(start 418.862764 -426.799248)
		(end 418.66947 -426.799248)
		(width 0.254)
		(layer "B.Cu")
		(net "P1V8_CPU0_RT_1D")
	)
	(segment
		(start 418.874194 -427.594014)
		(end 418.739828 -427.594014)
		(width 0.254)
		(layer "B.Cu")
		(net "P1V8_CPU0_RT_1D")
	)
	(segment
		(start 418.739828 -427.594014)
		(end 418.307266 -427.161452)
		(width 0.254)
		(layer "B.Cu")
		(net "P1V8_CPU0_RT_1D")
	)
	(segment
		(start 254.3683 -335.13268)
		(end 253.8349 -335.13268)
		(width 0.254)
		(layer "B.Cu")
		(net "P1V8_CPU0_RT_1D")
	)
	(segment
		(start 254.3683 -341.884)
		(end 253.8349 -341.884)
		(width 0.254)
		(layer "B.Cu")
		(net "P1V8_CPU0_RT_1D")
	)
	(segment
		(start 364.822994 -423.150792)
		(end 364.024926 -423.94886)
		(width 0.508)
		(layer "In6.Cu")
		(net "P1V8_CPU0_RT_1D")
	)
	(segment
		(start 368.544094 -404.63597)
		(end 367.807494 -404.63597)
		(width 0.508)
		(layer "In6.Cu")
		(net "P1V8_CPU0_RT_1D")
	)
	(segment
		(start 366.154208 -428.17288)
		(end 367.792 -426.535088)
		(width 0.508)
		(layer "In6.Cu")
		(net "P1V8_CPU0_RT_1D")
	)
	(segment
		(start 369.839494 -405.93137)
		(end 368.544094 -404.63597)
		(width 0.508)
		(layer "In6.Cu")
		(net "P1V8_CPU0_RT_1D")
	)
	(segment
		(start 364.94085 -412.997904)
		(end 366.457992 -411.480762)
		(width 0.508)
		(layer "In6.Cu")
		(net "P1V8_CPU0_RT_1D")
	)
	(segment
		(start 366.457992 -411.480762)
		(end 369.123976 -411.480762)
		(width 0.508)
		(layer "In6.Cu")
		(net "P1V8_CPU0_RT_1D")
	)
	(segment
		(start 364.719616 -430.36109)
		(end 366.154208 -428.926498)
		(width 0.508)
		(layer "In6.Cu")
		(net "P1V8_CPU0_RT_1D")
	)
	(segment
		(start 369.123976 -411.480762)
		(end 369.839494 -410.765244)
		(width 0.508)
		(layer "In6.Cu")
		(net "P1V8_CPU0_RT_1D")
	)
	(segment
		(start 364.024926 -423.94886)
		(end 364.024926 -429.6664)
		(width 0.508)
		(layer "In6.Cu")
		(net "P1V8_CPU0_RT_1D")
	)
	(segment
		(start 369.839494 -410.765244)
		(end 369.839494 -405.93137)
		(width 0.508)
		(layer "In6.Cu")
		(net "P1V8_CPU0_RT_1D")
	)
	(segment
		(start 366.154208 -428.926498)
		(end 366.154208 -428.17288)
		(width 0.508)
		(layer "In6.Cu")
		(net "P1V8_CPU0_RT_1D")
	)
	(segment
		(start 364.822994 -423.150792)
		(end 364.94085 -423.032936)
		(width 0.508)
		(layer "In6.Cu")
		(net "P1V8_CPU0_RT_1D")
	)
	(segment
		(start 364.024926 -429.6664)
		(end 364.719616 -430.36109)
		(width 0.508)
		(layer "In6.Cu")
		(net "P1V8_CPU0_RT_1D")
	)
	(segment
		(start 367.792 -426.535088)
		(end 367.792 -425.704)
		(width 0.508)
		(layer "In6.Cu")
		(net "P1V8_CPU0_RT_1D")
	)
	(segment
		(start 364.94085 -423.032936)
		(end 364.94085 -412.997904)
		(width 0.508)
		(layer "In6.Cu")
		(net "P1V8_CPU0_RT_1D")
	)
	(segment
		(start 190.518796 -165.192964)
		(end 184.814972 -170.896788)
		(width 0.1524)
		(layer "F.Cu")
		(net "FM_PWRGD_P1V8_RETIMER_CPU0")
	)
	(segment
		(start 198.106792 -184.333134)
		(end 200.288398 -186.51474)
		(width 0.1524)
		(layer "F.Cu")
		(net "FM_PWRGD_P1V8_RETIMER_CPU0")
	)
	(segment
		(start 184.814972 -172.872654)
		(end 196.275452 -184.333134)
		(width 0.1524)
		(layer "F.Cu")
		(net "FM_PWRGD_P1V8_RETIMER_CPU0")
	)
	(segment
		(start 190.518796 -164.779706)
		(end 190.518796 -165.192964)
		(width 0.1524)
		(layer "F.Cu")
		(net "FM_PWRGD_P1V8_RETIMER_CPU0")
	)
	(segment
		(start 189.12205 -113.05286)
		(end 189.51194 -112.66297)
		(width 0.10668)
		(layer "F.Cu")
		(net "FM_PWRGD_P1V8_RETIMER_CPU0")
	)
	(segment
		(start 184.814972 -170.896788)
		(end 184.814972 -172.872654)
		(width 0.1524)
		(layer "F.Cu")
		(net "FM_PWRGD_P1V8_RETIMER_CPU0")
	)
	(segment
		(start 196.275452 -184.333134)
		(end 198.106792 -184.333134)
		(width 0.1524)
		(layer "F.Cu")
		(net "FM_PWRGD_P1V8_RETIMER_CPU0")
	)
	(segment
		(start 200.288398 -186.51474)
		(end 200.288398 -186.54014)
		(width 0.1524)
		(layer "F.Cu")
		(net "FM_PWRGD_P1V8_RETIMER_CPU0")
	)
	(via
		(at 200.288398 -186.54014)
		(size 0.508)
		(drill 0.254)
		(layers "F.Cu" "B.Cu")
		(net "FM_PWRGD_P1V8_RETIMER_CPU0")
	)
	(via
		(at 189.51194 -112.66297)
		(size 0.4572)
		(drill 0.254)
		(layers "F.Cu" "B.Cu")
		(net "FM_PWRGD_P1V8_RETIMER_CPU0")
	)
	(via
		(at 190.518796 -164.779706)
		(size 0.508)
		(drill 0.254)
		(layers "F.Cu" "B.Cu")
		(net "FM_PWRGD_P1V8_RETIMER_CPU0")
	)
	(via
		(at 236.386878 -280.172414)
		(size 0.6604)
		(drill 0.3302)
		(layers "F.Cu" "B.Cu")
		(net "FM_PWRGD_P1V8_RETIMER_CPU0")
	)
	(segment
		(start 200.988676 -185.243724)
		(end 207.675226 -185.243724)
		(width 0.1524)
		(layer "B.Cu")
		(net "FM_PWRGD_P1V8_RETIMER_CPU0")
	)
	(segment
		(start 214.01278 -247.522238)
		(end 230.915464 -264.424922)
		(width 0.1524)
		(layer "B.Cu")
		(net "FM_PWRGD_P1V8_RETIMER_CPU0")
	)
	(segment
		(start 234.80141 -278.859488)
		(end 235.073952 -278.859488)
		(width 0.1524)
		(layer "B.Cu")
		(net "FM_PWRGD_P1V8_RETIMER_CPU0")
	)
	(segment
		(start 239.021366 -288.302446)
		(end 240.105692 -288.302446)
		(width 0.1524)
		(layer "B.Cu")
		(net "FM_PWRGD_P1V8_RETIMER_CPU0")
	)
	(segment
		(start 238.246158 -282.040838)
		(end 238.246158 -287.527238)
		(width 0.1524)
		(layer "B.Cu")
		(net "FM_PWRGD_P1V8_RETIMER_CPU0")
	)
	(segment
		(start 235.073952 -278.859488)
		(end 236.386878 -280.172414)
		(width 0.1524)
		(layer "B.Cu")
		(net "FM_PWRGD_P1V8_RETIMER_CPU0")
	)
	(segment
		(start 239.873028 -288.666682)
		(end 240.469928 -288.666682)
		(width 0.1524)
		(layer "B.Cu")
		(net "FM_PWRGD_P1V8_RETIMER_CPU0")
	)
	(segment
		(start 230.915464 -264.424922)
		(end 230.915464 -274.973542)
		(width 0.1524)
		(layer "B.Cu")
		(net "FM_PWRGD_P1V8_RETIMER_CPU0")
	)
	(segment
		(start 238.710978 -289.828732)
		(end 239.873028 -288.666682)
		(width 0.1524)
		(layer "B.Cu")
		(net "FM_PWRGD_P1V8_RETIMER_CPU0")
	)
	(segment
		(start 230.915464 -274.973542)
		(end 234.80141 -278.859488)
		(width 0.1524)
		(layer "B.Cu")
		(net "FM_PWRGD_P1V8_RETIMER_CPU0")
	)
	(segment
		(start 236.386878 -280.172414)
		(end 236.386878 -280.181558)
		(width 0.1524)
		(layer "B.Cu")
		(net "FM_PWRGD_P1V8_RETIMER_CPU0")
	)
	(segment
		(start 214.01278 -191.581278)
		(end 214.01278 -247.522238)
		(width 0.1524)
		(layer "B.Cu")
		(net "FM_PWRGD_P1V8_RETIMER_CPU0")
	)
	(segment
		(start 236.386878 -280.181558)
		(end 238.246158 -282.040838)
		(width 0.1524)
		(layer "B.Cu")
		(net "FM_PWRGD_P1V8_RETIMER_CPU0")
	)
	(segment
		(start 207.675226 -185.243724)
		(end 214.01278 -191.581278)
		(width 0.1524)
		(layer "B.Cu")
		(net "FM_PWRGD_P1V8_RETIMER_CPU0")
	)
	(segment
		(start 240.105692 -288.302446)
		(end 240.469928 -288.666682)
		(width 0.1524)
		(layer "B.Cu")
		(net "FM_PWRGD_P1V8_RETIMER_CPU0")
	)
	(segment
		(start 200.288398 -186.54014)
		(end 200.288398 -185.944002)
		(width 0.1524)
		(layer "B.Cu")
		(net "FM_PWRGD_P1V8_RETIMER_CPU0")
	)
	(segment
		(start 200.288398 -185.944002)
		(end 200.988676 -185.243724)
		(width 0.1524)
		(layer "B.Cu")
		(net "FM_PWRGD_P1V8_RETIMER_CPU0")
	)
	(segment
		(start 238.246158 -287.527238)
		(end 239.021366 -288.302446)
		(width 0.1524)
		(layer "B.Cu")
		(net "FM_PWRGD_P1V8_RETIMER_CPU0")
	)
	(segment
		(start 196.45249 -140.758672)
		(end 196.669914 -140.541248)
		(width 0.1524)
		(layer "In4.Cu")
		(net "FM_PWRGD_P1V8_RETIMER_CPU0")
	)
	(segment
		(start 191.06007 -161.790126)
		(end 199.8599 -161.790126)
		(width 0.1524)
		(layer "In4.Cu")
		(net "FM_PWRGD_P1V8_RETIMER_CPU0")
	)
	(segment
		(start 190.518796 -162.3314)
		(end 191.06007 -161.790126)
		(width 0.1524)
		(layer "In4.Cu")
		(net "FM_PWRGD_P1V8_RETIMER_CPU0")
	)
	(segment
		(start 196.669914 -140.541248)
		(end 196.669914 -132.161534)
		(width 0.1524)
		(layer "In4.Cu")
		(net "FM_PWRGD_P1V8_RETIMER_CPU0")
	)
	(segment
		(start 190.473076 -119.451628)
		(end 190.170816 -119.451628)
		(width 0.11684)
		(layer "In4.Cu")
		(net "FM_PWRGD_P1V8_RETIMER_CPU0")
	)
	(segment
		(start 190.518796 -164.779706)
		(end 190.518796 -162.3314)
		(width 0.1524)
		(layer "In4.Cu")
		(net "FM_PWRGD_P1V8_RETIMER_CPU0")
	)
	(segment
		(start 190.721996 -124.044964)
		(end 190.721996 -119.700548)
		(width 0.11684)
		(layer "In4.Cu")
		(net "FM_PWRGD_P1V8_RETIMER_CPU0")
	)
	(segment
		(start 198.660258 -146.974052)
		(end 198.660258 -144.576546)
		(width 0.1524)
		(layer "In4.Cu")
		(net "FM_PWRGD_P1V8_RETIMER_CPU0")
	)
	(segment
		(start 198.660258 -144.576546)
		(end 196.45249 -142.368778)
		(width 0.1524)
		(layer "In4.Cu")
		(net "FM_PWRGD_P1V8_RETIMER_CPU0")
	)
	(segment
		(start 190.170816 -119.451628)
		(end 189.918594 -119.199406)
		(width 0.11684)
		(layer "In4.Cu")
		(net "FM_PWRGD_P1V8_RETIMER_CPU0")
	)
	(segment
		(start 196.669914 -132.161534)
		(end 194.531488 -130.023108)
		(width 0.1524)
		(layer "In4.Cu")
		(net "FM_PWRGD_P1V8_RETIMER_CPU0")
	)
	(segment
		(start 189.918594 -119.199406)
		(end 189.918594 -115.514628)
		(width 0.11684)
		(layer "In4.Cu")
		(net "FM_PWRGD_P1V8_RETIMER_CPU0")
	)
	(segment
		(start 199.8599 -161.790126)
		(end 201.65314 -159.996886)
		(width 0.1524)
		(layer "In4.Cu")
		(net "FM_PWRGD_P1V8_RETIMER_CPU0")
	)
	(segment
		(start 189.918594 -115.514628)
		(end 189.100968 -114.697002)
		(width 0.11684)
		(layer "In4.Cu")
		(net "FM_PWRGD_P1V8_RETIMER_CPU0")
	)
	(segment
		(start 190.721996 -119.700548)
		(end 190.473076 -119.451628)
		(width 0.11684)
		(layer "In4.Cu")
		(net "FM_PWRGD_P1V8_RETIMER_CPU0")
	)
	(segment
		(start 194.531488 -127.854456)
		(end 190.890906 -124.213874)
		(width 0.1524)
		(layer "In4.Cu")
		(net "FM_PWRGD_P1V8_RETIMER_CPU0")
	)
	(segment
		(start 190.890906 -124.213874)
		(end 190.721996 -124.044964)
		(width 0.11684)
		(layer "In4.Cu")
		(net "FM_PWRGD_P1V8_RETIMER_CPU0")
	)
	(segment
		(start 201.65314 -149.966934)
		(end 198.660258 -146.974052)
		(width 0.1524)
		(layer "In4.Cu")
		(net "FM_PWRGD_P1V8_RETIMER_CPU0")
	)
	(segment
		(start 196.45249 -142.368778)
		(end 196.45249 -140.758672)
		(width 0.1524)
		(layer "In4.Cu")
		(net "FM_PWRGD_P1V8_RETIMER_CPU0")
	)
	(segment
		(start 201.65314 -159.996886)
		(end 201.65314 -149.966934)
		(width 0.1524)
		(layer "In4.Cu")
		(net "FM_PWRGD_P1V8_RETIMER_CPU0")
	)
	(segment
		(start 189.100968 -114.697002)
		(end 189.100968 -113.073942)
		(width 0.11684)
		(layer "In4.Cu")
		(net "FM_PWRGD_P1V8_RETIMER_CPU0")
	)
	(segment
		(start 189.100968 -113.073942)
		(end 189.51194 -112.66297)
		(width 0.11684)
		(layer "In4.Cu")
		(net "FM_PWRGD_P1V8_RETIMER_CPU0")
	)
	(segment
		(start 194.531488 -130.023108)
		(end 194.531488 -127.854456)
		(width 0.1524)
		(layer "In4.Cu")
		(net "FM_PWRGD_P1V8_RETIMER_CPU0")
	)
	(segment
		(start 104.250744 -36.11118)
		(end 103.806498 -36.11118)
		(width 0.10668)
		(layer "F.Cu")
		(net "USB_HUB2_TI_TEST")
	)
	(segment
		(start 103.806498 -36.11118)
		(end 103.124 -35.428682)
		(width 0.10668)
		(layer "F.Cu")
		(net "USB_HUB2_TI_TEST")
	)
	(segment
		(start 102.183946 -35.428682)
		(end 101.760528 -35.8521)
		(width 0.10668)
		(layer "F.Cu")
		(net "USB_HUB2_TI_TEST")
	)
	(segment
		(start 103.124 -35.428682)
		(end 102.183946 -35.428682)
		(width 0.10668)
		(layer "F.Cu")
		(net "USB_HUB2_TI_TEST")
	)
	(segment
		(start 104.791764 -36.6522)
		(end 104.250744 -36.11118)
		(width 0.10668)
		(layer "F.Cu")
		(net "USB_HUB2_TI_TEST")
	)
	(via
		(at 103.124 -35.428682)
		(size 0.762)
		(drill 0.381)
		(layers "F.Cu" "B.Cu")
		(net "USB_HUB2_TI_TEST")
	)
	(segment
		(start 205.75905 -133.096)
		(end 206.042006 -133.096)
		(width 0.10668)
		(layer "F.Cu")
		(net "SW_P3V3_EN_R")
	)
	(segment
		(start 208.153 -133.096)
		(end 206.042006 -133.096)
		(width 0.10668)
		(layer "F.Cu")
		(net "SW_P3V3_EN_R")
	)
	(segment
		(start 205.63205 -131.064)
		(end 205.63205 -132.969)
		(width 0.10668)
		(layer "F.Cu")
		(net "SW_P3V3_EN_R")
	)
	(segment
		(start 205.63205 -132.969)
		(end 205.75905 -133.096)
		(width 0.10668)
		(layer "F.Cu")
		(net "SW_P3V3_EN_R")
	)
	(segment
		(start 208.28 -132.27304)
		(end 208.28 -132.969)
		(width 0.10668)
		(layer "F.Cu")
		(net "SW_P3V3_EN_R")
	)
	(segment
		(start 205.63205 -130.048)
		(end 205.63205 -131.064)
		(width 0.10668)
		(layer "F.Cu")
		(net "SW_P3V3_EN_R")
	)
	(segment
		(start 208.28 -132.969)
		(end 208.153 -133.096)
		(width 0.10668)
		(layer "F.Cu")
		(net "SW_P3V3_EN_R")
	)
	(via
		(at 206.042006 -133.096)
		(size 0.762)
		(drill 0.381)
		(layers "F.Cu" "B.Cu")
		(net "SW_P3V3_EN_R")
	)
	(segment
		(start 208.153 -135.382)
		(end 207.630014 -135.382)
		(width 0.10668)
		(layer "F.Cu")
		(net "SW_P3V3_EN_N")
	)
	(segment
		(start 206.14005 -135.763)
		(end 207.249014 -135.763)
		(width 0.10668)
		(layer "F.Cu")
		(net "SW_P3V3_EN_N")
	)
	(segment
		(start 208.28 -134.17296)
		(end 208.28 -135.255)
		(width 0.10668)
		(layer "F.Cu")
		(net "SW_P3V3_EN_N")
	)
	(segment
		(start 207.249014 -135.763)
		(end 207.630014 -135.382)
		(width 0.10668)
		(layer "F.Cu")
		(net "SW_P3V3_EN_N")
	)
	(segment
		(start 207.630014 -134.17296)
		(end 207.630014 -135.382)
		(width 0.10668)
		(layer "F.Cu")
		(net "SW_P3V3_EN_N")
	)
	(segment
		(start 208.28 -135.255)
		(end 208.153 -135.382)
		(width 0.10668)
		(layer "F.Cu")
		(net "SW_P3V3_EN_N")
	)
	(via
		(at 207.630014 -135.382)
		(size 0.762)
		(drill 0.381)
		(layers "F.Cu" "B.Cu")
		(net "SW_P3V3_EN_N")
	)
	(segment
		(start 211.074 -129.13995)
		(end 209.423 -129.13995)
		(width 0.10668)
		(layer "F.Cu")
		(net "SW_P3V3_EN_ISO_R")
	)
	(segment
		(start 209.423 -129.13995)
		(end 208.407 -129.13995)
		(width 0.10668)
		(layer "F.Cu")
		(net "SW_P3V3_EN_ISO_R")
	)
	(segment
		(start 212.44433 -129.13995)
		(end 212.938868 -129.634488)
		(width 0.10668)
		(layer "F.Cu")
		(net "SW_P3V3_EN_ISO_R")
	)
	(segment
		(start 437.766968 -73.388728)
		(end 437.766968 -74.439272)
		(width 0.10668)
		(layer "F.Cu")
		(net "SW_P3V3_EN_ISO_R")
	)
	(segment
		(start 438.294526 -72.86117)
		(end 437.766968 -73.388728)
		(width 0.10668)
		(layer "F.Cu")
		(net "SW_P3V3_EN_ISO_R")
	)
	(segment
		(start 212.938868 -129.634488)
		(end 212.938868 -130.71094)
		(width 0.10668)
		(layer "F.Cu")
		(net "SW_P3V3_EN_ISO_R")
	)
	(segment
		(start 439.565034 -72.86117)
		(end 438.294526 -72.86117)
		(width 0.10668)
		(layer "F.Cu")
		(net "SW_P3V3_EN_ISO_R")
	)
	(segment
		(start 211.074 -129.13995)
		(end 212.44433 -129.13995)
		(width 0.10668)
		(layer "F.Cu")
		(net "SW_P3V3_EN_ISO_R")
	)
	(via
		(at 249.007884 -89.795858)
		(size 0.508)
		(drill 0.254)
		(layers "F.Cu" "B.Cu")
		(net "SW_P3V3_EN_ISO_R")
	)
	(via
		(at 437.766968 -74.439272)
		(size 0.508)
		(drill 0.254)
		(layers "F.Cu" "B.Cu")
		(net "SW_P3V3_EN_ISO_R")
	)
	(via
		(at 212.938868 -130.71094)
		(size 0.508)
		(drill 0.254)
		(layers "F.Cu" "B.Cu")
		(net "SW_P3V3_EN_ISO_R")
	)
	(via
		(at 249.632724 -126.645924)
		(size 0.508)
		(drill 0.254)
		(layers "F.Cu" "B.Cu")
		(net "SW_P3V3_EN_ISO_R")
	)
	(segment
		(start 388.207504 -49.823624)
		(end 422.639998 -49.823624)
		(width 0.11684)
		(layer "In6.Cu")
		(net "SW_P3V3_EN_ISO_R")
	)
	(segment
		(start 435.727856 -62.911482)
		(end 435.727856 -72.40016)
		(width 0.11684)
		(layer "In6.Cu")
		(net "SW_P3V3_EN_ISO_R")
	)
	(segment
		(start 288.881058 -58.701178)
		(end 307.980842 -58.701178)
		(width 0.11684)
		(layer "In6.Cu")
		(net "SW_P3V3_EN_ISO_R")
	)
	(segment
		(start 308.99608 -57.68594)
		(end 380.345188 -57.68594)
		(width 0.11684)
		(layer "In6.Cu")
		(net "SW_P3V3_EN_ISO_R")
	)
	(segment
		(start 248.62028 -89.468706)
		(end 248.62028 -88.29675)
		(width 0.11684)
		(layer "In6.Cu")
		(net "SW_P3V3_EN_ISO_R")
	)
	(segment
		(start 281.39644 -75.29195)
		(end 281.39644 -66.185796)
		(width 0.11684)
		(layer "In6.Cu")
		(net "SW_P3V3_EN_ISO_R")
	)
	(segment
		(start 252.343158 -84.573872)
		(end 272.114518 -84.573872)
		(width 0.11684)
		(layer "In6.Cu")
		(net "SW_P3V3_EN_ISO_R")
	)
	(segment
		(start 422.639998 -49.823624)
		(end 435.727856 -62.911482)
		(width 0.11684)
		(layer "In6.Cu")
		(net "SW_P3V3_EN_ISO_R")
	)
	(segment
		(start 281.39644 -66.185796)
		(end 288.881058 -58.701178)
		(width 0.11684)
		(layer "In6.Cu")
		(net "SW_P3V3_EN_ISO_R")
	)
	(segment
		(start 249.007884 -89.795858)
		(end 248.947432 -89.795858)
		(width 0.11684)
		(layer "In6.Cu")
		(net "SW_P3V3_EN_ISO_R")
	)
	(segment
		(start 248.947432 -89.795858)
		(end 248.62028 -89.468706)
		(width 0.11684)
		(layer "In6.Cu")
		(net "SW_P3V3_EN_ISO_R")
	)
	(segment
		(start 435.727856 -72.40016)
		(end 437.766968 -74.439272)
		(width 0.11684)
		(layer "In6.Cu")
		(net "SW_P3V3_EN_ISO_R")
	)
	(segment
		(start 380.345188 -57.68594)
		(end 388.207504 -49.823624)
		(width 0.11684)
		(layer "In6.Cu")
		(net "SW_P3V3_EN_ISO_R")
	)
	(segment
		(start 307.980842 -58.701178)
		(end 308.99608 -57.68594)
		(width 0.11684)
		(layer "In6.Cu")
		(net "SW_P3V3_EN_ISO_R")
	)
	(segment
		(start 248.62028 -88.29675)
		(end 252.343158 -84.573872)
		(width 0.11684)
		(layer "In6.Cu")
		(net "SW_P3V3_EN_ISO_R")
	)
	(segment
		(start 272.114518 -84.573872)
		(end 281.39644 -75.29195)
		(width 0.11684)
		(layer "In6.Cu")
		(net "SW_P3V3_EN_ISO_R")
	)
	(segment
		(start 248.509282 -108.98759)
		(end 248.509282 -124.482098)
		(width 0.11684)
		(layer "In11.Cu")
		(net "SW_P3V3_EN_ISO_R")
	)
	(segment
		(start 247.268492 -107.7468)
		(end 248.509282 -108.98759)
		(width 0.11684)
		(layer "In11.Cu")
		(net "SW_P3V3_EN_ISO_R")
	)
	(segment
		(start 249.03557 -89.988898)
		(end 247.268492 -91.755976)
		(width 0.11684)
		(layer "In11.Cu")
		(net "SW_P3V3_EN_ISO_R")
	)
	(segment
		(start 248.509282 -124.482098)
		(end 249.632724 -125.60554)
		(width 0.11684)
		(layer "In11.Cu")
		(net "SW_P3V3_EN_ISO_R")
	)
	(segment
		(start 249.007884 -89.795858)
		(end 249.03557 -89.823544)
		(width 0.11684)
		(layer "In11.Cu")
		(net "SW_P3V3_EN_ISO_R")
	)
	(segment
		(start 249.632724 -125.60554)
		(end 249.632724 -126.645924)
		(width 0.11684)
		(layer "In11.Cu")
		(net "SW_P3V3_EN_ISO_R")
	)
	(segment
		(start 247.268492 -91.755976)
		(end 247.268492 -107.7468)
		(width 0.11684)
		(layer "In11.Cu")
		(net "SW_P3V3_EN_ISO_R")
	)
	(segment
		(start 249.03557 -89.823544)
		(end 249.03557 -89.988898)
		(width 0.11684)
		(layer "In11.Cu")
		(net "SW_P3V3_EN_ISO_R")
	)
	(segment
		(start 249.632724 -126.645924)
		(end 247.201182 -129.077466)
		(width 0.11684)
		(layer "In15.Cu")
		(net "SW_P3V3_EN_ISO_R")
	)
	(segment
		(start 219.82684 -130.455924)
		(end 213.19363 -130.455924)
		(width 0.11684)
		(layer "In15.Cu")
		(net "SW_P3V3_EN_ISO_R")
	)
	(segment
		(start 220.447108 -131.076192)
		(end 219.82684 -130.455924)
		(width 0.11684)
		(layer "In15.Cu")
		(net "SW_P3V3_EN_ISO_R")
	)
	(segment
		(start 213.19363 -130.455924)
		(end 212.938868 -130.71094)
		(width 0.11684)
		(layer "In15.Cu")
		(net "SW_P3V3_EN_ISO_R")
	)
	(segment
		(start 247.201182 -129.077466)
		(end 241.220244 -129.077466)
		(width 0.11684)
		(layer "In15.Cu")
		(net "SW_P3V3_EN_ISO_R")
	)
	(segment
		(start 241.220244 -129.077466)
		(end 239.221518 -131.076192)
		(width 0.11684)
		(layer "In15.Cu")
		(net "SW_P3V3_EN_ISO_R")
	)
	(segment
		(start 239.221518 -131.076192)
		(end 220.447108 -131.076192)
		(width 0.11684)
		(layer "In15.Cu")
		(net "SW_P3V3_EN_ISO_R")
	)
	(segment
		(start 208.407 -131.319016)
		(end 208.929986 -131.842002)
		(width 0.10668)
		(layer "F.Cu")
		(net "SW_P3V3_EN_ISO")
	)
	(segment
		(start 208.929986 -131.842002)
		(end 208.929986 -132.27304)
		(width 0.10668)
		(layer "F.Cu")
		(net "SW_P3V3_EN_ISO")
	)
	(segment
		(start 208.407 -129.94005)
		(end 208.407 -130.892042)
		(width 0.10668)
		(layer "F.Cu")
		(net "SW_P3V3_EN_ISO")
	)
	(segment
		(start 208.407 -130.892042)
		(end 208.407 -131.319016)
		(width 0.10668)
		(layer "F.Cu")
		(net "SW_P3V3_EN_ISO")
	)
	(via
		(at 208.407 -130.892042)
		(size 0.762)
		(drill 0.381)
		(layers "F.Cu" "B.Cu")
		(net "SW_P3V3_EN_ISO")
	)
	(segment
		(start 165.912038 -130.579368)
		(end 165.584632 -130.579368)
		(width 0.10668)
		(layer "F.Cu")
		(net "PWRGD_P5V_R_N")
	)
	(segment
		(start 166.170356 -130.32105)
		(end 165.912038 -130.579368)
		(width 0.10668)
		(layer "F.Cu")
		(net "PWRGD_P5V_R_N")
	)
	(segment
		(start 164.888164 -130.199638)
		(end 165.267894 -130.579368)
		(width 0.10668)
		(layer "F.Cu")
		(net "PWRGD_P5V_R_N")
	)
	(segment
		(start 164.333936 -130.199638)
		(end 164.888164 -130.199638)
		(width 0.10668)
		(layer "F.Cu")
		(net "PWRGD_P5V_R_N")
	)
	(segment
		(start 165.267894 -130.579368)
		(end 165.584632 -130.579368)
		(width 0.10668)
		(layer "F.Cu")
		(net "PWRGD_P5V_R_N")
	)
	(segment
		(start 166.624 -130.32105)
		(end 166.170356 -130.32105)
		(width 0.10668)
		(layer "F.Cu")
		(net "PWRGD_P5V_R_N")
	)
	(segment
		(start 166.624 -131.55295)
		(end 166.624 -130.32105)
		(width 0.10668)
		(layer "F.Cu")
		(net "PWRGD_P5V_R_N")
	)
	(via
		(at 165.584632 -130.579368)
		(size 0.762)
		(drill 0.381)
		(layers "F.Cu" "B.Cu")
		(net "PWRGD_P5V_R_N")
	)
	(segment
		(start 163.30295 -123.952)
		(end 163.30295 -126.13005)
		(width 0.10668)
		(layer "F.Cu")
		(net "PWRGD_P5V_R2")
	)
	(segment
		(start 161.097976 -128.335024)
		(end 161.097976 -128.895602)
		(width 0.10668)
		(layer "F.Cu")
		(net "PWRGD_P5V_R2")
	)
	(segment
		(start 162.433 -127)
		(end 161.930588 -127.502412)
		(width 0.10668)
		(layer "F.Cu")
		(net "PWRGD_P5V_R2")
	)
	(segment
		(start 163.068 -126.746)
		(end 162.814 -127)
		(width 0.10668)
		(layer "F.Cu")
		(net "PWRGD_P5V_R2")
	)
	(segment
		(start 161.10204 -128.899666)
		(end 162.434016 -128.899666)
		(width 0.10668)
		(layer "F.Cu")
		(net "PWRGD_P5V_R2")
	)
	(segment
		(start 163.068 -126.365)
		(end 163.068 -126.746)
		(width 0.10668)
		(layer "F.Cu")
		(net "PWRGD_P5V_R2")
	)
	(segment
		(start 163.30295 -126.13005)
		(end 163.068 -126.365)
		(width 0.10668)
		(layer "F.Cu")
		(net "PWRGD_P5V_R2")
	)
	(segment
		(start 161.930588 -127.502412)
		(end 161.097976 -128.335024)
		(width 0.10668)
		(layer "F.Cu")
		(net "PWRGD_P5V_R2")
	)
	(segment
		(start 161.097976 -128.895602)
		(end 161.10204 -128.899666)
		(width 0.10668)
		(layer "F.Cu")
		(net "PWRGD_P5V_R2")
	)
	(segment
		(start 162.814 -127)
		(end 162.433 -127)
		(width 0.10668)
		(layer "F.Cu")
		(net "PWRGD_P5V_R2")
	)
	(via
		(at 161.930588 -127.502412)
		(size 0.762)
		(drill 0.381)
		(layers "F.Cu" "B.Cu")
		(net "PWRGD_P5V_R2")
	)
	(segment
		(start 163.355528 -131.71551)
		(end 163.401502 -131.761484)
		(width 0.10668)
		(layer "F.Cu")
		(net "PWRGD_P5V_R1")
	)
	(segment
		(start 162.434016 -129.549652)
		(end 162.443668 -129.54)
		(width 0.10668)
		(layer "F.Cu")
		(net "PWRGD_P5V_R1")
	)
	(segment
		(start 163.593018 -131.953)
		(end 163.401502 -131.761484)
		(width 0.10668)
		(layer "F.Cu")
		(net "PWRGD_P5V_R1")
	)
	(segment
		(start 163.068 -129.54)
		(end 163.355528 -129.827528)
		(width 0.10668)
		(layer "F.Cu")
		(net "PWRGD_P5V_R1")
	)
	(segment
		(start 163.355528 -129.827528)
		(end 163.355528 -131.71551)
		(width 0.10668)
		(layer "F.Cu")
		(net "PWRGD_P5V_R1")
	)
	(segment
		(start 162.443668 -129.54)
		(end 163.068 -129.54)
		(width 0.10668)
		(layer "F.Cu")
		(net "PWRGD_P5V_R1")
	)
	(segment
		(start 164.31895 -131.953)
		(end 163.593018 -131.953)
		(width 0.10668)
		(layer "F.Cu")
		(net "PWRGD_P5V_R1")
	)
	(via
		(at 163.401502 -131.761484)
		(size 0.762)
		(drill 0.381)
		(layers "F.Cu" "B.Cu")
		(net "PWRGD_P5V_R1")
	)
	(segment
		(start 165.11905 -131.953)
		(end 165.11905 -132.73405)
		(width 0.10668)
		(layer "F.Cu")
		(net "PWRGD_P5V_R")
	)
	(segment
		(start 204.83195 -131.064)
		(end 204.83195 -133.75005)
		(width 0.10668)
		(layer "F.Cu")
		(net "PWRGD_P5V_R")
	)
	(segment
		(start 168.499028 -133.974078)
		(end 168.499028 -133.02996)
		(width 0.10668)
		(layer "F.Cu")
		(net "PWRGD_P5V_R")
	)
	(segment
		(start 203.327 -135.255)
		(end 203.327 -137.287)
		(width 0.10668)
		(layer "F.Cu")
		(net "PWRGD_P5V_R")
	)
	(segment
		(start 165.41496 -133.02996)
		(end 168.499028 -133.02996)
		(width 0.10668)
		(layer "F.Cu")
		(net "PWRGD_P5V_R")
	)
	(segment
		(start 204.83195 -133.75005)
		(end 203.327 -135.255)
		(width 0.10668)
		(layer "F.Cu")
		(net "PWRGD_P5V_R")
	)
	(segment
		(start 169.01795 -135.509)
		(end 169.01795 -134.493)
		(width 0.10668)
		(layer "F.Cu")
		(net "PWRGD_P5V_R")
	)
	(segment
		(start 169.01795 -136.398)
		(end 169.01795 -135.509)
		(width 0.10668)
		(layer "F.Cu")
		(net "PWRGD_P5V_R")
	)
	(segment
		(start 165.11905 -132.73405)
		(end 165.41496 -133.02996)
		(width 0.10668)
		(layer "F.Cu")
		(net "PWRGD_P5V_R")
	)
	(segment
		(start 169.01795 -134.493)
		(end 168.499028 -133.974078)
		(width 0.10668)
		(layer "F.Cu")
		(net "PWRGD_P5V_R")
	)
	(via
		(at 203.327 -137.287)
		(size 0.508)
		(drill 0.254)
		(layers "F.Cu" "B.Cu")
		(net "PWRGD_P5V_R")
	)
	(via
		(at 169.01795 -136.398)
		(size 0.508)
		(drill 0.254)
		(layers "F.Cu" "B.Cu")
		(net "PWRGD_P5V_R")
	)
	(segment
		(start 202.565 -138.049)
		(end 203.327 -137.287)
		(width 0.11684)
		(layer "In6.Cu")
		(net "PWRGD_P5V_R")
	)
	(segment
		(start 169.01795 -136.398)
		(end 171.68495 -139.065)
		(width 0.11684)
		(layer "In6.Cu")
		(net "PWRGD_P5V_R")
	)
	(segment
		(start 187.579 -138.176)
		(end 187.706 -138.049)
		(width 0.11684)
		(layer "In6.Cu")
		(net "PWRGD_P5V_R")
	)
	(segment
		(start 187.579 -138.938)
		(end 187.579 -138.176)
		(width 0.11684)
		(layer "In6.Cu")
		(net "PWRGD_P5V_R")
	)
	(segment
		(start 187.198 -139.319)
		(end 187.579 -138.938)
		(width 0.11684)
		(layer "In6.Cu")
		(net "PWRGD_P5V_R")
	)
	(segment
		(start 187.706 -138.049)
		(end 202.565 -138.049)
		(width 0.11684)
		(layer "In6.Cu")
		(net "PWRGD_P5V_R")
	)
	(segment
		(start 175.494696 -139.573)
		(end 184.531 -139.573)
		(width 0.11684)
		(layer "In6.Cu")
		(net "PWRGD_P5V_R")
	)
	(segment
		(start 184.785 -139.319)
		(end 187.198 -139.319)
		(width 0.11684)
		(layer "In6.Cu")
		(net "PWRGD_P5V_R")
	)
	(segment
		(start 174.986696 -139.065)
		(end 175.494696 -139.573)
		(width 0.11684)
		(layer "In6.Cu")
		(net "PWRGD_P5V_R")
	)
	(segment
		(start 184.531 -139.573)
		(end 184.785 -139.319)
		(width 0.11684)
		(layer "In6.Cu")
		(net "PWRGD_P5V_R")
	)
	(segment
		(start 171.68495 -139.065)
		(end 174.986696 -139.065)
		(width 0.11684)
		(layer "In6.Cu")
		(net "PWRGD_P5V_R")
	)
	(segment
		(start 164.641784 -129.54)
		(end 165.058598 -129.54)
		(width 0.10668)
		(layer "F.Cu")
		(net "PWRGD_P5V_N")
	)
	(segment
		(start 166.091616 -129.52095)
		(end 165.584632 -129.013966)
		(width 0.10668)
		(layer "F.Cu")
		(net "PWRGD_P5V_N")
	)
	(segment
		(start 164.333936 -129.549652)
		(end 164.632132 -129.549652)
		(width 0.10668)
		(layer "F.Cu")
		(net "PWRGD_P5V_N")
	)
	(segment
		(start 164.632132 -129.549652)
		(end 164.641784 -129.54)
		(width 0.10668)
		(layer "F.Cu")
		(net "PWRGD_P5V_N")
	)
	(segment
		(start 165.058598 -129.54)
		(end 165.584632 -129.013966)
		(width 0.10668)
		(layer "F.Cu")
		(net "PWRGD_P5V_N")
	)
	(segment
		(start 166.624 -129.52095)
		(end 166.091616 -129.52095)
		(width 0.10668)
		(layer "F.Cu")
		(net "PWRGD_P5V_N")
	)
	(via
		(at 165.584632 -129.013966)
		(size 0.762)
		(drill 0.381)
		(layers "F.Cu" "B.Cu")
		(net "PWRGD_P5V_N")
	)
	(segment
		(start 164.10305 -123.952)
		(end 164.39896 -123.952)
		(width 0.10668)
		(layer "F.Cu")
		(net "PWRGD_P5V")
	)
	(segment
		(start 164.39896 -123.952)
		(end 164.973 -124.52604)
		(width 0.10668)
		(layer "F.Cu")
		(net "PWRGD_P5V")
	)
	(segment
		(start 177.122074 -118.652798)
		(end 176.732184 -119.042688)
		(width 0.10668)
		(layer "F.Cu")
		(net "PWRGD_P5V")
	)
	(via
		(at 164.973 -124.52604)
		(size 0.508)
		(drill 0.254)
		(layers "F.Cu" "B.Cu")
		(net "PWRGD_P5V")
	)
	(via
		(at 176.732184 -119.042688)
		(size 0.4572)
		(drill 0.254)
		(layers "F.Cu" "B.Cu")
		(net "PWRGD_P5V")
	)
	(segment
		(start 175.26 -121.92)
		(end 172.085 -121.92)
		(width 0.11684)
		(layer "In4.Cu")
		(net "PWRGD_P5V")
	)
	(segment
		(start 176.486312 -119.042688)
		(end 176.149 -119.38)
		(width 0.11684)
		(layer "In4.Cu")
		(net "PWRGD_P5V")
	)
	(segment
		(start 170.24096 -124.52604)
		(end 164.973 -124.52604)
		(width 0.11684)
		(layer "In4.Cu")
		(net "PWRGD_P5V")
	)
	(segment
		(start 171.704 -122.301)
		(end 171.704 -123.063)
		(width 0.11684)
		(layer "In4.Cu")
		(net "PWRGD_P5V")
	)
	(segment
		(start 171.704 -123.063)
		(end 170.24096 -124.52604)
		(width 0.11684)
		(layer "In4.Cu")
		(net "PWRGD_P5V")
	)
	(segment
		(start 172.085 -121.92)
		(end 171.704 -122.301)
		(width 0.11684)
		(layer "In4.Cu")
		(net "PWRGD_P5V")
	)
	(segment
		(start 176.732184 -119.042688)
		(end 176.486312 -119.042688)
		(width 0.11684)
		(layer "In4.Cu")
		(net "PWRGD_P5V")
	)
	(segment
		(start 176.149 -119.38)
		(end 176.149 -121.031)
		(width 0.11684)
		(layer "In4.Cu")
		(net "PWRGD_P5V")
	)
	(segment
		(start 176.149 -121.031)
		(end 175.26 -121.92)
		(width 0.11684)
		(layer "In4.Cu")
		(net "PWRGD_P5V")
	)
	(segment
		(start 115.180364 -124.400564)
		(end 113.713514 -124.400564)
		(width 0.10668)
		(layer "F.Cu")
		(net "PWRGD_P3V3_EN_R")
	)
	(segment
		(start 115.181888 -124.39904)
		(end 115.180364 -124.400564)
		(width 0.10668)
		(layer "F.Cu")
		(net "PWRGD_P3V3_EN_R")
	)
	(segment
		(start 111.633 -125.32995)
		(end 111.633 -124.35205)
		(width 0.10668)
		(layer "F.Cu")
		(net "PWRGD_P3V3_EN_R")
	)
	(segment
		(start 113.665 -124.35205)
		(end 112.649 -124.35205)
		(width 0.10668)
		(layer "F.Cu")
		(net "PWRGD_P3V3_EN_R")
	)
	(segment
		(start 111.633 -124.35205)
		(end 112.649 -124.35205)
		(width 0.10668)
		(layer "F.Cu")
		(net "PWRGD_P3V3_EN_R")
	)
	(segment
		(start 113.713514 -124.400564)
		(end 113.665 -124.35205)
		(width 0.10668)
		(layer "F.Cu")
		(net "PWRGD_P3V3_EN_R")
	)
	(via
		(at 113.713514 -124.400564)
		(size 0.762)
		(drill 0.381)
		(layers "F.Cu" "B.Cu")
		(net "PWRGD_P3V3_EN_R")
	)
	(segment
		(start 98.994722 -121.910602)
		(end 99.81692 -121.088404)
		(width 0.10668)
		(layer "F.Cu")
		(net "PU_U38_6")
	)
	(segment
		(start 98.994722 -122.52833)
		(end 98.994722 -121.910602)
		(width 0.10668)
		(layer "F.Cu")
		(net "PU_U38_6")
	)
	(segment
		(start 99.917504 -119.957088)
		(end 100.203 -120.242584)
		(width 0.10668)
		(layer "F.Cu")
		(net "PU_U38_6")
	)
	(segment
		(start 99.81692 -121.088404)
		(end 100.122736 -121.088404)
		(width 0.10668)
		(layer "F.Cu")
		(net "PU_U38_6")
	)
	(segment
		(start 100.203 -120.242584)
		(end 100.203 -121.00814)
		(width 0.10668)
		(layer "F.Cu")
		(net "PU_U38_6")
	)
	(segment
		(start 100.203 -121.00814)
		(end 100.122736 -121.088404)
		(width 0.10668)
		(layer "F.Cu")
		(net "PU_U38_6")
	)
	(via
		(at 100.122736 -121.088404)
		(size 0.762)
		(drill 0.381)
		(layers "F.Cu" "B.Cu")
		(net "PU_U38_6")
	)
	(segment
		(start 125.570488 -389.467344)
		(end 126.091188 -389.467344)
		(width 0.127)
		(layer "F.Cu")
		(net "P5E_CPU1_P3_TX_BUF_DP<9>")
	)
	(segment
		(start 144.587976 -407.954734)
		(end 144.587976 -407.27503)
		(width 0.12954)
		(layer "B.Cu")
		(net "P5E_CPU1_P3_TX_BUF_DP<9>")
	)
	(segment
		(start 144.883886 -408.250644)
		(end 144.587976 -407.954734)
		(width 0.12954)
		(layer "B.Cu")
		(net "P5E_CPU1_P3_TX_BUF_DP<9>")
	)
	(segment
		(start 144.587976 -407.27503)
		(end 144.858486 -407.00452)
		(width 0.12954)
		(layer "B.Cu")
		(net "P5E_CPU1_P3_TX_BUF_DP<9>")
	)
	(segment
		(start 141.961108 -402.124418)
		(end 142.35557 -402.28774)
		(width 0.14224)
		(layer "In6.Cu")
		(net "P5E_CPU1_P3_TX_BUF_DP<9>")
	)
	(segment
		(start 142.429738 -402.467318)
		(end 142.429738 -402.467064)
		(width 0.14224)
		(layer "In6.Cu")
		(net "P5E_CPU1_P3_TX_BUF_DP<9>")
	)
	(segment
		(start 142.429992 -402.467064)
		(end 142.8242 -402.630386)
		(width 0.14224)
		(layer "In6.Cu")
		(net "P5E_CPU1_P3_TX_BUF_DP<9>")
	)
	(segment
		(start 142.8242 -402.630386)
		(end 143.00327 -402.555964)
		(width 0.14224)
		(layer "In6.Cu")
		(net "P5E_CPU1_P3_TX_BUF_DP<9>")
	)
	(segment
		(start 142.429992 -402.467318)
		(end 142.429992 -402.467064)
		(width 0.14224)
		(layer "In6.Cu")
		(net "P5E_CPU1_P3_TX_BUF_DP<9>")
	)
	(segment
		(start 125.706886 -389.441944)
		(end 125.706886 -389.486902)
		(width 0.14224)
		(layer "In6.Cu")
		(net "P5E_CPU1_P3_TX_BUF_DP<9>")
	)
	(segment
		(start 142.35557 -402.28774)
		(end 142.429738 -402.467318)
		(width 0.14224)
		(layer "In6.Cu")
		(net "P5E_CPU1_P3_TX_BUF_DP<9>")
	)
	(segment
		(start 125.819662 -389.758936)
		(end 125.93574 -389.875014)
		(width 0.14224)
		(layer "In6.Cu")
		(net "P5E_CPU1_P3_TX_BUF_DP<9>")
	)
	(segment
		(start 141.782038 -402.198586)
		(end 141.961108 -402.124418)
		(width 0.14224)
		(layer "In6.Cu")
		(net "P5E_CPU1_P3_TX_BUF_DP<9>")
	)
	(segment
		(start 134.011416 -399.601436)
		(end 139.61618 -401.301458)
		(width 0.14224)
		(layer "In6.Cu")
		(net "P5E_CPU1_P3_TX_BUF_DP<9>")
	)
	(segment
		(start 144.089882 -403.154896)
		(end 144.201134 -403.266148)
		(width 0.14224)
		(layer "In6.Cu")
		(net "P5E_CPU1_P3_TX_BUF_DP<9>")
	)
	(segment
		(start 141.38783 -402.035518)
		(end 141.782038 -402.198586)
		(width 0.14224)
		(layer "In6.Cu")
		(net "P5E_CPU1_P3_TX_BUF_DP<9>")
	)
	(segment
		(start 126.073916 -390.56183)
		(end 126.345696 -391.453878)
		(width 0.14224)
		(layer "In6.Cu")
		(net "P5E_CPU1_P3_TX_BUF_DP<9>")
	)
	(segment
		(start 140.9192 -401.692872)
		(end 141.313662 -401.856194)
		(width 0.14224)
		(layer "In6.Cu")
		(net "P5E_CPU1_P3_TX_BUF_DP<9>")
	)
	(segment
		(start 140.74013 -401.76704)
		(end 140.9192 -401.692872)
		(width 0.14224)
		(layer "In6.Cu")
		(net "P5E_CPU1_P3_TX_BUF_DP<9>")
	)
	(segment
		(start 143.397732 -402.71954)
		(end 143.4719 -402.898864)
		(width 0.14224)
		(layer "In6.Cu")
		(net "P5E_CPU1_P3_TX_BUF_DP<9>")
	)
	(segment
		(start 139.61618 -401.301458)
		(end 140.74013 -401.76704)
		(width 0.14224)
		(layer "In6.Cu")
		(net "P5E_CPU1_P3_TX_BUF_DP<9>")
	)
	(segment
		(start 143.00327 -402.555964)
		(end 143.397732 -402.71954)
		(width 0.14224)
		(layer "In6.Cu")
		(net "P5E_CPU1_P3_TX_BUF_DP<9>")
	)
	(segment
		(start 126.468632 -392.004042)
		(end 126.468632 -395.68247)
		(width 0.14224)
		(layer "In6.Cu")
		(net "P5E_CPU1_P3_TX_BUF_DP<9>")
	)
	(segment
		(start 144.567656 -404.15083)
		(end 144.567656 -406.71369)
		(width 0.14224)
		(layer "In6.Cu")
		(net "P5E_CPU1_P3_TX_BUF_DP<9>")
	)
	(segment
		(start 141.313662 -401.856194)
		(end 141.38783 -402.035518)
		(width 0.14224)
		(layer "In6.Cu")
		(net "P5E_CPU1_P3_TX_BUF_DP<9>")
	)
	(segment
		(start 125.97638 -389.352536)
		(end 125.796294 -389.352536)
		(width 0.14224)
		(layer "In6.Cu")
		(net "P5E_CPU1_P3_TX_BUF_DP<9>")
	)
	(segment
		(start 126.345696 -391.453878)
		(end 126.411736 -391.651744)
		(width 0.14224)
		(layer "In6.Cu")
		(net "P5E_CPU1_P3_TX_BUF_DP<9>")
	)
	(segment
		(start 126.091188 -389.467344)
		(end 125.97638 -389.352536)
		(width 0.14224)
		(layer "In6.Cu")
		(net "P5E_CPU1_P3_TX_BUF_DP<9>")
	)
	(segment
		(start 126.065534 -390.188704)
		(end 126.065534 -390.505442)
		(width 0.14224)
		(layer "In6.Cu")
		(net "P5E_CPU1_P3_TX_BUF_DP<9>")
	)
	(segment
		(start 143.4719 -402.898864)
		(end 144.089882 -403.154896)
		(width 0.14224)
		(layer "In6.Cu")
		(net "P5E_CPU1_P3_TX_BUF_DP<9>")
	)
	(segment
		(start 142.429738 -402.467064)
		(end 142.429992 -402.467318)
		(width 0.14224)
		(layer "In6.Cu")
		(net "P5E_CPU1_P3_TX_BUF_DP<9>")
	)
	(segment
		(start 131.059936 -398.861788)
		(end 134.011416 -399.601436)
		(width 0.14224)
		(layer "In6.Cu")
		(net "P5E_CPU1_P3_TX_BUF_DP<9>")
	)
	(segment
		(start 126.627636 -395.995144)
		(end 128.606804 -397.974312)
		(width 0.14224)
		(layer "In6.Cu")
		(net "P5E_CPU1_P3_TX_BUF_DP<9>")
	)
	(segment
		(start 125.796294 -389.352536)
		(end 125.706886 -389.441944)
		(width 0.14224)
		(layer "In6.Cu")
		(net "P5E_CPU1_P3_TX_BUF_DP<9>")
	)
	(segment
		(start 129.79781 -398.610836)
		(end 131.059936 -398.861788)
		(width 0.14224)
		(layer "In6.Cu")
		(net "P5E_CPU1_P3_TX_BUF_DP<9>")
	)
	(segment
		(start 144.567656 -406.71369)
		(end 144.858486 -407.00452)
		(width 0.14224)
		(layer "In6.Cu")
		(net "P5E_CPU1_P3_TX_BUF_DP<9>")
	)
	(arc
		(start 125.93574 -389.875014)
		(mid 126.031876 -390.018937)
		(end 126.065534 -390.188704)
		(width 0.14224)
		(layer "In6.Cu")
		(net "P5E_CPU1_P3_TX_BUF_DP<9>")
	)
	(arc
		(start 125.706886 -389.486902)
		(mid 125.736193 -389.634148)
		(end 125.819662 -389.758936)
		(width 0.14224)
		(layer "In6.Cu")
		(net "P5E_CPU1_P3_TX_BUF_DP<9>")
	)
	(arc
		(start 126.065534 -390.505442)
		(mid 126.067647 -390.533944)
		(end 126.073916 -390.56183)
		(width 0.14224)
		(layer "In6.Cu")
		(net "P5E_CPU1_P3_TX_BUF_DP<9>")
	)
	(arc
		(start 126.411736 -391.651744)
		(mid 126.454308 -391.825612)
		(end 126.468632 -392.004042)
		(width 0.14224)
		(layer "In6.Cu")
		(net "P5E_CPU1_P3_TX_BUF_DP<9>")
	)
	(arc
		(start 144.201134 -403.266148)
		(mid 144.472398 -403.672029)
		(end 144.567656 -404.15083)
		(width 0.14224)
		(layer "In6.Cu")
		(net "P5E_CPU1_P3_TX_BUF_DP<9>")
	)
	(arc
		(start 126.51867 -395.857984)
		(mid 126.56918 -395.929721)
		(end 126.627636 -395.995144)
		(width 0.14224)
		(layer "In6.Cu")
		(net "P5E_CPU1_P3_TX_BUF_DP<9>")
	)
	(arc
		(start 126.468632 -395.68247)
		(mid 126.481342 -395.773739)
		(end 126.51867 -395.857984)
		(width 0.14224)
		(layer "In6.Cu")
		(net "P5E_CPU1_P3_TX_BUF_DP<9>")
	)
	(arc
		(start 128.606804 -397.974312)
		(mid 129.155086 -398.380936)
		(end 129.79781 -398.610836)
		(width 0.14224)
		(layer "In6.Cu")
		(net "P5E_CPU1_P3_TX_BUF_DP<9>")
	)
	(segment
		(start 124.370592 -389.467344)
		(end 124.891292 -389.467344)
		(width 0.127)
		(layer "F.Cu")
		(net "P5E_CPU1_P3_TX_BUF_DP<8>")
	)
	(segment
		(start 141.524736 -407.27503)
		(end 141.795246 -407.00452)
		(width 0.12954)
		(layer "B.Cu")
		(net "P5E_CPU1_P3_TX_BUF_DP<8>")
	)
	(segment
		(start 141.820646 -408.250644)
		(end 141.524736 -407.954734)
		(width 0.12954)
		(layer "B.Cu")
		(net "P5E_CPU1_P3_TX_BUF_DP<8>")
	)
	(segment
		(start 141.524736 -407.954734)
		(end 141.524736 -407.27503)
		(width 0.12954)
		(layer "B.Cu")
		(net "P5E_CPU1_P3_TX_BUF_DP<8>")
	)
	(segment
		(start 124.776484 -389.352536)
		(end 124.58319 -389.352536)
		(width 0.14224)
		(layer "In6.Cu")
		(net "P5E_CPU1_P3_TX_BUF_DP<8>")
	)
	(segment
		(start 133.68147 -400.484848)
		(end 136.748774 -401.41525)
		(width 0.14224)
		(layer "In6.Cu")
		(net "P5E_CPU1_P3_TX_BUF_DP<8>")
	)
	(segment
		(start 140.43025 -402.940266)
		(end 140.917168 -403.141942)
		(width 0.14224)
		(layer "In6.Cu")
		(net "P5E_CPU1_P3_TX_BUF_DP<8>")
	)
	(segment
		(start 125.358652 -395.0843)
		(end 125.221492 -395.22146)
		(width 0.14224)
		(layer "In6.Cu")
		(net "P5E_CPU1_P3_TX_BUF_DP<8>")
	)
	(segment
		(start 125.358652 -394.65758)
		(end 125.358652 -395.0843)
		(width 0.14224)
		(layer "In6.Cu")
		(net "P5E_CPU1_P3_TX_BUF_DP<8>")
	)
	(segment
		(start 141.504416 -404.15464)
		(end 141.504416 -406.71369)
		(width 0.14224)
		(layer "In6.Cu")
		(net "P5E_CPU1_P3_TX_BUF_DP<8>")
	)
	(segment
		(start 125.221492 -395.22146)
		(end 125.221492 -395.683994)
		(width 0.14224)
		(layer "In6.Cu")
		(net "P5E_CPU1_P3_TX_BUF_DP<8>")
	)
	(segment
		(start 138.616182 -402.188934)
		(end 139.782296 -402.671788)
		(width 0.14224)
		(layer "In6.Cu")
		(net "P5E_CPU1_P3_TX_BUF_DP<8>")
	)
	(segment
		(start 137.968228 -401.920456)
		(end 138.147552 -401.846034)
		(width 0.14224)
		(layer "In6.Cu")
		(net "P5E_CPU1_P3_TX_BUF_DP<8>")
	)
	(segment
		(start 125.221492 -394.52042)
		(end 125.358652 -394.65758)
		(width 0.14224)
		(layer "In6.Cu")
		(net "P5E_CPU1_P3_TX_BUF_DP<8>")
	)
	(segment
		(start 138.147552 -401.846034)
		(end 138.542014 -402.009356)
		(width 0.14224)
		(layer "In6.Cu")
		(net "P5E_CPU1_P3_TX_BUF_DP<8>")
	)
	(segment
		(start 124.621798 -389.760968)
		(end 124.724668 -389.863838)
		(width 0.14224)
		(layer "In6.Cu")
		(net "P5E_CPU1_P3_TX_BUF_DP<8>")
	)
	(segment
		(start 136.748774 -401.41525)
		(end 137.968228 -401.920456)
		(width 0.14224)
		(layer "In6.Cu")
		(net "P5E_CPU1_P3_TX_BUF_DP<8>")
	)
	(segment
		(start 125.385322 -396.079472)
		(end 128.021588 -398.715738)
		(width 0.14224)
		(layer "In6.Cu")
		(net "P5E_CPU1_P3_TX_BUF_DP<8>")
	)
	(segment
		(start 129.494534 -399.503138)
		(end 130.802634 -399.763234)
		(width 0.14224)
		(layer "In6.Cu")
		(net "P5E_CPU1_P3_TX_BUF_DP<8>")
	)
	(segment
		(start 124.873004 -390.466072)
		(end 125.221492 -391.616438)
		(width 0.14224)
		(layer "In6.Cu")
		(net "P5E_CPU1_P3_TX_BUF_DP<8>")
	)
	(segment
		(start 138.542014 -402.009356)
		(end 138.616182 -402.188934)
		(width 0.14224)
		(layer "In6.Cu")
		(net "P5E_CPU1_P3_TX_BUF_DP<8>")
	)
	(segment
		(start 124.58319 -389.352536)
		(end 124.50699 -389.428736)
		(width 0.14224)
		(layer "In6.Cu")
		(net "P5E_CPU1_P3_TX_BUF_DP<8>")
	)
	(segment
		(start 124.891292 -389.467344)
		(end 124.776484 -389.352536)
		(width 0.14224)
		(layer "In6.Cu")
		(net "P5E_CPU1_P3_TX_BUF_DP<8>")
	)
	(segment
		(start 124.854462 -390.177528)
		(end 124.854462 -390.341358)
		(width 0.14224)
		(layer "In6.Cu")
		(net "P5E_CPU1_P3_TX_BUF_DP<8>")
	)
	(segment
		(start 139.961366 -402.59762)
		(end 140.355828 -402.760942)
		(width 0.14224)
		(layer "In6.Cu")
		(net "P5E_CPU1_P3_TX_BUF_DP<8>")
	)
	(segment
		(start 139.782296 -402.671788)
		(end 139.961366 -402.59762)
		(width 0.14224)
		(layer "In6.Cu")
		(net "P5E_CPU1_P3_TX_BUF_DP<8>")
	)
	(segment
		(start 140.917168 -403.141942)
		(end 141.203426 -403.4282)
		(width 0.14224)
		(layer "In6.Cu")
		(net "P5E_CPU1_P3_TX_BUF_DP<8>")
	)
	(segment
		(start 125.221492 -391.616438)
		(end 125.221492 -394.52042)
		(width 0.14224)
		(layer "In6.Cu")
		(net "P5E_CPU1_P3_TX_BUF_DP<8>")
	)
	(segment
		(start 130.802634 -399.763234)
		(end 133.68147 -400.484848)
		(width 0.14224)
		(layer "In6.Cu")
		(net "P5E_CPU1_P3_TX_BUF_DP<8>")
	)
	(segment
		(start 141.504416 -406.71369)
		(end 141.795246 -407.00452)
		(width 0.14224)
		(layer "In6.Cu")
		(net "P5E_CPU1_P3_TX_BUF_DP<8>")
	)
	(segment
		(start 140.355828 -402.760942)
		(end 140.43025 -402.940266)
		(width 0.14224)
		(layer "In6.Cu")
		(net "P5E_CPU1_P3_TX_BUF_DP<8>")
	)
	(segment
		(start 124.50699 -389.428736)
		(end 124.50699 -389.484108)
		(width 0.14224)
		(layer "In6.Cu")
		(net "P5E_CPU1_P3_TX_BUF_DP<8>")
	)
	(arc
		(start 124.724668 -389.863838)
		(mid 124.820804 -390.007761)
		(end 124.854462 -390.177528)
		(width 0.14224)
		(layer "In6.Cu")
		(net "P5E_CPU1_P3_TX_BUF_DP<8>")
	)
	(arc
		(start 128.021588 -398.715738)
		(mid 128.699675 -399.218648)
		(end 129.494534 -399.503138)
		(width 0.14224)
		(layer "In6.Cu")
		(net "P5E_CPU1_P3_TX_BUF_DP<8>")
	)
	(arc
		(start 124.854462 -390.341358)
		(mid 124.859143 -390.404397)
		(end 124.873004 -390.466072)
		(width 0.14224)
		(layer "In6.Cu")
		(net "P5E_CPU1_P3_TX_BUF_DP<8>")
	)
	(arc
		(start 124.50699 -389.484108)
		(mid 124.536834 -389.633964)
		(end 124.621798 -389.760968)
		(width 0.14224)
		(layer "In6.Cu")
		(net "P5E_CPU1_P3_TX_BUF_DP<8>")
	)
	(arc
		(start 141.203426 -403.4282)
		(mid 141.426179 -403.761479)
		(end 141.504416 -404.15464)
		(width 0.14224)
		(layer "In6.Cu")
		(net "P5E_CPU1_P3_TX_BUF_DP<8>")
	)
	(arc
		(start 125.221492 -395.683994)
		(mid 125.264052 -395.898046)
		(end 125.385322 -396.079472)
		(width 0.14224)
		(layer "In6.Cu")
		(net "P5E_CPU1_P3_TX_BUF_DP<8>")
	)
	(segment
		(start 123.170442 -389.467344)
		(end 123.691142 -389.467344)
		(width 0.127)
		(layer "F.Cu")
		(net "P5E_CPU1_P3_TX_BUF_DP<7>")
	)
	(segment
		(start 138.461496 -407.954734)
		(end 138.461496 -407.27503)
		(width 0.12954)
		(layer "B.Cu")
		(net "P5E_CPU1_P3_TX_BUF_DP<7>")
	)
	(segment
		(start 138.757406 -408.250644)
		(end 138.461496 -407.954734)
		(width 0.12954)
		(layer "B.Cu")
		(net "P5E_CPU1_P3_TX_BUF_DP<7>")
	)
	(segment
		(start 138.461496 -407.27503)
		(end 138.732006 -407.00452)
		(width 0.12954)
		(layer "B.Cu")
		(net "P5E_CPU1_P3_TX_BUF_DP<7>")
	)
	(segment
		(start 123.647708 -390.140698)
		(end 123.647708 -390.332976)
		(width 0.14224)
		(layer "In6.Cu")
		(net "P5E_CPU1_P3_TX_BUF_DP<7>")
	)
	(segment
		(start 134.519416 -401.729194)
		(end 135.624316 -402.186902)
		(width 0.14224)
		(layer "In6.Cu")
		(net "P5E_CPU1_P3_TX_BUF_DP<7>")
	)
	(segment
		(start 138.441176 -404.211028)
		(end 138.441176 -406.71369)
		(width 0.14224)
		(layer "In6.Cu")
		(net "P5E_CPU1_P3_TX_BUF_DP<7>")
	)
	(segment
		(start 124.053854 -395.205458)
		(end 124.053854 -395.926564)
		(width 0.14224)
		(layer "In6.Cu")
		(net "P5E_CPU1_P3_TX_BUF_DP<7>")
	)
	(segment
		(start 137.24001 -402.707602)
		(end 137.314178 -402.88718)
		(width 0.14224)
		(layer "In6.Cu")
		(net "P5E_CPU1_P3_TX_BUF_DP<7>")
	)
	(segment
		(start 135.624316 -402.186902)
		(end 135.803386 -402.112734)
		(width 0.14224)
		(layer "In6.Cu")
		(net "P5E_CPU1_P3_TX_BUF_DP<7>")
	)
	(segment
		(start 124.191014 -395.068298)
		(end 124.053854 -395.205458)
		(width 0.14224)
		(layer "In6.Cu")
		(net "P5E_CPU1_P3_TX_BUF_DP<7>")
	)
	(segment
		(start 123.35764 -389.666734)
		(end 123.517914 -389.827008)
		(width 0.14224)
		(layer "In6.Cu")
		(net "P5E_CPU1_P3_TX_BUF_DP<7>")
	)
	(segment
		(start 136.27227 -402.45538)
		(end 136.666478 -402.618448)
		(width 0.14224)
		(layer "In6.Cu")
		(net "P5E_CPU1_P3_TX_BUF_DP<7>")
	)
	(segment
		(start 123.691142 -389.467344)
		(end 123.576334 -389.352536)
		(width 0.14224)
		(layer "In6.Cu")
		(net "P5E_CPU1_P3_TX_BUF_DP<7>")
	)
	(segment
		(start 123.66625 -390.457944)
		(end 124.023374 -391.635742)
		(width 0.14224)
		(layer "In6.Cu")
		(net "P5E_CPU1_P3_TX_BUF_DP<7>")
	)
	(segment
		(start 130.292094 -400.612864)
		(end 133.436614 -401.400772)
		(width 0.14224)
		(layer "In6.Cu")
		(net "P5E_CPU1_P3_TX_BUF_DP<7>")
	)
	(segment
		(start 133.436614 -401.400772)
		(end 134.519416 -401.729194)
		(width 0.14224)
		(layer "In6.Cu")
		(net "P5E_CPU1_P3_TX_BUF_DP<7>")
	)
	(segment
		(start 138.441176 -406.71369)
		(end 138.732006 -407.00452)
		(width 0.14224)
		(layer "In6.Cu")
		(net "P5E_CPU1_P3_TX_BUF_DP<7>")
	)
	(segment
		(start 135.803386 -402.112734)
		(end 136.197848 -402.276056)
		(width 0.14224)
		(layer "In6.Cu")
		(net "P5E_CPU1_P3_TX_BUF_DP<7>")
	)
	(segment
		(start 137.734548 -403.06117)
		(end 138.12774 -403.454362)
		(width 0.14224)
		(layer "In6.Cu")
		(net "P5E_CPU1_P3_TX_BUF_DP<7>")
	)
	(segment
		(start 124.053854 -391.84199)
		(end 124.053854 -394.504418)
		(width 0.14224)
		(layer "In6.Cu")
		(net "P5E_CPU1_P3_TX_BUF_DP<7>")
	)
	(segment
		(start 137.314178 -402.88718)
		(end 137.734548 -403.06117)
		(width 0.14224)
		(layer "In6.Cu")
		(net "P5E_CPU1_P3_TX_BUF_DP<7>")
	)
	(segment
		(start 136.666478 -402.618448)
		(end 136.845548 -402.54428)
		(width 0.14224)
		(layer "In6.Cu")
		(net "P5E_CPU1_P3_TX_BUF_DP<7>")
	)
	(segment
		(start 136.197848 -402.276056)
		(end 136.27227 -402.45538)
		(width 0.14224)
		(layer "In6.Cu")
		(net "P5E_CPU1_P3_TX_BUF_DP<7>")
	)
	(segment
		(start 124.053854 -394.504418)
		(end 124.191014 -394.641578)
		(width 0.14224)
		(layer "In6.Cu")
		(net "P5E_CPU1_P3_TX_BUF_DP<7>")
	)
	(segment
		(start 129.247646 -400.405092)
		(end 130.292094 -400.612864)
		(width 0.14224)
		(layer "In6.Cu")
		(net "P5E_CPU1_P3_TX_BUF_DP<7>")
	)
	(segment
		(start 123.576334 -389.352536)
		(end 123.40971 -389.352536)
		(width 0.14224)
		(layer "In6.Cu")
		(net "P5E_CPU1_P3_TX_BUF_DP<7>")
	)
	(segment
		(start 136.845548 -402.54428)
		(end 137.24001 -402.707602)
		(width 0.14224)
		(layer "In6.Cu")
		(net "P5E_CPU1_P3_TX_BUF_DP<7>")
	)
	(segment
		(start 123.40971 -389.352536)
		(end 123.313952 -389.448294)
		(width 0.14224)
		(layer "In6.Cu")
		(net "P5E_CPU1_P3_TX_BUF_DP<7>")
	)
	(segment
		(start 124.191014 -394.641578)
		(end 124.191014 -395.068298)
		(width 0.14224)
		(layer "In6.Cu")
		(net "P5E_CPU1_P3_TX_BUF_DP<7>")
	)
	(segment
		(start 123.313952 -389.448294)
		(end 123.313952 -389.561324)
		(width 0.14224)
		(layer "In6.Cu")
		(net "P5E_CPU1_P3_TX_BUF_DP<7>")
	)
	(segment
		(start 124.156978 -396.17523)
		(end 127.398272 -399.416524)
		(width 0.14224)
		(layer "In6.Cu")
		(net "P5E_CPU1_P3_TX_BUF_DP<7>")
	)
	(arc
		(start 124.023374 -391.635742)
		(mid 124.046191 -391.737745)
		(end 124.053854 -391.84199)
		(width 0.14224)
		(layer "In6.Cu")
		(net "P5E_CPU1_P3_TX_BUF_DP<7>")
	)
	(arc
		(start 138.12774 -403.454362)
		(mid 138.359706 -403.801523)
		(end 138.441176 -404.211028)
		(width 0.14224)
		(layer "In6.Cu")
		(net "P5E_CPU1_P3_TX_BUF_DP<7>")
	)
	(arc
		(start 127.398272 -399.416524)
		(mid 128.249645 -400.047959)
		(end 129.247646 -400.405092)
		(width 0.14224)
		(layer "In6.Cu")
		(net "P5E_CPU1_P3_TX_BUF_DP<7>")
	)
	(arc
		(start 124.053854 -395.926564)
		(mid 124.080663 -396.06116)
		(end 124.156978 -396.17523)
		(width 0.14224)
		(layer "In6.Cu")
		(net "P5E_CPU1_P3_TX_BUF_DP<7>")
	)
	(arc
		(start 123.517914 -389.827008)
		(mid 123.61405 -389.970931)
		(end 123.647708 -390.140698)
		(width 0.14224)
		(layer "In6.Cu")
		(net "P5E_CPU1_P3_TX_BUF_DP<7>")
	)
	(arc
		(start 123.647708 -390.332976)
		(mid 123.652362 -390.396146)
		(end 123.66625 -390.457944)
		(width 0.14224)
		(layer "In6.Cu")
		(net "P5E_CPU1_P3_TX_BUF_DP<7>")
	)
	(arc
		(start 123.313952 -389.561324)
		(mid 123.325286 -389.618396)
		(end 123.35764 -389.666734)
		(width 0.14224)
		(layer "In6.Cu")
		(net "P5E_CPU1_P3_TX_BUF_DP<7>")
	)
	(segment
		(start 121.970546 -389.467344)
		(end 122.491246 -389.467344)
		(width 0.127)
		(layer "F.Cu")
		(net "P5E_CPU1_P3_TX_BUF_DP<6>")
	)
	(segment
		(start 135.694166 -408.250644)
		(end 135.398256 -407.954734)
		(width 0.12954)
		(layer "B.Cu")
		(net "P5E_CPU1_P3_TX_BUF_DP<6>")
	)
	(segment
		(start 135.398256 -407.27503)
		(end 135.668766 -407.00452)
		(width 0.12954)
		(layer "B.Cu")
		(net "P5E_CPU1_P3_TX_BUF_DP<6>")
	)
	(segment
		(start 135.398256 -407.954734)
		(end 135.398256 -407.27503)
		(width 0.12954)
		(layer "B.Cu")
		(net "P5E_CPU1_P3_TX_BUF_DP<6>")
	)
	(segment
		(start 134.193534 -402.68779)
		(end 134.267702 -402.867114)
		(width 0.14224)
		(layer "In6.Cu")
		(net "P5E_CPU1_P3_TX_BUF_DP<6>")
	)
	(segment
		(start 134.693914 -403.043644)
		(end 134.976108 -403.325838)
		(width 0.14224)
		(layer "In6.Cu")
		(net "P5E_CPU1_P3_TX_BUF_DP<6>")
	)
	(segment
		(start 122.486166 -390.490964)
		(end 122.82297 -391.602976)
		(width 0.14224)
		(layer "In6.Cu")
		(net "P5E_CPU1_P3_TX_BUF_DP<6>")
	)
	(segment
		(start 135.515096 -405.798528)
		(end 135.377936 -405.935688)
		(width 0.14224)
		(layer "In6.Cu")
		(net "P5E_CPU1_P3_TX_BUF_DP<6>")
	)
	(segment
		(start 122.242326 -389.781796)
		(end 122.33783 -389.8773)
		(width 0.14224)
		(layer "In6.Cu")
		(net "P5E_CPU1_P3_TX_BUF_DP<6>")
	)
	(segment
		(start 122.376438 -389.352536)
		(end 122.196352 -389.352536)
		(width 0.14224)
		(layer "In6.Cu")
		(net "P5E_CPU1_P3_TX_BUF_DP<6>")
	)
	(segment
		(start 133.619748 -402.598636)
		(end 133.799072 -402.524468)
		(width 0.14224)
		(layer "In6.Cu")
		(net "P5E_CPU1_P3_TX_BUF_DP<6>")
	)
	(segment
		(start 130.139948 -401.540472)
		(end 132.484622 -402.127974)
		(width 0.14224)
		(layer "In6.Cu")
		(net "P5E_CPU1_P3_TX_BUF_DP<6>")
	)
	(segment
		(start 133.799072 -402.524468)
		(end 134.193534 -402.68779)
		(width 0.14224)
		(layer "In6.Cu")
		(net "P5E_CPU1_P3_TX_BUF_DP<6>")
	)
	(segment
		(start 135.377936 -405.935688)
		(end 135.377936 -406.71369)
		(width 0.14224)
		(layer "In6.Cu")
		(net "P5E_CPU1_P3_TX_BUF_DP<6>")
	)
	(segment
		(start 122.990864 -395.094714)
		(end 122.853704 -395.231874)
		(width 0.14224)
		(layer "In6.Cu")
		(net "P5E_CPU1_P3_TX_BUF_DP<6>")
	)
	(segment
		(start 134.267702 -402.867114)
		(end 134.267702 -402.86686)
		(width 0.14224)
		(layer "In6.Cu")
		(net "P5E_CPU1_P3_TX_BUF_DP<6>")
	)
	(segment
		(start 135.515096 -405.371808)
		(end 135.515096 -405.798528)
		(width 0.14224)
		(layer "In6.Cu")
		(net "P5E_CPU1_P3_TX_BUF_DP<6>")
	)
	(segment
		(start 123.06808 -396.411196)
		(end 126.847092 -400.190208)
		(width 0.14224)
		(layer "In6.Cu")
		(net "P5E_CPU1_P3_TX_BUF_DP<6>")
	)
	(segment
		(start 135.377936 -404.295864)
		(end 135.377936 -405.234648)
		(width 0.14224)
		(layer "In6.Cu")
		(net "P5E_CPU1_P3_TX_BUF_DP<6>")
	)
	(segment
		(start 122.853704 -391.809478)
		(end 122.853704 -394.530834)
		(width 0.14224)
		(layer "In6.Cu")
		(net "P5E_CPU1_P3_TX_BUF_DP<6>")
	)
	(segment
		(start 135.377936 -406.71369)
		(end 135.668766 -407.00452)
		(width 0.14224)
		(layer "In6.Cu")
		(net "P5E_CPU1_P3_TX_BUF_DP<6>")
	)
	(segment
		(start 122.106944 -389.441944)
		(end 122.106944 -389.455152)
		(width 0.14224)
		(layer "In6.Cu")
		(net "P5E_CPU1_P3_TX_BUF_DP<6>")
	)
	(segment
		(start 132.484622 -402.127974)
		(end 133.619748 -402.598382)
		(width 0.14224)
		(layer "In6.Cu")
		(net "P5E_CPU1_P3_TX_BUF_DP<6>")
	)
	(segment
		(start 135.377936 -405.234648)
		(end 135.515096 -405.371808)
		(width 0.14224)
		(layer "In6.Cu")
		(net "P5E_CPU1_P3_TX_BUF_DP<6>")
	)
	(segment
		(start 122.467624 -390.190736)
		(end 122.467624 -390.36625)
		(width 0.14224)
		(layer "In6.Cu")
		(net "P5E_CPU1_P3_TX_BUF_DP<6>")
	)
	(segment
		(start 122.853704 -395.231874)
		(end 122.853704 -395.893798)
		(width 0.14224)
		(layer "In6.Cu")
		(net "P5E_CPU1_P3_TX_BUF_DP<6>")
	)
	(segment
		(start 134.267702 -402.86686)
		(end 134.693914 -403.043644)
		(width 0.14224)
		(layer "In6.Cu")
		(net "P5E_CPU1_P3_TX_BUF_DP<6>")
	)
	(segment
		(start 122.990864 -394.667994)
		(end 122.990864 -395.094714)
		(width 0.14224)
		(layer "In6.Cu")
		(net "P5E_CPU1_P3_TX_BUF_DP<6>")
	)
	(segment
		(start 122.853704 -394.530834)
		(end 122.990864 -394.667994)
		(width 0.14224)
		(layer "In6.Cu")
		(net "P5E_CPU1_P3_TX_BUF_DP<6>")
	)
	(segment
		(start 133.619748 -402.598382)
		(end 133.619748 -402.598636)
		(width 0.14224)
		(layer "In6.Cu")
		(net "P5E_CPU1_P3_TX_BUF_DP<6>")
	)
	(segment
		(start 122.491246 -389.467344)
		(end 122.376438 -389.352536)
		(width 0.14224)
		(layer "In6.Cu")
		(net "P5E_CPU1_P3_TX_BUF_DP<6>")
	)
	(segment
		(start 128.919732 -401.297902)
		(end 130.139948 -401.540472)
		(width 0.14224)
		(layer "In6.Cu")
		(net "P5E_CPU1_P3_TX_BUF_DP<6>")
	)
	(segment
		(start 122.196352 -389.352536)
		(end 122.106944 -389.441944)
		(width 0.14224)
		(layer "In6.Cu")
		(net "P5E_CPU1_P3_TX_BUF_DP<6>")
	)
	(arc
		(start 122.467624 -390.36625)
		(mid 122.472307 -390.429288)
		(end 122.486166 -390.490964)
		(width 0.14224)
		(layer "In6.Cu")
		(net "P5E_CPU1_P3_TX_BUF_DP<6>")
	)
	(arc
		(start 122.106944 -389.455152)
		(mid 122.142129 -389.631947)
		(end 122.242326 -389.781796)
		(width 0.14224)
		(layer "In6.Cu")
		(net "P5E_CPU1_P3_TX_BUF_DP<6>")
	)
	(arc
		(start 122.853704 -395.893798)
		(mid 122.909422 -396.173822)
		(end 123.06808 -396.411196)
		(width 0.14224)
		(layer "In6.Cu")
		(net "P5E_CPU1_P3_TX_BUF_DP<6>")
	)
	(arc
		(start 126.847092 -400.190208)
		(mid 127.801239 -400.897815)
		(end 128.919732 -401.297902)
		(width 0.14224)
		(layer "In6.Cu")
		(net "P5E_CPU1_P3_TX_BUF_DP<6>")
	)
	(arc
		(start 122.82297 -391.602976)
		(mid 122.845959 -391.705093)
		(end 122.853704 -391.809478)
		(width 0.14224)
		(layer "In6.Cu")
		(net "P5E_CPU1_P3_TX_BUF_DP<6>")
	)
	(arc
		(start 134.976108 -403.325838)
		(mid 135.273482 -403.77089)
		(end 135.377936 -404.295864)
		(width 0.14224)
		(layer "In6.Cu")
		(net "P5E_CPU1_P3_TX_BUF_DP<6>")
	)
	(arc
		(start 122.33783 -389.8773)
		(mid 122.433918 -390.021106)
		(end 122.467624 -390.190736)
		(width 0.14224)
		(layer "In6.Cu")
		(net "P5E_CPU1_P3_TX_BUF_DP<6>")
	)
	(segment
		(start 120.77065 -389.467344)
		(end 121.29135 -389.467344)
		(width 0.127)
		(layer "F.Cu")
		(net "P5E_CPU1_P3_TX_BUF_DP<5>")
	)
	(segment
		(start 132.335016 -407.954734)
		(end 132.335016 -407.27503)
		(width 0.12954)
		(layer "B.Cu")
		(net "P5E_CPU1_P3_TX_BUF_DP<5>")
	)
	(segment
		(start 132.630926 -408.250644)
		(end 132.335016 -407.954734)
		(width 0.12954)
		(layer "B.Cu")
		(net "P5E_CPU1_P3_TX_BUF_DP<5>")
	)
	(segment
		(start 132.335016 -407.27503)
		(end 132.605526 -407.00452)
		(width 0.12954)
		(layer "B.Cu")
		(net "P5E_CPU1_P3_TX_BUF_DP<5>")
	)
	(segment
		(start 131.15163 -402.810472)
		(end 131.234688 -402.98624)
		(width 0.14224)
		(layer "In6.Cu")
		(net "P5E_CPU1_P3_TX_BUF_DP<5>")
	)
	(segment
		(start 120.907048 -389.441944)
		(end 120.907048 -389.508746)
		(width 0.14224)
		(layer "In6.Cu")
		(net "P5E_CPU1_P3_TX_BUF_DP<5>")
	)
	(segment
		(start 130.749548 -402.666708)
		(end 131.15163 -402.810472)
		(width 0.14224)
		(layer "In6.Cu")
		(net "P5E_CPU1_P3_TX_BUF_DP<5>")
	)
	(segment
		(start 121.29135 -389.467344)
		(end 121.176542 -389.352536)
		(width 0.14224)
		(layer "In6.Cu")
		(net "P5E_CPU1_P3_TX_BUF_DP<5>")
	)
	(segment
		(start 121.653808 -391.827766)
		(end 121.653808 -394.805154)
		(width 0.14224)
		(layer "In6.Cu")
		(net "P5E_CPU1_P3_TX_BUF_DP<5>")
	)
	(segment
		(start 131.900168 -403.296882)
		(end 132.03047 -403.427184)
		(width 0.14224)
		(layer "In6.Cu")
		(net "P5E_CPU1_P3_TX_BUF_DP<5>")
	)
	(segment
		(start 121.653808 -394.805154)
		(end 121.790968 -394.942314)
		(width 0.14224)
		(layer "In6.Cu")
		(net "P5E_CPU1_P3_TX_BUF_DP<5>")
	)
	(segment
		(start 121.00433 -389.743442)
		(end 121.14784 -389.886698)
		(width 0.14224)
		(layer "In6.Cu")
		(net "P5E_CPU1_P3_TX_BUF_DP<5>")
	)
	(segment
		(start 131.636262 -403.12975)
		(end 131.900168 -403.296882)
		(width 0.14224)
		(layer "In6.Cu")
		(net "P5E_CPU1_P3_TX_BUF_DP<5>")
	)
	(segment
		(start 131.234688 -402.98624)
		(end 131.636262 -403.12975)
		(width 0.14224)
		(layer "In6.Cu")
		(net "P5E_CPU1_P3_TX_BUF_DP<5>")
	)
	(segment
		(start 120.996456 -389.352536)
		(end 120.907048 -389.441944)
		(width 0.14224)
		(layer "In6.Cu")
		(net "P5E_CPU1_P3_TX_BUF_DP<5>")
	)
	(segment
		(start 132.451856 -405.504142)
		(end 132.451856 -405.930862)
		(width 0.14224)
		(layer "In6.Cu")
		(net "P5E_CPU1_P3_TX_BUF_DP<5>")
	)
	(segment
		(start 121.790968 -395.369034)
		(end 121.653808 -395.506194)
		(width 0.14224)
		(layer "In6.Cu")
		(net "P5E_CPU1_P3_TX_BUF_DP<5>")
	)
	(segment
		(start 132.314696 -406.068022)
		(end 132.314696 -406.71369)
		(width 0.14224)
		(layer "In6.Cu")
		(net "P5E_CPU1_P3_TX_BUF_DP<5>")
	)
	(segment
		(start 121.653808 -395.506194)
		(end 121.653808 -396.03934)
		(width 0.14224)
		(layer "In6.Cu")
		(net "P5E_CPU1_P3_TX_BUF_DP<5>")
	)
	(segment
		(start 132.451856 -405.930862)
		(end 132.314696 -406.068022)
		(width 0.14224)
		(layer "In6.Cu")
		(net "P5E_CPU1_P3_TX_BUF_DP<5>")
	)
	(segment
		(start 121.176542 -389.352536)
		(end 120.996456 -389.352536)
		(width 0.14224)
		(layer "In6.Cu")
		(net "P5E_CPU1_P3_TX_BUF_DP<5>")
	)
	(segment
		(start 132.314696 -404.113492)
		(end 132.314696 -405.366982)
		(width 0.14224)
		(layer "In6.Cu")
		(net "P5E_CPU1_P3_TX_BUF_DP<5>")
	)
	(segment
		(start 130.574288 -402.749766)
		(end 130.749548 -402.666708)
		(width 0.14224)
		(layer "In6.Cu")
		(net "P5E_CPU1_P3_TX_BUF_DP<5>")
	)
	(segment
		(start 132.314696 -405.366982)
		(end 132.451856 -405.504142)
		(width 0.14224)
		(layer "In6.Cu")
		(net "P5E_CPU1_P3_TX_BUF_DP<5>")
	)
	(segment
		(start 132.314696 -406.71369)
		(end 132.605526 -407.00452)
		(width 0.14224)
		(layer "In6.Cu")
		(net "P5E_CPU1_P3_TX_BUF_DP<5>")
	)
	(segment
		(start 128.467358 -402.162264)
		(end 129.512568 -402.370036)
		(width 0.14224)
		(layer "In6.Cu")
		(net "P5E_CPU1_P3_TX_BUF_DP<5>")
	)
	(segment
		(start 121.2723 -390.186926)
		(end 121.2723 -390.40054)
		(width 0.14224)
		(layer "In6.Cu")
		(net "P5E_CPU1_P3_TX_BUF_DP<5>")
	)
	(segment
		(start 129.512568 -402.370036)
		(end 130.574288 -402.749766)
		(width 0.14224)
		(layer "In6.Cu")
		(net "P5E_CPU1_P3_TX_BUF_DP<5>")
	)
	(segment
		(start 121.790968 -394.942314)
		(end 121.790968 -395.369034)
		(width 0.14224)
		(layer "In6.Cu")
		(net "P5E_CPU1_P3_TX_BUF_DP<5>")
	)
	(segment
		(start 121.290842 -390.525254)
		(end 121.623074 -391.621264)
		(width 0.14224)
		(layer "In6.Cu")
		(net "P5E_CPU1_P3_TX_BUF_DP<5>")
	)
	(segment
		(start 121.849896 -396.512542)
		(end 126.388368 -401.051014)
		(width 0.14224)
		(layer "In6.Cu")
		(net "P5E_CPU1_P3_TX_BUF_DP<5>")
	)
	(arc
		(start 132.03047 -403.427184)
		(mid 132.240813 -403.742079)
		(end 132.314696 -404.113492)
		(width 0.14224)
		(layer "In6.Cu")
		(net "P5E_CPU1_P3_TX_BUF_DP<5>")
	)
	(arc
		(start 121.623074 -391.621264)
		(mid 121.646072 -391.723381)
		(end 121.653808 -391.827766)
		(width 0.14224)
		(layer "In6.Cu")
		(net "P5E_CPU1_P3_TX_BUF_DP<5>")
	)
	(arc
		(start 121.2723 -390.40054)
		(mid 121.276983 -390.463578)
		(end 121.290842 -390.525254)
		(width 0.14224)
		(layer "In6.Cu")
		(net "P5E_CPU1_P3_TX_BUF_DP<5>")
	)
	(arc
		(start 120.907048 -389.508746)
		(mid 120.932333 -389.635774)
		(end 121.00433 -389.743442)
		(width 0.14224)
		(layer "In6.Cu")
		(net "P5E_CPU1_P3_TX_BUF_DP<5>")
	)
	(arc
		(start 126.388368 -401.051014)
		(mid 127.345431 -401.760861)
		(end 128.467358 -402.162264)
		(width 0.14224)
		(layer "In6.Cu")
		(net "P5E_CPU1_P3_TX_BUF_DP<5>")
	)
	(arc
		(start 121.653808 -396.03934)
		(mid 121.70477 -396.295452)
		(end 121.849896 -396.512542)
		(width 0.14224)
		(layer "In6.Cu")
		(net "P5E_CPU1_P3_TX_BUF_DP<5>")
	)
	(arc
		(start 121.14784 -389.886698)
		(mid 121.239933 -390.02443)
		(end 121.2723 -390.186926)
		(width 0.14224)
		(layer "In6.Cu")
		(net "P5E_CPU1_P3_TX_BUF_DP<5>")
	)
	(segment
		(start 119.5705 -389.467344)
		(end 120.0912 -389.467344)
		(width 0.127)
		(layer "F.Cu")
		(net "P5E_CPU1_P3_TX_BUF_DP<4>")
	)
	(segment
		(start 129.271776 -407.954734)
		(end 129.271776 -407.27503)
		(width 0.12954)
		(layer "B.Cu")
		(net "P5E_CPU1_P3_TX_BUF_DP<4>")
	)
	(segment
		(start 129.271776 -407.27503)
		(end 129.542286 -407.00452)
		(width 0.12954)
		(layer "B.Cu")
		(net "P5E_CPU1_P3_TX_BUF_DP<4>")
	)
	(segment
		(start 129.567686 -408.250644)
		(end 129.271776 -407.954734)
		(width 0.12954)
		(layer "B.Cu")
		(net "P5E_CPU1_P3_TX_BUF_DP<4>")
	)
	(segment
		(start 120.067578 -390.17575)
		(end 120.067578 -390.35355)
		(width 0.14224)
		(layer "In6.Cu")
		(net "P5E_CPU1_P3_TX_BUF_DP<4>")
	)
	(segment
		(start 120.64619 -396.867126)
		(end 122.096276 -398.317212)
		(width 0.14224)
		(layer "In6.Cu")
		(net "P5E_CPU1_P3_TX_BUF_DP<4>")
	)
	(segment
		(start 126.09068 -402.311616)
		(end 126.85395 -402.821648)
		(width 0.14224)
		(layer "In6.Cu")
		(net "P5E_CPU1_P3_TX_BUF_DP<4>")
	)
	(segment
		(start 126.85395 -402.821648)
		(end 127.27432 -402.949156)
		(width 0.14224)
		(layer "In6.Cu")
		(net "P5E_CPU1_P3_TX_BUF_DP<4>")
	)
	(segment
		(start 120.0912 -389.467344)
		(end 119.976392 -389.352536)
		(width 0.14224)
		(layer "In6.Cu")
		(net "P5E_CPU1_P3_TX_BUF_DP<4>")
	)
	(segment
		(start 122.096276 -398.317212)
		(end 122.290078 -398.317212)
		(width 0.14224)
		(layer "In6.Cu")
		(net "P5E_CPU1_P3_TX_BUF_DP<4>")
	)
	(segment
		(start 129.251456 -405.38019)
		(end 129.388616 -405.51735)
		(width 0.14224)
		(layer "In6.Cu")
		(net "P5E_CPU1_P3_TX_BUF_DP<4>")
	)
	(segment
		(start 129.251456 -406.08123)
		(end 129.251456 -406.71369)
		(width 0.14224)
		(layer "In6.Cu")
		(net "P5E_CPU1_P3_TX_BUF_DP<4>")
	)
	(segment
		(start 120.453658 -394.539978)
		(end 120.590818 -394.677138)
		(width 0.14224)
		(layer "In6.Cu")
		(net "P5E_CPU1_P3_TX_BUF_DP<4>")
	)
	(segment
		(start 129.388616 -405.94407)
		(end 129.251456 -406.08123)
		(width 0.14224)
		(layer "In6.Cu")
		(net "P5E_CPU1_P3_TX_BUF_DP<4>")
	)
	(segment
		(start 120.590818 -394.677138)
		(end 120.590818 -395.103858)
		(width 0.14224)
		(layer "In6.Cu")
		(net "P5E_CPU1_P3_TX_BUF_DP<4>")
	)
	(segment
		(start 119.976392 -389.352536)
		(end 119.796306 -389.352536)
		(width 0.14224)
		(layer "In6.Cu")
		(net "P5E_CPU1_P3_TX_BUF_DP<4>")
	)
	(segment
		(start 119.706898 -389.441944)
		(end 119.706898 -389.501888)
		(width 0.14224)
		(layer "In6.Cu")
		(net "P5E_CPU1_P3_TX_BUF_DP<4>")
	)
	(segment
		(start 122.592084 -398.81302)
		(end 126.09068 -402.311616)
		(width 0.14224)
		(layer "In6.Cu")
		(net "P5E_CPU1_P3_TX_BUF_DP<4>")
	)
	(segment
		(start 119.796306 -389.352536)
		(end 119.706898 -389.441944)
		(width 0.14224)
		(layer "In6.Cu")
		(net "P5E_CPU1_P3_TX_BUF_DP<4>")
	)
	(segment
		(start 129.388616 -405.51735)
		(end 129.388616 -405.94407)
		(width 0.14224)
		(layer "In6.Cu")
		(net "P5E_CPU1_P3_TX_BUF_DP<4>")
	)
	(segment
		(start 128.85293 -403.36216)
		(end 128.950974 -403.460204)
		(width 0.14224)
		(layer "In6.Cu")
		(net "P5E_CPU1_P3_TX_BUF_DP<4>")
	)
	(segment
		(start 122.592084 -398.619218)
		(end 122.592084 -398.81302)
		(width 0.14224)
		(layer "In6.Cu")
		(net "P5E_CPU1_P3_TX_BUF_DP<4>")
	)
	(segment
		(start 129.251456 -406.71369)
		(end 129.542286 -407.00452)
		(width 0.14224)
		(layer "In6.Cu")
		(net "P5E_CPU1_P3_TX_BUF_DP<4>")
	)
	(segment
		(start 122.290078 -398.317212)
		(end 122.592084 -398.619218)
		(width 0.14224)
		(layer "In6.Cu")
		(net "P5E_CPU1_P3_TX_BUF_DP<4>")
	)
	(segment
		(start 120.453658 -391.796016)
		(end 120.453658 -394.539978)
		(width 0.14224)
		(layer "In6.Cu")
		(net "P5E_CPU1_P3_TX_BUF_DP<4>")
	)
	(segment
		(start 120.453658 -395.241018)
		(end 120.453658 -396.40256)
		(width 0.14224)
		(layer "In6.Cu")
		(net "P5E_CPU1_P3_TX_BUF_DP<4>")
	)
	(segment
		(start 127.27432 -402.949156)
		(end 128.351534 -403.109176)
		(width 0.14224)
		(layer "In6.Cu")
		(net "P5E_CPU1_P3_TX_BUF_DP<4>")
	)
	(segment
		(start 120.590818 -395.103858)
		(end 120.453658 -395.241018)
		(width 0.14224)
		(layer "In6.Cu")
		(net "P5E_CPU1_P3_TX_BUF_DP<4>")
	)
	(segment
		(start 129.251456 -404.185628)
		(end 129.251456 -405.38019)
		(width 0.14224)
		(layer "In6.Cu")
		(net "P5E_CPU1_P3_TX_BUF_DP<4>")
	)
	(segment
		(start 120.08612 -390.478518)
		(end 120.423178 -391.589514)
		(width 0.14224)
		(layer "In6.Cu")
		(net "P5E_CPU1_P3_TX_BUF_DP<4>")
	)
	(segment
		(start 119.809006 -389.748268)
		(end 119.94769 -389.886698)
		(width 0.14224)
		(layer "In6.Cu")
		(net "P5E_CPU1_P3_TX_BUF_DP<4>")
	)
	(arc
		(start 120.067578 -390.35355)
		(mid 120.072245 -390.416716)
		(end 120.08612 -390.478518)
		(width 0.14224)
		(layer "In6.Cu")
		(net "P5E_CPU1_P3_TX_BUF_DP<4>")
	)
	(arc
		(start 119.94769 -389.886698)
		(mid 120.036386 -390.019301)
		(end 120.067578 -390.17575)
		(width 0.14224)
		(layer "In6.Cu")
		(net "P5E_CPU1_P3_TX_BUF_DP<4>")
	)
	(arc
		(start 128.351534 -403.109176)
		(mid 128.622569 -403.195364)
		(end 128.85293 -403.36216)
		(width 0.14224)
		(layer "In6.Cu")
		(net "P5E_CPU1_P3_TX_BUF_DP<4>")
	)
	(arc
		(start 120.423178 -391.589514)
		(mid 120.446022 -391.691642)
		(end 120.453658 -391.796016)
		(width 0.14224)
		(layer "In6.Cu")
		(net "P5E_CPU1_P3_TX_BUF_DP<4>")
	)
	(arc
		(start 120.453658 -396.40256)
		(mid 120.503692 -396.654006)
		(end 120.64619 -396.867126)
		(width 0.14224)
		(layer "In6.Cu")
		(net "P5E_CPU1_P3_TX_BUF_DP<4>")
	)
	(arc
		(start 119.706898 -389.501888)
		(mid 119.73344 -389.635234)
		(end 119.809006 -389.748268)
		(width 0.14224)
		(layer "In6.Cu")
		(net "P5E_CPU1_P3_TX_BUF_DP<4>")
	)
	(arc
		(start 128.950974 -403.460204)
		(mid 129.173362 -403.793031)
		(end 129.251456 -404.185628)
		(width 0.14224)
		(layer "In6.Cu")
		(net "P5E_CPU1_P3_TX_BUF_DP<4>")
	)
	(segment
		(start 118.370604 -389.467344)
		(end 118.891304 -389.467344)
		(width 0.127)
		(layer "F.Cu")
		(net "P5E_CPU1_P3_TX_BUF_DP<3>")
	)
	(segment
		(start 126.208536 -407.27503)
		(end 126.479046 -407.00452)
		(width 0.12954)
		(layer "B.Cu")
		(net "P5E_CPU1_P3_TX_BUF_DP<3>")
	)
	(segment
		(start 126.504446 -408.250644)
		(end 126.208536 -407.954734)
		(width 0.12954)
		(layer "B.Cu")
		(net "P5E_CPU1_P3_TX_BUF_DP<3>")
	)
	(segment
		(start 126.208536 -407.954734)
		(end 126.208536 -407.27503)
		(width 0.12954)
		(layer "B.Cu")
		(net "P5E_CPU1_P3_TX_BUF_DP<3>")
	)
	(segment
		(start 126.188216 -405.723598)
		(end 126.188216 -406.71369)
		(width 0.14224)
		(layer "In6.Cu")
		(net "P5E_CPU1_P3_TX_BUF_DP<3>")
	)
	(segment
		(start 119.253762 -395.429232)
		(end 119.390922 -395.566392)
		(width 0.14224)
		(layer "In6.Cu")
		(net "P5E_CPU1_P3_TX_BUF_DP<3>")
	)
	(segment
		(start 119.202962 -391.590784)
		(end 119.241316 -391.843768)
		(width 0.14224)
		(layer "In6.Cu")
		(net "P5E_CPU1_P3_TX_BUF_DP<3>")
	)
	(segment
		(start 119.39143 -397.016478)
		(end 125.875034 -403.500082)
		(width 0.14224)
		(layer "In6.Cu")
		(net "P5E_CPU1_P3_TX_BUF_DP<3>")
	)
	(segment
		(start 118.584472 -389.72363)
		(end 118.747794 -389.886952)
		(width 0.14224)
		(layer "In6.Cu")
		(net "P5E_CPU1_P3_TX_BUF_DP<3>")
	)
	(segment
		(start 118.59641 -389.352536)
		(end 118.507002 -389.441944)
		(width 0.14224)
		(layer "In6.Cu")
		(net "P5E_CPU1_P3_TX_BUF_DP<3>")
	)
	(segment
		(start 119.253762 -392.012424)
		(end 119.253762 -394.301472)
		(width 0.14224)
		(layer "In6.Cu")
		(net "P5E_CPU1_P3_TX_BUF_DP<3>")
	)
	(segment
		(start 118.776496 -389.352536)
		(end 118.59641 -389.352536)
		(width 0.14224)
		(layer "In6.Cu")
		(net "P5E_CPU1_P3_TX_BUF_DP<3>")
	)
	(segment
		(start 118.886224 -390.502902)
		(end 119.166386 -391.427462)
		(width 0.14224)
		(layer "In6.Cu")
		(net "P5E_CPU1_P3_TX_BUF_DP<3>")
	)
	(segment
		(start 126.325376 -405.159718)
		(end 126.325376 -405.586438)
		(width 0.14224)
		(layer "In6.Cu")
		(net "P5E_CPU1_P3_TX_BUF_DP<3>")
	)
	(segment
		(start 119.390922 -395.566392)
		(end 119.390922 -395.993112)
		(width 0.14224)
		(layer "In6.Cu")
		(net "P5E_CPU1_P3_TX_BUF_DP<3>")
	)
	(segment
		(start 119.253762 -395.002512)
		(end 119.253762 -395.429232)
		(width 0.14224)
		(layer "In6.Cu")
		(net "P5E_CPU1_P3_TX_BUF_DP<3>")
	)
	(segment
		(start 126.188216 -405.022558)
		(end 126.325376 -405.159718)
		(width 0.14224)
		(layer "In6.Cu")
		(net "P5E_CPU1_P3_TX_BUF_DP<3>")
	)
	(segment
		(start 119.390922 -394.438632)
		(end 119.390922 -394.865352)
		(width 0.14224)
		(layer "In6.Cu")
		(net "P5E_CPU1_P3_TX_BUF_DP<3>")
	)
	(segment
		(start 126.188216 -406.71369)
		(end 126.479046 -407.00452)
		(width 0.14224)
		(layer "In6.Cu")
		(net "P5E_CPU1_P3_TX_BUF_DP<3>")
	)
	(segment
		(start 118.507002 -389.441944)
		(end 118.507002 -389.536686)
		(width 0.14224)
		(layer "In6.Cu")
		(net "P5E_CPU1_P3_TX_BUF_DP<3>")
	)
	(segment
		(start 119.390922 -395.993112)
		(end 119.253762 -396.130272)
		(width 0.14224)
		(layer "In6.Cu")
		(net "P5E_CPU1_P3_TX_BUF_DP<3>")
	)
	(segment
		(start 119.253762 -396.130272)
		(end 119.253762 -396.683992)
		(width 0.14224)
		(layer "In6.Cu")
		(net "P5E_CPU1_P3_TX_BUF_DP<3>")
	)
	(segment
		(start 118.891304 -389.467344)
		(end 118.776496 -389.352536)
		(width 0.14224)
		(layer "In6.Cu")
		(net "P5E_CPU1_P3_TX_BUF_DP<3>")
	)
	(segment
		(start 119.390922 -394.865352)
		(end 119.253762 -395.002512)
		(width 0.14224)
		(layer "In6.Cu")
		(net "P5E_CPU1_P3_TX_BUF_DP<3>")
	)
	(segment
		(start 118.867682 -390.176512)
		(end 118.867682 -390.378188)
		(width 0.14224)
		(layer "In6.Cu")
		(net "P5E_CPU1_P3_TX_BUF_DP<3>")
	)
	(segment
		(start 126.188216 -404.255732)
		(end 126.188216 -405.022558)
		(width 0.14224)
		(layer "In6.Cu")
		(net "P5E_CPU1_P3_TX_BUF_DP<3>")
	)
	(segment
		(start 119.253762 -394.301472)
		(end 119.390922 -394.438632)
		(width 0.14224)
		(layer "In6.Cu")
		(net "P5E_CPU1_P3_TX_BUF_DP<3>")
	)
	(segment
		(start 126.325376 -405.586438)
		(end 126.188216 -405.723598)
		(width 0.14224)
		(layer "In6.Cu")
		(net "P5E_CPU1_P3_TX_BUF_DP<3>")
	)
	(arc
		(start 118.747794 -389.886952)
		(mid 118.836509 -390.019817)
		(end 118.867682 -390.176512)
		(width 0.14224)
		(layer "In6.Cu")
		(net "P5E_CPU1_P3_TX_BUF_DP<3>")
	)
	(arc
		(start 118.867682 -390.378188)
		(mid 118.872365 -390.441226)
		(end 118.886224 -390.502902)
		(width 0.14224)
		(layer "In6.Cu")
		(net "P5E_CPU1_P3_TX_BUF_DP<3>")
	)
	(arc
		(start 119.241316 -391.843768)
		(mid 119.250704 -391.927862)
		(end 119.253762 -392.012424)
		(width 0.14224)
		(layer "In6.Cu")
		(net "P5E_CPU1_P3_TX_BUF_DP<3>")
	)
	(arc
		(start 119.253762 -396.683992)
		(mid 119.289535 -396.863926)
		(end 119.39143 -397.016478)
		(width 0.14224)
		(layer "In6.Cu")
		(net "P5E_CPU1_P3_TX_BUF_DP<3>")
	)
	(arc
		(start 125.875034 -403.500082)
		(mid 126.106718 -403.846776)
		(end 126.188216 -404.255732)
		(width 0.14224)
		(layer "In6.Cu")
		(net "P5E_CPU1_P3_TX_BUF_DP<3>")
	)
	(arc
		(start 119.166386 -391.427462)
		(mid 119.187629 -391.508461)
		(end 119.202962 -391.590784)
		(width 0.14224)
		(layer "In6.Cu")
		(net "P5E_CPU1_P3_TX_BUF_DP<3>")
	)
	(arc
		(start 118.507002 -389.536686)
		(mid 118.527129 -389.637873)
		(end 118.584472 -389.72363)
		(width 0.14224)
		(layer "In6.Cu")
		(net "P5E_CPU1_P3_TX_BUF_DP<3>")
	)
	(segment
		(start 117.170454 -389.467344)
		(end 117.691154 -389.467344)
		(width 0.127)
		(layer "F.Cu")
		(net "P5E_CPU1_P3_TX_BUF_DP<2>")
	)
	(segment
		(start 123.145296 -407.954734)
		(end 123.145296 -407.27503)
		(width 0.12954)
		(layer "B.Cu")
		(net "P5E_CPU1_P3_TX_BUF_DP<2>")
	)
	(segment
		(start 123.145296 -407.27503)
		(end 123.415806 -407.00452)
		(width 0.12954)
		(layer "B.Cu")
		(net "P5E_CPU1_P3_TX_BUF_DP<2>")
	)
	(segment
		(start 123.441206 -408.250644)
		(end 123.145296 -407.954734)
		(width 0.12954)
		(layer "B.Cu")
		(net "P5E_CPU1_P3_TX_BUF_DP<2>")
	)
	(segment
		(start 118.253764 -397.255238)
		(end 121.622312 -401.360132)
		(width 0.14224)
		(layer "In6.Cu")
		(net "P5E_CPU1_P3_TX_BUF_DP<2>")
	)
	(segment
		(start 117.694964 -390.242298)
		(end 117.694964 -390.477502)
		(width 0.14224)
		(layer "In6.Cu")
		(net "P5E_CPU1_P3_TX_BUF_DP<2>")
	)
	(segment
		(start 118.053866 -396.156688)
		(end 118.053866 -396.697454)
		(width 0.14224)
		(layer "In6.Cu")
		(net "P5E_CPU1_P3_TX_BUF_DP<2>")
	)
	(segment
		(start 121.622566 -401.360132)
		(end 121.815606 -401.379182)
		(width 0.14224)
		(layer "In6.Cu")
		(net "P5E_CPU1_P3_TX_BUF_DP<2>")
	)
	(segment
		(start 117.420898 -389.352536)
		(end 117.306852 -389.466582)
		(width 0.14224)
		(layer "In6.Cu")
		(net "P5E_CPU1_P3_TX_BUF_DP<2>")
	)
	(segment
		(start 123.124976 -403.841204)
		(end 123.124976 -406.71369)
		(width 0.14224)
		(layer "In6.Cu")
		(net "P5E_CPU1_P3_TX_BUF_DP<2>")
	)
	(segment
		(start 118.191026 -396.019528)
		(end 118.053866 -396.156688)
		(width 0.14224)
		(layer "In6.Cu")
		(net "P5E_CPU1_P3_TX_BUF_DP<2>")
	)
	(segment
		(start 118.053866 -394.327888)
		(end 118.191026 -394.465048)
		(width 0.14224)
		(layer "In6.Cu")
		(net "P5E_CPU1_P3_TX_BUF_DP<2>")
	)
	(segment
		(start 122.067574 -401.902422)
		(end 122.71248 -402.688298)
		(width 0.14224)
		(layer "In6.Cu")
		(net "P5E_CPU1_P3_TX_BUF_DP<2>")
	)
	(segment
		(start 122.08637 -401.709382)
		(end 122.067574 -401.902422)
		(width 0.14224)
		(layer "In6.Cu")
		(net "P5E_CPU1_P3_TX_BUF_DP<2>")
	)
	(segment
		(start 118.191026 -394.465048)
		(end 118.191026 -394.891768)
		(width 0.14224)
		(layer "In6.Cu")
		(net "P5E_CPU1_P3_TX_BUF_DP<2>")
	)
	(segment
		(start 118.053866 -395.028928)
		(end 118.053866 -395.455648)
		(width 0.14224)
		(layer "In6.Cu")
		(net "P5E_CPU1_P3_TX_BUF_DP<2>")
	)
	(segment
		(start 117.713506 -390.602216)
		(end 118.023132 -391.621772)
		(width 0.14224)
		(layer "In6.Cu")
		(net "P5E_CPU1_P3_TX_BUF_DP<2>")
	)
	(segment
		(start 118.053866 -391.828274)
		(end 118.053866 -394.327888)
		(width 0.14224)
		(layer "In6.Cu")
		(net "P5E_CPU1_P3_TX_BUF_DP<2>")
	)
	(segment
		(start 118.191026 -394.891768)
		(end 118.053866 -395.028928)
		(width 0.14224)
		(layer "In6.Cu")
		(net "P5E_CPU1_P3_TX_BUF_DP<2>")
	)
	(segment
		(start 117.306852 -389.466582)
		(end 117.306852 -389.514588)
		(width 0.14224)
		(layer "In6.Cu")
		(net "P5E_CPU1_P3_TX_BUF_DP<2>")
	)
	(segment
		(start 121.622312 -401.360132)
		(end 121.622566 -401.360132)
		(width 0.14224)
		(layer "In6.Cu")
		(net "P5E_CPU1_P3_TX_BUF_DP<2>")
	)
	(segment
		(start 117.691154 -389.467344)
		(end 117.576346 -389.352536)
		(width 0.14224)
		(layer "In6.Cu")
		(net "P5E_CPU1_P3_TX_BUF_DP<2>")
	)
	(segment
		(start 118.191026 -395.592808)
		(end 118.191026 -396.019528)
		(width 0.14224)
		(layer "In6.Cu")
		(net "P5E_CPU1_P3_TX_BUF_DP<2>")
	)
	(segment
		(start 117.40007 -389.739632)
		(end 117.548152 -389.887714)
		(width 0.14224)
		(layer "In6.Cu")
		(net "P5E_CPU1_P3_TX_BUF_DP<2>")
	)
	(segment
		(start 121.815606 -401.379182)
		(end 122.08637 -401.709382)
		(width 0.14224)
		(layer "In6.Cu")
		(net "P5E_CPU1_P3_TX_BUF_DP<2>")
	)
	(segment
		(start 117.576346 -389.352536)
		(end 117.420898 -389.352536)
		(width 0.14224)
		(layer "In6.Cu")
		(net "P5E_CPU1_P3_TX_BUF_DP<2>")
	)
	(segment
		(start 123.124976 -406.71369)
		(end 123.415806 -407.00452)
		(width 0.14224)
		(layer "In6.Cu")
		(net "P5E_CPU1_P3_TX_BUF_DP<2>")
	)
	(segment
		(start 118.053866 -395.455648)
		(end 118.191026 -395.592808)
		(width 0.14224)
		(layer "In6.Cu")
		(net "P5E_CPU1_P3_TX_BUF_DP<2>")
	)
	(arc
		(start 122.71248 -402.688298)
		(mid 123.018753 -403.228964)
		(end 123.124976 -403.841204)
		(width 0.14224)
		(layer "In6.Cu")
		(net "P5E_CPU1_P3_TX_BUF_DP<2>")
	)
	(arc
		(start 117.548152 -389.887714)
		(mid 117.656801 -390.050413)
		(end 117.694964 -390.242298)
		(width 0.14224)
		(layer "In6.Cu")
		(net "P5E_CPU1_P3_TX_BUF_DP<2>")
	)
	(arc
		(start 118.053866 -396.697454)
		(mid 118.105443 -396.993677)
		(end 118.253764 -397.255238)
		(width 0.14224)
		(layer "In6.Cu")
		(net "P5E_CPU1_P3_TX_BUF_DP<2>")
	)
	(arc
		(start 117.306852 -389.514588)
		(mid 117.331078 -389.636382)
		(end 117.40007 -389.739632)
		(width 0.14224)
		(layer "In6.Cu")
		(net "P5E_CPU1_P3_TX_BUF_DP<2>")
	)
	(arc
		(start 117.694964 -390.477502)
		(mid 117.699619 -390.540546)
		(end 117.713506 -390.602216)
		(width 0.14224)
		(layer "In6.Cu")
		(net "P5E_CPU1_P3_TX_BUF_DP<2>")
	)
	(arc
		(start 118.023132 -391.621772)
		(mid 118.046118 -391.723889)
		(end 118.053866 -391.828274)
		(width 0.14224)
		(layer "In6.Cu")
		(net "P5E_CPU1_P3_TX_BUF_DP<2>")
	)
	(segment
		(start 115.970558 -389.467344)
		(end 116.491258 -389.467344)
		(width 0.127)
		(layer "F.Cu")
		(net "P5E_CPU1_P3_TX_BUF_DP<1>")
	)
	(segment
		(start 120.082056 -407.27503)
		(end 120.352566 -407.00452)
		(width 0.12954)
		(layer "B.Cu")
		(net "P5E_CPU1_P3_TX_BUF_DP<1>")
	)
	(segment
		(start 120.082056 -407.954734)
		(end 120.082056 -407.27503)
		(width 0.12954)
		(layer "B.Cu")
		(net "P5E_CPU1_P3_TX_BUF_DP<1>")
	)
	(segment
		(start 120.377966 -408.250644)
		(end 120.082056 -407.954734)
		(width 0.12954)
		(layer "B.Cu")
		(net "P5E_CPU1_P3_TX_BUF_DP<1>")
	)
	(segment
		(start 119.4562 -401.992084)
		(end 119.390668 -402.17471)
		(width 0.14224)
		(layer "In6.Cu")
		(net "P5E_CPU1_P3_TX_BUF_DP<1>")
	)
	(segment
		(start 116.478304 -390.201658)
		(end 116.478304 -390.367266)
		(width 0.14224)
		(layer "In6.Cu")
		(net "P5E_CPU1_P3_TX_BUF_DP<1>")
	)
	(segment
		(start 118.353586 -399.981674)
		(end 118.596918 -400.496532)
		(width 0.14224)
		(layer "In6.Cu")
		(net "P5E_CPU1_P3_TX_BUF_DP<1>")
	)
	(segment
		(start 116.520468 -390.649968)
		(end 116.638832 -391.03935)
		(width 0.14224)
		(layer "In6.Cu")
		(net "P5E_CPU1_P3_TX_BUF_DP<1>")
	)
	(segment
		(start 116.491258 -389.467344)
		(end 116.37645 -389.352536)
		(width 0.14224)
		(layer "In6.Cu")
		(net "P5E_CPU1_P3_TX_BUF_DP<1>")
	)
	(segment
		(start 119.390668 -402.17471)
		(end 119.891302 -403.233382)
		(width 0.14224)
		(layer "In6.Cu")
		(net "P5E_CPU1_P3_TX_BUF_DP<1>")
	)
	(segment
		(start 116.196364 -389.352536)
		(end 116.106956 -389.441944)
		(width 0.14224)
		(layer "In6.Cu")
		(net "P5E_CPU1_P3_TX_BUF_DP<1>")
	)
	(segment
		(start 118.053612 -399.34769)
		(end 118.236492 -399.412968)
		(width 0.14224)
		(layer "In6.Cu")
		(net "P5E_CPU1_P3_TX_BUF_DP<1>")
	)
	(segment
		(start 118.596918 -400.496532)
		(end 118.779798 -400.56181)
		(width 0.14224)
		(layer "In6.Cu")
		(net "P5E_CPU1_P3_TX_BUF_DP<1>")
	)
	(segment
		(start 116.85524 -392.486388)
		(end 116.862098 -396.520924)
		(width 0.14224)
		(layer "In6.Cu")
		(net "P5E_CPU1_P3_TX_BUF_DP<1>")
	)
	(segment
		(start 116.37645 -389.352536)
		(end 116.196364 -389.352536)
		(width 0.14224)
		(layer "In6.Cu")
		(net "P5E_CPU1_P3_TX_BUF_DP<1>")
	)
	(segment
		(start 116.189252 -389.728456)
		(end 116.347748 -389.886698)
		(width 0.14224)
		(layer "In6.Cu")
		(net "P5E_CPU1_P3_TX_BUF_DP<1>")
	)
	(segment
		(start 117.87124 -398.962118)
		(end 118.053612 -399.34769)
		(width 0.14224)
		(layer "In6.Cu")
		(net "P5E_CPU1_P3_TX_BUF_DP<1>")
	)
	(segment
		(start 118.896892 -401.130516)
		(end 119.090694 -401.540726)
		(width 0.14224)
		(layer "In6.Cu")
		(net "P5E_CPU1_P3_TX_BUF_DP<1>")
	)
	(segment
		(start 120.061736 -406.71369)
		(end 120.352566 -407.00452)
		(width 0.14224)
		(layer "In6.Cu")
		(net "P5E_CPU1_P3_TX_BUF_DP<1>")
	)
	(segment
		(start 118.418864 -399.799048)
		(end 118.353586 -399.981674)
		(width 0.14224)
		(layer "In6.Cu")
		(net "P5E_CPU1_P3_TX_BUF_DP<1>")
	)
	(segment
		(start 119.273574 -401.606004)
		(end 119.4562 -401.992084)
		(width 0.14224)
		(layer "In6.Cu")
		(net "P5E_CPU1_P3_TX_BUF_DP<1>")
	)
	(segment
		(start 119.090694 -401.540726)
		(end 119.273574 -401.606004)
		(width 0.14224)
		(layer "In6.Cu")
		(net "P5E_CPU1_P3_TX_BUF_DP<1>")
	)
	(segment
		(start 120.061736 -403.992588)
		(end 120.061736 -406.71369)
		(width 0.14224)
		(layer "In6.Cu")
		(net "P5E_CPU1_P3_TX_BUF_DP<1>")
	)
	(segment
		(start 116.106956 -389.441944)
		(end 116.106956 -389.529828)
		(width 0.14224)
		(layer "In6.Cu")
		(net "P5E_CPU1_P3_TX_BUF_DP<1>")
	)
	(segment
		(start 116.948204 -396.917926)
		(end 117.87124 -398.962118)
		(width 0.14224)
		(layer "In6.Cu")
		(net "P5E_CPU1_P3_TX_BUF_DP<1>")
	)
	(segment
		(start 118.962424 -400.94789)
		(end 118.896892 -401.130516)
		(width 0.14224)
		(layer "In6.Cu")
		(net "P5E_CPU1_P3_TX_BUF_DP<1>")
	)
	(segment
		(start 118.236492 -399.412968)
		(end 118.418864 -399.799048)
		(width 0.14224)
		(layer "In6.Cu")
		(net "P5E_CPU1_P3_TX_BUF_DP<1>")
	)
	(segment
		(start 118.779798 -400.56181)
		(end 118.962424 -400.94789)
		(width 0.14224)
		(layer "In6.Cu")
		(net "P5E_CPU1_P3_TX_BUF_DP<1>")
	)
	(arc
		(start 116.862098 -396.520924)
		(mid 116.884099 -396.723993)
		(end 116.948204 -396.917926)
		(width 0.14224)
		(layer "In6.Cu")
		(net "P5E_CPU1_P3_TX_BUF_DP<1>")
	)
	(arc
		(start 119.891302 -403.233382)
		(mid 120.018601 -403.603538)
		(end 120.061736 -403.992588)
		(width 0.14224)
		(layer "In6.Cu")
		(net "P5E_CPU1_P3_TX_BUF_DP<1>")
	)
	(arc
		(start 116.106956 -389.529828)
		(mid 116.12834 -389.637333)
		(end 116.189252 -389.728456)
		(width 0.14224)
		(layer "In6.Cu")
		(net "P5E_CPU1_P3_TX_BUF_DP<1>")
	)
	(arc
		(start 116.478304 -390.367266)
		(mid 116.488942 -390.510174)
		(end 116.520468 -390.649968)
		(width 0.14224)
		(layer "In6.Cu")
		(net "P5E_CPU1_P3_TX_BUF_DP<1>")
	)
	(arc
		(start 116.347748 -389.886698)
		(mid 116.444357 -390.031189)
		(end 116.478304 -390.201658)
		(width 0.14224)
		(layer "In6.Cu")
		(net "P5E_CPU1_P3_TX_BUF_DP<1>")
	)
	(arc
		(start 116.638832 -391.03935)
		(mid 116.800196 -391.754918)
		(end 116.85524 -392.486388)
		(width 0.14224)
		(layer "In6.Cu")
		(net "P5E_CPU1_P3_TX_BUF_DP<1>")
	)
	(segment
		(start 132.770626 -389.467344)
		(end 133.291326 -389.467344)
		(width 0.127)
		(layer "F.Cu")
		(net "P5E_CPU1_P3_TX_BUF_DP<15>")
	)
	(segment
		(start 163.263326 -408.250644)
		(end 162.967416 -407.954734)
		(width 0.12954)
		(layer "B.Cu")
		(net "P5E_CPU1_P3_TX_BUF_DP<15>")
	)
	(segment
		(start 162.967416 -407.954734)
		(end 162.967416 -407.27503)
		(width 0.12954)
		(layer "B.Cu")
		(net "P5E_CPU1_P3_TX_BUF_DP<15>")
	)
	(segment
		(start 162.967416 -407.27503)
		(end 163.237926 -407.00452)
		(width 0.12954)
		(layer "B.Cu")
		(net "P5E_CPU1_P3_TX_BUF_DP<15>")
	)
	(segment
		(start 162.97529 -404.715472)
		(end 162.97529 -406.741884)
		(width 0.14224)
		(layer "In6.Cu")
		(net "P5E_CPU1_P3_TX_BUF_DP<15>")
	)
	(segment
		(start 148.987256 -397.43761)
		(end 149.398736 -397.551402)
		(width 0.14224)
		(layer "In6.Cu")
		(net "P5E_CPU1_P3_TX_BUF_DP<15>")
	)
	(segment
		(start 146.759168 -396.963392)
		(end 148.8186 -397.533368)
		(width 0.14224)
		(layer "In6.Cu")
		(net "P5E_CPU1_P3_TX_BUF_DP<15>")
	)
	(segment
		(start 139.915138 -394.92682)
		(end 140.326618 -395.040612)
		(width 0.14224)
		(layer "In6.Cu")
		(net "P5E_CPU1_P3_TX_BUF_DP<15>")
	)
	(segment
		(start 146.66341 -396.794228)
		(end 146.758914 -396.963392)
		(width 0.14224)
		(layer "In6.Cu")
		(net "P5E_CPU1_P3_TX_BUF_DP<15>")
	)
	(segment
		(start 133.84403 -393.71651)
		(end 133.884924 -393.733274)
		(width 0.14224)
		(layer "In6.Cu")
		(net "P5E_CPU1_P3_TX_BUF_DP<15>")
	)
	(segment
		(start 151.059134 -398.153382)
		(end 161.603944 -402.52142)
		(width 0.14224)
		(layer "In6.Cu")
		(net "P5E_CPU1_P3_TX_BUF_DP<15>")
	)
	(segment
		(start 133.291326 -389.467344)
		(end 133.176518 -389.352536)
		(width 0.14224)
		(layer "In6.Cu")
		(net "P5E_CPU1_P3_TX_BUF_DP<15>")
	)
	(segment
		(start 146.251676 -396.680436)
		(end 146.66341 -396.794228)
		(width 0.14224)
		(layer "In6.Cu")
		(net "P5E_CPU1_P3_TX_BUF_DP<15>")
	)
	(segment
		(start 148.8186 -397.533368)
		(end 148.987256 -397.43761)
		(width 0.14224)
		(layer "In6.Cu")
		(net "P5E_CPU1_P3_TX_BUF_DP<15>")
	)
	(segment
		(start 139.746228 -395.022324)
		(end 139.915138 -394.92682)
		(width 0.14224)
		(layer "In6.Cu")
		(net "P5E_CPU1_P3_TX_BUF_DP<15>")
	)
	(segment
		(start 146.08302 -396.776194)
		(end 146.251676 -396.680436)
		(width 0.14224)
		(layer "In6.Cu")
		(net "P5E_CPU1_P3_TX_BUF_DP<15>")
	)
	(segment
		(start 132.996178 -389.735314)
		(end 133.124194 -389.863076)
		(width 0.14224)
		(layer "In6.Cu")
		(net "P5E_CPU1_P3_TX_BUF_DP<15>")
	)
	(segment
		(start 162.97529 -406.741884)
		(end 163.237926 -407.00452)
		(width 0.14224)
		(layer "In6.Cu")
		(net "P5E_CPU1_P3_TX_BUF_DP<15>")
	)
	(segment
		(start 149.398736 -397.551402)
		(end 149.494494 -397.720566)
		(width 0.14224)
		(layer "In6.Cu")
		(net "P5E_CPU1_P3_TX_BUF_DP<15>")
	)
	(segment
		(start 132.907024 -389.441944)
		(end 132.907024 -389.520176)
		(width 0.14224)
		(layer "In6.Cu")
		(net "P5E_CPU1_P3_TX_BUF_DP<15>")
	)
	(segment
		(start 135.000238 -393.95527)
		(end 136.74852 -394.19276)
		(width 0.14224)
		(layer "In6.Cu")
		(net "P5E_CPU1_P3_TX_BUF_DP<15>")
	)
	(segment
		(start 132.996432 -389.352536)
		(end 132.907024 -389.441944)
		(width 0.14224)
		(layer "In6.Cu")
		(net "P5E_CPU1_P3_TX_BUF_DP<15>")
	)
	(segment
		(start 149.494494 -397.720312)
		(end 151.059134 -398.153382)
		(width 0.14224)
		(layer "In6.Cu")
		(net "P5E_CPU1_P3_TX_BUF_DP<15>")
	)
	(segment
		(start 149.494494 -397.720566)
		(end 149.494494 -397.720312)
		(width 0.14224)
		(layer "In6.Cu")
		(net "P5E_CPU1_P3_TX_BUF_DP<15>")
	)
	(segment
		(start 162.465004 -403.228048)
		(end 162.5727 -403.389338)
		(width 0.14224)
		(layer "In6.Cu")
		(net "P5E_CPU1_P3_TX_BUF_DP<15>")
	)
	(segment
		(start 133.176518 -389.352536)
		(end 132.996432 -389.352536)
		(width 0.14224)
		(layer "In6.Cu")
		(net "P5E_CPU1_P3_TX_BUF_DP<15>")
	)
	(segment
		(start 140.326618 -395.040612)
		(end 140.422122 -395.209522)
		(width 0.14224)
		(layer "In6.Cu")
		(net "P5E_CPU1_P3_TX_BUF_DP<15>")
	)
	(segment
		(start 133.255512 -390.059418)
		(end 133.590284 -390.868662)
		(width 0.14224)
		(layer "In6.Cu")
		(net "P5E_CPU1_P3_TX_BUF_DP<15>")
	)
	(segment
		(start 133.654292 -391.05586)
		(end 133.654292 -393.526772)
		(width 0.14224)
		(layer "In6.Cu")
		(net "P5E_CPU1_P3_TX_BUF_DP<15>")
	)
	(segment
		(start 146.758914 -396.963392)
		(end 146.759168 -396.963392)
		(width 0.14224)
		(layer "In6.Cu")
		(net "P5E_CPU1_P3_TX_BUF_DP<15>")
	)
	(segment
		(start 140.422122 -395.209522)
		(end 146.08302 -396.776194)
		(width 0.14224)
		(layer "In6.Cu")
		(net "P5E_CPU1_P3_TX_BUF_DP<15>")
	)
	(segment
		(start 133.884924 -393.733274)
		(end 135.000238 -393.95527)
		(width 0.14224)
		(layer "In6.Cu")
		(net "P5E_CPU1_P3_TX_BUF_DP<15>")
	)
	(segment
		(start 133.654292 -393.526772)
		(end 133.84403 -393.71651)
		(width 0.14224)
		(layer "In6.Cu")
		(net "P5E_CPU1_P3_TX_BUF_DP<15>")
	)
	(segment
		(start 136.74852 -394.19276)
		(end 139.746228 -395.022324)
		(width 0.14224)
		(layer "In6.Cu")
		(net "P5E_CPU1_P3_TX_BUF_DP<15>")
	)
	(arc
		(start 132.907024 -389.520176)
		(mid 132.930202 -389.636609)
		(end 132.996178 -389.735314)
		(width 0.14224)
		(layer "In6.Cu")
		(net "P5E_CPU1_P3_TX_BUF_DP<15>")
	)
	(arc
		(start 161.603944 -402.52142)
		(mid 162.086835 -402.810922)
		(end 162.465004 -403.228048)
		(width 0.14224)
		(layer "In6.Cu")
		(net "P5E_CPU1_P3_TX_BUF_DP<15>")
	)
	(arc
		(start 162.5727 -403.389338)
		(mid 162.872378 -404.022533)
		(end 162.97529 -404.715472)
		(width 0.14224)
		(layer "In6.Cu")
		(net "P5E_CPU1_P3_TX_BUF_DP<15>")
	)
	(arc
		(start 133.590284 -390.868662)
		(mid 133.62524 -390.961252)
		(end 133.654292 -391.05586)
		(width 0.14224)
		(layer "In6.Cu")
		(net "P5E_CPU1_P3_TX_BUF_DP<15>")
	)
	(arc
		(start 133.20776 -389.96747)
		(mid 133.233608 -390.01242)
		(end 133.255512 -390.059418)
		(width 0.14224)
		(layer "In6.Cu")
		(net "P5E_CPU1_P3_TX_BUF_DP<15>")
	)
	(arc
		(start 133.124194 -389.863076)
		(mid 133.168878 -389.912951)
		(end 133.20776 -389.96747)
		(width 0.14224)
		(layer "In6.Cu")
		(net "P5E_CPU1_P3_TX_BUF_DP<15>")
	)
	(segment
		(start 131.570476 -389.467344)
		(end 132.091176 -389.467344)
		(width 0.127)
		(layer "F.Cu")
		(net "P5E_CPU1_P3_TX_BUF_DP<14>")
	)
	(segment
		(start 159.904176 -407.27503)
		(end 160.174686 -407.00452)
		(width 0.12954)
		(layer "B.Cu")
		(net "P5E_CPU1_P3_TX_BUF_DP<14>")
	)
	(segment
		(start 160.200086 -408.250644)
		(end 159.904176 -407.954734)
		(width 0.12954)
		(layer "B.Cu")
		(net "P5E_CPU1_P3_TX_BUF_DP<14>")
	)
	(segment
		(start 159.904176 -407.954734)
		(end 159.904176 -407.27503)
		(width 0.12954)
		(layer "B.Cu")
		(net "P5E_CPU1_P3_TX_BUF_DP<14>")
	)
	(segment
		(start 132.501132 -394.17498)
		(end 132.693664 -394.367512)
		(width 0.14224)
		(layer "In6.Cu")
		(net "P5E_CPU1_P3_TX_BUF_DP<14>")
	)
	(segment
		(start 131.782312 -389.352536)
		(end 131.699 -389.435848)
		(width 0.14224)
		(layer "In6.Cu")
		(net "P5E_CPU1_P3_TX_BUF_DP<14>")
	)
	(segment
		(start 153.389584 -400.435572)
		(end 153.7843 -400.598894)
		(width 0.14224)
		(layer "In6.Cu")
		(net "P5E_CPU1_P3_TX_BUF_DP<14>")
	)
	(segment
		(start 153.7843 -400.598894)
		(end 153.858468 -400.778472)
		(width 0.14224)
		(layer "In6.Cu")
		(net "P5E_CPU1_P3_TX_BUF_DP<14>")
	)
	(segment
		(start 132.139436 -390.49325)
		(end 132.43306 -391.78992)
		(width 0.14224)
		(layer "In6.Cu")
		(net "P5E_CPU1_P3_TX_BUF_DP<14>")
	)
	(segment
		(start 155.071826 -401.132548)
		(end 155.466288 -401.29587)
		(width 0.14224)
		(layer "In6.Cu")
		(net "P5E_CPU1_P3_TX_BUF_DP<14>")
	)
	(segment
		(start 131.814824 -389.75411)
		(end 131.891786 -389.831072)
		(width 0.14224)
		(layer "In6.Cu")
		(net "P5E_CPU1_P3_TX_BUF_DP<14>")
	)
	(segment
		(start 147.263866 -398.413478)
		(end 147.435062 -398.322038)
		(width 0.14224)
		(layer "In6.Cu")
		(net "P5E_CPU1_P3_TX_BUF_DP<14>")
	)
	(segment
		(start 154.892502 -401.206716)
		(end 155.071826 -401.132548)
		(width 0.14224)
		(layer "In6.Cu")
		(net "P5E_CPU1_P3_TX_BUF_DP<14>")
	)
	(segment
		(start 147.435062 -398.322038)
		(end 147.843748 -398.445736)
		(width 0.14224)
		(layer "In6.Cu")
		(net "P5E_CPU1_P3_TX_BUF_DP<14>")
	)
	(segment
		(start 155.466288 -401.29587)
		(end 155.540456 -401.475194)
		(width 0.14224)
		(layer "In6.Cu")
		(net "P5E_CPU1_P3_TX_BUF_DP<14>")
	)
	(segment
		(start 140.421614 -396.338044)
		(end 147.263866 -398.413478)
		(width 0.14224)
		(layer "In6.Cu")
		(net "P5E_CPU1_P3_TX_BUF_DP<14>")
	)
	(segment
		(start 155.540456 -401.475194)
		(end 159.086296 -402.943822)
		(width 0.14224)
		(layer "In6.Cu")
		(net "P5E_CPU1_P3_TX_BUF_DP<14>")
	)
	(segment
		(start 132.80263 -394.429234)
		(end 140.421614 -396.338044)
		(width 0.14224)
		(layer "In6.Cu")
		(net "P5E_CPU1_P3_TX_BUF_DP<14>")
	)
	(segment
		(start 147.935188 -398.617186)
		(end 150.571454 -399.416778)
		(width 0.14224)
		(layer "In6.Cu")
		(net "P5E_CPU1_P3_TX_BUF_DP<14>")
	)
	(segment
		(start 153.210514 -400.509994)
		(end 153.389584 -400.435572)
		(width 0.14224)
		(layer "In6.Cu")
		(net "P5E_CPU1_P3_TX_BUF_DP<14>")
	)
	(segment
		(start 131.699 -389.435848)
		(end 131.699 -389.474456)
		(width 0.14224)
		(layer "In6.Cu")
		(net "P5E_CPU1_P3_TX_BUF_DP<14>")
	)
	(segment
		(start 132.093716 -390.228582)
		(end 132.11556 -390.36879)
		(width 0.14224)
		(layer "In6.Cu")
		(net "P5E_CPU1_P3_TX_BUF_DP<14>")
	)
	(segment
		(start 153.858468 -400.778472)
		(end 154.892502 -401.206716)
		(width 0.14224)
		(layer "In6.Cu")
		(net "P5E_CPU1_P3_TX_BUF_DP<14>")
	)
	(segment
		(start 159.883856 -406.71369)
		(end 160.174686 -407.00452)
		(width 0.14224)
		(layer "In6.Cu")
		(net "P5E_CPU1_P3_TX_BUF_DP<14>")
	)
	(segment
		(start 147.843748 -398.445736)
		(end 147.935188 -398.617186)
		(width 0.14224)
		(layer "In6.Cu")
		(net "P5E_CPU1_P3_TX_BUF_DP<14>")
	)
	(segment
		(start 132.453888 -391.978134)
		(end 132.453888 -394.060934)
		(width 0.14224)
		(layer "In6.Cu")
		(net "P5E_CPU1_P3_TX_BUF_DP<14>")
	)
	(segment
		(start 159.883856 -404.137622)
		(end 159.883856 -406.71369)
		(width 0.14224)
		(layer "In6.Cu")
		(net "P5E_CPU1_P3_TX_BUF_DP<14>")
	)
	(segment
		(start 150.571454 -399.416778)
		(end 153.210514 -400.509994)
		(width 0.14224)
		(layer "In6.Cu")
		(net "P5E_CPU1_P3_TX_BUF_DP<14>")
	)
	(segment
		(start 132.091176 -389.467344)
		(end 131.976368 -389.352536)
		(width 0.14224)
		(layer "In6.Cu")
		(net "P5E_CPU1_P3_TX_BUF_DP<14>")
	)
	(segment
		(start 131.976368 -389.352536)
		(end 131.782312 -389.352536)
		(width 0.14224)
		(layer "In6.Cu")
		(net "P5E_CPU1_P3_TX_BUF_DP<14>")
	)
	(arc
		(start 132.43306 -391.78992)
		(mid 132.44874 -391.883445)
		(end 132.453888 -391.978134)
		(width 0.14224)
		(layer "In6.Cu")
		(net "P5E_CPU1_P3_TX_BUF_DP<14>")
	)
	(arc
		(start 132.693664 -394.367512)
		(mid 132.743956 -394.405768)
		(end 132.80263 -394.429234)
		(width 0.14224)
		(layer "In6.Cu")
		(net "P5E_CPU1_P3_TX_BUF_DP<14>")
	)
	(arc
		(start 131.891786 -389.831072)
		(mid 132.024359 -390.013772)
		(end 132.093716 -390.228582)
		(width 0.14224)
		(layer "In6.Cu")
		(net "P5E_CPU1_P3_TX_BUF_DP<14>")
	)
	(arc
		(start 132.453888 -394.060934)
		(mid 132.466165 -394.122657)
		(end 132.501132 -394.17498)
		(width 0.14224)
		(layer "In6.Cu")
		(net "P5E_CPU1_P3_TX_BUF_DP<14>")
	)
	(arc
		(start 159.086296 -402.943822)
		(mid 159.66607 -403.419789)
		(end 159.883856 -404.137622)
		(width 0.14224)
		(layer "In6.Cu")
		(net "P5E_CPU1_P3_TX_BUF_DP<14>")
	)
	(arc
		(start 132.11556 -390.36879)
		(mid 132.126451 -390.431221)
		(end 132.139436 -390.49325)
		(width 0.14224)
		(layer "In6.Cu")
		(net "P5E_CPU1_P3_TX_BUF_DP<14>")
	)
	(arc
		(start 131.699 -389.474456)
		(mid 131.729104 -389.625799)
		(end 131.814824 -389.75411)
		(width 0.14224)
		(layer "In6.Cu")
		(net "P5E_CPU1_P3_TX_BUF_DP<14>")
	)
	(segment
		(start 130.37058 -389.467344)
		(end 130.89128 -389.467344)
		(width 0.127)
		(layer "F.Cu")
		(net "P5E_CPU1_P3_TX_BUF_DP<13>")
	)
	(segment
		(start 156.840936 -407.954734)
		(end 156.840936 -407.27503)
		(width 0.12954)
		(layer "B.Cu")
		(net "P5E_CPU1_P3_TX_BUF_DP<13>")
	)
	(segment
		(start 156.840936 -407.27503)
		(end 157.111446 -407.00452)
		(width 0.12954)
		(layer "B.Cu")
		(net "P5E_CPU1_P3_TX_BUF_DP<13>")
	)
	(segment
		(start 157.136846 -408.250644)
		(end 156.840936 -407.954734)
		(width 0.12954)
		(layer "B.Cu")
		(net "P5E_CPU1_P3_TX_BUF_DP<13>")
	)
	(segment
		(start 154.470862 -402.318728)
		(end 154.650186 -402.24456)
		(width 0.14224)
		(layer "In6.Cu")
		(net "P5E_CPU1_P3_TX_BUF_DP<13>")
	)
	(segment
		(start 145.62963 -399.037556)
		(end 145.805144 -398.954752)
		(width 0.14224)
		(layer "In6.Cu")
		(net "P5E_CPU1_P3_TX_BUF_DP<13>")
	)
	(segment
		(start 149.882606 -400.413728)
		(end 150.284688 -400.557492)
		(width 0.14224)
		(layer "In6.Cu")
		(net "P5E_CPU1_P3_TX_BUF_DP<13>")
	)
	(segment
		(start 156.820616 -406.71369)
		(end 157.111446 -407.00452)
		(width 0.14224)
		(layer "In6.Cu")
		(net "P5E_CPU1_P3_TX_BUF_DP<13>")
	)
	(segment
		(start 155.118816 -402.587206)
		(end 156.131006 -403.006306)
		(width 0.14224)
		(layer "In6.Cu")
		(net "P5E_CPU1_P3_TX_BUF_DP<13>")
	)
	(segment
		(start 156.820616 -404.038308)
		(end 156.820616 -406.71369)
		(width 0.14224)
		(layer "In6.Cu")
		(net "P5E_CPU1_P3_TX_BUF_DP<13>")
	)
	(segment
		(start 154.650186 -402.24456)
		(end 155.044648 -402.407882)
		(width 0.14224)
		(layer "In6.Cu")
		(net "P5E_CPU1_P3_TX_BUF_DP<13>")
	)
	(segment
		(start 145.228056 -398.894046)
		(end 145.62963 -399.037556)
		(width 0.14224)
		(layer "In6.Cu")
		(net "P5E_CPU1_P3_TX_BUF_DP<13>")
	)
	(segment
		(start 152.383998 -401.454366)
		(end 154.470862 -402.318728)
		(width 0.14224)
		(layer "In6.Cu")
		(net "P5E_CPU1_P3_TX_BUF_DP<13>")
	)
	(segment
		(start 131.253738 -391.787634)
		(end 131.253738 -394.374878)
		(width 0.14224)
		(layer "In6.Cu")
		(net "P5E_CPU1_P3_TX_BUF_DP<13>")
	)
	(segment
		(start 150.284688 -400.557492)
		(end 150.367746 -400.733006)
		(width 0.14224)
		(layer "In6.Cu")
		(net "P5E_CPU1_P3_TX_BUF_DP<13>")
	)
	(segment
		(start 146.206972 -399.098516)
		(end 146.29003 -399.27403)
		(width 0.14224)
		(layer "In6.Cu")
		(net "P5E_CPU1_P3_TX_BUF_DP<13>")
	)
	(segment
		(start 146.29003 -399.27403)
		(end 149.707346 -400.496532)
		(width 0.14224)
		(layer "In6.Cu")
		(net "P5E_CPU1_P3_TX_BUF_DP<13>")
	)
	(segment
		(start 132.294884 -395.265402)
		(end 137.872724 -396.662656)
		(width 0.14224)
		(layer "In6.Cu")
		(net "P5E_CPU1_P3_TX_BUF_DP<13>")
	)
	(segment
		(start 131.308856 -394.507974)
		(end 131.767834 -394.966952)
		(width 0.14224)
		(layer "In6.Cu")
		(net "P5E_CPU1_P3_TX_BUF_DP<13>")
	)
	(segment
		(start 130.89128 -389.467344)
		(end 130.776472 -389.352536)
		(width 0.14224)
		(layer "In6.Cu")
		(net "P5E_CPU1_P3_TX_BUF_DP<13>")
	)
	(segment
		(start 130.594608 -389.73379)
		(end 130.74777 -389.886952)
		(width 0.14224)
		(layer "In6.Cu")
		(net "P5E_CPU1_P3_TX_BUF_DP<13>")
	)
	(segment
		(start 130.506978 -389.441944)
		(end 130.506978 -389.522462)
		(width 0.14224)
		(layer "In6.Cu")
		(net "P5E_CPU1_P3_TX_BUF_DP<13>")
	)
	(segment
		(start 150.367746 -400.733006)
		(end 152.383998 -401.454366)
		(width 0.14224)
		(layer "In6.Cu")
		(net "P5E_CPU1_P3_TX_BUF_DP<13>")
	)
	(segment
		(start 130.867658 -390.176512)
		(end 130.867658 -390.430766)
		(width 0.14224)
		(layer "In6.Cu")
		(net "P5E_CPU1_P3_TX_BUF_DP<13>")
	)
	(segment
		(start 149.707346 -400.496532)
		(end 149.882606 -400.413728)
		(width 0.14224)
		(layer "In6.Cu")
		(net "P5E_CPU1_P3_TX_BUF_DP<13>")
	)
	(segment
		(start 130.776472 -389.352536)
		(end 130.596386 -389.352536)
		(width 0.14224)
		(layer "In6.Cu")
		(net "P5E_CPU1_P3_TX_BUF_DP<13>")
	)
	(segment
		(start 155.044648 -402.407882)
		(end 155.118816 -402.587206)
		(width 0.14224)
		(layer "In6.Cu")
		(net "P5E_CPU1_P3_TX_BUF_DP<13>")
	)
	(segment
		(start 130.892042 -390.59485)
		(end 131.253738 -391.787634)
		(width 0.14224)
		(layer "In6.Cu")
		(net "P5E_CPU1_P3_TX_BUF_DP<13>")
	)
	(segment
		(start 130.596386 -389.352536)
		(end 130.506978 -389.441944)
		(width 0.14224)
		(layer "In6.Cu")
		(net "P5E_CPU1_P3_TX_BUF_DP<13>")
	)
	(segment
		(start 145.805144 -398.954752)
		(end 146.206972 -399.098516)
		(width 0.14224)
		(layer "In6.Cu")
		(net "P5E_CPU1_P3_TX_BUF_DP<13>")
	)
	(segment
		(start 137.872724 -396.662656)
		(end 145.228056 -398.894046)
		(width 0.14224)
		(layer "In6.Cu")
		(net "P5E_CPU1_P3_TX_BUF_DP<13>")
	)
	(arc
		(start 130.867658 -390.430766)
		(mid 130.873794 -390.513707)
		(end 130.892042 -390.59485)
		(width 0.14224)
		(layer "In6.Cu")
		(net "P5E_CPU1_P3_TX_BUF_DP<13>")
	)
	(arc
		(start 130.506978 -389.522462)
		(mid 130.52975 -389.636854)
		(end 130.594608 -389.73379)
		(width 0.14224)
		(layer "In6.Cu")
		(net "P5E_CPU1_P3_TX_BUF_DP<13>")
	)
	(arc
		(start 130.74777 -389.886952)
		(mid 130.836485 -390.019817)
		(end 130.867658 -390.176512)
		(width 0.14224)
		(layer "In6.Cu")
		(net "P5E_CPU1_P3_TX_BUF_DP<13>")
	)
	(arc
		(start 131.767834 -394.966952)
		(mid 132.011108 -395.151927)
		(end 132.294884 -395.265402)
		(width 0.14224)
		(layer "In6.Cu")
		(net "P5E_CPU1_P3_TX_BUF_DP<13>")
	)
	(arc
		(start 131.253738 -394.374878)
		(mid 131.268065 -394.446904)
		(end 131.308856 -394.507974)
		(width 0.14224)
		(layer "In6.Cu")
		(net "P5E_CPU1_P3_TX_BUF_DP<13>")
	)
	(arc
		(start 156.131006 -403.006306)
		(mid 156.632309 -403.417721)
		(end 156.820616 -404.038308)
		(width 0.14224)
		(layer "In6.Cu")
		(net "P5E_CPU1_P3_TX_BUF_DP<13>")
	)
	(segment
		(start 129.17043 -389.467344)
		(end 129.69113 -389.467344)
		(width 0.127)
		(layer "F.Cu")
		(net "P5E_CPU1_P3_TX_BUF_DP<12>")
	)
	(segment
		(start 153.777696 -407.27503)
		(end 154.048206 -407.00452)
		(width 0.12954)
		(layer "B.Cu")
		(net "P5E_CPU1_P3_TX_BUF_DP<12>")
	)
	(segment
		(start 154.073606 -408.250644)
		(end 153.777696 -407.954734)
		(width 0.12954)
		(layer "B.Cu")
		(net "P5E_CPU1_P3_TX_BUF_DP<12>")
	)
	(segment
		(start 153.777696 -407.954734)
		(end 153.777696 -407.27503)
		(width 0.12954)
		(layer "B.Cu")
		(net "P5E_CPU1_P3_TX_BUF_DP<12>")
	)
	(segment
		(start 129.69113 -389.467344)
		(end 129.576322 -389.352536)
		(width 0.14224)
		(layer "In6.Cu")
		(net "P5E_CPU1_P3_TX_BUF_DP<12>")
	)
	(segment
		(start 150.860252 -402.010372)
		(end 151.254714 -402.173694)
		(width 0.14224)
		(layer "In6.Cu")
		(net "P5E_CPU1_P3_TX_BUF_DP<12>")
	)
	(segment
		(start 136.96442 -397.44015)
		(end 146.322542 -400.279108)
		(width 0.14224)
		(layer "In6.Cu")
		(net "P5E_CPU1_P3_TX_BUF_DP<12>")
	)
	(segment
		(start 151.254714 -402.173694)
		(end 151.328882 -402.353272)
		(width 0.14224)
		(layer "In6.Cu")
		(net "P5E_CPU1_P3_TX_BUF_DP<12>")
	)
	(segment
		(start 153.757376 -406.71369)
		(end 154.048206 -407.00452)
		(width 0.14224)
		(layer "In6.Cu")
		(net "P5E_CPU1_P3_TX_BUF_DP<12>")
	)
	(segment
		(start 146.322542 -400.279108)
		(end 149.63902 -401.65274)
		(width 0.14224)
		(layer "In6.Cu")
		(net "P5E_CPU1_P3_TX_BUF_DP<12>")
	)
	(segment
		(start 130.549142 -395.151102)
		(end 130.851148 -395.453108)
		(width 0.14224)
		(layer "In6.Cu")
		(net "P5E_CPU1_P3_TX_BUF_DP<12>")
	)
	(segment
		(start 150.681182 -402.08454)
		(end 150.860252 -402.010372)
		(width 0.14224)
		(layer "In6.Cu")
		(net "P5E_CPU1_P3_TX_BUF_DP<12>")
	)
	(segment
		(start 150.286974 -401.921472)
		(end 150.681182 -402.08454)
		(width 0.14224)
		(layer "In6.Cu")
		(net "P5E_CPU1_P3_TX_BUF_DP<12>")
	)
	(segment
		(start 129.667508 -390.176512)
		(end 129.667508 -390.36625)
		(width 0.14224)
		(layer "In6.Cu")
		(net "P5E_CPU1_P3_TX_BUF_DP<12>")
	)
	(segment
		(start 129.307082 -389.458708)
		(end 129.307082 -389.528304)
		(width 0.14224)
		(layer "In6.Cu")
		(net "P5E_CPU1_P3_TX_BUF_DP<12>")
	)
	(segment
		(start 149.63902 -401.652994)
		(end 149.81809 -401.578572)
		(width 0.14224)
		(layer "In6.Cu")
		(net "P5E_CPU1_P3_TX_BUF_DP<12>")
	)
	(segment
		(start 129.68732 -390.4996)
		(end 130.053588 -391.70737)
		(width 0.14224)
		(layer "In6.Cu")
		(net "P5E_CPU1_P3_TX_BUF_DP<12>")
	)
	(segment
		(start 153.259028 -403.15261)
		(end 153.42616 -403.319742)
		(width 0.14224)
		(layer "In6.Cu")
		(net "P5E_CPU1_P3_TX_BUF_DP<12>")
	)
	(segment
		(start 151.328882 -402.353272)
		(end 151.328882 -402.353018)
		(width 0.14224)
		(layer "In6.Cu")
		(net "P5E_CPU1_P3_TX_BUF_DP<12>")
	)
	(segment
		(start 130.150108 -394.946124)
		(end 130.355086 -395.151102)
		(width 0.14224)
		(layer "In6.Cu")
		(net "P5E_CPU1_P3_TX_BUF_DP<12>")
	)
	(segment
		(start 130.355086 -395.151102)
		(end 130.549142 -395.151102)
		(width 0.14224)
		(layer "In6.Cu")
		(net "P5E_CPU1_P3_TX_BUF_DP<12>")
	)
	(segment
		(start 153.757376 -404.119334)
		(end 153.757376 -406.71369)
		(width 0.14224)
		(layer "In6.Cu")
		(net "P5E_CPU1_P3_TX_BUF_DP<12>")
	)
	(segment
		(start 129.576322 -389.352536)
		(end 129.413254 -389.352536)
		(width 0.14224)
		(layer "In6.Cu")
		(net "P5E_CPU1_P3_TX_BUF_DP<12>")
	)
	(segment
		(start 129.413254 -389.352536)
		(end 129.307082 -389.458708)
		(width 0.14224)
		(layer "In6.Cu")
		(net "P5E_CPU1_P3_TX_BUF_DP<12>")
	)
	(segment
		(start 130.851148 -395.453108)
		(end 130.851148 -395.647164)
		(width 0.14224)
		(layer "In6.Cu")
		(net "P5E_CPU1_P3_TX_BUF_DP<12>")
	)
	(segment
		(start 149.81809 -401.578572)
		(end 150.212552 -401.741894)
		(width 0.14224)
		(layer "In6.Cu")
		(net "P5E_CPU1_P3_TX_BUF_DP<12>")
	)
	(segment
		(start 130.053588 -391.70737)
		(end 130.053588 -394.713206)
		(width 0.14224)
		(layer "In6.Cu")
		(net "P5E_CPU1_P3_TX_BUF_DP<12>")
	)
	(segment
		(start 131.411218 -396.048484)
		(end 136.96442 -397.44015)
		(width 0.14224)
		(layer "In6.Cu")
		(net "P5E_CPU1_P3_TX_BUF_DP<12>")
	)
	(segment
		(start 130.851148 -395.647164)
		(end 131.04495 -395.840966)
		(width 0.14224)
		(layer "In6.Cu")
		(net "P5E_CPU1_P3_TX_BUF_DP<12>")
	)
	(segment
		(start 149.63902 -401.65274)
		(end 149.63902 -401.652994)
		(width 0.14224)
		(layer "In6.Cu")
		(net "P5E_CPU1_P3_TX_BUF_DP<12>")
	)
	(segment
		(start 129.390648 -389.72998)
		(end 129.54762 -389.886952)
		(width 0.14224)
		(layer "In6.Cu")
		(net "P5E_CPU1_P3_TX_BUF_DP<12>")
	)
	(segment
		(start 150.212552 -401.741894)
		(end 150.286974 -401.921472)
		(width 0.14224)
		(layer "In6.Cu")
		(net "P5E_CPU1_P3_TX_BUF_DP<12>")
	)
	(segment
		(start 151.328882 -402.353018)
		(end 153.259028 -403.15261)
		(width 0.14224)
		(layer "In6.Cu")
		(net "P5E_CPU1_P3_TX_BUF_DP<12>")
	)
	(arc
		(start 129.54762 -389.886952)
		(mid 129.636335 -390.019817)
		(end 129.667508 -390.176512)
		(width 0.14224)
		(layer "In6.Cu")
		(net "P5E_CPU1_P3_TX_BUF_DP<12>")
	)
	(arc
		(start 130.053588 -394.713206)
		(mid 130.07868 -394.839262)
		(end 130.150108 -394.946124)
		(width 0.14224)
		(layer "In6.Cu")
		(net "P5E_CPU1_P3_TX_BUF_DP<12>")
	)
	(arc
		(start 131.04495 -395.840966)
		(mid 131.213997 -395.969586)
		(end 131.411218 -396.048484)
		(width 0.14224)
		(layer "In6.Cu")
		(net "P5E_CPU1_P3_TX_BUF_DP<12>")
	)
	(arc
		(start 129.307082 -389.528304)
		(mid 129.328795 -389.637461)
		(end 129.390648 -389.72998)
		(width 0.14224)
		(layer "In6.Cu")
		(net "P5E_CPU1_P3_TX_BUF_DP<12>")
	)
	(arc
		(start 153.42616 -403.319742)
		(mid 153.671285 -403.686598)
		(end 153.757376 -404.119334)
		(width 0.14224)
		(layer "In6.Cu")
		(net "P5E_CPU1_P3_TX_BUF_DP<12>")
	)
	(arc
		(start 129.667508 -390.36625)
		(mid 129.672496 -390.433655)
		(end 129.68732 -390.4996)
		(width 0.14224)
		(layer "In6.Cu")
		(net "P5E_CPU1_P3_TX_BUF_DP<12>")
	)
	(segment
		(start 127.970534 -389.467344)
		(end 128.491234 -389.467344)
		(width 0.127)
		(layer "F.Cu")
		(net "P5E_CPU1_P3_TX_BUF_DP<11>")
	)
	(segment
		(start 151.010366 -408.250644)
		(end 150.714456 -407.954734)
		(width 0.12954)
		(layer "B.Cu")
		(net "P5E_CPU1_P3_TX_BUF_DP<11>")
	)
	(segment
		(start 150.714456 -407.954734)
		(end 150.714456 -407.27503)
		(width 0.12954)
		(layer "B.Cu")
		(net "P5E_CPU1_P3_TX_BUF_DP<11>")
	)
	(segment
		(start 150.714456 -407.27503)
		(end 150.984966 -407.00452)
		(width 0.12954)
		(layer "B.Cu")
		(net "P5E_CPU1_P3_TX_BUF_DP<11>")
	)
	(segment
		(start 129.678938 -396.251684)
		(end 130.041904 -396.61465)
		(width 0.14224)
		(layer "In6.Cu")
		(net "P5E_CPU1_P3_TX_BUF_DP<11>")
	)
	(segment
		(start 130.250946 -396.733014)
		(end 135.185658 -397.96847)
		(width 0.14224)
		(layer "In6.Cu")
		(net "P5E_CPU1_P3_TX_BUF_DP<11>")
	)
	(segment
		(start 128.491234 -389.467344)
		(end 128.376426 -389.352536)
		(width 0.14224)
		(layer "In6.Cu")
		(net "P5E_CPU1_P3_TX_BUF_DP<11>")
	)
	(segment
		(start 150.831296 -405.133048)
		(end 150.831296 -405.559768)
		(width 0.14224)
		(layer "In6.Cu")
		(net "P5E_CPU1_P3_TX_BUF_DP<11>")
	)
	(segment
		(start 150.694136 -404.24227)
		(end 150.694136 -404.995888)
		(width 0.14224)
		(layer "In6.Cu")
		(net "P5E_CPU1_P3_TX_BUF_DP<11>")
	)
	(segment
		(start 128.517904 -390.61517)
		(end 128.853692 -391.72261)
		(width 0.14224)
		(layer "In6.Cu")
		(net "P5E_CPU1_P3_TX_BUF_DP<11>")
	)
	(segment
		(start 147.74164 -402.086572)
		(end 147.920964 -402.012658)
		(width 0.14224)
		(layer "In6.Cu")
		(net "P5E_CPU1_P3_TX_BUF_DP<11>")
	)
	(segment
		(start 144.98066 -400.940016)
		(end 147.74164 -402.086572)
		(width 0.14224)
		(layer "In6.Cu")
		(net "P5E_CPU1_P3_TX_BUF_DP<11>")
	)
	(segment
		(start 128.19634 -389.352536)
		(end 128.106932 -389.441944)
		(width 0.14224)
		(layer "In6.Cu")
		(net "P5E_CPU1_P3_TX_BUF_DP<11>")
	)
	(segment
		(start 129.0066 -395.579346)
		(end 129.182876 -395.755622)
		(width 0.14224)
		(layer "In6.Cu")
		(net "P5E_CPU1_P3_TX_BUF_DP<11>")
	)
	(segment
		(start 148.38934 -402.355812)
		(end 149.95271 -403.005036)
		(width 0.14224)
		(layer "In6.Cu")
		(net "P5E_CPU1_P3_TX_BUF_DP<11>")
	)
	(segment
		(start 150.195788 -403.16912)
		(end 150.283926 -403.251924)
		(width 0.14224)
		(layer "In6.Cu")
		(net "P5E_CPU1_P3_TX_BUF_DP<11>")
	)
	(segment
		(start 135.185658 -397.96847)
		(end 144.98066 -400.940016)
		(width 0.14224)
		(layer "In6.Cu")
		(net "P5E_CPU1_P3_TX_BUF_DP<11>")
	)
	(segment
		(start 129.376932 -395.755622)
		(end 129.678938 -396.057628)
		(width 0.14224)
		(layer "In6.Cu")
		(net "P5E_CPU1_P3_TX_BUF_DP<11>")
	)
	(segment
		(start 147.920964 -402.012658)
		(end 148.315172 -402.176234)
		(width 0.14224)
		(layer "In6.Cu")
		(net "P5E_CPU1_P3_TX_BUF_DP<11>")
	)
	(segment
		(start 128.106932 -389.441944)
		(end 128.106932 -389.543544)
		(width 0.14224)
		(layer "In6.Cu")
		(net "P5E_CPU1_P3_TX_BUF_DP<11>")
	)
	(segment
		(start 128.376426 -389.352536)
		(end 128.19634 -389.352536)
		(width 0.14224)
		(layer "In6.Cu")
		(net "P5E_CPU1_P3_TX_BUF_DP<11>")
	)
	(segment
		(start 128.853692 -391.72261)
		(end 128.853692 -395.210538)
		(width 0.14224)
		(layer "In6.Cu")
		(net "P5E_CPU1_P3_TX_BUF_DP<11>")
	)
	(segment
		(start 150.694136 -405.696928)
		(end 150.694136 -406.71369)
		(width 0.14224)
		(layer "In6.Cu")
		(net "P5E_CPU1_P3_TX_BUF_DP<11>")
	)
	(segment
		(start 150.694136 -404.995888)
		(end 150.831296 -405.133048)
		(width 0.14224)
		(layer "In6.Cu")
		(net "P5E_CPU1_P3_TX_BUF_DP<11>")
	)
	(segment
		(start 148.315172 -402.176234)
		(end 148.38934 -402.355812)
		(width 0.14224)
		(layer "In6.Cu")
		(net "P5E_CPU1_P3_TX_BUF_DP<11>")
	)
	(segment
		(start 128.179576 -389.718804)
		(end 128.347724 -389.886952)
		(width 0.14224)
		(layer "In6.Cu")
		(net "P5E_CPU1_P3_TX_BUF_DP<11>")
	)
	(segment
		(start 150.831296 -405.559768)
		(end 150.694136 -405.696928)
		(width 0.14224)
		(layer "In6.Cu")
		(net "P5E_CPU1_P3_TX_BUF_DP<11>")
	)
	(segment
		(start 150.694136 -406.71369)
		(end 150.984966 -407.00452)
		(width 0.14224)
		(layer "In6.Cu")
		(net "P5E_CPU1_P3_TX_BUF_DP<11>")
	)
	(segment
		(start 129.678938 -396.057628)
		(end 129.678938 -396.251684)
		(width 0.14224)
		(layer "In6.Cu")
		(net "P5E_CPU1_P3_TX_BUF_DP<11>")
	)
	(segment
		(start 128.467612 -390.176512)
		(end 128.467612 -390.275064)
		(width 0.14224)
		(layer "In6.Cu")
		(net "P5E_CPU1_P3_TX_BUF_DP<11>")
	)
	(segment
		(start 129.182876 -395.755622)
		(end 129.376932 -395.755622)
		(width 0.14224)
		(layer "In6.Cu")
		(net "P5E_CPU1_P3_TX_BUF_DP<11>")
	)
	(arc
		(start 128.467612 -390.275064)
		(mid 128.480208 -390.446974)
		(end 128.517904 -390.61517)
		(width 0.14224)
		(layer "In6.Cu")
		(net "P5E_CPU1_P3_TX_BUF_DP<11>")
	)
	(arc
		(start 149.95271 -403.005036)
		(mid 150.080844 -403.077308)
		(end 150.195788 -403.16912)
		(width 0.14224)
		(layer "In6.Cu")
		(net "P5E_CPU1_P3_TX_BUF_DP<11>")
	)
	(arc
		(start 128.347724 -389.886952)
		(mid 128.436439 -390.019817)
		(end 128.467612 -390.176512)
		(width 0.14224)
		(layer "In6.Cu")
		(net "P5E_CPU1_P3_TX_BUF_DP<11>")
	)
	(arc
		(start 128.106932 -389.543544)
		(mid 128.125818 -389.638399)
		(end 128.179576 -389.718804)
		(width 0.14224)
		(layer "In6.Cu")
		(net "P5E_CPU1_P3_TX_BUF_DP<11>")
	)
	(arc
		(start 130.041904 -396.61465)
		(mid 130.13838 -396.688041)
		(end 130.250946 -396.733014)
		(width 0.14224)
		(layer "In6.Cu")
		(net "P5E_CPU1_P3_TX_BUF_DP<11>")
	)
	(arc
		(start 128.853692 -395.210538)
		(mid 128.893435 -395.410162)
		(end 129.0066 -395.579346)
		(width 0.14224)
		(layer "In6.Cu")
		(net "P5E_CPU1_P3_TX_BUF_DP<11>")
	)
	(arc
		(start 150.283926 -403.251924)
		(mid 150.587529 -403.706299)
		(end 150.694136 -404.24227)
		(width 0.14224)
		(layer "In6.Cu")
		(net "P5E_CPU1_P3_TX_BUF_DP<11>")
	)
	(segment
		(start 126.770638 -389.467344)
		(end 127.291338 -389.467344)
		(width 0.127)
		(layer "F.Cu")
		(net "P5E_CPU1_P3_TX_BUF_DP<10>")
	)
	(segment
		(start 147.651216 -407.27503)
		(end 147.921726 -407.00452)
		(width 0.12954)
		(layer "B.Cu")
		(net "P5E_CPU1_P3_TX_BUF_DP<10>")
	)
	(segment
		(start 147.947126 -408.250644)
		(end 147.651216 -407.954734)
		(width 0.12954)
		(layer "B.Cu")
		(net "P5E_CPU1_P3_TX_BUF_DP<10>")
	)
	(segment
		(start 147.651216 -407.954734)
		(end 147.651216 -407.27503)
		(width 0.12954)
		(layer "B.Cu")
		(net "P5E_CPU1_P3_TX_BUF_DP<10>")
	)
	(segment
		(start 126.907036 -389.421624)
		(end 126.907036 -389.541766)
		(width 0.14224)
		(layer "In6.Cu")
		(net "P5E_CPU1_P3_TX_BUF_DP<10>")
	)
	(segment
		(start 145.543778 -402.481288)
		(end 145.942304 -402.633434)
		(width 0.14224)
		(layer "In6.Cu")
		(net "P5E_CPU1_P3_TX_BUF_DP<10>")
	)
	(segment
		(start 134.349236 -398.722596)
		(end 134.394194 -398.735042)
		(width 0.14224)
		(layer "In6.Cu")
		(net "P5E_CPU1_P3_TX_BUF_DP<10>")
	)
	(segment
		(start 126.98095 -389.720074)
		(end 127.147828 -389.886698)
		(width 0.14224)
		(layer "In6.Cu")
		(net "P5E_CPU1_P3_TX_BUF_DP<10>")
	)
	(segment
		(start 144.888712 -402.23059)
		(end 145.06575 -402.151342)
		(width 0.14224)
		(layer "In6.Cu")
		(net "P5E_CPU1_P3_TX_BUF_DP<10>")
	)
	(segment
		(start 145.464784 -402.303742)
		(end 145.543778 -402.481288)
		(width 0.14224)
		(layer "In6.Cu")
		(net "P5E_CPU1_P3_TX_BUF_DP<10>")
	)
	(segment
		(start 127.615696 -391.637012)
		(end 127.615696 -395.190218)
		(width 0.14224)
		(layer "In6.Cu")
		(net "P5E_CPU1_P3_TX_BUF_DP<10>")
	)
	(segment
		(start 129.44729 -397.403828)
		(end 129.753868 -397.564356)
		(width 0.14224)
		(layer "In6.Cu")
		(net "P5E_CPU1_P3_TX_BUF_DP<10>")
	)
	(segment
		(start 144.012158 -401.748752)
		(end 144.411192 -401.900898)
		(width 0.14224)
		(layer "In6.Cu")
		(net "P5E_CPU1_P3_TX_BUF_DP<10>")
	)
	(segment
		(start 144.411192 -401.900898)
		(end 144.490186 -402.078444)
		(width 0.14224)
		(layer "In6.Cu")
		(net "P5E_CPU1_P3_TX_BUF_DP<10>")
	)
	(segment
		(start 127.291338 -389.467344)
		(end 127.17653 -389.352536)
		(width 0.14224)
		(layer "In6.Cu")
		(net "P5E_CPU1_P3_TX_BUF_DP<10>")
	)
	(segment
		(start 141.625574 -400.93519)
		(end 143.068802 -401.533614)
		(width 0.14224)
		(layer "In6.Cu")
		(net "P5E_CPU1_P3_TX_BUF_DP<10>")
	)
	(segment
		(start 134.394194 -398.735042)
		(end 141.506448 -400.892518)
		(width 0.14224)
		(layer "In6.Cu")
		(net "P5E_CPU1_P3_TX_BUF_DP<10>")
	)
	(segment
		(start 127.908812 -395.897862)
		(end 129.325116 -397.314166)
		(width 0.14224)
		(layer "In6.Cu")
		(net "P5E_CPU1_P3_TX_BUF_DP<10>")
	)
	(segment
		(start 127.267716 -390.176258)
		(end 127.267716 -390.33958)
		(width 0.14224)
		(layer "In6.Cu")
		(net "P5E_CPU1_P3_TX_BUF_DP<10>")
	)
	(segment
		(start 126.976124 -389.352536)
		(end 126.907036 -389.421624)
		(width 0.14224)
		(layer "In6.Cu")
		(net "P5E_CPU1_P3_TX_BUF_DP<10>")
	)
	(segment
		(start 127.286258 -390.464294)
		(end 127.591312 -391.472674)
		(width 0.14224)
		(layer "In6.Cu")
		(net "P5E_CPU1_P3_TX_BUF_DP<10>")
	)
	(segment
		(start 145.06575 -402.151342)
		(end 145.464784 -402.303742)
		(width 0.14224)
		(layer "In6.Cu")
		(net "P5E_CPU1_P3_TX_BUF_DP<10>")
	)
	(segment
		(start 147.630896 -403.854158)
		(end 147.630896 -406.71369)
		(width 0.14224)
		(layer "In6.Cu")
		(net "P5E_CPU1_P3_TX_BUF_DP<10>")
	)
	(segment
		(start 147.630896 -406.71369)
		(end 147.921726 -407.00452)
		(width 0.14224)
		(layer "In6.Cu")
		(net "P5E_CPU1_P3_TX_BUF_DP<10>")
	)
	(segment
		(start 146.99615 -403.036532)
		(end 147.1803 -403.102318)
		(width 0.14224)
		(layer "In6.Cu")
		(net "P5E_CPU1_P3_TX_BUF_DP<10>")
	)
	(segment
		(start 146.59737 -402.884132)
		(end 146.99615 -403.036532)
		(width 0.14224)
		(layer "In6.Cu")
		(net "P5E_CPU1_P3_TX_BUF_DP<10>")
	)
	(segment
		(start 146.518122 -402.70684)
		(end 146.59737 -402.884132)
		(width 0.14224)
		(layer "In6.Cu")
		(net "P5E_CPU1_P3_TX_BUF_DP<10>")
	)
	(segment
		(start 145.942304 -402.633434)
		(end 146.119342 -402.55444)
		(width 0.14224)
		(layer "In6.Cu")
		(net "P5E_CPU1_P3_TX_BUF_DP<10>")
	)
	(segment
		(start 143.83512 -401.827746)
		(end 144.012158 -401.748752)
		(width 0.14224)
		(layer "In6.Cu")
		(net "P5E_CPU1_P3_TX_BUF_DP<10>")
	)
	(segment
		(start 143.141192 -401.56257)
		(end 143.83512 -401.827746)
		(width 0.14224)
		(layer "In6.Cu")
		(net "P5E_CPU1_P3_TX_BUF_DP<10>")
	)
	(segment
		(start 127.17653 -389.352536)
		(end 126.976124 -389.352536)
		(width 0.14224)
		(layer "In6.Cu")
		(net "P5E_CPU1_P3_TX_BUF_DP<10>")
	)
	(segment
		(start 146.119342 -402.55444)
		(end 146.518122 -402.70684)
		(width 0.14224)
		(layer "In6.Cu")
		(net "P5E_CPU1_P3_TX_BUF_DP<10>")
	)
	(segment
		(start 129.809748 -397.585692)
		(end 134.349236 -398.722596)
		(width 0.14224)
		(layer "In6.Cu")
		(net "P5E_CPU1_P3_TX_BUF_DP<10>")
	)
	(segment
		(start 144.490186 -402.078444)
		(end 144.888712 -402.23059)
		(width 0.14224)
		(layer "In6.Cu")
		(net "P5E_CPU1_P3_TX_BUF_DP<10>")
	)
	(arc
		(start 127.615696 -395.190218)
		(mid 127.691874 -395.573192)
		(end 127.908812 -395.897862)
		(width 0.14224)
		(layer "In6.Cu")
		(net "P5E_CPU1_P3_TX_BUF_DP<10>")
	)
	(arc
		(start 141.506448 -400.892518)
		(mid 141.566534 -400.912393)
		(end 141.625574 -400.93519)
		(width 0.14224)
		(layer "In6.Cu")
		(net "P5E_CPU1_P3_TX_BUF_DP<10>")
	)
	(arc
		(start 129.753868 -397.564356)
		(mid 129.781178 -397.576672)
		(end 129.809748 -397.585692)
		(width 0.14224)
		(layer "In6.Cu")
		(net "P5E_CPU1_P3_TX_BUF_DP<10>")
	)
	(arc
		(start 129.325116 -397.314166)
		(mid 129.382801 -397.363632)
		(end 129.44729 -397.403828)
		(width 0.14224)
		(layer "In6.Cu")
		(net "P5E_CPU1_P3_TX_BUF_DP<10>")
	)
	(arc
		(start 126.907036 -389.541766)
		(mid 126.92625 -389.638273)
		(end 126.98095 -389.720074)
		(width 0.14224)
		(layer "In6.Cu")
		(net "P5E_CPU1_P3_TX_BUF_DP<10>")
	)
	(arc
		(start 147.467574 -403.331426)
		(mid 147.583949 -403.581946)
		(end 147.630896 -403.854158)
		(width 0.14224)
		(layer "In6.Cu")
		(net "P5E_CPU1_P3_TX_BUF_DP<10>")
	)
	(arc
		(start 127.267716 -390.33958)
		(mid 127.272391 -390.402621)
		(end 127.286258 -390.464294)
		(width 0.14224)
		(layer "In6.Cu")
		(net "P5E_CPU1_P3_TX_BUF_DP<10>")
	)
	(arc
		(start 127.591312 -391.472674)
		(mid 127.609556 -391.553945)
		(end 127.615696 -391.637012)
		(width 0.14224)
		(layer "In6.Cu")
		(net "P5E_CPU1_P3_TX_BUF_DP<10>")
	)
	(arc
		(start 127.147828 -389.886698)
		(mid 127.236621 -390.019536)
		(end 127.267716 -390.176258)
		(width 0.14224)
		(layer "In6.Cu")
		(net "P5E_CPU1_P3_TX_BUF_DP<10>")
	)
	(arc
		(start 147.1803 -403.102318)
		(mid 147.342979 -403.192992)
		(end 147.467574 -403.331426)
		(width 0.14224)
		(layer "In6.Cu")
		(net "P5E_CPU1_P3_TX_BUF_DP<10>")
	)
	(arc
		(start 143.068802 -401.533614)
		(mid 143.104896 -401.548345)
		(end 143.141192 -401.56257)
		(width 0.14224)
		(layer "In6.Cu")
		(net "P5E_CPU1_P3_TX_BUF_DP<10>")
	)
	(segment
		(start 114.770662 -389.467344)
		(end 115.291362 -389.467344)
		(width 0.127)
		(layer "F.Cu")
		(net "P5E_CPU1_P3_TX_BUF_DP<0>")
	)
	(segment
		(start 117.018816 -407.27503)
		(end 117.289326 -407.00452)
		(width 0.12954)
		(layer "B.Cu")
		(net "P5E_CPU1_P3_TX_BUF_DP<0>")
	)
	(segment
		(start 117.018816 -407.954734)
		(end 117.018816 -407.27503)
		(width 0.12954)
		(layer "B.Cu")
		(net "P5E_CPU1_P3_TX_BUF_DP<0>")
	)
	(segment
		(start 117.314726 -408.250644)
		(end 117.018816 -407.954734)
		(width 0.12954)
		(layer "B.Cu")
		(net "P5E_CPU1_P3_TX_BUF_DP<0>")
	)
	(segment
		(start 116.351558 -399.640806)
		(end 116.434616 -400.059652)
		(width 0.14224)
		(layer "In6.Cu")
		(net "P5E_CPU1_P3_TX_BUF_DP<0>")
	)
	(segment
		(start 116.190268 -399.532856)
		(end 116.351558 -399.640806)
		(width 0.14224)
		(layer "In6.Cu")
		(net "P5E_CPU1_P3_TX_BUF_DP<0>")
	)
	(segment
		(start 116.76507 -402.433536)
		(end 116.998496 -403.612604)
		(width 0.14224)
		(layer "In6.Cu")
		(net "P5E_CPU1_P3_TX_BUF_DP<0>")
	)
	(segment
		(start 116.57076 -400.74723)
		(end 116.653818 -401.166076)
		(width 0.14224)
		(layer "In6.Cu")
		(net "P5E_CPU1_P3_TX_BUF_DP<0>")
	)
	(segment
		(start 115.176554 -389.352536)
		(end 114.996468 -389.352536)
		(width 0.14224)
		(layer "In6.Cu")
		(net "P5E_CPU1_P3_TX_BUF_DP<0>")
	)
	(segment
		(start 116.434616 -400.059652)
		(end 116.326666 -400.220942)
		(width 0.14224)
		(layer "In6.Cu")
		(net "P5E_CPU1_P3_TX_BUF_DP<0>")
	)
	(segment
		(start 116.545868 -401.327366)
		(end 116.628672 -401.745704)
		(width 0.14224)
		(layer "In6.Cu")
		(net "P5E_CPU1_P3_TX_BUF_DP<0>")
	)
	(segment
		(start 114.975386 -389.714232)
		(end 115.147598 -389.886444)
		(width 0.14224)
		(layer "In6.Cu")
		(net "P5E_CPU1_P3_TX_BUF_DP<0>")
	)
	(segment
		(start 116.190522 -399.532856)
		(end 116.190268 -399.532856)
		(width 0.14224)
		(layer "In6.Cu")
		(net "P5E_CPU1_P3_TX_BUF_DP<0>")
	)
	(segment
		(start 115.286282 -390.485884)
		(end 115.62334 -391.59688)
		(width 0.14224)
		(layer "In6.Cu")
		(net "P5E_CPU1_P3_TX_BUF_DP<0>")
	)
	(segment
		(start 115.291362 -389.467344)
		(end 115.176554 -389.352536)
		(width 0.14224)
		(layer "In6.Cu")
		(net "P5E_CPU1_P3_TX_BUF_DP<0>")
	)
	(segment
		(start 116.653818 -401.166076)
		(end 116.545868 -401.327366)
		(width 0.14224)
		(layer "In6.Cu")
		(net "P5E_CPU1_P3_TX_BUF_DP<0>")
	)
	(segment
		(start 114.90706 -389.441944)
		(end 114.90706 -389.549894)
		(width 0.14224)
		(layer "In6.Cu")
		(net "P5E_CPU1_P3_TX_BUF_DP<0>")
	)
	(segment
		(start 114.996468 -389.352536)
		(end 114.90706 -389.441944)
		(width 0.14224)
		(layer "In6.Cu")
		(net "P5E_CPU1_P3_TX_BUF_DP<0>")
	)
	(segment
		(start 116.998496 -406.71369)
		(end 117.289326 -407.00452)
		(width 0.14224)
		(layer "In6.Cu")
		(net "P5E_CPU1_P3_TX_BUF_DP<0>")
	)
	(segment
		(start 115.65382 -396.824962)
		(end 116.190522 -399.532856)
		(width 0.14224)
		(layer "In6.Cu")
		(net "P5E_CPU1_P3_TX_BUF_DP<0>")
	)
	(segment
		(start 116.326666 -400.220942)
		(end 116.40947 -400.63928)
		(width 0.14224)
		(layer "In6.Cu")
		(net "P5E_CPU1_P3_TX_BUF_DP<0>")
	)
	(segment
		(start 115.26774 -390.17575)
		(end 115.26774 -390.360916)
		(width 0.14224)
		(layer "In6.Cu")
		(net "P5E_CPU1_P3_TX_BUF_DP<0>")
	)
	(segment
		(start 116.998496 -403.612604)
		(end 116.998496 -406.71369)
		(width 0.14224)
		(layer "In6.Cu")
		(net "P5E_CPU1_P3_TX_BUF_DP<0>")
	)
	(segment
		(start 116.628672 -401.745704)
		(end 116.789962 -401.853654)
		(width 0.14224)
		(layer "In6.Cu")
		(net "P5E_CPU1_P3_TX_BUF_DP<0>")
	)
	(segment
		(start 116.87302 -402.2725)
		(end 116.76507 -402.433536)
		(width 0.14224)
		(layer "In6.Cu")
		(net "P5E_CPU1_P3_TX_BUF_DP<0>")
	)
	(segment
		(start 116.40947 -400.63928)
		(end 116.57076 -400.74723)
		(width 0.14224)
		(layer "In6.Cu")
		(net "P5E_CPU1_P3_TX_BUF_DP<0>")
	)
	(segment
		(start 116.789962 -401.853654)
		(end 116.87302 -402.2725)
		(width 0.14224)
		(layer "In6.Cu")
		(net "P5E_CPU1_P3_TX_BUF_DP<0>")
	)
	(segment
		(start 115.65382 -391.803382)
		(end 115.65382 -396.824962)
		(width 0.14224)
		(layer "In6.Cu")
		(net "P5E_CPU1_P3_TX_BUF_DP<0>")
	)
	(arc
		(start 115.147598 -389.886444)
		(mid 115.236479 -390.019135)
		(end 115.26774 -390.17575)
		(width 0.14224)
		(layer "In6.Cu")
		(net "P5E_CPU1_P3_TX_BUF_DP<0>")
	)
	(arc
		(start 114.90706 -389.549894)
		(mid 114.924869 -389.638863)
		(end 114.975386 -389.714232)
		(width 0.14224)
		(layer "In6.Cu")
		(net "P5E_CPU1_P3_TX_BUF_DP<0>")
	)
	(arc
		(start 115.26774 -390.360916)
		(mid 115.272407 -390.424082)
		(end 115.286282 -390.485884)
		(width 0.14224)
		(layer "In6.Cu")
		(net "P5E_CPU1_P3_TX_BUF_DP<0>")
	)
	(arc
		(start 115.62334 -391.59688)
		(mid 115.646184 -391.699008)
		(end 115.65382 -391.803382)
		(width 0.14224)
		(layer "In6.Cu")
		(net "P5E_CPU1_P3_TX_BUF_DP<0>")
	)
	(segment
		(start 125.170438 -388.774432)
		(end 125.691138 -388.774432)
		(width 0.127)
		(layer "F.Cu")
		(net "P5E_CPU1_P3_TX_BUF_DN<9>")
	)
	(segment
		(start 144.265396 -407.27503)
		(end 143.994886 -407.00452)
		(width 0.12954)
		(layer "B.Cu")
		(net "P5E_CPU1_P3_TX_BUF_DN<9>")
	)
	(segment
		(start 144.265396 -407.954734)
		(end 144.265396 -407.27503)
		(width 0.12954)
		(layer "B.Cu")
		(net "P5E_CPU1_P3_TX_BUF_DN<9>")
	)
	(segment
		(start 143.969486 -408.250644)
		(end 144.265396 -407.954734)
		(width 0.12954)
		(layer "B.Cu")
		(net "P5E_CPU1_P3_TX_BUF_DN<9>")
	)
	(segment
		(start 139.52093 -401.567396)
		(end 143.36395 -403.159214)
		(width 0.14224)
		(layer "In6.Cu")
		(net "P5E_CPU1_P3_TX_BUF_DN<9>")
	)
	(segment
		(start 125.620272 -389.958326)
		(end 125.73635 -390.074404)
		(width 0.14224)
		(layer "In6.Cu")
		(net "P5E_CPU1_P3_TX_BUF_DN<9>")
	)
	(segment
		(start 126.4285 -396.194788)
		(end 128.407414 -398.173702)
		(width 0.14224)
		(layer "In6.Cu")
		(net "P5E_CPU1_P3_TX_BUF_DN<9>")
	)
	(segment
		(start 130.99796 -399.137124)
		(end 133.936232 -399.87347)
		(width 0.14224)
		(layer "In6.Cu")
		(net "P5E_CPU1_P3_TX_BUF_DN<9>")
	)
	(segment
		(start 125.804168 -390.643872)
		(end 126.076964 -391.539476)
		(width 0.14224)
		(layer "In6.Cu")
		(net "P5E_CPU1_P3_TX_BUF_DN<9>")
	)
	(segment
		(start 125.743462 -389.006588)
		(end 125.424946 -389.325104)
		(width 0.14224)
		(layer "In6.Cu")
		(net "P5E_CPU1_P3_TX_BUF_DN<9>")
	)
	(segment
		(start 143.930116 -403.39391)
		(end 144.001744 -403.465538)
		(width 0.14224)
		(layer "In6.Cu")
		(net "P5E_CPU1_P3_TX_BUF_DN<9>")
	)
	(segment
		(start 125.691138 -388.774432)
		(end 125.743462 -388.826756)
		(width 0.14224)
		(layer "In6.Cu")
		(net "P5E_CPU1_P3_TX_BUF_DN<9>")
	)
	(segment
		(start 144.285716 -406.71369)
		(end 143.994886 -407.00452)
		(width 0.14224)
		(layer "In6.Cu")
		(net "P5E_CPU1_P3_TX_BUF_DN<9>")
	)
	(segment
		(start 144.285716 -404.15083)
		(end 144.285716 -406.71369)
		(width 0.14224)
		(layer "In6.Cu")
		(net "P5E_CPU1_P3_TX_BUF_DN<9>")
	)
	(segment
		(start 143.36395 -403.159214)
		(end 143.364204 -403.159468)
		(width 0.14224)
		(layer "In6.Cu")
		(net "P5E_CPU1_P3_TX_BUF_DN<9>")
	)
	(segment
		(start 125.743462 -388.826756)
		(end 125.743462 -389.006588)
		(width 0.14224)
		(layer "In6.Cu")
		(net "P5E_CPU1_P3_TX_BUF_DN<9>")
	)
	(segment
		(start 126.076964 -391.539476)
		(end 126.14402 -391.740898)
		(width 0.14224)
		(layer "In6.Cu")
		(net "P5E_CPU1_P3_TX_BUF_DN<9>")
	)
	(segment
		(start 126.186692 -392.004296)
		(end 126.186692 -395.68247)
		(width 0.14224)
		(layer "In6.Cu")
		(net "P5E_CPU1_P3_TX_BUF_DN<9>")
	)
	(segment
		(start 125.424946 -389.325104)
		(end 125.424946 -389.486902)
		(width 0.14224)
		(layer "In6.Cu")
		(net "P5E_CPU1_P3_TX_BUF_DN<9>")
	)
	(segment
		(start 125.783594 -390.18845)
		(end 125.783594 -390.505696)
		(width 0.14224)
		(layer "In6.Cu")
		(net "P5E_CPU1_P3_TX_BUF_DN<9>")
	)
	(segment
		(start 133.936232 -399.87347)
		(end 139.52093 -401.567396)
		(width 0.14224)
		(layer "In6.Cu")
		(net "P5E_CPU1_P3_TX_BUF_DN<9>")
	)
	(segment
		(start 129.742692 -398.887442)
		(end 130.99796 -399.137124)
		(width 0.14224)
		(layer "In6.Cu")
		(net "P5E_CPU1_P3_TX_BUF_DN<9>")
	)
	(segment
		(start 143.364204 -403.159468)
		(end 143.930116 -403.39391)
		(width 0.14224)
		(layer "In6.Cu")
		(net "P5E_CPU1_P3_TX_BUF_DN<9>")
	)
	(arc
		(start 125.783594 -390.505696)
		(mid 125.788756 -390.575549)
		(end 125.804168 -390.643872)
		(width 0.14224)
		(layer "In6.Cu")
		(net "P5E_CPU1_P3_TX_BUF_DN<9>")
	)
	(arc
		(start 126.279148 -396.006828)
		(mid 126.348407 -396.105111)
		(end 126.4285 -396.194788)
		(width 0.14224)
		(layer "In6.Cu")
		(net "P5E_CPU1_P3_TX_BUF_DN<9>")
	)
	(arc
		(start 126.186692 -395.68247)
		(mid 126.210228 -395.851116)
		(end 126.279148 -396.006828)
		(width 0.14224)
		(layer "In6.Cu")
		(net "P5E_CPU1_P3_TX_BUF_DN<9>")
	)
	(arc
		(start 144.001744 -403.465538)
		(mid 144.211937 -403.779924)
		(end 144.285716 -404.15083)
		(width 0.14224)
		(layer "In6.Cu")
		(net "P5E_CPU1_P3_TX_BUF_DN<9>")
	)
	(arc
		(start 126.14402 -391.740898)
		(mid 126.175913 -391.870887)
		(end 126.186692 -392.004296)
		(width 0.14224)
		(layer "In6.Cu")
		(net "P5E_CPU1_P3_TX_BUF_DN<9>")
	)
	(arc
		(start 128.407414 -398.173702)
		(mid 129.02212 -398.629598)
		(end 129.742692 -398.887442)
		(width 0.14224)
		(layer "In6.Cu")
		(net "P5E_CPU1_P3_TX_BUF_DN<9>")
	)
	(arc
		(start 125.424946 -389.486902)
		(mid 125.475714 -389.742042)
		(end 125.620272 -389.958326)
		(width 0.14224)
		(layer "In6.Cu")
		(net "P5E_CPU1_P3_TX_BUF_DN<9>")
	)
	(arc
		(start 125.73635 -390.074404)
		(mid 125.771312 -390.126729)
		(end 125.783594 -390.18845)
		(width 0.14224)
		(layer "In6.Cu")
		(net "P5E_CPU1_P3_TX_BUF_DN<9>")
	)
	(segment
		(start 123.970542 -388.774432)
		(end 124.491242 -388.774432)
		(width 0.127)
		(layer "F.Cu")
		(net "P5E_CPU1_P3_TX_BUF_DN<8>")
	)
	(segment
		(start 141.202156 -407.27503)
		(end 140.931646 -407.00452)
		(width 0.12954)
		(layer "B.Cu")
		(net "P5E_CPU1_P3_TX_BUF_DN<8>")
	)
	(segment
		(start 141.202156 -407.954734)
		(end 141.202156 -407.27503)
		(width 0.12954)
		(layer "B.Cu")
		(net "P5E_CPU1_P3_TX_BUF_DN<8>")
	)
	(segment
		(start 140.906246 -408.250644)
		(end 141.202156 -407.954734)
		(width 0.12954)
		(layer "B.Cu")
		(net "P5E_CPU1_P3_TX_BUF_DN<8>")
	)
	(segment
		(start 140.3223 -403.20087)
		(end 140.322554 -403.20087)
		(width 0.14224)
		(layer "In6.Cu")
		(net "P5E_CPU1_P3_TX_BUF_DN<8>")
	)
	(segment
		(start 133.606032 -400.756882)
		(end 136.653524 -401.681188)
		(width 0.14224)
		(layer "In6.Cu")
		(net "P5E_CPU1_P3_TX_BUF_DN<8>")
	)
	(segment
		(start 129.439416 -399.779744)
		(end 130.740658 -400.03857)
		(width 0.14224)
		(layer "In6.Cu")
		(net "P5E_CPU1_P3_TX_BUF_DN<8>")
	)
	(segment
		(start 140.757402 -403.380956)
		(end 141.004036 -403.62759)
		(width 0.14224)
		(layer "In6.Cu")
		(net "P5E_CPU1_P3_TX_BUF_DN<8>")
	)
	(segment
		(start 141.222476 -406.71369)
		(end 140.931646 -407.00452)
		(width 0.14224)
		(layer "In6.Cu")
		(net "P5E_CPU1_P3_TX_BUF_DN<8>")
	)
	(segment
		(start 124.572522 -390.177274)
		(end 124.572522 -390.341612)
		(width 0.14224)
		(layer "In6.Cu")
		(net "P5E_CPU1_P3_TX_BUF_DN<8>")
	)
	(segment
		(start 125.185932 -396.278862)
		(end 127.822198 -398.915128)
		(width 0.14224)
		(layer "In6.Cu")
		(net "P5E_CPU1_P3_TX_BUF_DN<8>")
	)
	(segment
		(start 136.653524 -401.681188)
		(end 140.3223 -403.20087)
		(width 0.14224)
		(layer "In6.Cu")
		(net "P5E_CPU1_P3_TX_BUF_DN<8>")
	)
	(segment
		(start 124.939552 -391.658348)
		(end 124.939552 -395.684248)
		(width 0.14224)
		(layer "In6.Cu")
		(net "P5E_CPU1_P3_TX_BUF_DN<8>")
	)
	(segment
		(start 140.322554 -403.20087)
		(end 140.757402 -403.380956)
		(width 0.14224)
		(layer "In6.Cu")
		(net "P5E_CPU1_P3_TX_BUF_DN<8>")
	)
	(segment
		(start 124.603002 -390.54786)
		(end 124.939552 -391.658348)
		(width 0.14224)
		(layer "In6.Cu")
		(net "P5E_CPU1_P3_TX_BUF_DN<8>")
	)
	(segment
		(start 124.491242 -388.774432)
		(end 124.536962 -388.820152)
		(width 0.14224)
		(layer "In6.Cu")
		(net "P5E_CPU1_P3_TX_BUF_DN<8>")
	)
	(segment
		(start 124.536962 -388.820152)
		(end 124.536962 -388.999984)
		(width 0.14224)
		(layer "In6.Cu")
		(net "P5E_CPU1_P3_TX_BUF_DN<8>")
	)
	(segment
		(start 124.22505 -389.311896)
		(end 124.22505 -389.484108)
		(width 0.14224)
		(layer "In6.Cu")
		(net "P5E_CPU1_P3_TX_BUF_DN<8>")
	)
	(segment
		(start 124.536962 -388.999984)
		(end 124.22505 -389.311896)
		(width 0.14224)
		(layer "In6.Cu")
		(net "P5E_CPU1_P3_TX_BUF_DN<8>")
	)
	(segment
		(start 130.740658 -400.03857)
		(end 133.606032 -400.756882)
		(width 0.14224)
		(layer "In6.Cu")
		(net "P5E_CPU1_P3_TX_BUF_DN<8>")
	)
	(segment
		(start 141.222476 -404.15464)
		(end 141.222476 -406.71369)
		(width 0.14224)
		(layer "In6.Cu")
		(net "P5E_CPU1_P3_TX_BUF_DN<8>")
	)
	(segment
		(start 124.422408 -389.960358)
		(end 124.525278 -390.063228)
		(width 0.14224)
		(layer "In6.Cu")
		(net "P5E_CPU1_P3_TX_BUF_DN<8>")
	)
	(arc
		(start 141.004036 -403.62759)
		(mid 141.165717 -403.869374)
		(end 141.222476 -404.15464)
		(width 0.14224)
		(layer "In6.Cu")
		(net "P5E_CPU1_P3_TX_BUF_DN<8>")
	)
	(arc
		(start 127.822198 -398.915128)
		(mid 128.566688 -399.467367)
		(end 129.439416 -399.779744)
		(width 0.14224)
		(layer "In6.Cu")
		(net "P5E_CPU1_P3_TX_BUF_DN<8>")
	)
	(arc
		(start 124.22505 -389.484108)
		(mid 124.27634 -389.741872)
		(end 124.422408 -389.960358)
		(width 0.14224)
		(layer "In6.Cu")
		(net "P5E_CPU1_P3_TX_BUF_DN<8>")
	)
	(arc
		(start 124.525278 -390.063228)
		(mid 124.56024 -390.115553)
		(end 124.572522 -390.177274)
		(width 0.14224)
		(layer "In6.Cu")
		(net "P5E_CPU1_P3_TX_BUF_DN<8>")
	)
	(arc
		(start 124.572522 -390.341612)
		(mid 124.580192 -390.445853)
		(end 124.603002 -390.54786)
		(width 0.14224)
		(layer "In6.Cu")
		(net "P5E_CPU1_P3_TX_BUF_DN<8>")
	)
	(arc
		(start 124.939552 -395.684248)
		(mid 125.003622 -396.006057)
		(end 125.185932 -396.278862)
		(width 0.14224)
		(layer "In6.Cu")
		(net "P5E_CPU1_P3_TX_BUF_DN<8>")
	)
	(segment
		(start 122.770646 -388.774432)
		(end 123.291346 -388.774432)
		(width 0.127)
		(layer "F.Cu")
		(net "P5E_CPU1_P3_TX_BUF_DN<7>")
	)
	(segment
		(start 138.138916 -407.27503)
		(end 137.868406 -407.00452)
		(width 0.12954)
		(layer "B.Cu")
		(net "P5E_CPU1_P3_TX_BUF_DN<7>")
	)
	(segment
		(start 138.138916 -407.954734)
		(end 138.138916 -407.27503)
		(width 0.12954)
		(layer "B.Cu")
		(net "P5E_CPU1_P3_TX_BUF_DN<7>")
	)
	(segment
		(start 137.843006 -408.250644)
		(end 138.138916 -407.954734)
		(width 0.12954)
		(layer "B.Cu")
		(net "P5E_CPU1_P3_TX_BUF_DN<7>")
	)
	(segment
		(start 123.15825 -389.866124)
		(end 123.318524 -390.026398)
		(width 0.14224)
		(layer "In6.Cu")
		(net "P5E_CPU1_P3_TX_BUF_DN<7>")
	)
	(segment
		(start 137.206482 -403.147784)
		(end 137.574782 -403.300184)
		(width 0.14224)
		(layer "In6.Cu")
		(net "P5E_CPU1_P3_TX_BUF_DN<7>")
	)
	(segment
		(start 134.424166 -401.995132)
		(end 137.206482 -403.147784)
		(width 0.14224)
		(layer "In6.Cu")
		(net "P5E_CPU1_P3_TX_BUF_DN<7>")
	)
	(segment
		(start 123.396248 -390.539732)
		(end 123.753372 -391.71753)
		(width 0.14224)
		(layer "In6.Cu")
		(net "P5E_CPU1_P3_TX_BUF_DN<7>")
	)
	(segment
		(start 129.192528 -400.681698)
		(end 130.230118 -400.8882)
		(width 0.14224)
		(layer "In6.Cu")
		(net "P5E_CPU1_P3_TX_BUF_DN<7>")
	)
	(segment
		(start 123.34367 -388.826756)
		(end 123.34367 -389.019796)
		(width 0.14224)
		(layer "In6.Cu")
		(net "P5E_CPU1_P3_TX_BUF_DN<7>")
	)
	(segment
		(start 133.361176 -401.672806)
		(end 134.424166 -401.995132)
		(width 0.14224)
		(layer "In6.Cu")
		(net "P5E_CPU1_P3_TX_BUF_DN<7>")
	)
	(segment
		(start 123.771914 -391.842244)
		(end 123.771914 -395.926564)
		(width 0.14224)
		(layer "In6.Cu")
		(net "P5E_CPU1_P3_TX_BUF_DN<7>")
	)
	(segment
		(start 123.957588 -396.37462)
		(end 127.198882 -399.615914)
		(width 0.14224)
		(layer "In6.Cu")
		(net "P5E_CPU1_P3_TX_BUF_DN<7>")
	)
	(segment
		(start 138.159236 -406.71369)
		(end 137.868406 -407.00452)
		(width 0.14224)
		(layer "In6.Cu")
		(net "P5E_CPU1_P3_TX_BUF_DN<7>")
	)
	(segment
		(start 123.032012 -389.331454)
		(end 123.032012 -389.561578)
		(width 0.14224)
		(layer "In6.Cu")
		(net "P5E_CPU1_P3_TX_BUF_DN<7>")
	)
	(segment
		(start 138.159236 -404.211028)
		(end 138.159236 -406.71369)
		(width 0.14224)
		(layer "In6.Cu")
		(net "P5E_CPU1_P3_TX_BUF_DN<7>")
	)
	(segment
		(start 123.34367 -389.019796)
		(end 123.032012 -389.331454)
		(width 0.14224)
		(layer "In6.Cu")
		(net "P5E_CPU1_P3_TX_BUF_DN<7>")
	)
	(segment
		(start 130.230118 -400.8882)
		(end 133.361176 -401.672806)
		(width 0.14224)
		(layer "In6.Cu")
		(net "P5E_CPU1_P3_TX_BUF_DN<7>")
	)
	(segment
		(start 137.574782 -403.300184)
		(end 137.92835 -403.653752)
		(width 0.14224)
		(layer "In6.Cu")
		(net "P5E_CPU1_P3_TX_BUF_DN<7>")
	)
	(segment
		(start 123.365768 -390.140444)
		(end 123.365768 -390.33323)
		(width 0.14224)
		(layer "In6.Cu")
		(net "P5E_CPU1_P3_TX_BUF_DN<7>")
	)
	(segment
		(start 123.291346 -388.774432)
		(end 123.34367 -388.826756)
		(width 0.14224)
		(layer "In6.Cu")
		(net "P5E_CPU1_P3_TX_BUF_DN<7>")
	)
	(arc
		(start 123.753372 -391.71753)
		(mid 123.767247 -391.779203)
		(end 123.771914 -391.842244)
		(width 0.14224)
		(layer "In6.Cu")
		(net "P5E_CPU1_P3_TX_BUF_DN<7>")
	)
	(arc
		(start 137.92835 -403.653752)
		(mid 138.099244 -403.909418)
		(end 138.159236 -404.211028)
		(width 0.14224)
		(layer "In6.Cu")
		(net "P5E_CPU1_P3_TX_BUF_DN<7>")
	)
	(arc
		(start 123.771914 -395.926564)
		(mid 123.820169 -396.169068)
		(end 123.957588 -396.37462)
		(width 0.14224)
		(layer "In6.Cu")
		(net "P5E_CPU1_P3_TX_BUF_DN<7>")
	)
	(arc
		(start 123.365768 -390.33323)
		(mid 123.373385 -390.437607)
		(end 123.396248 -390.539732)
		(width 0.14224)
		(layer "In6.Cu")
		(net "P5E_CPU1_P3_TX_BUF_DN<7>")
	)
	(arc
		(start 123.318524 -390.026398)
		(mid 123.353486 -390.078723)
		(end 123.365768 -390.140444)
		(width 0.14224)
		(layer "In6.Cu")
		(net "P5E_CPU1_P3_TX_BUF_DN<7>")
	)
	(arc
		(start 123.032012 -389.561578)
		(mid 123.064856 -389.726407)
		(end 123.15825 -389.866124)
		(width 0.14224)
		(layer "In6.Cu")
		(net "P5E_CPU1_P3_TX_BUF_DN<7>")
	)
	(arc
		(start 127.198882 -399.615914)
		(mid 128.116679 -400.29662)
		(end 129.192528 -400.681698)
		(width 0.14224)
		(layer "In6.Cu")
		(net "P5E_CPU1_P3_TX_BUF_DN<7>")
	)
	(segment
		(start 121.570496 -388.774432)
		(end 122.091196 -388.774432)
		(width 0.127)
		(layer "F.Cu")
		(net "P5E_CPU1_P3_TX_BUF_DN<6>")
	)
	(segment
		(start 135.075676 -407.954734)
		(end 135.075676 -407.27503)
		(width 0.12954)
		(layer "B.Cu")
		(net "P5E_CPU1_P3_TX_BUF_DN<6>")
	)
	(segment
		(start 134.779766 -408.250644)
		(end 135.075676 -407.954734)
		(width 0.12954)
		(layer "B.Cu")
		(net "P5E_CPU1_P3_TX_BUF_DN<6>")
	)
	(segment
		(start 135.075676 -407.27503)
		(end 134.805166 -407.00452)
		(width 0.12954)
		(layer "B.Cu")
		(net "P5E_CPU1_P3_TX_BUF_DN<6>")
	)
	(segment
		(start 122.571764 -391.809732)
		(end 122.571764 -395.893798)
		(width 0.14224)
		(layer "In6.Cu")
		(net "P5E_CPU1_P3_TX_BUF_DN<6>")
	)
	(segment
		(start 134.534148 -403.282658)
		(end 134.776718 -403.525228)
		(width 0.14224)
		(layer "In6.Cu")
		(net "P5E_CPU1_P3_TX_BUF_DN<6>")
	)
	(segment
		(start 122.216164 -390.572752)
		(end 122.553222 -391.685018)
		(width 0.14224)
		(layer "In6.Cu")
		(net "P5E_CPU1_P3_TX_BUF_DN<6>")
	)
	(segment
		(start 130.077972 -401.815808)
		(end 132.39496 -402.396452)
		(width 0.14224)
		(layer "In6.Cu")
		(net "P5E_CPU1_P3_TX_BUF_DN<6>")
	)
	(segment
		(start 132.39496 -402.396452)
		(end 134.159752 -403.127718)
		(width 0.14224)
		(layer "In6.Cu")
		(net "P5E_CPU1_P3_TX_BUF_DN<6>")
	)
	(segment
		(start 128.864614 -401.574508)
		(end 130.077972 -401.815808)
		(width 0.14224)
		(layer "In6.Cu")
		(net "P5E_CPU1_P3_TX_BUF_DN<6>")
	)
	(segment
		(start 134.160006 -403.127464)
		(end 134.534148 -403.282658)
		(width 0.14224)
		(layer "In6.Cu")
		(net "P5E_CPU1_P3_TX_BUF_DN<6>")
	)
	(segment
		(start 122.86869 -396.610586)
		(end 126.647702 -400.389598)
		(width 0.14224)
		(layer "In6.Cu")
		(net "P5E_CPU1_P3_TX_BUF_DN<6>")
	)
	(segment
		(start 122.14352 -388.826756)
		(end 122.14352 -389.006588)
		(width 0.14224)
		(layer "In6.Cu")
		(net "P5E_CPU1_P3_TX_BUF_DN<6>")
	)
	(segment
		(start 135.095996 -404.295864)
		(end 135.095996 -406.71369)
		(width 0.14224)
		(layer "In6.Cu")
		(net "P5E_CPU1_P3_TX_BUF_DN<6>")
	)
	(segment
		(start 134.159752 -403.127718)
		(end 134.160006 -403.127464)
		(width 0.14224)
		(layer "In6.Cu")
		(net "P5E_CPU1_P3_TX_BUF_DN<6>")
	)
	(segment
		(start 122.14352 -389.006588)
		(end 121.825004 -389.325104)
		(width 0.14224)
		(layer "In6.Cu")
		(net "P5E_CPU1_P3_TX_BUF_DN<6>")
	)
	(segment
		(start 135.095996 -406.71369)
		(end 134.805166 -407.00452)
		(width 0.14224)
		(layer "In6.Cu")
		(net "P5E_CPU1_P3_TX_BUF_DN<6>")
	)
	(segment
		(start 122.091196 -388.774432)
		(end 122.14352 -388.826756)
		(width 0.14224)
		(layer "In6.Cu")
		(net "P5E_CPU1_P3_TX_BUF_DN<6>")
	)
	(segment
		(start 121.825004 -389.325104)
		(end 121.825004 -389.455152)
		(width 0.14224)
		(layer "In6.Cu")
		(net "P5E_CPU1_P3_TX_BUF_DN<6>")
	)
	(segment
		(start 122.185684 -390.190736)
		(end 122.185684 -390.366504)
		(width 0.14224)
		(layer "In6.Cu")
		(net "P5E_CPU1_P3_TX_BUF_DN<6>")
	)
	(segment
		(start 122.042936 -389.981186)
		(end 122.13844 -390.07669)
		(width 0.14224)
		(layer "In6.Cu")
		(net "P5E_CPU1_P3_TX_BUF_DN<6>")
	)
	(arc
		(start 122.571764 -395.893798)
		(mid 122.648928 -396.28173)
		(end 122.86869 -396.610586)
		(width 0.14224)
		(layer "In6.Cu")
		(net "P5E_CPU1_P3_TX_BUF_DN<6>")
	)
	(arc
		(start 122.553222 -391.685018)
		(mid 122.567097 -391.746691)
		(end 122.571764 -391.809732)
		(width 0.14224)
		(layer "In6.Cu")
		(net "P5E_CPU1_P3_TX_BUF_DN<6>")
	)
	(arc
		(start 134.776718 -403.525228)
		(mid 135.01302 -403.878785)
		(end 135.095996 -404.295864)
		(width 0.14224)
		(layer "In6.Cu")
		(net "P5E_CPU1_P3_TX_BUF_DN<6>")
	)
	(arc
		(start 121.825004 -389.455152)
		(mid 121.88165 -389.739841)
		(end 122.042936 -389.981186)
		(width 0.14224)
		(layer "In6.Cu")
		(net "P5E_CPU1_P3_TX_BUF_DN<6>")
	)
	(arc
		(start 122.13844 -390.07669)
		(mid 122.173402 -390.129015)
		(end 122.185684 -390.190736)
		(width 0.14224)
		(layer "In6.Cu")
		(net "P5E_CPU1_P3_TX_BUF_DN<6>")
	)
	(arc
		(start 122.185684 -390.366504)
		(mid 122.19332 -390.470753)
		(end 122.216164 -390.572752)
		(width 0.14224)
		(layer "In6.Cu")
		(net "P5E_CPU1_P3_TX_BUF_DN<6>")
	)
	(arc
		(start 126.647702 -400.389598)
		(mid 127.668272 -401.146477)
		(end 128.864614 -401.574508)
		(width 0.14224)
		(layer "In6.Cu")
		(net "P5E_CPU1_P3_TX_BUF_DN<6>")
	)
	(segment
		(start 120.3706 -388.774432)
		(end 120.8913 -388.774432)
		(width 0.127)
		(layer "F.Cu")
		(net "P5E_CPU1_P3_TX_BUF_DN<5>")
	)
	(segment
		(start 132.012436 -407.27503)
		(end 131.741926 -407.00452)
		(width 0.12954)
		(layer "B.Cu")
		(net "P5E_CPU1_P3_TX_BUF_DN<5>")
	)
	(segment
		(start 132.012436 -407.954734)
		(end 132.012436 -407.27503)
		(width 0.12954)
		(layer "B.Cu")
		(net "P5E_CPU1_P3_TX_BUF_DN<5>")
	)
	(segment
		(start 131.716526 -408.250644)
		(end 132.012436 -407.954734)
		(width 0.12954)
		(layer "B.Cu")
		(net "P5E_CPU1_P3_TX_BUF_DN<5>")
	)
	(segment
		(start 131.722876 -403.51837)
		(end 131.83108 -403.626574)
		(width 0.14224)
		(layer "In6.Cu")
		(net "P5E_CPU1_P3_TX_BUF_DN<5>")
	)
	(segment
		(start 120.625108 -389.325104)
		(end 120.625108 -389.508746)
		(width 0.14224)
		(layer "In6.Cu")
		(net "P5E_CPU1_P3_TX_BUF_DN<5>")
	)
	(segment
		(start 131.139946 -403.251924)
		(end 131.511802 -403.384766)
		(width 0.14224)
		(layer "In6.Cu")
		(net "P5E_CPU1_P3_TX_BUF_DN<5>")
	)
	(segment
		(start 121.02084 -390.607042)
		(end 121.353326 -391.703306)
		(width 0.14224)
		(layer "In6.Cu")
		(net "P5E_CPU1_P3_TX_BUF_DN<5>")
	)
	(segment
		(start 120.99036 -390.18718)
		(end 120.99036 -390.400794)
		(width 0.14224)
		(layer "In6.Cu")
		(net "P5E_CPU1_P3_TX_BUF_DN<5>")
	)
	(segment
		(start 121.650506 -396.711932)
		(end 126.188978 -401.250404)
		(width 0.14224)
		(layer "In6.Cu")
		(net "P5E_CPU1_P3_TX_BUF_DN<5>")
	)
	(segment
		(start 120.80494 -389.942832)
		(end 120.94845 -390.086342)
		(width 0.14224)
		(layer "In6.Cu")
		(net "P5E_CPU1_P3_TX_BUF_DN<5>")
	)
	(segment
		(start 121.371868 -391.82802)
		(end 121.371868 -396.03934)
		(width 0.14224)
		(layer "In6.Cu")
		(net "P5E_CPU1_P3_TX_BUF_DN<5>")
	)
	(segment
		(start 132.032756 -404.113492)
		(end 132.032756 -406.71369)
		(width 0.14224)
		(layer "In6.Cu")
		(net "P5E_CPU1_P3_TX_BUF_DN<5>")
	)
	(segment
		(start 132.032756 -406.71369)
		(end 131.741926 -407.00452)
		(width 0.14224)
		(layer "In6.Cu")
		(net "P5E_CPU1_P3_TX_BUF_DN<5>")
	)
	(segment
		(start 120.943624 -388.826756)
		(end 120.943624 -389.006588)
		(width 0.14224)
		(layer "In6.Cu")
		(net "P5E_CPU1_P3_TX_BUF_DN<5>")
	)
	(segment
		(start 129.43713 -402.642578)
		(end 131.139946 -403.251924)
		(width 0.14224)
		(layer "In6.Cu")
		(net "P5E_CPU1_P3_TX_BUF_DN<5>")
	)
	(segment
		(start 120.8913 -388.774432)
		(end 120.943624 -388.826756)
		(width 0.14224)
		(layer "In6.Cu")
		(net "P5E_CPU1_P3_TX_BUF_DN<5>")
	)
	(segment
		(start 128.412494 -402.43887)
		(end 129.43713 -402.642578)
		(width 0.14224)
		(layer "In6.Cu")
		(net "P5E_CPU1_P3_TX_BUF_DN<5>")
	)
	(segment
		(start 120.943624 -389.006588)
		(end 120.625108 -389.325104)
		(width 0.14224)
		(layer "In6.Cu")
		(net "P5E_CPU1_P3_TX_BUF_DN<5>")
	)
	(segment
		(start 131.511802 -403.384766)
		(end 131.722876 -403.51837)
		(width 0.14224)
		(layer "In6.Cu")
		(net "P5E_CPU1_P3_TX_BUF_DN<5>")
	)
	(arc
		(start 126.188978 -401.250404)
		(mid 127.212574 -402.009582)
		(end 128.412494 -402.43887)
		(width 0.14224)
		(layer "In6.Cu")
		(net "P5E_CPU1_P3_TX_BUF_DN<5>")
	)
	(arc
		(start 120.99036 -390.400794)
		(mid 120.997996 -390.505043)
		(end 121.02084 -390.607042)
		(width 0.14224)
		(layer "In6.Cu")
		(net "P5E_CPU1_P3_TX_BUF_DN<5>")
	)
	(arc
		(start 121.371868 -396.03934)
		(mid 121.444291 -396.403346)
		(end 121.650506 -396.711932)
		(width 0.14224)
		(layer "In6.Cu")
		(net "P5E_CPU1_P3_TX_BUF_DN<5>")
	)
	(arc
		(start 131.83108 -403.626574)
		(mid 131.980351 -403.849974)
		(end 132.032756 -404.113492)
		(width 0.14224)
		(layer "In6.Cu")
		(net "P5E_CPU1_P3_TX_BUF_DN<5>")
	)
	(arc
		(start 121.353326 -391.703306)
		(mid 121.367209 -391.764978)
		(end 121.371868 -391.82802)
		(width 0.14224)
		(layer "In6.Cu")
		(net "P5E_CPU1_P3_TX_BUF_DN<5>")
	)
	(arc
		(start 120.94845 -390.086342)
		(mid 120.979417 -390.132593)
		(end 120.99036 -390.18718)
		(width 0.14224)
		(layer "In6.Cu")
		(net "P5E_CPU1_P3_TX_BUF_DN<5>")
	)
	(arc
		(start 120.625108 -389.508746)
		(mid 120.67184 -389.743682)
		(end 120.80494 -389.942832)
		(width 0.14224)
		(layer "In6.Cu")
		(net "P5E_CPU1_P3_TX_BUF_DN<5>")
	)
	(segment
		(start 119.17045 -388.774432)
		(end 119.69115 -388.774432)
		(width 0.127)
		(layer "F.Cu")
		(net "P5E_CPU1_P3_TX_BUF_DN<4>")
	)
	(segment
		(start 128.653286 -408.250644)
		(end 128.949196 -407.954734)
		(width 0.12954)
		(layer "B.Cu")
		(net "P5E_CPU1_P3_TX_BUF_DN<4>")
	)
	(segment
		(start 128.949196 -407.27503)
		(end 128.678686 -407.00452)
		(width 0.12954)
		(layer "B.Cu")
		(net "P5E_CPU1_P3_TX_BUF_DN<4>")
	)
	(segment
		(start 128.949196 -407.954734)
		(end 128.949196 -407.27503)
		(width 0.12954)
		(layer "B.Cu")
		(net "P5E_CPU1_P3_TX_BUF_DN<4>")
	)
	(segment
		(start 119.816118 -390.560306)
		(end 120.153176 -391.671556)
		(width 0.14224)
		(layer "In6.Cu")
		(net "P5E_CPU1_P3_TX_BUF_DN<4>")
	)
	(segment
		(start 128.969516 -404.185628)
		(end 128.969516 -406.71369)
		(width 0.14224)
		(layer "In6.Cu")
		(net "P5E_CPU1_P3_TX_BUF_DN<4>")
	)
	(segment
		(start 120.4468 -397.066516)
		(end 125.910848 -402.530564)
		(width 0.14224)
		(layer "In6.Cu")
		(net "P5E_CPU1_P3_TX_BUF_DN<4>")
	)
	(segment
		(start 126.73203 -403.079458)
		(end 127.212344 -403.225)
		(width 0.14224)
		(layer "In6.Cu")
		(net "P5E_CPU1_P3_TX_BUF_DN<4>")
	)
	(segment
		(start 128.65354 -403.56155)
		(end 128.751584 -403.659594)
		(width 0.14224)
		(layer "In6.Cu")
		(net "P5E_CPU1_P3_TX_BUF_DN<4>")
	)
	(segment
		(start 127.212344 -403.225)
		(end 128.309878 -403.388322)
		(width 0.14224)
		(layer "In6.Cu")
		(net "P5E_CPU1_P3_TX_BUF_DN<4>")
	)
	(segment
		(start 119.743474 -389.006588)
		(end 119.424958 -389.325104)
		(width 0.14224)
		(layer "In6.Cu")
		(net "P5E_CPU1_P3_TX_BUF_DN<4>")
	)
	(segment
		(start 119.424958 -389.325104)
		(end 119.424958 -389.501888)
		(width 0.14224)
		(layer "In6.Cu")
		(net "P5E_CPU1_P3_TX_BUF_DN<4>")
	)
	(segment
		(start 120.171718 -391.79627)
		(end 120.171718 -396.40256)
		(width 0.14224)
		(layer "In6.Cu")
		(net "P5E_CPU1_P3_TX_BUF_DN<4>")
	)
	(segment
		(start 119.743474 -388.826756)
		(end 119.743474 -389.006588)
		(width 0.14224)
		(layer "In6.Cu")
		(net "P5E_CPU1_P3_TX_BUF_DN<4>")
	)
	(segment
		(start 128.969516 -406.71369)
		(end 128.678686 -407.00452)
		(width 0.14224)
		(layer "In6.Cu")
		(net "P5E_CPU1_P3_TX_BUF_DN<4>")
	)
	(segment
		(start 119.609616 -389.947658)
		(end 119.7483 -390.086342)
		(width 0.14224)
		(layer "In6.Cu")
		(net "P5E_CPU1_P3_TX_BUF_DN<4>")
	)
	(segment
		(start 119.785638 -390.176004)
		(end 119.785638 -390.353296)
		(width 0.14224)
		(layer "In6.Cu")
		(net "P5E_CPU1_P3_TX_BUF_DN<4>")
	)
	(segment
		(start 119.69115 -388.774432)
		(end 119.743474 -388.826756)
		(width 0.14224)
		(layer "In6.Cu")
		(net "P5E_CPU1_P3_TX_BUF_DN<4>")
	)
	(segment
		(start 125.910848 -402.530564)
		(end 126.73203 -403.079458)
		(width 0.14224)
		(layer "In6.Cu")
		(net "P5E_CPU1_P3_TX_BUF_DN<4>")
	)
	(arc
		(start 119.424958 -389.501888)
		(mid 119.472946 -389.743142)
		(end 119.609616 -389.947658)
		(width 0.14224)
		(layer "In6.Cu")
		(net "P5E_CPU1_P3_TX_BUF_DN<4>")
	)
	(arc
		(start 128.751584 -403.659594)
		(mid 128.9129 -403.900926)
		(end 128.969516 -404.185628)
		(width 0.14224)
		(layer "In6.Cu")
		(net "P5E_CPU1_P3_TX_BUF_DN<4>")
	)
	(arc
		(start 120.171718 -396.40256)
		(mid 120.243213 -396.7619)
		(end 120.4468 -397.066516)
		(width 0.14224)
		(layer "In6.Cu")
		(net "P5E_CPU1_P3_TX_BUF_DN<4>")
	)
	(arc
		(start 128.309878 -403.388322)
		(mid 128.495607 -403.447346)
		(end 128.65354 -403.56155)
		(width 0.14224)
		(layer "In6.Cu")
		(net "P5E_CPU1_P3_TX_BUF_DN<4>")
	)
	(arc
		(start 119.785638 -390.353296)
		(mid 119.79322 -390.457929)
		(end 119.816118 -390.560306)
		(width 0.14224)
		(layer "In6.Cu")
		(net "P5E_CPU1_P3_TX_BUF_DN<4>")
	)
	(arc
		(start 120.153176 -391.671556)
		(mid 120.167059 -391.733228)
		(end 120.171718 -391.79627)
		(width 0.14224)
		(layer "In6.Cu")
		(net "P5E_CPU1_P3_TX_BUF_DN<4>")
	)
	(arc
		(start 119.7483 -390.086342)
		(mid 119.77587 -390.127464)
		(end 119.785638 -390.176004)
		(width 0.14224)
		(layer "In6.Cu")
		(net "P5E_CPU1_P3_TX_BUF_DN<4>")
	)
	(segment
		(start 117.970554 -388.774432)
		(end 118.491254 -388.774432)
		(width 0.127)
		(layer "F.Cu")
		(net "P5E_CPU1_P3_TX_BUF_DN<3>")
	)
	(segment
		(start 125.885956 -407.954734)
		(end 125.885956 -407.27503)
		(width 0.12954)
		(layer "B.Cu")
		(net "P5E_CPU1_P3_TX_BUF_DN<3>")
	)
	(segment
		(start 125.590046 -408.250644)
		(end 125.885956 -407.954734)
		(width 0.12954)
		(layer "B.Cu")
		(net "P5E_CPU1_P3_TX_BUF_DN<3>")
	)
	(segment
		(start 125.885956 -407.27503)
		(end 125.615446 -407.00452)
		(width 0.12954)
		(layer "B.Cu")
		(net "P5E_CPU1_P3_TX_BUF_DN<3>")
	)
	(segment
		(start 118.971822 -392.01217)
		(end 118.971822 -396.683992)
		(width 0.14224)
		(layer "In6.Cu")
		(net "P5E_CPU1_P3_TX_BUF_DN<3>")
	)
	(segment
		(start 118.616222 -390.584436)
		(end 118.896384 -391.50925)
		(width 0.14224)
		(layer "In6.Cu")
		(net "P5E_CPU1_P3_TX_BUF_DN<3>")
	)
	(segment
		(start 118.92407 -391.632694)
		(end 118.962424 -391.885932)
		(width 0.14224)
		(layer "In6.Cu")
		(net "P5E_CPU1_P3_TX_BUF_DN<3>")
	)
	(segment
		(start 118.543578 -388.826756)
		(end 118.543578 -389.006588)
		(width 0.14224)
		(layer "In6.Cu")
		(net "P5E_CPU1_P3_TX_BUF_DN<3>")
	)
	(segment
		(start 118.225062 -389.325104)
		(end 118.225062 -389.536686)
		(width 0.14224)
		(layer "In6.Cu")
		(net "P5E_CPU1_P3_TX_BUF_DN<3>")
	)
	(segment
		(start 125.906276 -406.71369)
		(end 125.615446 -407.00452)
		(width 0.14224)
		(layer "In6.Cu")
		(net "P5E_CPU1_P3_TX_BUF_DN<3>")
	)
	(segment
		(start 118.385082 -389.92302)
		(end 118.548404 -390.086342)
		(width 0.14224)
		(layer "In6.Cu")
		(net "P5E_CPU1_P3_TX_BUF_DN<3>")
	)
	(segment
		(start 119.19204 -397.215868)
		(end 125.675644 -403.699472)
		(width 0.14224)
		(layer "In6.Cu")
		(net "P5E_CPU1_P3_TX_BUF_DN<3>")
	)
	(segment
		(start 125.906276 -404.255986)
		(end 125.906276 -406.71369)
		(width 0.14224)
		(layer "In6.Cu")
		(net "P5E_CPU1_P3_TX_BUF_DN<3>")
	)
	(segment
		(start 118.543578 -389.006588)
		(end 118.225062 -389.325104)
		(width 0.14224)
		(layer "In6.Cu")
		(net "P5E_CPU1_P3_TX_BUF_DN<3>")
	)
	(segment
		(start 118.491254 -388.774432)
		(end 118.543578 -388.826756)
		(width 0.14224)
		(layer "In6.Cu")
		(net "P5E_CPU1_P3_TX_BUF_DN<3>")
	)
	(segment
		(start 118.585742 -390.176512)
		(end 118.585742 -390.378442)
		(width 0.14224)
		(layer "In6.Cu")
		(net "P5E_CPU1_P3_TX_BUF_DN<3>")
	)
	(arc
		(start 118.896384 -391.50925)
		(mid 118.912453 -391.570473)
		(end 118.92407 -391.632694)
		(width 0.14224)
		(layer "In6.Cu")
		(net "P5E_CPU1_P3_TX_BUF_DN<3>")
	)
	(arc
		(start 118.962424 -391.885932)
		(mid 118.969502 -391.948874)
		(end 118.971822 -392.01217)
		(width 0.14224)
		(layer "In6.Cu")
		(net "P5E_CPU1_P3_TX_BUF_DN<3>")
	)
	(arc
		(start 118.548404 -390.086342)
		(mid 118.576047 -390.127712)
		(end 118.585742 -390.176512)
		(width 0.14224)
		(layer "In6.Cu")
		(net "P5E_CPU1_P3_TX_BUF_DN<3>")
	)
	(arc
		(start 118.225062 -389.536686)
		(mid 118.266651 -389.745767)
		(end 118.385082 -389.92302)
		(width 0.14224)
		(layer "In6.Cu")
		(net "P5E_CPU1_P3_TX_BUF_DN<3>")
	)
	(arc
		(start 118.585742 -390.378442)
		(mid 118.593397 -390.482562)
		(end 118.616222 -390.584436)
		(width 0.14224)
		(layer "In6.Cu")
		(net "P5E_CPU1_P3_TX_BUF_DN<3>")
	)
	(arc
		(start 125.675644 -403.699472)
		(mid 125.846334 -403.954788)
		(end 125.906276 -404.255986)
		(width 0.14224)
		(layer "In6.Cu")
		(net "P5E_CPU1_P3_TX_BUF_DN<3>")
	)
	(arc
		(start 118.971822 -396.683992)
		(mid 119.029057 -396.97182)
		(end 119.19204 -397.215868)
		(width 0.14224)
		(layer "In6.Cu")
		(net "P5E_CPU1_P3_TX_BUF_DN<3>")
	)
	(segment
		(start 116.770658 -388.774432)
		(end 117.291358 -388.774432)
		(width 0.127)
		(layer "F.Cu")
		(net "P5E_CPU1_P3_TX_BUF_DN<2>")
	)
	(segment
		(start 122.822716 -407.954734)
		(end 122.822716 -407.27503)
		(width 0.12954)
		(layer "B.Cu")
		(net "P5E_CPU1_P3_TX_BUF_DN<2>")
	)
	(segment
		(start 122.822716 -407.27503)
		(end 122.552206 -407.00452)
		(width 0.12954)
		(layer "B.Cu")
		(net "P5E_CPU1_P3_TX_BUF_DN<2>")
	)
	(segment
		(start 122.526806 -408.250644)
		(end 122.822716 -407.954734)
		(width 0.12954)
		(layer "B.Cu")
		(net "P5E_CPU1_P3_TX_BUF_DN<2>")
	)
	(segment
		(start 121.849642 -402.081492)
		(end 122.494294 -402.867368)
		(width 0.14224)
		(layer "In6.Cu")
		(net "P5E_CPU1_P3_TX_BUF_DN<2>")
	)
	(segment
		(start 117.771926 -391.828528)
		(end 117.771926 -396.697454)
		(width 0.14224)
		(layer "In6.Cu")
		(net "P5E_CPU1_P3_TX_BUF_DN<2>")
	)
	(segment
		(start 117.291358 -388.774432)
		(end 117.343682 -388.826756)
		(width 0.14224)
		(layer "In6.Cu")
		(net "P5E_CPU1_P3_TX_BUF_DN<2>")
	)
	(segment
		(start 117.443504 -390.684258)
		(end 117.753384 -391.703814)
		(width 0.14224)
		(layer "In6.Cu")
		(net "P5E_CPU1_P3_TX_BUF_DN<2>")
	)
	(segment
		(start 118.035578 -397.434308)
		(end 121.849388 -402.081492)
		(width 0.14224)
		(layer "In6.Cu")
		(net "P5E_CPU1_P3_TX_BUF_DN<2>")
	)
	(segment
		(start 117.024912 -389.349742)
		(end 117.024912 -389.514588)
		(width 0.14224)
		(layer "In6.Cu")
		(net "P5E_CPU1_P3_TX_BUF_DN<2>")
	)
	(segment
		(start 122.843036 -403.841204)
		(end 122.843036 -406.71369)
		(width 0.14224)
		(layer "In6.Cu")
		(net "P5E_CPU1_P3_TX_BUF_DN<2>")
	)
	(segment
		(start 117.343682 -389.030972)
		(end 117.024912 -389.349742)
		(width 0.14224)
		(layer "In6.Cu")
		(net "P5E_CPU1_P3_TX_BUF_DN<2>")
	)
	(segment
		(start 122.843036 -406.71369)
		(end 122.552206 -407.00452)
		(width 0.14224)
		(layer "In6.Cu")
		(net "P5E_CPU1_P3_TX_BUF_DN<2>")
	)
	(segment
		(start 121.849388 -402.081492)
		(end 121.849642 -402.081492)
		(width 0.14224)
		(layer "In6.Cu")
		(net "P5E_CPU1_P3_TX_BUF_DN<2>")
	)
	(segment
		(start 117.20068 -389.939022)
		(end 117.348762 -390.087104)
		(width 0.14224)
		(layer "In6.Cu")
		(net "P5E_CPU1_P3_TX_BUF_DN<2>")
	)
	(segment
		(start 117.413024 -390.242298)
		(end 117.413024 -390.477756)
		(width 0.14224)
		(layer "In6.Cu")
		(net "P5E_CPU1_P3_TX_BUF_DN<2>")
	)
	(segment
		(start 117.343682 -388.826756)
		(end 117.343682 -389.030972)
		(width 0.14224)
		(layer "In6.Cu")
		(net "P5E_CPU1_P3_TX_BUF_DN<2>")
	)
	(arc
		(start 117.413024 -390.477756)
		(mid 117.420647 -390.582132)
		(end 117.443504 -390.684258)
		(width 0.14224)
		(layer "In6.Cu")
		(net "P5E_CPU1_P3_TX_BUF_DN<2>")
	)
	(arc
		(start 117.753384 -391.703814)
		(mid 117.767255 -391.765487)
		(end 117.771926 -391.828528)
		(width 0.14224)
		(layer "In6.Cu")
		(net "P5E_CPU1_P3_TX_BUF_DN<2>")
	)
	(arc
		(start 117.771926 -396.697454)
		(mid 117.839822 -397.088757)
		(end 118.035578 -397.434308)
		(width 0.14224)
		(layer "In6.Cu")
		(net "P5E_CPU1_P3_TX_BUF_DN<2>")
	)
	(arc
		(start 117.024912 -389.514588)
		(mid 117.070585 -389.74429)
		(end 117.20068 -389.939022)
		(width 0.14224)
		(layer "In6.Cu")
		(net "P5E_CPU1_P3_TX_BUF_DN<2>")
	)
	(arc
		(start 117.348762 -390.087104)
		(mid 117.396339 -390.158308)
		(end 117.413024 -390.242298)
		(width 0.14224)
		(layer "In6.Cu")
		(net "P5E_CPU1_P3_TX_BUF_DN<2>")
	)
	(arc
		(start 122.494294 -402.867368)
		(mid 122.753145 -403.324034)
		(end 122.843036 -403.841204)
		(width 0.14224)
		(layer "In6.Cu")
		(net "P5E_CPU1_P3_TX_BUF_DN<2>")
	)
	(segment
		(start 115.570508 -388.774432)
		(end 116.091208 -388.774432)
		(width 0.127)
		(layer "F.Cu")
		(net "P5E_CPU1_P3_TX_BUF_DN<1>")
	)
	(segment
		(start 119.759476 -407.27503)
		(end 119.488966 -407.00452)
		(width 0.12954)
		(layer "B.Cu")
		(net "P5E_CPU1_P3_TX_BUF_DN<1>")
	)
	(segment
		(start 119.463566 -408.250644)
		(end 119.759476 -407.954734)
		(width 0.12954)
		(layer "B.Cu")
		(net "P5E_CPU1_P3_TX_BUF_DN<1>")
	)
	(segment
		(start 119.759476 -407.954734)
		(end 119.759476 -407.27503)
		(width 0.12954)
		(layer "B.Cu")
		(net "P5E_CPU1_P3_TX_BUF_DN<1>")
	)
	(segment
		(start 116.091208 -388.774432)
		(end 116.143532 -388.826756)
		(width 0.14224)
		(layer "In6.Cu")
		(net "P5E_CPU1_P3_TX_BUF_DN<1>")
	)
	(segment
		(start 116.143532 -388.826756)
		(end 116.143532 -389.006588)
		(width 0.14224)
		(layer "In6.Cu")
		(net "P5E_CPU1_P3_TX_BUF_DN<1>")
	)
	(segment
		(start 116.691156 -397.034004)
		(end 117.615208 -399.080482)
		(width 0.14224)
		(layer "In6.Cu")
		(net "P5E_CPU1_P3_TX_BUF_DN<1>")
	)
	(segment
		(start 115.989862 -389.927846)
		(end 116.148358 -390.086088)
		(width 0.14224)
		(layer "In6.Cu")
		(net "P5E_CPU1_P3_TX_BUF_DN<1>")
	)
	(segment
		(start 116.196364 -390.201658)
		(end 116.196364 -390.36752)
		(width 0.14224)
		(layer "In6.Cu")
		(net "P5E_CPU1_P3_TX_BUF_DN<1>")
	)
	(segment
		(start 119.779796 -403.992588)
		(end 119.779796 -406.71369)
		(width 0.14224)
		(layer "In6.Cu")
		(net "P5E_CPU1_P3_TX_BUF_DN<1>")
	)
	(segment
		(start 119.779796 -406.71369)
		(end 119.488966 -407.00452)
		(width 0.14224)
		(layer "In6.Cu")
		(net "P5E_CPU1_P3_TX_BUF_DN<1>")
	)
	(segment
		(start 116.143532 -389.006588)
		(end 115.825016 -389.325104)
		(width 0.14224)
		(layer "In6.Cu")
		(net "P5E_CPU1_P3_TX_BUF_DN<1>")
	)
	(segment
		(start 116.25072 -390.73201)
		(end 116.369084 -391.121392)
		(width 0.14224)
		(layer "In6.Cu")
		(net "P5E_CPU1_P3_TX_BUF_DN<1>")
	)
	(segment
		(start 116.5733 -392.486896)
		(end 116.579904 -396.521432)
		(width 0.14224)
		(layer "In6.Cu")
		(net "P5E_CPU1_P3_TX_BUF_DN<1>")
	)
	(segment
		(start 117.615208 -399.080482)
		(end 119.636286 -403.354032)
		(width 0.14224)
		(layer "In6.Cu")
		(net "P5E_CPU1_P3_TX_BUF_DN<1>")
	)
	(segment
		(start 115.825016 -389.325104)
		(end 115.825016 -389.529828)
		(width 0.14224)
		(layer "In6.Cu")
		(net "P5E_CPU1_P3_TX_BUF_DN<1>")
	)
	(arc
		(start 115.825016 -389.529828)
		(mid 115.867861 -389.745227)
		(end 115.989862 -389.927846)
		(width 0.14224)
		(layer "In6.Cu")
		(net "P5E_CPU1_P3_TX_BUF_DN<1>")
	)
	(arc
		(start 116.579904 -396.521432)
		(mid 116.608383 -396.783609)
		(end 116.691156 -397.034004)
		(width 0.14224)
		(layer "In6.Cu")
		(net "P5E_CPU1_P3_TX_BUF_DN<1>")
	)
	(arc
		(start 119.636286 -403.354032)
		(mid 119.743467 -403.665352)
		(end 119.779796 -403.992588)
		(width 0.14224)
		(layer "In6.Cu")
		(net "P5E_CPU1_P3_TX_BUF_DN<1>")
	)
	(arc
		(start 116.369084 -391.121392)
		(mid 116.521352 -391.796641)
		(end 116.5733 -392.486896)
		(width 0.14224)
		(layer "In6.Cu")
		(net "P5E_CPU1_P3_TX_BUF_DN<1>")
	)
	(arc
		(start 116.148358 -390.086088)
		(mid 116.183924 -390.139083)
		(end 116.196364 -390.201658)
		(width 0.14224)
		(layer "In6.Cu")
		(net "P5E_CPU1_P3_TX_BUF_DN<1>")
	)
	(arc
		(start 116.196364 -390.36752)
		(mid 116.210087 -390.551771)
		(end 116.25072 -390.73201)
		(width 0.14224)
		(layer "In6.Cu")
		(net "P5E_CPU1_P3_TX_BUF_DN<1>")
	)
	(segment
		(start 132.370576 -388.774432)
		(end 132.891276 -388.774432)
		(width 0.127)
		(layer "F.Cu")
		(net "P5E_CPU1_P3_TX_BUF_DN<15>")
	)
	(segment
		(start 162.348926 -408.250644)
		(end 162.644836 -407.954734)
		(width 0.12954)
		(layer "B.Cu")
		(net "P5E_CPU1_P3_TX_BUF_DN<15>")
	)
	(segment
		(start 162.644836 -407.27503)
		(end 162.374326 -407.00452)
		(width 0.12954)
		(layer "B.Cu")
		(net "P5E_CPU1_P3_TX_BUF_DN<15>")
	)
	(segment
		(start 162.644836 -407.954734)
		(end 162.644836 -407.27503)
		(width 0.12954)
		(layer "B.Cu")
		(net "P5E_CPU1_P3_TX_BUF_DN<15>")
	)
	(segment
		(start 133.372352 -391.095738)
		(end 133.372352 -391.977372)
		(width 0.14224)
		(layer "In6.Cu")
		(net "P5E_CPU1_P3_TX_BUF_DN<15>")
	)
	(segment
		(start 132.9436 -388.826756)
		(end 132.9436 -389.006588)
		(width 0.14224)
		(layer "In6.Cu")
		(net "P5E_CPU1_P3_TX_BUF_DN<15>")
	)
	(segment
		(start 133.372352 -391.978388)
		(end 133.372352 -393.643612)
		(width 0.14224)
		(layer "In6.Cu")
		(net "P5E_CPU1_P3_TX_BUF_DN<15>")
	)
	(segment
		(start 136.691624 -394.46962)
		(end 139.783566 -395.325346)
		(width 0.14224)
		(layer "In6.Cu")
		(net "P5E_CPU1_P3_TX_BUF_DN<15>")
	)
	(segment
		(start 139.783566 -395.325346)
		(end 139.783566 -395.3256)
		(width 0.14224)
		(layer "In6.Cu")
		(net "P5E_CPU1_P3_TX_BUF_DN<15>")
	)
	(segment
		(start 134.953756 -394.233654)
		(end 136.691624 -394.46962)
		(width 0.14224)
		(layer "In6.Cu")
		(net "P5E_CPU1_P3_TX_BUF_DN<15>")
	)
	(segment
		(start 162.69335 -404.715726)
		(end 162.69335 -406.685496)
		(width 0.14224)
		(layer "In6.Cu")
		(net "P5E_CPU1_P3_TX_BUF_DN<15>")
	)
	(segment
		(start 132.891276 -388.774432)
		(end 132.9436 -388.826756)
		(width 0.14224)
		(layer "In6.Cu")
		(net "P5E_CPU1_P3_TX_BUF_DN<15>")
	)
	(segment
		(start 132.625084 -389.325104)
		(end 132.625084 -389.520176)
		(width 0.14224)
		(layer "In6.Cu")
		(net "P5E_CPU1_P3_TX_BUF_DN<15>")
	)
	(segment
		(start 133.372352 -391.977372)
		(end 133.371844 -391.97788)
		(width 0.14224)
		(layer "In6.Cu")
		(net "P5E_CPU1_P3_TX_BUF_DN<15>")
	)
	(segment
		(start 133.372352 -393.643612)
		(end 133.684772 -393.956032)
		(width 0.14224)
		(layer "In6.Cu")
		(net "P5E_CPU1_P3_TX_BUF_DN<15>")
	)
	(segment
		(start 133.803136 -394.004546)
		(end 134.953756 -394.233654)
		(width 0.14224)
		(layer "In6.Cu")
		(net "P5E_CPU1_P3_TX_BUF_DN<15>")
	)
	(segment
		(start 139.783566 -395.3256)
		(end 150.967186 -398.42059)
		(width 0.14224)
		(layer "In6.Cu")
		(net "P5E_CPU1_P3_TX_BUF_DN<15>")
	)
	(segment
		(start 133.371844 -391.97788)
		(end 133.372352 -391.978388)
		(width 0.14224)
		(layer "In6.Cu")
		(net "P5E_CPU1_P3_TX_BUF_DN<15>")
	)
	(segment
		(start 150.967186 -398.42059)
		(end 161.495994 -402.782024)
		(width 0.14224)
		(layer "In6.Cu")
		(net "P5E_CPU1_P3_TX_BUF_DN<15>")
	)
	(segment
		(start 162.230562 -403.384766)
		(end 162.338258 -403.546056)
		(width 0.14224)
		(layer "In6.Cu")
		(net "P5E_CPU1_P3_TX_BUF_DN<15>")
	)
	(segment
		(start 162.69335 -406.685496)
		(end 162.374326 -407.00452)
		(width 0.14224)
		(layer "In6.Cu")
		(net "P5E_CPU1_P3_TX_BUF_DN<15>")
	)
	(segment
		(start 133.684772 -393.956032)
		(end 133.803136 -394.004546)
		(width 0.14224)
		(layer "In6.Cu")
		(net "P5E_CPU1_P3_TX_BUF_DN<15>")
	)
	(segment
		(start 132.796788 -389.934704)
		(end 132.924804 -390.06272)
		(width 0.14224)
		(layer "In6.Cu")
		(net "P5E_CPU1_P3_TX_BUF_DN<15>")
	)
	(segment
		(start 132.9436 -389.006588)
		(end 132.625084 -389.325104)
		(width 0.14224)
		(layer "In6.Cu")
		(net "P5E_CPU1_P3_TX_BUF_DN<15>")
	)
	(segment
		(start 132.994908 -390.167368)
		(end 133.32968 -390.976612)
		(width 0.14224)
		(layer "In6.Cu")
		(net "P5E_CPU1_P3_TX_BUF_DN<15>")
	)
	(arc
		(start 132.969508 -390.118346)
		(mid 132.983263 -390.142311)
		(end 132.994908 -390.167368)
		(width 0.14224)
		(layer "In6.Cu")
		(net "P5E_CPU1_P3_TX_BUF_DN<15>")
	)
	(arc
		(start 133.32968 -390.976612)
		(mid 133.352478 -391.035651)
		(end 133.372352 -391.095738)
		(width 0.14224)
		(layer "In6.Cu")
		(net "P5E_CPU1_P3_TX_BUF_DN<15>")
	)
	(arc
		(start 162.338258 -403.546056)
		(mid 162.602634 -404.104532)
		(end 162.69335 -404.715726)
		(width 0.14224)
		(layer "In6.Cu")
		(net "P5E_CPU1_P3_TX_BUF_DN<15>")
	)
	(arc
		(start 161.495994 -402.782024)
		(mid 161.907985 -403.028918)
		(end 162.230562 -403.384766)
		(width 0.14224)
		(layer "In6.Cu")
		(net "P5E_CPU1_P3_TX_BUF_DN<15>")
	)
	(arc
		(start 132.924804 -390.06272)
		(mid 132.948692 -390.089298)
		(end 132.969508 -390.118346)
		(width 0.14224)
		(layer "In6.Cu")
		(net "P5E_CPU1_P3_TX_BUF_DN<15>")
	)
	(arc
		(start 132.625084 -389.520176)
		(mid 132.669708 -389.744517)
		(end 132.796788 -389.934704)
		(width 0.14224)
		(layer "In6.Cu")
		(net "P5E_CPU1_P3_TX_BUF_DN<15>")
	)
	(segment
		(start 131.17068 -388.774432)
		(end 131.69138 -388.774432)
		(width 0.127)
		(layer "F.Cu")
		(net "P5E_CPU1_P3_TX_BUF_DN<14>")
	)
	(segment
		(start 159.581596 -407.954734)
		(end 159.581596 -407.27503)
		(width 0.12954)
		(layer "B.Cu")
		(net "P5E_CPU1_P3_TX_BUF_DN<14>")
	)
	(segment
		(start 159.285686 -408.250644)
		(end 159.581596 -407.954734)
		(width 0.12954)
		(layer "B.Cu")
		(net "P5E_CPU1_P3_TX_BUF_DN<14>")
	)
	(segment
		(start 159.581596 -407.27503)
		(end 159.311086 -407.00452)
		(width 0.12954)
		(layer "B.Cu")
		(net "P5E_CPU1_P3_TX_BUF_DN<14>")
	)
	(segment
		(start 155.432506 -401.735798)
		(end 155.43276 -401.735798)
		(width 0.14224)
		(layer "In6.Cu")
		(net "P5E_CPU1_P3_TX_BUF_DN<14>")
	)
	(segment
		(start 131.736592 -388.999476)
		(end 131.41706 -389.319008)
		(width 0.14224)
		(layer "In6.Cu")
		(net "P5E_CPU1_P3_TX_BUF_DN<14>")
	)
	(segment
		(start 159.601916 -406.71369)
		(end 159.311086 -407.00452)
		(width 0.14224)
		(layer "In6.Cu")
		(net "P5E_CPU1_P3_TX_BUF_DN<14>")
	)
	(segment
		(start 131.41706 -389.319008)
		(end 131.41706 -389.474456)
		(width 0.14224)
		(layer "In6.Cu")
		(net "P5E_CPU1_P3_TX_BUF_DN<14>")
	)
	(segment
		(start 131.615434 -389.9535)
		(end 131.692396 -390.030462)
		(width 0.14224)
		(layer "In6.Cu")
		(net "P5E_CPU1_P3_TX_BUF_DN<14>")
	)
	(segment
		(start 131.736592 -388.819644)
		(end 131.736592 -388.999476)
		(width 0.14224)
		(layer "In6.Cu")
		(net "P5E_CPU1_P3_TX_BUF_DN<14>")
	)
	(segment
		(start 132.73405 -394.702792)
		(end 140.34643 -396.610078)
		(width 0.14224)
		(layer "In6.Cu")
		(net "P5E_CPU1_P3_TX_BUF_DN<14>")
	)
	(segment
		(start 131.69138 -388.774432)
		(end 131.736592 -388.819644)
		(width 0.14224)
		(layer "In6.Cu")
		(net "P5E_CPU1_P3_TX_BUF_DN<14>")
	)
	(segment
		(start 132.171948 -391.97788)
		(end 132.171948 -394.060934)
		(width 0.14224)
		(layer "In6.Cu")
		(net "P5E_CPU1_P3_TX_BUF_DN<14>")
	)
	(segment
		(start 155.43276 -401.735798)
		(end 158.978346 -403.204426)
		(width 0.14224)
		(layer "In6.Cu")
		(net "P5E_CPU1_P3_TX_BUF_DN<14>")
	)
	(segment
		(start 131.864354 -390.55548)
		(end 132.157978 -391.85215)
		(width 0.14224)
		(layer "In6.Cu")
		(net "P5E_CPU1_P3_TX_BUF_DN<14>")
	)
	(segment
		(start 131.815078 -390.272016)
		(end 131.836922 -390.412478)
		(width 0.14224)
		(layer "In6.Cu")
		(net "P5E_CPU1_P3_TX_BUF_DN<14>")
	)
	(segment
		(start 132.301742 -394.37437)
		(end 132.494274 -394.566902)
		(width 0.14224)
		(layer "In6.Cu")
		(net "P5E_CPU1_P3_TX_BUF_DN<14>")
	)
	(segment
		(start 140.34643 -396.610078)
		(end 150.476204 -399.682716)
		(width 0.14224)
		(layer "In6.Cu")
		(net "P5E_CPU1_P3_TX_BUF_DN<14>")
	)
	(segment
		(start 150.476204 -399.682716)
		(end 155.432506 -401.735798)
		(width 0.14224)
		(layer "In6.Cu")
		(net "P5E_CPU1_P3_TX_BUF_DN<14>")
	)
	(segment
		(start 159.601916 -404.137622)
		(end 159.601916 -406.71369)
		(width 0.14224)
		(layer "In6.Cu")
		(net "P5E_CPU1_P3_TX_BUF_DN<14>")
	)
	(arc
		(start 132.171948 -394.060934)
		(mid 132.205687 -394.230551)
		(end 132.301742 -394.37437)
		(width 0.14224)
		(layer "In6.Cu")
		(net "P5E_CPU1_P3_TX_BUF_DN<14>")
	)
	(arc
		(start 132.494274 -394.566902)
		(mid 132.604928 -394.65114)
		(end 132.73405 -394.702792)
		(width 0.14224)
		(layer "In6.Cu")
		(net "P5E_CPU1_P3_TX_BUF_DN<14>")
	)
	(arc
		(start 158.978346 -403.204426)
		(mid 159.431638 -403.576457)
		(end 159.601916 -404.137622)
		(width 0.14224)
		(layer "In6.Cu")
		(net "P5E_CPU1_P3_TX_BUF_DN<14>")
	)
	(arc
		(start 131.692396 -390.030462)
		(mid 131.772956 -390.141481)
		(end 131.815078 -390.272016)
		(width 0.14224)
		(layer "In6.Cu")
		(net "P5E_CPU1_P3_TX_BUF_DN<14>")
	)
	(arc
		(start 131.836922 -390.412478)
		(mid 131.849431 -390.484211)
		(end 131.864354 -390.55548)
		(width 0.14224)
		(layer "In6.Cu")
		(net "P5E_CPU1_P3_TX_BUF_DN<14>")
	)
	(arc
		(start 132.157978 -391.85215)
		(mid 132.168464 -391.914626)
		(end 132.171948 -391.97788)
		(width 0.14224)
		(layer "In6.Cu")
		(net "P5E_CPU1_P3_TX_BUF_DN<14>")
	)
	(arc
		(start 131.41706 -389.474456)
		(mid 131.46861 -389.733707)
		(end 131.615434 -389.9535)
		(width 0.14224)
		(layer "In6.Cu")
		(net "P5E_CPU1_P3_TX_BUF_DN<14>")
	)
	(segment
		(start 129.97053 -388.774432)
		(end 130.49123 -388.774432)
		(width 0.127)
		(layer "F.Cu")
		(net "P5E_CPU1_P3_TX_BUF_DN<13>")
	)
	(segment
		(start 156.222446 -408.250644)
		(end 156.518356 -407.954734)
		(width 0.12954)
		(layer "B.Cu")
		(net "P5E_CPU1_P3_TX_BUF_DN<13>")
	)
	(segment
		(start 156.518356 -407.27503)
		(end 156.247846 -407.00452)
		(width 0.12954)
		(layer "B.Cu")
		(net "P5E_CPU1_P3_TX_BUF_DN<13>")
	)
	(segment
		(start 156.518356 -407.954734)
		(end 156.518356 -407.27503)
		(width 0.12954)
		(layer "B.Cu")
		(net "P5E_CPU1_P3_TX_BUF_DN<13>")
	)
	(segment
		(start 130.395218 -389.93318)
		(end 130.54838 -390.086342)
		(width 0.14224)
		(layer "In6.Cu")
		(net "P5E_CPU1_P3_TX_BUF_DN<13>")
	)
	(segment
		(start 152.282398 -401.71751)
		(end 155.010866 -402.84781)
		(width 0.14224)
		(layer "In6.Cu")
		(net "P5E_CPU1_P3_TX_BUF_DN<13>")
	)
	(segment
		(start 137.79754 -396.93469)
		(end 145.13941 -399.162016)
		(width 0.14224)
		(layer "In6.Cu")
		(net "P5E_CPU1_P3_TX_BUF_DN<13>")
	)
	(segment
		(start 156.538676 -404.038308)
		(end 156.538676 -406.71369)
		(width 0.14224)
		(layer "In6.Cu")
		(net "P5E_CPU1_P3_TX_BUF_DN<13>")
	)
	(segment
		(start 130.971798 -391.829544)
		(end 130.971798 -394.374878)
		(width 0.14224)
		(layer "In6.Cu")
		(net "P5E_CPU1_P3_TX_BUF_DN<13>")
	)
	(segment
		(start 131.109466 -394.707364)
		(end 131.568444 -395.166342)
		(width 0.14224)
		(layer "In6.Cu")
		(net "P5E_CPU1_P3_TX_BUF_DN<13>")
	)
	(segment
		(start 155.01112 -402.84781)
		(end 156.023056 -403.26691)
		(width 0.14224)
		(layer "In6.Cu")
		(net "P5E_CPU1_P3_TX_BUF_DN<13>")
	)
	(segment
		(start 130.543554 -388.826756)
		(end 130.543554 -389.006588)
		(width 0.14224)
		(layer "In6.Cu")
		(net "P5E_CPU1_P3_TX_BUF_DN<13>")
	)
	(segment
		(start 156.538676 -406.71369)
		(end 156.247846 -407.00452)
		(width 0.14224)
		(layer "In6.Cu")
		(net "P5E_CPU1_P3_TX_BUF_DN<13>")
	)
	(segment
		(start 130.49123 -388.774432)
		(end 130.543554 -388.826756)
		(width 0.14224)
		(layer "In6.Cu")
		(net "P5E_CPU1_P3_TX_BUF_DN<13>")
	)
	(segment
		(start 130.225038 -389.325104)
		(end 130.225038 -389.522462)
		(width 0.14224)
		(layer "In6.Cu")
		(net "P5E_CPU1_P3_TX_BUF_DN<13>")
	)
	(segment
		(start 146.195034 -399.539714)
		(end 146.19478 -399.540222)
		(width 0.14224)
		(layer "In6.Cu")
		(net "P5E_CPU1_P3_TX_BUF_DN<13>")
	)
	(segment
		(start 146.19478 -399.540222)
		(end 152.282398 -401.71751)
		(width 0.14224)
		(layer "In6.Cu")
		(net "P5E_CPU1_P3_TX_BUF_DN<13>")
	)
	(segment
		(start 155.010866 -402.84781)
		(end 155.01112 -402.84781)
		(width 0.14224)
		(layer "In6.Cu")
		(net "P5E_CPU1_P3_TX_BUF_DN<13>")
	)
	(segment
		(start 130.62204 -390.676638)
		(end 130.971798 -391.829544)
		(width 0.14224)
		(layer "In6.Cu")
		(net "P5E_CPU1_P3_TX_BUF_DN<13>")
	)
	(segment
		(start 145.13941 -399.162016)
		(end 146.195034 -399.539714)
		(width 0.14224)
		(layer "In6.Cu")
		(net "P5E_CPU1_P3_TX_BUF_DN<13>")
	)
	(segment
		(start 130.585718 -390.176512)
		(end 130.585718 -390.430512)
		(width 0.14224)
		(layer "In6.Cu")
		(net "P5E_CPU1_P3_TX_BUF_DN<13>")
	)
	(segment
		(start 130.543554 -389.006588)
		(end 130.225038 -389.325104)
		(width 0.14224)
		(layer "In6.Cu")
		(net "P5E_CPU1_P3_TX_BUF_DN<13>")
	)
	(segment
		(start 132.226304 -395.53896)
		(end 137.79754 -396.93469)
		(width 0.14224)
		(layer "In6.Cu")
		(net "P5E_CPU1_P3_TX_BUF_DN<13>")
	)
	(arc
		(start 130.585718 -390.430512)
		(mid 130.594766 -390.554921)
		(end 130.62204 -390.676638)
		(width 0.14224)
		(layer "In6.Cu")
		(net "P5E_CPU1_P3_TX_BUF_DN<13>")
	)
	(arc
		(start 130.971798 -394.374878)
		(mid 131.007571 -394.554812)
		(end 131.109466 -394.707364)
		(width 0.14224)
		(layer "In6.Cu")
		(net "P5E_CPU1_P3_TX_BUF_DN<13>")
	)
	(arc
		(start 130.225038 -389.522462)
		(mid 130.269271 -389.744748)
		(end 130.395218 -389.93318)
		(width 0.14224)
		(layer "In6.Cu")
		(net "P5E_CPU1_P3_TX_BUF_DN<13>")
	)
	(arc
		(start 156.023056 -403.26691)
		(mid 156.397877 -403.57439)
		(end 156.538676 -404.038308)
		(width 0.14224)
		(layer "In6.Cu")
		(net "P5E_CPU1_P3_TX_BUF_DN<13>")
	)
	(arc
		(start 131.568444 -395.166342)
		(mid 131.87206 -395.39735)
		(end 132.226304 -395.53896)
		(width 0.14224)
		(layer "In6.Cu")
		(net "P5E_CPU1_P3_TX_BUF_DN<13>")
	)
	(arc
		(start 130.54838 -390.086342)
		(mid 130.576023 -390.127712)
		(end 130.585718 -390.176512)
		(width 0.14224)
		(layer "In6.Cu")
		(net "P5E_CPU1_P3_TX_BUF_DN<13>")
	)
	(segment
		(start 128.770634 -388.774432)
		(end 129.291334 -388.774432)
		(width 0.127)
		(layer "F.Cu")
		(net "P5E_CPU1_P3_TX_BUF_DN<12>")
	)
	(segment
		(start 153.455116 -407.27503)
		(end 153.184606 -407.00452)
		(width 0.12954)
		(layer "B.Cu")
		(net "P5E_CPU1_P3_TX_BUF_DN<12>")
	)
	(segment
		(start 153.455116 -407.954734)
		(end 153.455116 -407.27503)
		(width 0.12954)
		(layer "B.Cu")
		(net "P5E_CPU1_P3_TX_BUF_DN<12>")
	)
	(segment
		(start 153.159206 -408.250644)
		(end 153.455116 -407.954734)
		(width 0.12954)
		(layer "B.Cu")
		(net "P5E_CPU1_P3_TX_BUF_DN<12>")
	)
	(segment
		(start 129.191258 -389.92937)
		(end 129.34823 -390.086342)
		(width 0.14224)
		(layer "In6.Cu")
		(net "P5E_CPU1_P3_TX_BUF_DN<12>")
	)
	(segment
		(start 151.221186 -402.613622)
		(end 153.099262 -403.391624)
		(width 0.14224)
		(layer "In6.Cu")
		(net "P5E_CPU1_P3_TX_BUF_DN<12>")
	)
	(segment
		(start 153.475436 -406.71369)
		(end 153.184606 -407.00452)
		(width 0.14224)
		(layer "In6.Cu")
		(net "P5E_CPU1_P3_TX_BUF_DN<12>")
	)
	(segment
		(start 129.343658 -389.023352)
		(end 129.025142 -389.341868)
		(width 0.14224)
		(layer "In6.Cu")
		(net "P5E_CPU1_P3_TX_BUF_DN<12>")
	)
	(segment
		(start 129.343658 -388.826756)
		(end 129.343658 -389.023352)
		(width 0.14224)
		(layer "In6.Cu")
		(net "P5E_CPU1_P3_TX_BUF_DN<12>")
	)
	(segment
		(start 136.889236 -397.712184)
		(end 146.227292 -400.545046)
		(width 0.14224)
		(layer "In6.Cu")
		(net "P5E_CPU1_P3_TX_BUF_DN<12>")
	)
	(segment
		(start 146.227292 -400.545046)
		(end 151.220932 -402.613622)
		(width 0.14224)
		(layer "In6.Cu")
		(net "P5E_CPU1_P3_TX_BUF_DN<12>")
	)
	(segment
		(start 131.342638 -396.322042)
		(end 136.889236 -397.712184)
		(width 0.14224)
		(layer "In6.Cu")
		(net "P5E_CPU1_P3_TX_BUF_DN<12>")
	)
	(segment
		(start 151.220932 -402.613622)
		(end 151.221186 -402.613622)
		(width 0.14224)
		(layer "In6.Cu")
		(net "P5E_CPU1_P3_TX_BUF_DN<12>")
	)
	(segment
		(start 129.771648 -391.74928)
		(end 129.771648 -394.713206)
		(width 0.14224)
		(layer "In6.Cu")
		(net "P5E_CPU1_P3_TX_BUF_DN<12>")
	)
	(segment
		(start 129.417318 -390.581388)
		(end 129.771648 -391.74928)
		(width 0.14224)
		(layer "In6.Cu")
		(net "P5E_CPU1_P3_TX_BUF_DN<12>")
	)
	(segment
		(start 129.291334 -388.774432)
		(end 129.343658 -388.826756)
		(width 0.14224)
		(layer "In6.Cu")
		(net "P5E_CPU1_P3_TX_BUF_DN<12>")
	)
	(segment
		(start 153.099262 -403.391624)
		(end 153.22677 -403.519132)
		(width 0.14224)
		(layer "In6.Cu")
		(net "P5E_CPU1_P3_TX_BUF_DN<12>")
	)
	(segment
		(start 129.950718 -395.145514)
		(end 130.84556 -396.040356)
		(width 0.14224)
		(layer "In6.Cu")
		(net "P5E_CPU1_P3_TX_BUF_DN<12>")
	)
	(segment
		(start 153.475436 -404.119334)
		(end 153.475436 -406.71369)
		(width 0.14224)
		(layer "In6.Cu")
		(net "P5E_CPU1_P3_TX_BUF_DN<12>")
	)
	(segment
		(start 129.025142 -389.341868)
		(end 129.025142 -389.528304)
		(width 0.14224)
		(layer "In6.Cu")
		(net "P5E_CPU1_P3_TX_BUF_DN<12>")
	)
	(segment
		(start 129.385568 -390.176512)
		(end 129.385568 -390.365996)
		(width 0.14224)
		(layer "In6.Cu")
		(net "P5E_CPU1_P3_TX_BUF_DN<12>")
	)
	(arc
		(start 129.025142 -389.528304)
		(mid 129.068316 -389.745355)
		(end 129.191258 -389.92937)
		(width 0.14224)
		(layer "In6.Cu")
		(net "P5E_CPU1_P3_TX_BUF_DN<12>")
	)
	(arc
		(start 153.22677 -403.519132)
		(mid 153.410823 -403.794493)
		(end 153.475436 -404.119334)
		(width 0.14224)
		(layer "In6.Cu")
		(net "P5E_CPU1_P3_TX_BUF_DN<12>")
	)
	(arc
		(start 129.771648 -394.713206)
		(mid 129.818186 -394.94717)
		(end 129.950718 -395.145514)
		(width 0.14224)
		(layer "In6.Cu")
		(net "P5E_CPU1_P3_TX_BUF_DN<12>")
	)
	(arc
		(start 130.84556 -396.040356)
		(mid 131.074965 -396.21497)
		(end 131.342638 -396.322042)
		(width 0.14224)
		(layer "In6.Cu")
		(net "P5E_CPU1_P3_TX_BUF_DN<12>")
	)
	(arc
		(start 129.34823 -390.086342)
		(mid 129.375873 -390.127712)
		(end 129.385568 -390.176512)
		(width 0.14224)
		(layer "In6.Cu")
		(net "P5E_CPU1_P3_TX_BUF_DN<12>")
	)
	(arc
		(start 129.385568 -390.365996)
		(mid 129.393468 -390.474868)
		(end 129.417318 -390.581388)
		(width 0.14224)
		(layer "In6.Cu")
		(net "P5E_CPU1_P3_TX_BUF_DN<12>")
	)
	(segment
		(start 127.570484 -388.774432)
		(end 128.091184 -388.774432)
		(width 0.127)
		(layer "F.Cu")
		(net "P5E_CPU1_P3_TX_BUF_DN<11>")
	)
	(segment
		(start 150.391876 -407.27503)
		(end 150.121366 -407.00452)
		(width 0.12954)
		(layer "B.Cu")
		(net "P5E_CPU1_P3_TX_BUF_DN<11>")
	)
	(segment
		(start 150.095966 -408.250644)
		(end 150.391876 -407.954734)
		(width 0.12954)
		(layer "B.Cu")
		(net "P5E_CPU1_P3_TX_BUF_DN<11>")
	)
	(segment
		(start 150.391876 -407.954734)
		(end 150.391876 -407.27503)
		(width 0.12954)
		(layer "B.Cu")
		(net "P5E_CPU1_P3_TX_BUF_DN<11>")
	)
	(segment
		(start 150.002494 -403.37486)
		(end 150.08733 -403.454362)
		(width 0.14224)
		(layer "In6.Cu")
		(net "P5E_CPU1_P3_TX_BUF_DN<11>")
	)
	(segment
		(start 128.185672 -390.176512)
		(end 128.185672 -390.275064)
		(width 0.14224)
		(layer "In6.Cu")
		(net "P5E_CPU1_P3_TX_BUF_DN<11>")
	)
	(segment
		(start 150.412196 -406.71369)
		(end 150.121366 -407.00452)
		(width 0.14224)
		(layer "In6.Cu")
		(net "P5E_CPU1_P3_TX_BUF_DN<11>")
	)
	(segment
		(start 130.182366 -397.006572)
		(end 135.110474 -398.240504)
		(width 0.14224)
		(layer "In6.Cu")
		(net "P5E_CPU1_P3_TX_BUF_DN<11>")
	)
	(segment
		(start 128.143508 -389.006588)
		(end 127.824992 -389.325104)
		(width 0.14224)
		(layer "In6.Cu")
		(net "P5E_CPU1_P3_TX_BUF_DN<11>")
	)
	(segment
		(start 128.247902 -390.696958)
		(end 128.571752 -391.76452)
		(width 0.14224)
		(layer "In6.Cu")
		(net "P5E_CPU1_P3_TX_BUF_DN<11>")
	)
	(segment
		(start 128.80721 -395.778736)
		(end 129.842514 -396.81404)
		(width 0.14224)
		(layer "In6.Cu")
		(net "P5E_CPU1_P3_TX_BUF_DN<11>")
	)
	(segment
		(start 150.412196 -404.24227)
		(end 150.412196 -406.71369)
		(width 0.14224)
		(layer "In6.Cu")
		(net "P5E_CPU1_P3_TX_BUF_DN<11>")
	)
	(segment
		(start 128.143508 -388.826756)
		(end 128.143508 -389.006588)
		(width 0.14224)
		(layer "In6.Cu")
		(net "P5E_CPU1_P3_TX_BUF_DN<11>")
	)
	(segment
		(start 135.110474 -398.240504)
		(end 144.88541 -401.205954)
		(width 0.14224)
		(layer "In6.Cu")
		(net "P5E_CPU1_P3_TX_BUF_DN<11>")
	)
	(segment
		(start 127.824992 -389.325104)
		(end 127.824992 -389.543544)
		(width 0.14224)
		(layer "In6.Cu")
		(net "P5E_CPU1_P3_TX_BUF_DN<11>")
	)
	(segment
		(start 128.571752 -391.76452)
		(end 128.571752 -395.210538)
		(width 0.14224)
		(layer "In6.Cu")
		(net "P5E_CPU1_P3_TX_BUF_DN<11>")
	)
	(segment
		(start 127.980186 -389.918194)
		(end 128.148334 -390.086342)
		(width 0.14224)
		(layer "In6.Cu")
		(net "P5E_CPU1_P3_TX_BUF_DN<11>")
	)
	(segment
		(start 144.88541 -401.205954)
		(end 149.838918 -403.2631)
		(width 0.14224)
		(layer "In6.Cu")
		(net "P5E_CPU1_P3_TX_BUF_DN<11>")
	)
	(segment
		(start 128.091184 -388.774432)
		(end 128.143508 -388.826756)
		(width 0.14224)
		(layer "In6.Cu")
		(net "P5E_CPU1_P3_TX_BUF_DN<11>")
	)
	(arc
		(start 150.08733 -403.454362)
		(mid 150.327726 -403.816168)
		(end 150.412196 -404.24227)
		(width 0.14224)
		(layer "In6.Cu")
		(net "P5E_CPU1_P3_TX_BUF_DN<11>")
	)
	(arc
		(start 129.842514 -396.81404)
		(mid 129.999369 -396.933375)
		(end 130.182366 -397.006572)
		(width 0.14224)
		(layer "In6.Cu")
		(net "P5E_CPU1_P3_TX_BUF_DN<11>")
	)
	(arc
		(start 128.571752 -395.210538)
		(mid 128.632942 -395.51807)
		(end 128.80721 -395.778736)
		(width 0.14224)
		(layer "In6.Cu")
		(net "P5E_CPU1_P3_TX_BUF_DN<11>")
	)
	(arc
		(start 149.838918 -403.2631)
		(mid 149.925097 -403.312555)
		(end 150.002494 -403.37486)
		(width 0.14224)
		(layer "In6.Cu")
		(net "P5E_CPU1_P3_TX_BUF_DN<11>")
	)
	(arc
		(start 128.185672 -390.275064)
		(mid 128.201239 -390.488304)
		(end 128.247902 -390.696958)
		(width 0.14224)
		(layer "In6.Cu")
		(net "P5E_CPU1_P3_TX_BUF_DN<11>")
	)
	(arc
		(start 128.148334 -390.086342)
		(mid 128.175977 -390.127712)
		(end 128.185672 -390.176512)
		(width 0.14224)
		(layer "In6.Cu")
		(net "P5E_CPU1_P3_TX_BUF_DN<11>")
	)
	(arc
		(start 127.824992 -389.543544)
		(mid 127.865324 -389.746307)
		(end 127.980186 -389.918194)
		(width 0.14224)
		(layer "In6.Cu")
		(net "P5E_CPU1_P3_TX_BUF_DN<11>")
	)
	(segment
		(start 126.370588 -388.774432)
		(end 126.891288 -388.774432)
		(width 0.127)
		(layer "F.Cu")
		(net "P5E_CPU1_P3_TX_BUF_DN<10>")
	)
	(segment
		(start 147.328636 -407.27503)
		(end 147.058126 -407.00452)
		(width 0.12954)
		(layer "B.Cu")
		(net "P5E_CPU1_P3_TX_BUF_DN<10>")
	)
	(segment
		(start 147.032726 -408.250644)
		(end 147.328636 -407.954734)
		(width 0.12954)
		(layer "B.Cu")
		(net "P5E_CPU1_P3_TX_BUF_DN<10>")
	)
	(segment
		(start 147.328636 -407.954734)
		(end 147.328636 -407.27503)
		(width 0.12954)
		(layer "B.Cu")
		(net "P5E_CPU1_P3_TX_BUF_DN<10>")
	)
	(segment
		(start 147.348956 -403.860254)
		(end 147.348956 -406.71369)
		(width 0.14224)
		(layer "In6.Cu")
		(net "P5E_CPU1_P3_TX_BUF_DN<10>")
	)
	(segment
		(start 127.016256 -390.546082)
		(end 127.32131 -391.554462)
		(width 0.14224)
		(layer "In6.Cu")
		(net "P5E_CPU1_P3_TX_BUF_DN<10>")
	)
	(segment
		(start 126.625096 -389.304784)
		(end 126.625096 -389.541766)
		(width 0.14224)
		(layer "In6.Cu")
		(net "P5E_CPU1_P3_TX_BUF_DN<10>")
	)
	(segment
		(start 146.89836 -403.3012)
		(end 147.085304 -403.368002)
		(width 0.14224)
		(layer "In6.Cu")
		(net "P5E_CPU1_P3_TX_BUF_DN<10>")
	)
	(segment
		(start 126.78156 -389.919464)
		(end 126.948438 -390.086342)
		(width 0.14224)
		(layer "In6.Cu")
		(net "P5E_CPU1_P3_TX_BUF_DN<10>")
	)
	(segment
		(start 129.31648 -397.653764)
		(end 129.623058 -397.814292)
		(width 0.14224)
		(layer "In6.Cu")
		(net "P5E_CPU1_P3_TX_BUF_DN<10>")
	)
	(segment
		(start 126.891288 -388.774432)
		(end 126.933452 -388.816596)
		(width 0.14224)
		(layer "In6.Cu")
		(net "P5E_CPU1_P3_TX_BUF_DN<10>")
	)
	(segment
		(start 134.354824 -399.017998)
		(end 141.424406 -401.162266)
		(width 0.14224)
		(layer "In6.Cu")
		(net "P5E_CPU1_P3_TX_BUF_DN<10>")
	)
	(segment
		(start 147.348956 -406.71369)
		(end 147.058126 -407.00452)
		(width 0.14224)
		(layer "In6.Cu")
		(net "P5E_CPU1_P3_TX_BUF_DN<10>")
	)
	(segment
		(start 127.709422 -396.097252)
		(end 129.125726 -397.513556)
		(width 0.14224)
		(layer "In6.Cu")
		(net "P5E_CPU1_P3_TX_BUF_DN<10>")
	)
	(segment
		(start 126.933452 -388.996428)
		(end 126.625096 -389.304784)
		(width 0.14224)
		(layer "In6.Cu")
		(net "P5E_CPU1_P3_TX_BUF_DN<10>")
	)
	(segment
		(start 126.933452 -388.816596)
		(end 126.933452 -388.996428)
		(width 0.14224)
		(layer "In6.Cu")
		(net "P5E_CPU1_P3_TX_BUF_DN<10>")
	)
	(segment
		(start 141.51737 -401.195794)
		(end 142.960852 -401.794218)
		(width 0.14224)
		(layer "In6.Cu")
		(net "P5E_CPU1_P3_TX_BUF_DN<10>")
	)
	(segment
		(start 143.040608 -401.825968)
		(end 146.89836 -403.3012)
		(width 0.14224)
		(layer "In6.Cu")
		(net "P5E_CPU1_P3_TX_BUF_DN<10>")
	)
	(segment
		(start 126.985776 -390.176258)
		(end 126.985776 -390.339834)
		(width 0.14224)
		(layer "In6.Cu")
		(net "P5E_CPU1_P3_TX_BUF_DN<10>")
	)
	(segment
		(start 127.333756 -391.637266)
		(end 127.333756 -395.190218)
		(width 0.14224)
		(layer "In6.Cu")
		(net "P5E_CPU1_P3_TX_BUF_DN<10>")
	)
	(segment
		(start 129.741168 -397.85925)
		(end 134.23265 -398.984216)
		(width 0.14224)
		(layer "In6.Cu")
		(net "P5E_CPU1_P3_TX_BUF_DN<10>")
	)
	(arc
		(start 127.32131 -391.554462)
		(mid 127.330576 -391.595406)
		(end 127.333756 -391.637266)
		(width 0.14224)
		(layer "In6.Cu")
		(net "P5E_CPU1_P3_TX_BUF_DN<10>")
	)
	(arc
		(start 127.333756 -395.190218)
		(mid 127.431381 -395.6811)
		(end 127.709422 -396.097252)
		(width 0.14224)
		(layer "In6.Cu")
		(net "P5E_CPU1_P3_TX_BUF_DN<10>")
	)
	(arc
		(start 142.960852 -401.794218)
		(mid 143.000619 -401.810372)
		(end 143.040608 -401.825968)
		(width 0.14224)
		(layer "In6.Cu")
		(net "P5E_CPU1_P3_TX_BUF_DN<10>")
	)
	(arc
		(start 129.125726 -397.513556)
		(mid 129.215768 -397.59092)
		(end 129.31648 -397.653764)
		(width 0.14224)
		(layer "In6.Cu")
		(net "P5E_CPU1_P3_TX_BUF_DN<10>")
	)
	(arc
		(start 126.948438 -390.086342)
		(mid 126.976057 -390.127582)
		(end 126.985776 -390.176258)
		(width 0.14224)
		(layer "In6.Cu")
		(net "P5E_CPU1_P3_TX_BUF_DN<10>")
	)
	(arc
		(start 141.424406 -401.162266)
		(mid 141.471301 -401.177884)
		(end 141.51737 -401.195794)
		(width 0.14224)
		(layer "In6.Cu")
		(net "P5E_CPU1_P3_TX_BUF_DN<10>")
	)
	(arc
		(start 147.22983 -403.483064)
		(mid 147.314106 -403.663851)
		(end 147.348956 -403.860254)
		(width 0.14224)
		(layer "In6.Cu")
		(net "P5E_CPU1_P3_TX_BUF_DN<10>")
	)
	(arc
		(start 126.985776 -390.339834)
		(mid 126.993441 -390.444077)
		(end 127.016256 -390.546082)
		(width 0.14224)
		(layer "In6.Cu")
		(net "P5E_CPU1_P3_TX_BUF_DN<10>")
	)
	(arc
		(start 126.625096 -389.541766)
		(mid 126.665757 -389.746181)
		(end 126.78156 -389.919464)
		(width 0.14224)
		(layer "In6.Cu")
		(net "P5E_CPU1_P3_TX_BUF_DN<10>")
	)
	(arc
		(start 147.085304 -403.368002)
		(mid 147.167109 -403.413538)
		(end 147.22983 -403.483064)
		(width 0.14224)
		(layer "In6.Cu")
		(net "P5E_CPU1_P3_TX_BUF_DN<10>")
	)
	(arc
		(start 134.23265 -398.984216)
		(mid 134.293945 -399.000355)
		(end 134.354824 -399.017998)
		(width 0.14224)
		(layer "In6.Cu")
		(net "P5E_CPU1_P3_TX_BUF_DN<10>")
	)
	(arc
		(start 129.623058 -397.814292)
		(mid 129.680781 -397.840271)
		(end 129.741168 -397.85925)
		(width 0.14224)
		(layer "In6.Cu")
		(net "P5E_CPU1_P3_TX_BUF_DN<10>")
	)
	(segment
		(start 114.370612 -388.774432)
		(end 114.891312 -388.774432)
		(width 0.127)
		(layer "F.Cu")
		(net "P5E_CPU1_P3_TX_BUF_DN<0>")
	)
	(segment
		(start 116.696236 -407.27503)
		(end 116.425726 -407.00452)
		(width 0.12954)
		(layer "B.Cu")
		(net "P5E_CPU1_P3_TX_BUF_DN<0>")
	)
	(segment
		(start 116.400326 -408.250644)
		(end 116.696236 -407.954734)
		(width 0.12954)
		(layer "B.Cu")
		(net "P5E_CPU1_P3_TX_BUF_DN<0>")
	)
	(segment
		(start 116.696236 -407.954734)
		(end 116.696236 -407.27503)
		(width 0.12954)
		(layer "B.Cu")
		(net "P5E_CPU1_P3_TX_BUF_DN<0>")
	)
	(segment
		(start 115.37188 -391.803636)
		(end 115.37188 -396.852648)
		(width 0.14224)
		(layer "In6.Cu")
		(net "P5E_CPU1_P3_TX_BUF_DN<0>")
	)
	(segment
		(start 114.943636 -389.006588)
		(end 114.62512 -389.325104)
		(width 0.14224)
		(layer "In6.Cu")
		(net "P5E_CPU1_P3_TX_BUF_DN<0>")
	)
	(segment
		(start 115.37188 -396.852648)
		(end 116.716556 -403.64029)
		(width 0.14224)
		(layer "In6.Cu")
		(net "P5E_CPU1_P3_TX_BUF_DN<0>")
	)
	(segment
		(start 114.9858 -390.176004)
		(end 114.9858 -390.360662)
		(width 0.14224)
		(layer "In6.Cu")
		(net "P5E_CPU1_P3_TX_BUF_DN<0>")
	)
	(segment
		(start 114.891312 -388.774432)
		(end 114.943636 -388.826756)
		(width 0.14224)
		(layer "In6.Cu")
		(net "P5E_CPU1_P3_TX_BUF_DN<0>")
	)
	(segment
		(start 114.943636 -388.826756)
		(end 114.943636 -389.006588)
		(width 0.14224)
		(layer "In6.Cu")
		(net "P5E_CPU1_P3_TX_BUF_DN<0>")
	)
	(segment
		(start 116.716556 -403.64029)
		(end 116.716556 -406.71369)
		(width 0.14224)
		(layer "In6.Cu")
		(net "P5E_CPU1_P3_TX_BUF_DN<0>")
	)
	(segment
		(start 114.62512 -389.325104)
		(end 114.62512 -389.550148)
		(width 0.14224)
		(layer "In6.Cu")
		(net "P5E_CPU1_P3_TX_BUF_DN<0>")
	)
	(segment
		(start 116.716556 -406.71369)
		(end 116.425726 -407.00452)
		(width 0.14224)
		(layer "In6.Cu")
		(net "P5E_CPU1_P3_TX_BUF_DN<0>")
	)
	(segment
		(start 115.01628 -390.567672)
		(end 115.353338 -391.678922)
		(width 0.14224)
		(layer "In6.Cu")
		(net "P5E_CPU1_P3_TX_BUF_DN<0>")
	)
	(segment
		(start 114.775996 -389.913876)
		(end 114.948462 -390.086088)
		(width 0.14224)
		(layer "In6.Cu")
		(net "P5E_CPU1_P3_TX_BUF_DN<0>")
	)
	(arc
		(start 115.353338 -391.678922)
		(mid 115.367221 -391.740594)
		(end 115.37188 -391.803636)
		(width 0.14224)
		(layer "In6.Cu")
		(net "P5E_CPU1_P3_TX_BUF_DN<0>")
	)
	(arc
		(start 114.62512 -389.550148)
		(mid 114.66439 -389.74701)
		(end 114.775996 -389.913876)
		(width 0.14224)
		(layer "In6.Cu")
		(net "P5E_CPU1_P3_TX_BUF_DN<0>")
	)
	(arc
		(start 114.948462 -390.086088)
		(mid 114.976081 -390.127328)
		(end 114.9858 -390.176004)
		(width 0.14224)
		(layer "In6.Cu")
		(net "P5E_CPU1_P3_TX_BUF_DN<0>")
	)
	(arc
		(start 114.9858 -390.360662)
		(mid 114.993382 -390.465295)
		(end 115.01628 -390.567672)
		(width 0.14224)
		(layer "In6.Cu")
		(net "P5E_CPU1_P3_TX_BUF_DN<0>")
	)
	(segment
		(start 144.587976 -409.079954)
		(end 144.587976 -409.759658)
		(width 0.12954)
		(layer "B.Cu")
		(net "P5E_CPU1_P3_TX_BUF_C_DP<9>")
	)
	(segment
		(start 144.587976 -409.759658)
		(end 144.858486 -410.030168)
		(width 0.12954)
		(layer "B.Cu")
		(net "P5E_CPU1_P3_TX_BUF_C_DP<9>")
	)
	(segment
		(start 144.883886 -408.784044)
		(end 144.587976 -409.079954)
		(width 0.12954)
		(layer "B.Cu")
		(net "P5E_CPU1_P3_TX_BUF_C_DP<9>")
	)
	(segment
		(start 144.567656 -411.19425)
		(end 144.567656 -410.320998)
		(width 0.14224)
		(layer "In6.Cu")
		(net "P5E_CPU1_P3_TX_BUF_C_DP<9>")
	)
	(segment
		(start 144.567656 -410.320998)
		(end 144.858486 -410.030168)
		(width 0.14224)
		(layer "In6.Cu")
		(net "P5E_CPU1_P3_TX_BUF_C_DP<9>")
	)
	(segment
		(start 144.533366 -416.515804)
		(end 144.554194 -416.089338)
		(width 0.14224)
		(layer "In6.Cu")
		(net "P5E_CPU1_P3_TX_BUF_C_DP<9>")
	)
	(segment
		(start 144.665192 -413.836358)
		(end 144.53489 -413.692594)
		(width 0.14224)
		(layer "In6.Cu")
		(net "P5E_CPU1_P3_TX_BUF_C_DP<9>")
	)
	(segment
		(start 144.567656 -413.022288)
		(end 144.567656 -411.89529)
		(width 0.14224)
		(layer "In6.Cu")
		(net "P5E_CPU1_P3_TX_BUF_C_DP<9>")
	)
	(segment
		(start 144.44472 -415.519616)
		(end 144.588738 -415.389314)
		(width 0.14224)
		(layer "In6.Cu")
		(net "P5E_CPU1_P3_TX_BUF_C_DP<9>")
	)
	(segment
		(start 144.232376 -427.54296)
		(end 144.07007 -427.380654)
		(width 0.14224)
		(layer "In6.Cu")
		(net "P5E_CPU1_P3_TX_BUF_C_DP<9>")
	)
	(segment
		(start 144.389348 -416.646106)
		(end 144.533366 -416.515804)
		(width 0.14224)
		(layer "In6.Cu")
		(net "P5E_CPU1_P3_TX_BUF_C_DP<9>")
	)
	(segment
		(start 144.07007 -423.15257)
		(end 144.389348 -416.646106)
		(width 0.14224)
		(layer "In6.Cu")
		(net "P5E_CPU1_P3_TX_BUF_C_DP<9>")
	)
	(segment
		(start 144.07007 -427.380654)
		(end 144.07007 -423.15257)
		(width 0.14224)
		(layer "In6.Cu")
		(net "P5E_CPU1_P3_TX_BUF_C_DP<9>")
	)
	(segment
		(start 144.567656 -411.89529)
		(end 144.704816 -411.75813)
		(width 0.14224)
		(layer "In6.Cu")
		(net "P5E_CPU1_P3_TX_BUF_C_DP<9>")
	)
	(segment
		(start 144.554194 -416.089338)
		(end 144.423892 -415.945574)
		(width 0.14224)
		(layer "In6.Cu")
		(net "P5E_CPU1_P3_TX_BUF_C_DP<9>")
	)
	(segment
		(start 144.750028 -427.089824)
		(end 144.750028 -427.41596)
		(width 0.14224)
		(layer "In6.Cu")
		(net "P5E_CPU1_P3_TX_BUF_C_DP<9>")
	)
	(segment
		(start 144.750028 -427.41596)
		(end 144.623028 -427.54296)
		(width 0.14224)
		(layer "In6.Cu")
		(net "P5E_CPU1_P3_TX_BUF_C_DP<9>")
	)
	(segment
		(start 144.623028 -427.54296)
		(end 144.232376 -427.54296)
		(width 0.14224)
		(layer "In6.Cu")
		(net "P5E_CPU1_P3_TX_BUF_C_DP<9>")
	)
	(segment
		(start 144.704816 -411.75813)
		(end 144.704816 -411.33141)
		(width 0.14224)
		(layer "In6.Cu")
		(net "P5E_CPU1_P3_TX_BUF_C_DP<9>")
	)
	(segment
		(start 144.588738 -415.389314)
		(end 144.609566 -414.962848)
		(width 0.14224)
		(layer "In6.Cu")
		(net "P5E_CPU1_P3_TX_BUF_C_DP<9>")
	)
	(segment
		(start 144.500092 -414.393126)
		(end 144.64411 -414.262824)
		(width 0.14224)
		(layer "In6.Cu")
		(net "P5E_CPU1_P3_TX_BUF_C_DP<9>")
	)
	(segment
		(start 144.704816 -411.33141)
		(end 144.567656 -411.19425)
		(width 0.14224)
		(layer "In6.Cu")
		(net "P5E_CPU1_P3_TX_BUF_C_DP<9>")
	)
	(segment
		(start 144.423892 -415.945574)
		(end 144.44472 -415.519616)
		(width 0.14224)
		(layer "In6.Cu")
		(net "P5E_CPU1_P3_TX_BUF_C_DP<9>")
	)
	(segment
		(start 144.479264 -414.819084)
		(end 144.500092 -414.393126)
		(width 0.14224)
		(layer "In6.Cu")
		(net "P5E_CPU1_P3_TX_BUF_C_DP<9>")
	)
	(segment
		(start 144.64411 -414.262824)
		(end 144.665192 -413.836358)
		(width 0.14224)
		(layer "In6.Cu")
		(net "P5E_CPU1_P3_TX_BUF_C_DP<9>")
	)
	(segment
		(start 144.609566 -414.962848)
		(end 144.479264 -414.819084)
		(width 0.14224)
		(layer "In6.Cu")
		(net "P5E_CPU1_P3_TX_BUF_C_DP<9>")
	)
	(segment
		(start 144.53489 -413.692594)
		(end 144.567656 -413.022288)
		(width 0.14224)
		(layer "In6.Cu")
		(net "P5E_CPU1_P3_TX_BUF_C_DP<9>")
	)
	(segment
		(start 141.524736 -409.079954)
		(end 141.524736 -409.759658)
		(width 0.12954)
		(layer "B.Cu")
		(net "P5E_CPU1_P3_TX_BUF_C_DP<8>")
	)
	(segment
		(start 141.524736 -409.759658)
		(end 141.795246 -410.030168)
		(width 0.12954)
		(layer "B.Cu")
		(net "P5E_CPU1_P3_TX_BUF_C_DP<8>")
	)
	(segment
		(start 141.820646 -408.784044)
		(end 141.524736 -409.079954)
		(width 0.12954)
		(layer "B.Cu")
		(net "P5E_CPU1_P3_TX_BUF_C_DP<8>")
	)
	(segment
		(start 141.641576 -411.354778)
		(end 141.504416 -411.217618)
		(width 0.14224)
		(layer "In6.Cu")
		(net "P5E_CPU1_P3_TX_BUF_C_DP<8>")
	)
	(segment
		(start 141.691614 -417.036758)
		(end 141.670786 -416.6108)
		(width 0.14224)
		(layer "In6.Cu")
		(net "P5E_CPU1_P3_TX_BUF_C_DP<8>")
	)
	(segment
		(start 141.801088 -416.467036)
		(end 141.78026 -416.04057)
		(width 0.14224)
		(layer "In6.Cu")
		(net "P5E_CPU1_P3_TX_BUF_C_DP<8>")
	)
	(segment
		(start 141.636242 -415.910268)
		(end 141.615414 -415.48431)
		(width 0.14224)
		(layer "In6.Cu")
		(net "P5E_CPU1_P3_TX_BUF_C_DP<8>")
	)
	(segment
		(start 141.724888 -414.91408)
		(end 141.58087 -414.783778)
		(width 0.14224)
		(layer "In6.Cu")
		(net "P5E_CPU1_P3_TX_BUF_C_DP<8>")
	)
	(segment
		(start 141.560042 -414.35782)
		(end 141.690344 -414.214056)
		(width 0.14224)
		(layer "In6.Cu")
		(net "P5E_CPU1_P3_TX_BUF_C_DP<8>")
	)
	(segment
		(start 141.745716 -415.340546)
		(end 141.724888 -414.91408)
		(width 0.14224)
		(layer "In6.Cu")
		(net "P5E_CPU1_P3_TX_BUF_C_DP<8>")
	)
	(segment
		(start 142.070074 -426.315378)
		(end 142.070074 -424.75023)
		(width 0.14224)
		(layer "In6.Cu")
		(net "P5E_CPU1_P3_TX_BUF_C_DP<8>")
	)
	(segment
		(start 141.615414 -415.48431)
		(end 141.745716 -415.340546)
		(width 0.14224)
		(layer "In6.Cu")
		(net "P5E_CPU1_P3_TX_BUF_C_DP<8>")
	)
	(segment
		(start 142.750032 -426.42155)
		(end 142.622524 -426.549058)
		(width 0.14224)
		(layer "In6.Cu")
		(net "P5E_CPU1_P3_TX_BUF_C_DP<8>")
	)
	(segment
		(start 141.669516 -413.78759)
		(end 141.525498 -413.657288)
		(width 0.14224)
		(layer "In6.Cu")
		(net "P5E_CPU1_P3_TX_BUF_C_DP<8>")
	)
	(segment
		(start 141.78026 -416.04057)
		(end 141.636242 -415.910268)
		(width 0.14224)
		(layer "In6.Cu")
		(net "P5E_CPU1_P3_TX_BUF_C_DP<8>")
	)
	(segment
		(start 141.690344 -414.214056)
		(end 141.669516 -413.78759)
		(width 0.14224)
		(layer "In6.Cu")
		(net "P5E_CPU1_P3_TX_BUF_C_DP<8>")
	)
	(segment
		(start 141.504416 -410.320998)
		(end 141.795246 -410.030168)
		(width 0.14224)
		(layer "In6.Cu")
		(net "P5E_CPU1_P3_TX_BUF_C_DP<8>")
	)
	(segment
		(start 141.504416 -411.217618)
		(end 141.504416 -410.320998)
		(width 0.14224)
		(layer "In6.Cu")
		(net "P5E_CPU1_P3_TX_BUF_C_DP<8>")
	)
	(segment
		(start 141.670786 -416.6108)
		(end 141.801088 -416.467036)
		(width 0.14224)
		(layer "In6.Cu")
		(net "P5E_CPU1_P3_TX_BUF_C_DP<8>")
	)
	(segment
		(start 141.504416 -411.918658)
		(end 141.641576 -411.781498)
		(width 0.14224)
		(layer "In6.Cu")
		(net "P5E_CPU1_P3_TX_BUF_C_DP<8>")
	)
	(segment
		(start 141.58087 -414.783778)
		(end 141.560042 -414.35782)
		(width 0.14224)
		(layer "In6.Cu")
		(net "P5E_CPU1_P3_TX_BUF_C_DP<8>")
	)
	(segment
		(start 142.303754 -426.549058)
		(end 142.070074 -426.315378)
		(width 0.14224)
		(layer "In6.Cu")
		(net "P5E_CPU1_P3_TX_BUF_C_DP<8>")
	)
	(segment
		(start 141.726158 -417.73729)
		(end 141.85646 -417.593526)
		(width 0.14224)
		(layer "In6.Cu")
		(net "P5E_CPU1_P3_TX_BUF_C_DP<8>")
	)
	(segment
		(start 142.622524 -426.549058)
		(end 142.303754 -426.549058)
		(width 0.14224)
		(layer "In6.Cu")
		(net "P5E_CPU1_P3_TX_BUF_C_DP<8>")
	)
	(segment
		(start 141.504416 -413.23133)
		(end 141.504416 -411.918658)
		(width 0.14224)
		(layer "In6.Cu")
		(net "P5E_CPU1_P3_TX_BUF_C_DP<8>")
	)
	(segment
		(start 141.835632 -417.16706)
		(end 141.691614 -417.036758)
		(width 0.14224)
		(layer "In6.Cu")
		(net "P5E_CPU1_P3_TX_BUF_C_DP<8>")
	)
	(segment
		(start 141.641576 -411.781498)
		(end 141.641576 -411.354778)
		(width 0.14224)
		(layer "In6.Cu")
		(net "P5E_CPU1_P3_TX_BUF_C_DP<8>")
	)
	(segment
		(start 141.85646 -417.593526)
		(end 141.835632 -417.16706)
		(width 0.14224)
		(layer "In6.Cu")
		(net "P5E_CPU1_P3_TX_BUF_C_DP<8>")
	)
	(segment
		(start 141.525498 -413.657288)
		(end 141.50467 -413.23133)
		(width 0.14224)
		(layer "In6.Cu")
		(net "P5E_CPU1_P3_TX_BUF_C_DP<8>")
	)
	(segment
		(start 141.50467 -413.23133)
		(end 141.504416 -413.23133)
		(width 0.14224)
		(layer "In6.Cu")
		(net "P5E_CPU1_P3_TX_BUF_C_DP<8>")
	)
	(segment
		(start 142.070074 -424.75023)
		(end 141.726158 -417.73729)
		(width 0.14224)
		(layer "In6.Cu")
		(net "P5E_CPU1_P3_TX_BUF_C_DP<8>")
	)
	(segment
		(start 142.750032 -426.089826)
		(end 142.750032 -426.42155)
		(width 0.14224)
		(layer "In6.Cu")
		(net "P5E_CPU1_P3_TX_BUF_C_DP<8>")
	)
	(segment
		(start 138.461496 -409.759658)
		(end 138.732006 -410.030168)
		(width 0.12954)
		(layer "B.Cu")
		(net "P5E_CPU1_P3_TX_BUF_C_DP<7>")
	)
	(segment
		(start 138.757406 -408.784044)
		(end 138.461496 -409.079954)
		(width 0.12954)
		(layer "B.Cu")
		(net "P5E_CPU1_P3_TX_BUF_C_DP<7>")
	)
	(segment
		(start 138.461496 -409.079954)
		(end 138.461496 -409.759658)
		(width 0.12954)
		(layer "B.Cu")
		(net "P5E_CPU1_P3_TX_BUF_C_DP<7>")
	)
	(segment
		(start 138.593576 -414.623504)
		(end 138.743944 -414.746694)
		(width 0.14224)
		(layer "In6.Cu")
		(net "P5E_CPU1_P3_TX_BUF_C_DP<7>")
	)
	(segment
		(start 139.237974 -427.548802)
		(end 139.62253 -427.548802)
		(width 0.14224)
		(layer "In6.Cu")
		(net "P5E_CPU1_P3_TX_BUF_C_DP<7>")
	)
	(segment
		(start 138.773408 -416.443922)
		(end 139.069826 -419.456616)
		(width 0.14224)
		(layer "In6.Cu")
		(net "P5E_CPU1_P3_TX_BUF_C_DP<7>")
	)
	(segment
		(start 138.662664 -415.321496)
		(end 138.70432 -415.74593)
		(width 0.14224)
		(layer "In6.Cu")
		(net "P5E_CPU1_P3_TX_BUF_C_DP<7>")
	)
	(segment
		(start 138.55192 -414.19907)
		(end 138.593576 -414.623504)
		(width 0.14224)
		(layer "In6.Cu")
		(net "P5E_CPU1_P3_TX_BUF_C_DP<7>")
	)
	(segment
		(start 138.441176 -410.320998)
		(end 138.441176 -413.076644)
		(width 0.14224)
		(layer "In6.Cu")
		(net "P5E_CPU1_P3_TX_BUF_C_DP<7>")
	)
	(segment
		(start 138.6332 -413.624268)
		(end 138.674856 -414.04921)
		(width 0.14224)
		(layer "In6.Cu")
		(net "P5E_CPU1_P3_TX_BUF_C_DP<7>")
	)
	(segment
		(start 139.069826 -427.380654)
		(end 139.237974 -427.548802)
		(width 0.14224)
		(layer "In6.Cu")
		(net "P5E_CPU1_P3_TX_BUF_C_DP<7>")
	)
	(segment
		(start 139.62253 -427.548802)
		(end 139.749784 -427.421548)
		(width 0.14224)
		(layer "In6.Cu")
		(net "P5E_CPU1_P3_TX_BUF_C_DP<7>")
	)
	(segment
		(start 138.674856 -414.04921)
		(end 138.55192 -414.19907)
		(width 0.14224)
		(layer "In6.Cu")
		(net "P5E_CPU1_P3_TX_BUF_C_DP<7>")
	)
	(segment
		(start 138.7856 -415.171636)
		(end 138.662664 -415.321496)
		(width 0.14224)
		(layer "In6.Cu")
		(net "P5E_CPU1_P3_TX_BUF_C_DP<7>")
	)
	(segment
		(start 138.732006 -410.030168)
		(end 138.441176 -410.320998)
		(width 0.14224)
		(layer "In6.Cu")
		(net "P5E_CPU1_P3_TX_BUF_C_DP<7>")
	)
	(segment
		(start 139.749784 -427.421548)
		(end 139.749784 -427.089824)
		(width 0.14224)
		(layer "In6.Cu")
		(net "P5E_CPU1_P3_TX_BUF_C_DP<7>")
	)
	(segment
		(start 138.482832 -413.501078)
		(end 138.6332 -413.624268)
		(width 0.14224)
		(layer "In6.Cu")
		(net "P5E_CPU1_P3_TX_BUF_C_DP<7>")
	)
	(segment
		(start 138.441176 -413.076644)
		(end 138.482832 -413.501078)
		(width 0.14224)
		(layer "In6.Cu")
		(net "P5E_CPU1_P3_TX_BUF_C_DP<7>")
	)
	(segment
		(start 138.743944 -414.746694)
		(end 138.7856 -415.171636)
		(width 0.14224)
		(layer "In6.Cu")
		(net "P5E_CPU1_P3_TX_BUF_C_DP<7>")
	)
	(segment
		(start 138.70432 -415.74593)
		(end 138.854434 -415.86912)
		(width 0.14224)
		(layer "In6.Cu")
		(net "P5E_CPU1_P3_TX_BUF_C_DP<7>")
	)
	(segment
		(start 139.069826 -419.456616)
		(end 139.069826 -427.380654)
		(width 0.14224)
		(layer "In6.Cu")
		(net "P5E_CPU1_P3_TX_BUF_C_DP<7>")
	)
	(segment
		(start 138.854434 -415.86912)
		(end 138.896344 -416.294062)
		(width 0.14224)
		(layer "In6.Cu")
		(net "P5E_CPU1_P3_TX_BUF_C_DP<7>")
	)
	(segment
		(start 138.896344 -416.294062)
		(end 138.773408 -416.443922)
		(width 0.14224)
		(layer "In6.Cu")
		(net "P5E_CPU1_P3_TX_BUF_C_DP<7>")
	)
	(segment
		(start 135.694166 -408.784044)
		(end 135.398256 -409.079954)
		(width 0.12954)
		(layer "B.Cu")
		(net "P5E_CPU1_P3_TX_BUF_C_DP<6>")
	)
	(segment
		(start 135.398256 -409.759658)
		(end 135.668766 -410.030168)
		(width 0.12954)
		(layer "B.Cu")
		(net "P5E_CPU1_P3_TX_BUF_C_DP<6>")
	)
	(segment
		(start 135.398256 -409.079954)
		(end 135.398256 -409.759658)
		(width 0.12954)
		(layer "B.Cu")
		(net "P5E_CPU1_P3_TX_BUF_C_DP<6>")
	)
	(segment
		(start 136.583928 -416.029648)
		(end 136.40435 -415.95548)
		(width 0.14224)
		(layer "In6.Cu")
		(net "P5E_CPU1_P3_TX_BUF_C_DP<6>")
	)
	(segment
		(start 137.749788 -426.089826)
		(end 137.749788 -426.42155)
		(width 0.14224)
		(layer "In6.Cu")
		(net "P5E_CPU1_P3_TX_BUF_C_DP<6>")
	)
	(segment
		(start 135.377936 -411.08884)
		(end 135.377936 -410.320998)
		(width 0.14224)
		(layer "In6.Cu")
		(net "P5E_CPU1_P3_TX_BUF_C_DP<6>")
	)
	(segment
		(start 136.89457 -417.138104)
		(end 136.673082 -416.60318)
		(width 0.14224)
		(layer "In6.Cu")
		(net "P5E_CPU1_P3_TX_BUF_C_DP<6>")
	)
	(segment
		(start 137.749788 -426.42155)
		(end 137.59307 -426.578268)
		(width 0.14224)
		(layer "In6.Cu")
		(net "P5E_CPU1_P3_TX_BUF_C_DP<6>")
	)
	(segment
		(start 135.515096 -411.65272)
		(end 135.515096 -411.226)
		(width 0.14224)
		(layer "In6.Cu")
		(net "P5E_CPU1_P3_TX_BUF_C_DP<6>")
	)
	(segment
		(start 136.673082 -416.60318)
		(end 136.74725 -416.42411)
		(width 0.14224)
		(layer "In6.Cu")
		(net "P5E_CPU1_P3_TX_BUF_C_DP<6>")
	)
	(segment
		(start 137.06983 -426.315378)
		(end 137.06983 -418.91966)
		(width 0.14224)
		(layer "In6.Cu")
		(net "P5E_CPU1_P3_TX_BUF_C_DP<6>")
	)
	(segment
		(start 135.972804 -414.913318)
		(end 135.809736 -414.51911)
		(width 0.14224)
		(layer "In6.Cu")
		(net "P5E_CPU1_P3_TX_BUF_C_DP<6>")
	)
	(segment
		(start 136.74725 -416.42411)
		(end 136.583928 -416.029648)
		(width 0.14224)
		(layer "In6.Cu")
		(net "P5E_CPU1_P3_TX_BUF_C_DP<6>")
	)
	(segment
		(start 135.377936 -411.78988)
		(end 135.515096 -411.65272)
		(width 0.14224)
		(layer "In6.Cu")
		(net "P5E_CPU1_P3_TX_BUF_C_DP<6>")
	)
	(segment
		(start 135.883904 -414.339786)
		(end 135.720582 -413.945324)
		(width 0.14224)
		(layer "In6.Cu")
		(net "P5E_CPU1_P3_TX_BUF_C_DP<6>")
	)
	(segment
		(start 135.377936 -413.296354)
		(end 135.377936 -411.78988)
		(width 0.14224)
		(layer "In6.Cu")
		(net "P5E_CPU1_P3_TX_BUF_C_DP<6>")
	)
	(segment
		(start 136.40435 -415.95548)
		(end 136.241282 -415.561272)
		(width 0.14224)
		(layer "In6.Cu")
		(net "P5E_CPU1_P3_TX_BUF_C_DP<6>")
	)
	(segment
		(start 137.59307 -426.578268)
		(end 137.33272 -426.578268)
		(width 0.14224)
		(layer "In6.Cu")
		(net "P5E_CPU1_P3_TX_BUF_C_DP<6>")
	)
	(segment
		(start 136.241282 -415.561272)
		(end 136.315704 -415.381948)
		(width 0.14224)
		(layer "In6.Cu")
		(net "P5E_CPU1_P3_TX_BUF_C_DP<6>")
	)
	(segment
		(start 135.541004 -413.871156)
		(end 135.447024 -413.643826)
		(width 0.14224)
		(layer "In6.Cu")
		(net "P5E_CPU1_P3_TX_BUF_C_DP<6>")
	)
	(segment
		(start 135.720582 -413.945324)
		(end 135.541004 -413.871156)
		(width 0.14224)
		(layer "In6.Cu")
		(net "P5E_CPU1_P3_TX_BUF_C_DP<6>")
	)
	(segment
		(start 135.447024 -413.643826)
		(end 135.377936 -413.296354)
		(width 0.14224)
		(layer "In6.Cu")
		(net "P5E_CPU1_P3_TX_BUF_C_DP<6>")
	)
	(segment
		(start 136.152382 -414.987486)
		(end 135.972804 -414.913318)
		(width 0.14224)
		(layer "In6.Cu")
		(net "P5E_CPU1_P3_TX_BUF_C_DP<6>")
	)
	(segment
		(start 135.515096 -411.226)
		(end 135.377936 -411.08884)
		(width 0.14224)
		(layer "In6.Cu")
		(net "P5E_CPU1_P3_TX_BUF_C_DP<6>")
	)
	(segment
		(start 136.315704 -415.381948)
		(end 136.152382 -414.987486)
		(width 0.14224)
		(layer "In6.Cu")
		(net "P5E_CPU1_P3_TX_BUF_C_DP<6>")
	)
	(segment
		(start 137.33272 -426.578268)
		(end 137.06983 -426.315378)
		(width 0.14224)
		(layer "In6.Cu")
		(net "P5E_CPU1_P3_TX_BUF_C_DP<6>")
	)
	(segment
		(start 135.809736 -414.51911)
		(end 135.883904 -414.339786)
		(width 0.14224)
		(layer "In6.Cu")
		(net "P5E_CPU1_P3_TX_BUF_C_DP<6>")
	)
	(segment
		(start 135.377936 -410.320998)
		(end 135.668766 -410.030168)
		(width 0.14224)
		(layer "In6.Cu")
		(net "P5E_CPU1_P3_TX_BUF_C_DP<6>")
	)
	(segment
		(start 137.06983 -418.91966)
		(end 136.89457 -417.138104)
		(width 0.14224)
		(layer "In6.Cu")
		(net "P5E_CPU1_P3_TX_BUF_C_DP<6>")
	)
	(segment
		(start 132.630926 -408.784044)
		(end 132.335016 -409.079954)
		(width 0.12954)
		(layer "B.Cu")
		(net "P5E_CPU1_P3_TX_BUF_C_DP<5>")
	)
	(segment
		(start 132.335016 -409.079954)
		(end 132.335016 -409.759658)
		(width 0.12954)
		(layer "B.Cu")
		(net "P5E_CPU1_P3_TX_BUF_C_DP<5>")
	)
	(segment
		(start 132.335016 -409.759658)
		(end 132.605526 -410.030168)
		(width 0.12954)
		(layer "B.Cu")
		(net "P5E_CPU1_P3_TX_BUF_C_DP<5>")
	)
	(segment
		(start 135.069834 -418.41293)
		(end 134.971536 -417.526216)
		(width 0.14224)
		(layer "In6.Cu")
		(net "P5E_CPU1_P3_TX_BUF_C_DP<5>")
	)
	(segment
		(start 133.848348 -415.5313)
		(end 133.886194 -415.341054)
		(width 0.14224)
		(layer "In6.Cu")
		(net "P5E_CPU1_P3_TX_BUF_C_DP<5>")
	)
	(segment
		(start 134.512812 -416.278822)
		(end 134.275576 -415.92373)
		(width 0.14224)
		(layer "In6.Cu")
		(net "P5E_CPU1_P3_TX_BUF_C_DP<5>")
	)
	(segment
		(start 135.749792 -427.41596)
		(end 135.622792 -427.54296)
		(width 0.14224)
		(layer "In6.Cu")
		(net "P5E_CPU1_P3_TX_BUF_C_DP<5>")
	)
	(segment
		(start 133.22173 -414.593532)
		(end 133.259576 -414.403286)
		(width 0.14224)
		(layer "In6.Cu")
		(net "P5E_CPU1_P3_TX_BUF_C_DP<5>")
	)
	(segment
		(start 133.648958 -414.985962)
		(end 133.458712 -414.948116)
		(width 0.14224)
		(layer "In6.Cu")
		(net "P5E_CPU1_P3_TX_BUF_C_DP<5>")
	)
	(segment
		(start 133.022086 -414.048194)
		(end 132.83184 -414.010348)
		(width 0.14224)
		(layer "In6.Cu")
		(net "P5E_CPU1_P3_TX_BUF_C_DP<5>")
	)
	(segment
		(start 132.314696 -410.320998)
		(end 132.605526 -410.030168)
		(width 0.14224)
		(layer "In6.Cu")
		(net "P5E_CPU1_P3_TX_BUF_C_DP<5>")
	)
	(segment
		(start 134.275576 -415.92373)
		(end 134.08533 -415.885884)
		(width 0.14224)
		(layer "In6.Cu")
		(net "P5E_CPU1_P3_TX_BUF_C_DP<5>")
	)
	(segment
		(start 135.622792 -427.54296)
		(end 135.23214 -427.54296)
		(width 0.14224)
		(layer "In6.Cu")
		(net "P5E_CPU1_P3_TX_BUF_C_DP<5>")
	)
	(segment
		(start 134.08533 -415.885884)
		(end 133.848348 -415.5313)
		(width 0.14224)
		(layer "In6.Cu")
		(net "P5E_CPU1_P3_TX_BUF_C_DP<5>")
	)
	(segment
		(start 133.458712 -414.948116)
		(end 133.22173 -414.593532)
		(width 0.14224)
		(layer "In6.Cu")
		(net "P5E_CPU1_P3_TX_BUF_C_DP<5>")
	)
	(segment
		(start 134.971536 -417.526216)
		(end 134.865364 -417.053776)
		(width 0.14224)
		(layer "In6.Cu")
		(net "P5E_CPU1_P3_TX_BUF_C_DP<5>")
	)
	(segment
		(start 132.314696 -410.994098)
		(end 132.314696 -410.320998)
		(width 0.14224)
		(layer "In6.Cu")
		(net "P5E_CPU1_P3_TX_BUF_C_DP<5>")
	)
	(segment
		(start 134.865364 -417.053776)
		(end 134.474966 -416.469068)
		(width 0.14224)
		(layer "In6.Cu")
		(net "P5E_CPU1_P3_TX_BUF_C_DP<5>")
	)
	(segment
		(start 133.259576 -414.403286)
		(end 133.022086 -414.048194)
		(width 0.14224)
		(layer "In6.Cu")
		(net "P5E_CPU1_P3_TX_BUF_C_DP<5>")
	)
	(segment
		(start 132.451856 -411.131258)
		(end 132.314696 -410.994098)
		(width 0.14224)
		(layer "In6.Cu")
		(net "P5E_CPU1_P3_TX_BUF_C_DP<5>")
	)
	(segment
		(start 132.451856 -411.557978)
		(end 132.451856 -411.131258)
		(width 0.14224)
		(layer "In6.Cu")
		(net "P5E_CPU1_P3_TX_BUF_C_DP<5>")
	)
	(segment
		(start 135.23214 -427.54296)
		(end 135.069834 -427.380654)
		(width 0.14224)
		(layer "In6.Cu")
		(net "P5E_CPU1_P3_TX_BUF_C_DP<5>")
	)
	(segment
		(start 132.427726 -413.40532)
		(end 132.314696 -413.032702)
		(width 0.14224)
		(layer "In6.Cu")
		(net "P5E_CPU1_P3_TX_BUF_C_DP<5>")
	)
	(segment
		(start 134.474966 -416.469068)
		(end 134.512812 -416.278822)
		(width 0.14224)
		(layer "In6.Cu")
		(net "P5E_CPU1_P3_TX_BUF_C_DP<5>")
	)
	(segment
		(start 132.314696 -413.032702)
		(end 132.314696 -411.695138)
		(width 0.14224)
		(layer "In6.Cu")
		(net "P5E_CPU1_P3_TX_BUF_C_DP<5>")
	)
	(segment
		(start 135.069834 -427.380654)
		(end 135.069834 -418.41293)
		(width 0.14224)
		(layer "In6.Cu")
		(net "P5E_CPU1_P3_TX_BUF_C_DP<5>")
	)
	(segment
		(start 133.886194 -415.341054)
		(end 133.648958 -414.985962)
		(width 0.14224)
		(layer "In6.Cu")
		(net "P5E_CPU1_P3_TX_BUF_C_DP<5>")
	)
	(segment
		(start 132.314696 -411.695138)
		(end 132.451856 -411.557978)
		(width 0.14224)
		(layer "In6.Cu")
		(net "P5E_CPU1_P3_TX_BUF_C_DP<5>")
	)
	(segment
		(start 132.83184 -414.010348)
		(end 132.427726 -413.40532)
		(width 0.14224)
		(layer "In6.Cu")
		(net "P5E_CPU1_P3_TX_BUF_C_DP<5>")
	)
	(segment
		(start 135.749792 -427.089824)
		(end 135.749792 -427.41596)
		(width 0.14224)
		(layer "In6.Cu")
		(net "P5E_CPU1_P3_TX_BUF_C_DP<5>")
	)
	(segment
		(start 129.567686 -408.784044)
		(end 129.271776 -409.079954)
		(width 0.12954)
		(layer "B.Cu")
		(net "P5E_CPU1_P3_TX_BUF_C_DP<4>")
	)
	(segment
		(start 129.271776 -409.079954)
		(end 129.271776 -409.759658)
		(width 0.12954)
		(layer "B.Cu")
		(net "P5E_CPU1_P3_TX_BUF_C_DP<4>")
	)
	(segment
		(start 129.271776 -409.759658)
		(end 129.542286 -410.030168)
		(width 0.12954)
		(layer "B.Cu")
		(net "P5E_CPU1_P3_TX_BUF_C_DP<4>")
	)
	(segment
		(start 131.875276 -415.933636)
		(end 131.880102 -416.127438)
		(width 0.14224)
		(layer "In6.Cu")
		(net "P5E_CPU1_P3_TX_BUF_C_DP<4>")
	)
	(segment
		(start 131.372102 -415.643822)
		(end 131.566158 -415.638996)
		(width 0.14224)
		(layer "In6.Cu")
		(net "P5E_CPU1_P3_TX_BUF_C_DP<4>")
	)
	(segment
		(start 132.944616 -417.140644)
		(end 133.069838 -417.433252)
		(width 0.14224)
		(layer "In6.Cu")
		(net "P5E_CPU1_P3_TX_BUF_C_DP<4>")
	)
	(segment
		(start 132.383022 -416.416744)
		(end 132.692394 -416.71113)
		(width 0.14224)
		(layer "In6.Cu")
		(net "P5E_CPU1_P3_TX_BUF_C_DP<4>")
	)
	(segment
		(start 129.251456 -410.320998)
		(end 129.251456 -411.125924)
		(width 0.14224)
		(layer "In6.Cu")
		(net "P5E_CPU1_P3_TX_BUF_C_DP<4>")
	)
	(segment
		(start 132.188966 -416.42157)
		(end 132.383022 -416.416744)
		(width 0.14224)
		(layer "In6.Cu")
		(net "P5E_CPU1_P3_TX_BUF_C_DP<4>")
	)
	(segment
		(start 133.069838 -417.433252)
		(end 133.069838 -426.315378)
		(width 0.14224)
		(layer "In6.Cu")
		(net "P5E_CPU1_P3_TX_BUF_C_DP<4>")
	)
	(segment
		(start 131.058412 -415.155888)
		(end 131.063238 -415.34969)
		(width 0.14224)
		(layer "In6.Cu")
		(net "P5E_CPU1_P3_TX_BUF_C_DP<4>")
	)
	(segment
		(start 133.069838 -426.315378)
		(end 133.303518 -426.549058)
		(width 0.14224)
		(layer "In6.Cu")
		(net "P5E_CPU1_P3_TX_BUF_C_DP<4>")
	)
	(segment
		(start 130.246374 -414.571942)
		(end 130.555238 -414.866074)
		(width 0.14224)
		(layer "In6.Cu")
		(net "P5E_CPU1_P3_TX_BUF_C_DP<4>")
	)
	(segment
		(start 129.251456 -411.125924)
		(end 129.388616 -411.263084)
		(width 0.14224)
		(layer "In6.Cu")
		(net "P5E_CPU1_P3_TX_BUF_C_DP<4>")
	)
	(segment
		(start 131.063238 -415.34969)
		(end 131.372102 -415.643822)
		(width 0.14224)
		(layer "In6.Cu")
		(net "P5E_CPU1_P3_TX_BUF_C_DP<4>")
	)
	(segment
		(start 129.572004 -413.92983)
		(end 129.738374 -414.088326)
		(width 0.14224)
		(layer "In6.Cu")
		(net "P5E_CPU1_P3_TX_BUF_C_DP<4>")
	)
	(segment
		(start 130.749294 -414.861248)
		(end 131.058412 -415.155888)
		(width 0.14224)
		(layer "In6.Cu")
		(net "P5E_CPU1_P3_TX_BUF_C_DP<4>")
	)
	(segment
		(start 129.251456 -413.36468)
		(end 129.354326 -413.612838)
		(width 0.14224)
		(layer "In6.Cu")
		(net "P5E_CPU1_P3_TX_BUF_C_DP<4>")
	)
	(segment
		(start 133.303518 -426.549058)
		(end 133.622288 -426.549058)
		(width 0.14224)
		(layer "In6.Cu")
		(net "P5E_CPU1_P3_TX_BUF_C_DP<4>")
	)
	(segment
		(start 133.749796 -426.42155)
		(end 133.749796 -426.089826)
		(width 0.14224)
		(layer "In6.Cu")
		(net "P5E_CPU1_P3_TX_BUF_C_DP<4>")
	)
	(segment
		(start 131.566158 -415.638996)
		(end 131.875276 -415.933636)
		(width 0.14224)
		(layer "In6.Cu")
		(net "P5E_CPU1_P3_TX_BUF_C_DP<4>")
	)
	(segment
		(start 129.542286 -410.030168)
		(end 129.251456 -410.320998)
		(width 0.14224)
		(layer "In6.Cu")
		(net "P5E_CPU1_P3_TX_BUF_C_DP<4>")
	)
	(segment
		(start 132.696966 -416.904932)
		(end 132.944616 -417.140644)
		(width 0.14224)
		(layer "In6.Cu")
		(net "P5E_CPU1_P3_TX_BUF_C_DP<4>")
	)
	(segment
		(start 129.93243 -414.0835)
		(end 130.241548 -414.37814)
		(width 0.14224)
		(layer "In6.Cu")
		(net "P5E_CPU1_P3_TX_BUF_C_DP<4>")
	)
	(segment
		(start 130.555238 -414.866074)
		(end 130.749294 -414.861248)
		(width 0.14224)
		(layer "In6.Cu")
		(net "P5E_CPU1_P3_TX_BUF_C_DP<4>")
	)
	(segment
		(start 131.880102 -416.127438)
		(end 132.188966 -416.42157)
		(width 0.14224)
		(layer "In6.Cu")
		(net "P5E_CPU1_P3_TX_BUF_C_DP<4>")
	)
	(segment
		(start 133.622288 -426.549058)
		(end 133.749796 -426.42155)
		(width 0.14224)
		(layer "In6.Cu")
		(net "P5E_CPU1_P3_TX_BUF_C_DP<4>")
	)
	(segment
		(start 129.388616 -411.689804)
		(end 129.251456 -411.826964)
		(width 0.14224)
		(layer "In6.Cu")
		(net "P5E_CPU1_P3_TX_BUF_C_DP<4>")
	)
	(segment
		(start 132.692394 -416.71113)
		(end 132.696966 -416.904932)
		(width 0.14224)
		(layer "In6.Cu")
		(net "P5E_CPU1_P3_TX_BUF_C_DP<4>")
	)
	(segment
		(start 129.251456 -411.826964)
		(end 129.251456 -413.36468)
		(width 0.14224)
		(layer "In6.Cu")
		(net "P5E_CPU1_P3_TX_BUF_C_DP<4>")
	)
	(segment
		(start 129.388616 -411.263084)
		(end 129.388616 -411.689804)
		(width 0.14224)
		(layer "In6.Cu")
		(net "P5E_CPU1_P3_TX_BUF_C_DP<4>")
	)
	(segment
		(start 130.241548 -414.37814)
		(end 130.246374 -414.571942)
		(width 0.14224)
		(layer "In6.Cu")
		(net "P5E_CPU1_P3_TX_BUF_C_DP<4>")
	)
	(segment
		(start 129.738374 -414.088326)
		(end 129.93243 -414.0835)
		(width 0.14224)
		(layer "In6.Cu")
		(net "P5E_CPU1_P3_TX_BUF_C_DP<4>")
	)
	(arc
		(start 129.354326 -413.612838)
		(mid 129.446615 -413.782698)
		(end 129.572004 -413.92983)
		(width 0.14224)
		(layer "In6.Cu")
		(net "P5E_CPU1_P3_TX_BUF_C_DP<4>")
	)
	(segment
		(start 126.504446 -408.784044)
		(end 126.208536 -409.079954)
		(width 0.12954)
		(layer "B.Cu")
		(net "P5E_CPU1_P3_TX_BUF_C_DP<3>")
	)
	(segment
		(start 126.208536 -409.759658)
		(end 126.479046 -410.030168)
		(width 0.12954)
		(layer "B.Cu")
		(net "P5E_CPU1_P3_TX_BUF_C_DP<3>")
	)
	(segment
		(start 126.208536 -409.079954)
		(end 126.208536 -409.759658)
		(width 0.12954)
		(layer "B.Cu")
		(net "P5E_CPU1_P3_TX_BUF_C_DP<3>")
	)
	(segment
		(start 129.17297 -415.499296)
		(end 129.363216 -415.46145)
		(width 0.14224)
		(layer "In6.Cu")
		(net "P5E_CPU1_P3_TX_BUF_C_DP<3>")
	)
	(segment
		(start 131.069842 -427.380654)
		(end 131.23799 -427.548802)
		(width 0.14224)
		(layer "In6.Cu")
		(net "P5E_CPU1_P3_TX_BUF_C_DP<3>")
	)
	(segment
		(start 126.347982 -413.611314)
		(end 127.297434 -414.245806)
		(width 0.14224)
		(layer "In6.Cu")
		(net "P5E_CPU1_P3_TX_BUF_C_DP<3>")
	)
	(segment
		(start 128.425448 -414.834578)
		(end 128.78054 -415.072068)
		(width 0.14224)
		(layer "In6.Cu")
		(net "P5E_CPU1_P3_TX_BUF_C_DP<3>")
	)
	(segment
		(start 129.718308 -415.69894)
		(end 129.756154 -415.889186)
		(width 0.14224)
		(layer "In6.Cu")
		(net "P5E_CPU1_P3_TX_BUF_C_DP<3>")
	)
	(segment
		(start 131.069842 -418.275008)
		(end 131.069842 -427.380654)
		(width 0.14224)
		(layer "In6.Cu")
		(net "P5E_CPU1_P3_TX_BUF_C_DP<3>")
	)
	(segment
		(start 130.863594 -417.253166)
		(end 130.869182 -417.266628)
		(width 0.14224)
		(layer "In6.Cu")
		(net "P5E_CPU1_P3_TX_BUF_C_DP<3>")
	)
	(segment
		(start 129.363216 -415.46145)
		(end 129.718308 -415.69894)
		(width 0.14224)
		(layer "In6.Cu")
		(net "P5E_CPU1_P3_TX_BUF_C_DP<3>")
	)
	(segment
		(start 126.188216 -410.320998)
		(end 126.188216 -413.323786)
		(width 0.14224)
		(layer "In6.Cu")
		(net "P5E_CPU1_P3_TX_BUF_C_DP<3>")
	)
	(segment
		(start 127.297434 -414.245806)
		(end 127.48768 -414.20796)
		(width 0.14224)
		(layer "In6.Cu")
		(net "P5E_CPU1_P3_TX_BUF_C_DP<3>")
	)
	(segment
		(start 126.479046 -410.030168)
		(end 126.188216 -410.320998)
		(width 0.14224)
		(layer "In6.Cu")
		(net "P5E_CPU1_P3_TX_BUF_C_DP<3>")
	)
	(segment
		(start 131.23799 -427.548802)
		(end 131.622546 -427.548802)
		(width 0.14224)
		(layer "In6.Cu")
		(net "P5E_CPU1_P3_TX_BUF_C_DP<3>")
	)
	(segment
		(start 131.7498 -427.421548)
		(end 131.7498 -427.089824)
		(width 0.14224)
		(layer "In6.Cu")
		(net "P5E_CPU1_P3_TX_BUF_C_DP<3>")
	)
	(segment
		(start 130.110738 -416.126168)
		(end 130.863594 -417.253166)
		(width 0.14224)
		(layer "In6.Cu")
		(net "P5E_CPU1_P3_TX_BUF_C_DP<3>")
	)
	(segment
		(start 127.48768 -414.20796)
		(end 127.842772 -414.445196)
		(width 0.14224)
		(layer "In6.Cu")
		(net "P5E_CPU1_P3_TX_BUF_C_DP<3>")
	)
	(segment
		(start 128.235202 -414.872424)
		(end 128.425448 -414.834578)
		(width 0.14224)
		(layer "In6.Cu")
		(net "P5E_CPU1_P3_TX_BUF_C_DP<3>")
	)
	(segment
		(start 128.818386 -415.262314)
		(end 129.17297 -415.499296)
		(width 0.14224)
		(layer "In6.Cu")
		(net "P5E_CPU1_P3_TX_BUF_C_DP<3>")
	)
	(segment
		(start 126.204726 -413.386524)
		(end 126.308358 -413.568388)
		(width 0.14224)
		(layer "In6.Cu")
		(net "P5E_CPU1_P3_TX_BUF_C_DP<3>")
	)
	(segment
		(start 131.622546 -427.548802)
		(end 131.7498 -427.421548)
		(width 0.14224)
		(layer "In6.Cu")
		(net "P5E_CPU1_P3_TX_BUF_C_DP<3>")
	)
	(segment
		(start 127.880618 -414.635442)
		(end 128.235202 -414.872424)
		(width 0.14224)
		(layer "In6.Cu")
		(net "P5E_CPU1_P3_TX_BUF_C_DP<3>")
	)
	(segment
		(start 129.756154 -415.889186)
		(end 130.110738 -416.126168)
		(width 0.14224)
		(layer "In6.Cu")
		(net "P5E_CPU1_P3_TX_BUF_C_DP<3>")
	)
	(segment
		(start 128.78054 -415.072068)
		(end 128.818386 -415.262314)
		(width 0.14224)
		(layer "In6.Cu")
		(net "P5E_CPU1_P3_TX_BUF_C_DP<3>")
	)
	(segment
		(start 127.842772 -414.445196)
		(end 127.880618 -414.635442)
		(width 0.14224)
		(layer "In6.Cu")
		(net "P5E_CPU1_P3_TX_BUF_C_DP<3>")
	)
	(arc
		(start 130.869182 -417.266628)
		(mid 131.019194 -417.760932)
		(end 131.069842 -418.275008)
		(width 0.14224)
		(layer "In6.Cu")
		(net "P5E_CPU1_P3_TX_BUF_C_DP<3>")
	)
	(arc
		(start 126.188216 -413.323786)
		(mid 126.192411 -413.356224)
		(end 126.204726 -413.386524)
		(width 0.14224)
		(layer "In6.Cu")
		(net "P5E_CPU1_P3_TX_BUF_C_DP<3>")
	)
	(arc
		(start 126.308358 -413.568388)
		(mid 126.325654 -413.592174)
		(end 126.347982 -413.611314)
		(width 0.14224)
		(layer "In6.Cu")
		(net "P5E_CPU1_P3_TX_BUF_C_DP<3>")
	)
	(segment
		(start 123.145296 -409.079954)
		(end 123.145296 -409.759658)
		(width 0.12954)
		(layer "B.Cu")
		(net "P5E_CPU1_P3_TX_BUF_C_DP<2>")
	)
	(segment
		(start 123.145296 -409.759658)
		(end 123.415806 -410.030168)
		(width 0.12954)
		(layer "B.Cu")
		(net "P5E_CPU1_P3_TX_BUF_C_DP<2>")
	)
	(segment
		(start 123.441206 -408.784044)
		(end 123.145296 -409.079954)
		(width 0.12954)
		(layer "B.Cu")
		(net "P5E_CPU1_P3_TX_BUF_C_DP<2>")
	)
	(segment
		(start 123.262136 -411.385766)
		(end 123.262136 -411.812486)
		(width 0.14224)
		(layer "In6.Cu")
		(net "P5E_CPU1_P3_TX_BUF_C_DP<2>")
	)
	(segment
		(start 129.749804 -426.42155)
		(end 129.749804 -426.089826)
		(width 0.14224)
		(layer "In6.Cu")
		(net "P5E_CPU1_P3_TX_BUF_C_DP<2>")
	)
	(segment
		(start 129.069846 -426.315378)
		(end 129.303526 -426.549058)
		(width 0.14224)
		(layer "In6.Cu")
		(net "P5E_CPU1_P3_TX_BUF_C_DP<2>")
	)
	(segment
		(start 123.43638 -413.996632)
		(end 124.151136 -414.474152)
		(width 0.14224)
		(layer "In6.Cu")
		(net "P5E_CPU1_P3_TX_BUF_C_DP<2>")
	)
	(segment
		(start 123.262136 -411.812486)
		(end 123.124976 -411.949646)
		(width 0.14224)
		(layer "In6.Cu")
		(net "P5E_CPU1_P3_TX_BUF_C_DP<2>")
	)
	(segment
		(start 125.950472 -415.070798)
		(end 126.344934 -415.23412)
		(width 0.14224)
		(layer "In6.Cu")
		(net "P5E_CPU1_P3_TX_BUF_C_DP<2>")
	)
	(segment
		(start 123.124976 -411.248606)
		(end 123.262136 -411.385766)
		(width 0.14224)
		(layer "In6.Cu")
		(net "P5E_CPU1_P3_TX_BUF_C_DP<2>")
	)
	(segment
		(start 123.25985 -413.697674)
		(end 123.337066 -413.883348)
		(width 0.14224)
		(layer "In6.Cu")
		(net "P5E_CPU1_P3_TX_BUF_C_DP<2>")
	)
	(segment
		(start 126.419102 -415.413698)
		(end 126.81331 -415.576766)
		(width 0.14224)
		(layer "In6.Cu")
		(net "P5E_CPU1_P3_TX_BUF_C_DP<2>")
	)
	(segment
		(start 124.90831 -414.639252)
		(end 125.302772 -414.802574)
		(width 0.14224)
		(layer "In6.Cu")
		(net "P5E_CPU1_P3_TX_BUF_C_DP<2>")
	)
	(segment
		(start 127.386842 -415.66592)
		(end 127.46101 -415.845498)
		(width 0.14224)
		(layer "In6.Cu")
		(net "P5E_CPU1_P3_TX_BUF_C_DP<2>")
	)
	(segment
		(start 125.771148 -415.14522)
		(end 125.950472 -415.070798)
		(width 0.14224)
		(layer "In6.Cu")
		(net "P5E_CPU1_P3_TX_BUF_C_DP<2>")
	)
	(segment
		(start 123.364498 -413.92475)
		(end 123.43638 -413.996632)
		(width 0.14224)
		(layer "In6.Cu")
		(net "P5E_CPU1_P3_TX_BUF_C_DP<2>")
	)
	(segment
		(start 123.124976 -411.949646)
		(end 123.124976 -413.020256)
		(width 0.14224)
		(layer "In6.Cu")
		(net "P5E_CPU1_P3_TX_BUF_C_DP<2>")
	)
	(segment
		(start 126.344934 -415.23412)
		(end 126.419102 -415.413698)
		(width 0.14224)
		(layer "In6.Cu")
		(net "P5E_CPU1_P3_TX_BUF_C_DP<2>")
	)
	(segment
		(start 126.81331 -415.576766)
		(end 126.99238 -415.502598)
		(width 0.14224)
		(layer "In6.Cu")
		(net "P5E_CPU1_P3_TX_BUF_C_DP<2>")
	)
	(segment
		(start 125.37694 -414.982152)
		(end 125.771148 -415.14522)
		(width 0.14224)
		(layer "In6.Cu")
		(net "P5E_CPU1_P3_TX_BUF_C_DP<2>")
	)
	(segment
		(start 128.223772 -416.437064)
		(end 128.417828 -416.437064)
		(width 0.14224)
		(layer "In6.Cu")
		(net "P5E_CPU1_P3_TX_BUF_C_DP<2>")
	)
	(segment
		(start 127.753364 -415.966656)
		(end 128.223772 -416.437064)
		(width 0.14224)
		(layer "In6.Cu")
		(net "P5E_CPU1_P3_TX_BUF_C_DP<2>")
	)
	(segment
		(start 123.124976 -410.320998)
		(end 123.124976 -411.248606)
		(width 0.14224)
		(layer "In6.Cu")
		(net "P5E_CPU1_P3_TX_BUF_C_DP<2>")
	)
	(segment
		(start 123.415806 -410.030168)
		(end 123.124976 -410.320998)
		(width 0.14224)
		(layer "In6.Cu")
		(net "P5E_CPU1_P3_TX_BUF_C_DP<2>")
	)
	(segment
		(start 129.303526 -426.549058)
		(end 129.622296 -426.549058)
		(width 0.14224)
		(layer "In6.Cu")
		(net "P5E_CPU1_P3_TX_BUF_C_DP<2>")
	)
	(segment
		(start 127.46101 -415.845498)
		(end 127.753364 -415.966656)
		(width 0.14224)
		(layer "In6.Cu")
		(net "P5E_CPU1_P3_TX_BUF_C_DP<2>")
	)
	(segment
		(start 128.719834 -416.73907)
		(end 128.719834 -416.933126)
		(width 0.14224)
		(layer "In6.Cu")
		(net "P5E_CPU1_P3_TX_BUF_C_DP<2>")
	)
	(segment
		(start 125.302772 -414.802574)
		(end 125.37694 -414.982152)
		(width 0.14224)
		(layer "In6.Cu")
		(net "P5E_CPU1_P3_TX_BUF_C_DP<2>")
	)
	(segment
		(start 126.99238 -415.502598)
		(end 127.386842 -415.66592)
		(width 0.14224)
		(layer "In6.Cu")
		(net "P5E_CPU1_P3_TX_BUF_C_DP<2>")
	)
	(segment
		(start 129.069846 -417.452556)
		(end 129.069846 -426.315378)
		(width 0.14224)
		(layer "In6.Cu")
		(net "P5E_CPU1_P3_TX_BUF_C_DP<2>")
	)
	(segment
		(start 124.728986 -414.71342)
		(end 124.90831 -414.639252)
		(width 0.14224)
		(layer "In6.Cu")
		(net "P5E_CPU1_P3_TX_BUF_C_DP<2>")
	)
	(segment
		(start 129.622296 -426.549058)
		(end 129.749804 -426.42155)
		(width 0.14224)
		(layer "In6.Cu")
		(net "P5E_CPU1_P3_TX_BUF_C_DP<2>")
	)
	(segment
		(start 128.417828 -416.437064)
		(end 128.719834 -416.73907)
		(width 0.14224)
		(layer "In6.Cu")
		(net "P5E_CPU1_P3_TX_BUF_C_DP<2>")
	)
	(segment
		(start 128.719834 -416.933126)
		(end 128.949958 -417.16325)
		(width 0.14224)
		(layer "In6.Cu")
		(net "P5E_CPU1_P3_TX_BUF_C_DP<2>")
	)
	(segment
		(start 124.151136 -414.474152)
		(end 124.728986 -414.71342)
		(width 0.14224)
		(layer "In6.Cu")
		(net "P5E_CPU1_P3_TX_BUF_C_DP<2>")
	)
	(arc
		(start 123.337066 -413.883348)
		(mid 123.348723 -413.905416)
		(end 123.364498 -413.92475)
		(width 0.14224)
		(layer "In6.Cu")
		(net "P5E_CPU1_P3_TX_BUF_C_DP<2>")
	)
	(arc
		(start 123.124976 -413.020256)
		(mid 123.159007 -413.365614)
		(end 123.25985 -413.697674)
		(width 0.14224)
		(layer "In6.Cu")
		(net "P5E_CPU1_P3_TX_BUF_C_DP<2>")
	)
	(arc
		(start 128.949958 -417.16325)
		(mid 129.038702 -417.29597)
		(end 129.069846 -417.452556)
		(width 0.14224)
		(layer "In6.Cu")
		(net "P5E_CPU1_P3_TX_BUF_C_DP<2>")
	)
	(segment
		(start 120.377966 -408.784044)
		(end 120.082056 -409.079954)
		(width 0.12954)
		(layer "B.Cu")
		(net "P5E_CPU1_P3_TX_BUF_C_DP<1>")
	)
	(segment
		(start 120.082056 -409.759658)
		(end 120.352566 -410.030168)
		(width 0.12954)
		(layer "B.Cu")
		(net "P5E_CPU1_P3_TX_BUF_C_DP<1>")
	)
	(segment
		(start 120.082056 -409.079954)
		(end 120.082056 -409.759658)
		(width 0.12954)
		(layer "B.Cu")
		(net "P5E_CPU1_P3_TX_BUF_C_DP<1>")
	)
	(segment
		(start 120.352566 -410.030168)
		(end 120.061736 -410.320998)
		(width 0.14224)
		(layer "In6.Cu")
		(net "P5E_CPU1_P3_TX_BUF_C_DP<1>")
	)
	(segment
		(start 127.06985 -427.380654)
		(end 127.237998 -427.548802)
		(width 0.14224)
		(layer "In6.Cu")
		(net "P5E_CPU1_P3_TX_BUF_C_DP<1>")
	)
	(segment
		(start 122.543316 -416.52571)
		(end 122.780806 -416.880802)
		(width 0.14224)
		(layer "In6.Cu")
		(net "P5E_CPU1_P3_TX_BUF_C_DP<1>")
	)
	(segment
		(start 122.35307 -416.487864)
		(end 122.543316 -416.52571)
		(width 0.14224)
		(layer "In6.Cu")
		(net "P5E_CPU1_P3_TX_BUF_C_DP<1>")
	)
	(segment
		(start 122.74296 -417.071048)
		(end 124.45492 -419.633146)
		(width 0.14224)
		(layer "In6.Cu")
		(net "P5E_CPU1_P3_TX_BUF_C_DP<1>")
	)
	(segment
		(start 127.06985 -424.525186)
		(end 127.06985 -427.380654)
		(width 0.14224)
		(layer "In6.Cu")
		(net "P5E_CPU1_P3_TX_BUF_C_DP<1>")
	)
	(segment
		(start 121.276364 -414.629346)
		(end 121.238518 -414.819592)
		(width 0.14224)
		(layer "In6.Cu")
		(net "P5E_CPU1_P3_TX_BUF_C_DP<1>")
	)
	(segment
		(start 121.693686 -415.253932)
		(end 121.930922 -415.609024)
		(width 0.14224)
		(layer "In6.Cu")
		(net "P5E_CPU1_P3_TX_BUF_C_DP<1>")
	)
	(segment
		(start 120.061736 -410.320998)
		(end 120.061736 -412.888938)
		(width 0.14224)
		(layer "In6.Cu")
		(net "P5E_CPU1_P3_TX_BUF_C_DP<1>")
	)
	(segment
		(start 124.45492 -419.633146)
		(end 127.06985 -424.525186)
		(width 0.14224)
		(layer "In6.Cu")
		(net "P5E_CPU1_P3_TX_BUF_C_DP<1>")
	)
	(segment
		(start 122.780806 -416.880802)
		(end 122.74296 -417.071048)
		(width 0.14224)
		(layer "In6.Cu")
		(net "P5E_CPU1_P3_TX_BUF_C_DP<1>")
	)
	(segment
		(start 120.848628 -414.236408)
		(end 121.038874 -414.274254)
		(width 0.14224)
		(layer "In6.Cu")
		(net "P5E_CPU1_P3_TX_BUF_C_DP<1>")
	)
	(segment
		(start 127.622554 -427.548802)
		(end 127.749808 -427.421548)
		(width 0.14224)
		(layer "In6.Cu")
		(net "P5E_CPU1_P3_TX_BUF_C_DP<1>")
	)
	(segment
		(start 127.749808 -427.421548)
		(end 127.749808 -427.089824)
		(width 0.14224)
		(layer "In6.Cu")
		(net "P5E_CPU1_P3_TX_BUF_C_DP<1>")
	)
	(segment
		(start 121.238518 -414.819592)
		(end 121.50344 -415.216086)
		(width 0.14224)
		(layer "In6.Cu")
		(net "P5E_CPU1_P3_TX_BUF_C_DP<1>")
	)
	(segment
		(start 121.038874 -414.274254)
		(end 121.276364 -414.629346)
		(width 0.14224)
		(layer "In6.Cu")
		(net "P5E_CPU1_P3_TX_BUF_C_DP<1>")
	)
	(segment
		(start 127.237998 -427.548802)
		(end 127.622554 -427.548802)
		(width 0.14224)
		(layer "In6.Cu")
		(net "P5E_CPU1_P3_TX_BUF_C_DP<1>")
	)
	(segment
		(start 121.893076 -415.79927)
		(end 122.35307 -416.487864)
		(width 0.14224)
		(layer "In6.Cu")
		(net "P5E_CPU1_P3_TX_BUF_C_DP<1>")
	)
	(segment
		(start 121.50344 -415.216086)
		(end 121.693686 -415.253932)
		(width 0.14224)
		(layer "In6.Cu")
		(net "P5E_CPU1_P3_TX_BUF_C_DP<1>")
	)
	(segment
		(start 120.15597 -413.199834)
		(end 120.848628 -414.236408)
		(width 0.14224)
		(layer "In6.Cu")
		(net "P5E_CPU1_P3_TX_BUF_C_DP<1>")
	)
	(segment
		(start 121.930922 -415.609024)
		(end 121.893076 -415.79927)
		(width 0.14224)
		(layer "In6.Cu")
		(net "P5E_CPU1_P3_TX_BUF_C_DP<1>")
	)
	(arc
		(start 120.061736 -412.888938)
		(mid 120.085827 -413.05136)
		(end 120.15597 -413.199834)
		(width 0.14224)
		(layer "In6.Cu")
		(net "P5E_CPU1_P3_TX_BUF_C_DP<1>")
	)
	(segment
		(start 163.263326 -408.784044)
		(end 162.967416 -409.079954)
		(width 0.12954)
		(layer "B.Cu")
		(net "P5E_CPU1_P3_TX_BUF_C_DP<15>")
	)
	(segment
		(start 162.967416 -409.079954)
		(end 162.967416 -409.759658)
		(width 0.12954)
		(layer "B.Cu")
		(net "P5E_CPU1_P3_TX_BUF_C_DP<15>")
	)
	(segment
		(start 162.967416 -409.759658)
		(end 163.237926 -410.030168)
		(width 0.12954)
		(layer "B.Cu")
		(net "P5E_CPU1_P3_TX_BUF_C_DP<15>")
	)
	(segment
		(start 161.334704 -416.201606)
		(end 161.097468 -416.556698)
		(width 0.14224)
		(layer "In6.Cu")
		(net "P5E_CPU1_P3_TX_BUF_C_DP<15>")
	)
	(segment
		(start 162.947096 -410.320998)
		(end 162.947096 -411.069536)
		(width 0.14224)
		(layer "In6.Cu")
		(net "P5E_CPU1_P3_TX_BUF_C_DP<15>")
	)
	(segment
		(start 160.177988 -417.685982)
		(end 156.304488 -423.483024)
		(width 0.14224)
		(layer "In6.Cu")
		(net "P5E_CPU1_P3_TX_BUF_C_DP<15>")
	)
	(segment
		(start 162.750754 -413.835596)
		(end 162.513772 -414.19018)
		(width 0.14224)
		(layer "In6.Cu")
		(net "P5E_CPU1_P3_TX_BUF_C_DP<15>")
	)
	(segment
		(start 163.084256 -411.206696)
		(end 163.084256 -411.633416)
		(width 0.14224)
		(layer "In6.Cu")
		(net "P5E_CPU1_P3_TX_BUF_C_DP<15>")
	)
	(segment
		(start 162.513772 -414.19018)
		(end 162.551618 -414.380426)
		(width 0.14224)
		(layer "In6.Cu")
		(net "P5E_CPU1_P3_TX_BUF_C_DP<15>")
	)
	(segment
		(start 163.084256 -411.633416)
		(end 162.947096 -411.770576)
		(width 0.14224)
		(layer "In6.Cu")
		(net "P5E_CPU1_P3_TX_BUF_C_DP<15>")
	)
	(segment
		(start 162.551618 -414.380426)
		(end 162.314382 -414.735518)
		(width 0.14224)
		(layer "In6.Cu")
		(net "P5E_CPU1_P3_TX_BUF_C_DP<15>")
	)
	(segment
		(start 156.070046 -427.380654)
		(end 156.238194 -427.548802)
		(width 0.14224)
		(layer "In6.Cu")
		(net "P5E_CPU1_P3_TX_BUF_C_DP<15>")
	)
	(segment
		(start 162.947096 -413.18815)
		(end 162.750754 -413.835596)
		(width 0.14224)
		(layer "In6.Cu")
		(net "P5E_CPU1_P3_TX_BUF_C_DP<15>")
	)
	(segment
		(start 161.097468 -416.556698)
		(end 160.907222 -416.594544)
		(width 0.14224)
		(layer "In6.Cu")
		(net "P5E_CPU1_P3_TX_BUF_C_DP<15>")
	)
	(segment
		(start 160.907222 -416.594544)
		(end 160.567624 -417.102798)
		(width 0.14224)
		(layer "In6.Cu")
		(net "P5E_CPU1_P3_TX_BUF_C_DP<15>")
	)
	(segment
		(start 163.237926 -410.030168)
		(end 162.947096 -410.320998)
		(width 0.14224)
		(layer "In6.Cu")
		(net "P5E_CPU1_P3_TX_BUF_C_DP<15>")
	)
	(segment
		(start 162.314382 -414.735518)
		(end 162.124136 -414.773364)
		(width 0.14224)
		(layer "In6.Cu")
		(net "P5E_CPU1_P3_TX_BUF_C_DP<15>")
	)
	(segment
		(start 156.238194 -427.548802)
		(end 156.62275 -427.548802)
		(width 0.14224)
		(layer "In6.Cu")
		(net "P5E_CPU1_P3_TX_BUF_C_DP<15>")
	)
	(segment
		(start 156.750004 -427.421548)
		(end 156.750004 -427.089824)
		(width 0.14224)
		(layer "In6.Cu")
		(net "P5E_CPU1_P3_TX_BUF_C_DP<15>")
	)
	(segment
		(start 161.296858 -416.01136)
		(end 161.334704 -416.201606)
		(width 0.14224)
		(layer "In6.Cu")
		(net "P5E_CPU1_P3_TX_BUF_C_DP<15>")
	)
	(segment
		(start 160.567624 -417.102798)
		(end 160.60547 -417.293044)
		(width 0.14224)
		(layer "In6.Cu")
		(net "P5E_CPU1_P3_TX_BUF_C_DP<15>")
	)
	(segment
		(start 162.124136 -414.773364)
		(end 161.296858 -416.01136)
		(width 0.14224)
		(layer "In6.Cu")
		(net "P5E_CPU1_P3_TX_BUF_C_DP<15>")
	)
	(segment
		(start 156.62275 -427.548802)
		(end 156.750004 -427.421548)
		(width 0.14224)
		(layer "In6.Cu")
		(net "P5E_CPU1_P3_TX_BUF_C_DP<15>")
	)
	(segment
		(start 160.368234 -417.648136)
		(end 160.177988 -417.685982)
		(width 0.14224)
		(layer "In6.Cu")
		(net "P5E_CPU1_P3_TX_BUF_C_DP<15>")
	)
	(segment
		(start 162.947096 -411.770576)
		(end 162.947096 -413.18815)
		(width 0.14224)
		(layer "In6.Cu")
		(net "P5E_CPU1_P3_TX_BUF_C_DP<15>")
	)
	(segment
		(start 162.947096 -411.069536)
		(end 163.084256 -411.206696)
		(width 0.14224)
		(layer "In6.Cu")
		(net "P5E_CPU1_P3_TX_BUF_C_DP<15>")
	)
	(segment
		(start 160.60547 -417.293044)
		(end 160.368234 -417.648136)
		(width 0.14224)
		(layer "In6.Cu")
		(net "P5E_CPU1_P3_TX_BUF_C_DP<15>")
	)
	(segment
		(start 156.070046 -424.2562)
		(end 156.070046 -427.380654)
		(width 0.14224)
		(layer "In6.Cu")
		(net "P5E_CPU1_P3_TX_BUF_C_DP<15>")
	)
	(arc
		(start 156.304488 -423.483024)
		(mid 156.129951 -423.852228)
		(end 156.070046 -424.2562)
		(width 0.14224)
		(layer "In6.Cu")
		(net "P5E_CPU1_P3_TX_BUF_C_DP<15>")
	)
	(segment
		(start 159.904176 -409.759658)
		(end 160.174686 -410.030168)
		(width 0.12954)
		(layer "B.Cu")
		(net "P5E_CPU1_P3_TX_BUF_C_DP<14>")
	)
	(segment
		(start 160.200086 -408.784044)
		(end 159.904176 -409.079954)
		(width 0.12954)
		(layer "B.Cu")
		(net "P5E_CPU1_P3_TX_BUF_C_DP<14>")
	)
	(segment
		(start 159.904176 -409.079954)
		(end 159.904176 -409.759658)
		(width 0.12954)
		(layer "B.Cu")
		(net "P5E_CPU1_P3_TX_BUF_C_DP<14>")
	)
	(segment
		(start 157.758384 -417.755578)
		(end 157.557216 -418.13226)
		(width 0.14224)
		(layer "In6.Cu")
		(net "P5E_CPU1_P3_TX_BUF_C_DP<14>")
	)
	(segment
		(start 160.174686 -410.030168)
		(end 159.883856 -410.320998)
		(width 0.14224)
		(layer "In6.Cu")
		(net "P5E_CPU1_P3_TX_BUF_C_DP<14>")
	)
	(segment
		(start 157.903164 -417.19373)
		(end 157.70225 -417.569904)
		(width 0.14224)
		(layer "In6.Cu")
		(net "P5E_CPU1_P3_TX_BUF_C_DP<14>")
	)
	(segment
		(start 159.537908 -414.426654)
		(end 159.352234 -414.482788)
		(width 0.14224)
		(layer "In6.Cu")
		(net "P5E_CPU1_P3_TX_BUF_C_DP<14>")
	)
	(segment
		(start 154.30373 -426.549058)
		(end 154.6225 -426.549058)
		(width 0.14224)
		(layer "In6.Cu")
		(net "P5E_CPU1_P3_TX_BUF_C_DP<14>")
	)
	(segment
		(start 157.371542 -418.188394)
		(end 154.225244 -424.075352)
		(width 0.14224)
		(layer "In6.Cu")
		(net "P5E_CPU1_P3_TX_BUF_C_DP<14>")
	)
	(segment
		(start 158.765494 -415.580576)
		(end 158.821882 -415.76625)
		(width 0.14224)
		(layer "In6.Cu")
		(net "P5E_CPU1_P3_TX_BUF_C_DP<14>")
	)
	(segment
		(start 158.088838 -417.137596)
		(end 157.903164 -417.19373)
		(width 0.14224)
		(layer "In6.Cu")
		(net "P5E_CPU1_P3_TX_BUF_C_DP<14>")
	)
	(segment
		(start 159.352234 -414.482788)
		(end 158.765494 -415.580576)
		(width 0.14224)
		(layer "In6.Cu")
		(net "P5E_CPU1_P3_TX_BUF_C_DP<14>")
	)
	(segment
		(start 158.821882 -415.76625)
		(end 158.620714 -416.142678)
		(width 0.14224)
		(layer "In6.Cu")
		(net "P5E_CPU1_P3_TX_BUF_C_DP<14>")
	)
	(segment
		(start 158.290006 -416.760914)
		(end 158.088838 -417.137596)
		(width 0.14224)
		(layer "In6.Cu")
		(net "P5E_CPU1_P3_TX_BUF_C_DP<14>")
	)
	(segment
		(start 159.883856 -413.488124)
		(end 159.682942 -413.864298)
		(width 0.14224)
		(layer "In6.Cu")
		(net "P5E_CPU1_P3_TX_BUF_C_DP<14>")
	)
	(segment
		(start 157.70225 -417.569904)
		(end 157.758384 -417.755578)
		(width 0.14224)
		(layer "In6.Cu")
		(net "P5E_CPU1_P3_TX_BUF_C_DP<14>")
	)
	(segment
		(start 154.07005 -424.694604)
		(end 154.07005 -426.315378)
		(width 0.14224)
		(layer "In6.Cu")
		(net "P5E_CPU1_P3_TX_BUF_C_DP<14>")
	)
	(segment
		(start 157.557216 -418.13226)
		(end 157.371542 -418.188394)
		(width 0.14224)
		(layer "In6.Cu")
		(net "P5E_CPU1_P3_TX_BUF_C_DP<14>")
	)
	(segment
		(start 154.6225 -426.549058)
		(end 154.750008 -426.42155)
		(width 0.14224)
		(layer "In6.Cu")
		(net "P5E_CPU1_P3_TX_BUF_C_DP<14>")
	)
	(segment
		(start 160.021016 -411.664404)
		(end 159.883856 -411.801564)
		(width 0.14224)
		(layer "In6.Cu")
		(net "P5E_CPU1_P3_TX_BUF_C_DP<14>")
	)
	(segment
		(start 159.883856 -411.100524)
		(end 160.021016 -411.237684)
		(width 0.14224)
		(layer "In6.Cu")
		(net "P5E_CPU1_P3_TX_BUF_C_DP<14>")
	)
	(segment
		(start 159.883856 -411.801564)
		(end 159.883856 -413.488124)
		(width 0.14224)
		(layer "In6.Cu")
		(net "P5E_CPU1_P3_TX_BUF_C_DP<14>")
	)
	(segment
		(start 160.021016 -411.237684)
		(end 160.021016 -411.664404)
		(width 0.14224)
		(layer "In6.Cu")
		(net "P5E_CPU1_P3_TX_BUF_C_DP<14>")
	)
	(segment
		(start 158.434786 -416.199066)
		(end 158.233872 -416.57524)
		(width 0.14224)
		(layer "In6.Cu")
		(net "P5E_CPU1_P3_TX_BUF_C_DP<14>")
	)
	(segment
		(start 158.620714 -416.142678)
		(end 158.434786 -416.199066)
		(width 0.14224)
		(layer "In6.Cu")
		(net "P5E_CPU1_P3_TX_BUF_C_DP<14>")
	)
	(segment
		(start 154.07005 -426.315378)
		(end 154.30373 -426.549058)
		(width 0.14224)
		(layer "In6.Cu")
		(net "P5E_CPU1_P3_TX_BUF_C_DP<14>")
	)
	(segment
		(start 154.750008 -426.42155)
		(end 154.750008 -426.089826)
		(width 0.14224)
		(layer "In6.Cu")
		(net "P5E_CPU1_P3_TX_BUF_C_DP<14>")
	)
	(segment
		(start 158.233872 -416.57524)
		(end 158.290006 -416.760914)
		(width 0.14224)
		(layer "In6.Cu")
		(net "P5E_CPU1_P3_TX_BUF_C_DP<14>")
	)
	(segment
		(start 159.739076 -414.049972)
		(end 159.537908 -414.426654)
		(width 0.14224)
		(layer "In6.Cu")
		(net "P5E_CPU1_P3_TX_BUF_C_DP<14>")
	)
	(segment
		(start 159.883856 -410.320998)
		(end 159.883856 -411.100524)
		(width 0.14224)
		(layer "In6.Cu")
		(net "P5E_CPU1_P3_TX_BUF_C_DP<14>")
	)
	(segment
		(start 159.682942 -413.864298)
		(end 159.739076 -414.049972)
		(width 0.14224)
		(layer "In6.Cu")
		(net "P5E_CPU1_P3_TX_BUF_C_DP<14>")
	)
	(arc
		(start 154.225244 -424.075352)
		(mid 154.109436 -424.375405)
		(end 154.07005 -424.694604)
		(width 0.14224)
		(layer "In6.Cu")
		(net "P5E_CPU1_P3_TX_BUF_C_DP<14>")
	)
	(segment
		(start 156.840936 -409.079954)
		(end 156.840936 -409.759658)
		(width 0.12954)
		(layer "B.Cu")
		(net "P5E_CPU1_P3_TX_BUF_C_DP<13>")
	)
	(segment
		(start 156.840936 -409.759658)
		(end 157.111446 -410.030168)
		(width 0.12954)
		(layer "B.Cu")
		(net "P5E_CPU1_P3_TX_BUF_C_DP<13>")
	)
	(segment
		(start 157.136846 -408.784044)
		(end 156.840936 -409.079954)
		(width 0.12954)
		(layer "B.Cu")
		(net "P5E_CPU1_P3_TX_BUF_C_DP<13>")
	)
	(segment
		(start 155.549092 -416.248342)
		(end 155.369514 -416.32251)
		(width 0.14224)
		(layer "In6.Cu")
		(net "P5E_CPU1_P3_TX_BUF_C_DP<13>")
	)
	(segment
		(start 155.280614 -416.895788)
		(end 155.117292 -417.290504)
		(width 0.14224)
		(layer "In6.Cu")
		(net "P5E_CPU1_P3_TX_BUF_C_DP<13>")
	)
	(segment
		(start 156.820616 -411.178756)
		(end 156.957776 -411.315916)
		(width 0.14224)
		(layer "In6.Cu")
		(net "P5E_CPU1_P3_TX_BUF_C_DP<13>")
	)
	(segment
		(start 156.789374 -413.191706)
		(end 156.358844 -414.231074)
		(width 0.14224)
		(layer "In6.Cu")
		(net "P5E_CPU1_P3_TX_BUF_C_DP<13>")
	)
	(segment
		(start 155.206446 -416.716718)
		(end 155.280614 -416.895788)
		(width 0.14224)
		(layer "In6.Cu")
		(net "P5E_CPU1_P3_TX_BUF_C_DP<13>")
	)
	(segment
		(start 152.750012 -427.421548)
		(end 152.750012 -427.089824)
		(width 0.14224)
		(layer "In6.Cu")
		(net "P5E_CPU1_P3_TX_BUF_C_DP<13>")
	)
	(segment
		(start 155.117292 -417.290504)
		(end 154.937714 -417.364672)
		(width 0.14224)
		(layer "In6.Cu")
		(net "P5E_CPU1_P3_TX_BUF_C_DP<13>")
	)
	(segment
		(start 155.369514 -416.32251)
		(end 155.206446 -416.716718)
		(width 0.14224)
		(layer "In6.Cu")
		(net "P5E_CPU1_P3_TX_BUF_C_DP<13>")
	)
	(segment
		(start 155.81122 -415.255964)
		(end 155.637992 -415.674556)
		(width 0.14224)
		(layer "In6.Cu")
		(net "P5E_CPU1_P3_TX_BUF_C_DP<13>")
	)
	(segment
		(start 156.820616 -411.879796)
		(end 156.820616 -413.034988)
		(width 0.14224)
		(layer "In6.Cu")
		(net "P5E_CPU1_P3_TX_BUF_C_DP<13>")
	)
	(segment
		(start 156.820616 -410.320998)
		(end 156.820616 -411.178756)
		(width 0.14224)
		(layer "In6.Cu")
		(net "P5E_CPU1_P3_TX_BUF_C_DP<13>")
	)
	(segment
		(start 156.957776 -411.315916)
		(end 156.957776 -411.742636)
		(width 0.14224)
		(layer "In6.Cu")
		(net "P5E_CPU1_P3_TX_BUF_C_DP<13>")
	)
	(segment
		(start 155.637992 -415.674556)
		(end 155.71216 -415.85388)
		(width 0.14224)
		(layer "In6.Cu")
		(net "P5E_CPU1_P3_TX_BUF_C_DP<13>")
	)
	(segment
		(start 156.358844 -414.231074)
		(end 155.81122 -415.255964)
		(width 0.14224)
		(layer "In6.Cu")
		(net "P5E_CPU1_P3_TX_BUF_C_DP<13>")
	)
	(segment
		(start 154.937714 -417.364672)
		(end 152.21712 -423.933112)
		(width 0.14224)
		(layer "In6.Cu")
		(net "P5E_CPU1_P3_TX_BUF_C_DP<13>")
	)
	(segment
		(start 152.238202 -427.548802)
		(end 152.622758 -427.548802)
		(width 0.14224)
		(layer "In6.Cu")
		(net "P5E_CPU1_P3_TX_BUF_C_DP<13>")
	)
	(segment
		(start 152.622758 -427.548802)
		(end 152.750012 -427.421548)
		(width 0.14224)
		(layer "In6.Cu")
		(net "P5E_CPU1_P3_TX_BUF_C_DP<13>")
	)
	(segment
		(start 152.070054 -427.380654)
		(end 152.238202 -427.548802)
		(width 0.14224)
		(layer "In6.Cu")
		(net "P5E_CPU1_P3_TX_BUF_C_DP<13>")
	)
	(segment
		(start 152.070054 -424.671998)
		(end 152.070054 -427.380654)
		(width 0.14224)
		(layer "In6.Cu")
		(net "P5E_CPU1_P3_TX_BUF_C_DP<13>")
	)
	(segment
		(start 155.71216 -415.85388)
		(end 155.549092 -416.248342)
		(width 0.14224)
		(layer "In6.Cu")
		(net "P5E_CPU1_P3_TX_BUF_C_DP<13>")
	)
	(segment
		(start 157.111446 -410.030168)
		(end 156.820616 -410.320998)
		(width 0.14224)
		(layer "In6.Cu")
		(net "P5E_CPU1_P3_TX_BUF_C_DP<13>")
	)
	(segment
		(start 156.957776 -411.742636)
		(end 156.820616 -411.879796)
		(width 0.14224)
		(layer "In6.Cu")
		(net "P5E_CPU1_P3_TX_BUF_C_DP<13>")
	)
	(arc
		(start 152.21712 -423.933112)
		(mid 152.107199 -424.295313)
		(end 152.070054 -424.671998)
		(width 0.14224)
		(layer "In6.Cu")
		(net "P5E_CPU1_P3_TX_BUF_C_DP<13>")
	)
	(arc
		(start 156.820616 -413.034988)
		(mid 156.812695 -413.11488)
		(end 156.789374 -413.191706)
		(width 0.14224)
		(layer "In6.Cu")
		(net "P5E_CPU1_P3_TX_BUF_C_DP<13>")
	)
	(segment
		(start 153.777696 -409.759658)
		(end 154.048206 -410.030168)
		(width 0.12954)
		(layer "B.Cu")
		(net "P5E_CPU1_P3_TX_BUF_C_DP<12>")
	)
	(segment
		(start 153.777696 -409.079954)
		(end 153.777696 -409.759658)
		(width 0.12954)
		(layer "B.Cu")
		(net "P5E_CPU1_P3_TX_BUF_C_DP<12>")
	)
	(segment
		(start 154.073606 -408.784044)
		(end 153.777696 -409.079954)
		(width 0.12954)
		(layer "B.Cu")
		(net "P5E_CPU1_P3_TX_BUF_C_DP<12>")
	)
	(segment
		(start 152.323292 -417.852352)
		(end 150.732236 -423.09796)
		(width 0.14224)
		(layer "In6.Cu")
		(net "P5E_CPU1_P3_TX_BUF_C_DP<12>")
	)
	(segment
		(start 153.894536 -411.3784)
		(end 153.894536 -411.80512)
		(width 0.14224)
		(layer "In6.Cu")
		(net "P5E_CPU1_P3_TX_BUF_C_DP<12>")
	)
	(segment
		(start 153.757376 -411.94228)
		(end 153.757376 -413.02813)
		(width 0.14224)
		(layer "In6.Cu")
		(net "P5E_CPU1_P3_TX_BUF_C_DP<12>")
	)
	(segment
		(start 152.854406 -416.102038)
		(end 152.945846 -416.273234)
		(width 0.14224)
		(layer "In6.Cu")
		(net "P5E_CPU1_P3_TX_BUF_C_DP<12>")
	)
	(segment
		(start 153.217626 -415.37763)
		(end 153.04643 -415.46907)
		(width 0.14224)
		(layer "In6.Cu")
		(net "P5E_CPU1_P3_TX_BUF_C_DP<12>")
	)
	(segment
		(start 152.945846 -416.273234)
		(end 152.822148 -416.681666)
		(width 0.14224)
		(layer "In6.Cu")
		(net "P5E_CPU1_P3_TX_BUF_C_DP<12>")
	)
	(segment
		(start 152.650698 -416.773106)
		(end 152.527 -417.181284)
		(width 0.14224)
		(layer "In6.Cu")
		(net "P5E_CPU1_P3_TX_BUF_C_DP<12>")
	)
	(segment
		(start 153.728928 -413.220408)
		(end 153.577544 -413.718502)
		(width 0.14224)
		(layer "In6.Cu")
		(net "P5E_CPU1_P3_TX_BUF_C_DP<12>")
	)
	(segment
		(start 153.545286 -414.298384)
		(end 153.373836 -414.389824)
		(width 0.14224)
		(layer "In6.Cu")
		(net "P5E_CPU1_P3_TX_BUF_C_DP<12>")
	)
	(segment
		(start 153.373836 -414.389824)
		(end 153.250138 -414.798002)
		(width 0.14224)
		(layer "In6.Cu")
		(net "P5E_CPU1_P3_TX_BUF_C_DP<12>")
	)
	(segment
		(start 150.732236 -423.09796)
		(end 150.273258 -424.205908)
		(width 0.14224)
		(layer "In6.Cu")
		(net "P5E_CPU1_P3_TX_BUF_C_DP<12>")
	)
	(segment
		(start 153.04643 -415.46907)
		(end 152.854406 -416.102038)
		(width 0.14224)
		(layer "In6.Cu")
		(net "P5E_CPU1_P3_TX_BUF_C_DP<12>")
	)
	(segment
		(start 152.61844 -417.35248)
		(end 152.494488 -417.760912)
		(width 0.14224)
		(layer "In6.Cu")
		(net "P5E_CPU1_P3_TX_BUF_C_DP<12>")
	)
	(segment
		(start 152.494488 -417.760912)
		(end 152.323292 -417.852352)
		(width 0.14224)
		(layer "In6.Cu")
		(net "P5E_CPU1_P3_TX_BUF_C_DP<12>")
	)
	(segment
		(start 154.048206 -410.030168)
		(end 153.757376 -410.320998)
		(width 0.14224)
		(layer "In6.Cu")
		(net "P5E_CPU1_P3_TX_BUF_C_DP<12>")
	)
	(segment
		(start 153.577544 -413.718502)
		(end 153.668984 -413.889698)
		(width 0.14224)
		(layer "In6.Cu")
		(net "P5E_CPU1_P3_TX_BUF_C_DP<12>")
	)
	(segment
		(start 150.303738 -426.549058)
		(end 150.622508 -426.549058)
		(width 0.14224)
		(layer "In6.Cu")
		(net "P5E_CPU1_P3_TX_BUF_C_DP<12>")
	)
	(segment
		(start 152.822148 -416.681666)
		(end 152.650698 -416.773106)
		(width 0.14224)
		(layer "In6.Cu")
		(net "P5E_CPU1_P3_TX_BUF_C_DP<12>")
	)
	(segment
		(start 150.070058 -426.315378)
		(end 150.303738 -426.549058)
		(width 0.14224)
		(layer "In6.Cu")
		(net "P5E_CPU1_P3_TX_BUF_C_DP<12>")
	)
	(segment
		(start 150.070058 -425.228258)
		(end 150.070058 -426.315378)
		(width 0.14224)
		(layer "In6.Cu")
		(net "P5E_CPU1_P3_TX_BUF_C_DP<12>")
	)
	(segment
		(start 153.894536 -411.80512)
		(end 153.757376 -411.94228)
		(width 0.14224)
		(layer "In6.Cu")
		(net "P5E_CPU1_P3_TX_BUF_C_DP<12>")
	)
	(segment
		(start 153.250138 -414.798002)
		(end 153.341578 -414.969198)
		(width 0.14224)
		(layer "In6.Cu")
		(net "P5E_CPU1_P3_TX_BUF_C_DP<12>")
	)
	(segment
		(start 153.757376 -410.320998)
		(end 153.757376 -411.24124)
		(width 0.14224)
		(layer "In6.Cu")
		(net "P5E_CPU1_P3_TX_BUF_C_DP<12>")
	)
	(segment
		(start 153.757376 -411.24124)
		(end 153.894536 -411.3784)
		(width 0.14224)
		(layer "In6.Cu")
		(net "P5E_CPU1_P3_TX_BUF_C_DP<12>")
	)
	(segment
		(start 153.341578 -414.969198)
		(end 153.217626 -415.37763)
		(width 0.14224)
		(layer "In6.Cu")
		(net "P5E_CPU1_P3_TX_BUF_C_DP<12>")
	)
	(segment
		(start 150.622508 -426.549058)
		(end 150.750016 -426.42155)
		(width 0.14224)
		(layer "In6.Cu")
		(net "P5E_CPU1_P3_TX_BUF_C_DP<12>")
	)
	(segment
		(start 152.527 -417.181284)
		(end 152.61844 -417.35248)
		(width 0.14224)
		(layer "In6.Cu")
		(net "P5E_CPU1_P3_TX_BUF_C_DP<12>")
	)
	(segment
		(start 150.750016 -426.42155)
		(end 150.750016 -426.089826)
		(width 0.14224)
		(layer "In6.Cu")
		(net "P5E_CPU1_P3_TX_BUF_C_DP<12>")
	)
	(segment
		(start 153.668984 -413.889698)
		(end 153.545286 -414.298384)
		(width 0.14224)
		(layer "In6.Cu")
		(net "P5E_CPU1_P3_TX_BUF_C_DP<12>")
	)
	(arc
		(start 153.757376 -413.02813)
		(mid 153.750237 -413.125316)
		(end 153.728928 -413.220408)
		(width 0.14224)
		(layer "In6.Cu")
		(net "P5E_CPU1_P3_TX_BUF_C_DP<12>")
	)
	(arc
		(start 150.273258 -424.205908)
		(mid 150.121306 -424.707076)
		(end 150.070058 -425.228258)
		(width 0.14224)
		(layer "In6.Cu")
		(net "P5E_CPU1_P3_TX_BUF_C_DP<12>")
	)
	(segment
		(start 150.714456 -409.079954)
		(end 150.714456 -409.759658)
		(width 0.12954)
		(layer "B.Cu")
		(net "P5E_CPU1_P3_TX_BUF_C_DP<11>")
	)
	(segment
		(start 150.714456 -409.759658)
		(end 150.984966 -410.030168)
		(width 0.12954)
		(layer "B.Cu")
		(net "P5E_CPU1_P3_TX_BUF_C_DP<11>")
	)
	(segment
		(start 151.010366 -408.784044)
		(end 150.714456 -409.079954)
		(width 0.12954)
		(layer "B.Cu")
		(net "P5E_CPU1_P3_TX_BUF_C_DP<11>")
	)
	(segment
		(start 148.070062 -424.113452)
		(end 148.070062 -427.380654)
		(width 0.14224)
		(layer "In6.Cu")
		(net "P5E_CPU1_P3_TX_BUF_C_DP<11>")
	)
	(segment
		(start 150.042372 -415.972752)
		(end 150.142194 -416.139122)
		(width 0.14224)
		(layer "In6.Cu")
		(net "P5E_CPU1_P3_TX_BUF_C_DP<11>")
	)
	(segment
		(start 150.690326 -413.951166)
		(end 150.586694 -414.36544)
		(width 0.14224)
		(layer "In6.Cu")
		(net "P5E_CPU1_P3_TX_BUF_C_DP<11>")
	)
	(segment
		(start 148.75002 -427.421548)
		(end 148.75002 -427.089824)
		(width 0.14224)
		(layer "In6.Cu")
		(net "P5E_CPU1_P3_TX_BUF_C_DP<11>")
	)
	(segment
		(start 148.23821 -427.548802)
		(end 148.622766 -427.548802)
		(width 0.14224)
		(layer "In6.Cu")
		(net "P5E_CPU1_P3_TX_BUF_C_DP<11>")
	)
	(segment
		(start 150.316438 -414.878774)
		(end 150.41626 -415.045144)
		(width 0.14224)
		(layer "In6.Cu")
		(net "P5E_CPU1_P3_TX_BUF_C_DP<11>")
	)
	(segment
		(start 150.984966 -410.030168)
		(end 150.694136 -410.320998)
		(width 0.14224)
		(layer "In6.Cu")
		(net "P5E_CPU1_P3_TX_BUF_C_DP<11>")
	)
	(segment
		(start 150.146004 -415.558986)
		(end 150.042372 -415.972752)
		(width 0.14224)
		(layer "In6.Cu")
		(net "P5E_CPU1_P3_TX_BUF_C_DP<11>")
	)
	(segment
		(start 150.586694 -414.36544)
		(end 150.42007 -414.465008)
		(width 0.14224)
		(layer "In6.Cu")
		(net "P5E_CPU1_P3_TX_BUF_C_DP<11>")
	)
	(segment
		(start 150.590504 -413.784796)
		(end 150.690326 -413.951166)
		(width 0.14224)
		(layer "In6.Cu")
		(net "P5E_CPU1_P3_TX_BUF_C_DP<11>")
	)
	(segment
		(start 150.312628 -415.459418)
		(end 150.146004 -415.558986)
		(width 0.14224)
		(layer "In6.Cu")
		(net "P5E_CPU1_P3_TX_BUF_C_DP<11>")
	)
	(segment
		(start 149.868128 -417.2331)
		(end 149.764496 -417.647374)
		(width 0.14224)
		(layer "In6.Cu")
		(net "P5E_CPU1_P3_TX_BUF_C_DP<11>")
	)
	(segment
		(start 150.142194 -416.139122)
		(end 150.038562 -416.553396)
		(width 0.14224)
		(layer "In6.Cu")
		(net "P5E_CPU1_P3_TX_BUF_C_DP<11>")
	)
	(segment
		(start 149.764496 -417.647374)
		(end 149.597872 -417.746942)
		(width 0.14224)
		(layer "In6.Cu")
		(net "P5E_CPU1_P3_TX_BUF_C_DP<11>")
	)
	(segment
		(start 150.42007 -414.465008)
		(end 150.316438 -414.878774)
		(width 0.14224)
		(layer "In6.Cu")
		(net "P5E_CPU1_P3_TX_BUF_C_DP<11>")
	)
	(segment
		(start 149.871938 -416.652964)
		(end 149.768306 -417.06673)
		(width 0.14224)
		(layer "In6.Cu")
		(net "P5E_CPU1_P3_TX_BUF_C_DP<11>")
	)
	(segment
		(start 149.597872 -417.746942)
		(end 148.134832 -423.588688)
		(width 0.14224)
		(layer "In6.Cu")
		(net "P5E_CPU1_P3_TX_BUF_C_DP<11>")
	)
	(segment
		(start 150.694136 -410.320998)
		(end 150.694136 -413.154368)
		(width 0.14224)
		(layer "In6.Cu")
		(net "P5E_CPU1_P3_TX_BUF_C_DP<11>")
	)
	(segment
		(start 150.038562 -416.553396)
		(end 149.871938 -416.652964)
		(width 0.14224)
		(layer "In6.Cu")
		(net "P5E_CPU1_P3_TX_BUF_C_DP<11>")
	)
	(segment
		(start 148.070062 -427.380654)
		(end 148.23821 -427.548802)
		(width 0.14224)
		(layer "In6.Cu")
		(net "P5E_CPU1_P3_TX_BUF_C_DP<11>")
	)
	(segment
		(start 150.641304 -413.58185)
		(end 150.590504 -413.784796)
		(width 0.14224)
		(layer "In6.Cu")
		(net "P5E_CPU1_P3_TX_BUF_C_DP<11>")
	)
	(segment
		(start 150.41626 -415.045144)
		(end 150.312628 -415.459418)
		(width 0.14224)
		(layer "In6.Cu")
		(net "P5E_CPU1_P3_TX_BUF_C_DP<11>")
	)
	(segment
		(start 149.768306 -417.06673)
		(end 149.868128 -417.2331)
		(width 0.14224)
		(layer "In6.Cu")
		(net "P5E_CPU1_P3_TX_BUF_C_DP<11>")
	)
	(segment
		(start 148.622766 -427.548802)
		(end 148.75002 -427.421548)
		(width 0.14224)
		(layer "In6.Cu")
		(net "P5E_CPU1_P3_TX_BUF_C_DP<11>")
	)
	(arc
		(start 150.694136 -413.154368)
		(mid 150.680863 -413.369733)
		(end 150.641304 -413.58185)
		(width 0.14224)
		(layer "In6.Cu")
		(net "P5E_CPU1_P3_TX_BUF_C_DP<11>")
	)
	(arc
		(start 148.134832 -423.588688)
		(mid 148.086326 -423.84908)
		(end 148.070062 -424.113452)
		(width 0.14224)
		(layer "In6.Cu")
		(net "P5E_CPU1_P3_TX_BUF_C_DP<11>")
	)
	(segment
		(start 147.651216 -409.079954)
		(end 147.651216 -409.759658)
		(width 0.12954)
		(layer "B.Cu")
		(net "P5E_CPU1_P3_TX_BUF_C_DP<10>")
	)
	(segment
		(start 147.947126 -408.784044)
		(end 147.651216 -409.079954)
		(width 0.12954)
		(layer "B.Cu")
		(net "P5E_CPU1_P3_TX_BUF_C_DP<10>")
	)
	(segment
		(start 147.651216 -409.759658)
		(end 147.921726 -410.030168)
		(width 0.12954)
		(layer "B.Cu")
		(net "P5E_CPU1_P3_TX_BUF_C_DP<10>")
	)
	(segment
		(start 147.630896 -413.248348)
		(end 147.630896 -411.824932)
		(width 0.14224)
		(layer "In6.Cu")
		(net "P5E_CPU1_P3_TX_BUF_C_DP<10>")
	)
	(segment
		(start 146.76374 -419.090348)
		(end 146.764248 -419.08984)
		(width 0.14224)
		(layer "In6.Cu")
		(net "P5E_CPU1_P3_TX_BUF_C_DP<10>")
	)
	(segment
		(start 147.393914 -414.845754)
		(end 147.46351 -414.376108)
		(width 0.14224)
		(layer "In6.Cu")
		(net "P5E_CPU1_P3_TX_BUF_C_DP<10>")
	)
	(segment
		(start 146.303746 -426.549058)
		(end 146.070066 -426.315378)
		(width 0.14224)
		(layer "In6.Cu")
		(net "P5E_CPU1_P3_TX_BUF_C_DP<10>")
	)
	(segment
		(start 146.929348 -417.97478)
		(end 147.085558 -417.859464)
		(width 0.14224)
		(layer "In6.Cu")
		(net "P5E_CPU1_P3_TX_BUF_C_DP<10>")
	)
	(segment
		(start 146.622516 -426.549058)
		(end 146.303746 -426.549058)
		(width 0.14224)
		(layer "In6.Cu")
		(net "P5E_CPU1_P3_TX_BUF_C_DP<10>")
	)
	(segment
		(start 146.750024 -426.42155)
		(end 146.622516 -426.549058)
		(width 0.14224)
		(layer "In6.Cu")
		(net "P5E_CPU1_P3_TX_BUF_C_DP<10>")
	)
	(segment
		(start 147.630896 -411.824932)
		(end 147.768056 -411.687772)
		(width 0.14224)
		(layer "In6.Cu")
		(net "P5E_CPU1_P3_TX_BUF_C_DP<10>")
	)
	(segment
		(start 147.509484 -415.001456)
		(end 147.393914 -414.845754)
		(width 0.14224)
		(layer "In6.Cu")
		(net "P5E_CPU1_P3_TX_BUF_C_DP<10>")
	)
	(segment
		(start 147.682204 -413.83839)
		(end 147.566634 -413.682434)
		(width 0.14224)
		(layer "In6.Cu")
		(net "P5E_CPU1_P3_TX_BUF_C_DP<10>")
	)
	(segment
		(start 147.148042 -417.437062)
		(end 147.032472 -417.281106)
		(width 0.14224)
		(layer "In6.Cu")
		(net "P5E_CPU1_P3_TX_BUF_C_DP<10>")
	)
	(segment
		(start 146.764248 -419.08984)
		(end 146.929348 -417.97478)
		(width 0.14224)
		(layer "In6.Cu")
		(net "P5E_CPU1_P3_TX_BUF_C_DP<10>")
	)
	(segment
		(start 147.566634 -413.682434)
		(end 147.630896 -413.248348)
		(width 0.14224)
		(layer "In6.Cu")
		(net "P5E_CPU1_P3_TX_BUF_C_DP<10>")
	)
	(segment
		(start 147.094956 -416.859212)
		(end 147.250912 -416.743642)
		(width 0.14224)
		(layer "In6.Cu")
		(net "P5E_CPU1_P3_TX_BUF_C_DP<10>")
	)
	(segment
		(start 147.19808 -416.165538)
		(end 147.29079 -415.539428)
		(width 0.14224)
		(layer "In6.Cu")
		(net "P5E_CPU1_P3_TX_BUF_C_DP<10>")
	)
	(segment
		(start 147.46351 -414.376108)
		(end 147.619466 -414.260792)
		(width 0.14224)
		(layer "In6.Cu")
		(net "P5E_CPU1_P3_TX_BUF_C_DP<10>")
	)
	(segment
		(start 147.768056 -411.261052)
		(end 147.630896 -411.123892)
		(width 0.14224)
		(layer "In6.Cu")
		(net "P5E_CPU1_P3_TX_BUF_C_DP<10>")
	)
	(segment
		(start 147.447 -415.423858)
		(end 147.509484 -415.001456)
		(width 0.14224)
		(layer "In6.Cu")
		(net "P5E_CPU1_P3_TX_BUF_C_DP<10>")
	)
	(segment
		(start 147.630896 -411.123892)
		(end 147.630896 -410.320998)
		(width 0.14224)
		(layer "In6.Cu")
		(net "P5E_CPU1_P3_TX_BUF_C_DP<10>")
	)
	(segment
		(start 147.032472 -417.281106)
		(end 147.094956 -416.859212)
		(width 0.14224)
		(layer "In6.Cu")
		(net "P5E_CPU1_P3_TX_BUF_C_DP<10>")
	)
	(segment
		(start 147.085558 -417.859464)
		(end 147.148042 -417.437062)
		(width 0.14224)
		(layer "In6.Cu")
		(net "P5E_CPU1_P3_TX_BUF_C_DP<10>")
	)
	(segment
		(start 146.750024 -426.089826)
		(end 146.750024 -426.42155)
		(width 0.14224)
		(layer "In6.Cu")
		(net "P5E_CPU1_P3_TX_BUF_C_DP<10>")
	)
	(segment
		(start 147.619466 -414.260792)
		(end 147.682204 -413.83839)
		(width 0.14224)
		(layer "In6.Cu")
		(net "P5E_CPU1_P3_TX_BUF_C_DP<10>")
	)
	(segment
		(start 147.29079 -415.539428)
		(end 147.447 -415.423858)
		(width 0.14224)
		(layer "In6.Cu")
		(net "P5E_CPU1_P3_TX_BUF_C_DP<10>")
	)
	(segment
		(start 147.630896 -410.320998)
		(end 147.921726 -410.030168)
		(width 0.14224)
		(layer "In6.Cu")
		(net "P5E_CPU1_P3_TX_BUF_C_DP<10>")
	)
	(segment
		(start 147.250912 -416.743642)
		(end 147.31365 -416.32124)
		(width 0.14224)
		(layer "In6.Cu")
		(net "P5E_CPU1_P3_TX_BUF_C_DP<10>")
	)
	(segment
		(start 146.070066 -423.770806)
		(end 146.76374 -419.090348)
		(width 0.14224)
		(layer "In6.Cu")
		(net "P5E_CPU1_P3_TX_BUF_C_DP<10>")
	)
	(segment
		(start 147.31365 -416.32124)
		(end 147.19808 -416.165538)
		(width 0.14224)
		(layer "In6.Cu")
		(net "P5E_CPU1_P3_TX_BUF_C_DP<10>")
	)
	(segment
		(start 146.070066 -426.315378)
		(end 146.070066 -423.770806)
		(width 0.14224)
		(layer "In6.Cu")
		(net "P5E_CPU1_P3_TX_BUF_C_DP<10>")
	)
	(segment
		(start 147.768056 -411.687772)
		(end 147.768056 -411.261052)
		(width 0.14224)
		(layer "In6.Cu")
		(net "P5E_CPU1_P3_TX_BUF_C_DP<10>")
	)
	(segment
		(start 117.018816 -409.079954)
		(end 117.018816 -409.759658)
		(width 0.12954)
		(layer "B.Cu")
		(net "P5E_CPU1_P3_TX_BUF_C_DP<0>")
	)
	(segment
		(start 117.018816 -409.759658)
		(end 117.289326 -410.030168)
		(width 0.12954)
		(layer "B.Cu")
		(net "P5E_CPU1_P3_TX_BUF_C_DP<0>")
	)
	(segment
		(start 117.314726 -408.784044)
		(end 117.018816 -409.079954)
		(width 0.12954)
		(layer "B.Cu")
		(net "P5E_CPU1_P3_TX_BUF_C_DP<0>")
	)
	(segment
		(start 120.134126 -417.796472)
		(end 120.528842 -418.328094)
		(width 0.14224)
		(layer "In6.Cu")
		(net "P5E_CPU1_P3_TX_BUF_C_DP<0>")
	)
	(segment
		(start 120.528842 -418.328094)
		(end 121.67743 -419.095682)
		(width 0.14224)
		(layer "In6.Cu")
		(net "P5E_CPU1_P3_TX_BUF_C_DP<0>")
	)
	(segment
		(start 117.909594 -414.797748)
		(end 118.101364 -414.826196)
		(width 0.14224)
		(layer "In6.Cu")
		(net "P5E_CPU1_P3_TX_BUF_C_DP<0>")
	)
	(segment
		(start 125.622304 -426.549058)
		(end 125.749812 -426.42155)
		(width 0.14224)
		(layer "In6.Cu")
		(net "P5E_CPU1_P3_TX_BUF_C_DP<0>")
	)
	(segment
		(start 121.867676 -419.057836)
		(end 122.222768 -419.295072)
		(width 0.14224)
		(layer "In6.Cu")
		(net "P5E_CPU1_P3_TX_BUF_C_DP<0>")
	)
	(segment
		(start 117.135656 -411.747462)
		(end 116.998496 -411.884622)
		(width 0.14224)
		(layer "In6.Cu")
		(net "P5E_CPU1_P3_TX_BUF_C_DP<0>")
	)
	(segment
		(start 116.998496 -410.320998)
		(end 116.998496 -411.183582)
		(width 0.14224)
		(layer "In6.Cu")
		(net "P5E_CPU1_P3_TX_BUF_C_DP<0>")
	)
	(segment
		(start 116.998496 -411.183582)
		(end 117.135656 -411.320742)
		(width 0.14224)
		(layer "In6.Cu")
		(net "P5E_CPU1_P3_TX_BUF_C_DP<0>")
	)
	(segment
		(start 117.096794 -413.702246)
		(end 117.909594 -414.797748)
		(width 0.14224)
		(layer "In6.Cu")
		(net "P5E_CPU1_P3_TX_BUF_C_DP<0>")
	)
	(segment
		(start 120.162574 -417.604702)
		(end 120.134126 -417.796472)
		(width 0.14224)
		(layer "In6.Cu")
		(net "P5E_CPU1_P3_TX_BUF_C_DP<0>")
	)
	(segment
		(start 118.355872 -415.169096)
		(end 118.327424 -415.36112)
		(width 0.14224)
		(layer "In6.Cu")
		(net "P5E_CPU1_P3_TX_BUF_C_DP<0>")
	)
	(segment
		(start 117.135656 -411.320742)
		(end 117.135656 -411.747462)
		(width 0.14224)
		(layer "In6.Cu")
		(net "P5E_CPU1_P3_TX_BUF_C_DP<0>")
	)
	(segment
		(start 125.749812 -426.42155)
		(end 125.749812 -426.089826)
		(width 0.14224)
		(layer "In6.Cu")
		(net "P5E_CPU1_P3_TX_BUF_C_DP<0>")
	)
	(segment
		(start 118.101364 -414.826196)
		(end 118.355872 -415.169096)
		(width 0.14224)
		(layer "In6.Cu")
		(net "P5E_CPU1_P3_TX_BUF_C_DP<0>")
	)
	(segment
		(start 119.286274 -416.653726)
		(end 119.716042 -417.233354)
		(width 0.14224)
		(layer "In6.Cu")
		(net "P5E_CPU1_P3_TX_BUF_C_DP<0>")
	)
	(segment
		(start 117.289326 -410.030168)
		(end 116.998496 -410.320998)
		(width 0.14224)
		(layer "In6.Cu")
		(net "P5E_CPU1_P3_TX_BUF_C_DP<0>")
	)
	(segment
		(start 119.716042 -417.233354)
		(end 119.908066 -417.261802)
		(width 0.14224)
		(layer "In6.Cu")
		(net "P5E_CPU1_P3_TX_BUF_C_DP<0>")
	)
	(segment
		(start 122.260614 -419.485318)
		(end 123.501912 -420.314882)
		(width 0.14224)
		(layer "In6.Cu")
		(net "P5E_CPU1_P3_TX_BUF_C_DP<0>")
	)
	(segment
		(start 116.998496 -411.884622)
		(end 116.998496 -413.404304)
		(width 0.14224)
		(layer "In6.Cu")
		(net "P5E_CPU1_P3_TX_BUF_C_DP<0>")
	)
	(segment
		(start 123.501912 -420.314882)
		(end 124.037852 -421.184578)
		(width 0.14224)
		(layer "In6.Cu")
		(net "P5E_CPU1_P3_TX_BUF_C_DP<0>")
	)
	(segment
		(start 124.956062 -426.549058)
		(end 125.622304 -426.549058)
		(width 0.14224)
		(layer "In6.Cu")
		(net "P5E_CPU1_P3_TX_BUF_C_DP<0>")
	)
	(segment
		(start 124.037852 -421.184578)
		(end 124.663708 -426.256704)
		(width 0.14224)
		(layer "In6.Cu")
		(net "P5E_CPU1_P3_TX_BUF_C_DP<0>")
	)
	(segment
		(start 119.060214 -416.118802)
		(end 119.314722 -416.461956)
		(width 0.14224)
		(layer "In6.Cu")
		(net "P5E_CPU1_P3_TX_BUF_C_DP<0>")
	)
	(segment
		(start 124.663708 -426.256704)
		(end 124.956062 -426.549058)
		(width 0.14224)
		(layer "In6.Cu")
		(net "P5E_CPU1_P3_TX_BUF_C_DP<0>")
	)
	(segment
		(start 121.67743 -419.095682)
		(end 121.867676 -419.057836)
		(width 0.14224)
		(layer "In6.Cu")
		(net "P5E_CPU1_P3_TX_BUF_C_DP<0>")
	)
	(segment
		(start 118.868444 -416.090354)
		(end 119.060214 -416.118802)
		(width 0.14224)
		(layer "In6.Cu")
		(net "P5E_CPU1_P3_TX_BUF_C_DP<0>")
	)
	(segment
		(start 122.222768 -419.295072)
		(end 122.260614 -419.485318)
		(width 0.14224)
		(layer "In6.Cu")
		(net "P5E_CPU1_P3_TX_BUF_C_DP<0>")
	)
	(segment
		(start 119.314722 -416.461956)
		(end 119.286274 -416.653726)
		(width 0.14224)
		(layer "In6.Cu")
		(net "P5E_CPU1_P3_TX_BUF_C_DP<0>")
	)
	(segment
		(start 119.908066 -417.261802)
		(end 120.162574 -417.604702)
		(width 0.14224)
		(layer "In6.Cu")
		(net "P5E_CPU1_P3_TX_BUF_C_DP<0>")
	)
	(segment
		(start 118.327424 -415.36112)
		(end 118.868444 -416.090354)
		(width 0.14224)
		(layer "In6.Cu")
		(net "P5E_CPU1_P3_TX_BUF_C_DP<0>")
	)
	(arc
		(start 116.998496 -413.404304)
		(mid 117.023668 -413.561185)
		(end 117.096794 -413.702246)
		(width 0.14224)
		(layer "In6.Cu")
		(net "P5E_CPU1_P3_TX_BUF_C_DP<0>")
	)
	(segment
		(start 144.265396 -409.759658)
		(end 143.994886 -410.030168)
		(width 0.12954)
		(layer "B.Cu")
		(net "P5E_CPU1_P3_TX_BUF_C_DN<9>")
	)
	(segment
		(start 143.969486 -408.784044)
		(end 144.265396 -409.079954)
		(width 0.12954)
		(layer "B.Cu")
		(net "P5E_CPU1_P3_TX_BUF_C_DN<9>")
	)
	(segment
		(start 144.265396 -409.079954)
		(end 144.265396 -409.759658)
		(width 0.12954)
		(layer "B.Cu")
		(net "P5E_CPU1_P3_TX_BUF_C_DN<9>")
	)
	(segment
		(start 143.78813 -423.145458)
		(end 144.107408 -416.634676)
		(width 0.14224)
		(layer "In6.Cu")
		(net "P5E_CPU1_P3_TX_BUF_C_DN<9>")
	)
	(segment
		(start 144.107916 -416.634422)
		(end 144.285716 -413.015176)
		(width 0.14224)
		(layer "In6.Cu")
		(net "P5E_CPU1_P3_TX_BUF_C_DN<9>")
	)
	(segment
		(start 144.115536 -427.8249)
		(end 143.78813 -427.497494)
		(width 0.14224)
		(layer "In6.Cu")
		(net "P5E_CPU1_P3_TX_BUF_C_DN<9>")
	)
	(segment
		(start 144.285716 -413.015176)
		(end 144.285716 -410.320998)
		(width 0.14224)
		(layer "In6.Cu")
		(net "P5E_CPU1_P3_TX_BUF_C_DN<9>")
	)
	(segment
		(start 143.78813 -427.497494)
		(end 143.78813 -423.145458)
		(width 0.14224)
		(layer "In6.Cu")
		(net "P5E_CPU1_P3_TX_BUF_C_DN<9>")
	)
	(segment
		(start 144.616932 -427.8249)
		(end 144.115536 -427.8249)
		(width 0.14224)
		(layer "In6.Cu")
		(net "P5E_CPU1_P3_TX_BUF_C_DN<9>")
	)
	(segment
		(start 144.750028 -428.28972)
		(end 144.750028 -427.957996)
		(width 0.14224)
		(layer "In6.Cu")
		(net "P5E_CPU1_P3_TX_BUF_C_DN<9>")
	)
	(segment
		(start 144.107408 -416.634676)
		(end 144.107916 -416.634422)
		(width 0.14224)
		(layer "In6.Cu")
		(net "P5E_CPU1_P3_TX_BUF_C_DN<9>")
	)
	(segment
		(start 144.285716 -410.320998)
		(end 143.994886 -410.030168)
		(width 0.14224)
		(layer "In6.Cu")
		(net "P5E_CPU1_P3_TX_BUF_C_DN<9>")
	)
	(segment
		(start 144.750028 -427.957996)
		(end 144.616932 -427.8249)
		(width 0.14224)
		(layer "In6.Cu")
		(net "P5E_CPU1_P3_TX_BUF_C_DN<9>")
	)
	(segment
		(start 141.202156 -409.079954)
		(end 141.202156 -409.759658)
		(width 0.12954)
		(layer "B.Cu")
		(net "P5E_CPU1_P3_TX_BUF_C_DN<8>")
	)
	(segment
		(start 140.906246 -408.784044)
		(end 141.202156 -409.079954)
		(width 0.12954)
		(layer "B.Cu")
		(net "P5E_CPU1_P3_TX_BUF_C_DN<8>")
	)
	(segment
		(start 141.202156 -409.759658)
		(end 140.931646 -410.030168)
		(width 0.12954)
		(layer "B.Cu")
		(net "P5E_CPU1_P3_TX_BUF_C_DN<8>")
	)
	(segment
		(start 141.222476 -410.320998)
		(end 140.931646 -410.030168)
		(width 0.14224)
		(layer "In6.Cu")
		(net "P5E_CPU1_P3_TX_BUF_C_DN<8>")
	)
	(segment
		(start 142.622778 -426.830998)
		(end 142.186914 -426.830998)
		(width 0.14224)
		(layer "In6.Cu")
		(net "P5E_CPU1_P3_TX_BUF_C_DN<8>")
	)
	(segment
		(start 142.186914 -426.830998)
		(end 141.788134 -426.432218)
		(width 0.14224)
		(layer "In6.Cu")
		(net "P5E_CPU1_P3_TX_BUF_C_DN<8>")
	)
	(segment
		(start 142.750032 -427.289976)
		(end 142.750032 -426.958252)
		(width 0.14224)
		(layer "In6.Cu")
		(net "P5E_CPU1_P3_TX_BUF_C_DN<8>")
	)
	(segment
		(start 141.788134 -426.432218)
		(end 141.788134 -424.757342)
		(width 0.14224)
		(layer "In6.Cu")
		(net "P5E_CPU1_P3_TX_BUF_C_DN<8>")
	)
	(segment
		(start 141.222984 -413.245046)
		(end 141.222476 -413.244538)
		(width 0.14224)
		(layer "In6.Cu")
		(net "P5E_CPU1_P3_TX_BUF_C_DN<8>")
	)
	(segment
		(start 141.788134 -424.757342)
		(end 141.222984 -413.245046)
		(width 0.14224)
		(layer "In6.Cu")
		(net "P5E_CPU1_P3_TX_BUF_C_DN<8>")
	)
	(segment
		(start 141.222476 -413.244538)
		(end 141.222476 -410.320998)
		(width 0.14224)
		(layer "In6.Cu")
		(net "P5E_CPU1_P3_TX_BUF_C_DN<8>")
	)
	(segment
		(start 142.750032 -426.958252)
		(end 142.622778 -426.830998)
		(width 0.14224)
		(layer "In6.Cu")
		(net "P5E_CPU1_P3_TX_BUF_C_DN<8>")
	)
	(segment
		(start 138.138916 -409.759658)
		(end 137.868406 -410.030168)
		(width 0.12954)
		(layer "B.Cu")
		(net "P5E_CPU1_P3_TX_BUF_C_DN<7>")
	)
	(segment
		(start 137.843006 -408.784044)
		(end 138.138916 -409.079954)
		(width 0.12954)
		(layer "B.Cu")
		(net "P5E_CPU1_P3_TX_BUF_C_DN<7>")
	)
	(segment
		(start 138.138916 -409.079954)
		(end 138.138916 -409.759658)
		(width 0.12954)
		(layer "B.Cu")
		(net "P5E_CPU1_P3_TX_BUF_C_DN<7>")
	)
	(segment
		(start 139.121134 -427.830742)
		(end 138.787886 -427.497494)
		(width 0.14224)
		(layer "In6.Cu")
		(net "P5E_CPU1_P3_TX_BUF_C_DN<7>")
	)
	(segment
		(start 138.787886 -427.497494)
		(end 138.787886 -419.470586)
		(width 0.14224)
		(layer "In6.Cu")
		(net "P5E_CPU1_P3_TX_BUF_C_DN<7>")
	)
	(segment
		(start 138.159236 -410.320998)
		(end 137.868406 -410.030168)
		(width 0.14224)
		(layer "In6.Cu")
		(net "P5E_CPU1_P3_TX_BUF_C_DN<7>")
	)
	(segment
		(start 138.159236 -413.090614)
		(end 138.159236 -410.320998)
		(width 0.14224)
		(layer "In6.Cu")
		(net "P5E_CPU1_P3_TX_BUF_C_DN<7>")
	)
	(segment
		(start 138.787886 -419.470586)
		(end 138.159236 -413.090614)
		(width 0.14224)
		(layer "In6.Cu")
		(net "P5E_CPU1_P3_TX_BUF_C_DN<7>")
	)
	(segment
		(start 139.62253 -427.830742)
		(end 139.121134 -427.830742)
		(width 0.14224)
		(layer "In6.Cu")
		(net "P5E_CPU1_P3_TX_BUF_C_DN<7>")
	)
	(segment
		(start 139.749784 -428.28972)
		(end 139.749784 -427.957996)
		(width 0.14224)
		(layer "In6.Cu")
		(net "P5E_CPU1_P3_TX_BUF_C_DN<7>")
	)
	(segment
		(start 139.749784 -427.957996)
		(end 139.62253 -427.830742)
		(width 0.14224)
		(layer "In6.Cu")
		(net "P5E_CPU1_P3_TX_BUF_C_DN<7>")
	)
	(segment
		(start 134.779766 -408.784044)
		(end 135.075676 -409.079954)
		(width 0.12954)
		(layer "B.Cu")
		(net "P5E_CPU1_P3_TX_BUF_C_DN<6>")
	)
	(segment
		(start 135.075676 -409.759658)
		(end 134.805166 -410.030168)
		(width 0.12954)
		(layer "B.Cu")
		(net "P5E_CPU1_P3_TX_BUF_C_DN<6>")
	)
	(segment
		(start 135.075676 -409.079954)
		(end 135.075676 -409.759658)
		(width 0.12954)
		(layer "B.Cu")
		(net "P5E_CPU1_P3_TX_BUF_C_DN<6>")
	)
	(segment
		(start 135.095996 -413.324294)
		(end 135.095996 -410.320998)
		(width 0.14224)
		(layer "In6.Cu")
		(net "P5E_CPU1_P3_TX_BUF_C_DN<6>")
	)
	(segment
		(start 135.325612 -414.08731)
		(end 135.325104 -414.087056)
		(width 0.14224)
		(layer "In6.Cu")
		(net "P5E_CPU1_P3_TX_BUF_C_DN<6>")
	)
	(segment
		(start 137.749788 -426.987208)
		(end 137.622788 -426.860208)
		(width 0.14224)
		(layer "In6.Cu")
		(net "P5E_CPU1_P3_TX_BUF_C_DN<6>")
	)
	(segment
		(start 136.78789 -418.93363)
		(end 136.617964 -417.207446)
		(width 0.14224)
		(layer "In6.Cu")
		(net "P5E_CPU1_P3_TX_BUF_C_DN<6>")
	)
	(segment
		(start 135.175752 -413.726122)
		(end 135.095996 -413.324294)
		(width 0.14224)
		(layer "In6.Cu")
		(net "P5E_CPU1_P3_TX_BUF_C_DN<6>")
	)
	(segment
		(start 135.325104 -414.087056)
		(end 135.175752 -413.726122)
		(width 0.14224)
		(layer "In6.Cu")
		(net "P5E_CPU1_P3_TX_BUF_C_DN<6>")
	)
	(segment
		(start 137.21588 -426.860208)
		(end 136.78789 -426.432218)
		(width 0.14224)
		(layer "In6.Cu")
		(net "P5E_CPU1_P3_TX_BUF_C_DN<6>")
	)
	(segment
		(start 136.78789 -426.432218)
		(end 136.78789 -418.93363)
		(width 0.14224)
		(layer "In6.Cu")
		(net "P5E_CPU1_P3_TX_BUF_C_DN<6>")
	)
	(segment
		(start 137.749788 -427.289976)
		(end 137.749788 -426.987208)
		(width 0.14224)
		(layer "In6.Cu")
		(net "P5E_CPU1_P3_TX_BUF_C_DN<6>")
	)
	(segment
		(start 135.095996 -410.320998)
		(end 134.805166 -410.030168)
		(width 0.14224)
		(layer "In6.Cu")
		(net "P5E_CPU1_P3_TX_BUF_C_DN<6>")
	)
	(segment
		(start 137.622788 -426.860208)
		(end 137.21588 -426.860208)
		(width 0.14224)
		(layer "In6.Cu")
		(net "P5E_CPU1_P3_TX_BUF_C_DN<6>")
	)
	(segment
		(start 136.617964 -417.207446)
		(end 135.325612 -414.08731)
		(width 0.14224)
		(layer "In6.Cu")
		(net "P5E_CPU1_P3_TX_BUF_C_DN<6>")
	)
	(segment
		(start 132.012436 -409.079954)
		(end 132.012436 -409.759658)
		(width 0.12954)
		(layer "B.Cu")
		(net "P5E_CPU1_P3_TX_BUF_C_DN<5>")
	)
	(segment
		(start 131.716526 -408.784044)
		(end 132.012436 -409.079954)
		(width 0.12954)
		(layer "B.Cu")
		(net "P5E_CPU1_P3_TX_BUF_C_DN<5>")
	)
	(segment
		(start 132.012436 -409.759658)
		(end 131.741926 -410.030168)
		(width 0.12954)
		(layer "B.Cu")
		(net "P5E_CPU1_P3_TX_BUF_C_DN<5>")
	)
	(segment
		(start 135.749792 -428.28972)
		(end 135.749792 -427.957996)
		(width 0.14224)
		(layer "In6.Cu")
		(net "P5E_CPU1_P3_TX_BUF_C_DN<5>")
	)
	(segment
		(start 134.787894 -427.497494)
		(end 134.787894 -418.428678)
		(width 0.14224)
		(layer "In6.Cu")
		(net "P5E_CPU1_P3_TX_BUF_C_DN<5>")
	)
	(segment
		(start 134.787894 -418.428678)
		(end 134.692898 -417.572952)
		(width 0.14224)
		(layer "In6.Cu")
		(net "P5E_CPU1_P3_TX_BUF_C_DN<5>")
	)
	(segment
		(start 134.601712 -417.166806)
		(end 134.240524 -416.625786)
		(width 0.14224)
		(layer "In6.Cu")
		(net "P5E_CPU1_P3_TX_BUF_C_DN<5>")
	)
	(segment
		(start 133.971792 -416.223704)
		(end 133.971538 -416.223704)
		(width 0.14224)
		(layer "In6.Cu")
		(net "P5E_CPU1_P3_TX_BUF_C_DN<5>")
	)
	(segment
		(start 132.662168 -414.264094)
		(end 132.169916 -413.52724)
		(width 0.14224)
		(layer "In6.Cu")
		(net "P5E_CPU1_P3_TX_BUF_C_DN<5>")
	)
	(segment
		(start 134.24027 -416.625786)
		(end 133.971792 -416.223704)
		(width 0.14224)
		(layer "In6.Cu")
		(net "P5E_CPU1_P3_TX_BUF_C_DN<5>")
	)
	(segment
		(start 132.032756 -410.320998)
		(end 131.741926 -410.030168)
		(width 0.14224)
		(layer "In6.Cu")
		(net "P5E_CPU1_P3_TX_BUF_C_DN<5>")
	)
	(segment
		(start 134.240524 -416.625786)
		(end 134.24027 -416.625786)
		(width 0.14224)
		(layer "In6.Cu")
		(net "P5E_CPU1_P3_TX_BUF_C_DN<5>")
	)
	(segment
		(start 132.032756 -413.074612)
		(end 132.032756 -410.320998)
		(width 0.14224)
		(layer "In6.Cu")
		(net "P5E_CPU1_P3_TX_BUF_C_DN<5>")
	)
	(segment
		(start 135.616696 -427.8249)
		(end 135.1153 -427.8249)
		(width 0.14224)
		(layer "In6.Cu")
		(net "P5E_CPU1_P3_TX_BUF_C_DN<5>")
	)
	(segment
		(start 132.662422 -414.264348)
		(end 132.662168 -414.264094)
		(width 0.14224)
		(layer "In6.Cu")
		(net "P5E_CPU1_P3_TX_BUF_C_DN<5>")
	)
	(segment
		(start 135.749792 -427.957996)
		(end 135.616696 -427.8249)
		(width 0.14224)
		(layer "In6.Cu")
		(net "P5E_CPU1_P3_TX_BUF_C_DN<5>")
	)
	(segment
		(start 133.971538 -416.223704)
		(end 132.662422 -414.264348)
		(width 0.14224)
		(layer "In6.Cu")
		(net "P5E_CPU1_P3_TX_BUF_C_DN<5>")
	)
	(segment
		(start 134.692898 -417.572952)
		(end 134.601712 -417.166806)
		(width 0.14224)
		(layer "In6.Cu")
		(net "P5E_CPU1_P3_TX_BUF_C_DN<5>")
	)
	(segment
		(start 132.169916 -413.52724)
		(end 132.032756 -413.074612)
		(width 0.14224)
		(layer "In6.Cu")
		(net "P5E_CPU1_P3_TX_BUF_C_DN<5>")
	)
	(segment
		(start 135.1153 -427.8249)
		(end 134.787894 -427.497494)
		(width 0.14224)
		(layer "In6.Cu")
		(net "P5E_CPU1_P3_TX_BUF_C_DN<5>")
	)
	(segment
		(start 128.949196 -409.079954)
		(end 128.949196 -409.759658)
		(width 0.12954)
		(layer "B.Cu")
		(net "P5E_CPU1_P3_TX_BUF_C_DN<4>")
	)
	(segment
		(start 128.653286 -408.784044)
		(end 128.949196 -409.079954)
		(width 0.12954)
		(layer "B.Cu")
		(net "P5E_CPU1_P3_TX_BUF_C_DN<4>")
	)
	(segment
		(start 128.949196 -409.759658)
		(end 128.678686 -410.030168)
		(width 0.12954)
		(layer "B.Cu")
		(net "P5E_CPU1_P3_TX_BUF_C_DN<4>")
	)
	(segment
		(start 129.37744 -414.134046)
		(end 129.628392 -414.373314)
		(width 0.14224)
		(layer "In6.Cu")
		(net "P5E_CPU1_P3_TX_BUF_C_DN<4>")
	)
	(segment
		(start 132.708142 -417.304982)
		(end 132.787898 -417.491164)
		(width 0.14224)
		(layer "In6.Cu")
		(net "P5E_CPU1_P3_TX_BUF_C_DN<4>")
	)
	(segment
		(start 132.787898 -417.491164)
		(end 132.787898 -426.432218)
		(width 0.14224)
		(layer "In6.Cu")
		(net "P5E_CPU1_P3_TX_BUF_C_DN<4>")
	)
	(segment
		(start 133.622542 -426.830998)
		(end 133.749796 -426.958252)
		(width 0.14224)
		(layer "In6.Cu")
		(net "P5E_CPU1_P3_TX_BUF_C_DN<4>")
	)
	(segment
		(start 128.969516 -410.320998)
		(end 128.969516 -413.420814)
		(width 0.14224)
		(layer "In6.Cu")
		(net "P5E_CPU1_P3_TX_BUF_C_DN<4>")
	)
	(segment
		(start 133.186678 -426.830998)
		(end 133.622542 -426.830998)
		(width 0.14224)
		(layer "In6.Cu")
		(net "P5E_CPU1_P3_TX_BUF_C_DN<4>")
	)
	(segment
		(start 132.787898 -426.432218)
		(end 133.186678 -426.830998)
		(width 0.14224)
		(layer "In6.Cu")
		(net "P5E_CPU1_P3_TX_BUF_C_DN<4>")
	)
	(segment
		(start 128.969516 -413.420814)
		(end 129.093722 -413.721042)
		(width 0.14224)
		(layer "In6.Cu")
		(net "P5E_CPU1_P3_TX_BUF_C_DN<4>")
	)
	(segment
		(start 129.6289 -414.373314)
		(end 132.708142 -417.304982)
		(width 0.14224)
		(layer "In6.Cu")
		(net "P5E_CPU1_P3_TX_BUF_C_DN<4>")
	)
	(segment
		(start 128.678686 -410.030168)
		(end 128.969516 -410.320998)
		(width 0.14224)
		(layer "In6.Cu")
		(net "P5E_CPU1_P3_TX_BUF_C_DN<4>")
	)
	(segment
		(start 129.628392 -414.373314)
		(end 129.6289 -414.373314)
		(width 0.14224)
		(layer "In6.Cu")
		(net "P5E_CPU1_P3_TX_BUF_C_DN<4>")
	)
	(segment
		(start 133.749796 -426.958252)
		(end 133.749796 -427.289976)
		(width 0.14224)
		(layer "In6.Cu")
		(net "P5E_CPU1_P3_TX_BUF_C_DN<4>")
	)
	(arc
		(start 129.093722 -413.721042)
		(mid 129.213996 -413.942374)
		(end 129.37744 -414.134046)
		(width 0.14224)
		(layer "In6.Cu")
		(net "P5E_CPU1_P3_TX_BUF_C_DN<4>")
	)
	(segment
		(start 125.885956 -409.759658)
		(end 125.615446 -410.030168)
		(width 0.12954)
		(layer "B.Cu")
		(net "P5E_CPU1_P3_TX_BUF_C_DN<3>")
	)
	(segment
		(start 125.590046 -408.784044)
		(end 125.885956 -409.079954)
		(width 0.12954)
		(layer "B.Cu")
		(net "P5E_CPU1_P3_TX_BUF_C_DN<3>")
	)
	(segment
		(start 125.885956 -409.079954)
		(end 125.885956 -409.759658)
		(width 0.12954)
		(layer "B.Cu")
		(net "P5E_CPU1_P3_TX_BUF_C_DN<3>")
	)
	(segment
		(start 125.906276 -410.320998)
		(end 125.906276 -413.323786)
		(width 0.14224)
		(layer "In6.Cu")
		(net "P5E_CPU1_P3_TX_BUF_C_DN<3>")
	)
	(segment
		(start 125.615446 -410.030168)
		(end 125.906276 -410.320998)
		(width 0.14224)
		(layer "In6.Cu")
		(net "P5E_CPU1_P3_TX_BUF_C_DN<3>")
	)
	(segment
		(start 131.12115 -427.830742)
		(end 131.622546 -427.830742)
		(width 0.14224)
		(layer "In6.Cu")
		(net "P5E_CPU1_P3_TX_BUF_C_DN<3>")
	)
	(segment
		(start 131.7498 -427.957996)
		(end 131.7498 -428.28972)
		(width 0.14224)
		(layer "In6.Cu")
		(net "P5E_CPU1_P3_TX_BUF_C_DN<3>")
	)
	(segment
		(start 129.907284 -416.329622)
		(end 130.613404 -417.38677)
		(width 0.14224)
		(layer "In6.Cu")
		(net "P5E_CPU1_P3_TX_BUF_C_DN<3>")
	)
	(segment
		(start 130.787902 -418.275008)
		(end 130.787902 -427.497494)
		(width 0.14224)
		(layer "In6.Cu")
		(net "P5E_CPU1_P3_TX_BUF_C_DN<3>")
	)
	(segment
		(start 130.787902 -427.497494)
		(end 131.12115 -427.830742)
		(width 0.14224)
		(layer "In6.Cu")
		(net "P5E_CPU1_P3_TX_BUF_C_DN<3>")
	)
	(segment
		(start 131.622546 -427.830742)
		(end 131.7498 -427.957996)
		(width 0.14224)
		(layer "In6.Cu")
		(net "P5E_CPU1_P3_TX_BUF_C_DN<3>")
	)
	(segment
		(start 125.959362 -413.525462)
		(end 126.062994 -413.707834)
		(width 0.14224)
		(layer "In6.Cu")
		(net "P5E_CPU1_P3_TX_BUF_C_DN<3>")
	)
	(segment
		(start 126.191264 -413.845756)
		(end 129.907284 -416.329622)
		(width 0.14224)
		(layer "In6.Cu")
		(net "P5E_CPU1_P3_TX_BUF_C_DN<3>")
	)
	(arc
		(start 130.613404 -417.38677)
		(mid 130.743779 -417.822416)
		(end 130.787902 -418.275008)
		(width 0.14224)
		(layer "In6.Cu")
		(net "P5E_CPU1_P3_TX_BUF_C_DN<3>")
	)
	(arc
		(start 126.062994 -413.707834)
		(mid 126.119073 -413.784286)
		(end 126.191264 -413.845756)
		(width 0.14224)
		(layer "In6.Cu")
		(net "P5E_CPU1_P3_TX_BUF_C_DN<3>")
	)
	(arc
		(start 125.906276 -413.323786)
		(mid 125.919768 -413.42806)
		(end 125.959362 -413.525462)
		(width 0.14224)
		(layer "In6.Cu")
		(net "P5E_CPU1_P3_TX_BUF_C_DN<3>")
	)
	(segment
		(start 122.822716 -409.079954)
		(end 122.822716 -409.759658)
		(width 0.12954)
		(layer "B.Cu")
		(net "P5E_CPU1_P3_TX_BUF_C_DN<2>")
	)
	(segment
		(start 122.526806 -408.784044)
		(end 122.822716 -409.079954)
		(width 0.12954)
		(layer "B.Cu")
		(net "P5E_CPU1_P3_TX_BUF_C_DN<2>")
	)
	(segment
		(start 122.822716 -409.759658)
		(end 122.552206 -410.030168)
		(width 0.12954)
		(layer "B.Cu")
		(net "P5E_CPU1_P3_TX_BUF_C_DN<2>")
	)
	(segment
		(start 129.62255 -426.830998)
		(end 129.749804 -426.958252)
		(width 0.14224)
		(layer "In6.Cu")
		(net "P5E_CPU1_P3_TX_BUF_C_DN<2>")
	)
	(segment
		(start 129.186686 -426.830998)
		(end 129.62255 -426.830998)
		(width 0.14224)
		(layer "In6.Cu")
		(net "P5E_CPU1_P3_TX_BUF_C_DN<2>")
	)
	(segment
		(start 128.787906 -417.452556)
		(end 128.787906 -426.432218)
		(width 0.14224)
		(layer "In6.Cu")
		(net "P5E_CPU1_P3_TX_BUF_C_DN<2>")
	)
	(segment
		(start 127.593598 -416.20567)
		(end 128.750568 -417.36264)
		(width 0.14224)
		(layer "In6.Cu")
		(net "P5E_CPU1_P3_TX_BUF_C_DN<2>")
	)
	(segment
		(start 122.552206 -410.030168)
		(end 122.843036 -410.320998)
		(width 0.14224)
		(layer "In6.Cu")
		(net "P5E_CPU1_P3_TX_BUF_C_DN<2>")
	)
	(segment
		(start 123.256548 -414.21558)
		(end 124.017278 -414.724088)
		(width 0.14224)
		(layer "In6.Cu")
		(net "P5E_CPU1_P3_TX_BUF_C_DN<2>")
	)
	(segment
		(start 127.353314 -416.106102)
		(end 127.593598 -416.20567)
		(width 0.14224)
		(layer "In6.Cu")
		(net "P5E_CPU1_P3_TX_BUF_C_DN<2>")
	)
	(segment
		(start 129.749804 -426.958252)
		(end 129.749804 -427.289976)
		(width 0.14224)
		(layer "In6.Cu")
		(net "P5E_CPU1_P3_TX_BUF_C_DN<2>")
	)
	(segment
		(start 122.9995 -413.805878)
		(end 123.076462 -413.991044)
		(width 0.14224)
		(layer "In6.Cu")
		(net "P5E_CPU1_P3_TX_BUF_C_DN<2>")
	)
	(segment
		(start 124.017278 -414.724088)
		(end 127.35306 -416.105848)
		(width 0.14224)
		(layer "In6.Cu")
		(net "P5E_CPU1_P3_TX_BUF_C_DN<2>")
	)
	(segment
		(start 127.35306 -416.105848)
		(end 127.353314 -416.106102)
		(width 0.14224)
		(layer "In6.Cu")
		(net "P5E_CPU1_P3_TX_BUF_C_DN<2>")
	)
	(segment
		(start 128.787906 -426.432218)
		(end 129.186686 -426.830998)
		(width 0.14224)
		(layer "In6.Cu")
		(net "P5E_CPU1_P3_TX_BUF_C_DN<2>")
	)
	(segment
		(start 122.843036 -410.320998)
		(end 122.843036 -413.020256)
		(width 0.14224)
		(layer "In6.Cu")
		(net "P5E_CPU1_P3_TX_BUF_C_DN<2>")
	)
	(segment
		(start 123.164854 -414.123886)
		(end 123.256548 -414.21558)
		(width 0.14224)
		(layer "In6.Cu")
		(net "P5E_CPU1_P3_TX_BUF_C_DN<2>")
	)
	(arc
		(start 128.750568 -417.36264)
		(mid 128.778187 -417.40388)
		(end 128.787906 -417.452556)
		(width 0.14224)
		(layer "In6.Cu")
		(net "P5E_CPU1_P3_TX_BUF_C_DN<2>")
	)
	(arc
		(start 123.076462 -413.991044)
		(mid 123.114101 -414.06183)
		(end 123.164854 -414.123886)
		(width 0.14224)
		(layer "In6.Cu")
		(net "P5E_CPU1_P3_TX_BUF_C_DN<2>")
	)
	(arc
		(start 122.843036 -413.020256)
		(mid 122.882518 -413.420782)
		(end 122.9995 -413.805878)
		(width 0.14224)
		(layer "In6.Cu")
		(net "P5E_CPU1_P3_TX_BUF_C_DN<2>")
	)
	(segment
		(start 119.759476 -409.079954)
		(end 119.759476 -409.759658)
		(width 0.12954)
		(layer "B.Cu")
		(net "P5E_CPU1_P3_TX_BUF_C_DN<1>")
	)
	(segment
		(start 119.759476 -409.759658)
		(end 119.488966 -410.030168)
		(width 0.12954)
		(layer "B.Cu")
		(net "P5E_CPU1_P3_TX_BUF_C_DN<1>")
	)
	(segment
		(start 119.463566 -408.784044)
		(end 119.759476 -409.079954)
		(width 0.12954)
		(layer "B.Cu")
		(net "P5E_CPU1_P3_TX_BUF_C_DN<1>")
	)
	(segment
		(start 126.78791 -427.497494)
		(end 127.121158 -427.830742)
		(width 0.14224)
		(layer "In6.Cu")
		(net "P5E_CPU1_P3_TX_BUF_C_DN<1>")
	)
	(segment
		(start 122.508264 -417.227766)
		(end 122.508518 -417.227766)
		(width 0.14224)
		(layer "In6.Cu")
		(net "P5E_CPU1_P3_TX_BUF_C_DN<1>")
	)
	(segment
		(start 120.678956 -414.490408)
		(end 120.679464 -414.490662)
		(width 0.14224)
		(layer "In6.Cu")
		(net "P5E_CPU1_P3_TX_BUF_C_DN<1>")
	)
	(segment
		(start 122.508518 -417.227766)
		(end 124.212604 -419.778434)
		(width 0.14224)
		(layer "In6.Cu")
		(net "P5E_CPU1_P3_TX_BUF_C_DN<1>")
	)
	(segment
		(start 120.679464 -414.490662)
		(end 122.508264 -417.227766)
		(width 0.14224)
		(layer "In6.Cu")
		(net "P5E_CPU1_P3_TX_BUF_C_DN<1>")
	)
	(segment
		(start 119.488966 -410.030168)
		(end 119.779796 -410.320998)
		(width 0.14224)
		(layer "In6.Cu")
		(net "P5E_CPU1_P3_TX_BUF_C_DN<1>")
	)
	(segment
		(start 127.121158 -427.830742)
		(end 127.622554 -427.830742)
		(width 0.14224)
		(layer "In6.Cu")
		(net "P5E_CPU1_P3_TX_BUF_C_DN<1>")
	)
	(segment
		(start 119.921528 -413.356552)
		(end 120.678956 -414.490408)
		(width 0.14224)
		(layer "In6.Cu")
		(net "P5E_CPU1_P3_TX_BUF_C_DN<1>")
	)
	(segment
		(start 126.78791 -424.596052)
		(end 126.78791 -427.497494)
		(width 0.14224)
		(layer "In6.Cu")
		(net "P5E_CPU1_P3_TX_BUF_C_DN<1>")
	)
	(segment
		(start 119.779796 -410.320998)
		(end 119.779796 -412.888938)
		(width 0.14224)
		(layer "In6.Cu")
		(net "P5E_CPU1_P3_TX_BUF_C_DN<1>")
	)
	(segment
		(start 124.212604 -419.778434)
		(end 126.78791 -424.596052)
		(width 0.14224)
		(layer "In6.Cu")
		(net "P5E_CPU1_P3_TX_BUF_C_DN<1>")
	)
	(segment
		(start 127.749808 -427.957996)
		(end 127.749808 -428.28972)
		(width 0.14224)
		(layer "In6.Cu")
		(net "P5E_CPU1_P3_TX_BUF_C_DN<1>")
	)
	(segment
		(start 127.622554 -427.830742)
		(end 127.749808 -427.957996)
		(width 0.14224)
		(layer "In6.Cu")
		(net "P5E_CPU1_P3_TX_BUF_C_DN<1>")
	)
	(arc
		(start 119.779796 -412.888938)
		(mid 119.815968 -413.133262)
		(end 119.921528 -413.356552)
		(width 0.14224)
		(layer "In6.Cu")
		(net "P5E_CPU1_P3_TX_BUF_C_DN<1>")
	)
	(segment
		(start 162.644836 -409.759658)
		(end 162.374326 -410.030168)
		(width 0.12954)
		(layer "B.Cu")
		(net "P5E_CPU1_P3_TX_BUF_C_DN<15>")
	)
	(segment
		(start 162.644836 -409.079954)
		(end 162.644836 -409.759658)
		(width 0.12954)
		(layer "B.Cu")
		(net "P5E_CPU1_P3_TX_BUF_C_DN<15>")
	)
	(segment
		(start 162.348926 -408.784044)
		(end 162.644836 -409.079954)
		(width 0.12954)
		(layer "B.Cu")
		(net "P5E_CPU1_P3_TX_BUF_C_DN<15>")
	)
	(segment
		(start 156.750004 -427.957996)
		(end 156.750004 -428.28972)
		(width 0.14224)
		(layer "In6.Cu")
		(net "P5E_CPU1_P3_TX_BUF_C_DN<15>")
	)
	(segment
		(start 155.788106 -424.256454)
		(end 155.788106 -427.497494)
		(width 0.14224)
		(layer "In6.Cu")
		(net "P5E_CPU1_P3_TX_BUF_C_DN<15>")
	)
	(segment
		(start 162.374326 -410.030168)
		(end 162.665156 -410.320998)
		(width 0.14224)
		(layer "In6.Cu")
		(net "P5E_CPU1_P3_TX_BUF_C_DN<15>")
	)
	(segment
		(start 162.665156 -410.320998)
		(end 162.665156 -413.14624)
		(width 0.14224)
		(layer "In6.Cu")
		(net "P5E_CPU1_P3_TX_BUF_C_DN<15>")
	)
	(segment
		(start 162.492944 -413.713676)
		(end 156.070046 -423.326306)
		(width 0.14224)
		(layer "In6.Cu")
		(net "P5E_CPU1_P3_TX_BUF_C_DN<15>")
	)
	(segment
		(start 155.788106 -427.497494)
		(end 156.121354 -427.830742)
		(width 0.14224)
		(layer "In6.Cu")
		(net "P5E_CPU1_P3_TX_BUF_C_DN<15>")
	)
	(segment
		(start 156.62275 -427.830742)
		(end 156.750004 -427.957996)
		(width 0.14224)
		(layer "In6.Cu")
		(net "P5E_CPU1_P3_TX_BUF_C_DN<15>")
	)
	(segment
		(start 162.665156 -413.14624)
		(end 162.492944 -413.713676)
		(width 0.14224)
		(layer "In6.Cu")
		(net "P5E_CPU1_P3_TX_BUF_C_DN<15>")
	)
	(segment
		(start 156.121354 -427.830742)
		(end 156.62275 -427.830742)
		(width 0.14224)
		(layer "In6.Cu")
		(net "P5E_CPU1_P3_TX_BUF_C_DN<15>")
	)
	(arc
		(start 156.070046 -423.326306)
		(mid 155.860066 -423.770462)
		(end 155.788106 -424.256454)
		(width 0.14224)
		(layer "In6.Cu")
		(net "P5E_CPU1_P3_TX_BUF_C_DN<15>")
	)
	(segment
		(start 159.285686 -408.784044)
		(end 159.581596 -409.079954)
		(width 0.12954)
		(layer "B.Cu")
		(net "P5E_CPU1_P3_TX_BUF_C_DN<14>")
	)
	(segment
		(start 159.581596 -409.079954)
		(end 159.581596 -409.759658)
		(width 0.12954)
		(layer "B.Cu")
		(net "P5E_CPU1_P3_TX_BUF_C_DN<14>")
	)
	(segment
		(start 159.581596 -409.759658)
		(end 159.311086 -410.030168)
		(width 0.12954)
		(layer "B.Cu")
		(net "P5E_CPU1_P3_TX_BUF_C_DN<14>")
	)
	(segment
		(start 159.311086 -410.030168)
		(end 159.601916 -410.320998)
		(width 0.14224)
		(layer "In6.Cu")
		(net "P5E_CPU1_P3_TX_BUF_C_DN<14>")
	)
	(segment
		(start 154.750008 -426.958252)
		(end 154.750008 -427.289976)
		(width 0.14224)
		(layer "In6.Cu")
		(net "P5E_CPU1_P3_TX_BUF_C_DN<14>")
	)
	(segment
		(start 159.601916 -413.417258)
		(end 153.976324 -423.942256)
		(width 0.14224)
		(layer "In6.Cu")
		(net "P5E_CPU1_P3_TX_BUF_C_DN<14>")
	)
	(segment
		(start 154.622754 -426.830998)
		(end 154.750008 -426.958252)
		(width 0.14224)
		(layer "In6.Cu")
		(net "P5E_CPU1_P3_TX_BUF_C_DN<14>")
	)
	(segment
		(start 159.601916 -410.320998)
		(end 159.601916 -413.417258)
		(width 0.14224)
		(layer "In6.Cu")
		(net "P5E_CPU1_P3_TX_BUF_C_DN<14>")
	)
	(segment
		(start 153.78811 -426.432218)
		(end 154.18689 -426.830998)
		(width 0.14224)
		(layer "In6.Cu")
		(net "P5E_CPU1_P3_TX_BUF_C_DN<14>")
	)
	(segment
		(start 153.78811 -424.69435)
		(end 153.78811 -426.432218)
		(width 0.14224)
		(layer "In6.Cu")
		(net "P5E_CPU1_P3_TX_BUF_C_DN<14>")
	)
	(segment
		(start 154.18689 -426.830998)
		(end 154.622754 -426.830998)
		(width 0.14224)
		(layer "In6.Cu")
		(net "P5E_CPU1_P3_TX_BUF_C_DN<14>")
	)
	(arc
		(start 153.976324 -423.942256)
		(mid 153.835858 -424.306701)
		(end 153.78811 -424.69435)
		(width 0.14224)
		(layer "In6.Cu")
		(net "P5E_CPU1_P3_TX_BUF_C_DN<14>")
	)
	(segment
		(start 156.222446 -408.784044)
		(end 156.518356 -409.079954)
		(width 0.12954)
		(layer "B.Cu")
		(net "P5E_CPU1_P3_TX_BUF_C_DN<13>")
	)
	(segment
		(start 156.518356 -409.759658)
		(end 156.247846 -410.030168)
		(width 0.12954)
		(layer "B.Cu")
		(net "P5E_CPU1_P3_TX_BUF_C_DN<13>")
	)
	(segment
		(start 156.518356 -409.079954)
		(end 156.518356 -409.759658)
		(width 0.12954)
		(layer "B.Cu")
		(net "P5E_CPU1_P3_TX_BUF_C_DN<13>")
	)
	(segment
		(start 151.788114 -424.671744)
		(end 151.788114 -427.497494)
		(width 0.14224)
		(layer "In6.Cu")
		(net "P5E_CPU1_P3_TX_BUF_C_DN<13>")
	)
	(segment
		(start 152.622758 -427.830742)
		(end 152.750012 -427.957996)
		(width 0.14224)
		(layer "In6.Cu")
		(net "P5E_CPU1_P3_TX_BUF_C_DN<13>")
	)
	(segment
		(start 156.52877 -413.083756)
		(end 156.103574 -414.110424)
		(width 0.14224)
		(layer "In6.Cu")
		(net "P5E_CPU1_P3_TX_BUF_C_DN<13>")
	)
	(segment
		(start 156.103574 -414.110424)
		(end 155.55595 -415.135314)
		(width 0.14224)
		(layer "In6.Cu")
		(net "P5E_CPU1_P3_TX_BUF_C_DN<13>")
	)
	(segment
		(start 155.55595 -415.135314)
		(end 151.956516 -423.825162)
		(width 0.14224)
		(layer "In6.Cu")
		(net "P5E_CPU1_P3_TX_BUF_C_DN<13>")
	)
	(segment
		(start 156.538676 -410.320998)
		(end 156.538676 -413.034734)
		(width 0.14224)
		(layer "In6.Cu")
		(net "P5E_CPU1_P3_TX_BUF_C_DN<13>")
	)
	(segment
		(start 156.52877 -413.083502)
		(end 156.52877 -413.083756)
		(width 0.14224)
		(layer "In6.Cu")
		(net "P5E_CPU1_P3_TX_BUF_C_DN<13>")
	)
	(segment
		(start 152.750012 -427.957996)
		(end 152.750012 -428.28972)
		(width 0.14224)
		(layer "In6.Cu")
		(net "P5E_CPU1_P3_TX_BUF_C_DN<13>")
	)
	(segment
		(start 156.247846 -410.030168)
		(end 156.538676 -410.320998)
		(width 0.14224)
		(layer "In6.Cu")
		(net "P5E_CPU1_P3_TX_BUF_C_DN<13>")
	)
	(segment
		(start 151.788114 -427.497494)
		(end 152.121362 -427.830742)
		(width 0.14224)
		(layer "In6.Cu")
		(net "P5E_CPU1_P3_TX_BUF_C_DN<13>")
	)
	(segment
		(start 152.121362 -427.830742)
		(end 152.622758 -427.830742)
		(width 0.14224)
		(layer "In6.Cu")
		(net "P5E_CPU1_P3_TX_BUF_C_DN<13>")
	)
	(arc
		(start 151.956516 -423.825162)
		(mid 151.830615 -424.24016)
		(end 151.788114 -424.671744)
		(width 0.14224)
		(layer "In6.Cu")
		(net "P5E_CPU1_P3_TX_BUF_C_DN<13>")
	)
	(arc
		(start 156.538676 -413.034734)
		(mid 156.536126 -413.059606)
		(end 156.52877 -413.083502)
		(width 0.14224)
		(layer "In6.Cu")
		(net "P5E_CPU1_P3_TX_BUF_C_DN<13>")
	)
	(segment
		(start 153.455116 -409.759658)
		(end 153.184606 -410.030168)
		(width 0.12954)
		(layer "B.Cu")
		(net "P5E_CPU1_P3_TX_BUF_C_DN<12>")
	)
	(segment
		(start 153.455116 -409.079954)
		(end 153.455116 -409.759658)
		(width 0.12954)
		(layer "B.Cu")
		(net "P5E_CPU1_P3_TX_BUF_C_DN<12>")
	)
	(segment
		(start 153.159206 -408.784044)
		(end 153.455116 -409.079954)
		(width 0.12954)
		(layer "B.Cu")
		(net "P5E_CPU1_P3_TX_BUF_C_DN<12>")
	)
	(segment
		(start 149.788118 -425.228512)
		(end 149.788118 -426.432218)
		(width 0.14224)
		(layer "In6.Cu")
		(net "P5E_CPU1_P3_TX_BUF_C_DN<12>")
	)
	(segment
		(start 150.186898 -426.830998)
		(end 150.622762 -426.830998)
		(width 0.14224)
		(layer "In6.Cu")
		(net "P5E_CPU1_P3_TX_BUF_C_DN<12>")
	)
	(segment
		(start 153.184606 -410.030168)
		(end 153.475436 -410.320998)
		(width 0.14224)
		(layer "In6.Cu")
		(net "P5E_CPU1_P3_TX_BUF_C_DN<12>")
	)
	(segment
		(start 153.475436 -410.320998)
		(end 153.475436 -413.028384)
		(width 0.14224)
		(layer "In6.Cu")
		(net "P5E_CPU1_P3_TX_BUF_C_DN<12>")
	)
	(segment
		(start 153.475436 -413.028384)
		(end 153.475182 -413.028384)
		(width 0.14224)
		(layer "In6.Cu")
		(net "P5E_CPU1_P3_TX_BUF_C_DN<12>")
	)
	(segment
		(start 153.458926 -413.138366)
		(end 150.466298 -423.00271)
		(width 0.14224)
		(layer "In6.Cu")
		(net "P5E_CPU1_P3_TX_BUF_C_DN<12>")
	)
	(segment
		(start 150.466298 -423.00271)
		(end 150.012654 -424.097958)
		(width 0.14224)
		(layer "In6.Cu")
		(net "P5E_CPU1_P3_TX_BUF_C_DN<12>")
	)
	(segment
		(start 150.622762 -426.830998)
		(end 150.750016 -426.958252)
		(width 0.14224)
		(layer "In6.Cu")
		(net "P5E_CPU1_P3_TX_BUF_C_DN<12>")
	)
	(segment
		(start 150.750016 -426.958252)
		(end 150.750016 -427.289976)
		(width 0.14224)
		(layer "In6.Cu")
		(net "P5E_CPU1_P3_TX_BUF_C_DN<12>")
	)
	(segment
		(start 149.788118 -426.432218)
		(end 150.186898 -426.830998)
		(width 0.14224)
		(layer "In6.Cu")
		(net "P5E_CPU1_P3_TX_BUF_C_DN<12>")
	)
	(arc
		(start 150.012654 -424.097958)
		(mid 149.84472 -424.652178)
		(end 149.788118 -425.228512)
		(width 0.14224)
		(layer "In6.Cu")
		(net "P5E_CPU1_P3_TX_BUF_C_DN<12>")
	)
	(arc
		(start 153.475182 -413.028384)
		(mid 153.471089 -413.08397)
		(end 153.458926 -413.138366)
		(width 0.14224)
		(layer "In6.Cu")
		(net "P5E_CPU1_P3_TX_BUF_C_DN<12>")
	)
	(segment
		(start 150.391876 -409.759658)
		(end 150.121366 -410.030168)
		(width 0.12954)
		(layer "B.Cu")
		(net "P5E_CPU1_P3_TX_BUF_C_DN<11>")
	)
	(segment
		(start 150.095966 -408.784044)
		(end 150.391876 -409.079954)
		(width 0.12954)
		(layer "B.Cu")
		(net "P5E_CPU1_P3_TX_BUF_C_DN<11>")
	)
	(segment
		(start 150.391876 -409.079954)
		(end 150.391876 -409.759658)
		(width 0.12954)
		(layer "B.Cu")
		(net "P5E_CPU1_P3_TX_BUF_C_DN<11>")
	)
	(segment
		(start 148.12137 -427.830742)
		(end 148.622766 -427.830742)
		(width 0.14224)
		(layer "In6.Cu")
		(net "P5E_CPU1_P3_TX_BUF_C_DN<11>")
	)
	(segment
		(start 148.622766 -427.830742)
		(end 148.75002 -427.957996)
		(width 0.14224)
		(layer "In6.Cu")
		(net "P5E_CPU1_P3_TX_BUF_C_DN<11>")
	)
	(segment
		(start 150.367746 -413.51327)
		(end 149.324568 -417.678616)
		(width 0.14224)
		(layer "In6.Cu")
		(net "P5E_CPU1_P3_TX_BUF_C_DN<11>")
	)
	(segment
		(start 149.324568 -417.678616)
		(end 149.324314 -417.678616)
		(width 0.14224)
		(layer "In6.Cu")
		(net "P5E_CPU1_P3_TX_BUF_C_DN<11>")
	)
	(segment
		(start 150.121366 -410.030168)
		(end 150.412196 -410.320998)
		(width 0.14224)
		(layer "In6.Cu")
		(net "P5E_CPU1_P3_TX_BUF_C_DN<11>")
	)
	(segment
		(start 147.788122 -424.113198)
		(end 147.788122 -427.497494)
		(width 0.14224)
		(layer "In6.Cu")
		(net "P5E_CPU1_P3_TX_BUF_C_DN<11>")
	)
	(segment
		(start 148.75002 -427.957996)
		(end 148.75002 -428.28972)
		(width 0.14224)
		(layer "In6.Cu")
		(net "P5E_CPU1_P3_TX_BUF_C_DN<11>")
	)
	(segment
		(start 150.412196 -410.320998)
		(end 150.412196 -413.154114)
		(width 0.14224)
		(layer "In6.Cu")
		(net "P5E_CPU1_P3_TX_BUF_C_DN<11>")
	)
	(segment
		(start 147.788122 -427.497494)
		(end 148.12137 -427.830742)
		(width 0.14224)
		(layer "In6.Cu")
		(net "P5E_CPU1_P3_TX_BUF_C_DN<11>")
	)
	(segment
		(start 149.324314 -417.678616)
		(end 147.861274 -423.520108)
		(width 0.14224)
		(layer "In6.Cu")
		(net "P5E_CPU1_P3_TX_BUF_C_DN<11>")
	)
	(arc
		(start 150.412196 -413.154114)
		(mid 150.401031 -413.335062)
		(end 150.367746 -413.51327)
		(width 0.14224)
		(layer "In6.Cu")
		(net "P5E_CPU1_P3_TX_BUF_C_DN<11>")
	)
	(arc
		(start 147.861274 -423.520108)
		(mid 147.806473 -423.814406)
		(end 147.788122 -424.113198)
		(width 0.14224)
		(layer "In6.Cu")
		(net "P5E_CPU1_P3_TX_BUF_C_DN<11>")
	)
	(segment
		(start 147.032726 -408.784044)
		(end 147.328636 -409.079954)
		(width 0.12954)
		(layer "B.Cu")
		(net "P5E_CPU1_P3_TX_BUF_C_DN<10>")
	)
	(segment
		(start 147.328636 -409.759658)
		(end 147.058126 -410.030168)
		(width 0.12954)
		(layer "B.Cu")
		(net "P5E_CPU1_P3_TX_BUF_C_DN<10>")
	)
	(segment
		(start 147.328636 -409.079954)
		(end 147.328636 -409.759658)
		(width 0.12954)
		(layer "B.Cu")
		(net "P5E_CPU1_P3_TX_BUF_C_DN<10>")
	)
	(segment
		(start 147.348956 -410.320998)
		(end 147.058126 -410.030168)
		(width 0.14224)
		(layer "In6.Cu")
		(net "P5E_CPU1_P3_TX_BUF_C_DN<10>")
	)
	(segment
		(start 145.788126 -423.749978)
		(end 146.49831 -418.956744)
		(width 0.14224)
		(layer "In6.Cu")
		(net "P5E_CPU1_P3_TX_BUF_C_DN<10>")
	)
	(segment
		(start 146.62277 -426.830998)
		(end 146.186906 -426.830998)
		(width 0.14224)
		(layer "In6.Cu")
		(net "P5E_CPU1_P3_TX_BUF_C_DN<10>")
	)
	(segment
		(start 146.650456 -417.933378)
		(end 146.650964 -417.933124)
		(width 0.14224)
		(layer "In6.Cu")
		(net "P5E_CPU1_P3_TX_BUF_C_DN<10>")
	)
	(segment
		(start 146.750024 -426.958252)
		(end 146.62277 -426.830998)
		(width 0.14224)
		(layer "In6.Cu")
		(net "P5E_CPU1_P3_TX_BUF_C_DN<10>")
	)
	(segment
		(start 146.186906 -426.830998)
		(end 145.788126 -426.432218)
		(width 0.14224)
		(layer "In6.Cu")
		(net "P5E_CPU1_P3_TX_BUF_C_DN<10>")
	)
	(segment
		(start 146.650964 -417.933124)
		(end 147.348956 -413.22752)
		(width 0.14224)
		(layer "In6.Cu")
		(net "P5E_CPU1_P3_TX_BUF_C_DN<10>")
	)
	(segment
		(start 145.788126 -426.432218)
		(end 145.788126 -423.749978)
		(width 0.14224)
		(layer "In6.Cu")
		(net "P5E_CPU1_P3_TX_BUF_C_DN<10>")
	)
	(segment
		(start 147.348956 -413.22752)
		(end 147.348956 -410.320998)
		(width 0.14224)
		(layer "In6.Cu")
		(net "P5E_CPU1_P3_TX_BUF_C_DN<10>")
	)
	(segment
		(start 146.49831 -418.956744)
		(end 146.498818 -418.956236)
		(width 0.14224)
		(layer "In6.Cu")
		(net "P5E_CPU1_P3_TX_BUF_C_DN<10>")
	)
	(segment
		(start 146.498818 -418.956236)
		(end 146.650456 -417.933378)
		(width 0.14224)
		(layer "In6.Cu")
		(net "P5E_CPU1_P3_TX_BUF_C_DN<10>")
	)
	(segment
		(start 146.750024 -427.289976)
		(end 146.750024 -426.958252)
		(width 0.14224)
		(layer "In6.Cu")
		(net "P5E_CPU1_P3_TX_BUF_C_DN<10>")
	)
	(segment
		(start 116.696236 -409.079954)
		(end 116.696236 -409.759658)
		(width 0.12954)
		(layer "B.Cu")
		(net "P5E_CPU1_P3_TX_BUF_C_DN<0>")
	)
	(segment
		(start 116.400326 -408.784044)
		(end 116.696236 -409.079954)
		(width 0.12954)
		(layer "B.Cu")
		(net "P5E_CPU1_P3_TX_BUF_C_DN<0>")
	)
	(segment
		(start 116.696236 -409.759658)
		(end 116.425726 -410.030168)
		(width 0.12954)
		(layer "B.Cu")
		(net "P5E_CPU1_P3_TX_BUF_C_DN<0>")
	)
	(segment
		(start 119.907558 -417.964874)
		(end 119.907812 -417.96462)
		(width 0.14224)
		(layer "In6.Cu")
		(net "P5E_CPU1_P3_TX_BUF_C_DN<0>")
	)
	(segment
		(start 125.622558 -426.830998)
		(end 125.749812 -426.958252)
		(width 0.14224)
		(layer "In6.Cu")
		(net "P5E_CPU1_P3_TX_BUF_C_DN<0>")
	)
	(segment
		(start 124.395738 -426.387514)
		(end 124.839222 -426.830998)
		(width 0.14224)
		(layer "In6.Cu")
		(net "P5E_CPU1_P3_TX_BUF_C_DN<0>")
	)
	(segment
		(start 116.425726 -410.030168)
		(end 116.716556 -410.320998)
		(width 0.14224)
		(layer "In6.Cu")
		(net "P5E_CPU1_P3_TX_BUF_C_DN<0>")
	)
	(segment
		(start 123.76531 -421.280336)
		(end 124.395738 -426.387514)
		(width 0.14224)
		(layer "In6.Cu")
		(net "P5E_CPU1_P3_TX_BUF_C_DN<0>")
	)
	(segment
		(start 123.293886 -420.515288)
		(end 123.76531 -421.280336)
		(width 0.14224)
		(layer "In6.Cu")
		(net "P5E_CPU1_P3_TX_BUF_C_DN<0>")
	)
	(segment
		(start 119.907812 -417.96462)
		(end 120.331484 -418.535358)
		(width 0.14224)
		(layer "In6.Cu")
		(net "P5E_CPU1_P3_TX_BUF_C_DN<0>")
	)
	(segment
		(start 124.839222 -426.830998)
		(end 125.622558 -426.830998)
		(width 0.14224)
		(layer "In6.Cu")
		(net "P5E_CPU1_P3_TX_BUF_C_DN<0>")
	)
	(segment
		(start 125.749812 -426.958252)
		(end 125.749812 -427.289976)
		(width 0.14224)
		(layer "In6.Cu")
		(net "P5E_CPU1_P3_TX_BUF_C_DN<0>")
	)
	(segment
		(start 116.716556 -410.320998)
		(end 116.716556 -413.404304)
		(width 0.14224)
		(layer "In6.Cu")
		(net "P5E_CPU1_P3_TX_BUF_C_DN<0>")
	)
	(segment
		(start 120.331484 -418.535358)
		(end 123.293886 -420.515288)
		(width 0.14224)
		(layer "In6.Cu")
		(net "P5E_CPU1_P3_TX_BUF_C_DN<0>")
	)
	(segment
		(start 116.870226 -413.87014)
		(end 119.907558 -417.964874)
		(width 0.14224)
		(layer "In6.Cu")
		(net "P5E_CPU1_P3_TX_BUF_C_DN<0>")
	)
	(arc
		(start 116.716556 -413.404304)
		(mid 116.755929 -413.649579)
		(end 116.870226 -413.87014)
		(width 0.14224)
		(layer "In6.Cu")
		(net "P5E_CPU1_P3_TX_BUF_C_DN<0>")
	)
	(segment
		(start 125.10262 -391.488676)
		(end 125.0315 -391.559796)
		(width 0.1016)
		(layer "F.Cu")
		(net "P5E_CPU1_P3_RX_BUF_DP<9>")
	)
	(segment
		(start 125.018038 -391.281158)
		(end 125.10262 -391.36574)
		(width 0.1016)
		(layer "F.Cu")
		(net "P5E_CPU1_P3_RX_BUF_DP<9>")
	)
	(segment
		(start 125.284738 -392.977116)
		(end 125.577854 -392.977116)
		(width 0.1016)
		(layer "F.Cu")
		(net "P5E_CPU1_P3_RX_BUF_DP<9>")
	)
	(segment
		(start 125.716538 -393.1158)
		(end 125.716538 -393.292838)
		(width 0.1016)
		(layer "F.Cu")
		(net "P5E_CPU1_P3_RX_BUF_DP<9>")
	)
	(segment
		(start 125.0315 -392.723878)
		(end 125.284738 -392.977116)
		(width 0.1016)
		(layer "F.Cu")
		(net "P5E_CPU1_P3_RX_BUF_DP<9>")
	)
	(segment
		(start 125.577854 -392.977116)
		(end 125.716538 -393.1158)
		(width 0.1016)
		(layer "F.Cu")
		(net "P5E_CPU1_P3_RX_BUF_DP<9>")
	)
	(segment
		(start 125.0315 -391.559796)
		(end 125.0315 -392.723878)
		(width 0.1016)
		(layer "F.Cu")
		(net "P5E_CPU1_P3_RX_BUF_DP<9>")
	)
	(segment
		(start 125.10262 -391.36574)
		(end 125.10262 -391.488676)
		(width 0.1016)
		(layer "F.Cu")
		(net "P5E_CPU1_P3_RX_BUF_DP<9>")
	)
	(segment
		(start 144.53362 -413.935418)
		(end 144.567656 -413.220154)
		(width 0.14224)
		(layer "In13.Cu")
		(net "P5E_CPU1_P3_RX_BUF_DP<9>")
	)
	(segment
		(start 144.567656 -413.220154)
		(end 144.567656 -411.799278)
		(width 0.14224)
		(layer "In13.Cu")
		(net "P5E_CPU1_P3_RX_BUF_DP<9>")
	)
	(segment
		(start 144.404842 -419.51402)
		(end 144.425416 -419.087554)
		(width 0.14224)
		(layer "In13.Cu")
		(net "P5E_CPU1_P3_RX_BUF_DP<9>")
	)
	(segment
		(start 143.173196 -407.53538)
		(end 143.036036 -407.39822)
		(width 0.14224)
		(layer "In13.Cu")
		(net "P5E_CPU1_P3_RX_BUF_DP<9>")
	)
	(segment
		(start 141.833346 -405.574754)
		(end 141.761718 -405.545036)
		(width 0.14224)
		(layer "In13.Cu")
		(net "P5E_CPU1_P3_RX_BUF_DP<9>")
	)
	(segment
		(start 144.64411 -414.505648)
		(end 144.66443 -414.079182)
		(width 0.14224)
		(layer "In13.Cu")
		(net "P5E_CPU1_P3_RX_BUF_DP<9>")
	)
	(segment
		(start 144.458944 -418.38753)
		(end 144.479264 -417.961064)
		(width 0.14224)
		(layer "In13.Cu")
		(net "P5E_CPU1_P3_RX_BUF_DP<9>")
	)
	(segment
		(start 144.456404 -415.564574)
		(end 144.500346 -414.636204)
		(width 0.14224)
		(layer "In13.Cu")
		(net "P5E_CPU1_P3_RX_BUF_DP<9>")
	)
	(segment
		(start 144.66443 -414.079182)
		(end 144.533874 -413.935672)
		(width 0.14224)
		(layer "In13.Cu")
		(net "P5E_CPU1_P3_RX_BUF_DP<9>")
	)
	(segment
		(start 144.500346 -414.636204)
		(end 144.64411 -414.505648)
		(width 0.14224)
		(layer "In13.Cu")
		(net "P5E_CPU1_P3_RX_BUF_DP<9>")
	)
	(segment
		(start 144.750028 -434.289962)
		(end 144.750028 -434.618638)
		(width 0.14224)
		(layer "In13.Cu")
		(net "P5E_CPU1_P3_RX_BUF_DP<9>")
	)
	(segment
		(start 144.348708 -417.817554)
		(end 144.369028 -417.391342)
		(width 0.14224)
		(layer "In13.Cu")
		(net "P5E_CPU1_P3_RX_BUF_DP<9>")
	)
	(segment
		(start 143.147034 -410.902658)
		(end 143.036036 -410.736542)
		(width 0.14224)
		(layer "In13.Cu")
		(net "P5E_CPU1_P3_RX_BUF_DP<9>")
	)
	(segment
		(start 142.83055 -405.92883)
		(end 142.569184 -405.667464)
		(width 0.14224)
		(layer "In13.Cu")
		(net "P5E_CPU1_P3_RX_BUF_DP<9>")
	)
	(segment
		(start 126.356618 -397.380206)
		(end 126.05512 -397.078708)
		(width 0.14224)
		(layer "In13.Cu")
		(net "P5E_CPU1_P3_RX_BUF_DP<9>")
	)
	(segment
		(start 144.533112 -416.834574)
		(end 144.402556 -416.691064)
		(width 0.14224)
		(layer "In13.Cu")
		(net "P5E_CPU1_P3_RX_BUF_DP<9>")
	)
	(segment
		(start 125.25756 -396.228316)
		(end 125.25756 -395.854428)
		(width 0.14224)
		(layer "In13.Cu")
		(net "P5E_CPU1_P3_RX_BUF_DP<9>")
	)
	(segment
		(start 144.512792 -417.26104)
		(end 144.533112 -416.834574)
		(width 0.14224)
		(layer "In13.Cu")
		(net "P5E_CPU1_P3_RX_BUF_DP<9>")
	)
	(segment
		(start 144.185894 -411.333188)
		(end 143.147034 -410.902658)
		(width 0.14224)
		(layer "In13.Cu")
		(net "P5E_CPU1_P3_RX_BUF_DP<9>")
	)
	(segment
		(start 144.261078 -419.644576)
		(end 144.404842 -419.51402)
		(width 0.14224)
		(layer "In13.Cu")
		(net "P5E_CPU1_P3_RX_BUF_DP<9>")
	)
	(segment
		(start 140.681964 -402.806154)
		(end 128.312164 -399.053304)
		(width 0.14224)
		(layer "In13.Cu")
		(net "P5E_CPU1_P3_RX_BUF_DP<9>")
	)
	(segment
		(start 126.05512 -397.078708)
		(end 126.05512 -396.884652)
		(width 0.14224)
		(layer "In13.Cu")
		(net "P5E_CPU1_P3_RX_BUF_DP<9>")
	)
	(segment
		(start 126.85268 -397.682212)
		(end 126.550674 -397.380206)
		(width 0.14224)
		(layer "In13.Cu")
		(net "P5E_CPU1_P3_RX_BUF_DP<9>")
	)
	(segment
		(start 144.479264 -417.961064)
		(end 144.348708 -417.817554)
		(width 0.14224)
		(layer "In13.Cu")
		(net "P5E_CPU1_P3_RX_BUF_DP<9>")
	)
	(segment
		(start 144.533874 -413.935672)
		(end 144.53362 -413.935418)
		(width 0.14224)
		(layer "In13.Cu")
		(net "P5E_CPU1_P3_RX_BUF_DP<9>")
	)
	(segment
		(start 125.559058 -396.582646)
		(end 125.294898 -396.318486)
		(width 0.14224)
		(layer "In13.Cu")
		(net "P5E_CPU1_P3_RX_BUF_DP<9>")
	)
	(segment
		(start 126.05512 -396.884652)
		(end 125.753114 -396.582646)
		(width 0.14224)
		(layer "In13.Cu")
		(net "P5E_CPU1_P3_RX_BUF_DP<9>")
	)
	(segment
		(start 127.607314 -398.630902)
		(end 126.85268 -397.876268)
		(width 0.14224)
		(layer "In13.Cu")
		(net "P5E_CPU1_P3_RX_BUF_DP<9>")
	)
	(segment
		(start 144.07642 -422.401746)
		(end 144.179544 -421.355266)
		(width 0.14224)
		(layer "In13.Cu")
		(net "P5E_CPU1_P3_RX_BUF_DP<9>")
	)
	(segment
		(start 144.402556 -416.691064)
		(end 144.422622 -416.264852)
		(width 0.14224)
		(layer "In13.Cu")
		(net "P5E_CPU1_P3_RX_BUF_DP<9>")
	)
	(segment
		(start 144.375124 -434.756814)
		(end 144.07642 -434.45811)
		(width 0.14224)
		(layer "In13.Cu")
		(net "P5E_CPU1_P3_RX_BUF_DP<9>")
	)
	(segment
		(start 141.761718 -405.545036)
		(end 141.57706 -405.360378)
		(width 0.14224)
		(layer "In13.Cu")
		(net "P5E_CPU1_P3_RX_BUF_DP<9>")
	)
	(segment
		(start 143.036036 -410.736542)
		(end 143.036036 -409.22702)
		(width 0.14224)
		(layer "In13.Cu")
		(net "P5E_CPU1_P3_RX_BUF_DP<9>")
	)
	(segment
		(start 144.586706 -415.708084)
		(end 144.456404 -415.564574)
		(width 0.14224)
		(layer "In13.Cu")
		(net "P5E_CPU1_P3_RX_BUF_DP<9>")
	)
	(segment
		(start 141.57706 -405.360378)
		(end 141.504416 -405.184864)
		(width 0.14224)
		(layer "In13.Cu")
		(net "P5E_CPU1_P3_RX_BUF_DP<9>")
	)
	(segment
		(start 143.036036 -408.09926)
		(end 143.173196 -407.9621)
		(width 0.14224)
		(layer "In13.Cu")
		(net "P5E_CPU1_P3_RX_BUF_DP<9>")
	)
	(segment
		(start 144.611852 -434.756814)
		(end 144.375124 -434.756814)
		(width 0.14224)
		(layer "In13.Cu")
		(net "P5E_CPU1_P3_RX_BUF_DP<9>")
	)
	(segment
		(start 141.504416 -405.184864)
		(end 141.504416 -403.436582)
		(width 0.14224)
		(layer "In13.Cu")
		(net "P5E_CPU1_P3_RX_BUF_DP<9>")
	)
	(segment
		(start 125.25756 -393.138406)
		(end 125.38456 -393.011406)
		(width 0.14224)
		(layer "In13.Cu")
		(net "P5E_CPU1_P3_RX_BUF_DP<9>")
	)
	(segment
		(start 144.56664 -416.13455)
		(end 144.586706 -415.708084)
		(width 0.14224)
		(layer "In13.Cu")
		(net "P5E_CPU1_P3_RX_BUF_DP<9>")
	)
	(segment
		(start 143.173196 -407.9621)
		(end 143.173196 -407.53538)
		(width 0.14224)
		(layer "In13.Cu")
		(net "P5E_CPU1_P3_RX_BUF_DP<9>")
	)
	(segment
		(start 144.179544 -421.355266)
		(end 144.261078 -419.644576)
		(width 0.14224)
		(layer "In13.Cu")
		(net "P5E_CPU1_P3_RX_BUF_DP<9>")
	)
	(segment
		(start 144.750028 -434.618638)
		(end 144.611852 -434.756814)
		(width 0.14224)
		(layer "In13.Cu")
		(net "P5E_CPU1_P3_RX_BUF_DP<9>")
	)
	(segment
		(start 142.569184 -405.667464)
		(end 142.345664 -405.574754)
		(width 0.14224)
		(layer "In13.Cu")
		(net "P5E_CPU1_P3_RX_BUF_DP<9>")
	)
	(segment
		(start 143.036036 -406.424892)
		(end 142.83055 -405.92883)
		(width 0.14224)
		(layer "In13.Cu")
		(net "P5E_CPU1_P3_RX_BUF_DP<9>")
	)
	(segment
		(start 144.369028 -417.391342)
		(end 144.512792 -417.26104)
		(width 0.14224)
		(layer "In13.Cu")
		(net "P5E_CPU1_P3_RX_BUF_DP<9>")
	)
	(segment
		(start 125.589538 -393.011406)
		(end 125.716538 -393.138406)
		(width 0.14224)
		(layer "In13.Cu")
		(net "P5E_CPU1_P3_RX_BUF_DP<9>")
	)
	(segment
		(start 143.036036 -408.52598)
		(end 143.036036 -408.09926)
		(width 0.14224)
		(layer "In13.Cu")
		(net "P5E_CPU1_P3_RX_BUF_DP<9>")
	)
	(segment
		(start 141.504416 -403.436582)
		(end 141.2367 -403.036024)
		(width 0.14224)
		(layer "In13.Cu")
		(net "P5E_CPU1_P3_RX_BUF_DP<9>")
	)
	(segment
		(start 143.173196 -408.66314)
		(end 143.036036 -408.52598)
		(width 0.14224)
		(layer "In13.Cu")
		(net "P5E_CPU1_P3_RX_BUF_DP<9>")
	)
	(segment
		(start 126.550674 -397.380206)
		(end 126.356618 -397.380206)
		(width 0.14224)
		(layer "In13.Cu")
		(net "P5E_CPU1_P3_RX_BUF_DP<9>")
	)
	(segment
		(start 144.29486 -418.944044)
		(end 144.31518 -418.517832)
		(width 0.14224)
		(layer "In13.Cu")
		(net "P5E_CPU1_P3_RX_BUF_DP<9>")
	)
	(segment
		(start 125.25756 -395.854428)
		(end 125.39472 -395.717268)
		(width 0.14224)
		(layer "In13.Cu")
		(net "P5E_CPU1_P3_RX_BUF_DP<9>")
	)
	(segment
		(start 144.31518 -418.517832)
		(end 144.458944 -418.38753)
		(width 0.14224)
		(layer "In13.Cu")
		(net "P5E_CPU1_P3_RX_BUF_DP<9>")
	)
	(segment
		(start 125.39472 -395.290548)
		(end 125.25756 -395.153388)
		(width 0.14224)
		(layer "In13.Cu")
		(net "P5E_CPU1_P3_RX_BUF_DP<9>")
	)
	(segment
		(start 144.07642 -434.45811)
		(end 144.07642 -422.401746)
		(width 0.14224)
		(layer "In13.Cu")
		(net "P5E_CPU1_P3_RX_BUF_DP<9>")
	)
	(segment
		(start 144.422622 -416.264852)
		(end 144.56664 -416.13455)
		(width 0.14224)
		(layer "In13.Cu")
		(net "P5E_CPU1_P3_RX_BUF_DP<9>")
	)
	(segment
		(start 143.036036 -407.39822)
		(end 143.036036 -406.424892)
		(width 0.14224)
		(layer "In13.Cu")
		(net "P5E_CPU1_P3_RX_BUF_DP<9>")
	)
	(segment
		(start 125.25756 -395.153388)
		(end 125.25756 -393.138406)
		(width 0.14224)
		(layer "In13.Cu")
		(net "P5E_CPU1_P3_RX_BUF_DP<9>")
	)
	(segment
		(start 141.2367 -403.036024)
		(end 140.681964 -402.806154)
		(width 0.14224)
		(layer "In13.Cu")
		(net "P5E_CPU1_P3_RX_BUF_DP<9>")
	)
	(segment
		(start 144.425416 -419.087554)
		(end 144.29486 -418.944044)
		(width 0.14224)
		(layer "In13.Cu")
		(net "P5E_CPU1_P3_RX_BUF_DP<9>")
	)
	(segment
		(start 144.413224 -411.516322)
		(end 144.318736 -411.422088)
		(width 0.14224)
		(layer "In13.Cu")
		(net "P5E_CPU1_P3_RX_BUF_DP<9>")
	)
	(segment
		(start 125.753114 -396.582646)
		(end 125.559058 -396.582646)
		(width 0.14224)
		(layer "In13.Cu")
		(net "P5E_CPU1_P3_RX_BUF_DP<9>")
	)
	(segment
		(start 126.85268 -397.876268)
		(end 126.85268 -397.682212)
		(width 0.14224)
		(layer "In13.Cu")
		(net "P5E_CPU1_P3_RX_BUF_DP<9>")
	)
	(segment
		(start 142.345664 -405.574754)
		(end 141.833346 -405.574754)
		(width 0.14224)
		(layer "In13.Cu")
		(net "P5E_CPU1_P3_RX_BUF_DP<9>")
	)
	(segment
		(start 125.39472 -395.717268)
		(end 125.39472 -395.290548)
		(width 0.14224)
		(layer "In13.Cu")
		(net "P5E_CPU1_P3_RX_BUF_DP<9>")
	)
	(segment
		(start 143.036036 -409.22702)
		(end 143.173196 -409.08986)
		(width 0.14224)
		(layer "In13.Cu")
		(net "P5E_CPU1_P3_RX_BUF_DP<9>")
	)
	(segment
		(start 143.173196 -409.08986)
		(end 143.173196 -408.66314)
		(width 0.14224)
		(layer "In13.Cu")
		(net "P5E_CPU1_P3_RX_BUF_DP<9>")
	)
	(segment
		(start 144.567656 -411.799278)
		(end 144.511014 -411.662372)
		(width 0.14224)
		(layer "In13.Cu")
		(net "P5E_CPU1_P3_RX_BUF_DP<9>")
	)
	(segment
		(start 125.716538 -393.138406)
		(end 125.716538 -393.292838)
		(width 0.14224)
		(layer "In13.Cu")
		(net "P5E_CPU1_P3_RX_BUF_DP<9>")
	)
	(segment
		(start 125.38456 -393.011406)
		(end 125.589538 -393.011406)
		(width 0.14224)
		(layer "In13.Cu")
		(net "P5E_CPU1_P3_RX_BUF_DP<9>")
	)
	(arc
		(start 144.318736 -411.422088)
		(mid 144.256682 -411.371116)
		(end 144.185894 -411.333188)
		(width 0.14224)
		(layer "In13.Cu")
		(net "P5E_CPU1_P3_RX_BUF_DP<9>")
	)
	(arc
		(start 125.294898 -396.318486)
		(mid 125.267255 -396.277116)
		(end 125.25756 -396.228316)
		(width 0.14224)
		(layer "In13.Cu")
		(net "P5E_CPU1_P3_RX_BUF_DP<9>")
	)
	(arc
		(start 128.312164 -399.053304)
		(mid 127.933684 -398.885578)
		(end 127.607314 -398.630902)
		(width 0.14224)
		(layer "In13.Cu")
		(net "P5E_CPU1_P3_RX_BUF_DP<9>")
	)
	(arc
		(start 144.511014 -411.662372)
		(mid 144.46928 -411.58455)
		(end 144.413224 -411.516322)
		(width 0.14224)
		(layer "In13.Cu")
		(net "P5E_CPU1_P3_RX_BUF_DP<9>")
	)
	(segment
		(start 123.90247 -391.36574)
		(end 123.90247 -391.488676)
		(width 0.1016)
		(layer "F.Cu")
		(net "P5E_CPU1_P3_RX_BUF_DP<8>")
	)
	(segment
		(start 123.817888 -391.281158)
		(end 123.90247 -391.36574)
		(width 0.1016)
		(layer "F.Cu")
		(net "P5E_CPU1_P3_RX_BUF_DP<8>")
	)
	(segment
		(start 124.067062 -392.977116)
		(end 124.377704 -392.977116)
		(width 0.1016)
		(layer "F.Cu")
		(net "P5E_CPU1_P3_RX_BUF_DP<8>")
	)
	(segment
		(start 123.813824 -392.723878)
		(end 124.067062 -392.977116)
		(width 0.1016)
		(layer "F.Cu")
		(net "P5E_CPU1_P3_RX_BUF_DP<8>")
	)
	(segment
		(start 124.516642 -393.116054)
		(end 124.516642 -393.292838)
		(width 0.1016)
		(layer "F.Cu")
		(net "P5E_CPU1_P3_RX_BUF_DP<8>")
	)
	(segment
		(start 123.813824 -391.577322)
		(end 123.813824 -392.723878)
		(width 0.1016)
		(layer "F.Cu")
		(net "P5E_CPU1_P3_RX_BUF_DP<8>")
	)
	(segment
		(start 123.90247 -391.488676)
		(end 123.813824 -391.577322)
		(width 0.1016)
		(layer "F.Cu")
		(net "P5E_CPU1_P3_RX_BUF_DP<8>")
	)
	(segment
		(start 124.377704 -392.977116)
		(end 124.516642 -393.116054)
		(width 0.1016)
		(layer "F.Cu")
		(net "P5E_CPU1_P3_RX_BUF_DP<8>")
	)
	(segment
		(start 142.076424 -421.165274)
		(end 142.076424 -433.458112)
		(width 0.14224)
		(layer "In13.Cu")
		(net "P5E_CPU1_P3_RX_BUF_DP<8>")
	)
	(segment
		(start 124.19711 -392.989562)
		(end 124.057664 -393.129008)
		(width 0.14224)
		(layer "In13.Cu")
		(net "P5E_CPU1_P3_RX_BUF_DP<8>")
	)
	(segment
		(start 139.972796 -408.900376)
		(end 140.109956 -409.037536)
		(width 0.14224)
		(layer "In13.Cu")
		(net "P5E_CPU1_P3_RX_BUF_DP<8>")
	)
	(segment
		(start 125.652784 -398.321784)
		(end 125.954536 -398.623282)
		(width 0.14224)
		(layer "In13.Cu")
		(net "P5E_CPU1_P3_RX_BUF_DP<8>")
	)
	(segment
		(start 124.057664 -393.129008)
		(end 124.057664 -394.471144)
		(width 0.14224)
		(layer "In13.Cu")
		(net "P5E_CPU1_P3_RX_BUF_DP<8>")
	)
	(segment
		(start 125.156976 -397.825722)
		(end 125.350778 -397.825722)
		(width 0.14224)
		(layer "In13.Cu")
		(net "P5E_CPU1_P3_RX_BUF_DP<8>")
	)
	(segment
		(start 141.715998 -415.379662)
		(end 141.866112 -415.502598)
		(width 0.14224)
		(layer "In13.Cu")
		(net "P5E_CPU1_P3_RX_BUF_DP<8>")
	)
	(segment
		(start 126.450344 -398.925288)
		(end 126.450344 -399.11909)
		(width 0.14224)
		(layer "In13.Cu")
		(net "P5E_CPU1_P3_RX_BUF_DP<8>")
	)
	(segment
		(start 141.729714 -414.118044)
		(end 141.771624 -414.542986)
		(width 0.14224)
		(layer "In13.Cu")
		(net "P5E_CPU1_P3_RX_BUF_DP<8>")
	)
	(segment
		(start 142.03299 -417.479988)
		(end 142.053818 -417.906454)
		(width 0.14224)
		(layer "In13.Cu")
		(net "P5E_CPU1_P3_RX_BUF_DP<8>")
	)
	(segment
		(start 140.109956 -409.464256)
		(end 139.972796 -409.601416)
		(width 0.14224)
		(layer "In13.Cu")
		(net "P5E_CPU1_P3_RX_BUF_DP<8>")
	)
	(segment
		(start 125.350778 -397.825722)
		(end 125.652784 -398.127728)
		(width 0.14224)
		(layer "In13.Cu")
		(net "P5E_CPU1_P3_RX_BUF_DP<8>")
	)
	(segment
		(start 125.652784 -398.127728)
		(end 125.652784 -398.321784)
		(width 0.14224)
		(layer "In13.Cu")
		(net "P5E_CPU1_P3_RX_BUF_DP<8>")
	)
	(segment
		(start 124.359162 -397.028162)
		(end 124.553218 -397.028162)
		(width 0.14224)
		(layer "In13.Cu")
		(net "P5E_CPU1_P3_RX_BUF_DP<8>")
	)
	(segment
		(start 141.771624 -414.542986)
		(end 141.648434 -414.692846)
		(width 0.14224)
		(layer "In13.Cu")
		(net "P5E_CPU1_P3_RX_BUF_DP<8>")
	)
	(segment
		(start 140.270484 -410.980382)
		(end 141.178788 -411.356556)
		(width 0.14224)
		(layer "In13.Cu")
		(net "P5E_CPU1_P3_RX_BUF_DP<8>")
	)
	(segment
		(start 138.698478 -405.545036)
		(end 138.770106 -405.574754)
		(width 0.14224)
		(layer "In13.Cu")
		(net "P5E_CPU1_P3_RX_BUF_DP<8>")
	)
	(segment
		(start 138.441176 -405.184864)
		(end 138.51382 -405.360378)
		(width 0.14224)
		(layer "In13.Cu")
		(net "P5E_CPU1_P3_RX_BUF_DP<8>")
	)
	(segment
		(start 141.648434 -414.692846)
		(end 141.715998 -415.379662)
		(width 0.14224)
		(layer "In13.Cu")
		(net "P5E_CPU1_P3_RX_BUF_DP<8>")
	)
	(segment
		(start 138.51382 -405.360378)
		(end 138.698478 -405.545036)
		(width 0.14224)
		(layer "In13.Cu")
		(net "P5E_CPU1_P3_RX_BUF_DP<8>")
	)
	(segment
		(start 142.750032 -433.61864)
		(end 142.750032 -433.289964)
		(width 0.14224)
		(layer "In13.Cu")
		(net "P5E_CPU1_P3_RX_BUF_DP<8>")
	)
	(segment
		(start 124.553218 -397.028162)
		(end 124.855224 -397.330168)
		(width 0.14224)
		(layer "In13.Cu")
		(net "P5E_CPU1_P3_RX_BUF_DP<8>")
	)
	(segment
		(start 124.855224 -397.524224)
		(end 125.156976 -397.825722)
		(width 0.14224)
		(layer "In13.Cu")
		(net "P5E_CPU1_P3_RX_BUF_DP<8>")
	)
	(segment
		(start 141.178788 -411.356556)
		(end 141.316964 -411.494732)
		(width 0.14224)
		(layer "In13.Cu")
		(net "P5E_CPU1_P3_RX_BUF_DP<8>")
	)
	(segment
		(start 139.454636 -405.646128)
		(end 139.788392 -405.979884)
		(width 0.14224)
		(layer "In13.Cu")
		(net "P5E_CPU1_P3_RX_BUF_DP<8>")
	)
	(segment
		(start 139.972796 -409.601416)
		(end 139.972796 -410.574744)
		(width 0.14224)
		(layer "In13.Cu")
		(net "P5E_CPU1_P3_RX_BUF_DP<8>")
	)
	(segment
		(start 124.194824 -395.736064)
		(end 124.194824 -396.162784)
		(width 0.14224)
		(layer "In13.Cu")
		(net "P5E_CPU1_P3_RX_BUF_DP<8>")
	)
	(segment
		(start 126.893828 -399.562574)
		(end 127.070358 -399.668238)
		(width 0.14224)
		(layer "In13.Cu")
		(net "P5E_CPU1_P3_RX_BUF_DP<8>")
	)
	(segment
		(start 124.194824 -394.608304)
		(end 124.194824 -395.035024)
		(width 0.14224)
		(layer "In13.Cu")
		(net "P5E_CPU1_P3_RX_BUF_DP<8>")
	)
	(segment
		(start 139.972796 -406.424892)
		(end 139.972796 -407.772616)
		(width 0.14224)
		(layer "In13.Cu")
		(net "P5E_CPU1_P3_RX_BUF_DP<8>")
	)
	(segment
		(start 142.053818 -417.906454)
		(end 141.923516 -418.050218)
		(width 0.14224)
		(layer "In13.Cu")
		(net "P5E_CPU1_P3_RX_BUF_DP<8>")
	)
	(segment
		(start 124.057664 -394.471144)
		(end 124.194824 -394.608304)
		(width 0.14224)
		(layer "In13.Cu")
		(net "P5E_CPU1_P3_RX_BUF_DP<8>")
	)
	(segment
		(start 124.095002 -396.764002)
		(end 124.359162 -397.028162)
		(width 0.14224)
		(layer "In13.Cu")
		(net "P5E_CPU1_P3_RX_BUF_DP<8>")
	)
	(segment
		(start 138.038078 -402.995638)
		(end 138.441176 -403.39899)
		(width 0.14224)
		(layer "In13.Cu")
		(net "P5E_CPU1_P3_RX_BUF_DP<8>")
	)
	(segment
		(start 124.057664 -396.299944)
		(end 124.057664 -396.673832)
		(width 0.14224)
		(layer "In13.Cu")
		(net "P5E_CPU1_P3_RX_BUF_DP<8>")
	)
	(segment
		(start 124.377196 -392.989562)
		(end 124.19711 -392.989562)
		(width 0.14224)
		(layer "In13.Cu")
		(net "P5E_CPU1_P3_RX_BUF_DP<8>")
	)
	(segment
		(start 141.5796 -413.994854)
		(end 141.729714 -414.118044)
		(width 0.14224)
		(layer "In13.Cu")
		(net "P5E_CPU1_P3_RX_BUF_DP<8>")
	)
	(segment
		(start 141.908022 -415.92754)
		(end 141.784832 -416.0774)
		(width 0.14224)
		(layer "In13.Cu")
		(net "P5E_CPU1_P3_RX_BUF_DP<8>")
	)
	(segment
		(start 126.450344 -399.11909)
		(end 126.893828 -399.562574)
		(width 0.14224)
		(layer "In13.Cu")
		(net "P5E_CPU1_P3_RX_BUF_DP<8>")
	)
	(segment
		(start 141.868144 -416.923728)
		(end 141.888972 -417.349686)
		(width 0.14224)
		(layer "In13.Cu")
		(net "P5E_CPU1_P3_RX_BUF_DP<8>")
	)
	(segment
		(start 124.516642 -393.129008)
		(end 124.377196 -392.989562)
		(width 0.14224)
		(layer "In13.Cu")
		(net "P5E_CPU1_P3_RX_BUF_DP<8>")
	)
	(segment
		(start 141.866112 -415.502598)
		(end 141.908022 -415.92754)
		(width 0.14224)
		(layer "In13.Cu")
		(net "P5E_CPU1_P3_RX_BUF_DP<8>")
	)
	(segment
		(start 139.282424 -405.574754)
		(end 139.454636 -405.646128)
		(width 0.14224)
		(layer "In13.Cu")
		(net "P5E_CPU1_P3_RX_BUF_DP<8>")
	)
	(segment
		(start 138.441176 -403.39899)
		(end 138.441176 -405.184864)
		(width 0.14224)
		(layer "In13.Cu")
		(net "P5E_CPU1_P3_RX_BUF_DP<8>")
	)
	(segment
		(start 139.972796 -408.473656)
		(end 139.972796 -408.900376)
		(width 0.14224)
		(layer "In13.Cu")
		(net "P5E_CPU1_P3_RX_BUF_DP<8>")
	)
	(segment
		(start 127.070358 -399.668238)
		(end 138.038078 -402.995638)
		(width 0.14224)
		(layer "In13.Cu")
		(net "P5E_CPU1_P3_RX_BUF_DP<8>")
	)
	(segment
		(start 126.148338 -398.623282)
		(end 126.450344 -398.925288)
		(width 0.14224)
		(layer "In13.Cu")
		(net "P5E_CPU1_P3_RX_BUF_DP<8>")
	)
	(segment
		(start 141.504416 -413.23133)
		(end 141.5796 -413.994854)
		(width 0.14224)
		(layer "In13.Cu")
		(net "P5E_CPU1_P3_RX_BUF_DP<8>")
	)
	(segment
		(start 124.194824 -396.162784)
		(end 124.057664 -396.299944)
		(width 0.14224)
		(layer "In13.Cu")
		(net "P5E_CPU1_P3_RX_BUF_DP<8>")
	)
	(segment
		(start 138.770106 -405.574754)
		(end 139.282424 -405.574754)
		(width 0.14224)
		(layer "In13.Cu")
		(net "P5E_CPU1_P3_RX_BUF_DP<8>")
	)
	(segment
		(start 124.194824 -395.035024)
		(end 124.057664 -395.172184)
		(width 0.14224)
		(layer "In13.Cu")
		(net "P5E_CPU1_P3_RX_BUF_DP<8>")
	)
	(segment
		(start 142.611856 -433.756816)
		(end 142.750032 -433.61864)
		(width 0.14224)
		(layer "In13.Cu")
		(net "P5E_CPU1_P3_RX_BUF_DP<8>")
	)
	(segment
		(start 125.954536 -398.623282)
		(end 126.148338 -398.623282)
		(width 0.14224)
		(layer "In13.Cu")
		(net "P5E_CPU1_P3_RX_BUF_DP<8>")
	)
	(segment
		(start 141.923516 -418.050218)
		(end 142.076424 -421.165274)
		(width 0.14224)
		(layer "In13.Cu")
		(net "P5E_CPU1_P3_RX_BUF_DP<8>")
	)
	(segment
		(start 139.972796 -407.772616)
		(end 140.109956 -407.909776)
		(width 0.14224)
		(layer "In13.Cu")
		(net "P5E_CPU1_P3_RX_BUF_DP<8>")
	)
	(segment
		(start 142.076424 -433.458112)
		(end 142.375128 -433.756816)
		(width 0.14224)
		(layer "In13.Cu")
		(net "P5E_CPU1_P3_RX_BUF_DP<8>")
	)
	(segment
		(start 124.516642 -393.292838)
		(end 124.516642 -393.129008)
		(width 0.14224)
		(layer "In13.Cu")
		(net "P5E_CPU1_P3_RX_BUF_DP<8>")
	)
	(segment
		(start 124.855224 -397.330168)
		(end 124.855224 -397.524224)
		(width 0.14224)
		(layer "In13.Cu")
		(net "P5E_CPU1_P3_RX_BUF_DP<8>")
	)
	(segment
		(start 140.109956 -408.336496)
		(end 139.972796 -408.473656)
		(width 0.14224)
		(layer "In13.Cu")
		(net "P5E_CPU1_P3_RX_BUF_DP<8>")
	)
	(segment
		(start 142.375128 -433.756816)
		(end 142.611856 -433.756816)
		(width 0.14224)
		(layer "In13.Cu")
		(net "P5E_CPU1_P3_RX_BUF_DP<8>")
	)
	(segment
		(start 139.788392 -405.979884)
		(end 139.972796 -406.424892)
		(width 0.14224)
		(layer "In13.Cu")
		(net "P5E_CPU1_P3_RX_BUF_DP<8>")
	)
	(segment
		(start 140.067792 -410.803852)
		(end 140.19149 -410.92755)
		(width 0.14224)
		(layer "In13.Cu")
		(net "P5E_CPU1_P3_RX_BUF_DP<8>")
	)
	(segment
		(start 141.316964 -411.494732)
		(end 141.504416 -411.947614)
		(width 0.14224)
		(layer "In13.Cu")
		(net "P5E_CPU1_P3_RX_BUF_DP<8>")
	)
	(segment
		(start 140.109956 -409.037536)
		(end 140.109956 -409.464256)
		(width 0.14224)
		(layer "In13.Cu")
		(net "P5E_CPU1_P3_RX_BUF_DP<8>")
	)
	(segment
		(start 141.784832 -416.0774)
		(end 141.868144 -416.923728)
		(width 0.14224)
		(layer "In13.Cu")
		(net "P5E_CPU1_P3_RX_BUF_DP<8>")
	)
	(segment
		(start 141.888972 -417.349686)
		(end 142.03299 -417.479988)
		(width 0.14224)
		(layer "In13.Cu")
		(net "P5E_CPU1_P3_RX_BUF_DP<8>")
	)
	(segment
		(start 139.972796 -410.574744)
		(end 140.067792 -410.803852)
		(width 0.14224)
		(layer "In13.Cu")
		(net "P5E_CPU1_P3_RX_BUF_DP<8>")
	)
	(segment
		(start 140.19149 -410.92755)
		(end 140.270484 -410.980382)
		(width 0.14224)
		(layer "In13.Cu")
		(net "P5E_CPU1_P3_RX_BUF_DP<8>")
	)
	(segment
		(start 141.504416 -411.947614)
		(end 141.504416 -413.23133)
		(width 0.14224)
		(layer "In13.Cu")
		(net "P5E_CPU1_P3_RX_BUF_DP<8>")
	)
	(segment
		(start 140.109956 -407.909776)
		(end 140.109956 -408.336496)
		(width 0.14224)
		(layer "In13.Cu")
		(net "P5E_CPU1_P3_RX_BUF_DP<8>")
	)
	(segment
		(start 124.057664 -395.172184)
		(end 124.057664 -395.598904)
		(width 0.14224)
		(layer "In13.Cu")
		(net "P5E_CPU1_P3_RX_BUF_DP<8>")
	)
	(segment
		(start 124.057664 -395.598904)
		(end 124.194824 -395.736064)
		(width 0.14224)
		(layer "In13.Cu")
		(net "P5E_CPU1_P3_RX_BUF_DP<8>")
	)
	(arc
		(start 124.057664 -396.673832)
		(mid 124.06737 -396.722627)
		(end 124.095002 -396.764002)
		(width 0.14224)
		(layer "In13.Cu")
		(net "P5E_CPU1_P3_RX_BUF_DP<8>")
	)
	(segment
		(start 122.867166 -392.977116)
		(end 123.177808 -392.977116)
		(width 0.1016)
		(layer "F.Cu")
		(net "P5E_CPU1_P3_RX_BUF_DP<7>")
	)
	(segment
		(start 122.702574 -391.36574)
		(end 122.702574 -391.488676)
		(width 0.1016)
		(layer "F.Cu")
		(net "P5E_CPU1_P3_RX_BUF_DP<7>")
	)
	(segment
		(start 122.702574 -391.488676)
		(end 122.613928 -391.577322)
		(width 0.1016)
		(layer "F.Cu")
		(net "P5E_CPU1_P3_RX_BUF_DP<7>")
	)
	(segment
		(start 123.177808 -392.977116)
		(end 123.316492 -393.1158)
		(width 0.1016)
		(layer "F.Cu")
		(net "P5E_CPU1_P3_RX_BUF_DP<7>")
	)
	(segment
		(start 122.613928 -392.723878)
		(end 122.867166 -392.977116)
		(width 0.1016)
		(layer "F.Cu")
		(net "P5E_CPU1_P3_RX_BUF_DP<7>")
	)
	(segment
		(start 122.613928 -391.577322)
		(end 122.613928 -392.723878)
		(width 0.1016)
		(layer "F.Cu")
		(net "P5E_CPU1_P3_RX_BUF_DP<7>")
	)
	(segment
		(start 123.316492 -393.1158)
		(end 123.316492 -393.292838)
		(width 0.1016)
		(layer "F.Cu")
		(net "P5E_CPU1_P3_RX_BUF_DP<7>")
	)
	(segment
		(start 122.617992 -391.281158)
		(end 122.702574 -391.36574)
		(width 0.1016)
		(layer "F.Cu")
		(net "P5E_CPU1_P3_RX_BUF_DP<7>")
	)
	(segment
		(start 122.99696 -392.989562)
		(end 123.177046 -392.989562)
		(width 0.14224)
		(layer "In13.Cu")
		(net "P5E_CPU1_P3_RX_BUF_DP<7>")
	)
	(segment
		(start 122.857514 -393.129008)
		(end 122.99696 -392.989562)
		(width 0.14224)
		(layer "In13.Cu")
		(net "P5E_CPU1_P3_RX_BUF_DP<7>")
	)
	(segment
		(start 122.994674 -394.587984)
		(end 122.857514 -394.450824)
		(width 0.14224)
		(layer "In13.Cu")
		(net "P5E_CPU1_P3_RX_BUF_DP<7>")
	)
	(segment
		(start 138.018012 -411.347412)
		(end 137.268204 -411.037278)
		(width 0.14224)
		(layer "In13.Cu")
		(net "P5E_CPU1_P3_RX_BUF_DP<7>")
	)
	(segment
		(start 123.159012 -397.38808)
		(end 122.894852 -397.12392)
		(width 0.14224)
		(layer "In13.Cu")
		(net "P5E_CPU1_P3_RX_BUF_DP<7>")
	)
	(segment
		(start 123.655074 -397.884142)
		(end 123.655074 -397.690086)
		(width 0.14224)
		(layer "In13.Cu")
		(net "P5E_CPU1_P3_RX_BUF_DP<7>")
	)
	(segment
		(start 138.847068 -416.082226)
		(end 138.964162 -415.92754)
		(width 0.14224)
		(layer "In13.Cu")
		(net "P5E_CPU1_P3_RX_BUF_DP<7>")
	)
	(segment
		(start 136.219184 -405.574754)
		(end 135.706866 -405.574754)
		(width 0.14224)
		(layer "In13.Cu")
		(net "P5E_CPU1_P3_RX_BUF_DP<7>")
	)
	(segment
		(start 136.909556 -410.452316)
		(end 136.909556 -409.476702)
		(width 0.14224)
		(layer "In13.Cu")
		(net "P5E_CPU1_P3_RX_BUF_DP<7>")
	)
	(segment
		(start 122.857514 -397.03375)
		(end 122.857514 -396.279624)
		(width 0.14224)
		(layer "In13.Cu")
		(net "P5E_CPU1_P3_RX_BUF_DP<7>")
	)
	(segment
		(start 122.994674 -395.014704)
		(end 122.994674 -394.587984)
		(width 0.14224)
		(layer "In13.Cu")
		(net "P5E_CPU1_P3_RX_BUF_DP<7>")
	)
	(segment
		(start 135.635238 -405.545036)
		(end 135.495792 -405.40559)
		(width 0.14224)
		(layer "In13.Cu")
		(net "P5E_CPU1_P3_RX_BUF_DP<7>")
	)
	(segment
		(start 135.377936 -405.12111)
		(end 135.377936 -403.742144)
		(width 0.14224)
		(layer "In13.Cu")
		(net "P5E_CPU1_P3_RX_BUF_DP<7>")
	)
	(segment
		(start 137.168382 -410.961586)
		(end 136.992868 -410.738574)
		(width 0.14224)
		(layer "In13.Cu")
		(net "P5E_CPU1_P3_RX_BUF_DP<7>")
	)
	(segment
		(start 132.955792 -402.577046)
		(end 131.690364 -402.053298)
		(width 0.14224)
		(layer "In13.Cu")
		(net "P5E_CPU1_P3_RX_BUF_DP<7>")
	)
	(segment
		(start 131.690364 -402.053298)
		(end 126.407926 -400.450558)
		(width 0.14224)
		(layer "In13.Cu")
		(net "P5E_CPU1_P3_RX_BUF_DP<7>")
	)
	(segment
		(start 122.857514 -396.279624)
		(end 122.994674 -396.142464)
		(width 0.14224)
		(layer "In13.Cu")
		(net "P5E_CPU1_P3_RX_BUF_DP<7>")
	)
	(segment
		(start 125.250194 -399.285206)
		(end 124.948188 -398.9832)
		(width 0.14224)
		(layer "In13.Cu")
		(net "P5E_CPU1_P3_RX_BUF_DP<7>")
	)
	(segment
		(start 122.857514 -394.450824)
		(end 122.857514 -393.129008)
		(width 0.14224)
		(layer "In13.Cu")
		(net "P5E_CPU1_P3_RX_BUF_DP<7>")
	)
	(segment
		(start 138.905742 -415.50463)
		(end 138.751056 -415.387536)
		(width 0.14224)
		(layer "In13.Cu")
		(net "P5E_CPU1_P3_RX_BUF_DP<7>")
	)
	(segment
		(start 136.725152 -405.979884)
		(end 136.391396 -405.646128)
		(width 0.14224)
		(layer "In13.Cu")
		(net "P5E_CPU1_P3_RX_BUF_DP<7>")
	)
	(segment
		(start 136.909556 -407.647902)
		(end 136.909556 -406.424892)
		(width 0.14224)
		(layer "In13.Cu")
		(net "P5E_CPU1_P3_RX_BUF_DP<7>")
	)
	(segment
		(start 136.909556 -408.775662)
		(end 136.909556 -408.348942)
		(width 0.14224)
		(layer "In13.Cu")
		(net "P5E_CPU1_P3_RX_BUF_DP<7>")
	)
	(segment
		(start 138.751056 -415.387536)
		(end 138.69289 -414.96488)
		(width 0.14224)
		(layer "In13.Cu")
		(net "P5E_CPU1_P3_RX_BUF_DP<7>")
	)
	(segment
		(start 133.529578 -402.665946)
		(end 133.134862 -402.502624)
		(width 0.14224)
		(layer "In13.Cu")
		(net "P5E_CPU1_P3_RX_BUF_DP<7>")
	)
	(segment
		(start 138.964162 -415.92754)
		(end 138.905742 -415.50463)
		(width 0.14224)
		(layer "In13.Cu")
		(net "P5E_CPU1_P3_RX_BUF_DP<7>")
	)
	(segment
		(start 139.749784 -434.618638)
		(end 139.611608 -434.756814)
		(width 0.14224)
		(layer "In13.Cu")
		(net "P5E_CPU1_P3_RX_BUF_DP<7>")
	)
	(segment
		(start 125.250194 -399.479262)
		(end 125.250194 -399.285206)
		(width 0.14224)
		(layer "In13.Cu")
		(net "P5E_CPU1_P3_RX_BUF_DP<7>")
	)
	(segment
		(start 124.452634 -398.487646)
		(end 124.150628 -398.18564)
		(width 0.14224)
		(layer "In13.Cu")
		(net "P5E_CPU1_P3_RX_BUF_DP<7>")
	)
	(segment
		(start 133.603746 -402.84527)
		(end 133.529578 -402.665946)
		(width 0.14224)
		(layer "In13.Cu")
		(net "P5E_CPU1_P3_RX_BUF_DP<7>")
	)
	(segment
		(start 133.134862 -402.502624)
		(end 132.955792 -402.577046)
		(width 0.14224)
		(layer "In13.Cu")
		(net "P5E_CPU1_P3_RX_BUF_DP<7>")
	)
	(segment
		(start 136.909556 -408.348942)
		(end 137.046716 -408.211782)
		(width 0.14224)
		(layer "In13.Cu")
		(net "P5E_CPU1_P3_RX_BUF_DP<7>")
	)
	(segment
		(start 122.857514 -395.578584)
		(end 122.857514 -395.151864)
		(width 0.14224)
		(layer "In13.Cu")
		(net "P5E_CPU1_P3_RX_BUF_DP<7>")
	)
	(segment
		(start 139.076176 -417.74491)
		(end 138.847068 -416.082226)
		(width 0.14224)
		(layer "In13.Cu")
		(net "P5E_CPU1_P3_RX_BUF_DP<7>")
	)
	(segment
		(start 134.422642 -403.008338)
		(end 134.023354 -403.008338)
		(width 0.14224)
		(layer "In13.Cu")
		(net "P5E_CPU1_P3_RX_BUF_DP<7>")
	)
	(segment
		(start 137.046716 -409.339542)
		(end 137.046716 -408.912822)
		(width 0.14224)
		(layer "In13.Cu")
		(net "P5E_CPU1_P3_RX_BUF_DP<7>")
	)
	(segment
		(start 123.177046 -392.989562)
		(end 123.316492 -393.129008)
		(width 0.14224)
		(layer "In13.Cu")
		(net "P5E_CPU1_P3_RX_BUF_DP<7>")
	)
	(segment
		(start 139.749784 -434.289962)
		(end 139.749784 -434.618638)
		(width 0.14224)
		(layer "In13.Cu")
		(net "P5E_CPU1_P3_RX_BUF_DP<7>")
	)
	(segment
		(start 139.611608 -434.756814)
		(end 139.37488 -434.756814)
		(width 0.14224)
		(layer "In13.Cu")
		(net "P5E_CPU1_P3_RX_BUF_DP<7>")
	)
	(segment
		(start 139.076176 -434.45811)
		(end 139.076176 -417.74491)
		(width 0.14224)
		(layer "In13.Cu")
		(net "P5E_CPU1_P3_RX_BUF_DP<7>")
	)
	(segment
		(start 122.994674 -395.715744)
		(end 122.857514 -395.578584)
		(width 0.14224)
		(layer "In13.Cu")
		(net "P5E_CPU1_P3_RX_BUF_DP<7>")
	)
	(segment
		(start 123.353068 -397.38808)
		(end 123.159012 -397.38808)
		(width 0.14224)
		(layer "In13.Cu")
		(net "P5E_CPU1_P3_RX_BUF_DP<7>")
	)
	(segment
		(start 123.956826 -398.18564)
		(end 123.655074 -397.884142)
		(width 0.14224)
		(layer "In13.Cu")
		(net "P5E_CPU1_P3_RX_BUF_DP<7>")
	)
	(segment
		(start 138.69289 -414.96488)
		(end 138.809984 -414.810448)
		(width 0.14224)
		(layer "In13.Cu")
		(net "P5E_CPU1_P3_RX_BUF_DP<7>")
	)
	(segment
		(start 124.452634 -398.681702)
		(end 124.452634 -398.487646)
		(width 0.14224)
		(layer "In13.Cu")
		(net "P5E_CPU1_P3_RX_BUF_DP<7>")
	)
	(segment
		(start 137.046716 -408.211782)
		(end 137.046716 -407.785062)
		(width 0.14224)
		(layer "In13.Cu")
		(net "P5E_CPU1_P3_RX_BUF_DP<7>")
	)
	(segment
		(start 136.391396 -405.646128)
		(end 136.219184 -405.574754)
		(width 0.14224)
		(layer "In13.Cu")
		(net "P5E_CPU1_P3_RX_BUF_DP<7>")
	)
	(segment
		(start 137.046716 -408.912822)
		(end 136.909556 -408.775662)
		(width 0.14224)
		(layer "In13.Cu")
		(net "P5E_CPU1_P3_RX_BUF_DP<7>")
	)
	(segment
		(start 124.754386 -398.9832)
		(end 124.452634 -398.681702)
		(width 0.14224)
		(layer "In13.Cu")
		(net "P5E_CPU1_P3_RX_BUF_DP<7>")
	)
	(segment
		(start 138.809984 -414.810448)
		(end 138.751818 -414.387284)
		(width 0.14224)
		(layer "In13.Cu")
		(net "P5E_CPU1_P3_RX_BUF_DP<7>")
	)
	(segment
		(start 133.974586 -402.998686)
		(end 133.603746 -402.84527)
		(width 0.14224)
		(layer "In13.Cu")
		(net "P5E_CPU1_P3_RX_BUF_DP<7>")
	)
	(segment
		(start 137.046716 -407.785062)
		(end 136.909556 -407.647902)
		(width 0.14224)
		(layer "In13.Cu")
		(net "P5E_CPU1_P3_RX_BUF_DP<7>")
	)
	(segment
		(start 135.019542 -403.205188)
		(end 134.654798 -403.054312)
		(width 0.14224)
		(layer "In13.Cu")
		(net "P5E_CPU1_P3_RX_BUF_DP<7>")
	)
	(segment
		(start 136.909556 -409.476702)
		(end 137.046716 -409.339542)
		(width 0.14224)
		(layer "In13.Cu")
		(net "P5E_CPU1_P3_RX_BUF_DP<7>")
	)
	(segment
		(start 138.596878 -414.27019)
		(end 138.441176 -413.140652)
		(width 0.14224)
		(layer "In13.Cu")
		(net "P5E_CPU1_P3_RX_BUF_DP<7>")
	)
	(segment
		(start 138.441176 -413.140652)
		(end 138.441176 -412.1277)
		(width 0.14224)
		(layer "In13.Cu")
		(net "P5E_CPU1_P3_RX_BUF_DP<7>")
	)
	(segment
		(start 136.909556 -406.424892)
		(end 136.725152 -405.979884)
		(width 0.14224)
		(layer "In13.Cu")
		(net "P5E_CPU1_P3_RX_BUF_DP<7>")
	)
	(segment
		(start 124.948188 -398.9832)
		(end 124.754386 -398.9832)
		(width 0.14224)
		(layer "In13.Cu")
		(net "P5E_CPU1_P3_RX_BUF_DP<7>")
	)
	(segment
		(start 123.655074 -397.690086)
		(end 123.353068 -397.38808)
		(width 0.14224)
		(layer "In13.Cu")
		(net "P5E_CPU1_P3_RX_BUF_DP<7>")
	)
	(segment
		(start 123.316492 -393.129008)
		(end 123.316492 -393.292838)
		(width 0.14224)
		(layer "In13.Cu")
		(net "P5E_CPU1_P3_RX_BUF_DP<7>")
	)
	(segment
		(start 122.994674 -396.142464)
		(end 122.994674 -395.715744)
		(width 0.14224)
		(layer "In13.Cu")
		(net "P5E_CPU1_P3_RX_BUF_DP<7>")
	)
	(segment
		(start 139.37488 -434.756814)
		(end 139.076176 -434.45811)
		(width 0.14224)
		(layer "In13.Cu")
		(net "P5E_CPU1_P3_RX_BUF_DP<7>")
	)
	(segment
		(start 135.706866 -405.574754)
		(end 135.635238 -405.545036)
		(width 0.14224)
		(layer "In13.Cu")
		(net "P5E_CPU1_P3_RX_BUF_DP<7>")
	)
	(segment
		(start 125.942852 -400.17192)
		(end 125.250194 -399.479262)
		(width 0.14224)
		(layer "In13.Cu")
		(net "P5E_CPU1_P3_RX_BUF_DP<7>")
	)
	(segment
		(start 124.150628 -398.18564)
		(end 123.956826 -398.18564)
		(width 0.14224)
		(layer "In13.Cu")
		(net "P5E_CPU1_P3_RX_BUF_DP<7>")
	)
	(segment
		(start 138.751818 -414.387284)
		(end 138.596878 -414.27019)
		(width 0.14224)
		(layer "In13.Cu")
		(net "P5E_CPU1_P3_RX_BUF_DP<7>")
	)
	(segment
		(start 138.400536 -411.903672)
		(end 138.300206 -411.637988)
		(width 0.14224)
		(layer "In13.Cu")
		(net "P5E_CPU1_P3_RX_BUF_DP<7>")
	)
	(segment
		(start 122.857514 -395.151864)
		(end 122.994674 -395.014704)
		(width 0.14224)
		(layer "In13.Cu")
		(net "P5E_CPU1_P3_RX_BUF_DP<7>")
	)
	(arc
		(start 135.495792 -405.40559)
		(mid 135.408581 -405.275069)
		(end 135.377936 -405.12111)
		(width 0.14224)
		(layer "In13.Cu")
		(net "P5E_CPU1_P3_RX_BUF_DP<7>")
	)
	(arc
		(start 136.992868 -410.738574)
		(mid 136.958276 -410.685107)
		(end 136.934448 -410.626052)
		(width 0.14224)
		(layer "In13.Cu")
		(net "P5E_CPU1_P3_RX_BUF_DP<7>")
	)
	(arc
		(start 138.300206 -411.637988)
		(mid 138.189223 -411.463447)
		(end 138.018012 -411.347412)
		(width 0.14224)
		(layer "In13.Cu")
		(net "P5E_CPU1_P3_RX_BUF_DP<7>")
	)
	(arc
		(start 136.934448 -410.626052)
		(mid 136.915766 -410.540077)
		(end 136.909556 -410.452316)
		(width 0.14224)
		(layer "In13.Cu")
		(net "P5E_CPU1_P3_RX_BUF_DP<7>")
	)
	(arc
		(start 126.407926 -400.450558)
		(mid 126.158206 -400.339917)
		(end 125.942852 -400.17192)
		(width 0.14224)
		(layer "In13.Cu")
		(net "P5E_CPU1_P3_RX_BUF_DP<7>")
	)
	(arc
		(start 137.268204 -411.037278)
		(mid 137.213425 -411.005852)
		(end 137.168382 -410.961586)
		(width 0.14224)
		(layer "In13.Cu")
		(net "P5E_CPU1_P3_RX_BUF_DP<7>")
	)
	(arc
		(start 135.377936 -403.742144)
		(mid 135.280286 -403.419255)
		(end 135.019542 -403.205188)
		(width 0.14224)
		(layer "In13.Cu")
		(net "P5E_CPU1_P3_RX_BUF_DP<7>")
	)
	(arc
		(start 134.654798 -403.054312)
		(mid 134.540979 -403.019915)
		(end 134.422642 -403.008338)
		(width 0.14224)
		(layer "In13.Cu")
		(net "P5E_CPU1_P3_RX_BUF_DP<7>")
	)
	(arc
		(start 134.023354 -403.008338)
		(mid 133.998501 -403.005892)
		(end 133.974586 -402.998686)
		(width 0.14224)
		(layer "In13.Cu")
		(net "P5E_CPU1_P3_RX_BUF_DP<7>")
	)
	(arc
		(start 122.894852 -397.12392)
		(mid 122.867209 -397.08255)
		(end 122.857514 -397.03375)
		(width 0.14224)
		(layer "In13.Cu")
		(net "P5E_CPU1_P3_RX_BUF_DP<7>")
	)
	(arc
		(start 138.441176 -412.1277)
		(mid 138.431025 -412.013841)
		(end 138.400536 -411.903672)
		(width 0.14224)
		(layer "In13.Cu")
		(net "P5E_CPU1_P3_RX_BUF_DP<7>")
	)
	(segment
		(start 121.422668 -391.568432)
		(end 121.422668 -392.723878)
		(width 0.1016)
		(layer "F.Cu")
		(net "P5E_CPU1_P3_RX_BUF_DP<6>")
	)
	(segment
		(start 121.977658 -392.977116)
		(end 122.116596 -393.116054)
		(width 0.1016)
		(layer "F.Cu")
		(net "P5E_CPU1_P3_RX_BUF_DP<6>")
	)
	(segment
		(start 121.417842 -391.281158)
		(end 121.502424 -391.36574)
		(width 0.1016)
		(layer "F.Cu")
		(net "P5E_CPU1_P3_RX_BUF_DP<6>")
	)
	(segment
		(start 121.502424 -391.36574)
		(end 121.502424 -391.488676)
		(width 0.1016)
		(layer "F.Cu")
		(net "P5E_CPU1_P3_RX_BUF_DP<6>")
	)
	(segment
		(start 121.502424 -391.488676)
		(end 121.422668 -391.568432)
		(width 0.1016)
		(layer "F.Cu")
		(net "P5E_CPU1_P3_RX_BUF_DP<6>")
	)
	(segment
		(start 122.116596 -393.116054)
		(end 122.116596 -393.292838)
		(width 0.1016)
		(layer "F.Cu")
		(net "P5E_CPU1_P3_RX_BUF_DP<6>")
	)
	(segment
		(start 121.422668 -392.723878)
		(end 121.675906 -392.977116)
		(width 0.1016)
		(layer "F.Cu")
		(net "P5E_CPU1_P3_RX_BUF_DP<6>")
	)
	(segment
		(start 121.675906 -392.977116)
		(end 121.977658 -392.977116)
		(width 0.1016)
		(layer "F.Cu")
		(net "P5E_CPU1_P3_RX_BUF_DP<6>")
	)
	(segment
		(start 121.794778 -395.061694)
		(end 121.794778 -394.634974)
		(width 0.14224)
		(layer "In13.Cu")
		(net "P5E_CPU1_P3_RX_BUF_DP<6>")
	)
	(segment
		(start 121.794778 -396.189454)
		(end 121.794778 -395.762734)
		(width 0.14224)
		(layer "In13.Cu")
		(net "P5E_CPU1_P3_RX_BUF_DP<6>")
	)
	(segment
		(start 135.977376 -414.863026)
		(end 135.417306 -413.510476)
		(width 0.14224)
		(layer "In13.Cu")
		(net "P5E_CPU1_P3_RX_BUF_DP<6>")
	)
	(segment
		(start 132.314696 -403.807676)
		(end 132.105908 -403.405086)
		(width 0.14224)
		(layer "In13.Cu")
		(net "P5E_CPU1_P3_RX_BUF_DP<6>")
	)
	(segment
		(start 135.14832 -411.396688)
		(end 134.076948 -410.952188)
		(width 0.14224)
		(layer "In13.Cu")
		(net "P5E_CPU1_P3_RX_BUF_DP<6>")
	)
	(segment
		(start 136.245854 -415.51098)
		(end 136.320022 -415.331656)
		(width 0.14224)
		(layer "In13.Cu")
		(net "P5E_CPU1_P3_RX_BUF_DP<6>")
	)
	(segment
		(start 121.794778 -394.634974)
		(end 121.657618 -394.497814)
		(width 0.14224)
		(layer "In13.Cu")
		(net "P5E_CPU1_P3_RX_BUF_DP<6>")
	)
	(segment
		(start 122.950732 -398.577308)
		(end 122.756676 -398.577308)
		(width 0.14224)
		(layer "In13.Cu")
		(net "P5E_CPU1_P3_RX_BUF_DP<6>")
	)
	(segment
		(start 133.895084 -410.763212)
		(end 133.846316 -410.645864)
		(width 0.14224)
		(layer "In13.Cu")
		(net "P5E_CPU1_P3_RX_BUF_DP<6>")
	)
	(segment
		(start 133.846316 -408.67076)
		(end 133.846316 -408.24404)
		(width 0.14224)
		(layer "In13.Cu")
		(net "P5E_CPU1_P3_RX_BUF_DP<6>")
	)
	(segment
		(start 135.377936 -411.626304)
		(end 135.14832 -411.396688)
		(width 0.14224)
		(layer "In13.Cu")
		(net "P5E_CPU1_P3_RX_BUF_DP<6>")
	)
	(segment
		(start 133.846316 -407.543)
		(end 133.846316 -406.424892)
		(width 0.14224)
		(layer "In13.Cu")
		(net "P5E_CPU1_P3_RX_BUF_DP<6>")
	)
	(segment
		(start 136.408922 -415.905188)
		(end 136.245854 -415.51098)
		(width 0.14224)
		(layer "In13.Cu")
		(net "P5E_CPU1_P3_RX_BUF_DP<6>")
	)
	(segment
		(start 133.846316 -406.424892)
		(end 133.661912 -405.979884)
		(width 0.14224)
		(layer "In13.Cu")
		(net "P5E_CPU1_P3_RX_BUF_DP<6>")
	)
	(segment
		(start 137.611612 -433.756816)
		(end 137.374884 -433.756816)
		(width 0.14224)
		(layer "In13.Cu")
		(net "P5E_CPU1_P3_RX_BUF_DP<6>")
	)
	(segment
		(start 121.657618 -396.326614)
		(end 121.794778 -396.189454)
		(width 0.14224)
		(layer "In13.Cu")
		(net "P5E_CPU1_P3_RX_BUF_DP<6>")
	)
	(segment
		(start 121.657618 -395.198854)
		(end 121.794778 -395.061694)
		(width 0.14224)
		(layer "In13.Cu")
		(net "P5E_CPU1_P3_RX_BUF_DP<6>")
	)
	(segment
		(start 133.155944 -405.574754)
		(end 132.741416 -405.574754)
		(width 0.14224)
		(layer "In13.Cu")
		(net "P5E_CPU1_P3_RX_BUF_DP<6>")
	)
	(segment
		(start 121.97715 -392.989562)
		(end 122.116596 -393.129008)
		(width 0.14224)
		(layer "In13.Cu")
		(net "P5E_CPU1_P3_RX_BUF_DP<6>")
	)
	(segment
		(start 123.252738 -398.879314)
		(end 122.950732 -398.577308)
		(width 0.14224)
		(layer "In13.Cu")
		(net "P5E_CPU1_P3_RX_BUF_DP<6>")
	)
	(segment
		(start 124.625862 -400.252438)
		(end 124.431806 -400.252438)
		(width 0.14224)
		(layer "In13.Cu")
		(net "P5E_CPU1_P3_RX_BUF_DP<6>")
	)
	(segment
		(start 133.846316 -410.645864)
		(end 133.846316 -409.3718)
		(width 0.14224)
		(layer "In13.Cu")
		(net "P5E_CPU1_P3_RX_BUF_DP<6>")
	)
	(segment
		(start 122.153172 -397.779748)
		(end 121.959116 -397.779748)
		(width 0.14224)
		(layer "In13.Cu")
		(net "P5E_CPU1_P3_RX_BUF_DP<6>")
	)
	(segment
		(start 137.749788 -433.289964)
		(end 137.749788 -433.61864)
		(width 0.14224)
		(layer "In13.Cu")
		(net "P5E_CPU1_P3_RX_BUF_DP<6>")
	)
	(segment
		(start 134.017766 -410.912564)
		(end 133.895084 -410.763212)
		(width 0.14224)
		(layer "In13.Cu")
		(net "P5E_CPU1_P3_RX_BUF_DP<6>")
	)
	(segment
		(start 137.07618 -417.51631)
		(end 136.6774 -416.553142)
		(width 0.14224)
		(layer "In13.Cu")
		(net "P5E_CPU1_P3_RX_BUF_DP<6>")
	)
	(segment
		(start 136.751568 -416.373818)
		(end 136.5885 -415.979356)
		(width 0.14224)
		(layer "In13.Cu")
		(net "P5E_CPU1_P3_RX_BUF_DP<6>")
	)
	(segment
		(start 121.657618 -395.625574)
		(end 121.657618 -395.198854)
		(width 0.14224)
		(layer "In13.Cu")
		(net "P5E_CPU1_P3_RX_BUF_DP<6>")
	)
	(segment
		(start 123.252738 -399.07337)
		(end 123.252738 -398.879314)
		(width 0.14224)
		(layer "In13.Cu")
		(net "P5E_CPU1_P3_RX_BUF_DP<6>")
	)
	(segment
		(start 133.983476 -407.68016)
		(end 133.846316 -407.543)
		(width 0.14224)
		(layer "In13.Cu")
		(net "P5E_CPU1_P3_RX_BUF_DP<6>")
	)
	(segment
		(start 132.642356 -405.533606)
		(end 132.329428 -405.220678)
		(width 0.14224)
		(layer "In13.Cu")
		(net "P5E_CPU1_P3_RX_BUF_DP<6>")
	)
	(segment
		(start 137.07618 -433.458112)
		(end 137.07618 -417.51631)
		(width 0.14224)
		(layer "In13.Cu")
		(net "P5E_CPU1_P3_RX_BUF_DP<6>")
	)
	(segment
		(start 124.927868 -400.554444)
		(end 124.625862 -400.252438)
		(width 0.14224)
		(layer "In13.Cu")
		(net "P5E_CPU1_P3_RX_BUF_DP<6>")
	)
	(segment
		(start 122.455178 -398.27581)
		(end 122.455178 -398.081754)
		(width 0.14224)
		(layer "In13.Cu")
		(net "P5E_CPU1_P3_RX_BUF_DP<6>")
	)
	(segment
		(start 125.222762 -401.043394)
		(end 124.927868 -400.7485)
		(width 0.14224)
		(layer "In13.Cu")
		(net "P5E_CPU1_P3_RX_BUF_DP<6>")
	)
	(segment
		(start 132.314696 -405.185118)
		(end 132.314696 -403.807676)
		(width 0.14224)
		(layer "In13.Cu")
		(net "P5E_CPU1_P3_RX_BUF_DP<6>")
	)
	(segment
		(start 122.756676 -398.577308)
		(end 122.455178 -398.27581)
		(width 0.14224)
		(layer "In13.Cu")
		(net "P5E_CPU1_P3_RX_BUF_DP<6>")
	)
	(segment
		(start 136.5885 -415.979356)
		(end 136.408922 -415.905188)
		(width 0.14224)
		(layer "In13.Cu")
		(net "P5E_CPU1_P3_RX_BUF_DP<6>")
	)
	(segment
		(start 124.050298 -399.87093)
		(end 124.050298 -399.676874)
		(width 0.14224)
		(layer "In13.Cu")
		(net "P5E_CPU1_P3_RX_BUF_DP<6>")
	)
	(segment
		(start 122.455178 -398.081754)
		(end 122.153172 -397.779748)
		(width 0.14224)
		(layer "In13.Cu")
		(net "P5E_CPU1_P3_RX_BUF_DP<6>")
	)
	(segment
		(start 121.797064 -392.989562)
		(end 121.97715 -392.989562)
		(width 0.14224)
		(layer "In13.Cu")
		(net "P5E_CPU1_P3_RX_BUF_DP<6>")
	)
	(segment
		(start 133.846316 -408.24404)
		(end 133.983476 -408.10688)
		(width 0.14224)
		(layer "In13.Cu")
		(net "P5E_CPU1_P3_RX_BUF_DP<6>")
	)
	(segment
		(start 121.657618 -397.266922)
		(end 121.657618 -396.326614)
		(width 0.14224)
		(layer "In13.Cu")
		(net "P5E_CPU1_P3_RX_BUF_DP<6>")
	)
	(segment
		(start 133.328156 -405.646128)
		(end 133.155944 -405.574754)
		(width 0.14224)
		(layer "In13.Cu")
		(net "P5E_CPU1_P3_RX_BUF_DP<6>")
	)
	(segment
		(start 124.050298 -399.676874)
		(end 123.748292 -399.374868)
		(width 0.14224)
		(layer "In13.Cu")
		(net "P5E_CPU1_P3_RX_BUF_DP<6>")
	)
	(segment
		(start 131.552696 -403.01545)
		(end 125.39726 -401.148042)
		(width 0.14224)
		(layer "In13.Cu")
		(net "P5E_CPU1_P3_RX_BUF_DP<6>")
	)
	(segment
		(start 133.983476 -409.23464)
		(end 133.983476 -408.80792)
		(width 0.14224)
		(layer "In13.Cu")
		(net "P5E_CPU1_P3_RX_BUF_DP<6>")
	)
	(segment
		(start 133.983476 -408.80792)
		(end 133.846316 -408.67076)
		(width 0.14224)
		(layer "In13.Cu")
		(net "P5E_CPU1_P3_RX_BUF_DP<6>")
	)
	(segment
		(start 135.377936 -413.31261)
		(end 135.377936 -411.626304)
		(width 0.14224)
		(layer "In13.Cu")
		(net "P5E_CPU1_P3_RX_BUF_DP<6>")
	)
	(segment
		(start 124.431806 -400.252438)
		(end 124.050298 -399.87093)
		(width 0.14224)
		(layer "In13.Cu")
		(net "P5E_CPU1_P3_RX_BUF_DP<6>")
	)
	(segment
		(start 137.374884 -433.756816)
		(end 137.07618 -433.458112)
		(width 0.14224)
		(layer "In13.Cu")
		(net "P5E_CPU1_P3_RX_BUF_DP<6>")
	)
	(segment
		(start 132.105908 -403.405086)
		(end 131.552696 -403.01545)
		(width 0.14224)
		(layer "In13.Cu")
		(net "P5E_CPU1_P3_RX_BUF_DP<6>")
	)
	(segment
		(start 121.794778 -395.762734)
		(end 121.657618 -395.625574)
		(width 0.14224)
		(layer "In13.Cu")
		(net "P5E_CPU1_P3_RX_BUF_DP<6>")
	)
	(segment
		(start 136.6774 -416.553142)
		(end 136.751568 -416.373818)
		(width 0.14224)
		(layer "In13.Cu")
		(net "P5E_CPU1_P3_RX_BUF_DP<6>")
	)
	(segment
		(start 136.1567 -414.937194)
		(end 135.977376 -414.863026)
		(width 0.14224)
		(layer "In13.Cu")
		(net "P5E_CPU1_P3_RX_BUF_DP<6>")
	)
	(segment
		(start 123.748292 -399.374868)
		(end 123.554236 -399.374868)
		(width 0.14224)
		(layer "In13.Cu")
		(net "P5E_CPU1_P3_RX_BUF_DP<6>")
	)
	(segment
		(start 137.749788 -433.61864)
		(end 137.611612 -433.756816)
		(width 0.14224)
		(layer "In13.Cu")
		(net "P5E_CPU1_P3_RX_BUF_DP<6>")
	)
	(segment
		(start 134.076948 -410.952188)
		(end 134.017766 -410.912564)
		(width 0.14224)
		(layer "In13.Cu")
		(net "P5E_CPU1_P3_RX_BUF_DP<6>")
	)
	(segment
		(start 124.927868 -400.7485)
		(end 124.927868 -400.554444)
		(width 0.14224)
		(layer "In13.Cu")
		(net "P5E_CPU1_P3_RX_BUF_DP<6>")
	)
	(segment
		(start 133.661912 -405.979884)
		(end 133.328156 -405.646128)
		(width 0.14224)
		(layer "In13.Cu")
		(net "P5E_CPU1_P3_RX_BUF_DP<6>")
	)
	(segment
		(start 121.657618 -394.497814)
		(end 121.657618 -393.129008)
		(width 0.14224)
		(layer "In13.Cu")
		(net "P5E_CPU1_P3_RX_BUF_DP<6>")
	)
	(segment
		(start 121.959116 -397.779748)
		(end 121.807224 -397.627856)
		(width 0.14224)
		(layer "In13.Cu")
		(net "P5E_CPU1_P3_RX_BUF_DP<6>")
	)
	(segment
		(start 136.320022 -415.331656)
		(end 136.1567 -414.937194)
		(width 0.14224)
		(layer "In13.Cu")
		(net "P5E_CPU1_P3_RX_BUF_DP<6>")
	)
	(segment
		(start 121.657618 -393.129008)
		(end 121.797064 -392.989562)
		(width 0.14224)
		(layer "In13.Cu")
		(net "P5E_CPU1_P3_RX_BUF_DP<6>")
	)
	(segment
		(start 133.983476 -408.10688)
		(end 133.983476 -407.68016)
		(width 0.14224)
		(layer "In13.Cu")
		(net "P5E_CPU1_P3_RX_BUF_DP<6>")
	)
	(segment
		(start 132.329428 -405.220678)
		(end 132.314696 -405.185118)
		(width 0.14224)
		(layer "In13.Cu")
		(net "P5E_CPU1_P3_RX_BUF_DP<6>")
	)
	(segment
		(start 123.554236 -399.374868)
		(end 123.252738 -399.07337)
		(width 0.14224)
		(layer "In13.Cu")
		(net "P5E_CPU1_P3_RX_BUF_DP<6>")
	)
	(segment
		(start 122.116596 -393.129008)
		(end 122.116596 -393.292838)
		(width 0.14224)
		(layer "In13.Cu")
		(net "P5E_CPU1_P3_RX_BUF_DP<6>")
	)
	(segment
		(start 133.846316 -409.3718)
		(end 133.983476 -409.23464)
		(width 0.14224)
		(layer "In13.Cu")
		(net "P5E_CPU1_P3_RX_BUF_DP<6>")
	)
	(arc
		(start 135.417306 -413.510476)
		(mid 135.387873 -413.413482)
		(end 135.377936 -413.31261)
		(width 0.14224)
		(layer "In13.Cu")
		(net "P5E_CPU1_P3_RX_BUF_DP<6>")
	)
	(arc
		(start 125.39726 -401.148042)
		(mid 125.303566 -401.106468)
		(end 125.222762 -401.043394)
		(width 0.14224)
		(layer "In13.Cu")
		(net "P5E_CPU1_P3_RX_BUF_DP<6>")
	)
	(arc
		(start 121.807224 -397.627856)
		(mid 121.696521 -397.462272)
		(end 121.657618 -397.266922)
		(width 0.14224)
		(layer "In13.Cu")
		(net "P5E_CPU1_P3_RX_BUF_DP<6>")
	)
	(arc
		(start 132.741416 -405.574754)
		(mid 132.687814 -405.563998)
		(end 132.642356 -405.533606)
		(width 0.14224)
		(layer "In13.Cu")
		(net "P5E_CPU1_P3_RX_BUF_DP<6>")
	)
	(segment
		(start 120.777762 -392.977116)
		(end 120.916446 -393.1158)
		(width 0.1016)
		(layer "F.Cu")
		(net "P5E_CPU1_P3_RX_BUF_DP<5>")
	)
	(segment
		(start 120.302528 -391.36574)
		(end 120.302528 -391.488676)
		(width 0.1016)
		(layer "F.Cu")
		(net "P5E_CPU1_P3_RX_BUF_DP<5>")
	)
	(segment
		(start 120.213882 -392.723878)
		(end 120.46712 -392.977116)
		(width 0.1016)
		(layer "F.Cu")
		(net "P5E_CPU1_P3_RX_BUF_DP<5>")
	)
	(segment
		(start 120.46712 -392.977116)
		(end 120.777762 -392.977116)
		(width 0.1016)
		(layer "F.Cu")
		(net "P5E_CPU1_P3_RX_BUF_DP<5>")
	)
	(segment
		(start 120.916446 -393.1158)
		(end 120.916446 -393.292838)
		(width 0.1016)
		(layer "F.Cu")
		(net "P5E_CPU1_P3_RX_BUF_DP<5>")
	)
	(segment
		(start 120.302528 -391.488676)
		(end 120.213882 -391.577322)
		(width 0.1016)
		(layer "F.Cu")
		(net "P5E_CPU1_P3_RX_BUF_DP<5>")
	)
	(segment
		(start 120.217946 -391.281158)
		(end 120.302528 -391.36574)
		(width 0.1016)
		(layer "F.Cu")
		(net "P5E_CPU1_P3_RX_BUF_DP<5>")
	)
	(segment
		(start 120.213882 -391.577322)
		(end 120.213882 -392.723878)
		(width 0.1016)
		(layer "F.Cu")
		(net "P5E_CPU1_P3_RX_BUF_DP<5>")
	)
	(segment
		(start 134.269734 -415.810192)
		(end 134.082536 -415.758376)
		(width 0.14224)
		(layer "In13.Cu")
		(net "P5E_CPU1_P3_RX_BUF_DP<5>")
	)
	(segment
		(start 122.850148 -400.170904)
		(end 122.548142 -399.868898)
		(width 0.14224)
		(layer "In13.Cu")
		(net "P5E_CPU1_P3_RX_BUF_DP<5>")
	)
	(segment
		(start 134.952486 -417.294314)
		(end 134.42823 -416.368738)
		(width 0.14224)
		(layer "In13.Cu")
		(net "P5E_CPU1_P3_RX_BUF_DP<5>")
	)
	(segment
		(start 130.783076 -407.964386)
		(end 130.783076 -406.424892)
		(width 0.14224)
		(layer "In13.Cu")
		(net "P5E_CPU1_P3_RX_BUF_DP<5>")
	)
	(segment
		(start 127.14478 -402.67636)
		(end 124.657104 -401.922742)
		(width 0.14224)
		(layer "In13.Cu")
		(net "P5E_CPU1_P3_RX_BUF_DP<5>")
	)
	(segment
		(start 130.920236 -409.229306)
		(end 130.783076 -409.092146)
		(width 0.14224)
		(layer "In13.Cu")
		(net "P5E_CPU1_P3_RX_BUF_DP<5>")
	)
	(segment
		(start 122.052588 -399.373344)
		(end 121.750582 -399.071338)
		(width 0.14224)
		(layer "In13.Cu")
		(net "P5E_CPU1_P3_RX_BUF_DP<5>")
	)
	(segment
		(start 135.749792 -434.618638)
		(end 135.611616 -434.756814)
		(width 0.14224)
		(layer "In13.Cu")
		(net "P5E_CPU1_P3_RX_BUF_DP<5>")
	)
	(segment
		(start 130.878072 -410.803852)
		(end 130.783076 -410.574744)
		(width 0.14224)
		(layer "In13.Cu")
		(net "P5E_CPU1_P3_RX_BUF_DP<5>")
	)
	(segment
		(start 122.052588 -399.5674)
		(end 122.052588 -399.373344)
		(width 0.14224)
		(layer "In13.Cu")
		(net "P5E_CPU1_P3_RX_BUF_DP<5>")
	)
	(segment
		(start 132.70484 -413.833818)
		(end 132.425694 -413.493712)
		(width 0.14224)
		(layer "In13.Cu")
		(net "P5E_CPU1_P3_RX_BUF_DP<5>")
	)
	(segment
		(start 120.457468 -395.988032)
		(end 120.457468 -395.487398)
		(width 0.14224)
		(layer "In13.Cu")
		(net "P5E_CPU1_P3_RX_BUF_DP<5>")
	)
	(segment
		(start 129.251456 -403.668992)
		(end 129.08534 -403.421342)
		(width 0.14224)
		(layer "In13.Cu")
		(net "P5E_CPU1_P3_RX_BUF_DP<5>")
	)
	(segment
		(start 130.264916 -405.646128)
		(end 130.092704 -405.574754)
		(width 0.14224)
		(layer "In13.Cu")
		(net "P5E_CPU1_P3_RX_BUF_DP<5>")
	)
	(segment
		(start 120.594628 -394.923518)
		(end 120.457468 -394.786358)
		(width 0.14224)
		(layer "In13.Cu")
		(net "P5E_CPU1_P3_RX_BUF_DP<5>")
	)
	(segment
		(start 129.08534 -403.421342)
		(end 128.562862 -403.106636)
		(width 0.14224)
		(layer "In13.Cu")
		(net "P5E_CPU1_P3_RX_BUF_DP<5>")
	)
	(segment
		(start 128.562862 -403.106636)
		(end 127.145034 -402.676868)
		(width 0.14224)
		(layer "In13.Cu")
		(net "P5E_CPU1_P3_RX_BUF_DP<5>")
	)
	(segment
		(start 123.151646 -400.666458)
		(end 122.850148 -400.36496)
		(width 0.14224)
		(layer "In13.Cu")
		(net "P5E_CPU1_P3_RX_BUF_DP<5>")
	)
	(segment
		(start 120.758966 -398.273778)
		(end 120.494806 -398.009618)
		(width 0.14224)
		(layer "In13.Cu")
		(net "P5E_CPU1_P3_RX_BUF_DP<5>")
	)
	(segment
		(start 122.548142 -399.868898)
		(end 122.354086 -399.868898)
		(width 0.14224)
		(layer "In13.Cu")
		(net "P5E_CPU1_P3_RX_BUF_DP<5>")
	)
	(segment
		(start 132.314696 -411.947106)
		(end 132.14858 -411.546294)
		(width 0.14224)
		(layer "In13.Cu")
		(net "P5E_CPU1_P3_RX_BUF_DP<5>")
	)
	(segment
		(start 123.647708 -400.968464)
		(end 123.345702 -400.666458)
		(width 0.14224)
		(layer "In13.Cu")
		(net "P5E_CPU1_P3_RX_BUF_DP<5>")
	)
	(segment
		(start 120.596914 -392.989562)
		(end 120.777 -392.989562)
		(width 0.14224)
		(layer "In13.Cu")
		(net "P5E_CPU1_P3_RX_BUF_DP<5>")
	)
	(segment
		(start 120.916446 -393.129008)
		(end 120.916446 -393.292838)
		(width 0.14224)
		(layer "In13.Cu")
		(net "P5E_CPU1_P3_RX_BUF_DP<5>")
	)
	(segment
		(start 131.00177 -410.92755)
		(end 130.878072 -410.803852)
		(width 0.14224)
		(layer "In13.Cu")
		(net "P5E_CPU1_P3_RX_BUF_DP<5>")
	)
	(segment
		(start 122.354086 -399.868898)
		(end 122.052588 -399.5674)
		(width 0.14224)
		(layer "In13.Cu")
		(net "P5E_CPU1_P3_RX_BUF_DP<5>")
	)
	(segment
		(start 134.42823 -416.368738)
		(end 134.480046 -416.181794)
		(width 0.14224)
		(layer "In13.Cu")
		(net "P5E_CPU1_P3_RX_BUF_DP<5>")
	)
	(segment
		(start 120.953022 -398.273778)
		(end 120.758966 -398.273778)
		(width 0.14224)
		(layer "In13.Cu")
		(net "P5E_CPU1_P3_RX_BUF_DP<5>")
	)
	(segment
		(start 121.255028 -398.575784)
		(end 120.953022 -398.273778)
		(width 0.14224)
		(layer "In13.Cu")
		(net "P5E_CPU1_P3_RX_BUF_DP<5>")
	)
	(segment
		(start 135.749792 -434.289962)
		(end 135.749792 -434.618638)
		(width 0.14224)
		(layer "In13.Cu")
		(net "P5E_CPU1_P3_RX_BUF_DP<5>")
	)
	(segment
		(start 129.559558 -405.514302)
		(end 129.266188 -405.220932)
		(width 0.14224)
		(layer "In13.Cu")
		(net "P5E_CPU1_P3_RX_BUF_DP<5>")
	)
	(segment
		(start 130.783076 -409.793186)
		(end 130.920236 -409.656026)
		(width 0.14224)
		(layer "In13.Cu")
		(net "P5E_CPU1_P3_RX_BUF_DP<5>")
	)
	(segment
		(start 135.611616 -434.756814)
		(end 135.374888 -434.756814)
		(width 0.14224)
		(layer "In13.Cu")
		(net "P5E_CPU1_P3_RX_BUF_DP<5>")
	)
	(segment
		(start 130.092704 -405.574754)
		(end 129.705608 -405.574754)
		(width 0.14224)
		(layer "In13.Cu")
		(net "P5E_CPU1_P3_RX_BUF_DP<5>")
	)
	(segment
		(start 132.89788 -413.852868)
		(end 132.70484 -413.833818)
		(width 0.14224)
		(layer "In13.Cu")
		(net "P5E_CPU1_P3_RX_BUF_DP<5>")
	)
	(segment
		(start 130.783076 -410.574744)
		(end 130.783076 -409.793186)
		(width 0.14224)
		(layer "In13.Cu")
		(net "P5E_CPU1_P3_RX_BUF_DP<5>")
	)
	(segment
		(start 123.647708 -401.16252)
		(end 123.647708 -400.968464)
		(width 0.14224)
		(layer "In13.Cu")
		(net "P5E_CPU1_P3_RX_BUF_DP<5>")
	)
	(segment
		(start 120.457468 -397.919448)
		(end 120.457468 -396.689072)
		(width 0.14224)
		(layer "In13.Cu")
		(net "P5E_CPU1_P3_RX_BUF_DP<5>")
	)
	(segment
		(start 124.035312 -401.550124)
		(end 123.647708 -401.16252)
		(width 0.14224)
		(layer "In13.Cu")
		(net "P5E_CPU1_P3_RX_BUF_DP<5>")
	)
	(segment
		(start 130.920236 -409.656026)
		(end 130.920236 -409.229306)
		(width 0.14224)
		(layer "In13.Cu")
		(net "P5E_CPU1_P3_RX_BUF_DP<5>")
	)
	(segment
		(start 132.314696 -413.32785)
		(end 132.314696 -411.947106)
		(width 0.14224)
		(layer "In13.Cu")
		(net "P5E_CPU1_P3_RX_BUF_DP<5>")
	)
	(segment
		(start 120.457468 -393.129008)
		(end 120.596914 -392.989562)
		(width 0.14224)
		(layer "In13.Cu")
		(net "P5E_CPU1_P3_RX_BUF_DP<5>")
	)
	(segment
		(start 135.374888 -434.756814)
		(end 135.076184 -434.45811)
		(width 0.14224)
		(layer "In13.Cu")
		(net "P5E_CPU1_P3_RX_BUF_DP<5>")
	)
	(segment
		(start 134.480046 -416.181794)
		(end 134.269734 -415.810192)
		(width 0.14224)
		(layer "In13.Cu")
		(net "P5E_CPU1_P3_RX_BUF_DP<5>")
	)
	(segment
		(start 120.457468 -394.786358)
		(end 120.457468 -393.129008)
		(width 0.14224)
		(layer "In13.Cu")
		(net "P5E_CPU1_P3_RX_BUF_DP<5>")
	)
	(segment
		(start 130.783076 -409.092146)
		(end 130.783076 -408.665426)
		(width 0.14224)
		(layer "In13.Cu")
		(net "P5E_CPU1_P3_RX_BUF_DP<5>")
	)
	(segment
		(start 133.168644 -414.183068)
		(end 132.89788 -413.852868)
		(width 0.14224)
		(layer "In13.Cu")
		(net "P5E_CPU1_P3_RX_BUF_DP<5>")
	)
	(segment
		(start 120.594628 -396.551912)
		(end 120.594628 -396.125192)
		(width 0.14224)
		(layer "In13.Cu")
		(net "P5E_CPU1_P3_RX_BUF_DP<5>")
	)
	(segment
		(start 120.594628 -396.125192)
		(end 120.457468 -395.988032)
		(width 0.14224)
		(layer "In13.Cu")
		(net "P5E_CPU1_P3_RX_BUF_DP<5>")
	)
	(segment
		(start 130.920236 -408.101546)
		(end 130.783076 -407.964386)
		(width 0.14224)
		(layer "In13.Cu")
		(net "P5E_CPU1_P3_RX_BUF_DP<5>")
	)
	(segment
		(start 121.255028 -398.76984)
		(end 121.255028 -398.575784)
		(width 0.14224)
		(layer "In13.Cu")
		(net "P5E_CPU1_P3_RX_BUF_DP<5>")
	)
	(segment
		(start 123.345702 -400.666458)
		(end 123.151646 -400.666458)
		(width 0.14224)
		(layer "In13.Cu")
		(net "P5E_CPU1_P3_RX_BUF_DP<5>")
	)
	(segment
		(start 120.457468 -395.487398)
		(end 120.594628 -395.350238)
		(width 0.14224)
		(layer "In13.Cu")
		(net "P5E_CPU1_P3_RX_BUF_DP<5>")
	)
	(segment
		(start 130.920236 -408.528266)
		(end 130.920236 -408.101546)
		(width 0.14224)
		(layer "In13.Cu")
		(net "P5E_CPU1_P3_RX_BUF_DP<5>")
	)
	(segment
		(start 130.598672 -405.979884)
		(end 130.264916 -405.646128)
		(width 0.14224)
		(layer "In13.Cu")
		(net "P5E_CPU1_P3_RX_BUF_DP<5>")
	)
	(segment
		(start 133.633718 -414.96615)
		(end 133.149594 -414.376108)
		(width 0.14224)
		(layer "In13.Cu")
		(net "P5E_CPU1_P3_RX_BUF_DP<5>")
	)
	(segment
		(start 135.076184 -434.45811)
		(end 135.076184 -417.763198)
		(width 0.14224)
		(layer "In13.Cu")
		(net "P5E_CPU1_P3_RX_BUF_DP<5>")
	)
	(segment
		(start 121.750582 -399.071338)
		(end 121.556526 -399.071338)
		(width 0.14224)
		(layer "In13.Cu")
		(net "P5E_CPU1_P3_RX_BUF_DP<5>")
	)
	(segment
		(start 133.149594 -414.376108)
		(end 133.168644 -414.183068)
		(width 0.14224)
		(layer "In13.Cu")
		(net "P5E_CPU1_P3_RX_BUF_DP<5>")
	)
	(segment
		(start 120.777 -392.989562)
		(end 120.916446 -393.129008)
		(width 0.14224)
		(layer "In13.Cu")
		(net "P5E_CPU1_P3_RX_BUF_DP<5>")
	)
	(segment
		(start 131.937506 -411.33522)
		(end 131.080764 -410.980382)
		(width 0.14224)
		(layer "In13.Cu")
		(net "P5E_CPU1_P3_RX_BUF_DP<5>")
	)
	(segment
		(start 127.145034 -402.676868)
		(end 127.14478 -402.67636)
		(width 0.14224)
		(layer "In13.Cu")
		(net "P5E_CPU1_P3_RX_BUF_DP<5>")
	)
	(segment
		(start 130.783076 -406.424892)
		(end 130.598672 -405.979884)
		(width 0.14224)
		(layer "In13.Cu")
		(net "P5E_CPU1_P3_RX_BUF_DP<5>")
	)
	(segment
		(start 120.457468 -396.689072)
		(end 120.594628 -396.551912)
		(width 0.14224)
		(layer "In13.Cu")
		(net "P5E_CPU1_P3_RX_BUF_DP<5>")
	)
	(segment
		(start 122.850148 -400.36496)
		(end 122.850148 -400.170904)
		(width 0.14224)
		(layer "In13.Cu")
		(net "P5E_CPU1_P3_RX_BUF_DP<5>")
	)
	(segment
		(start 129.266188 -405.220932)
		(end 129.251456 -405.185372)
		(width 0.14224)
		(layer "In13.Cu")
		(net "P5E_CPU1_P3_RX_BUF_DP<5>")
	)
	(segment
		(start 132.425694 -413.493712)
		(end 132.314696 -413.32785)
		(width 0.14224)
		(layer "In13.Cu")
		(net "P5E_CPU1_P3_RX_BUF_DP<5>")
	)
	(segment
		(start 132.14858 -411.546294)
		(end 131.937506 -411.33522)
		(width 0.14224)
		(layer "In13.Cu")
		(net "P5E_CPU1_P3_RX_BUF_DP<5>")
	)
	(segment
		(start 121.556526 -399.071338)
		(end 121.255028 -398.76984)
		(width 0.14224)
		(layer "In13.Cu")
		(net "P5E_CPU1_P3_RX_BUF_DP<5>")
	)
	(segment
		(start 131.080764 -410.980382)
		(end 131.00177 -410.92755)
		(width 0.14224)
		(layer "In13.Cu")
		(net "P5E_CPU1_P3_RX_BUF_DP<5>")
	)
	(segment
		(start 130.783076 -408.665426)
		(end 130.920236 -408.528266)
		(width 0.14224)
		(layer "In13.Cu")
		(net "P5E_CPU1_P3_RX_BUF_DP<5>")
	)
	(segment
		(start 134.082536 -415.758376)
		(end 133.633718 -414.96615)
		(width 0.14224)
		(layer "In13.Cu")
		(net "P5E_CPU1_P3_RX_BUF_DP<5>")
	)
	(segment
		(start 129.251456 -405.185372)
		(end 129.251456 -403.668992)
		(width 0.14224)
		(layer "In13.Cu")
		(net "P5E_CPU1_P3_RX_BUF_DP<5>")
	)
	(segment
		(start 120.594628 -395.350238)
		(end 120.594628 -394.923518)
		(width 0.14224)
		(layer "In13.Cu")
		(net "P5E_CPU1_P3_RX_BUF_DP<5>")
	)
	(arc
		(start 129.705608 -405.574754)
		(mid 129.626569 -405.55905)
		(end 129.559558 -405.514302)
		(width 0.14224)
		(layer "In13.Cu")
		(net "P5E_CPU1_P3_RX_BUF_DP<5>")
	)
	(arc
		(start 124.657104 -401.922742)
		(mid 124.323216 -401.774798)
		(end 124.035312 -401.550124)
		(width 0.14224)
		(layer "In13.Cu")
		(net "P5E_CPU1_P3_RX_BUF_DP<5>")
	)
	(arc
		(start 120.494806 -398.009618)
		(mid 120.467163 -397.968248)
		(end 120.457468 -397.919448)
		(width 0.14224)
		(layer "In13.Cu")
		(net "P5E_CPU1_P3_RX_BUF_DP<5>")
	)
	(arc
		(start 135.076184 -417.763198)
		(mid 135.044723 -417.520735)
		(end 134.952486 -417.294314)
		(width 0.14224)
		(layer "In13.Cu")
		(net "P5E_CPU1_P3_RX_BUF_DP<5>")
	)
	(segment
		(start 119.577866 -392.977116)
		(end 119.71655 -393.1158)
		(width 0.1016)
		(layer "F.Cu")
		(net "P5E_CPU1_P3_RX_BUF_DP<4>")
	)
	(segment
		(start 119.71655 -393.1158)
		(end 119.71655 -393.292838)
		(width 0.1016)
		(layer "F.Cu")
		(net "P5E_CPU1_P3_RX_BUF_DP<4>")
	)
	(segment
		(start 119.102632 -391.488676)
		(end 119.013986 -391.577322)
		(width 0.1016)
		(layer "F.Cu")
		(net "P5E_CPU1_P3_RX_BUF_DP<4>")
	)
	(segment
		(start 119.013986 -391.577322)
		(end 119.013986 -392.723878)
		(width 0.1016)
		(layer "F.Cu")
		(net "P5E_CPU1_P3_RX_BUF_DP<4>")
	)
	(segment
		(start 119.01805 -391.281158)
		(end 119.102632 -391.36574)
		(width 0.1016)
		(layer "F.Cu")
		(net "P5E_CPU1_P3_RX_BUF_DP<4>")
	)
	(segment
		(start 119.013986 -392.723878)
		(end 119.267224 -392.977116)
		(width 0.1016)
		(layer "F.Cu")
		(net "P5E_CPU1_P3_RX_BUF_DP<4>")
	)
	(segment
		(start 119.102632 -391.36574)
		(end 119.102632 -391.488676)
		(width 0.1016)
		(layer "F.Cu")
		(net "P5E_CPU1_P3_RX_BUF_DP<4>")
	)
	(segment
		(start 119.267224 -392.977116)
		(end 119.577866 -392.977116)
		(width 0.1016)
		(layer "F.Cu")
		(net "P5E_CPU1_P3_RX_BUF_DP<4>")
	)
	(segment
		(start 123.290838 -402.241512)
		(end 122.988832 -401.939506)
		(width 0.14224)
		(layer "In13.Cu")
		(net "P5E_CPU1_P3_RX_BUF_DP<4>")
	)
	(segment
		(start 125.435868 -403.138132)
		(end 123.6726 -402.787104)
		(width 0.14224)
		(layer "In13.Cu")
		(net "P5E_CPU1_P3_RX_BUF_DP<4>")
	)
	(segment
		(start 127.93853 -410.92755)
		(end 127.814832 -410.803852)
		(width 0.14224)
		(layer "In13.Cu")
		(net "P5E_CPU1_P3_RX_BUF_DP<4>")
	)
	(segment
		(start 122.988832 -401.939506)
		(end 122.794776 -401.939506)
		(width 0.14224)
		(layer "In13.Cu")
		(net "P5E_CPU1_P3_RX_BUF_DP<4>")
	)
	(segment
		(start 119.257572 -395.042644)
		(end 119.394732 -394.905484)
		(width 0.14224)
		(layer "In13.Cu")
		(net "P5E_CPU1_P3_RX_BUF_DP<4>")
	)
	(segment
		(start 127.719836 -406.424892)
		(end 127.535432 -405.979884)
		(width 0.14224)
		(layer "In13.Cu")
		(net "P5E_CPU1_P3_RX_BUF_DP<4>")
	)
	(segment
		(start 119.394732 -396.033244)
		(end 119.394732 -395.606524)
		(width 0.14224)
		(layer "In13.Cu")
		(net "P5E_CPU1_P3_RX_BUF_DP<4>")
	)
	(segment
		(start 119.257572 -394.341604)
		(end 119.257572 -393.129008)
		(width 0.14224)
		(layer "In13.Cu")
		(net "P5E_CPU1_P3_RX_BUF_DP<4>")
	)
	(segment
		(start 119.257572 -397.298164)
		(end 119.394732 -397.161004)
		(width 0.14224)
		(layer "In13.Cu")
		(net "P5E_CPU1_P3_RX_BUF_DP<4>")
	)
	(segment
		(start 119.397018 -392.989562)
		(end 119.577104 -392.989562)
		(width 0.14224)
		(layer "In13.Cu")
		(net "P5E_CPU1_P3_RX_BUF_DP<4>")
	)
	(segment
		(start 121.650252 -400.794982)
		(end 121.650252 -400.600926)
		(width 0.14224)
		(layer "In13.Cu")
		(net "P5E_CPU1_P3_RX_BUF_DP<4>")
	)
	(segment
		(start 122.191272 -401.141946)
		(end 121.997216 -401.141946)
		(width 0.14224)
		(layer "In13.Cu")
		(net "P5E_CPU1_P3_RX_BUF_DP<4>")
	)
	(segment
		(start 121.997216 -401.141946)
		(end 121.650252 -400.794982)
		(width 0.14224)
		(layer "In13.Cu")
		(net "P5E_CPU1_P3_RX_BUF_DP<4>")
	)
	(segment
		(start 122.493278 -401.638008)
		(end 122.493278 -401.443952)
		(width 0.14224)
		(layer "In13.Cu")
		(net "P5E_CPU1_P3_RX_BUF_DP<4>")
	)
	(segment
		(start 119.257572 -395.469364)
		(end 119.257572 -395.042644)
		(width 0.14224)
		(layer "In13.Cu")
		(net "P5E_CPU1_P3_RX_BUF_DP<4>")
	)
	(segment
		(start 126.991364 -405.574754)
		(end 126.517146 -405.574754)
		(width 0.14224)
		(layer "In13.Cu")
		(net "P5E_CPU1_P3_RX_BUF_DP<4>")
	)
	(segment
		(start 127.535432 -405.979884)
		(end 127.2286 -405.673052)
		(width 0.14224)
		(layer "In13.Cu")
		(net "P5E_CPU1_P3_RX_BUF_DP<4>")
	)
	(segment
		(start 130.433064 -414.79724)
		(end 129.574798 -414.127442)
		(width 0.14224)
		(layer "In13.Cu")
		(net "P5E_CPU1_P3_RX_BUF_DP<4>")
	)
	(segment
		(start 130.962146 -415.036254)
		(end 130.625596 -414.773364)
		(width 0.14224)
		(layer "In13.Cu")
		(net "P5E_CPU1_P3_RX_BUF_DP<4>")
	)
	(segment
		(start 119.257572 -393.129008)
		(end 119.397018 -392.989562)
		(width 0.14224)
		(layer "In13.Cu")
		(net "P5E_CPU1_P3_RX_BUF_DP<4>")
	)
	(segment
		(start 127.719836 -410.574744)
		(end 127.719836 -408.914854)
		(width 0.14224)
		(layer "In13.Cu")
		(net "P5E_CPU1_P3_RX_BUF_DP<4>")
	)
	(segment
		(start 121.15419 -400.29892)
		(end 120.852692 -399.997422)
		(width 0.14224)
		(layer "In13.Cu")
		(net "P5E_CPU1_P3_RX_BUF_DP<4>")
	)
	(segment
		(start 133.374892 -433.756816)
		(end 133.076188 -433.458112)
		(width 0.14224)
		(layer "In13.Cu")
		(net "P5E_CPU1_P3_RX_BUF_DP<4>")
	)
	(segment
		(start 133.749796 -433.61864)
		(end 133.61162 -433.756816)
		(width 0.14224)
		(layer "In13.Cu")
		(net "P5E_CPU1_P3_RX_BUF_DP<4>")
	)
	(segment
		(start 130.986022 -415.228786)
		(end 130.962146 -415.036254)
		(width 0.14224)
		(layer "In13.Cu")
		(net "P5E_CPU1_P3_RX_BUF_DP<4>")
	)
	(segment
		(start 123.607576 -402.752306)
		(end 123.290838 -402.435568)
		(width 0.14224)
		(layer "In13.Cu")
		(net "P5E_CPU1_P3_RX_BUF_DP<4>")
	)
	(segment
		(start 126.26086 -405.360378)
		(end 126.188216 -405.184864)
		(width 0.14224)
		(layer "In13.Cu")
		(net "P5E_CPU1_P3_RX_BUF_DP<4>")
	)
	(segment
		(start 129.064512 -411.49524)
		(end 128.926844 -411.357064)
		(width 0.14224)
		(layer "In13.Cu")
		(net "P5E_CPU1_P3_RX_BUF_DP<4>")
	)
	(segment
		(start 119.55907 -398.7038)
		(end 119.307102 -398.451832)
		(width 0.14224)
		(layer "In13.Cu")
		(net "P5E_CPU1_P3_RX_BUF_DP<4>")
	)
	(segment
		(start 119.577104 -392.989562)
		(end 119.71655 -393.129008)
		(width 0.14224)
		(layer "In13.Cu")
		(net "P5E_CPU1_P3_RX_BUF_DP<4>")
	)
	(segment
		(start 133.749796 -433.289964)
		(end 133.749796 -433.61864)
		(width 0.14224)
		(layer "In13.Cu")
		(net "P5E_CPU1_P3_RX_BUF_DP<4>")
	)
	(segment
		(start 120.550686 -399.50136)
		(end 120.35663 -399.50136)
		(width 0.14224)
		(layer "In13.Cu")
		(net "P5E_CPU1_P3_RX_BUF_DP<4>")
	)
	(segment
		(start 126.517146 -405.574754)
		(end 126.445518 -405.545036)
		(width 0.14224)
		(layer "In13.Cu")
		(net "P5E_CPU1_P3_RX_BUF_DP<4>")
	)
	(segment
		(start 120.35663 -399.50136)
		(end 120.055132 -399.199862)
		(width 0.14224)
		(layer "In13.Cu")
		(net "P5E_CPU1_P3_RX_BUF_DP<4>")
	)
	(segment
		(start 119.394732 -395.606524)
		(end 119.257572 -395.469364)
		(width 0.14224)
		(layer "In13.Cu")
		(net "P5E_CPU1_P3_RX_BUF_DP<4>")
	)
	(segment
		(start 119.753126 -398.7038)
		(end 119.55907 -398.7038)
		(width 0.14224)
		(layer "In13.Cu")
		(net "P5E_CPU1_P3_RX_BUF_DP<4>")
	)
	(segment
		(start 127.719836 -408.213814)
		(end 127.719836 -406.424892)
		(width 0.14224)
		(layer "In13.Cu")
		(net "P5E_CPU1_P3_RX_BUF_DP<4>")
	)
	(segment
		(start 127.719836 -408.914854)
		(end 127.856996 -408.777694)
		(width 0.14224)
		(layer "In13.Cu")
		(net "P5E_CPU1_P3_RX_BUF_DP<4>")
	)
	(segment
		(start 119.394732 -394.905484)
		(end 119.394732 -394.478764)
		(width 0.14224)
		(layer "In13.Cu")
		(net "P5E_CPU1_P3_RX_BUF_DP<4>")
	)
	(segment
		(start 119.257572 -396.170404)
		(end 119.394732 -396.033244)
		(width 0.14224)
		(layer "In13.Cu")
		(net "P5E_CPU1_P3_RX_BUF_DP<4>")
	)
	(segment
		(start 129.574798 -414.127442)
		(end 129.380742 -413.933386)
		(width 0.14224)
		(layer "In13.Cu")
		(net "P5E_CPU1_P3_RX_BUF_DP<4>")
	)
	(segment
		(start 120.055132 -399.199862)
		(end 120.055132 -399.005806)
		(width 0.14224)
		(layer "In13.Cu")
		(net "P5E_CPU1_P3_RX_BUF_DP<4>")
	)
	(segment
		(start 122.493278 -401.443952)
		(end 122.191272 -401.141946)
		(width 0.14224)
		(layer "In13.Cu")
		(net "P5E_CPU1_P3_RX_BUF_DP<4>")
	)
	(segment
		(start 130.625596 -414.773364)
		(end 130.433064 -414.79724)
		(width 0.14224)
		(layer "In13.Cu")
		(net "P5E_CPU1_P3_RX_BUF_DP<4>")
	)
	(segment
		(start 123.290838 -402.435568)
		(end 123.290838 -402.241512)
		(width 0.14224)
		(layer "In13.Cu")
		(net "P5E_CPU1_P3_RX_BUF_DP<4>")
	)
	(segment
		(start 127.856996 -408.350974)
		(end 127.719836 -408.213814)
		(width 0.14224)
		(layer "In13.Cu")
		(net "P5E_CPU1_P3_RX_BUF_DP<4>")
	)
	(segment
		(start 128.926844 -411.357064)
		(end 128.017778 -410.980382)
		(width 0.14224)
		(layer "In13.Cu")
		(net "P5E_CPU1_P3_RX_BUF_DP<4>")
	)
	(segment
		(start 121.348246 -400.29892)
		(end 121.15419 -400.29892)
		(width 0.14224)
		(layer "In13.Cu")
		(net "P5E_CPU1_P3_RX_BUF_DP<4>")
	)
	(segment
		(start 125.988826 -403.513544)
		(end 125.739144 -403.263862)
		(width 0.14224)
		(layer "In13.Cu")
		(net "P5E_CPU1_P3_RX_BUF_DP<4>")
	)
	(segment
		(start 126.188216 -405.184864)
		(end 126.188216 -403.994874)
		(width 0.14224)
		(layer "In13.Cu")
		(net "P5E_CPU1_P3_RX_BUF_DP<4>")
	)
	(segment
		(start 126.445518 -405.545036)
		(end 126.26086 -405.360378)
		(width 0.14224)
		(layer "In13.Cu")
		(net "P5E_CPU1_P3_RX_BUF_DP<4>")
	)
	(segment
		(start 120.852692 -399.803366)
		(end 120.550686 -399.50136)
		(width 0.14224)
		(layer "In13.Cu")
		(net "P5E_CPU1_P3_RX_BUF_DP<4>")
	)
	(segment
		(start 133.076188 -433.458112)
		(end 133.076188 -417.428172)
		(width 0.14224)
		(layer "In13.Cu")
		(net "P5E_CPU1_P3_RX_BUF_DP<4>")
	)
	(segment
		(start 120.055132 -399.005806)
		(end 119.753126 -398.7038)
		(width 0.14224)
		(layer "In13.Cu")
		(net "P5E_CPU1_P3_RX_BUF_DP<4>")
	)
	(segment
		(start 127.814832 -410.803852)
		(end 127.719836 -410.574744)
		(width 0.14224)
		(layer "In13.Cu")
		(net "P5E_CPU1_P3_RX_BUF_DP<4>")
	)
	(segment
		(start 128.017778 -410.980382)
		(end 127.93853 -410.92755)
		(width 0.14224)
		(layer "In13.Cu")
		(net "P5E_CPU1_P3_RX_BUF_DP<4>")
	)
	(segment
		(start 119.257572 -398.332198)
		(end 119.257572 -397.298164)
		(width 0.14224)
		(layer "In13.Cu")
		(net "P5E_CPU1_P3_RX_BUF_DP<4>")
	)
	(segment
		(start 125.739144 -403.263862)
		(end 125.435868 -403.138132)
		(width 0.14224)
		(layer "In13.Cu")
		(net "P5E_CPU1_P3_RX_BUF_DP<4>")
	)
	(segment
		(start 127.856996 -408.777694)
		(end 127.856996 -408.350974)
		(width 0.14224)
		(layer "In13.Cu")
		(net "P5E_CPU1_P3_RX_BUF_DP<4>")
	)
	(segment
		(start 120.852692 -399.997422)
		(end 120.852692 -399.803366)
		(width 0.14224)
		(layer "In13.Cu")
		(net "P5E_CPU1_P3_RX_BUF_DP<4>")
	)
	(segment
		(start 133.076188 -417.428172)
		(end 132.821934 -416.814762)
		(width 0.14224)
		(layer "In13.Cu")
		(net "P5E_CPU1_P3_RX_BUF_DP<4>")
	)
	(segment
		(start 122.794776 -401.939506)
		(end 122.493278 -401.638008)
		(width 0.14224)
		(layer "In13.Cu")
		(net "P5E_CPU1_P3_RX_BUF_DP<4>")
	)
	(segment
		(start 132.821934 -416.814762)
		(end 132.471922 -416.388296)
		(width 0.14224)
		(layer "In13.Cu")
		(net "P5E_CPU1_P3_RX_BUF_DP<4>")
	)
	(segment
		(start 129.251456 -411.948122)
		(end 129.064512 -411.49524)
		(width 0.14224)
		(layer "In13.Cu")
		(net "P5E_CPU1_P3_RX_BUF_DP<4>")
	)
	(segment
		(start 132.471922 -416.388296)
		(end 130.986022 -415.228786)
		(width 0.14224)
		(layer "In13.Cu")
		(net "P5E_CPU1_P3_RX_BUF_DP<4>")
	)
	(segment
		(start 119.394732 -396.734284)
		(end 119.257572 -396.597124)
		(width 0.14224)
		(layer "In13.Cu")
		(net "P5E_CPU1_P3_RX_BUF_DP<4>")
	)
	(segment
		(start 133.61162 -433.756816)
		(end 133.374892 -433.756816)
		(width 0.14224)
		(layer "In13.Cu")
		(net "P5E_CPU1_P3_RX_BUF_DP<4>")
	)
	(segment
		(start 119.71655 -393.129008)
		(end 119.71655 -393.292838)
		(width 0.14224)
		(layer "In13.Cu")
		(net "P5E_CPU1_P3_RX_BUF_DP<4>")
	)
	(segment
		(start 119.394732 -397.161004)
		(end 119.394732 -396.734284)
		(width 0.14224)
		(layer "In13.Cu")
		(net "P5E_CPU1_P3_RX_BUF_DP<4>")
	)
	(segment
		(start 129.251456 -413.620712)
		(end 129.251456 -411.948122)
		(width 0.14224)
		(layer "In13.Cu")
		(net "P5E_CPU1_P3_RX_BUF_DP<4>")
	)
	(segment
		(start 127.2286 -405.673052)
		(end 126.991364 -405.574754)
		(width 0.14224)
		(layer "In13.Cu")
		(net "P5E_CPU1_P3_RX_BUF_DP<4>")
	)
	(segment
		(start 129.380742 -413.933386)
		(end 129.251456 -413.620712)
		(width 0.14224)
		(layer "In13.Cu")
		(net "P5E_CPU1_P3_RX_BUF_DP<4>")
	)
	(segment
		(start 119.394732 -394.478764)
		(end 119.257572 -394.341604)
		(width 0.14224)
		(layer "In13.Cu")
		(net "P5E_CPU1_P3_RX_BUF_DP<4>")
	)
	(segment
		(start 119.257572 -396.597124)
		(end 119.257572 -396.170404)
		(width 0.14224)
		(layer "In13.Cu")
		(net "P5E_CPU1_P3_RX_BUF_DP<4>")
	)
	(segment
		(start 121.650252 -400.600926)
		(end 121.348246 -400.29892)
		(width 0.14224)
		(layer "In13.Cu")
		(net "P5E_CPU1_P3_RX_BUF_DP<4>")
	)
	(arc
		(start 123.6726 -402.787104)
		(mid 123.637506 -402.774528)
		(end 123.607576 -402.752306)
		(width 0.14224)
		(layer "In13.Cu")
		(net "P5E_CPU1_P3_RX_BUF_DP<4>")
	)
	(arc
		(start 126.188216 -403.994874)
		(mid 126.136399 -403.734374)
		(end 125.988826 -403.513544)
		(width 0.14224)
		(layer "In13.Cu")
		(net "P5E_CPU1_P3_RX_BUF_DP<4>")
	)
	(arc
		(start 119.307102 -398.451832)
		(mid 119.270427 -398.396943)
		(end 119.257572 -398.332198)
		(width 0.14224)
		(layer "In13.Cu")
		(net "P5E_CPU1_P3_RX_BUF_DP<4>")
	)
	(segment
		(start 117.902482 -391.488676)
		(end 117.827044 -391.564114)
		(width 0.1016)
		(layer "F.Cu")
		(net "P5E_CPU1_P3_RX_BUF_DP<3>")
	)
	(segment
		(start 117.827044 -391.564114)
		(end 117.827044 -392.723878)
		(width 0.1016)
		(layer "F.Cu")
		(net "P5E_CPU1_P3_RX_BUF_DP<3>")
	)
	(segment
		(start 117.902482 -391.36574)
		(end 117.902482 -391.488676)
		(width 0.1016)
		(layer "F.Cu")
		(net "P5E_CPU1_P3_RX_BUF_DP<3>")
	)
	(segment
		(start 117.8179 -391.281158)
		(end 117.902482 -391.36574)
		(width 0.1016)
		(layer "F.Cu")
		(net "P5E_CPU1_P3_RX_BUF_DP<3>")
	)
	(segment
		(start 118.080282 -392.977116)
		(end 118.377716 -392.977116)
		(width 0.1016)
		(layer "F.Cu")
		(net "P5E_CPU1_P3_RX_BUF_DP<3>")
	)
	(segment
		(start 117.827044 -392.723878)
		(end 118.080282 -392.977116)
		(width 0.1016)
		(layer "F.Cu")
		(net "P5E_CPU1_P3_RX_BUF_DP<3>")
	)
	(segment
		(start 118.5164 -393.1158)
		(end 118.5164 -393.292838)
		(width 0.1016)
		(layer "F.Cu")
		(net "P5E_CPU1_P3_RX_BUF_DP<3>")
	)
	(segment
		(start 118.377716 -392.977116)
		(end 118.5164 -393.1158)
		(width 0.1016)
		(layer "F.Cu")
		(net "P5E_CPU1_P3_RX_BUF_DP<3>")
	)
	(segment
		(start 121.247662 -401.92198)
		(end 121.247662 -401.727924)
		(width 0.14224)
		(layer "In13.Cu")
		(net "P5E_CPU1_P3_RX_BUF_DP<3>")
	)
	(segment
		(start 124.656596 -408.826462)
		(end 124.656596 -408.399742)
		(width 0.14224)
		(layer "In13.Cu")
		(net "P5E_CPU1_P3_RX_BUF_DP<3>")
	)
	(segment
		(start 123.19762 -405.360378)
		(end 123.124976 -405.185118)
		(width 0.14224)
		(layer "In13.Cu")
		(net "P5E_CPU1_P3_RX_BUF_DP<3>")
	)
	(segment
		(start 118.35892 -399.033238)
		(end 118.09476 -398.769078)
		(width 0.14224)
		(layer "In13.Cu")
		(net "P5E_CPU1_P3_RX_BUF_DP<3>")
	)
	(segment
		(start 122.045222 -402.525484)
		(end 121.743216 -402.223478)
		(width 0.14224)
		(layer "In13.Cu")
		(net "P5E_CPU1_P3_RX_BUF_DP<3>")
	)
	(segment
		(start 118.194582 -396.064486)
		(end 118.194582 -395.637766)
		(width 0.14224)
		(layer "In13.Cu")
		(net "P5E_CPU1_P3_RX_BUF_DP<3>")
	)
	(segment
		(start 121.247662 -401.727924)
		(end 120.945656 -401.425918)
		(width 0.14224)
		(layer "In13.Cu")
		(net "P5E_CPU1_P3_RX_BUF_DP<3>")
	)
	(segment
		(start 131.374896 -434.756814)
		(end 131.076192 -434.45811)
		(width 0.14224)
		(layer "In13.Cu")
		(net "P5E_CPU1_P3_RX_BUF_DP<3>")
	)
	(segment
		(start 124.656596 -406.424892)
		(end 124.472192 -405.979884)
		(width 0.14224)
		(layer "In13.Cu")
		(net "P5E_CPU1_P3_RX_BUF_DP<3>")
	)
	(segment
		(start 119.350536 -399.830798)
		(end 119.15648 -399.830798)
		(width 0.14224)
		(layer "In13.Cu")
		(net "P5E_CPU1_P3_RX_BUF_DP<3>")
	)
	(segment
		(start 118.552976 -399.033238)
		(end 118.35892 -399.033238)
		(width 0.14224)
		(layer "In13.Cu")
		(net "P5E_CPU1_P3_RX_BUF_DP<3>")
	)
	(segment
		(start 124.472192 -405.979884)
		(end 124.138436 -405.646128)
		(width 0.14224)
		(layer "In13.Cu")
		(net "P5E_CPU1_P3_RX_BUF_DP<3>")
	)
	(segment
		(start 118.194582 -394.936726)
		(end 118.194582 -394.510006)
		(width 0.14224)
		(layer "In13.Cu")
		(net "P5E_CPU1_P3_RX_BUF_DP<3>")
	)
	(segment
		(start 124.656596 -409.527502)
		(end 124.793756 -409.390342)
		(width 0.14224)
		(layer "In13.Cu")
		(net "P5E_CPU1_P3_RX_BUF_DP<3>")
	)
	(segment
		(start 118.194582 -394.510006)
		(end 118.057422 -394.372846)
		(width 0.14224)
		(layer "In13.Cu")
		(net "P5E_CPU1_P3_RX_BUF_DP<3>")
	)
	(segment
		(start 123.124976 -405.185118)
		(end 123.124976 -404.052024)
		(width 0.14224)
		(layer "In13.Cu")
		(net "P5E_CPU1_P3_RX_BUF_DP<3>")
	)
	(segment
		(start 122.045222 -402.71954)
		(end 122.045222 -402.525484)
		(width 0.14224)
		(layer "In13.Cu")
		(net "P5E_CPU1_P3_RX_BUF_DP<3>")
	)
	(segment
		(start 124.656596 -407.698702)
		(end 124.656596 -406.424892)
		(width 0.14224)
		(layer "In13.Cu")
		(net "P5E_CPU1_P3_RX_BUF_DP<3>")
	)
	(segment
		(start 124.138436 -405.646128)
		(end 123.966224 -405.574754)
		(width 0.14224)
		(layer "In13.Cu")
		(net "P5E_CPU1_P3_RX_BUF_DP<3>")
	)
	(segment
		(start 118.057422 -393.129008)
		(end 118.196868 -392.989562)
		(width 0.14224)
		(layer "In13.Cu")
		(net "P5E_CPU1_P3_RX_BUF_DP<3>")
	)
	(segment
		(start 118.194582 -397.192246)
		(end 118.194582 -396.765526)
		(width 0.14224)
		(layer "In13.Cu")
		(net "P5E_CPU1_P3_RX_BUF_DP<3>")
	)
	(segment
		(start 131.7498 -434.289962)
		(end 131.7498 -434.618638)
		(width 0.14224)
		(layer "In13.Cu")
		(net "P5E_CPU1_P3_RX_BUF_DP<3>")
	)
	(segment
		(start 120.148096 -400.628358)
		(end 119.95404 -400.628358)
		(width 0.14224)
		(layer "In13.Cu")
		(net "P5E_CPU1_P3_RX_BUF_DP<3>")
	)
	(segment
		(start 123.453906 -405.574754)
		(end 123.382278 -405.545036)
		(width 0.14224)
		(layer "In13.Cu")
		(net "P5E_CPU1_P3_RX_BUF_DP<3>")
	)
	(segment
		(start 118.854982 -399.335244)
		(end 118.552976 -399.033238)
		(width 0.14224)
		(layer "In13.Cu")
		(net "P5E_CPU1_P3_RX_BUF_DP<3>")
	)
	(segment
		(start 127.463296 -414.201102)
		(end 126.270258 -413.465264)
		(width 0.14224)
		(layer "In13.Cu")
		(net "P5E_CPU1_P3_RX_BUF_DP<3>")
	)
	(segment
		(start 124.656596 -408.399742)
		(end 124.793756 -408.262582)
		(width 0.14224)
		(layer "In13.Cu")
		(net "P5E_CPU1_P3_RX_BUF_DP<3>")
	)
	(segment
		(start 118.057422 -396.628366)
		(end 118.057422 -396.201646)
		(width 0.14224)
		(layer "In13.Cu")
		(net "P5E_CPU1_P3_RX_BUF_DP<3>")
	)
	(segment
		(start 118.194582 -396.765526)
		(end 118.057422 -396.628366)
		(width 0.14224)
		(layer "In13.Cu")
		(net "P5E_CPU1_P3_RX_BUF_DP<3>")
	)
	(segment
		(start 119.652542 -400.132804)
		(end 119.350536 -399.830798)
		(width 0.14224)
		(layer "In13.Cu")
		(net "P5E_CPU1_P3_RX_BUF_DP<3>")
	)
	(segment
		(start 120.450102 -400.930364)
		(end 120.148096 -400.628358)
		(width 0.14224)
		(layer "In13.Cu")
		(net "P5E_CPU1_P3_RX_BUF_DP<3>")
	)
	(segment
		(start 130.126994 -416.279838)
		(end 127.463296 -414.201102)
		(width 0.14224)
		(layer "In13.Cu")
		(net "P5E_CPU1_P3_RX_BUF_DP<3>")
	)
	(segment
		(start 119.15648 -399.830798)
		(end 118.854982 -399.5293)
		(width 0.14224)
		(layer "In13.Cu")
		(net "P5E_CPU1_P3_RX_BUF_DP<3>")
	)
	(segment
		(start 118.057422 -396.201646)
		(end 118.194582 -396.064486)
		(width 0.14224)
		(layer "In13.Cu")
		(net "P5E_CPU1_P3_RX_BUF_DP<3>")
	)
	(segment
		(start 118.196868 -392.989562)
		(end 118.376954 -392.989562)
		(width 0.14224)
		(layer "In13.Cu")
		(net "P5E_CPU1_P3_RX_BUF_DP<3>")
	)
	(segment
		(start 119.95404 -400.628358)
		(end 119.652542 -400.32686)
		(width 0.14224)
		(layer "In13.Cu")
		(net "P5E_CPU1_P3_RX_BUF_DP<3>")
	)
	(segment
		(start 125.834648 -411.364938)
		(end 124.956062 -411.001464)
		(width 0.14224)
		(layer "In13.Cu")
		(net "P5E_CPU1_P3_RX_BUF_DP<3>")
	)
	(segment
		(start 118.057422 -394.372846)
		(end 118.057422 -393.129008)
		(width 0.14224)
		(layer "In13.Cu")
		(net "P5E_CPU1_P3_RX_BUF_DP<3>")
	)
	(segment
		(start 121.743216 -402.223478)
		(end 121.54916 -402.223478)
		(width 0.14224)
		(layer "In13.Cu")
		(net "P5E_CPU1_P3_RX_BUF_DP<3>")
	)
	(segment
		(start 124.793756 -409.390342)
		(end 124.793756 -408.963622)
		(width 0.14224)
		(layer "In13.Cu")
		(net "P5E_CPU1_P3_RX_BUF_DP<3>")
	)
	(segment
		(start 124.656596 -410.701998)
		(end 124.656596 -409.527502)
		(width 0.14224)
		(layer "In13.Cu")
		(net "P5E_CPU1_P3_RX_BUF_DP<3>")
	)
	(segment
		(start 124.793756 -408.963622)
		(end 124.656596 -408.826462)
		(width 0.14224)
		(layer "In13.Cu")
		(net "P5E_CPU1_P3_RX_BUF_DP<3>")
	)
	(segment
		(start 118.5164 -393.129008)
		(end 118.5164 -393.292838)
		(width 0.14224)
		(layer "In13.Cu")
		(net "P5E_CPU1_P3_RX_BUF_DP<3>")
	)
	(segment
		(start 118.194582 -395.637766)
		(end 118.057422 -395.500606)
		(width 0.14224)
		(layer "In13.Cu")
		(net "P5E_CPU1_P3_RX_BUF_DP<3>")
	)
	(segment
		(start 131.611624 -434.756814)
		(end 131.374896 -434.756814)
		(width 0.14224)
		(layer "In13.Cu")
		(net "P5E_CPU1_P3_RX_BUF_DP<3>")
	)
	(segment
		(start 131.7498 -434.618638)
		(end 131.611624 -434.756814)
		(width 0.14224)
		(layer "In13.Cu")
		(net "P5E_CPU1_P3_RX_BUF_DP<3>")
	)
	(segment
		(start 123.382278 -405.545036)
		(end 123.19762 -405.360378)
		(width 0.14224)
		(layer "In13.Cu")
		(net "P5E_CPU1_P3_RX_BUF_DP<3>")
	)
	(segment
		(start 119.652542 -400.32686)
		(end 119.652542 -400.132804)
		(width 0.14224)
		(layer "In13.Cu")
		(net "P5E_CPU1_P3_RX_BUF_DP<3>")
	)
	(segment
		(start 126.188216 -413.318452)
		(end 126.188216 -411.894274)
		(width 0.14224)
		(layer "In13.Cu")
		(net "P5E_CPU1_P3_RX_BUF_DP<3>")
	)
	(segment
		(start 124.793756 -408.262582)
		(end 124.793756 -407.835862)
		(width 0.14224)
		(layer "In13.Cu")
		(net "P5E_CPU1_P3_RX_BUF_DP<3>")
	)
	(segment
		(start 131.076192 -434.45811)
		(end 131.076192 -417.378134)
		(width 0.14224)
		(layer "In13.Cu")
		(net "P5E_CPU1_P3_RX_BUF_DP<3>")
	)
	(segment
		(start 124.956062 -411.001464)
		(end 124.656596 -410.701998)
		(width 0.14224)
		(layer "In13.Cu")
		(net "P5E_CPU1_P3_RX_BUF_DP<3>")
	)
	(segment
		(start 118.057422 -397.329406)
		(end 118.194582 -397.192246)
		(width 0.14224)
		(layer "In13.Cu")
		(net "P5E_CPU1_P3_RX_BUF_DP<3>")
	)
	(segment
		(start 120.450102 -401.12442)
		(end 120.450102 -400.930364)
		(width 0.14224)
		(layer "In13.Cu")
		(net "P5E_CPU1_P3_RX_BUF_DP<3>")
	)
	(segment
		(start 124.793756 -407.835862)
		(end 124.656596 -407.698702)
		(width 0.14224)
		(layer "In13.Cu")
		(net "P5E_CPU1_P3_RX_BUF_DP<3>")
	)
	(segment
		(start 118.057422 -398.678908)
		(end 118.057422 -397.329406)
		(width 0.14224)
		(layer "In13.Cu")
		(net "P5E_CPU1_P3_RX_BUF_DP<3>")
	)
	(segment
		(start 118.057422 -395.500606)
		(end 118.057422 -395.073886)
		(width 0.14224)
		(layer "In13.Cu")
		(net "P5E_CPU1_P3_RX_BUF_DP<3>")
	)
	(segment
		(start 118.376954 -392.989562)
		(end 118.5164 -393.129008)
		(width 0.14224)
		(layer "In13.Cu")
		(net "P5E_CPU1_P3_RX_BUF_DP<3>")
	)
	(segment
		(start 120.7516 -401.425918)
		(end 120.450102 -401.12442)
		(width 0.14224)
		(layer "In13.Cu")
		(net "P5E_CPU1_P3_RX_BUF_DP<3>")
	)
	(segment
		(start 120.945656 -401.425918)
		(end 120.7516 -401.425918)
		(width 0.14224)
		(layer "In13.Cu")
		(net "P5E_CPU1_P3_RX_BUF_DP<3>")
	)
	(segment
		(start 118.854982 -399.5293)
		(end 118.854982 -399.335244)
		(width 0.14224)
		(layer "In13.Cu")
		(net "P5E_CPU1_P3_RX_BUF_DP<3>")
	)
	(segment
		(start 118.057422 -395.073886)
		(end 118.194582 -394.936726)
		(width 0.14224)
		(layer "In13.Cu")
		(net "P5E_CPU1_P3_RX_BUF_DP<3>")
	)
	(segment
		(start 123.966224 -405.574754)
		(end 123.453906 -405.574754)
		(width 0.14224)
		(layer "In13.Cu")
		(net "P5E_CPU1_P3_RX_BUF_DP<3>")
	)
	(segment
		(start 122.94616 -403.620478)
		(end 122.045222 -402.71954)
		(width 0.14224)
		(layer "In13.Cu")
		(net "P5E_CPU1_P3_RX_BUF_DP<3>")
	)
	(segment
		(start 130.952748 -417.085272)
		(end 130.126994 -416.279838)
		(width 0.14224)
		(layer "In13.Cu")
		(net "P5E_CPU1_P3_RX_BUF_DP<3>")
	)
	(segment
		(start 121.54916 -402.223478)
		(end 121.247662 -401.92198)
		(width 0.14224)
		(layer "In13.Cu")
		(net "P5E_CPU1_P3_RX_BUF_DP<3>")
	)
	(arc
		(start 126.188216 -411.894274)
		(mid 126.091695 -411.575995)
		(end 125.834648 -411.364938)
		(width 0.14224)
		(layer "In13.Cu")
		(net "P5E_CPU1_P3_RX_BUF_DP<3>")
	)
	(arc
		(start 131.076192 -417.378134)
		(mid 131.044075 -417.219222)
		(end 130.952748 -417.085272)
		(width 0.14224)
		(layer "In13.Cu")
		(net "P5E_CPU1_P3_RX_BUF_DP<3>")
	)
	(arc
		(start 126.270258 -413.465264)
		(mid 126.210147 -413.402532)
		(end 126.188216 -413.318452)
		(width 0.14224)
		(layer "In13.Cu")
		(net "P5E_CPU1_P3_RX_BUF_DP<3>")
	)
	(arc
		(start 118.09476 -398.769078)
		(mid 118.067117 -398.727708)
		(end 118.057422 -398.678908)
		(width 0.14224)
		(layer "In13.Cu")
		(net "P5E_CPU1_P3_RX_BUF_DP<3>")
	)
	(arc
		(start 123.124976 -404.052024)
		(mid 123.0785 -403.818463)
		(end 122.94616 -403.620478)
		(width 0.14224)
		(layer "In13.Cu")
		(net "P5E_CPU1_P3_RX_BUF_DP<3>")
	)
	(segment
		(start 116.702586 -391.488676)
		(end 116.61394 -391.577322)
		(width 0.1016)
		(layer "F.Cu")
		(net "P5E_CPU1_P3_RX_BUF_DP<2>")
	)
	(segment
		(start 116.702586 -391.36574)
		(end 116.702586 -391.488676)
		(width 0.1016)
		(layer "F.Cu")
		(net "P5E_CPU1_P3_RX_BUF_DP<2>")
	)
	(segment
		(start 116.61394 -391.577322)
		(end 116.61394 -392.723878)
		(width 0.1016)
		(layer "F.Cu")
		(net "P5E_CPU1_P3_RX_BUF_DP<2>")
	)
	(segment
		(start 116.618004 -391.281158)
		(end 116.702586 -391.36574)
		(width 0.1016)
		(layer "F.Cu")
		(net "P5E_CPU1_P3_RX_BUF_DP<2>")
	)
	(segment
		(start 117.17782 -392.977116)
		(end 117.316504 -393.1158)
		(width 0.1016)
		(layer "F.Cu")
		(net "P5E_CPU1_P3_RX_BUF_DP<2>")
	)
	(segment
		(start 117.316504 -393.1158)
		(end 117.316504 -393.292838)
		(width 0.1016)
		(layer "F.Cu")
		(net "P5E_CPU1_P3_RX_BUF_DP<2>")
	)
	(segment
		(start 116.867178 -392.977116)
		(end 117.17782 -392.977116)
		(width 0.1016)
		(layer "F.Cu")
		(net "P5E_CPU1_P3_RX_BUF_DP<2>")
	)
	(segment
		(start 116.61394 -392.723878)
		(end 116.867178 -392.977116)
		(width 0.1016)
		(layer "F.Cu")
		(net "P5E_CPU1_P3_RX_BUF_DP<2>")
	)
	(segment
		(start 121.593356 -407.757122)
		(end 121.593356 -406.424892)
		(width 0.14224)
		(layer "In13.Cu")
		(net "P5E_CPU1_P3_RX_BUF_DP<2>")
	)
	(segment
		(start 125.121162 -414.610804)
		(end 125.046994 -414.43148)
		(width 0.14224)
		(layer "In13.Cu")
		(net "P5E_CPU1_P3_RX_BUF_DP<2>")
	)
	(segment
		(start 117.177058 -392.989562)
		(end 117.316504 -393.129008)
		(width 0.14224)
		(layer "In13.Cu")
		(net "P5E_CPU1_P3_RX_BUF_DP<2>")
	)
	(segment
		(start 121.730516 -407.894282)
		(end 121.593356 -407.757122)
		(width 0.14224)
		(layer "In13.Cu")
		(net "P5E_CPU1_P3_RX_BUF_DP<2>")
	)
	(segment
		(start 120.061736 -405.185118)
		(end 120.061736 -403.77745)
		(width 0.14224)
		(layer "In13.Cu")
		(net "P5E_CPU1_P3_RX_BUF_DP<2>")
	)
	(segment
		(start 120.390666 -405.574754)
		(end 120.319038 -405.545036)
		(width 0.14224)
		(layer "In13.Cu")
		(net "P5E_CPU1_P3_RX_BUF_DP<2>")
	)
	(segment
		(start 117.151912 -399.946114)
		(end 116.92636 -399.671032)
		(width 0.14224)
		(layer "In13.Cu")
		(net "P5E_CPU1_P3_RX_BUF_DP<2>")
	)
	(segment
		(start 120.319038 -405.545036)
		(end 120.13438 -405.360378)
		(width 0.14224)
		(layer "In13.Cu")
		(net "P5E_CPU1_P3_RX_BUF_DP<2>")
	)
	(segment
		(start 121.730516 -409.448762)
		(end 121.730516 -409.022042)
		(width 0.14224)
		(layer "In13.Cu")
		(net "P5E_CPU1_P3_RX_BUF_DP<2>")
	)
	(segment
		(start 117.344952 -399.965164)
		(end 117.151912 -399.946114)
		(width 0.14224)
		(layer "In13.Cu")
		(net "P5E_CPU1_P3_RX_BUF_DP<2>")
	)
	(segment
		(start 129.611628 -433.756816)
		(end 129.441702 -433.756816)
		(width 0.14224)
		(layer "In13.Cu")
		(net "P5E_CPU1_P3_RX_BUF_DP<2>")
	)
	(segment
		(start 116.857526 -396.80007)
		(end 116.857526 -396.37335)
		(width 0.14224)
		(layer "In13.Cu")
		(net "P5E_CPU1_P3_RX_BUF_DP<2>")
	)
	(segment
		(start 116.994686 -395.80947)
		(end 116.857526 -395.67231)
		(width 0.14224)
		(layer "In13.Cu")
		(net "P5E_CPU1_P3_RX_BUF_DP<2>")
	)
	(segment
		(start 116.994686 -396.23619)
		(end 116.994686 -395.80947)
		(width 0.14224)
		(layer "In13.Cu")
		(net "P5E_CPU1_P3_RX_BUF_DP<2>")
	)
	(segment
		(start 121.075196 -405.646128)
		(end 120.902984 -405.574754)
		(width 0.14224)
		(layer "In13.Cu")
		(net "P5E_CPU1_P3_RX_BUF_DP<2>")
	)
	(segment
		(start 116.994686 -398.06499)
		(end 116.857526 -397.92783)
		(width 0.14224)
		(layer "In13.Cu")
		(net "P5E_CPU1_P3_RX_BUF_DP<2>")
	)
	(segment
		(start 121.730516 -408.321002)
		(end 121.730516 -407.894282)
		(width 0.14224)
		(layer "In13.Cu")
		(net "P5E_CPU1_P3_RX_BUF_DP<2>")
	)
	(segment
		(start 119.034052 -402.023326)
		(end 118.841012 -402.004276)
		(width 0.14224)
		(layer "In13.Cu")
		(net "P5E_CPU1_P3_RX_BUF_DP<2>")
	)
	(segment
		(start 121.730516 -409.022042)
		(end 121.593356 -408.884882)
		(width 0.14224)
		(layer "In13.Cu")
		(net "P5E_CPU1_P3_RX_BUF_DP<2>")
	)
	(segment
		(start 129.327656 -433.709572)
		(end 129.12344 -433.505356)
		(width 0.14224)
		(layer "In13.Cu")
		(net "P5E_CPU1_P3_RX_BUF_DP<2>")
	)
	(segment
		(start 125.046994 -414.43148)
		(end 124.652532 -414.268158)
		(width 0.14224)
		(layer "In13.Cu")
		(net "P5E_CPU1_P3_RX_BUF_DP<2>")
	)
	(segment
		(start 116.857526 -393.129008)
		(end 116.996972 -392.989562)
		(width 0.14224)
		(layer "In13.Cu")
		(net "P5E_CPU1_P3_RX_BUF_DP<2>")
	)
	(segment
		(start 118.312184 -401.360132)
		(end 118.331234 -401.167092)
		(width 0.14224)
		(layer "In13.Cu")
		(net "P5E_CPU1_P3_RX_BUF_DP<2>")
	)
	(segment
		(start 117.316504 -393.129008)
		(end 117.316504 -393.292838)
		(width 0.14224)
		(layer "In13.Cu")
		(net "P5E_CPU1_P3_RX_BUF_DP<2>")
	)
	(segment
		(start 119.30507 -402.353526)
		(end 119.034052 -402.023326)
		(width 0.14224)
		(layer "In13.Cu")
		(net "P5E_CPU1_P3_RX_BUF_DP<2>")
	)
	(segment
		(start 121.408952 -405.979884)
		(end 121.075196 -405.646128)
		(width 0.14224)
		(layer "In13.Cu")
		(net "P5E_CPU1_P3_RX_BUF_DP<2>")
	)
	(segment
		(start 121.593356 -408.458162)
		(end 121.730516 -408.321002)
		(width 0.14224)
		(layer "In13.Cu")
		(net "P5E_CPU1_P3_RX_BUF_DP<2>")
	)
	(segment
		(start 116.857526 -399.478754)
		(end 116.857526 -398.62887)
		(width 0.14224)
		(layer "In13.Cu")
		(net "P5E_CPU1_P3_RX_BUF_DP<2>")
	)
	(segment
		(start 121.593356 -408.884882)
		(end 121.593356 -408.458162)
		(width 0.14224)
		(layer "In13.Cu")
		(net "P5E_CPU1_P3_RX_BUF_DP<2>")
	)
	(segment
		(start 118.060216 -400.836892)
		(end 117.867176 -400.817842)
		(width 0.14224)
		(layer "In13.Cu")
		(net "P5E_CPU1_P3_RX_BUF_DP<2>")
	)
	(segment
		(start 120.902984 -405.574754)
		(end 120.390666 -405.574754)
		(width 0.14224)
		(layer "In13.Cu")
		(net "P5E_CPU1_P3_RX_BUF_DP<2>")
	)
	(segment
		(start 124.473462 -414.342326)
		(end 123.873768 -414.093914)
		(width 0.14224)
		(layer "In13.Cu")
		(net "P5E_CPU1_P3_RX_BUF_DP<2>")
	)
	(segment
		(start 117.867176 -400.817842)
		(end 117.596666 -400.48815)
		(width 0.14224)
		(layer "In13.Cu")
		(net "P5E_CPU1_P3_RX_BUF_DP<2>")
	)
	(segment
		(start 121.593356 -409.585922)
		(end 121.730516 -409.448762)
		(width 0.14224)
		(layer "In13.Cu")
		(net "P5E_CPU1_P3_RX_BUF_DP<2>")
	)
	(segment
		(start 116.857526 -395.67231)
		(end 116.857526 -395.24559)
		(width 0.14224)
		(layer "In13.Cu")
		(net "P5E_CPU1_P3_RX_BUF_DP<2>")
	)
	(segment
		(start 116.994686 -396.93723)
		(end 116.857526 -396.80007)
		(width 0.14224)
		(layer "In13.Cu")
		(net "P5E_CPU1_P3_RX_BUF_DP<2>")
	)
	(segment
		(start 129.749804 -433.61864)
		(end 129.611628 -433.756816)
		(width 0.14224)
		(layer "In13.Cu")
		(net "P5E_CPU1_P3_RX_BUF_DP<2>")
	)
	(segment
		(start 128.652016 -416.679126)
		(end 126.26213 -415.083498)
		(width 0.14224)
		(layer "In13.Cu")
		(net "P5E_CPU1_P3_RX_BUF_DP<2>")
	)
	(segment
		(start 117.596666 -400.48815)
		(end 117.615716 -400.29511)
		(width 0.14224)
		(layer "In13.Cu")
		(net "P5E_CPU1_P3_RX_BUF_DP<2>")
	)
	(segment
		(start 117.615716 -400.29511)
		(end 117.344952 -399.965164)
		(width 0.14224)
		(layer "In13.Cu")
		(net "P5E_CPU1_P3_RX_BUF_DP<2>")
	)
	(segment
		(start 123.093988 -411.87243)
		(end 122.988832 -411.618176)
		(width 0.14224)
		(layer "In13.Cu")
		(net "P5E_CPU1_P3_RX_BUF_DP<2>")
	)
	(segment
		(start 121.801636 -410.852874)
		(end 121.703592 -410.75483)
		(width 0.14224)
		(layer "In13.Cu")
		(net "P5E_CPU1_P3_RX_BUF_DP<2>")
	)
	(segment
		(start 118.841012 -402.004276)
		(end 118.312184 -401.360132)
		(width 0.14224)
		(layer "In13.Cu")
		(net "P5E_CPU1_P3_RX_BUF_DP<2>")
	)
	(segment
		(start 116.857526 -397.50111)
		(end 116.994686 -397.36395)
		(width 0.14224)
		(layer "In13.Cu")
		(net "P5E_CPU1_P3_RX_BUF_DP<2>")
	)
	(segment
		(start 123.124976 -413.451294)
		(end 123.124976 -412.028894)
		(width 0.14224)
		(layer "In13.Cu")
		(net "P5E_CPU1_P3_RX_BUF_DP<2>")
	)
	(segment
		(start 121.593356 -410.488638)
		(end 121.593356 -409.585922)
		(width 0.14224)
		(layer "In13.Cu")
		(net "P5E_CPU1_P3_RX_BUF_DP<2>")
	)
	(segment
		(start 123.394216 -413.773366)
		(end 123.162314 -413.541464)
		(width 0.14224)
		(layer "In13.Cu")
		(net "P5E_CPU1_P3_RX_BUF_DP<2>")
	)
	(segment
		(start 116.857526 -395.24559)
		(end 116.994686 -395.10843)
		(width 0.14224)
		(layer "In13.Cu")
		(net "P5E_CPU1_P3_RX_BUF_DP<2>")
	)
	(segment
		(start 120.13438 -405.360378)
		(end 120.061736 -405.185118)
		(width 0.14224)
		(layer "In13.Cu")
		(net "P5E_CPU1_P3_RX_BUF_DP<2>")
	)
	(segment
		(start 116.994686 -394.68171)
		(end 116.857526 -394.54455)
		(width 0.14224)
		(layer "In13.Cu")
		(net "P5E_CPU1_P3_RX_BUF_DP<2>")
	)
	(segment
		(start 116.857526 -397.92783)
		(end 116.857526 -397.50111)
		(width 0.14224)
		(layer "In13.Cu")
		(net "P5E_CPU1_P3_RX_BUF_DP<2>")
	)
	(segment
		(start 119.28602 -402.546566)
		(end 119.30507 -402.353526)
		(width 0.14224)
		(layer "In13.Cu")
		(net "P5E_CPU1_P3_RX_BUF_DP<2>")
	)
	(segment
		(start 116.857526 -394.54455)
		(end 116.857526 -393.129008)
		(width 0.14224)
		(layer "In13.Cu")
		(net "P5E_CPU1_P3_RX_BUF_DP<2>")
	)
	(segment
		(start 116.857526 -398.62887)
		(end 116.994686 -398.49171)
		(width 0.14224)
		(layer "In13.Cu")
		(net "P5E_CPU1_P3_RX_BUF_DP<2>")
	)
	(segment
		(start 116.994686 -398.49171)
		(end 116.994686 -398.06499)
		(width 0.14224)
		(layer "In13.Cu")
		(net "P5E_CPU1_P3_RX_BUF_DP<2>")
	)
	(segment
		(start 126.26213 -415.083498)
		(end 125.121162 -414.610804)
		(width 0.14224)
		(layer "In13.Cu")
		(net "P5E_CPU1_P3_RX_BUF_DP<2>")
	)
	(segment
		(start 129.076196 -433.39131)
		(end 129.076196 -417.472876)
		(width 0.14224)
		(layer "In13.Cu")
		(net "P5E_CPU1_P3_RX_BUF_DP<2>")
	)
	(segment
		(start 116.857526 -396.37335)
		(end 116.994686 -396.23619)
		(width 0.14224)
		(layer "In13.Cu")
		(net "P5E_CPU1_P3_RX_BUF_DP<2>")
	)
	(segment
		(start 116.994686 -397.36395)
		(end 116.994686 -396.93723)
		(width 0.14224)
		(layer "In13.Cu")
		(net "P5E_CPU1_P3_RX_BUF_DP<2>")
	)
	(segment
		(start 121.593356 -406.424892)
		(end 121.408952 -405.979884)
		(width 0.14224)
		(layer "In13.Cu")
		(net "P5E_CPU1_P3_RX_BUF_DP<2>")
	)
	(segment
		(start 119.881142 -403.271482)
		(end 119.28602 -402.546566)
		(width 0.14224)
		(layer "In13.Cu")
		(net "P5E_CPU1_P3_RX_BUF_DP<2>")
	)
	(segment
		(start 122.675904 -411.305756)
		(end 122.159776 -411.092142)
		(width 0.14224)
		(layer "In13.Cu")
		(net "P5E_CPU1_P3_RX_BUF_DP<2>")
	)
	(segment
		(start 118.331234 -401.167092)
		(end 118.060216 -400.836892)
		(width 0.14224)
		(layer "In13.Cu")
		(net "P5E_CPU1_P3_RX_BUF_DP<2>")
	)
	(segment
		(start 116.996972 -392.989562)
		(end 117.177058 -392.989562)
		(width 0.14224)
		(layer "In13.Cu")
		(net "P5E_CPU1_P3_RX_BUF_DP<2>")
	)
	(segment
		(start 124.652532 -414.268158)
		(end 124.473462 -414.342326)
		(width 0.14224)
		(layer "In13.Cu")
		(net "P5E_CPU1_P3_RX_BUF_DP<2>")
	)
	(segment
		(start 116.994686 -395.10843)
		(end 116.994686 -394.68171)
		(width 0.14224)
		(layer "In13.Cu")
		(net "P5E_CPU1_P3_RX_BUF_DP<2>")
	)
	(segment
		(start 129.749804 -433.289964)
		(end 129.749804 -433.61864)
		(width 0.14224)
		(layer "In13.Cu")
		(net "P5E_CPU1_P3_RX_BUF_DP<2>")
	)
	(arc
		(start 129.076196 -417.472876)
		(mid 128.963557 -417.022854)
		(end 128.652016 -416.679126)
		(width 0.14224)
		(layer "In13.Cu")
		(net "P5E_CPU1_P3_RX_BUF_DP<2>")
	)
	(arc
		(start 122.988832 -411.618176)
		(mid 122.863494 -411.430782)
		(end 122.675904 -411.305756)
		(width 0.14224)
		(layer "In13.Cu")
		(net "P5E_CPU1_P3_RX_BUF_DP<2>")
	)
	(arc
		(start 129.441702 -433.756816)
		(mid 129.379979 -433.744539)
		(end 129.327656 -433.709572)
		(width 0.14224)
		(layer "In13.Cu")
		(net "P5E_CPU1_P3_RX_BUF_DP<2>")
	)
	(arc
		(start 123.124976 -412.028894)
		(mid 123.117183 -411.949136)
		(end 123.093988 -411.87243)
		(width 0.14224)
		(layer "In13.Cu")
		(net "P5E_CPU1_P3_RX_BUF_DP<2>")
	)
	(arc
		(start 116.92636 -399.671032)
		(mid 116.875262 -399.580866)
		(end 116.857526 -399.478754)
		(width 0.14224)
		(layer "In13.Cu")
		(net "P5E_CPU1_P3_RX_BUF_DP<2>")
	)
	(arc
		(start 121.703592 -410.75483)
		(mid 121.621987 -410.6327)
		(end 121.593356 -410.488638)
		(width 0.14224)
		(layer "In13.Cu")
		(net "P5E_CPU1_P3_RX_BUF_DP<2>")
	)
	(arc
		(start 123.162314 -413.541464)
		(mid 123.134671 -413.500094)
		(end 123.124976 -413.451294)
		(width 0.14224)
		(layer "In13.Cu")
		(net "P5E_CPU1_P3_RX_BUF_DP<2>")
	)
	(arc
		(start 122.159776 -411.092142)
		(mid 121.968918 -410.990152)
		(end 121.801636 -410.852874)
		(width 0.14224)
		(layer "In13.Cu")
		(net "P5E_CPU1_P3_RX_BUF_DP<2>")
	)
	(arc
		(start 129.12344 -433.505356)
		(mid 129.088478 -433.453031)
		(end 129.076196 -433.39131)
		(width 0.14224)
		(layer "In13.Cu")
		(net "P5E_CPU1_P3_RX_BUF_DP<2>")
	)
	(arc
		(start 120.061736 -403.77745)
		(mid 120.015301 -403.508818)
		(end 119.881142 -403.271482)
		(width 0.14224)
		(layer "In13.Cu")
		(net "P5E_CPU1_P3_RX_BUF_DP<2>")
	)
	(arc
		(start 123.873768 -414.093914)
		(mid 123.618209 -413.957252)
		(end 123.394216 -413.773366)
		(width 0.14224)
		(layer "In13.Cu")
		(net "P5E_CPU1_P3_RX_BUF_DP<2>")
	)
	(segment
		(start 115.417854 -391.281158)
		(end 115.502436 -391.36574)
		(width 0.1016)
		(layer "F.Cu")
		(net "P5E_CPU1_P3_RX_BUF_DP<1>")
	)
	(segment
		(start 115.41379 -391.577322)
		(end 115.41379 -392.723878)
		(width 0.1016)
		(layer "F.Cu")
		(net "P5E_CPU1_P3_RX_BUF_DP<1>")
	)
	(segment
		(start 116.116354 -393.1158)
		(end 116.116354 -393.292838)
		(width 0.1016)
		(layer "F.Cu")
		(net "P5E_CPU1_P3_RX_BUF_DP<1>")
	)
	(segment
		(start 115.97767 -392.977116)
		(end 116.116354 -393.1158)
		(width 0.1016)
		(layer "F.Cu")
		(net "P5E_CPU1_P3_RX_BUF_DP<1>")
	)
	(segment
		(start 115.667028 -392.977116)
		(end 115.97767 -392.977116)
		(width 0.1016)
		(layer "F.Cu")
		(net "P5E_CPU1_P3_RX_BUF_DP<1>")
	)
	(segment
		(start 115.502436 -391.488676)
		(end 115.41379 -391.577322)
		(width 0.1016)
		(layer "F.Cu")
		(net "P5E_CPU1_P3_RX_BUF_DP<1>")
	)
	(segment
		(start 115.41379 -392.723878)
		(end 115.667028 -392.977116)
		(width 0.1016)
		(layer "F.Cu")
		(net "P5E_CPU1_P3_RX_BUF_DP<1>")
	)
	(segment
		(start 115.502436 -391.36574)
		(end 115.502436 -391.488676)
		(width 0.1016)
		(layer "F.Cu")
		(net "P5E_CPU1_P3_RX_BUF_DP<1>")
	)
	(segment
		(start 116.431822 -401.84832)
		(end 116.252244 -401.774152)
		(width 0.14224)
		(layer "In13.Cu")
		(net "P5E_CPU1_P3_RX_BUF_DP<1>")
	)
	(segment
		(start 115.794536 -394.46327)
		(end 115.657376 -394.32611)
		(width 0.14224)
		(layer "In13.Cu")
		(net "P5E_CPU1_P3_RX_BUF_DP<1>")
	)
	(segment
		(start 115.657376 -400.312382)
		(end 115.657376 -399.53819)
		(width 0.14224)
		(layer "In13.Cu")
		(net "P5E_CPU1_P3_RX_BUF_DP<1>")
	)
	(segment
		(start 116.163344 -401.20062)
		(end 116.000022 -400.806158)
		(width 0.14224)
		(layer "In13.Cu")
		(net "P5E_CPU1_P3_RX_BUF_DP<1>")
	)
	(segment
		(start 127.374904 -434.756814)
		(end 127.0762 -434.45811)
		(width 0.14224)
		(layer "In13.Cu")
		(net "P5E_CPU1_P3_RX_BUF_DP<1>")
	)
	(segment
		(start 118.530116 -409.414218)
		(end 118.667276 -409.277058)
		(width 0.14224)
		(layer "In13.Cu")
		(net "P5E_CPU1_P3_RX_BUF_DP<1>")
	)
	(segment
		(start 121.411238 -414.06953)
		(end 121.231914 -414.143698)
		(width 0.14224)
		(layer "In13.Cu")
		(net "P5E_CPU1_P3_RX_BUF_DP<1>")
	)
	(segment
		(start 118.07063 -405.704802)
		(end 117.756686 -405.574754)
		(width 0.14224)
		(layer "In13.Cu")
		(net "P5E_CPU1_P3_RX_BUF_DP<1>")
	)
	(segment
		(start 118.530116 -410.337508)
		(end 118.530116 -409.414218)
		(width 0.14224)
		(layer "In13.Cu")
		(net "P5E_CPU1_P3_RX_BUF_DP<1>")
	)
	(segment
		(start 118.667276 -408.060144)
		(end 118.667276 -407.633424)
		(width 0.14224)
		(layer "In13.Cu")
		(net "P5E_CPU1_P3_RX_BUF_DP<1>")
	)
	(segment
		(start 115.976908 -392.989562)
		(end 116.116354 -393.129008)
		(width 0.14224)
		(layer "In13.Cu")
		(net "P5E_CPU1_P3_RX_BUF_DP<1>")
	)
	(segment
		(start 116.116354 -393.129008)
		(end 116.116354 -393.292838)
		(width 0.14224)
		(layer "In13.Cu")
		(net "P5E_CPU1_P3_RX_BUF_DP<1>")
	)
	(segment
		(start 118.667276 -409.277058)
		(end 118.667276 -408.850338)
		(width 0.14224)
		(layer "In13.Cu")
		(net "P5E_CPU1_P3_RX_BUF_DP<1>")
	)
	(segment
		(start 118.530116 -408.197304)
		(end 118.667276 -408.060144)
		(width 0.14224)
		(layer "In13.Cu")
		(net "P5E_CPU1_P3_RX_BUF_DP<1>")
	)
	(segment
		(start 127.611632 -434.756814)
		(end 127.374904 -434.756814)
		(width 0.14224)
		(layer "In13.Cu")
		(net "P5E_CPU1_P3_RX_BUF_DP<1>")
	)
	(segment
		(start 116.998496 -405.185118)
		(end 116.998496 -403.575774)
		(width 0.14224)
		(layer "In13.Cu")
		(net "P5E_CPU1_P3_RX_BUF_DP<1>")
	)
	(segment
		(start 115.657376 -396.58163)
		(end 115.657376 -396.15491)
		(width 0.14224)
		(layer "In13.Cu")
		(net "P5E_CPU1_P3_RX_BUF_DP<1>")
	)
	(segment
		(start 120.061736 -413.442404)
		(end 120.061736 -412.031688)
		(width 0.14224)
		(layer "In13.Cu")
		(net "P5E_CPU1_P3_RX_BUF_DP<1>")
	)
	(segment
		(start 115.657376 -399.53819)
		(end 115.794536 -399.40103)
		(width 0.14224)
		(layer "In13.Cu")
		(net "P5E_CPU1_P3_RX_BUF_DP<1>")
	)
	(segment
		(start 117.327426 -405.574754)
		(end 117.255798 -405.545036)
		(width 0.14224)
		(layer "In13.Cu")
		(net "P5E_CPU1_P3_RX_BUF_DP<1>")
	)
	(segment
		(start 115.657376 -396.15491)
		(end 115.794536 -396.01775)
		(width 0.14224)
		(layer "In13.Cu")
		(net "P5E_CPU1_P3_RX_BUF_DP<1>")
	)
	(segment
		(start 121.879868 -414.412176)
		(end 121.8057 -414.232598)
		(width 0.14224)
		(layer "In13.Cu")
		(net "P5E_CPU1_P3_RX_BUF_DP<1>")
	)
	(segment
		(start 115.657376 -398.83715)
		(end 115.657376 -398.41043)
		(width 0.14224)
		(layer "In13.Cu")
		(net "P5E_CPU1_P3_RX_BUF_DP<1>")
	)
	(segment
		(start 121.8057 -414.232598)
		(end 121.411238 -414.06953)
		(width 0.14224)
		(layer "In13.Cu")
		(net "P5E_CPU1_P3_RX_BUF_DP<1>")
	)
	(segment
		(start 115.794536 -396.71879)
		(end 115.657376 -396.58163)
		(width 0.14224)
		(layer "In13.Cu")
		(net "P5E_CPU1_P3_RX_BUF_DP<1>")
	)
	(segment
		(start 124.877322 -415.65322)
		(end 121.879868 -414.412176)
		(width 0.14224)
		(layer "In13.Cu")
		(net "P5E_CPU1_P3_RX_BUF_DP<1>")
	)
	(segment
		(start 116.252244 -401.774152)
		(end 116.089176 -401.379944)
		(width 0.14224)
		(layer "In13.Cu")
		(net "P5E_CPU1_P3_RX_BUF_DP<1>")
	)
	(segment
		(start 117.07114 -405.360378)
		(end 116.998496 -405.185118)
		(width 0.14224)
		(layer "In13.Cu")
		(net "P5E_CPU1_P3_RX_BUF_DP<1>")
	)
	(segment
		(start 117.756686 -405.574754)
		(end 117.327426 -405.574754)
		(width 0.14224)
		(layer "In13.Cu")
		(net "P5E_CPU1_P3_RX_BUF_DP<1>")
	)
	(segment
		(start 115.657376 -395.02715)
		(end 115.794536 -394.88999)
		(width 0.14224)
		(layer "In13.Cu")
		(net "P5E_CPU1_P3_RX_BUF_DP<1>")
	)
	(segment
		(start 119.657114 -411.324044)
		(end 118.864888 -410.995876)
		(width 0.14224)
		(layer "In13.Cu")
		(net "P5E_CPU1_P3_RX_BUF_DP<1>")
	)
	(segment
		(start 115.794536 -398.97431)
		(end 115.657376 -398.83715)
		(width 0.14224)
		(layer "In13.Cu")
		(net "P5E_CPU1_P3_RX_BUF_DP<1>")
	)
	(segment
		(start 118.667276 -407.633424)
		(end 118.530116 -407.496264)
		(width 0.14224)
		(layer "In13.Cu")
		(net "P5E_CPU1_P3_RX_BUF_DP<1>")
	)
	(segment
		(start 118.530116 -406.424892)
		(end 118.345712 -405.979884)
		(width 0.14224)
		(layer "In13.Cu")
		(net "P5E_CPU1_P3_RX_BUF_DP<1>")
	)
	(segment
		(start 115.794536 -397.14551)
		(end 115.794536 -396.71879)
		(width 0.14224)
		(layer "In13.Cu")
		(net "P5E_CPU1_P3_RX_BUF_DP<1>")
	)
	(segment
		(start 116.089176 -401.379944)
		(end 116.163344 -401.20062)
		(width 0.14224)
		(layer "In13.Cu")
		(net "P5E_CPU1_P3_RX_BUF_DP<1>")
	)
	(segment
		(start 127.749808 -434.289962)
		(end 127.749808 -434.618638)
		(width 0.14224)
		(layer "In13.Cu")
		(net "P5E_CPU1_P3_RX_BUF_DP<1>")
	)
	(segment
		(start 116.595144 -402.242782)
		(end 116.431822 -401.84832)
		(width 0.14224)
		(layer "In13.Cu")
		(net "P5E_CPU1_P3_RX_BUF_DP<1>")
	)
	(segment
		(start 115.657376 -394.32611)
		(end 115.657376 -393.129008)
		(width 0.14224)
		(layer "In13.Cu")
		(net "P5E_CPU1_P3_RX_BUF_DP<1>")
	)
	(segment
		(start 115.794536 -398.27327)
		(end 115.794536 -397.84655)
		(width 0.14224)
		(layer "In13.Cu")
		(net "P5E_CPU1_P3_RX_BUF_DP<1>")
	)
	(segment
		(start 115.657376 -397.70939)
		(end 115.657376 -397.28267)
		(width 0.14224)
		(layer "In13.Cu")
		(net "P5E_CPU1_P3_RX_BUF_DP<1>")
	)
	(segment
		(start 118.667276 -408.850338)
		(end 118.530116 -408.713178)
		(width 0.14224)
		(layer "In13.Cu")
		(net "P5E_CPU1_P3_RX_BUF_DP<1>")
	)
	(segment
		(start 126.415292 -416.68065)
		(end 124.877322 -415.65322)
		(width 0.14224)
		(layer "In13.Cu")
		(net "P5E_CPU1_P3_RX_BUF_DP<1>")
	)
	(segment
		(start 115.657376 -398.41043)
		(end 115.794536 -398.27327)
		(width 0.14224)
		(layer "In13.Cu")
		(net "P5E_CPU1_P3_RX_BUF_DP<1>")
	)
	(segment
		(start 127.749808 -434.618638)
		(end 127.611632 -434.756814)
		(width 0.14224)
		(layer "In13.Cu")
		(net "P5E_CPU1_P3_RX_BUF_DP<1>")
	)
	(segment
		(start 115.657376 -397.28267)
		(end 115.794536 -397.14551)
		(width 0.14224)
		(layer "In13.Cu")
		(net "P5E_CPU1_P3_RX_BUF_DP<1>")
	)
	(segment
		(start 126.85522 -417.166298)
		(end 126.415292 -416.68065)
		(width 0.14224)
		(layer "In13.Cu")
		(net "P5E_CPU1_P3_RX_BUF_DP<1>")
	)
	(segment
		(start 118.530116 -407.496264)
		(end 118.530116 -406.424892)
		(width 0.14224)
		(layer "In13.Cu")
		(net "P5E_CPU1_P3_RX_BUF_DP<1>")
	)
	(segment
		(start 118.345712 -405.979884)
		(end 118.07063 -405.704802)
		(width 0.14224)
		(layer "In13.Cu")
		(net "P5E_CPU1_P3_RX_BUF_DP<1>")
	)
	(segment
		(start 115.657376 -393.129008)
		(end 115.796822 -392.989562)
		(width 0.14224)
		(layer "In13.Cu")
		(net "P5E_CPU1_P3_RX_BUF_DP<1>")
	)
	(segment
		(start 115.794536 -394.88999)
		(end 115.794536 -394.46327)
		(width 0.14224)
		(layer "In13.Cu")
		(net "P5E_CPU1_P3_RX_BUF_DP<1>")
	)
	(segment
		(start 115.796822 -392.989562)
		(end 115.976908 -392.989562)
		(width 0.14224)
		(layer "In13.Cu")
		(net "P5E_CPU1_P3_RX_BUF_DP<1>")
	)
	(segment
		(start 118.530116 -408.713178)
		(end 118.530116 -408.197304)
		(width 0.14224)
		(layer "In13.Cu")
		(net "P5E_CPU1_P3_RX_BUF_DP<1>")
	)
	(segment
		(start 115.794536 -396.01775)
		(end 115.794536 -395.59103)
		(width 0.14224)
		(layer "In13.Cu")
		(net "P5E_CPU1_P3_RX_BUF_DP<1>")
	)
	(segment
		(start 120.566942 -413.868362)
		(end 120.13565 -413.580834)
		(width 0.14224)
		(layer "In13.Cu")
		(net "P5E_CPU1_P3_RX_BUF_DP<1>")
	)
	(segment
		(start 116.998496 -403.575774)
		(end 116.520722 -402.422106)
		(width 0.14224)
		(layer "In13.Cu")
		(net "P5E_CPU1_P3_RX_BUF_DP<1>")
	)
	(segment
		(start 120.035574 -411.900116)
		(end 119.89689 -411.564328)
		(width 0.14224)
		(layer "In13.Cu")
		(net "P5E_CPU1_P3_RX_BUF_DP<1>")
	)
	(segment
		(start 115.657376 -395.45387)
		(end 115.657376 -395.02715)
		(width 0.14224)
		(layer "In13.Cu")
		(net "P5E_CPU1_P3_RX_BUF_DP<1>")
	)
	(segment
		(start 127.0762 -434.45811)
		(end 127.0762 -417.739322)
		(width 0.14224)
		(layer "In13.Cu")
		(net "P5E_CPU1_P3_RX_BUF_DP<1>")
	)
	(segment
		(start 117.255798 -405.545036)
		(end 117.07114 -405.360378)
		(width 0.14224)
		(layer "In13.Cu")
		(net "P5E_CPU1_P3_RX_BUF_DP<1>")
	)
	(segment
		(start 115.820444 -400.73199)
		(end 115.667028 -400.36115)
		(width 0.14224)
		(layer "In13.Cu")
		(net "P5E_CPU1_P3_RX_BUF_DP<1>")
	)
	(segment
		(start 121.231914 -414.143698)
		(end 120.566942 -413.868362)
		(width 0.14224)
		(layer "In13.Cu")
		(net "P5E_CPU1_P3_RX_BUF_DP<1>")
	)
	(segment
		(start 115.794536 -397.84655)
		(end 115.657376 -397.70939)
		(width 0.14224)
		(layer "In13.Cu")
		(net "P5E_CPU1_P3_RX_BUF_DP<1>")
	)
	(segment
		(start 115.794536 -399.40103)
		(end 115.794536 -398.97431)
		(width 0.14224)
		(layer "In13.Cu")
		(net "P5E_CPU1_P3_RX_BUF_DP<1>")
	)
	(segment
		(start 116.000022 -400.806158)
		(end 115.820444 -400.73199)
		(width 0.14224)
		(layer "In13.Cu")
		(net "P5E_CPU1_P3_RX_BUF_DP<1>")
	)
	(segment
		(start 116.520722 -402.422106)
		(end 116.595144 -402.242782)
		(width 0.14224)
		(layer "In13.Cu")
		(net "P5E_CPU1_P3_RX_BUF_DP<1>")
	)
	(segment
		(start 115.794536 -395.59103)
		(end 115.657376 -395.45387)
		(width 0.14224)
		(layer "In13.Cu")
		(net "P5E_CPU1_P3_RX_BUF_DP<1>")
	)
	(arc
		(start 118.637304 -410.808932)
		(mid 118.606832 -410.753025)
		(end 118.586758 -410.6926)
		(width 0.14224)
		(layer "In13.Cu")
		(net "P5E_CPU1_P3_RX_BUF_DP<1>")
	)
	(arc
		(start 118.586758 -410.6926)
		(mid 118.561871 -410.578531)
		(end 118.54053 -410.463746)
		(width 0.14224)
		(layer "In13.Cu")
		(net "P5E_CPU1_P3_RX_BUF_DP<1>")
	)
	(arc
		(start 118.54053 -410.463746)
		(mid 118.532662 -410.400847)
		(end 118.530116 -410.337508)
		(width 0.14224)
		(layer "In13.Cu")
		(net "P5E_CPU1_P3_RX_BUF_DP<1>")
	)
	(arc
		(start 119.89689 -411.564328)
		(mid 119.800946 -411.420281)
		(end 119.657114 -411.324044)
		(width 0.14224)
		(layer "In13.Cu")
		(net "P5E_CPU1_P3_RX_BUF_DP<1>")
	)
	(arc
		(start 118.864888 -410.995876)
		(mid 118.737215 -410.919305)
		(end 118.637304 -410.808932)
		(width 0.14224)
		(layer "In13.Cu")
		(net "P5E_CPU1_P3_RX_BUF_DP<1>")
	)
	(arc
		(start 127.0762 -417.739322)
		(mid 127.019041 -417.432244)
		(end 126.85522 -417.166298)
		(width 0.14224)
		(layer "In13.Cu")
		(net "P5E_CPU1_P3_RX_BUF_DP<1>")
	)
	(arc
		(start 120.13565 -413.580834)
		(mid 120.081384 -413.520864)
		(end 120.061736 -413.442404)
		(width 0.14224)
		(layer "In13.Cu")
		(net "P5E_CPU1_P3_RX_BUF_DP<1>")
	)
	(arc
		(start 115.667028 -400.36115)
		(mid 115.659783 -400.337243)
		(end 115.657376 -400.312382)
		(width 0.14224)
		(layer "In13.Cu")
		(net "P5E_CPU1_P3_RX_BUF_DP<1>")
	)
	(arc
		(start 120.061736 -412.031688)
		(mid 120.055141 -411.96461)
		(end 120.035574 -411.900116)
		(width 0.14224)
		(layer "In13.Cu")
		(net "P5E_CPU1_P3_RX_BUF_DP<1>")
	)
	(segment
		(start 132.213858 -391.577322)
		(end 132.213858 -392.723878)
		(width 0.1016)
		(layer "F.Cu")
		(net "P5E_CPU1_P3_RX_BUF_DP<15>")
	)
	(segment
		(start 132.467096 -392.977116)
		(end 132.761228 -392.977116)
		(width 0.1016)
		(layer "F.Cu")
		(net "P5E_CPU1_P3_RX_BUF_DP<15>")
	)
	(segment
		(start 132.217922 -391.281158)
		(end 132.302504 -391.36574)
		(width 0.1016)
		(layer "F.Cu")
		(net "P5E_CPU1_P3_RX_BUF_DP<15>")
	)
	(segment
		(start 132.302504 -391.488676)
		(end 132.213858 -391.577322)
		(width 0.1016)
		(layer "F.Cu")
		(net "P5E_CPU1_P3_RX_BUF_DP<15>")
	)
	(segment
		(start 132.761228 -392.977116)
		(end 132.916422 -393.13231)
		(width 0.1016)
		(layer "F.Cu")
		(net "P5E_CPU1_P3_RX_BUF_DP<15>")
	)
	(segment
		(start 132.916422 -393.13231)
		(end 132.916422 -393.292838)
		(width 0.1016)
		(layer "F.Cu")
		(net "P5E_CPU1_P3_RX_BUF_DP<15>")
	)
	(segment
		(start 132.213858 -392.723878)
		(end 132.467096 -392.977116)
		(width 0.1016)
		(layer "F.Cu")
		(net "P5E_CPU1_P3_RX_BUF_DP<15>")
	)
	(segment
		(start 132.302504 -391.36574)
		(end 132.302504 -391.488676)
		(width 0.1016)
		(layer "F.Cu")
		(net "P5E_CPU1_P3_RX_BUF_DP<15>")
	)
	(segment
		(start 156.387546 -423.543476)
		(end 162.83178 -413.899096)
		(width 0.14224)
		(layer "In13.Cu")
		(net "P5E_CPU1_P3_RX_BUF_DP<15>")
	)
	(segment
		(start 159.883856 -403.80539)
		(end 159.501078 -402.881084)
		(width 0.14224)
		(layer "In13.Cu")
		(net "P5E_CPU1_P3_RX_BUF_DP<15>")
	)
	(segment
		(start 159.9565 -405.360378)
		(end 159.883856 -405.185118)
		(width 0.14224)
		(layer "In13.Cu")
		(net "P5E_CPU1_P3_RX_BUF_DP<15>")
	)
	(segment
		(start 162.621468 -411.356556)
		(end 161.713164 -410.980382)
		(width 0.14224)
		(layer "In13.Cu")
		(net "P5E_CPU1_P3_RX_BUF_DP<15>")
	)
	(segment
		(start 162.83178 -413.899096)
		(end 162.947096 -413.518604)
		(width 0.14224)
		(layer "In13.Cu")
		(net "P5E_CPU1_P3_RX_BUF_DP<15>")
	)
	(segment
		(start 161.415476 -408.161744)
		(end 161.552636 -408.024584)
		(width 0.14224)
		(layer "In13.Cu")
		(net "P5E_CPU1_P3_RX_BUF_DP<15>")
	)
	(segment
		(start 160.897316 -405.646128)
		(end 160.725104 -405.574754)
		(width 0.14224)
		(layer "In13.Cu")
		(net "P5E_CPU1_P3_RX_BUF_DP<15>")
	)
	(segment
		(start 137.986262 -395.24432)
		(end 137.863072 -395.094206)
		(width 0.14224)
		(layer "In13.Cu")
		(net "P5E_CPU1_P3_RX_BUF_DP<15>")
	)
	(segment
		(start 145.026634 -395.937486)
		(end 143.614902 -395.798548)
		(width 0.14224)
		(layer "In13.Cu")
		(net "P5E_CPU1_P3_RX_BUF_DP<15>")
	)
	(segment
		(start 135.41375 -394.852906)
		(end 135.26389 -394.976096)
		(width 0.14224)
		(layer "In13.Cu")
		(net "P5E_CPU1_P3_RX_BUF_DP<15>")
	)
	(segment
		(start 161.63417 -410.92755)
		(end 161.510472 -410.803852)
		(width 0.14224)
		(layer "In13.Cu")
		(net "P5E_CPU1_P3_RX_BUF_DP<15>")
	)
	(segment
		(start 151.46655 -397.400526)
		(end 149.889464 -396.747238)
		(width 0.14224)
		(layer "In13.Cu")
		(net "P5E_CPU1_P3_RX_BUF_DP<15>")
	)
	(segment
		(start 153.77414 -398.77746)
		(end 153.419048 -398.540224)
		(width 0.14224)
		(layer "In13.Cu")
		(net "P5E_CPU1_P3_RX_BUF_DP<15>")
	)
	(segment
		(start 156.357828 -434.739542)
		(end 156.076396 -434.45811)
		(width 0.14224)
		(layer "In13.Cu")
		(net "P5E_CPU1_P3_RX_BUF_DP<15>")
	)
	(segment
		(start 148.102574 -396.251938)
		(end 147.941284 -396.359634)
		(width 0.14224)
		(layer "In13.Cu")
		(net "P5E_CPU1_P3_RX_BUF_DP<15>")
	)
	(segment
		(start 159.883856 -405.185118)
		(end 159.883856 -403.80539)
		(width 0.14224)
		(layer "In13.Cu")
		(net "P5E_CPU1_P3_RX_BUF_DP<15>")
	)
	(segment
		(start 156.750004 -434.618638)
		(end 156.6291 -434.739542)
		(width 0.14224)
		(layer "In13.Cu")
		(net "P5E_CPU1_P3_RX_BUF_DP<15>")
	)
	(segment
		(start 160.141158 -405.545036)
		(end 159.9565 -405.360378)
		(width 0.14224)
		(layer "In13.Cu")
		(net "P5E_CPU1_P3_RX_BUF_DP<15>")
	)
	(segment
		(start 161.552636 -409.152344)
		(end 161.552636 -408.725624)
		(width 0.14224)
		(layer "In13.Cu")
		(net "P5E_CPU1_P3_RX_BUF_DP<15>")
	)
	(segment
		(start 132.5499 -394.297154)
		(end 132.457444 -394.172694)
		(width 0.14224)
		(layer "In13.Cu")
		(net "P5E_CPU1_P3_RX_BUF_DP<15>")
	)
	(segment
		(start 138.513566 -395.296136)
		(end 137.986262 -395.24432)
		(width 0.14224)
		(layer "In13.Cu")
		(net "P5E_CPU1_P3_RX_BUF_DP<15>")
	)
	(segment
		(start 142.91691 -395.729714)
		(end 140.565632 -395.49832)
		(width 0.14224)
		(layer "In13.Cu")
		(net "P5E_CPU1_P3_RX_BUF_DP<15>")
	)
	(segment
		(start 161.415476 -409.289504)
		(end 161.552636 -409.152344)
		(width 0.14224)
		(layer "In13.Cu")
		(net "P5E_CPU1_P3_RX_BUF_DP<15>")
	)
	(segment
		(start 160.725104 -405.574754)
		(end 160.212786 -405.574754)
		(width 0.14224)
		(layer "In13.Cu")
		(net "P5E_CPU1_P3_RX_BUF_DP<15>")
	)
	(segment
		(start 139.088368 -395.214856)
		(end 138.663426 -395.172946)
		(width 0.14224)
		(layer "In13.Cu")
		(net "P5E_CPU1_P3_RX_BUF_DP<15>")
	)
	(segment
		(start 137.863072 -395.094206)
		(end 137.43813 -395.052296)
		(width 0.14224)
		(layer "In13.Cu")
		(net "P5E_CPU1_P3_RX_BUF_DP<15>")
	)
	(segment
		(start 145.724626 -396.00632)
		(end 145.601436 -395.856206)
		(width 0.14224)
		(layer "In13.Cu")
		(net "P5E_CPU1_P3_RX_BUF_DP<15>")
	)
	(segment
		(start 138.663426 -395.172946)
		(end 138.513566 -395.296136)
		(width 0.14224)
		(layer "In13.Cu")
		(net "P5E_CPU1_P3_RX_BUF_DP<15>")
	)
	(segment
		(start 145.601436 -395.856206)
		(end 145.176494 -395.814296)
		(width 0.14224)
		(layer "In13.Cu")
		(net "P5E_CPU1_P3_RX_BUF_DP<15>")
	)
	(segment
		(start 161.415476 -407.460704)
		(end 161.415476 -406.424892)
		(width 0.14224)
		(layer "In13.Cu")
		(net "P5E_CPU1_P3_RX_BUF_DP<15>")
	)
	(segment
		(start 145.176494 -395.814296)
		(end 145.026634 -395.937486)
		(width 0.14224)
		(layer "In13.Cu")
		(net "P5E_CPU1_P3_RX_BUF_DP<15>")
	)
	(segment
		(start 134.464298 -394.897356)
		(end 133.442202 -394.693902)
		(width 0.14224)
		(layer "In13.Cu")
		(net "P5E_CPU1_P3_RX_BUF_DP<15>")
	)
	(segment
		(start 140.0175 -395.306296)
		(end 139.86764 -395.429486)
		(width 0.14224)
		(layer "In13.Cu")
		(net "P5E_CPU1_P3_RX_BUF_DP<15>")
	)
	(segment
		(start 139.86764 -395.429486)
		(end 139.211304 -395.36497)
		(width 0.14224)
		(layer "In13.Cu")
		(net "P5E_CPU1_P3_RX_BUF_DP<15>")
	)
	(segment
		(start 148.521166 -396.334996)
		(end 148.102574 -396.251938)
		(width 0.14224)
		(layer "In13.Cu")
		(net "P5E_CPU1_P3_RX_BUF_DP<15>")
	)
	(segment
		(start 161.552636 -407.597864)
		(end 161.415476 -407.460704)
		(width 0.14224)
		(layer "In13.Cu")
		(net "P5E_CPU1_P3_RX_BUF_DP<15>")
	)
	(segment
		(start 137.28827 -395.175486)
		(end 135.961882 -395.04493)
		(width 0.14224)
		(layer "In13.Cu")
		(net "P5E_CPU1_P3_RX_BUF_DP<15>")
	)
	(segment
		(start 153.419048 -398.540224)
		(end 153.228802 -398.57807)
		(width 0.14224)
		(layer "In13.Cu")
		(net "P5E_CPU1_P3_RX_BUF_DP<15>")
	)
	(segment
		(start 149.889464 -396.747238)
		(end 148.629116 -396.49654)
		(width 0.14224)
		(layer "In13.Cu")
		(net "P5E_CPU1_P3_RX_BUF_DP<15>")
	)
	(segment
		(start 135.838692 -394.894816)
		(end 135.41375 -394.852906)
		(width 0.14224)
		(layer "In13.Cu")
		(net "P5E_CPU1_P3_RX_BUF_DP<15>")
	)
	(segment
		(start 161.415476 -408.588464)
		(end 161.415476 -408.161744)
		(width 0.14224)
		(layer "In13.Cu")
		(net "P5E_CPU1_P3_RX_BUF_DP<15>")
	)
	(segment
		(start 159.501078 -402.881084)
		(end 159.16402 -402.544026)
		(width 0.14224)
		(layer "In13.Cu")
		(net "P5E_CPU1_P3_RX_BUF_DP<15>")
	)
	(segment
		(start 162.947096 -411.78734)
		(end 162.872928 -411.608016)
		(width 0.14224)
		(layer "In13.Cu")
		(net "P5E_CPU1_P3_RX_BUF_DP<15>")
	)
	(segment
		(start 156.076396 -434.45811)
		(end 156.076396 -424.569636)
		(width 0.14224)
		(layer "In13.Cu")
		(net "P5E_CPU1_P3_RX_BUF_DP<15>")
	)
	(segment
		(start 135.961882 -395.04493)
		(end 135.838692 -394.894816)
		(width 0.14224)
		(layer "In13.Cu")
		(net "P5E_CPU1_P3_RX_BUF_DP<15>")
	)
	(segment
		(start 143.614902 -395.798548)
		(end 143.491966 -395.648434)
		(width 0.14224)
		(layer "In13.Cu")
		(net "P5E_CPU1_P3_RX_BUF_DP<15>")
	)
	(segment
		(start 161.510472 -410.803852)
		(end 161.415476 -410.574744)
		(width 0.14224)
		(layer "In13.Cu")
		(net "P5E_CPU1_P3_RX_BUF_DP<15>")
	)
	(segment
		(start 143.067024 -395.606524)
		(end 142.91691 -395.729714)
		(width 0.14224)
		(layer "In13.Cu")
		(net "P5E_CPU1_P3_RX_BUF_DP<15>")
	)
	(segment
		(start 140.565632 -395.49832)
		(end 140.442442 -395.348206)
		(width 0.14224)
		(layer "In13.Cu")
		(net "P5E_CPU1_P3_RX_BUF_DP<15>")
	)
	(segment
		(start 161.415476 -410.574744)
		(end 161.415476 -409.289504)
		(width 0.14224)
		(layer "In13.Cu")
		(net "P5E_CPU1_P3_RX_BUF_DP<15>")
	)
	(segment
		(start 133.442202 -394.693902)
		(end 132.864352 -394.518642)
		(width 0.14224)
		(layer "In13.Cu")
		(net "P5E_CPU1_P3_RX_BUF_DP<15>")
	)
	(segment
		(start 161.552636 -408.024584)
		(end 161.552636 -407.597864)
		(width 0.14224)
		(layer "In13.Cu")
		(net "P5E_CPU1_P3_RX_BUF_DP<15>")
	)
	(segment
		(start 146.59483 -396.091918)
		(end 145.724626 -396.00632)
		(width 0.14224)
		(layer "In13.Cu")
		(net "P5E_CPU1_P3_RX_BUF_DP<15>")
	)
	(segment
		(start 153.228802 -398.57807)
		(end 151.46655 -397.400526)
		(width 0.14224)
		(layer "In13.Cu")
		(net "P5E_CPU1_P3_RX_BUF_DP<15>")
	)
	(segment
		(start 143.491966 -395.648434)
		(end 143.067024 -395.606524)
		(width 0.14224)
		(layer "In13.Cu")
		(net "P5E_CPU1_P3_RX_BUF_DP<15>")
	)
	(segment
		(start 132.457444 -393.129008)
		(end 132.59689 -392.989562)
		(width 0.14224)
		(layer "In13.Cu")
		(net "P5E_CPU1_P3_RX_BUF_DP<15>")
	)
	(segment
		(start 156.750004 -434.289962)
		(end 156.750004 -434.618638)
		(width 0.14224)
		(layer "In13.Cu")
		(net "P5E_CPU1_P3_RX_BUF_DP<15>")
	)
	(segment
		(start 132.457444 -394.172694)
		(end 132.457444 -393.129008)
		(width 0.14224)
		(layer "In13.Cu")
		(net "P5E_CPU1_P3_RX_BUF_DP<15>")
	)
	(segment
		(start 139.211304 -395.36497)
		(end 139.088368 -395.214856)
		(width 0.14224)
		(layer "In13.Cu")
		(net "P5E_CPU1_P3_RX_BUF_DP<15>")
	)
	(segment
		(start 132.59689 -392.989562)
		(end 132.776976 -392.989562)
		(width 0.14224)
		(layer "In13.Cu")
		(net "P5E_CPU1_P3_RX_BUF_DP<15>")
	)
	(segment
		(start 147.941284 -396.359634)
		(end 146.59483 -396.091918)
		(width 0.14224)
		(layer "In13.Cu")
		(net "P5E_CPU1_P3_RX_BUF_DP<15>")
	)
	(segment
		(start 148.629116 -396.49654)
		(end 148.521166 -396.334996)
		(width 0.14224)
		(layer "In13.Cu")
		(net "P5E_CPU1_P3_RX_BUF_DP<15>")
	)
	(segment
		(start 137.43813 -395.052296)
		(end 137.28827 -395.175486)
		(width 0.14224)
		(layer "In13.Cu")
		(net "P5E_CPU1_P3_RX_BUF_DP<15>")
	)
	(segment
		(start 161.415476 -406.424892)
		(end 161.231072 -405.979884)
		(width 0.14224)
		(layer "In13.Cu")
		(net "P5E_CPU1_P3_RX_BUF_DP<15>")
	)
	(segment
		(start 161.231072 -405.979884)
		(end 160.897316 -405.646128)
		(width 0.14224)
		(layer "In13.Cu")
		(net "P5E_CPU1_P3_RX_BUF_DP<15>")
	)
	(segment
		(start 162.947096 -413.518604)
		(end 162.947096 -411.78734)
		(width 0.14224)
		(layer "In13.Cu")
		(net "P5E_CPU1_P3_RX_BUF_DP<15>")
	)
	(segment
		(start 140.442442 -395.348206)
		(end 140.0175 -395.306296)
		(width 0.14224)
		(layer "In13.Cu")
		(net "P5E_CPU1_P3_RX_BUF_DP<15>")
	)
	(segment
		(start 161.713164 -410.980382)
		(end 161.63417 -410.92755)
		(width 0.14224)
		(layer "In13.Cu")
		(net "P5E_CPU1_P3_RX_BUF_DP<15>")
	)
	(segment
		(start 135.26389 -394.976096)
		(end 134.464298 -394.897356)
		(width 0.14224)
		(layer "In13.Cu")
		(net "P5E_CPU1_P3_RX_BUF_DP<15>")
	)
	(segment
		(start 132.916422 -393.129008)
		(end 132.916422 -393.292838)
		(width 0.14224)
		(layer "In13.Cu")
		(net "P5E_CPU1_P3_RX_BUF_DP<15>")
	)
	(segment
		(start 159.16402 -402.544026)
		(end 153.811986 -398.967706)
		(width 0.14224)
		(layer "In13.Cu")
		(net "P5E_CPU1_P3_RX_BUF_DP<15>")
	)
	(segment
		(start 160.212786 -405.574754)
		(end 160.141158 -405.545036)
		(width 0.14224)
		(layer "In13.Cu")
		(net "P5E_CPU1_P3_RX_BUF_DP<15>")
	)
	(segment
		(start 161.552636 -408.725624)
		(end 161.415476 -408.588464)
		(width 0.14224)
		(layer "In13.Cu")
		(net "P5E_CPU1_P3_RX_BUF_DP<15>")
	)
	(segment
		(start 162.872928 -411.608016)
		(end 162.621468 -411.356556)
		(width 0.14224)
		(layer "In13.Cu")
		(net "P5E_CPU1_P3_RX_BUF_DP<15>")
	)
	(segment
		(start 153.811986 -398.967706)
		(end 153.77414 -398.77746)
		(width 0.14224)
		(layer "In13.Cu")
		(net "P5E_CPU1_P3_RX_BUF_DP<15>")
	)
	(segment
		(start 132.776976 -392.989562)
		(end 132.916422 -393.129008)
		(width 0.14224)
		(layer "In13.Cu")
		(net "P5E_CPU1_P3_RX_BUF_DP<15>")
	)
	(segment
		(start 156.6291 -434.739542)
		(end 156.357828 -434.739542)
		(width 0.14224)
		(layer "In13.Cu")
		(net "P5E_CPU1_P3_RX_BUF_DP<15>")
	)
	(arc
		(start 132.864352 -394.518642)
		(mid 132.689335 -394.433163)
		(end 132.5499 -394.297154)
		(width 0.14224)
		(layer "In13.Cu")
		(net "P5E_CPU1_P3_RX_BUF_DP<15>")
	)
	(arc
		(start 156.076396 -424.569636)
		(mid 156.155849 -424.033471)
		(end 156.387546 -423.543476)
		(width 0.14224)
		(layer "In13.Cu")
		(net "P5E_CPU1_P3_RX_BUF_DP<15>")
	)
	(segment
		(start 131.013962 -392.723878)
		(end 131.2672 -392.977116)
		(width 0.1016)
		(layer "F.Cu")
		(net "P5E_CPU1_P3_RX_BUF_DP<14>")
	)
	(segment
		(start 131.018026 -391.281158)
		(end 131.102608 -391.36574)
		(width 0.1016)
		(layer "F.Cu")
		(net "P5E_CPU1_P3_RX_BUF_DP<14>")
	)
	(segment
		(start 131.102608 -391.488676)
		(end 131.013962 -391.577322)
		(width 0.1016)
		(layer "F.Cu")
		(net "P5E_CPU1_P3_RX_BUF_DP<14>")
	)
	(segment
		(start 131.013962 -391.577322)
		(end 131.013962 -392.723878)
		(width 0.1016)
		(layer "F.Cu")
		(net "P5E_CPU1_P3_RX_BUF_DP<14>")
	)
	(segment
		(start 131.102608 -391.36574)
		(end 131.102608 -391.488676)
		(width 0.1016)
		(layer "F.Cu")
		(net "P5E_CPU1_P3_RX_BUF_DP<14>")
	)
	(segment
		(start 131.2672 -392.977116)
		(end 131.559808 -392.977116)
		(width 0.1016)
		(layer "F.Cu")
		(net "P5E_CPU1_P3_RX_BUF_DP<14>")
	)
	(segment
		(start 131.559808 -392.977116)
		(end 131.716526 -393.133834)
		(width 0.1016)
		(layer "F.Cu")
		(net "P5E_CPU1_P3_RX_BUF_DP<14>")
	)
	(segment
		(start 131.716526 -393.133834)
		(end 131.716526 -393.292838)
		(width 0.1016)
		(layer "F.Cu")
		(net "P5E_CPU1_P3_RX_BUF_DP<14>")
	)
	(segment
		(start 158.489396 -408.118056)
		(end 158.489396 -407.691336)
		(width 0.14224)
		(layer "In13.Cu")
		(net "P5E_CPU1_P3_RX_BUF_DP<14>")
	)
	(segment
		(start 158.200344 -416.467036)
		(end 158.410402 -416.095942)
		(width 0.14224)
		(layer "In13.Cu")
		(net "P5E_CPU1_P3_RX_BUF_DP<14>")
	)
	(segment
		(start 142.877794 -397.175482)
		(end 142.762224 -397.019526)
		(width 0.14224)
		(layer "In13.Cu")
		(net "P5E_CPU1_P3_RX_BUF_DP<14>")
	)
	(segment
		(start 154.36723 -433.748942)
		(end 154.0764 -433.458112)
		(width 0.14224)
		(layer "In13.Cu")
		(net "P5E_CPU1_P3_RX_BUF_DP<14>")
	)
	(segment
		(start 158.352236 -409.382976)
		(end 158.489396 -409.245816)
		(width 0.14224)
		(layer "In13.Cu")
		(net "P5E_CPU1_P3_RX_BUF_DP<14>")
	)
	(segment
		(start 144.772126 -397.317976)
		(end 144.616424 -397.433546)
		(width 0.14224)
		(layer "In13.Cu")
		(net "P5E_CPU1_P3_RX_BUF_DP<14>")
	)
	(segment
		(start 131.716526 -393.129008)
		(end 131.716526 -393.292838)
		(width 0.14224)
		(layer "In13.Cu")
		(net "P5E_CPU1_P3_RX_BUF_DP<14>")
	)
	(segment
		(start 146.35226 -397.691102)
		(end 145.310098 -397.53667)
		(width 0.14224)
		(layer "In13.Cu")
		(net "P5E_CPU1_P3_RX_BUF_DP<14>")
	)
	(segment
		(start 131.396994 -392.989562)
		(end 131.57708 -392.989562)
		(width 0.14224)
		(layer "In13.Cu")
		(net "P5E_CPU1_P3_RX_BUF_DP<14>")
	)
	(segment
		(start 158.352236 -408.681936)
		(end 158.352236 -408.255216)
		(width 0.14224)
		(layer "In13.Cu")
		(net "P5E_CPU1_P3_RX_BUF_DP<14>")
	)
	(segment
		(start 146.930364 -397.63827)
		(end 146.508216 -397.575532)
		(width 0.14224)
		(layer "In13.Cu")
		(net "P5E_CPU1_P3_RX_BUF_DP<14>")
	)
	(segment
		(start 156.820616 -403.865588)
		(end 156.71038 -403.599396)
		(width 0.14224)
		(layer "In13.Cu")
		(net "P5E_CPU1_P3_RX_BUF_DP<14>")
	)
	(segment
		(start 154.0764 -433.458112)
		(end 154.0764 -424.54957)
		(width 0.14224)
		(layer "In13.Cu")
		(net "P5E_CPU1_P3_RX_BUF_DP<14>")
	)
	(segment
		(start 158.410402 -416.095942)
		(end 158.5976 -416.044126)
		(width 0.14224)
		(layer "In13.Cu")
		(net "P5E_CPU1_P3_RX_BUF_DP<14>")
	)
	(segment
		(start 145.194528 -397.38046)
		(end 144.772126 -397.317976)
		(width 0.14224)
		(layer "In13.Cu")
		(net "P5E_CPU1_P3_RX_BUF_DP<14>")
	)
	(segment
		(start 139.236958 -396.63497)
		(end 139.121388 -396.47876)
		(width 0.14224)
		(layer "In13.Cu")
		(net "P5E_CPU1_P3_RX_BUF_DP<14>")
	)
	(segment
		(start 158.676086 -410.991304)
		(end 158.418022 -410.73324)
		(width 0.14224)
		(layer "In13.Cu")
		(net "P5E_CPU1_P3_RX_BUF_DP<14>")
	)
	(segment
		(start 158.489396 -407.691336)
		(end 158.352236 -407.554176)
		(width 0.14224)
		(layer "In13.Cu")
		(net "P5E_CPU1_P3_RX_BUF_DP<14>")
	)
	(segment
		(start 131.57708 -392.989562)
		(end 131.716526 -393.129008)
		(width 0.14224)
		(layer "In13.Cu")
		(net "P5E_CPU1_P3_RX_BUF_DP<14>")
	)
	(segment
		(start 131.634484 -395.094714)
		(end 131.49199 -394.95222)
		(width 0.14224)
		(layer "In13.Cu")
		(net "P5E_CPU1_P3_RX_BUF_DP<14>")
	)
	(segment
		(start 157.077918 -405.545036)
		(end 156.89326 -405.360378)
		(width 0.14224)
		(layer "In13.Cu")
		(net "P5E_CPU1_P3_RX_BUF_DP<14>")
	)
	(segment
		(start 156.89326 -405.360378)
		(end 156.820616 -405.185118)
		(width 0.14224)
		(layer "In13.Cu")
		(net "P5E_CPU1_P3_RX_BUF_DP<14>")
	)
	(segment
		(start 138.543284 -396.531846)
		(end 137.148062 -396.324836)
		(width 0.14224)
		(layer "In13.Cu")
		(net "P5E_CPU1_P3_RX_BUF_DP<14>")
	)
	(segment
		(start 148.527516 -398.095978)
		(end 147.89023 -397.919448)
		(width 0.14224)
		(layer "In13.Cu")
		(net "P5E_CPU1_P3_RX_BUF_DP<14>")
	)
	(segment
		(start 154.750008 -433.61864)
		(end 154.619706 -433.748942)
		(width 0.14224)
		(layer "In13.Cu")
		(net "P5E_CPU1_P3_RX_BUF_DP<14>")
	)
	(segment
		(start 144.616424 -397.433546)
		(end 142.877794 -397.175482)
		(width 0.14224)
		(layer "In13.Cu")
		(net "P5E_CPU1_P3_RX_BUF_DP<14>")
	)
	(segment
		(start 158.041848 -417.025328)
		(end 158.25216 -416.65398)
		(width 0.14224)
		(layer "In13.Cu")
		(net "P5E_CPU1_P3_RX_BUF_DP<14>")
	)
	(segment
		(start 154.472132 -423.048176)
		(end 157.85465 -417.077144)
		(width 0.14224)
		(layer "In13.Cu")
		(net "P5E_CPU1_P3_RX_BUF_DP<14>")
	)
	(segment
		(start 158.352236 -408.255216)
		(end 158.489396 -408.118056)
		(width 0.14224)
		(layer "In13.Cu")
		(net "P5E_CPU1_P3_RX_BUF_DP<14>")
	)
	(segment
		(start 159.265112 -414.587182)
		(end 159.45231 -414.53562)
		(width 0.14224)
		(layer "In13.Cu")
		(net "P5E_CPU1_P3_RX_BUF_DP<14>")
	)
	(segment
		(start 158.5976 -416.044126)
		(end 158.807912 -415.672524)
		(width 0.14224)
		(layer "In13.Cu")
		(net "P5E_CPU1_P3_RX_BUF_DP<14>")
	)
	(segment
		(start 149.704044 -398.591532)
		(end 148.527516 -398.095978)
		(width 0.14224)
		(layer "In13.Cu")
		(net "P5E_CPU1_P3_RX_BUF_DP<14>")
	)
	(segment
		(start 145.310098 -397.53667)
		(end 145.194528 -397.38046)
		(width 0.14224)
		(layer "In13.Cu")
		(net "P5E_CPU1_P3_RX_BUF_DP<14>")
	)
	(segment
		(start 140.302742 -396.654274)
		(end 140.14704 -396.769844)
		(width 0.14224)
		(layer "In13.Cu")
		(net "P5E_CPU1_P3_RX_BUF_DP<14>")
	)
	(segment
		(start 159.558228 -411.356556)
		(end 158.676086 -410.991304)
		(width 0.14224)
		(layer "In13.Cu")
		(net "P5E_CPU1_P3_RX_BUF_DP<14>")
	)
	(segment
		(start 156.33319 -403.035008)
		(end 155.730194 -402.390102)
		(width 0.14224)
		(layer "In13.Cu")
		(net "P5E_CPU1_P3_RX_BUF_DP<14>")
	)
	(segment
		(start 158.489396 -408.819096)
		(end 158.352236 -408.681936)
		(width 0.14224)
		(layer "In13.Cu")
		(net "P5E_CPU1_P3_RX_BUF_DP<14>")
	)
	(segment
		(start 158.352236 -407.554176)
		(end 158.352236 -406.424892)
		(width 0.14224)
		(layer "In13.Cu")
		(net "P5E_CPU1_P3_RX_BUF_DP<14>")
	)
	(segment
		(start 139.121388 -396.47876)
		(end 138.698986 -396.416276)
		(width 0.14224)
		(layer "In13.Cu")
		(net "P5E_CPU1_P3_RX_BUF_DP<14>")
	)
	(segment
		(start 140.725144 -396.717012)
		(end 140.302742 -396.654274)
		(width 0.14224)
		(layer "In13.Cu")
		(net "P5E_CPU1_P3_RX_BUF_DP<14>")
	)
	(segment
		(start 147.89023 -397.919448)
		(end 147.045934 -397.794226)
		(width 0.14224)
		(layer "In13.Cu")
		(net "P5E_CPU1_P3_RX_BUF_DP<14>")
	)
	(segment
		(start 135.971534 -396.209012)
		(end 133.48081 -395.713458)
		(width 0.14224)
		(layer "In13.Cu")
		(net "P5E_CPU1_P3_RX_BUF_DP<14>")
	)
	(segment
		(start 157.834076 -405.646128)
		(end 157.661864 -405.574754)
		(width 0.14224)
		(layer "In13.Cu")
		(net "P5E_CPU1_P3_RX_BUF_DP<14>")
	)
	(segment
		(start 158.75635 -415.48558)
		(end 159.265112 -414.587182)
		(width 0.14224)
		(layer "In13.Cu")
		(net "P5E_CPU1_P3_RX_BUF_DP<14>")
	)
	(segment
		(start 159.610806 -413.977074)
		(end 159.883856 -413.494982)
		(width 0.14224)
		(layer "In13.Cu")
		(net "P5E_CPU1_P3_RX_BUF_DP<14>")
	)
	(segment
		(start 159.883856 -413.494982)
		(end 159.883856 -411.947106)
		(width 0.14224)
		(layer "In13.Cu")
		(net "P5E_CPU1_P3_RX_BUF_DP<14>")
	)
	(segment
		(start 154.750008 -433.289964)
		(end 154.750008 -433.61864)
		(width 0.14224)
		(layer "In13.Cu")
		(net "P5E_CPU1_P3_RX_BUF_DP<14>")
	)
	(segment
		(start 154.619706 -433.748942)
		(end 154.36723 -433.748942)
		(width 0.14224)
		(layer "In13.Cu")
		(net "P5E_CPU1_P3_RX_BUF_DP<14>")
	)
	(segment
		(start 137.148062 -396.324836)
		(end 135.971534 -396.209012)
		(width 0.14224)
		(layer "In13.Cu")
		(net "P5E_CPU1_P3_RX_BUF_DP<14>")
	)
	(segment
		(start 157.85465 -417.077144)
		(end 158.041848 -417.025328)
		(width 0.14224)
		(layer "In13.Cu")
		(net "P5E_CPU1_P3_RX_BUF_DP<14>")
	)
	(segment
		(start 158.352236 -406.424892)
		(end 158.167832 -405.979884)
		(width 0.14224)
		(layer "In13.Cu")
		(net "P5E_CPU1_P3_RX_BUF_DP<14>")
	)
	(segment
		(start 131.257548 -394.386308)
		(end 131.257548 -393.129008)
		(width 0.14224)
		(layer "In13.Cu")
		(net "P5E_CPU1_P3_RX_BUF_DP<14>")
	)
	(segment
		(start 156.71038 -403.599396)
		(end 156.33319 -403.035008)
		(width 0.14224)
		(layer "In13.Cu")
		(net "P5E_CPU1_P3_RX_BUF_DP<14>")
	)
	(segment
		(start 159.45231 -414.53562)
		(end 159.662622 -414.164018)
		(width 0.14224)
		(layer "In13.Cu")
		(net "P5E_CPU1_P3_RX_BUF_DP<14>")
	)
	(segment
		(start 154.209242 -401.217892)
		(end 149.704044 -398.591532)
		(width 0.14224)
		(layer "In13.Cu")
		(net "P5E_CPU1_P3_RX_BUF_DP<14>")
	)
	(segment
		(start 155.730194 -402.390102)
		(end 154.209242 -401.217892)
		(width 0.14224)
		(layer "In13.Cu")
		(net "P5E_CPU1_P3_RX_BUF_DP<14>")
	)
	(segment
		(start 131.257548 -393.129008)
		(end 131.396994 -392.989562)
		(width 0.14224)
		(layer "In13.Cu")
		(net "P5E_CPU1_P3_RX_BUF_DP<14>")
	)
	(segment
		(start 142.762224 -397.019526)
		(end 142.340076 -396.956788)
		(width 0.14224)
		(layer "In13.Cu")
		(net "P5E_CPU1_P3_RX_BUF_DP<14>")
	)
	(segment
		(start 158.167832 -405.979884)
		(end 157.834076 -405.646128)
		(width 0.14224)
		(layer "In13.Cu")
		(net "P5E_CPU1_P3_RX_BUF_DP<14>")
	)
	(segment
		(start 156.820616 -405.185118)
		(end 156.820616 -403.865588)
		(width 0.14224)
		(layer "In13.Cu")
		(net "P5E_CPU1_P3_RX_BUF_DP<14>")
	)
	(segment
		(start 140.14704 -396.769844)
		(end 139.236958 -396.63497)
		(width 0.14224)
		(layer "In13.Cu")
		(net "P5E_CPU1_P3_RX_BUF_DP<14>")
	)
	(segment
		(start 140.840714 -396.872968)
		(end 140.725144 -396.717012)
		(width 0.14224)
		(layer "In13.Cu")
		(net "P5E_CPU1_P3_RX_BUF_DP<14>")
	)
	(segment
		(start 158.418022 -410.73324)
		(end 158.352236 -410.57449)
		(width 0.14224)
		(layer "In13.Cu")
		(net "P5E_CPU1_P3_RX_BUF_DP<14>")
	)
	(segment
		(start 142.18412 -397.072358)
		(end 140.840714 -396.872968)
		(width 0.14224)
		(layer "In13.Cu")
		(net "P5E_CPU1_P3_RX_BUF_DP<14>")
	)
	(segment
		(start 142.340076 -396.956788)
		(end 142.18412 -397.072358)
		(width 0.14224)
		(layer "In13.Cu")
		(net "P5E_CPU1_P3_RX_BUF_DP<14>")
	)
	(segment
		(start 158.489396 -409.245816)
		(end 158.489396 -408.819096)
		(width 0.14224)
		(layer "In13.Cu")
		(net "P5E_CPU1_P3_RX_BUF_DP<14>")
	)
	(segment
		(start 133.48081 -395.713458)
		(end 131.831842 -395.213078)
		(width 0.14224)
		(layer "In13.Cu")
		(net "P5E_CPU1_P3_RX_BUF_DP<14>")
	)
	(segment
		(start 157.149546 -405.574754)
		(end 157.077918 -405.545036)
		(width 0.14224)
		(layer "In13.Cu")
		(net "P5E_CPU1_P3_RX_BUF_DP<14>")
	)
	(segment
		(start 159.662622 -414.164018)
		(end 159.610806 -413.977074)
		(width 0.14224)
		(layer "In13.Cu")
		(net "P5E_CPU1_P3_RX_BUF_DP<14>")
	)
	(segment
		(start 159.883856 -411.947106)
		(end 159.696404 -411.494732)
		(width 0.14224)
		(layer "In13.Cu")
		(net "P5E_CPU1_P3_RX_BUF_DP<14>")
	)
	(segment
		(start 138.698986 -396.416276)
		(end 138.543284 -396.531846)
		(width 0.14224)
		(layer "In13.Cu")
		(net "P5E_CPU1_P3_RX_BUF_DP<14>")
	)
	(segment
		(start 157.661864 -405.574754)
		(end 157.149546 -405.574754)
		(width 0.14224)
		(layer "In13.Cu")
		(net "P5E_CPU1_P3_RX_BUF_DP<14>")
	)
	(segment
		(start 146.508216 -397.575532)
		(end 146.35226 -397.691102)
		(width 0.14224)
		(layer "In13.Cu")
		(net "P5E_CPU1_P3_RX_BUF_DP<14>")
	)
	(segment
		(start 147.045934 -397.794226)
		(end 146.930364 -397.63827)
		(width 0.14224)
		(layer "In13.Cu")
		(net "P5E_CPU1_P3_RX_BUF_DP<14>")
	)
	(segment
		(start 158.25216 -416.65398)
		(end 158.200344 -416.467036)
		(width 0.14224)
		(layer "In13.Cu")
		(net "P5E_CPU1_P3_RX_BUF_DP<14>")
	)
	(segment
		(start 159.696404 -411.494732)
		(end 159.558228 -411.356556)
		(width 0.14224)
		(layer "In13.Cu")
		(net "P5E_CPU1_P3_RX_BUF_DP<14>")
	)
	(segment
		(start 158.352236 -410.57449)
		(end 158.352236 -409.382976)
		(width 0.14224)
		(layer "In13.Cu")
		(net "P5E_CPU1_P3_RX_BUF_DP<14>")
	)
	(segment
		(start 158.807912 -415.672524)
		(end 158.75635 -415.48558)
		(width 0.14224)
		(layer "In13.Cu")
		(net "P5E_CPU1_P3_RX_BUF_DP<14>")
	)
	(arc
		(start 131.831842 -395.213078)
		(mid 131.725874 -395.166053)
		(end 131.634484 -395.094714)
		(width 0.14224)
		(layer "In13.Cu")
		(net "P5E_CPU1_P3_RX_BUF_DP<14>")
	)
	(arc
		(start 154.0764 -424.54957)
		(mid 154.176995 -423.773235)
		(end 154.472132 -423.048176)
		(width 0.14224)
		(layer "In13.Cu")
		(net "P5E_CPU1_P3_RX_BUF_DP<14>")
	)
	(arc
		(start 131.49199 -394.95222)
		(mid 131.318502 -394.692577)
		(end 131.257548 -394.386308)
		(width 0.14224)
		(layer "In13.Cu")
		(net "P5E_CPU1_P3_RX_BUF_DP<14>")
	)
	(segment
		(start 129.817876 -391.281158)
		(end 129.902458 -391.36574)
		(width 0.1016)
		(layer "F.Cu")
		(net "P5E_CPU1_P3_RX_BUF_DP<13>")
	)
	(segment
		(start 130.075686 -392.977116)
		(end 130.377692 -392.977116)
		(width 0.1016)
		(layer "F.Cu")
		(net "P5E_CPU1_P3_RX_BUF_DP<13>")
	)
	(segment
		(start 129.822448 -392.723878)
		(end 130.075686 -392.977116)
		(width 0.1016)
		(layer "F.Cu")
		(net "P5E_CPU1_P3_RX_BUF_DP<13>")
	)
	(segment
		(start 129.902458 -391.488676)
		(end 129.822448 -391.568686)
		(width 0.1016)
		(layer "F.Cu")
		(net "P5E_CPU1_P3_RX_BUF_DP<13>")
	)
	(segment
		(start 129.902458 -391.36574)
		(end 129.902458 -391.488676)
		(width 0.1016)
		(layer "F.Cu")
		(net "P5E_CPU1_P3_RX_BUF_DP<13>")
	)
	(segment
		(start 130.516376 -393.1158)
		(end 130.516376 -393.292838)
		(width 0.1016)
		(layer "F.Cu")
		(net "P5E_CPU1_P3_RX_BUF_DP<13>")
	)
	(segment
		(start 129.822448 -391.568686)
		(end 129.822448 -392.723878)
		(width 0.1016)
		(layer "F.Cu")
		(net "P5E_CPU1_P3_RX_BUF_DP<13>")
	)
	(segment
		(start 130.377692 -392.977116)
		(end 130.516376 -393.1158)
		(width 0.1016)
		(layer "F.Cu")
		(net "P5E_CPU1_P3_RX_BUF_DP<13>")
	)
	(segment
		(start 152.076404 -434.45811)
		(end 152.076404 -423.888662)
		(width 0.14224)
		(layer "In13.Cu")
		(net "P5E_CPU1_P3_RX_BUF_DP<13>")
	)
	(segment
		(start 139.951714 -397.96339)
		(end 139.836144 -397.807434)
		(width 0.14224)
		(layer "In13.Cu")
		(net "P5E_CPU1_P3_RX_BUF_DP<13>")
	)
	(segment
		(start 147.111466 -399.218404)
		(end 145.607278 -398.802098)
		(width 0.14224)
		(layer "In13.Cu")
		(net "P5E_CPU1_P3_RX_BUF_DP<13>")
	)
	(segment
		(start 130.196844 -392.989562)
		(end 130.389376 -392.989562)
		(width 0.14224)
		(layer "In13.Cu")
		(net "P5E_CPU1_P3_RX_BUF_DP<13>")
	)
	(segment
		(start 154.014678 -405.545036)
		(end 153.83002 -405.360378)
		(width 0.14224)
		(layer "In13.Cu")
		(net "P5E_CPU1_P3_RX_BUF_DP<13>")
	)
	(segment
		(start 143.2941 -398.459198)
		(end 143.17853 -398.302988)
		(width 0.14224)
		(layer "In13.Cu")
		(net "P5E_CPU1_P3_RX_BUF_DP<13>")
	)
	(segment
		(start 152.750012 -434.618638)
		(end 152.628854 -434.739796)
		(width 0.14224)
		(layer "In13.Cu")
		(net "P5E_CPU1_P3_RX_BUF_DP<13>")
	)
	(segment
		(start 154.593798 -417.788344)
		(end 154.794966 -417.411662)
		(width 0.14224)
		(layer "In13.Cu")
		(net "P5E_CPU1_P3_RX_BUF_DP<13>")
	)
	(segment
		(start 155.537408 -415.731706)
		(end 155.723336 -415.675318)
		(width 0.14224)
		(layer "In13.Cu")
		(net "P5E_CPU1_P3_RX_BUF_DP<13>")
	)
	(segment
		(start 152.628854 -434.739796)
		(end 152.35809 -434.739796)
		(width 0.14224)
		(layer "In13.Cu")
		(net "P5E_CPU1_P3_RX_BUF_DP<13>")
	)
	(segment
		(start 152.72639 -421.465502)
		(end 153.598372 -419.359334)
		(width 0.14224)
		(layer "In13.Cu")
		(net "P5E_CPU1_P3_RX_BUF_DP<13>")
	)
	(segment
		(start 156.820616 -413.331406)
		(end 156.820616 -411.839156)
		(width 0.14224)
		(layer "In13.Cu")
		(net "P5E_CPU1_P3_RX_BUF_DP<13>")
	)
	(segment
		(start 152.725882 -421.465756)
		(end 152.72639 -421.465502)
		(width 0.14224)
		(layer "In13.Cu")
		(net "P5E_CPU1_P3_RX_BUF_DP<13>")
	)
	(segment
		(start 155.005786 -416.72637)
		(end 155.191714 -416.670236)
		(width 0.14224)
		(layer "In13.Cu")
		(net "P5E_CPU1_P3_RX_BUF_DP<13>")
	)
	(segment
		(start 142.029434 -398.132554)
		(end 141.607032 -398.07007)
		(width 0.14224)
		(layer "In13.Cu")
		(net "P5E_CPU1_P3_RX_BUF_DP<13>")
	)
	(segment
		(start 156.2862 -414.622742)
		(end 156.487368 -414.246314)
		(width 0.14224)
		(layer "In13.Cu")
		(net "P5E_CPU1_P3_RX_BUF_DP<13>")
	)
	(segment
		(start 138.519154 -397.750792)
		(end 138.403584 -397.594836)
		(width 0.14224)
		(layer "In13.Cu")
		(net "P5E_CPU1_P3_RX_BUF_DP<13>")
	)
	(segment
		(start 156.487368 -414.246314)
		(end 156.43098 -414.06064)
		(width 0.14224)
		(layer "In13.Cu")
		(net "P5E_CPU1_P3_RX_BUF_DP<13>")
	)
	(segment
		(start 155.191714 -416.670236)
		(end 155.392882 -416.293554)
		(width 0.14224)
		(layer "In13.Cu")
		(net "P5E_CPU1_P3_RX_BUF_DP<13>")
	)
	(segment
		(start 155.419044 -410.956252)
		(end 155.288996 -410.826204)
		(width 0.14224)
		(layer "In13.Cu")
		(net "P5E_CPU1_P3_RX_BUF_DP<13>")
	)
	(segment
		(start 151.641556 -401.748498)
		(end 149.479508 -400.303238)
		(width 0.14224)
		(layer "In13.Cu")
		(net "P5E_CPU1_P3_RX_BUF_DP<13>")
	)
	(segment
		(start 155.86837 -415.113216)
		(end 156.100272 -414.67913)
		(width 0.14224)
		(layer "In13.Cu")
		(net "P5E_CPU1_P3_RX_BUF_DP<13>")
	)
	(segment
		(start 153.757376 -405.184864)
		(end 153.757376 -403.589744)
		(width 0.14224)
		(layer "In13.Cu")
		(net "P5E_CPU1_P3_RX_BUF_DP<13>")
	)
	(segment
		(start 142.756128 -398.240504)
		(end 142.600426 -398.356074)
		(width 0.14224)
		(layer "In13.Cu")
		(net "P5E_CPU1_P3_RX_BUF_DP<13>")
	)
	(segment
		(start 153.876248 -418.839142)
		(end 154.062176 -418.783008)
		(width 0.14224)
		(layer "In13.Cu")
		(net "P5E_CPU1_P3_RX_BUF_DP<13>")
	)
	(segment
		(start 154.770836 -405.646128)
		(end 154.598624 -405.574754)
		(width 0.14224)
		(layer "In13.Cu")
		(net "P5E_CPU1_P3_RX_BUF_DP<13>")
	)
	(segment
		(start 139.413742 -397.744696)
		(end 139.25804 -397.860266)
		(width 0.14224)
		(layer "In13.Cu")
		(net "P5E_CPU1_P3_RX_BUF_DP<13>")
	)
	(segment
		(start 137.981182 -397.532098)
		(end 137.82548 -397.647668)
		(width 0.14224)
		(layer "In13.Cu")
		(net "P5E_CPU1_P3_RX_BUF_DP<13>")
	)
	(segment
		(start 130.057398 -393.129008)
		(end 130.196844 -392.989562)
		(width 0.14224)
		(layer "In13.Cu")
		(net "P5E_CPU1_P3_RX_BUF_DP<13>")
	)
	(segment
		(start 130.057398 -394.658342)
		(end 130.057398 -393.129008)
		(width 0.14224)
		(layer "In13.Cu")
		(net "P5E_CPU1_P3_RX_BUF_DP<13>")
	)
	(segment
		(start 130.516376 -393.116562)
		(end 130.516376 -393.292838)
		(width 0.14224)
		(layer "In13.Cu")
		(net "P5E_CPU1_P3_RX_BUF_DP<13>")
	)
	(segment
		(start 155.288996 -410.826204)
		(end 155.288996 -406.424892)
		(width 0.14224)
		(layer "In13.Cu")
		(net "P5E_CPU1_P3_RX_BUF_DP<13>")
	)
	(segment
		(start 152.403556 -422.243758)
		(end 152.725882 -421.465756)
		(width 0.14224)
		(layer "In13.Cu")
		(net "P5E_CPU1_P3_RX_BUF_DP<13>")
	)
	(segment
		(start 149.479508 -400.303238)
		(end 147.111466 -399.218404)
		(width 0.14224)
		(layer "In13.Cu")
		(net "P5E_CPU1_P3_RX_BUF_DP<13>")
	)
	(segment
		(start 130.389376 -392.989562)
		(end 130.516376 -393.116562)
		(width 0.14224)
		(layer "In13.Cu")
		(net "P5E_CPU1_P3_RX_BUF_DP<13>")
	)
	(segment
		(start 153.598372 -419.359334)
		(end 153.876248 -418.839142)
		(width 0.14224)
		(layer "In13.Cu")
		(net "P5E_CPU1_P3_RX_BUF_DP<13>")
	)
	(segment
		(start 156.540962 -411.420818)
		(end 155.419044 -410.956252)
		(width 0.14224)
		(layer "In13.Cu")
		(net "P5E_CPU1_P3_RX_BUF_DP<13>")
	)
	(segment
		(start 154.794966 -417.411662)
		(end 154.738832 -417.225988)
		(width 0.14224)
		(layer "In13.Cu")
		(net "P5E_CPU1_P3_RX_BUF_DP<13>")
	)
	(segment
		(start 153.622502 -403.264116)
		(end 153.044906 -402.68652)
		(width 0.14224)
		(layer "In13.Cu")
		(net "P5E_CPU1_P3_RX_BUF_DP<13>")
	)
	(segment
		(start 152.750012 -434.289962)
		(end 152.750012 -434.618638)
		(width 0.14224)
		(layer "In13.Cu")
		(net "P5E_CPU1_P3_RX_BUF_DP<13>")
	)
	(segment
		(start 152.22474 -402.138388)
		(end 152.186894 -401.948142)
		(width 0.14224)
		(layer "In13.Cu")
		(net "P5E_CPU1_P3_RX_BUF_DP<13>")
	)
	(segment
		(start 155.336494 -416.10788)
		(end 155.537408 -415.731706)
		(width 0.14224)
		(layer "In13.Cu")
		(net "P5E_CPU1_P3_RX_BUF_DP<13>")
	)
	(segment
		(start 153.83002 -405.360378)
		(end 153.757376 -405.184864)
		(width 0.14224)
		(layer "In13.Cu")
		(net "P5E_CPU1_P3_RX_BUF_DP<13>")
	)
	(segment
		(start 141.45133 -398.18564)
		(end 139.951714 -397.96339)
		(width 0.14224)
		(layer "In13.Cu")
		(net "P5E_CPU1_P3_RX_BUF_DP<13>")
	)
	(segment
		(start 155.392882 -416.293554)
		(end 155.336494 -416.10788)
		(width 0.14224)
		(layer "In13.Cu")
		(net "P5E_CPU1_P3_RX_BUF_DP<13>")
	)
	(segment
		(start 152.35809 -434.739796)
		(end 152.076404 -434.45811)
		(width 0.14224)
		(layer "In13.Cu")
		(net "P5E_CPU1_P3_RX_BUF_DP<13>")
	)
	(segment
		(start 154.062176 -418.783008)
		(end 154.263344 -418.406326)
		(width 0.14224)
		(layer "In13.Cu")
		(net "P5E_CPU1_P3_RX_BUF_DP<13>")
	)
	(segment
		(start 152.186894 -401.948142)
		(end 151.831802 -401.710652)
		(width 0.14224)
		(layer "In13.Cu")
		(net "P5E_CPU1_P3_RX_BUF_DP<13>")
	)
	(segment
		(start 142.600426 -398.356074)
		(end 142.145004 -398.288764)
		(width 0.14224)
		(layer "In13.Cu")
		(net "P5E_CPU1_P3_RX_BUF_DP<13>")
	)
	(segment
		(start 143.17853 -398.302988)
		(end 142.756128 -398.240504)
		(width 0.14224)
		(layer "In13.Cu")
		(net "P5E_CPU1_P3_RX_BUF_DP<13>")
	)
	(segment
		(start 155.723336 -415.675318)
		(end 155.924504 -415.29889)
		(width 0.14224)
		(layer "In13.Cu")
		(net "P5E_CPU1_P3_RX_BUF_DP<13>")
	)
	(segment
		(start 155.104592 -405.979884)
		(end 154.770836 -405.646128)
		(width 0.14224)
		(layer "In13.Cu")
		(net "P5E_CPU1_P3_RX_BUF_DP<13>")
	)
	(segment
		(start 137.82548 -397.647668)
		(end 135.460486 -397.297148)
		(width 0.14224)
		(layer "In13.Cu")
		(net "P5E_CPU1_P3_RX_BUF_DP<13>")
	)
	(segment
		(start 154.086306 -405.574754)
		(end 154.014678 -405.545036)
		(width 0.14224)
		(layer "In13.Cu")
		(net "P5E_CPU1_P3_RX_BUF_DP<13>")
	)
	(segment
		(start 142.145004 -398.288764)
		(end 142.029434 -398.132554)
		(width 0.14224)
		(layer "In13.Cu")
		(net "P5E_CPU1_P3_RX_BUF_DP<13>")
	)
	(segment
		(start 154.20721 -418.220652)
		(end 154.408124 -417.844478)
		(width 0.14224)
		(layer "In13.Cu")
		(net "P5E_CPU1_P3_RX_BUF_DP<13>")
	)
	(segment
		(start 139.25804 -397.860266)
		(end 138.519154 -397.750792)
		(width 0.14224)
		(layer "In13.Cu")
		(net "P5E_CPU1_P3_RX_BUF_DP<13>")
	)
	(segment
		(start 154.263344 -418.406326)
		(end 154.20721 -418.220652)
		(width 0.14224)
		(layer "In13.Cu")
		(net "P5E_CPU1_P3_RX_BUF_DP<13>")
	)
	(segment
		(start 135.460486 -397.297148)
		(end 131.408932 -396.068042)
		(width 0.14224)
		(layer "In13.Cu")
		(net "P5E_CPU1_P3_RX_BUF_DP<13>")
	)
	(segment
		(start 138.403584 -397.594836)
		(end 137.981182 -397.532098)
		(width 0.14224)
		(layer "In13.Cu")
		(net "P5E_CPU1_P3_RX_BUF_DP<13>")
	)
	(segment
		(start 145.607278 -398.802098)
		(end 143.2941 -398.459198)
		(width 0.14224)
		(layer "In13.Cu")
		(net "P5E_CPU1_P3_RX_BUF_DP<13>")
	)
	(segment
		(start 154.738832 -417.225988)
		(end 155.005786 -416.72637)
		(width 0.14224)
		(layer "In13.Cu")
		(net "P5E_CPU1_P3_RX_BUF_DP<13>")
	)
	(segment
		(start 153.044906 -402.68652)
		(end 152.22474 -402.138388)
		(width 0.14224)
		(layer "In13.Cu")
		(net "P5E_CPU1_P3_RX_BUF_DP<13>")
	)
	(segment
		(start 156.100272 -414.67913)
		(end 156.2862 -414.622742)
		(width 0.14224)
		(layer "In13.Cu")
		(net "P5E_CPU1_P3_RX_BUF_DP<13>")
	)
	(segment
		(start 139.836144 -397.807434)
		(end 139.413742 -397.744696)
		(width 0.14224)
		(layer "In13.Cu")
		(net "P5E_CPU1_P3_RX_BUF_DP<13>")
	)
	(segment
		(start 156.43098 -414.06064)
		(end 156.820616 -413.331406)
		(width 0.14224)
		(layer "In13.Cu")
		(net "P5E_CPU1_P3_RX_BUF_DP<13>")
	)
	(segment
		(start 141.607032 -398.07007)
		(end 141.45133 -398.18564)
		(width 0.14224)
		(layer "In13.Cu")
		(net "P5E_CPU1_P3_RX_BUF_DP<13>")
	)
	(segment
		(start 151.831802 -401.710652)
		(end 151.641556 -401.748498)
		(width 0.14224)
		(layer "In13.Cu")
		(net "P5E_CPU1_P3_RX_BUF_DP<13>")
	)
	(segment
		(start 154.598624 -405.574754)
		(end 154.086306 -405.574754)
		(width 0.14224)
		(layer "In13.Cu")
		(net "P5E_CPU1_P3_RX_BUF_DP<13>")
	)
	(segment
		(start 130.899408 -395.762734)
		(end 130.243072 -395.106398)
		(width 0.14224)
		(layer "In13.Cu")
		(net "P5E_CPU1_P3_RX_BUF_DP<13>")
	)
	(segment
		(start 154.408124 -417.844478)
		(end 154.593798 -417.788344)
		(width 0.14224)
		(layer "In13.Cu")
		(net "P5E_CPU1_P3_RX_BUF_DP<13>")
	)
	(segment
		(start 155.288996 -406.424892)
		(end 155.104592 -405.979884)
		(width 0.14224)
		(layer "In13.Cu")
		(net "P5E_CPU1_P3_RX_BUF_DP<13>")
	)
	(segment
		(start 155.924504 -415.29889)
		(end 155.86837 -415.113216)
		(width 0.14224)
		(layer "In13.Cu")
		(net "P5E_CPU1_P3_RX_BUF_DP<13>")
	)
	(arc
		(start 131.408932 -396.068042)
		(mid 131.135334 -395.946821)
		(end 130.899408 -395.762734)
		(width 0.14224)
		(layer "In13.Cu")
		(net "P5E_CPU1_P3_RX_BUF_DP<13>")
	)
	(arc
		(start 156.820616 -411.839156)
		(mid 156.744203 -411.587592)
		(end 156.540962 -411.420818)
		(width 0.14224)
		(layer "In13.Cu")
		(net "P5E_CPU1_P3_RX_BUF_DP<13>")
	)
	(arc
		(start 152.076404 -423.888662)
		(mid 152.158949 -423.050091)
		(end 152.403556 -422.243758)
		(width 0.14224)
		(layer "In13.Cu")
		(net "P5E_CPU1_P3_RX_BUF_DP<13>")
	)
	(arc
		(start 153.757376 -403.589744)
		(mid 153.722322 -403.413518)
		(end 153.622502 -403.264116)
		(width 0.14224)
		(layer "In13.Cu")
		(net "P5E_CPU1_P3_RX_BUF_DP<13>")
	)
	(arc
		(start 130.243072 -395.106398)
		(mid 130.105661 -394.900842)
		(end 130.057398 -394.658342)
		(width 0.14224)
		(layer "In13.Cu")
		(net "P5E_CPU1_P3_RX_BUF_DP<13>")
	)
	(segment
		(start 128.867154 -392.977116)
		(end 129.174494 -392.977116)
		(width 0.1016)
		(layer "F.Cu")
		(net "P5E_CPU1_P3_RX_BUF_DP<12>")
	)
	(segment
		(start 128.613916 -392.723878)
		(end 128.867154 -392.977116)
		(width 0.1016)
		(layer "F.Cu")
		(net "P5E_CPU1_P3_RX_BUF_DP<12>")
	)
	(segment
		(start 128.61798 -391.281158)
		(end 128.702562 -391.36574)
		(width 0.1016)
		(layer "F.Cu")
		(net "P5E_CPU1_P3_RX_BUF_DP<12>")
	)
	(segment
		(start 128.702562 -391.36574)
		(end 128.702562 -391.488676)
		(width 0.1016)
		(layer "F.Cu")
		(net "P5E_CPU1_P3_RX_BUF_DP<12>")
	)
	(segment
		(start 129.31648 -393.119102)
		(end 129.31648 -393.292838)
		(width 0.1016)
		(layer "F.Cu")
		(net "P5E_CPU1_P3_RX_BUF_DP<12>")
	)
	(segment
		(start 128.613916 -391.577322)
		(end 128.613916 -392.723878)
		(width 0.1016)
		(layer "F.Cu")
		(net "P5E_CPU1_P3_RX_BUF_DP<12>")
	)
	(segment
		(start 128.702562 -391.488676)
		(end 128.613916 -391.577322)
		(width 0.1016)
		(layer "F.Cu")
		(net "P5E_CPU1_P3_RX_BUF_DP<12>")
	)
	(segment
		(start 129.174494 -392.977116)
		(end 129.31648 -393.119102)
		(width 0.1016)
		(layer "F.Cu")
		(net "P5E_CPU1_P3_RX_BUF_DP<12>")
	)
	(segment
		(start 143.527018 -399.744184)
		(end 143.365474 -399.851626)
		(width 0.14224)
		(layer "In13.Cu")
		(net "P5E_CPU1_P3_RX_BUF_DP<12>")
	)
	(segment
		(start 139.048744 -398.846802)
		(end 138.8872 -398.954244)
		(width 0.14224)
		(layer "In13.Cu")
		(net "P5E_CPU1_P3_RX_BUF_DP<12>")
	)
	(segment
		(start 150.076408 -433.458112)
		(end 150.076408 -423.117772)
		(width 0.14224)
		(layer "In13.Cu")
		(net "P5E_CPU1_P3_RX_BUF_DP<12>")
	)
	(segment
		(start 150.951438 -405.545036)
		(end 150.76678 -405.360378)
		(width 0.14224)
		(layer "In13.Cu")
		(net "P5E_CPU1_P3_RX_BUF_DP<12>")
	)
	(segment
		(start 147.924774 -401.327112)
		(end 147.886928 -401.136866)
		(width 0.14224)
		(layer "In13.Cu")
		(net "P5E_CPU1_P3_RX_BUF_DP<12>")
	)
	(segment
		(start 152.405334 -417.030916)
		(end 152.331166 -416.851592)
		(width 0.14224)
		(layer "In13.Cu")
		(net "P5E_CPU1_P3_RX_BUF_DP<12>")
	)
	(segment
		(start 152.362916 -408.912822)
		(end 152.225756 -408.775662)
		(width 0.14224)
		(layer "In13.Cu")
		(net "P5E_CPU1_P3_RX_BUF_DP<12>")
	)
	(segment
		(start 147.53209 -400.89963)
		(end 147.341844 -400.937476)
		(width 0.14224)
		(layer "In13.Cu")
		(net "P5E_CPU1_P3_RX_BUF_DP<12>")
	)
	(segment
		(start 153.570178 -411.494732)
		(end 153.431748 -411.356556)
		(width 0.14224)
		(layer "In13.Cu")
		(net "P5E_CPU1_P3_RX_BUF_DP<12>")
	)
	(segment
		(start 152.362916 -409.339542)
		(end 152.362916 -408.912822)
		(width 0.14224)
		(layer "In13.Cu")
		(net "P5E_CPU1_P3_RX_BUF_DP<12>")
	)
	(segment
		(start 148.469604 -401.526248)
		(end 148.279358 -401.564094)
		(width 0.14224)
		(layer "In13.Cu")
		(net "P5E_CPU1_P3_RX_BUF_DP<12>")
	)
	(segment
		(start 137.914634 -398.619472)
		(end 137.75309 -398.726914)
		(width 0.14224)
		(layer "In13.Cu")
		(net "P5E_CPU1_P3_RX_BUF_DP<12>")
	)
	(segment
		(start 138.440668 -398.864836)
		(end 138.333226 -398.703292)
		(width 0.14224)
		(layer "In13.Cu")
		(net "P5E_CPU1_P3_RX_BUF_DP<12>")
	)
	(segment
		(start 152.362916 -407.785062)
		(end 152.225756 -407.647902)
		(width 0.14224)
		(layer "In13.Cu")
		(net "P5E_CPU1_P3_RX_BUF_DP<12>")
	)
	(segment
		(start 139.575032 -399.092166)
		(end 139.467336 -398.930622)
		(width 0.14224)
		(layer "In13.Cu")
		(net "P5E_CPU1_P3_RX_BUF_DP<12>")
	)
	(segment
		(start 152.44445 -410.92755)
		(end 152.320752 -410.803852)
		(width 0.14224)
		(layer "In13.Cu")
		(net "P5E_CPU1_P3_RX_BUF_DP<12>")
	)
	(segment
		(start 152.362916 -408.211782)
		(end 152.362916 -407.785062)
		(width 0.14224)
		(layer "In13.Cu")
		(net "P5E_CPU1_P3_RX_BUF_DP<12>")
	)
	(segment
		(start 150.76678 -405.360378)
		(end 150.694136 -405.183594)
		(width 0.14224)
		(layer "In13.Cu")
		(net "P5E_CPU1_P3_RX_BUF_DP<12>")
	)
	(segment
		(start 137.75309 -398.726914)
		(end 135.332724 -398.242028)
		(width 0.14224)
		(layer "In13.Cu")
		(net "P5E_CPU1_P3_RX_BUF_DP<12>")
	)
	(segment
		(start 150.750016 -433.289964)
		(end 150.750016 -433.61864)
		(width 0.14224)
		(layer "In13.Cu")
		(net "P5E_CPU1_P3_RX_BUF_DP<12>")
	)
	(segment
		(start 146.973036 -400.691096)
		(end 146.512534 -400.500342)
		(width 0.14224)
		(layer "In13.Cu")
		(net "P5E_CPU1_P3_RX_BUF_DP<12>")
	)
	(segment
		(start 150.694136 -405.183594)
		(end 150.694136 -403.799802)
		(width 0.14224)
		(layer "In13.Cu")
		(net "P5E_CPU1_P3_RX_BUF_DP<12>")
	)
	(segment
		(start 153.757376 -413.408368)
		(end 153.757376 -411.947868)
		(width 0.14224)
		(layer "In13.Cu")
		(net "P5E_CPU1_P3_RX_BUF_DP<12>")
	)
	(segment
		(start 152.523698 -410.980382)
		(end 152.44445 -410.927296)
		(width 0.14224)
		(layer "In13.Cu")
		(net "P5E_CPU1_P3_RX_BUF_DP<12>")
	)
	(segment
		(start 143.94561 -399.828004)
		(end 143.527018 -399.744184)
		(width 0.14224)
		(layer "In13.Cu")
		(net "P5E_CPU1_P3_RX_BUF_DP<12>")
	)
	(segment
		(start 152.320752 -410.803852)
		(end 152.225756 -410.574744)
		(width 0.14224)
		(layer "In13.Cu")
		(net "P5E_CPU1_P3_RX_BUF_DP<12>")
	)
	(segment
		(start 139.467336 -398.930622)
		(end 139.048744 -398.846802)
		(width 0.14224)
		(layer "In13.Cu")
		(net "P5E_CPU1_P3_RX_BUF_DP<12>")
	)
	(segment
		(start 150.027386 -402.73224)
		(end 148.862542 -401.95373)
		(width 0.14224)
		(layer "In13.Cu")
		(net "P5E_CPU1_P3_RX_BUF_DP<12>")
	)
	(segment
		(start 148.862542 -401.95373)
		(end 148.824696 -401.763484)
		(width 0.14224)
		(layer "In13.Cu")
		(net "P5E_CPU1_P3_RX_BUF_DP<12>")
	)
	(segment
		(start 129.25679 -395.760956)
		(end 128.940814 -395.474444)
		(width 0.14224)
		(layer "In13.Cu")
		(net "P5E_CPU1_P3_RX_BUF_DP<12>")
	)
	(segment
		(start 128.996948 -392.989562)
		(end 129.177034 -392.989562)
		(width 0.14224)
		(layer "In13.Cu")
		(net "P5E_CPU1_P3_RX_BUF_DP<12>")
	)
	(segment
		(start 147.341844 -400.937476)
		(end 146.973036 -400.691096)
		(width 0.14224)
		(layer "In13.Cu")
		(net "P5E_CPU1_P3_RX_BUF_DP<12>")
	)
	(segment
		(start 128.857502 -395.066012)
		(end 128.857502 -393.129008)
		(width 0.14224)
		(layer "In13.Cu")
		(net "P5E_CPU1_P3_RX_BUF_DP<12>")
	)
	(segment
		(start 129.450338 -395.751558)
		(end 129.25679 -395.760956)
		(width 0.14224)
		(layer "In13.Cu")
		(net "P5E_CPU1_P3_RX_BUF_DP<12>")
	)
	(segment
		(start 138.8872 -398.954244)
		(end 138.440668 -398.864836)
		(width 0.14224)
		(layer "In13.Cu")
		(net "P5E_CPU1_P3_RX_BUF_DP<12>")
	)
	(segment
		(start 150.750016 -433.61864)
		(end 150.603204 -433.765452)
		(width 0.14224)
		(layer "In13.Cu")
		(net "P5E_CPU1_P3_RX_BUF_DP<12>")
	)
	(segment
		(start 152.331166 -416.851592)
		(end 153.071068 -415.06521)
		(width 0.14224)
		(layer "In13.Cu")
		(net "P5E_CPU1_P3_RX_BUF_DP<12>")
	)
	(segment
		(start 152.062688 -417.499546)
		(end 152.242012 -417.425378)
		(width 0.14224)
		(layer "In13.Cu")
		(net "P5E_CPU1_P3_RX_BUF_DP<12>")
	)
	(segment
		(start 129.31648 -393.129008)
		(end 129.31648 -393.292838)
		(width 0.14224)
		(layer "In13.Cu")
		(net "P5E_CPU1_P3_RX_BUF_DP<12>")
	)
	(segment
		(start 128.857502 -393.129008)
		(end 128.996948 -392.989562)
		(width 0.14224)
		(layer "In13.Cu")
		(net "P5E_CPU1_P3_RX_BUF_DP<12>")
	)
	(segment
		(start 153.757376 -411.947868)
		(end 153.570178 -411.494732)
		(width 0.14224)
		(layer "In13.Cu")
		(net "P5E_CPU1_P3_RX_BUF_DP<12>")
	)
	(segment
		(start 150.603204 -433.765452)
		(end 150.383748 -433.765452)
		(width 0.14224)
		(layer "In13.Cu")
		(net "P5E_CPU1_P3_RX_BUF_DP<12>")
	)
	(segment
		(start 147.886928 -401.136866)
		(end 147.53209 -400.89963)
		(width 0.14224)
		(layer "In13.Cu")
		(net "P5E_CPU1_P3_RX_BUF_DP<12>")
	)
	(segment
		(start 151.535384 -405.574754)
		(end 151.023066 -405.574754)
		(width 0.14224)
		(layer "In13.Cu")
		(net "P5E_CPU1_P3_RX_BUF_DP<12>")
	)
	(segment
		(start 152.225756 -406.424892)
		(end 152.041352 -405.979884)
		(width 0.14224)
		(layer "In13.Cu")
		(net "P5E_CPU1_P3_RX_BUF_DP<12>")
	)
	(segment
		(start 152.225756 -409.476702)
		(end 152.362916 -409.339542)
		(width 0.14224)
		(layer "In13.Cu")
		(net "P5E_CPU1_P3_RX_BUF_DP<12>")
	)
	(segment
		(start 148.824696 -401.763484)
		(end 148.469604 -401.526248)
		(width 0.14224)
		(layer "In13.Cu")
		(net "P5E_CPU1_P3_RX_BUF_DP<12>")
	)
	(segment
		(start 153.339546 -414.417256)
		(end 153.757376 -413.408368)
		(width 0.14224)
		(layer "In13.Cu")
		(net "P5E_CPU1_P3_RX_BUF_DP<12>")
	)
	(segment
		(start 129.77622 -396.23238)
		(end 129.766822 -396.038578)
		(width 0.14224)
		(layer "In13.Cu")
		(net "P5E_CPU1_P3_RX_BUF_DP<12>")
	)
	(segment
		(start 150.391622 -421.533828)
		(end 152.062688 -417.499546)
		(width 0.14224)
		(layer "In13.Cu")
		(net "P5E_CPU1_P3_RX_BUF_DP<12>")
	)
	(segment
		(start 135.332724 -398.242028)
		(end 130.373882 -396.737332)
		(width 0.14224)
		(layer "In13.Cu")
		(net "P5E_CPU1_P3_RX_BUF_DP<12>")
	)
	(segment
		(start 152.242012 -417.425378)
		(end 152.405334 -417.030916)
		(width 0.14224)
		(layer "In13.Cu")
		(net "P5E_CPU1_P3_RX_BUF_DP<12>")
	)
	(segment
		(start 150.383748 -433.765452)
		(end 150.076408 -433.458112)
		(width 0.14224)
		(layer "In13.Cu")
		(net "P5E_CPU1_P3_RX_BUF_DP<12>")
	)
	(segment
		(start 152.225756 -408.348942)
		(end 152.362916 -408.211782)
		(width 0.14224)
		(layer "In13.Cu")
		(net "P5E_CPU1_P3_RX_BUF_DP<12>")
	)
	(segment
		(start 129.177034 -392.989562)
		(end 129.31648 -393.129008)
		(width 0.14224)
		(layer "In13.Cu")
		(net "P5E_CPU1_P3_RX_BUF_DP<12>")
	)
	(segment
		(start 152.225756 -408.775662)
		(end 152.225756 -408.348942)
		(width 0.14224)
		(layer "In13.Cu")
		(net "P5E_CPU1_P3_RX_BUF_DP<12>")
	)
	(segment
		(start 146.337274 -400.447256)
		(end 144.053052 -399.989548)
		(width 0.14224)
		(layer "In13.Cu")
		(net "P5E_CPU1_P3_RX_BUF_DP<12>")
	)
	(segment
		(start 153.431748 -411.356556)
		(end 152.523698 -410.980382)
		(width 0.14224)
		(layer "In13.Cu")
		(net "P5E_CPU1_P3_RX_BUF_DP<12>")
	)
	(segment
		(start 150.410672 -403.115526)
		(end 150.027386 -402.73224)
		(width 0.14224)
		(layer "In13.Cu")
		(net "P5E_CPU1_P3_RX_BUF_DP<12>")
	)
	(segment
		(start 152.44445 -410.927296)
		(end 152.44445 -410.92755)
		(width 0.14224)
		(layer "In13.Cu")
		(net "P5E_CPU1_P3_RX_BUF_DP<12>")
	)
	(segment
		(start 130.264662 -396.67561)
		(end 129.77622 -396.23238)
		(width 0.14224)
		(layer "In13.Cu")
		(net "P5E_CPU1_P3_RX_BUF_DP<12>")
	)
	(segment
		(start 143.365474 -399.851626)
		(end 139.575032 -399.092166)
		(width 0.14224)
		(layer "In13.Cu")
		(net "P5E_CPU1_P3_RX_BUF_DP<12>")
	)
	(segment
		(start 129.766822 -396.038578)
		(end 129.450338 -395.751558)
		(width 0.14224)
		(layer "In13.Cu")
		(net "P5E_CPU1_P3_RX_BUF_DP<12>")
	)
	(segment
		(start 153.250392 -414.991042)
		(end 153.413714 -414.59658)
		(width 0.14224)
		(layer "In13.Cu")
		(net "P5E_CPU1_P3_RX_BUF_DP<12>")
	)
	(segment
		(start 151.023066 -405.574754)
		(end 150.951438 -405.545036)
		(width 0.14224)
		(layer "In13.Cu")
		(net "P5E_CPU1_P3_RX_BUF_DP<12>")
	)
	(segment
		(start 153.071068 -415.06521)
		(end 153.250392 -414.991042)
		(width 0.14224)
		(layer "In13.Cu")
		(net "P5E_CPU1_P3_RX_BUF_DP<12>")
	)
	(segment
		(start 152.225756 -410.574744)
		(end 152.225756 -409.476702)
		(width 0.14224)
		(layer "In13.Cu")
		(net "P5E_CPU1_P3_RX_BUF_DP<12>")
	)
	(segment
		(start 152.225756 -407.647902)
		(end 152.225756 -406.424892)
		(width 0.14224)
		(layer "In13.Cu")
		(net "P5E_CPU1_P3_RX_BUF_DP<12>")
	)
	(segment
		(start 153.413714 -414.59658)
		(end 153.339546 -414.417256)
		(width 0.14224)
		(layer "In13.Cu")
		(net "P5E_CPU1_P3_RX_BUF_DP<12>")
	)
	(segment
		(start 151.707596 -405.646128)
		(end 151.535384 -405.574754)
		(width 0.14224)
		(layer "In13.Cu")
		(net "P5E_CPU1_P3_RX_BUF_DP<12>")
	)
	(segment
		(start 152.041352 -405.979884)
		(end 151.707596 -405.646128)
		(width 0.14224)
		(layer "In13.Cu")
		(net "P5E_CPU1_P3_RX_BUF_DP<12>")
	)
	(segment
		(start 144.053052 -399.989548)
		(end 143.94561 -399.828004)
		(width 0.14224)
		(layer "In13.Cu")
		(net "P5E_CPU1_P3_RX_BUF_DP<12>")
	)
	(segment
		(start 148.279358 -401.564094)
		(end 147.924774 -401.327112)
		(width 0.14224)
		(layer "In13.Cu")
		(net "P5E_CPU1_P3_RX_BUF_DP<12>")
	)
	(segment
		(start 138.333226 -398.703292)
		(end 137.914634 -398.619472)
		(width 0.14224)
		(layer "In13.Cu")
		(net "P5E_CPU1_P3_RX_BUF_DP<12>")
	)
	(segment
		(start 146.512534 -400.500342)
		(end 146.337274 -400.447256)
		(width 0.14224)
		(layer "In13.Cu")
		(net "P5E_CPU1_P3_RX_BUF_DP<12>")
	)
	(arc
		(start 150.076408 -423.117772)
		(mid 150.155994 -422.310272)
		(end 150.391622 -421.533828)
		(width 0.14224)
		(layer "In13.Cu")
		(net "P5E_CPU1_P3_RX_BUF_DP<12>")
	)
	(arc
		(start 128.940814 -395.474444)
		(mid 128.90117 -395.423979)
		(end 128.880616 -395.363192)
		(width 0.14224)
		(layer "In13.Cu")
		(net "P5E_CPU1_P3_RX_BUF_DP<12>")
	)
	(arc
		(start 128.880616 -395.363192)
		(mid 128.86327 -395.215052)
		(end 128.857502 -395.066012)
		(width 0.14224)
		(layer "In13.Cu")
		(net "P5E_CPU1_P3_RX_BUF_DP<12>")
	)
	(arc
		(start 150.694136 -403.799802)
		(mid 150.620471 -403.429464)
		(end 150.410672 -403.115526)
		(width 0.14224)
		(layer "In13.Cu")
		(net "P5E_CPU1_P3_RX_BUF_DP<12>")
	)
	(arc
		(start 130.373882 -396.737332)
		(mid 130.315847 -396.712531)
		(end 130.264662 -396.67561)
		(width 0.14224)
		(layer "In13.Cu")
		(net "P5E_CPU1_P3_RX_BUF_DP<12>")
	)
	(segment
		(start 127.977646 -392.977116)
		(end 128.116584 -393.116054)
		(width 0.1016)
		(layer "F.Cu")
		(net "P5E_CPU1_P3_RX_BUF_DP<11>")
	)
	(segment
		(start 127.41783 -391.281158)
		(end 127.502412 -391.36574)
		(width 0.1016)
		(layer "F.Cu")
		(net "P5E_CPU1_P3_RX_BUF_DP<11>")
	)
	(segment
		(start 127.413766 -391.577322)
		(end 127.413766 -392.723878)
		(width 0.1016)
		(layer "F.Cu")
		(net "P5E_CPU1_P3_RX_BUF_DP<11>")
	)
	(segment
		(start 128.116584 -393.116054)
		(end 128.116584 -393.292838)
		(width 0.1016)
		(layer "F.Cu")
		(net "P5E_CPU1_P3_RX_BUF_DP<11>")
	)
	(segment
		(start 127.413766 -392.723878)
		(end 127.667004 -392.977116)
		(width 0.1016)
		(layer "F.Cu")
		(net "P5E_CPU1_P3_RX_BUF_DP<11>")
	)
	(segment
		(start 127.667004 -392.977116)
		(end 127.977646 -392.977116)
		(width 0.1016)
		(layer "F.Cu")
		(net "P5E_CPU1_P3_RX_BUF_DP<11>")
	)
	(segment
		(start 127.502412 -391.36574)
		(end 127.502412 -391.488676)
		(width 0.1016)
		(layer "F.Cu")
		(net "P5E_CPU1_P3_RX_BUF_DP<11>")
	)
	(segment
		(start 127.502412 -391.488676)
		(end 127.413766 -391.577322)
		(width 0.1016)
		(layer "F.Cu")
		(net "P5E_CPU1_P3_RX_BUF_DP<11>")
	)
	(segment
		(start 149.162516 -410.574744)
		(end 149.162516 -409.382976)
		(width 0.14224)
		(layer "In13.Cu")
		(net "P5E_CPU1_P3_RX_BUF_DP<11>")
	)
	(segment
		(start 150.368508 -411.356556)
		(end 149.460204 -410.980382)
		(width 0.14224)
		(layer "In13.Cu")
		(net "P5E_CPU1_P3_RX_BUF_DP<11>")
	)
	(segment
		(start 135.484108 -399.270982)
		(end 129.853944 -397.562578)
		(width 0.14224)
		(layer "In13.Cu")
		(net "P5E_CPU1_P3_RX_BUF_DP<11>")
	)
	(segment
		(start 140.052298 -400.388836)
		(end 139.948666 -400.224752)
		(width 0.14224)
		(layer "In13.Cu")
		(net "P5E_CPU1_P3_RX_BUF_DP<11>")
	)
	(segment
		(start 150.328884 -414.47847)
		(end 150.492206 -414.084008)
		(width 0.14224)
		(layer "In13.Cu")
		(net "P5E_CPU1_P3_RX_BUF_DP<11>")
	)
	(segment
		(start 150.694136 -413.237934)
		(end 150.694136 -411.947614)
		(width 0.14224)
		(layer "In13.Cu")
		(net "P5E_CPU1_P3_RX_BUF_DP<11>")
	)
	(segment
		(start 142.669006 -400.97837)
		(end 142.252954 -400.884644)
		(width 0.14224)
		(layer "In13.Cu")
		(net "P5E_CPU1_P3_RX_BUF_DP<11>")
	)
	(segment
		(start 142.252954 -400.884644)
		(end 142.149068 -400.72056)
		(width 0.14224)
		(layer "In13.Cu")
		(net "P5E_CPU1_P3_RX_BUF_DP<11>")
	)
	(segment
		(start 140.632434 -400.378676)
		(end 140.46835 -400.482562)
		(width 0.14224)
		(layer "In13.Cu")
		(net "P5E_CPU1_P3_RX_BUF_DP<11>")
	)
	(segment
		(start 138.267694 -399.9865)
		(end 137.604246 -399.837148)
		(width 0.14224)
		(layer "In13.Cu")
		(net "P5E_CPU1_P3_RX_BUF_DP<11>")
	)
	(segment
		(start 150.492206 -414.084008)
		(end 150.418038 -413.904684)
		(width 0.14224)
		(layer "In13.Cu")
		(net "P5E_CPU1_P3_RX_BUF_DP<11>")
	)
	(segment
		(start 147.70354 -405.360378)
		(end 147.630896 -405.184864)
		(width 0.14224)
		(layer "In13.Cu")
		(net "P5E_CPU1_P3_RX_BUF_DP<11>")
	)
	(segment
		(start 148.644356 -405.646128)
		(end 148.472144 -405.574754)
		(width 0.14224)
		(layer "In13.Cu")
		(net "P5E_CPU1_P3_RX_BUF_DP<11>")
	)
	(segment
		(start 149.257512 -410.803852)
		(end 149.162516 -410.574744)
		(width 0.14224)
		(layer "In13.Cu")
		(net "P5E_CPU1_P3_RX_BUF_DP<11>")
	)
	(segment
		(start 149.162516 -408.681936)
		(end 149.162516 -408.255216)
		(width 0.14224)
		(layer "In13.Cu")
		(net "P5E_CPU1_P3_RX_BUF_DP<11>")
	)
	(segment
		(start 139.948666 -400.224752)
		(end 139.532106 -400.130772)
		(width 0.14224)
		(layer "In13.Cu")
		(net "P5E_CPU1_P3_RX_BUF_DP<11>")
	)
	(segment
		(start 150.418038 -413.904684)
		(end 150.694136 -413.237934)
		(width 0.14224)
		(layer "In13.Cu")
		(net "P5E_CPU1_P3_RX_BUF_DP<11>")
	)
	(segment
		(start 127.797052 -392.989562)
		(end 127.977138 -392.989562)
		(width 0.14224)
		(layer "In13.Cu")
		(net "P5E_CPU1_P3_RX_BUF_DP<11>")
	)
	(segment
		(start 127.977138 -392.989562)
		(end 128.116584 -393.129008)
		(width 0.14224)
		(layer "In13.Cu")
		(net "P5E_CPU1_P3_RX_BUF_DP<11>")
	)
	(segment
		(start 150.694136 -411.947614)
		(end 150.506684 -411.494732)
		(width 0.14224)
		(layer "In13.Cu")
		(net "P5E_CPU1_P3_RX_BUF_DP<11>")
	)
	(segment
		(start 149.299676 -408.118056)
		(end 149.299676 -407.691336)
		(width 0.14224)
		(layer "In13.Cu")
		(net "P5E_CPU1_P3_RX_BUF_DP<11>")
	)
	(segment
		(start 150.506684 -411.494732)
		(end 150.368508 -411.356556)
		(width 0.14224)
		(layer "In13.Cu")
		(net "P5E_CPU1_P3_RX_BUF_DP<11>")
	)
	(segment
		(start 147.959826 -405.574754)
		(end 147.888198 -405.545036)
		(width 0.14224)
		(layer "In13.Cu")
		(net "P5E_CPU1_P3_RX_BUF_DP<11>")
	)
	(segment
		(start 148.365718 -434.747416)
		(end 148.076412 -434.45811)
		(width 0.14224)
		(layer "In13.Cu")
		(net "P5E_CPU1_P3_RX_BUF_DP<11>")
	)
	(segment
		(start 147.630896 -405.184864)
		(end 147.630896 -403.88667)
		(width 0.14224)
		(layer "In13.Cu")
		(net "P5E_CPU1_P3_RX_BUF_DP<11>")
	)
	(segment
		(start 148.621242 -434.747416)
		(end 148.365718 -434.747416)
		(width 0.14224)
		(layer "In13.Cu")
		(net "P5E_CPU1_P3_RX_BUF_DP<11>")
	)
	(segment
		(start 149.836886 -415.66592)
		(end 150.000208 -415.271458)
		(width 0.14224)
		(layer "In13.Cu")
		(net "P5E_CPU1_P3_RX_BUF_DP<11>")
	)
	(segment
		(start 142.832836 -400.874738)
		(end 142.669006 -400.97837)
		(width 0.14224)
		(layer "In13.Cu")
		(net "P5E_CPU1_P3_RX_BUF_DP<11>")
	)
	(segment
		(start 148.75002 -434.618638)
		(end 148.621242 -434.747416)
		(width 0.14224)
		(layer "In13.Cu")
		(net "P5E_CPU1_P3_RX_BUF_DP<11>")
	)
	(segment
		(start 148.380196 -421.304466)
		(end 149.32914 -416.533076)
		(width 0.14224)
		(layer "In13.Cu")
		(net "P5E_CPU1_P3_RX_BUF_DP<11>")
	)
	(segment
		(start 148.75002 -434.289962)
		(end 148.75002 -434.618638)
		(width 0.14224)
		(layer "In13.Cu")
		(net "P5E_CPU1_P3_RX_BUF_DP<11>")
	)
	(segment
		(start 149.32914 -416.533076)
		(end 149.657562 -415.740342)
		(width 0.14224)
		(layer "In13.Cu")
		(net "P5E_CPU1_P3_RX_BUF_DP<11>")
	)
	(segment
		(start 129.744724 -397.500856)
		(end 127.70739 -395.657578)
		(width 0.14224)
		(layer "In13.Cu")
		(net "P5E_CPU1_P3_RX_BUF_DP<11>")
	)
	(segment
		(start 127.794766 -394.636244)
		(end 127.657606 -394.499084)
		(width 0.14224)
		(layer "In13.Cu")
		(net "P5E_CPU1_P3_RX_BUF_DP<11>")
	)
	(segment
		(start 149.299676 -409.245816)
		(end 149.299676 -408.819096)
		(width 0.14224)
		(layer "In13.Cu")
		(net "P5E_CPU1_P3_RX_BUF_DP<11>")
	)
	(segment
		(start 146.849084 -402.401278)
		(end 145.903188 -401.752308)
		(width 0.14224)
		(layer "In13.Cu")
		(net "P5E_CPU1_P3_RX_BUF_DP<11>")
	)
	(segment
		(start 149.162516 -408.255216)
		(end 149.299676 -408.118056)
		(width 0.14224)
		(layer "In13.Cu")
		(net "P5E_CPU1_P3_RX_BUF_DP<11>")
	)
	(segment
		(start 149.460204 -410.980382)
		(end 149.38121 -410.92755)
		(width 0.14224)
		(layer "In13.Cu")
		(net "P5E_CPU1_P3_RX_BUF_DP<11>")
	)
	(segment
		(start 141.04874 -400.472656)
		(end 140.632434 -400.378676)
		(width 0.14224)
		(layer "In13.Cu")
		(net "P5E_CPU1_P3_RX_BUF_DP<11>")
	)
	(segment
		(start 149.162516 -407.554176)
		(end 149.162516 -406.424892)
		(width 0.14224)
		(layer "In13.Cu")
		(net "P5E_CPU1_P3_RX_BUF_DP<11>")
	)
	(segment
		(start 143.353028 -401.132802)
		(end 143.249396 -400.968718)
		(width 0.14224)
		(layer "In13.Cu")
		(net "P5E_CPU1_P3_RX_BUF_DP<11>")
	)
	(segment
		(start 141.568678 -400.730466)
		(end 141.152626 -400.63674)
		(width 0.14224)
		(layer "In13.Cu")
		(net "P5E_CPU1_P3_RX_BUF_DP<11>")
	)
	(segment
		(start 138.848084 -399.976594)
		(end 138.431524 -399.882868)
		(width 0.14224)
		(layer "In13.Cu")
		(net "P5E_CPU1_P3_RX_BUF_DP<11>")
	)
	(segment
		(start 138.95197 -400.140678)
		(end 138.848084 -399.976594)
		(width 0.14224)
		(layer "In13.Cu")
		(net "P5E_CPU1_P3_RX_BUF_DP<11>")
	)
	(segment
		(start 139.532106 -400.130772)
		(end 139.368022 -400.234404)
		(width 0.14224)
		(layer "In13.Cu")
		(net "P5E_CPU1_P3_RX_BUF_DP<11>")
	)
	(segment
		(start 137.490962 -399.809462)
		(end 136.044686 -399.429478)
		(width 0.14224)
		(layer "In13.Cu")
		(net "P5E_CPU1_P3_RX_BUF_DP<11>")
	)
	(segment
		(start 148.978112 -405.979884)
		(end 148.644356 -405.646128)
		(width 0.14224)
		(layer "In13.Cu")
		(net "P5E_CPU1_P3_RX_BUF_DP<11>")
	)
	(segment
		(start 149.92604 -415.092388)
		(end 150.14956 -414.552638)
		(width 0.14224)
		(layer "In13.Cu")
		(net "P5E_CPU1_P3_RX_BUF_DP<11>")
	)
	(segment
		(start 127.657606 -395.545056)
		(end 127.657606 -395.200124)
		(width 0.14224)
		(layer "In13.Cu")
		(net "P5E_CPU1_P3_RX_BUF_DP<11>")
	)
	(segment
		(start 127.657606 -394.499084)
		(end 127.657606 -393.129008)
		(width 0.14224)
		(layer "In13.Cu")
		(net "P5E_CPU1_P3_RX_BUF_DP<11>")
	)
	(segment
		(start 127.657606 -393.129008)
		(end 127.797052 -392.989562)
		(width 0.14224)
		(layer "In13.Cu")
		(net "P5E_CPU1_P3_RX_BUF_DP<11>")
	)
	(segment
		(start 149.162516 -406.424892)
		(end 148.978112 -405.979884)
		(width 0.14224)
		(layer "In13.Cu")
		(net "P5E_CPU1_P3_RX_BUF_DP<11>")
	)
	(segment
		(start 149.299676 -408.819096)
		(end 149.162516 -408.681936)
		(width 0.14224)
		(layer "In13.Cu")
		(net "P5E_CPU1_P3_RX_BUF_DP<11>")
	)
	(segment
		(start 143.249396 -400.968718)
		(end 142.832836 -400.874738)
		(width 0.14224)
		(layer "In13.Cu")
		(net "P5E_CPU1_P3_RX_BUF_DP<11>")
	)
	(segment
		(start 139.368022 -400.234404)
		(end 138.95197 -400.140678)
		(width 0.14224)
		(layer "In13.Cu")
		(net "P5E_CPU1_P3_RX_BUF_DP<11>")
	)
	(segment
		(start 128.116584 -393.129008)
		(end 128.116584 -393.292838)
		(width 0.14224)
		(layer "In13.Cu")
		(net "P5E_CPU1_P3_RX_BUF_DP<11>")
	)
	(segment
		(start 148.076412 -434.45811)
		(end 148.076412 -424.38955)
		(width 0.14224)
		(layer "In13.Cu")
		(net "P5E_CPU1_P3_RX_BUF_DP<11>")
	)
	(segment
		(start 150.000208 -415.271458)
		(end 149.92604 -415.092388)
		(width 0.14224)
		(layer "In13.Cu")
		(net "P5E_CPU1_P3_RX_BUF_DP<11>")
	)
	(segment
		(start 149.657562 -415.740342)
		(end 149.836886 -415.66592)
		(width 0.14224)
		(layer "In13.Cu")
		(net "P5E_CPU1_P3_RX_BUF_DP<11>")
	)
	(segment
		(start 127.794766 -395.062964)
		(end 127.794766 -394.636244)
		(width 0.14224)
		(layer "In13.Cu")
		(net "P5E_CPU1_P3_RX_BUF_DP<11>")
	)
	(segment
		(start 149.38121 -410.92755)
		(end 149.257512 -410.803852)
		(width 0.14224)
		(layer "In13.Cu")
		(net "P5E_CPU1_P3_RX_BUF_DP<11>")
	)
	(segment
		(start 149.299676 -407.691336)
		(end 149.162516 -407.554176)
		(width 0.14224)
		(layer "In13.Cu")
		(net "P5E_CPU1_P3_RX_BUF_DP<11>")
	)
	(segment
		(start 141.152626 -400.63674)
		(end 141.04874 -400.472656)
		(width 0.14224)
		(layer "In13.Cu")
		(net "P5E_CPU1_P3_RX_BUF_DP<11>")
	)
	(segment
		(start 147.888198 -405.545036)
		(end 147.70354 -405.360378)
		(width 0.14224)
		(layer "In13.Cu")
		(net "P5E_CPU1_P3_RX_BUF_DP<11>")
	)
	(segment
		(start 145.690844 -401.659598)
		(end 143.353028 -401.132802)
		(width 0.14224)
		(layer "In13.Cu")
		(net "P5E_CPU1_P3_RX_BUF_DP<11>")
	)
	(segment
		(start 150.14956 -414.552638)
		(end 150.328884 -414.47847)
		(width 0.14224)
		(layer "In13.Cu")
		(net "P5E_CPU1_P3_RX_BUF_DP<11>")
	)
	(segment
		(start 127.657606 -395.200124)
		(end 127.794766 -395.062964)
		(width 0.14224)
		(layer "In13.Cu")
		(net "P5E_CPU1_P3_RX_BUF_DP<11>")
	)
	(segment
		(start 148.472144 -405.574754)
		(end 147.959826 -405.574754)
		(width 0.14224)
		(layer "In13.Cu")
		(net "P5E_CPU1_P3_RX_BUF_DP<11>")
	)
	(segment
		(start 149.162516 -409.382976)
		(end 149.299676 -409.245816)
		(width 0.14224)
		(layer "In13.Cu")
		(net "P5E_CPU1_P3_RX_BUF_DP<11>")
	)
	(segment
		(start 138.431524 -399.882868)
		(end 138.267694 -399.9865)
		(width 0.14224)
		(layer "In13.Cu")
		(net "P5E_CPU1_P3_RX_BUF_DP<11>")
	)
	(segment
		(start 142.149068 -400.72056)
		(end 141.732762 -400.62658)
		(width 0.14224)
		(layer "In13.Cu")
		(net "P5E_CPU1_P3_RX_BUF_DP<11>")
	)
	(segment
		(start 140.46835 -400.482562)
		(end 140.052298 -400.388836)
		(width 0.14224)
		(layer "In13.Cu")
		(net "P5E_CPU1_P3_RX_BUF_DP<11>")
	)
	(segment
		(start 141.732762 -400.62658)
		(end 141.568678 -400.730466)
		(width 0.14224)
		(layer "In13.Cu")
		(net "P5E_CPU1_P3_RX_BUF_DP<11>")
	)
	(arc
		(start 129.853944 -397.562578)
		(mid 129.795928 -397.537746)
		(end 129.744724 -397.500856)
		(width 0.14224)
		(layer "In13.Cu")
		(net "P5E_CPU1_P3_RX_BUF_DP<11>")
	)
	(arc
		(start 148.076412 -424.38955)
		(mid 148.152545 -422.839549)
		(end 148.380196 -421.304466)
		(width 0.14224)
		(layer "In13.Cu")
		(net "P5E_CPU1_P3_RX_BUF_DP<11>")
	)
	(arc
		(start 147.630896 -403.88667)
		(mid 147.423709 -403.047912)
		(end 146.849846 -402.40204)
		(width 0.14224)
		(layer "In13.Cu")
		(net "P5E_CPU1_P3_RX_BUF_DP<11>")
	)
	(arc
		(start 137.604246 -399.837148)
		(mid 137.547482 -399.823803)
		(end 137.490962 -399.809462)
		(width 0.14224)
		(layer "In13.Cu")
		(net "P5E_CPU1_P3_RX_BUF_DP<11>")
	)
	(arc
		(start 136.044686 -399.429478)
		(mid 135.763649 -399.352877)
		(end 135.484108 -399.270982)
		(width 0.14224)
		(layer "In13.Cu")
		(net "P5E_CPU1_P3_RX_BUF_DP<11>")
	)
	(arc
		(start 145.903188 -401.752308)
		(mid 145.801427 -401.695847)
		(end 145.690844 -401.659598)
		(width 0.14224)
		(layer "In13.Cu")
		(net "P5E_CPU1_P3_RX_BUF_DP<11>")
	)
	(arc
		(start 127.70739 -395.657578)
		(mid 127.670596 -395.606589)
		(end 127.657606 -395.545056)
		(width 0.14224)
		(layer "In13.Cu")
		(net "P5E_CPU1_P3_RX_BUF_DP<11>")
	)
	(arc
		(start 146.849846 -402.40204)
		(mid 146.849465 -402.401659)
		(end 146.849084 -402.401278)
		(width 0.14224)
		(layer "In13.Cu")
		(net "P5E_CPU1_P3_RX_BUF_DP<11>")
	)
	(segment
		(start 126.467108 -392.977116)
		(end 126.21387 -392.723878)
		(width 0.1016)
		(layer "F.Cu")
		(net "P5E_CPU1_P3_RX_BUF_DP<10>")
	)
	(segment
		(start 126.77775 -392.977116)
		(end 126.467108 -392.977116)
		(width 0.1016)
		(layer "F.Cu")
		(net "P5E_CPU1_P3_RX_BUF_DP<10>")
	)
	(segment
		(start 126.302008 -391.365232)
		(end 126.217934 -391.281158)
		(width 0.1016)
		(layer "F.Cu")
		(net "P5E_CPU1_P3_RX_BUF_DP<10>")
	)
	(segment
		(start 126.916688 -393.292838)
		(end 126.916688 -393.116054)
		(width 0.1016)
		(layer "F.Cu")
		(net "P5E_CPU1_P3_RX_BUF_DP<10>")
	)
	(segment
		(start 126.916688 -393.116054)
		(end 126.77775 -392.977116)
		(width 0.1016)
		(layer "F.Cu")
		(net "P5E_CPU1_P3_RX_BUF_DP<10>")
	)
	(segment
		(start 126.21387 -392.723878)
		(end 126.21387 -391.577322)
		(width 0.1016)
		(layer "F.Cu")
		(net "P5E_CPU1_P3_RX_BUF_DP<10>")
	)
	(segment
		(start 126.302008 -391.489184)
		(end 126.302008 -391.365232)
		(width 0.1016)
		(layer "F.Cu")
		(net "P5E_CPU1_P3_RX_BUF_DP<10>")
	)
	(segment
		(start 126.21387 -391.577322)
		(end 126.302008 -391.489184)
		(width 0.1016)
		(layer "F.Cu")
		(net "P5E_CPU1_P3_RX_BUF_DP<10>")
	)
	(segment
		(start 147.630896 -412.123128)
		(end 147.630896 -413.685736)
		(width 0.14224)
		(layer "In13.Cu")
		(net "P5E_CPU1_P3_RX_BUF_DP<10>")
	)
	(segment
		(start 146.397472 -410.980636)
		(end 147.167854 -411.29966)
		(width 0.14224)
		(layer "In13.Cu")
		(net "P5E_CPU1_P3_RX_BUF_DP<10>")
	)
	(segment
		(start 146.236436 -409.264104)
		(end 146.099276 -409.401264)
		(width 0.14224)
		(layer "In13.Cu")
		(net "P5E_CPU1_P3_RX_BUF_DP<10>")
	)
	(segment
		(start 145.581116 -405.646128)
		(end 145.914872 -405.979884)
		(width 0.14224)
		(layer "In13.Cu")
		(net "P5E_CPU1_P3_RX_BUF_DP<10>")
	)
	(segment
		(start 139.481052 -401.46605)
		(end 143.637254 -402.726398)
		(width 0.14224)
		(layer "In13.Cu")
		(net "P5E_CPU1_P3_RX_BUF_DP<10>")
	)
	(segment
		(start 138.809984 -401.262342)
		(end 138.980926 -401.170902)
		(width 0.14224)
		(layer "In13.Cu")
		(net "P5E_CPU1_P3_RX_BUF_DP<10>")
	)
	(segment
		(start 146.377914 -422.133776)
		(end 146.18208 -423.4561)
		(width 0.14224)
		(layer "In13.Cu")
		(net "P5E_CPU1_P3_RX_BUF_DP<10>")
	)
	(segment
		(start 144.48282 -403.297644)
		(end 144.521936 -403.390608)
		(width 0.14224)
		(layer "In13.Cu")
		(net "P5E_CPU1_P3_RX_BUF_DP<10>")
	)
	(segment
		(start 146.534124 -422.018206)
		(end 146.377914 -422.133776)
		(width 0.14224)
		(layer "In13.Cu")
		(net "P5E_CPU1_P3_RX_BUF_DP<10>")
	)
	(segment
		(start 127.87376 -397.175736)
		(end 128.175766 -397.477742)
		(width 0.14224)
		(layer "In13.Cu")
		(net "P5E_CPU1_P3_RX_BUF_DP<10>")
	)
	(segment
		(start 144.567656 -403.620732)
		(end 144.567656 -405.176736)
		(width 0.14224)
		(layer "In13.Cu")
		(net "P5E_CPU1_P3_RX_BUF_DP<10>")
	)
	(segment
		(start 146.099276 -410.574744)
		(end 146.194272 -410.803852)
		(width 0.14224)
		(layer "In13.Cu")
		(net "P5E_CPU1_P3_RX_BUF_DP<10>")
	)
	(segment
		(start 126.597156 -392.989562)
		(end 126.45771 -393.129008)
		(width 0.14224)
		(layer "In13.Cu")
		(net "P5E_CPU1_P3_RX_BUF_DP<10>")
	)
	(segment
		(start 126.916688 -393.129008)
		(end 126.777242 -392.989562)
		(width 0.14224)
		(layer "In13.Cu")
		(net "P5E_CPU1_P3_RX_BUF_DP<10>")
	)
	(segment
		(start 146.761962 -420.480236)
		(end 146.699478 -420.902638)
		(width 0.14224)
		(layer "In13.Cu")
		(net "P5E_CPU1_P3_RX_BUF_DP<10>")
	)
	(segment
		(start 146.076416 -433.458112)
		(end 146.351244 -433.73294)
		(width 0.14224)
		(layer "In13.Cu")
		(net "P5E_CPU1_P3_RX_BUF_DP<10>")
	)
	(segment
		(start 128.441958 -397.93799)
		(end 129.233168 -398.346422)
		(width 0.14224)
		(layer "In13.Cu")
		(net "P5E_CPU1_P3_RX_BUF_DP<10>")
	)
	(segment
		(start 146.18208 -423.4561)
		(end 146.076416 -424.885866)
		(width 0.14224)
		(layer "In13.Cu")
		(net "P5E_CPU1_P3_RX_BUF_DP<10>")
	)
	(segment
		(start 145.914872 -405.979884)
		(end 146.099276 -406.424892)
		(width 0.14224)
		(layer "In13.Cu")
		(net "P5E_CPU1_P3_RX_BUF_DP<10>")
	)
	(segment
		(start 144.02181 -402.897086)
		(end 144.257776 -403.03831)
		(width 0.14224)
		(layer "In13.Cu")
		(net "P5E_CPU1_P3_RX_BUF_DP<10>")
	)
	(segment
		(start 146.099276 -406.424892)
		(end 146.099276 -407.572464)
		(width 0.14224)
		(layer "In13.Cu")
		(net "P5E_CPU1_P3_RX_BUF_DP<10>")
	)
	(segment
		(start 147.630896 -413.685736)
		(end 147.310094 -415.851086)
		(width 0.14224)
		(layer "In13.Cu")
		(net "P5E_CPU1_P3_RX_BUF_DP<10>")
	)
	(segment
		(start 146.635724 -433.73294)
		(end 146.750024 -433.61864)
		(width 0.14224)
		(layer "In13.Cu")
		(net "P5E_CPU1_P3_RX_BUF_DP<10>")
	)
	(segment
		(start 146.596608 -421.595804)
		(end 146.534124 -422.018206)
		(width 0.14224)
		(layer "In13.Cu")
		(net "P5E_CPU1_P3_RX_BUF_DP<10>")
	)
	(segment
		(start 127.378206 -396.680182)
		(end 127.378206 -396.874238)
		(width 0.14224)
		(layer "In13.Cu")
		(net "P5E_CPU1_P3_RX_BUF_DP<10>")
	)
	(segment
		(start 126.45771 -395.339062)
		(end 126.45771 -395.780006)
		(width 0.14224)
		(layer "In13.Cu")
		(net "P5E_CPU1_P3_RX_BUF_DP<10>")
	)
	(segment
		(start 126.45771 -393.129008)
		(end 126.45771 -394.638022)
		(width 0.14224)
		(layer "In13.Cu")
		(net "P5E_CPU1_P3_RX_BUF_DP<10>")
	)
	(segment
		(start 126.59487 -395.201902)
		(end 126.45771 -395.339062)
		(width 0.14224)
		(layer "In13.Cu")
		(net "P5E_CPU1_P3_RX_BUF_DP<10>")
	)
	(segment
		(start 126.882144 -396.378176)
		(end 127.0762 -396.378176)
		(width 0.14224)
		(layer "In13.Cu")
		(net "P5E_CPU1_P3_RX_BUF_DP<10>")
	)
	(segment
		(start 144.854422 -405.574754)
		(end 145.409158 -405.574754)
		(width 0.14224)
		(layer "In13.Cu")
		(net "P5E_CPU1_P3_RX_BUF_DP<10>")
	)
	(segment
		(start 146.076416 -424.885866)
		(end 146.076416 -433.458112)
		(width 0.14224)
		(layer "In13.Cu")
		(net "P5E_CPU1_P3_RX_BUF_DP<10>")
	)
	(segment
		(start 128.175766 -397.671798)
		(end 128.441958 -397.93799)
		(width 0.14224)
		(layer "In13.Cu")
		(net "P5E_CPU1_P3_RX_BUF_DP<10>")
	)
	(segment
		(start 147.425664 -416.006788)
		(end 147.362926 -416.42919)
		(width 0.14224)
		(layer "In13.Cu")
		(net "P5E_CPU1_P3_RX_BUF_DP<10>")
	)
	(segment
		(start 139.389612 -401.294854)
		(end 139.481052 -401.46605)
		(width 0.14224)
		(layer "In13.Cu")
		(net "P5E_CPU1_P3_RX_BUF_DP<10>")
	)
	(segment
		(start 146.750024 -433.61864)
		(end 146.750024 -433.289964)
		(width 0.14224)
		(layer "In13.Cu")
		(net "P5E_CPU1_P3_RX_BUF_DP<10>")
	)
	(segment
		(start 146.351244 -433.73294)
		(end 146.635724 -433.73294)
		(width 0.14224)
		(layer "In13.Cu")
		(net "P5E_CPU1_P3_RX_BUF_DP<10>")
	)
	(segment
		(start 126.45771 -394.638022)
		(end 126.59487 -394.775182)
		(width 0.14224)
		(layer "In13.Cu")
		(net "P5E_CPU1_P3_RX_BUF_DP<10>")
	)
	(segment
		(start 129.350516 -398.39392)
		(end 138.809984 -401.262342)
		(width 0.14224)
		(layer "In13.Cu")
		(net "P5E_CPU1_P3_RX_BUF_DP<10>")
	)
	(segment
		(start 145.409158 -405.574754)
		(end 145.581116 -405.646128)
		(width 0.14224)
		(layer "In13.Cu")
		(net "P5E_CPU1_P3_RX_BUF_DP<10>")
	)
	(segment
		(start 146.932396 -418.397182)
		(end 147.047966 -418.552884)
		(width 0.14224)
		(layer "In13.Cu")
		(net "P5E_CPU1_P3_RX_BUF_DP<10>")
	)
	(segment
		(start 147.310094 -415.851086)
		(end 147.425664 -416.006788)
		(width 0.14224)
		(layer "In13.Cu")
		(net "P5E_CPU1_P3_RX_BUF_DP<10>")
	)
	(segment
		(start 126.916688 -393.292838)
		(end 126.916688 -393.129008)
		(width 0.14224)
		(layer "In13.Cu")
		(net "P5E_CPU1_P3_RX_BUF_DP<10>")
	)
	(segment
		(start 147.031964 -417.724082)
		(end 146.932396 -418.397182)
		(width 0.14224)
		(layer "In13.Cu")
		(net "P5E_CPU1_P3_RX_BUF_DP<10>")
	)
	(segment
		(start 146.099276 -407.572464)
		(end 146.236436 -407.709624)
		(width 0.14224)
		(layer "In13.Cu")
		(net "P5E_CPU1_P3_RX_BUF_DP<10>")
	)
	(segment
		(start 146.646392 -420.32428)
		(end 146.761962 -420.480236)
		(width 0.14224)
		(layer "In13.Cu")
		(net "P5E_CPU1_P3_RX_BUF_DP<10>")
	)
	(segment
		(start 147.362926 -416.42919)
		(end 147.20697 -416.54476)
		(width 0.14224)
		(layer "In13.Cu")
		(net "P5E_CPU1_P3_RX_BUF_DP<10>")
	)
	(segment
		(start 144.728692 -405.522684)
		(end 144.854422 -405.574754)
		(width 0.14224)
		(layer "In13.Cu")
		(net "P5E_CPU1_P3_RX_BUF_DP<10>")
	)
	(segment
		(start 146.985228 -418.975286)
		(end 146.829272 -419.090856)
		(width 0.14224)
		(layer "In13.Cu")
		(net "P5E_CPU1_P3_RX_BUF_DP<10>")
	)
	(segment
		(start 146.236436 -407.709624)
		(end 146.236436 -408.136344)
		(width 0.14224)
		(layer "In13.Cu")
		(net "P5E_CPU1_P3_RX_BUF_DP<10>")
	)
	(segment
		(start 138.980926 -401.170902)
		(end 139.389612 -401.294854)
		(width 0.14224)
		(layer "In13.Cu")
		(net "P5E_CPU1_P3_RX_BUF_DP<10>")
	)
	(segment
		(start 126.59487 -394.775182)
		(end 126.59487 -395.201902)
		(width 0.14224)
		(layer "In13.Cu")
		(net "P5E_CPU1_P3_RX_BUF_DP<10>")
	)
	(segment
		(start 126.777242 -392.989562)
		(end 126.597156 -392.989562)
		(width 0.14224)
		(layer "In13.Cu")
		(net "P5E_CPU1_P3_RX_BUF_DP<10>")
	)
	(segment
		(start 127.378206 -396.874238)
		(end 127.679704 -397.175736)
		(width 0.14224)
		(layer "In13.Cu")
		(net "P5E_CPU1_P3_RX_BUF_DP<10>")
	)
	(segment
		(start 127.679704 -397.175736)
		(end 127.87376 -397.175736)
		(width 0.14224)
		(layer "In13.Cu")
		(net "P5E_CPU1_P3_RX_BUF_DP<10>")
	)
	(segment
		(start 147.18792 -417.608512)
		(end 147.031964 -417.724082)
		(width 0.14224)
		(layer "In13.Cu")
		(net "P5E_CPU1_P3_RX_BUF_DP<10>")
	)
	(segment
		(start 146.236436 -408.837384)
		(end 146.236436 -409.264104)
		(width 0.14224)
		(layer "In13.Cu")
		(net "P5E_CPU1_P3_RX_BUF_DP<10>")
	)
	(segment
		(start 146.829272 -419.090856)
		(end 146.646392 -420.32428)
		(width 0.14224)
		(layer "In13.Cu")
		(net "P5E_CPU1_P3_RX_BUF_DP<10>")
	)
	(segment
		(start 146.099276 -409.401264)
		(end 146.099276 -410.574744)
		(width 0.14224)
		(layer "In13.Cu")
		(net "P5E_CPU1_P3_RX_BUF_DP<10>")
	)
	(segment
		(start 146.194272 -410.803852)
		(end 146.31797 -410.92755)
		(width 0.14224)
		(layer "In13.Cu")
		(net "P5E_CPU1_P3_RX_BUF_DP<10>")
	)
	(segment
		(start 146.543522 -421.017954)
		(end 146.481038 -421.439848)
		(width 0.14224)
		(layer "In13.Cu")
		(net "P5E_CPU1_P3_RX_BUF_DP<10>")
	)
	(segment
		(start 146.481038 -421.439848)
		(end 146.596608 -421.595804)
		(width 0.14224)
		(layer "In13.Cu")
		(net "P5E_CPU1_P3_RX_BUF_DP<10>")
	)
	(segment
		(start 147.135088 -417.030408)
		(end 147.250658 -417.18611)
		(width 0.14224)
		(layer "In13.Cu")
		(net "P5E_CPU1_P3_RX_BUF_DP<10>")
	)
	(segment
		(start 146.099276 -408.700224)
		(end 146.236436 -408.837384)
		(width 0.14224)
		(layer "In13.Cu")
		(net "P5E_CPU1_P3_RX_BUF_DP<10>")
	)
	(segment
		(start 127.0762 -396.378176)
		(end 127.378206 -396.680182)
		(width 0.14224)
		(layer "In13.Cu")
		(net "P5E_CPU1_P3_RX_BUF_DP<10>")
	)
	(segment
		(start 147.20697 -416.54476)
		(end 147.135088 -417.030408)
		(width 0.14224)
		(layer "In13.Cu")
		(net "P5E_CPU1_P3_RX_BUF_DP<10>")
	)
	(segment
		(start 144.698466 -405.492458)
		(end 144.728692 -405.522684)
		(width 0.14224)
		(layer "In13.Cu")
		(net "P5E_CPU1_P3_RX_BUF_DP<10>")
	)
	(segment
		(start 146.236436 -408.136344)
		(end 146.099276 -408.273504)
		(width 0.14224)
		(layer "In13.Cu")
		(net "P5E_CPU1_P3_RX_BUF_DP<10>")
	)
	(segment
		(start 147.047966 -418.552884)
		(end 146.985228 -418.975286)
		(width 0.14224)
		(layer "In13.Cu")
		(net "P5E_CPU1_P3_RX_BUF_DP<10>")
	)
	(segment
		(start 147.250658 -417.18611)
		(end 147.18792 -417.608512)
		(width 0.14224)
		(layer "In13.Cu")
		(net "P5E_CPU1_P3_RX_BUF_DP<10>")
	)
	(segment
		(start 126.580646 -396.076678)
		(end 126.882144 -396.378176)
		(width 0.14224)
		(layer "In13.Cu")
		(net "P5E_CPU1_P3_RX_BUF_DP<10>")
	)
	(segment
		(start 146.699478 -420.902638)
		(end 146.543522 -421.017954)
		(width 0.14224)
		(layer "In13.Cu")
		(net "P5E_CPU1_P3_RX_BUF_DP<10>")
	)
	(segment
		(start 146.099276 -408.273504)
		(end 146.099276 -408.700224)
		(width 0.14224)
		(layer "In13.Cu")
		(net "P5E_CPU1_P3_RX_BUF_DP<10>")
	)
	(segment
		(start 128.175766 -397.477742)
		(end 128.175766 -397.671798)
		(width 0.14224)
		(layer "In13.Cu")
		(net "P5E_CPU1_P3_RX_BUF_DP<10>")
	)
	(arc
		(start 147.167854 -411.29966)
		(mid 147.293585 -411.374426)
		(end 147.39239 -411.482286)
		(width 0.14224)
		(layer "In13.Cu")
		(net "P5E_CPU1_P3_RX_BUF_DP<10>")
	)
	(arc
		(start 146.31797 -410.92755)
		(mid 146.3551 -410.958021)
		(end 146.397472 -410.980636)
		(width 0.14224)
		(layer "In13.Cu")
		(net "P5E_CPU1_P3_RX_BUF_DP<10>")
	)
	(arc
		(start 144.567656 -405.176736)
		(mid 144.601646 -405.347616)
		(end 144.698466 -405.492458)
		(width 0.14224)
		(layer "In13.Cu")
		(net "P5E_CPU1_P3_RX_BUF_DP<10>")
	)
	(arc
		(start 143.637254 -402.726398)
		(mid 143.834721 -402.800049)
		(end 144.02181 -402.897086)
		(width 0.14224)
		(layer "In13.Cu")
		(net "P5E_CPU1_P3_RX_BUF_DP<10>")
	)
	(arc
		(start 147.482052 -411.618684)
		(mid 147.592996 -411.860131)
		(end 147.630896 -412.123128)
		(width 0.14224)
		(layer "In13.Cu")
		(net "P5E_CPU1_P3_RX_BUF_DP<10>")
	)
	(arc
		(start 147.39239 -411.482286)
		(mid 147.437555 -411.550265)
		(end 147.482052 -411.618684)
		(width 0.14224)
		(layer "In13.Cu")
		(net "P5E_CPU1_P3_RX_BUF_DP<10>")
	)
	(arc
		(start 129.233168 -398.346422)
		(mid 129.290769 -398.372823)
		(end 129.350516 -398.39392)
		(width 0.14224)
		(layer "In13.Cu")
		(net "P5E_CPU1_P3_RX_BUF_DP<10>")
	)
	(arc
		(start 144.257776 -403.03831)
		(mid 144.390978 -403.150025)
		(end 144.48282 -403.297644)
		(width 0.14224)
		(layer "In13.Cu")
		(net "P5E_CPU1_P3_RX_BUF_DP<10>")
	)
	(arc
		(start 126.45771 -395.780006)
		(mid 126.489666 -395.940569)
		(end 126.580646 -396.076678)
		(width 0.14224)
		(layer "In13.Cu")
		(net "P5E_CPU1_P3_RX_BUF_DP<10>")
	)
	(arc
		(start 144.521936 -403.390608)
		(mid 144.556079 -403.503428)
		(end 144.567656 -403.620732)
		(width 0.14224)
		(layer "In13.Cu")
		(net "P5E_CPU1_P3_RX_BUF_DP<10>")
	)
	(segment
		(start 114.191542 -391.599674)
		(end 114.191542 -392.701526)
		(width 0.1016)
		(layer "F.Cu")
		(net "P5E_CPU1_P3_RX_BUF_DP<0>")
	)
	(segment
		(start 114.30254 -391.36574)
		(end 114.30254 -391.488676)
		(width 0.1016)
		(layer "F.Cu")
		(net "P5E_CPU1_P3_RX_BUF_DP<0>")
	)
	(segment
		(start 114.191542 -392.701526)
		(end 114.467132 -392.977116)
		(width 0.1016)
		(layer "F.Cu")
		(net "P5E_CPU1_P3_RX_BUF_DP<0>")
	)
	(segment
		(start 114.30254 -391.488676)
		(end 114.191542 -391.599674)
		(width 0.1016)
		(layer "F.Cu")
		(net "P5E_CPU1_P3_RX_BUF_DP<0>")
	)
	(segment
		(start 114.467132 -392.977116)
		(end 114.777774 -392.977116)
		(width 0.1016)
		(layer "F.Cu")
		(net "P5E_CPU1_P3_RX_BUF_DP<0>")
	)
	(segment
		(start 114.217958 -391.281158)
		(end 114.30254 -391.36574)
		(width 0.1016)
		(layer "F.Cu")
		(net "P5E_CPU1_P3_RX_BUF_DP<0>")
	)
	(segment
		(start 114.777774 -392.977116)
		(end 114.916458 -393.1158)
		(width 0.1016)
		(layer "F.Cu")
		(net "P5E_CPU1_P3_RX_BUF_DP<0>")
	)
	(segment
		(start 114.916458 -393.1158)
		(end 114.916458 -393.292838)
		(width 0.1016)
		(layer "F.Cu")
		(net "P5E_CPU1_P3_RX_BUF_DP<0>")
	)
	(segment
		(start 114.45748 -400.558)
		(end 114.45748 -400.13128)
		(width 0.14224)
		(layer "In13.Cu")
		(net "P5E_CPU1_P3_RX_BUF_DP<0>")
	)
	(segment
		(start 114.45748 -401.25904)
		(end 114.59464 -401.12188)
		(width 0.14224)
		(layer "In13.Cu")
		(net "P5E_CPU1_P3_RX_BUF_DP<0>")
	)
	(segment
		(start 114.45748 -398.30248)
		(end 114.45748 -397.87576)
		(width 0.14224)
		(layer "In13.Cu")
		(net "P5E_CPU1_P3_RX_BUF_DP<0>")
	)
	(segment
		(start 125.749812 -433.61864)
		(end 125.611636 -433.756816)
		(width 0.14224)
		(layer "In13.Cu")
		(net "P5E_CPU1_P3_RX_BUF_DP<0>")
	)
	(segment
		(start 114.45748 -396.04696)
		(end 114.45748 -395.62024)
		(width 0.14224)
		(layer "In13.Cu")
		(net "P5E_CPU1_P3_RX_BUF_DP<0>")
	)
	(segment
		(start 114.59464 -398.86636)
		(end 114.59464 -398.43964)
		(width 0.14224)
		(layer "In13.Cu")
		(net "P5E_CPU1_P3_RX_BUF_DP<0>")
	)
	(segment
		(start 115.466876 -410.57449)
		(end 115.466876 -409.254452)
		(width 0.14224)
		(layer "In13.Cu")
		(net "P5E_CPU1_P3_RX_BUF_DP<0>")
	)
	(segment
		(start 120.816878 -415.24936)
		(end 120.637808 -415.323528)
		(width 0.14224)
		(layer "In13.Cu")
		(net "P5E_CPU1_P3_RX_BUF_DP<0>")
	)
	(segment
		(start 125.611636 -433.756816)
		(end 125.073664 -433.756816)
		(width 0.14224)
		(layer "In13.Cu")
		(net "P5E_CPU1_P3_RX_BUF_DP<0>")
	)
	(segment
		(start 114.145314 -403.160738)
		(end 114.311938 -403.06117)
		(width 0.14224)
		(layer "In13.Cu")
		(net "P5E_CPU1_P3_RX_BUF_DP<0>")
	)
	(segment
		(start 114.45748 -395.62024)
		(end 114.59464 -395.48308)
		(width 0.14224)
		(layer "In13.Cu")
		(net "P5E_CPU1_P3_RX_BUF_DP<0>")
	)
	(segment
		(start 115.466876 -408.126692)
		(end 115.604036 -407.989532)
		(width 0.14224)
		(layer "In13.Cu")
		(net "P5E_CPU1_P3_RX_BUF_DP<0>")
	)
	(segment
		(start 114.59464 -396.61084)
		(end 114.59464 -396.18412)
		(width 0.14224)
		(layer "In13.Cu")
		(net "P5E_CPU1_P3_RX_BUF_DP<0>")
	)
	(segment
		(start 124.974604 -433.715668)
		(end 124.92609 -433.667154)
		(width 0.14224)
		(layer "In13.Cu")
		(net "P5E_CPU1_P3_RX_BUF_DP<0>")
	)
	(segment
		(start 115.466876 -406.424892)
		(end 115.35664 -406.1587)
		(width 0.14224)
		(layer "In13.Cu")
		(net "P5E_CPU1_P3_RX_BUF_DP<0>")
	)
	(segment
		(start 114.45748 -393.129008)
		(end 114.596926 -392.989562)
		(width 0.14224)
		(layer "In13.Cu")
		(net "P5E_CPU1_P3_RX_BUF_DP<0>")
	)
	(segment
		(start 114.192558 -405.545036)
		(end 114.0079 -405.360378)
		(width 0.14224)
		(layer "In13.Cu")
		(net "P5E_CPU1_P3_RX_BUF_DP<0>")
	)
	(segment
		(start 114.916458 -393.129008)
		(end 114.916458 -393.292838)
		(width 0.14224)
		(layer "In13.Cu")
		(net "P5E_CPU1_P3_RX_BUF_DP<0>")
	)
	(segment
		(start 115.604036 -409.117292)
		(end 115.604036 -408.690572)
		(width 0.14224)
		(layer "In13.Cu")
		(net "P5E_CPU1_P3_RX_BUF_DP<0>")
	)
	(segment
		(start 113.965736 -403.878034)
		(end 114.145314 -403.160738)
		(width 0.14224)
		(layer "In13.Cu")
		(net "P5E_CPU1_P3_RX_BUF_DP<0>")
	)
	(segment
		(start 113.929922 -404.057612)
		(end 113.965736 -403.878034)
		(width 0.14224)
		(layer "In13.Cu")
		(net "P5E_CPU1_P3_RX_BUF_DP<0>")
	)
	(segment
		(start 114.59464 -395.05636)
		(end 114.45748 -394.9192)
		(width 0.14224)
		(layer "In13.Cu")
		(net "P5E_CPU1_P3_RX_BUF_DP<0>")
	)
	(segment
		(start 115.466876 -409.254452)
		(end 115.604036 -409.117292)
		(width 0.14224)
		(layer "In13.Cu")
		(net "P5E_CPU1_P3_RX_BUF_DP<0>")
	)
	(segment
		(start 114.45748 -396.748)
		(end 114.59464 -396.61084)
		(width 0.14224)
		(layer "In13.Cu")
		(net "P5E_CPU1_P3_RX_BUF_DP<0>")
	)
	(segment
		(start 114.45748 -399.00352)
		(end 114.59464 -398.86636)
		(width 0.14224)
		(layer "In13.Cu")
		(net "P5E_CPU1_P3_RX_BUF_DP<0>")
	)
	(segment
		(start 114.777012 -392.989562)
		(end 114.916458 -393.129008)
		(width 0.14224)
		(layer "In13.Cu")
		(net "P5E_CPU1_P3_RX_BUF_DP<0>")
	)
	(segment
		(start 115.466876 -407.425652)
		(end 115.466876 -406.424892)
		(width 0.14224)
		(layer "In13.Cu")
		(net "P5E_CPU1_P3_RX_BUF_DP<0>")
	)
	(segment
		(start 114.45748 -394.9192)
		(end 114.45748 -393.129008)
		(width 0.14224)
		(layer "In13.Cu")
		(net "P5E_CPU1_P3_RX_BUF_DP<0>")
	)
	(segment
		(start 114.45748 -397.17472)
		(end 114.45748 -396.748)
		(width 0.14224)
		(layer "In13.Cu")
		(net "P5E_CPU1_P3_RX_BUF_DP<0>")
	)
	(segment
		(start 114.59464 -398.43964)
		(end 114.45748 -398.30248)
		(width 0.14224)
		(layer "In13.Cu")
		(net "P5E_CPU1_P3_RX_BUF_DP<0>")
	)
	(segment
		(start 117.138958 -413.662622)
		(end 117.008148 -413.3469)
		(width 0.14224)
		(layer "In13.Cu")
		(net "P5E_CPU1_P3_RX_BUF_DP<0>")
	)
	(segment
		(start 120.637808 -415.323528)
		(end 117.405658 -413.984948)
		(width 0.14224)
		(layer "In13.Cu")
		(net "P5E_CPU1_P3_RX_BUF_DP<0>")
	)
	(segment
		(start 114.41557 -402.646896)
		(end 114.316002 -402.480526)
		(width 0.14224)
		(layer "In13.Cu")
		(net "P5E_CPU1_P3_RX_BUF_DP<0>")
	)
	(segment
		(start 115.466876 -408.553412)
		(end 115.466876 -408.126692)
		(width 0.14224)
		(layer "In13.Cu")
		(net "P5E_CPU1_P3_RX_BUF_DP<0>")
	)
	(segment
		(start 114.59464 -400.69516)
		(end 114.45748 -400.558)
		(width 0.14224)
		(layer "In13.Cu")
		(net "P5E_CPU1_P3_RX_BUF_DP<0>")
	)
	(segment
		(start 115.604036 -407.562812)
		(end 115.466876 -407.425652)
		(width 0.14224)
		(layer "In13.Cu")
		(net "P5E_CPU1_P3_RX_BUF_DP<0>")
	)
	(segment
		(start 121.21134 -415.412682)
		(end 120.816878 -415.24936)
		(width 0.14224)
		(layer "In13.Cu")
		(net "P5E_CPU1_P3_RX_BUF_DP<0>")
	)
	(segment
		(start 114.264186 -405.574754)
		(end 114.192558 -405.545036)
		(width 0.14224)
		(layer "In13.Cu")
		(net "P5E_CPU1_P3_RX_BUF_DP<0>")
	)
	(segment
		(start 114.59464 -397.7386)
		(end 114.59464 -397.31188)
		(width 0.14224)
		(layer "In13.Cu")
		(net "P5E_CPU1_P3_RX_BUF_DP<0>")
	)
	(segment
		(start 124.768864 -417.239958)
		(end 124.592334 -417.063428)
		(width 0.14224)
		(layer "In13.Cu")
		(net "P5E_CPU1_P3_RX_BUF_DP<0>")
	)
	(segment
		(start 114.59464 -397.31188)
		(end 114.45748 -397.17472)
		(width 0.14224)
		(layer "In13.Cu")
		(net "P5E_CPU1_P3_RX_BUF_DP<0>")
	)
	(segment
		(start 114.59464 -399.5674)
		(end 114.45748 -399.43024)
		(width 0.14224)
		(layer "In13.Cu")
		(net "P5E_CPU1_P3_RX_BUF_DP<0>")
	)
	(segment
		(start 124.191776 -416.795712)
		(end 121.285762 -415.592006)
		(width 0.14224)
		(layer "In13.Cu")
		(net "P5E_CPU1_P3_RX_BUF_DP<0>")
	)
	(segment
		(start 115.604036 -407.989532)
		(end 115.604036 -407.562812)
		(width 0.14224)
		(layer "In13.Cu")
		(net "P5E_CPU1_P3_RX_BUF_DP<0>")
	)
	(segment
		(start 114.45748 -397.87576)
		(end 114.59464 -397.7386)
		(width 0.14224)
		(layer "In13.Cu")
		(net "P5E_CPU1_P3_RX_BUF_DP<0>")
	)
	(segment
		(start 115.572032 -410.82849)
		(end 115.466876 -410.57449)
		(width 0.14224)
		(layer "In13.Cu")
		(net "P5E_CPU1_P3_RX_BUF_DP<0>")
	)
	(segment
		(start 121.285762 -415.592006)
		(end 121.21134 -415.412682)
		(width 0.14224)
		(layer "In13.Cu")
		(net "P5E_CPU1_P3_RX_BUF_DP<0>")
	)
	(segment
		(start 115.604036 -408.690572)
		(end 115.466876 -408.553412)
		(width 0.14224)
		(layer "In13.Cu")
		(net "P5E_CPU1_P3_RX_BUF_DP<0>")
	)
	(segment
		(start 116.998242 -412.030418)
		(end 116.998242 -411.733238)
		(width 0.14224)
		(layer "In13.Cu")
		(net "P5E_CPU1_P3_RX_BUF_DP<0>")
	)
	(segment
		(start 114.59464 -395.48308)
		(end 114.59464 -395.05636)
		(width 0.14224)
		(layer "In13.Cu")
		(net "P5E_CPU1_P3_RX_BUF_DP<0>")
	)
	(segment
		(start 114.45748 -401.914868)
		(end 114.45748 -401.25904)
		(width 0.14224)
		(layer "In13.Cu")
		(net "P5E_CPU1_P3_RX_BUF_DP<0>")
	)
	(segment
		(start 115.35664 -406.1587)
		(end 114.772694 -405.574754)
		(width 0.14224)
		(layer "In13.Cu")
		(net "P5E_CPU1_P3_RX_BUF_DP<0>")
	)
	(segment
		(start 125.749812 -433.289964)
		(end 125.749812 -433.61864)
		(width 0.14224)
		(layer "In13.Cu")
		(net "P5E_CPU1_P3_RX_BUF_DP<0>")
	)
	(segment
		(start 114.59464 -399.99412)
		(end 114.59464 -399.5674)
		(width 0.14224)
		(layer "In13.Cu")
		(net "P5E_CPU1_P3_RX_BUF_DP<0>")
	)
	(segment
		(start 114.0079 -405.360378)
		(end 113.929922 -405.172164)
		(width 0.14224)
		(layer "In13.Cu")
		(net "P5E_CPU1_P3_RX_BUF_DP<0>")
	)
	(segment
		(start 117.405658 -413.984948)
		(end 117.405404 -413.984694)
		(width 0.14224)
		(layer "In13.Cu")
		(net "P5E_CPU1_P3_RX_BUF_DP<0>")
	)
	(segment
		(start 114.59464 -401.12188)
		(end 114.59464 -400.69516)
		(width 0.14224)
		(layer "In13.Cu")
		(net "P5E_CPU1_P3_RX_BUF_DP<0>")
	)
	(segment
		(start 116.998496 -413.298132)
		(end 116.998496 -412.030672)
		(width 0.14224)
		(layer "In13.Cu")
		(net "P5E_CPU1_P3_RX_BUF_DP<0>")
	)
	(segment
		(start 114.311938 -403.06117)
		(end 114.41557 -402.646896)
		(width 0.14224)
		(layer "In13.Cu")
		(net "P5E_CPU1_P3_RX_BUF_DP<0>")
	)
	(segment
		(start 114.596926 -392.989562)
		(end 114.777012 -392.989562)
		(width 0.14224)
		(layer "In13.Cu")
		(net "P5E_CPU1_P3_RX_BUF_DP<0>")
	)
	(segment
		(start 114.59464 -396.18412)
		(end 114.45748 -396.04696)
		(width 0.14224)
		(layer "In13.Cu")
		(net "P5E_CPU1_P3_RX_BUF_DP<0>")
	)
	(segment
		(start 114.45748 -399.43024)
		(end 114.45748 -399.00352)
		(width 0.14224)
		(layer "In13.Cu")
		(net "P5E_CPU1_P3_RX_BUF_DP<0>")
	)
	(segment
		(start 114.772694 -405.574754)
		(end 114.264186 -405.574754)
		(width 0.14224)
		(layer "In13.Cu")
		(net "P5E_CPU1_P3_RX_BUF_DP<0>")
	)
	(segment
		(start 114.316002 -402.480526)
		(end 114.45748 -401.914868)
		(width 0.14224)
		(layer "In13.Cu")
		(net "P5E_CPU1_P3_RX_BUF_DP<0>")
	)
	(segment
		(start 113.929922 -405.172164)
		(end 113.929922 -404.057612)
		(width 0.14224)
		(layer "In13.Cu")
		(net "P5E_CPU1_P3_RX_BUF_DP<0>")
	)
	(segment
		(start 116.998496 -412.030672)
		(end 116.998242 -412.030418)
		(width 0.14224)
		(layer "In13.Cu")
		(net "P5E_CPU1_P3_RX_BUF_DP<0>")
	)
	(segment
		(start 124.888752 -433.577238)
		(end 124.888752 -417.529518)
		(width 0.14224)
		(layer "In13.Cu")
		(net "P5E_CPU1_P3_RX_BUF_DP<0>")
	)
	(segment
		(start 114.45748 -400.13128)
		(end 114.59464 -399.99412)
		(width 0.14224)
		(layer "In13.Cu")
		(net "P5E_CPU1_P3_RX_BUF_DP<0>")
	)
	(segment
		(start 116.74602 -411.355032)
		(end 115.640866 -410.89707)
		(width 0.14224)
		(layer "In13.Cu")
		(net "P5E_CPU1_P3_RX_BUF_DP<0>")
	)
	(arc
		(start 117.405404 -413.984694)
		(mid 117.332866 -413.942027)
		(end 117.274848 -413.881062)
		(width 0.14224)
		(layer "In13.Cu")
		(net "P5E_CPU1_P3_RX_BUF_DP<0>")
	)
	(arc
		(start 117.274848 -413.881062)
		(mid 117.236913 -413.827748)
		(end 117.19941 -413.774128)
		(width 0.14224)
		(layer "In13.Cu")
		(net "P5E_CPU1_P3_RX_BUF_DP<0>")
	)
	(arc
		(start 125.073664 -433.756816)
		(mid 125.020062 -433.74606)
		(end 124.974604 -433.715668)
		(width 0.14224)
		(layer "In13.Cu")
		(net "P5E_CPU1_P3_RX_BUF_DP<0>")
	)
	(arc
		(start 117.008148 -413.3469)
		(mid 117.000903 -413.322993)
		(end 116.998496 -413.298132)
		(width 0.14224)
		(layer "In13.Cu")
		(net "P5E_CPU1_P3_RX_BUF_DP<0>")
	)
	(arc
		(start 115.640866 -410.89707)
		(mid 115.599674 -410.869594)
		(end 115.572032 -410.82849)
		(width 0.14224)
		(layer "In13.Cu")
		(net "P5E_CPU1_P3_RX_BUF_DP<0>")
	)
	(arc
		(start 116.998242 -411.733238)
		(mid 116.929481 -411.505871)
		(end 116.74602 -411.355032)
		(width 0.14224)
		(layer "In13.Cu")
		(net "P5E_CPU1_P3_RX_BUF_DP<0>")
	)
	(arc
		(start 124.592334 -417.063428)
		(mid 124.405241 -416.909839)
		(end 124.191776 -416.795712)
		(width 0.14224)
		(layer "In13.Cu")
		(net "P5E_CPU1_P3_RX_BUF_DP<0>")
	)
	(arc
		(start 124.888752 -417.529518)
		(mid 124.8576 -417.372815)
		(end 124.768864 -417.239958)
		(width 0.14224)
		(layer "In13.Cu")
		(net "P5E_CPU1_P3_RX_BUF_DP<0>")
	)
	(arc
		(start 117.19941 -413.774128)
		(mid 117.166239 -413.719972)
		(end 117.138958 -413.662622)
		(width 0.14224)
		(layer "In13.Cu")
		(net "P5E_CPU1_P3_RX_BUF_DP<0>")
	)
	(arc
		(start 124.92609 -433.667154)
		(mid 124.898471 -433.625914)
		(end 124.888752 -433.577238)
		(width 0.14224)
		(layer "In13.Cu")
		(net "P5E_CPU1_P3_RX_BUF_DP<0>")
	)
	(segment
		(start 125.31852 -390.761982)
		(end 125.31852 -391.578338)
		(width 0.1016)
		(layer "F.Cu")
		(net "P5E_CPU1_P3_RX_BUF_DN<9>")
	)
	(segment
		(start 125.2474 -392.634216)
		(end 125.3744 -392.761216)
		(width 0.1016)
		(layer "F.Cu")
		(net "P5E_CPU1_P3_RX_BUF_DN<9>")
	)
	(segment
		(start 125.716538 -392.6205)
		(end 125.716538 -392.429238)
		(width 0.1016)
		(layer "F.Cu")
		(net "P5E_CPU1_P3_RX_BUF_DN<9>")
	)
	(segment
		(start 125.2474 -391.649458)
		(end 125.2474 -392.634216)
		(width 0.1016)
		(layer "F.Cu")
		(net "P5E_CPU1_P3_RX_BUF_DN<9>")
	)
	(segment
		(start 125.31852 -391.578338)
		(end 125.2474 -391.649458)
		(width 0.1016)
		(layer "F.Cu")
		(net "P5E_CPU1_P3_RX_BUF_DN<9>")
	)
	(segment
		(start 125.3744 -392.761216)
		(end 125.575822 -392.761216)
		(width 0.1016)
		(layer "F.Cu")
		(net "P5E_CPU1_P3_RX_BUF_DN<9>")
	)
	(segment
		(start 125.318012 -390.761474)
		(end 125.31852 -390.761982)
		(width 0.1016)
		(layer "F.Cu")
		(net "P5E_CPU1_P3_RX_BUF_DN<9>")
	)
	(segment
		(start 125.575822 -392.761216)
		(end 125.716538 -392.6205)
		(width 0.1016)
		(layer "F.Cu")
		(net "P5E_CPU1_P3_RX_BUF_DN<9>")
	)
	(segment
		(start 126.57074 -397.993108)
		(end 126.570486 -397.993108)
		(width 0.14224)
		(layer "In13.Cu")
		(net "P5E_CPU1_P3_RX_BUF_DN<9>")
	)
	(segment
		(start 142.96009 -411.130496)
		(end 142.754096 -410.82214)
		(width 0.14224)
		(layer "In13.Cu")
		(net "P5E_CPU1_P3_RX_BUF_DN<9>")
	)
	(segment
		(start 143.898112 -421.334692)
		(end 143.979138 -419.632638)
		(width 0.14224)
		(layer "In13.Cu")
		(net "P5E_CPU1_P3_RX_BUF_DN<9>")
	)
	(segment
		(start 144.750028 -435.489858)
		(end 144.750028 -435.165754)
		(width 0.14224)
		(layer "In13.Cu")
		(net "P5E_CPU1_P3_RX_BUF_DN<9>")
	)
	(segment
		(start 143.79448 -434.57495)
		(end 143.79448 -422.387776)
		(width 0.14224)
		(layer "In13.Cu")
		(net "P5E_CPU1_P3_RX_BUF_DN<9>")
	)
	(segment
		(start 144.623028 -435.038754)
		(end 144.258284 -435.038754)
		(width 0.14224)
		(layer "In13.Cu")
		(net "P5E_CPU1_P3_RX_BUF_DN<9>")
	)
	(segment
		(start 143.979392 -419.632638)
		(end 144.285716 -413.213296)
		(width 0.14224)
		(layer "In13.Cu")
		(net "P5E_CPU1_P3_RX_BUF_DN<9>")
	)
	(segment
		(start 142.591536 -406.088596)
		(end 142.409418 -405.906478)
		(width 0.14224)
		(layer "In13.Cu")
		(net "P5E_CPU1_P3_RX_BUF_DN<9>")
	)
	(segment
		(start 143.79448 -422.387776)
		(end 143.898112 -421.334692)
		(width 0.14224)
		(layer "In13.Cu")
		(net "P5E_CPU1_P3_RX_BUF_DN<9>")
	)
	(segment
		(start 142.754096 -410.82214)
		(end 142.754096 -406.481026)
		(width 0.14224)
		(layer "In13.Cu")
		(net "P5E_CPU1_P3_RX_BUF_DN<9>")
	)
	(segment
		(start 141.601952 -405.78405)
		(end 141.338046 -405.520144)
		(width 0.14224)
		(layer "In13.Cu")
		(net "P5E_CPU1_P3_RX_BUF_DN<9>")
	)
	(segment
		(start 127.407924 -398.830292)
		(end 126.57074 -397.993108)
		(width 0.14224)
		(layer "In13.Cu")
		(net "P5E_CPU1_P3_RX_BUF_DN<9>")
	)
	(segment
		(start 126.570486 -397.993108)
		(end 125.095508 -396.517876)
		(width 0.14224)
		(layer "In13.Cu")
		(net "P5E_CPU1_P3_RX_BUF_DN<9>")
	)
	(segment
		(start 144.750028 -435.165754)
		(end 144.623028 -435.038754)
		(width 0.14224)
		(layer "In13.Cu")
		(net "P5E_CPU1_P3_RX_BUF_DN<9>")
	)
	(segment
		(start 144.258284 -435.038754)
		(end 143.79448 -434.57495)
		(width 0.14224)
		(layer "In13.Cu")
		(net "P5E_CPU1_P3_RX_BUF_DN<9>")
	)
	(segment
		(start 143.979138 -419.632638)
		(end 143.979392 -419.632638)
		(width 0.14224)
		(layer "In13.Cu")
		(net "P5E_CPU1_P3_RX_BUF_DN<9>")
	)
	(segment
		(start 140.586714 -403.072092)
		(end 128.230122 -399.323306)
		(width 0.14224)
		(layer "In13.Cu")
		(net "P5E_CPU1_P3_RX_BUF_DN<9>")
	)
	(segment
		(start 144.077944 -411.593792)
		(end 142.96009 -411.130496)
		(width 0.14224)
		(layer "In13.Cu")
		(net "P5E_CPU1_P3_RX_BUF_DN<9>")
	)
	(segment
		(start 141.049502 -403.263862)
		(end 140.586714 -403.072092)
		(width 0.14224)
		(layer "In13.Cu")
		(net "P5E_CPU1_P3_RX_BUF_DN<9>")
	)
	(segment
		(start 125.567694 -392.729466)
		(end 125.716538 -392.580622)
		(width 0.14224)
		(layer "In13.Cu")
		(net "P5E_CPU1_P3_RX_BUF_DN<9>")
	)
	(segment
		(start 124.97562 -393.021566)
		(end 125.26772 -392.729466)
		(width 0.14224)
		(layer "In13.Cu")
		(net "P5E_CPU1_P3_RX_BUF_DN<9>")
	)
	(segment
		(start 144.285716 -413.213296)
		(end 144.285716 -411.855666)
		(width 0.14224)
		(layer "In13.Cu")
		(net "P5E_CPU1_P3_RX_BUF_DN<9>")
	)
	(segment
		(start 142.409418 -405.906478)
		(end 142.289276 -405.856694)
		(width 0.14224)
		(layer "In13.Cu")
		(net "P5E_CPU1_P3_RX_BUF_DN<9>")
	)
	(segment
		(start 141.222476 -405.240998)
		(end 141.222476 -403.52218)
		(width 0.14224)
		(layer "In13.Cu")
		(net "P5E_CPU1_P3_RX_BUF_DN<9>")
	)
	(segment
		(start 125.716538 -392.580622)
		(end 125.716538 -392.429238)
		(width 0.14224)
		(layer "In13.Cu")
		(net "P5E_CPU1_P3_RX_BUF_DN<9>")
	)
	(segment
		(start 124.97562 -396.228316)
		(end 124.97562 -393.021566)
		(width 0.14224)
		(layer "In13.Cu")
		(net "P5E_CPU1_P3_RX_BUF_DN<9>")
	)
	(segment
		(start 141.776958 -405.856694)
		(end 141.601952 -405.78405)
		(width 0.14224)
		(layer "In13.Cu")
		(net "P5E_CPU1_P3_RX_BUF_DN<9>")
	)
	(segment
		(start 141.338046 -405.520144)
		(end 141.222476 -405.240998)
		(width 0.14224)
		(layer "In13.Cu")
		(net "P5E_CPU1_P3_RX_BUF_DN<9>")
	)
	(segment
		(start 142.289276 -405.856694)
		(end 141.776958 -405.856694)
		(width 0.14224)
		(layer "In13.Cu")
		(net "P5E_CPU1_P3_RX_BUF_DN<9>")
	)
	(segment
		(start 144.285716 -411.855666)
		(end 144.25041 -411.77083)
		(width 0.14224)
		(layer "In13.Cu")
		(net "P5E_CPU1_P3_RX_BUF_DN<9>")
	)
	(segment
		(start 142.754096 -406.481026)
		(end 142.591536 -406.088596)
		(width 0.14224)
		(layer "In13.Cu")
		(net "P5E_CPU1_P3_RX_BUF_DN<9>")
	)
	(segment
		(start 141.222476 -403.52218)
		(end 141.049502 -403.263862)
		(width 0.14224)
		(layer "In13.Cu")
		(net "P5E_CPU1_P3_RX_BUF_DN<9>")
	)
	(segment
		(start 125.26772 -392.729466)
		(end 125.567694 -392.729466)
		(width 0.14224)
		(layer "In13.Cu")
		(net "P5E_CPU1_P3_RX_BUF_DN<9>")
	)
	(segment
		(start 144.21358 -411.715712)
		(end 144.119346 -411.621478)
		(width 0.14224)
		(layer "In13.Cu")
		(net "P5E_CPU1_P3_RX_BUF_DN<9>")
	)
	(arc
		(start 125.095508 -396.517876)
		(mid 125.006793 -396.385011)
		(end 124.97562 -396.228316)
		(width 0.14224)
		(layer "In13.Cu")
		(net "P5E_CPU1_P3_RX_BUF_DN<9>")
	)
	(arc
		(start 144.119346 -411.621478)
		(mid 144.100021 -411.605572)
		(end 144.077944 -411.593792)
		(width 0.14224)
		(layer "In13.Cu")
		(net "P5E_CPU1_P3_RX_BUF_DN<9>")
	)
	(arc
		(start 144.25041 -411.77083)
		(mid 144.234679 -411.741479)
		(end 144.21358 -411.715712)
		(width 0.14224)
		(layer "In13.Cu")
		(net "P5E_CPU1_P3_RX_BUF_DN<9>")
	)
	(arc
		(start 128.230122 -399.323306)
		(mid 127.788638 -399.127477)
		(end 127.407924 -398.830292)
		(width 0.14224)
		(layer "In13.Cu")
		(net "P5E_CPU1_P3_RX_BUF_DN<9>")
	)
	(segment
		(start 124.516642 -392.429238)
		(end 124.516642 -392.620246)
		(width 0.1016)
		(layer "F.Cu")
		(net "P5E_CPU1_P3_RX_BUF_DN<8>")
	)
	(segment
		(start 124.029724 -391.666984)
		(end 124.11837 -391.578338)
		(width 0.1016)
		(layer "F.Cu")
		(net "P5E_CPU1_P3_RX_BUF_DN<8>")
	)
	(segment
		(start 124.516642 -392.620246)
		(end 124.375672 -392.761216)
		(width 0.1016)
		(layer "F.Cu")
		(net "P5E_CPU1_P3_RX_BUF_DN<8>")
	)
	(segment
		(start 124.375672 -392.761216)
		(end 124.156724 -392.761216)
		(width 0.1016)
		(layer "F.Cu")
		(net "P5E_CPU1_P3_RX_BUF_DN<8>")
	)
	(segment
		(start 124.11837 -390.761982)
		(end 124.117862 -390.761474)
		(width 0.1016)
		(layer "F.Cu")
		(net "P5E_CPU1_P3_RX_BUF_DN<8>")
	)
	(segment
		(start 124.11837 -391.578338)
		(end 124.11837 -390.761982)
		(width 0.1016)
		(layer "F.Cu")
		(net "P5E_CPU1_P3_RX_BUF_DN<8>")
	)
	(segment
		(start 124.156724 -392.761216)
		(end 124.029724 -392.634216)
		(width 0.1016)
		(layer "F.Cu")
		(net "P5E_CPU1_P3_RX_BUF_DN<8>")
	)
	(segment
		(start 124.029724 -392.634216)
		(end 124.029724 -391.666984)
		(width 0.1016)
		(layer "F.Cu")
		(net "P5E_CPU1_P3_RX_BUF_DN<8>")
	)
	(segment
		(start 139.828778 -410.963618)
		(end 140.011658 -411.146498)
		(width 0.14224)
		(layer "In13.Cu")
		(net "P5E_CPU1_P3_RX_BUF_DN<8>")
	)
	(segment
		(start 123.895612 -396.963392)
		(end 126.16815 -399.23593)
		(width 0.14224)
		(layer "In13.Cu")
		(net "P5E_CPU1_P3_RX_BUF_DN<8>")
	)
	(segment
		(start 141.07795 -411.654498)
		(end 141.077696 -411.654498)
		(width 0.14224)
		(layer "In13.Cu")
		(net "P5E_CPU1_P3_RX_BUF_DN<8>")
	)
	(segment
		(start 139.29487 -405.885142)
		(end 139.549378 -406.13965)
		(width 0.14224)
		(layer "In13.Cu")
		(net "P5E_CPU1_P3_RX_BUF_DN<8>")
	)
	(segment
		(start 141.077696 -411.654498)
		(end 141.222476 -412.003748)
		(width 0.14224)
		(layer "In13.Cu")
		(net "P5E_CPU1_P3_RX_BUF_DN<8>")
	)
	(segment
		(start 138.713718 -405.856694)
		(end 139.22629 -405.856694)
		(width 0.14224)
		(layer "In13.Cu")
		(net "P5E_CPU1_P3_RX_BUF_DN<8>")
	)
	(segment
		(start 126.719076 -399.786602)
		(end 126.955296 -399.92808)
		(width 0.14224)
		(layer "In13.Cu")
		(net "P5E_CPU1_P3_RX_BUF_DN<8>")
	)
	(segment
		(start 139.690856 -410.630878)
		(end 139.828778 -410.963618)
		(width 0.14224)
		(layer "In13.Cu")
		(net "P5E_CPU1_P3_RX_BUF_DN<8>")
	)
	(segment
		(start 138.159236 -403.51583)
		(end 138.159236 -405.241252)
		(width 0.14224)
		(layer "In13.Cu")
		(net "P5E_CPU1_P3_RX_BUF_DN<8>")
	)
	(segment
		(start 139.690856 -406.481026)
		(end 139.690856 -410.630878)
		(width 0.14224)
		(layer "In13.Cu")
		(net "P5E_CPU1_P3_RX_BUF_DN<8>")
	)
	(segment
		(start 141.794484 -421.172386)
		(end 141.794484 -433.574952)
		(width 0.14224)
		(layer "In13.Cu")
		(net "P5E_CPU1_P3_RX_BUF_DN<8>")
	)
	(segment
		(start 126.16815 -399.23593)
		(end 126.168404 -399.23593)
		(width 0.14224)
		(layer "In13.Cu")
		(net "P5E_CPU1_P3_RX_BUF_DN<8>")
	)
	(segment
		(start 137.888472 -403.245066)
		(end 138.159236 -403.51583)
		(width 0.14224)
		(layer "In13.Cu")
		(net "P5E_CPU1_P3_RX_BUF_DN<8>")
	)
	(segment
		(start 139.22629 -405.856694)
		(end 139.29487 -405.885142)
		(width 0.14224)
		(layer "In13.Cu")
		(net "P5E_CPU1_P3_RX_BUF_DN<8>")
	)
	(segment
		(start 126.168404 -399.23593)
		(end 126.719076 -399.786602)
		(width 0.14224)
		(layer "In13.Cu")
		(net "P5E_CPU1_P3_RX_BUF_DN<8>")
	)
	(segment
		(start 141.019022 -411.59557)
		(end 141.07795 -411.654498)
		(width 0.14224)
		(layer "In13.Cu")
		(net "P5E_CPU1_P3_RX_BUF_DN<8>")
	)
	(segment
		(start 140.011658 -411.146498)
		(end 140.13688 -411.230318)
		(width 0.14224)
		(layer "In13.Cu")
		(net "P5E_CPU1_P3_RX_BUF_DN<8>")
	)
	(segment
		(start 141.586712 -416.944556)
		(end 141.794484 -421.172386)
		(width 0.14224)
		(layer "In13.Cu")
		(net "P5E_CPU1_P3_RX_BUF_DN<8>")
	)
	(segment
		(start 141.222476 -412.003748)
		(end 141.222476 -413.2453)
		(width 0.14224)
		(layer "In13.Cu")
		(net "P5E_CPU1_P3_RX_BUF_DN<8>")
	)
	(segment
		(start 124.08027 -392.707622)
		(end 123.775724 -393.012168)
		(width 0.14224)
		(layer "In13.Cu")
		(net "P5E_CPU1_P3_RX_BUF_DN<8>")
	)
	(segment
		(start 142.623032 -434.038756)
		(end 142.750032 -434.165756)
		(width 0.14224)
		(layer "In13.Cu")
		(net "P5E_CPU1_P3_RX_BUF_DN<8>")
	)
	(segment
		(start 141.222476 -413.2453)
		(end 141.586712 -416.944556)
		(width 0.14224)
		(layer "In13.Cu")
		(net "P5E_CPU1_P3_RX_BUF_DN<8>")
	)
	(segment
		(start 139.549378 -406.13965)
		(end 139.690856 -406.481026)
		(width 0.14224)
		(layer "In13.Cu")
		(net "P5E_CPU1_P3_RX_BUF_DN<8>")
	)
	(segment
		(start 138.538712 -405.78405)
		(end 138.713718 -405.856694)
		(width 0.14224)
		(layer "In13.Cu")
		(net "P5E_CPU1_P3_RX_BUF_DN<8>")
	)
	(segment
		(start 142.750032 -434.165756)
		(end 142.750032 -434.48986)
		(width 0.14224)
		(layer "In13.Cu")
		(net "P5E_CPU1_P3_RX_BUF_DN<8>")
	)
	(segment
		(start 126.955296 -399.92808)
		(end 137.888472 -403.245066)
		(width 0.14224)
		(layer "In13.Cu")
		(net "P5E_CPU1_P3_RX_BUF_DN<8>")
	)
	(segment
		(start 124.516642 -392.580622)
		(end 124.389642 -392.707622)
		(width 0.14224)
		(layer "In13.Cu")
		(net "P5E_CPU1_P3_RX_BUF_DN<8>")
	)
	(segment
		(start 138.159236 -405.241252)
		(end 138.274806 -405.520144)
		(width 0.14224)
		(layer "In13.Cu")
		(net "P5E_CPU1_P3_RX_BUF_DN<8>")
	)
	(segment
		(start 124.516642 -392.429238)
		(end 124.516642 -392.580622)
		(width 0.14224)
		(layer "In13.Cu")
		(net "P5E_CPU1_P3_RX_BUF_DN<8>")
	)
	(segment
		(start 124.389642 -392.707622)
		(end 124.08027 -392.707622)
		(width 0.14224)
		(layer "In13.Cu")
		(net "P5E_CPU1_P3_RX_BUF_DN<8>")
	)
	(segment
		(start 140.13688 -411.230318)
		(end 141.019022 -411.59557)
		(width 0.14224)
		(layer "In13.Cu")
		(net "P5E_CPU1_P3_RX_BUF_DN<8>")
	)
	(segment
		(start 141.794484 -433.574952)
		(end 142.258288 -434.038756)
		(width 0.14224)
		(layer "In13.Cu")
		(net "P5E_CPU1_P3_RX_BUF_DN<8>")
	)
	(segment
		(start 123.775724 -393.012168)
		(end 123.775724 -396.673832)
		(width 0.14224)
		(layer "In13.Cu")
		(net "P5E_CPU1_P3_RX_BUF_DN<8>")
	)
	(segment
		(start 138.274806 -405.520144)
		(end 138.538712 -405.78405)
		(width 0.14224)
		(layer "In13.Cu")
		(net "P5E_CPU1_P3_RX_BUF_DN<8>")
	)
	(segment
		(start 142.258288 -434.038756)
		(end 142.623032 -434.038756)
		(width 0.14224)
		(layer "In13.Cu")
		(net "P5E_CPU1_P3_RX_BUF_DN<8>")
	)
	(arc
		(start 123.775724 -396.673832)
		(mid 123.806876 -396.830535)
		(end 123.895612 -396.963392)
		(width 0.14224)
		(layer "In13.Cu")
		(net "P5E_CPU1_P3_RX_BUF_DN<8>")
	)
	(segment
		(start 122.917966 -390.761474)
		(end 122.918474 -390.761982)
		(width 0.1016)
		(layer "F.Cu")
		(net "P5E_CPU1_P3_RX_BUF_DN<7>")
	)
	(segment
		(start 122.956828 -392.761216)
		(end 123.175776 -392.761216)
		(width 0.1016)
		(layer "F.Cu")
		(net "P5E_CPU1_P3_RX_BUF_DN<7>")
	)
	(segment
		(start 122.918474 -390.761982)
		(end 122.918474 -391.578338)
		(width 0.1016)
		(layer "F.Cu")
		(net "P5E_CPU1_P3_RX_BUF_DN<7>")
	)
	(segment
		(start 122.829828 -391.666984)
		(end 122.829828 -392.634216)
		(width 0.1016)
		(layer "F.Cu")
		(net "P5E_CPU1_P3_RX_BUF_DN<7>")
	)
	(segment
		(start 122.918474 -391.578338)
		(end 122.829828 -391.666984)
		(width 0.1016)
		(layer "F.Cu")
		(net "P5E_CPU1_P3_RX_BUF_DN<7>")
	)
	(segment
		(start 123.175776 -392.761216)
		(end 123.316492 -392.6205)
		(width 0.1016)
		(layer "F.Cu")
		(net "P5E_CPU1_P3_RX_BUF_DN<7>")
	)
	(segment
		(start 122.829828 -392.634216)
		(end 122.956828 -392.761216)
		(width 0.1016)
		(layer "F.Cu")
		(net "P5E_CPU1_P3_RX_BUF_DN<7>")
	)
	(segment
		(start 123.316492 -392.6205)
		(end 123.316492 -392.429238)
		(width 0.1016)
		(layer "F.Cu")
		(net "P5E_CPU1_P3_RX_BUF_DN<7>")
	)
	(segment
		(start 137.910316 -411.608016)
		(end 137.160508 -411.297882)
		(width 0.14224)
		(layer "In13.Cu")
		(net "P5E_CPU1_P3_RX_BUF_DN<7>")
	)
	(segment
		(start 135.095996 -405.12111)
		(end 135.095996 -403.74189)
		(width 0.14224)
		(layer "In13.Cu")
		(net "P5E_CPU1_P3_RX_BUF_DN<7>")
	)
	(segment
		(start 138.13663 -412.003494)
		(end 138.0363 -411.73781)
		(width 0.14224)
		(layer "In13.Cu")
		(net "P5E_CPU1_P3_RX_BUF_DN<7>")
	)
	(segment
		(start 136.23163 -405.885142)
		(end 136.16305 -405.856694)
		(width 0.14224)
		(layer "In13.Cu")
		(net "P5E_CPU1_P3_RX_BUF_DN<7>")
	)
	(segment
		(start 125.743462 -400.37131)
		(end 122.695462 -397.32331)
		(width 0.14224)
		(layer "In13.Cu")
		(net "P5E_CPU1_P3_RX_BUF_DN<7>")
	)
	(segment
		(start 136.627616 -406.481026)
		(end 136.486138 -406.13965)
		(width 0.14224)
		(layer "In13.Cu")
		(net "P5E_CPU1_P3_RX_BUF_DN<7>")
	)
	(segment
		(start 136.627616 -410.452062)
		(end 136.627616 -406.481026)
		(width 0.14224)
		(layer "In13.Cu")
		(net "P5E_CPU1_P3_RX_BUF_DN<7>")
	)
	(segment
		(start 132.848096 -402.83765)
		(end 131.595114 -402.319236)
		(width 0.14224)
		(layer "In13.Cu")
		(net "P5E_CPU1_P3_RX_BUF_DN<7>")
	)
	(segment
		(start 138.794236 -417.764468)
		(end 138.159236 -413.16021)
		(width 0.14224)
		(layer "In13.Cu")
		(net "P5E_CPU1_P3_RX_BUF_DN<7>")
	)
	(segment
		(start 139.622784 -435.038754)
		(end 139.25804 -435.038754)
		(width 0.14224)
		(layer "In13.Cu")
		(net "P5E_CPU1_P3_RX_BUF_DN<7>")
	)
	(segment
		(start 138.159236 -413.16021)
		(end 138.159236 -412.127446)
		(width 0.14224)
		(layer "In13.Cu")
		(net "P5E_CPU1_P3_RX_BUF_DN<7>")
	)
	(segment
		(start 132.847842 -402.83765)
		(end 132.848096 -402.83765)
		(width 0.14224)
		(layer "In13.Cu")
		(net "P5E_CPU1_P3_RX_BUF_DN<7>")
	)
	(segment
		(start 122.575574 -397.03375)
		(end 122.575574 -393.012168)
		(width 0.14224)
		(layer "In13.Cu")
		(net "P5E_CPU1_P3_RX_BUF_DN<7>")
	)
	(segment
		(start 136.486138 -406.13965)
		(end 136.23163 -405.885142)
		(width 0.14224)
		(layer "In13.Cu")
		(net "P5E_CPU1_P3_RX_BUF_DN<7>")
	)
	(segment
		(start 123.189492 -392.707622)
		(end 123.316492 -392.580622)
		(width 0.14224)
		(layer "In13.Cu")
		(net "P5E_CPU1_P3_RX_BUF_DN<7>")
	)
	(segment
		(start 134.422388 -403.290278)
		(end 134.023354 -403.290278)
		(width 0.14224)
		(layer "In13.Cu")
		(net "P5E_CPU1_P3_RX_BUF_DN<7>")
	)
	(segment
		(start 135.430006 -405.738584)
		(end 135.296402 -405.60498)
		(width 0.14224)
		(layer "In13.Cu")
		(net "P5E_CPU1_P3_RX_BUF_DN<7>")
	)
	(segment
		(start 133.86689 -403.25929)
		(end 132.847842 -402.83765)
		(width 0.14224)
		(layer "In13.Cu")
		(net "P5E_CPU1_P3_RX_BUF_DN<7>")
	)
	(segment
		(start 122.88012 -392.707622)
		(end 123.189492 -392.707622)
		(width 0.14224)
		(layer "In13.Cu")
		(net "P5E_CPU1_P3_RX_BUF_DN<7>")
	)
	(segment
		(start 122.575574 -393.012168)
		(end 122.88012 -392.707622)
		(width 0.14224)
		(layer "In13.Cu")
		(net "P5E_CPU1_P3_RX_BUF_DN<7>")
	)
	(segment
		(start 123.316492 -392.580622)
		(end 123.316492 -392.429238)
		(width 0.14224)
		(layer "In13.Cu")
		(net "P5E_CPU1_P3_RX_BUF_DN<7>")
	)
	(segment
		(start 136.94664 -411.136084)
		(end 136.77138 -410.913326)
		(width 0.14224)
		(layer "In13.Cu")
		(net "P5E_CPU1_P3_RX_BUF_DN<7>")
	)
	(segment
		(start 139.749784 -435.489858)
		(end 139.749784 -435.165754)
		(width 0.14224)
		(layer "In13.Cu")
		(net "P5E_CPU1_P3_RX_BUF_DN<7>")
	)
	(segment
		(start 138.794236 -434.57495)
		(end 138.794236 -417.764468)
		(width 0.14224)
		(layer "In13.Cu")
		(net "P5E_CPU1_P3_RX_BUF_DN<7>")
	)
	(segment
		(start 139.25804 -435.038754)
		(end 138.794236 -434.57495)
		(width 0.14224)
		(layer "In13.Cu")
		(net "P5E_CPU1_P3_RX_BUF_DN<7>")
	)
	(segment
		(start 139.749784 -435.165754)
		(end 139.622784 -435.038754)
		(width 0.14224)
		(layer "In13.Cu")
		(net "P5E_CPU1_P3_RX_BUF_DN<7>")
	)
	(segment
		(start 134.911592 -403.465792)
		(end 134.547102 -403.314916)
		(width 0.14224)
		(layer "In13.Cu")
		(net "P5E_CPU1_P3_RX_BUF_DN<7>")
	)
	(segment
		(start 131.595114 -402.319236)
		(end 126.325884 -400.72056)
		(width 0.14224)
		(layer "In13.Cu")
		(net "P5E_CPU1_P3_RX_BUF_DN<7>")
	)
	(segment
		(start 136.16305 -405.856694)
		(end 135.71474 -405.856694)
		(width 0.14224)
		(layer "In13.Cu")
		(net "P5E_CPU1_P3_RX_BUF_DN<7>")
	)
	(arc
		(start 126.325884 -400.72056)
		(mid 126.01316 -400.581816)
		(end 125.743462 -400.37131)
		(width 0.14224)
		(layer "In13.Cu")
		(net "P5E_CPU1_P3_RX_BUF_DN<7>")
	)
	(arc
		(start 138.0363 -411.73781)
		(mid 137.986766 -411.659846)
		(end 137.910316 -411.608016)
		(width 0.14224)
		(layer "In13.Cu")
		(net "P5E_CPU1_P3_RX_BUF_DN<7>")
	)
	(arc
		(start 134.023354 -403.290278)
		(mid 133.943596 -403.282485)
		(end 133.86689 -403.25929)
		(width 0.14224)
		(layer "In13.Cu")
		(net "P5E_CPU1_P3_RX_BUF_DN<7>")
	)
	(arc
		(start 134.547102 -403.314916)
		(mid 134.486205 -403.296524)
		(end 134.422896 -403.290278)
		(width 0.14224)
		(layer "In13.Cu")
		(net "P5E_CPU1_P3_RX_BUF_DN<7>")
	)
	(arc
		(start 135.296402 -405.60498)
		(mid 135.148065 -405.382979)
		(end 135.095996 -405.12111)
		(width 0.14224)
		(layer "In13.Cu")
		(net "P5E_CPU1_P3_RX_BUF_DN<7>")
	)
	(arc
		(start 136.663938 -410.705808)
		(mid 136.636654 -410.58024)
		(end 136.627616 -410.452062)
		(width 0.14224)
		(layer "In13.Cu")
		(net "P5E_CPU1_P3_RX_BUF_DN<7>")
	)
	(arc
		(start 138.159236 -412.127446)
		(mid 138.153565 -412.064442)
		(end 138.13663 -412.003494)
		(width 0.14224)
		(layer "In13.Cu")
		(net "P5E_CPU1_P3_RX_BUF_DN<7>")
	)
	(arc
		(start 122.695462 -397.32331)
		(mid 122.606747 -397.190445)
		(end 122.575574 -397.03375)
		(width 0.14224)
		(layer "In13.Cu")
		(net "P5E_CPU1_P3_RX_BUF_DN<7>")
	)
	(arc
		(start 137.160508 -411.297882)
		(mid 137.043151 -411.230759)
		(end 136.94664 -411.136084)
		(width 0.14224)
		(layer "In13.Cu")
		(net "P5E_CPU1_P3_RX_BUF_DN<7>")
	)
	(arc
		(start 136.77138 -410.913326)
		(mid 136.707725 -410.814709)
		(end 136.663938 -410.705808)
		(width 0.14224)
		(layer "In13.Cu")
		(net "P5E_CPU1_P3_RX_BUF_DN<7>")
	)
	(arc
		(start 135.71474 -405.856694)
		(mid 135.560607 -405.825999)
		(end 135.430006 -405.738584)
		(width 0.14224)
		(layer "In13.Cu")
		(net "P5E_CPU1_P3_RX_BUF_DN<7>")
	)
	(arc
		(start 135.095996 -403.74189)
		(mid 135.04579 -403.575785)
		(end 134.911592 -403.465792)
		(width 0.14224)
		(layer "In13.Cu")
		(net "P5E_CPU1_P3_RX_BUF_DN<7>")
	)
	(arc
		(start 134.422896 -403.290278)
		(mid 134.422642 -403.290278)
		(end 134.422388 -403.290278)
		(width 0.14224)
		(layer "In13.Cu")
		(net "P5E_CPU1_P3_RX_BUF_DN<7>")
	)
	(segment
		(start 121.638568 -392.634216)
		(end 121.765568 -392.761216)
		(width 0.1016)
		(layer "F.Cu")
		(net "P5E_CPU1_P3_RX_BUF_DN<6>")
	)
	(segment
		(start 121.71807 -390.761474)
		(end 121.718578 -390.761982)
		(width 0.1016)
		(layer "F.Cu")
		(net "P5E_CPU1_P3_RX_BUF_DN<6>")
	)
	(segment
		(start 122.116596 -392.6205)
		(end 122.116596 -392.429238)
		(width 0.1016)
		(layer "F.Cu")
		(net "P5E_CPU1_P3_RX_BUF_DN<6>")
	)
	(segment
		(start 121.718324 -391.36574)
		(end 121.718324 -391.578338)
		(width 0.1016)
		(layer "F.Cu")
		(net "P5E_CPU1_P3_RX_BUF_DN<6>")
	)
	(segment
		(start 121.718324 -391.578338)
		(end 121.638568 -391.658094)
		(width 0.1016)
		(layer "F.Cu")
		(net "P5E_CPU1_P3_RX_BUF_DN<6>")
	)
	(segment
		(start 121.718578 -391.365486)
		(end 121.718324 -391.36574)
		(width 0.1016)
		(layer "F.Cu")
		(net "P5E_CPU1_P3_RX_BUF_DN<6>")
	)
	(segment
		(start 121.765568 -392.761216)
		(end 121.97588 -392.761216)
		(width 0.1016)
		(layer "F.Cu")
		(net "P5E_CPU1_P3_RX_BUF_DN<6>")
	)
	(segment
		(start 121.638568 -391.658094)
		(end 121.638568 -392.634216)
		(width 0.1016)
		(layer "F.Cu")
		(net "P5E_CPU1_P3_RX_BUF_DN<6>")
	)
	(segment
		(start 121.718578 -390.761982)
		(end 121.718578 -391.365486)
		(width 0.1016)
		(layer "F.Cu")
		(net "P5E_CPU1_P3_RX_BUF_DN<6>")
	)
	(segment
		(start 121.97588 -392.761216)
		(end 122.116596 -392.6205)
		(width 0.1016)
		(layer "F.Cu")
		(net "P5E_CPU1_P3_RX_BUF_DN<6>")
	)
	(segment
		(start 125.023372 -401.242784)
		(end 124.645928 -400.86534)
		(width 0.14224)
		(layer "In13.Cu")
		(net "P5E_CPU1_P3_RX_BUF_DN<6>")
	)
	(segment
		(start 133.09981 -405.856694)
		(end 132.741162 -405.856694)
		(width 0.14224)
		(layer "In13.Cu")
		(net "P5E_CPU1_P3_RX_BUF_DN<6>")
	)
	(segment
		(start 135.850884 -415.294826)
		(end 135.156702 -413.618426)
		(width 0.14224)
		(layer "In13.Cu")
		(net "P5E_CPU1_P3_RX_BUF_DN<6>")
	)
	(segment
		(start 134.988554 -411.635702)
		(end 133.942836 -411.202124)
		(width 0.14224)
		(layer "In13.Cu")
		(net "P5E_CPU1_P3_RX_BUF_DN<6>")
	)
	(segment
		(start 135.095996 -411.743144)
		(end 134.988554 -411.635702)
		(width 0.14224)
		(layer "In13.Cu")
		(net "P5E_CPU1_P3_RX_BUF_DN<6>")
	)
	(segment
		(start 137.749788 -434.48986)
		(end 137.749788 -434.165756)
		(width 0.14224)
		(layer "In13.Cu")
		(net "P5E_CPU1_P3_RX_BUF_DN<6>")
	)
	(segment
		(start 133.422898 -406.13965)
		(end 133.16839 -405.885142)
		(width 0.14224)
		(layer "In13.Cu")
		(net "P5E_CPU1_P3_RX_BUF_DN<6>")
	)
	(segment
		(start 133.650482 -410.90977)
		(end 133.564376 -410.701998)
		(width 0.14224)
		(layer "In13.Cu")
		(net "P5E_CPU1_P3_RX_BUF_DN<6>")
	)
	(segment
		(start 122.116596 -392.580622)
		(end 122.116596 -392.429238)
		(width 0.14224)
		(layer "In13.Cu")
		(net "P5E_CPU1_P3_RX_BUF_DN<6>")
	)
	(segment
		(start 132.032756 -403.87651)
		(end 131.887214 -403.596094)
		(width 0.14224)
		(layer "In13.Cu")
		(net "P5E_CPU1_P3_RX_BUF_DN<6>")
	)
	(segment
		(start 132.442966 -405.732996)
		(end 132.090414 -405.380444)
		(width 0.14224)
		(layer "In13.Cu")
		(net "P5E_CPU1_P3_RX_BUF_DN<6>")
	)
	(segment
		(start 136.79424 -417.572444)
		(end 135.850884 -415.294826)
		(width 0.14224)
		(layer "In13.Cu")
		(net "P5E_CPU1_P3_RX_BUF_DN<6>")
	)
	(segment
		(start 135.095996 -413.31261)
		(end 135.095996 -411.743144)
		(width 0.14224)
		(layer "In13.Cu")
		(net "P5E_CPU1_P3_RX_BUF_DN<6>")
	)
	(segment
		(start 132.090414 -405.380444)
		(end 132.032756 -405.241252)
		(width 0.14224)
		(layer "In13.Cu")
		(net "P5E_CPU1_P3_RX_BUF_DN<6>")
	)
	(segment
		(start 132.032756 -405.241252)
		(end 132.032756 -403.87651)
		(width 0.14224)
		(layer "In13.Cu")
		(net "P5E_CPU1_P3_RX_BUF_DN<6>")
	)
	(segment
		(start 136.79424 -433.574952)
		(end 136.79424 -417.572444)
		(width 0.14224)
		(layer "In13.Cu")
		(net "P5E_CPU1_P3_RX_BUF_DN<6>")
	)
	(segment
		(start 133.564376 -410.701998)
		(end 133.564376 -406.481026)
		(width 0.14224)
		(layer "In13.Cu")
		(net "P5E_CPU1_P3_RX_BUF_DN<6>")
	)
	(segment
		(start 124.645928 -400.86534)
		(end 124.645674 -400.86534)
		(width 0.14224)
		(layer "In13.Cu")
		(net "P5E_CPU1_P3_RX_BUF_DN<6>")
	)
	(segment
		(start 133.825996 -411.123638)
		(end 133.650482 -410.90977)
		(width 0.14224)
		(layer "In13.Cu")
		(net "P5E_CPU1_P3_RX_BUF_DN<6>")
	)
	(segment
		(start 131.42722 -403.272244)
		(end 125.315218 -401.418044)
		(width 0.14224)
		(layer "In13.Cu")
		(net "P5E_CPU1_P3_RX_BUF_DN<6>")
	)
	(segment
		(start 121.375678 -393.012168)
		(end 121.680224 -392.707622)
		(width 0.14224)
		(layer "In13.Cu")
		(net "P5E_CPU1_P3_RX_BUF_DN<6>")
	)
	(segment
		(start 121.375678 -397.266922)
		(end 121.375678 -393.012168)
		(width 0.14224)
		(layer "In13.Cu")
		(net "P5E_CPU1_P3_RX_BUF_DN<6>")
	)
	(segment
		(start 137.749788 -434.165756)
		(end 137.622788 -434.038756)
		(width 0.14224)
		(layer "In13.Cu")
		(net "P5E_CPU1_P3_RX_BUF_DN<6>")
	)
	(segment
		(start 133.564376 -406.481026)
		(end 133.422898 -406.13965)
		(width 0.14224)
		(layer "In13.Cu")
		(net "P5E_CPU1_P3_RX_BUF_DN<6>")
	)
	(segment
		(start 137.258044 -434.038756)
		(end 136.79424 -433.574952)
		(width 0.14224)
		(layer "In13.Cu")
		(net "P5E_CPU1_P3_RX_BUF_DN<6>")
	)
	(segment
		(start 121.680224 -392.707622)
		(end 121.989596 -392.707622)
		(width 0.14224)
		(layer "In13.Cu")
		(net "P5E_CPU1_P3_RX_BUF_DN<6>")
	)
	(segment
		(start 124.645674 -400.86534)
		(end 121.607834 -397.827246)
		(width 0.14224)
		(layer "In13.Cu")
		(net "P5E_CPU1_P3_RX_BUF_DN<6>")
	)
	(segment
		(start 137.622788 -434.038756)
		(end 137.258044 -434.038756)
		(width 0.14224)
		(layer "In13.Cu")
		(net "P5E_CPU1_P3_RX_BUF_DN<6>")
	)
	(segment
		(start 121.989596 -392.707622)
		(end 122.116596 -392.580622)
		(width 0.14224)
		(layer "In13.Cu")
		(net "P5E_CPU1_P3_RX_BUF_DN<6>")
	)
	(segment
		(start 133.16839 -405.885142)
		(end 133.09981 -405.856694)
		(width 0.14224)
		(layer "In13.Cu")
		(net "P5E_CPU1_P3_RX_BUF_DN<6>")
	)
	(segment
		(start 133.942836 -411.202124)
		(end 133.825996 -411.123638)
		(width 0.14224)
		(layer "In13.Cu")
		(net "P5E_CPU1_P3_RX_BUF_DN<6>")
	)
	(segment
		(start 131.887214 -403.596094)
		(end 131.42722 -403.272244)
		(width 0.14224)
		(layer "In13.Cu")
		(net "P5E_CPU1_P3_RX_BUF_DN<6>")
	)
	(arc
		(start 125.315218 -401.418044)
		(mid 125.158469 -401.348432)
		(end 125.023372 -401.242784)
		(width 0.14224)
		(layer "In13.Cu")
		(net "P5E_CPU1_P3_RX_BUF_DN<6>")
	)
	(arc
		(start 121.607834 -397.827246)
		(mid 121.436006 -397.570181)
		(end 121.375678 -397.266922)
		(width 0.14224)
		(layer "In13.Cu")
		(net "P5E_CPU1_P3_RX_BUF_DN<6>")
	)
	(arc
		(start 135.156702 -413.618426)
		(mid 135.111264 -413.46851)
		(end 135.095996 -413.31261)
		(width 0.14224)
		(layer "In13.Cu")
		(net "P5E_CPU1_P3_RX_BUF_DN<6>")
	)
	(arc
		(start 132.741162 -405.856694)
		(mid 132.57975 -405.824511)
		(end 132.442966 -405.732996)
		(width 0.14224)
		(layer "In13.Cu")
		(net "P5E_CPU1_P3_RX_BUF_DN<6>")
	)
	(segment
		(start 120.556782 -392.761216)
		(end 120.77573 -392.761216)
		(width 0.1016)
		(layer "F.Cu")
		(net "P5E_CPU1_P3_RX_BUF_DN<5>")
	)
	(segment
		(start 120.77573 -392.761216)
		(end 120.916446 -392.6205)
		(width 0.1016)
		(layer "F.Cu")
		(net "P5E_CPU1_P3_RX_BUF_DN<5>")
	)
	(segment
		(start 120.429782 -392.634216)
		(end 120.556782 -392.761216)
		(width 0.1016)
		(layer "F.Cu")
		(net "P5E_CPU1_P3_RX_BUF_DN<5>")
	)
	(segment
		(start 120.518428 -391.578338)
		(end 120.429782 -391.666984)
		(width 0.1016)
		(layer "F.Cu")
		(net "P5E_CPU1_P3_RX_BUF_DN<5>")
	)
	(segment
		(start 120.51792 -390.761474)
		(end 120.518428 -390.761982)
		(width 0.1016)
		(layer "F.Cu")
		(net "P5E_CPU1_P3_RX_BUF_DN<5>")
	)
	(segment
		(start 120.916446 -392.6205)
		(end 120.916446 -392.429238)
		(width 0.1016)
		(layer "F.Cu")
		(net "P5E_CPU1_P3_RX_BUF_DN<5>")
	)
	(segment
		(start 120.429782 -391.666984)
		(end 120.429782 -392.634216)
		(width 0.1016)
		(layer "F.Cu")
		(net "P5E_CPU1_P3_RX_BUF_DN<5>")
	)
	(segment
		(start 120.518428 -390.761982)
		(end 120.518428 -391.578338)
		(width 0.1016)
		(layer "F.Cu")
		(net "P5E_CPU1_P3_RX_BUF_DN<5>")
	)
	(segment
		(start 130.639058 -410.963618)
		(end 130.501136 -410.630878)
		(width 0.14224)
		(layer "In13.Cu")
		(net "P5E_CPU1_P3_RX_BUF_DN<5>")
	)
	(segment
		(start 134.707122 -417.433252)
		(end 133.400292 -415.12617)
		(width 0.14224)
		(layer "In13.Cu")
		(net "P5E_CPU1_P3_RX_BUF_DN<5>")
	)
	(segment
		(start 131.77774 -411.574234)
		(end 130.94716 -411.230318)
		(width 0.14224)
		(layer "In13.Cu")
		(net "P5E_CPU1_P3_RX_BUF_DN<5>")
	)
	(segment
		(start 130.359658 -406.13965)
		(end 130.10515 -405.885142)
		(width 0.14224)
		(layer "In13.Cu")
		(net "P5E_CPU1_P3_RX_BUF_DN<5>")
	)
	(segment
		(start 135.749792 -435.489858)
		(end 135.749792 -435.165754)
		(width 0.14224)
		(layer "In13.Cu")
		(net "P5E_CPU1_P3_RX_BUF_DN<5>")
	)
	(segment
		(start 120.789446 -392.707622)
		(end 120.916446 -392.580622)
		(width 0.14224)
		(layer "In13.Cu")
		(net "P5E_CPU1_P3_RX_BUF_DN<5>")
	)
	(segment
		(start 129.027174 -405.380698)
		(end 128.969516 -405.241506)
		(width 0.14224)
		(layer "In13.Cu")
		(net "P5E_CPU1_P3_RX_BUF_DN<5>")
	)
	(segment
		(start 130.501136 -406.481026)
		(end 130.359658 -406.13965)
		(width 0.14224)
		(layer "In13.Cu")
		(net "P5E_CPU1_P3_RX_BUF_DN<5>")
	)
	(segment
		(start 120.175528 -393.012168)
		(end 120.480074 -392.707622)
		(width 0.14224)
		(layer "In13.Cu")
		(net "P5E_CPU1_P3_RX_BUF_DN<5>")
	)
	(segment
		(start 120.480074 -392.707622)
		(end 120.789446 -392.707622)
		(width 0.14224)
		(layer "In13.Cu")
		(net "P5E_CPU1_P3_RX_BUF_DN<5>")
	)
	(segment
		(start 132.032756 -413.413448)
		(end 132.032756 -412.003494)
		(width 0.14224)
		(layer "In13.Cu")
		(net "P5E_CPU1_P3_RX_BUF_DN<5>")
	)
	(segment
		(start 128.969516 -405.241506)
		(end 128.969516 -403.754844)
		(width 0.14224)
		(layer "In13.Cu")
		(net "P5E_CPU1_P3_RX_BUF_DN<5>")
	)
	(segment
		(start 128.88595 -403.630638)
		(end 128.447292 -403.366478)
		(width 0.14224)
		(layer "In13.Cu")
		(net "P5E_CPU1_P3_RX_BUF_DN<5>")
	)
	(segment
		(start 130.501136 -410.630878)
		(end 130.501136 -406.481026)
		(width 0.14224)
		(layer "In13.Cu")
		(net "P5E_CPU1_P3_RX_BUF_DN<5>")
	)
	(segment
		(start 135.622792 -435.038754)
		(end 135.258048 -435.038754)
		(width 0.14224)
		(layer "In13.Cu")
		(net "P5E_CPU1_P3_RX_BUF_DN<5>")
	)
	(segment
		(start 135.258048 -435.038754)
		(end 134.794244 -434.57495)
		(width 0.14224)
		(layer "In13.Cu")
		(net "P5E_CPU1_P3_RX_BUF_DN<5>")
	)
	(segment
		(start 129.360168 -405.713692)
		(end 129.027174 -405.380698)
		(width 0.14224)
		(layer "In13.Cu")
		(net "P5E_CPU1_P3_RX_BUF_DN<5>")
	)
	(segment
		(start 132.032756 -412.003494)
		(end 131.909566 -411.70606)
		(width 0.14224)
		(layer "In13.Cu")
		(net "P5E_CPU1_P3_RX_BUF_DN<5>")
	)
	(segment
		(start 130.10515 -405.885142)
		(end 130.03657 -405.856694)
		(width 0.14224)
		(layer "In13.Cu")
		(net "P5E_CPU1_P3_RX_BUF_DN<5>")
	)
	(segment
		(start 130.94716 -411.230318)
		(end 130.821938 -411.146498)
		(width 0.14224)
		(layer "In13.Cu")
		(net "P5E_CPU1_P3_RX_BUF_DN<5>")
	)
	(segment
		(start 120.916446 -392.580622)
		(end 120.916446 -392.429238)
		(width 0.14224)
		(layer "In13.Cu")
		(net "P5E_CPU1_P3_RX_BUF_DN<5>")
	)
	(segment
		(start 133.400292 -415.12617)
		(end 132.198872 -413.66186)
		(width 0.14224)
		(layer "In13.Cu")
		(net "P5E_CPU1_P3_RX_BUF_DN<5>")
	)
	(segment
		(start 123.835922 -401.749514)
		(end 120.295416 -398.209008)
		(width 0.14224)
		(layer "In13.Cu")
		(net "P5E_CPU1_P3_RX_BUF_DN<5>")
	)
	(segment
		(start 130.03657 -405.856694)
		(end 129.705608 -405.856694)
		(width 0.14224)
		(layer "In13.Cu")
		(net "P5E_CPU1_P3_RX_BUF_DN<5>")
	)
	(segment
		(start 128.969516 -403.754844)
		(end 128.88595 -403.630638)
		(width 0.14224)
		(layer "In13.Cu")
		(net "P5E_CPU1_P3_RX_BUF_DN<5>")
	)
	(segment
		(start 135.749792 -435.165754)
		(end 135.622792 -435.038754)
		(width 0.14224)
		(layer "In13.Cu")
		(net "P5E_CPU1_P3_RX_BUF_DN<5>")
	)
	(segment
		(start 134.794244 -434.57495)
		(end 134.794244 -417.763452)
		(width 0.14224)
		(layer "In13.Cu")
		(net "P5E_CPU1_P3_RX_BUF_DN<5>")
	)
	(segment
		(start 131.909566 -411.70606)
		(end 131.77774 -411.574234)
		(width 0.14224)
		(layer "In13.Cu")
		(net "P5E_CPU1_P3_RX_BUF_DN<5>")
	)
	(segment
		(start 130.821938 -411.146498)
		(end 130.639058 -410.963618)
		(width 0.14224)
		(layer "In13.Cu")
		(net "P5E_CPU1_P3_RX_BUF_DN<5>")
	)
	(segment
		(start 128.447292 -403.366478)
		(end 124.575316 -402.192744)
		(width 0.14224)
		(layer "In13.Cu")
		(net "P5E_CPU1_P3_RX_BUF_DN<5>")
	)
	(segment
		(start 132.198872 -413.66186)
		(end 132.032756 -413.413448)
		(width 0.14224)
		(layer "In13.Cu")
		(net "P5E_CPU1_P3_RX_BUF_DN<5>")
	)
	(segment
		(start 120.175528 -397.919448)
		(end 120.175528 -393.012168)
		(width 0.14224)
		(layer "In13.Cu")
		(net "P5E_CPU1_P3_RX_BUF_DN<5>")
	)
	(arc
		(start 120.295416 -398.209008)
		(mid 120.206701 -398.076143)
		(end 120.175528 -397.919448)
		(width 0.14224)
		(layer "In13.Cu")
		(net "P5E_CPU1_P3_RX_BUF_DN<5>")
	)
	(arc
		(start 134.794244 -417.763452)
		(mid 134.772059 -417.592714)
		(end 134.707122 -417.433252)
		(width 0.14224)
		(layer "In13.Cu")
		(net "P5E_CPU1_P3_RX_BUF_DN<5>")
	)
	(arc
		(start 129.705608 -405.856694)
		(mid 129.518675 -405.819529)
		(end 129.360168 -405.713692)
		(width 0.14224)
		(layer "In13.Cu")
		(net "P5E_CPU1_P3_RX_BUF_DN<5>")
	)
	(arc
		(start 124.575316 -402.192744)
		(mid 124.178278 -402.016742)
		(end 123.835922 -401.749514)
		(width 0.14224)
		(layer "In13.Cu")
		(net "P5E_CPU1_P3_RX_BUF_DN<5>")
	)
	(segment
		(start 119.318532 -391.578338)
		(end 119.229886 -391.666984)
		(width 0.1016)
		(layer "F.Cu")
		(net "P5E_CPU1_P3_RX_BUF_DN<4>")
	)
	(segment
		(start 119.356886 -392.761216)
		(end 119.575834 -392.761216)
		(width 0.1016)
		(layer "F.Cu")
		(net "P5E_CPU1_P3_RX_BUF_DN<4>")
	)
	(segment
		(start 119.575834 -392.761216)
		(end 119.71655 -392.6205)
		(width 0.1016)
		(layer "F.Cu")
		(net "P5E_CPU1_P3_RX_BUF_DN<4>")
	)
	(segment
		(start 119.229886 -392.634216)
		(end 119.356886 -392.761216)
		(width 0.1016)
		(layer "F.Cu")
		(net "P5E_CPU1_P3_RX_BUF_DN<4>")
	)
	(segment
		(start 119.318024 -390.761474)
		(end 119.318532 -390.761982)
		(width 0.1016)
		(layer "F.Cu")
		(net "P5E_CPU1_P3_RX_BUF_DN<4>")
	)
	(segment
		(start 119.229886 -391.666984)
		(end 119.229886 -392.634216)
		(width 0.1016)
		(layer "F.Cu")
		(net "P5E_CPU1_P3_RX_BUF_DN<4>")
	)
	(segment
		(start 119.71655 -392.6205)
		(end 119.71655 -392.429238)
		(width 0.1016)
		(layer "F.Cu")
		(net "P5E_CPU1_P3_RX_BUF_DN<4>")
	)
	(segment
		(start 119.318532 -390.761982)
		(end 119.318532 -391.578338)
		(width 0.1016)
		(layer "F.Cu")
		(net "P5E_CPU1_P3_RX_BUF_DN<4>")
	)
	(segment
		(start 125.353572 -403.409404)
		(end 123.617482 -403.06371)
		(width 0.14224)
		(layer "In13.Cu")
		(net "P5E_CPU1_P3_RX_BUF_DN<4>")
	)
	(segment
		(start 119.280178 -392.707622)
		(end 119.58955 -392.707622)
		(width 0.14224)
		(layer "In13.Cu")
		(net "P5E_CPU1_P3_RX_BUF_DN<4>")
	)
	(segment
		(start 133.622796 -434.038756)
		(end 133.258052 -434.038756)
		(width 0.14224)
		(layer "In13.Cu")
		(net "P5E_CPU1_P3_RX_BUF_DN<4>")
	)
	(segment
		(start 128.969516 -412.004256)
		(end 128.82499 -411.654752)
		(width 0.14224)
		(layer "In13.Cu")
		(net "P5E_CPU1_P3_RX_BUF_DN<4>")
	)
	(segment
		(start 126.93523 -405.856694)
		(end 126.460758 -405.856694)
		(width 0.14224)
		(layer "In13.Cu")
		(net "P5E_CPU1_P3_RX_BUF_DN<4>")
	)
	(segment
		(start 128.76657 -411.596078)
		(end 127.884174 -411.230318)
		(width 0.14224)
		(layer "In13.Cu")
		(net "P5E_CPU1_P3_RX_BUF_DN<4>")
	)
	(segment
		(start 127.575818 -410.963618)
		(end 127.437896 -410.630878)
		(width 0.14224)
		(layer "In13.Cu")
		(net "P5E_CPU1_P3_RX_BUF_DN<4>")
	)
	(segment
		(start 133.749796 -434.48986)
		(end 133.749796 -434.165756)
		(width 0.14224)
		(layer "In13.Cu")
		(net "P5E_CPU1_P3_RX_BUF_DN<4>")
	)
	(segment
		(start 132.794248 -433.574952)
		(end 132.794248 -417.484306)
		(width 0.14224)
		(layer "In13.Cu")
		(net "P5E_CPU1_P3_RX_BUF_DN<4>")
	)
	(segment
		(start 119.71655 -392.580622)
		(end 119.71655 -392.429238)
		(width 0.14224)
		(layer "In13.Cu")
		(net "P5E_CPU1_P3_RX_BUF_DN<4>")
	)
	(segment
		(start 128.969516 -413.676846)
		(end 128.969516 -412.004256)
		(width 0.14224)
		(layer "In13.Cu")
		(net "P5E_CPU1_P3_RX_BUF_DN<4>")
	)
	(segment
		(start 129.3876 -414.339024)
		(end 129.141474 -414.093152)
		(width 0.14224)
		(layer "In13.Cu")
		(net "P5E_CPU1_P3_RX_BUF_DN<4>")
	)
	(segment
		(start 118.975632 -398.332198)
		(end 118.975632 -393.012168)
		(width 0.14224)
		(layer "In13.Cu")
		(net "P5E_CPU1_P3_RX_BUF_DN<4>")
	)
	(segment
		(start 125.906276 -405.240998)
		(end 125.906276 -403.994874)
		(width 0.14224)
		(layer "In13.Cu")
		(net "P5E_CPU1_P3_RX_BUF_DN<4>")
	)
	(segment
		(start 129.141474 -414.093152)
		(end 128.969516 -413.676846)
		(width 0.14224)
		(layer "In13.Cu")
		(net "P5E_CPU1_P3_RX_BUF_DN<4>")
	)
	(segment
		(start 126.021846 -405.520144)
		(end 125.906276 -405.240998)
		(width 0.14224)
		(layer "In13.Cu")
		(net "P5E_CPU1_P3_RX_BUF_DN<4>")
	)
	(segment
		(start 133.258052 -434.038756)
		(end 132.794248 -433.574952)
		(width 0.14224)
		(layer "In13.Cu")
		(net "P5E_CPU1_P3_RX_BUF_DN<4>")
	)
	(segment
		(start 130.395218 -415.125408)
		(end 129.3876 -414.339024)
		(width 0.14224)
		(layer "In13.Cu")
		(net "P5E_CPU1_P3_RX_BUF_DN<4>")
	)
	(segment
		(start 123.408186 -402.951696)
		(end 119.107712 -398.651222)
		(width 0.14224)
		(layer "In13.Cu")
		(net "P5E_CPU1_P3_RX_BUF_DN<4>")
	)
	(segment
		(start 125.789436 -403.712934)
		(end 125.579378 -403.502876)
		(width 0.14224)
		(layer "In13.Cu")
		(net "P5E_CPU1_P3_RX_BUF_DN<4>")
	)
	(segment
		(start 125.579378 -403.502876)
		(end 125.353572 -403.409404)
		(width 0.14224)
		(layer "In13.Cu")
		(net "P5E_CPU1_P3_RX_BUF_DN<4>")
	)
	(segment
		(start 118.975632 -393.012168)
		(end 119.280178 -392.707622)
		(width 0.14224)
		(layer "In13.Cu")
		(net "P5E_CPU1_P3_RX_BUF_DN<4>")
	)
	(segment
		(start 132.794248 -417.484306)
		(end 132.577332 -416.961574)
		(width 0.14224)
		(layer "In13.Cu")
		(net "P5E_CPU1_P3_RX_BUF_DN<4>")
	)
	(segment
		(start 132.273548 -416.591496)
		(end 130.395218 -415.125408)
		(width 0.14224)
		(layer "In13.Cu")
		(net "P5E_CPU1_P3_RX_BUF_DN<4>")
	)
	(segment
		(start 127.296418 -406.13965)
		(end 127.068834 -405.912066)
		(width 0.14224)
		(layer "In13.Cu")
		(net "P5E_CPU1_P3_RX_BUF_DN<4>")
	)
	(segment
		(start 132.577332 -416.961574)
		(end 132.273548 -416.591496)
		(width 0.14224)
		(layer "In13.Cu")
		(net "P5E_CPU1_P3_RX_BUF_DN<4>")
	)
	(segment
		(start 119.58955 -392.707622)
		(end 119.71655 -392.580622)
		(width 0.14224)
		(layer "In13.Cu")
		(net "P5E_CPU1_P3_RX_BUF_DN<4>")
	)
	(segment
		(start 127.884174 -411.230318)
		(end 127.758698 -411.146498)
		(width 0.14224)
		(layer "In13.Cu")
		(net "P5E_CPU1_P3_RX_BUF_DN<4>")
	)
	(segment
		(start 133.749796 -434.165756)
		(end 133.622796 -434.038756)
		(width 0.14224)
		(layer "In13.Cu")
		(net "P5E_CPU1_P3_RX_BUF_DN<4>")
	)
	(segment
		(start 128.82499 -411.654752)
		(end 128.76657 -411.596078)
		(width 0.14224)
		(layer "In13.Cu")
		(net "P5E_CPU1_P3_RX_BUF_DN<4>")
	)
	(segment
		(start 127.068834 -405.912066)
		(end 126.93523 -405.856694)
		(width 0.14224)
		(layer "In13.Cu")
		(net "P5E_CPU1_P3_RX_BUF_DN<4>")
	)
	(segment
		(start 127.437896 -406.481026)
		(end 127.296418 -406.13965)
		(width 0.14224)
		(layer "In13.Cu")
		(net "P5E_CPU1_P3_RX_BUF_DN<4>")
	)
	(segment
		(start 126.460758 -405.856694)
		(end 126.285752 -405.78405)
		(width 0.14224)
		(layer "In13.Cu")
		(net "P5E_CPU1_P3_RX_BUF_DN<4>")
	)
	(segment
		(start 126.285752 -405.78405)
		(end 126.021846 -405.520144)
		(width 0.14224)
		(layer "In13.Cu")
		(net "P5E_CPU1_P3_RX_BUF_DN<4>")
	)
	(segment
		(start 127.758698 -411.146498)
		(end 127.575818 -410.963618)
		(width 0.14224)
		(layer "In13.Cu")
		(net "P5E_CPU1_P3_RX_BUF_DN<4>")
	)
	(segment
		(start 127.437896 -410.630878)
		(end 127.437896 -406.481026)
		(width 0.14224)
		(layer "In13.Cu")
		(net "P5E_CPU1_P3_RX_BUF_DN<4>")
	)
	(arc
		(start 125.906276 -403.994874)
		(mid 125.875906 -403.842282)
		(end 125.789436 -403.712934)
		(width 0.14224)
		(layer "In13.Cu")
		(net "P5E_CPU1_P3_RX_BUF_DN<4>")
	)
	(arc
		(start 119.107712 -398.651222)
		(mid 119.009965 -398.504838)
		(end 118.975632 -398.332198)
		(width 0.14224)
		(layer "In13.Cu")
		(net "P5E_CPU1_P3_RX_BUF_DN<4>")
	)
	(arc
		(start 123.617482 -403.06371)
		(mid 123.504525 -403.023226)
		(end 123.408186 -402.951696)
		(width 0.14224)
		(layer "In13.Cu")
		(net "P5E_CPU1_P3_RX_BUF_DN<4>")
	)
	(segment
		(start 118.117874 -390.761474)
		(end 118.118382 -390.761982)
		(width 0.1016)
		(layer "F.Cu")
		(net "P5E_CPU1_P3_RX_BUF_DN<3>")
	)
	(segment
		(start 118.375684 -392.761216)
		(end 118.5164 -392.6205)
		(width 0.1016)
		(layer "F.Cu")
		(net "P5E_CPU1_P3_RX_BUF_DN<3>")
	)
	(segment
		(start 118.118382 -391.578338)
		(end 118.042944 -391.653776)
		(width 0.1016)
		(layer "F.Cu")
		(net "P5E_CPU1_P3_RX_BUF_DN<3>")
	)
	(segment
		(start 118.5164 -392.6205)
		(end 118.5164 -392.429238)
		(width 0.1016)
		(layer "F.Cu")
		(net "P5E_CPU1_P3_RX_BUF_DN<3>")
	)
	(segment
		(start 118.042944 -392.634216)
		(end 118.169944 -392.761216)
		(width 0.1016)
		(layer "F.Cu")
		(net "P5E_CPU1_P3_RX_BUF_DN<3>")
	)
	(segment
		(start 118.118382 -390.761982)
		(end 118.118382 -391.578338)
		(width 0.1016)
		(layer "F.Cu")
		(net "P5E_CPU1_P3_RX_BUF_DN<3>")
	)
	(segment
		(start 118.042944 -391.653776)
		(end 118.042944 -392.634216)
		(width 0.1016)
		(layer "F.Cu")
		(net "P5E_CPU1_P3_RX_BUF_DN<3>")
	)
	(segment
		(start 118.169944 -392.761216)
		(end 118.375684 -392.761216)
		(width 0.1016)
		(layer "F.Cu")
		(net "P5E_CPU1_P3_RX_BUF_DN<3>")
	)
	(segment
		(start 130.755898 -417.287202)
		(end 129.941066 -416.49269)
		(width 0.14224)
		(layer "In13.Cu")
		(net "P5E_CPU1_P3_RX_BUF_DN<3>")
	)
	(segment
		(start 124.796296 -411.240478)
		(end 124.374656 -410.818838)
		(width 0.14224)
		(layer "In13.Cu")
		(net "P5E_CPU1_P3_RX_BUF_DN<3>")
	)
	(segment
		(start 131.6228 -435.038754)
		(end 131.258056 -435.038754)
		(width 0.14224)
		(layer "In13.Cu")
		(net "P5E_CPU1_P3_RX_BUF_DN<3>")
	)
	(segment
		(start 131.258056 -435.038754)
		(end 130.794252 -434.57495)
		(width 0.14224)
		(layer "In13.Cu")
		(net "P5E_CPU1_P3_RX_BUF_DN<3>")
	)
	(segment
		(start 131.7498 -435.489858)
		(end 131.7498 -435.165754)
		(width 0.14224)
		(layer "In13.Cu")
		(net "P5E_CPU1_P3_RX_BUF_DN<3>")
	)
	(segment
		(start 117.775482 -393.012168)
		(end 118.080028 -392.707622)
		(width 0.14224)
		(layer "In13.Cu")
		(net "P5E_CPU1_P3_RX_BUF_DN<3>")
	)
	(segment
		(start 125.726698 -411.625542)
		(end 124.796296 -411.240478)
		(width 0.14224)
		(layer "In13.Cu")
		(net "P5E_CPU1_P3_RX_BUF_DN<3>")
	)
	(segment
		(start 129.941066 -416.49269)
		(end 127.302006 -414.433004)
		(width 0.14224)
		(layer "In13.Cu")
		(net "P5E_CPU1_P3_RX_BUF_DN<3>")
	)
	(segment
		(start 118.3894 -392.707622)
		(end 118.5164 -392.580622)
		(width 0.14224)
		(layer "In13.Cu")
		(net "P5E_CPU1_P3_RX_BUF_DN<3>")
	)
	(segment
		(start 118.5164 -392.580622)
		(end 118.5164 -392.429238)
		(width 0.14224)
		(layer "In13.Cu")
		(net "P5E_CPU1_P3_RX_BUF_DN<3>")
	)
	(segment
		(start 123.397518 -405.856694)
		(end 123.222512 -405.78405)
		(width 0.14224)
		(layer "In13.Cu")
		(net "P5E_CPU1_P3_RX_BUF_DN<3>")
	)
	(segment
		(start 117.775482 -398.678908)
		(end 117.775482 -393.012168)
		(width 0.14224)
		(layer "In13.Cu")
		(net "P5E_CPU1_P3_RX_BUF_DN<3>")
	)
	(segment
		(start 130.794252 -434.57495)
		(end 130.794252 -417.378134)
		(width 0.14224)
		(layer "In13.Cu")
		(net "P5E_CPU1_P3_RX_BUF_DN<3>")
	)
	(segment
		(start 124.233178 -406.13965)
		(end 123.97867 -405.885142)
		(width 0.14224)
		(layer "In13.Cu")
		(net "P5E_CPU1_P3_RX_BUF_DN<3>")
	)
	(segment
		(start 123.91009 -405.856694)
		(end 123.397518 -405.856694)
		(width 0.14224)
		(layer "In13.Cu")
		(net "P5E_CPU1_P3_RX_BUF_DN<3>")
	)
	(segment
		(start 122.74677 -403.819868)
		(end 117.89537 -398.968468)
		(width 0.14224)
		(layer "In13.Cu")
		(net "P5E_CPU1_P3_RX_BUF_DN<3>")
	)
	(segment
		(start 118.080028 -392.707622)
		(end 118.3894 -392.707622)
		(width 0.14224)
		(layer "In13.Cu")
		(net "P5E_CPU1_P3_RX_BUF_DN<3>")
	)
	(segment
		(start 123.222512 -405.78405)
		(end 122.958606 -405.520144)
		(width 0.14224)
		(layer "In13.Cu")
		(net "P5E_CPU1_P3_RX_BUF_DN<3>")
	)
	(segment
		(start 124.374656 -410.818838)
		(end 124.374656 -406.481026)
		(width 0.14224)
		(layer "In13.Cu")
		(net "P5E_CPU1_P3_RX_BUF_DN<3>")
	)
	(segment
		(start 131.7498 -435.165754)
		(end 131.6228 -435.038754)
		(width 0.14224)
		(layer "In13.Cu")
		(net "P5E_CPU1_P3_RX_BUF_DN<3>")
	)
	(segment
		(start 122.843036 -405.241252)
		(end 122.843036 -404.052024)
		(width 0.14224)
		(layer "In13.Cu")
		(net "P5E_CPU1_P3_RX_BUF_DN<3>")
	)
	(segment
		(start 123.97867 -405.885142)
		(end 123.91009 -405.856694)
		(width 0.14224)
		(layer "In13.Cu")
		(net "P5E_CPU1_P3_RX_BUF_DN<3>")
	)
	(segment
		(start 124.374656 -406.481026)
		(end 124.233178 -406.13965)
		(width 0.14224)
		(layer "In13.Cu")
		(net "P5E_CPU1_P3_RX_BUF_DN<3>")
	)
	(segment
		(start 122.958606 -405.520144)
		(end 122.843036 -405.241252)
		(width 0.14224)
		(layer "In13.Cu")
		(net "P5E_CPU1_P3_RX_BUF_DN<3>")
	)
	(segment
		(start 127.302006 -414.433004)
		(end 126.122176 -413.705548)
		(width 0.14224)
		(layer "In13.Cu")
		(net "P5E_CPU1_P3_RX_BUF_DN<3>")
	)
	(segment
		(start 125.906276 -413.318452)
		(end 125.906276 -411.894274)
		(width 0.14224)
		(layer "In13.Cu")
		(net "P5E_CPU1_P3_RX_BUF_DN<3>")
	)
	(arc
		(start 130.794252 -417.378134)
		(mid 130.784273 -417.328787)
		(end 130.755898 -417.287202)
		(width 0.14224)
		(layer "In13.Cu")
		(net "P5E_CPU1_P3_RX_BUF_DN<3>")
	)
	(arc
		(start 122.843036 -404.052024)
		(mid 122.818021 -403.926357)
		(end 122.74677 -403.819868)
		(width 0.14224)
		(layer "In13.Cu")
		(net "P5E_CPU1_P3_RX_BUF_DN<3>")
	)
	(arc
		(start 125.906276 -411.894274)
		(mid 125.857247 -411.732674)
		(end 125.726698 -411.625542)
		(width 0.14224)
		(layer "In13.Cu")
		(net "P5E_CPU1_P3_RX_BUF_DN<3>")
	)
	(arc
		(start 126.122176 -413.705548)
		(mid 125.963806 -413.540114)
		(end 125.906276 -413.318452)
		(width 0.14224)
		(layer "In13.Cu")
		(net "P5E_CPU1_P3_RX_BUF_DN<3>")
	)
	(arc
		(start 117.89537 -398.968468)
		(mid 117.806655 -398.835603)
		(end 117.775482 -398.678908)
		(width 0.14224)
		(layer "In13.Cu")
		(net "P5E_CPU1_P3_RX_BUF_DN<3>")
	)
	(segment
		(start 116.918486 -391.578338)
		(end 116.82984 -391.666984)
		(width 0.1016)
		(layer "F.Cu")
		(net "P5E_CPU1_P3_RX_BUF_DN<2>")
	)
	(segment
		(start 117.175788 -392.761216)
		(end 117.316504 -392.6205)
		(width 0.1016)
		(layer "F.Cu")
		(net "P5E_CPU1_P3_RX_BUF_DN<2>")
	)
	(segment
		(start 116.82984 -391.666984)
		(end 116.82984 -392.634216)
		(width 0.1016)
		(layer "F.Cu")
		(net "P5E_CPU1_P3_RX_BUF_DN<2>")
	)
	(segment
		(start 116.917978 -390.761474)
		(end 116.918486 -390.761982)
		(width 0.1016)
		(layer "F.Cu")
		(net "P5E_CPU1_P3_RX_BUF_DN<2>")
	)
	(segment
		(start 116.95684 -392.761216)
		(end 117.175788 -392.761216)
		(width 0.1016)
		(layer "F.Cu")
		(net "P5E_CPU1_P3_RX_BUF_DN<2>")
	)
	(segment
		(start 116.918486 -390.761982)
		(end 116.918486 -391.578338)
		(width 0.1016)
		(layer "F.Cu")
		(net "P5E_CPU1_P3_RX_BUF_DN<2>")
	)
	(segment
		(start 117.316504 -392.6205)
		(end 117.316504 -392.429238)
		(width 0.1016)
		(layer "F.Cu")
		(net "P5E_CPU1_P3_RX_BUF_DN<2>")
	)
	(segment
		(start 116.82984 -392.634216)
		(end 116.95684 -392.761216)
		(width 0.1016)
		(layer "F.Cu")
		(net "P5E_CPU1_P3_RX_BUF_DN<2>")
	)
	(segment
		(start 119.895366 -405.520144)
		(end 119.779796 -405.241252)
		(width 0.14224)
		(layer "In13.Cu")
		(net "P5E_CPU1_P3_RX_BUF_DN<2>")
	)
	(segment
		(start 119.779796 -405.241252)
		(end 119.779796 -403.77745)
		(width 0.14224)
		(layer "In13.Cu")
		(net "P5E_CPU1_P3_RX_BUF_DN<2>")
	)
	(segment
		(start 123.194826 -413.972756)
		(end 122.962924 -413.740854)
		(width 0.14224)
		(layer "In13.Cu")
		(net "P5E_CPU1_P3_RX_BUF_DN<2>")
	)
	(segment
		(start 121.311416 -406.481026)
		(end 121.169938 -406.13965)
		(width 0.14224)
		(layer "In13.Cu")
		(net "P5E_CPU1_P3_RX_BUF_DN<2>")
	)
	(segment
		(start 117.316504 -392.580622)
		(end 117.316504 -392.429238)
		(width 0.14224)
		(layer "In13.Cu")
		(net "P5E_CPU1_P3_RX_BUF_DN<2>")
	)
	(segment
		(start 116.575586 -399.478754)
		(end 116.575586 -393.012168)
		(width 0.14224)
		(layer "In13.Cu")
		(net "P5E_CPU1_P3_RX_BUF_DN<2>")
	)
	(segment
		(start 128.794256 -433.391056)
		(end 128.794256 -417.472876)
		(width 0.14224)
		(layer "In13.Cu")
		(net "P5E_CPU1_P3_RX_BUF_DN<2>")
	)
	(segment
		(start 119.662956 -403.450552)
		(end 116.708174 -399.850102)
		(width 0.14224)
		(layer "In13.Cu")
		(net "P5E_CPU1_P3_RX_BUF_DN<2>")
	)
	(segment
		(start 122.843036 -413.451294)
		(end 122.843036 -412.02864)
		(width 0.14224)
		(layer "In13.Cu")
		(net "P5E_CPU1_P3_RX_BUF_DN<2>")
	)
	(segment
		(start 129.210816 -433.991512)
		(end 128.92405 -433.704746)
		(width 0.14224)
		(layer "In13.Cu")
		(net "P5E_CPU1_P3_RX_BUF_DN<2>")
	)
	(segment
		(start 128.495298 -416.913568)
		(end 126.128526 -415.333434)
		(width 0.14224)
		(layer "In13.Cu")
		(net "P5E_CPU1_P3_RX_BUF_DN<2>")
	)
	(segment
		(start 128.495298 -416.913822)
		(end 128.495298 -416.913568)
		(width 0.14224)
		(layer "In13.Cu")
		(net "P5E_CPU1_P3_RX_BUF_DN<2>")
	)
	(segment
		(start 116.880132 -392.707622)
		(end 117.189504 -392.707622)
		(width 0.14224)
		(layer "In13.Cu")
		(net "P5E_CPU1_P3_RX_BUF_DN<2>")
	)
	(segment
		(start 129.622804 -434.038756)
		(end 129.324862 -434.038756)
		(width 0.14224)
		(layer "In13.Cu")
		(net "P5E_CPU1_P3_RX_BUF_DN<2>")
	)
	(segment
		(start 121.169938 -406.13965)
		(end 120.91543 -405.885142)
		(width 0.14224)
		(layer "In13.Cu")
		(net "P5E_CPU1_P3_RX_BUF_DN<2>")
	)
	(segment
		(start 129.749804 -434.48986)
		(end 129.749804 -434.165756)
		(width 0.14224)
		(layer "In13.Cu")
		(net "P5E_CPU1_P3_RX_BUF_DN<2>")
	)
	(segment
		(start 120.334278 -405.856694)
		(end 120.159272 -405.78405)
		(width 0.14224)
		(layer "In13.Cu")
		(net "P5E_CPU1_P3_RX_BUF_DN<2>")
	)
	(segment
		(start 121.602246 -411.052264)
		(end 121.504202 -410.95422)
		(width 0.14224)
		(layer "In13.Cu")
		(net "P5E_CPU1_P3_RX_BUF_DN<2>")
	)
	(segment
		(start 126.128526 -415.333434)
		(end 123.765818 -414.354518)
		(width 0.14224)
		(layer "In13.Cu")
		(net "P5E_CPU1_P3_RX_BUF_DN<2>")
	)
	(segment
		(start 120.84685 -405.856694)
		(end 120.334278 -405.856694)
		(width 0.14224)
		(layer "In13.Cu")
		(net "P5E_CPU1_P3_RX_BUF_DN<2>")
	)
	(segment
		(start 120.91543 -405.885142)
		(end 120.84685 -405.856694)
		(width 0.14224)
		(layer "In13.Cu")
		(net "P5E_CPU1_P3_RX_BUF_DN<2>")
	)
	(segment
		(start 122.843036 -412.02864)
		(end 122.842782 -412.028894)
		(width 0.14224)
		(layer "In13.Cu")
		(net "P5E_CPU1_P3_RX_BUF_DN<2>")
	)
	(segment
		(start 122.833384 -411.980126)
		(end 122.728228 -411.726126)
		(width 0.14224)
		(layer "In13.Cu")
		(net "P5E_CPU1_P3_RX_BUF_DN<2>")
	)
	(segment
		(start 116.575586 -393.012168)
		(end 116.880132 -392.707622)
		(width 0.14224)
		(layer "In13.Cu")
		(net "P5E_CPU1_P3_RX_BUF_DN<2>")
	)
	(segment
		(start 121.311416 -410.488638)
		(end 121.311416 -406.481026)
		(width 0.14224)
		(layer "In13.Cu")
		(net "P5E_CPU1_P3_RX_BUF_DN<2>")
	)
	(segment
		(start 120.159272 -405.78405)
		(end 119.895366 -405.520144)
		(width 0.14224)
		(layer "In13.Cu")
		(net "P5E_CPU1_P3_RX_BUF_DN<2>")
	)
	(segment
		(start 129.749804 -434.165756)
		(end 129.622804 -434.038756)
		(width 0.14224)
		(layer "In13.Cu")
		(net "P5E_CPU1_P3_RX_BUF_DN<2>")
	)
	(segment
		(start 122.568208 -411.56636)
		(end 122.05208 -411.352746)
		(width 0.14224)
		(layer "In13.Cu")
		(net "P5E_CPU1_P3_RX_BUF_DN<2>")
	)
	(segment
		(start 117.189504 -392.707622)
		(end 117.316504 -392.580622)
		(width 0.14224)
		(layer "In13.Cu")
		(net "P5E_CPU1_P3_RX_BUF_DN<2>")
	)
	(arc
		(start 129.324862 -434.038756)
		(mid 129.263139 -434.026479)
		(end 129.210816 -433.991512)
		(width 0.14224)
		(layer "In13.Cu")
		(net "P5E_CPU1_P3_RX_BUF_DN<2>")
	)
	(arc
		(start 128.92405 -433.704746)
		(mid 128.827914 -433.560823)
		(end 128.794256 -433.391056)
		(width 0.14224)
		(layer "In13.Cu")
		(net "P5E_CPU1_P3_RX_BUF_DN<2>")
	)
	(arc
		(start 128.794256 -417.472876)
		(mid 128.714814 -417.155903)
		(end 128.495298 -416.913822)
		(width 0.14224)
		(layer "In13.Cu")
		(net "P5E_CPU1_P3_RX_BUF_DN<2>")
	)
	(arc
		(start 116.708174 -399.850102)
		(mid 116.609654 -399.675935)
		(end 116.575586 -399.478754)
		(width 0.14224)
		(layer "In13.Cu")
		(net "P5E_CPU1_P3_RX_BUF_DN<2>")
	)
	(arc
		(start 122.842782 -412.028894)
		(mid 122.840489 -412.004046)
		(end 122.833384 -411.980126)
		(width 0.14224)
		(layer "In13.Cu")
		(net "P5E_CPU1_P3_RX_BUF_DN<2>")
	)
	(arc
		(start 122.728228 -411.726126)
		(mid 122.664147 -411.630275)
		(end 122.568208 -411.56636)
		(width 0.14224)
		(layer "In13.Cu")
		(net "P5E_CPU1_P3_RX_BUF_DN<2>")
	)
	(arc
		(start 121.504202 -410.95422)
		(mid 121.361525 -410.740595)
		(end 121.311416 -410.488638)
		(width 0.14224)
		(layer "In13.Cu")
		(net "P5E_CPU1_P3_RX_BUF_DN<2>")
	)
	(arc
		(start 122.05208 -411.352746)
		(mid 121.812354 -411.224674)
		(end 121.602246 -411.052264)
		(width 0.14224)
		(layer "In13.Cu")
		(net "P5E_CPU1_P3_RX_BUF_DN<2>")
	)
	(arc
		(start 122.962924 -413.740854)
		(mid 122.874209 -413.607989)
		(end 122.843036 -413.451294)
		(width 0.14224)
		(layer "In13.Cu")
		(net "P5E_CPU1_P3_RX_BUF_DN<2>")
	)
	(arc
		(start 119.779796 -403.77745)
		(mid 119.749767 -403.603846)
		(end 119.662956 -403.450552)
		(width 0.14224)
		(layer "In13.Cu")
		(net "P5E_CPU1_P3_RX_BUF_DN<2>")
	)
	(arc
		(start 123.765818 -414.354518)
		(mid 123.461521 -414.191755)
		(end 123.194826 -413.972756)
		(width 0.14224)
		(layer "In13.Cu")
		(net "P5E_CPU1_P3_RX_BUF_DN<2>")
	)
	(segment
		(start 115.975638 -392.761216)
		(end 116.116354 -392.6205)
		(width 0.1016)
		(layer "F.Cu")
		(net "P5E_CPU1_P3_RX_BUF_DN<1>")
	)
	(segment
		(start 115.717828 -390.761474)
		(end 115.718336 -390.761982)
		(width 0.1016)
		(layer "F.Cu")
		(net "P5E_CPU1_P3_RX_BUF_DN<1>")
	)
	(segment
		(start 115.75669 -392.761216)
		(end 115.975638 -392.761216)
		(width 0.1016)
		(layer "F.Cu")
		(net "P5E_CPU1_P3_RX_BUF_DN<1>")
	)
	(segment
		(start 115.718336 -390.761982)
		(end 115.718336 -391.578338)
		(width 0.1016)
		(layer "F.Cu")
		(net "P5E_CPU1_P3_RX_BUF_DN<1>")
	)
	(segment
		(start 116.116354 -392.6205)
		(end 116.116354 -392.429238)
		(width 0.1016)
		(layer "F.Cu")
		(net "P5E_CPU1_P3_RX_BUF_DN<1>")
	)
	(segment
		(start 115.62969 -391.666984)
		(end 115.62969 -392.634216)
		(width 0.1016)
		(layer "F.Cu")
		(net "P5E_CPU1_P3_RX_BUF_DN<1>")
	)
	(segment
		(start 115.718336 -391.578338)
		(end 115.62969 -391.666984)
		(width 0.1016)
		(layer "F.Cu")
		(net "P5E_CPU1_P3_RX_BUF_DN<1>")
	)
	(segment
		(start 115.62969 -392.634216)
		(end 115.75669 -392.761216)
		(width 0.1016)
		(layer "F.Cu")
		(net "P5E_CPU1_P3_RX_BUF_DN<1>")
	)
	(segment
		(start 119.77497 -412.007812)
		(end 119.636032 -411.672024)
		(width 0.14224)
		(layer "In13.Cu")
		(net "P5E_CPU1_P3_RX_BUF_DN<1>")
	)
	(segment
		(start 116.116354 -392.580622)
		(end 116.116354 -392.429238)
		(width 0.14224)
		(layer "In13.Cu")
		(net "P5E_CPU1_P3_RX_BUF_DN<1>")
	)
	(segment
		(start 118.248176 -406.481026)
		(end 118.106698 -406.13965)
		(width 0.14224)
		(layer "In13.Cu")
		(net "P5E_CPU1_P3_RX_BUF_DN<1>")
	)
	(segment
		(start 117.271038 -405.856694)
		(end 117.096032 -405.78405)
		(width 0.14224)
		(layer "In13.Cu")
		(net "P5E_CPU1_P3_RX_BUF_DN<1>")
	)
	(segment
		(start 127.622808 -435.038754)
		(end 127.258064 -435.038754)
		(width 0.14224)
		(layer "In13.Cu")
		(net "P5E_CPU1_P3_RX_BUF_DN<1>")
	)
	(segment
		(start 117.096032 -405.78405)
		(end 116.832126 -405.520144)
		(width 0.14224)
		(layer "In13.Cu")
		(net "P5E_CPU1_P3_RX_BUF_DN<1>")
	)
	(segment
		(start 115.375436 -400.312128)
		(end 115.375436 -393.012168)
		(width 0.14224)
		(layer "In13.Cu")
		(net "P5E_CPU1_P3_RX_BUF_DN<1>")
	)
	(segment
		(start 118.757192 -411.256734)
		(end 118.756938 -411.25648)
		(width 0.14224)
		(layer "In13.Cu")
		(net "P5E_CPU1_P3_RX_BUF_DN<1>")
	)
	(segment
		(start 126.646178 -417.355528)
		(end 126.229618 -416.895788)
		(width 0.14224)
		(layer "In13.Cu")
		(net "P5E_CPU1_P3_RX_BUF_DN<1>")
	)
	(segment
		(start 124.743718 -415.903156)
		(end 120.433338 -414.118552)
		(width 0.14224)
		(layer "In13.Cu")
		(net "P5E_CPU1_P3_RX_BUF_DN<1>")
	)
	(segment
		(start 115.560094 -400.839686)
		(end 115.55984 -400.839686)
		(width 0.14224)
		(layer "In13.Cu")
		(net "P5E_CPU1_P3_RX_BUF_DN<1>")
	)
	(segment
		(start 115.375436 -393.012168)
		(end 115.679982 -392.707622)
		(width 0.14224)
		(layer "In13.Cu")
		(net "P5E_CPU1_P3_RX_BUF_DN<1>")
	)
	(segment
		(start 126.229618 -416.895788)
		(end 124.743718 -415.903156)
		(width 0.14224)
		(layer "In13.Cu")
		(net "P5E_CPU1_P3_RX_BUF_DN<1>")
	)
	(segment
		(start 119.54891 -411.584648)
		(end 118.757192 -411.25648)
		(width 0.14224)
		(layer "In13.Cu")
		(net "P5E_CPU1_P3_RX_BUF_DN<1>")
	)
	(segment
		(start 115.55984 -400.839686)
		(end 115.406424 -400.468846)
		(width 0.14224)
		(layer "In13.Cu")
		(net "P5E_CPU1_P3_RX_BUF_DN<1>")
	)
	(segment
		(start 118.106698 -406.13965)
		(end 117.910864 -405.943816)
		(width 0.14224)
		(layer "In13.Cu")
		(net "P5E_CPU1_P3_RX_BUF_DN<1>")
	)
	(segment
		(start 117.910864 -405.943816)
		(end 117.700552 -405.856694)
		(width 0.14224)
		(layer "In13.Cu")
		(net "P5E_CPU1_P3_RX_BUF_DN<1>")
	)
	(segment
		(start 118.248176 -410.337)
		(end 118.248176 -406.481026)
		(width 0.14224)
		(layer "In13.Cu")
		(net "P5E_CPU1_P3_RX_BUF_DN<1>")
	)
	(segment
		(start 126.79426 -434.57495)
		(end 126.79426 -417.739322)
		(width 0.14224)
		(layer "In13.Cu")
		(net "P5E_CPU1_P3_RX_BUF_DN<1>")
	)
	(segment
		(start 116.716556 -405.241252)
		(end 116.716556 -403.631908)
		(width 0.14224)
		(layer "In13.Cu")
		(net "P5E_CPU1_P3_RX_BUF_DN<1>")
	)
	(segment
		(start 117.700552 -405.856694)
		(end 117.271038 -405.856694)
		(width 0.14224)
		(layer "In13.Cu")
		(net "P5E_CPU1_P3_RX_BUF_DN<1>")
	)
	(segment
		(start 127.258064 -435.038754)
		(end 126.79426 -434.57495)
		(width 0.14224)
		(layer "In13.Cu")
		(net "P5E_CPU1_P3_RX_BUF_DN<1>")
	)
	(segment
		(start 127.749808 -435.489858)
		(end 127.749808 -435.165754)
		(width 0.14224)
		(layer "In13.Cu")
		(net "P5E_CPU1_P3_RX_BUF_DN<1>")
	)
	(segment
		(start 118.757192 -411.25648)
		(end 118.757192 -411.256734)
		(width 0.14224)
		(layer "In13.Cu")
		(net "P5E_CPU1_P3_RX_BUF_DN<1>")
	)
	(segment
		(start 127.749808 -435.165754)
		(end 127.622808 -435.038754)
		(width 0.14224)
		(layer "In13.Cu")
		(net "P5E_CPU1_P3_RX_BUF_DN<1>")
	)
	(segment
		(start 115.989354 -392.707622)
		(end 116.116354 -392.580622)
		(width 0.14224)
		(layer "In13.Cu")
		(net "P5E_CPU1_P3_RX_BUF_DN<1>")
	)
	(segment
		(start 115.679982 -392.707622)
		(end 115.989354 -392.707622)
		(width 0.14224)
		(layer "In13.Cu")
		(net "P5E_CPU1_P3_RX_BUF_DN<1>")
	)
	(segment
		(start 120.433338 -414.118552)
		(end 119.978932 -413.81553)
		(width 0.14224)
		(layer "In13.Cu")
		(net "P5E_CPU1_P3_RX_BUF_DN<1>")
	)
	(segment
		(start 119.779796 -413.442404)
		(end 119.779796 -412.031942)
		(width 0.14224)
		(layer "In13.Cu")
		(net "P5E_CPU1_P3_RX_BUF_DN<1>")
	)
	(segment
		(start 116.832126 -405.520144)
		(end 116.716556 -405.241252)
		(width 0.14224)
		(layer "In13.Cu")
		(net "P5E_CPU1_P3_RX_BUF_DN<1>")
	)
	(segment
		(start 116.716556 -403.631908)
		(end 115.560094 -400.839686)
		(width 0.14224)
		(layer "In13.Cu")
		(net "P5E_CPU1_P3_RX_BUF_DN<1>")
	)
	(arc
		(start 118.312184 -410.757116)
		(mid 118.285381 -410.634312)
		(end 118.2624 -410.510736)
		(width 0.14224)
		(layer "In13.Cu")
		(net "P5E_CPU1_P3_RX_BUF_DN<1>")
	)
	(arc
		(start 115.406424 -400.468846)
		(mid 115.383221 -400.392012)
		(end 115.375436 -400.312128)
		(width 0.14224)
		(layer "In13.Cu")
		(net "P5E_CPU1_P3_RX_BUF_DN<1>")
	)
	(arc
		(start 126.79426 -417.739322)
		(mid 126.755961 -417.533632)
		(end 126.646178 -417.355528)
		(width 0.14224)
		(layer "In13.Cu")
		(net "P5E_CPU1_P3_RX_BUF_DN<1>")
	)
	(arc
		(start 118.2624 -410.510736)
		(mid 118.251621 -410.424168)
		(end 118.248176 -410.337)
		(width 0.14224)
		(layer "In13.Cu")
		(net "P5E_CPU1_P3_RX_BUF_DN<1>")
	)
	(arc
		(start 118.756938 -411.25648)
		(mid 118.558152 -411.137259)
		(end 118.402608 -410.965396)
		(width 0.14224)
		(layer "In13.Cu")
		(net "P5E_CPU1_P3_RX_BUF_DN<1>")
	)
	(arc
		(start 119.636032 -411.672024)
		(mid 119.60119 -411.619637)
		(end 119.54891 -411.584648)
		(width 0.14224)
		(layer "In13.Cu")
		(net "P5E_CPU1_P3_RX_BUF_DN<1>")
	)
	(arc
		(start 118.402608 -410.965396)
		(mid 118.348072 -410.865303)
		(end 118.312184 -410.757116)
		(width 0.14224)
		(layer "In13.Cu")
		(net "P5E_CPU1_P3_RX_BUF_DN<1>")
	)
	(arc
		(start 119.978932 -413.81553)
		(mid 119.832609 -413.653914)
		(end 119.779796 -413.442404)
		(width 0.14224)
		(layer "In13.Cu")
		(net "P5E_CPU1_P3_RX_BUF_DN<1>")
	)
	(arc
		(start 119.779796 -412.031942)
		(mid 119.778573 -412.01964)
		(end 119.77497 -412.007812)
		(width 0.14224)
		(layer "In13.Cu")
		(net "P5E_CPU1_P3_RX_BUF_DN<1>")
	)
	(segment
		(start 132.518404 -391.578338)
		(end 132.518404 -390.761982)
		(width 0.1016)
		(layer "F.Cu")
		(net "P5E_CPU1_P3_RX_BUF_DN<15>")
	)
	(segment
		(start 132.916422 -392.429238)
		(end 132.916422 -392.599926)
		(width 0.1016)
		(layer "F.Cu")
		(net "P5E_CPU1_P3_RX_BUF_DN<15>")
	)
	(segment
		(start 132.755132 -392.761216)
		(end 132.556758 -392.761216)
		(width 0.1016)
		(layer "F.Cu")
		(net "P5E_CPU1_P3_RX_BUF_DN<15>")
	)
	(segment
		(start 132.429758 -391.666984)
		(end 132.518404 -391.578338)
		(width 0.1016)
		(layer "F.Cu")
		(net "P5E_CPU1_P3_RX_BUF_DN<15>")
	)
	(segment
		(start 132.518404 -390.761982)
		(end 132.517896 -390.761474)
		(width 0.1016)
		(layer "F.Cu")
		(net "P5E_CPU1_P3_RX_BUF_DN<15>")
	)
	(segment
		(start 132.916422 -392.599926)
		(end 132.755132 -392.761216)
		(width 0.1016)
		(layer "F.Cu")
		(net "P5E_CPU1_P3_RX_BUF_DN<15>")
	)
	(segment
		(start 132.556758 -392.761216)
		(end 132.429758 -392.634216)
		(width 0.1016)
		(layer "F.Cu")
		(net "P5E_CPU1_P3_RX_BUF_DN<15>")
	)
	(segment
		(start 132.429758 -392.634216)
		(end 132.429758 -391.666984)
		(width 0.1016)
		(layer "F.Cu")
		(net "P5E_CPU1_P3_RX_BUF_DN<15>")
	)
	(segment
		(start 160.992058 -406.13965)
		(end 160.73755 -405.885142)
		(width 0.14224)
		(layer "In13.Cu")
		(net "P5E_CPU1_P3_RX_BUF_DN<15>")
	)
	(segment
		(start 159.981392 -405.78405)
		(end 159.717486 -405.520144)
		(width 0.14224)
		(layer "In13.Cu")
		(net "P5E_CPU1_P3_RX_BUF_DN<15>")
	)
	(segment
		(start 132.323586 -394.465302)
		(end 132.175504 -394.266166)
		(width 0.14224)
		(layer "In13.Cu")
		(net "P5E_CPU1_P3_RX_BUF_DN<15>")
	)
	(segment
		(start 161.271458 -410.963618)
		(end 161.133536 -410.630878)
		(width 0.14224)
		(layer "In13.Cu")
		(net "P5E_CPU1_P3_RX_BUF_DN<15>")
	)
	(segment
		(start 155.794456 -434.57495)
		(end 155.794456 -424.569636)
		(width 0.14224)
		(layer "In13.Cu")
		(net "P5E_CPU1_P3_RX_BUF_DN<15>")
	)
	(segment
		(start 161.57956 -411.230318)
		(end 161.454338 -411.146498)
		(width 0.14224)
		(layer "In13.Cu")
		(net "P5E_CPU1_P3_RX_BUF_DN<15>")
	)
	(segment
		(start 162.63366 -411.767782)
		(end 162.461702 -411.59557)
		(width 0.14224)
		(layer "In13.Cu")
		(net "P5E_CPU1_P3_RX_BUF_DN<15>")
	)
	(segment
		(start 160.156398 -405.856694)
		(end 159.981392 -405.78405)
		(width 0.14224)
		(layer "In13.Cu")
		(net "P5E_CPU1_P3_RX_BUF_DN<15>")
	)
	(segment
		(start 156.750004 -435.165754)
		(end 156.605732 -435.021482)
		(width 0.14224)
		(layer "In13.Cu")
		(net "P5E_CPU1_P3_RX_BUF_DN<15>")
	)
	(segment
		(start 158.984188 -402.762974)
		(end 151.332946 -397.650462)
		(width 0.14224)
		(layer "In13.Cu")
		(net "P5E_CPU1_P3_RX_BUF_DN<15>")
	)
	(segment
		(start 162.461702 -411.59557)
		(end 161.57956 -411.230318)
		(width 0.14224)
		(layer "In13.Cu")
		(net "P5E_CPU1_P3_RX_BUF_DN<15>")
	)
	(segment
		(start 132.789422 -392.707622)
		(end 132.916422 -392.580622)
		(width 0.14224)
		(layer "In13.Cu")
		(net "P5E_CPU1_P3_RX_BUF_DN<15>")
	)
	(segment
		(start 156.240988 -435.021482)
		(end 155.794456 -434.57495)
		(width 0.14224)
		(layer "In13.Cu")
		(net "P5E_CPU1_P3_RX_BUF_DN<15>")
	)
	(segment
		(start 160.73755 -405.885142)
		(end 160.66897 -405.856694)
		(width 0.14224)
		(layer "In13.Cu")
		(net "P5E_CPU1_P3_RX_BUF_DN<15>")
	)
	(segment
		(start 162.665156 -413.476694)
		(end 162.665156 -411.843474)
		(width 0.14224)
		(layer "In13.Cu")
		(net "P5E_CPU1_P3_RX_BUF_DN<15>")
	)
	(segment
		(start 161.133536 -410.630878)
		(end 161.133536 -406.481026)
		(width 0.14224)
		(layer "In13.Cu")
		(net "P5E_CPU1_P3_RX_BUF_DN<15>")
	)
	(segment
		(start 159.601916 -405.241252)
		(end 159.601916 -403.861524)
		(width 0.14224)
		(layer "In13.Cu")
		(net "P5E_CPU1_P3_RX_BUF_DN<15>")
	)
	(segment
		(start 132.175504 -393.012168)
		(end 132.48005 -392.707622)
		(width 0.14224)
		(layer "In13.Cu")
		(net "P5E_CPU1_P3_RX_BUF_DN<15>")
	)
	(segment
		(start 132.916422 -392.580622)
		(end 132.916422 -392.429238)
		(width 0.14224)
		(layer "In13.Cu")
		(net "P5E_CPU1_P3_RX_BUF_DN<15>")
	)
	(segment
		(start 146.553428 -396.371318)
		(end 134.422896 -395.176756)
		(width 0.14224)
		(layer "In13.Cu")
		(net "P5E_CPU1_P3_RX_BUF_DN<15>")
	)
	(segment
		(start 159.601916 -403.861524)
		(end 159.262064 -403.04085)
		(width 0.14224)
		(layer "In13.Cu")
		(net "P5E_CPU1_P3_RX_BUF_DN<15>")
	)
	(segment
		(start 161.454338 -411.146498)
		(end 161.271458 -410.963618)
		(width 0.14224)
		(layer "In13.Cu")
		(net "P5E_CPU1_P3_RX_BUF_DN<15>")
	)
	(segment
		(start 149.807168 -397.01851)
		(end 146.553428 -396.371318)
		(width 0.14224)
		(layer "In13.Cu")
		(net "P5E_CPU1_P3_RX_BUF_DN<15>")
	)
	(segment
		(start 132.48005 -392.707622)
		(end 132.789422 -392.707622)
		(width 0.14224)
		(layer "In13.Cu")
		(net "P5E_CPU1_P3_RX_BUF_DN<15>")
	)
	(segment
		(start 160.66897 -405.856694)
		(end 160.156398 -405.856694)
		(width 0.14224)
		(layer "In13.Cu")
		(net "P5E_CPU1_P3_RX_BUF_DN<15>")
	)
	(segment
		(start 159.262064 -403.04085)
		(end 158.984188 -402.762974)
		(width 0.14224)
		(layer "In13.Cu")
		(net "P5E_CPU1_P3_RX_BUF_DN<15>")
	)
	(segment
		(start 162.665156 -411.843474)
		(end 162.63366 -411.767782)
		(width 0.14224)
		(layer "In13.Cu")
		(net "P5E_CPU1_P3_RX_BUF_DN<15>")
	)
	(segment
		(start 161.133536 -406.481026)
		(end 160.992058 -406.13965)
		(width 0.14224)
		(layer "In13.Cu")
		(net "P5E_CPU1_P3_RX_BUF_DN<15>")
	)
	(segment
		(start 159.717486 -405.520144)
		(end 159.601916 -405.241252)
		(width 0.14224)
		(layer "In13.Cu")
		(net "P5E_CPU1_P3_RX_BUF_DN<15>")
	)
	(segment
		(start 134.422896 -395.176756)
		(end 133.373622 -394.967968)
		(width 0.14224)
		(layer "In13.Cu")
		(net "P5E_CPU1_P3_RX_BUF_DN<15>")
	)
	(segment
		(start 132.175504 -394.266166)
		(end 132.175504 -393.012168)
		(width 0.14224)
		(layer "In13.Cu")
		(net "P5E_CPU1_P3_RX_BUF_DN<15>")
	)
	(segment
		(start 156.750004 -435.489858)
		(end 156.750004 -435.165754)
		(width 0.14224)
		(layer "In13.Cu")
		(net "P5E_CPU1_P3_RX_BUF_DN<15>")
	)
	(segment
		(start 156.605732 -435.021482)
		(end 156.240988 -435.021482)
		(width 0.14224)
		(layer "In13.Cu")
		(net "P5E_CPU1_P3_RX_BUF_DN<15>")
	)
	(segment
		(start 162.57397 -413.777176)
		(end 162.665156 -413.476694)
		(width 0.14224)
		(layer "In13.Cu")
		(net "P5E_CPU1_P3_RX_BUF_DN<15>")
	)
	(segment
		(start 156.153104 -423.386758)
		(end 162.57397 -413.777176)
		(width 0.14224)
		(layer "In13.Cu")
		(net "P5E_CPU1_P3_RX_BUF_DN<15>")
	)
	(segment
		(start 151.332946 -397.650462)
		(end 149.807168 -397.01851)
		(width 0.14224)
		(layer "In13.Cu")
		(net "P5E_CPU1_P3_RX_BUF_DN<15>")
	)
	(segment
		(start 133.373622 -394.967968)
		(end 132.78231 -394.788644)
		(width 0.14224)
		(layer "In13.Cu")
		(net "P5E_CPU1_P3_RX_BUF_DN<15>")
	)
	(arc
		(start 132.78231 -394.788644)
		(mid 132.526969 -394.663832)
		(end 132.323586 -394.465302)
		(width 0.14224)
		(layer "In13.Cu")
		(net "P5E_CPU1_P3_RX_BUF_DN<15>")
	)
	(arc
		(start 155.794456 -424.569636)
		(mid 155.886057 -423.951601)
		(end 156.153104 -423.386758)
		(width 0.14224)
		(layer "In13.Cu")
		(net "P5E_CPU1_P3_RX_BUF_DN<15>")
	)
	(segment
		(start 131.716526 -392.429238)
		(end 131.716526 -392.59383)
		(width 0.1016)
		(layer "F.Cu")
		(net "P5E_CPU1_P3_RX_BUF_DN<14>")
	)
	(segment
		(start 131.716526 -392.59383)
		(end 131.54914 -392.761216)
		(width 0.1016)
		(layer "F.Cu")
		(net "P5E_CPU1_P3_RX_BUF_DN<14>")
	)
	(segment
		(start 131.318508 -390.761982)
		(end 131.318 -390.761474)
		(width 0.1016)
		(layer "F.Cu")
		(net "P5E_CPU1_P3_RX_BUF_DN<14>")
	)
	(segment
		(start 131.229862 -391.666984)
		(end 131.318508 -391.578338)
		(width 0.1016)
		(layer "F.Cu")
		(net "P5E_CPU1_P3_RX_BUF_DN<14>")
	)
	(segment
		(start 131.356862 -392.761216)
		(end 131.229862 -392.634216)
		(width 0.1016)
		(layer "F.Cu")
		(net "P5E_CPU1_P3_RX_BUF_DN<14>")
	)
	(segment
		(start 131.229862 -392.634216)
		(end 131.229862 -391.666984)
		(width 0.1016)
		(layer "F.Cu")
		(net "P5E_CPU1_P3_RX_BUF_DN<14>")
	)
	(segment
		(start 131.54914 -392.761216)
		(end 131.356862 -392.761216)
		(width 0.1016)
		(layer "F.Cu")
		(net "P5E_CPU1_P3_RX_BUF_DN<14>")
	)
	(segment
		(start 131.318508 -391.578338)
		(end 131.318508 -390.761982)
		(width 0.1016)
		(layer "F.Cu")
		(net "P5E_CPU1_P3_RX_BUF_DN<14>")
	)
	(segment
		(start 147.831556 -398.196054)
		(end 137.113518 -396.604744)
		(width 0.14224)
		(layer "In13.Cu")
		(net "P5E_CPU1_P3_RX_BUF_DN<14>")
	)
	(segment
		(start 158.179008 -410.893006)
		(end 158.070296 -410.630878)
		(width 0.14224)
		(layer "In13.Cu")
		(net "P5E_CPU1_P3_RX_BUF_DN<14>")
	)
	(segment
		(start 158.070296 -410.630878)
		(end 158.070296 -406.481026)
		(width 0.14224)
		(layer "In13.Cu")
		(net "P5E_CPU1_P3_RX_BUF_DN<14>")
	)
	(segment
		(start 135.930132 -396.488412)
		(end 133.41223 -395.987524)
		(width 0.14224)
		(layer "In13.Cu")
		(net "P5E_CPU1_P3_RX_BUF_DN<14>")
	)
	(segment
		(start 157.67431 -405.885142)
		(end 157.60573 -405.856694)
		(width 0.14224)
		(layer "In13.Cu")
		(net "P5E_CPU1_P3_RX_BUF_DN<14>")
	)
	(segment
		(start 154.226768 -422.909238)
		(end 159.601916 -413.42056)
		(width 0.14224)
		(layer "In13.Cu")
		(net "P5E_CPU1_P3_RX_BUF_DN<14>")
	)
	(segment
		(start 148.434806 -398.362932)
		(end 147.831556 -398.196054)
		(width 0.14224)
		(layer "In13.Cu")
		(net "P5E_CPU1_P3_RX_BUF_DN<14>")
	)
	(segment
		(start 156.538676 -405.241252)
		(end 156.538676 -403.921722)
		(width 0.14224)
		(layer "In13.Cu")
		(net "P5E_CPU1_P3_RX_BUF_DN<14>")
	)
	(segment
		(start 154.051508 -401.452334)
		(end 149.577806 -398.844516)
		(width 0.14224)
		(layer "In13.Cu")
		(net "P5E_CPU1_P3_RX_BUF_DN<14>")
	)
	(segment
		(start 159.45739 -411.654498)
		(end 159.398462 -411.59557)
		(width 0.14224)
		(layer "In13.Cu")
		(net "P5E_CPU1_P3_RX_BUF_DN<14>")
	)
	(segment
		(start 131.280154 -392.707622)
		(end 131.589526 -392.707622)
		(width 0.14224)
		(layer "In13.Cu")
		(net "P5E_CPU1_P3_RX_BUF_DN<14>")
	)
	(segment
		(start 133.41223 -395.987524)
		(end 131.7498 -395.48308)
		(width 0.14224)
		(layer "In13.Cu")
		(net "P5E_CPU1_P3_RX_BUF_DN<14>")
	)
	(segment
		(start 154.615134 -434.030882)
		(end 154.25039 -434.030882)
		(width 0.14224)
		(layer "In13.Cu")
		(net "P5E_CPU1_P3_RX_BUF_DN<14>")
	)
	(segment
		(start 154.25039 -434.030882)
		(end 153.79446 -433.574952)
		(width 0.14224)
		(layer "In13.Cu")
		(net "P5E_CPU1_P3_RX_BUF_DN<14>")
	)
	(segment
		(start 156.918152 -405.78405)
		(end 156.654246 -405.520144)
		(width 0.14224)
		(layer "In13.Cu")
		(net "P5E_CPU1_P3_RX_BUF_DN<14>")
	)
	(segment
		(start 153.79446 -433.574952)
		(end 153.79446 -424.54957)
		(width 0.14224)
		(layer "In13.Cu")
		(net "P5E_CPU1_P3_RX_BUF_DN<14>")
	)
	(segment
		(start 154.750008 -434.48986)
		(end 154.750008 -434.165756)
		(width 0.14224)
		(layer "In13.Cu")
		(net "P5E_CPU1_P3_RX_BUF_DN<14>")
	)
	(segment
		(start 137.113518 -396.604744)
		(end 135.930132 -396.488412)
		(width 0.14224)
		(layer "In13.Cu")
		(net "P5E_CPU1_P3_RX_BUF_DN<14>")
	)
	(segment
		(start 159.601916 -412.00324)
		(end 159.45739 -411.654498)
		(width 0.14224)
		(layer "In13.Cu")
		(net "P5E_CPU1_P3_RX_BUF_DN<14>")
	)
	(segment
		(start 159.601916 -413.42056)
		(end 159.601916 -412.00324)
		(width 0.14224)
		(layer "In13.Cu")
		(net "P5E_CPU1_P3_RX_BUF_DN<14>")
	)
	(segment
		(start 159.398462 -411.59557)
		(end 158.51632 -411.230318)
		(width 0.14224)
		(layer "In13.Cu")
		(net "P5E_CPU1_P3_RX_BUF_DN<14>")
	)
	(segment
		(start 156.460444 -403.733)
		(end 156.111448 -403.210776)
		(width 0.14224)
		(layer "In13.Cu")
		(net "P5E_CPU1_P3_RX_BUF_DN<14>")
	)
	(segment
		(start 157.928818 -406.13965)
		(end 157.67431 -405.885142)
		(width 0.14224)
		(layer "In13.Cu")
		(net "P5E_CPU1_P3_RX_BUF_DN<14>")
	)
	(segment
		(start 157.093158 -405.856694)
		(end 156.918152 -405.78405)
		(width 0.14224)
		(layer "In13.Cu")
		(net "P5E_CPU1_P3_RX_BUF_DN<14>")
	)
	(segment
		(start 130.975608 -393.012168)
		(end 131.280154 -392.707622)
		(width 0.14224)
		(layer "In13.Cu")
		(net "P5E_CPU1_P3_RX_BUF_DN<14>")
	)
	(segment
		(start 130.975608 -394.386308)
		(end 130.975608 -393.012168)
		(width 0.14224)
		(layer "In13.Cu")
		(net "P5E_CPU1_P3_RX_BUF_DN<14>")
	)
	(segment
		(start 156.111448 -403.210776)
		(end 155.539694 -402.599652)
		(width 0.14224)
		(layer "In13.Cu")
		(net "P5E_CPU1_P3_RX_BUF_DN<14>")
	)
	(segment
		(start 158.51632 -411.230318)
		(end 158.179008 -410.893006)
		(width 0.14224)
		(layer "In13.Cu")
		(net "P5E_CPU1_P3_RX_BUF_DN<14>")
	)
	(segment
		(start 131.589526 -392.707622)
		(end 131.716526 -392.580622)
		(width 0.14224)
		(layer "In13.Cu")
		(net "P5E_CPU1_P3_RX_BUF_DN<14>")
	)
	(segment
		(start 156.538676 -403.921722)
		(end 156.460444 -403.733)
		(width 0.14224)
		(layer "In13.Cu")
		(net "P5E_CPU1_P3_RX_BUF_DN<14>")
	)
	(segment
		(start 149.577806 -398.844516)
		(end 148.434806 -398.362932)
		(width 0.14224)
		(layer "In13.Cu")
		(net "P5E_CPU1_P3_RX_BUF_DN<14>")
	)
	(segment
		(start 131.716526 -392.580622)
		(end 131.716526 -392.429238)
		(width 0.14224)
		(layer "In13.Cu")
		(net "P5E_CPU1_P3_RX_BUF_DN<14>")
	)
	(segment
		(start 157.60573 -405.856694)
		(end 157.093158 -405.856694)
		(width 0.14224)
		(layer "In13.Cu")
		(net "P5E_CPU1_P3_RX_BUF_DN<14>")
	)
	(segment
		(start 155.539694 -402.599652)
		(end 154.051508 -401.452334)
		(width 0.14224)
		(layer "In13.Cu")
		(net "P5E_CPU1_P3_RX_BUF_DN<14>")
	)
	(segment
		(start 154.750008 -434.165756)
		(end 154.615134 -434.030882)
		(width 0.14224)
		(layer "In13.Cu")
		(net "P5E_CPU1_P3_RX_BUF_DN<14>")
	)
	(segment
		(start 158.070296 -406.481026)
		(end 157.928818 -406.13965)
		(width 0.14224)
		(layer "In13.Cu")
		(net "P5E_CPU1_P3_RX_BUF_DN<14>")
	)
	(segment
		(start 156.654246 -405.520144)
		(end 156.538676 -405.241252)
		(width 0.14224)
		(layer "In13.Cu")
		(net "P5E_CPU1_P3_RX_BUF_DN<14>")
	)
	(segment
		(start 131.435094 -395.294104)
		(end 131.2926 -395.15161)
		(width 0.14224)
		(layer "In13.Cu")
		(net "P5E_CPU1_P3_RX_BUF_DN<14>")
	)
	(arc
		(start 131.7498 -395.48308)
		(mid 131.580793 -395.407998)
		(end 131.435094 -395.294104)
		(width 0.14224)
		(layer "In13.Cu")
		(net "P5E_CPU1_P3_RX_BUF_DN<14>")
	)
	(arc
		(start 153.79446 -424.54957)
		(mid 153.904351 -423.701398)
		(end 154.226768 -422.909238)
		(width 0.14224)
		(layer "In13.Cu")
		(net "P5E_CPU1_P3_RX_BUF_DN<14>")
	)
	(arc
		(start 131.2926 -395.15161)
		(mid 131.057987 -394.800486)
		(end 130.975608 -394.386308)
		(width 0.14224)
		(layer "In13.Cu")
		(net "P5E_CPU1_P3_RX_BUF_DN<14>")
	)
	(segment
		(start 130.118358 -390.761982)
		(end 130.118358 -391.578338)
		(width 0.1016)
		(layer "F.Cu")
		(net "P5E_CPU1_P3_RX_BUF_DN<13>")
	)
	(segment
		(start 130.11785 -390.761474)
		(end 130.118358 -390.761982)
		(width 0.1016)
		(layer "F.Cu")
		(net "P5E_CPU1_P3_RX_BUF_DN<13>")
	)
	(segment
		(start 130.118358 -391.578338)
		(end 130.038348 -391.658348)
		(width 0.1016)
		(layer "F.Cu")
		(net "P5E_CPU1_P3_RX_BUF_DN<13>")
	)
	(segment
		(start 130.516376 -392.6205)
		(end 130.516376 -392.429238)
		(width 0.1016)
		(layer "F.Cu")
		(net "P5E_CPU1_P3_RX_BUF_DN<13>")
	)
	(segment
		(start 130.165348 -392.761216)
		(end 130.37566 -392.761216)
		(width 0.1016)
		(layer "F.Cu")
		(net "P5E_CPU1_P3_RX_BUF_DN<13>")
	)
	(segment
		(start 130.37566 -392.761216)
		(end 130.516376 -392.6205)
		(width 0.1016)
		(layer "F.Cu")
		(net "P5E_CPU1_P3_RX_BUF_DN<13>")
	)
	(segment
		(start 130.038348 -391.658348)
		(end 130.038348 -392.634216)
		(width 0.1016)
		(layer "F.Cu")
		(net "P5E_CPU1_P3_RX_BUF_DN<13>")
	)
	(segment
		(start 130.038348 -392.634216)
		(end 130.165348 -392.761216)
		(width 0.1016)
		(layer "F.Cu")
		(net "P5E_CPU1_P3_RX_BUF_DN<13>")
	)
	(segment
		(start 155.259278 -411.195266)
		(end 155.007056 -410.943044)
		(width 0.14224)
		(layer "In13.Cu")
		(net "P5E_CPU1_P3_RX_BUF_DN<13>")
	)
	(segment
		(start 156.433012 -411.681422)
		(end 155.259278 -411.195266)
		(width 0.14224)
		(layer "In13.Cu")
		(net "P5E_CPU1_P3_RX_BUF_DN<13>")
	)
	(segment
		(start 135.39851 -397.572992)
		(end 131.32689 -396.338044)
		(width 0.14224)
		(layer "In13.Cu")
		(net "P5E_CPU1_P3_RX_BUF_DN<13>")
	)
	(segment
		(start 154.029918 -405.856694)
		(end 153.854912 -405.78405)
		(width 0.14224)
		(layer "In13.Cu")
		(net "P5E_CPU1_P3_RX_BUF_DN<13>")
	)
	(segment
		(start 129.775458 -394.658342)
		(end 129.775458 -393.012168)
		(width 0.14224)
		(layer "In13.Cu")
		(net "P5E_CPU1_P3_RX_BUF_DN<13>")
	)
	(segment
		(start 129.775458 -393.012168)
		(end 130.080004 -392.707622)
		(width 0.14224)
		(layer "In13.Cu")
		(net "P5E_CPU1_P3_RX_BUF_DN<13>")
	)
	(segment
		(start 152.24125 -435.021736)
		(end 151.794464 -434.57495)
		(width 0.14224)
		(layer "In13.Cu")
		(net "P5E_CPU1_P3_RX_BUF_DN<13>")
	)
	(segment
		(start 152.142952 -422.135808)
		(end 152.505664 -421.260524)
		(width 0.14224)
		(layer "In13.Cu")
		(net "P5E_CPU1_P3_RX_BUF_DN<13>")
	)
	(segment
		(start 152.750012 -435.489858)
		(end 152.750012 -435.165754)
		(width 0.14224)
		(layer "In13.Cu")
		(net "P5E_CPU1_P3_RX_BUF_DN<13>")
	)
	(segment
		(start 155.007056 -406.481026)
		(end 154.865578 -406.13965)
		(width 0.14224)
		(layer "In13.Cu")
		(net "P5E_CPU1_P3_RX_BUF_DN<13>")
	)
	(segment
		(start 152.605994 -435.021736)
		(end 152.24125 -435.021736)
		(width 0.14224)
		(layer "In13.Cu")
		(net "P5E_CPU1_P3_RX_BUF_DN<13>")
	)
	(segment
		(start 147.014438 -399.484342)
		(end 145.548604 -399.078704)
		(width 0.14224)
		(layer "In13.Cu")
		(net "P5E_CPU1_P3_RX_BUF_DN<13>")
	)
	(segment
		(start 154.54249 -405.856694)
		(end 154.029918 -405.856694)
		(width 0.14224)
		(layer "In13.Cu")
		(net "P5E_CPU1_P3_RX_BUF_DN<13>")
	)
	(segment
		(start 149.341332 -400.55038)
		(end 147.014438 -399.484342)
		(width 0.14224)
		(layer "In13.Cu")
		(net "P5E_CPU1_P3_RX_BUF_DN<13>")
	)
	(segment
		(start 130.080004 -392.707622)
		(end 130.389376 -392.707622)
		(width 0.14224)
		(layer "In13.Cu")
		(net "P5E_CPU1_P3_RX_BUF_DN<13>")
	)
	(segment
		(start 153.682954 -418.602668)
		(end 156.538676 -413.26054)
		(width 0.14224)
		(layer "In13.Cu")
		(net "P5E_CPU1_P3_RX_BUF_DN<13>")
	)
	(segment
		(start 153.343102 -419.238684)
		(end 153.682446 -418.602922)
		(width 0.14224)
		(layer "In13.Cu")
		(net "P5E_CPU1_P3_RX_BUF_DN<13>")
	)
	(segment
		(start 151.794464 -434.57495)
		(end 151.794464 -423.888662)
		(width 0.14224)
		(layer "In13.Cu")
		(net "P5E_CPU1_P3_RX_BUF_DN<13>")
	)
	(segment
		(start 152.505664 -421.260524)
		(end 152.505918 -421.26027)
		(width 0.14224)
		(layer "In13.Cu")
		(net "P5E_CPU1_P3_RX_BUF_DN<13>")
	)
	(segment
		(start 153.682446 -418.602922)
		(end 153.682954 -418.602668)
		(width 0.14224)
		(layer "In13.Cu")
		(net "P5E_CPU1_P3_RX_BUF_DN<13>")
	)
	(segment
		(start 153.423112 -403.463506)
		(end 152.865074 -402.905468)
		(width 0.14224)
		(layer "In13.Cu")
		(net "P5E_CPU1_P3_RX_BUF_DN<13>")
	)
	(segment
		(start 155.007056 -410.943044)
		(end 155.007056 -406.481026)
		(width 0.14224)
		(layer "In13.Cu")
		(net "P5E_CPU1_P3_RX_BUF_DN<13>")
	)
	(segment
		(start 153.591006 -405.520144)
		(end 153.475436 -405.240998)
		(width 0.14224)
		(layer "In13.Cu")
		(net "P5E_CPU1_P3_RX_BUF_DN<13>")
	)
	(segment
		(start 153.475436 -405.240998)
		(end 153.475436 -403.589744)
		(width 0.14224)
		(layer "In13.Cu")
		(net "P5E_CPU1_P3_RX_BUF_DN<13>")
	)
	(segment
		(start 152.750012 -435.165754)
		(end 152.605994 -435.021736)
		(width 0.14224)
		(layer "In13.Cu")
		(net "P5E_CPU1_P3_RX_BUF_DN<13>")
	)
	(segment
		(start 154.61107 -405.885142)
		(end 154.54249 -405.856694)
		(width 0.14224)
		(layer "In13.Cu")
		(net "P5E_CPU1_P3_RX_BUF_DN<13>")
	)
	(segment
		(start 152.865074 -402.905468)
		(end 149.341332 -400.55038)
		(width 0.14224)
		(layer "In13.Cu")
		(net "P5E_CPU1_P3_RX_BUF_DN<13>")
	)
	(segment
		(start 153.854912 -405.78405)
		(end 153.591006 -405.520144)
		(width 0.14224)
		(layer "In13.Cu")
		(net "P5E_CPU1_P3_RX_BUF_DN<13>")
	)
	(segment
		(start 152.505918 -421.26027)
		(end 153.343102 -419.238684)
		(width 0.14224)
		(layer "In13.Cu")
		(net "P5E_CPU1_P3_RX_BUF_DN<13>")
	)
	(segment
		(start 130.700018 -395.962124)
		(end 130.043682 -395.305788)
		(width 0.14224)
		(layer "In13.Cu")
		(net "P5E_CPU1_P3_RX_BUF_DN<13>")
	)
	(segment
		(start 130.389376 -392.707622)
		(end 130.516376 -392.580622)
		(width 0.14224)
		(layer "In13.Cu")
		(net "P5E_CPU1_P3_RX_BUF_DN<13>")
	)
	(segment
		(start 130.516376 -392.580622)
		(end 130.516376 -392.429238)
		(width 0.14224)
		(layer "In13.Cu")
		(net "P5E_CPU1_P3_RX_BUF_DN<13>")
	)
	(segment
		(start 145.548604 -399.078704)
		(end 135.39851 -397.572992)
		(width 0.14224)
		(layer "In13.Cu")
		(net "P5E_CPU1_P3_RX_BUF_DN<13>")
	)
	(segment
		(start 156.538676 -413.26054)
		(end 156.538676 -411.83941)
		(width 0.14224)
		(layer "In13.Cu")
		(net "P5E_CPU1_P3_RX_BUF_DN<13>")
	)
	(segment
		(start 154.865578 -406.13965)
		(end 154.61107 -405.885142)
		(width 0.14224)
		(layer "In13.Cu")
		(net "P5E_CPU1_P3_RX_BUF_DN<13>")
	)
	(arc
		(start 131.32689 -396.338044)
		(mid 130.990288 -396.18872)
		(end 130.700018 -395.962124)
		(width 0.14224)
		(layer "In13.Cu")
		(net "P5E_CPU1_P3_RX_BUF_DN<13>")
	)
	(arc
		(start 156.538676 -411.83941)
		(mid 156.509848 -411.744334)
		(end 156.433012 -411.681422)
		(width 0.14224)
		(layer "In13.Cu")
		(net "P5E_CPU1_P3_RX_BUF_DN<13>")
	)
	(arc
		(start 153.475436 -403.589744)
		(mid 153.461844 -403.521411)
		(end 153.423112 -403.463506)
		(width 0.14224)
		(layer "In13.Cu")
		(net "P5E_CPU1_P3_RX_BUF_DN<13>")
	)
	(arc
		(start 130.043682 -395.305788)
		(mid 129.845145 -395.008751)
		(end 129.775458 -394.658342)
		(width 0.14224)
		(layer "In13.Cu")
		(net "P5E_CPU1_P3_RX_BUF_DN<13>")
	)
	(arc
		(start 151.794464 -423.888662)
		(mid 151.882379 -422.995071)
		(end 152.142952 -422.135808)
		(width 0.14224)
		(layer "In13.Cu")
		(net "P5E_CPU1_P3_RX_BUF_DN<13>")
	)
	(segment
		(start 128.918462 -391.578338)
		(end 128.918462 -390.761982)
		(width 0.1016)
		(layer "F.Cu")
		(net "P5E_CPU1_P3_RX_BUF_DN<12>")
	)
	(segment
		(start 128.918462 -390.761982)
		(end 128.917954 -390.761474)
		(width 0.1016)
		(layer "F.Cu")
		(net "P5E_CPU1_P3_RX_BUF_DN<12>")
	)
	(segment
		(start 128.956816 -392.761216)
		(end 128.829816 -392.634216)
		(width 0.1016)
		(layer "F.Cu")
		(net "P5E_CPU1_P3_RX_BUF_DN<12>")
	)
	(segment
		(start 129.31648 -392.429238)
		(end 129.31648 -392.595862)
		(width 0.1016)
		(layer "F.Cu")
		(net "P5E_CPU1_P3_RX_BUF_DN<12>")
	)
	(segment
		(start 128.829816 -392.634216)
		(end 128.829816 -391.666984)
		(width 0.1016)
		(layer "F.Cu")
		(net "P5E_CPU1_P3_RX_BUF_DN<12>")
	)
	(segment
		(start 129.151126 -392.761216)
		(end 128.956816 -392.761216)
		(width 0.1016)
		(layer "F.Cu")
		(net "P5E_CPU1_P3_RX_BUF_DN<12>")
	)
	(segment
		(start 129.31648 -392.595862)
		(end 129.151126 -392.761216)
		(width 0.1016)
		(layer "F.Cu")
		(net "P5E_CPU1_P3_RX_BUF_DN<12>")
	)
	(segment
		(start 128.829816 -391.666984)
		(end 128.918462 -391.578338)
		(width 0.1016)
		(layer "F.Cu")
		(net "P5E_CPU1_P3_RX_BUF_DN<12>")
	)
	(segment
		(start 152.264618 -411.146498)
		(end 152.081738 -410.963618)
		(width 0.14224)
		(layer "In13.Cu")
		(net "P5E_CPU1_P3_RX_BUF_DN<12>")
	)
	(segment
		(start 146.839432 -400.941032)
		(end 146.417284 -400.76628)
		(width 0.14224)
		(layer "In13.Cu")
		(net "P5E_CPU1_P3_RX_BUF_DN<12>")
	)
	(segment
		(start 129.31648 -392.580622)
		(end 129.31648 -392.429238)
		(width 0.14224)
		(layer "In13.Cu")
		(net "P5E_CPU1_P3_RX_BUF_DN<12>")
	)
	(segment
		(start 151.54783 -405.885142)
		(end 151.47925 -405.856694)
		(width 0.14224)
		(layer "In13.Cu")
		(net "P5E_CPU1_P3_RX_BUF_DN<12>")
	)
	(segment
		(start 152.38984 -411.230318)
		(end 152.264618 -411.146498)
		(width 0.14224)
		(layer "In13.Cu")
		(net "P5E_CPU1_P3_RX_BUF_DN<12>")
	)
	(segment
		(start 150.791672 -405.78405)
		(end 150.527258 -405.51989)
		(width 0.14224)
		(layer "In13.Cu")
		(net "P5E_CPU1_P3_RX_BUF_DN<12>")
	)
	(segment
		(start 146.417284 -400.76628)
		(end 146.26844 -400.721068)
		(width 0.14224)
		(layer "In13.Cu")
		(net "P5E_CPU1_P3_RX_BUF_DN<12>")
	)
	(segment
		(start 149.847554 -402.951188)
		(end 146.839432 -400.941032)
		(width 0.14224)
		(layer "In13.Cu")
		(net "P5E_CPU1_P3_RX_BUF_DN<12>")
	)
	(segment
		(start 150.750016 -434.48986)
		(end 150.750016 -434.165756)
		(width 0.14224)
		(layer "In13.Cu")
		(net "P5E_CPU1_P3_RX_BUF_DN<12>")
	)
	(segment
		(start 150.131018 -421.425878)
		(end 153.475436 -413.352234)
		(width 0.14224)
		(layer "In13.Cu")
		(net "P5E_CPU1_P3_RX_BUF_DN<12>")
	)
	(segment
		(start 150.966678 -405.856694)
		(end 150.791672 -405.78405)
		(width 0.14224)
		(layer "In13.Cu")
		(net "P5E_CPU1_P3_RX_BUF_DN<12>")
	)
	(segment
		(start 153.475436 -413.352234)
		(end 153.475436 -412.004002)
		(width 0.14224)
		(layer "In13.Cu")
		(net "P5E_CPU1_P3_RX_BUF_DN<12>")
	)
	(segment
		(start 128.575562 -393.012168)
		(end 128.880108 -392.707622)
		(width 0.14224)
		(layer "In13.Cu")
		(net "P5E_CPU1_P3_RX_BUF_DN<12>")
	)
	(segment
		(start 149.794468 -433.574952)
		(end 149.794468 -423.117772)
		(width 0.14224)
		(layer "In13.Cu")
		(net "P5E_CPU1_P3_RX_BUF_DN<12>")
	)
	(segment
		(start 146.26844 -400.721068)
		(end 135.26389 -398.51584)
		(width 0.14224)
		(layer "In13.Cu")
		(net "P5E_CPU1_P3_RX_BUF_DN<12>")
	)
	(segment
		(start 129.18948 -392.707622)
		(end 129.31648 -392.580622)
		(width 0.14224)
		(layer "In13.Cu")
		(net "P5E_CPU1_P3_RX_BUF_DN<12>")
	)
	(segment
		(start 150.211282 -403.314916)
		(end 149.847554 -402.951188)
		(width 0.14224)
		(layer "In13.Cu")
		(net "P5E_CPU1_P3_RX_BUF_DN<12>")
	)
	(segment
		(start 151.47925 -405.856694)
		(end 150.966678 -405.856694)
		(width 0.14224)
		(layer "In13.Cu")
		(net "P5E_CPU1_P3_RX_BUF_DN<12>")
	)
	(segment
		(start 130.075432 -396.884652)
		(end 128.75133 -395.683486)
		(width 0.14224)
		(layer "In13.Cu")
		(net "P5E_CPU1_P3_RX_BUF_DN<12>")
	)
	(segment
		(start 150.631652 -434.047392)
		(end 150.266908 -434.047392)
		(width 0.14224)
		(layer "In13.Cu")
		(net "P5E_CPU1_P3_RX_BUF_DN<12>")
	)
	(segment
		(start 151.943816 -410.630878)
		(end 151.943816 -406.481026)
		(width 0.14224)
		(layer "In13.Cu")
		(net "P5E_CPU1_P3_RX_BUF_DN<12>")
	)
	(segment
		(start 150.412196 -405.239474)
		(end 150.412196 -403.799802)
		(width 0.14224)
		(layer "In13.Cu")
		(net "P5E_CPU1_P3_RX_BUF_DN<12>")
	)
	(segment
		(start 150.266908 -434.047392)
		(end 149.794468 -433.574952)
		(width 0.14224)
		(layer "In13.Cu")
		(net "P5E_CPU1_P3_RX_BUF_DN<12>")
	)
	(segment
		(start 153.33091 -411.654498)
		(end 153.271982 -411.59557)
		(width 0.14224)
		(layer "In13.Cu")
		(net "P5E_CPU1_P3_RX_BUF_DN<12>")
	)
	(segment
		(start 153.475436 -412.004002)
		(end 153.33091 -411.654498)
		(width 0.14224)
		(layer "In13.Cu")
		(net "P5E_CPU1_P3_RX_BUF_DN<12>")
	)
	(segment
		(start 128.575562 -395.065758)
		(end 128.575562 -393.012168)
		(width 0.14224)
		(layer "In13.Cu")
		(net "P5E_CPU1_P3_RX_BUF_DN<12>")
	)
	(segment
		(start 151.802338 -406.13965)
		(end 151.54783 -405.885142)
		(width 0.14224)
		(layer "In13.Cu")
		(net "P5E_CPU1_P3_RX_BUF_DN<12>")
	)
	(segment
		(start 151.943816 -406.481026)
		(end 151.802338 -406.13965)
		(width 0.14224)
		(layer "In13.Cu")
		(net "P5E_CPU1_P3_RX_BUF_DN<12>")
	)
	(segment
		(start 153.271982 -411.59557)
		(end 152.38984 -411.230318)
		(width 0.14224)
		(layer "In13.Cu")
		(net "P5E_CPU1_P3_RX_BUF_DN<12>")
	)
	(segment
		(start 152.081738 -410.963618)
		(end 151.943816 -410.630878)
		(width 0.14224)
		(layer "In13.Cu")
		(net "P5E_CPU1_P3_RX_BUF_DN<12>")
	)
	(segment
		(start 128.880108 -392.707622)
		(end 129.18948 -392.707622)
		(width 0.14224)
		(layer "In13.Cu")
		(net "P5E_CPU1_P3_RX_BUF_DN<12>")
	)
	(segment
		(start 135.26389 -398.51584)
		(end 130.292094 -397.007334)
		(width 0.14224)
		(layer "In13.Cu")
		(net "P5E_CPU1_P3_RX_BUF_DN<12>")
	)
	(segment
		(start 150.527258 -405.51989)
		(end 150.412196 -405.239474)
		(width 0.14224)
		(layer "In13.Cu")
		(net "P5E_CPU1_P3_RX_BUF_DN<12>")
	)
	(segment
		(start 150.750016 -434.165756)
		(end 150.631652 -434.047392)
		(width 0.14224)
		(layer "In13.Cu")
		(net "P5E_CPU1_P3_RX_BUF_DN<12>")
	)
	(arc
		(start 149.794468 -423.117772)
		(mid 149.879424 -422.255252)
		(end 150.131018 -421.425878)
		(width 0.14224)
		(layer "In13.Cu")
		(net "P5E_CPU1_P3_RX_BUF_DN<12>")
	)
	(arc
		(start 128.75133 -395.683486)
		(mid 128.652959 -395.557978)
		(end 128.601978 -395.40688)
		(width 0.14224)
		(layer "In13.Cu")
		(net "P5E_CPU1_P3_RX_BUF_DN<12>")
	)
	(arc
		(start 130.292094 -397.007334)
		(mid 130.176959 -396.958008)
		(end 130.075432 -396.884652)
		(width 0.14224)
		(layer "In13.Cu")
		(net "P5E_CPU1_P3_RX_BUF_DN<12>")
	)
	(arc
		(start 150.412196 -403.799802)
		(mid 150.359978 -403.537372)
		(end 150.211282 -403.314916)
		(width 0.14224)
		(layer "In13.Cu")
		(net "P5E_CPU1_P3_RX_BUF_DN<12>")
	)
	(arc
		(start 128.601978 -395.40688)
		(mid 128.582129 -395.236833)
		(end 128.575562 -395.065758)
		(width 0.14224)
		(layer "In13.Cu")
		(net "P5E_CPU1_P3_RX_BUF_DN<12>")
	)
	(segment
		(start 127.629666 -391.666984)
		(end 127.718312 -391.578338)
		(width 0.1016)
		(layer "F.Cu")
		(net "P5E_CPU1_P3_RX_BUF_DN<11>")
	)
	(segment
		(start 127.756666 -392.761216)
		(end 127.629666 -392.634216)
		(width 0.1016)
		(layer "F.Cu")
		(net "P5E_CPU1_P3_RX_BUF_DN<11>")
	)
	(segment
		(start 127.629666 -392.634216)
		(end 127.629666 -391.666984)
		(width 0.1016)
		(layer "F.Cu")
		(net "P5E_CPU1_P3_RX_BUF_DN<11>")
	)
	(segment
		(start 127.975614 -392.761216)
		(end 127.756666 -392.761216)
		(width 0.1016)
		(layer "F.Cu")
		(net "P5E_CPU1_P3_RX_BUF_DN<11>")
	)
	(segment
		(start 128.116584 -392.620246)
		(end 127.975614 -392.761216)
		(width 0.1016)
		(layer "F.Cu")
		(net "P5E_CPU1_P3_RX_BUF_DN<11>")
	)
	(segment
		(start 127.718312 -391.578338)
		(end 127.718312 -390.761728)
		(width 0.1016)
		(layer "F.Cu")
		(net "P5E_CPU1_P3_RX_BUF_DN<11>")
	)
	(segment
		(start 128.116584 -392.429238)
		(end 128.116584 -392.620246)
		(width 0.1016)
		(layer "F.Cu")
		(net "P5E_CPU1_P3_RX_BUF_DN<11>")
	)
	(segment
		(start 127.718312 -390.761728)
		(end 127.718058 -390.761474)
		(width 0.1016)
		(layer "F.Cu")
		(net "P5E_CPU1_P3_RX_BUF_DN<11>")
	)
	(segment
		(start 147.728432 -405.78405)
		(end 147.464526 -405.520144)
		(width 0.14224)
		(layer "In13.Cu")
		(net "P5E_CPU1_P3_RX_BUF_DN<11>")
	)
	(segment
		(start 147.464526 -405.520144)
		(end 147.348956 -405.240998)
		(width 0.14224)
		(layer "In13.Cu")
		(net "P5E_CPU1_P3_RX_BUF_DN<11>")
	)
	(segment
		(start 148.613622 -435.029356)
		(end 148.248878 -435.029356)
		(width 0.14224)
		(layer "In13.Cu")
		(net "P5E_CPU1_P3_RX_BUF_DN<11>")
	)
	(segment
		(start 140.406374 -400.757898)
		(end 140.406374 -400.757644)
		(width 0.14224)
		(layer "In13.Cu")
		(net "P5E_CPU1_P3_RX_BUF_DN<11>")
	)
	(segment
		(start 146.689318 -402.633942)
		(end 145.743676 -401.984972)
		(width 0.14224)
		(layer "In13.Cu")
		(net "P5E_CPU1_P3_RX_BUF_DN<11>")
	)
	(segment
		(start 148.880576 -410.630878)
		(end 148.880576 -406.481026)
		(width 0.14224)
		(layer "In13.Cu")
		(net "P5E_CPU1_P3_RX_BUF_DN<11>")
	)
	(segment
		(start 147.903438 -405.856694)
		(end 147.728432 -405.78405)
		(width 0.14224)
		(layer "In13.Cu")
		(net "P5E_CPU1_P3_RX_BUF_DN<11>")
	)
	(segment
		(start 148.10359 -421.249348)
		(end 149.057868 -416.45078)
		(width 0.14224)
		(layer "In13.Cu")
		(net "P5E_CPU1_P3_RX_BUF_DN<11>")
	)
	(segment
		(start 147.794472 -434.57495)
		(end 147.794472 -424.38955)
		(width 0.14224)
		(layer "In13.Cu")
		(net "P5E_CPU1_P3_RX_BUF_DN<11>")
	)
	(segment
		(start 150.208742 -411.59557)
		(end 149.3266 -411.230318)
		(width 0.14224)
		(layer "In13.Cu")
		(net "P5E_CPU1_P3_RX_BUF_DN<11>")
	)
	(segment
		(start 128.116584 -392.580622)
		(end 128.116584 -392.429238)
		(width 0.14224)
		(layer "In13.Cu")
		(net "P5E_CPU1_P3_RX_BUF_DN<11>")
	)
	(segment
		(start 145.62836 -401.93468)
		(end 140.406374 -400.757898)
		(width 0.14224)
		(layer "In13.Cu")
		(net "P5E_CPU1_P3_RX_BUF_DN<11>")
	)
	(segment
		(start 149.057868 -416.45078)
		(end 150.412196 -413.1818)
		(width 0.14224)
		(layer "In13.Cu")
		(net "P5E_CPU1_P3_RX_BUF_DN<11>")
	)
	(segment
		(start 148.41601 -405.856694)
		(end 147.903438 -405.856694)
		(width 0.14224)
		(layer "In13.Cu")
		(net "P5E_CPU1_P3_RX_BUF_DN<11>")
	)
	(segment
		(start 149.201378 -411.146498)
		(end 149.018498 -410.963618)
		(width 0.14224)
		(layer "In13.Cu")
		(net "P5E_CPU1_P3_RX_BUF_DN<11>")
	)
	(segment
		(start 148.880576 -406.481026)
		(end 148.739098 -406.13965)
		(width 0.14224)
		(layer "In13.Cu")
		(net "P5E_CPU1_P3_RX_BUF_DN<11>")
	)
	(segment
		(start 135.402066 -399.54073)
		(end 129.772156 -397.83258)
		(width 0.14224)
		(layer "In13.Cu")
		(net "P5E_CPU1_P3_RX_BUF_DN<11>")
	)
	(segment
		(start 127.375666 -393.012168)
		(end 127.680212 -392.707622)
		(width 0.14224)
		(layer "In13.Cu")
		(net "P5E_CPU1_P3_RX_BUF_DN<11>")
	)
	(segment
		(start 150.412196 -412.003748)
		(end 150.26767 -411.654498)
		(width 0.14224)
		(layer "In13.Cu")
		(net "P5E_CPU1_P3_RX_BUF_DN<11>")
	)
	(segment
		(start 129.555494 -397.710152)
		(end 127.51816 -395.86662)
		(width 0.14224)
		(layer "In13.Cu")
		(net "P5E_CPU1_P3_RX_BUF_DN<11>")
	)
	(segment
		(start 147.348956 -405.240998)
		(end 147.348956 -403.88667)
		(width 0.14224)
		(layer "In13.Cu")
		(net "P5E_CPU1_P3_RX_BUF_DN<11>")
	)
	(segment
		(start 149.018498 -410.963618)
		(end 148.880576 -410.630878)
		(width 0.14224)
		(layer "In13.Cu")
		(net "P5E_CPU1_P3_RX_BUF_DN<11>")
	)
	(segment
		(start 127.680212 -392.707622)
		(end 127.989584 -392.707622)
		(width 0.14224)
		(layer "In13.Cu")
		(net "P5E_CPU1_P3_RX_BUF_DN<11>")
	)
	(segment
		(start 127.375666 -395.544802)
		(end 127.375666 -393.012168)
		(width 0.14224)
		(layer "In13.Cu")
		(net "P5E_CPU1_P3_RX_BUF_DN<11>")
	)
	(segment
		(start 148.248878 -435.029356)
		(end 147.794472 -434.57495)
		(width 0.14224)
		(layer "In13.Cu")
		(net "P5E_CPU1_P3_RX_BUF_DN<11>")
	)
	(segment
		(start 137.419334 -400.082258)
		(end 135.973312 -399.702274)
		(width 0.14224)
		(layer "In13.Cu")
		(net "P5E_CPU1_P3_RX_BUF_DN<11>")
	)
	(segment
		(start 148.48459 -405.885142)
		(end 148.41601 -405.856694)
		(width 0.14224)
		(layer "In13.Cu")
		(net "P5E_CPU1_P3_RX_BUF_DN<11>")
	)
	(segment
		(start 140.406374 -400.757644)
		(end 137.54227 -400.11223)
		(width 0.14224)
		(layer "In13.Cu")
		(net "P5E_CPU1_P3_RX_BUF_DN<11>")
	)
	(segment
		(start 148.75002 -435.489858)
		(end 148.75002 -435.165754)
		(width 0.14224)
		(layer "In13.Cu")
		(net "P5E_CPU1_P3_RX_BUF_DN<11>")
	)
	(segment
		(start 148.75002 -435.165754)
		(end 148.613622 -435.029356)
		(width 0.14224)
		(layer "In13.Cu")
		(net "P5E_CPU1_P3_RX_BUF_DN<11>")
	)
	(segment
		(start 148.739098 -406.13965)
		(end 148.48459 -405.885142)
		(width 0.14224)
		(layer "In13.Cu")
		(net "P5E_CPU1_P3_RX_BUF_DN<11>")
	)
	(segment
		(start 150.26767 -411.654498)
		(end 150.208742 -411.59557)
		(width 0.14224)
		(layer "In13.Cu")
		(net "P5E_CPU1_P3_RX_BUF_DN<11>")
	)
	(segment
		(start 127.989584 -392.707622)
		(end 128.116584 -392.580622)
		(width 0.14224)
		(layer "In13.Cu")
		(net "P5E_CPU1_P3_RX_BUF_DN<11>")
	)
	(segment
		(start 149.3266 -411.230318)
		(end 149.201378 -411.146498)
		(width 0.14224)
		(layer "In13.Cu")
		(net "P5E_CPU1_P3_RX_BUF_DN<11>")
	)
	(segment
		(start 150.412196 -413.1818)
		(end 150.412196 -412.003748)
		(width 0.14224)
		(layer "In13.Cu")
		(net "P5E_CPU1_P3_RX_BUF_DN<11>")
	)
	(arc
		(start 147.794472 -424.38955)
		(mid 147.871918 -422.811859)
		(end 148.10359 -421.249348)
		(width 0.14224)
		(layer "In13.Cu")
		(net "P5E_CPU1_P3_RX_BUF_DN<11>")
	)
	(arc
		(start 137.54227 -400.11223)
		(mid 137.48067 -400.097784)
		(end 137.419334 -400.082258)
		(width 0.14224)
		(layer "In13.Cu")
		(net "P5E_CPU1_P3_RX_BUF_DN<11>")
	)
	(arc
		(start 145.743676 -401.984972)
		(mid 145.68842 -401.954315)
		(end 145.62836 -401.93468)
		(width 0.14224)
		(layer "In13.Cu")
		(net "P5E_CPU1_P3_RX_BUF_DN<11>")
	)
	(arc
		(start 127.51816 -395.86662)
		(mid 127.412801 -395.720818)
		(end 127.375666 -395.544802)
		(width 0.14224)
		(layer "In13.Cu")
		(net "P5E_CPU1_P3_RX_BUF_DN<11>")
	)
	(arc
		(start 135.973312 -399.702274)
		(mid 135.686926 -399.624201)
		(end 135.402066 -399.54073)
		(width 0.14224)
		(layer "In13.Cu")
		(net "P5E_CPU1_P3_RX_BUF_DN<11>")
	)
	(arc
		(start 129.772156 -397.83258)
		(mid 129.657041 -397.783367)
		(end 129.555494 -397.710152)
		(width 0.14224)
		(layer "In13.Cu")
		(net "P5E_CPU1_P3_RX_BUF_DN<11>")
	)
	(arc
		(start 147.348956 -403.88667)
		(mid 147.173975 -403.17877)
		(end 146.689318 -402.633942)
		(width 0.14224)
		(layer "In13.Cu")
		(net "P5E_CPU1_P3_RX_BUF_DN<11>")
	)
	(segment
		(start 126.775718 -392.761216)
		(end 126.55677 -392.761216)
		(width 0.1016)
		(layer "F.Cu")
		(net "P5E_CPU1_P3_RX_BUF_DN<10>")
	)
	(segment
		(start 126.916688 -392.429238)
		(end 126.916688 -392.620246)
		(width 0.1016)
		(layer "F.Cu")
		(net "P5E_CPU1_P3_RX_BUF_DN<10>")
	)
	(segment
		(start 126.42977 -391.666984)
		(end 126.517908 -391.578846)
		(width 0.1016)
		(layer "F.Cu")
		(net "P5E_CPU1_P3_RX_BUF_DN<10>")
	)
	(segment
		(start 126.916688 -392.620246)
		(end 126.775718 -392.761216)
		(width 0.1016)
		(layer "F.Cu")
		(net "P5E_CPU1_P3_RX_BUF_DN<10>")
	)
	(segment
		(start 126.42977 -392.634216)
		(end 126.42977 -391.666984)
		(width 0.1016)
		(layer "F.Cu")
		(net "P5E_CPU1_P3_RX_BUF_DN<10>")
	)
	(segment
		(start 126.55677 -392.761216)
		(end 126.42977 -392.634216)
		(width 0.1016)
		(layer "F.Cu")
		(net "P5E_CPU1_P3_RX_BUF_DN<10>")
	)
	(segment
		(start 126.517908 -391.578846)
		(end 126.517908 -390.761474)
		(width 0.1016)
		(layer "F.Cu")
		(net "P5E_CPU1_P3_RX_BUF_DN<10>")
	)
	(segment
		(start 146.289522 -411.24124)
		(end 147.060158 -411.560264)
		(width 0.14224)
		(layer "In13.Cu")
		(net "P5E_CPU1_P3_RX_BUF_DN<10>")
	)
	(segment
		(start 145.675858 -406.13965)
		(end 145.817336 -406.481026)
		(width 0.14224)
		(layer "In13.Cu")
		(net "P5E_CPU1_P3_RX_BUF_DN<10>")
	)
	(segment
		(start 126.916688 -392.580622)
		(end 126.789688 -392.707622)
		(width 0.14224)
		(layer "In13.Cu")
		(net "P5E_CPU1_P3_RX_BUF_DN<10>")
	)
	(segment
		(start 129.268474 -398.663922)
		(end 143.555212 -402.996146)
		(width 0.14224)
		(layer "In13.Cu")
		(net "P5E_CPU1_P3_RX_BUF_DN<10>")
	)
	(segment
		(start 126.17577 -393.012168)
		(end 126.17577 -395.780006)
		(width 0.14224)
		(layer "In13.Cu")
		(net "P5E_CPU1_P3_RX_BUF_DN<10>")
	)
	(segment
		(start 126.789688 -392.707622)
		(end 126.480316 -392.707622)
		(width 0.14224)
		(layer "In13.Cu")
		(net "P5E_CPU1_P3_RX_BUF_DN<10>")
	)
	(segment
		(start 126.381256 -396.276068)
		(end 128.273556 -398.168368)
		(width 0.14224)
		(layer "In13.Cu")
		(net "P5E_CPU1_P3_RX_BUF_DN<10>")
	)
	(segment
		(start 145.817336 -410.630878)
		(end 145.955258 -410.963618)
		(width 0.14224)
		(layer "In13.Cu")
		(net "P5E_CPU1_P3_RX_BUF_DN<10>")
	)
	(segment
		(start 147.031202 -415.809684)
		(end 147.030694 -415.809684)
		(width 0.14224)
		(layer "In13.Cu")
		(net "P5E_CPU1_P3_RX_BUF_DN<10>")
	)
	(segment
		(start 146.750024 -434.165756)
		(end 146.750024 -434.48986)
		(width 0.14224)
		(layer "In13.Cu")
		(net "P5E_CPU1_P3_RX_BUF_DN<10>")
	)
	(segment
		(start 145.90141 -423.424858)
		(end 145.794476 -424.875452)
		(width 0.14224)
		(layer "In13.Cu")
		(net "P5E_CPU1_P3_RX_BUF_DN<10>")
	)
	(segment
		(start 144.568926 -405.761698)
		(end 144.798288 -405.856694)
		(width 0.14224)
		(layer "In13.Cu")
		(net "P5E_CPU1_P3_RX_BUF_DN<10>")
	)
	(segment
		(start 145.794476 -433.574952)
		(end 146.234404 -434.01488)
		(width 0.14224)
		(layer "In13.Cu")
		(net "P5E_CPU1_P3_RX_BUF_DN<10>")
	)
	(segment
		(start 128.273556 -398.168368)
		(end 129.104136 -398.597374)
		(width 0.14224)
		(layer "In13.Cu")
		(net "P5E_CPU1_P3_RX_BUF_DN<10>")
	)
	(segment
		(start 144.499076 -405.691848)
		(end 144.568926 -405.761698)
		(width 0.14224)
		(layer "In13.Cu")
		(net "P5E_CPU1_P3_RX_BUF_DN<10>")
	)
	(segment
		(start 144.798288 -405.856694)
		(end 145.35277 -405.856694)
		(width 0.14224)
		(layer "In13.Cu")
		(net "P5E_CPU1_P3_RX_BUF_DN<10>")
	)
	(segment
		(start 144.222724 -403.407118)
		(end 144.261586 -403.499066)
		(width 0.14224)
		(layer "In13.Cu")
		(net "P5E_CPU1_P3_RX_BUF_DN<10>")
	)
	(segment
		(start 147.030694 -415.809684)
		(end 145.90141 -423.424858)
		(width 0.14224)
		(layer "In13.Cu")
		(net "P5E_CPU1_P3_RX_BUF_DN<10>")
	)
	(segment
		(start 146.234404 -434.01488)
		(end 146.599148 -434.01488)
		(width 0.14224)
		(layer "In13.Cu")
		(net "P5E_CPU1_P3_RX_BUF_DN<10>")
	)
	(segment
		(start 147.348956 -412.122874)
		(end 147.348956 -413.664908)
		(width 0.14224)
		(layer "In13.Cu")
		(net "P5E_CPU1_P3_RX_BUF_DN<10>")
	)
	(segment
		(start 126.480316 -392.707622)
		(end 126.17577 -393.012168)
		(width 0.14224)
		(layer "In13.Cu")
		(net "P5E_CPU1_P3_RX_BUF_DN<10>")
	)
	(segment
		(start 145.35277 -405.856694)
		(end 145.42135 -405.885142)
		(width 0.14224)
		(layer "In13.Cu")
		(net "P5E_CPU1_P3_RX_BUF_DN<10>")
	)
	(segment
		(start 147.348956 -413.664908)
		(end 147.031202 -415.809684)
		(width 0.14224)
		(layer "In13.Cu")
		(net "P5E_CPU1_P3_RX_BUF_DN<10>")
	)
	(segment
		(start 144.285716 -403.620986)
		(end 144.285716 -405.176736)
		(width 0.14224)
		(layer "In13.Cu")
		(net "P5E_CPU1_P3_RX_BUF_DN<10>")
	)
	(segment
		(start 143.876776 -403.139148)
		(end 144.112742 -403.280372)
		(width 0.14224)
		(layer "In13.Cu")
		(net "P5E_CPU1_P3_RX_BUF_DN<10>")
	)
	(segment
		(start 145.42135 -405.885142)
		(end 145.675858 -406.13965)
		(width 0.14224)
		(layer "In13.Cu")
		(net "P5E_CPU1_P3_RX_BUF_DN<10>")
	)
	(segment
		(start 146.599148 -434.01488)
		(end 146.750024 -434.165756)
		(width 0.14224)
		(layer "In13.Cu")
		(net "P5E_CPU1_P3_RX_BUF_DN<10>")
	)
	(segment
		(start 145.794476 -424.875452)
		(end 145.794476 -433.574952)
		(width 0.14224)
		(layer "In13.Cu")
		(net "P5E_CPU1_P3_RX_BUF_DN<10>")
	)
	(segment
		(start 145.817336 -406.481026)
		(end 145.817336 -410.630878)
		(width 0.14224)
		(layer "In13.Cu")
		(net "P5E_CPU1_P3_RX_BUF_DN<10>")
	)
	(segment
		(start 145.955258 -410.963618)
		(end 146.11858 -411.12694)
		(width 0.14224)
		(layer "In13.Cu")
		(net "P5E_CPU1_P3_RX_BUF_DN<10>")
	)
	(segment
		(start 126.916688 -392.429238)
		(end 126.916688 -392.580622)
		(width 0.14224)
		(layer "In13.Cu")
		(net "P5E_CPU1_P3_RX_BUF_DN<10>")
	)
	(arc
		(start 126.17577 -395.780006)
		(mid 126.229172 -396.048477)
		(end 126.381256 -396.276068)
		(width 0.14224)
		(layer "In13.Cu")
		(net "P5E_CPU1_P3_RX_BUF_DN<10>")
	)
	(arc
		(start 147.060158 -411.560264)
		(mid 147.115175 -411.593052)
		(end 147.158456 -411.640274)
		(width 0.14224)
		(layer "In13.Cu")
		(net "P5E_CPU1_P3_RX_BUF_DN<10>")
	)
	(arc
		(start 147.245324 -411.771846)
		(mid 147.322548 -411.93986)
		(end 147.348956 -412.122874)
		(width 0.14224)
		(layer "In13.Cu")
		(net "P5E_CPU1_P3_RX_BUF_DN<10>")
	)
	(arc
		(start 144.261586 -403.499066)
		(mid 144.27959 -403.55885)
		(end 144.285716 -403.620986)
		(width 0.14224)
		(layer "In13.Cu")
		(net "P5E_CPU1_P3_RX_BUF_DN<10>")
	)
	(arc
		(start 146.11858 -411.12694)
		(mid 146.198423 -411.192505)
		(end 146.289522 -411.24124)
		(width 0.14224)
		(layer "In13.Cu")
		(net "P5E_CPU1_P3_RX_BUF_DN<10>")
	)
	(arc
		(start 144.285716 -405.176736)
		(mid 144.341168 -405.45551)
		(end 144.499076 -405.691848)
		(width 0.14224)
		(layer "In13.Cu")
		(net "P5E_CPU1_P3_RX_BUF_DN<10>")
	)
	(arc
		(start 143.555212 -402.996146)
		(mid 143.720346 -403.057862)
		(end 143.876776 -403.139148)
		(width 0.14224)
		(layer "In13.Cu")
		(net "P5E_CPU1_P3_RX_BUF_DN<10>")
	)
	(arc
		(start 144.112742 -403.280372)
		(mid 144.177889 -403.334939)
		(end 144.222724 -403.407118)
		(width 0.14224)
		(layer "In13.Cu")
		(net "P5E_CPU1_P3_RX_BUF_DN<10>")
	)
	(arc
		(start 147.158456 -411.640274)
		(mid 147.202213 -411.705847)
		(end 147.245324 -411.771846)
		(width 0.14224)
		(layer "In13.Cu")
		(net "P5E_CPU1_P3_RX_BUF_DN<10>")
	)
	(arc
		(start 129.104136 -398.597374)
		(mid 129.184805 -398.634352)
		(end 129.268474 -398.663922)
		(width 0.14224)
		(layer "In13.Cu")
		(net "P5E_CPU1_P3_RX_BUF_DN<10>")
	)
	(segment
		(start 114.407442 -392.611864)
		(end 114.556794 -392.761216)
		(width 0.1016)
		(layer "F.Cu")
		(net "P5E_CPU1_P3_RX_BUF_DN<0>")
	)
	(segment
		(start 114.517932 -390.761474)
		(end 114.51844 -390.761982)
		(width 0.1016)
		(layer "F.Cu")
		(net "P5E_CPU1_P3_RX_BUF_DN<0>")
	)
	(segment
		(start 114.407442 -391.689336)
		(end 114.407442 -392.611864)
		(width 0.1016)
		(layer "F.Cu")
		(net "P5E_CPU1_P3_RX_BUF_DN<0>")
	)
	(segment
		(start 114.51844 -391.578338)
		(end 114.407442 -391.689336)
		(width 0.1016)
		(layer "F.Cu")
		(net "P5E_CPU1_P3_RX_BUF_DN<0>")
	)
	(segment
		(start 114.556794 -392.761216)
		(end 114.775742 -392.761216)
		(width 0.1016)
		(layer "F.Cu")
		(net "P5E_CPU1_P3_RX_BUF_DN<0>")
	)
	(segment
		(start 114.51844 -390.761982)
		(end 114.51844 -391.578338)
		(width 0.1016)
		(layer "F.Cu")
		(net "P5E_CPU1_P3_RX_BUF_DN<0>")
	)
	(segment
		(start 114.775742 -392.761216)
		(end 114.916458 -392.6205)
		(width 0.1016)
		(layer "F.Cu")
		(net "P5E_CPU1_P3_RX_BUF_DN<0>")
	)
	(segment
		(start 114.916458 -392.6205)
		(end 114.916458 -392.429238)
		(width 0.1016)
		(layer "F.Cu")
		(net "P5E_CPU1_P3_RX_BUF_DN<0>")
	)
	(segment
		(start 113.768886 -405.520144)
		(end 113.647982 -405.228298)
		(width 0.14224)
		(layer "In13.Cu")
		(net "P5E_CPU1_P3_RX_BUF_DN<0>")
	)
	(segment
		(start 116.878608 -413.771334)
		(end 116.747544 -413.454596)
		(width 0.14224)
		(layer "In13.Cu")
		(net "P5E_CPU1_P3_RX_BUF_DN<0>")
	)
	(segment
		(start 114.17554 -401.88007)
		(end 114.17554 -393.012168)
		(width 0.14224)
		(layer "In13.Cu")
		(net "P5E_CPU1_P3_RX_BUF_DN<0>")
	)
	(segment
		(start 125.749812 -434.48986)
		(end 125.749812 -434.165756)
		(width 0.14224)
		(layer "In13.Cu")
		(net "P5E_CPU1_P3_RX_BUF_DN<0>")
	)
	(segment
		(start 124.775214 -433.915058)
		(end 124.7267 -433.866544)
		(width 0.14224)
		(layer "In13.Cu")
		(net "P5E_CPU1_P3_RX_BUF_DN<0>")
	)
	(segment
		(start 114.17554 -393.012168)
		(end 114.480086 -392.707622)
		(width 0.14224)
		(layer "In13.Cu")
		(net "P5E_CPU1_P3_RX_BUF_DN<0>")
	)
	(segment
		(start 113.6904 -403.816058)
		(end 114.17554 -401.88007)
		(width 0.14224)
		(layer "In13.Cu")
		(net "P5E_CPU1_P3_RX_BUF_DN<0>")
	)
	(segment
		(start 114.655854 -405.856694)
		(end 114.207798 -405.856694)
		(width 0.14224)
		(layer "In13.Cu")
		(net "P5E_CPU1_P3_RX_BUF_DN<0>")
	)
	(segment
		(start 114.789458 -392.707622)
		(end 114.916458 -392.580622)
		(width 0.14224)
		(layer "In13.Cu")
		(net "P5E_CPU1_P3_RX_BUF_DN<0>")
	)
	(segment
		(start 116.716556 -413.297878)
		(end 116.716556 -412.030418)
		(width 0.14224)
		(layer "In13.Cu")
		(net "P5E_CPU1_P3_RX_BUF_DN<0>")
	)
	(segment
		(start 115.184936 -410.631132)
		(end 115.184936 -406.481026)
		(width 0.14224)
		(layer "In13.Cu")
		(net "P5E_CPU1_P3_RX_BUF_DN<0>")
	)
	(segment
		(start 114.480086 -392.707622)
		(end 114.789458 -392.707622)
		(width 0.14224)
		(layer "In13.Cu")
		(net "P5E_CPU1_P3_RX_BUF_DN<0>")
	)
	(segment
		(start 114.033046 -405.784304)
		(end 113.768886 -405.520144)
		(width 0.14224)
		(layer "In13.Cu")
		(net "P5E_CPU1_P3_RX_BUF_DN<0>")
	)
	(segment
		(start 113.647982 -405.228298)
		(end 113.647982 -404.029672)
		(width 0.14224)
		(layer "In13.Cu")
		(net "P5E_CPU1_P3_RX_BUF_DN<0>")
	)
	(segment
		(start 115.117626 -406.318466)
		(end 114.655854 -405.856694)
		(width 0.14224)
		(layer "In13.Cu")
		(net "P5E_CPU1_P3_RX_BUF_DN<0>")
	)
	(segment
		(start 116.716556 -412.030418)
		(end 116.716302 -412.030672)
		(width 0.14224)
		(layer "In13.Cu")
		(net "P5E_CPU1_P3_RX_BUF_DN<0>")
	)
	(segment
		(start 125.749812 -434.165756)
		(end 125.622812 -434.038756)
		(width 0.14224)
		(layer "In13.Cu")
		(net "P5E_CPU1_P3_RX_BUF_DN<0>")
	)
	(segment
		(start 115.311682 -410.936694)
		(end 115.184936 -410.631132)
		(width 0.14224)
		(layer "In13.Cu")
		(net "P5E_CPU1_P3_RX_BUF_DN<0>")
	)
	(segment
		(start 115.184936 -406.481026)
		(end 115.117626 -406.318466)
		(width 0.14224)
		(layer "In13.Cu")
		(net "P5E_CPU1_P3_RX_BUF_DN<0>")
	)
	(segment
		(start 114.207798 -405.856694)
		(end 114.033046 -405.784304)
		(width 0.14224)
		(layer "In13.Cu")
		(net "P5E_CPU1_P3_RX_BUF_DN<0>")
	)
	(segment
		(start 124.606812 -433.577238)
		(end 124.606812 -417.529518)
		(width 0.14224)
		(layer "In13.Cu")
		(net "P5E_CPU1_P3_RX_BUF_DN<0>")
	)
	(segment
		(start 124.083826 -417.056316)
		(end 117.297962 -414.245552)
		(width 0.14224)
		(layer "In13.Cu")
		(net "P5E_CPU1_P3_RX_BUF_DN<0>")
	)
	(segment
		(start 113.647982 -404.029672)
		(end 113.6904 -403.816058)
		(width 0.14224)
		(layer "In13.Cu")
		(net "P5E_CPU1_P3_RX_BUF_DN<0>")
	)
	(segment
		(start 125.622812 -434.038756)
		(end 125.07341 -434.038756)
		(width 0.14224)
		(layer "In13.Cu")
		(net "P5E_CPU1_P3_RX_BUF_DN<0>")
	)
	(segment
		(start 116.637816 -411.615636)
		(end 115.532662 -411.157674)
		(width 0.14224)
		(layer "In13.Cu")
		(net "P5E_CPU1_P3_RX_BUF_DN<0>")
	)
	(segment
		(start 124.569474 -417.439348)
		(end 124.392944 -417.262818)
		(width 0.14224)
		(layer "In13.Cu")
		(net "P5E_CPU1_P3_RX_BUF_DN<0>")
	)
	(segment
		(start 116.716302 -412.030672)
		(end 116.716302 -411.733238)
		(width 0.14224)
		(layer "In13.Cu")
		(net "P5E_CPU1_P3_RX_BUF_DN<0>")
	)
	(segment
		(start 114.916458 -392.580622)
		(end 114.916458 -392.429238)
		(width 0.14224)
		(layer "In13.Cu")
		(net "P5E_CPU1_P3_RX_BUF_DN<0>")
	)
	(arc
		(start 124.392944 -417.262818)
		(mid 124.248547 -417.144358)
		(end 124.083826 -417.056316)
		(width 0.14224)
		(layer "In13.Cu")
		(net "P5E_CPU1_P3_RX_BUF_DN<0>")
	)
	(arc
		(start 116.967254 -413.934148)
		(mid 116.918642 -413.855076)
		(end 116.878608 -413.771334)
		(width 0.14224)
		(layer "In13.Cu")
		(net "P5E_CPU1_P3_RX_BUF_DN<0>")
	)
	(arc
		(start 115.532662 -411.157674)
		(mid 115.400229 -411.069127)
		(end 115.311682 -410.936694)
		(width 0.14224)
		(layer "In13.Cu")
		(net "P5E_CPU1_P3_RX_BUF_DN<0>")
	)
	(arc
		(start 117.297962 -414.245552)
		(mid 117.157376 -414.162999)
		(end 117.044978 -414.044892)
		(width 0.14224)
		(layer "In13.Cu")
		(net "P5E_CPU1_P3_RX_BUF_DN<0>")
	)
	(arc
		(start 116.747544 -413.454596)
		(mid 116.724341 -413.377762)
		(end 116.716556 -413.297878)
		(width 0.14224)
		(layer "In13.Cu")
		(net "P5E_CPU1_P3_RX_BUF_DN<0>")
	)
	(arc
		(start 117.044978 -414.044892)
		(mid 117.005892 -413.989677)
		(end 116.967254 -413.934148)
		(width 0.14224)
		(layer "In13.Cu")
		(net "P5E_CPU1_P3_RX_BUF_DN<0>")
	)
	(arc
		(start 124.606812 -417.529518)
		(mid 124.597106 -417.480723)
		(end 124.569474 -417.439348)
		(width 0.14224)
		(layer "In13.Cu")
		(net "P5E_CPU1_P3_RX_BUF_DN<0>")
	)
	(arc
		(start 124.7267 -433.866544)
		(mid 124.637956 -433.733824)
		(end 124.606812 -433.577238)
		(width 0.14224)
		(layer "In13.Cu")
		(net "P5E_CPU1_P3_RX_BUF_DN<0>")
	)
	(arc
		(start 116.716302 -411.733238)
		(mid 116.69487 -411.662561)
		(end 116.637816 -411.615636)
		(width 0.14224)
		(layer "In13.Cu")
		(net "P5E_CPU1_P3_RX_BUF_DN<0>")
	)
	(arc
		(start 125.07341 -434.038756)
		(mid 124.911998 -434.006573)
		(end 124.775214 -433.915058)
		(width 0.14224)
		(layer "In13.Cu")
		(net "P5E_CPU1_P3_RX_BUF_DN<0>")
	)
	(segment
		(start 143.056356 -407.954734)
		(end 143.056356 -404.73503)
		(width 0.12954)
		(layer "F.Cu")
		(net "P5E_CPU1_P2_TX_BUF_DP<9>")
	)
	(segment
		(start 158.098236 -389.467344)
		(end 158.618936 -389.467344)
		(width 0.127)
		(layer "F.Cu")
		(net "P5E_CPU1_P2_TX_BUF_DP<9>")
	)
	(segment
		(start 143.056356 -404.73503)
		(end 143.326866 -404.46452)
		(width 0.12954)
		(layer "F.Cu")
		(net "P5E_CPU1_P2_TX_BUF_DP<9>")
	)
	(segment
		(start 143.352266 -408.250644)
		(end 143.056356 -407.954734)
		(width 0.12954)
		(layer "F.Cu")
		(net "P5E_CPU1_P2_TX_BUF_DP<9>")
	)
	(segment
		(start 158.219394 -389.457184)
		(end 158.219394 -389.515858)
		(width 0.14224)
		(layer "In4.Cu")
		(net "P5E_CPU1_P2_TX_BUF_DP<9>")
	)
	(segment
		(start 157.703774 -395.562074)
		(end 154.347926 -398.917922)
		(width 0.14224)
		(layer "In4.Cu")
		(net "P5E_CPU1_P2_TX_BUF_DP<9>")
	)
	(segment
		(start 158.595314 -390.122918)
		(end 158.595314 -390.476486)
		(width 0.14224)
		(layer "In4.Cu")
		(net "P5E_CPU1_P2_TX_BUF_DP<9>")
	)
	(segment
		(start 157.960822 -394.451586)
		(end 157.960822 -394.878306)
		(width 0.14224)
		(layer "In4.Cu")
		(net "P5E_CPU1_P2_TX_BUF_DP<9>")
	)
	(segment
		(start 158.504128 -389.352536)
		(end 158.324042 -389.352536)
		(width 0.14224)
		(layer "In4.Cu")
		(net "P5E_CPU1_P2_TX_BUF_DP<9>")
	)
	(segment
		(start 158.324042 -389.352536)
		(end 158.219394 -389.457184)
		(width 0.14224)
		(layer "In4.Cu")
		(net "P5E_CPU1_P2_TX_BUF_DP<9>")
	)
	(segment
		(start 158.298134 -389.70585)
		(end 158.510478 -389.918194)
		(width 0.14224)
		(layer "In4.Cu")
		(net "P5E_CPU1_P2_TX_BUF_DP<9>")
	)
	(segment
		(start 143.036036 -404.17369)
		(end 143.326866 -404.46452)
		(width 0.14224)
		(layer "In4.Cu")
		(net "P5E_CPU1_P2_TX_BUF_DP<9>")
	)
	(segment
		(start 143.036036 -403.849078)
		(end 143.036036 -404.17369)
		(width 0.14224)
		(layer "In4.Cu")
		(net "P5E_CPU1_P2_TX_BUF_DP<9>")
	)
	(segment
		(start 144.962372 -402.968968)
		(end 144.786858 -402.886164)
		(width 0.14224)
		(layer "In4.Cu")
		(net "P5E_CPU1_P2_TX_BUF_DP<9>")
	)
	(segment
		(start 145.447258 -402.64969)
		(end 145.3642 -402.825204)
		(width 0.14224)
		(layer "In4.Cu")
		(net "P5E_CPU1_P2_TX_BUF_DP<9>")
	)
	(segment
		(start 145.3642 -402.825204)
		(end 144.962372 -402.968968)
		(width 0.14224)
		(layer "In4.Cu")
		(net "P5E_CPU1_P2_TX_BUF_DP<9>")
	)
	(segment
		(start 157.823662 -395.015466)
		(end 157.823662 -395.272768)
		(width 0.14224)
		(layer "In4.Cu")
		(net "P5E_CPU1_P2_TX_BUF_DP<9>")
	)
	(segment
		(start 144.30248 -403.205188)
		(end 143.900398 -403.348952)
		(width 0.14224)
		(layer "In4.Cu")
		(net "P5E_CPU1_P2_TX_BUF_DP<9>")
	)
	(segment
		(start 152.527254 -400.134328)
		(end 149.055582 -401.572476)
		(width 0.14224)
		(layer "In4.Cu")
		(net "P5E_CPU1_P2_TX_BUF_DP<9>")
	)
	(segment
		(start 145.756884 -402.538946)
		(end 145.447258 -402.64969)
		(width 0.14224)
		(layer "In4.Cu")
		(net "P5E_CPU1_P2_TX_BUF_DP<9>")
	)
	(segment
		(start 157.960822 -394.878306)
		(end 157.823662 -395.015466)
		(width 0.14224)
		(layer "In4.Cu")
		(net "P5E_CPU1_P2_TX_BUF_DP<9>")
	)
	(segment
		(start 157.823662 -394.314426)
		(end 157.960822 -394.451586)
		(width 0.14224)
		(layer "In4.Cu")
		(net "P5E_CPU1_P2_TX_BUF_DP<9>")
	)
	(segment
		(start 149.055582 -401.572476)
		(end 145.756884 -402.538946)
		(width 0.14224)
		(layer "In4.Cu")
		(net "P5E_CPU1_P2_TX_BUF_DP<9>")
	)
	(segment
		(start 143.264382 -403.43074)
		(end 143.170656 -403.524212)
		(width 0.14224)
		(layer "In4.Cu")
		(net "P5E_CPU1_P2_TX_BUF_DP<9>")
	)
	(segment
		(start 144.786858 -402.886164)
		(end 144.385284 -403.029674)
		(width 0.14224)
		(layer "In4.Cu")
		(net "P5E_CPU1_P2_TX_BUF_DP<9>")
	)
	(segment
		(start 143.900398 -403.348952)
		(end 143.725138 -403.265894)
		(width 0.14224)
		(layer "In4.Cu")
		(net "P5E_CPU1_P2_TX_BUF_DP<9>")
	)
	(segment
		(start 144.385284 -403.029674)
		(end 144.30248 -403.205188)
		(width 0.14224)
		(layer "In4.Cu")
		(net "P5E_CPU1_P2_TX_BUF_DP<9>")
	)
	(segment
		(start 158.618936 -389.467344)
		(end 158.504128 -389.352536)
		(width 0.14224)
		(layer "In4.Cu")
		(net "P5E_CPU1_P2_TX_BUF_DP<9>")
	)
	(segment
		(start 143.725138 -403.265894)
		(end 143.264382 -403.43074)
		(width 0.14224)
		(layer "In4.Cu")
		(net "P5E_CPU1_P2_TX_BUF_DP<9>")
	)
	(segment
		(start 158.319978 -391.141204)
		(end 157.870906 -391.590276)
		(width 0.14224)
		(layer "In4.Cu")
		(net "P5E_CPU1_P2_TX_BUF_DP<9>")
	)
	(segment
		(start 157.823662 -391.704322)
		(end 157.823662 -394.314426)
		(width 0.14224)
		(layer "In4.Cu")
		(net "P5E_CPU1_P2_TX_BUF_DP<9>")
	)
	(arc
		(start 158.595314 -390.476486)
		(mid 158.523757 -390.836229)
		(end 158.319978 -391.141204)
		(width 0.14224)
		(layer "In4.Cu")
		(net "P5E_CPU1_P2_TX_BUF_DP<9>")
	)
	(arc
		(start 158.510478 -389.918194)
		(mid 158.573239 -390.012122)
		(end 158.595314 -390.122918)
		(width 0.14224)
		(layer "In4.Cu")
		(net "P5E_CPU1_P2_TX_BUF_DP<9>")
	)
	(arc
		(start 157.823662 -395.272768)
		(mid 157.792499 -395.429346)
		(end 157.703774 -395.562074)
		(width 0.14224)
		(layer "In4.Cu")
		(net "P5E_CPU1_P2_TX_BUF_DP<9>")
	)
	(arc
		(start 143.170656 -403.524212)
		(mid 143.07101 -403.673248)
		(end 143.036036 -403.849078)
		(width 0.14224)
		(layer "In4.Cu")
		(net "P5E_CPU1_P2_TX_BUF_DP<9>")
	)
	(arc
		(start 158.219394 -389.515858)
		(mid 158.23988 -389.618669)
		(end 158.298134 -389.70585)
		(width 0.14224)
		(layer "In4.Cu")
		(net "P5E_CPU1_P2_TX_BUF_DP<9>")
	)
	(arc
		(start 154.347926 -398.917922)
		(mid 153.497486 -399.615772)
		(end 152.527254 -400.134328)
		(width 0.14224)
		(layer "In4.Cu")
		(net "P5E_CPU1_P2_TX_BUF_DP<9>")
	)
	(arc
		(start 157.870906 -391.590276)
		(mid 157.835944 -391.642601)
		(end 157.823662 -391.704322)
		(width 0.14224)
		(layer "In4.Cu")
		(net "P5E_CPU1_P2_TX_BUF_DP<9>")
	)
	(segment
		(start 140.289026 -408.250644)
		(end 139.993116 -407.954734)
		(width 0.12954)
		(layer "F.Cu")
		(net "P5E_CPU1_P2_TX_BUF_DP<8>")
	)
	(segment
		(start 139.993116 -404.73503)
		(end 140.263626 -404.46452)
		(width 0.12954)
		(layer "F.Cu")
		(net "P5E_CPU1_P2_TX_BUF_DP<8>")
	)
	(segment
		(start 139.993116 -407.954734)
		(end 139.993116 -404.73503)
		(width 0.12954)
		(layer "F.Cu")
		(net "P5E_CPU1_P2_TX_BUF_DP<8>")
	)
	(segment
		(start 156.89834 -389.467344)
		(end 157.41904 -389.467344)
		(width 0.127)
		(layer "F.Cu")
		(net "P5E_CPU1_P2_TX_BUF_DP<8>")
	)
	(segment
		(start 143.188182 -402.256752)
		(end 143.10995 -402.434552)
		(width 0.14224)
		(layer "In4.Cu")
		(net "P5E_CPU1_P2_TX_BUF_DP<8>")
	)
	(segment
		(start 141.087348 -403.074124)
		(end 141.01953 -403.229826)
		(width 0.14224)
		(layer "In4.Cu")
		(net "P5E_CPU1_P2_TX_BUF_DP<8>")
	)
	(segment
		(start 140.621512 -403.384766)
		(end 140.466064 -403.315932)
		(width 0.14224)
		(layer "In4.Cu")
		(net "P5E_CPU1_P2_TX_BUF_DP<8>")
	)
	(segment
		(start 157.41904 -389.467344)
		(end 157.304232 -389.352536)
		(width 0.14224)
		(layer "In4.Cu")
		(net "P5E_CPU1_P2_TX_BUF_DP<8>")
	)
	(segment
		(start 152.14473 -399.280634)
		(end 148.98624 -400.58848)
		(width 0.14224)
		(layer "In4.Cu")
		(net "P5E_CPU1_P2_TX_BUF_DP<8>")
	)
	(segment
		(start 157.124146 -389.352536)
		(end 157.034738 -389.441944)
		(width 0.14224)
		(layer "In4.Cu")
		(net "P5E_CPU1_P2_TX_BUF_DP<8>")
	)
	(segment
		(start 145.966434 -401.425918)
		(end 143.585692 -402.102066)
		(width 0.14224)
		(layer "In4.Cu")
		(net "P5E_CPU1_P2_TX_BUF_DP<8>")
	)
	(segment
		(start 139.972796 -404.17369)
		(end 140.263626 -404.46452)
		(width 0.14224)
		(layer "In4.Cu")
		(net "P5E_CPU1_P2_TX_BUF_DP<8>")
	)
	(segment
		(start 142.058898 -402.843492)
		(end 141.661134 -402.998178)
		(width 0.14224)
		(layer "In4.Cu")
		(net "P5E_CPU1_P2_TX_BUF_DP<8>")
	)
	(segment
		(start 157.084522 -391.166604)
		(end 156.611828 -391.639552)
		(width 0.14224)
		(layer "In4.Cu")
		(net "P5E_CPU1_P2_TX_BUF_DP<8>")
	)
	(segment
		(start 143.10995 -402.434552)
		(end 142.712186 -402.589238)
		(width 0.14224)
		(layer "In4.Cu")
		(net "P5E_CPU1_P2_TX_BUF_DP<8>")
	)
	(segment
		(start 142.712186 -402.589238)
		(end 142.53464 -402.511006)
		(width 0.14224)
		(layer "In4.Cu")
		(net "P5E_CPU1_P2_TX_BUF_DP<8>")
	)
	(segment
		(start 157.304232 -389.352536)
		(end 157.124146 -389.352536)
		(width 0.14224)
		(layer "In4.Cu")
		(net "P5E_CPU1_P2_TX_BUF_DP<8>")
	)
	(segment
		(start 141.661134 -402.998178)
		(end 141.483588 -402.919946)
		(width 0.14224)
		(layer "In4.Cu")
		(net "P5E_CPU1_P2_TX_BUF_DP<8>")
	)
	(segment
		(start 140.202158 -403.418548)
		(end 140.061188 -403.559518)
		(width 0.14224)
		(layer "In4.Cu")
		(net "P5E_CPU1_P2_TX_BUF_DP<8>")
	)
	(segment
		(start 157.034738 -389.441944)
		(end 157.034738 -389.49376)
		(width 0.14224)
		(layer "In4.Cu")
		(net "P5E_CPU1_P2_TX_BUF_DP<8>")
	)
	(segment
		(start 143.585692 -402.102066)
		(end 143.188182 -402.256752)
		(width 0.14224)
		(layer "In4.Cu")
		(net "P5E_CPU1_P2_TX_BUF_DP<8>")
	)
	(segment
		(start 142.53464 -402.511006)
		(end 142.13713 -402.665692)
		(width 0.14224)
		(layer "In4.Cu")
		(net "P5E_CPU1_P2_TX_BUF_DP<8>")
	)
	(segment
		(start 142.13713 -402.665692)
		(end 142.058898 -402.843492)
		(width 0.14224)
		(layer "In4.Cu")
		(net "P5E_CPU1_P2_TX_BUF_DP<8>")
	)
	(segment
		(start 146.723608 -401.275042)
		(end 145.966434 -401.425918)
		(width 0.14224)
		(layer "In4.Cu")
		(net "P5E_CPU1_P2_TX_BUF_DP<8>")
	)
	(segment
		(start 157.395418 -390.176512)
		(end 157.395418 -390.41578)
		(width 0.14224)
		(layer "In4.Cu")
		(net "P5E_CPU1_P2_TX_BUF_DP<8>")
	)
	(segment
		(start 156.55798 -391.7696)
		(end 156.55798 -394.570204)
		(width 0.14224)
		(layer "In4.Cu")
		(net "P5E_CPU1_P2_TX_BUF_DP<8>")
	)
	(segment
		(start 140.466064 -403.315932)
		(end 140.202158 -403.418548)
		(width 0.14224)
		(layer "In4.Cu")
		(net "P5E_CPU1_P2_TX_BUF_DP<8>")
	)
	(segment
		(start 141.01953 -403.229826)
		(end 140.621512 -403.384766)
		(width 0.14224)
		(layer "In4.Cu")
		(net "P5E_CPU1_P2_TX_BUF_DP<8>")
	)
	(segment
		(start 148.98624 -400.58848)
		(end 146.723608 -401.275042)
		(width 0.14224)
		(layer "In4.Cu")
		(net "P5E_CPU1_P2_TX_BUF_DP<8>")
	)
	(segment
		(start 157.142688 -389.75411)
		(end 157.27553 -389.886952)
		(width 0.14224)
		(layer "In4.Cu")
		(net "P5E_CPU1_P2_TX_BUF_DP<8>")
	)
	(segment
		(start 141.483588 -402.919946)
		(end 141.087348 -403.074124)
		(width 0.14224)
		(layer "In4.Cu")
		(net "P5E_CPU1_P2_TX_BUF_DP<8>")
	)
	(segment
		(start 156.092652 -395.693392)
		(end 153.231342 -398.554702)
		(width 0.14224)
		(layer "In4.Cu")
		(net "P5E_CPU1_P2_TX_BUF_DP<8>")
	)
	(segment
		(start 139.972796 -403.772878)
		(end 139.972796 -404.17369)
		(width 0.14224)
		(layer "In4.Cu")
		(net "P5E_CPU1_P2_TX_BUF_DP<8>")
	)
	(arc
		(start 157.034738 -389.49376)
		(mid 157.062788 -389.634688)
		(end 157.142688 -389.75411)
		(width 0.14224)
		(layer "In4.Cu")
		(net "P5E_CPU1_P2_TX_BUF_DP<8>")
	)
	(arc
		(start 153.231342 -398.554702)
		(mid 152.723801 -398.971205)
		(end 152.14473 -399.280634)
		(width 0.14224)
		(layer "In4.Cu")
		(net "P5E_CPU1_P2_TX_BUF_DP<8>")
	)
	(arc
		(start 157.395418 -390.41578)
		(mid 157.314614 -390.822097)
		(end 157.084522 -391.166604)
		(width 0.14224)
		(layer "In4.Cu")
		(net "P5E_CPU1_P2_TX_BUF_DP<8>")
	)
	(arc
		(start 140.061188 -403.559518)
		(mid 139.99578 -403.657408)
		(end 139.972796 -403.772878)
		(width 0.14224)
		(layer "In4.Cu")
		(net "P5E_CPU1_P2_TX_BUF_DP<8>")
	)
	(arc
		(start 156.55798 -394.570204)
		(mid 156.437046 -395.178089)
		(end 156.092652 -395.693392)
		(width 0.14224)
		(layer "In4.Cu")
		(net "P5E_CPU1_P2_TX_BUF_DP<8>")
	)
	(arc
		(start 157.27553 -389.886952)
		(mid 157.364245 -390.019817)
		(end 157.395418 -390.176512)
		(width 0.14224)
		(layer "In4.Cu")
		(net "P5E_CPU1_P2_TX_BUF_DP<8>")
	)
	(arc
		(start 156.611828 -391.639552)
		(mid 156.57196 -391.699219)
		(end 156.55798 -391.7696)
		(width 0.14224)
		(layer "In4.Cu")
		(net "P5E_CPU1_P2_TX_BUF_DP<8>")
	)
	(segment
		(start 137.225786 -408.250644)
		(end 136.929876 -407.954734)
		(width 0.12954)
		(layer "F.Cu")
		(net "P5E_CPU1_P2_TX_BUF_DP<7>")
	)
	(segment
		(start 136.929876 -407.954734)
		(end 136.929876 -404.73503)
		(width 0.12954)
		(layer "F.Cu")
		(net "P5E_CPU1_P2_TX_BUF_DP<7>")
	)
	(segment
		(start 155.69819 -389.467344)
		(end 156.21889 -389.467344)
		(width 0.127)
		(layer "F.Cu")
		(net "P5E_CPU1_P2_TX_BUF_DP<7>")
	)
	(segment
		(start 136.929876 -404.73503)
		(end 137.200386 -404.46452)
		(width 0.12954)
		(layer "F.Cu")
		(net "P5E_CPU1_P2_TX_BUF_DP<7>")
	)
	(segment
		(start 136.909556 -403.80412)
		(end 136.909556 -404.17369)
		(width 0.14224)
		(layer "In4.Cu")
		(net "P5E_CPU1_P2_TX_BUF_DP<7>")
	)
	(segment
		(start 155.092908 -395.318996)
		(end 152.468326 -397.943578)
		(width 0.14224)
		(layer "In4.Cu")
		(net "P5E_CPU1_P2_TX_BUF_DP<7>")
	)
	(segment
		(start 151.709374 -398.450816)
		(end 148.867368 -399.627852)
		(width 0.14224)
		(layer "In4.Cu")
		(net "P5E_CPU1_P2_TX_BUF_DP<7>")
	)
	(segment
		(start 148.867368 -399.627852)
		(end 146.485864 -400.350228)
		(width 0.14224)
		(layer "In4.Cu")
		(net "P5E_CPU1_P2_TX_BUF_DP<7>")
	)
	(segment
		(start 139.213844 -402.514816)
		(end 139.139422 -402.69414)
		(width 0.14224)
		(layer "In4.Cu")
		(net "P5E_CPU1_P2_TX_BUF_DP<7>")
	)
	(segment
		(start 155.92425 -389.352536)
		(end 155.841954 -389.434832)
		(width 0.14224)
		(layer "In4.Cu")
		(net "P5E_CPU1_P2_TX_BUF_DP<7>")
	)
	(segment
		(start 156.104082 -389.352536)
		(end 155.92425 -389.352536)
		(width 0.14224)
		(layer "In4.Cu")
		(net "P5E_CPU1_P2_TX_BUF_DP<7>")
	)
	(segment
		(start 146.485864 -400.350228)
		(end 145.497296 -400.547078)
		(width 0.14224)
		(layer "In4.Cu")
		(net "P5E_CPU1_P2_TX_BUF_DP<7>")
	)
	(segment
		(start 139.139422 -402.69414)
		(end 138.74496 -402.857462)
		(width 0.14224)
		(layer "In4.Cu")
		(net "P5E_CPU1_P2_TX_BUF_DP<7>")
	)
	(segment
		(start 138.171682 -402.946362)
		(end 138.09726 -403.125686)
		(width 0.14224)
		(layer "In4.Cu")
		(net "P5E_CPU1_P2_TX_BUF_DP<7>")
	)
	(segment
		(start 140.178282 -402.16074)
		(end 139.770104 -402.284438)
		(width 0.14224)
		(layer "In4.Cu")
		(net "P5E_CPU1_P2_TX_BUF_DP<7>")
	)
	(segment
		(start 137.12952 -403.377908)
		(end 137.055606 -403.451822)
		(width 0.14224)
		(layer "In4.Cu")
		(net "P5E_CPU1_P2_TX_BUF_DP<7>")
	)
	(segment
		(start 138.56589 -402.783294)
		(end 138.171682 -402.946362)
		(width 0.14224)
		(layer "In4.Cu")
		(net "P5E_CPU1_P2_TX_BUF_DP<7>")
	)
	(segment
		(start 155.841954 -389.434832)
		(end 155.841954 -389.534146)
		(width 0.14224)
		(layer "In4.Cu")
		(net "P5E_CPU1_P2_TX_BUF_DP<7>")
	)
	(segment
		(start 155.926282 -389.7376)
		(end 156.075634 -389.886698)
		(width 0.14224)
		(layer "In4.Cu")
		(net "P5E_CPU1_P2_TX_BUF_DP<7>")
	)
	(segment
		(start 156.21889 -389.467344)
		(end 156.104082 -389.352536)
		(width 0.14224)
		(layer "In4.Cu")
		(net "P5E_CPU1_P2_TX_BUF_DP<7>")
	)
	(segment
		(start 140.84935 -401.957032)
		(end 140.75791 -402.128228)
		(width 0.14224)
		(layer "In4.Cu")
		(net "P5E_CPU1_P2_TX_BUF_DP<7>")
	)
	(segment
		(start 136.909556 -404.17369)
		(end 137.200386 -404.46452)
		(width 0.14224)
		(layer "In4.Cu")
		(net "P5E_CPU1_P2_TX_BUF_DP<7>")
	)
	(segment
		(start 145.497296 -400.547078)
		(end 140.84935 -401.957032)
		(width 0.14224)
		(layer "In4.Cu")
		(net "P5E_CPU1_P2_TX_BUF_DP<7>")
	)
	(segment
		(start 156.195522 -390.176258)
		(end 156.195522 -390.541764)
		(width 0.14224)
		(layer "In4.Cu")
		(net "P5E_CPU1_P2_TX_BUF_DP<7>")
	)
	(segment
		(start 139.770104 -402.284438)
		(end 139.213844 -402.514816)
		(width 0.14224)
		(layer "In4.Cu")
		(net "P5E_CPU1_P2_TX_BUF_DP<7>")
	)
	(segment
		(start 155.99791 -391.018776)
		(end 155.516326 -391.50036)
		(width 0.14224)
		(layer "In4.Cu")
		(net "P5E_CPU1_P2_TX_BUF_DP<7>")
	)
	(segment
		(start 138.74496 -402.857462)
		(end 138.56589 -402.783294)
		(width 0.14224)
		(layer "In4.Cu")
		(net "P5E_CPU1_P2_TX_BUF_DP<7>")
	)
	(segment
		(start 155.417266 -391.739628)
		(end 155.417266 -394.535914)
		(width 0.14224)
		(layer "In4.Cu")
		(net "P5E_CPU1_P2_TX_BUF_DP<7>")
	)
	(segment
		(start 137.702798 -403.289008)
		(end 137.523728 -403.21484)
		(width 0.14224)
		(layer "In4.Cu")
		(net "P5E_CPU1_P2_TX_BUF_DP<7>")
	)
	(segment
		(start 140.75791 -402.128228)
		(end 140.349478 -402.25218)
		(width 0.14224)
		(layer "In4.Cu")
		(net "P5E_CPU1_P2_TX_BUF_DP<7>")
	)
	(segment
		(start 137.523728 -403.21484)
		(end 137.12952 -403.377908)
		(width 0.14224)
		(layer "In4.Cu")
		(net "P5E_CPU1_P2_TX_BUF_DP<7>")
	)
	(segment
		(start 140.349478 -402.25218)
		(end 140.178282 -402.16074)
		(width 0.14224)
		(layer "In4.Cu")
		(net "P5E_CPU1_P2_TX_BUF_DP<7>")
	)
	(segment
		(start 138.09726 -403.125686)
		(end 137.702798 -403.289008)
		(width 0.14224)
		(layer "In4.Cu")
		(net "P5E_CPU1_P2_TX_BUF_DP<7>")
	)
	(arc
		(start 156.195522 -390.541764)
		(mid 156.144169 -390.799931)
		(end 155.99791 -391.018776)
		(width 0.14224)
		(layer "In4.Cu")
		(net "P5E_CPU1_P2_TX_BUF_DP<7>")
	)
	(arc
		(start 155.516326 -391.50036)
		(mid 155.443029 -391.610151)
		(end 155.417266 -391.739628)
		(width 0.14224)
		(layer "In4.Cu")
		(net "P5E_CPU1_P2_TX_BUF_DP<7>")
	)
	(arc
		(start 137.055606 -403.451822)
		(mid 136.947497 -403.613429)
		(end 136.909556 -403.80412)
		(width 0.14224)
		(layer "In4.Cu")
		(net "P5E_CPU1_P2_TX_BUF_DP<7>")
	)
	(arc
		(start 156.075634 -389.886698)
		(mid 156.164427 -390.019536)
		(end 156.195522 -390.176258)
		(width 0.14224)
		(layer "In4.Cu")
		(net "P5E_CPU1_P2_TX_BUF_DP<7>")
	)
	(arc
		(start 155.417266 -394.535914)
		(mid 155.332967 -394.959713)
		(end 155.092908 -395.318996)
		(width 0.14224)
		(layer "In4.Cu")
		(net "P5E_CPU1_P2_TX_BUF_DP<7>")
	)
	(arc
		(start 155.841954 -389.534146)
		(mid 155.863875 -389.644261)
		(end 155.926282 -389.7376)
		(width 0.14224)
		(layer "In4.Cu")
		(net "P5E_CPU1_P2_TX_BUF_DP<7>")
	)
	(arc
		(start 152.468326 -397.943578)
		(mid 152.113838 -398.234589)
		(end 151.709374 -398.450816)
		(width 0.14224)
		(layer "In4.Cu")
		(net "P5E_CPU1_P2_TX_BUF_DP<7>")
	)
	(segment
		(start 133.866636 -404.73503)
		(end 134.137146 -404.46452)
		(width 0.12954)
		(layer "F.Cu")
		(net "P5E_CPU1_P2_TX_BUF_DP<6>")
	)
	(segment
		(start 133.866636 -407.954734)
		(end 133.866636 -404.73503)
		(width 0.12954)
		(layer "F.Cu")
		(net "P5E_CPU1_P2_TX_BUF_DP<6>")
	)
	(segment
		(start 154.498294 -389.467344)
		(end 155.018994 -389.467344)
		(width 0.127)
		(layer "F.Cu")
		(net "P5E_CPU1_P2_TX_BUF_DP<6>")
	)
	(segment
		(start 134.162546 -408.250644)
		(end 133.866636 -407.954734)
		(width 0.12954)
		(layer "F.Cu")
		(net "P5E_CPU1_P2_TX_BUF_DP<6>")
	)
	(segment
		(start 154.689302 -391.142474)
		(end 154.258518 -391.573258)
		(width 0.14224)
		(layer "In4.Cu")
		(net "P5E_CPU1_P2_TX_BUF_DP<6>")
	)
	(segment
		(start 148.683218 -398.694656)
		(end 146.93646 -399.2245)
		(width 0.14224)
		(layer "In4.Cu")
		(net "P5E_CPU1_P2_TX_BUF_DP<6>")
	)
	(segment
		(start 136.142222 -402.6154)
		(end 135.74776 -402.778722)
		(width 0.14224)
		(layer "In4.Cu")
		(net "P5E_CPU1_P2_TX_BUF_DP<6>")
	)
	(segment
		(start 134.038848 -403.33803)
		(end 133.931914 -403.444964)
		(width 0.14224)
		(layer "In4.Cu")
		(net "P5E_CPU1_P2_TX_BUF_DP<6>")
	)
	(segment
		(start 146.93646 -399.2245)
		(end 146.08302 -399.394426)
		(width 0.14224)
		(layer "In4.Cu")
		(net "P5E_CPU1_P2_TX_BUF_DP<6>")
	)
	(segment
		(start 136.216644 -402.436076)
		(end 136.142222 -402.6154)
		(width 0.14224)
		(layer "In4.Cu")
		(net "P5E_CPU1_P2_TX_BUF_DP<6>")
	)
	(segment
		(start 153.87828 -395.170406)
		(end 151.7015 -397.347186)
		(width 0.14224)
		(layer "In4.Cu")
		(net "P5E_CPU1_P2_TX_BUF_DP<6>")
	)
	(segment
		(start 146.08302 -399.394426)
		(end 137.733024 -401.927314)
		(width 0.14224)
		(layer "In4.Cu")
		(net "P5E_CPU1_P2_TX_BUF_DP<6>")
	)
	(segment
		(start 136.216898 -402.435822)
		(end 136.216644 -402.436076)
		(width 0.14224)
		(layer "In4.Cu")
		(net "P5E_CPU1_P2_TX_BUF_DP<6>")
	)
	(segment
		(start 155.018994 -389.467344)
		(end 154.904186 -389.352536)
		(width 0.14224)
		(layer "In4.Cu")
		(net "P5E_CPU1_P2_TX_BUF_DP<6>")
	)
	(segment
		(start 154.995372 -390.176512)
		(end 154.995372 -390.403588)
		(width 0.14224)
		(layer "In4.Cu")
		(net "P5E_CPU1_P2_TX_BUF_DP<6>")
	)
	(segment
		(start 136.653778 -402.25472)
		(end 136.216898 -402.435822)
		(width 0.14224)
		(layer "In4.Cu")
		(net "P5E_CPU1_P2_TX_BUF_DP<6>")
	)
	(segment
		(start 135.74776 -402.778722)
		(end 135.56869 -402.704554)
		(width 0.14224)
		(layer "In4.Cu")
		(net "P5E_CPU1_P2_TX_BUF_DP<6>")
	)
	(segment
		(start 154.192986 -391.7315)
		(end 154.192986 -394.410692)
		(width 0.14224)
		(layer "In4.Cu")
		(net "P5E_CPU1_P2_TX_BUF_DP<6>")
	)
	(segment
		(start 154.7241 -389.352536)
		(end 154.634692 -389.441944)
		(width 0.14224)
		(layer "In4.Cu")
		(net "P5E_CPU1_P2_TX_BUF_DP<6>")
	)
	(segment
		(start 133.846316 -404.17369)
		(end 134.137146 -404.46452)
		(width 0.14224)
		(layer "In4.Cu")
		(net "P5E_CPU1_P2_TX_BUF_DP<6>")
	)
	(segment
		(start 137.061956 -402.131022)
		(end 136.653778 -402.25472)
		(width 0.14224)
		(layer "In4.Cu")
		(net "P5E_CPU1_P2_TX_BUF_DP<6>")
	)
	(segment
		(start 134.526528 -403.1361)
		(end 134.038848 -403.33803)
		(width 0.14224)
		(layer "In4.Cu")
		(net "P5E_CPU1_P2_TX_BUF_DP<6>")
	)
	(segment
		(start 154.904186 -389.352536)
		(end 154.7241 -389.352536)
		(width 0.14224)
		(layer "In4.Cu")
		(net "P5E_CPU1_P2_TX_BUF_DP<6>")
	)
	(segment
		(start 135.100314 -403.0472)
		(end 134.705598 -403.210268)
		(width 0.14224)
		(layer "In4.Cu")
		(net "P5E_CPU1_P2_TX_BUF_DP<6>")
	)
	(segment
		(start 133.846316 -403.651466)
		(end 133.846316 -404.17369)
		(width 0.14224)
		(layer "In4.Cu")
		(net "P5E_CPU1_P2_TX_BUF_DP<6>")
	)
	(segment
		(start 154.72029 -389.731758)
		(end 154.875484 -389.886952)
		(width 0.14224)
		(layer "In4.Cu")
		(net "P5E_CPU1_P2_TX_BUF_DP<6>")
	)
	(segment
		(start 154.634692 -389.441944)
		(end 154.634692 -389.525256)
		(width 0.14224)
		(layer "In4.Cu")
		(net "P5E_CPU1_P2_TX_BUF_DP<6>")
	)
	(segment
		(start 134.705598 -403.210268)
		(end 134.526528 -403.1361)
		(width 0.14224)
		(layer "In4.Cu")
		(net "P5E_CPU1_P2_TX_BUF_DP<6>")
	)
	(segment
		(start 137.733024 -401.927314)
		(end 137.641584 -402.09851)
		(width 0.14224)
		(layer "In4.Cu")
		(net "P5E_CPU1_P2_TX_BUF_DP<6>")
	)
	(segment
		(start 151.31796 -397.603472)
		(end 148.683218 -398.694656)
		(width 0.14224)
		(layer "In4.Cu")
		(net "P5E_CPU1_P2_TX_BUF_DP<6>")
	)
	(segment
		(start 137.233152 -402.222462)
		(end 137.061956 -402.131022)
		(width 0.14224)
		(layer "In4.Cu")
		(net "P5E_CPU1_P2_TX_BUF_DP<6>")
	)
	(segment
		(start 135.56869 -402.704554)
		(end 135.174482 -402.867622)
		(width 0.14224)
		(layer "In4.Cu")
		(net "P5E_CPU1_P2_TX_BUF_DP<6>")
	)
	(segment
		(start 135.174482 -402.867622)
		(end 135.100314 -403.0472)
		(width 0.14224)
		(layer "In4.Cu")
		(net "P5E_CPU1_P2_TX_BUF_DP<6>")
	)
	(segment
		(start 137.641584 -402.09851)
		(end 137.233152 -402.222462)
		(width 0.14224)
		(layer "In4.Cu")
		(net "P5E_CPU1_P2_TX_BUF_DP<6>")
	)
	(arc
		(start 154.875484 -389.886952)
		(mid 154.964199 -390.019817)
		(end 154.995372 -390.176512)
		(width 0.14224)
		(layer "In4.Cu")
		(net "P5E_CPU1_P2_TX_BUF_DP<6>")
	)
	(arc
		(start 154.258518 -391.573258)
		(mid 154.210007 -391.64586)
		(end 154.192986 -391.7315)
		(width 0.14224)
		(layer "In4.Cu")
		(net "P5E_CPU1_P2_TX_BUF_DP<6>")
	)
	(arc
		(start 154.995372 -390.403588)
		(mid 154.915829 -390.803475)
		(end 154.689302 -391.142474)
		(width 0.14224)
		(layer "In4.Cu")
		(net "P5E_CPU1_P2_TX_BUF_DP<6>")
	)
	(arc
		(start 151.7015 -397.347186)
		(mid 151.522348 -397.494211)
		(end 151.31796 -397.603472)
		(width 0.14224)
		(layer "In4.Cu")
		(net "P5E_CPU1_P2_TX_BUF_DP<6>")
	)
	(arc
		(start 133.931914 -403.444964)
		(mid 133.868554 -403.539694)
		(end 133.846316 -403.651466)
		(width 0.14224)
		(layer "In4.Cu")
		(net "P5E_CPU1_P2_TX_BUF_DP<6>")
	)
	(arc
		(start 154.634692 -389.525256)
		(mid 154.656942 -389.637024)
		(end 154.72029 -389.731758)
		(width 0.14224)
		(layer "In4.Cu")
		(net "P5E_CPU1_P2_TX_BUF_DP<6>")
	)
	(arc
		(start 154.192986 -394.410692)
		(mid 154.111201 -394.821855)
		(end 153.87828 -395.170406)
		(width 0.14224)
		(layer "In4.Cu")
		(net "P5E_CPU1_P2_TX_BUF_DP<6>")
	)
	(segment
		(start 130.803396 -404.73503)
		(end 131.073906 -404.46452)
		(width 0.12954)
		(layer "F.Cu")
		(net "P5E_CPU1_P2_TX_BUF_DP<5>")
	)
	(segment
		(start 131.099306 -408.250644)
		(end 130.803396 -407.954734)
		(width 0.12954)
		(layer "F.Cu")
		(net "P5E_CPU1_P2_TX_BUF_DP<5>")
	)
	(segment
		(start 153.298398 -389.467344)
		(end 153.819098 -389.467344)
		(width 0.127)
		(layer "F.Cu")
		(net "P5E_CPU1_P2_TX_BUF_DP<5>")
	)
	(segment
		(start 130.803396 -407.954734)
		(end 130.803396 -404.73503)
		(width 0.12954)
		(layer "F.Cu")
		(net "P5E_CPU1_P2_TX_BUF_DP<5>")
	)
	(segment
		(start 133.014974 -402.749004)
		(end 132.620512 -402.912326)
		(width 0.14224)
		(layer "In4.Cu")
		(net "P5E_CPU1_P2_TX_BUF_DP<5>")
	)
	(segment
		(start 130.783076 -403.79777)
		(end 130.783076 -404.17369)
		(width 0.14224)
		(layer "In4.Cu")
		(net "P5E_CPU1_P2_TX_BUF_DP<5>")
	)
	(segment
		(start 152.763982 -394.914882)
		(end 150.990046 -396.688818)
		(width 0.14224)
		(layer "In4.Cu")
		(net "P5E_CPU1_P2_TX_BUF_DP<5>")
	)
	(segment
		(start 148.436584 -397.787368)
		(end 146.952716 -398.23771)
		(width 0.14224)
		(layer "In4.Cu")
		(net "P5E_CPU1_P2_TX_BUF_DP<5>")
	)
	(segment
		(start 132.620512 -402.912326)
		(end 132.441442 -402.838158)
		(width 0.14224)
		(layer "In4.Cu")
		(net "P5E_CPU1_P2_TX_BUF_DP<5>")
	)
	(segment
		(start 153.819098 -389.467344)
		(end 153.70429 -389.352536)
		(width 0.14224)
		(layer "In4.Cu")
		(net "P5E_CPU1_P2_TX_BUF_DP<5>")
	)
	(segment
		(start 131.005072 -403.433026)
		(end 130.884168 -403.55393)
		(width 0.14224)
		(layer "In4.Cu")
		(net "P5E_CPU1_P2_TX_BUF_DP<5>")
	)
	(segment
		(start 134.057136 -402.317458)
		(end 133.662674 -402.48078)
		(width 0.14224)
		(layer "In4.Cu")
		(net "P5E_CPU1_P2_TX_BUF_DP<5>")
	)
	(segment
		(start 132.441442 -402.838158)
		(end 132.047234 -403.00148)
		(width 0.14224)
		(layer "In4.Cu")
		(net "P5E_CPU1_P2_TX_BUF_DP<5>")
	)
	(segment
		(start 131.39928 -403.269958)
		(end 131.005072 -403.433026)
		(width 0.14224)
		(layer "In4.Cu")
		(net "P5E_CPU1_P2_TX_BUF_DP<5>")
	)
	(segment
		(start 153.62047 -390.965182)
		(end 153.091388 -391.494264)
		(width 0.14224)
		(layer "In4.Cu")
		(net "P5E_CPU1_P2_TX_BUF_DP<5>")
	)
	(segment
		(start 134.971282 -401.790408)
		(end 134.131558 -402.138134)
		(width 0.14224)
		(layer "In4.Cu")
		(net "P5E_CPU1_P2_TX_BUF_DP<5>")
	)
	(segment
		(start 146.169126 -398.393412)
		(end 134.971282 -401.790408)
		(width 0.14224)
		(layer "In4.Cu")
		(net "P5E_CPU1_P2_TX_BUF_DP<5>")
	)
	(segment
		(start 134.131558 -402.138134)
		(end 134.057136 -402.317458)
		(width 0.14224)
		(layer "In4.Cu")
		(net "P5E_CPU1_P2_TX_BUF_DP<5>")
	)
	(segment
		(start 131.972812 -403.180804)
		(end 131.57835 -403.344126)
		(width 0.14224)
		(layer "In4.Cu")
		(net "P5E_CPU1_P2_TX_BUF_DP<5>")
	)
	(segment
		(start 130.783076 -404.17369)
		(end 131.073906 -404.46452)
		(width 0.14224)
		(layer "In4.Cu")
		(net "P5E_CPU1_P2_TX_BUF_DP<5>")
	)
	(segment
		(start 150.829264 -396.79626)
		(end 148.436584 -397.787368)
		(width 0.14224)
		(layer "In4.Cu")
		(net "P5E_CPU1_P2_TX_BUF_DP<5>")
	)
	(segment
		(start 153.70429 -389.352536)
		(end 153.540968 -389.352536)
		(width 0.14224)
		(layer "In4.Cu")
		(net "P5E_CPU1_P2_TX_BUF_DP<5>")
	)
	(segment
		(start 152.996646 -391.722864)
		(end 152.996646 -394.353288)
		(width 0.14224)
		(layer "In4.Cu")
		(net "P5E_CPU1_P2_TX_BUF_DP<5>")
	)
	(segment
		(start 132.047234 -403.00148)
		(end 131.972812 -403.180804)
		(width 0.14224)
		(layer "In4.Cu")
		(net "P5E_CPU1_P2_TX_BUF_DP<5>")
	)
	(segment
		(start 131.57835 -403.344126)
		(end 131.39928 -403.269958)
		(width 0.14224)
		(layer "In4.Cu")
		(net "P5E_CPU1_P2_TX_BUF_DP<5>")
	)
	(segment
		(start 133.662674 -402.48078)
		(end 133.483604 -402.406612)
		(width 0.14224)
		(layer "In4.Cu")
		(net "P5E_CPU1_P2_TX_BUF_DP<5>")
	)
	(segment
		(start 133.089396 -402.56968)
		(end 133.014974 -402.749004)
		(width 0.14224)
		(layer "In4.Cu")
		(net "P5E_CPU1_P2_TX_BUF_DP<5>")
	)
	(segment
		(start 146.952716 -398.23771)
		(end 146.169126 -398.393412)
		(width 0.14224)
		(layer "In4.Cu")
		(net "P5E_CPU1_P2_TX_BUF_DP<5>")
	)
	(segment
		(start 153.434796 -389.458708)
		(end 153.434796 -389.493506)
		(width 0.14224)
		(layer "In4.Cu")
		(net "P5E_CPU1_P2_TX_BUF_DP<5>")
	)
	(segment
		(start 133.483604 -402.406612)
		(end 133.089396 -402.56968)
		(width 0.14224)
		(layer "In4.Cu")
		(net "P5E_CPU1_P2_TX_BUF_DP<5>")
	)
	(segment
		(start 153.540968 -389.352536)
		(end 153.434796 -389.458708)
		(width 0.14224)
		(layer "In4.Cu")
		(net "P5E_CPU1_P2_TX_BUF_DP<5>")
	)
	(segment
		(start 153.795476 -390.363202)
		(end 153.795476 -390.54278)
		(width 0.14224)
		(layer "In4.Cu")
		(net "P5E_CPU1_P2_TX_BUF_DP<5>")
	)
	(arc
		(start 150.990046 -396.688818)
		(mid 150.91496 -396.750482)
		(end 150.829264 -396.79626)
		(width 0.14224)
		(layer "In4.Cu")
		(net "P5E_CPU1_P2_TX_BUF_DP<5>")
	)
	(arc
		(start 130.884168 -403.55393)
		(mid 130.809362 -403.66579)
		(end 130.783076 -403.79777)
		(width 0.14224)
		(layer "In4.Cu")
		(net "P5E_CPU1_P2_TX_BUF_DP<5>")
	)
	(arc
		(start 153.434796 -389.493506)
		(mid 153.462972 -389.634686)
		(end 153.543 -389.754364)
		(width 0.14224)
		(layer "In4.Cu")
		(net "P5E_CPU1_P2_TX_BUF_DP<5>")
	)
	(arc
		(start 153.543 -389.754364)
		(mid 153.729706 -390.0337)
		(end 153.795476 -390.363202)
		(width 0.14224)
		(layer "In4.Cu")
		(net "P5E_CPU1_P2_TX_BUF_DP<5>")
	)
	(arc
		(start 153.795476 -390.54278)
		(mid 153.749986 -390.771384)
		(end 153.62047 -390.965182)
		(width 0.14224)
		(layer "In4.Cu")
		(net "P5E_CPU1_P2_TX_BUF_DP<5>")
	)
	(arc
		(start 153.091388 -391.494264)
		(mid 153.021254 -391.599132)
		(end 152.996646 -391.722864)
		(width 0.14224)
		(layer "In4.Cu")
		(net "P5E_CPU1_P2_TX_BUF_DP<5>")
	)
	(arc
		(start 152.996646 -394.353288)
		(mid 152.936172 -394.657223)
		(end 152.763982 -394.914882)
		(width 0.14224)
		(layer "In4.Cu")
		(net "P5E_CPU1_P2_TX_BUF_DP<5>")
	)
	(segment
		(start 152.098248 -389.467344)
		(end 152.618948 -389.467344)
		(width 0.127)
		(layer "F.Cu")
		(net "P5E_CPU1_P2_TX_BUF_DP<4>")
	)
	(segment
		(start 128.036066 -408.250644)
		(end 127.740156 -407.954734)
		(width 0.12954)
		(layer "F.Cu")
		(net "P5E_CPU1_P2_TX_BUF_DP<4>")
	)
	(segment
		(start 127.740156 -407.954734)
		(end 127.740156 -404.73503)
		(width 0.12954)
		(layer "F.Cu")
		(net "P5E_CPU1_P2_TX_BUF_DP<4>")
	)
	(segment
		(start 127.740156 -404.73503)
		(end 128.010666 -404.46452)
		(width 0.12954)
		(layer "F.Cu")
		(net "P5E_CPU1_P2_TX_BUF_DP<4>")
	)
	(segment
		(start 128.560322 -403.283674)
		(end 128.381252 -403.209506)
		(width 0.14224)
		(layer "In4.Cu")
		(net "P5E_CPU1_P2_TX_BUF_DP<4>")
	)
	(segment
		(start 146.116802 -397.434562)
		(end 131.947412 -401.732496)
		(width 0.14224)
		(layer "In4.Cu")
		(net "P5E_CPU1_P2_TX_BUF_DP<4>")
	)
	(segment
		(start 152.413462 -390.903206)
		(end 151.873712 -391.442956)
		(width 0.14224)
		(layer "In4.Cu")
		(net "P5E_CPU1_P2_TX_BUF_DP<4>")
	)
	(segment
		(start 152.234646 -389.441944)
		(end 152.234646 -389.59155)
		(width 0.14224)
		(layer "In4.Cu")
		(net "P5E_CPU1_P2_TX_BUF_DP<4>")
	)
	(segment
		(start 127.719836 -403.837902)
		(end 127.719836 -404.17369)
		(width 0.14224)
		(layer "In4.Cu")
		(net "P5E_CPU1_P2_TX_BUF_DP<4>")
	)
	(segment
		(start 130.465576 -402.346414)
		(end 130.071368 -402.509482)
		(width 0.14224)
		(layer "In4.Cu")
		(net "P5E_CPU1_P2_TX_BUF_DP<4>")
	)
	(segment
		(start 151.817578 -391.578592)
		(end 151.817578 -394.248894)
		(width 0.14224)
		(layer "In4.Cu")
		(net "P5E_CPU1_P2_TX_BUF_DP<4>")
	)
	(segment
		(start 131.947412 -401.732496)
		(end 131.11353 -402.077936)
		(width 0.14224)
		(layer "In4.Cu")
		(net "P5E_CPU1_P2_TX_BUF_DP<4>")
	)
	(segment
		(start 129.602484 -402.852128)
		(end 129.423414 -402.77796)
		(width 0.14224)
		(layer "In4.Cu")
		(net "P5E_CPU1_P2_TX_BUF_DP<4>")
	)
	(segment
		(start 152.271984 -389.681466)
		(end 152.474168 -389.88365)
		(width 0.14224)
		(layer "In4.Cu")
		(net "P5E_CPU1_P2_TX_BUF_DP<4>")
	)
	(segment
		(start 146.63674 -397.331184)
		(end 146.116802 -397.434562)
		(width 0.14224)
		(layer "In4.Cu")
		(net "P5E_CPU1_P2_TX_BUF_DP<4>")
	)
	(segment
		(start 128.954784 -403.120352)
		(end 128.560322 -403.283674)
		(width 0.14224)
		(layer "In4.Cu")
		(net "P5E_CPU1_P2_TX_BUF_DP<4>")
	)
	(segment
		(start 129.029206 -402.941028)
		(end 128.954784 -403.120352)
		(width 0.14224)
		(layer "In4.Cu")
		(net "P5E_CPU1_P2_TX_BUF_DP<4>")
	)
	(segment
		(start 130.644646 -402.420582)
		(end 130.465576 -402.346414)
		(width 0.14224)
		(layer "In4.Cu")
		(net "P5E_CPU1_P2_TX_BUF_DP<4>")
	)
	(segment
		(start 152.618948 -389.467344)
		(end 152.50414 -389.352536)
		(width 0.14224)
		(layer "In4.Cu")
		(net "P5E_CPU1_P2_TX_BUF_DP<4>")
	)
	(segment
		(start 151.654256 -394.643102)
		(end 150.499572 -395.797786)
		(width 0.14224)
		(layer "In4.Cu")
		(net "P5E_CPU1_P2_TX_BUF_DP<4>")
	)
	(segment
		(start 127.987044 -403.372574)
		(end 127.860044 -403.499574)
		(width 0.14224)
		(layer "In4.Cu")
		(net "P5E_CPU1_P2_TX_BUF_DP<4>")
	)
	(segment
		(start 150.004272 -396.128748)
		(end 148.374354 -396.80388)
		(width 0.14224)
		(layer "In4.Cu")
		(net "P5E_CPU1_P2_TX_BUF_DP<4>")
	)
	(segment
		(start 148.374354 -396.80388)
		(end 146.63674 -397.331184)
		(width 0.14224)
		(layer "In4.Cu")
		(net "P5E_CPU1_P2_TX_BUF_DP<4>")
	)
	(segment
		(start 130.071368 -402.509482)
		(end 129.996946 -402.688806)
		(width 0.14224)
		(layer "In4.Cu")
		(net "P5E_CPU1_P2_TX_BUF_DP<4>")
	)
	(segment
		(start 127.719836 -404.17369)
		(end 128.010666 -404.46452)
		(width 0.14224)
		(layer "In4.Cu")
		(net "P5E_CPU1_P2_TX_BUF_DP<4>")
	)
	(segment
		(start 131.11353 -402.077936)
		(end 131.039108 -402.25726)
		(width 0.14224)
		(layer "In4.Cu")
		(net "P5E_CPU1_P2_TX_BUF_DP<4>")
	)
	(segment
		(start 128.381252 -403.209506)
		(end 127.987044 -403.372574)
		(width 0.14224)
		(layer "In4.Cu")
		(net "P5E_CPU1_P2_TX_BUF_DP<4>")
	)
	(segment
		(start 131.039108 -402.25726)
		(end 130.644646 -402.420582)
		(width 0.14224)
		(layer "In4.Cu")
		(net "P5E_CPU1_P2_TX_BUF_DP<4>")
	)
	(segment
		(start 152.595326 -390.176258)
		(end 152.595326 -390.46404)
		(width 0.14224)
		(layer "In4.Cu")
		(net "P5E_CPU1_P2_TX_BUF_DP<4>")
	)
	(segment
		(start 152.324054 -389.352536)
		(end 152.234646 -389.441944)
		(width 0.14224)
		(layer "In4.Cu")
		(net "P5E_CPU1_P2_TX_BUF_DP<4>")
	)
	(segment
		(start 152.50414 -389.352536)
		(end 152.324054 -389.352536)
		(width 0.14224)
		(layer "In4.Cu")
		(net "P5E_CPU1_P2_TX_BUF_DP<4>")
	)
	(segment
		(start 129.996946 -402.688806)
		(end 129.602484 -402.852128)
		(width 0.14224)
		(layer "In4.Cu")
		(net "P5E_CPU1_P2_TX_BUF_DP<4>")
	)
	(segment
		(start 129.423414 -402.77796)
		(end 129.029206 -402.941028)
		(width 0.14224)
		(layer "In4.Cu")
		(net "P5E_CPU1_P2_TX_BUF_DP<4>")
	)
	(arc
		(start 150.499572 -395.797786)
		(mid 150.268217 -395.987652)
		(end 150.004272 -396.128748)
		(width 0.14224)
		(layer "In4.Cu")
		(net "P5E_CPU1_P2_TX_BUF_DP<4>")
	)
	(arc
		(start 127.860044 -403.499574)
		(mid 127.756271 -403.654786)
		(end 127.719836 -403.837902)
		(width 0.14224)
		(layer "In4.Cu")
		(net "P5E_CPU1_P2_TX_BUF_DP<4>")
	)
	(arc
		(start 151.873712 -391.442956)
		(mid 151.832185 -391.505201)
		(end 151.817578 -391.578592)
		(width 0.14224)
		(layer "In4.Cu")
		(net "P5E_CPU1_P2_TX_BUF_DP<4>")
	)
	(arc
		(start 152.474168 -389.88365)
		(mid 152.563817 -390.017914)
		(end 152.595326 -390.176258)
		(width 0.14224)
		(layer "In4.Cu")
		(net "P5E_CPU1_P2_TX_BUF_DP<4>")
	)
	(arc
		(start 151.817578 -394.248894)
		(mid 151.775139 -394.462251)
		(end 151.654256 -394.643102)
		(width 0.14224)
		(layer "In4.Cu")
		(net "P5E_CPU1_P2_TX_BUF_DP<4>")
	)
	(arc
		(start 152.595326 -390.46404)
		(mid 152.548068 -390.701712)
		(end 152.413462 -390.903206)
		(width 0.14224)
		(layer "In4.Cu")
		(net "P5E_CPU1_P2_TX_BUF_DP<4>")
	)
	(arc
		(start 152.234646 -389.59155)
		(mid 152.244348 -389.640234)
		(end 152.271984 -389.681466)
		(width 0.14224)
		(layer "In4.Cu")
		(net "P5E_CPU1_P2_TX_BUF_DP<4>")
	)
	(segment
		(start 150.898352 -389.467344)
		(end 151.419052 -389.467344)
		(width 0.127)
		(layer "F.Cu")
		(net "P5E_CPU1_P2_TX_BUF_DP<3>")
	)
	(segment
		(start 124.676916 -404.73503)
		(end 124.947426 -404.46452)
		(width 0.12954)
		(layer "F.Cu")
		(net "P5E_CPU1_P2_TX_BUF_DP<3>")
	)
	(segment
		(start 124.676916 -407.954734)
		(end 124.676916 -404.73503)
		(width 0.12954)
		(layer "F.Cu")
		(net "P5E_CPU1_P2_TX_BUF_DP<3>")
	)
	(segment
		(start 124.972826 -408.250644)
		(end 124.676916 -407.954734)
		(width 0.12954)
		(layer "F.Cu")
		(net "P5E_CPU1_P2_TX_BUF_DP<3>")
	)
	(segment
		(start 151.304244 -389.352536)
		(end 151.124158 -389.352536)
		(width 0.14224)
		(layer "In4.Cu")
		(net "P5E_CPU1_P2_TX_BUF_DP<3>")
	)
	(segment
		(start 151.124158 -389.352536)
		(end 151.03475 -389.441944)
		(width 0.14224)
		(layer "In4.Cu")
		(net "P5E_CPU1_P2_TX_BUF_DP<3>")
	)
	(segment
		(start 124.656596 -404.17369)
		(end 124.947426 -404.46452)
		(width 0.14224)
		(layer "In4.Cu")
		(net "P5E_CPU1_P2_TX_BUF_DP<3>")
	)
	(segment
		(start 125.048772 -403.252686)
		(end 124.774198 -403.52726)
		(width 0.14224)
		(layer "In4.Cu")
		(net "P5E_CPU1_P2_TX_BUF_DP<3>")
	)
	(segment
		(start 126.673102 -402.569426)
		(end 126.278894 -402.732494)
		(width 0.14224)
		(layer "In4.Cu")
		(net "P5E_CPU1_P2_TX_BUF_DP<3>")
	)
	(segment
		(start 149.521672 -395.318742)
		(end 148.084286 -395.914372)
		(width 0.14224)
		(layer "In4.Cu")
		(net "P5E_CPU1_P2_TX_BUF_DP<3>")
	)
	(segment
		(start 128.28905 -402.048726)
		(end 127.894588 -402.212048)
		(width 0.14224)
		(layer "In4.Cu")
		(net "P5E_CPU1_P2_TX_BUF_DP<3>")
	)
	(segment
		(start 128.578356 -401.779994)
		(end 128.363218 -401.869148)
		(width 0.14224)
		(layer "In4.Cu")
		(net "P5E_CPU1_P2_TX_BUF_DP<3>")
	)
	(segment
		(start 146.742658 -396.32128)
		(end 146.25193 -396.41907)
		(width 0.14224)
		(layer "In4.Cu")
		(net "P5E_CPU1_P2_TX_BUF_DP<3>")
	)
	(segment
		(start 127.715264 -402.137626)
		(end 127.321056 -402.300694)
		(width 0.14224)
		(layer "In4.Cu")
		(net "P5E_CPU1_P2_TX_BUF_DP<3>")
	)
	(segment
		(start 127.894588 -402.212048)
		(end 127.715264 -402.137626)
		(width 0.14224)
		(layer "In4.Cu")
		(net "P5E_CPU1_P2_TX_BUF_DP<3>")
	)
	(segment
		(start 128.363218 -401.869148)
		(end 128.28905 -402.048726)
		(width 0.14224)
		(layer "In4.Cu")
		(net "P5E_CPU1_P2_TX_BUF_DP<3>")
	)
	(segment
		(start 151.03475 -389.441944)
		(end 151.03475 -389.537956)
		(width 0.14224)
		(layer "In4.Cu")
		(net "P5E_CPU1_P2_TX_BUF_DP<3>")
	)
	(segment
		(start 151.111458 -389.722868)
		(end 151.275542 -389.886698)
		(width 0.14224)
		(layer "In4.Cu")
		(net "P5E_CPU1_P2_TX_BUF_DP<3>")
	)
	(segment
		(start 146.25193 -396.41907)
		(end 128.578356 -401.779994)
		(width 0.14224)
		(layer "In4.Cu")
		(net "P5E_CPU1_P2_TX_BUF_DP<3>")
	)
	(segment
		(start 126.204726 -402.912072)
		(end 125.810264 -403.075394)
		(width 0.14224)
		(layer "In4.Cu")
		(net "P5E_CPU1_P2_TX_BUF_DP<3>")
	)
	(segment
		(start 151.39543 -390.17575)
		(end 151.39543 -390.335516)
		(width 0.14224)
		(layer "In4.Cu")
		(net "P5E_CPU1_P2_TX_BUF_DP<3>")
	)
	(segment
		(start 150.50135 -394.45819)
		(end 149.880828 -395.078712)
		(width 0.14224)
		(layer "In4.Cu")
		(net "P5E_CPU1_P2_TX_BUF_DP<3>")
	)
	(segment
		(start 148.084286 -395.914372)
		(end 146.742658 -396.32128)
		(width 0.14224)
		(layer "In4.Cu")
		(net "P5E_CPU1_P2_TX_BUF_DP<3>")
	)
	(segment
		(start 125.810264 -403.075394)
		(end 125.63094 -403.000972)
		(width 0.14224)
		(layer "In4.Cu")
		(net "P5E_CPU1_P2_TX_BUF_DP<3>")
	)
	(segment
		(start 126.852426 -402.643594)
		(end 126.673102 -402.569426)
		(width 0.14224)
		(layer "In4.Cu")
		(net "P5E_CPU1_P2_TX_BUF_DP<3>")
	)
	(segment
		(start 127.321056 -402.300694)
		(end 127.246888 -402.480272)
		(width 0.14224)
		(layer "In4.Cu")
		(net "P5E_CPU1_P2_TX_BUF_DP<3>")
	)
	(segment
		(start 124.656596 -403.810978)
		(end 124.656596 -404.17369)
		(width 0.14224)
		(layer "In4.Cu")
		(net "P5E_CPU1_P2_TX_BUF_DP<3>")
	)
	(segment
		(start 151.419052 -389.467344)
		(end 151.304244 -389.352536)
		(width 0.14224)
		(layer "In4.Cu")
		(net "P5E_CPU1_P2_TX_BUF_DP<3>")
	)
	(segment
		(start 150.621238 -391.513314)
		(end 150.621238 -394.168884)
		(width 0.14224)
		(layer "In4.Cu")
		(net "P5E_CPU1_P2_TX_BUF_DP<3>")
	)
	(segment
		(start 127.246888 -402.480272)
		(end 126.852426 -402.643594)
		(width 0.14224)
		(layer "In4.Cu")
		(net "P5E_CPU1_P2_TX_BUF_DP<3>")
	)
	(segment
		(start 125.63094 -403.000972)
		(end 125.090174 -403.225)
		(width 0.14224)
		(layer "In4.Cu")
		(net "P5E_CPU1_P2_TX_BUF_DP<3>")
	)
	(segment
		(start 151.200866 -390.805162)
		(end 150.71217 -391.293858)
		(width 0.14224)
		(layer "In4.Cu")
		(net "P5E_CPU1_P2_TX_BUF_DP<3>")
	)
	(segment
		(start 126.278894 -402.732494)
		(end 126.204726 -402.912072)
		(width 0.14224)
		(layer "In4.Cu")
		(net "P5E_CPU1_P2_TX_BUF_DP<3>")
	)
	(arc
		(start 150.71217 -391.293858)
		(mid 150.644893 -391.394545)
		(end 150.621238 -391.513314)
		(width 0.14224)
		(layer "In4.Cu")
		(net "P5E_CPU1_P2_TX_BUF_DP<3>")
	)
	(arc
		(start 151.275542 -389.886698)
		(mid 151.364238 -390.019301)
		(end 151.39543 -390.17575)
		(width 0.14224)
		(layer "In4.Cu")
		(net "P5E_CPU1_P2_TX_BUF_DP<3>")
	)
	(arc
		(start 125.090174 -403.225)
		(mid 125.068099 -403.236791)
		(end 125.048772 -403.252686)
		(width 0.14224)
		(layer "In4.Cu")
		(net "P5E_CPU1_P2_TX_BUF_DP<3>")
	)
	(arc
		(start 149.880828 -395.078712)
		(mid 149.713063 -395.216401)
		(end 149.521672 -395.318742)
		(width 0.14224)
		(layer "In4.Cu")
		(net "P5E_CPU1_P2_TX_BUF_DP<3>")
	)
	(arc
		(start 124.774198 -403.52726)
		(mid 124.687167 -403.657417)
		(end 124.656596 -403.810978)
		(width 0.14224)
		(layer "In4.Cu")
		(net "P5E_CPU1_P2_TX_BUF_DP<3>")
	)
	(arc
		(start 150.621238 -394.168884)
		(mid 150.590075 -394.325462)
		(end 150.50135 -394.45819)
		(width 0.14224)
		(layer "In4.Cu")
		(net "P5E_CPU1_P2_TX_BUF_DP<3>")
	)
	(arc
		(start 151.39543 -390.335516)
		(mid 151.34487 -390.589698)
		(end 151.200866 -390.805162)
		(width 0.14224)
		(layer "In4.Cu")
		(net "P5E_CPU1_P2_TX_BUF_DP<3>")
	)
	(arc
		(start 151.03475 -389.537956)
		(mid 151.054695 -389.638045)
		(end 151.111458 -389.722868)
		(width 0.14224)
		(layer "In4.Cu")
		(net "P5E_CPU1_P2_TX_BUF_DP<3>")
	)
	(segment
		(start 149.698202 -389.467344)
		(end 150.218902 -389.467344)
		(width 0.127)
		(layer "F.Cu")
		(net "P5E_CPU1_P2_TX_BUF_DP<2>")
	)
	(segment
		(start 121.909586 -408.250644)
		(end 121.613676 -407.954734)
		(width 0.12954)
		(layer "F.Cu")
		(net "P5E_CPU1_P2_TX_BUF_DP<2>")
	)
	(segment
		(start 121.613676 -407.954734)
		(end 121.613676 -404.73503)
		(width 0.12954)
		(layer "F.Cu")
		(net "P5E_CPU1_P2_TX_BUF_DP<2>")
	)
	(segment
		(start 121.613676 -404.73503)
		(end 121.884186 -404.46452)
		(width 0.12954)
		(layer "F.Cu")
		(net "P5E_CPU1_P2_TX_BUF_DP<2>")
	)
	(segment
		(start 121.593356 -403.890226)
		(end 121.593356 -404.17369)
		(width 0.14224)
		(layer "In4.Cu")
		(net "P5E_CPU1_P2_TX_BUF_DP<2>")
	)
	(segment
		(start 122.998738 -402.894292)
		(end 122.924316 -403.073616)
		(width 0.14224)
		(layer "In4.Cu")
		(net "P5E_CPU1_P2_TX_BUF_DP<2>")
	)
	(segment
		(start 150.103078 -389.35152)
		(end 149.953218 -389.35152)
		(width 0.14224)
		(layer "In4.Cu")
		(net "P5E_CPU1_P2_TX_BUF_DP<2>")
	)
	(segment
		(start 148.948902 -394.534136)
		(end 148.185124 -394.850112)
		(width 0.14224)
		(layer "In4.Cu")
		(net "P5E_CPU1_P2_TX_BUF_DP<2>")
	)
	(segment
		(start 122.924316 -403.073616)
		(end 122.529854 -403.236938)
		(width 0.14224)
		(layer "In4.Cu")
		(net "P5E_CPU1_P2_TX_BUF_DP<2>")
	)
	(segment
		(start 148.04009 -394.901928)
		(end 126.90348 -401.31365)
		(width 0.14224)
		(layer "In4.Cu")
		(net "P5E_CPU1_P2_TX_BUF_DP<2>")
	)
	(segment
		(start 150.218902 -389.467344)
		(end 150.103078 -389.35152)
		(width 0.14224)
		(layer "In4.Cu")
		(net "P5E_CPU1_P2_TX_BUF_DP<2>")
	)
	(segment
		(start 123.572016 -402.805392)
		(end 123.392946 -402.731224)
		(width 0.14224)
		(layer "In4.Cu")
		(net "P5E_CPU1_P2_TX_BUF_DP<2>")
	)
	(segment
		(start 149.836378 -389.46836)
		(end 149.836378 -389.48995)
		(width 0.14224)
		(layer "In4.Cu")
		(net "P5E_CPU1_P2_TX_BUF_DP<2>")
	)
	(segment
		(start 150.108412 -390.173718)
		(end 150.108412 -390.301988)
		(width 0.14224)
		(layer "In4.Cu")
		(net "P5E_CPU1_P2_TX_BUF_DP<2>")
	)
	(segment
		(start 121.915428 -403.35327)
		(end 121.745248 -403.52345)
		(width 0.14224)
		(layer "In4.Cu")
		(net "P5E_CPU1_P2_TX_BUF_DP<2>")
	)
	(segment
		(start 123.966478 -402.64207)
		(end 123.572016 -402.805392)
		(width 0.14224)
		(layer "In4.Cu")
		(net "P5E_CPU1_P2_TX_BUF_DP<2>")
	)
	(segment
		(start 149.953218 -389.35152)
		(end 149.836378 -389.46836)
		(width 0.14224)
		(layer "In4.Cu")
		(net "P5E_CPU1_P2_TX_BUF_DP<2>")
	)
	(segment
		(start 121.593356 -404.17369)
		(end 121.884186 -404.46452)
		(width 0.14224)
		(layer "In4.Cu")
		(net "P5E_CPU1_P2_TX_BUF_DP<2>")
	)
	(segment
		(start 124.614178 -402.373846)
		(end 124.435108 -402.299678)
		(width 0.14224)
		(layer "In4.Cu")
		(net "P5E_CPU1_P2_TX_BUF_DP<2>")
	)
	(segment
		(start 149.43836 -391.452354)
		(end 149.43836 -393.800584)
		(width 0.14224)
		(layer "In4.Cu")
		(net "P5E_CPU1_P2_TX_BUF_DP<2>")
	)
	(segment
		(start 122.350784 -403.16277)
		(end 121.956576 -403.325838)
		(width 0.14224)
		(layer "In4.Cu")
		(net "P5E_CPU1_P2_TX_BUF_DP<2>")
	)
	(segment
		(start 125.083062 -402.0312)
		(end 125.00864 -402.210524)
		(width 0.14224)
		(layer "In4.Cu")
		(net "P5E_CPU1_P2_TX_BUF_DP<2>")
	)
	(segment
		(start 149.901402 -390.80186)
		(end 149.571202 -391.13206)
		(width 0.14224)
		(layer "In4.Cu")
		(net "P5E_CPU1_P2_TX_BUF_DP<2>")
	)
	(segment
		(start 122.529854 -403.236938)
		(end 122.350784 -403.16277)
		(width 0.14224)
		(layer "In4.Cu")
		(net "P5E_CPU1_P2_TX_BUF_DP<2>")
	)
	(segment
		(start 124.0409 -402.462746)
		(end 123.966478 -402.64207)
		(width 0.14224)
		(layer "In4.Cu")
		(net "P5E_CPU1_P2_TX_BUF_DP<2>")
	)
	(segment
		(start 125.00864 -402.210524)
		(end 124.614178 -402.373846)
		(width 0.14224)
		(layer "In4.Cu")
		(net "P5E_CPU1_P2_TX_BUF_DP<2>")
	)
	(segment
		(start 124.435108 -402.299678)
		(end 124.0409 -402.462746)
		(width 0.14224)
		(layer "In4.Cu")
		(net "P5E_CPU1_P2_TX_BUF_DP<2>")
	)
	(segment
		(start 126.256542 -401.545044)
		(end 125.083062 -402.0312)
		(width 0.14224)
		(layer "In4.Cu")
		(net "P5E_CPU1_P2_TX_BUF_DP<2>")
	)
	(segment
		(start 123.392946 -402.731224)
		(end 122.998738 -402.894292)
		(width 0.14224)
		(layer "In4.Cu")
		(net "P5E_CPU1_P2_TX_BUF_DP<2>")
	)
	(arc
		(start 149.43836 -393.800584)
		(mid 149.38918 -394.076508)
		(end 149.247352 -394.318236)
		(width 0.14224)
		(layer "In4.Cu")
		(net "P5E_CPU1_P2_TX_BUF_DP<2>")
	)
	(arc
		(start 149.836378 -389.48995)
		(mid 149.863486 -389.630888)
		(end 149.940772 -389.751824)
		(width 0.14224)
		(layer "In4.Cu")
		(net "P5E_CPU1_P2_TX_BUF_DP<2>")
	)
	(arc
		(start 149.247352 -394.318236)
		(mid 149.110892 -394.44383)
		(end 148.948902 -394.534136)
		(width 0.14224)
		(layer "In4.Cu")
		(net "P5E_CPU1_P2_TX_BUF_DP<2>")
	)
	(arc
		(start 148.185124 -394.850112)
		(mid 148.11324 -394.87779)
		(end 148.04009 -394.901928)
		(width 0.14224)
		(layer "In4.Cu")
		(net "P5E_CPU1_P2_TX_BUF_DP<2>")
	)
	(arc
		(start 150.108412 -390.301988)
		(mid 150.054619 -390.572514)
		(end 149.901402 -390.80186)
		(width 0.14224)
		(layer "In4.Cu")
		(net "P5E_CPU1_P2_TX_BUF_DP<2>")
	)
	(arc
		(start 126.90348 -401.31365)
		(mid 126.577171 -401.421406)
		(end 126.256542 -401.545044)
		(width 0.14224)
		(layer "In4.Cu")
		(net "P5E_CPU1_P2_TX_BUF_DP<2>")
	)
	(arc
		(start 149.571202 -391.13206)
		(mid 149.472982 -391.279011)
		(end 149.43836 -391.452354)
		(width 0.14224)
		(layer "In4.Cu")
		(net "P5E_CPU1_P2_TX_BUF_DP<2>")
	)
	(arc
		(start 149.940772 -389.751824)
		(mid 150.06506 -389.946691)
		(end 150.108412 -390.173718)
		(width 0.14224)
		(layer "In4.Cu")
		(net "P5E_CPU1_P2_TX_BUF_DP<2>")
	)
	(arc
		(start 121.956576 -403.325838)
		(mid 121.934666 -403.337548)
		(end 121.915428 -403.35327)
		(width 0.14224)
		(layer "In4.Cu")
		(net "P5E_CPU1_P2_TX_BUF_DP<2>")
	)
	(arc
		(start 121.745248 -403.52345)
		(mid 121.632808 -403.691728)
		(end 121.593356 -403.890226)
		(width 0.14224)
		(layer "In4.Cu")
		(net "P5E_CPU1_P2_TX_BUF_DP<2>")
	)
	(segment
		(start 118.550436 -404.73503)
		(end 118.820946 -404.46452)
		(width 0.12954)
		(layer "F.Cu")
		(net "P5E_CPU1_P2_TX_BUF_DP<1>")
	)
	(segment
		(start 118.550436 -407.954734)
		(end 118.550436 -404.73503)
		(width 0.12954)
		(layer "F.Cu")
		(net "P5E_CPU1_P2_TX_BUF_DP<1>")
	)
	(segment
		(start 148.498306 -389.467344)
		(end 149.019006 -389.467344)
		(width 0.127)
		(layer "F.Cu")
		(net "P5E_CPU1_P2_TX_BUF_DP<1>")
	)
	(segment
		(start 118.846346 -408.250644)
		(end 118.550436 -407.954734)
		(width 0.12954)
		(layer "F.Cu")
		(net "P5E_CPU1_P2_TX_BUF_DP<1>")
	)
	(segment
		(start 147.93722 -391.285984)
		(end 147.442428 -391.285984)
		(width 0.14224)
		(layer "In4.Cu")
		(net "P5E_CPU1_P2_TX_BUF_DP<1>")
	)
	(segment
		(start 145.511774 -394.218414)
		(end 145.022316 -394.707872)
		(width 0.14224)
		(layer "In4.Cu")
		(net "P5E_CPU1_P2_TX_BUF_DP<1>")
	)
	(segment
		(start 120.942862 -402.414994)
		(end 120.868694 -402.594572)
		(width 0.14224)
		(layer "In4.Cu")
		(net "P5E_CPU1_P2_TX_BUF_DP<1>")
	)
	(segment
		(start 118.745508 -403.442932)
		(end 118.663466 -403.524974)
		(width 0.14224)
		(layer "In4.Cu")
		(net "P5E_CPU1_P2_TX_BUF_DP<1>")
	)
	(segment
		(start 118.530116 -404.17369)
		(end 118.820946 -404.46452)
		(width 0.14224)
		(layer "In4.Cu")
		(net "P5E_CPU1_P2_TX_BUF_DP<1>")
	)
	(segment
		(start 146.948144 -391.93597)
		(end 146.948144 -392.774424)
		(width 0.14224)
		(layer "In4.Cu")
		(net "P5E_CPU1_P2_TX_BUF_DP<1>")
	)
	(segment
		(start 123.026932 -401.551648)
		(end 122.952764 -401.731226)
		(width 0.14224)
		(layer "In4.Cu")
		(net "P5E_CPU1_P2_TX_BUF_DP<1>")
	)
	(segment
		(start 120.868694 -402.594572)
		(end 120.474232 -402.757894)
		(width 0.14224)
		(layer "In4.Cu")
		(net "P5E_CPU1_P2_TX_BUF_DP<1>")
	)
	(segment
		(start 128.244092 -399.932398)
		(end 127.157226 -399.932398)
		(width 0.14224)
		(layer "In4.Cu")
		(net "P5E_CPU1_P2_TX_BUF_DP<1>")
	)
	(segment
		(start 148.724112 -389.352536)
		(end 148.634704 -389.441944)
		(width 0.14224)
		(layer "In4.Cu")
		(net "P5E_CPU1_P2_TX_BUF_DP<1>")
	)
	(segment
		(start 122.952764 -401.731226)
		(end 122.558302 -401.894548)
		(width 0.14224)
		(layer "In4.Cu")
		(net "P5E_CPU1_P2_TX_BUF_DP<1>")
	)
	(segment
		(start 144.567148 -394.980668)
		(end 136.722612 -397.360394)
		(width 0.14224)
		(layer "In4.Cu")
		(net "P5E_CPU1_P2_TX_BUF_DP<1>")
	)
	(segment
		(start 126.731522 -400.01698)
		(end 123.026932 -401.551648)
		(width 0.14224)
		(layer "In4.Cu")
		(net "P5E_CPU1_P2_TX_BUF_DP<1>")
	)
	(segment
		(start 118.530116 -403.846792)
		(end 118.530116 -404.17369)
		(width 0.14224)
		(layer "In4.Cu")
		(net "P5E_CPU1_P2_TX_BUF_DP<1>")
	)
	(segment
		(start 136.722612 -397.360394)
		(end 136.722612 -397.360648)
		(width 0.14224)
		(layer "In4.Cu")
		(net "P5E_CPU1_P2_TX_BUF_DP<1>")
	)
	(segment
		(start 122.558302 -401.894548)
		(end 122.379232 -401.820126)
		(width 0.14224)
		(layer "In4.Cu")
		(net "P5E_CPU1_P2_TX_BUF_DP<1>")
	)
	(segment
		(start 148.904198 -389.352536)
		(end 148.724112 -389.352536)
		(width 0.14224)
		(layer "In4.Cu")
		(net "P5E_CPU1_P2_TX_BUF_DP<1>")
	)
	(segment
		(start 148.634704 -389.441944)
		(end 148.634704 -389.563356)
		(width 0.14224)
		(layer "In4.Cu")
		(net "P5E_CPU1_P2_TX_BUF_DP<1>")
	)
	(segment
		(start 121.985024 -401.983448)
		(end 121.910602 -402.162772)
		(width 0.14224)
		(layer "In4.Cu")
		(net "P5E_CPU1_P2_TX_BUF_DP<1>")
	)
	(segment
		(start 147.286726 -391.3505)
		(end 147.122896 -391.51433)
		(width 0.14224)
		(layer "In4.Cu")
		(net "P5E_CPU1_P2_TX_BUF_DP<1>")
	)
	(segment
		(start 146.374866 -393.743942)
		(end 145.511774 -394.218414)
		(width 0.14224)
		(layer "In4.Cu")
		(net "P5E_CPU1_P2_TX_BUF_DP<1>")
	)
	(segment
		(start 136.722612 -397.360648)
		(end 128.244092 -399.932398)
		(width 0.14224)
		(layer "In4.Cu")
		(net "P5E_CPU1_P2_TX_BUF_DP<1>")
	)
	(segment
		(start 121.51614 -402.326094)
		(end 121.33707 -402.251926)
		(width 0.14224)
		(layer "In4.Cu")
		(net "P5E_CPU1_P2_TX_BUF_DP<1>")
	)
	(segment
		(start 120.474232 -402.757894)
		(end 120.294908 -402.683726)
		(width 0.14224)
		(layer "In4.Cu")
		(net "P5E_CPU1_P2_TX_BUF_DP<1>")
	)
	(segment
		(start 149.019006 -389.467344)
		(end 148.904198 -389.352536)
		(width 0.14224)
		(layer "In4.Cu")
		(net "P5E_CPU1_P2_TX_BUF_DP<1>")
	)
	(segment
		(start 121.33707 -402.251926)
		(end 120.942862 -402.414994)
		(width 0.14224)
		(layer "In4.Cu")
		(net "P5E_CPU1_P2_TX_BUF_DP<1>")
	)
	(segment
		(start 122.379232 -401.820126)
		(end 121.985024 -401.983448)
		(width 0.14224)
		(layer "In4.Cu")
		(net "P5E_CPU1_P2_TX_BUF_DP<1>")
	)
	(segment
		(start 148.672042 -389.653526)
		(end 148.89988 -389.881364)
		(width 0.14224)
		(layer "In4.Cu")
		(net "P5E_CPU1_P2_TX_BUF_DP<1>")
	)
	(segment
		(start 148.89988 -390.459214)
		(end 148.169122 -391.189972)
		(width 0.14224)
		(layer "In4.Cu")
		(net "P5E_CPU1_P2_TX_BUF_DP<1>")
	)
	(segment
		(start 121.910602 -402.162772)
		(end 121.51614 -402.326094)
		(width 0.14224)
		(layer "In4.Cu")
		(net "P5E_CPU1_P2_TX_BUF_DP<1>")
	)
	(segment
		(start 120.294908 -402.683726)
		(end 119.259858 -403.112224)
		(width 0.14224)
		(layer "In4.Cu")
		(net "P5E_CPU1_P2_TX_BUF_DP<1>")
	)
	(arc
		(start 148.634704 -389.563356)
		(mid 148.64441 -389.612151)
		(end 148.672042 -389.653526)
		(width 0.14224)
		(layer "In4.Cu")
		(net "P5E_CPU1_P2_TX_BUF_DP<1>")
	)
	(arc
		(start 146.948144 -392.774424)
		(mid 146.794099 -393.337583)
		(end 146.374866 -393.743942)
		(width 0.14224)
		(layer "In4.Cu")
		(net "P5E_CPU1_P2_TX_BUF_DP<1>")
	)
	(arc
		(start 147.122896 -391.51433)
		(mid 146.993583 -391.707766)
		(end 146.948144 -391.93597)
		(width 0.14224)
		(layer "In4.Cu")
		(net "P5E_CPU1_P2_TX_BUF_DP<1>")
	)
	(arc
		(start 148.89988 -389.881364)
		(mid 149.019684 -390.170326)
		(end 148.89988 -390.459214)
		(width 0.14224)
		(layer "In4.Cu")
		(net "P5E_CPU1_P2_TX_BUF_DP<1>")
	)
	(arc
		(start 147.442428 -391.285984)
		(mid 147.358154 -391.302747)
		(end 147.286726 -391.3505)
		(width 0.14224)
		(layer "In4.Cu")
		(net "P5E_CPU1_P2_TX_BUF_DP<1>")
	)
	(arc
		(start 148.169122 -391.189972)
		(mid 148.06271 -391.261011)
		(end 147.93722 -391.285984)
		(width 0.14224)
		(layer "In4.Cu")
		(net "P5E_CPU1_P2_TX_BUF_DP<1>")
	)
	(arc
		(start 119.259858 -403.112224)
		(mid 118.987872 -403.254542)
		(end 118.745508 -403.442932)
		(width 0.14224)
		(layer "In4.Cu")
		(net "P5E_CPU1_P2_TX_BUF_DP<1>")
	)
	(arc
		(start 118.663466 -403.524974)
		(mid 118.564755 -403.672611)
		(end 118.530116 -403.846792)
		(width 0.14224)
		(layer "In4.Cu")
		(net "P5E_CPU1_P2_TX_BUF_DP<1>")
	)
	(arc
		(start 145.022316 -394.707872)
		(mid 144.811559 -394.872349)
		(end 144.567148 -394.980668)
		(width 0.14224)
		(layer "In4.Cu")
		(net "P5E_CPU1_P2_TX_BUF_DP<1>")
	)
	(arc
		(start 127.157226 -399.932398)
		(mid 126.940209 -399.953724)
		(end 126.731522 -400.01698)
		(width 0.14224)
		(layer "In4.Cu")
		(net "P5E_CPU1_P2_TX_BUF_DP<1>")
	)
	(segment
		(start 165.298374 -389.467344)
		(end 165.819074 -389.467344)
		(width 0.127)
		(layer "F.Cu")
		(net "P5E_CPU1_P2_TX_BUF_DP<15>")
	)
	(segment
		(start 161.435796 -407.954734)
		(end 161.435796 -404.73503)
		(width 0.12954)
		(layer "F.Cu")
		(net "P5E_CPU1_P2_TX_BUF_DP<15>")
	)
	(segment
		(start 161.435796 -404.73503)
		(end 161.706306 -404.46452)
		(width 0.12954)
		(layer "F.Cu")
		(net "P5E_CPU1_P2_TX_BUF_DP<15>")
	)
	(segment
		(start 161.731706 -408.250644)
		(end 161.435796 -407.954734)
		(width 0.12954)
		(layer "F.Cu")
		(net "P5E_CPU1_P2_TX_BUF_DP<15>")
	)
	(segment
		(start 163.224464 -400.177762)
		(end 162.975036 -400.644614)
		(width 0.14224)
		(layer "In4.Cu")
		(net "P5E_CPU1_P2_TX_BUF_DP<15>")
	)
	(segment
		(start 162.830002 -401.206716)
		(end 162.644074 -401.263104)
		(width 0.14224)
		(layer "In4.Cu")
		(net "P5E_CPU1_P2_TX_BUF_DP<15>")
	)
	(segment
		(start 165.819074 -389.467344)
		(end 165.704266 -389.352536)
		(width 0.14224)
		(layer "In4.Cu")
		(net "P5E_CPU1_P2_TX_BUF_DP<15>")
	)
	(segment
		(start 162.499548 -401.824952)
		(end 162.29838 -402.201634)
		(width 0.14224)
		(layer "In4.Cu")
		(net "P5E_CPU1_P2_TX_BUF_DP<15>")
	)
	(segment
		(start 165.704266 -389.352536)
		(end 165.52418 -389.352536)
		(width 0.14224)
		(layer "In4.Cu")
		(net "P5E_CPU1_P2_TX_BUF_DP<15>")
	)
	(segment
		(start 161.415476 -403.931374)
		(end 161.415476 -404.17369)
		(width 0.14224)
		(layer "In4.Cu")
		(net "P5E_CPU1_P2_TX_BUF_DP<15>")
	)
	(segment
		(start 163.410392 -400.121628)
		(end 163.224464 -400.177762)
		(width 0.14224)
		(layer "In4.Cu")
		(net "P5E_CPU1_P2_TX_BUF_DP<15>")
	)
	(segment
		(start 165.434772 -389.441944)
		(end 165.434772 -389.592566)
		(width 0.14224)
		(layer "In4.Cu")
		(net "P5E_CPU1_P2_TX_BUF_DP<15>")
	)
	(segment
		(start 161.415476 -404.17369)
		(end 161.706306 -404.46452)
		(width 0.14224)
		(layer "In4.Cu")
		(net "P5E_CPU1_P2_TX_BUF_DP<15>")
	)
	(segment
		(start 165.030404 -391.720578)
		(end 165.030404 -394.923518)
		(width 0.14224)
		(layer "In4.Cu")
		(net "P5E_CPU1_P2_TX_BUF_DP<15>")
	)
	(segment
		(start 163.03117 -400.830288)
		(end 162.830002 -401.206716)
		(width 0.14224)
		(layer "In4.Cu")
		(net "P5E_CPU1_P2_TX_BUF_DP<15>")
	)
	(segment
		(start 165.795452 -390.176512)
		(end 165.795452 -390.584944)
		(width 0.14224)
		(layer "In4.Cu")
		(net "P5E_CPU1_P2_TX_BUF_DP<15>")
	)
	(segment
		(start 162.112452 -402.257768)
		(end 161.58972 -403.236176)
		(width 0.14224)
		(layer "In4.Cu")
		(net "P5E_CPU1_P2_TX_BUF_DP<15>")
	)
	(segment
		(start 162.44316 -401.639278)
		(end 162.499548 -401.824952)
		(width 0.14224)
		(layer "In4.Cu")
		(net "P5E_CPU1_P2_TX_BUF_DP<15>")
	)
	(segment
		(start 165.581076 -391.103104)
		(end 165.077648 -391.606532)
		(width 0.14224)
		(layer "In4.Cu")
		(net "P5E_CPU1_P2_TX_BUF_DP<15>")
	)
	(segment
		(start 163.61156 -399.744946)
		(end 163.410392 -400.121628)
		(width 0.14224)
		(layer "In4.Cu")
		(net "P5E_CPU1_P2_TX_BUF_DP<15>")
	)
	(segment
		(start 164.085778 -398.566894)
		(end 163.555172 -399.559526)
		(width 0.14224)
		(layer "In4.Cu")
		(net "P5E_CPU1_P2_TX_BUF_DP<15>")
	)
	(segment
		(start 162.29838 -402.201634)
		(end 162.112452 -402.257768)
		(width 0.14224)
		(layer "In4.Cu")
		(net "P5E_CPU1_P2_TX_BUF_DP<15>")
	)
	(segment
		(start 162.644074 -401.263104)
		(end 162.44316 -401.639278)
		(width 0.14224)
		(layer "In4.Cu")
		(net "P5E_CPU1_P2_TX_BUF_DP<15>")
	)
	(segment
		(start 165.47211 -389.682482)
		(end 165.674802 -389.885174)
		(width 0.14224)
		(layer "In4.Cu")
		(net "P5E_CPU1_P2_TX_BUF_DP<15>")
	)
	(segment
		(start 164.84981 -396.386812)
		(end 164.708332 -396.952216)
		(width 0.14224)
		(layer "In4.Cu")
		(net "P5E_CPU1_P2_TX_BUF_DP<15>")
	)
	(segment
		(start 165.52418 -389.352536)
		(end 165.434772 -389.441944)
		(width 0.14224)
		(layer "In4.Cu")
		(net "P5E_CPU1_P2_TX_BUF_DP<15>")
	)
	(segment
		(start 163.555172 -399.559526)
		(end 163.61156 -399.744946)
		(width 0.14224)
		(layer "In4.Cu")
		(net "P5E_CPU1_P2_TX_BUF_DP<15>")
	)
	(segment
		(start 162.975036 -400.644614)
		(end 163.03117 -400.830288)
		(width 0.14224)
		(layer "In4.Cu")
		(net "P5E_CPU1_P2_TX_BUF_DP<15>")
	)
	(arc
		(start 165.674802 -389.885174)
		(mid 165.764115 -390.018841)
		(end 165.795452 -390.176512)
		(width 0.14224)
		(layer "In4.Cu")
		(net "P5E_CPU1_P2_TX_BUF_DP<15>")
	)
	(arc
		(start 165.795452 -390.584944)
		(mid 165.739857 -390.865381)
		(end 165.581076 -391.103104)
		(width 0.14224)
		(layer "In4.Cu")
		(net "P5E_CPU1_P2_TX_BUF_DP<15>")
	)
	(arc
		(start 164.708332 -396.952216)
		(mid 164.446675 -397.778686)
		(end 164.085778 -398.566894)
		(width 0.14224)
		(layer "In4.Cu")
		(net "P5E_CPU1_P2_TX_BUF_DP<15>")
	)
	(arc
		(start 165.077648 -391.606532)
		(mid 165.042686 -391.658857)
		(end 165.030404 -391.720578)
		(width 0.14224)
		(layer "In4.Cu")
		(net "P5E_CPU1_P2_TX_BUF_DP<15>")
	)
	(arc
		(start 165.030404 -394.923518)
		(mid 164.985051 -395.660711)
		(end 164.84981 -396.386812)
		(width 0.14224)
		(layer "In4.Cu")
		(net "P5E_CPU1_P2_TX_BUF_DP<15>")
	)
	(arc
		(start 165.434772 -389.592566)
		(mid 165.444474 -389.64125)
		(end 165.47211 -389.682482)
		(width 0.14224)
		(layer "In4.Cu")
		(net "P5E_CPU1_P2_TX_BUF_DP<15>")
	)
	(arc
		(start 161.58972 -403.236176)
		(mid 161.45973 -403.573031)
		(end 161.415476 -403.931374)
		(width 0.14224)
		(layer "In4.Cu")
		(net "P5E_CPU1_P2_TX_BUF_DP<15>")
	)
	(segment
		(start 158.668466 -408.250644)
		(end 158.372556 -407.954734)
		(width 0.12954)
		(layer "F.Cu")
		(net "P5E_CPU1_P2_TX_BUF_DP<14>")
	)
	(segment
		(start 164.098224 -389.467344)
		(end 164.618924 -389.467344)
		(width 0.127)
		(layer "F.Cu")
		(net "P5E_CPU1_P2_TX_BUF_DP<14>")
	)
	(segment
		(start 158.372556 -404.73503)
		(end 158.643066 -404.46452)
		(width 0.12954)
		(layer "F.Cu")
		(net "P5E_CPU1_P2_TX_BUF_DP<14>")
	)
	(segment
		(start 158.372556 -407.954734)
		(end 158.372556 -404.73503)
		(width 0.12954)
		(layer "F.Cu")
		(net "P5E_CPU1_P2_TX_BUF_DP<14>")
	)
	(segment
		(start 164.504116 -389.352536)
		(end 164.324284 -389.352536)
		(width 0.14224)
		(layer "In4.Cu")
		(net "P5E_CPU1_P2_TX_BUF_DP<14>")
	)
	(segment
		(start 163.830254 -391.81151)
		(end 163.830254 -395.43609)
		(width 0.14224)
		(layer "In4.Cu")
		(net "P5E_CPU1_P2_TX_BUF_DP<14>")
	)
	(segment
		(start 161.570162 -399.043652)
		(end 161.589212 -399.236692)
		(width 0.14224)
		(layer "In4.Cu")
		(net "P5E_CPU1_P2_TX_BUF_DP<14>")
	)
	(segment
		(start 164.324284 -389.352536)
		(end 164.234876 -389.441944)
		(width 0.14224)
		(layer "In4.Cu")
		(net "P5E_CPU1_P2_TX_BUF_DP<14>")
	)
	(segment
		(start 160.463738 -400.391884)
		(end 160.482534 -400.584924)
		(width 0.14224)
		(layer "In4.Cu")
		(net "P5E_CPU1_P2_TX_BUF_DP<14>")
	)
	(segment
		(start 164.618924 -389.467344)
		(end 164.504116 -389.352536)
		(width 0.14224)
		(layer "In4.Cu")
		(net "P5E_CPU1_P2_TX_BUF_DP<14>")
	)
	(segment
		(start 158.352236 -404.17369)
		(end 158.643066 -404.46452)
		(width 0.14224)
		(layer "In4.Cu")
		(net "P5E_CPU1_P2_TX_BUF_DP<14>")
	)
	(segment
		(start 164.387276 -391.076688)
		(end 163.956238 -391.507472)
		(width 0.14224)
		(layer "In4.Cu")
		(net "P5E_CPU1_P2_TX_BUF_DP<14>")
	)
	(segment
		(start 163.288726 -396.949422)
		(end 162.669474 -397.70431)
		(width 0.14224)
		(layer "In4.Cu")
		(net "P5E_CPU1_P2_TX_BUF_DP<14>")
	)
	(segment
		(start 161.318194 -399.566892)
		(end 161.125154 -399.585942)
		(width 0.14224)
		(layer "In4.Cu")
		(net "P5E_CPU1_P2_TX_BUF_DP<14>")
	)
	(segment
		(start 162.669474 -397.70431)
		(end 162.68827 -397.89735)
		(width 0.14224)
		(layer "In4.Cu")
		(net "P5E_CPU1_P2_TX_BUF_DP<14>")
	)
	(segment
		(start 164.624512 -390.271508)
		(end 164.624512 -390.504426)
		(width 0.14224)
		(layer "In4.Cu")
		(net "P5E_CPU1_P2_TX_BUF_DP<14>")
	)
	(segment
		(start 160.01873 -400.93392)
		(end 159.502348 -401.563078)
		(width 0.14224)
		(layer "In4.Cu")
		(net "P5E_CPU1_P2_TX_BUF_DP<14>")
	)
	(segment
		(start 159.502348 -401.563078)
		(end 158.436564 -403.157944)
		(width 0.14224)
		(layer "In4.Cu")
		(net "P5E_CPU1_P2_TX_BUF_DP<14>")
	)
	(segment
		(start 164.234876 -389.441944)
		(end 164.234876 -389.583422)
		(width 0.14224)
		(layer "In4.Cu")
		(net "P5E_CPU1_P2_TX_BUF_DP<14>")
	)
	(segment
		(start 160.482534 -400.584924)
		(end 160.21177 -400.91487)
		(width 0.14224)
		(layer "In4.Cu")
		(net "P5E_CPU1_P2_TX_BUF_DP<14>")
	)
	(segment
		(start 158.352236 -403.436074)
		(end 158.352236 -404.17369)
		(width 0.14224)
		(layer "In4.Cu")
		(net "P5E_CPU1_P2_TX_BUF_DP<14>")
	)
	(segment
		(start 164.272214 -389.673338)
		(end 164.450268 -389.851138)
		(width 0.14224)
		(layer "In4.Cu")
		(net "P5E_CPU1_P2_TX_BUF_DP<14>")
	)
	(segment
		(start 162.417506 -398.227296)
		(end 162.224466 -398.246346)
		(width 0.14224)
		(layer "In4.Cu")
		(net "P5E_CPU1_P2_TX_BUF_DP<14>")
	)
	(segment
		(start 160.21177 -400.91487)
		(end 160.01873 -400.93392)
		(width 0.14224)
		(layer "In4.Cu")
		(net "P5E_CPU1_P2_TX_BUF_DP<14>")
	)
	(segment
		(start 161.125154 -399.585942)
		(end 160.463738 -400.391884)
		(width 0.14224)
		(layer "In4.Cu")
		(net "P5E_CPU1_P2_TX_BUF_DP<14>")
	)
	(segment
		(start 161.589212 -399.236692)
		(end 161.318194 -399.566892)
		(width 0.14224)
		(layer "In4.Cu")
		(net "P5E_CPU1_P2_TX_BUF_DP<14>")
	)
	(segment
		(start 162.68827 -397.89735)
		(end 162.417506 -398.227296)
		(width 0.14224)
		(layer "In4.Cu")
		(net "P5E_CPU1_P2_TX_BUF_DP<14>")
	)
	(segment
		(start 162.224466 -398.246346)
		(end 161.570162 -399.043652)
		(width 0.14224)
		(layer "In4.Cu")
		(net "P5E_CPU1_P2_TX_BUF_DP<14>")
	)
	(arc
		(start 164.234876 -389.583422)
		(mid 164.244578 -389.632106)
		(end 164.272214 -389.673338)
		(width 0.14224)
		(layer "In4.Cu")
		(net "P5E_CPU1_P2_TX_BUF_DP<14>")
	)
	(arc
		(start 163.956238 -391.507472)
		(mid 163.862977 -391.646952)
		(end 163.830254 -391.81151)
		(width 0.14224)
		(layer "In4.Cu")
		(net "P5E_CPU1_P2_TX_BUF_DP<14>")
	)
	(arc
		(start 163.830254 -395.43609)
		(mid 163.690756 -396.239729)
		(end 163.288726 -396.949422)
		(width 0.14224)
		(layer "In4.Cu")
		(net "P5E_CPU1_P2_TX_BUF_DP<14>")
	)
	(arc
		(start 164.450268 -389.851138)
		(mid 164.579192 -390.043991)
		(end 164.624512 -390.271508)
		(width 0.14224)
		(layer "In4.Cu")
		(net "P5E_CPU1_P2_TX_BUF_DP<14>")
	)
	(arc
		(start 158.436564 -403.157944)
		(mid 158.373789 -403.290759)
		(end 158.352236 -403.436074)
		(width 0.14224)
		(layer "In4.Cu")
		(net "P5E_CPU1_P2_TX_BUF_DP<14>")
	)
	(arc
		(start 164.624512 -390.504426)
		(mid 164.562863 -390.814179)
		(end 164.387276 -391.076688)
		(width 0.14224)
		(layer "In4.Cu")
		(net "P5E_CPU1_P2_TX_BUF_DP<14>")
	)
	(segment
		(start 162.898328 -389.467344)
		(end 163.419028 -389.467344)
		(width 0.127)
		(layer "F.Cu")
		(net "P5E_CPU1_P2_TX_BUF_DP<13>")
	)
	(segment
		(start 155.605226 -408.250644)
		(end 155.309316 -407.954734)
		(width 0.12954)
		(layer "F.Cu")
		(net "P5E_CPU1_P2_TX_BUF_DP<13>")
	)
	(segment
		(start 155.309316 -407.954734)
		(end 155.309316 -404.73503)
		(width 0.12954)
		(layer "F.Cu")
		(net "P5E_CPU1_P2_TX_BUF_DP<13>")
	)
	(segment
		(start 155.309316 -404.73503)
		(end 155.579826 -404.46452)
		(width 0.12954)
		(layer "F.Cu")
		(net "P5E_CPU1_P2_TX_BUF_DP<13>")
	)
	(segment
		(start 157.644846 -401.097242)
		(end 156.82976 -401.912328)
		(width 0.14224)
		(layer "In4.Cu")
		(net "P5E_CPU1_P2_TX_BUF_DP<13>")
	)
	(segment
		(start 156.333952 -402.408136)
		(end 155.52801 -403.214078)
		(width 0.14224)
		(layer "In4.Cu")
		(net "P5E_CPU1_P2_TX_BUF_DP<13>")
	)
	(segment
		(start 156.82976 -402.10613)
		(end 156.527754 -402.408136)
		(width 0.14224)
		(layer "In4.Cu")
		(net "P5E_CPU1_P2_TX_BUF_DP<13>")
	)
	(segment
		(start 158.951168 -399.984722)
		(end 158.757366 -399.984722)
		(width 0.14224)
		(layer "In4.Cu")
		(net "P5E_CPU1_P2_TX_BUF_DP<13>")
	)
	(segment
		(start 159.253174 -399.682716)
		(end 158.951168 -399.984722)
		(width 0.14224)
		(layer "In4.Cu")
		(net "P5E_CPU1_P2_TX_BUF_DP<13>")
	)
	(segment
		(start 158.140908 -400.60118)
		(end 158.140908 -400.795236)
		(width 0.14224)
		(layer "In4.Cu")
		(net "P5E_CPU1_P2_TX_BUF_DP<13>")
	)
	(segment
		(start 159.253174 -399.488914)
		(end 159.253174 -399.682716)
		(width 0.14224)
		(layer "In4.Cu")
		(net "P5E_CPU1_P2_TX_BUF_DP<13>")
	)
	(segment
		(start 163.20262 -391.06475)
		(end 162.680142 -391.587228)
		(width 0.14224)
		(layer "In4.Cu")
		(net "P5E_CPU1_P2_TX_BUF_DP<13>")
	)
	(segment
		(start 162.630358 -391.70737)
		(end 162.630358 -395.648942)
		(width 0.14224)
		(layer "In4.Cu")
		(net "P5E_CPU1_P2_TX_BUF_DP<13>")
	)
	(segment
		(start 162.303206 -396.438882)
		(end 159.253174 -399.488914)
		(width 0.14224)
		(layer "In4.Cu")
		(net "P5E_CPU1_P2_TX_BUF_DP<13>")
	)
	(segment
		(start 158.140908 -400.795236)
		(end 157.838902 -401.097242)
		(width 0.14224)
		(layer "In4.Cu")
		(net "P5E_CPU1_P2_TX_BUF_DP<13>")
	)
	(segment
		(start 163.395406 -390.382506)
		(end 163.395406 -390.564624)
		(width 0.14224)
		(layer "In4.Cu")
		(net "P5E_CPU1_P2_TX_BUF_DP<13>")
	)
	(segment
		(start 158.757366 -399.984722)
		(end 158.140908 -400.60118)
		(width 0.14224)
		(layer "In4.Cu")
		(net "P5E_CPU1_P2_TX_BUF_DP<13>")
	)
	(segment
		(start 156.82976 -401.912328)
		(end 156.82976 -402.10613)
		(width 0.14224)
		(layer "In4.Cu")
		(net "P5E_CPU1_P2_TX_BUF_DP<13>")
	)
	(segment
		(start 163.30422 -389.352536)
		(end 163.124134 -389.352536)
		(width 0.14224)
		(layer "In4.Cu")
		(net "P5E_CPU1_P2_TX_BUF_DP<13>")
	)
	(segment
		(start 155.288996 -403.790912)
		(end 155.288996 -404.17369)
		(width 0.14224)
		(layer "In4.Cu")
		(net "P5E_CPU1_P2_TX_BUF_DP<13>")
	)
	(segment
		(start 156.527754 -402.408136)
		(end 156.333952 -402.408136)
		(width 0.14224)
		(layer "In4.Cu")
		(net "P5E_CPU1_P2_TX_BUF_DP<13>")
	)
	(segment
		(start 163.034726 -389.441944)
		(end 163.034726 -389.504936)
		(width 0.14224)
		(layer "In4.Cu")
		(net "P5E_CPU1_P2_TX_BUF_DP<13>")
	)
	(segment
		(start 163.419028 -389.467344)
		(end 163.30422 -389.352536)
		(width 0.14224)
		(layer "In4.Cu")
		(net "P5E_CPU1_P2_TX_BUF_DP<13>")
	)
	(segment
		(start 157.838902 -401.097242)
		(end 157.644846 -401.097242)
		(width 0.14224)
		(layer "In4.Cu")
		(net "P5E_CPU1_P2_TX_BUF_DP<13>")
	)
	(segment
		(start 155.288996 -404.17369)
		(end 155.579826 -404.46452)
		(width 0.14224)
		(layer "In4.Cu")
		(net "P5E_CPU1_P2_TX_BUF_DP<13>")
	)
	(segment
		(start 163.124134 -389.352536)
		(end 163.034726 -389.441944)
		(width 0.14224)
		(layer "In4.Cu")
		(net "P5E_CPU1_P2_TX_BUF_DP<13>")
	)
	(arc
		(start 163.034726 -389.504936)
		(mid 163.060388 -389.634842)
		(end 163.133532 -389.74522)
		(width 0.14224)
		(layer "In4.Cu")
		(net "P5E_CPU1_P2_TX_BUF_DP<13>")
	)
	(arc
		(start 162.680142 -391.587228)
		(mid 162.643311 -391.64235)
		(end 162.630358 -391.70737)
		(width 0.14224)
		(layer "In4.Cu")
		(net "P5E_CPU1_P2_TX_BUF_DP<13>")
	)
	(arc
		(start 155.52801 -403.214078)
		(mid 155.35112 -403.478717)
		(end 155.288996 -403.790912)
		(width 0.14224)
		(layer "In4.Cu")
		(net "P5E_CPU1_P2_TX_BUF_DP<13>")
	)
	(arc
		(start 163.133532 -389.74522)
		(mid 163.327483 -390.037977)
		(end 163.395406 -390.382506)
		(width 0.14224)
		(layer "In4.Cu")
		(net "P5E_CPU1_P2_TX_BUF_DP<13>")
	)
	(arc
		(start 163.395406 -390.564624)
		(mid 163.379736 -390.721337)
		(end 163.332922 -390.87171)
		(width 0.14224)
		(layer "In4.Cu")
		(net "P5E_CPU1_P2_TX_BUF_DP<13>")
	)
	(arc
		(start 162.630358 -395.648942)
		(mid 162.545339 -396.076449)
		(end 162.303206 -396.438882)
		(width 0.14224)
		(layer "In4.Cu")
		(net "P5E_CPU1_P2_TX_BUF_DP<13>")
	)
	(arc
		(start 163.332922 -390.87171)
		(mid 163.27698 -390.974445)
		(end 163.20262 -391.06475)
		(width 0.14224)
		(layer "In4.Cu")
		(net "P5E_CPU1_P2_TX_BUF_DP<13>")
	)
	(segment
		(start 152.246076 -404.73503)
		(end 152.516586 -404.46452)
		(width 0.12954)
		(layer "F.Cu")
		(net "P5E_CPU1_P2_TX_BUF_DP<12>")
	)
	(segment
		(start 161.698178 -389.467344)
		(end 162.218878 -389.467344)
		(width 0.127)
		(layer "F.Cu")
		(net "P5E_CPU1_P2_TX_BUF_DP<12>")
	)
	(segment
		(start 152.246076 -407.954734)
		(end 152.246076 -404.73503)
		(width 0.12954)
		(layer "F.Cu")
		(net "P5E_CPU1_P2_TX_BUF_DP<12>")
	)
	(segment
		(start 152.541986 -408.250644)
		(end 152.246076 -407.954734)
		(width 0.12954)
		(layer "F.Cu")
		(net "P5E_CPU1_P2_TX_BUF_DP<12>")
	)
	(segment
		(start 161.430208 -395.236446)
		(end 161.567368 -395.099286)
		(width 0.14224)
		(layer "In4.Cu")
		(net "P5E_CPU1_P2_TX_BUF_DP<12>")
	)
	(segment
		(start 161.83483 -389.521954)
		(end 161.83483 -389.441944)
		(width 0.14224)
		(layer "In4.Cu")
		(net "P5E_CPU1_P2_TX_BUF_DP<12>")
	)
	(segment
		(start 161.567368 -395.099286)
		(end 161.567368 -394.672566)
		(width 0.14224)
		(layer "In4.Cu")
		(net "P5E_CPU1_P2_TX_BUF_DP<12>")
	)
	(segment
		(start 155.255468 -402.10994)
		(end 161.237676 -396.127732)
		(width 0.14224)
		(layer "In4.Cu")
		(net "P5E_CPU1_P2_TX_BUF_DP<12>")
	)
	(segment
		(start 153.091134 -403.263862)
		(end 153.483564 -403.09546)
		(width 0.14224)
		(layer "In4.Cu")
		(net "P5E_CPU1_P2_TX_BUF_DP<12>")
	)
	(segment
		(start 154.519884 -402.650452)
		(end 154.591766 -402.470112)
		(width 0.14224)
		(layer "In4.Cu")
		(net "P5E_CPU1_P2_TX_BUF_DP<12>")
	)
	(segment
		(start 162.10407 -389.352536)
		(end 162.218878 -389.467344)
		(width 0.14224)
		(layer "In4.Cu")
		(net "P5E_CPU1_P2_TX_BUF_DP<12>")
	)
	(segment
		(start 161.83483 -389.441944)
		(end 161.924238 -389.352536)
		(width 0.14224)
		(layer "In4.Cu")
		(net "P5E_CPU1_P2_TX_BUF_DP<12>")
	)
	(segment
		(start 153.947368 -402.746972)
		(end 154.127454 -402.818854)
		(width 0.14224)
		(layer "In4.Cu")
		(net "P5E_CPU1_P2_TX_BUF_DP<12>")
	)
	(segment
		(start 152.519126 -403.360128)
		(end 152.911048 -403.19198)
		(width 0.14224)
		(layer "In4.Cu")
		(net "P5E_CPU1_P2_TX_BUF_DP<12>")
	)
	(segment
		(start 161.477452 -391.569702)
		(end 161.964624 -391.08253)
		(width 0.14224)
		(layer "In4.Cu")
		(net "P5E_CPU1_P2_TX_BUF_DP<12>")
	)
	(segment
		(start 161.430208 -394.535406)
		(end 161.430208 -391.683748)
		(width 0.14224)
		(layer "In4.Cu")
		(net "P5E_CPU1_P2_TX_BUF_DP<12>")
	)
	(segment
		(start 152.911048 -403.19198)
		(end 153.091134 -403.263862)
		(width 0.14224)
		(layer "In4.Cu")
		(net "P5E_CPU1_P2_TX_BUF_DP<12>")
	)
	(segment
		(start 152.225756 -404.17369)
		(end 152.225756 -403.745192)
		(width 0.14224)
		(layer "In4.Cu")
		(net "P5E_CPU1_P2_TX_BUF_DP<12>")
	)
	(segment
		(start 161.430208 -395.663166)
		(end 161.430208 -395.236446)
		(width 0.14224)
		(layer "In4.Cu")
		(net "P5E_CPU1_P2_TX_BUF_DP<12>")
	)
	(segment
		(start 153.483564 -403.09546)
		(end 153.555446 -402.91512)
		(width 0.14224)
		(layer "In4.Cu")
		(net "P5E_CPU1_P2_TX_BUF_DP<12>")
	)
	(segment
		(start 162.063176 -389.864092)
		(end 161.915602 -389.716772)
		(width 0.14224)
		(layer "In4.Cu")
		(net "P5E_CPU1_P2_TX_BUF_DP<12>")
	)
	(segment
		(start 154.591766 -402.470112)
		(end 154.952192 -402.315426)
		(width 0.14224)
		(layer "In4.Cu")
		(net "P5E_CPU1_P2_TX_BUF_DP<12>")
	)
	(segment
		(start 162.183318 -390.554718)
		(end 162.183318 -390.153652)
		(width 0.14224)
		(layer "In4.Cu")
		(net "P5E_CPU1_P2_TX_BUF_DP<12>")
	)
	(segment
		(start 152.29078 -403.588474)
		(end 152.519126 -403.360128)
		(width 0.14224)
		(layer "In4.Cu")
		(net "P5E_CPU1_P2_TX_BUF_DP<12>")
	)
	(segment
		(start 152.516586 -404.46452)
		(end 152.225756 -404.17369)
		(width 0.14224)
		(layer "In4.Cu")
		(net "P5E_CPU1_P2_TX_BUF_DP<12>")
	)
	(segment
		(start 161.924238 -389.352536)
		(end 162.10407 -389.352536)
		(width 0.14224)
		(layer "In4.Cu")
		(net "P5E_CPU1_P2_TX_BUF_DP<12>")
	)
	(segment
		(start 153.555446 -402.91512)
		(end 153.947368 -402.746972)
		(width 0.14224)
		(layer "In4.Cu")
		(net "P5E_CPU1_P2_TX_BUF_DP<12>")
	)
	(segment
		(start 161.567368 -394.672566)
		(end 161.430208 -394.535406)
		(width 0.14224)
		(layer "In4.Cu")
		(net "P5E_CPU1_P2_TX_BUF_DP<12>")
	)
	(segment
		(start 154.127454 -402.818854)
		(end 154.519884 -402.650452)
		(width 0.14224)
		(layer "In4.Cu")
		(net "P5E_CPU1_P2_TX_BUF_DP<12>")
	)
	(arc
		(start 152.225756 -403.745192)
		(mid 152.24265 -403.660349)
		(end 152.29078 -403.588474)
		(width 0.14224)
		(layer "In4.Cu")
		(net "P5E_CPU1_P2_TX_BUF_DP<12>")
	)
	(arc
		(start 161.915602 -389.716772)
		(mid 161.855824 -389.627403)
		(end 161.83483 -389.521954)
		(width 0.14224)
		(layer "In4.Cu")
		(net "P5E_CPU1_P2_TX_BUF_DP<12>")
	)
	(arc
		(start 162.183318 -390.153652)
		(mid 162.152086 -389.996909)
		(end 162.063176 -389.864092)
		(width 0.14224)
		(layer "In4.Cu")
		(net "P5E_CPU1_P2_TX_BUF_DP<12>")
	)
	(arc
		(start 154.952192 -402.315426)
		(mid 155.113605 -402.227113)
		(end 155.255468 -402.10994)
		(width 0.14224)
		(layer "In4.Cu")
		(net "P5E_CPU1_P2_TX_BUF_DP<12>")
	)
	(arc
		(start 161.430208 -391.683748)
		(mid 161.442485 -391.622025)
		(end 161.477452 -391.569702)
		(width 0.14224)
		(layer "In4.Cu")
		(net "P5E_CPU1_P2_TX_BUF_DP<12>")
	)
	(arc
		(start 161.237676 -396.127732)
		(mid 161.380148 -395.914602)
		(end 161.430208 -395.663166)
		(width 0.14224)
		(layer "In4.Cu")
		(net "P5E_CPU1_P2_TX_BUF_DP<12>")
	)
	(arc
		(start 161.964624 -391.08253)
		(mid 162.126485 -390.840382)
		(end 162.183318 -390.554718)
		(width 0.14224)
		(layer "In4.Cu")
		(net "P5E_CPU1_P2_TX_BUF_DP<12>")
	)
	(segment
		(start 149.182836 -404.73503)
		(end 149.453346 -404.46452)
		(width 0.12954)
		(layer "F.Cu")
		(net "P5E_CPU1_P2_TX_BUF_DP<11>")
	)
	(segment
		(start 160.498282 -389.467344)
		(end 161.018982 -389.467344)
		(width 0.127)
		(layer "F.Cu")
		(net "P5E_CPU1_P2_TX_BUF_DP<11>")
	)
	(segment
		(start 149.478746 -408.250644)
		(end 149.182836 -407.954734)
		(width 0.12954)
		(layer "F.Cu")
		(net "P5E_CPU1_P2_TX_BUF_DP<11>")
	)
	(segment
		(start 149.182836 -407.954734)
		(end 149.182836 -404.73503)
		(width 0.12954)
		(layer "F.Cu")
		(net "P5E_CPU1_P2_TX_BUF_DP<11>")
	)
	(segment
		(start 153.484072 -401.75815)
		(end 152.772364 -402.05279)
		(width 0.14224)
		(layer "In4.Cu")
		(net "P5E_CPU1_P2_TX_BUF_DP<11>")
	)
	(segment
		(start 149.162516 -403.851872)
		(end 149.162516 -404.17369)
		(width 0.14224)
		(layer "In4.Cu")
		(net "P5E_CPU1_P2_TX_BUF_DP<11>")
	)
	(segment
		(start 151.492966 -402.582634)
		(end 151.418544 -402.761958)
		(width 0.14224)
		(layer "In4.Cu")
		(net "P5E_CPU1_P2_TX_BUF_DP<11>")
	)
	(segment
		(start 160.706562 -389.718042)
		(end 160.875472 -389.886952)
		(width 0.14224)
		(layer "In4.Cu")
		(net "P5E_CPU1_P2_TX_BUF_DP<11>")
	)
	(segment
		(start 152.698196 -402.232114)
		(end 152.30348 -402.395436)
		(width 0.14224)
		(layer "In4.Cu")
		(net "P5E_CPU1_P2_TX_BUF_DP<11>")
	)
	(segment
		(start 152.30348 -402.395436)
		(end 152.12441 -402.321268)
		(width 0.14224)
		(layer "In4.Cu")
		(net "P5E_CPU1_P2_TX_BUF_DP<11>")
	)
	(segment
		(start 160.99536 -390.176512)
		(end 160.99536 -390.430004)
		(width 0.14224)
		(layer "In4.Cu")
		(net "P5E_CPU1_P2_TX_BUF_DP<11>")
	)
	(segment
		(start 149.80285 -403.282658)
		(end 149.378416 -403.458426)
		(width 0.14224)
		(layer "In4.Cu")
		(net "P5E_CPU1_P2_TX_BUF_DP<11>")
	)
	(segment
		(start 160.63468 -389.441944)
		(end 160.63468 -389.544814)
		(width 0.14224)
		(layer "In4.Cu")
		(net "P5E_CPU1_P2_TX_BUF_DP<11>")
	)
	(segment
		(start 152.772364 -402.05279)
		(end 152.698196 -402.232114)
		(width 0.14224)
		(layer "In4.Cu")
		(net "P5E_CPU1_P2_TX_BUF_DP<11>")
	)
	(segment
		(start 152.12441 -402.321268)
		(end 151.492966 -402.582634)
		(width 0.14224)
		(layer "In4.Cu")
		(net "P5E_CPU1_P2_TX_BUF_DP<11>")
	)
	(segment
		(start 150.845012 -402.851112)
		(end 150.450804 -403.01418)
		(width 0.14224)
		(layer "In4.Cu")
		(net "P5E_CPU1_P2_TX_BUF_DP<11>")
	)
	(segment
		(start 151.024082 -402.92528)
		(end 150.845012 -402.851112)
		(width 0.14224)
		(layer "In4.Cu")
		(net "P5E_CPU1_P2_TX_BUF_DP<11>")
	)
	(segment
		(start 160.230312 -391.667238)
		(end 160.230312 -395.196822)
		(width 0.14224)
		(layer "In4.Cu")
		(net "P5E_CPU1_P2_TX_BUF_DP<11>")
	)
	(segment
		(start 160.904174 -389.352536)
		(end 160.724088 -389.352536)
		(width 0.14224)
		(layer "In4.Cu")
		(net "P5E_CPU1_P2_TX_BUF_DP<11>")
	)
	(segment
		(start 160.708594 -391.122154)
		(end 160.277556 -391.553192)
		(width 0.14224)
		(layer "In4.Cu")
		(net "P5E_CPU1_P2_TX_BUF_DP<11>")
	)
	(segment
		(start 159.84347 -396.130526)
		(end 155.689554 -400.284442)
		(width 0.14224)
		(layer "In4.Cu")
		(net "P5E_CPU1_P2_TX_BUF_DP<11>")
	)
	(segment
		(start 160.724088 -389.352536)
		(end 160.63468 -389.441944)
		(width 0.14224)
		(layer "In4.Cu")
		(net "P5E_CPU1_P2_TX_BUF_DP<11>")
	)
	(segment
		(start 151.418544 -402.761958)
		(end 151.024082 -402.92528)
		(width 0.14224)
		(layer "In4.Cu")
		(net "P5E_CPU1_P2_TX_BUF_DP<11>")
	)
	(segment
		(start 149.98192 -403.35708)
		(end 149.80285 -403.282658)
		(width 0.14224)
		(layer "In4.Cu")
		(net "P5E_CPU1_P2_TX_BUF_DP<11>")
	)
	(segment
		(start 149.162516 -404.17369)
		(end 149.453346 -404.46452)
		(width 0.14224)
		(layer "In4.Cu")
		(net "P5E_CPU1_P2_TX_BUF_DP<11>")
	)
	(segment
		(start 161.018982 -389.467344)
		(end 160.904174 -389.352536)
		(width 0.14224)
		(layer "In4.Cu")
		(net "P5E_CPU1_P2_TX_BUF_DP<11>")
	)
	(segment
		(start 149.378416 -403.458426)
		(end 149.288246 -403.548596)
		(width 0.14224)
		(layer "In4.Cu")
		(net "P5E_CPU1_P2_TX_BUF_DP<11>")
	)
	(segment
		(start 150.450804 -403.01418)
		(end 150.376382 -403.193758)
		(width 0.14224)
		(layer "In4.Cu")
		(net "P5E_CPU1_P2_TX_BUF_DP<11>")
	)
	(segment
		(start 150.376382 -403.193758)
		(end 149.98192 -403.35708)
		(width 0.14224)
		(layer "In4.Cu")
		(net "P5E_CPU1_P2_TX_BUF_DP<11>")
	)
	(arc
		(start 149.288246 -403.548596)
		(mid 149.195219 -403.687726)
		(end 149.162516 -403.851872)
		(width 0.14224)
		(layer "In4.Cu")
		(net "P5E_CPU1_P2_TX_BUF_DP<11>")
	)
	(arc
		(start 160.230312 -395.196822)
		(mid 160.129776 -395.702159)
		(end 159.84347 -396.130526)
		(width 0.14224)
		(layer "In4.Cu")
		(net "P5E_CPU1_P2_TX_BUF_DP<11>")
	)
	(arc
		(start 160.99536 -390.430004)
		(mid 160.920829 -390.804605)
		(end 160.708594 -391.122154)
		(width 0.14224)
		(layer "In4.Cu")
		(net "P5E_CPU1_P2_TX_BUF_DP<11>")
	)
	(arc
		(start 160.875472 -389.886952)
		(mid 160.964187 -390.019817)
		(end 160.99536 -390.176512)
		(width 0.14224)
		(layer "In4.Cu")
		(net "P5E_CPU1_P2_TX_BUF_DP<11>")
	)
	(arc
		(start 160.63468 -389.544814)
		(mid 160.653368 -389.638585)
		(end 160.706562 -389.718042)
		(width 0.14224)
		(layer "In4.Cu")
		(net "P5E_CPU1_P2_TX_BUF_DP<11>")
	)
	(arc
		(start 160.277556 -391.553192)
		(mid 160.242594 -391.605517)
		(end 160.230312 -391.667238)
		(width 0.14224)
		(layer "In4.Cu")
		(net "P5E_CPU1_P2_TX_BUF_DP<11>")
	)
	(arc
		(start 155.689554 -400.284442)
		(mid 154.659385 -401.129899)
		(end 153.484072 -401.75815)
		(width 0.14224)
		(layer "In4.Cu")
		(net "P5E_CPU1_P2_TX_BUF_DP<11>")
	)
	(segment
		(start 159.298386 -389.467344)
		(end 159.819086 -389.467344)
		(width 0.127)
		(layer "F.Cu")
		(net "P5E_CPU1_P2_TX_BUF_DP<10>")
	)
	(segment
		(start 146.119596 -407.954734)
		(end 146.119596 -404.73503)
		(width 0.12954)
		(layer "F.Cu")
		(net "P5E_CPU1_P2_TX_BUF_DP<10>")
	)
	(segment
		(start 146.119596 -404.73503)
		(end 146.390106 -404.46452)
		(width 0.12954)
		(layer "F.Cu")
		(net "P5E_CPU1_P2_TX_BUF_DP<10>")
	)
	(segment
		(start 146.415506 -408.250644)
		(end 146.119596 -407.954734)
		(width 0.12954)
		(layer "F.Cu")
		(net "P5E_CPU1_P2_TX_BUF_DP<10>")
	)
	(segment
		(start 159.01162 -391.620756)
		(end 159.501078 -391.131298)
		(width 0.14224)
		(layer "In4.Cu")
		(net "P5E_CPU1_P2_TX_BUF_DP<10>")
	)
	(segment
		(start 155.019502 -399.577052)
		(end 158.844488 -395.752066)
		(width 0.14224)
		(layer "In4.Cu")
		(net "P5E_CPU1_P2_TX_BUF_DP<10>")
	)
	(segment
		(start 146.830796 -403.227286)
		(end 147.001992 -403.318726)
		(width 0.14224)
		(layer "In4.Cu")
		(net "P5E_CPU1_P2_TX_BUF_DP<10>")
	)
	(segment
		(start 159.434784 -389.59155)
		(end 159.434784 -389.441944)
		(width 0.14224)
		(layer "In4.Cu")
		(net "P5E_CPU1_P2_TX_BUF_DP<10>")
	)
	(segment
		(start 159.524192 -389.352536)
		(end 159.704278 -389.352536)
		(width 0.14224)
		(layer "In4.Cu")
		(net "P5E_CPU1_P2_TX_BUF_DP<10>")
	)
	(segment
		(start 148.081238 -402.99132)
		(end 148.48967 -402.867622)
		(width 0.14224)
		(layer "In4.Cu")
		(net "P5E_CPU1_P2_TX_BUF_DP<10>")
	)
	(segment
		(start 158.964376 -395.03604)
		(end 159.101536 -394.89888)
		(width 0.14224)
		(layer "In4.Cu")
		(net "P5E_CPU1_P2_TX_BUF_DP<10>")
	)
	(segment
		(start 146.099276 -404.17369)
		(end 146.099276 -403.7838)
		(width 0.14224)
		(layer "In4.Cu")
		(net "P5E_CPU1_P2_TX_BUF_DP<10>")
	)
	(segment
		(start 159.795464 -390.420606)
		(end 159.795464 -390.176258)
		(width 0.14224)
		(layer "In4.Cu")
		(net "P5E_CPU1_P2_TX_BUF_DP<10>")
	)
	(segment
		(start 147.910042 -402.89988)
		(end 148.081238 -402.99132)
		(width 0.14224)
		(layer "In4.Cu")
		(net "P5E_CPU1_P2_TX_BUF_DP<10>")
	)
	(segment
		(start 159.434784 -389.441944)
		(end 159.524192 -389.352536)
		(width 0.14224)
		(layer "In4.Cu")
		(net "P5E_CPU1_P2_TX_BUF_DP<10>")
	)
	(segment
		(start 149.330664 -402.469096)
		(end 152.91054 -400.986244)
		(width 0.14224)
		(layer "In4.Cu")
		(net "P5E_CPU1_P2_TX_BUF_DP<10>")
	)
	(segment
		(start 146.422618 -403.350984)
		(end 146.830796 -403.227286)
		(width 0.14224)
		(layer "In4.Cu")
		(net "P5E_CPU1_P2_TX_BUF_DP<10>")
	)
	(segment
		(start 148.58111 -402.696172)
		(end 149.330664 -402.469096)
		(width 0.14224)
		(layer "In4.Cu")
		(net "P5E_CPU1_P2_TX_BUF_DP<10>")
	)
	(segment
		(start 159.101536 -394.47216)
		(end 158.964376 -394.335)
		(width 0.14224)
		(layer "In4.Cu")
		(net "P5E_CPU1_P2_TX_BUF_DP<10>")
	)
	(segment
		(start 148.48967 -402.867622)
		(end 148.58111 -402.696172)
		(width 0.14224)
		(layer "In4.Cu")
		(net "P5E_CPU1_P2_TX_BUF_DP<10>")
	)
	(segment
		(start 159.704278 -389.352536)
		(end 159.819086 -389.467344)
		(width 0.14224)
		(layer "In4.Cu")
		(net "P5E_CPU1_P2_TX_BUF_DP<10>")
	)
	(segment
		(start 159.674306 -389.88365)
		(end 159.472122 -389.681466)
		(width 0.14224)
		(layer "In4.Cu")
		(net "P5E_CPU1_P2_TX_BUF_DP<10>")
	)
	(segment
		(start 147.410424 -403.194774)
		(end 147.501864 -403.023578)
		(width 0.14224)
		(layer "In4.Cu")
		(net "P5E_CPU1_P2_TX_BUF_DP<10>")
	)
	(segment
		(start 146.390106 -404.46452)
		(end 146.099276 -404.17369)
		(width 0.14224)
		(layer "In4.Cu")
		(net "P5E_CPU1_P2_TX_BUF_DP<10>")
	)
	(segment
		(start 159.101536 -394.89888)
		(end 159.101536 -394.47216)
		(width 0.14224)
		(layer "In4.Cu")
		(net "P5E_CPU1_P2_TX_BUF_DP<10>")
	)
	(segment
		(start 147.001992 -403.318726)
		(end 147.410424 -403.194774)
		(width 0.14224)
		(layer "In4.Cu")
		(net "P5E_CPU1_P2_TX_BUF_DP<10>")
	)
	(segment
		(start 158.964376 -395.46276)
		(end 158.964376 -395.03604)
		(width 0.14224)
		(layer "In4.Cu")
		(net "P5E_CPU1_P2_TX_BUF_DP<10>")
	)
	(segment
		(start 146.176746 -403.596856)
		(end 146.422618 -403.350984)
		(width 0.14224)
		(layer "In4.Cu")
		(net "P5E_CPU1_P2_TX_BUF_DP<10>")
	)
	(segment
		(start 158.964376 -394.335)
		(end 158.964376 -391.734802)
		(width 0.14224)
		(layer "In4.Cu")
		(net "P5E_CPU1_P2_TX_BUF_DP<10>")
	)
	(segment
		(start 147.501864 -403.023578)
		(end 147.910042 -402.89988)
		(width 0.14224)
		(layer "In4.Cu")
		(net "P5E_CPU1_P2_TX_BUF_DP<10>")
	)
	(arc
		(start 158.964376 -391.734802)
		(mid 158.976653 -391.673079)
		(end 159.01162 -391.620756)
		(width 0.14224)
		(layer "In4.Cu")
		(net "P5E_CPU1_P2_TX_BUF_DP<10>")
	)
	(arc
		(start 146.099276 -403.7838)
		(mid 146.119403 -403.682613)
		(end 146.176746 -403.596856)
		(width 0.14224)
		(layer "In4.Cu")
		(net "P5E_CPU1_P2_TX_BUF_DP<10>")
	)
	(arc
		(start 159.501078 -391.131298)
		(mid 159.71895 -390.80523)
		(end 159.795464 -390.420606)
		(width 0.14224)
		(layer "In4.Cu")
		(net "P5E_CPU1_P2_TX_BUF_DP<10>")
	)
	(arc
		(start 152.91054 -400.986244)
		(mid 154.034427 -400.385517)
		(end 155.019502 -399.577052)
		(width 0.14224)
		(layer "In4.Cu")
		(net "P5E_CPU1_P2_TX_BUF_DP<10>")
	)
	(arc
		(start 159.795464 -390.176258)
		(mid 159.763983 -390.017902)
		(end 159.674306 -389.88365)
		(width 0.14224)
		(layer "In4.Cu")
		(net "P5E_CPU1_P2_TX_BUF_DP<10>")
	)
	(arc
		(start 159.472122 -389.681466)
		(mid 159.444503 -389.640226)
		(end 159.434784 -389.59155)
		(width 0.14224)
		(layer "In4.Cu")
		(net "P5E_CPU1_P2_TX_BUF_DP<10>")
	)
	(arc
		(start 158.844488 -395.752066)
		(mid 158.933232 -395.619346)
		(end 158.964376 -395.46276)
		(width 0.14224)
		(layer "In4.Cu")
		(net "P5E_CPU1_P2_TX_BUF_DP<10>")
	)
	(segment
		(start 147.29841 -389.467344)
		(end 147.81911 -389.467344)
		(width 0.127)
		(layer "F.Cu")
		(net "P5E_CPU1_P2_TX_BUF_DP<0>")
	)
	(segment
		(start 115.783106 -408.250644)
		(end 115.487196 -407.954734)
		(width 0.12954)
		(layer "F.Cu")
		(net "P5E_CPU1_P2_TX_BUF_DP<0>")
	)
	(segment
		(start 115.487196 -407.954734)
		(end 115.487196 -404.73503)
		(width 0.12954)
		(layer "F.Cu")
		(net "P5E_CPU1_P2_TX_BUF_DP<0>")
	)
	(segment
		(start 115.487196 -404.73503)
		(end 115.757706 -404.46452)
		(width 0.12954)
		(layer "F.Cu")
		(net "P5E_CPU1_P2_TX_BUF_DP<0>")
	)
	(segment
		(start 147.518628 -389.344662)
		(end 147.325334 -389.537956)
		(width 0.14224)
		(layer "In4.Cu")
		(net "P5E_CPU1_P2_TX_BUF_DP<0>")
	)
	(segment
		(start 143.912844 -394.204698)
		(end 128.729232 -398.810734)
		(width 0.14224)
		(layer "In4.Cu")
		(net "P5E_CPU1_P2_TX_BUF_DP<0>")
	)
	(segment
		(start 128.36271 -398.86509)
		(end 127.029718 -398.86509)
		(width 0.14224)
		(layer "In4.Cu")
		(net "P5E_CPU1_P2_TX_BUF_DP<0>")
	)
	(segment
		(start 117.618002 -402.760942)
		(end 117.438932 -402.686774)
		(width 0.14224)
		(layer "In4.Cu")
		(net "P5E_CPU1_P2_TX_BUF_DP<0>")
	)
	(segment
		(start 145.34007 -393.022582)
		(end 144.524476 -393.838176)
		(width 0.14224)
		(layer "In4.Cu")
		(net "P5E_CPU1_P2_TX_BUF_DP<0>")
	)
	(segment
		(start 117.438932 -402.686774)
		(end 117.044724 -402.849842)
		(width 0.14224)
		(layer "In4.Cu")
		(net "P5E_CPU1_P2_TX_BUF_DP<0>")
	)
	(segment
		(start 115.68811 -403.43836)
		(end 115.594638 -403.531832)
		(width 0.14224)
		(layer "In4.Cu")
		(net "P5E_CPU1_P2_TX_BUF_DP<0>")
	)
	(segment
		(start 147.81911 -389.467344)
		(end 147.696428 -389.344662)
		(width 0.14224)
		(layer "In4.Cu")
		(net "P5E_CPU1_P2_TX_BUF_DP<0>")
	)
	(segment
		(start 117.044724 -402.849842)
		(end 116.970556 -403.02942)
		(width 0.14224)
		(layer "In4.Cu")
		(net "P5E_CPU1_P2_TX_BUF_DP<0>")
	)
	(segment
		(start 146.361658 -390.12749)
		(end 145.506694 -392.192002)
		(width 0.14224)
		(layer "In4.Cu")
		(net "P5E_CPU1_P2_TX_BUF_DP<0>")
	)
	(segment
		(start 119.116094 -401.992084)
		(end 119.048022 -402.156168)
		(width 0.14224)
		(layer "In4.Cu")
		(net "P5E_CPU1_P2_TX_BUF_DP<0>")
	)
	(segment
		(start 118.65356 -402.31949)
		(end 118.48973 -402.251672)
		(width 0.14224)
		(layer "In4.Cu")
		(net "P5E_CPU1_P2_TX_BUF_DP<0>")
	)
	(segment
		(start 146.966432 -389.686546)
		(end 146.863054 -389.686546)
		(width 0.14224)
		(layer "In4.Cu")
		(net "P5E_CPU1_P2_TX_BUF_DP<0>")
	)
	(segment
		(start 119.048022 -402.156168)
		(end 118.65356 -402.31949)
		(width 0.14224)
		(layer "In4.Cu")
		(net "P5E_CPU1_P2_TX_BUF_DP<0>")
	)
	(segment
		(start 147.696428 -389.344662)
		(end 147.518628 -389.344662)
		(width 0.14224)
		(layer "In4.Cu")
		(net "P5E_CPU1_P2_TX_BUF_DP<0>")
	)
	(segment
		(start 115.466876 -404.17369)
		(end 115.757706 -404.46452)
		(width 0.14224)
		(layer "In4.Cu")
		(net "P5E_CPU1_P2_TX_BUF_DP<0>")
	)
	(segment
		(start 116.397024 -403.11832)
		(end 115.792758 -403.36851)
		(width 0.14224)
		(layer "In4.Cu")
		(net "P5E_CPU1_P2_TX_BUF_DP<0>")
	)
	(segment
		(start 118.012464 -402.59762)
		(end 117.618002 -402.760942)
		(width 0.14224)
		(layer "In4.Cu")
		(net "P5E_CPU1_P2_TX_BUF_DP<0>")
	)
	(segment
		(start 118.48973 -402.251672)
		(end 118.086886 -402.418296)
		(width 0.14224)
		(layer "In4.Cu")
		(net "P5E_CPU1_P2_TX_BUF_DP<0>")
	)
	(segment
		(start 118.086886 -402.418296)
		(end 118.012464 -402.59762)
		(width 0.14224)
		(layer "In4.Cu")
		(net "P5E_CPU1_P2_TX_BUF_DP<0>")
	)
	(segment
		(start 115.466876 -403.839934)
		(end 115.466876 -404.17369)
		(width 0.14224)
		(layer "In4.Cu")
		(net "P5E_CPU1_P2_TX_BUF_DP<0>")
	)
	(segment
		(start 145.506694 -392.192002)
		(end 145.506694 -392.620754)
		(width 0.14224)
		(layer "In4.Cu")
		(net "P5E_CPU1_P2_TX_BUF_DP<0>")
	)
	(segment
		(start 146.75993 -389.729218)
		(end 146.361658 -390.12749)
		(width 0.14224)
		(layer "In4.Cu")
		(net "P5E_CPU1_P2_TX_BUF_DP<0>")
	)
	(segment
		(start 116.970556 -403.02942)
		(end 116.576094 -403.192488)
		(width 0.14224)
		(layer "In4.Cu")
		(net "P5E_CPU1_P2_TX_BUF_DP<0>")
	)
	(segment
		(start 116.576094 -403.192488)
		(end 116.397024 -403.11832)
		(width 0.14224)
		(layer "In4.Cu")
		(net "P5E_CPU1_P2_TX_BUF_DP<0>")
	)
	(segment
		(start 126.329948 -399.004282)
		(end 119.116094 -401.992084)
		(width 0.14224)
		(layer "In4.Cu")
		(net "P5E_CPU1_P2_TX_BUF_DP<0>")
	)
	(arc
		(start 127.029718 -398.86509)
		(mid 126.672981 -398.900231)
		(end 126.329948 -399.004282)
		(width 0.14224)
		(layer "In4.Cu")
		(net "P5E_CPU1_P2_TX_BUF_DP<0>")
	)
	(arc
		(start 115.792758 -403.36851)
		(mid 115.736986 -403.398273)
		(end 115.68811 -403.43836)
		(width 0.14224)
		(layer "In4.Cu")
		(net "P5E_CPU1_P2_TX_BUF_DP<0>")
	)
	(arc
		(start 115.594638 -403.531832)
		(mid 115.500078 -403.673162)
		(end 115.466876 -403.839934)
		(width 0.14224)
		(layer "In4.Cu")
		(net "P5E_CPU1_P2_TX_BUF_DP<0>")
	)
	(arc
		(start 147.325334 -389.537956)
		(mid 147.160654 -389.647928)
		(end 146.966432 -389.686546)
		(width 0.14224)
		(layer "In4.Cu")
		(net "P5E_CPU1_P2_TX_BUF_DP<0>")
	)
	(arc
		(start 146.863054 -389.686546)
		(mid 146.807246 -389.697629)
		(end 146.75993 -389.729218)
		(width 0.14224)
		(layer "In4.Cu")
		(net "P5E_CPU1_P2_TX_BUF_DP<0>")
	)
	(arc
		(start 128.729232 -398.810734)
		(mid 128.547976 -398.851424)
		(end 128.36271 -398.86509)
		(width 0.14224)
		(layer "In4.Cu")
		(net "P5E_CPU1_P2_TX_BUF_DP<0>")
	)
	(arc
		(start 145.506694 -392.620754)
		(mid 145.463355 -392.838252)
		(end 145.34007 -393.022582)
		(width 0.14224)
		(layer "In4.Cu")
		(net "P5E_CPU1_P2_TX_BUF_DP<0>")
	)
	(arc
		(start 144.524476 -393.838176)
		(mid 144.241258 -394.059143)
		(end 143.912844 -394.204698)
		(width 0.14224)
		(layer "In4.Cu")
		(net "P5E_CPU1_P2_TX_BUF_DP<0>")
	)
	(segment
		(start 142.733776 -407.954734)
		(end 142.733776 -404.73503)
		(width 0.12954)
		(layer "F.Cu")
		(net "P5E_CPU1_P2_TX_BUF_DN<9>")
	)
	(segment
		(start 142.733776 -404.73503)
		(end 142.463266 -404.46452)
		(width 0.12954)
		(layer "F.Cu")
		(net "P5E_CPU1_P2_TX_BUF_DN<9>")
	)
	(segment
		(start 157.698186 -388.774432)
		(end 158.218886 -388.774432)
		(width 0.127)
		(layer "F.Cu")
		(net "P5E_CPU1_P2_TX_BUF_DN<9>")
	)
	(segment
		(start 142.437866 -408.250644)
		(end 142.733776 -407.954734)
		(width 0.12954)
		(layer "F.Cu")
		(net "P5E_CPU1_P2_TX_BUF_DN<9>")
	)
	(segment
		(start 158.27121 -388.826756)
		(end 158.27121 -389.006588)
		(width 0.14224)
		(layer "In4.Cu")
		(net "P5E_CPU1_P2_TX_BUF_DN<9>")
	)
	(segment
		(start 157.541722 -391.704576)
		(end 157.541722 -395.272768)
		(width 0.14224)
		(layer "In4.Cu")
		(net "P5E_CPU1_P2_TX_BUF_DN<9>")
	)
	(segment
		(start 157.937454 -389.340344)
		(end 157.937454 -389.515858)
		(width 0.14224)
		(layer "In4.Cu")
		(net "P5E_CPU1_P2_TX_BUF_DN<9>")
	)
	(segment
		(start 143.109696 -403.186392)
		(end 142.971266 -403.324822)
		(width 0.14224)
		(layer "In4.Cu")
		(net "P5E_CPU1_P2_TX_BUF_DN<9>")
	)
	(segment
		(start 158.120588 -390.941814)
		(end 157.671516 -391.390886)
		(width 0.14224)
		(layer "In4.Cu")
		(net "P5E_CPU1_P2_TX_BUF_DN<9>")
	)
	(segment
		(start 158.313374 -390.122918)
		(end 158.313374 -390.476486)
		(width 0.14224)
		(layer "In4.Cu")
		(net "P5E_CPU1_P2_TX_BUF_DN<9>")
	)
	(segment
		(start 148.961602 -401.30603)
		(end 145.669762 -402.270468)
		(width 0.14224)
		(layer "In4.Cu")
		(net "P5E_CPU1_P2_TX_BUF_DN<9>")
	)
	(segment
		(start 158.27121 -389.006588)
		(end 157.937454 -389.340344)
		(width 0.14224)
		(layer "In4.Cu")
		(net "P5E_CPU1_P2_TX_BUF_DN<9>")
	)
	(segment
		(start 157.504384 -395.362684)
		(end 154.148536 -398.718532)
		(width 0.14224)
		(layer "In4.Cu")
		(net "P5E_CPU1_P2_TX_BUF_DN<9>")
	)
	(segment
		(start 142.754096 -404.17369)
		(end 142.463266 -404.46452)
		(width 0.14224)
		(layer "In4.Cu")
		(net "P5E_CPU1_P2_TX_BUF_DN<9>")
	)
	(segment
		(start 145.669762 -402.270468)
		(end 143.109696 -403.186392)
		(width 0.14224)
		(layer "In4.Cu")
		(net "P5E_CPU1_P2_TX_BUF_DN<9>")
	)
	(segment
		(start 158.098744 -389.90524)
		(end 158.311088 -390.117584)
		(width 0.14224)
		(layer "In4.Cu")
		(net "P5E_CPU1_P2_TX_BUF_DN<9>")
	)
	(segment
		(start 152.419304 -399.873724)
		(end 148.961602 -401.30603)
		(width 0.14224)
		(layer "In4.Cu")
		(net "P5E_CPU1_P2_TX_BUF_DN<9>")
	)
	(segment
		(start 142.754096 -403.849078)
		(end 142.754096 -404.17369)
		(width 0.14224)
		(layer "In4.Cu")
		(net "P5E_CPU1_P2_TX_BUF_DN<9>")
	)
	(segment
		(start 158.218886 -388.774432)
		(end 158.27121 -388.826756)
		(width 0.14224)
		(layer "In4.Cu")
		(net "P5E_CPU1_P2_TX_BUF_DN<9>")
	)
	(arc
		(start 158.311088 -390.117584)
		(mid 158.312778 -390.120016)
		(end 158.313374 -390.122918)
		(width 0.14224)
		(layer "In4.Cu")
		(net "P5E_CPU1_P2_TX_BUF_DN<9>")
	)
	(arc
		(start 157.937454 -389.515858)
		(mid 157.979318 -389.726616)
		(end 158.098744 -389.90524)
		(width 0.14224)
		(layer "In4.Cu")
		(net "P5E_CPU1_P2_TX_BUF_DN<9>")
	)
	(arc
		(start 154.148536 -398.718532)
		(mid 153.340806 -399.381281)
		(end 152.419304 -399.873724)
		(width 0.14224)
		(layer "In4.Cu")
		(net "P5E_CPU1_P2_TX_BUF_DN<9>")
	)
	(arc
		(start 157.541722 -395.272768)
		(mid 157.53202 -395.321452)
		(end 157.504384 -395.362684)
		(width 0.14224)
		(layer "In4.Cu")
		(net "P5E_CPU1_P2_TX_BUF_DN<9>")
	)
	(arc
		(start 142.971266 -403.324822)
		(mid 142.810549 -403.565353)
		(end 142.754096 -403.849078)
		(width 0.14224)
		(layer "In4.Cu")
		(net "P5E_CPU1_P2_TX_BUF_DN<9>")
	)
	(arc
		(start 158.313374 -390.476486)
		(mid 158.263263 -390.728321)
		(end 158.120588 -390.941814)
		(width 0.14224)
		(layer "In4.Cu")
		(net "P5E_CPU1_P2_TX_BUF_DN<9>")
	)
	(arc
		(start 157.671516 -391.390886)
		(mid 157.57538 -391.534809)
		(end 157.541722 -391.704576)
		(width 0.14224)
		(layer "In4.Cu")
		(net "P5E_CPU1_P2_TX_BUF_DN<9>")
	)
	(segment
		(start 139.670536 -404.73503)
		(end 139.400026 -404.46452)
		(width 0.12954)
		(layer "F.Cu")
		(net "P5E_CPU1_P2_TX_BUF_DN<8>")
	)
	(segment
		(start 139.670536 -407.954734)
		(end 139.670536 -404.73503)
		(width 0.12954)
		(layer "F.Cu")
		(net "P5E_CPU1_P2_TX_BUF_DN<8>")
	)
	(segment
		(start 156.49829 -388.774432)
		(end 157.01899 -388.774432)
		(width 0.127)
		(layer "F.Cu")
		(net "P5E_CPU1_P2_TX_BUF_DN<8>")
	)
	(segment
		(start 139.374626 -408.250644)
		(end 139.670536 -407.954734)
		(width 0.12954)
		(layer "F.Cu")
		(net "P5E_CPU1_P2_TX_BUF_DN<8>")
	)
	(segment
		(start 157.071314 -389.006588)
		(end 156.752798 -389.325104)
		(width 0.14224)
		(layer "In4.Cu")
		(net "P5E_CPU1_P2_TX_BUF_DN<8>")
	)
	(segment
		(start 157.071314 -388.826756)
		(end 157.071314 -389.006588)
		(width 0.14224)
		(layer "In4.Cu")
		(net "P5E_CPU1_P2_TX_BUF_DN<8>")
	)
	(segment
		(start 148.89099 -400.322542)
		(end 146.655028 -401.000976)
		(width 0.14224)
		(layer "In4.Cu")
		(net "P5E_CPU1_P2_TX_BUF_DN<8>")
	)
	(segment
		(start 156.752798 -389.325104)
		(end 156.752798 -389.49376)
		(width 0.14224)
		(layer "In4.Cu")
		(net "P5E_CPU1_P2_TX_BUF_DN<8>")
	)
	(segment
		(start 155.893262 -395.494002)
		(end 153.031952 -398.355312)
		(width 0.14224)
		(layer "In4.Cu")
		(net "P5E_CPU1_P2_TX_BUF_DN<8>")
	)
	(segment
		(start 152.03678 -399.02003)
		(end 148.89099 -400.322542)
		(width 0.14224)
		(layer "In4.Cu")
		(net "P5E_CPU1_P2_TX_BUF_DN<8>")
	)
	(segment
		(start 146.655028 -401.000976)
		(end 145.90014 -401.151598)
		(width 0.14224)
		(layer "In4.Cu")
		(net "P5E_CPU1_P2_TX_BUF_DN<8>")
	)
	(segment
		(start 145.90014 -401.151598)
		(end 143.495776 -401.83435)
		(width 0.14224)
		(layer "In4.Cu")
		(net "P5E_CPU1_P2_TX_BUF_DN<8>")
	)
	(segment
		(start 139.690856 -404.17369)
		(end 139.400026 -404.46452)
		(width 0.14224)
		(layer "In4.Cu")
		(net "P5E_CPU1_P2_TX_BUF_DN<8>")
	)
	(segment
		(start 157.01899 -388.774432)
		(end 157.071314 -388.826756)
		(width 0.14224)
		(layer "In4.Cu")
		(net "P5E_CPU1_P2_TX_BUF_DN<8>")
	)
	(segment
		(start 156.27604 -391.7696)
		(end 156.27604 -394.570204)
		(width 0.14224)
		(layer "In4.Cu")
		(net "P5E_CPU1_P2_TX_BUF_DN<8>")
	)
	(segment
		(start 156.885132 -390.967214)
		(end 156.412438 -391.440162)
		(width 0.14224)
		(layer "In4.Cu")
		(net "P5E_CPU1_P2_TX_BUF_DN<8>")
	)
	(segment
		(start 139.690856 -403.772878)
		(end 139.690856 -404.17369)
		(width 0.14224)
		(layer "In4.Cu")
		(net "P5E_CPU1_P2_TX_BUF_DN<8>")
	)
	(segment
		(start 157.113478 -390.176512)
		(end 157.113478 -390.41578)
		(width 0.14224)
		(layer "In4.Cu")
		(net "P5E_CPU1_P2_TX_BUF_DN<8>")
	)
	(segment
		(start 143.495776 -401.83435)
		(end 140.044678 -403.177248)
		(width 0.14224)
		(layer "In4.Cu")
		(net "P5E_CPU1_P2_TX_BUF_DN<8>")
	)
	(segment
		(start 140.044678 -403.177248)
		(end 139.861798 -403.360128)
		(width 0.14224)
		(layer "In4.Cu")
		(net "P5E_CPU1_P2_TX_BUF_DN<8>")
	)
	(segment
		(start 156.943298 -389.9535)
		(end 157.07614 -390.086342)
		(width 0.14224)
		(layer "In4.Cu")
		(net "P5E_CPU1_P2_TX_BUF_DN<8>")
	)
	(arc
		(start 156.752798 -389.49376)
		(mid 156.80231 -389.742582)
		(end 156.943298 -389.9535)
		(width 0.14224)
		(layer "In4.Cu")
		(net "P5E_CPU1_P2_TX_BUF_DN<8>")
	)
	(arc
		(start 139.861798 -403.360128)
		(mid 139.735264 -403.549499)
		(end 139.690856 -403.772878)
		(width 0.14224)
		(layer "In4.Cu")
		(net "P5E_CPU1_P2_TX_BUF_DN<8>")
	)
	(arc
		(start 156.412438 -391.440162)
		(mid 156.311498 -391.591324)
		(end 156.27604 -391.7696)
		(width 0.14224)
		(layer "In4.Cu")
		(net "P5E_CPU1_P2_TX_BUF_DN<8>")
	)
	(arc
		(start 153.031952 -398.355312)
		(mid 152.567106 -398.736686)
		(end 152.03678 -399.02003)
		(width 0.14224)
		(layer "In4.Cu")
		(net "P5E_CPU1_P2_TX_BUF_DN<8>")
	)
	(arc
		(start 157.07614 -390.086342)
		(mid 157.103783 -390.127712)
		(end 157.113478 -390.176512)
		(width 0.14224)
		(layer "In4.Cu")
		(net "P5E_CPU1_P2_TX_BUF_DN<8>")
	)
	(arc
		(start 156.27604 -394.570204)
		(mid 156.176553 -395.070181)
		(end 155.893262 -395.494002)
		(width 0.14224)
		(layer "In4.Cu")
		(net "P5E_CPU1_P2_TX_BUF_DN<8>")
	)
	(arc
		(start 157.113478 -390.41578)
		(mid 157.054136 -390.714203)
		(end 156.885132 -390.967214)
		(width 0.14224)
		(layer "In4.Cu")
		(net "P5E_CPU1_P2_TX_BUF_DN<8>")
	)
	(segment
		(start 136.311386 -408.250644)
		(end 136.607296 -407.954734)
		(width 0.12954)
		(layer "F.Cu")
		(net "P5E_CPU1_P2_TX_BUF_DN<7>")
	)
	(segment
		(start 136.607296 -407.954734)
		(end 136.607296 -404.73503)
		(width 0.12954)
		(layer "F.Cu")
		(net "P5E_CPU1_P2_TX_BUF_DN<7>")
	)
	(segment
		(start 136.607296 -404.73503)
		(end 136.336786 -404.46452)
		(width 0.12954)
		(layer "F.Cu")
		(net "P5E_CPU1_P2_TX_BUF_DN<7>")
	)
	(segment
		(start 155.298394 -388.774432)
		(end 155.819094 -388.774432)
		(width 0.127)
		(layer "F.Cu")
		(net "P5E_CPU1_P2_TX_BUF_DN<7>")
	)
	(segment
		(start 136.627616 -404.17369)
		(end 136.336786 -404.46452)
		(width 0.14224)
		(layer "In4.Cu")
		(net "P5E_CPU1_P2_TX_BUF_DN<7>")
	)
	(segment
		(start 155.79852 -390.819386)
		(end 155.316936 -391.30097)
		(width 0.14224)
		(layer "In4.Cu")
		(net "P5E_CPU1_P2_TX_BUF_DN<7>")
	)
	(segment
		(start 136.627616 -403.80412)
		(end 136.627616 -404.17369)
		(width 0.14224)
		(layer "In4.Cu")
		(net "P5E_CPU1_P2_TX_BUF_DN<7>")
	)
	(segment
		(start 151.601424 -398.190212)
		(end 148.772118 -399.361914)
		(width 0.14224)
		(layer "In4.Cu")
		(net "P5E_CPU1_P2_TX_BUF_DN<7>")
	)
	(segment
		(start 145.428716 -400.273012)
		(end 139.674854 -402.0185)
		(width 0.14224)
		(layer "In4.Cu")
		(net "P5E_CPU1_P2_TX_BUF_DN<7>")
	)
	(segment
		(start 155.871418 -388.826756)
		(end 155.871418 -389.006588)
		(width 0.14224)
		(layer "In4.Cu")
		(net "P5E_CPU1_P2_TX_BUF_DN<7>")
	)
	(segment
		(start 155.560014 -389.317992)
		(end 155.560014 -389.534146)
		(width 0.14224)
		(layer "In4.Cu")
		(net "P5E_CPU1_P2_TX_BUF_DN<7>")
	)
	(segment
		(start 155.726892 -389.93699)
		(end 155.876244 -390.086342)
		(width 0.14224)
		(layer "In4.Cu")
		(net "P5E_CPU1_P2_TX_BUF_DN<7>")
	)
	(segment
		(start 146.417284 -400.076162)
		(end 145.428716 -400.273012)
		(width 0.14224)
		(layer "In4.Cu")
		(net "P5E_CPU1_P2_TX_BUF_DN<7>")
	)
	(segment
		(start 155.819094 -388.774432)
		(end 155.871418 -388.826756)
		(width 0.14224)
		(layer "In4.Cu")
		(net "P5E_CPU1_P2_TX_BUF_DN<7>")
	)
	(segment
		(start 136.969754 -403.138894)
		(end 136.856216 -403.252432)
		(width 0.14224)
		(layer "In4.Cu")
		(net "P5E_CPU1_P2_TX_BUF_DN<7>")
	)
	(segment
		(start 155.135326 -391.739628)
		(end 155.135326 -394.535914)
		(width 0.14224)
		(layer "In4.Cu")
		(net "P5E_CPU1_P2_TX_BUF_DN<7>")
	)
	(segment
		(start 154.893518 -395.119606)
		(end 152.268936 -397.744188)
		(width 0.14224)
		(layer "In4.Cu")
		(net "P5E_CPU1_P2_TX_BUF_DN<7>")
	)
	(segment
		(start 139.674854 -402.0185)
		(end 136.969754 -403.138894)
		(width 0.14224)
		(layer "In4.Cu")
		(net "P5E_CPU1_P2_TX_BUF_DN<7>")
	)
	(segment
		(start 155.871418 -389.006588)
		(end 155.560014 -389.317992)
		(width 0.14224)
		(layer "In4.Cu")
		(net "P5E_CPU1_P2_TX_BUF_DN<7>")
	)
	(segment
		(start 155.913582 -390.176004)
		(end 155.913582 -390.541764)
		(width 0.14224)
		(layer "In4.Cu")
		(net "P5E_CPU1_P2_TX_BUF_DN<7>")
	)
	(segment
		(start 148.772118 -399.361914)
		(end 146.417284 -400.076162)
		(width 0.14224)
		(layer "In4.Cu")
		(net "P5E_CPU1_P2_TX_BUF_DN<7>")
	)
	(arc
		(start 155.316936 -391.30097)
		(mid 155.182513 -391.502242)
		(end 155.135326 -391.739628)
		(width 0.14224)
		(layer "In4.Cu")
		(net "P5E_CPU1_P2_TX_BUF_DN<7>")
	)
	(arc
		(start 152.268936 -397.744188)
		(mid 151.957144 -398.00007)
		(end 151.601424 -398.190212)
		(width 0.14224)
		(layer "In4.Cu")
		(net "P5E_CPU1_P2_TX_BUF_DN<7>")
	)
	(arc
		(start 155.913582 -390.541764)
		(mid 155.883676 -390.692023)
		(end 155.79852 -390.819386)
		(width 0.14224)
		(layer "In4.Cu")
		(net "P5E_CPU1_P2_TX_BUF_DN<7>")
	)
	(arc
		(start 155.135326 -394.535914)
		(mid 155.072489 -394.851819)
		(end 154.893518 -395.119606)
		(width 0.14224)
		(layer "In4.Cu")
		(net "P5E_CPU1_P2_TX_BUF_DN<7>")
	)
	(arc
		(start 155.560014 -389.534146)
		(mid 155.603382 -389.752169)
		(end 155.726892 -389.93699)
		(width 0.14224)
		(layer "In4.Cu")
		(net "P5E_CPU1_P2_TX_BUF_DN<7>")
	)
	(arc
		(start 136.856216 -403.252432)
		(mid 136.687035 -403.505534)
		(end 136.627616 -403.80412)
		(width 0.14224)
		(layer "In4.Cu")
		(net "P5E_CPU1_P2_TX_BUF_DN<7>")
	)
	(arc
		(start 155.876244 -390.086342)
		(mid 155.903814 -390.127464)
		(end 155.913582 -390.176004)
		(width 0.14224)
		(layer "In4.Cu")
		(net "P5E_CPU1_P2_TX_BUF_DN<7>")
	)
	(segment
		(start 133.248146 -408.250644)
		(end 133.544056 -407.954734)
		(width 0.12954)
		(layer "F.Cu")
		(net "P5E_CPU1_P2_TX_BUF_DN<6>")
	)
	(segment
		(start 133.544056 -404.73503)
		(end 133.273546 -404.46452)
		(width 0.12954)
		(layer "F.Cu")
		(net "P5E_CPU1_P2_TX_BUF_DN<6>")
	)
	(segment
		(start 133.544056 -407.954734)
		(end 133.544056 -404.73503)
		(width 0.12954)
		(layer "F.Cu")
		(net "P5E_CPU1_P2_TX_BUF_DN<6>")
	)
	(segment
		(start 154.098244 -388.774432)
		(end 154.618944 -388.774432)
		(width 0.127)
		(layer "F.Cu")
		(net "P5E_CPU1_P2_TX_BUF_DN<6>")
	)
	(segment
		(start 154.671268 -389.006588)
		(end 154.352752 -389.325104)
		(width 0.14224)
		(layer "In4.Cu")
		(net "P5E_CPU1_P2_TX_BUF_DN<6>")
	)
	(segment
		(start 136.558528 -401.988782)
		(end 133.879082 -403.099016)
		(width 0.14224)
		(layer "In4.Cu")
		(net "P5E_CPU1_P2_TX_BUF_DN<6>")
	)
	(segment
		(start 154.671268 -388.826756)
		(end 154.671268 -389.006588)
		(width 0.14224)
		(layer "In4.Cu")
		(net "P5E_CPU1_P2_TX_BUF_DN<6>")
	)
	(segment
		(start 154.352752 -389.325104)
		(end 154.352752 -389.525256)
		(width 0.14224)
		(layer "In4.Cu")
		(net "P5E_CPU1_P2_TX_BUF_DN<6>")
	)
	(segment
		(start 154.5209 -389.931148)
		(end 154.676094 -390.086342)
		(width 0.14224)
		(layer "In4.Cu")
		(net "P5E_CPU1_P2_TX_BUF_DN<6>")
	)
	(segment
		(start 153.67889 -394.971016)
		(end 151.50211 -397.147796)
		(width 0.14224)
		(layer "In4.Cu")
		(net "P5E_CPU1_P2_TX_BUF_DN<6>")
	)
	(segment
		(start 151.21001 -397.342868)
		(end 148.587968 -398.428718)
		(width 0.14224)
		(layer "In4.Cu")
		(net "P5E_CPU1_P2_TX_BUF_DN<6>")
	)
	(segment
		(start 153.911046 -391.7315)
		(end 153.911046 -394.410692)
		(width 0.14224)
		(layer "In4.Cu")
		(net "P5E_CPU1_P2_TX_BUF_DN<6>")
	)
	(segment
		(start 154.489912 -390.943084)
		(end 154.059128 -391.373868)
		(width 0.14224)
		(layer "In4.Cu")
		(net "P5E_CPU1_P2_TX_BUF_DN<6>")
	)
	(segment
		(start 154.713432 -390.176512)
		(end 154.713432 -390.403588)
		(width 0.14224)
		(layer "In4.Cu")
		(net "P5E_CPU1_P2_TX_BUF_DN<6>")
	)
	(segment
		(start 133.879082 -403.099016)
		(end 133.732524 -403.245574)
		(width 0.14224)
		(layer "In4.Cu")
		(net "P5E_CPU1_P2_TX_BUF_DN<6>")
	)
	(segment
		(start 154.618944 -388.774432)
		(end 154.671268 -388.826756)
		(width 0.14224)
		(layer "In4.Cu")
		(net "P5E_CPU1_P2_TX_BUF_DN<6>")
	)
	(segment
		(start 146.01444 -399.12036)
		(end 136.558528 -401.988782)
		(width 0.14224)
		(layer "In4.Cu")
		(net "P5E_CPU1_P2_TX_BUF_DN<6>")
	)
	(segment
		(start 148.587968 -398.428718)
		(end 146.86788 -398.950434)
		(width 0.14224)
		(layer "In4.Cu")
		(net "P5E_CPU1_P2_TX_BUF_DN<6>")
	)
	(segment
		(start 146.86788 -398.950434)
		(end 146.01444 -399.12036)
		(width 0.14224)
		(layer "In4.Cu")
		(net "P5E_CPU1_P2_TX_BUF_DN<6>")
	)
	(segment
		(start 133.564376 -403.651466)
		(end 133.564376 -404.17369)
		(width 0.14224)
		(layer "In4.Cu")
		(net "P5E_CPU1_P2_TX_BUF_DN<6>")
	)
	(segment
		(start 133.564376 -404.17369)
		(end 133.273546 -404.46452)
		(width 0.14224)
		(layer "In4.Cu")
		(net "P5E_CPU1_P2_TX_BUF_DN<6>")
	)
	(arc
		(start 154.352752 -389.525256)
		(mid 154.396448 -389.744932)
		(end 154.5209 -389.931148)
		(width 0.14224)
		(layer "In4.Cu")
		(net "P5E_CPU1_P2_TX_BUF_DN<6>")
	)
	(arc
		(start 154.713432 -390.403588)
		(mid 154.655336 -390.695567)
		(end 154.489912 -390.943084)
		(width 0.14224)
		(layer "In4.Cu")
		(net "P5E_CPU1_P2_TX_BUF_DN<6>")
	)
	(arc
		(start 154.676094 -390.086342)
		(mid 154.703737 -390.127712)
		(end 154.713432 -390.176512)
		(width 0.14224)
		(layer "In4.Cu")
		(net "P5E_CPU1_P2_TX_BUF_DN<6>")
	)
	(arc
		(start 133.732524 -403.245574)
		(mid 133.608093 -403.431799)
		(end 133.564376 -403.651466)
		(width 0.14224)
		(layer "In4.Cu")
		(net "P5E_CPU1_P2_TX_BUF_DN<6>")
	)
	(arc
		(start 154.059128 -391.373868)
		(mid 153.949545 -391.537965)
		(end 153.911046 -391.7315)
		(width 0.14224)
		(layer "In4.Cu")
		(net "P5E_CPU1_P2_TX_BUF_DN<6>")
	)
	(arc
		(start 153.911046 -394.410692)
		(mid 153.850707 -394.713947)
		(end 153.67889 -394.971016)
		(width 0.14224)
		(layer "In4.Cu")
		(net "P5E_CPU1_P2_TX_BUF_DN<6>")
	)
	(arc
		(start 151.50211 -397.147796)
		(mid 151.365668 -397.25972)
		(end 151.21001 -397.342868)
		(width 0.14224)
		(layer "In4.Cu")
		(net "P5E_CPU1_P2_TX_BUF_DN<6>")
	)
	(segment
		(start 130.480816 -404.73503)
		(end 130.210306 -404.46452)
		(width 0.12954)
		(layer "F.Cu")
		(net "P5E_CPU1_P2_TX_BUF_DN<5>")
	)
	(segment
		(start 130.184906 -408.250644)
		(end 130.480816 -407.954734)
		(width 0.12954)
		(layer "F.Cu")
		(net "P5E_CPU1_P2_TX_BUF_DN<5>")
	)
	(segment
		(start 130.480816 -407.954734)
		(end 130.480816 -404.73503)
		(width 0.12954)
		(layer "F.Cu")
		(net "P5E_CPU1_P2_TX_BUF_DN<5>")
	)
	(segment
		(start 152.898348 -388.774432)
		(end 153.419048 -388.774432)
		(width 0.127)
		(layer "F.Cu")
		(net "P5E_CPU1_P2_TX_BUF_DN<5>")
	)
	(segment
		(start 150.721314 -396.535656)
		(end 148.341334 -397.52143)
		(width 0.14224)
		(layer "In4.Cu")
		(net "P5E_CPU1_P2_TX_BUF_DN<5>")
	)
	(segment
		(start 130.501136 -403.79777)
		(end 130.501136 -404.17369)
		(width 0.14224)
		(layer "In4.Cu")
		(net "P5E_CPU1_P2_TX_BUF_DN<5>")
	)
	(segment
		(start 134.876032 -401.52447)
		(end 130.845306 -403.194012)
		(width 0.14224)
		(layer "In4.Cu")
		(net "P5E_CPU1_P2_TX_BUF_DN<5>")
	)
	(segment
		(start 153.513536 -390.363456)
		(end 153.513536 -390.54278)
		(width 0.14224)
		(layer "In4.Cu")
		(net "P5E_CPU1_P2_TX_BUF_DN<5>")
	)
	(segment
		(start 153.419048 -388.774432)
		(end 153.469594 -388.824978)
		(width 0.14224)
		(layer "In4.Cu")
		(net "P5E_CPU1_P2_TX_BUF_DN<5>")
	)
	(segment
		(start 146.884136 -397.963644)
		(end 146.100546 -398.119346)
		(width 0.14224)
		(layer "In4.Cu")
		(net "P5E_CPU1_P2_TX_BUF_DN<5>")
	)
	(segment
		(start 153.469594 -388.824978)
		(end 153.469594 -389.02513)
		(width 0.14224)
		(layer "In4.Cu")
		(net "P5E_CPU1_P2_TX_BUF_DN<5>")
	)
	(segment
		(start 153.469594 -389.02513)
		(end 153.152856 -389.341868)
		(width 0.14224)
		(layer "In4.Cu")
		(net "P5E_CPU1_P2_TX_BUF_DN<5>")
	)
	(segment
		(start 153.152856 -389.341868)
		(end 153.152856 -389.49376)
		(width 0.14224)
		(layer "In4.Cu")
		(net "P5E_CPU1_P2_TX_BUF_DN<5>")
	)
	(segment
		(start 130.845306 -403.194012)
		(end 130.684778 -403.35454)
		(width 0.14224)
		(layer "In4.Cu")
		(net "P5E_CPU1_P2_TX_BUF_DN<5>")
	)
	(segment
		(start 152.564592 -394.715492)
		(end 150.790656 -396.489428)
		(width 0.14224)
		(layer "In4.Cu")
		(net "P5E_CPU1_P2_TX_BUF_DN<5>")
	)
	(segment
		(start 146.100546 -398.119346)
		(end 134.876032 -401.52447)
		(width 0.14224)
		(layer "In4.Cu")
		(net "P5E_CPU1_P2_TX_BUF_DN<5>")
	)
	(segment
		(start 148.341334 -397.52143)
		(end 146.884136 -397.963644)
		(width 0.14224)
		(layer "In4.Cu")
		(net "P5E_CPU1_P2_TX_BUF_DN<5>")
	)
	(segment
		(start 130.501136 -404.17369)
		(end 130.210306 -404.46452)
		(width 0.14224)
		(layer "In4.Cu")
		(net "P5E_CPU1_P2_TX_BUF_DN<5>")
	)
	(segment
		(start 152.714706 -391.722864)
		(end 152.714706 -394.353288)
		(width 0.14224)
		(layer "In4.Cu")
		(net "P5E_CPU1_P2_TX_BUF_DN<5>")
	)
	(segment
		(start 153.42108 -390.765792)
		(end 152.891998 -391.294874)
		(width 0.14224)
		(layer "In4.Cu")
		(net "P5E_CPU1_P2_TX_BUF_DN<5>")
	)
	(arc
		(start 150.790656 -396.489428)
		(mid 150.758265 -396.515964)
		(end 150.721314 -396.535656)
		(width 0.14224)
		(layer "In4.Cu")
		(net "P5E_CPU1_P2_TX_BUF_DN<5>")
	)
	(arc
		(start 130.684778 -403.35454)
		(mid 130.548846 -403.557881)
		(end 130.501136 -403.79777)
		(width 0.14224)
		(layer "In4.Cu")
		(net "P5E_CPU1_P2_TX_BUF_DN<5>")
	)
	(arc
		(start 152.891998 -391.294874)
		(mid 152.760792 -391.491237)
		(end 152.714706 -391.722864)
		(width 0.14224)
		(layer "In4.Cu")
		(net "P5E_CPU1_P2_TX_BUF_DN<5>")
	)
	(arc
		(start 153.34361 -389.953754)
		(mid 153.469322 -390.141711)
		(end 153.513536 -390.363456)
		(width 0.14224)
		(layer "In4.Cu")
		(net "P5E_CPU1_P2_TX_BUF_DN<5>")
	)
	(arc
		(start 152.714706 -394.353288)
		(mid 152.675693 -394.549329)
		(end 152.564592 -394.715492)
		(width 0.14224)
		(layer "In4.Cu")
		(net "P5E_CPU1_P2_TX_BUF_DN<5>")
	)
	(arc
		(start 153.152856 -389.49376)
		(mid 153.202459 -389.742751)
		(end 153.34361 -389.953754)
		(width 0.14224)
		(layer "In4.Cu")
		(net "P5E_CPU1_P2_TX_BUF_DN<5>")
	)
	(arc
		(start 153.513536 -390.54278)
		(mid 153.489507 -390.66349)
		(end 153.42108 -390.765792)
		(width 0.14224)
		(layer "In4.Cu")
		(net "P5E_CPU1_P2_TX_BUF_DN<5>")
	)
	(segment
		(start 127.121666 -408.250644)
		(end 127.417576 -407.954734)
		(width 0.12954)
		(layer "F.Cu")
		(net "P5E_CPU1_P2_TX_BUF_DN<4>")
	)
	(segment
		(start 127.417576 -404.73503)
		(end 127.147066 -404.46452)
		(width 0.12954)
		(layer "F.Cu")
		(net "P5E_CPU1_P2_TX_BUF_DN<4>")
	)
	(segment
		(start 127.417576 -407.954734)
		(end 127.417576 -404.73503)
		(width 0.12954)
		(layer "F.Cu")
		(net "P5E_CPU1_P2_TX_BUF_DN<4>")
	)
	(segment
		(start 151.698198 -388.774432)
		(end 152.218898 -388.774432)
		(width 0.127)
		(layer "F.Cu")
		(net "P5E_CPU1_P2_TX_BUF_DN<4>")
	)
	(segment
		(start 152.271222 -388.826756)
		(end 152.271222 -389.006588)
		(width 0.14224)
		(layer "In4.Cu")
		(net "P5E_CPU1_P2_TX_BUF_DN<4>")
	)
	(segment
		(start 127.827278 -403.13356)
		(end 127.660654 -403.300184)
		(width 0.14224)
		(layer "In4.Cu")
		(net "P5E_CPU1_P2_TX_BUF_DN<4>")
	)
	(segment
		(start 127.437896 -403.837902)
		(end 127.437896 -404.17369)
		(width 0.14224)
		(layer "In4.Cu")
		(net "P5E_CPU1_P2_TX_BUF_DN<4>")
	)
	(segment
		(start 146.048222 -397.160496)
		(end 131.852162 -401.466558)
		(width 0.14224)
		(layer "In4.Cu")
		(net "P5E_CPU1_P2_TX_BUF_DN<4>")
	)
	(segment
		(start 151.535638 -391.578592)
		(end 151.535638 -394.248894)
		(width 0.14224)
		(layer "In4.Cu")
		(net "P5E_CPU1_P2_TX_BUF_DN<4>")
	)
	(segment
		(start 148.279104 -396.537942)
		(end 146.56816 -397.057118)
		(width 0.14224)
		(layer "In4.Cu")
		(net "P5E_CPU1_P2_TX_BUF_DN<4>")
	)
	(segment
		(start 152.313386 -390.176258)
		(end 152.313386 -390.46404)
		(width 0.14224)
		(layer "In4.Cu")
		(net "P5E_CPU1_P2_TX_BUF_DN<4>")
	)
	(segment
		(start 151.454866 -394.443712)
		(end 150.300182 -395.598396)
		(width 0.14224)
		(layer "In4.Cu")
		(net "P5E_CPU1_P2_TX_BUF_DN<4>")
	)
	(segment
		(start 127.437896 -404.17369)
		(end 127.147066 -404.46452)
		(width 0.14224)
		(layer "In4.Cu")
		(net "P5E_CPU1_P2_TX_BUF_DN<4>")
	)
	(segment
		(start 149.896322 -395.868144)
		(end 148.279104 -396.537942)
		(width 0.14224)
		(layer "In4.Cu")
		(net "P5E_CPU1_P2_TX_BUF_DN<4>")
	)
	(segment
		(start 152.271222 -389.006588)
		(end 151.952706 -389.325104)
		(width 0.14224)
		(layer "In4.Cu")
		(net "P5E_CPU1_P2_TX_BUF_DN<4>")
	)
	(segment
		(start 151.952706 -389.325104)
		(end 151.952706 -389.59155)
		(width 0.14224)
		(layer "In4.Cu")
		(net "P5E_CPU1_P2_TX_BUF_DN<4>")
	)
	(segment
		(start 131.852162 -401.466558)
		(end 127.827278 -403.13356)
		(width 0.14224)
		(layer "In4.Cu")
		(net "P5E_CPU1_P2_TX_BUF_DN<4>")
	)
	(segment
		(start 152.218898 -388.774432)
		(end 152.271222 -388.826756)
		(width 0.14224)
		(layer "In4.Cu")
		(net "P5E_CPU1_P2_TX_BUF_DN<4>")
	)
	(segment
		(start 146.56816 -397.057118)
		(end 146.048222 -397.160496)
		(width 0.14224)
		(layer "In4.Cu")
		(net "P5E_CPU1_P2_TX_BUF_DN<4>")
	)
	(segment
		(start 152.214072 -390.703816)
		(end 151.674322 -391.243566)
		(width 0.14224)
		(layer "In4.Cu")
		(net "P5E_CPU1_P2_TX_BUF_DN<4>")
	)
	(segment
		(start 152.072594 -389.880856)
		(end 152.274778 -390.08304)
		(width 0.14224)
		(layer "In4.Cu")
		(net "P5E_CPU1_P2_TX_BUF_DN<4>")
	)
	(arc
		(start 152.274778 -390.08304)
		(mid 152.303355 -390.125809)
		(end 152.313386 -390.176258)
		(width 0.14224)
		(layer "In4.Cu")
		(net "P5E_CPU1_P2_TX_BUF_DN<4>")
	)
	(arc
		(start 151.674322 -391.243566)
		(mid 151.571669 -391.397291)
		(end 151.535638 -391.578592)
		(width 0.14224)
		(layer "In4.Cu")
		(net "P5E_CPU1_P2_TX_BUF_DN<4>")
	)
	(arc
		(start 152.313386 -390.46404)
		(mid 152.287574 -390.593804)
		(end 152.214072 -390.703816)
		(width 0.14224)
		(layer "In4.Cu")
		(net "P5E_CPU1_P2_TX_BUF_DN<4>")
	)
	(arc
		(start 150.300182 -395.598396)
		(mid 150.111523 -395.753133)
		(end 149.896322 -395.868144)
		(width 0.14224)
		(layer "In4.Cu")
		(net "P5E_CPU1_P2_TX_BUF_DN<4>")
	)
	(arc
		(start 151.535638 -394.248894)
		(mid 151.514645 -394.354343)
		(end 151.454866 -394.443712)
		(width 0.14224)
		(layer "In4.Cu")
		(net "P5E_CPU1_P2_TX_BUF_DN<4>")
	)
	(arc
		(start 151.952706 -389.59155)
		(mid 151.983869 -389.748128)
		(end 152.072594 -389.880856)
		(width 0.14224)
		(layer "In4.Cu")
		(net "P5E_CPU1_P2_TX_BUF_DN<4>")
	)
	(arc
		(start 127.660654 -403.300184)
		(mid 127.49581 -403.546891)
		(end 127.437896 -403.837902)
		(width 0.14224)
		(layer "In4.Cu")
		(net "P5E_CPU1_P2_TX_BUF_DN<4>")
	)
	(segment
		(start 150.498302 -388.774432)
		(end 151.019002 -388.774432)
		(width 0.127)
		(layer "F.Cu")
		(net "P5E_CPU1_P2_TX_BUF_DN<3>")
	)
	(segment
		(start 124.354336 -407.954734)
		(end 124.354336 -404.73503)
		(width 0.12954)
		(layer "F.Cu")
		(net "P5E_CPU1_P2_TX_BUF_DN<3>")
	)
	(segment
		(start 124.058426 -408.250644)
		(end 124.354336 -407.954734)
		(width 0.12954)
		(layer "F.Cu")
		(net "P5E_CPU1_P2_TX_BUF_DN<3>")
	)
	(segment
		(start 124.354336 -404.73503)
		(end 124.083826 -404.46452)
		(width 0.12954)
		(layer "F.Cu")
		(net "P5E_CPU1_P2_TX_BUF_DN<3>")
	)
	(segment
		(start 124.374656 -404.17369)
		(end 124.083826 -404.46452)
		(width 0.14224)
		(layer "In4.Cu")
		(net "P5E_CPU1_P2_TX_BUF_DN<3>")
	)
	(segment
		(start 124.374656 -403.810978)
		(end 124.374656 -404.17369)
		(width 0.14224)
		(layer "In4.Cu")
		(net "P5E_CPU1_P2_TX_BUF_DN<3>")
	)
	(segment
		(start 124.849382 -403.053296)
		(end 124.574808 -403.32787)
		(width 0.14224)
		(layer "In4.Cu")
		(net "P5E_CPU1_P2_TX_BUF_DN<3>")
	)
	(segment
		(start 151.071326 -389.006588)
		(end 150.75281 -389.325104)
		(width 0.14224)
		(layer "In4.Cu")
		(net "P5E_CPU1_P2_TX_BUF_DN<3>")
	)
	(segment
		(start 150.339298 -391.513314)
		(end 150.339298 -394.168884)
		(width 0.14224)
		(layer "In4.Cu")
		(net "P5E_CPU1_P2_TX_BUF_DN<3>")
	)
	(segment
		(start 149.413722 -395.058138)
		(end 147.989036 -395.648434)
		(width 0.14224)
		(layer "In4.Cu")
		(net "P5E_CPU1_P2_TX_BUF_DN<3>")
	)
	(segment
		(start 150.912068 -389.922258)
		(end 151.076152 -390.086342)
		(width 0.14224)
		(layer "In4.Cu")
		(net "P5E_CPU1_P2_TX_BUF_DN<3>")
	)
	(segment
		(start 150.30196 -394.2588)
		(end 149.681438 -394.879322)
		(width 0.14224)
		(layer "In4.Cu")
		(net "P5E_CPU1_P2_TX_BUF_DN<3>")
	)
	(segment
		(start 151.019002 -388.774432)
		(end 151.071326 -388.826756)
		(width 0.14224)
		(layer "In4.Cu")
		(net "P5E_CPU1_P2_TX_BUF_DN<3>")
	)
	(segment
		(start 151.11349 -390.176004)
		(end 151.11349 -390.335516)
		(width 0.14224)
		(layer "In4.Cu")
		(net "P5E_CPU1_P2_TX_BUF_DN<3>")
	)
	(segment
		(start 151.001476 -390.605772)
		(end 150.51278 -391.094468)
		(width 0.14224)
		(layer "In4.Cu")
		(net "P5E_CPU1_P2_TX_BUF_DN<3>")
	)
	(segment
		(start 128.483106 -401.514056)
		(end 124.982224 -402.964396)
		(width 0.14224)
		(layer "In4.Cu")
		(net "P5E_CPU1_P2_TX_BUF_DN<3>")
	)
	(segment
		(start 146.18335 -396.145004)
		(end 128.483106 -401.514056)
		(width 0.14224)
		(layer "In4.Cu")
		(net "P5E_CPU1_P2_TX_BUF_DN<3>")
	)
	(segment
		(start 147.989036 -395.648434)
		(end 146.674078 -396.047214)
		(width 0.14224)
		(layer "In4.Cu")
		(net "P5E_CPU1_P2_TX_BUF_DN<3>")
	)
	(segment
		(start 151.071326 -388.826756)
		(end 151.071326 -389.006588)
		(width 0.14224)
		(layer "In4.Cu")
		(net "P5E_CPU1_P2_TX_BUF_DN<3>")
	)
	(segment
		(start 146.674078 -396.047214)
		(end 146.18335 -396.145004)
		(width 0.14224)
		(layer "In4.Cu")
		(net "P5E_CPU1_P2_TX_BUF_DN<3>")
	)
	(segment
		(start 150.75281 -389.325104)
		(end 150.75281 -389.537956)
		(width 0.14224)
		(layer "In4.Cu")
		(net "P5E_CPU1_P2_TX_BUF_DN<3>")
	)
	(arc
		(start 124.982224 -402.964396)
		(mid 124.911412 -403.002288)
		(end 124.849382 -403.053296)
		(width 0.14224)
		(layer "In4.Cu")
		(net "P5E_CPU1_P2_TX_BUF_DN<3>")
	)
	(arc
		(start 150.75281 -389.537956)
		(mid 150.794201 -389.745953)
		(end 150.912068 -389.922258)
		(width 0.14224)
		(layer "In4.Cu")
		(net "P5E_CPU1_P2_TX_BUF_DN<3>")
	)
	(arc
		(start 150.51278 -391.094468)
		(mid 150.384377 -391.286636)
		(end 150.339298 -391.513314)
		(width 0.14224)
		(layer "In4.Cu")
		(net "P5E_CPU1_P2_TX_BUF_DN<3>")
	)
	(arc
		(start 124.574808 -403.32787)
		(mid 124.426651 -403.549508)
		(end 124.374656 -403.810978)
		(width 0.14224)
		(layer "In4.Cu")
		(net "P5E_CPU1_P2_TX_BUF_DN<3>")
	)
	(arc
		(start 151.076152 -390.086342)
		(mid 151.103722 -390.127464)
		(end 151.11349 -390.176004)
		(width 0.14224)
		(layer "In4.Cu")
		(net "P5E_CPU1_P2_TX_BUF_DN<3>")
	)
	(arc
		(start 150.339298 -394.168884)
		(mid 150.329596 -394.217568)
		(end 150.30196 -394.2588)
		(width 0.14224)
		(layer "In4.Cu")
		(net "P5E_CPU1_P2_TX_BUF_DN<3>")
	)
	(arc
		(start 149.681438 -394.879322)
		(mid 149.556384 -394.98191)
		(end 149.413722 -395.058138)
		(width 0.14224)
		(layer "In4.Cu")
		(net "P5E_CPU1_P2_TX_BUF_DN<3>")
	)
	(arc
		(start 151.11349 -390.335516)
		(mid 151.084376 -390.48179)
		(end 151.001476 -390.605772)
		(width 0.14224)
		(layer "In4.Cu")
		(net "P5E_CPU1_P2_TX_BUF_DN<3>")
	)
	(segment
		(start 149.298406 -388.774432)
		(end 149.819106 -388.774432)
		(width 0.127)
		(layer "F.Cu")
		(net "P5E_CPU1_P2_TX_BUF_DN<2>")
	)
	(segment
		(start 121.291096 -407.954734)
		(end 121.291096 -404.73503)
		(width 0.12954)
		(layer "F.Cu")
		(net "P5E_CPU1_P2_TX_BUF_DN<2>")
	)
	(segment
		(start 121.291096 -404.73503)
		(end 121.020586 -404.46452)
		(width 0.12954)
		(layer "F.Cu")
		(net "P5E_CPU1_P2_TX_BUF_DN<2>")
	)
	(segment
		(start 120.995186 -408.250644)
		(end 121.291096 -407.954734)
		(width 0.12954)
		(layer "F.Cu")
		(net "P5E_CPU1_P2_TX_BUF_DN<2>")
	)
	(segment
		(start 121.311416 -403.890226)
		(end 121.311416 -404.17369)
		(width 0.14224)
		(layer "In4.Cu")
		(net "P5E_CPU1_P2_TX_BUF_DN<2>")
	)
	(segment
		(start 148.841206 -394.273532)
		(end 148.077428 -394.589508)
		(width 0.14224)
		(layer "In4.Cu")
		(net "P5E_CPU1_P2_TX_BUF_DN<2>")
	)
	(segment
		(start 149.870414 -388.82574)
		(end 149.870414 -389.035544)
		(width 0.14224)
		(layer "In4.Cu")
		(net "P5E_CPU1_P2_TX_BUF_DN<2>")
	)
	(segment
		(start 149.15642 -391.4521)
		(end 149.15642 -393.800584)
		(width 0.14224)
		(layer "In4.Cu")
		(net "P5E_CPU1_P2_TX_BUF_DN<2>")
	)
	(segment
		(start 149.826472 -390.173464)
		(end 149.826472 -390.301988)
		(width 0.14224)
		(layer "In4.Cu")
		(net "P5E_CPU1_P2_TX_BUF_DN<2>")
	)
	(segment
		(start 126.148592 -401.28444)
		(end 124.867162 -401.8153)
		(width 0.14224)
		(layer "In4.Cu")
		(net "P5E_CPU1_P2_TX_BUF_DN<2>")
	)
	(segment
		(start 149.819106 -388.774432)
		(end 149.870414 -388.82574)
		(width 0.14224)
		(layer "In4.Cu")
		(net "P5E_CPU1_P2_TX_BUF_DN<2>")
	)
	(segment
		(start 149.870414 -389.035544)
		(end 149.554438 -389.35152)
		(width 0.14224)
		(layer "In4.Cu")
		(net "P5E_CPU1_P2_TX_BUF_DN<2>")
	)
	(segment
		(start 149.702012 -390.60247)
		(end 149.371812 -390.93267)
		(width 0.14224)
		(layer "In4.Cu")
		(net "P5E_CPU1_P2_TX_BUF_DN<2>")
	)
	(segment
		(start 121.716038 -403.15388)
		(end 121.545858 -403.32406)
		(width 0.14224)
		(layer "In4.Cu")
		(net "P5E_CPU1_P2_TX_BUF_DN<2>")
	)
	(segment
		(start 149.554438 -389.35152)
		(end 149.554438 -389.48995)
		(width 0.14224)
		(layer "In4.Cu")
		(net "P5E_CPU1_P2_TX_BUF_DN<2>")
	)
	(segment
		(start 124.867162 -401.815046)
		(end 121.84888 -403.065234)
		(width 0.14224)
		(layer "In4.Cu")
		(net "P5E_CPU1_P2_TX_BUF_DN<2>")
	)
	(segment
		(start 121.311416 -404.17369)
		(end 121.020586 -404.46452)
		(width 0.14224)
		(layer "In4.Cu")
		(net "P5E_CPU1_P2_TX_BUF_DN<2>")
	)
	(segment
		(start 124.867162 -401.8153)
		(end 124.867162 -401.815046)
		(width 0.14224)
		(layer "In4.Cu")
		(net "P5E_CPU1_P2_TX_BUF_DN<2>")
	)
	(segment
		(start 147.958302 -394.631926)
		(end 126.821692 -401.043648)
		(width 0.14224)
		(layer "In4.Cu")
		(net "P5E_CPU1_P2_TX_BUF_DN<2>")
	)
	(arc
		(start 148.077428 -394.589508)
		(mid 148.018385 -394.612177)
		(end 147.958302 -394.631926)
		(width 0.14224)
		(layer "In4.Cu")
		(net "P5E_CPU1_P2_TX_BUF_DN<2>")
	)
	(arc
		(start 126.821692 -401.043648)
		(mid 126.482184 -401.155776)
		(end 126.148592 -401.28444)
		(width 0.14224)
		(layer "In4.Cu")
		(net "P5E_CPU1_P2_TX_BUF_DN<2>")
	)
	(arc
		(start 149.554438 -389.48995)
		(mid 149.60144 -389.735172)
		(end 149.735794 -389.945626)
		(width 0.14224)
		(layer "In4.Cu")
		(net "P5E_CPU1_P2_TX_BUF_DN<2>")
	)
	(arc
		(start 121.84888 -403.065234)
		(mid 121.778102 -403.103026)
		(end 121.716038 -403.15388)
		(width 0.14224)
		(layer "In4.Cu")
		(net "P5E_CPU1_P2_TX_BUF_DN<2>")
	)
	(arc
		(start 149.826472 -390.301988)
		(mid 149.794125 -390.464606)
		(end 149.702012 -390.60247)
		(width 0.14224)
		(layer "In4.Cu")
		(net "P5E_CPU1_P2_TX_BUF_DN<2>")
	)
	(arc
		(start 149.032976 -394.134594)
		(mid 148.945297 -394.215384)
		(end 148.841206 -394.273532)
		(width 0.14224)
		(layer "In4.Cu")
		(net "P5E_CPU1_P2_TX_BUF_DN<2>")
	)
	(arc
		(start 149.371812 -390.93267)
		(mid 149.212516 -391.170985)
		(end 149.15642 -391.4521)
		(width 0.14224)
		(layer "In4.Cu")
		(net "P5E_CPU1_P2_TX_BUF_DN<2>")
	)
	(arc
		(start 149.15642 -393.800584)
		(mid 149.124571 -393.978629)
		(end 149.032976 -394.134594)
		(width 0.14224)
		(layer "In4.Cu")
		(net "P5E_CPU1_P2_TX_BUF_DN<2>")
	)
	(arc
		(start 121.545858 -403.32406)
		(mid 121.372346 -403.583833)
		(end 121.311416 -403.890226)
		(width 0.14224)
		(layer "In4.Cu")
		(net "P5E_CPU1_P2_TX_BUF_DN<2>")
	)
	(arc
		(start 149.735794 -389.945626)
		(mid 149.80299 -390.050849)
		(end 149.826472 -390.173464)
		(width 0.14224)
		(layer "In4.Cu")
		(net "P5E_CPU1_P2_TX_BUF_DN<2>")
	)
	(segment
		(start 117.931946 -408.250644)
		(end 118.227856 -407.954734)
		(width 0.12954)
		(layer "F.Cu")
		(net "P5E_CPU1_P2_TX_BUF_DN<1>")
	)
	(segment
		(start 148.098256 -388.774432)
		(end 148.618956 -388.774432)
		(width 0.127)
		(layer "F.Cu")
		(net "P5E_CPU1_P2_TX_BUF_DN<1>")
	)
	(segment
		(start 118.227856 -404.73503)
		(end 117.957346 -404.46452)
		(width 0.12954)
		(layer "F.Cu")
		(net "P5E_CPU1_P2_TX_BUF_DN<1>")
	)
	(segment
		(start 118.227856 -407.954734)
		(end 118.227856 -404.73503)
		(width 0.12954)
		(layer "F.Cu")
		(net "P5E_CPU1_P2_TX_BUF_DN<1>")
	)
	(segment
		(start 148.70049 -390.259824)
		(end 147.969732 -390.990582)
		(width 0.14224)
		(layer "In4.Cu")
		(net "P5E_CPU1_P2_TX_BUF_DN<1>")
	)
	(segment
		(start 136.440672 -397.151098)
		(end 136.440672 -397.151352)
		(width 0.14224)
		(layer "In4.Cu")
		(net "P5E_CPU1_P2_TX_BUF_DN<1>")
	)
	(segment
		(start 118.248176 -404.17369)
		(end 117.957346 -404.46452)
		(width 0.14224)
		(layer "In4.Cu")
		(net "P5E_CPU1_P2_TX_BUF_DN<1>")
	)
	(segment
		(start 145.340832 -393.990576)
		(end 144.822926 -394.508482)
		(width 0.14224)
		(layer "In4.Cu")
		(net "P5E_CPU1_P2_TX_BUF_DN<1>")
	)
	(segment
		(start 148.472652 -389.852916)
		(end 148.70049 -390.080754)
		(width 0.14224)
		(layer "In4.Cu")
		(net "P5E_CPU1_P2_TX_BUF_DN<1>")
	)
	(segment
		(start 118.55323 -403.236684)
		(end 118.552976 -403.236684)
		(width 0.14224)
		(layer "In4.Cu")
		(net "P5E_CPU1_P2_TX_BUF_DN<1>")
	)
	(segment
		(start 128.202182 -399.650458)
		(end 127.157226 -399.650458)
		(width 0.14224)
		(layer "In4.Cu")
		(net "P5E_CPU1_P2_TX_BUF_DN<1>")
	)
	(segment
		(start 146.238976 -393.4968)
		(end 145.340832 -393.990576)
		(width 0.14224)
		(layer "In4.Cu")
		(net "P5E_CPU1_P2_TX_BUF_DN<1>")
	)
	(segment
		(start 148.67128 -389.006588)
		(end 148.352764 -389.325104)
		(width 0.14224)
		(layer "In4.Cu")
		(net "P5E_CPU1_P2_TX_BUF_DN<1>")
	)
	(segment
		(start 118.552976 -403.236684)
		(end 118.464076 -403.325584)
		(width 0.14224)
		(layer "In4.Cu")
		(net "P5E_CPU1_P2_TX_BUF_DN<1>")
	)
	(segment
		(start 118.248176 -403.846792)
		(end 118.248176 -404.17369)
		(width 0.14224)
		(layer "In4.Cu")
		(net "P5E_CPU1_P2_TX_BUF_DN<1>")
	)
	(segment
		(start 148.352764 -389.325104)
		(end 148.352764 -389.563356)
		(width 0.14224)
		(layer "In4.Cu")
		(net "P5E_CPU1_P2_TX_BUF_DN<1>")
	)
	(segment
		(start 120.187212 -402.423122)
		(end 119.151908 -402.85162)
		(width 0.14224)
		(layer "In4.Cu")
		(net "P5E_CPU1_P2_TX_BUF_DN<1>")
	)
	(segment
		(start 148.618956 -388.774432)
		(end 148.67128 -388.826756)
		(width 0.14224)
		(layer "In4.Cu")
		(net "P5E_CPU1_P2_TX_BUF_DN<1>")
	)
	(segment
		(start 148.67128 -388.826756)
		(end 148.67128 -389.006588)
		(width 0.14224)
		(layer "In4.Cu")
		(net "P5E_CPU1_P2_TX_BUF_DN<1>")
	)
	(segment
		(start 147.93722 -391.004044)
		(end 147.442428 -391.004044)
		(width 0.14224)
		(layer "In4.Cu")
		(net "P5E_CPU1_P2_TX_BUF_DN<1>")
	)
	(segment
		(start 136.440672 -397.151352)
		(end 128.202182 -399.650458)
		(width 0.14224)
		(layer "In4.Cu")
		(net "P5E_CPU1_P2_TX_BUF_DN<1>")
	)
	(segment
		(start 146.666204 -391.93597)
		(end 146.666204 -392.774424)
		(width 0.14224)
		(layer "In4.Cu")
		(net "P5E_CPU1_P2_TX_BUF_DN<1>")
	)
	(segment
		(start 144.48536 -394.710666)
		(end 136.440672 -397.151098)
		(width 0.14224)
		(layer "In4.Cu")
		(net "P5E_CPU1_P2_TX_BUF_DN<1>")
	)
	(segment
		(start 126.623572 -399.756376)
		(end 120.186958 -402.422868)
		(width 0.14224)
		(layer "In4.Cu")
		(net "P5E_CPU1_P2_TX_BUF_DN<1>")
	)
	(segment
		(start 120.186958 -402.422868)
		(end 120.187212 -402.423122)
		(width 0.14224)
		(layer "In4.Cu")
		(net "P5E_CPU1_P2_TX_BUF_DN<1>")
	)
	(segment
		(start 147.087336 -391.15111)
		(end 146.923506 -391.31494)
		(width 0.14224)
		(layer "In4.Cu")
		(net "P5E_CPU1_P2_TX_BUF_DN<1>")
	)
	(arc
		(start 118.464076 -403.325584)
		(mid 118.304293 -403.564716)
		(end 118.248176 -403.846792)
		(width 0.14224)
		(layer "In4.Cu")
		(net "P5E_CPU1_P2_TX_BUF_DN<1>")
	)
	(arc
		(start 146.666204 -392.774424)
		(mid 146.551395 -393.194039)
		(end 146.238976 -393.4968)
		(width 0.14224)
		(layer "In4.Cu")
		(net "P5E_CPU1_P2_TX_BUF_DN<1>")
	)
	(arc
		(start 147.442428 -391.004044)
		(mid 147.25026 -391.042269)
		(end 147.087336 -391.15111)
		(width 0.14224)
		(layer "In4.Cu")
		(net "P5E_CPU1_P2_TX_BUF_DN<1>")
	)
	(arc
		(start 147.969732 -390.990582)
		(mid 147.954815 -391.000549)
		(end 147.93722 -391.004044)
		(width 0.14224)
		(layer "In4.Cu")
		(net "P5E_CPU1_P2_TX_BUF_DN<1>")
	)
	(arc
		(start 144.822926 -394.508482)
		(mid 144.666604 -394.630378)
		(end 144.48536 -394.710666)
		(width 0.14224)
		(layer "In4.Cu")
		(net "P5E_CPU1_P2_TX_BUF_DN<1>")
	)
	(arc
		(start 119.151908 -402.85162)
		(mid 118.835314 -403.017327)
		(end 118.55323 -403.236684)
		(width 0.14224)
		(layer "In4.Cu")
		(net "P5E_CPU1_P2_TX_BUF_DN<1>")
	)
	(arc
		(start 148.352764 -389.563356)
		(mid 148.383916 -389.720059)
		(end 148.472652 -389.852916)
		(width 0.14224)
		(layer "In4.Cu")
		(net "P5E_CPU1_P2_TX_BUF_DN<1>")
	)
	(arc
		(start 148.70049 -390.080754)
		(mid 148.737704 -390.170326)
		(end 148.70049 -390.259824)
		(width 0.14224)
		(layer "In4.Cu")
		(net "P5E_CPU1_P2_TX_BUF_DN<1>")
	)
	(arc
		(start 146.923506 -391.31494)
		(mid 146.733067 -391.599857)
		(end 146.666204 -391.93597)
		(width 0.14224)
		(layer "In4.Cu")
		(net "P5E_CPU1_P2_TX_BUF_DN<1>")
	)
	(arc
		(start 127.157226 -399.650458)
		(mid 126.885189 -399.677154)
		(end 126.623572 -399.756376)
		(width 0.14224)
		(layer "In4.Cu")
		(net "P5E_CPU1_P2_TX_BUF_DN<1>")
	)
	(segment
		(start 161.113216 -407.954734)
		(end 161.113216 -404.73503)
		(width 0.12954)
		(layer "F.Cu")
		(net "P5E_CPU1_P2_TX_BUF_DN<15>")
	)
	(segment
		(start 164.898324 -388.774432)
		(end 165.419024 -388.774432)
		(width 0.127)
		(layer "F.Cu")
		(net "P5E_CPU1_P2_TX_BUF_DN<15>")
	)
	(segment
		(start 161.113216 -404.73503)
		(end 160.842706 -404.46452)
		(width 0.12954)
		(layer "F.Cu")
		(net "P5E_CPU1_P2_TX_BUF_DN<15>")
	)
	(segment
		(start 160.817306 -408.250644)
		(end 161.113216 -407.954734)
		(width 0.12954)
		(layer "F.Cu")
		(net "P5E_CPU1_P2_TX_BUF_DN<15>")
	)
	(segment
		(start 161.133536 -403.93112)
		(end 161.133536 -404.17369)
		(width 0.14224)
		(layer "In4.Cu")
		(net "P5E_CPU1_P2_TX_BUF_DN<15>")
	)
	(segment
		(start 165.471348 -389.006588)
		(end 165.152832 -389.325104)
		(width 0.14224)
		(layer "In4.Cu")
		(net "P5E_CPU1_P2_TX_BUF_DN<15>")
	)
	(segment
		(start 161.133536 -404.17369)
		(end 160.842706 -404.46452)
		(width 0.14224)
		(layer "In4.Cu")
		(net "P5E_CPU1_P2_TX_BUF_DN<15>")
	)
	(segment
		(start 165.471348 -388.826756)
		(end 165.471348 -389.006588)
		(width 0.14224)
		(layer "In4.Cu")
		(net "P5E_CPU1_P2_TX_BUF_DN<15>")
	)
	(segment
		(start 165.381686 -390.903714)
		(end 164.878258 -391.407142)
		(width 0.14224)
		(layer "In4.Cu")
		(net "P5E_CPU1_P2_TX_BUF_DN<15>")
	)
	(segment
		(start 163.836858 -398.433798)
		(end 161.3408 -403.10308)
		(width 0.14224)
		(layer "In4.Cu")
		(net "P5E_CPU1_P2_TX_BUF_DN<15>")
	)
	(segment
		(start 164.576252 -396.318232)
		(end 164.434774 -396.883636)
		(width 0.14224)
		(layer "In4.Cu")
		(net "P5E_CPU1_P2_TX_BUF_DN<15>")
	)
	(segment
		(start 165.513512 -390.176512)
		(end 165.513512 -390.585198)
		(width 0.14224)
		(layer "In4.Cu")
		(net "P5E_CPU1_P2_TX_BUF_DN<15>")
	)
	(segment
		(start 165.152832 -389.325104)
		(end 165.152832 -389.592566)
		(width 0.14224)
		(layer "In4.Cu")
		(net "P5E_CPU1_P2_TX_BUF_DN<15>")
	)
	(segment
		(start 165.419024 -388.774432)
		(end 165.471348 -388.826756)
		(width 0.14224)
		(layer "In4.Cu")
		(net "P5E_CPU1_P2_TX_BUF_DN<15>")
	)
	(segment
		(start 165.27272 -389.881872)
		(end 165.475412 -390.084564)
		(width 0.14224)
		(layer "In4.Cu")
		(net "P5E_CPU1_P2_TX_BUF_DN<15>")
	)
	(segment
		(start 164.748464 -391.720832)
		(end 164.748464 -394.923264)
		(width 0.14224)
		(layer "In4.Cu")
		(net "P5E_CPU1_P2_TX_BUF_DN<15>")
	)
	(arc
		(start 165.513512 -390.585198)
		(mid 165.479232 -390.757536)
		(end 165.381686 -390.903714)
		(width 0.14224)
		(layer "In4.Cu")
		(net "P5E_CPU1_P2_TX_BUF_DN<15>")
	)
	(arc
		(start 164.878258 -391.407142)
		(mid 164.782122 -391.551065)
		(end 164.748464 -391.720832)
		(width 0.14224)
		(layer "In4.Cu")
		(net "P5E_CPU1_P2_TX_BUF_DN<15>")
	)
	(arc
		(start 164.748464 -394.923264)
		(mid 164.70522 -395.62604)
		(end 164.576252 -396.318232)
		(width 0.14224)
		(layer "In4.Cu")
		(net "P5E_CPU1_P2_TX_BUF_DN<15>")
	)
	(arc
		(start 165.152832 -389.592566)
		(mid 165.183995 -389.749144)
		(end 165.27272 -389.881872)
		(width 0.14224)
		(layer "In4.Cu")
		(net "P5E_CPU1_P2_TX_BUF_DN<15>")
	)
	(arc
		(start 161.3408 -403.10308)
		(mid 161.186153 -403.504327)
		(end 161.133536 -403.93112)
		(width 0.14224)
		(layer "In4.Cu")
		(net "P5E_CPU1_P2_TX_BUF_DN<15>")
	)
	(arc
		(start 164.434774 -396.883636)
		(mid 164.183449 -397.67709)
		(end 163.836858 -398.433798)
		(width 0.14224)
		(layer "In4.Cu")
		(net "P5E_CPU1_P2_TX_BUF_DN<15>")
	)
	(arc
		(start 165.475412 -390.084564)
		(mid 165.5036 -390.12675)
		(end 165.513512 -390.176512)
		(width 0.14224)
		(layer "In4.Cu")
		(net "P5E_CPU1_P2_TX_BUF_DN<15>")
	)
	(segment
		(start 158.049976 -407.954734)
		(end 158.049976 -404.73503)
		(width 0.12954)
		(layer "F.Cu")
		(net "P5E_CPU1_P2_TX_BUF_DN<14>")
	)
	(segment
		(start 163.698428 -388.774432)
		(end 164.219128 -388.774432)
		(width 0.127)
		(layer "F.Cu")
		(net "P5E_CPU1_P2_TX_BUF_DN<14>")
	)
	(segment
		(start 158.049976 -404.73503)
		(end 157.779466 -404.46452)
		(width 0.12954)
		(layer "F.Cu")
		(net "P5E_CPU1_P2_TX_BUF_DN<14>")
	)
	(segment
		(start 157.754066 -408.250644)
		(end 158.049976 -407.954734)
		(width 0.12954)
		(layer "F.Cu")
		(net "P5E_CPU1_P2_TX_BUF_DN<14>")
	)
	(segment
		(start 164.342572 -390.271762)
		(end 164.342572 -390.504172)
		(width 0.14224)
		(layer "In4.Cu")
		(net "P5E_CPU1_P2_TX_BUF_DN<14>")
	)
	(segment
		(start 163.548314 -391.81151)
		(end 163.548314 -395.435836)
		(width 0.14224)
		(layer "In4.Cu")
		(net "P5E_CPU1_P2_TX_BUF_DN<14>")
	)
	(segment
		(start 163.952936 -389.325104)
		(end 163.952936 -389.583422)
		(width 0.14224)
		(layer "In4.Cu")
		(net "P5E_CPU1_P2_TX_BUF_DN<14>")
	)
	(segment
		(start 158.070296 -403.436074)
		(end 158.070296 -404.17369)
		(width 0.14224)
		(layer "In4.Cu")
		(net "P5E_CPU1_P2_TX_BUF_DN<14>")
	)
	(segment
		(start 163.07054 -396.770352)
		(end 159.275526 -401.39493)
		(width 0.14224)
		(layer "In4.Cu")
		(net "P5E_CPU1_P2_TX_BUF_DN<14>")
	)
	(segment
		(start 159.275526 -401.39493)
		(end 158.202122 -403.001226)
		(width 0.14224)
		(layer "In4.Cu")
		(net "P5E_CPU1_P2_TX_BUF_DN<14>")
	)
	(segment
		(start 164.072824 -389.872728)
		(end 164.250878 -390.050782)
		(width 0.14224)
		(layer "In4.Cu")
		(net "P5E_CPU1_P2_TX_BUF_DN<14>")
	)
	(segment
		(start 158.070296 -404.17369)
		(end 157.779466 -404.46452)
		(width 0.14224)
		(layer "In4.Cu")
		(net "P5E_CPU1_P2_TX_BUF_DN<14>")
	)
	(segment
		(start 164.219128 -388.774432)
		(end 164.271452 -388.826756)
		(width 0.14224)
		(layer "In4.Cu")
		(net "P5E_CPU1_P2_TX_BUF_DN<14>")
	)
	(segment
		(start 164.271452 -388.826756)
		(end 164.271452 -389.006588)
		(width 0.14224)
		(layer "In4.Cu")
		(net "P5E_CPU1_P2_TX_BUF_DN<14>")
	)
	(segment
		(start 164.187886 -390.877298)
		(end 163.756848 -391.308082)
		(width 0.14224)
		(layer "In4.Cu")
		(net "P5E_CPU1_P2_TX_BUF_DN<14>")
	)
	(segment
		(start 164.271452 -389.006588)
		(end 163.952936 -389.325104)
		(width 0.14224)
		(layer "In4.Cu")
		(net "P5E_CPU1_P2_TX_BUF_DN<14>")
	)
	(arc
		(start 163.756848 -391.308082)
		(mid 163.602516 -391.539057)
		(end 163.548314 -391.81151)
		(width 0.14224)
		(layer "In4.Cu")
		(net "P5E_CPU1_P2_TX_BUF_DN<14>")
	)
	(arc
		(start 164.250878 -390.050782)
		(mid 164.318676 -390.152154)
		(end 164.342572 -390.271762)
		(width 0.14224)
		(layer "In4.Cu")
		(net "P5E_CPU1_P2_TX_BUF_DN<14>")
	)
	(arc
		(start 158.202122 -403.001226)
		(mid 158.103972 -403.208878)
		(end 158.070296 -403.436074)
		(width 0.14224)
		(layer "In4.Cu")
		(net "P5E_CPU1_P2_TX_BUF_DN<14>")
	)
	(arc
		(start 163.548314 -395.435836)
		(mid 163.425177 -396.14453)
		(end 163.07054 -396.770352)
		(width 0.14224)
		(layer "In4.Cu")
		(net "P5E_CPU1_P2_TX_BUF_DN<14>")
	)
	(arc
		(start 163.952936 -389.583422)
		(mid 163.984099 -389.74)
		(end 164.072824 -389.872728)
		(width 0.14224)
		(layer "In4.Cu")
		(net "P5E_CPU1_P2_TX_BUF_DN<14>")
	)
	(arc
		(start 164.342572 -390.504172)
		(mid 164.302433 -390.706168)
		(end 164.187886 -390.877298)
		(width 0.14224)
		(layer "In4.Cu")
		(net "P5E_CPU1_P2_TX_BUF_DN<14>")
	)
	(segment
		(start 162.498278 -388.774432)
		(end 163.018978 -388.774432)
		(width 0.127)
		(layer "F.Cu")
		(net "P5E_CPU1_P2_TX_BUF_DN<13>")
	)
	(segment
		(start 154.986736 -407.954734)
		(end 154.986736 -404.73503)
		(width 0.12954)
		(layer "F.Cu")
		(net "P5E_CPU1_P2_TX_BUF_DN<13>")
	)
	(segment
		(start 154.690826 -408.250644)
		(end 154.986736 -407.954734)
		(width 0.12954)
		(layer "F.Cu")
		(net "P5E_CPU1_P2_TX_BUF_DN<13>")
	)
	(segment
		(start 154.986736 -404.73503)
		(end 154.716226 -404.46452)
		(width 0.12954)
		(layer "F.Cu")
		(net "P5E_CPU1_P2_TX_BUF_DN<13>")
	)
	(segment
		(start 155.007056 -403.790912)
		(end 155.007056 -404.17369)
		(width 0.14224)
		(layer "In4.Cu")
		(net "P5E_CPU1_P2_TX_BUF_DN<13>")
	)
	(segment
		(start 163.071302 -388.826756)
		(end 163.071302 -389.006588)
		(width 0.14224)
		(layer "In4.Cu")
		(net "P5E_CPU1_P2_TX_BUF_DN<13>")
	)
	(segment
		(start 155.007056 -404.17369)
		(end 154.716226 -404.46452)
		(width 0.14224)
		(layer "In4.Cu")
		(net "P5E_CPU1_P2_TX_BUF_DN<13>")
	)
	(segment
		(start 162.752786 -389.325104)
		(end 162.752786 -389.504936)
		(width 0.14224)
		(layer "In4.Cu")
		(net "P5E_CPU1_P2_TX_BUF_DN<13>")
	)
	(segment
		(start 163.071302 -389.006588)
		(end 162.752786 -389.325104)
		(width 0.14224)
		(layer "In4.Cu")
		(net "P5E_CPU1_P2_TX_BUF_DN<13>")
	)
	(segment
		(start 163.018978 -388.774432)
		(end 163.071302 -388.826756)
		(width 0.14224)
		(layer "In4.Cu")
		(net "P5E_CPU1_P2_TX_BUF_DN<13>")
	)
	(segment
		(start 163.113466 -390.382252)
		(end 163.113466 -390.564878)
		(width 0.14224)
		(layer "In4.Cu")
		(net "P5E_CPU1_P2_TX_BUF_DN<13>")
	)
	(segment
		(start 162.103816 -396.239492)
		(end 155.32862 -403.014688)
		(width 0.14224)
		(layer "In4.Cu")
		(net "P5E_CPU1_P2_TX_BUF_DN<13>")
	)
	(segment
		(start 162.348418 -391.70737)
		(end 162.348418 -395.648942)
		(width 0.14224)
		(layer "In4.Cu")
		(net "P5E_CPU1_P2_TX_BUF_DN<13>")
	)
	(segment
		(start 163.002468 -390.865868)
		(end 162.480752 -391.387838)
		(width 0.14224)
		(layer "In4.Cu")
		(net "P5E_CPU1_P2_TX_BUF_DN<13>")
	)
	(arc
		(start 162.933126 -389.943594)
		(mid 163.066641 -390.145106)
		(end 163.113466 -390.382252)
		(width 0.14224)
		(layer "In4.Cu")
		(net "P5E_CPU1_P2_TX_BUF_DN<13>")
	)
	(arc
		(start 162.752786 -389.504936)
		(mid 162.799636 -389.742072)
		(end 162.933126 -389.943594)
		(width 0.14224)
		(layer "In4.Cu")
		(net "P5E_CPU1_P2_TX_BUF_DN<13>")
	)
	(arc
		(start 162.348418 -395.648942)
		(mid 162.284846 -395.968541)
		(end 162.103816 -396.239492)
		(width 0.14224)
		(layer "In4.Cu")
		(net "P5E_CPU1_P2_TX_BUF_DN<13>")
	)
	(arc
		(start 163.113466 -390.564878)
		(mid 163.103442 -390.664938)
		(end 163.073588 -390.760966)
		(width 0.14224)
		(layer "In4.Cu")
		(net "P5E_CPU1_P2_TX_BUF_DN<13>")
	)
	(arc
		(start 155.32862 -403.014688)
		(mid 155.090605 -403.370808)
		(end 155.007056 -403.790912)
		(width 0.14224)
		(layer "In4.Cu")
		(net "P5E_CPU1_P2_TX_BUF_DN<13>")
	)
	(arc
		(start 163.073588 -390.760966)
		(mid 163.043068 -390.816835)
		(end 163.002468 -390.865868)
		(width 0.14224)
		(layer "In4.Cu")
		(net "P5E_CPU1_P2_TX_BUF_DN<13>")
	)
	(arc
		(start 162.480752 -391.387838)
		(mid 162.382795 -391.534441)
		(end 162.348418 -391.70737)
		(width 0.14224)
		(layer "In4.Cu")
		(net "P5E_CPU1_P2_TX_BUF_DN<13>")
	)
	(segment
		(start 151.627586 -408.250644)
		(end 151.923496 -407.954734)
		(width 0.12954)
		(layer "F.Cu")
		(net "P5E_CPU1_P2_TX_BUF_DN<12>")
	)
	(segment
		(start 151.923496 -407.954734)
		(end 151.923496 -404.73503)
		(width 0.12954)
		(layer "F.Cu")
		(net "P5E_CPU1_P2_TX_BUF_DN<12>")
	)
	(segment
		(start 151.923496 -404.73503)
		(end 151.652986 -404.46452)
		(width 0.12954)
		(layer "F.Cu")
		(net "P5E_CPU1_P2_TX_BUF_DN<12>")
	)
	(segment
		(start 161.298382 -388.774432)
		(end 161.819082 -388.774432)
		(width 0.127)
		(layer "F.Cu")
		(net "P5E_CPU1_P2_TX_BUF_DN<12>")
	)
	(segment
		(start 152.35809 -403.122384)
		(end 154.372818 -402.25726)
		(width 0.14224)
		(layer "In4.Cu")
		(net "P5E_CPU1_P2_TX_BUF_DN<12>")
	)
	(segment
		(start 154.373072 -402.257006)
		(end 154.84094 -402.056346)
		(width 0.14224)
		(layer "In4.Cu")
		(net "P5E_CPU1_P2_TX_BUF_DN<12>")
	)
	(segment
		(start 161.55289 -389.325104)
		(end 161.871406 -389.006588)
		(width 0.14224)
		(layer "In4.Cu")
		(net "P5E_CPU1_P2_TX_BUF_DN<12>")
	)
	(segment
		(start 151.652986 -404.46452)
		(end 151.943816 -404.17369)
		(width 0.14224)
		(layer "In4.Cu")
		(net "P5E_CPU1_P2_TX_BUF_DN<12>")
	)
	(segment
		(start 161.86404 -390.063736)
		(end 161.716466 -389.916416)
		(width 0.14224)
		(layer "In4.Cu")
		(net "P5E_CPU1_P2_TX_BUF_DN<12>")
	)
	(segment
		(start 161.55289 -389.521954)
		(end 161.55289 -389.325104)
		(width 0.14224)
		(layer "In4.Cu")
		(net "P5E_CPU1_P2_TX_BUF_DN<12>")
	)
	(segment
		(start 161.871406 -388.826756)
		(end 161.819082 -388.774432)
		(width 0.14224)
		(layer "In4.Cu")
		(net "P5E_CPU1_P2_TX_BUF_DN<12>")
	)
	(segment
		(start 154.372818 -402.25726)
		(end 154.373072 -402.257006)
		(width 0.14224)
		(layer "In4.Cu")
		(net "P5E_CPU1_P2_TX_BUF_DN<12>")
	)
	(segment
		(start 161.901378 -390.554718)
		(end 161.901378 -390.153652)
		(width 0.14224)
		(layer "In4.Cu")
		(net "P5E_CPU1_P2_TX_BUF_DN<12>")
	)
	(segment
		(start 161.278062 -391.370312)
		(end 161.765234 -390.88314)
		(width 0.14224)
		(layer "In4.Cu")
		(net "P5E_CPU1_P2_TX_BUF_DN<12>")
	)
	(segment
		(start 155.056078 -401.91055)
		(end 161.038286 -395.928342)
		(width 0.14224)
		(layer "In4.Cu")
		(net "P5E_CPU1_P2_TX_BUF_DN<12>")
	)
	(segment
		(start 151.943816 -404.17369)
		(end 151.943816 -403.745192)
		(width 0.14224)
		(layer "In4.Cu")
		(net "P5E_CPU1_P2_TX_BUF_DN<12>")
	)
	(segment
		(start 152.09139 -403.389084)
		(end 152.35809 -403.122384)
		(width 0.14224)
		(layer "In4.Cu")
		(net "P5E_CPU1_P2_TX_BUF_DN<12>")
	)
	(segment
		(start 161.871406 -389.006588)
		(end 161.871406 -388.826756)
		(width 0.14224)
		(layer "In4.Cu")
		(net "P5E_CPU1_P2_TX_BUF_DN<12>")
	)
	(segment
		(start 161.148268 -395.663166)
		(end 161.148268 -391.684002)
		(width 0.14224)
		(layer "In4.Cu")
		(net "P5E_CPU1_P2_TX_BUF_DN<12>")
	)
	(arc
		(start 154.84094 -402.056346)
		(mid 154.955449 -401.99369)
		(end 155.056078 -401.91055)
		(width 0.14224)
		(layer "In4.Cu")
		(net "P5E_CPU1_P2_TX_BUF_DN<12>")
	)
	(arc
		(start 161.148268 -391.684002)
		(mid 161.181958 -391.514249)
		(end 161.278062 -391.370312)
		(width 0.14224)
		(layer "In4.Cu")
		(net "P5E_CPU1_P2_TX_BUF_DN<12>")
	)
	(arc
		(start 161.038286 -395.928342)
		(mid 161.119687 -395.806707)
		(end 161.148268 -395.663166)
		(width 0.14224)
		(layer "In4.Cu")
		(net "P5E_CPU1_P2_TX_BUF_DN<12>")
	)
	(arc
		(start 161.765234 -390.88314)
		(mid 161.86597 -390.732473)
		(end 161.901378 -390.554718)
		(width 0.14224)
		(layer "In4.Cu")
		(net "P5E_CPU1_P2_TX_BUF_DN<12>")
	)
	(arc
		(start 151.943816 -403.745192)
		(mid 151.982172 -403.552455)
		(end 152.09139 -403.389084)
		(width 0.14224)
		(layer "In4.Cu")
		(net "P5E_CPU1_P2_TX_BUF_DN<12>")
	)
	(arc
		(start 161.901378 -390.153652)
		(mid 161.891676 -390.104968)
		(end 161.86404 -390.063736)
		(width 0.14224)
		(layer "In4.Cu")
		(net "P5E_CPU1_P2_TX_BUF_DN<12>")
	)
	(arc
		(start 161.716466 -389.916416)
		(mid 161.595431 -389.735464)
		(end 161.55289 -389.521954)
		(width 0.14224)
		(layer "In4.Cu")
		(net "P5E_CPU1_P2_TX_BUF_DN<12>")
	)
	(segment
		(start 148.564346 -408.250644)
		(end 148.860256 -407.954734)
		(width 0.12954)
		(layer "F.Cu")
		(net "P5E_CPU1_P2_TX_BUF_DN<11>")
	)
	(segment
		(start 160.098232 -388.774432)
		(end 160.618932 -388.774432)
		(width 0.127)
		(layer "F.Cu")
		(net "P5E_CPU1_P2_TX_BUF_DN<11>")
	)
	(segment
		(start 148.860256 -407.954734)
		(end 148.860256 -404.73503)
		(width 0.12954)
		(layer "F.Cu")
		(net "P5E_CPU1_P2_TX_BUF_DN<11>")
	)
	(segment
		(start 148.860256 -404.73503)
		(end 148.589746 -404.46452)
		(width 0.12954)
		(layer "F.Cu")
		(net "P5E_CPU1_P2_TX_BUF_DN<11>")
	)
	(segment
		(start 159.948372 -391.667492)
		(end 159.948372 -395.196822)
		(width 0.14224)
		(layer "In4.Cu")
		(net "P5E_CPU1_P2_TX_BUF_DN<11>")
	)
	(segment
		(start 159.64408 -395.931136)
		(end 155.490164 -400.085052)
		(width 0.14224)
		(layer "In4.Cu")
		(net "P5E_CPU1_P2_TX_BUF_DN<11>")
	)
	(segment
		(start 160.618932 -388.774432)
		(end 160.671256 -388.826756)
		(width 0.14224)
		(layer "In4.Cu")
		(net "P5E_CPU1_P2_TX_BUF_DN<11>")
	)
	(segment
		(start 160.671256 -388.826756)
		(end 160.671256 -389.006588)
		(width 0.14224)
		(layer "In4.Cu")
		(net "P5E_CPU1_P2_TX_BUF_DN<11>")
	)
	(segment
		(start 160.671256 -389.006588)
		(end 160.35274 -389.325104)
		(width 0.14224)
		(layer "In4.Cu")
		(net "P5E_CPU1_P2_TX_BUF_DN<11>")
	)
	(segment
		(start 160.507172 -389.917432)
		(end 160.676082 -390.086342)
		(width 0.14224)
		(layer "In4.Cu")
		(net "P5E_CPU1_P2_TX_BUF_DN<11>")
	)
	(segment
		(start 160.71342 -390.176512)
		(end 160.71342 -390.430004)
		(width 0.14224)
		(layer "In4.Cu")
		(net "P5E_CPU1_P2_TX_BUF_DN<11>")
	)
	(segment
		(start 148.880576 -404.17369)
		(end 148.589746 -404.46452)
		(width 0.14224)
		(layer "In4.Cu")
		(net "P5E_CPU1_P2_TX_BUF_DN<11>")
	)
	(segment
		(start 149.21865 -403.219412)
		(end 149.088856 -403.349206)
		(width 0.14224)
		(layer "In4.Cu")
		(net "P5E_CPU1_P2_TX_BUF_DN<11>")
	)
	(segment
		(start 160.509204 -390.922764)
		(end 160.078166 -391.353802)
		(width 0.14224)
		(layer "In4.Cu")
		(net "P5E_CPU1_P2_TX_BUF_DN<11>")
	)
	(segment
		(start 148.880576 -403.851872)
		(end 148.880576 -404.17369)
		(width 0.14224)
		(layer "In4.Cu")
		(net "P5E_CPU1_P2_TX_BUF_DN<11>")
	)
	(segment
		(start 160.35274 -389.325104)
		(end 160.35274 -389.544814)
		(width 0.14224)
		(layer "In4.Cu")
		(net "P5E_CPU1_P2_TX_BUF_DN<11>")
	)
	(segment
		(start 153.376122 -401.497546)
		(end 149.21865 -403.219412)
		(width 0.14224)
		(layer "In4.Cu")
		(net "P5E_CPU1_P2_TX_BUF_DN<11>")
	)
	(arc
		(start 149.088856 -403.349206)
		(mid 148.934704 -403.579817)
		(end 148.880576 -403.851872)
		(width 0.14224)
		(layer "In4.Cu")
		(net "P5E_CPU1_P2_TX_BUF_DN<11>")
	)
	(arc
		(start 160.71342 -390.430004)
		(mid 160.660351 -390.696711)
		(end 160.509204 -390.922764)
		(width 0.14224)
		(layer "In4.Cu")
		(net "P5E_CPU1_P2_TX_BUF_DN<11>")
	)
	(arc
		(start 160.676082 -390.086342)
		(mid 160.703725 -390.127712)
		(end 160.71342 -390.176512)
		(width 0.14224)
		(layer "In4.Cu")
		(net "P5E_CPU1_P2_TX_BUF_DN<11>")
	)
	(arc
		(start 160.35274 -389.544814)
		(mid 160.392874 -389.746493)
		(end 160.507172 -389.917432)
		(width 0.14224)
		(layer "In4.Cu")
		(net "P5E_CPU1_P2_TX_BUF_DN<11>")
	)
	(arc
		(start 155.490164 -400.085052)
		(mid 154.502724 -400.895442)
		(end 153.376122 -401.497546)
		(width 0.14224)
		(layer "In4.Cu")
		(net "P5E_CPU1_P2_TX_BUF_DN<11>")
	)
	(arc
		(start 159.948372 -395.196822)
		(mid 159.869283 -395.594251)
		(end 159.64408 -395.931136)
		(width 0.14224)
		(layer "In4.Cu")
		(net "P5E_CPU1_P2_TX_BUF_DN<11>")
	)
	(arc
		(start 160.078166 -391.353802)
		(mid 159.98203 -391.497725)
		(end 159.948372 -391.667492)
		(width 0.14224)
		(layer "In4.Cu")
		(net "P5E_CPU1_P2_TX_BUF_DN<11>")
	)
	(segment
		(start 145.797016 -407.954734)
		(end 145.797016 -404.73503)
		(width 0.12954)
		(layer "F.Cu")
		(net "P5E_CPU1_P2_TX_BUF_DN<10>")
	)
	(segment
		(start 145.797016 -404.73503)
		(end 145.526506 -404.46452)
		(width 0.12954)
		(layer "F.Cu")
		(net "P5E_CPU1_P2_TX_BUF_DN<10>")
	)
	(segment
		(start 158.898336 -388.774432)
		(end 159.419036 -388.774432)
		(width 0.127)
		(layer "F.Cu")
		(net "P5E_CPU1_P2_TX_BUF_DN<10>")
	)
	(segment
		(start 145.501106 -408.250644)
		(end 145.797016 -407.954734)
		(width 0.12954)
		(layer "F.Cu")
		(net "P5E_CPU1_P2_TX_BUF_DN<10>")
	)
	(segment
		(start 158.645098 -395.552676)
		(end 154.820112 -399.377662)
		(width 0.14224)
		(layer "In4.Cu")
		(net "P5E_CPU1_P2_TX_BUF_DN<10>")
	)
	(segment
		(start 145.817336 -403.7838)
		(end 145.817336 -404.17369)
		(width 0.14224)
		(layer "In4.Cu")
		(net "P5E_CPU1_P2_TX_BUF_DN<10>")
	)
	(segment
		(start 159.301688 -390.931908)
		(end 158.81223 -391.421366)
		(width 0.14224)
		(layer "In4.Cu")
		(net "P5E_CPU1_P2_TX_BUF_DN<10>")
	)
	(segment
		(start 159.47136 -388.826756)
		(end 159.47136 -389.006588)
		(width 0.14224)
		(layer "In4.Cu")
		(net "P5E_CPU1_P2_TX_BUF_DN<10>")
	)
	(segment
		(start 146.273266 -403.101556)
		(end 145.977356 -403.397466)
		(width 0.14224)
		(layer "In4.Cu")
		(net "P5E_CPU1_P2_TX_BUF_DN<10>")
	)
	(segment
		(start 159.513524 -390.176258)
		(end 159.513524 -390.420606)
		(width 0.14224)
		(layer "In4.Cu")
		(net "P5E_CPU1_P2_TX_BUF_DN<10>")
	)
	(segment
		(start 152.80259 -400.72564)
		(end 149.235414 -402.203158)
		(width 0.14224)
		(layer "In4.Cu")
		(net "P5E_CPU1_P2_TX_BUF_DN<10>")
	)
	(segment
		(start 159.272732 -389.880856)
		(end 159.474916 -390.08304)
		(width 0.14224)
		(layer "In4.Cu")
		(net "P5E_CPU1_P2_TX_BUF_DN<10>")
	)
	(segment
		(start 158.682436 -391.735056)
		(end 158.682436 -395.46276)
		(width 0.14224)
		(layer "In4.Cu")
		(net "P5E_CPU1_P2_TX_BUF_DN<10>")
	)
	(segment
		(start 159.152844 -389.325104)
		(end 159.152844 -389.59155)
		(width 0.14224)
		(layer "In4.Cu")
		(net "P5E_CPU1_P2_TX_BUF_DN<10>")
	)
	(segment
		(start 159.47136 -389.006588)
		(end 159.152844 -389.325104)
		(width 0.14224)
		(layer "In4.Cu")
		(net "P5E_CPU1_P2_TX_BUF_DN<10>")
	)
	(segment
		(start 145.817336 -404.17369)
		(end 145.526506 -404.46452)
		(width 0.14224)
		(layer "In4.Cu")
		(net "P5E_CPU1_P2_TX_BUF_DN<10>")
	)
	(segment
		(start 159.419036 -388.774432)
		(end 159.47136 -388.826756)
		(width 0.14224)
		(layer "In4.Cu")
		(net "P5E_CPU1_P2_TX_BUF_DN<10>")
	)
	(segment
		(start 149.235414 -402.203158)
		(end 146.273266 -403.101556)
		(width 0.14224)
		(layer "In4.Cu")
		(net "P5E_CPU1_P2_TX_BUF_DN<10>")
	)
	(arc
		(start 159.513524 -390.420606)
		(mid 159.458463 -390.697325)
		(end 159.301688 -390.931908)
		(width 0.14224)
		(layer "In4.Cu")
		(net "P5E_CPU1_P2_TX_BUF_DN<10>")
	)
	(arc
		(start 158.81223 -391.421366)
		(mid 158.716094 -391.565289)
		(end 158.682436 -391.735056)
		(width 0.14224)
		(layer "In4.Cu")
		(net "P5E_CPU1_P2_TX_BUF_DN<10>")
	)
	(arc
		(start 159.152844 -389.59155)
		(mid 159.184007 -389.748128)
		(end 159.272732 -389.880856)
		(width 0.14224)
		(layer "In4.Cu")
		(net "P5E_CPU1_P2_TX_BUF_DN<10>")
	)
	(arc
		(start 158.682436 -395.46276)
		(mid 158.672734 -395.511444)
		(end 158.645098 -395.552676)
		(width 0.14224)
		(layer "In4.Cu")
		(net "P5E_CPU1_P2_TX_BUF_DN<10>")
	)
	(arc
		(start 159.474916 -390.08304)
		(mid 159.503493 -390.125809)
		(end 159.513524 -390.176258)
		(width 0.14224)
		(layer "In4.Cu")
		(net "P5E_CPU1_P2_TX_BUF_DN<10>")
	)
	(arc
		(start 145.977356 -403.397466)
		(mid 145.85892 -403.574718)
		(end 145.817336 -403.7838)
		(width 0.14224)
		(layer "In4.Cu")
		(net "P5E_CPU1_P2_TX_BUF_DN<10>")
	)
	(arc
		(start 154.820112 -399.377662)
		(mid 153.877732 -400.151003)
		(end 152.80259 -400.72564)
		(width 0.14224)
		(layer "In4.Cu")
		(net "P5E_CPU1_P2_TX_BUF_DN<10>")
	)
	(segment
		(start 146.89836 -388.774432)
		(end 147.41906 -388.774432)
		(width 0.127)
		(layer "F.Cu")
		(net "P5E_CPU1_P2_TX_BUF_DN<0>")
	)
	(segment
		(start 115.164616 -407.954734)
		(end 115.164616 -404.73503)
		(width 0.12954)
		(layer "F.Cu")
		(net "P5E_CPU1_P2_TX_BUF_DN<0>")
	)
	(segment
		(start 114.868706 -408.250644)
		(end 115.164616 -407.954734)
		(width 0.12954)
		(layer "F.Cu")
		(net "P5E_CPU1_P2_TX_BUF_DN<0>")
	)
	(segment
		(start 115.164616 -404.73503)
		(end 114.894106 -404.46452)
		(width 0.12954)
		(layer "F.Cu")
		(net "P5E_CPU1_P2_TX_BUF_DN<0>")
	)
	(segment
		(start 147.464526 -388.819898)
		(end 147.464526 -388.999984)
		(width 0.14224)
		(layer "In4.Cu")
		(net "P5E_CPU1_P2_TX_BUF_DN<0>")
	)
	(segment
		(start 126.221998 -398.743678)
		(end 115.684808 -403.107906)
		(width 0.14224)
		(layer "In4.Cu")
		(net "P5E_CPU1_P2_TX_BUF_DN<0>")
	)
	(segment
		(start 146.122644 -389.967724)
		(end 145.224754 -392.135868)
		(width 0.14224)
		(layer "In4.Cu")
		(net "P5E_CPU1_P2_TX_BUF_DN<0>")
	)
	(segment
		(start 147.41906 -388.774432)
		(end 147.464526 -388.819898)
		(width 0.14224)
		(layer "In4.Cu")
		(net "P5E_CPU1_P2_TX_BUF_DN<0>")
	)
	(segment
		(start 147.464526 -388.999984)
		(end 147.125944 -389.338566)
		(width 0.14224)
		(layer "In4.Cu")
		(net "P5E_CPU1_P2_TX_BUF_DN<0>")
	)
	(segment
		(start 146.56054 -389.529828)
		(end 146.122644 -389.967724)
		(width 0.14224)
		(layer "In4.Cu")
		(net "P5E_CPU1_P2_TX_BUF_DN<0>")
	)
	(segment
		(start 146.966432 -389.404606)
		(end 146.863054 -389.404606)
		(width 0.14224)
		(layer "In4.Cu")
		(net "P5E_CPU1_P2_TX_BUF_DN<0>")
	)
	(segment
		(start 143.831056 -393.934696)
		(end 128.64719 -398.540732)
		(width 0.14224)
		(layer "In4.Cu")
		(net "P5E_CPU1_P2_TX_BUF_DN<0>")
	)
	(segment
		(start 128.362456 -398.58315)
		(end 127.029718 -398.58315)
		(width 0.14224)
		(layer "In4.Cu")
		(net "P5E_CPU1_P2_TX_BUF_DN<0>")
	)
	(segment
		(start 145.14068 -392.823192)
		(end 144.325086 -393.638786)
		(width 0.14224)
		(layer "In4.Cu")
		(net "P5E_CPU1_P2_TX_BUF_DN<0>")
	)
	(segment
		(start 115.48872 -403.23897)
		(end 115.395248 -403.332442)
		(width 0.14224)
		(layer "In4.Cu")
		(net "P5E_CPU1_P2_TX_BUF_DN<0>")
	)
	(segment
		(start 115.184936 -404.17369)
		(end 114.894106 -404.46452)
		(width 0.14224)
		(layer "In4.Cu")
		(net "P5E_CPU1_P2_TX_BUF_DN<0>")
	)
	(segment
		(start 115.184936 -403.839934)
		(end 115.184936 -404.17369)
		(width 0.14224)
		(layer "In4.Cu")
		(net "P5E_CPU1_P2_TX_BUF_DN<0>")
	)
	(segment
		(start 145.224754 -392.135868)
		(end 145.224754 -392.6205)
		(width 0.14224)
		(layer "In4.Cu")
		(net "P5E_CPU1_P2_TX_BUF_DN<0>")
	)
	(arc
		(start 146.863054 -389.404606)
		(mid 146.699352 -389.43715)
		(end 146.56054 -389.529828)
		(width 0.14224)
		(layer "In4.Cu")
		(net "P5E_CPU1_P2_TX_BUF_DN<0>")
	)
	(arc
		(start 127.029718 -398.58315)
		(mid 126.617946 -398.623614)
		(end 126.221998 -398.743678)
		(width 0.14224)
		(layer "In4.Cu")
		(net "P5E_CPU1_P2_TX_BUF_DN<0>")
	)
	(arc
		(start 144.325086 -393.638786)
		(mid 144.096322 -393.817217)
		(end 143.831056 -393.934696)
		(width 0.14224)
		(layer "In4.Cu")
		(net "P5E_CPU1_P2_TX_BUF_DN<0>")
	)
	(arc
		(start 115.395248 -403.332442)
		(mid 115.239616 -403.565267)
		(end 115.184936 -403.839934)
		(width 0.14224)
		(layer "In4.Cu")
		(net "P5E_CPU1_P2_TX_BUF_DN<0>")
	)
	(arc
		(start 147.125944 -389.338566)
		(mid 147.052759 -389.387466)
		(end 146.966432 -389.404606)
		(width 0.14224)
		(layer "In4.Cu")
		(net "P5E_CPU1_P2_TX_BUF_DN<0>")
	)
	(arc
		(start 145.224754 -392.6205)
		(mid 145.202842 -392.730187)
		(end 145.14068 -392.823192)
		(width 0.14224)
		(layer "In4.Cu")
		(net "P5E_CPU1_P2_TX_BUF_DN<0>")
	)
	(arc
		(start 128.64719 -398.540732)
		(mid 128.50639 -398.572469)
		(end 128.362456 -398.58315)
		(width 0.14224)
		(layer "In4.Cu")
		(net "P5E_CPU1_P2_TX_BUF_DN<0>")
	)
	(arc
		(start 115.684808 -403.107906)
		(mid 115.580314 -403.163788)
		(end 115.48872 -403.23897)
		(width 0.14224)
		(layer "In4.Cu")
		(net "P5E_CPU1_P2_TX_BUF_DN<0>")
	)
	(segment
		(start 143.352266 -408.784044)
		(end 143.056356 -409.079954)
		(width 0.12954)
		(layer "F.Cu")
		(net "P5E_CPU1_P2_TX_BUF_C_DP<9>")
	)
	(segment
		(start 143.056356 -412.299658)
		(end 143.326866 -412.570168)
		(width 0.12954)
		(layer "F.Cu")
		(net "P5E_CPU1_P2_TX_BUF_C_DP<9>")
	)
	(segment
		(start 143.056356 -409.079954)
		(end 143.056356 -412.299658)
		(width 0.12954)
		(layer "F.Cu")
		(net "P5E_CPU1_P2_TX_BUF_C_DP<9>")
	)
	(segment
		(start 143.036036 -414.776666)
		(end 143.036036 -412.860998)
		(width 0.14224)
		(layer "In11.Cu")
		(net "P5E_CPU1_P2_TX_BUF_C_DP<9>")
	)
	(segment
		(start 144.217898 -431.148744)
		(end 144.07007 -431.000916)
		(width 0.14224)
		(layer "In11.Cu")
		(net "P5E_CPU1_P2_TX_BUF_C_DP<9>")
	)
	(segment
		(start 143.385286 -416.920172)
		(end 143.343376 -416.49523)
		(width 0.14224)
		(layer "In11.Cu")
		(net "P5E_CPU1_P2_TX_BUF_C_DP<9>")
	)
	(segment
		(start 143.14678 -415.899092)
		(end 143.269716 -415.749232)
		(width 0.14224)
		(layer "In11.Cu")
		(net "P5E_CPU1_P2_TX_BUF_C_DP<9>")
	)
	(segment
		(start 143.036036 -412.860998)
		(end 143.326866 -412.570168)
		(width 0.14224)
		(layer "In11.Cu")
		(net "P5E_CPU1_P2_TX_BUF_C_DP<9>")
	)
	(segment
		(start 144.622774 -431.148744)
		(end 144.217898 -431.148744)
		(width 0.14224)
		(layer "In11.Cu")
		(net "P5E_CPU1_P2_TX_BUF_C_DP<9>")
	)
	(segment
		(start 144.07007 -425.276264)
		(end 143.262096 -417.070032)
		(width 0.14224)
		(layer "In11.Cu")
		(net "P5E_CPU1_P2_TX_BUF_C_DP<9>")
	)
	(segment
		(start 144.750028 -430.689766)
		(end 144.750028 -431.02149)
		(width 0.14224)
		(layer "In11.Cu")
		(net "P5E_CPU1_P2_TX_BUF_C_DP<9>")
	)
	(segment
		(start 144.750028 -431.02149)
		(end 144.622774 -431.148744)
		(width 0.14224)
		(layer "In11.Cu")
		(net "P5E_CPU1_P2_TX_BUF_C_DP<9>")
	)
	(segment
		(start 144.07007 -431.000916)
		(end 144.07007 -425.276264)
		(width 0.14224)
		(layer "In11.Cu")
		(net "P5E_CPU1_P2_TX_BUF_C_DP<9>")
	)
	(segment
		(start 143.343376 -416.49523)
		(end 143.193262 -416.372294)
		(width 0.14224)
		(layer "In11.Cu")
		(net "P5E_CPU1_P2_TX_BUF_C_DP<9>")
	)
	(segment
		(start 143.262096 -417.070032)
		(end 143.385286 -416.920172)
		(width 0.14224)
		(layer "In11.Cu")
		(net "P5E_CPU1_P2_TX_BUF_C_DP<9>")
	)
	(segment
		(start 143.193262 -416.372294)
		(end 143.14678 -415.899092)
		(width 0.14224)
		(layer "In11.Cu")
		(net "P5E_CPU1_P2_TX_BUF_C_DP<9>")
	)
	(segment
		(start 143.269716 -415.749232)
		(end 143.22806 -415.32429)
		(width 0.14224)
		(layer "In11.Cu")
		(net "P5E_CPU1_P2_TX_BUF_C_DP<9>")
	)
	(segment
		(start 143.22806 -415.32429)
		(end 143.077692 -415.2011)
		(width 0.14224)
		(layer "In11.Cu")
		(net "P5E_CPU1_P2_TX_BUF_C_DP<9>")
	)
	(segment
		(start 143.077692 -415.2011)
		(end 143.036036 -414.776666)
		(width 0.14224)
		(layer "In11.Cu")
		(net "P5E_CPU1_P2_TX_BUF_C_DP<9>")
	)
	(segment
		(start 140.289026 -408.784044)
		(end 139.993116 -409.079954)
		(width 0.12954)
		(layer "F.Cu")
		(net "P5E_CPU1_P2_TX_BUF_C_DP<8>")
	)
	(segment
		(start 139.993116 -412.299658)
		(end 140.263626 -412.570168)
		(width 0.12954)
		(layer "F.Cu")
		(net "P5E_CPU1_P2_TX_BUF_C_DP<8>")
	)
	(segment
		(start 139.993116 -409.079954)
		(end 139.993116 -412.299658)
		(width 0.12954)
		(layer "F.Cu")
		(net "P5E_CPU1_P2_TX_BUF_C_DP<8>")
	)
	(segment
		(start 142.623032 -430.125632)
		(end 142.750032 -429.998632)
		(width 0.14224)
		(layer "In11.Cu")
		(net "P5E_CPU1_P2_TX_BUF_C_DP<8>")
	)
	(segment
		(start 141.572234 -429.99406)
		(end 141.717522 -430.125632)
		(width 0.14224)
		(layer "In11.Cu")
		(net "P5E_CPU1_P2_TX_BUF_C_DP<8>")
	)
	(segment
		(start 140.551662 -418.229796)
		(end 140.428726 -418.379656)
		(width 0.14224)
		(layer "In11.Cu")
		(net "P5E_CPU1_P2_TX_BUF_C_DP<8>")
	)
	(segment
		(start 140.375386 -416.439096)
		(end 140.417296 -416.864038)
		(width 0.14224)
		(layer "In11.Cu")
		(net "P5E_CPU1_P2_TX_BUF_C_DP<8>")
	)
	(segment
		(start 141.717522 -430.125632)
		(end 142.623032 -430.125632)
		(width 0.14224)
		(layer "In11.Cu")
		(net "P5E_CPU1_P2_TX_BUF_C_DP<8>")
	)
	(segment
		(start 140.428726 -418.379656)
		(end 140.487908 -418.98062)
		(width 0.14224)
		(layer "In11.Cu")
		(net "P5E_CPU1_P2_TX_BUF_C_DP<8>")
	)
	(segment
		(start 140.225272 -416.315906)
		(end 140.375386 -416.439096)
		(width 0.14224)
		(layer "In11.Cu")
		(net "P5E_CPU1_P2_TX_BUF_C_DP<8>")
	)
	(segment
		(start 140.638022 -419.10381)
		(end 140.679678 -419.528752)
		(width 0.14224)
		(layer "In11.Cu")
		(net "P5E_CPU1_P2_TX_BUF_C_DP<8>")
	)
	(segment
		(start 139.972796 -413.746696)
		(end 140.045186 -414.483804)
		(width 0.14224)
		(layer "In11.Cu")
		(net "P5E_CPU1_P2_TX_BUF_C_DP<8>")
	)
	(segment
		(start 140.11402 -415.181796)
		(end 140.225272 -416.315906)
		(width 0.14224)
		(layer "In11.Cu")
		(net "P5E_CPU1_P2_TX_BUF_C_DP<8>")
	)
	(segment
		(start 142.750032 -429.998632)
		(end 142.750032 -429.689768)
		(width 0.14224)
		(layer "In11.Cu")
		(net "P5E_CPU1_P2_TX_BUF_C_DP<8>")
	)
	(segment
		(start 140.1953 -414.606994)
		(end 140.236956 -415.031682)
		(width 0.14224)
		(layer "In11.Cu")
		(net "P5E_CPU1_P2_TX_BUF_C_DP<8>")
	)
	(segment
		(start 140.263626 -412.570168)
		(end 139.972796 -412.860998)
		(width 0.14224)
		(layer "In11.Cu")
		(net "P5E_CPU1_P2_TX_BUF_C_DP<8>")
	)
	(segment
		(start 140.045186 -414.483804)
		(end 140.1953 -414.606994)
		(width 0.14224)
		(layer "In11.Cu")
		(net "P5E_CPU1_P2_TX_BUF_C_DP<8>")
	)
	(segment
		(start 140.417296 -416.864038)
		(end 140.294106 -417.013898)
		(width 0.14224)
		(layer "In11.Cu")
		(net "P5E_CPU1_P2_TX_BUF_C_DP<8>")
	)
	(segment
		(start 140.359638 -417.681918)
		(end 140.510006 -417.804854)
		(width 0.14224)
		(layer "In11.Cu")
		(net "P5E_CPU1_P2_TX_BUF_C_DP<8>")
	)
	(segment
		(start 140.487908 -418.98062)
		(end 140.638022 -419.10381)
		(width 0.14224)
		(layer "In11.Cu")
		(net "P5E_CPU1_P2_TX_BUF_C_DP<8>")
	)
	(segment
		(start 140.510006 -417.804854)
		(end 140.551662 -418.229796)
		(width 0.14224)
		(layer "In11.Cu")
		(net "P5E_CPU1_P2_TX_BUF_C_DP<8>")
	)
	(segment
		(start 140.679678 -419.528752)
		(end 140.556742 -419.678612)
		(width 0.14224)
		(layer "In11.Cu")
		(net "P5E_CPU1_P2_TX_BUF_C_DP<8>")
	)
	(segment
		(start 140.294106 -417.013898)
		(end 140.359638 -417.681918)
		(width 0.14224)
		(layer "In11.Cu")
		(net "P5E_CPU1_P2_TX_BUF_C_DP<8>")
	)
	(segment
		(start 140.236956 -415.031682)
		(end 140.11402 -415.181796)
		(width 0.14224)
		(layer "In11.Cu")
		(net "P5E_CPU1_P2_TX_BUF_C_DP<8>")
	)
	(segment
		(start 139.972796 -412.860998)
		(end 139.972796 -413.746696)
		(width 0.14224)
		(layer "In11.Cu")
		(net "P5E_CPU1_P2_TX_BUF_C_DP<8>")
	)
	(segment
		(start 140.556742 -419.678612)
		(end 141.572234 -429.99406)
		(width 0.14224)
		(layer "In11.Cu")
		(net "P5E_CPU1_P2_TX_BUF_C_DP<8>")
	)
	(segment
		(start 136.929876 -412.299658)
		(end 137.200386 -412.570168)
		(width 0.12954)
		(layer "F.Cu")
		(net "P5E_CPU1_P2_TX_BUF_C_DP<7>")
	)
	(segment
		(start 137.225786 -408.784044)
		(end 136.929876 -409.079954)
		(width 0.12954)
		(layer "F.Cu")
		(net "P5E_CPU1_P2_TX_BUF_C_DP<7>")
	)
	(segment
		(start 136.929876 -409.079954)
		(end 136.929876 -412.299658)
		(width 0.12954)
		(layer "F.Cu")
		(net "P5E_CPU1_P2_TX_BUF_C_DP<7>")
	)
	(segment
		(start 139.749784 -430.689766)
		(end 139.749784 -431.02149)
		(width 0.14224)
		(layer "In11.Cu")
		(net "P5E_CPU1_P2_TX_BUF_C_DP<7>")
	)
	(segment
		(start 137.394188 -415.303716)
		(end 137.234168 -415.194242)
		(width 0.14224)
		(layer "In11.Cu")
		(net "P5E_CPU1_P2_TX_BUF_C_DP<7>")
	)
	(segment
		(start 139.749784 -431.02149)
		(end 139.62253 -431.148744)
		(width 0.14224)
		(layer "In11.Cu")
		(net "P5E_CPU1_P2_TX_BUF_C_DP<7>")
	)
	(segment
		(start 137.47242 -415.723578)
		(end 137.394188 -415.303716)
		(width 0.14224)
		(layer "In11.Cu")
		(net "P5E_CPU1_P2_TX_BUF_C_DP<7>")
	)
	(segment
		(start 137.644378 -416.645344)
		(end 137.484104 -416.535616)
		(width 0.14224)
		(layer "In11.Cu")
		(net "P5E_CPU1_P2_TX_BUF_C_DP<7>")
	)
	(segment
		(start 136.909556 -413.452056)
		(end 136.909556 -412.860998)
		(width 0.14224)
		(layer "In11.Cu")
		(net "P5E_CPU1_P2_TX_BUF_C_DP<7>")
	)
	(segment
		(start 136.909556 -412.860998)
		(end 137.200386 -412.570168)
		(width 0.14224)
		(layer "In11.Cu")
		(net "P5E_CPU1_P2_TX_BUF_C_DP<7>")
	)
	(segment
		(start 137.234168 -415.194242)
		(end 136.909556 -413.452056)
		(width 0.14224)
		(layer "In11.Cu")
		(net "P5E_CPU1_P2_TX_BUF_C_DP<7>")
	)
	(segment
		(start 139.62253 -431.148744)
		(end 139.217654 -431.148744)
		(width 0.14224)
		(layer "In11.Cu")
		(net "P5E_CPU1_P2_TX_BUF_C_DP<7>")
	)
	(segment
		(start 139.217654 -431.148744)
		(end 139.069826 -431.000916)
		(width 0.14224)
		(layer "In11.Cu")
		(net "P5E_CPU1_P2_TX_BUF_C_DP<7>")
	)
	(segment
		(start 139.069826 -425.045632)
		(end 137.612628 -417.224972)
		(width 0.14224)
		(layer "In11.Cu")
		(net "P5E_CPU1_P2_TX_BUF_C_DP<7>")
	)
	(segment
		(start 137.484104 -416.535616)
		(end 137.362692 -415.883598)
		(width 0.14224)
		(layer "In11.Cu")
		(net "P5E_CPU1_P2_TX_BUF_C_DP<7>")
	)
	(segment
		(start 139.069826 -431.000916)
		(end 139.069826 -425.045632)
		(width 0.14224)
		(layer "In11.Cu")
		(net "P5E_CPU1_P2_TX_BUF_C_DP<7>")
	)
	(segment
		(start 137.612628 -417.224972)
		(end 137.722356 -417.064952)
		(width 0.14224)
		(layer "In11.Cu")
		(net "P5E_CPU1_P2_TX_BUF_C_DP<7>")
	)
	(segment
		(start 137.722356 -417.064952)
		(end 137.644378 -416.645344)
		(width 0.14224)
		(layer "In11.Cu")
		(net "P5E_CPU1_P2_TX_BUF_C_DP<7>")
	)
	(segment
		(start 137.362692 -415.883598)
		(end 137.47242 -415.723578)
		(width 0.14224)
		(layer "In11.Cu")
		(net "P5E_CPU1_P2_TX_BUF_C_DP<7>")
	)
	(segment
		(start 134.162546 -408.784044)
		(end 133.866636 -409.079954)
		(width 0.12954)
		(layer "F.Cu")
		(net "P5E_CPU1_P2_TX_BUF_C_DP<6>")
	)
	(segment
		(start 133.866636 -409.079954)
		(end 133.866636 -412.299658)
		(width 0.12954)
		(layer "F.Cu")
		(net "P5E_CPU1_P2_TX_BUF_C_DP<6>")
	)
	(segment
		(start 133.866636 -412.299658)
		(end 134.137146 -412.570168)
		(width 0.12954)
		(layer "F.Cu")
		(net "P5E_CPU1_P2_TX_BUF_C_DP<6>")
	)
	(segment
		(start 135.342376 -419.349682)
		(end 135.67029 -420.659052)
		(width 0.14224)
		(layer "In11.Cu")
		(net "P5E_CPU1_P2_TX_BUF_C_DP<6>")
	)
	(segment
		(start 135.122666 -417.908486)
		(end 135.023098 -418.074856)
		(width 0.14224)
		(layer "In11.Cu")
		(net "P5E_CPU1_P2_TX_BUF_C_DP<6>")
	)
	(segment
		(start 137.280142 -430.125632)
		(end 137.622788 -430.125632)
		(width 0.14224)
		(layer "In11.Cu")
		(net "P5E_CPU1_P2_TX_BUF_C_DP<6>")
	)
	(segment
		(start 134.582662 -416.317176)
		(end 134.85241 -417.394644)
		(width 0.14224)
		(layer "In11.Cu")
		(net "P5E_CPU1_P2_TX_BUF_C_DP<6>")
	)
	(segment
		(start 134.578852 -415.736786)
		(end 134.682484 -416.150806)
		(width 0.14224)
		(layer "In11.Cu")
		(net "P5E_CPU1_P2_TX_BUF_C_DP<6>")
	)
	(segment
		(start 135.019034 -417.494466)
		(end 135.122666 -417.908486)
		(width 0.14224)
		(layer "In11.Cu")
		(net "P5E_CPU1_P2_TX_BUF_C_DP<6>")
	)
	(segment
		(start 133.846316 -413.377888)
		(end 134.412228 -415.636964)
		(width 0.14224)
		(layer "In11.Cu")
		(net "P5E_CPU1_P2_TX_BUF_C_DP<6>")
	)
	(segment
		(start 134.682484 -416.150806)
		(end 134.582662 -416.317176)
		(width 0.14224)
		(layer "In11.Cu")
		(net "P5E_CPU1_P2_TX_BUF_C_DP<6>")
	)
	(segment
		(start 133.846316 -412.860998)
		(end 133.846316 -413.377888)
		(width 0.14224)
		(layer "In11.Cu")
		(net "P5E_CPU1_P2_TX_BUF_C_DP<6>")
	)
	(segment
		(start 137.749788 -429.998632)
		(end 137.749788 -429.689768)
		(width 0.14224)
		(layer "In11.Cu")
		(net "P5E_CPU1_P2_TX_BUF_C_DP<6>")
	)
	(segment
		(start 137.06983 -429.91532)
		(end 137.280142 -430.125632)
		(width 0.14224)
		(layer "In11.Cu")
		(net "P5E_CPU1_P2_TX_BUF_C_DP<6>")
	)
	(segment
		(start 134.85241 -417.394644)
		(end 135.019034 -417.494466)
		(width 0.14224)
		(layer "In11.Cu")
		(net "P5E_CPU1_P2_TX_BUF_C_DP<6>")
	)
	(segment
		(start 137.622788 -430.125632)
		(end 137.749788 -429.998632)
		(width 0.14224)
		(layer "In11.Cu")
		(net "P5E_CPU1_P2_TX_BUF_C_DP<6>")
	)
	(segment
		(start 135.940546 -421.172894)
		(end 135.840724 -421.339264)
		(width 0.14224)
		(layer "In11.Cu")
		(net "P5E_CPU1_P2_TX_BUF_C_DP<6>")
	)
	(segment
		(start 135.171942 -418.66947)
		(end 135.338566 -418.769038)
		(width 0.14224)
		(layer "In11.Cu")
		(net "P5E_CPU1_P2_TX_BUF_C_DP<6>")
	)
	(segment
		(start 134.412228 -415.636964)
		(end 134.578852 -415.736786)
		(width 0.14224)
		(layer "In11.Cu")
		(net "P5E_CPU1_P2_TX_BUF_C_DP<6>")
	)
	(segment
		(start 135.67029 -420.659052)
		(end 135.836914 -420.75862)
		(width 0.14224)
		(layer "In11.Cu")
		(net "P5E_CPU1_P2_TX_BUF_C_DP<6>")
	)
	(segment
		(start 135.338566 -418.769038)
		(end 135.442198 -419.183312)
		(width 0.14224)
		(layer "In11.Cu")
		(net "P5E_CPU1_P2_TX_BUF_C_DP<6>")
	)
	(segment
		(start 135.840724 -421.339264)
		(end 137.06983 -426.246798)
		(width 0.14224)
		(layer "In11.Cu")
		(net "P5E_CPU1_P2_TX_BUF_C_DP<6>")
	)
	(segment
		(start 135.442198 -419.183312)
		(end 135.342376 -419.349682)
		(width 0.14224)
		(layer "In11.Cu")
		(net "P5E_CPU1_P2_TX_BUF_C_DP<6>")
	)
	(segment
		(start 134.137146 -412.570168)
		(end 133.846316 -412.860998)
		(width 0.14224)
		(layer "In11.Cu")
		(net "P5E_CPU1_P2_TX_BUF_C_DP<6>")
	)
	(segment
		(start 135.836914 -420.75862)
		(end 135.940546 -421.172894)
		(width 0.14224)
		(layer "In11.Cu")
		(net "P5E_CPU1_P2_TX_BUF_C_DP<6>")
	)
	(segment
		(start 137.06983 -426.246798)
		(end 137.06983 -429.91532)
		(width 0.14224)
		(layer "In11.Cu")
		(net "P5E_CPU1_P2_TX_BUF_C_DP<6>")
	)
	(segment
		(start 135.023098 -418.074856)
		(end 135.171942 -418.66947)
		(width 0.14224)
		(layer "In11.Cu")
		(net "P5E_CPU1_P2_TX_BUF_C_DP<6>")
	)
	(segment
		(start 130.803396 -412.299658)
		(end 131.073906 -412.570168)
		(width 0.12954)
		(layer "F.Cu")
		(net "P5E_CPU1_P2_TX_BUF_C_DP<5>")
	)
	(segment
		(start 131.099306 -408.784044)
		(end 130.803396 -409.079954)
		(width 0.12954)
		(layer "F.Cu")
		(net "P5E_CPU1_P2_TX_BUF_C_DP<5>")
	)
	(segment
		(start 130.803396 -409.079954)
		(end 130.803396 -412.299658)
		(width 0.12954)
		(layer "F.Cu")
		(net "P5E_CPU1_P2_TX_BUF_C_DP<5>")
	)
	(segment
		(start 131.073906 -412.570168)
		(end 130.830574 -412.8135)
		(width 0.14224)
		(layer "In11.Cu")
		(net "P5E_CPU1_P2_TX_BUF_C_DP<5>")
	)
	(segment
		(start 131.20497 -414.21558)
		(end 131.348734 -414.617662)
		(width 0.14224)
		(layer "In11.Cu")
		(net "P5E_CPU1_P2_TX_BUF_C_DP<5>")
	)
	(segment
		(start 131.645914 -415.854896)
		(end 131.854956 -416.439604)
		(width 0.14224)
		(layer "In11.Cu")
		(net "P5E_CPU1_P2_TX_BUF_C_DP<5>")
	)
	(segment
		(start 131.854956 -416.439604)
		(end 131.855464 -416.439858)
		(width 0.14224)
		(layer "In11.Cu")
		(net "P5E_CPU1_P2_TX_BUF_C_DP<5>")
	)
	(segment
		(start 135.622538 -431.148744)
		(end 135.749792 -431.02149)
		(width 0.14224)
		(layer "In11.Cu")
		(net "P5E_CPU1_P2_TX_BUF_C_DP<5>")
	)
	(segment
		(start 131.40944 -415.193734)
		(end 131.409694 -415.194496)
		(width 0.14224)
		(layer "In11.Cu")
		(net "P5E_CPU1_P2_TX_BUF_C_DP<5>")
	)
	(segment
		(start 135.217662 -431.148744)
		(end 135.622538 -431.148744)
		(width 0.14224)
		(layer "In11.Cu")
		(net "P5E_CPU1_P2_TX_BUF_C_DP<5>")
	)
	(segment
		(start 131.029456 -414.132522)
		(end 131.20497 -414.21558)
		(width 0.14224)
		(layer "In11.Cu")
		(net "P5E_CPU1_P2_TX_BUF_C_DP<5>")
	)
	(segment
		(start 131.348734 -414.617662)
		(end 131.26593 -414.792922)
		(width 0.14224)
		(layer "In11.Cu")
		(net "P5E_CPU1_P2_TX_BUF_C_DP<5>")
	)
	(segment
		(start 131.585208 -415.277554)
		(end 131.728972 -415.679636)
		(width 0.14224)
		(layer "In11.Cu")
		(net "P5E_CPU1_P2_TX_BUF_C_DP<5>")
	)
	(segment
		(start 130.783076 -413.443928)
		(end 131.029456 -414.132522)
		(width 0.14224)
		(layer "In11.Cu")
		(net "P5E_CPU1_P2_TX_BUF_C_DP<5>")
	)
	(segment
		(start 135.069834 -425.423584)
		(end 135.069834 -431.000916)
		(width 0.14224)
		(layer "In11.Cu")
		(net "P5E_CPU1_P2_TX_BUF_C_DP<5>")
	)
	(segment
		(start 131.855464 -416.439858)
		(end 135.069834 -425.423584)
		(width 0.14224)
		(layer "In11.Cu")
		(net "P5E_CPU1_P2_TX_BUF_C_DP<5>")
	)
	(segment
		(start 130.783076 -412.928054)
		(end 130.783076 -413.443928)
		(width 0.14224)
		(layer "In11.Cu")
		(net "P5E_CPU1_P2_TX_BUF_C_DP<5>")
	)
	(segment
		(start 131.409694 -415.194496)
		(end 131.585208 -415.277554)
		(width 0.14224)
		(layer "In11.Cu")
		(net "P5E_CPU1_P2_TX_BUF_C_DP<5>")
	)
	(segment
		(start 131.26593 -414.792922)
		(end 131.40944 -415.193734)
		(width 0.14224)
		(layer "In11.Cu")
		(net "P5E_CPU1_P2_TX_BUF_C_DP<5>")
	)
	(segment
		(start 135.749792 -431.02149)
		(end 135.749792 -430.689766)
		(width 0.14224)
		(layer "In11.Cu")
		(net "P5E_CPU1_P2_TX_BUF_C_DP<5>")
	)
	(segment
		(start 135.069834 -431.000916)
		(end 135.217662 -431.148744)
		(width 0.14224)
		(layer "In11.Cu")
		(net "P5E_CPU1_P2_TX_BUF_C_DP<5>")
	)
	(segment
		(start 131.728972 -415.679636)
		(end 131.645914 -415.854896)
		(width 0.14224)
		(layer "In11.Cu")
		(net "P5E_CPU1_P2_TX_BUF_C_DP<5>")
	)
	(arc
		(start 130.830574 -412.8135)
		(mid 130.795402 -412.866044)
		(end 130.783076 -412.928054)
		(width 0.14224)
		(layer "In11.Cu")
		(net "P5E_CPU1_P2_TX_BUF_C_DP<5>")
	)
	(segment
		(start 127.740156 -409.079954)
		(end 127.740156 -412.299658)
		(width 0.12954)
		(layer "F.Cu")
		(net "P5E_CPU1_P2_TX_BUF_C_DP<4>")
	)
	(segment
		(start 127.740156 -412.299658)
		(end 128.010666 -412.570168)
		(width 0.12954)
		(layer "F.Cu")
		(net "P5E_CPU1_P2_TX_BUF_C_DP<4>")
	)
	(segment
		(start 128.036066 -408.784044)
		(end 127.740156 -409.079954)
		(width 0.12954)
		(layer "F.Cu")
		(net "P5E_CPU1_P2_TX_BUF_C_DP<4>")
	)
	(segment
		(start 133.069838 -424.71594)
		(end 130.567938 -419.54958)
		(width 0.14224)
		(layer "In11.Cu")
		(net "P5E_CPU1_P2_TX_BUF_C_DP<4>")
	)
	(segment
		(start 130.567938 -419.54958)
		(end 130.631438 -419.366446)
		(width 0.14224)
		(layer "In11.Cu")
		(net "P5E_CPU1_P2_TX_BUF_C_DP<4>")
	)
	(segment
		(start 129.670556 -417.697412)
		(end 129.16662 -416.656774)
		(width 0.14224)
		(layer "In11.Cu")
		(net "P5E_CPU1_P2_TX_BUF_C_DP<4>")
	)
	(segment
		(start 130.631438 -419.366446)
		(end 130.44551 -418.982144)
		(width 0.14224)
		(layer "In11.Cu")
		(net "P5E_CPU1_P2_TX_BUF_C_DP<4>")
	)
	(segment
		(start 129.853944 -417.760912)
		(end 129.670556 -417.697412)
		(width 0.14224)
		(layer "In11.Cu")
		(net "P5E_CPU1_P2_TX_BUF_C_DP<4>")
	)
	(segment
		(start 133.749796 -429.998632)
		(end 133.622796 -430.125632)
		(width 0.14224)
		(layer "In11.Cu")
		(net "P5E_CPU1_P2_TX_BUF_C_DP<4>")
	)
	(segment
		(start 129.044192 -416.089338)
		(end 128.860804 -416.025584)
		(width 0.14224)
		(layer "In11.Cu")
		(net "P5E_CPU1_P2_TX_BUF_C_DP<4>")
	)
	(segment
		(start 133.28015 -430.125632)
		(end 133.069838 -429.91532)
		(width 0.14224)
		(layer "In11.Cu")
		(net "P5E_CPU1_P2_TX_BUF_C_DP<4>")
	)
	(segment
		(start 130.44551 -418.982144)
		(end 130.261868 -418.91839)
		(width 0.14224)
		(layer "In11.Cu")
		(net "P5E_CPU1_P2_TX_BUF_C_DP<4>")
	)
	(segment
		(start 128.557274 -415.398966)
		(end 128.621028 -415.215832)
		(width 0.14224)
		(layer "In11.Cu")
		(net "P5E_CPU1_P2_TX_BUF_C_DP<4>")
	)
	(segment
		(start 127.719836 -413.669988)
		(end 127.719836 -412.860998)
		(width 0.14224)
		(layer "In11.Cu")
		(net "P5E_CPU1_P2_TX_BUF_C_DP<4>")
	)
	(segment
		(start 133.069838 -429.91532)
		(end 133.069838 -424.71594)
		(width 0.14224)
		(layer "In11.Cu")
		(net "P5E_CPU1_P2_TX_BUF_C_DP<4>")
	)
	(segment
		(start 128.251458 -414.767776)
		(end 127.719836 -413.669988)
		(width 0.14224)
		(layer "In11.Cu")
		(net "P5E_CPU1_P2_TX_BUF_C_DP<4>")
	)
	(segment
		(start 130.261868 -418.91839)
		(end 129.976372 -418.328602)
		(width 0.14224)
		(layer "In11.Cu")
		(net "P5E_CPU1_P2_TX_BUF_C_DP<4>")
	)
	(segment
		(start 128.4351 -414.83153)
		(end 128.251458 -414.767776)
		(width 0.14224)
		(layer "In11.Cu")
		(net "P5E_CPU1_P2_TX_BUF_C_DP<4>")
	)
	(segment
		(start 127.719836 -412.860998)
		(end 128.010666 -412.570168)
		(width 0.14224)
		(layer "In11.Cu")
		(net "P5E_CPU1_P2_TX_BUF_C_DP<4>")
	)
	(segment
		(start 129.976372 -418.328602)
		(end 130.040126 -418.145214)
		(width 0.14224)
		(layer "In11.Cu")
		(net "P5E_CPU1_P2_TX_BUF_C_DP<4>")
	)
	(segment
		(start 129.16662 -416.656774)
		(end 129.23012 -416.47364)
		(width 0.14224)
		(layer "In11.Cu")
		(net "P5E_CPU1_P2_TX_BUF_C_DP<4>")
	)
	(segment
		(start 133.622796 -430.125632)
		(end 133.28015 -430.125632)
		(width 0.14224)
		(layer "In11.Cu")
		(net "P5E_CPU1_P2_TX_BUF_C_DP<4>")
	)
	(segment
		(start 129.23012 -416.47364)
		(end 129.044192 -416.089338)
		(width 0.14224)
		(layer "In11.Cu")
		(net "P5E_CPU1_P2_TX_BUF_C_DP<4>")
	)
	(segment
		(start 133.749796 -429.689768)
		(end 133.749796 -429.998632)
		(width 0.14224)
		(layer "In11.Cu")
		(net "P5E_CPU1_P2_TX_BUF_C_DP<4>")
	)
	(segment
		(start 130.040126 -418.145214)
		(end 129.853944 -417.760912)
		(width 0.14224)
		(layer "In11.Cu")
		(net "P5E_CPU1_P2_TX_BUF_C_DP<4>")
	)
	(segment
		(start 128.621028 -415.215832)
		(end 128.4351 -414.83153)
		(width 0.14224)
		(layer "In11.Cu")
		(net "P5E_CPU1_P2_TX_BUF_C_DP<4>")
	)
	(segment
		(start 128.860804 -416.025584)
		(end 128.557274 -415.398966)
		(width 0.14224)
		(layer "In11.Cu")
		(net "P5E_CPU1_P2_TX_BUF_C_DP<4>")
	)
	(segment
		(start 124.676916 -412.299658)
		(end 124.947426 -412.570168)
		(width 0.12954)
		(layer "F.Cu")
		(net "P5E_CPU1_P2_TX_BUF_C_DP<3>")
	)
	(segment
		(start 124.676916 -409.079954)
		(end 124.676916 -412.299658)
		(width 0.12954)
		(layer "F.Cu")
		(net "P5E_CPU1_P2_TX_BUF_C_DP<3>")
	)
	(segment
		(start 124.972826 -408.784044)
		(end 124.676916 -409.079954)
		(width 0.12954)
		(layer "F.Cu")
		(net "P5E_CPU1_P2_TX_BUF_C_DP<3>")
	)
	(segment
		(start 125.332998 -414.636966)
		(end 125.122686 -414.265618)
		(width 0.14224)
		(layer "In11.Cu")
		(net "P5E_CPU1_P2_TX_BUF_C_DP<3>")
	)
	(segment
		(start 131.7498 -431.02149)
		(end 131.622546 -431.148744)
		(width 0.14224)
		(layer "In11.Cu")
		(net "P5E_CPU1_P2_TX_BUF_C_DP<3>")
	)
	(segment
		(start 131.622546 -431.148744)
		(end 131.21767 -431.148744)
		(width 0.14224)
		(layer "In11.Cu")
		(net "P5E_CPU1_P2_TX_BUF_C_DP<3>")
	)
	(segment
		(start 126.008892 -416.10788)
		(end 126.060708 -415.920936)
		(width 0.14224)
		(layer "In11.Cu")
		(net "P5E_CPU1_P2_TX_BUF_C_DP<3>")
	)
	(segment
		(start 131.069842 -431.000916)
		(end 131.069842 -425.0436)
		(width 0.14224)
		(layer "In11.Cu")
		(net "P5E_CPU1_P2_TX_BUF_C_DP<3>")
	)
	(segment
		(start 126.060708 -415.920936)
		(end 125.850396 -415.549334)
		(width 0.14224)
		(layer "In11.Cu")
		(net "P5E_CPU1_P2_TX_BUF_C_DP<3>")
	)
	(segment
		(start 131.069842 -425.0436)
		(end 126.008892 -416.10788)
		(width 0.14224)
		(layer "In11.Cu")
		(net "P5E_CPU1_P2_TX_BUF_C_DP<3>")
	)
	(segment
		(start 131.21767 -431.148744)
		(end 131.069842 -431.000916)
		(width 0.14224)
		(layer "In11.Cu")
		(net "P5E_CPU1_P2_TX_BUF_C_DP<3>")
	)
	(segment
		(start 125.122686 -414.265618)
		(end 124.935488 -414.213802)
		(width 0.14224)
		(layer "In11.Cu")
		(net "P5E_CPU1_P2_TX_BUF_C_DP<3>")
	)
	(segment
		(start 124.935488 -414.213802)
		(end 124.656596 -413.721296)
		(width 0.14224)
		(layer "In11.Cu")
		(net "P5E_CPU1_P2_TX_BUF_C_DP<3>")
	)
	(segment
		(start 125.281436 -414.82391)
		(end 125.332998 -414.636966)
		(width 0.14224)
		(layer "In11.Cu")
		(net "P5E_CPU1_P2_TX_BUF_C_DP<3>")
	)
	(segment
		(start 125.663198 -415.497772)
		(end 125.281436 -414.82391)
		(width 0.14224)
		(layer "In11.Cu")
		(net "P5E_CPU1_P2_TX_BUF_C_DP<3>")
	)
	(segment
		(start 124.656596 -412.860998)
		(end 124.947426 -412.570168)
		(width 0.14224)
		(layer "In11.Cu")
		(net "P5E_CPU1_P2_TX_BUF_C_DP<3>")
	)
	(segment
		(start 125.850396 -415.549334)
		(end 125.663198 -415.497772)
		(width 0.14224)
		(layer "In11.Cu")
		(net "P5E_CPU1_P2_TX_BUF_C_DP<3>")
	)
	(segment
		(start 131.7498 -430.689766)
		(end 131.7498 -431.02149)
		(width 0.14224)
		(layer "In11.Cu")
		(net "P5E_CPU1_P2_TX_BUF_C_DP<3>")
	)
	(segment
		(start 124.656596 -413.721296)
		(end 124.656596 -412.860998)
		(width 0.14224)
		(layer "In11.Cu")
		(net "P5E_CPU1_P2_TX_BUF_C_DP<3>")
	)
	(segment
		(start 121.909586 -408.784044)
		(end 121.613676 -409.079954)
		(width 0.12954)
		(layer "F.Cu")
		(net "P5E_CPU1_P2_TX_BUF_C_DP<2>")
	)
	(segment
		(start 121.613676 -412.299658)
		(end 121.884186 -412.570168)
		(width 0.12954)
		(layer "F.Cu")
		(net "P5E_CPU1_P2_TX_BUF_C_DP<2>")
	)
	(segment
		(start 121.613676 -409.079954)
		(end 121.613676 -412.299658)
		(width 0.12954)
		(layer "F.Cu")
		(net "P5E_CPU1_P2_TX_BUF_C_DP<2>")
	)
	(segment
		(start 121.601992 -412.869634)
		(end 121.606564 -412.865062)
		(width 0.14224)
		(layer "In11.Cu")
		(net "P5E_CPU1_P2_TX_BUF_C_DP<2>")
	)
	(segment
		(start 129.217674 -430.148746)
		(end 129.069846 -430.000918)
		(width 0.14224)
		(layer "In11.Cu")
		(net "P5E_CPU1_P2_TX_BUF_C_DP<2>")
	)
	(segment
		(start 124.088652 -416.892994)
		(end 123.842526 -416.544506)
		(width 0.14224)
		(layer "In11.Cu")
		(net "P5E_CPU1_P2_TX_BUF_C_DP<2>")
	)
	(segment
		(start 125.366272 -418.700966)
		(end 124.493528 -417.46551)
		(width 0.14224)
		(layer "In11.Cu")
		(net "P5E_CPU1_P2_TX_BUF_C_DP<2>")
	)
	(segment
		(start 121.606564 -412.865062)
		(end 121.606564 -412.84779)
		(width 0.14224)
		(layer "In11.Cu")
		(net "P5E_CPU1_P2_TX_BUF_C_DP<2>")
	)
	(segment
		(start 123.842526 -416.544506)
		(end 123.875546 -416.353244)
		(width 0.14224)
		(layer "In11.Cu")
		(net "P5E_CPU1_P2_TX_BUF_C_DP<2>")
	)
	(segment
		(start 129.069846 -423.94378)
		(end 125.770894 -419.273736)
		(width 0.14224)
		(layer "In11.Cu")
		(net "P5E_CPU1_P2_TX_BUF_C_DP<2>")
	)
	(segment
		(start 125.55728 -418.733732)
		(end 125.366272 -418.700966)
		(width 0.14224)
		(layer "In11.Cu")
		(net "P5E_CPU1_P2_TX_BUF_C_DP<2>")
	)
	(segment
		(start 121.601992 -413.372554)
		(end 121.601992 -412.869634)
		(width 0.14224)
		(layer "In11.Cu")
		(net "P5E_CPU1_P2_TX_BUF_C_DP<2>")
	)
	(segment
		(start 129.749804 -430.021492)
		(end 129.62255 -430.148746)
		(width 0.14224)
		(layer "In11.Cu")
		(net "P5E_CPU1_P2_TX_BUF_C_DP<2>")
	)
	(segment
		(start 124.493528 -417.46551)
		(end 124.493274 -417.465764)
		(width 0.14224)
		(layer "In11.Cu")
		(net "P5E_CPU1_P2_TX_BUF_C_DP<2>")
	)
	(segment
		(start 123.437904 -415.971736)
		(end 122.787156 -415.050732)
		(width 0.14224)
		(layer "In11.Cu")
		(net "P5E_CPU1_P2_TX_BUF_C_DP<2>")
	)
	(segment
		(start 122.787156 -415.050732)
		(end 122.820176 -414.85947)
		(width 0.14224)
		(layer "In11.Cu")
		(net "P5E_CPU1_P2_TX_BUF_C_DP<2>")
	)
	(segment
		(start 121.606564 -412.84779)
		(end 121.884186 -412.570168)
		(width 0.14224)
		(layer "In11.Cu")
		(net "P5E_CPU1_P2_TX_BUF_C_DP<2>")
	)
	(segment
		(start 129.749804 -429.689768)
		(end 129.749804 -430.021492)
		(width 0.14224)
		(layer "In11.Cu")
		(net "P5E_CPU1_P2_TX_BUF_C_DP<2>")
	)
	(segment
		(start 123.875546 -416.353244)
		(end 123.628912 -416.004502)
		(width 0.14224)
		(layer "In11.Cu")
		(net "P5E_CPU1_P2_TX_BUF_C_DP<2>")
	)
	(segment
		(start 129.62255 -430.148746)
		(end 129.217674 -430.148746)
		(width 0.14224)
		(layer "In11.Cu")
		(net "P5E_CPU1_P2_TX_BUF_C_DP<2>")
	)
	(segment
		(start 124.27966 -416.92576)
		(end 124.088652 -416.892994)
		(width 0.14224)
		(layer "In11.Cu")
		(net "P5E_CPU1_P2_TX_BUF_C_DP<2>")
	)
	(segment
		(start 125.80366 -419.082474)
		(end 125.55728 -418.733732)
		(width 0.14224)
		(layer "In11.Cu")
		(net "P5E_CPU1_P2_TX_BUF_C_DP<2>")
	)
	(segment
		(start 122.573542 -414.510728)
		(end 122.382534 -414.477962)
		(width 0.14224)
		(layer "In11.Cu")
		(net "P5E_CPU1_P2_TX_BUF_C_DP<2>")
	)
	(segment
		(start 122.382534 -414.477962)
		(end 122.136408 -414.129474)
		(width 0.14224)
		(layer "In11.Cu")
		(net "P5E_CPU1_P2_TX_BUF_C_DP<2>")
	)
	(segment
		(start 129.069846 -430.000918)
		(end 129.069846 -423.94378)
		(width 0.14224)
		(layer "In11.Cu")
		(net "P5E_CPU1_P2_TX_BUF_C_DP<2>")
	)
	(segment
		(start 124.493274 -417.465764)
		(end 124.526294 -417.274502)
		(width 0.14224)
		(layer "In11.Cu")
		(net "P5E_CPU1_P2_TX_BUF_C_DP<2>")
	)
	(segment
		(start 122.136408 -414.128966)
		(end 121.601992 -413.372554)
		(width 0.14224)
		(layer "In11.Cu")
		(net "P5E_CPU1_P2_TX_BUF_C_DP<2>")
	)
	(segment
		(start 123.628912 -416.004502)
		(end 123.437904 -415.971736)
		(width 0.14224)
		(layer "In11.Cu")
		(net "P5E_CPU1_P2_TX_BUF_C_DP<2>")
	)
	(segment
		(start 122.820176 -414.85947)
		(end 122.573542 -414.510728)
		(width 0.14224)
		(layer "In11.Cu")
		(net "P5E_CPU1_P2_TX_BUF_C_DP<2>")
	)
	(segment
		(start 124.526294 -417.274502)
		(end 124.27966 -416.92576)
		(width 0.14224)
		(layer "In11.Cu")
		(net "P5E_CPU1_P2_TX_BUF_C_DP<2>")
	)
	(segment
		(start 122.136408 -414.129474)
		(end 122.136408 -414.128966)
		(width 0.14224)
		(layer "In11.Cu")
		(net "P5E_CPU1_P2_TX_BUF_C_DP<2>")
	)
	(segment
		(start 125.770894 -419.273736)
		(end 125.80366 -419.082474)
		(width 0.14224)
		(layer "In11.Cu")
		(net "P5E_CPU1_P2_TX_BUF_C_DP<2>")
	)
	(segment
		(start 118.550436 -409.079954)
		(end 118.550436 -412.299658)
		(width 0.12954)
		(layer "F.Cu")
		(net "P5E_CPU1_P2_TX_BUF_C_DP<1>")
	)
	(segment
		(start 118.550436 -412.299658)
		(end 118.820946 -412.570168)
		(width 0.12954)
		(layer "F.Cu")
		(net "P5E_CPU1_P2_TX_BUF_C_DP<1>")
	)
	(segment
		(start 118.846346 -408.784044)
		(end 118.550436 -409.079954)
		(width 0.12954)
		(layer "F.Cu")
		(net "P5E_CPU1_P2_TX_BUF_C_DP<1>")
	)
	(segment
		(start 119.292624 -414.185354)
		(end 119.59463 -414.48736)
		(width 0.14224)
		(layer "In11.Cu")
		(net "P5E_CPU1_P2_TX_BUF_C_DP<1>")
	)
	(segment
		(start 127.06985 -425.11853)
		(end 127.06985 -431.000916)
		(width 0.14224)
		(layer "In11.Cu")
		(net "P5E_CPU1_P2_TX_BUF_C_DP<1>")
	)
	(segment
		(start 118.567454 -413.65424)
		(end 119.098568 -414.185354)
		(width 0.14224)
		(layer "In11.Cu")
		(net "P5E_CPU1_P2_TX_BUF_C_DP<1>")
	)
	(segment
		(start 127.217678 -431.148744)
		(end 127.622554 -431.148744)
		(width 0.14224)
		(layer "In11.Cu")
		(net "P5E_CPU1_P2_TX_BUF_C_DP<1>")
	)
	(segment
		(start 119.098568 -414.185354)
		(end 119.292624 -414.185354)
		(width 0.14224)
		(layer "In11.Cu")
		(net "P5E_CPU1_P2_TX_BUF_C_DP<1>")
	)
	(segment
		(start 127.06985 -431.000916)
		(end 127.217678 -431.148744)
		(width 0.14224)
		(layer "In11.Cu")
		(net "P5E_CPU1_P2_TX_BUF_C_DP<1>")
	)
	(segment
		(start 127.749808 -431.02149)
		(end 127.749808 -430.689766)
		(width 0.14224)
		(layer "In11.Cu")
		(net "P5E_CPU1_P2_TX_BUF_C_DP<1>")
	)
	(segment
		(start 119.59463 -414.48736)
		(end 119.59463 -414.681416)
		(width 0.14224)
		(layer "In11.Cu")
		(net "P5E_CPU1_P2_TX_BUF_C_DP<1>")
	)
	(segment
		(start 120.39219 -415.28492)
		(end 120.39219 -415.478976)
		(width 0.14224)
		(layer "In11.Cu")
		(net "P5E_CPU1_P2_TX_BUF_C_DP<1>")
	)
	(segment
		(start 119.896128 -414.982914)
		(end 120.090184 -414.982914)
		(width 0.14224)
		(layer "In11.Cu")
		(net "P5E_CPU1_P2_TX_BUF_C_DP<1>")
	)
	(segment
		(start 126.377192 -423.446194)
		(end 127.06985 -425.11853)
		(width 0.14224)
		(layer "In11.Cu")
		(net "P5E_CPU1_P2_TX_BUF_C_DP<1>")
	)
	(segment
		(start 125.695456 -421.80002)
		(end 126.377192 -423.446194)
		(width 0.14224)
		(layer "In11.Cu")
		(net "P5E_CPU1_P2_TX_BUF_C_DP<1>")
	)
	(segment
		(start 119.59463 -414.681416)
		(end 119.896128 -414.982914)
		(width 0.14224)
		(layer "In11.Cu")
		(net "P5E_CPU1_P2_TX_BUF_C_DP<1>")
	)
	(segment
		(start 118.530116 -412.860998)
		(end 118.530116 -413.564324)
		(width 0.14224)
		(layer "In11.Cu")
		(net "P5E_CPU1_P2_TX_BUF_C_DP<1>")
	)
	(segment
		(start 120.090184 -414.982914)
		(end 120.39219 -415.28492)
		(width 0.14224)
		(layer "In11.Cu")
		(net "P5E_CPU1_P2_TX_BUF_C_DP<1>")
	)
	(segment
		(start 118.820946 -412.570168)
		(end 118.530116 -412.860998)
		(width 0.14224)
		(layer "In11.Cu")
		(net "P5E_CPU1_P2_TX_BUF_C_DP<1>")
	)
	(segment
		(start 123.645676 -418.732462)
		(end 125.695456 -421.80002)
		(width 0.14224)
		(layer "In11.Cu")
		(net "P5E_CPU1_P2_TX_BUF_C_DP<1>")
	)
	(segment
		(start 127.622554 -431.148744)
		(end 127.749808 -431.02149)
		(width 0.14224)
		(layer "In11.Cu")
		(net "P5E_CPU1_P2_TX_BUF_C_DP<1>")
	)
	(segment
		(start 120.39219 -415.478976)
		(end 123.645676 -418.732462)
		(width 0.14224)
		(layer "In11.Cu")
		(net "P5E_CPU1_P2_TX_BUF_C_DP<1>")
	)
	(arc
		(start 118.530116 -413.564324)
		(mid 118.539818 -413.613008)
		(end 118.567454 -413.65424)
		(width 0.14224)
		(layer "In11.Cu")
		(net "P5E_CPU1_P2_TX_BUF_C_DP<1>")
	)
	(segment
		(start 161.731706 -408.784044)
		(end 161.435796 -409.079954)
		(width 0.12954)
		(layer "F.Cu")
		(net "P5E_CPU1_P2_TX_BUF_C_DP<15>")
	)
	(segment
		(start 161.435796 -412.299658)
		(end 161.706306 -412.570168)
		(width 0.12954)
		(layer "F.Cu")
		(net "P5E_CPU1_P2_TX_BUF_C_DP<15>")
	)
	(segment
		(start 161.435796 -409.079954)
		(end 161.435796 -412.299658)
		(width 0.12954)
		(layer "F.Cu")
		(net "P5E_CPU1_P2_TX_BUF_C_DP<15>")
	)
	(segment
		(start 156.070046 -424.457622)
		(end 156.070046 -431.000916)
		(width 0.14224)
		(layer "In11.Cu")
		(net "P5E_CPU1_P2_TX_BUF_C_DP<15>")
	)
	(segment
		(start 158.703518 -420.23538)
		(end 156.226002 -423.943272)
		(width 0.14224)
		(layer "In11.Cu")
		(net "P5E_CPU1_P2_TX_BUF_C_DP<15>")
	)
	(segment
		(start 161.170874 -415.066734)
		(end 160.999678 -415.158174)
		(width 0.14224)
		(layer "In11.Cu")
		(net "P5E_CPU1_P2_TX_BUF_C_DP<15>")
	)
	(segment
		(start 160.167828 -417.139628)
		(end 158.703518 -420.23538)
		(width 0.14224)
		(layer "In11.Cu")
		(net "P5E_CPU1_P2_TX_BUF_C_DP<15>")
	)
	(segment
		(start 160.811718 -415.778188)
		(end 160.467802 -416.505644)
		(width 0.14224)
		(layer "In11.Cu")
		(net "P5E_CPU1_P2_TX_BUF_C_DP<15>")
	)
	(segment
		(start 156.070046 -431.000916)
		(end 156.217874 -431.148744)
		(width 0.14224)
		(layer "In11.Cu")
		(net "P5E_CPU1_P2_TX_BUF_C_DP<15>")
	)
	(segment
		(start 161.706306 -412.570168)
		(end 161.415476 -412.860998)
		(width 0.14224)
		(layer "In11.Cu")
		(net "P5E_CPU1_P2_TX_BUF_C_DP<15>")
	)
	(segment
		(start 160.467802 -416.505644)
		(end 160.53308 -416.68827)
		(width 0.14224)
		(layer "In11.Cu")
		(net "P5E_CPU1_P2_TX_BUF_C_DP<15>")
	)
	(segment
		(start 160.999678 -415.158174)
		(end 160.811718 -415.778188)
		(width 0.14224)
		(layer "In11.Cu")
		(net "P5E_CPU1_P2_TX_BUF_C_DP<15>")
	)
	(segment
		(start 161.294826 -414.658048)
		(end 161.170874 -415.066734)
		(width 0.14224)
		(layer "In11.Cu")
		(net "P5E_CPU1_P2_TX_BUF_C_DP<15>")
	)
	(segment
		(start 160.53308 -416.68827)
		(end 160.350708 -417.07435)
		(width 0.14224)
		(layer "In11.Cu")
		(net "P5E_CPU1_P2_TX_BUF_C_DP<15>")
	)
	(segment
		(start 161.391346 -413.867092)
		(end 161.203386 -414.486852)
		(width 0.14224)
		(layer "In11.Cu")
		(net "P5E_CPU1_P2_TX_BUF_C_DP<15>")
	)
	(segment
		(start 161.203386 -414.486852)
		(end 161.294826 -414.658048)
		(width 0.14224)
		(layer "In11.Cu")
		(net "P5E_CPU1_P2_TX_BUF_C_DP<15>")
	)
	(segment
		(start 156.750004 -431.02149)
		(end 156.750004 -430.689766)
		(width 0.14224)
		(layer "In11.Cu")
		(net "P5E_CPU1_P2_TX_BUF_C_DP<15>")
	)
	(segment
		(start 156.62275 -431.148744)
		(end 156.750004 -431.02149)
		(width 0.14224)
		(layer "In11.Cu")
		(net "P5E_CPU1_P2_TX_BUF_C_DP<15>")
	)
	(segment
		(start 160.350708 -417.07435)
		(end 160.167828 -417.139628)
		(width 0.14224)
		(layer "In11.Cu")
		(net "P5E_CPU1_P2_TX_BUF_C_DP<15>")
	)
	(segment
		(start 156.217874 -431.148744)
		(end 156.62275 -431.148744)
		(width 0.14224)
		(layer "In11.Cu")
		(net "P5E_CPU1_P2_TX_BUF_C_DP<15>")
	)
	(segment
		(start 161.415476 -412.860998)
		(end 161.415476 -413.703516)
		(width 0.14224)
		(layer "In11.Cu")
		(net "P5E_CPU1_P2_TX_BUF_C_DP<15>")
	)
	(arc
		(start 156.226002 -423.943272)
		(mid 156.109852 -424.188877)
		(end 156.070046 -424.457622)
		(width 0.14224)
		(layer "In11.Cu")
		(net "P5E_CPU1_P2_TX_BUF_C_DP<15>")
	)
	(arc
		(start 161.415476 -413.703516)
		(mid 161.409457 -413.786197)
		(end 161.391346 -413.867092)
		(width 0.14224)
		(layer "In11.Cu")
		(net "P5E_CPU1_P2_TX_BUF_C_DP<15>")
	)
	(segment
		(start 158.668466 -408.784044)
		(end 158.372556 -409.079954)
		(width 0.12954)
		(layer "F.Cu")
		(net "P5E_CPU1_P2_TX_BUF_C_DP<14>")
	)
	(segment
		(start 158.372556 -412.299658)
		(end 158.643066 -412.570168)
		(width 0.12954)
		(layer "F.Cu")
		(net "P5E_CPU1_P2_TX_BUF_C_DP<14>")
	)
	(segment
		(start 158.372556 -409.079954)
		(end 158.372556 -412.299658)
		(width 0.12954)
		(layer "F.Cu")
		(net "P5E_CPU1_P2_TX_BUF_C_DP<14>")
	)
	(segment
		(start 154.623008 -430.125632)
		(end 154.750008 -429.998632)
		(width 0.14224)
		(layer "In11.Cu")
		(net "P5E_CPU1_P2_TX_BUF_C_DP<14>")
	)
	(segment
		(start 156.031692 -419.63213)
		(end 156.100526 -419.813486)
		(width 0.14224)
		(layer "In11.Cu")
		(net "P5E_CPU1_P2_TX_BUF_C_DP<14>")
	)
	(segment
		(start 154.688286 -422.613836)
		(end 154.224228 -423.734484)
		(width 0.14224)
		(layer "In11.Cu")
		(net "P5E_CPU1_P2_TX_BUF_C_DP<14>")
	)
	(segment
		(start 157.556708 -415.847022)
		(end 157.403292 -416.24504)
		(width 0.14224)
		(layer "In11.Cu")
		(net "P5E_CPU1_P2_TX_BUF_C_DP<14>")
	)
	(segment
		(start 157.809184 -415.192718)
		(end 157.887924 -415.37001)
		(width 0.14224)
		(layer "In11.Cu")
		(net "P5E_CPU1_P2_TX_BUF_C_DP<14>")
	)
	(segment
		(start 156.20746 -419.243002)
		(end 156.206952 -419.243256)
		(width 0.14224)
		(layer "In11.Cu")
		(net "P5E_CPU1_P2_TX_BUF_C_DP<14>")
	)
	(segment
		(start 157.328362 -416.820858)
		(end 157.150816 -416.899344)
		(width 0.14224)
		(layer "In11.Cu")
		(net "P5E_CPU1_P2_TX_BUF_C_DP<14>")
	)
	(segment
		(start 157.075886 -417.474654)
		(end 156.92247 -417.87318)
		(width 0.14224)
		(layer "In11.Cu")
		(net "P5E_CPU1_P2_TX_BUF_C_DP<14>")
	)
	(segment
		(start 154.750008 -429.998632)
		(end 154.750008 -429.689768)
		(width 0.14224)
		(layer "In11.Cu")
		(net "P5E_CPU1_P2_TX_BUF_C_DP<14>")
	)
	(segment
		(start 154.224228 -423.734484)
		(end 154.224228 -423.734738)
		(width 0.14224)
		(layer "In11.Cu")
		(net "P5E_CPU1_P2_TX_BUF_C_DP<14>")
	)
	(segment
		(start 158.271718 -413.994092)
		(end 157.809438 -415.191956)
		(width 0.14224)
		(layer "In11.Cu")
		(net "P5E_CPU1_P2_TX_BUF_C_DP<14>")
	)
	(segment
		(start 154.07005 -424.509946)
		(end 154.07005 -429.91532)
		(width 0.14224)
		(layer "In11.Cu")
		(net "P5E_CPU1_P2_TX_BUF_C_DP<14>")
	)
	(segment
		(start 156.9974 -417.297362)
		(end 157.075886 -417.474654)
		(width 0.14224)
		(layer "In11.Cu")
		(net "P5E_CPU1_P2_TX_BUF_C_DP<14>")
	)
	(segment
		(start 156.73324 -417.981892)
		(end 156.481526 -418.634672)
		(width 0.14224)
		(layer "In11.Cu")
		(net "P5E_CPU1_P2_TX_BUF_C_DP<14>")
	)
	(segment
		(start 155.743656 -420.271702)
		(end 154.688286 -422.613836)
		(width 0.14224)
		(layer "In11.Cu")
		(net "P5E_CPU1_P2_TX_BUF_C_DP<14>")
	)
	(segment
		(start 156.481526 -418.634672)
		(end 156.20746 -419.243002)
		(width 0.14224)
		(layer "In11.Cu")
		(net "P5E_CPU1_P2_TX_BUF_C_DP<14>")
	)
	(segment
		(start 158.643066 -412.570168)
		(end 158.352236 -412.860998)
		(width 0.14224)
		(layer "In11.Cu")
		(net "P5E_CPU1_P2_TX_BUF_C_DP<14>")
	)
	(segment
		(start 157.481778 -416.422332)
		(end 157.328362 -416.820858)
		(width 0.14224)
		(layer "In11.Cu")
		(net "P5E_CPU1_P2_TX_BUF_C_DP<14>")
	)
	(segment
		(start 154.280362 -430.125632)
		(end 154.623008 -430.125632)
		(width 0.14224)
		(layer "In11.Cu")
		(net "P5E_CPU1_P2_TX_BUF_C_DP<14>")
	)
	(segment
		(start 154.07005 -429.91532)
		(end 154.280362 -430.125632)
		(width 0.14224)
		(layer "In11.Cu")
		(net "P5E_CPU1_P2_TX_BUF_C_DP<14>")
	)
	(segment
		(start 156.206952 -419.243256)
		(end 156.031692 -419.63213)
		(width 0.14224)
		(layer "In11.Cu")
		(net "P5E_CPU1_P2_TX_BUF_C_DP<14>")
	)
	(segment
		(start 157.809438 -415.191956)
		(end 157.809184 -415.192718)
		(width 0.14224)
		(layer "In11.Cu")
		(net "P5E_CPU1_P2_TX_BUF_C_DP<14>")
	)
	(segment
		(start 156.737558 -417.975542)
		(end 156.73324 -417.981892)
		(width 0.14224)
		(layer "In11.Cu")
		(net "P5E_CPU1_P2_TX_BUF_C_DP<14>")
	)
	(segment
		(start 157.150816 -416.899344)
		(end 156.9974 -417.297362)
		(width 0.14224)
		(layer "In11.Cu")
		(net "P5E_CPU1_P2_TX_BUF_C_DP<14>")
	)
	(segment
		(start 157.403292 -416.24504)
		(end 157.481778 -416.422332)
		(width 0.14224)
		(layer "In11.Cu")
		(net "P5E_CPU1_P2_TX_BUF_C_DP<14>")
	)
	(segment
		(start 156.745432 -417.951666)
		(end 156.737558 -417.975542)
		(width 0.14224)
		(layer "In11.Cu")
		(net "P5E_CPU1_P2_TX_BUF_C_DP<14>")
	)
	(segment
		(start 158.352236 -412.860998)
		(end 158.352236 -413.561022)
		(width 0.14224)
		(layer "In11.Cu")
		(net "P5E_CPU1_P2_TX_BUF_C_DP<14>")
	)
	(segment
		(start 155.925266 -420.202868)
		(end 155.743656 -420.271702)
		(width 0.14224)
		(layer "In11.Cu")
		(net "P5E_CPU1_P2_TX_BUF_C_DP<14>")
	)
	(segment
		(start 157.734254 -415.768536)
		(end 157.556708 -415.847022)
		(width 0.14224)
		(layer "In11.Cu")
		(net "P5E_CPU1_P2_TX_BUF_C_DP<14>")
	)
	(segment
		(start 156.100526 -419.813486)
		(end 155.925266 -420.202868)
		(width 0.14224)
		(layer "In11.Cu")
		(net "P5E_CPU1_P2_TX_BUF_C_DP<14>")
	)
	(segment
		(start 156.92247 -417.87318)
		(end 156.745432 -417.951666)
		(width 0.14224)
		(layer "In11.Cu")
		(net "P5E_CPU1_P2_TX_BUF_C_DP<14>")
	)
	(segment
		(start 157.887924 -415.37001)
		(end 157.734254 -415.768536)
		(width 0.14224)
		(layer "In11.Cu")
		(net "P5E_CPU1_P2_TX_BUF_C_DP<14>")
	)
	(arc
		(start 158.352236 -413.561022)
		(mid 158.331949 -413.781268)
		(end 158.271718 -413.994092)
		(width 0.14224)
		(layer "In11.Cu")
		(net "P5E_CPU1_P2_TX_BUF_C_DP<14>")
	)
	(arc
		(start 154.224228 -423.734738)
		(mid 154.108994 -424.114754)
		(end 154.07005 -424.509946)
		(width 0.14224)
		(layer "In11.Cu")
		(net "P5E_CPU1_P2_TX_BUF_C_DP<14>")
	)
	(segment
		(start 155.309316 -409.079954)
		(end 155.309316 -412.299658)
		(width 0.12954)
		(layer "F.Cu")
		(net "P5E_CPU1_P2_TX_BUF_C_DP<13>")
	)
	(segment
		(start 155.309316 -412.299658)
		(end 155.579826 -412.570168)
		(width 0.12954)
		(layer "F.Cu")
		(net "P5E_CPU1_P2_TX_BUF_C_DP<13>")
	)
	(segment
		(start 155.605226 -408.784044)
		(end 155.309316 -409.079954)
		(width 0.12954)
		(layer "F.Cu")
		(net "P5E_CPU1_P2_TX_BUF_C_DP<13>")
	)
	(segment
		(start 152.070054 -424.931332)
		(end 152.070054 -430.980596)
		(width 0.14224)
		(layer "In11.Cu")
		(net "P5E_CPU1_P2_TX_BUF_C_DP<13>")
	)
	(segment
		(start 155.141422 -414.689798)
		(end 155.232862 -414.860994)
		(width 0.14224)
		(layer "In11.Cu")
		(net "P5E_CPU1_P2_TX_BUF_C_DP<13>")
	)
	(segment
		(start 152.070308 -424.931586)
		(end 152.070054 -424.931332)
		(width 0.14224)
		(layer "In11.Cu")
		(net "P5E_CPU1_P2_TX_BUF_C_DP<13>")
	)
	(segment
		(start 152.750012 -431.02149)
		(end 152.750012 -430.689766)
		(width 0.14224)
		(layer "In11.Cu")
		(net "P5E_CPU1_P2_TX_BUF_C_DP<13>")
	)
	(segment
		(start 155.10891 -415.269426)
		(end 154.927554 -415.3662)
		(width 0.14224)
		(layer "In11.Cu")
		(net "P5E_CPU1_P2_TX_BUF_C_DP<13>")
	)
	(segment
		(start 154.47264 -416.892994)
		(end 153.68397 -419.493954)
		(width 0.14224)
		(layer "In11.Cu")
		(net "P5E_CPU1_P2_TX_BUF_C_DP<13>")
	)
	(segment
		(start 154.768042 -416.392614)
		(end 154.64409 -416.801046)
		(width 0.14224)
		(layer "In11.Cu")
		(net "P5E_CPU1_P2_TX_BUF_C_DP<13>")
	)
	(segment
		(start 155.142692 -414.685988)
		(end 155.141422 -414.689798)
		(width 0.14224)
		(layer "In11.Cu")
		(net "P5E_CPU1_P2_TX_BUF_C_DP<13>")
	)
	(segment
		(start 153.68397 -419.493954)
		(end 152.382982 -423.129456)
		(width 0.14224)
		(layer "In11.Cu")
		(net "P5E_CPU1_P2_TX_BUF_C_DP<13>")
	)
	(segment
		(start 152.238202 -431.148744)
		(end 152.622758 -431.148744)
		(width 0.14224)
		(layer "In11.Cu")
		(net "P5E_CPU1_P2_TX_BUF_C_DP<13>")
	)
	(segment
		(start 155.232862 -414.860994)
		(end 155.10891 -415.269426)
		(width 0.14224)
		(layer "In11.Cu")
		(net "P5E_CPU1_P2_TX_BUF_C_DP<13>")
	)
	(segment
		(start 154.671268 -416.211512)
		(end 154.768042 -416.392614)
		(width 0.14224)
		(layer "In11.Cu")
		(net "P5E_CPU1_P2_TX_BUF_C_DP<13>")
	)
	(segment
		(start 152.070054 -430.980596)
		(end 152.238202 -431.148744)
		(width 0.14224)
		(layer "In11.Cu")
		(net "P5E_CPU1_P2_TX_BUF_C_DP<13>")
	)
	(segment
		(start 154.472894 -416.892486)
		(end 154.47264 -416.892994)
		(width 0.14224)
		(layer "In11.Cu")
		(net "P5E_CPU1_P2_TX_BUF_C_DP<13>")
	)
	(segment
		(start 152.622758 -431.148744)
		(end 152.750012 -431.02149)
		(width 0.14224)
		(layer "In11.Cu")
		(net "P5E_CPU1_P2_TX_BUF_C_DP<13>")
	)
	(segment
		(start 154.927554 -415.3662)
		(end 154.671268 -416.211512)
		(width 0.14224)
		(layer "In11.Cu")
		(net "P5E_CPU1_P2_TX_BUF_C_DP<13>")
	)
	(segment
		(start 155.579826 -412.570168)
		(end 155.288996 -412.860998)
		(width 0.14224)
		(layer "In11.Cu")
		(net "P5E_CPU1_P2_TX_BUF_C_DP<13>")
	)
	(segment
		(start 154.64409 -416.801046)
		(end 154.472894 -416.892486)
		(width 0.14224)
		(layer "In11.Cu")
		(net "P5E_CPU1_P2_TX_BUF_C_DP<13>")
	)
	(segment
		(start 155.244546 -414.349184)
		(end 155.142692 -414.685988)
		(width 0.14224)
		(layer "In11.Cu")
		(net "P5E_CPU1_P2_TX_BUF_C_DP<13>")
	)
	(segment
		(start 155.288996 -412.860998)
		(end 155.288996 -414.04921)
		(width 0.14224)
		(layer "In11.Cu")
		(net "P5E_CPU1_P2_TX_BUF_C_DP<13>")
	)
	(arc
		(start 152.382982 -423.129456)
		(mid 152.149044 -424.017056)
		(end 152.070308 -424.931586)
		(width 0.14224)
		(layer "In11.Cu")
		(net "P5E_CPU1_P2_TX_BUF_C_DP<13>")
	)
	(arc
		(start 155.288996 -414.04921)
		(mid 155.277799 -414.20083)
		(end 155.244546 -414.349184)
		(width 0.14224)
		(layer "In11.Cu")
		(net "P5E_CPU1_P2_TX_BUF_C_DP<13>")
	)
	(segment
		(start 152.246076 -409.079954)
		(end 152.246076 -412.299658)
		(width 0.12954)
		(layer "F.Cu")
		(net "P5E_CPU1_P2_TX_BUF_C_DP<12>")
	)
	(segment
		(start 152.541986 -408.784044)
		(end 152.246076 -409.079954)
		(width 0.12954)
		(layer "F.Cu")
		(net "P5E_CPU1_P2_TX_BUF_C_DP<12>")
	)
	(segment
		(start 152.246076 -412.299658)
		(end 152.516586 -412.570168)
		(width 0.12954)
		(layer "F.Cu")
		(net "P5E_CPU1_P2_TX_BUF_C_DP<12>")
	)
	(segment
		(start 151.066754 -418.940488)
		(end 150.200868 -422.796462)
		(width 0.14224)
		(layer "In11.Cu")
		(net "P5E_CPU1_P2_TX_BUF_C_DP<12>")
	)
	(segment
		(start 152.142698 -414.776412)
		(end 151.978614 -414.880298)
		(width 0.14224)
		(layer "In11.Cu")
		(net "P5E_CPU1_P2_TX_BUF_C_DP<12>")
	)
	(segment
		(start 151.6634 -416.910266)
		(end 151.569928 -417.326826)
		(width 0.14224)
		(layer "In11.Cu")
		(net "P5E_CPU1_P2_TX_BUF_C_DP<12>")
	)
	(segment
		(start 151.560276 -416.744404)
		(end 151.559768 -416.746436)
		(width 0.14224)
		(layer "In11.Cu")
		(net "P5E_CPU1_P2_TX_BUF_C_DP<12>")
	)
	(segment
		(start 151.230838 -418.836856)
		(end 151.066754 -418.940488)
		(width 0.14224)
		(layer "In11.Cu")
		(net "P5E_CPU1_P2_TX_BUF_C_DP<12>")
	)
	(segment
		(start 151.895556 -415.876994)
		(end 151.731472 -415.98088)
		(width 0.14224)
		(layer "In11.Cu")
		(net "P5E_CPU1_P2_TX_BUF_C_DP<12>")
	)
	(segment
		(start 151.731472 -415.98088)
		(end 151.560276 -416.744404)
		(width 0.14224)
		(layer "In11.Cu")
		(net "P5E_CPU1_P2_TX_BUF_C_DP<12>")
	)
	(segment
		(start 150.070058 -423.975022)
		(end 150.070058 -429.91532)
		(width 0.14224)
		(layer "In11.Cu")
		(net "P5E_CPU1_P2_TX_BUF_C_DP<12>")
	)
	(segment
		(start 151.885142 -415.296604)
		(end 151.989028 -415.460434)
		(width 0.14224)
		(layer "In11.Cu")
		(net "P5E_CPU1_P2_TX_BUF_C_DP<12>")
	)
	(segment
		(start 151.220424 -418.256212)
		(end 151.32431 -418.420042)
		(width 0.14224)
		(layer "In11.Cu")
		(net "P5E_CPU1_P2_TX_BUF_C_DP<12>")
	)
	(segment
		(start 152.225756 -412.860998)
		(end 152.225756 -413.719518)
		(width 0.14224)
		(layer "In11.Cu")
		(net "P5E_CPU1_P2_TX_BUF_C_DP<12>")
	)
	(segment
		(start 150.28037 -430.125632)
		(end 150.623016 -430.125632)
		(width 0.14224)
		(layer "In11.Cu")
		(net "P5E_CPU1_P2_TX_BUF_C_DP<12>")
	)
	(segment
		(start 150.623016 -430.125632)
		(end 150.750016 -429.998632)
		(width 0.14224)
		(layer "In11.Cu")
		(net "P5E_CPU1_P2_TX_BUF_C_DP<12>")
	)
	(segment
		(start 151.32431 -418.420042)
		(end 151.230838 -418.836856)
		(width 0.14224)
		(layer "In11.Cu")
		(net "P5E_CPU1_P2_TX_BUF_C_DP<12>")
	)
	(segment
		(start 151.569928 -417.326826)
		(end 151.405844 -417.430712)
		(width 0.14224)
		(layer "In11.Cu")
		(net "P5E_CPU1_P2_TX_BUF_C_DP<12>")
	)
	(segment
		(start 152.23617 -414.359852)
		(end 152.142698 -414.776412)
		(width 0.14224)
		(layer "In11.Cu")
		(net "P5E_CPU1_P2_TX_BUF_C_DP<12>")
	)
	(segment
		(start 151.40559 -417.431728)
		(end 151.220424 -418.256212)
		(width 0.14224)
		(layer "In11.Cu")
		(net "P5E_CPU1_P2_TX_BUF_C_DP<12>")
	)
	(segment
		(start 150.750016 -429.998632)
		(end 150.750016 -429.689768)
		(width 0.14224)
		(layer "In11.Cu")
		(net "P5E_CPU1_P2_TX_BUF_C_DP<12>")
	)
	(segment
		(start 151.405844 -417.430712)
		(end 151.40559 -417.431728)
		(width 0.14224)
		(layer "In11.Cu")
		(net "P5E_CPU1_P2_TX_BUF_C_DP<12>")
	)
	(segment
		(start 152.132284 -414.196022)
		(end 152.23617 -414.359852)
		(width 0.14224)
		(layer "In11.Cu")
		(net "P5E_CPU1_P2_TX_BUF_C_DP<12>")
	)
	(segment
		(start 150.070058 -429.91532)
		(end 150.28037 -430.125632)
		(width 0.14224)
		(layer "In11.Cu")
		(net "P5E_CPU1_P2_TX_BUF_C_DP<12>")
	)
	(segment
		(start 151.978614 -414.880298)
		(end 151.97836 -414.881314)
		(width 0.14224)
		(layer "In11.Cu")
		(net "P5E_CPU1_P2_TX_BUF_C_DP<12>")
	)
	(segment
		(start 151.97836 -414.881314)
		(end 151.885142 -415.296604)
		(width 0.14224)
		(layer "In11.Cu")
		(net "P5E_CPU1_P2_TX_BUF_C_DP<12>")
	)
	(segment
		(start 152.516586 -412.570168)
		(end 152.225756 -412.860998)
		(width 0.14224)
		(layer "In11.Cu")
		(net "P5E_CPU1_P2_TX_BUF_C_DP<12>")
	)
	(segment
		(start 151.559768 -416.746436)
		(end 151.6634 -416.910266)
		(width 0.14224)
		(layer "In11.Cu")
		(net "P5E_CPU1_P2_TX_BUF_C_DP<12>")
	)
	(segment
		(start 152.212548 -413.83839)
		(end 152.132284 -414.196022)
		(width 0.14224)
		(layer "In11.Cu")
		(net "P5E_CPU1_P2_TX_BUF_C_DP<12>")
	)
	(segment
		(start 151.989028 -415.460434)
		(end 151.895556 -415.876994)
		(width 0.14224)
		(layer "In11.Cu")
		(net "P5E_CPU1_P2_TX_BUF_C_DP<12>")
	)
	(arc
		(start 152.225756 -413.719518)
		(mid 152.22245 -413.779321)
		(end 152.212548 -413.83839)
		(width 0.14224)
		(layer "In11.Cu")
		(net "P5E_CPU1_P2_TX_BUF_C_DP<12>")
	)
	(arc
		(start 150.200868 -422.796462)
		(mid 150.102874 -423.382125)
		(end 150.070058 -423.975022)
		(width 0.14224)
		(layer "In11.Cu")
		(net "P5E_CPU1_P2_TX_BUF_C_DP<12>")
	)
	(segment
		(start 149.182836 -409.079954)
		(end 149.182836 -412.299658)
		(width 0.12954)
		(layer "F.Cu")
		(net "P5E_CPU1_P2_TX_BUF_C_DP<11>")
	)
	(segment
		(start 149.478746 -408.784044)
		(end 149.182836 -409.079954)
		(width 0.12954)
		(layer "F.Cu")
		(net "P5E_CPU1_P2_TX_BUF_C_DP<11>")
	)
	(segment
		(start 149.182836 -412.299658)
		(end 149.453346 -412.570168)
		(width 0.12954)
		(layer "F.Cu")
		(net "P5E_CPU1_P2_TX_BUF_C_DP<11>")
	)
	(segment
		(start 148.75002 -430.689766)
		(end 148.75002 -431.02149)
		(width 0.14224)
		(layer "In11.Cu")
		(net "P5E_CPU1_P2_TX_BUF_C_DP<11>")
	)
	(segment
		(start 149.15388 -415.510726)
		(end 149.03069 -415.360612)
		(width 0.14224)
		(layer "In11.Cu")
		(net "P5E_CPU1_P2_TX_BUF_C_DP<11>")
	)
	(segment
		(start 149.151086 -414.135316)
		(end 149.162516 -414.123886)
		(width 0.14224)
		(layer "In11.Cu")
		(net "P5E_CPU1_P2_TX_BUF_C_DP<11>")
	)
	(segment
		(start 149.03069 -415.360612)
		(end 149.151086 -414.135316)
		(width 0.14224)
		(layer "In11.Cu")
		(net "P5E_CPU1_P2_TX_BUF_C_DP<11>")
	)
	(segment
		(start 148.801074 -417.692586)
		(end 148.846794 -417.227258)
		(width 0.14224)
		(layer "In11.Cu")
		(net "P5E_CPU1_P2_TX_BUF_C_DP<11>")
	)
	(segment
		(start 148.996908 -417.104322)
		(end 149.038818 -416.67938)
		(width 0.14224)
		(layer "In11.Cu")
		(net "P5E_CPU1_P2_TX_BUF_C_DP<11>")
	)
	(segment
		(start 148.208492 -431.139346)
		(end 148.070062 -431.000916)
		(width 0.14224)
		(layer "In11.Cu")
		(net "P5E_CPU1_P2_TX_BUF_C_DP<11>")
	)
	(segment
		(start 148.915628 -416.52952)
		(end 148.961856 -416.058604)
		(width 0.14224)
		(layer "In11.Cu")
		(net "P5E_CPU1_P2_TX_BUF_C_DP<11>")
	)
	(segment
		(start 148.070062 -425.128944)
		(end 148.800566 -417.69284)
		(width 0.14224)
		(layer "In11.Cu")
		(net "P5E_CPU1_P2_TX_BUF_C_DP<11>")
	)
	(segment
		(start 149.11197 -415.935414)
		(end 149.15388 -415.510726)
		(width 0.14224)
		(layer "In11.Cu")
		(net "P5E_CPU1_P2_TX_BUF_C_DP<11>")
	)
	(segment
		(start 148.632164 -431.139346)
		(end 148.208492 -431.139346)
		(width 0.14224)
		(layer "In11.Cu")
		(net "P5E_CPU1_P2_TX_BUF_C_DP<11>")
	)
	(segment
		(start 148.846794 -417.227258)
		(end 148.996908 -417.104322)
		(width 0.14224)
		(layer "In11.Cu")
		(net "P5E_CPU1_P2_TX_BUF_C_DP<11>")
	)
	(segment
		(start 148.75002 -431.02149)
		(end 148.632164 -431.139346)
		(width 0.14224)
		(layer "In11.Cu")
		(net "P5E_CPU1_P2_TX_BUF_C_DP<11>")
	)
	(segment
		(start 148.070062 -431.000916)
		(end 148.070062 -425.128944)
		(width 0.14224)
		(layer "In11.Cu")
		(net "P5E_CPU1_P2_TX_BUF_C_DP<11>")
	)
	(segment
		(start 148.800566 -417.69284)
		(end 148.801074 -417.692586)
		(width 0.14224)
		(layer "In11.Cu")
		(net "P5E_CPU1_P2_TX_BUF_C_DP<11>")
	)
	(segment
		(start 149.162516 -414.123886)
		(end 149.162516 -412.860998)
		(width 0.14224)
		(layer "In11.Cu")
		(net "P5E_CPU1_P2_TX_BUF_C_DP<11>")
	)
	(segment
		(start 149.162516 -412.860998)
		(end 149.453346 -412.570168)
		(width 0.14224)
		(layer "In11.Cu")
		(net "P5E_CPU1_P2_TX_BUF_C_DP<11>")
	)
	(segment
		(start 149.038818 -416.67938)
		(end 148.915628 -416.52952)
		(width 0.14224)
		(layer "In11.Cu")
		(net "P5E_CPU1_P2_TX_BUF_C_DP<11>")
	)
	(segment
		(start 148.961856 -416.058604)
		(end 149.11197 -415.935414)
		(width 0.14224)
		(layer "In11.Cu")
		(net "P5E_CPU1_P2_TX_BUF_C_DP<11>")
	)
	(segment
		(start 146.119596 -412.299658)
		(end 146.390106 -412.570168)
		(width 0.12954)
		(layer "F.Cu")
		(net "P5E_CPU1_P2_TX_BUF_C_DP<10>")
	)
	(segment
		(start 146.415506 -408.784044)
		(end 146.119596 -409.079954)
		(width 0.12954)
		(layer "F.Cu")
		(net "P5E_CPU1_P2_TX_BUF_C_DP<10>")
	)
	(segment
		(start 146.119596 -409.079954)
		(end 146.119596 -412.299658)
		(width 0.12954)
		(layer "F.Cu")
		(net "P5E_CPU1_P2_TX_BUF_C_DP<10>")
	)
	(segment
		(start 146.750024 -429.998632)
		(end 146.750024 -429.689768)
		(width 0.14224)
		(layer "In11.Cu")
		(net "P5E_CPU1_P2_TX_BUF_C_DP<10>")
	)
	(segment
		(start 146.087084 -429.932338)
		(end 146.280378 -430.125632)
		(width 0.14224)
		(layer "In11.Cu")
		(net "P5E_CPU1_P2_TX_BUF_C_DP<10>")
	)
	(segment
		(start 146.087084 -417.520628)
		(end 146.087084 -417.992052)
		(width 0.14224)
		(layer "In11.Cu")
		(net "P5E_CPU1_P2_TX_BUF_C_DP<10>")
	)
	(segment
		(start 146.087084 -416.019234)
		(end 146.087084 -416.819588)
		(width 0.14224)
		(layer "In11.Cu")
		(net "P5E_CPU1_P2_TX_BUF_C_DP<10>")
	)
	(segment
		(start 146.280378 -430.125632)
		(end 146.623024 -430.125632)
		(width 0.14224)
		(layer "In11.Cu")
		(net "P5E_CPU1_P2_TX_BUF_C_DP<10>")
	)
	(segment
		(start 146.087084 -415.318194)
		(end 146.224244 -415.455354)
		(width 0.14224)
		(layer "In11.Cu")
		(net "P5E_CPU1_P2_TX_BUF_C_DP<10>")
	)
	(segment
		(start 146.224244 -416.956748)
		(end 146.224244 -417.383468)
		(width 0.14224)
		(layer "In11.Cu")
		(net "P5E_CPU1_P2_TX_BUF_C_DP<10>")
	)
	(segment
		(start 146.623024 -430.125632)
		(end 146.750024 -429.998632)
		(width 0.14224)
		(layer "In11.Cu")
		(net "P5E_CPU1_P2_TX_BUF_C_DP<10>")
	)
	(segment
		(start 146.087084 -416.819588)
		(end 146.224244 -416.956748)
		(width 0.14224)
		(layer "In11.Cu")
		(net "P5E_CPU1_P2_TX_BUF_C_DP<10>")
	)
	(segment
		(start 146.224244 -414.327594)
		(end 146.224244 -414.754314)
		(width 0.14224)
		(layer "In11.Cu")
		(net "P5E_CPU1_P2_TX_BUF_C_DP<10>")
	)
	(segment
		(start 146.224244 -415.455354)
		(end 146.224244 -415.882074)
		(width 0.14224)
		(layer "In11.Cu")
		(net "P5E_CPU1_P2_TX_BUF_C_DP<10>")
	)
	(segment
		(start 146.224244 -417.383468)
		(end 146.087084 -417.520628)
		(width 0.14224)
		(layer "In11.Cu")
		(net "P5E_CPU1_P2_TX_BUF_C_DP<10>")
	)
	(segment
		(start 146.087084 -414.190434)
		(end 146.224244 -414.327594)
		(width 0.14224)
		(layer "In11.Cu")
		(net "P5E_CPU1_P2_TX_BUF_C_DP<10>")
	)
	(segment
		(start 146.390106 -412.570168)
		(end 146.087084 -412.87319)
		(width 0.14224)
		(layer "In11.Cu")
		(net "P5E_CPU1_P2_TX_BUF_C_DP<10>")
	)
	(segment
		(start 146.224244 -418.555932)
		(end 146.087084 -418.693092)
		(width 0.14224)
		(layer "In11.Cu")
		(net "P5E_CPU1_P2_TX_BUF_C_DP<10>")
	)
	(segment
		(start 146.087084 -418.693092)
		(end 146.087084 -429.932338)
		(width 0.14224)
		(layer "In11.Cu")
		(net "P5E_CPU1_P2_TX_BUF_C_DP<10>")
	)
	(segment
		(start 146.087084 -417.992052)
		(end 146.224244 -418.129212)
		(width 0.14224)
		(layer "In11.Cu")
		(net "P5E_CPU1_P2_TX_BUF_C_DP<10>")
	)
	(segment
		(start 146.224244 -415.882074)
		(end 146.087084 -416.019234)
		(width 0.14224)
		(layer "In11.Cu")
		(net "P5E_CPU1_P2_TX_BUF_C_DP<10>")
	)
	(segment
		(start 146.087084 -412.87319)
		(end 146.087084 -414.190434)
		(width 0.14224)
		(layer "In11.Cu")
		(net "P5E_CPU1_P2_TX_BUF_C_DP<10>")
	)
	(segment
		(start 146.224244 -418.129212)
		(end 146.224244 -418.555932)
		(width 0.14224)
		(layer "In11.Cu")
		(net "P5E_CPU1_P2_TX_BUF_C_DP<10>")
	)
	(segment
		(start 146.224244 -414.754314)
		(end 146.087084 -414.891474)
		(width 0.14224)
		(layer "In11.Cu")
		(net "P5E_CPU1_P2_TX_BUF_C_DP<10>")
	)
	(segment
		(start 146.087084 -414.891474)
		(end 146.087084 -415.318194)
		(width 0.14224)
		(layer "In11.Cu")
		(net "P5E_CPU1_P2_TX_BUF_C_DP<10>")
	)
	(segment
		(start 115.487196 -409.079954)
		(end 115.487196 -412.299658)
		(width 0.12954)
		(layer "F.Cu")
		(net "P5E_CPU1_P2_TX_BUF_C_DP<0>")
	)
	(segment
		(start 115.487196 -412.299658)
		(end 115.757706 -412.570168)
		(width 0.12954)
		(layer "F.Cu")
		(net "P5E_CPU1_P2_TX_BUF_C_DP<0>")
	)
	(segment
		(start 115.783106 -408.784044)
		(end 115.487196 -409.079954)
		(width 0.12954)
		(layer "F.Cu")
		(net "P5E_CPU1_P2_TX_BUF_C_DP<0>")
	)
	(segment
		(start 118.311676 -416.260788)
		(end 118.504462 -416.240722)
		(width 0.14224)
		(layer "In11.Cu")
		(net "P5E_CPU1_P2_TX_BUF_C_DP<0>")
	)
	(segment
		(start 117.628162 -415.530538)
		(end 117.959886 -415.799524)
		(width 0.14224)
		(layer "In11.Cu")
		(net "P5E_CPU1_P2_TX_BUF_C_DP<0>")
	)
	(segment
		(start 117.435376 -415.550604)
		(end 117.628162 -415.530538)
		(width 0.14224)
		(layer "In11.Cu")
		(net "P5E_CPU1_P2_TX_BUF_C_DP<0>")
	)
	(segment
		(start 119.732806 -417.412678)
		(end 123.65228 -420.589202)
		(width 0.14224)
		(layer "In11.Cu")
		(net "P5E_CPU1_P2_TX_BUF_C_DP<0>")
	)
	(segment
		(start 115.51412 -413.993584)
		(end 116.559076 -414.84042)
		(width 0.14224)
		(layer "In11.Cu")
		(net "P5E_CPU1_P2_TX_BUF_C_DP<0>")
	)
	(segment
		(start 124.595382 -430.125632)
		(end 125.622812 -430.125632)
		(width 0.14224)
		(layer "In11.Cu")
		(net "P5E_CPU1_P2_TX_BUF_C_DP<0>")
	)
	(segment
		(start 118.504462 -416.240722)
		(end 118.836186 -416.509708)
		(width 0.14224)
		(layer "In11.Cu")
		(net "P5E_CPU1_P2_TX_BUF_C_DP<0>")
	)
	(segment
		(start 117.980206 -415.99231)
		(end 118.311676 -416.260788)
		(width 0.14224)
		(layer "In11.Cu")
		(net "P5E_CPU1_P2_TX_BUF_C_DP<0>")
	)
	(segment
		(start 119.187976 -416.970972)
		(end 119.380762 -416.950906)
		(width 0.14224)
		(layer "In11.Cu")
		(net "P5E_CPU1_P2_TX_BUF_C_DP<0>")
	)
	(segment
		(start 117.08384 -415.089086)
		(end 117.103906 -415.282126)
		(width 0.14224)
		(layer "In11.Cu")
		(net "P5E_CPU1_P2_TX_BUF_C_DP<0>")
	)
	(segment
		(start 119.712486 -417.219892)
		(end 119.732806 -417.412678)
		(width 0.14224)
		(layer "In11.Cu")
		(net "P5E_CPU1_P2_TX_BUF_C_DP<0>")
	)
	(segment
		(start 124.401072 -429.931322)
		(end 124.595382 -430.125632)
		(width 0.14224)
		(layer "In11.Cu")
		(net "P5E_CPU1_P2_TX_BUF_C_DP<0>")
	)
	(segment
		(start 125.749812 -429.998632)
		(end 125.749812 -429.689768)
		(width 0.14224)
		(layer "In11.Cu")
		(net "P5E_CPU1_P2_TX_BUF_C_DP<0>")
	)
	(segment
		(start 117.959886 -415.799524)
		(end 117.980206 -415.99231)
		(width 0.14224)
		(layer "In11.Cu")
		(net "P5E_CPU1_P2_TX_BUF_C_DP<0>")
	)
	(segment
		(start 115.757706 -412.570168)
		(end 115.466876 -412.860998)
		(width 0.14224)
		(layer "In11.Cu")
		(net "P5E_CPU1_P2_TX_BUF_C_DP<0>")
	)
	(segment
		(start 123.65228 -420.589202)
		(end 124.401072 -423.57929)
		(width 0.14224)
		(layer "In11.Cu")
		(net "P5E_CPU1_P2_TX_BUF_C_DP<0>")
	)
	(segment
		(start 116.559076 -414.84042)
		(end 116.752116 -414.820354)
		(width 0.14224)
		(layer "In11.Cu")
		(net "P5E_CPU1_P2_TX_BUF_C_DP<0>")
	)
	(segment
		(start 118.856506 -416.702494)
		(end 119.187976 -416.970972)
		(width 0.14224)
		(layer "In11.Cu")
		(net "P5E_CPU1_P2_TX_BUF_C_DP<0>")
	)
	(segment
		(start 119.380762 -416.950906)
		(end 119.712486 -417.219892)
		(width 0.14224)
		(layer "In11.Cu")
		(net "P5E_CPU1_P2_TX_BUF_C_DP<0>")
	)
	(segment
		(start 118.836186 -416.509708)
		(end 118.856506 -416.702494)
		(width 0.14224)
		(layer "In11.Cu")
		(net "P5E_CPU1_P2_TX_BUF_C_DP<0>")
	)
	(segment
		(start 115.466876 -412.860998)
		(end 115.466876 -413.895032)
		(width 0.14224)
		(layer "In11.Cu")
		(net "P5E_CPU1_P2_TX_BUF_C_DP<0>")
	)
	(segment
		(start 116.752116 -414.820354)
		(end 117.08384 -415.089086)
		(width 0.14224)
		(layer "In11.Cu")
		(net "P5E_CPU1_P2_TX_BUF_C_DP<0>")
	)
	(segment
		(start 117.103906 -415.282126)
		(end 117.435376 -415.550604)
		(width 0.14224)
		(layer "In11.Cu")
		(net "P5E_CPU1_P2_TX_BUF_C_DP<0>")
	)
	(segment
		(start 125.622812 -430.125632)
		(end 125.749812 -429.998632)
		(width 0.14224)
		(layer "In11.Cu")
		(net "P5E_CPU1_P2_TX_BUF_C_DP<0>")
	)
	(segment
		(start 124.401072 -423.57929)
		(end 124.401072 -429.931322)
		(width 0.14224)
		(layer "In11.Cu")
		(net "P5E_CPU1_P2_TX_BUF_C_DP<0>")
	)
	(arc
		(start 115.466876 -413.895032)
		(mid 115.479345 -413.949657)
		(end 115.51412 -413.993584)
		(width 0.14224)
		(layer "In11.Cu")
		(net "P5E_CPU1_P2_TX_BUF_C_DP<0>")
	)
	(segment
		(start 142.733776 -412.299658)
		(end 142.463266 -412.570168)
		(width 0.12954)
		(layer "F.Cu")
		(net "P5E_CPU1_P2_TX_BUF_C_DN<9>")
	)
	(segment
		(start 142.437866 -408.784044)
		(end 142.733776 -409.079954)
		(width 0.12954)
		(layer "F.Cu")
		(net "P5E_CPU1_P2_TX_BUF_C_DN<9>")
	)
	(segment
		(start 142.733776 -409.079954)
		(end 142.733776 -412.299658)
		(width 0.12954)
		(layer "F.Cu")
		(net "P5E_CPU1_P2_TX_BUF_C_DN<9>")
	)
	(segment
		(start 144.750028 -431.889916)
		(end 144.750028 -431.558192)
		(width 0.14224)
		(layer "In11.Cu")
		(net "P5E_CPU1_P2_TX_BUF_C_DN<9>")
	)
	(segment
		(start 144.101058 -431.430684)
		(end 143.78813 -431.117756)
		(width 0.14224)
		(layer "In11.Cu")
		(net "P5E_CPU1_P2_TX_BUF_C_DN<9>")
	)
	(segment
		(start 143.78813 -431.117756)
		(end 143.78813 -425.290234)
		(width 0.14224)
		(layer "In11.Cu")
		(net "P5E_CPU1_P2_TX_BUF_C_DN<9>")
	)
	(segment
		(start 143.78813 -425.290234)
		(end 142.981426 -417.097464)
		(width 0.14224)
		(layer "In11.Cu")
		(net "P5E_CPU1_P2_TX_BUF_C_DN<9>")
	)
	(segment
		(start 142.981172 -417.096448)
		(end 142.754096 -414.790636)
		(width 0.14224)
		(layer "In11.Cu")
		(net "P5E_CPU1_P2_TX_BUF_C_DN<9>")
	)
	(segment
		(start 144.62252 -431.430684)
		(end 144.101058 -431.430684)
		(width 0.14224)
		(layer "In11.Cu")
		(net "P5E_CPU1_P2_TX_BUF_C_DN<9>")
	)
	(segment
		(start 142.754096 -414.790636)
		(end 142.754096 -412.860998)
		(width 0.14224)
		(layer "In11.Cu")
		(net "P5E_CPU1_P2_TX_BUF_C_DN<9>")
	)
	(segment
		(start 142.754096 -412.860998)
		(end 142.463266 -412.570168)
		(width 0.14224)
		(layer "In11.Cu")
		(net "P5E_CPU1_P2_TX_BUF_C_DN<9>")
	)
	(segment
		(start 142.981426 -417.097464)
		(end 142.981172 -417.096448)
		(width 0.14224)
		(layer "In11.Cu")
		(net "P5E_CPU1_P2_TX_BUF_C_DN<9>")
	)
	(segment
		(start 144.750028 -431.558192)
		(end 144.62252 -431.430684)
		(width 0.14224)
		(layer "In11.Cu")
		(net "P5E_CPU1_P2_TX_BUF_C_DN<9>")
	)
	(segment
		(start 139.374626 -408.784044)
		(end 139.670536 -409.079954)
		(width 0.12954)
		(layer "F.Cu")
		(net "P5E_CPU1_P2_TX_BUF_C_DN<8>")
	)
	(segment
		(start 139.670536 -409.079954)
		(end 139.670536 -412.299658)
		(width 0.12954)
		(layer "F.Cu")
		(net "P5E_CPU1_P2_TX_BUF_C_DN<8>")
	)
	(segment
		(start 139.670536 -412.299658)
		(end 139.400026 -412.570168)
		(width 0.12954)
		(layer "F.Cu")
		(net "P5E_CPU1_P2_TX_BUF_C_DN<8>")
	)
	(segment
		(start 141.608556 -430.407572)
		(end 142.59941 -430.407572)
		(width 0.14224)
		(layer "In11.Cu")
		(net "P5E_CPU1_P2_TX_BUF_C_DN<8>")
	)
	(segment
		(start 139.955778 -416.459924)
		(end 139.956032 -416.460178)
		(width 0.14224)
		(layer "In11.Cu")
		(net "P5E_CPU1_P2_TX_BUF_C_DN<8>")
	)
	(segment
		(start 139.956032 -416.460178)
		(end 141.302232 -430.12995)
		(width 0.14224)
		(layer "In11.Cu")
		(net "P5E_CPU1_P2_TX_BUF_C_DN<8>")
	)
	(segment
		(start 139.690856 -413.760666)
		(end 139.914884 -416.042856)
		(width 0.14224)
		(layer "In11.Cu")
		(net "P5E_CPU1_P2_TX_BUF_C_DN<8>")
	)
	(segment
		(start 142.750032 -430.558194)
		(end 142.750032 -430.889918)
		(width 0.14224)
		(layer "In11.Cu")
		(net "P5E_CPU1_P2_TX_BUF_C_DN<8>")
	)
	(segment
		(start 139.400026 -412.570168)
		(end 139.690856 -412.860998)
		(width 0.14224)
		(layer "In11.Cu")
		(net "P5E_CPU1_P2_TX_BUF_C_DN<8>")
	)
	(segment
		(start 142.59941 -430.407572)
		(end 142.750032 -430.558194)
		(width 0.14224)
		(layer "In11.Cu")
		(net "P5E_CPU1_P2_TX_BUF_C_DN<8>")
	)
	(segment
		(start 139.690856 -412.860998)
		(end 139.690856 -413.760666)
		(width 0.14224)
		(layer "In11.Cu")
		(net "P5E_CPU1_P2_TX_BUF_C_DN<8>")
	)
	(segment
		(start 139.914884 -416.042856)
		(end 139.955778 -416.459924)
		(width 0.14224)
		(layer "In11.Cu")
		(net "P5E_CPU1_P2_TX_BUF_C_DN<8>")
	)
	(segment
		(start 141.302232 -430.12995)
		(end 141.608556 -430.407572)
		(width 0.14224)
		(layer "In11.Cu")
		(net "P5E_CPU1_P2_TX_BUF_C_DN<8>")
	)
	(segment
		(start 136.311386 -408.784044)
		(end 136.607296 -409.079954)
		(width 0.12954)
		(layer "F.Cu")
		(net "P5E_CPU1_P2_TX_BUF_C_DN<7>")
	)
	(segment
		(start 136.607296 -409.079954)
		(end 136.607296 -412.299658)
		(width 0.12954)
		(layer "F.Cu")
		(net "P5E_CPU1_P2_TX_BUF_C_DN<7>")
	)
	(segment
		(start 136.607296 -412.299658)
		(end 136.336786 -412.570168)
		(width 0.12954)
		(layer "F.Cu")
		(net "P5E_CPU1_P2_TX_BUF_C_DN<7>")
	)
	(segment
		(start 137.33526 -417.276026)
		(end 136.627616 -413.478218)
		(width 0.14224)
		(layer "In11.Cu")
		(net "P5E_CPU1_P2_TX_BUF_C_DN<7>")
	)
	(segment
		(start 138.787886 -425.071794)
		(end 137.33526 -417.276534)
		(width 0.14224)
		(layer "In11.Cu")
		(net "P5E_CPU1_P2_TX_BUF_C_DN<7>")
	)
	(segment
		(start 136.627616 -412.860998)
		(end 136.336786 -412.570168)
		(width 0.14224)
		(layer "In11.Cu")
		(net "P5E_CPU1_P2_TX_BUF_C_DN<7>")
	)
	(segment
		(start 139.749784 -431.558192)
		(end 139.622276 -431.430684)
		(width 0.14224)
		(layer "In11.Cu")
		(net "P5E_CPU1_P2_TX_BUF_C_DN<7>")
	)
	(segment
		(start 136.627616 -413.478218)
		(end 136.627616 -412.860998)
		(width 0.14224)
		(layer "In11.Cu")
		(net "P5E_CPU1_P2_TX_BUF_C_DN<7>")
	)
	(segment
		(start 139.100814 -431.430684)
		(end 138.787886 -431.117756)
		(width 0.14224)
		(layer "In11.Cu")
		(net "P5E_CPU1_P2_TX_BUF_C_DN<7>")
	)
	(segment
		(start 137.33526 -417.276534)
		(end 137.33526 -417.276026)
		(width 0.14224)
		(layer "In11.Cu")
		(net "P5E_CPU1_P2_TX_BUF_C_DN<7>")
	)
	(segment
		(start 139.622276 -431.430684)
		(end 139.100814 -431.430684)
		(width 0.14224)
		(layer "In11.Cu")
		(net "P5E_CPU1_P2_TX_BUF_C_DN<7>")
	)
	(segment
		(start 139.749784 -431.889916)
		(end 139.749784 -431.558192)
		(width 0.14224)
		(layer "In11.Cu")
		(net "P5E_CPU1_P2_TX_BUF_C_DN<7>")
	)
	(segment
		(start 138.787886 -431.117756)
		(end 138.787886 -425.071794)
		(width 0.14224)
		(layer "In11.Cu")
		(net "P5E_CPU1_P2_TX_BUF_C_DN<7>")
	)
	(segment
		(start 133.544056 -412.299658)
		(end 133.273546 -412.570168)
		(width 0.12954)
		(layer "F.Cu")
		(net "P5E_CPU1_P2_TX_BUF_C_DN<6>")
	)
	(segment
		(start 133.248146 -408.784044)
		(end 133.544056 -409.079954)
		(width 0.12954)
		(layer "F.Cu")
		(net "P5E_CPU1_P2_TX_BUF_C_DN<6>")
	)
	(segment
		(start 133.544056 -409.079954)
		(end 133.544056 -412.299658)
		(width 0.12954)
		(layer "F.Cu")
		(net "P5E_CPU1_P2_TX_BUF_C_DN<6>")
	)
	(segment
		(start 136.78789 -430.03216)
		(end 136.78789 -426.281596)
		(width 0.14224)
		(layer "In11.Cu")
		(net "P5E_CPU1_P2_TX_BUF_C_DN<6>")
	)
	(segment
		(start 137.163302 -430.407572)
		(end 136.78789 -430.03216)
		(width 0.14224)
		(layer "In11.Cu")
		(net "P5E_CPU1_P2_TX_BUF_C_DN<6>")
	)
	(segment
		(start 137.749788 -430.889918)
		(end 137.749788 -430.558194)
		(width 0.14224)
		(layer "In11.Cu")
		(net "P5E_CPU1_P2_TX_BUF_C_DN<6>")
	)
	(segment
		(start 137.599166 -430.407572)
		(end 137.163302 -430.407572)
		(width 0.14224)
		(layer "In11.Cu")
		(net "P5E_CPU1_P2_TX_BUF_C_DN<6>")
	)
	(segment
		(start 133.564376 -412.860998)
		(end 133.273546 -412.570168)
		(width 0.14224)
		(layer "In11.Cu")
		(net "P5E_CPU1_P2_TX_BUF_C_DN<6>")
	)
	(segment
		(start 133.564376 -413.412686)
		(end 133.564376 -412.860998)
		(width 0.14224)
		(layer "In11.Cu")
		(net "P5E_CPU1_P2_TX_BUF_C_DN<6>")
	)
	(segment
		(start 137.749788 -430.558194)
		(end 137.599166 -430.407572)
		(width 0.14224)
		(layer "In11.Cu")
		(net "P5E_CPU1_P2_TX_BUF_C_DN<6>")
	)
	(segment
		(start 136.78789 -426.281596)
		(end 133.564376 -413.412686)
		(width 0.14224)
		(layer "In11.Cu")
		(net "P5E_CPU1_P2_TX_BUF_C_DN<6>")
	)
	(segment
		(start 130.480816 -409.079954)
		(end 130.480816 -412.299658)
		(width 0.12954)
		(layer "F.Cu")
		(net "P5E_CPU1_P2_TX_BUF_C_DN<5>")
	)
	(segment
		(start 130.184906 -408.784044)
		(end 130.480816 -409.079954)
		(width 0.12954)
		(layer "F.Cu")
		(net "P5E_CPU1_P2_TX_BUF_C_DN<5>")
	)
	(segment
		(start 130.480816 -412.299658)
		(end 130.210306 -412.570168)
		(width 0.12954)
		(layer "F.Cu")
		(net "P5E_CPU1_P2_TX_BUF_C_DN<5>")
	)
	(segment
		(start 134.787894 -431.117756)
		(end 135.100822 -431.430684)
		(width 0.14224)
		(layer "In11.Cu")
		(net "P5E_CPU1_P2_TX_BUF_C_DN<5>")
	)
	(segment
		(start 135.100822 -431.430684)
		(end 135.622284 -431.430684)
		(width 0.14224)
		(layer "In11.Cu")
		(net "P5E_CPU1_P2_TX_BUF_C_DN<5>")
	)
	(segment
		(start 131.627372 -416.64128)
		(end 131.62788 -416.641534)
		(width 0.14224)
		(layer "In11.Cu")
		(net "P5E_CPU1_P2_TX_BUF_C_DN<5>")
	)
	(segment
		(start 131.62788 -416.641534)
		(end 134.787894 -425.472606)
		(width 0.14224)
		(layer "In11.Cu")
		(net "P5E_CPU1_P2_TX_BUF_C_DN<5>")
	)
	(segment
		(start 131.143502 -415.288476)
		(end 131.143756 -415.289238)
		(width 0.14224)
		(layer "In11.Cu")
		(net "P5E_CPU1_P2_TX_BUF_C_DN<5>")
	)
	(segment
		(start 130.210306 -412.570168)
		(end 130.453638 -412.8135)
		(width 0.14224)
		(layer "In11.Cu")
		(net "P5E_CPU1_P2_TX_BUF_C_DN<5>")
	)
	(segment
		(start 134.787894 -425.472606)
		(end 134.787894 -431.117756)
		(width 0.14224)
		(layer "In11.Cu")
		(net "P5E_CPU1_P2_TX_BUF_C_DN<5>")
	)
	(segment
		(start 130.501136 -413.49295)
		(end 131.143502 -415.288476)
		(width 0.14224)
		(layer "In11.Cu")
		(net "P5E_CPU1_P2_TX_BUF_C_DN<5>")
	)
	(segment
		(start 131.143756 -415.289238)
		(end 131.627372 -416.64128)
		(width 0.14224)
		(layer "In11.Cu")
		(net "P5E_CPU1_P2_TX_BUF_C_DN<5>")
	)
	(segment
		(start 135.749792 -431.558192)
		(end 135.749792 -431.889916)
		(width 0.14224)
		(layer "In11.Cu")
		(net "P5E_CPU1_P2_TX_BUF_C_DN<5>")
	)
	(segment
		(start 135.622284 -431.430684)
		(end 135.749792 -431.558192)
		(width 0.14224)
		(layer "In11.Cu")
		(net "P5E_CPU1_P2_TX_BUF_C_DN<5>")
	)
	(segment
		(start 130.501136 -412.928054)
		(end 130.501136 -413.49295)
		(width 0.14224)
		(layer "In11.Cu")
		(net "P5E_CPU1_P2_TX_BUF_C_DN<5>")
	)
	(arc
		(start 130.453638 -412.8135)
		(mid 130.48881 -412.866044)
		(end 130.501136 -412.928054)
		(width 0.14224)
		(layer "In11.Cu")
		(net "P5E_CPU1_P2_TX_BUF_C_DN<5>")
	)
	(segment
		(start 127.121666 -408.784044)
		(end 127.417576 -409.079954)
		(width 0.12954)
		(layer "F.Cu")
		(net "P5E_CPU1_P2_TX_BUF_C_DN<4>")
	)
	(segment
		(start 127.417576 -412.299658)
		(end 127.147066 -412.570168)
		(width 0.12954)
		(layer "F.Cu")
		(net "P5E_CPU1_P2_TX_BUF_C_DN<4>")
	)
	(segment
		(start 127.417576 -409.079954)
		(end 127.417576 -412.299658)
		(width 0.12954)
		(layer "F.Cu")
		(net "P5E_CPU1_P2_TX_BUF_C_DN<4>")
	)
	(segment
		(start 133.599174 -430.407572)
		(end 133.749796 -430.558194)
		(width 0.14224)
		(layer "In11.Cu")
		(net "P5E_CPU1_P2_TX_BUF_C_DN<4>")
	)
	(segment
		(start 133.16331 -430.407572)
		(end 133.599174 -430.407572)
		(width 0.14224)
		(layer "In11.Cu")
		(net "P5E_CPU1_P2_TX_BUF_C_DN<4>")
	)
	(segment
		(start 127.147066 -412.570168)
		(end 127.437896 -412.860998)
		(width 0.14224)
		(layer "In11.Cu")
		(net "P5E_CPU1_P2_TX_BUF_C_DN<4>")
	)
	(segment
		(start 127.437896 -412.860998)
		(end 127.437896 -413.734758)
		(width 0.14224)
		(layer "In11.Cu")
		(net "P5E_CPU1_P2_TX_BUF_C_DN<4>")
	)
	(segment
		(start 133.749796 -430.558194)
		(end 133.749796 -430.889918)
		(width 0.14224)
		(layer "In11.Cu")
		(net "P5E_CPU1_P2_TX_BUF_C_DN<4>")
	)
	(segment
		(start 127.437896 -413.734758)
		(end 132.787898 -424.78071)
		(width 0.14224)
		(layer "In11.Cu")
		(net "P5E_CPU1_P2_TX_BUF_C_DN<4>")
	)
	(segment
		(start 132.787898 -430.03216)
		(end 133.16331 -430.407572)
		(width 0.14224)
		(layer "In11.Cu")
		(net "P5E_CPU1_P2_TX_BUF_C_DN<4>")
	)
	(segment
		(start 132.787898 -424.78071)
		(end 132.787898 -430.03216)
		(width 0.14224)
		(layer "In11.Cu")
		(net "P5E_CPU1_P2_TX_BUF_C_DN<4>")
	)
	(segment
		(start 124.354336 -412.299658)
		(end 124.083826 -412.570168)
		(width 0.12954)
		(layer "F.Cu")
		(net "P5E_CPU1_P2_TX_BUF_C_DN<3>")
	)
	(segment
		(start 124.354336 -409.079954)
		(end 124.354336 -412.299658)
		(width 0.12954)
		(layer "F.Cu")
		(net "P5E_CPU1_P2_TX_BUF_C_DN<3>")
	)
	(segment
		(start 124.058426 -408.784044)
		(end 124.354336 -409.079954)
		(width 0.12954)
		(layer "F.Cu")
		(net "P5E_CPU1_P2_TX_BUF_C_DN<3>")
	)
	(segment
		(start 131.622292 -431.430684)
		(end 131.10083 -431.430684)
		(width 0.14224)
		(layer "In11.Cu")
		(net "P5E_CPU1_P2_TX_BUF_C_DN<3>")
	)
	(segment
		(start 131.7498 -431.558192)
		(end 131.622292 -431.430684)
		(width 0.14224)
		(layer "In11.Cu")
		(net "P5E_CPU1_P2_TX_BUF_C_DN<3>")
	)
	(segment
		(start 124.374656 -413.795718)
		(end 124.374656 -412.860998)
		(width 0.14224)
		(layer "In11.Cu")
		(net "P5E_CPU1_P2_TX_BUF_C_DN<3>")
	)
	(segment
		(start 130.787902 -425.118022)
		(end 124.374656 -413.795718)
		(width 0.14224)
		(layer "In11.Cu")
		(net "P5E_CPU1_P2_TX_BUF_C_DN<3>")
	)
	(segment
		(start 124.374656 -412.860998)
		(end 124.083826 -412.570168)
		(width 0.14224)
		(layer "In11.Cu")
		(net "P5E_CPU1_P2_TX_BUF_C_DN<3>")
	)
	(segment
		(start 131.10083 -431.430684)
		(end 130.787902 -431.117756)
		(width 0.14224)
		(layer "In11.Cu")
		(net "P5E_CPU1_P2_TX_BUF_C_DN<3>")
	)
	(segment
		(start 131.7498 -431.889916)
		(end 131.7498 -431.558192)
		(width 0.14224)
		(layer "In11.Cu")
		(net "P5E_CPU1_P2_TX_BUF_C_DN<3>")
	)
	(segment
		(start 130.787902 -431.117756)
		(end 130.787902 -425.118022)
		(width 0.14224)
		(layer "In11.Cu")
		(net "P5E_CPU1_P2_TX_BUF_C_DN<3>")
	)
	(segment
		(start 120.995186 -408.784044)
		(end 121.291096 -409.079954)
		(width 0.12954)
		(layer "F.Cu")
		(net "P5E_CPU1_P2_TX_BUF_C_DN<2>")
	)
	(segment
		(start 121.291096 -409.079954)
		(end 121.291096 -412.299658)
		(width 0.12954)
		(layer "F.Cu")
		(net "P5E_CPU1_P2_TX_BUF_C_DN<2>")
	)
	(segment
		(start 121.291096 -412.299658)
		(end 121.020586 -412.570168)
		(width 0.12954)
		(layer "F.Cu")
		(net "P5E_CPU1_P2_TX_BUF_C_DN<2>")
	)
	(segment
		(start 121.854468 -414.219136)
		(end 121.854468 -414.218628)
		(width 0.14224)
		(layer "In11.Cu")
		(net "P5E_CPU1_P2_TX_BUF_C_DN<2>")
	)
	(segment
		(start 121.854468 -414.218628)
		(end 121.320052 -413.462216)
		(width 0.14224)
		(layer "In11.Cu")
		(net "P5E_CPU1_P2_TX_BUF_C_DN<2>")
	)
	(segment
		(start 129.749804 -430.558194)
		(end 129.622296 -430.430686)
		(width 0.14224)
		(layer "In11.Cu")
		(net "P5E_CPU1_P2_TX_BUF_C_DN<2>")
	)
	(segment
		(start 123.27509 -416.230054)
		(end 123.274836 -416.230054)
		(width 0.14224)
		(layer "In11.Cu")
		(net "P5E_CPU1_P2_TX_BUF_C_DN<2>")
	)
	(segment
		(start 121.320052 -413.462216)
		(end 121.320052 -412.869634)
		(width 0.14224)
		(layer "In11.Cu")
		(net "P5E_CPU1_P2_TX_BUF_C_DN<2>")
	)
	(segment
		(start 129.749804 -430.889918)
		(end 129.749804 -430.558194)
		(width 0.14224)
		(layer "In11.Cu")
		(net "P5E_CPU1_P2_TX_BUF_C_DN<2>")
	)
	(segment
		(start 121.320052 -412.869634)
		(end 121.020586 -412.570168)
		(width 0.14224)
		(layer "In11.Cu")
		(net "P5E_CPU1_P2_TX_BUF_C_DN<2>")
	)
	(segment
		(start 123.274836 -416.230054)
		(end 121.854468 -414.219136)
		(width 0.14224)
		(layer "In11.Cu")
		(net "P5E_CPU1_P2_TX_BUF_C_DN<2>")
	)
	(segment
		(start 128.787906 -430.117758)
		(end 128.787906 -424.033442)
		(width 0.14224)
		(layer "In11.Cu")
		(net "P5E_CPU1_P2_TX_BUF_C_DN<2>")
	)
	(segment
		(start 129.622296 -430.430686)
		(end 129.100834 -430.430686)
		(width 0.14224)
		(layer "In11.Cu")
		(net "P5E_CPU1_P2_TX_BUF_C_DN<2>")
	)
	(segment
		(start 128.787906 -424.033442)
		(end 123.27509 -416.230054)
		(width 0.14224)
		(layer "In11.Cu")
		(net "P5E_CPU1_P2_TX_BUF_C_DN<2>")
	)
	(segment
		(start 129.100834 -430.430686)
		(end 128.787906 -430.117758)
		(width 0.14224)
		(layer "In11.Cu")
		(net "P5E_CPU1_P2_TX_BUF_C_DN<2>")
	)
	(segment
		(start 118.227856 -409.079954)
		(end 118.227856 -412.299658)
		(width 0.12954)
		(layer "F.Cu")
		(net "P5E_CPU1_P2_TX_BUF_C_DN<1>")
	)
	(segment
		(start 117.931946 -408.784044)
		(end 118.227856 -409.079954)
		(width 0.12954)
		(layer "F.Cu")
		(net "P5E_CPU1_P2_TX_BUF_C_DN<1>")
	)
	(segment
		(start 118.227856 -412.299658)
		(end 117.957346 -412.570168)
		(width 0.12954)
		(layer "F.Cu")
		(net "P5E_CPU1_P2_TX_BUF_C_DN<1>")
	)
	(segment
		(start 126.78791 -431.117756)
		(end 127.100838 -431.430684)
		(width 0.14224)
		(layer "In11.Cu")
		(net "P5E_CPU1_P2_TX_BUF_C_DN<1>")
	)
	(segment
		(start 118.368064 -413.85363)
		(end 123.426728 -418.912294)
		(width 0.14224)
		(layer "In11.Cu")
		(net "P5E_CPU1_P2_TX_BUF_C_DN<1>")
	)
	(segment
		(start 126.78791 -425.174664)
		(end 126.78791 -431.117756)
		(width 0.14224)
		(layer "In11.Cu")
		(net "P5E_CPU1_P2_TX_BUF_C_DN<1>")
	)
	(segment
		(start 123.426728 -418.912294)
		(end 125.44552 -421.933624)
		(width 0.14224)
		(layer "In11.Cu")
		(net "P5E_CPU1_P2_TX_BUF_C_DN<1>")
	)
	(segment
		(start 118.248176 -412.860998)
		(end 118.248176 -413.564324)
		(width 0.14224)
		(layer "In11.Cu")
		(net "P5E_CPU1_P2_TX_BUF_C_DN<1>")
	)
	(segment
		(start 127.100838 -431.430684)
		(end 127.6223 -431.430684)
		(width 0.14224)
		(layer "In11.Cu")
		(net "P5E_CPU1_P2_TX_BUF_C_DN<1>")
	)
	(segment
		(start 125.44552 -421.933624)
		(end 126.78791 -425.174664)
		(width 0.14224)
		(layer "In11.Cu")
		(net "P5E_CPU1_P2_TX_BUF_C_DN<1>")
	)
	(segment
		(start 117.957346 -412.570168)
		(end 118.248176 -412.860998)
		(width 0.14224)
		(layer "In11.Cu")
		(net "P5E_CPU1_P2_TX_BUF_C_DN<1>")
	)
	(segment
		(start 127.749808 -431.558192)
		(end 127.749808 -431.889916)
		(width 0.14224)
		(layer "In11.Cu")
		(net "P5E_CPU1_P2_TX_BUF_C_DN<1>")
	)
	(segment
		(start 127.6223 -431.430684)
		(end 127.749808 -431.558192)
		(width 0.14224)
		(layer "In11.Cu")
		(net "P5E_CPU1_P2_TX_BUF_C_DN<1>")
	)
	(arc
		(start 118.248176 -413.564324)
		(mid 118.279339 -413.720902)
		(end 118.368064 -413.85363)
		(width 0.14224)
		(layer "In11.Cu")
		(net "P5E_CPU1_P2_TX_BUF_C_DN<1>")
	)
	(segment
		(start 161.113216 -412.299658)
		(end 160.842706 -412.570168)
		(width 0.12954)
		(layer "F.Cu")
		(net "P5E_CPU1_P2_TX_BUF_C_DN<15>")
	)
	(segment
		(start 160.817306 -408.784044)
		(end 161.113216 -409.079954)
		(width 0.12954)
		(layer "F.Cu")
		(net "P5E_CPU1_P2_TX_BUF_C_DN<15>")
	)
	(segment
		(start 161.113216 -409.079954)
		(end 161.113216 -412.299658)
		(width 0.12954)
		(layer "F.Cu")
		(net "P5E_CPU1_P2_TX_BUF_C_DN<15>")
	)
	(segment
		(start 156.101034 -431.430684)
		(end 156.622496 -431.430684)
		(width 0.14224)
		(layer "In11.Cu")
		(net "P5E_CPU1_P2_TX_BUF_C_DN<15>")
	)
	(segment
		(start 161.133536 -412.860998)
		(end 161.133536 -413.70377)
		(width 0.14224)
		(layer "In11.Cu")
		(net "P5E_CPU1_P2_TX_BUF_C_DN<15>")
	)
	(segment
		(start 160.547812 -415.676334)
		(end 158.457392 -420.095934)
		(width 0.14224)
		(layer "In11.Cu")
		(net "P5E_CPU1_P2_TX_BUF_C_DN<15>")
	)
	(segment
		(start 156.750004 -431.558192)
		(end 156.750004 -431.889916)
		(width 0.14224)
		(layer "In11.Cu")
		(net "P5E_CPU1_P2_TX_BUF_C_DN<15>")
	)
	(segment
		(start 161.121344 -413.785304)
		(end 160.547812 -415.676334)
		(width 0.14224)
		(layer "In11.Cu")
		(net "P5E_CPU1_P2_TX_BUF_C_DN<15>")
	)
	(segment
		(start 156.622496 -431.430684)
		(end 156.750004 -431.558192)
		(width 0.14224)
		(layer "In11.Cu")
		(net "P5E_CPU1_P2_TX_BUF_C_DN<15>")
	)
	(segment
		(start 161.133536 -413.70377)
		(end 161.133282 -413.70377)
		(width 0.14224)
		(layer "In11.Cu")
		(net "P5E_CPU1_P2_TX_BUF_C_DN<15>")
	)
	(segment
		(start 155.788106 -424.457876)
		(end 155.788106 -431.117756)
		(width 0.14224)
		(layer "In11.Cu")
		(net "P5E_CPU1_P2_TX_BUF_C_DN<15>")
	)
	(segment
		(start 160.842706 -412.570168)
		(end 161.133536 -412.860998)
		(width 0.14224)
		(layer "In11.Cu")
		(net "P5E_CPU1_P2_TX_BUF_C_DN<15>")
	)
	(segment
		(start 155.788106 -431.117756)
		(end 156.101034 -431.430684)
		(width 0.14224)
		(layer "In11.Cu")
		(net "P5E_CPU1_P2_TX_BUF_C_DN<15>")
	)
	(segment
		(start 158.457392 -420.095934)
		(end 155.99156 -423.786554)
		(width 0.14224)
		(layer "In11.Cu")
		(net "P5E_CPU1_P2_TX_BUF_C_DN<15>")
	)
	(arc
		(start 161.133282 -413.70377)
		(mid 161.130326 -413.744979)
		(end 161.121344 -413.785304)
		(width 0.14224)
		(layer "In11.Cu")
		(net "P5E_CPU1_P2_TX_BUF_C_DN<15>")
	)
	(arc
		(start 155.99156 -423.786554)
		(mid 155.840035 -424.107121)
		(end 155.788106 -424.457876)
		(width 0.14224)
		(layer "In11.Cu")
		(net "P5E_CPU1_P2_TX_BUF_C_DN<15>")
	)
	(segment
		(start 157.754066 -408.784044)
		(end 158.049976 -409.079954)
		(width 0.12954)
		(layer "F.Cu")
		(net "P5E_CPU1_P2_TX_BUF_C_DN<14>")
	)
	(segment
		(start 158.049976 -412.299658)
		(end 157.779466 -412.570168)
		(width 0.12954)
		(layer "F.Cu")
		(net "P5E_CPU1_P2_TX_BUF_C_DN<14>")
	)
	(segment
		(start 158.049976 -409.079954)
		(end 158.049976 -412.299658)
		(width 0.12954)
		(layer "F.Cu")
		(net "P5E_CPU1_P2_TX_BUF_C_DN<14>")
	)
	(segment
		(start 156.482034 -417.849812)
		(end 156.48178 -417.850574)
		(width 0.14224)
		(layer "In11.Cu")
		(net "P5E_CPU1_P2_TX_BUF_C_DN<14>")
	)
	(segment
		(start 156.000196 -419.014656)
		(end 154.429206 -422.501822)
		(width 0.14224)
		(layer "In11.Cu")
		(net "P5E_CPU1_P2_TX_BUF_C_DN<14>")
	)
	(segment
		(start 157.546802 -415.08934)
		(end 157.54604 -415.091626)
		(width 0.14224)
		(layer "In11.Cu")
		(net "P5E_CPU1_P2_TX_BUF_C_DN<14>")
	)
	(segment
		(start 158.070296 -413.561276)
		(end 158.070042 -413.561022)
		(width 0.14224)
		(layer "In11.Cu")
		(net "P5E_CPU1_P2_TX_BUF_C_DN<14>")
	)
	(segment
		(start 154.599386 -430.407572)
		(end 154.750008 -430.558194)
		(width 0.14224)
		(layer "In11.Cu")
		(net "P5E_CPU1_P2_TX_BUF_C_DN<14>")
	)
	(segment
		(start 154.163522 -430.407572)
		(end 154.599386 -430.407572)
		(width 0.14224)
		(layer "In11.Cu")
		(net "P5E_CPU1_P2_TX_BUF_C_DN<14>")
	)
	(segment
		(start 156.887672 -416.798252)
		(end 156.482034 -417.849812)
		(width 0.14224)
		(layer "In11.Cu")
		(net "P5E_CPU1_P2_TX_BUF_C_DN<14>")
	)
	(segment
		(start 153.78811 -430.03216)
		(end 154.163522 -430.407572)
		(width 0.14224)
		(layer "In11.Cu")
		(net "P5E_CPU1_P2_TX_BUF_C_DN<14>")
	)
	(segment
		(start 154.429206 -422.501822)
		(end 153.963624 -423.626788)
		(width 0.14224)
		(layer "In11.Cu")
		(net "P5E_CPU1_P2_TX_BUF_C_DN<14>")
	)
	(segment
		(start 154.750008 -430.558194)
		(end 154.750008 -430.889918)
		(width 0.14224)
		(layer "In11.Cu")
		(net "P5E_CPU1_P2_TX_BUF_C_DN<14>")
	)
	(segment
		(start 156.887926 -416.79749)
		(end 156.887672 -416.798252)
		(width 0.14224)
		(layer "In11.Cu")
		(net "P5E_CPU1_P2_TX_BUF_C_DN<14>")
	)
	(segment
		(start 156.000958 -419.014402)
		(end 156.000196 -419.014656)
		(width 0.14224)
		(layer "In11.Cu")
		(net "P5E_CPU1_P2_TX_BUF_C_DN<14>")
	)
	(segment
		(start 156.221176 -418.52596)
		(end 156.000958 -419.014402)
		(width 0.14224)
		(layer "In11.Cu")
		(net "P5E_CPU1_P2_TX_BUF_C_DN<14>")
	)
	(segment
		(start 157.779466 -412.570168)
		(end 158.070296 -412.860998)
		(width 0.14224)
		(layer "In11.Cu")
		(net "P5E_CPU1_P2_TX_BUF_C_DN<14>")
	)
	(segment
		(start 156.481272 -417.851336)
		(end 156.221176 -418.52596)
		(width 0.14224)
		(layer "In11.Cu")
		(net "P5E_CPU1_P2_TX_BUF_C_DN<14>")
	)
	(segment
		(start 153.78811 -424.509692)
		(end 153.78811 -430.03216)
		(width 0.14224)
		(layer "In11.Cu")
		(net "P5E_CPU1_P2_TX_BUF_C_DN<14>")
	)
	(segment
		(start 158.008574 -413.892746)
		(end 157.546548 -415.08934)
		(width 0.14224)
		(layer "In11.Cu")
		(net "P5E_CPU1_P2_TX_BUF_C_DN<14>")
	)
	(segment
		(start 158.070296 -412.860998)
		(end 158.070296 -413.561276)
		(width 0.14224)
		(layer "In11.Cu")
		(net "P5E_CPU1_P2_TX_BUF_C_DN<14>")
	)
	(segment
		(start 156.48178 -417.850574)
		(end 156.481272 -417.851336)
		(width 0.14224)
		(layer "In11.Cu")
		(net "P5E_CPU1_P2_TX_BUF_C_DN<14>")
	)
	(segment
		(start 157.54604 -415.091626)
		(end 156.887926 -416.79749)
		(width 0.14224)
		(layer "In11.Cu")
		(net "P5E_CPU1_P2_TX_BUF_C_DN<14>")
	)
	(segment
		(start 157.546548 -415.08934)
		(end 157.546802 -415.08934)
		(width 0.14224)
		(layer "In11.Cu")
		(net "P5E_CPU1_P2_TX_BUF_C_DN<14>")
	)
	(arc
		(start 158.070042 -413.561022)
		(mid 158.054648 -413.729728)
		(end 158.008574 -413.892746)
		(width 0.14224)
		(layer "In11.Cu")
		(net "P5E_CPU1_P2_TX_BUF_C_DN<14>")
	)
	(arc
		(start 153.963624 -423.626788)
		(mid 153.832423 -424.059603)
		(end 153.78811 -424.509692)
		(width 0.14224)
		(layer "In11.Cu")
		(net "P5E_CPU1_P2_TX_BUF_C_DN<14>")
	)
	(segment
		(start 154.986736 -409.079954)
		(end 154.986736 -412.299658)
		(width 0.12954)
		(layer "F.Cu")
		(net "P5E_CPU1_P2_TX_BUF_C_DN<13>")
	)
	(segment
		(start 154.986736 -412.299658)
		(end 154.716226 -412.570168)
		(width 0.12954)
		(layer "F.Cu")
		(net "P5E_CPU1_P2_TX_BUF_C_DN<13>")
	)
	(segment
		(start 154.690826 -408.784044)
		(end 154.986736 -409.079954)
		(width 0.12954)
		(layer "F.Cu")
		(net "P5E_CPU1_P2_TX_BUF_C_DN<13>")
	)
	(segment
		(start 154.691588 -415.172398)
		(end 154.367484 -416.241484)
		(width 0.14224)
		(layer "In11.Cu")
		(net "P5E_CPU1_P2_TX_BUF_C_DN<13>")
	)
	(segment
		(start 154.872436 -414.604454)
		(end 154.87142 -414.607502)
		(width 0.14224)
		(layer "In11.Cu")
		(net "P5E_CPU1_P2_TX_BUF_C_DN<13>")
	)
	(segment
		(start 154.372564 -416.25139)
		(end 154.203146 -416.810444)
		(width 0.14224)
		(layer "In11.Cu")
		(net "P5E_CPU1_P2_TX_BUF_C_DN<13>")
	)
	(segment
		(start 155.007056 -412.860998)
		(end 155.007056 -414.048956)
		(width 0.14224)
		(layer "In11.Cu")
		(net "P5E_CPU1_P2_TX_BUF_C_DN<13>")
	)
	(segment
		(start 154.87142 -414.607502)
		(end 154.701494 -415.167064)
		(width 0.14224)
		(layer "In11.Cu")
		(net "P5E_CPU1_P2_TX_BUF_C_DN<13>")
	)
	(segment
		(start 151.788114 -431.097436)
		(end 152.121362 -431.430684)
		(width 0.14224)
		(layer "In11.Cu")
		(net "P5E_CPU1_P2_TX_BUF_C_DN<13>")
	)
	(segment
		(start 153.416 -419.405308)
		(end 152.117298 -423.03446)
		(width 0.14224)
		(layer "In11.Cu")
		(net "P5E_CPU1_P2_TX_BUF_C_DN<13>")
	)
	(segment
		(start 152.622504 -431.430684)
		(end 152.750012 -431.558192)
		(width 0.14224)
		(layer "In11.Cu")
		(net "P5E_CPU1_P2_TX_BUF_C_DN<13>")
	)
	(segment
		(start 152.121362 -431.430684)
		(end 152.622504 -431.430684)
		(width 0.14224)
		(layer "In11.Cu")
		(net "P5E_CPU1_P2_TX_BUF_C_DN<13>")
	)
	(segment
		(start 154.974544 -414.267396)
		(end 154.872436 -414.604454)
		(width 0.14224)
		(layer "In11.Cu")
		(net "P5E_CPU1_P2_TX_BUF_C_DN<13>")
	)
	(segment
		(start 151.788114 -424.931586)
		(end 151.788114 -431.097436)
		(width 0.14224)
		(layer "In11.Cu")
		(net "P5E_CPU1_P2_TX_BUF_C_DN<13>")
	)
	(segment
		(start 154.202892 -416.810952)
		(end 153.416 -419.405308)
		(width 0.14224)
		(layer "In11.Cu")
		(net "P5E_CPU1_P2_TX_BUF_C_DN<13>")
	)
	(segment
		(start 154.701494 -415.167064)
		(end 154.691588 -415.172398)
		(width 0.14224)
		(layer "In11.Cu")
		(net "P5E_CPU1_P2_TX_BUF_C_DN<13>")
	)
	(segment
		(start 154.367484 -416.241484)
		(end 154.372564 -416.25139)
		(width 0.14224)
		(layer "In11.Cu")
		(net "P5E_CPU1_P2_TX_BUF_C_DN<13>")
	)
	(segment
		(start 152.750012 -431.558192)
		(end 152.750012 -431.889916)
		(width 0.14224)
		(layer "In11.Cu")
		(net "P5E_CPU1_P2_TX_BUF_C_DN<13>")
	)
	(segment
		(start 154.203146 -416.810444)
		(end 154.202892 -416.810952)
		(width 0.14224)
		(layer "In11.Cu")
		(net "P5E_CPU1_P2_TX_BUF_C_DN<13>")
	)
	(segment
		(start 154.716226 -412.570168)
		(end 155.007056 -412.860998)
		(width 0.14224)
		(layer "In11.Cu")
		(net "P5E_CPU1_P2_TX_BUF_C_DN<13>")
	)
	(arc
		(start 152.117298 -423.03446)
		(mid 151.870994 -423.968846)
		(end 151.788114 -424.931586)
		(width 0.14224)
		(layer "In11.Cu")
		(net "P5E_CPU1_P2_TX_BUF_C_DN<13>")
	)
	(arc
		(start 155.007056 -414.048956)
		(mid 154.998845 -414.159373)
		(end 154.974544 -414.267396)
		(width 0.14224)
		(layer "In11.Cu")
		(net "P5E_CPU1_P2_TX_BUF_C_DN<13>")
	)
	(segment
		(start 151.627586 -408.784044)
		(end 151.923496 -409.079954)
		(width 0.12954)
		(layer "F.Cu")
		(net "P5E_CPU1_P2_TX_BUF_C_DN<12>")
	)
	(segment
		(start 151.923496 -412.299658)
		(end 151.652986 -412.570168)
		(width 0.12954)
		(layer "F.Cu")
		(net "P5E_CPU1_P2_TX_BUF_C_DN<12>")
	)
	(segment
		(start 151.923496 -409.079954)
		(end 151.923496 -412.299658)
		(width 0.12954)
		(layer "F.Cu")
		(net "P5E_CPU1_P2_TX_BUF_C_DN<12>")
	)
	(segment
		(start 151.943816 -412.860998)
		(end 151.943816 -413.719264)
		(width 0.14224)
		(layer "In11.Cu")
		(net "P5E_CPU1_P2_TX_BUF_C_DN<12>")
	)
	(segment
		(start 149.788118 -430.03216)
		(end 150.16353 -430.407572)
		(width 0.14224)
		(layer "In11.Cu")
		(net "P5E_CPU1_P2_TX_BUF_C_DN<12>")
	)
	(segment
		(start 151.937212 -413.776668)
		(end 151.61006 -415.234374)
		(width 0.14224)
		(layer "In11.Cu")
		(net "P5E_CPU1_P2_TX_BUF_C_DN<12>")
	)
	(segment
		(start 150.599394 -430.407572)
		(end 150.750016 -430.558194)
		(width 0.14224)
		(layer "In11.Cu")
		(net "P5E_CPU1_P2_TX_BUF_C_DN<12>")
	)
	(segment
		(start 151.937212 -413.776414)
		(end 151.937212 -413.776668)
		(width 0.14224)
		(layer "In11.Cu")
		(net "P5E_CPU1_P2_TX_BUF_C_DN<12>")
	)
	(segment
		(start 151.456136 -415.919412)
		(end 151.28494 -416.682174)
		(width 0.14224)
		(layer "In11.Cu")
		(net "P5E_CPU1_P2_TX_BUF_C_DN<12>")
	)
	(segment
		(start 149.788118 -423.974768)
		(end 149.788118 -430.03216)
		(width 0.14224)
		(layer "In11.Cu")
		(net "P5E_CPU1_P2_TX_BUF_C_DN<12>")
	)
	(segment
		(start 151.284686 -416.68319)
		(end 151.130762 -417.368482)
		(width 0.14224)
		(layer "In11.Cu")
		(net "P5E_CPU1_P2_TX_BUF_C_DN<12>")
	)
	(segment
		(start 150.750016 -430.558194)
		(end 150.750016 -430.889918)
		(width 0.14224)
		(layer "In11.Cu")
		(net "P5E_CPU1_P2_TX_BUF_C_DN<12>")
	)
	(segment
		(start 151.61006 -415.234374)
		(end 151.609806 -415.23539)
		(width 0.14224)
		(layer "In11.Cu")
		(net "P5E_CPU1_P2_TX_BUF_C_DN<12>")
	)
	(segment
		(start 151.130762 -417.368482)
		(end 151.130508 -417.369498)
		(width 0.14224)
		(layer "In11.Cu")
		(net "P5E_CPU1_P2_TX_BUF_C_DN<12>")
	)
	(segment
		(start 151.45639 -415.918396)
		(end 151.456136 -415.919412)
		(width 0.14224)
		(layer "In11.Cu")
		(net "P5E_CPU1_P2_TX_BUF_C_DN<12>")
	)
	(segment
		(start 151.130508 -417.369498)
		(end 149.925532 -422.73474)
		(width 0.14224)
		(layer "In11.Cu")
		(net "P5E_CPU1_P2_TX_BUF_C_DN<12>")
	)
	(segment
		(start 150.16353 -430.407572)
		(end 150.599394 -430.407572)
		(width 0.14224)
		(layer "In11.Cu")
		(net "P5E_CPU1_P2_TX_BUF_C_DN<12>")
	)
	(segment
		(start 151.28494 -416.682174)
		(end 151.284686 -416.68319)
		(width 0.14224)
		(layer "In11.Cu")
		(net "P5E_CPU1_P2_TX_BUF_C_DN<12>")
	)
	(segment
		(start 151.609806 -415.23539)
		(end 151.45639 -415.918396)
		(width 0.14224)
		(layer "In11.Cu")
		(net "P5E_CPU1_P2_TX_BUF_C_DN<12>")
	)
	(segment
		(start 151.652986 -412.570168)
		(end 151.943816 -412.860998)
		(width 0.14224)
		(layer "In11.Cu")
		(net "P5E_CPU1_P2_TX_BUF_C_DN<12>")
	)
	(arc
		(start 149.925532 -422.73474)
		(mid 149.822548 -423.350956)
		(end 149.788118 -423.974768)
		(width 0.14224)
		(layer "In11.Cu")
		(net "P5E_CPU1_P2_TX_BUF_C_DN<12>")
	)
	(arc
		(start 151.943816 -413.719264)
		(mid 151.942084 -413.74802)
		(end 151.937212 -413.776414)
		(width 0.14224)
		(layer "In11.Cu")
		(net "P5E_CPU1_P2_TX_BUF_C_DN<12>")
	)
	(segment
		(start 148.860256 -412.299658)
		(end 148.589746 -412.570168)
		(width 0.12954)
		(layer "F.Cu")
		(net "P5E_CPU1_P2_TX_BUF_C_DN<11>")
	)
	(segment
		(start 148.564346 -408.784044)
		(end 148.860256 -409.079954)
		(width 0.12954)
		(layer "F.Cu")
		(net "P5E_CPU1_P2_TX_BUF_C_DN<11>")
	)
	(segment
		(start 148.860256 -409.079954)
		(end 148.860256 -412.299658)
		(width 0.12954)
		(layer "F.Cu")
		(net "P5E_CPU1_P2_TX_BUF_C_DN<11>")
	)
	(segment
		(start 147.788122 -431.117756)
		(end 147.788122 -425.114974)
		(width 0.14224)
		(layer "In11.Cu")
		(net "P5E_CPU1_P2_TX_BUF_C_DN<11>")
	)
	(segment
		(start 148.535136 -417.510214)
		(end 148.535644 -417.50996)
		(width 0.14224)
		(layer "In11.Cu")
		(net "P5E_CPU1_P2_TX_BUF_C_DN<11>")
	)
	(segment
		(start 148.589492 -416.967416)
		(end 148.880322 -414.0073)
		(width 0.14224)
		(layer "In11.Cu")
		(net "P5E_CPU1_P2_TX_BUF_C_DN<11>")
	)
	(segment
		(start 148.613114 -431.421286)
		(end 148.091652 -431.421286)
		(width 0.14224)
		(layer "In11.Cu")
		(net "P5E_CPU1_P2_TX_BUF_C_DN<11>")
	)
	(segment
		(start 148.75002 -431.889916)
		(end 148.75002 -431.558192)
		(width 0.14224)
		(layer "In11.Cu")
		(net "P5E_CPU1_P2_TX_BUF_C_DN<11>")
	)
	(segment
		(start 148.091652 -431.421286)
		(end 147.788122 -431.117756)
		(width 0.14224)
		(layer "In11.Cu")
		(net "P5E_CPU1_P2_TX_BUF_C_DN<11>")
	)
	(segment
		(start 147.788122 -425.114974)
		(end 148.535136 -417.510214)
		(width 0.14224)
		(layer "In11.Cu")
		(net "P5E_CPU1_P2_TX_BUF_C_DN<11>")
	)
	(segment
		(start 148.75002 -431.558192)
		(end 148.613114 -431.421286)
		(width 0.14224)
		(layer "In11.Cu")
		(net "P5E_CPU1_P2_TX_BUF_C_DN<11>")
	)
	(segment
		(start 148.535644 -417.50996)
		(end 148.589492 -416.967416)
		(width 0.14224)
		(layer "In11.Cu")
		(net "P5E_CPU1_P2_TX_BUF_C_DN<11>")
	)
	(segment
		(start 148.880576 -412.860998)
		(end 148.589746 -412.570168)
		(width 0.14224)
		(layer "In11.Cu")
		(net "P5E_CPU1_P2_TX_BUF_C_DN<11>")
	)
	(segment
		(start 148.880322 -414.0073)
		(end 148.880576 -414.007046)
		(width 0.14224)
		(layer "In11.Cu")
		(net "P5E_CPU1_P2_TX_BUF_C_DN<11>")
	)
	(segment
		(start 148.880576 -414.007046)
		(end 148.880576 -412.860998)
		(width 0.14224)
		(layer "In11.Cu")
		(net "P5E_CPU1_P2_TX_BUF_C_DN<11>")
	)
	(segment
		(start 145.501106 -408.784044)
		(end 145.797016 -409.079954)
		(width 0.12954)
		(layer "F.Cu")
		(net "P5E_CPU1_P2_TX_BUF_C_DN<10>")
	)
	(segment
		(start 145.797016 -409.079954)
		(end 145.797016 -412.299658)
		(width 0.12954)
		(layer "F.Cu")
		(net "P5E_CPU1_P2_TX_BUF_C_DN<10>")
	)
	(segment
		(start 145.797016 -412.299658)
		(end 145.526506 -412.570168)
		(width 0.12954)
		(layer "F.Cu")
		(net "P5E_CPU1_P2_TX_BUF_C_DN<10>")
	)
	(segment
		(start 145.805144 -412.848806)
		(end 145.805144 -430.049178)
		(width 0.14224)
		(layer "In11.Cu")
		(net "P5E_CPU1_P2_TX_BUF_C_DN<10>")
	)
	(segment
		(start 146.163538 -430.407572)
		(end 146.599402 -430.407572)
		(width 0.14224)
		(layer "In11.Cu")
		(net "P5E_CPU1_P2_TX_BUF_C_DN<10>")
	)
	(segment
		(start 145.526506 -412.570168)
		(end 145.805144 -412.848806)
		(width 0.14224)
		(layer "In11.Cu")
		(net "P5E_CPU1_P2_TX_BUF_C_DN<10>")
	)
	(segment
		(start 145.805144 -430.049178)
		(end 146.163538 -430.407572)
		(width 0.14224)
		(layer "In11.Cu")
		(net "P5E_CPU1_P2_TX_BUF_C_DN<10>")
	)
	(segment
		(start 146.599402 -430.407572)
		(end 146.750024 -430.558194)
		(width 0.14224)
		(layer "In11.Cu")
		(net "P5E_CPU1_P2_TX_BUF_C_DN<10>")
	)
	(segment
		(start 146.750024 -430.558194)
		(end 146.750024 -430.889918)
		(width 0.14224)
		(layer "In11.Cu")
		(net "P5E_CPU1_P2_TX_BUF_C_DN<10>")
	)
	(segment
		(start 115.164616 -412.299658)
		(end 114.894106 -412.570168)
		(width 0.12954)
		(layer "F.Cu")
		(net "P5E_CPU1_P2_TX_BUF_C_DN<0>")
	)
	(segment
		(start 114.868706 -408.784044)
		(end 115.164616 -409.079954)
		(width 0.12954)
		(layer "F.Cu")
		(net "P5E_CPU1_P2_TX_BUF_C_DN<0>")
	)
	(segment
		(start 115.164616 -409.079954)
		(end 115.164616 -412.299658)
		(width 0.12954)
		(layer "F.Cu")
		(net "P5E_CPU1_P2_TX_BUF_C_DN<0>")
	)
	(segment
		(start 124.119132 -423.614088)
		(end 124.119132 -430.048162)
		(width 0.14224)
		(layer "In11.Cu")
		(net "P5E_CPU1_P2_TX_BUF_C_DN<0>")
	)
	(segment
		(start 125.749812 -430.558194)
		(end 125.749812 -430.889918)
		(width 0.14224)
		(layer "In11.Cu")
		(net "P5E_CPU1_P2_TX_BUF_C_DN<0>")
	)
	(segment
		(start 114.894106 -412.570168)
		(end 115.184936 -412.860998)
		(width 0.14224)
		(layer "In11.Cu")
		(net "P5E_CPU1_P2_TX_BUF_C_DN<0>")
	)
	(segment
		(start 115.33632 -414.212786)
		(end 123.401582 -420.748968)
		(width 0.14224)
		(layer "In11.Cu")
		(net "P5E_CPU1_P2_TX_BUF_C_DN<0>")
	)
	(segment
		(start 124.478542 -430.407572)
		(end 125.59919 -430.407572)
		(width 0.14224)
		(layer "In11.Cu")
		(net "P5E_CPU1_P2_TX_BUF_C_DN<0>")
	)
	(segment
		(start 124.119132 -430.048162)
		(end 124.478542 -430.407572)
		(width 0.14224)
		(layer "In11.Cu")
		(net "P5E_CPU1_P2_TX_BUF_C_DN<0>")
	)
	(segment
		(start 115.184936 -412.860998)
		(end 115.184936 -413.895032)
		(width 0.14224)
		(layer "In11.Cu")
		(net "P5E_CPU1_P2_TX_BUF_C_DN<0>")
	)
	(segment
		(start 125.59919 -430.407572)
		(end 125.749812 -430.558194)
		(width 0.14224)
		(layer "In11.Cu")
		(net "P5E_CPU1_P2_TX_BUF_C_DN<0>")
	)
	(segment
		(start 123.401582 -420.748968)
		(end 124.119132 -423.614088)
		(width 0.14224)
		(layer "In11.Cu")
		(net "P5E_CPU1_P2_TX_BUF_C_DN<0>")
	)
	(arc
		(start 115.184936 -413.895032)
		(mid 115.224714 -414.07102)
		(end 115.33632 -414.212786)
		(width 0.14224)
		(layer "In11.Cu")
		(net "P5E_CPU1_P2_TX_BUF_C_DN<0>")
	)
	(segment
		(start 157.559248 -392.723878)
		(end 157.812486 -392.977116)
		(width 0.1016)
		(layer "F.Cu")
		(net "P5E_CPU1_P2_RX_BUF_DP<9>")
	)
	(segment
		(start 157.630368 -391.488676)
		(end 157.559248 -391.559796)
		(width 0.1016)
		(layer "F.Cu")
		(net "P5E_CPU1_P2_RX_BUF_DP<9>")
	)
	(segment
		(start 157.812486 -392.977116)
		(end 158.105602 -392.977116)
		(width 0.1016)
		(layer "F.Cu")
		(net "P5E_CPU1_P2_RX_BUF_DP<9>")
	)
	(segment
		(start 157.545786 -391.281158)
		(end 157.630368 -391.36574)
		(width 0.1016)
		(layer "F.Cu")
		(net "P5E_CPU1_P2_RX_BUF_DP<9>")
	)
	(segment
		(start 157.559248 -391.559796)
		(end 157.559248 -392.723878)
		(width 0.1016)
		(layer "F.Cu")
		(net "P5E_CPU1_P2_RX_BUF_DP<9>")
	)
	(segment
		(start 158.105602 -392.977116)
		(end 158.244286 -393.1158)
		(width 0.1016)
		(layer "F.Cu")
		(net "P5E_CPU1_P2_RX_BUF_DP<9>")
	)
	(segment
		(start 158.244286 -393.1158)
		(end 158.244286 -393.292838)
		(width 0.1016)
		(layer "F.Cu")
		(net "P5E_CPU1_P2_RX_BUF_DP<9>")
	)
	(segment
		(start 157.630368 -391.36574)
		(end 157.630368 -391.488676)
		(width 0.1016)
		(layer "F.Cu")
		(net "P5E_CPU1_P2_RX_BUF_DP<9>")
	)
	(segment
		(start 150.865078 -402.138134)
		(end 150.470616 -402.301456)
		(width 0.14224)
		(layer "In15.Cu")
		(net "P5E_CPU1_P2_RX_BUF_DP<9>")
	)
	(segment
		(start 157.785308 -393.159996)
		(end 157.785308 -395.537182)
		(width 0.14224)
		(layer "In15.Cu")
		(net "P5E_CPU1_P2_RX_BUF_DP<9>")
	)
	(segment
		(start 152.179274 -401.390358)
		(end 151.888698 -401.55495)
		(width 0.14224)
		(layer "In15.Cu")
		(net "P5E_CPU1_P2_RX_BUF_DP<9>")
	)
	(segment
		(start 157.927548 -393.017756)
		(end 157.785308 -393.159996)
		(width 0.14224)
		(layer "In15.Cu")
		(net "P5E_CPU1_P2_RX_BUF_DP<9>")
	)
	(segment
		(start 154.309826 -399.810732)
		(end 154.007566 -400.112738)
		(width 0.14224)
		(layer "In15.Cu")
		(net "P5E_CPU1_P2_RX_BUF_DP<9>")
	)
	(segment
		(start 146.236436 -407.669238)
		(end 146.236436 -408.095958)
		(width 0.14224)
		(layer "In15.Cu")
		(net "P5E_CPU1_P2_RX_BUF_DP<9>")
	)
	(segment
		(start 144.750028 -438.191148)
		(end 144.750028 -437.889904)
		(width 0.14224)
		(layer "In15.Cu")
		(net "P5E_CPU1_P2_RX_BUF_DP<9>")
	)
	(segment
		(start 144.2085 -438.341262)
		(end 144.599914 -438.341262)
		(width 0.14224)
		(layer "In15.Cu")
		(net "P5E_CPU1_P2_RX_BUF_DP<9>")
	)
	(segment
		(start 147.428458 -405.413464)
		(end 147.281646 -405.560276)
		(width 0.14224)
		(layer "In15.Cu")
		(net "P5E_CPU1_P2_RX_BUF_DP<9>")
	)
	(segment
		(start 144.071086 -418.21862)
		(end 144.208246 -418.35578)
		(width 0.14224)
		(layer "In15.Cu")
		(net "P5E_CPU1_P2_RX_BUF_DP<9>")
	)
	(segment
		(start 152.313894 -401.302474)
		(end 152.312116 -401.303744)
		(width 0.14224)
		(layer "In15.Cu")
		(net "P5E_CPU1_P2_RX_BUF_DP<9>")
	)
	(segment
		(start 144.208246 -418.35578)
		(end 144.208246 -418.7825)
		(width 0.14224)
		(layer "In15.Cu")
		(net "P5E_CPU1_P2_RX_BUF_DP<9>")
	)
	(segment
		(start 149.793452 -402.58238)
		(end 149.39899 -402.745702)
		(width 0.14224)
		(layer "In15.Cu")
		(net "P5E_CPU1_P2_RX_BUF_DP<9>")
	)
	(segment
		(start 150.291546 -402.227288)
		(end 149.86762 -402.402802)
		(width 0.14224)
		(layer "In15.Cu")
		(net "P5E_CPU1_P2_RX_BUF_DP<9>")
	)
	(segment
		(start 155.107386 -399.013426)
		(end 154.80538 -399.315432)
		(width 0.14224)
		(layer "In15.Cu")
		(net "P5E_CPU1_P2_RX_BUF_DP<9>")
	)
	(segment
		(start 146.099276 -406.638252)
		(end 146.099276 -407.532078)
		(width 0.14224)
		(layer "In15.Cu")
		(net "P5E_CPU1_P2_RX_BUF_DP<9>")
	)
	(segment
		(start 155.989274 -398.052544)
		(end 155.796234 -398.071594)
		(width 0.14224)
		(layer "In15.Cu")
		(net "P5E_CPU1_P2_RX_BUF_DP<9>")
	)
	(segment
		(start 149.39899 -402.745702)
		(end 149.21992 -402.67128)
		(width 0.14224)
		(layer "In15.Cu")
		(net "P5E_CPU1_P2_RX_BUF_DP<9>")
	)
	(segment
		(start 149.21992 -402.67128)
		(end 148.825712 -402.834602)
		(width 0.14224)
		(layer "In15.Cu")
		(net "P5E_CPU1_P2_RX_BUF_DP<9>")
	)
	(segment
		(start 144.567656 -411.84576)
		(end 144.567656 -413.863282)
		(width 0.14224)
		(layer "In15.Cu")
		(net "P5E_CPU1_P2_RX_BUF_DP<9>")
	)
	(segment
		(start 150.939246 -401.95881)
		(end 150.865078 -402.138134)
		(width 0.14224)
		(layer "In15.Cu")
		(net "P5E_CPU1_P2_RX_BUF_DP<9>")
	)
	(segment
		(start 147.281646 -405.560276)
		(end 146.966178 -405.771096)
		(width 0.14224)
		(layer "In15.Cu")
		(net "P5E_CPU1_P2_RX_BUF_DP<9>")
	)
	(segment
		(start 145.975578 -411.006798)
		(end 145.808192 -411.18282)
		(width 0.14224)
		(layer "In15.Cu")
		(net "P5E_CPU1_P2_RX_BUF_DP<9>")
	)
	(segment
		(start 155.796234 -398.071594)
		(end 155.525724 -398.401286)
		(width 0.14224)
		(layer "In15.Cu")
		(net "P5E_CPU1_P2_RX_BUF_DP<9>")
	)
	(segment
		(start 158.244286 -393.292838)
		(end 158.244286 -393.144756)
		(width 0.14224)
		(layer "In15.Cu")
		(net "P5E_CPU1_P2_RX_BUF_DP<9>")
	)
	(segment
		(start 157.385258 -396.13586)
		(end 156.241496 -397.529558)
		(width 0.14224)
		(layer "In15.Cu")
		(net "P5E_CPU1_P2_RX_BUF_DP<9>")
	)
	(segment
		(start 151.743664 -401.625562)
		(end 150.939246 -401.95881)
		(width 0.14224)
		(layer "In15.Cu")
		(net "P5E_CPU1_P2_RX_BUF_DP<9>")
	)
	(segment
		(start 154.309826 -399.61693)
		(end 154.309826 -399.810732)
		(width 0.14224)
		(layer "In15.Cu")
		(net "P5E_CPU1_P2_RX_BUF_DP<9>")
	)
	(segment
		(start 154.007566 -400.112738)
		(end 153.813764 -400.112738)
		(width 0.14224)
		(layer "In15.Cu")
		(net "P5E_CPU1_P2_RX_BUF_DP<9>")
	)
	(segment
		(start 144.208246 -417.22802)
		(end 144.208246 -417.65474)
		(width 0.14224)
		(layer "In15.Cu")
		(net "P5E_CPU1_P2_RX_BUF_DP<9>")
	)
	(segment
		(start 147.630896 -404.076154)
		(end 147.630896 -404.924514)
		(width 0.14224)
		(layer "In15.Cu")
		(net "P5E_CPU1_P2_RX_BUF_DP<9>")
	)
	(segment
		(start 144.599914 -438.341262)
		(end 144.750028 -438.191148)
		(width 0.14224)
		(layer "In15.Cu")
		(net "P5E_CPU1_P2_RX_BUF_DP<9>")
	)
	(segment
		(start 144.071086 -438.203848)
		(end 144.2085 -438.341262)
		(width 0.14224)
		(layer "In15.Cu")
		(net "P5E_CPU1_P2_RX_BUF_DP<9>")
	)
	(segment
		(start 144.208246 -418.7825)
		(end 144.071086 -418.91966)
		(width 0.14224)
		(layer "In15.Cu")
		(net "P5E_CPU1_P2_RX_BUF_DP<9>")
	)
	(segment
		(start 146.099276 -409.360878)
		(end 146.099276 -410.697172)
		(width 0.14224)
		(layer "In15.Cu")
		(net "P5E_CPU1_P2_RX_BUF_DP<9>")
	)
	(segment
		(start 150.470616 -402.301456)
		(end 150.291546 -402.227288)
		(width 0.14224)
		(layer "In15.Cu")
		(net "P5E_CPU1_P2_RX_BUF_DP<9>")
	)
	(segment
		(start 146.236436 -409.223718)
		(end 146.099276 -409.360878)
		(width 0.14224)
		(layer "In15.Cu")
		(net "P5E_CPU1_P2_RX_BUF_DP<9>")
	)
	(segment
		(start 144.208246 -417.65474)
		(end 144.071086 -417.7919)
		(width 0.14224)
		(layer "In15.Cu")
		(net "P5E_CPU1_P2_RX_BUF_DP<9>")
	)
	(segment
		(start 146.099276 -408.233118)
		(end 146.099276 -408.659838)
		(width 0.14224)
		(layer "In15.Cu")
		(net "P5E_CPU1_P2_RX_BUF_DP<9>")
	)
	(segment
		(start 158.244286 -393.144756)
		(end 158.117286 -393.017756)
		(width 0.14224)
		(layer "In15.Cu")
		(net "P5E_CPU1_P2_RX_BUF_DP<9>")
	)
	(segment
		(start 146.099276 -408.659838)
		(end 146.236436 -408.796998)
		(width 0.14224)
		(layer "In15.Cu")
		(net "P5E_CPU1_P2_RX_BUF_DP<9>")
	)
	(segment
		(start 146.966178 -405.771096)
		(end 146.690588 -405.885142)
		(width 0.14224)
		(layer "In15.Cu")
		(net "P5E_CPU1_P2_RX_BUF_DP<9>")
	)
	(segment
		(start 154.80538 -399.315432)
		(end 154.611578 -399.315432)
		(width 0.14224)
		(layer "In15.Cu")
		(net "P5E_CPU1_P2_RX_BUF_DP<9>")
	)
	(segment
		(start 153.813764 -400.112738)
		(end 153.512012 -400.414236)
		(width 0.14224)
		(layer "In15.Cu")
		(net "P5E_CPU1_P2_RX_BUF_DP<9>")
	)
	(segment
		(start 144.071086 -417.09086)
		(end 144.208246 -417.22802)
		(width 0.14224)
		(layer "In15.Cu")
		(net "P5E_CPU1_P2_RX_BUF_DP<9>")
	)
	(segment
		(start 149.86762 -402.402802)
		(end 149.793452 -402.58238)
		(width 0.14224)
		(layer "In15.Cu")
		(net "P5E_CPU1_P2_RX_BUF_DP<9>")
	)
	(segment
		(start 148.469604 -403.072854)
		(end 147.746212 -403.797516)
		(width 0.14224)
		(layer "In15.Cu")
		(net "P5E_CPU1_P2_RX_BUF_DP<9>")
	)
	(segment
		(start 154.611578 -399.315432)
		(end 154.309826 -399.61693)
		(width 0.14224)
		(layer "In15.Cu")
		(net "P5E_CPU1_P2_RX_BUF_DP<9>")
	)
	(segment
		(start 155.525724 -398.401286)
		(end 155.107386 -398.81937)
		(width 0.14224)
		(layer "In15.Cu")
		(net "P5E_CPU1_P2_RX_BUF_DP<9>")
	)
	(segment
		(start 144.071086 -417.7919)
		(end 144.071086 -418.21862)
		(width 0.14224)
		(layer "In15.Cu")
		(net "P5E_CPU1_P2_RX_BUF_DP<9>")
	)
	(segment
		(start 146.236436 -408.796998)
		(end 146.236436 -409.223718)
		(width 0.14224)
		(layer "In15.Cu")
		(net "P5E_CPU1_P2_RX_BUF_DP<9>")
	)
	(segment
		(start 157.785308 -395.537182)
		(end 157.385258 -396.13586)
		(width 0.14224)
		(layer "In15.Cu")
		(net "P5E_CPU1_P2_RX_BUF_DP<9>")
	)
	(segment
		(start 146.236436 -408.095958)
		(end 146.099276 -408.233118)
		(width 0.14224)
		(layer "In15.Cu")
		(net "P5E_CPU1_P2_RX_BUF_DP<9>")
	)
	(segment
		(start 155.107386 -398.81937)
		(end 155.107386 -399.013426)
		(width 0.14224)
		(layer "In15.Cu")
		(net "P5E_CPU1_P2_RX_BUF_DP<9>")
	)
	(segment
		(start 158.117286 -393.017756)
		(end 157.927548 -393.017756)
		(width 0.14224)
		(layer "In15.Cu")
		(net "P5E_CPU1_P2_RX_BUF_DP<9>")
	)
	(segment
		(start 144.071086 -418.91966)
		(end 144.071086 -438.203848)
		(width 0.14224)
		(layer "In15.Cu")
		(net "P5E_CPU1_P2_RX_BUF_DP<9>")
	)
	(segment
		(start 156.241496 -397.529558)
		(end 156.260292 -397.722598)
		(width 0.14224)
		(layer "In15.Cu")
		(net "P5E_CPU1_P2_RX_BUF_DP<9>")
	)
	(segment
		(start 144.071086 -415.062162)
		(end 144.071086 -417.09086)
		(width 0.14224)
		(layer "In15.Cu")
		(net "P5E_CPU1_P2_RX_BUF_DP<9>")
	)
	(segment
		(start 145.607786 -411.31998)
		(end 144.655286 -411.71495)
		(width 0.14224)
		(layer "In15.Cu")
		(net "P5E_CPU1_P2_RX_BUF_DP<9>")
	)
	(segment
		(start 146.099276 -407.532078)
		(end 146.236436 -407.669238)
		(width 0.14224)
		(layer "In15.Cu")
		(net "P5E_CPU1_P2_RX_BUF_DP<9>")
	)
	(segment
		(start 153.512012 -400.414236)
		(end 152.313894 -401.302474)
		(width 0.14224)
		(layer "In15.Cu")
		(net "P5E_CPU1_P2_RX_BUF_DP<9>")
	)
	(segment
		(start 156.260292 -397.722598)
		(end 155.989274 -398.052544)
		(width 0.14224)
		(layer "In15.Cu")
		(net "P5E_CPU1_P2_RX_BUF_DP<9>")
	)
	(arc
		(start 152.312116 -401.303744)
		(mid 152.246998 -401.349049)
		(end 152.179274 -401.390358)
		(width 0.14224)
		(layer "In15.Cu")
		(net "P5E_CPU1_P2_RX_BUF_DP<9>")
	)
	(arc
		(start 147.746212 -403.797516)
		(mid 147.660899 -403.925385)
		(end 147.630896 -404.076154)
		(width 0.14224)
		(layer "In15.Cu")
		(net "P5E_CPU1_P2_RX_BUF_DP<9>")
	)
	(arc
		(start 148.825712 -402.834602)
		(mid 148.635888 -402.936139)
		(end 148.469604 -403.072854)
		(width 0.14224)
		(layer "In15.Cu")
		(net "P5E_CPU1_P2_RX_BUF_DP<9>")
	)
	(arc
		(start 147.630896 -404.924514)
		(mid 147.578282 -405.189111)
		(end 147.428458 -405.413464)
		(width 0.14224)
		(layer "In15.Cu")
		(net "P5E_CPU1_P2_RX_BUF_DP<9>")
	)
	(arc
		(start 151.888698 -401.55495)
		(mid 151.817263 -401.592478)
		(end 151.743664 -401.625562)
		(width 0.14224)
		(layer "In15.Cu")
		(net "P5E_CPU1_P2_RX_BUF_DP<9>")
	)
	(arc
		(start 144.655286 -411.71495)
		(mid 144.591611 -411.767062)
		(end 144.567656 -411.84576)
		(width 0.14224)
		(layer "In15.Cu")
		(net "P5E_CPU1_P2_RX_BUF_DP<9>")
	)
	(arc
		(start 145.808192 -411.18282)
		(mid 145.715174 -411.261897)
		(end 145.607786 -411.31998)
		(width 0.14224)
		(layer "In15.Cu")
		(net "P5E_CPU1_P2_RX_BUF_DP<9>")
	)
	(arc
		(start 146.304254 -406.14346)
		(mid 146.152491 -406.370445)
		(end 146.099276 -406.638252)
		(width 0.14224)
		(layer "In15.Cu")
		(net "P5E_CPU1_P2_RX_BUF_DP<9>")
	)
	(arc
		(start 146.690588 -405.885142)
		(mid 146.484706 -405.995288)
		(end 146.304254 -406.14346)
		(width 0.14224)
		(layer "In15.Cu")
		(net "P5E_CPU1_P2_RX_BUF_DP<9>")
	)
	(arc
		(start 144.567656 -413.863282)
		(mid 144.493121 -414.237994)
		(end 144.28089 -414.555686)
		(width 0.14224)
		(layer "In15.Cu")
		(net "P5E_CPU1_P2_RX_BUF_DP<9>")
	)
	(arc
		(start 146.099276 -410.697172)
		(mid 146.067311 -410.86393)
		(end 145.975578 -411.006798)
		(width 0.14224)
		(layer "In15.Cu")
		(net "P5E_CPU1_P2_RX_BUF_DP<9>")
	)
	(arc
		(start 144.28089 -414.555686)
		(mid 144.125623 -414.788059)
		(end 144.071086 -415.062162)
		(width 0.14224)
		(layer "In15.Cu")
		(net "P5E_CPU1_P2_RX_BUF_DP<9>")
	)
	(segment
		(start 156.430218 -391.488676)
		(end 156.341572 -391.577322)
		(width 0.1016)
		(layer "F.Cu")
		(net "P5E_CPU1_P2_RX_BUF_DP<8>")
	)
	(segment
		(start 156.430218 -391.36574)
		(end 156.430218 -391.488676)
		(width 0.1016)
		(layer "F.Cu")
		(net "P5E_CPU1_P2_RX_BUF_DP<8>")
	)
	(segment
		(start 156.341572 -391.577322)
		(end 156.341572 -392.723878)
		(width 0.1016)
		(layer "F.Cu")
		(net "P5E_CPU1_P2_RX_BUF_DP<8>")
	)
	(segment
		(start 157.04439 -393.116054)
		(end 157.04439 -393.292838)
		(width 0.1016)
		(layer "F.Cu")
		(net "P5E_CPU1_P2_RX_BUF_DP<8>")
	)
	(segment
		(start 156.345636 -391.281158)
		(end 156.430218 -391.36574)
		(width 0.1016)
		(layer "F.Cu")
		(net "P5E_CPU1_P2_RX_BUF_DP<8>")
	)
	(segment
		(start 156.905452 -392.977116)
		(end 157.04439 -393.116054)
		(width 0.1016)
		(layer "F.Cu")
		(net "P5E_CPU1_P2_RX_BUF_DP<8>")
	)
	(segment
		(start 156.59481 -392.977116)
		(end 156.905452 -392.977116)
		(width 0.1016)
		(layer "F.Cu")
		(net "P5E_CPU1_P2_RX_BUF_DP<8>")
	)
	(segment
		(start 156.341572 -392.723878)
		(end 156.59481 -392.977116)
		(width 0.1016)
		(layer "F.Cu")
		(net "P5E_CPU1_P2_RX_BUF_DP<8>")
	)
	(segment
		(start 156.339794 -395.604746)
		(end 156.373068 -395.796008)
		(width 0.14224)
		(layer "In15.Cu")
		(net "P5E_CPU1_P2_RX_BUF_DP<8>")
	)
	(segment
		(start 141.504416 -422.463722)
		(end 141.641576 -422.600882)
		(width 0.14224)
		(layer "In15.Cu")
		(net "P5E_CPU1_P2_RX_BUF_DP<8>")
	)
	(segment
		(start 156.127196 -396.145004)
		(end 155.935934 -396.178278)
		(width 0.14224)
		(layer "In15.Cu")
		(net "P5E_CPU1_P2_RX_BUF_DP<8>")
	)
	(segment
		(start 146.619214 -402.570696)
		(end 146.225006 -402.734018)
		(width 0.14224)
		(layer "In15.Cu")
		(net "P5E_CPU1_P2_RX_BUF_DP<8>")
	)
	(segment
		(start 141.504416 -419.980364)
		(end 141.641576 -420.117524)
		(width 0.14224)
		(layer "In15.Cu")
		(net "P5E_CPU1_P2_RX_BUF_DP<8>")
	)
	(segment
		(start 144.365218 -405.413464)
		(end 144.218406 -405.560276)
		(width 0.14224)
		(layer "In15.Cu")
		(net "P5E_CPU1_P2_RX_BUF_DP<8>")
	)
	(segment
		(start 141.504416 -422.037002)
		(end 141.504416 -422.463722)
		(width 0.14224)
		(layer "In15.Cu")
		(net "P5E_CPU1_P2_RX_BUF_DP<8>")
	)
	(segment
		(start 157.04439 -393.292838)
		(end 157.04439 -393.144756)
		(width 0.14224)
		(layer "In15.Cu")
		(net "P5E_CPU1_P2_RX_BUF_DP<8>")
	)
	(segment
		(start 143.036036 -406.638252)
		(end 143.036036 -407.740358)
		(width 0.14224)
		(layer "In15.Cu")
		(net "P5E_CPU1_P2_RX_BUF_DP<8>")
	)
	(segment
		(start 141.641576 -421.473122)
		(end 141.641576 -421.899842)
		(width 0.14224)
		(layer "In15.Cu")
		(net "P5E_CPU1_P2_RX_BUF_DP<8>")
	)
	(segment
		(start 147.729194 -402.110702)
		(end 147.266914 -402.302218)
		(width 0.14224)
		(layer "In15.Cu")
		(net "P5E_CPU1_P2_RX_BUF_DP<8>")
	)
	(segment
		(start 144.567656 -404.05558)
		(end 144.567656 -404.924514)
		(width 0.14224)
		(layer "In15.Cu")
		(net "P5E_CPU1_P2_RX_BUF_DP<8>")
	)
	(segment
		(start 150.567644 -401.101814)
		(end 150.30958 -401.198842)
		(width 0.14224)
		(layer "In15.Cu")
		(net "P5E_CPU1_P2_RX_BUF_DP<8>")
	)
	(segment
		(start 141.641576 -422.600882)
		(end 141.641576 -423.027602)
		(width 0.14224)
		(layer "In15.Cu")
		(net "P5E_CPU1_P2_RX_BUF_DP<8>")
	)
	(segment
		(start 143.902938 -405.771096)
		(end 143.627348 -405.885142)
		(width 0.14224)
		(layer "In15.Cu")
		(net "P5E_CPU1_P2_RX_BUF_DP<8>")
	)
	(segment
		(start 141.504416 -423.164762)
		(end 141.504416 -423.591482)
		(width 0.14224)
		(layer "In15.Cu")
		(net "P5E_CPU1_P2_RX_BUF_DP<8>")
	)
	(segment
		(start 141.641576 -423.027602)
		(end 141.504416 -423.164762)
		(width 0.14224)
		(layer "In15.Cu")
		(net "P5E_CPU1_P2_RX_BUF_DP<8>")
	)
	(segment
		(start 141.504416 -421.335962)
		(end 141.641576 -421.473122)
		(width 0.14224)
		(layer "In15.Cu")
		(net "P5E_CPU1_P2_RX_BUF_DP<8>")
	)
	(segment
		(start 142.603982 -437.3372)
		(end 142.750032 -437.19115)
		(width 0.14224)
		(layer "In15.Cu")
		(net "P5E_CPU1_P2_RX_BUF_DP<8>")
	)
	(segment
		(start 141.504416 -424.292522)
		(end 141.504416 -436.642002)
		(width 0.14224)
		(layer "In15.Cu")
		(net "P5E_CPU1_P2_RX_BUF_DP<8>")
	)
	(segment
		(start 148.302726 -402.021548)
		(end 147.908264 -402.185124)
		(width 0.14224)
		(layer "In15.Cu")
		(net "P5E_CPU1_P2_RX_BUF_DP<8>")
	)
	(segment
		(start 141.504416 -420.681404)
		(end 141.504416 -421.335962)
		(width 0.14224)
		(layer "In15.Cu")
		(net "P5E_CPU1_P2_RX_BUF_DP<8>")
	)
	(segment
		(start 143.036036 -409.569158)
		(end 143.036036 -410.697172)
		(width 0.14224)
		(layer "In15.Cu")
		(net "P5E_CPU1_P2_RX_BUF_DP<8>")
	)
	(segment
		(start 156.585412 -393.159996)
		(end 156.585412 -395.256004)
		(width 0.14224)
		(layer "In15.Cu")
		(net "P5E_CPU1_P2_RX_BUF_DP<8>")
	)
	(segment
		(start 156.727652 -393.017756)
		(end 156.585412 -393.159996)
		(width 0.14224)
		(layer "In15.Cu")
		(net "P5E_CPU1_P2_RX_BUF_DP<8>")
	)
	(segment
		(start 141.641576 -424.155362)
		(end 141.504416 -424.292522)
		(width 0.14224)
		(layer "In15.Cu")
		(net "P5E_CPU1_P2_RX_BUF_DP<8>")
	)
	(segment
		(start 151.52624 -400.685508)
		(end 150.567644 -401.101814)
		(width 0.14224)
		(layer "In15.Cu")
		(net "P5E_CPU1_P2_RX_BUF_DP<8>")
	)
	(segment
		(start 141.641576 -421.899842)
		(end 141.504416 -422.037002)
		(width 0.14224)
		(layer "In15.Cu")
		(net "P5E_CPU1_P2_RX_BUF_DP<8>")
	)
	(segment
		(start 147.908264 -402.185124)
		(end 147.729194 -402.110702)
		(width 0.14224)
		(layer "In15.Cu")
		(net "P5E_CPU1_P2_RX_BUF_DP<8>")
	)
	(segment
		(start 148.376894 -401.842224)
		(end 148.302726 -402.021548)
		(width 0.14224)
		(layer "In15.Cu")
		(net "P5E_CPU1_P2_RX_BUF_DP<8>")
	)
	(segment
		(start 153.554938 -399.04797)
		(end 151.949912 -400.381724)
		(width 0.14224)
		(layer "In15.Cu")
		(net "P5E_CPU1_P2_RX_BUF_DP<8>")
	)
	(segment
		(start 147.192746 -402.481542)
		(end 146.798284 -402.645118)
		(width 0.14224)
		(layer "In15.Cu")
		(net "P5E_CPU1_P2_RX_BUF_DP<8>")
	)
	(segment
		(start 156.91739 -393.017756)
		(end 156.727652 -393.017756)
		(width 0.14224)
		(layer "In15.Cu")
		(net "P5E_CPU1_P2_RX_BUF_DP<8>")
	)
	(segment
		(start 146.798284 -402.645118)
		(end 146.619214 -402.570696)
		(width 0.14224)
		(layer "In15.Cu")
		(net "P5E_CPU1_P2_RX_BUF_DP<8>")
	)
	(segment
		(start 148.894546 -401.627848)
		(end 148.376894 -401.842224)
		(width 0.14224)
		(layer "In15.Cu")
		(net "P5E_CPU1_P2_RX_BUF_DP<8>")
	)
	(segment
		(start 143.036036 -408.868118)
		(end 143.173196 -409.005278)
		(width 0.14224)
		(layer "In15.Cu")
		(net "P5E_CPU1_P2_RX_BUF_DP<8>")
	)
	(segment
		(start 143.173196 -407.877518)
		(end 143.173196 -408.304238)
		(width 0.14224)
		(layer "In15.Cu")
		(net "P5E_CPU1_P2_RX_BUF_DP<8>")
	)
	(segment
		(start 143.173196 -408.304238)
		(end 143.036036 -408.441398)
		(width 0.14224)
		(layer "In15.Cu")
		(net "P5E_CPU1_P2_RX_BUF_DP<8>")
	)
	(segment
		(start 150.30958 -401.198842)
		(end 148.894546 -401.627848)
		(width 0.14224)
		(layer "In15.Cu")
		(net "P5E_CPU1_P2_RX_BUF_DP<8>")
	)
	(segment
		(start 141.641576 -423.728642)
		(end 141.641576 -424.155362)
		(width 0.14224)
		(layer "In15.Cu")
		(net "P5E_CPU1_P2_RX_BUF_DP<8>")
	)
	(segment
		(start 141.504416 -436.642002)
		(end 142.199614 -437.3372)
		(width 0.14224)
		(layer "In15.Cu")
		(net "P5E_CPU1_P2_RX_BUF_DP<8>")
	)
	(segment
		(start 147.266914 -402.302218)
		(end 147.192746 -402.481542)
		(width 0.14224)
		(layer "In15.Cu")
		(net "P5E_CPU1_P2_RX_BUF_DP<8>")
	)
	(segment
		(start 151.949912 -400.381724)
		(end 151.52624 -400.685508)
		(width 0.14224)
		(layer "In15.Cu")
		(net "P5E_CPU1_P2_RX_BUF_DP<8>")
	)
	(segment
		(start 157.04439 -393.144756)
		(end 156.91739 -393.017756)
		(width 0.14224)
		(layer "In15.Cu")
		(net "P5E_CPU1_P2_RX_BUF_DP<8>")
	)
	(segment
		(start 141.641576 -420.117524)
		(end 141.641576 -420.544244)
		(width 0.14224)
		(layer "In15.Cu")
		(net "P5E_CPU1_P2_RX_BUF_DP<8>")
	)
	(segment
		(start 156.373068 -395.796008)
		(end 156.127196 -396.145004)
		(width 0.14224)
		(layer "In15.Cu")
		(net "P5E_CPU1_P2_RX_BUF_DP<8>")
	)
	(segment
		(start 143.173196 -409.431998)
		(end 143.036036 -409.569158)
		(width 0.14224)
		(layer "In15.Cu")
		(net "P5E_CPU1_P2_RX_BUF_DP<8>")
	)
	(segment
		(start 143.173196 -409.005278)
		(end 143.173196 -409.431998)
		(width 0.14224)
		(layer "In15.Cu")
		(net "P5E_CPU1_P2_RX_BUF_DP<8>")
	)
	(segment
		(start 155.172918 -397.262096)
		(end 153.554938 -399.04797)
		(width 0.14224)
		(layer "In15.Cu")
		(net "P5E_CPU1_P2_RX_BUF_DP<8>")
	)
	(segment
		(start 141.504416 -423.591482)
		(end 141.641576 -423.728642)
		(width 0.14224)
		(layer "In15.Cu")
		(net "P5E_CPU1_P2_RX_BUF_DP<8>")
	)
	(segment
		(start 143.036036 -407.740358)
		(end 143.173196 -407.877518)
		(width 0.14224)
		(layer "In15.Cu")
		(net "P5E_CPU1_P2_RX_BUF_DP<8>")
	)
	(segment
		(start 142.912338 -411.006798)
		(end 142.744952 -411.18282)
		(width 0.14224)
		(layer "In15.Cu")
		(net "P5E_CPU1_P2_RX_BUF_DP<8>")
	)
	(segment
		(start 142.544546 -411.31998)
		(end 141.592046 -411.71495)
		(width 0.14224)
		(layer "In15.Cu")
		(net "P5E_CPU1_P2_RX_BUF_DP<8>")
	)
	(segment
		(start 144.218406 -405.560276)
		(end 143.902938 -405.771096)
		(width 0.14224)
		(layer "In15.Cu")
		(net "P5E_CPU1_P2_RX_BUF_DP<8>")
	)
	(segment
		(start 142.199614 -437.3372)
		(end 142.603982 -437.3372)
		(width 0.14224)
		(layer "In15.Cu")
		(net "P5E_CPU1_P2_RX_BUF_DP<8>")
	)
	(segment
		(start 143.036036 -408.441398)
		(end 143.036036 -408.868118)
		(width 0.14224)
		(layer "In15.Cu")
		(net "P5E_CPU1_P2_RX_BUF_DP<8>")
	)
	(segment
		(start 156.585412 -395.256004)
		(end 156.339794 -395.604746)
		(width 0.14224)
		(layer "In15.Cu")
		(net "P5E_CPU1_P2_RX_BUF_DP<8>")
	)
	(segment
		(start 141.504416 -411.84576)
		(end 141.504416 -419.980364)
		(width 0.14224)
		(layer "In15.Cu")
		(net "P5E_CPU1_P2_RX_BUF_DP<8>")
	)
	(segment
		(start 142.750032 -437.19115)
		(end 142.750032 -436.889906)
		(width 0.14224)
		(layer "In15.Cu")
		(net "P5E_CPU1_P2_RX_BUF_DP<8>")
	)
	(segment
		(start 155.935934 -396.178278)
		(end 155.172918 -397.262096)
		(width 0.14224)
		(layer "In15.Cu")
		(net "P5E_CPU1_P2_RX_BUF_DP<8>")
	)
	(segment
		(start 141.641576 -420.544244)
		(end 141.504416 -420.681404)
		(width 0.14224)
		(layer "In15.Cu")
		(net "P5E_CPU1_P2_RX_BUF_DP<8>")
	)
	(arc
		(start 144.567656 -404.924514)
		(mid 144.515042 -405.189111)
		(end 144.365218 -405.413464)
		(width 0.14224)
		(layer "In15.Cu")
		(net "P5E_CPU1_P2_RX_BUF_DP<8>")
	)
	(arc
		(start 142.744952 -411.18282)
		(mid 142.651934 -411.261897)
		(end 142.544546 -411.31998)
		(width 0.14224)
		(layer "In15.Cu")
		(net "P5E_CPU1_P2_RX_BUF_DP<8>")
	)
	(arc
		(start 143.241014 -406.14346)
		(mid 143.089251 -406.370445)
		(end 143.036036 -406.638252)
		(width 0.14224)
		(layer "In15.Cu")
		(net "P5E_CPU1_P2_RX_BUF_DP<8>")
	)
	(arc
		(start 146.225006 -402.734018)
		(mid 145.414649 -403.19047)
		(end 144.685258 -403.767544)
		(width 0.14224)
		(layer "In15.Cu")
		(net "P5E_CPU1_P2_RX_BUF_DP<8>")
	)
	(arc
		(start 143.627348 -405.885142)
		(mid 143.421466 -405.995288)
		(end 143.241014 -406.14346)
		(width 0.14224)
		(layer "In15.Cu")
		(net "P5E_CPU1_P2_RX_BUF_DP<8>")
	)
	(arc
		(start 141.592046 -411.71495)
		(mid 141.528371 -411.767062)
		(end 141.504416 -411.84576)
		(width 0.14224)
		(layer "In15.Cu")
		(net "P5E_CPU1_P2_RX_BUF_DP<8>")
	)
	(arc
		(start 144.685258 -403.767544)
		(mid 144.5982 -403.90003)
		(end 144.567656 -404.05558)
		(width 0.14224)
		(layer "In15.Cu")
		(net "P5E_CPU1_P2_RX_BUF_DP<8>")
	)
	(arc
		(start 143.036036 -410.697172)
		(mid 143.004071 -410.86393)
		(end 142.912338 -411.006798)
		(width 0.14224)
		(layer "In15.Cu")
		(net "P5E_CPU1_P2_RX_BUF_DP<8>")
	)
	(segment
		(start 155.230322 -391.488676)
		(end 155.141676 -391.577322)
		(width 0.1016)
		(layer "F.Cu")
		(net "P5E_CPU1_P2_RX_BUF_DP<7>")
	)
	(segment
		(start 155.141676 -392.723878)
		(end 155.394914 -392.977116)
		(width 0.1016)
		(layer "F.Cu")
		(net "P5E_CPU1_P2_RX_BUF_DP<7>")
	)
	(segment
		(start 155.394914 -392.977116)
		(end 155.705556 -392.977116)
		(width 0.1016)
		(layer "F.Cu")
		(net "P5E_CPU1_P2_RX_BUF_DP<7>")
	)
	(segment
		(start 155.14574 -391.281158)
		(end 155.230322 -391.36574)
		(width 0.1016)
		(layer "F.Cu")
		(net "P5E_CPU1_P2_RX_BUF_DP<7>")
	)
	(segment
		(start 155.705556 -392.977116)
		(end 155.84424 -393.1158)
		(width 0.1016)
		(layer "F.Cu")
		(net "P5E_CPU1_P2_RX_BUF_DP<7>")
	)
	(segment
		(start 155.230322 -391.36574)
		(end 155.230322 -391.488676)
		(width 0.1016)
		(layer "F.Cu")
		(net "P5E_CPU1_P2_RX_BUF_DP<7>")
	)
	(segment
		(start 155.84424 -393.1158)
		(end 155.84424 -393.292838)
		(width 0.1016)
		(layer "F.Cu")
		(net "P5E_CPU1_P2_RX_BUF_DP<7>")
	)
	(segment
		(start 155.141676 -391.577322)
		(end 155.141676 -392.723878)
		(width 0.1016)
		(layer "F.Cu")
		(net "P5E_CPU1_P2_RX_BUF_DP<7>")
	)
	(segment
		(start 139.60348 -438.337452)
		(end 139.213336 -438.337452)
		(width 0.14224)
		(layer "In15.Cu")
		(net "P5E_CPU1_P2_RX_BUF_DP<7>")
	)
	(segment
		(start 139.972796 -408.41168)
		(end 140.109956 -408.27452)
		(width 0.14224)
		(layer "In15.Cu")
		(net "P5E_CPU1_P2_RX_BUF_DP<7>")
	)
	(segment
		(start 149.19198 -400.541998)
		(end 150.668482 -400.013678)
		(width 0.14224)
		(layer "In15.Cu")
		(net "P5E_CPU1_P2_RX_BUF_DP<7>")
	)
	(segment
		(start 147.231354 -401.216114)
		(end 147.641564 -401.097242)
		(width 0.14224)
		(layer "In15.Cu")
		(net "P5E_CPU1_P2_RX_BUF_DP<7>")
	)
	(segment
		(start 139.071096 -418.137086)
		(end 139.208256 -417.999926)
		(width 0.14224)
		(layer "In15.Cu")
		(net "P5E_CPU1_P2_RX_BUF_DP<7>")
	)
	(segment
		(start 147.641564 -401.097242)
		(end 147.735036 -400.926808)
		(width 0.14224)
		(layer "In15.Cu")
		(net "P5E_CPU1_P2_RX_BUF_DP<7>")
	)
	(segment
		(start 155.341574 -393.203684)
		(end 155.527502 -393.017756)
		(width 0.14224)
		(layer "In15.Cu")
		(net "P5E_CPU1_P2_RX_BUF_DP<7>")
	)
	(segment
		(start 138.613388 -411.664404)
		(end 139.458446 -411.313884)
		(width 0.14224)
		(layer "In15.Cu")
		(net "P5E_CPU1_P2_RX_BUF_DP<7>")
	)
	(segment
		(start 139.208256 -416.120072)
		(end 139.071096 -415.982912)
		(width 0.14224)
		(layer "In15.Cu")
		(net "P5E_CPU1_P2_RX_BUF_DP<7>")
	)
	(segment
		(start 148.778468 -400.624294)
		(end 149.19198 -400.541998)
		(width 0.14224)
		(layer "In15.Cu")
		(net "P5E_CPU1_P2_RX_BUF_DP<7>")
	)
	(segment
		(start 140.455904 -405.931116)
		(end 140.83919 -405.771858)
		(width 0.14224)
		(layer "In15.Cu")
		(net "P5E_CPU1_P2_RX_BUF_DP<7>")
	)
	(segment
		(start 139.972796 -407.71064)
		(end 139.972796 -406.643332)
		(width 0.14224)
		(layer "In15.Cu")
		(net "P5E_CPU1_P2_RX_BUF_DP<7>")
	)
	(segment
		(start 139.213336 -438.337452)
		(end 139.071096 -438.195212)
		(width 0.14224)
		(layer "In15.Cu")
		(net "P5E_CPU1_P2_RX_BUF_DP<7>")
	)
	(segment
		(start 145.615152 -401.693126)
		(end 146.651726 -401.24126)
		(width 0.14224)
		(layer "In15.Cu")
		(net "P5E_CPU1_P2_RX_BUF_DP<7>")
	)
	(segment
		(start 142.904718 -402.875242)
		(end 143.085312 -402.946108)
		(width 0.14224)
		(layer "In15.Cu")
		(net "P5E_CPU1_P2_RX_BUF_DP<7>")
	)
	(segment
		(start 144.972278 -401.973542)
		(end 145.152872 -402.044408)
		(width 0.14224)
		(layer "In15.Cu")
		(net "P5E_CPU1_P2_RX_BUF_DP<7>")
	)
	(segment
		(start 152.401778 -398.749012)
		(end 153.918158 -397.251428)
		(width 0.14224)
		(layer "In15.Cu")
		(net "P5E_CPU1_P2_RX_BUF_DP<7>")
	)
	(segment
		(start 139.208256 -415.419032)
		(end 139.208256 -414.992312)
		(width 0.14224)
		(layer "In15.Cu")
		(net "P5E_CPU1_P2_RX_BUF_DP<7>")
	)
	(segment
		(start 139.972796 -409.53944)
		(end 140.109956 -409.40228)
		(width 0.14224)
		(layer "In15.Cu")
		(net "P5E_CPU1_P2_RX_BUF_DP<7>")
	)
	(segment
		(start 145.544286 -401.873974)
		(end 145.615152 -401.693126)
		(width 0.14224)
		(layer "In15.Cu")
		(net "P5E_CPU1_P2_RX_BUF_DP<7>")
	)
	(segment
		(start 139.749784 -437.889904)
		(end 139.749784 -438.191148)
		(width 0.14224)
		(layer "In15.Cu")
		(net "P5E_CPU1_P2_RX_BUF_DP<7>")
	)
	(segment
		(start 141.155166 -405.560276)
		(end 141.301978 -405.413464)
		(width 0.14224)
		(layer "In15.Cu")
		(net "P5E_CPU1_P2_RX_BUF_DP<7>")
	)
	(segment
		(start 141.69771 -403.654006)
		(end 141.861032 -403.490684)
		(width 0.14224)
		(layer "In15.Cu")
		(net "P5E_CPU1_P2_RX_BUF_DP<7>")
	)
	(segment
		(start 140.057378 -406.38603)
		(end 140.30579 -406.048972)
		(width 0.14224)
		(layer "In15.Cu")
		(net "P5E_CPU1_P2_RX_BUF_DP<7>")
	)
	(segment
		(start 140.83919 -405.771858)
		(end 141.155166 -405.560276)
		(width 0.14224)
		(layer "In15.Cu")
		(net "P5E_CPU1_P2_RX_BUF_DP<7>")
	)
	(segment
		(start 155.84424 -393.144756)
		(end 155.84424 -393.292838)
		(width 0.14224)
		(layer "In15.Cu")
		(net "P5E_CPU1_P2_RX_BUF_DP<7>")
	)
	(segment
		(start 154.662378 -396.350236)
		(end 155.184094 -395.56944)
		(width 0.14224)
		(layer "In15.Cu")
		(net "P5E_CPU1_P2_RX_BUF_DP<7>")
	)
	(segment
		(start 141.504416 -404.924514)
		(end 141.504416 -404.120604)
		(width 0.14224)
		(layer "In15.Cu")
		(net "P5E_CPU1_P2_RX_BUF_DP<7>")
	)
	(segment
		(start 138.939778 -414.175956)
		(end 138.566398 -413.802576)
		(width 0.14224)
		(layer "In15.Cu")
		(net "P5E_CPU1_P2_RX_BUF_DP<7>")
	)
	(segment
		(start 147.735036 -400.926808)
		(end 148.778468 -400.624294)
		(width 0.14224)
		(layer "In15.Cu")
		(net "P5E_CPU1_P2_RX_BUF_DP<7>")
	)
	(segment
		(start 144.119092 -402.495258)
		(end 144.510506 -402.324824)
		(width 0.14224)
		(layer "In15.Cu")
		(net "P5E_CPU1_P2_RX_BUF_DP<7>")
	)
	(segment
		(start 139.071096 -415.556192)
		(end 139.208256 -415.419032)
		(width 0.14224)
		(layer "In15.Cu")
		(net "P5E_CPU1_P2_RX_BUF_DP<7>")
	)
	(segment
		(start 143.547592 -402.594826)
		(end 143.938498 -402.424392)
		(width 0.14224)
		(layer "In15.Cu")
		(net "P5E_CPU1_P2_RX_BUF_DP<7>")
	)
	(segment
		(start 146.651726 -401.24126)
		(end 147.061428 -401.122388)
		(width 0.14224)
		(layer "In15.Cu")
		(net "P5E_CPU1_P2_RX_BUF_DP<7>")
	)
	(segment
		(start 145.152872 -402.044408)
		(end 145.544286 -401.873974)
		(width 0.14224)
		(layer "In15.Cu")
		(net "P5E_CPU1_P2_RX_BUF_DP<7>")
	)
	(segment
		(start 143.476726 -402.775674)
		(end 143.547592 -402.594826)
		(width 0.14224)
		(layer "In15.Cu")
		(net "P5E_CPU1_P2_RX_BUF_DP<7>")
	)
	(segment
		(start 143.938498 -402.424392)
		(end 144.119092 -402.495258)
		(width 0.14224)
		(layer "In15.Cu")
		(net "P5E_CPU1_P2_RX_BUF_DP<7>")
	)
	(segment
		(start 139.071096 -416.683952)
		(end 139.208256 -416.546792)
		(width 0.14224)
		(layer "In15.Cu")
		(net "P5E_CPU1_P2_RX_BUF_DP<7>")
	)
	(segment
		(start 139.208256 -414.992312)
		(end 139.071096 -414.855152)
		(width 0.14224)
		(layer "In15.Cu")
		(net "P5E_CPU1_P2_RX_BUF_DP<7>")
	)
	(segment
		(start 155.184094 -395.56944)
		(end 155.341574 -394.941298)
		(width 0.14224)
		(layer "In15.Cu")
		(net "P5E_CPU1_P2_RX_BUF_DP<7>")
	)
	(segment
		(start 150.668482 -400.013678)
		(end 151.178006 -399.72869)
		(width 0.14224)
		(layer "In15.Cu")
		(net "P5E_CPU1_P2_RX_BUF_DP<7>")
	)
	(segment
		(start 139.071096 -438.195212)
		(end 139.071096 -418.137086)
		(width 0.14224)
		(layer "In15.Cu")
		(net "P5E_CPU1_P2_RX_BUF_DP<7>")
	)
	(segment
		(start 144.510506 -402.324824)
		(end 144.581372 -402.143976)
		(width 0.14224)
		(layer "In15.Cu")
		(net "P5E_CPU1_P2_RX_BUF_DP<7>")
	)
	(segment
		(start 140.109956 -409.40228)
		(end 140.109956 -408.97556)
		(width 0.14224)
		(layer "In15.Cu")
		(net "P5E_CPU1_P2_RX_BUF_DP<7>")
	)
	(segment
		(start 139.972796 -408.8384)
		(end 139.972796 -408.41168)
		(width 0.14224)
		(layer "In15.Cu")
		(net "P5E_CPU1_P2_RX_BUF_DP<7>")
	)
	(segment
		(start 144.581372 -402.143976)
		(end 144.972278 -401.973542)
		(width 0.14224)
		(layer "In15.Cu")
		(net "P5E_CPU1_P2_RX_BUF_DP<7>")
	)
	(segment
		(start 155.71724 -393.017756)
		(end 155.84424 -393.144756)
		(width 0.14224)
		(layer "In15.Cu")
		(net "P5E_CPU1_P2_RX_BUF_DP<7>")
	)
	(segment
		(start 139.071096 -415.982912)
		(end 139.071096 -415.556192)
		(width 0.14224)
		(layer "In15.Cu")
		(net "P5E_CPU1_P2_RX_BUF_DP<7>")
	)
	(segment
		(start 151.178006 -399.72869)
		(end 152.401778 -398.749012)
		(width 0.14224)
		(layer "In15.Cu")
		(net "P5E_CPU1_P2_RX_BUF_DP<7>")
	)
	(segment
		(start 139.208256 -417.573206)
		(end 139.071096 -417.436046)
		(width 0.14224)
		(layer "In15.Cu")
		(net "P5E_CPU1_P2_RX_BUF_DP<7>")
	)
	(segment
		(start 139.68476 -411.122368)
		(end 139.894564 -410.787342)
		(width 0.14224)
		(layer "In15.Cu")
		(net "P5E_CPU1_P2_RX_BUF_DP<7>")
	)
	(segment
		(start 139.071096 -417.436046)
		(end 139.071096 -416.683952)
		(width 0.14224)
		(layer "In15.Cu")
		(net "P5E_CPU1_P2_RX_BUF_DP<7>")
	)
	(segment
		(start 155.341574 -394.941298)
		(end 155.341574 -393.203684)
		(width 0.14224)
		(layer "In15.Cu")
		(net "P5E_CPU1_P2_RX_BUF_DP<7>")
	)
	(segment
		(start 147.061428 -401.122388)
		(end 147.231354 -401.216114)
		(width 0.14224)
		(layer "In15.Cu")
		(net "P5E_CPU1_P2_RX_BUF_DP<7>")
	)
	(segment
		(start 153.918158 -397.251428)
		(end 154.662378 -396.350236)
		(width 0.14224)
		(layer "In15.Cu")
		(net "P5E_CPU1_P2_RX_BUF_DP<7>")
	)
	(segment
		(start 140.109956 -407.8478)
		(end 139.972796 -407.71064)
		(width 0.14224)
		(layer "In15.Cu")
		(net "P5E_CPU1_P2_RX_BUF_DP<7>")
	)
	(segment
		(start 139.071096 -414.855152)
		(end 139.071096 -414.492948)
		(width 0.14224)
		(layer "In15.Cu")
		(net "P5E_CPU1_P2_RX_BUF_DP<7>")
	)
	(segment
		(start 140.109956 -408.27452)
		(end 140.109956 -407.8478)
		(width 0.14224)
		(layer "In15.Cu")
		(net "P5E_CPU1_P2_RX_BUF_DP<7>")
	)
	(segment
		(start 139.208256 -417.999926)
		(end 139.208256 -417.573206)
		(width 0.14224)
		(layer "In15.Cu")
		(net "P5E_CPU1_P2_RX_BUF_DP<7>")
	)
	(segment
		(start 142.513812 -403.045676)
		(end 142.904718 -402.875242)
		(width 0.14224)
		(layer "In15.Cu")
		(net "P5E_CPU1_P2_RX_BUF_DP<7>")
	)
	(segment
		(start 139.749784 -438.191148)
		(end 139.60348 -438.337452)
		(width 0.14224)
		(layer "In15.Cu")
		(net "P5E_CPU1_P2_RX_BUF_DP<7>")
	)
	(segment
		(start 143.085312 -402.946108)
		(end 143.476726 -402.775674)
		(width 0.14224)
		(layer "In15.Cu")
		(net "P5E_CPU1_P2_RX_BUF_DP<7>")
	)
	(segment
		(start 155.527502 -393.017756)
		(end 155.71724 -393.017756)
		(width 0.14224)
		(layer "In15.Cu")
		(net "P5E_CPU1_P2_RX_BUF_DP<7>")
	)
	(segment
		(start 139.208256 -416.546792)
		(end 139.208256 -416.120072)
		(width 0.14224)
		(layer "In15.Cu")
		(net "P5E_CPU1_P2_RX_BUF_DP<7>")
	)
	(segment
		(start 140.109956 -408.97556)
		(end 139.972796 -408.8384)
		(width 0.14224)
		(layer "In15.Cu")
		(net "P5E_CPU1_P2_RX_BUF_DP<7>")
	)
	(segment
		(start 139.972796 -410.51353)
		(end 139.972796 -409.53944)
		(width 0.14224)
		(layer "In15.Cu")
		(net "P5E_CPU1_P2_RX_BUF_DP<7>")
	)
	(segment
		(start 138.441176 -413.50057)
		(end 138.441176 -411.922214)
		(width 0.14224)
		(layer "In15.Cu")
		(net "P5E_CPU1_P2_RX_BUF_DP<7>")
	)
	(arc
		(start 141.861032 -403.490684)
		(mid 142.16652 -403.237517)
		(end 142.513812 -403.045676)
		(width 0.14224)
		(layer "In15.Cu")
		(net "P5E_CPU1_P2_RX_BUF_DP<7>")
	)
	(arc
		(start 139.458446 -411.313884)
		(mid 139.586558 -411.235794)
		(end 139.68476 -411.122368)
		(width 0.14224)
		(layer "In15.Cu")
		(net "P5E_CPU1_P2_RX_BUF_DP<7>")
	)
	(arc
		(start 141.301978 -405.413464)
		(mid 141.451818 -405.189118)
		(end 141.504416 -404.924514)
		(width 0.14224)
		(layer "In15.Cu")
		(net "P5E_CPU1_P2_RX_BUF_DP<7>")
	)
	(arc
		(start 139.972796 -406.643332)
		(mid 139.994426 -406.507882)
		(end 140.057378 -406.38603)
		(width 0.14224)
		(layer "In15.Cu")
		(net "P5E_CPU1_P2_RX_BUF_DP<7>")
	)
	(arc
		(start 141.504416 -404.120604)
		(mid 141.554647 -403.868074)
		(end 141.69771 -403.654006)
		(width 0.14224)
		(layer "In15.Cu")
		(net "P5E_CPU1_P2_RX_BUF_DP<7>")
	)
	(arc
		(start 140.30579 -406.048972)
		(mid 140.372843 -405.979852)
		(end 140.455904 -405.931116)
		(width 0.14224)
		(layer "In15.Cu")
		(net "P5E_CPU1_P2_RX_BUF_DP<7>")
	)
	(arc
		(start 138.566398 -413.802576)
		(mid 138.47376 -413.664029)
		(end 138.441176 -413.50057)
		(width 0.14224)
		(layer "In15.Cu")
		(net "P5E_CPU1_P2_RX_BUF_DP<7>")
	)
	(arc
		(start 139.071096 -414.492948)
		(mid 139.03697 -414.321387)
		(end 138.939778 -414.175956)
		(width 0.14224)
		(layer "In15.Cu")
		(net "P5E_CPU1_P2_RX_BUF_DP<7>")
	)
	(arc
		(start 138.441176 -411.922214)
		(mid 138.488183 -411.767185)
		(end 138.613388 -411.664404)
		(width 0.14224)
		(layer "In15.Cu")
		(net "P5E_CPU1_P2_RX_BUF_DP<7>")
	)
	(arc
		(start 139.894564 -410.787342)
		(mid 139.952966 -410.655942)
		(end 139.972796 -410.51353)
		(width 0.14224)
		(layer "In15.Cu")
		(net "P5E_CPU1_P2_RX_BUF_DP<7>")
	)
	(segment
		(start 154.505406 -392.977116)
		(end 154.644344 -393.116054)
		(width 0.1016)
		(layer "F.Cu")
		(net "P5E_CPU1_P2_RX_BUF_DP<6>")
	)
	(segment
		(start 153.950416 -392.723878)
		(end 154.203654 -392.977116)
		(width 0.1016)
		(layer "F.Cu")
		(net "P5E_CPU1_P2_RX_BUF_DP<6>")
	)
	(segment
		(start 153.950416 -391.568432)
		(end 153.950416 -392.723878)
		(width 0.1016)
		(layer "F.Cu")
		(net "P5E_CPU1_P2_RX_BUF_DP<6>")
	)
	(segment
		(start 154.030172 -391.488676)
		(end 153.950416 -391.568432)
		(width 0.1016)
		(layer "F.Cu")
		(net "P5E_CPU1_P2_RX_BUF_DP<6>")
	)
	(segment
		(start 154.203654 -392.977116)
		(end 154.505406 -392.977116)
		(width 0.1016)
		(layer "F.Cu")
		(net "P5E_CPU1_P2_RX_BUF_DP<6>")
	)
	(segment
		(start 154.030172 -391.36574)
		(end 154.030172 -391.488676)
		(width 0.1016)
		(layer "F.Cu")
		(net "P5E_CPU1_P2_RX_BUF_DP<6>")
	)
	(segment
		(start 154.644344 -393.116054)
		(end 154.644344 -393.292838)
		(width 0.1016)
		(layer "F.Cu")
		(net "P5E_CPU1_P2_RX_BUF_DP<6>")
	)
	(segment
		(start 153.94559 -391.281158)
		(end 154.030172 -391.36574)
		(width 0.1016)
		(layer "F.Cu")
		(net "P5E_CPU1_P2_RX_BUF_DP<6>")
	)
	(segment
		(start 136.909556 -408.316938)
		(end 136.909556 -408.743658)
		(width 0.14224)
		(layer "In15.Cu")
		(net "P5E_CPU1_P2_RX_BUF_DP<6>")
	)
	(segment
		(start 138.99515 -403.39899)
		(end 138.644122 -403.743414)
		(width 0.14224)
		(layer "In15.Cu")
		(net "P5E_CPU1_P2_RX_BUF_DP<6>")
	)
	(segment
		(start 140.450316 -402.738082)
		(end 140.378434 -402.918676)
		(width 0.14224)
		(layer "In15.Cu")
		(net "P5E_CPU1_P2_RX_BUF_DP<6>")
	)
	(segment
		(start 137.046716 -407.753058)
		(end 137.046716 -408.179778)
		(width 0.14224)
		(layer "In15.Cu")
		(net "P5E_CPU1_P2_RX_BUF_DP<6>")
	)
	(segment
		(start 154.644344 -393.292838)
		(end 154.644344 -393.144756)
		(width 0.14224)
		(layer "In15.Cu")
		(net "P5E_CPU1_P2_RX_BUF_DP<6>")
	)
	(segment
		(start 154.517344 -393.017756)
		(end 154.327606 -393.017756)
		(width 0.14224)
		(layer "In15.Cu")
		(net "P5E_CPU1_P2_RX_BUF_DP<6>")
	)
	(segment
		(start 144.003522 -401.215606)
		(end 143.611346 -401.3835)
		(width 0.14224)
		(layer "In15.Cu")
		(net "P5E_CPU1_P2_RX_BUF_DP<6>")
	)
	(segment
		(start 135.47852 -413.411416)
		(end 136.103106 -414.036002)
		(width 0.14224)
		(layer "In15.Cu")
		(net "P5E_CPU1_P2_RX_BUF_DP<6>")
	)
	(segment
		(start 154.185366 -393.159996)
		(end 154.185366 -395.032738)
		(width 0.14224)
		(layer "In15.Cu")
		(net "P5E_CPU1_P2_RX_BUF_DP<6>")
	)
	(segment
		(start 153.624026 -396.05077)
		(end 151.125682 -398.549114)
		(width 0.14224)
		(layer "In15.Cu")
		(net "P5E_CPU1_P2_RX_BUF_DP<6>")
	)
	(segment
		(start 142.966694 -401.659852)
		(end 142.523972 -401.84959)
		(width 0.14224)
		(layer "In15.Cu")
		(net "P5E_CPU1_P2_RX_BUF_DP<6>")
	)
	(segment
		(start 136.103106 -414.036002)
		(end 136.297162 -414.036002)
		(width 0.14224)
		(layer "In15.Cu")
		(net "P5E_CPU1_P2_RX_BUF_DP<6>")
	)
	(segment
		(start 139.805918 -403.014688)
		(end 139.413742 -403.182582)
		(width 0.14224)
		(layer "In15.Cu")
		(net "P5E_CPU1_P2_RX_BUF_DP<6>")
	)
	(segment
		(start 140.378434 -402.918676)
		(end 139.986004 -403.08657)
		(width 0.14224)
		(layer "In15.Cu")
		(net "P5E_CPU1_P2_RX_BUF_DP<6>")
	)
	(segment
		(start 149.64029 -399.349722)
		(end 148.068538 -399.788126)
		(width 0.14224)
		(layer "In15.Cu")
		(net "P5E_CPU1_P2_RX_BUF_DP<6>")
	)
	(segment
		(start 139.986004 -403.08657)
		(end 139.805918 -403.014688)
		(width 0.14224)
		(layer "In15.Cu")
		(net "P5E_CPU1_P2_RX_BUF_DP<6>")
	)
	(segment
		(start 136.297162 -414.036002)
		(end 136.599168 -414.338008)
		(width 0.14224)
		(layer "In15.Cu")
		(net "P5E_CPU1_P2_RX_BUF_DP<6>")
	)
	(segment
		(start 141.415008 -402.474176)
		(end 141.022578 -402.64207)
		(width 0.14224)
		(layer "In15.Cu")
		(net "P5E_CPU1_P2_RX_BUF_DP<6>")
	)
	(segment
		(start 154.644344 -393.144756)
		(end 154.517344 -393.017756)
		(width 0.14224)
		(layer "In15.Cu")
		(net "P5E_CPU1_P2_RX_BUF_DP<6>")
	)
	(segment
		(start 142.059406 -402.197824)
		(end 141.87932 -402.125942)
		(width 0.14224)
		(layer "In15.Cu")
		(net "P5E_CPU1_P2_RX_BUF_DP<6>")
	)
	(segment
		(start 137.749788 -437.19115)
		(end 137.749788 -436.889906)
		(width 0.14224)
		(layer "In15.Cu")
		(net "P5E_CPU1_P2_RX_BUF_DP<6>")
	)
	(segment
		(start 136.909556 -407.615898)
		(end 137.046716 -407.753058)
		(width 0.14224)
		(layer "In15.Cu")
		(net "P5E_CPU1_P2_RX_BUF_DP<6>")
	)
	(segment
		(start 137.20826 -416.120072)
		(end 137.20826 -416.546792)
		(width 0.14224)
		(layer "In15.Cu")
		(net "P5E_CPU1_P2_RX_BUF_DP<6>")
	)
	(segment
		(start 136.909556 -406.638252)
		(end 136.909556 -407.615898)
		(width 0.14224)
		(layer "In15.Cu")
		(net "P5E_CPU1_P2_RX_BUF_DP<6>")
	)
	(segment
		(start 142.523972 -401.84959)
		(end 142.451836 -402.02993)
		(width 0.14224)
		(layer "In15.Cu")
		(net "P5E_CPU1_P2_RX_BUF_DP<6>")
	)
	(segment
		(start 143.53921 -401.56384)
		(end 143.14678 -401.731988)
		(width 0.14224)
		(layer "In15.Cu")
		(net "P5E_CPU1_P2_RX_BUF_DP<6>")
	)
	(segment
		(start 137.0711 -416.683952)
		(end 137.0711 -437.204104)
		(width 0.14224)
		(layer "In15.Cu")
		(net "P5E_CPU1_P2_RX_BUF_DP<6>")
	)
	(segment
		(start 154.185366 -395.032738)
		(end 153.99131 -395.501114)
		(width 0.14224)
		(layer "In15.Cu")
		(net "P5E_CPU1_P2_RX_BUF_DP<6>")
	)
	(segment
		(start 141.87932 -402.125942)
		(end 141.487144 -402.293836)
		(width 0.14224)
		(layer "In15.Cu")
		(net "P5E_CPU1_P2_RX_BUF_DP<6>")
	)
	(segment
		(start 154.327606 -393.017756)
		(end 154.185366 -393.159996)
		(width 0.14224)
		(layer "In15.Cu")
		(net "P5E_CPU1_P2_RX_BUF_DP<6>")
	)
	(segment
		(start 138.565128 -403.843236)
		(end 138.474704 -403.993096)
		(width 0.14224)
		(layer "In15.Cu")
		(net "P5E_CPU1_P2_RX_BUF_DP<6>")
	)
	(segment
		(start 137.20826 -416.546792)
		(end 137.0711 -416.683952)
		(width 0.14224)
		(layer "In15.Cu")
		(net "P5E_CPU1_P2_RX_BUF_DP<6>")
	)
	(segment
		(start 138.091926 -405.560276)
		(end 137.776458 -405.771096)
		(width 0.14224)
		(layer "In15.Cu")
		(net "P5E_CPU1_P2_RX_BUF_DP<6>")
	)
	(segment
		(start 143.611346 -401.3835)
		(end 143.53921 -401.56384)
		(width 0.14224)
		(layer "In15.Cu")
		(net "P5E_CPU1_P2_RX_BUF_DP<6>")
	)
	(segment
		(start 137.0711 -415.279586)
		(end 137.0711 -415.982912)
		(width 0.14224)
		(layer "In15.Cu")
		(net "P5E_CPU1_P2_RX_BUF_DP<6>")
	)
	(segment
		(start 136.909556 -408.743658)
		(end 137.046716 -408.880818)
		(width 0.14224)
		(layer "In15.Cu")
		(net "P5E_CPU1_P2_RX_BUF_DP<6>")
	)
	(segment
		(start 136.785858 -411.006798)
		(end 136.618472 -411.18282)
		(width 0.14224)
		(layer "In15.Cu")
		(net "P5E_CPU1_P2_RX_BUF_DP<6>")
	)
	(segment
		(start 145.552414 -400.55165)
		(end 144.648174 -400.939254)
		(width 0.14224)
		(layer "In15.Cu")
		(net "P5E_CPU1_P2_RX_BUF_DP<6>")
	)
	(segment
		(start 137.046716 -408.880818)
		(end 137.046716 -409.307538)
		(width 0.14224)
		(layer "In15.Cu")
		(net "P5E_CPU1_P2_RX_BUF_DP<6>")
	)
	(segment
		(start 140.842492 -402.570188)
		(end 140.450316 -402.738082)
		(width 0.14224)
		(layer "In15.Cu")
		(net "P5E_CPU1_P2_RX_BUF_DP<6>")
	)
	(segment
		(start 136.599168 -414.338008)
		(end 136.599168 -414.532064)
		(width 0.14224)
		(layer "In15.Cu")
		(net "P5E_CPU1_P2_RX_BUF_DP<6>")
	)
	(segment
		(start 137.0711 -437.204104)
		(end 137.20826 -437.341264)
		(width 0.14224)
		(layer "In15.Cu")
		(net "P5E_CPU1_P2_RX_BUF_DP<6>")
	)
	(segment
		(start 142.451836 -402.02993)
		(end 142.059406 -402.197824)
		(width 0.14224)
		(layer "In15.Cu")
		(net "P5E_CPU1_P2_RX_BUF_DP<6>")
	)
	(segment
		(start 148.068538 -399.788126)
		(end 145.552414 -400.55165)
		(width 0.14224)
		(layer "In15.Cu")
		(net "P5E_CPU1_P2_RX_BUF_DP<6>")
	)
	(segment
		(start 151.125682 -398.549114)
		(end 150.396702 -399.036286)
		(width 0.14224)
		(layer "In15.Cu")
		(net "P5E_CPU1_P2_RX_BUF_DP<6>")
	)
	(segment
		(start 150.396702 -399.036286)
		(end 149.64029 -399.349722)
		(width 0.14224)
		(layer "In15.Cu")
		(net "P5E_CPU1_P2_RX_BUF_DP<6>")
	)
	(segment
		(start 137.046716 -408.179778)
		(end 136.909556 -408.316938)
		(width 0.14224)
		(layer "In15.Cu")
		(net "P5E_CPU1_P2_RX_BUF_DP<6>")
	)
	(segment
		(start 137.20826 -437.341264)
		(end 137.599674 -437.341264)
		(width 0.14224)
		(layer "In15.Cu")
		(net "P5E_CPU1_P2_RX_BUF_DP<6>")
	)
	(segment
		(start 144.648174 -400.939254)
		(end 144.576038 -401.119594)
		(width 0.14224)
		(layer "In15.Cu")
		(net "P5E_CPU1_P2_RX_BUF_DP<6>")
	)
	(segment
		(start 136.418066 -411.31998)
		(end 135.465566 -411.71495)
		(width 0.14224)
		(layer "In15.Cu")
		(net "P5E_CPU1_P2_RX_BUF_DP<6>")
	)
	(segment
		(start 153.99131 -395.501114)
		(end 153.624026 -396.05077)
		(width 0.14224)
		(layer "In15.Cu")
		(net "P5E_CPU1_P2_RX_BUF_DP<6>")
	)
	(segment
		(start 144.576038 -401.119594)
		(end 144.183608 -401.287488)
		(width 0.14224)
		(layer "In15.Cu")
		(net "P5E_CPU1_P2_RX_BUF_DP<6>")
	)
	(segment
		(start 143.14678 -401.731988)
		(end 142.966694 -401.659852)
		(width 0.14224)
		(layer "In15.Cu")
		(net "P5E_CPU1_P2_RX_BUF_DP<6>")
	)
	(segment
		(start 138.441176 -404.113492)
		(end 138.441176 -404.924514)
		(width 0.14224)
		(layer "In15.Cu")
		(net "P5E_CPU1_P2_RX_BUF_DP<6>")
	)
	(segment
		(start 137.0711 -415.982912)
		(end 137.20826 -416.120072)
		(width 0.14224)
		(layer "In15.Cu")
		(net "P5E_CPU1_P2_RX_BUF_DP<6>")
	)
	(segment
		(start 144.183608 -401.287488)
		(end 144.003522 -401.215606)
		(width 0.14224)
		(layer "In15.Cu")
		(net "P5E_CPU1_P2_RX_BUF_DP<6>")
	)
	(segment
		(start 136.599168 -414.532064)
		(end 136.876282 -414.809178)
		(width 0.14224)
		(layer "In15.Cu")
		(net "P5E_CPU1_P2_RX_BUF_DP<6>")
	)
	(segment
		(start 135.377936 -411.846014)
		(end 135.377936 -413.168592)
		(width 0.14224)
		(layer "In15.Cu")
		(net "P5E_CPU1_P2_RX_BUF_DP<6>")
	)
	(segment
		(start 138.238738 -405.413464)
		(end 138.091926 -405.560276)
		(width 0.14224)
		(layer "In15.Cu")
		(net "P5E_CPU1_P2_RX_BUF_DP<6>")
	)
	(segment
		(start 141.022578 -402.64207)
		(end 140.842492 -402.570188)
		(width 0.14224)
		(layer "In15.Cu")
		(net "P5E_CPU1_P2_RX_BUF_DP<6>")
	)
	(segment
		(start 137.046716 -409.307538)
		(end 136.909556 -409.444698)
		(width 0.14224)
		(layer "In15.Cu")
		(net "P5E_CPU1_P2_RX_BUF_DP<6>")
	)
	(segment
		(start 137.776458 -405.771096)
		(end 137.500868 -405.885142)
		(width 0.14224)
		(layer "In15.Cu")
		(net "P5E_CPU1_P2_RX_BUF_DP<6>")
	)
	(segment
		(start 141.487144 -402.293836)
		(end 141.415008 -402.474176)
		(width 0.14224)
		(layer "In15.Cu")
		(net "P5E_CPU1_P2_RX_BUF_DP<6>")
	)
	(segment
		(start 139.309856 -403.229826)
		(end 139.07516 -403.342856)
		(width 0.14224)
		(layer "In15.Cu")
		(net "P5E_CPU1_P2_RX_BUF_DP<6>")
	)
	(segment
		(start 137.599674 -437.341264)
		(end 137.749788 -437.19115)
		(width 0.14224)
		(layer "In15.Cu")
		(net "P5E_CPU1_P2_RX_BUF_DP<6>")
	)
	(segment
		(start 136.909556 -409.444698)
		(end 136.909556 -410.697172)
		(width 0.14224)
		(layer "In15.Cu")
		(net "P5E_CPU1_P2_RX_BUF_DP<6>")
	)
	(arc
		(start 138.441176 -404.924514)
		(mid 138.388562 -405.189111)
		(end 138.238738 -405.413464)
		(width 0.14224)
		(layer "In15.Cu")
		(net "P5E_CPU1_P2_RX_BUF_DP<6>")
	)
	(arc
		(start 136.618472 -411.18282)
		(mid 136.525454 -411.261897)
		(end 136.418066 -411.31998)
		(width 0.14224)
		(layer "In15.Cu")
		(net "P5E_CPU1_P2_RX_BUF_DP<6>")
	)
	(arc
		(start 138.474704 -403.993096)
		(mid 138.44974 -404.051008)
		(end 138.441176 -404.113492)
		(width 0.14224)
		(layer "In15.Cu")
		(net "P5E_CPU1_P2_RX_BUF_DP<6>")
	)
	(arc
		(start 139.413742 -403.182582)
		(mid 139.361542 -403.205638)
		(end 139.309856 -403.229826)
		(width 0.14224)
		(layer "In15.Cu")
		(net "P5E_CPU1_P2_RX_BUF_DP<6>")
	)
	(arc
		(start 135.377936 -413.168592)
		(mid 135.404076 -413.300009)
		(end 135.47852 -413.411416)
		(width 0.14224)
		(layer "In15.Cu")
		(net "P5E_CPU1_P2_RX_BUF_DP<6>")
	)
	(arc
		(start 135.465566 -411.71495)
		(mid 135.401821 -411.767167)
		(end 135.377936 -411.846014)
		(width 0.14224)
		(layer "In15.Cu")
		(net "P5E_CPU1_P2_RX_BUF_DP<6>")
	)
	(arc
		(start 138.644122 -403.743414)
		(mid 138.601496 -403.790847)
		(end 138.565128 -403.843236)
		(width 0.14224)
		(layer "In15.Cu")
		(net "P5E_CPU1_P2_RX_BUF_DP<6>")
	)
	(arc
		(start 136.876282 -414.809178)
		(mid 137.020492 -415.025003)
		(end 137.0711 -415.279586)
		(width 0.14224)
		(layer "In15.Cu")
		(net "P5E_CPU1_P2_RX_BUF_DP<6>")
	)
	(arc
		(start 137.114534 -406.14346)
		(mid 136.962771 -406.370445)
		(end 136.909556 -406.638252)
		(width 0.14224)
		(layer "In15.Cu")
		(net "P5E_CPU1_P2_RX_BUF_DP<6>")
	)
	(arc
		(start 136.909556 -410.697172)
		(mid 136.877591 -410.86393)
		(end 136.785858 -411.006798)
		(width 0.14224)
		(layer "In15.Cu")
		(net "P5E_CPU1_P2_RX_BUF_DP<6>")
	)
	(arc
		(start 139.07516 -403.342856)
		(mid 139.032865 -403.367656)
		(end 138.99515 -403.39899)
		(width 0.14224)
		(layer "In15.Cu")
		(net "P5E_CPU1_P2_RX_BUF_DP<6>")
	)
	(arc
		(start 137.500868 -405.885142)
		(mid 137.294986 -405.995288)
		(end 137.114534 -406.14346)
		(width 0.14224)
		(layer "In15.Cu")
		(net "P5E_CPU1_P2_RX_BUF_DP<6>")
	)
	(segment
		(start 152.830276 -391.488676)
		(end 152.74163 -391.577322)
		(width 0.1016)
		(layer "F.Cu")
		(net "P5E_CPU1_P2_RX_BUF_DP<5>")
	)
	(segment
		(start 152.830276 -391.36574)
		(end 152.830276 -391.488676)
		(width 0.1016)
		(layer "F.Cu")
		(net "P5E_CPU1_P2_RX_BUF_DP<5>")
	)
	(segment
		(start 153.444194 -393.1158)
		(end 153.444194 -393.292838)
		(width 0.1016)
		(layer "F.Cu")
		(net "P5E_CPU1_P2_RX_BUF_DP<5>")
	)
	(segment
		(start 152.74163 -392.723878)
		(end 152.994868 -392.977116)
		(width 0.1016)
		(layer "F.Cu")
		(net "P5E_CPU1_P2_RX_BUF_DP<5>")
	)
	(segment
		(start 153.30551 -392.977116)
		(end 153.444194 -393.1158)
		(width 0.1016)
		(layer "F.Cu")
		(net "P5E_CPU1_P2_RX_BUF_DP<5>")
	)
	(segment
		(start 152.745694 -391.281158)
		(end 152.830276 -391.36574)
		(width 0.1016)
		(layer "F.Cu")
		(net "P5E_CPU1_P2_RX_BUF_DP<5>")
	)
	(segment
		(start 152.74163 -391.577322)
		(end 152.74163 -392.723878)
		(width 0.1016)
		(layer "F.Cu")
		(net "P5E_CPU1_P2_RX_BUF_DP<5>")
	)
	(segment
		(start 152.994868 -392.977116)
		(end 153.30551 -392.977116)
		(width 0.1016)
		(layer "F.Cu")
		(net "P5E_CPU1_P2_RX_BUF_DP<5>")
	)
	(segment
		(start 142.695676 -400.484594)
		(end 142.616174 -400.661886)
		(width 0.14224)
		(layer "In15.Cu")
		(net "P5E_CPU1_P2_RX_BUF_DP<5>")
	)
	(segment
		(start 133.846316 -406.638252)
		(end 133.846316 -407.487374)
		(width 0.14224)
		(layer "In15.Cu")
		(net "P5E_CPU1_P2_RX_BUF_DP<5>")
	)
	(segment
		(start 133.3373 -411.36062)
		(end 132.527294 -411.624526)
		(width 0.14224)
		(layer "In15.Cu")
		(net "P5E_CPU1_P2_RX_BUF_DP<5>")
	)
	(segment
		(start 134.561072 -416.26282)
		(end 134.91337 -416.615118)
		(width 0.14224)
		(layer "In15.Cu")
		(net "P5E_CPU1_P2_RX_BUF_DP<5>")
	)
	(segment
		(start 143.78686 -400.215862)
		(end 143.387826 -400.367754)
		(width 0.14224)
		(layer "In15.Cu")
		(net "P5E_CPU1_P2_RX_BUF_DP<5>")
	)
	(segment
		(start 134.06501 -415.766758)
		(end 134.259066 -415.766758)
		(width 0.14224)
		(layer "In15.Cu")
		(net "P5E_CPU1_P2_RX_BUF_DP<5>")
	)
	(segment
		(start 139.453874 -401.866608)
		(end 139.05484 -402.0185)
		(width 0.14224)
		(layer "In15.Cu")
		(net "P5E_CPU1_P2_RX_BUF_DP<5>")
	)
	(segment
		(start 141.16304 -401.215352)
		(end 140.986002 -401.13585)
		(width 0.14224)
		(layer "In15.Cu")
		(net "P5E_CPU1_P2_RX_BUF_DP<5>")
	)
	(segment
		(start 150.395686 -397.814546)
		(end 149.751796 -398.244822)
		(width 0.14224)
		(layer "In15.Cu")
		(net "P5E_CPU1_P2_RX_BUF_DP<5>")
	)
	(segment
		(start 135.028686 -405.560276)
		(end 134.713218 -405.771096)
		(width 0.14224)
		(layer "In15.Cu")
		(net "P5E_CPU1_P2_RX_BUF_DP<5>")
	)
	(segment
		(start 147.457414 -398.83207)
		(end 144.264888 -399.886932)
		(width 0.14224)
		(layer "In15.Cu")
		(net "P5E_CPU1_P2_RX_BUF_DP<5>")
	)
	(segment
		(start 139.931902 -401.537424)
		(end 139.533376 -401.689316)
		(width 0.14224)
		(layer "In15.Cu")
		(net "P5E_CPU1_P2_RX_BUF_DP<5>")
	)
	(segment
		(start 141.641576 -400.886168)
		(end 141.562074 -401.06346)
		(width 0.14224)
		(layer "In15.Cu")
		(net "P5E_CPU1_P2_RX_BUF_DP<5>")
	)
	(segment
		(start 134.713218 -405.771096)
		(end 134.437628 -405.885142)
		(width 0.14224)
		(layer "In15.Cu")
		(net "P5E_CPU1_P2_RX_BUF_DP<5>")
	)
	(segment
		(start 133.846316 -407.487374)
		(end 133.983476 -407.624534)
		(width 0.14224)
		(layer "In15.Cu")
		(net "P5E_CPU1_P2_RX_BUF_DP<5>")
	)
	(segment
		(start 153.317194 -393.017756)
		(end 153.127456 -393.017756)
		(width 0.14224)
		(layer "In15.Cu")
		(net "P5E_CPU1_P2_RX_BUF_DP<5>")
	)
	(segment
		(start 135.692388 -403.576028)
		(end 135.523478 -403.744938)
		(width 0.14224)
		(layer "In15.Cu")
		(net "P5E_CPU1_P2_RX_BUF_DP<5>")
	)
	(segment
		(start 135.275066 -438.341262)
		(end 135.599678 -438.341262)
		(width 0.14224)
		(layer "In15.Cu")
		(net "P5E_CPU1_P2_RX_BUF_DP<5>")
	)
	(segment
		(start 142.616174 -400.661886)
		(end 142.21714 -400.813778)
		(width 0.14224)
		(layer "In15.Cu")
		(net "P5E_CPU1_P2_RX_BUF_DP<5>")
	)
	(segment
		(start 138.399774 -402.268182)
		(end 138.00074 -402.420074)
		(width 0.14224)
		(layer "In15.Cu")
		(net "P5E_CPU1_P2_RX_BUF_DP<5>")
	)
	(segment
		(start 143.387826 -400.367754)
		(end 143.210788 -400.288506)
		(width 0.14224)
		(layer "In15.Cu")
		(net "P5E_CPU1_P2_RX_BUF_DP<5>")
	)
	(segment
		(start 149.751796 -398.244822)
		(end 149.143212 -398.49679)
		(width 0.14224)
		(layer "In15.Cu")
		(net "P5E_CPU1_P2_RX_BUF_DP<5>")
	)
	(segment
		(start 144.264888 -399.886932)
		(end 143.866362 -400.03857)
		(width 0.14224)
		(layer "In15.Cu")
		(net "P5E_CPU1_P2_RX_BUF_DP<5>")
	)
	(segment
		(start 143.866362 -400.03857)
		(end 143.78686 -400.215862)
		(width 0.14224)
		(layer "In15.Cu")
		(net "P5E_CPU1_P2_RX_BUF_DP<5>")
	)
	(segment
		(start 138.877802 -401.938998)
		(end 138.479276 -402.09089)
		(width 0.14224)
		(layer "In15.Cu")
		(net "P5E_CPU1_P2_RX_BUF_DP<5>")
	)
	(segment
		(start 152.985216 -393.159996)
		(end 152.985216 -395.125448)
		(width 0.14224)
		(layer "In15.Cu")
		(net "P5E_CPU1_P2_RX_BUF_DP<5>")
	)
	(segment
		(start 143.210788 -400.288506)
		(end 142.695676 -400.484594)
		(width 0.14224)
		(layer "In15.Cu")
		(net "P5E_CPU1_P2_RX_BUF_DP<5>")
	)
	(segment
		(start 133.846316 -409.316174)
		(end 133.846316 -410.652722)
		(width 0.14224)
		(layer "In15.Cu")
		(net "P5E_CPU1_P2_RX_BUF_DP<5>")
	)
	(segment
		(start 140.587476 -401.287742)
		(end 140.507974 -401.465034)
		(width 0.14224)
		(layer "In15.Cu")
		(net "P5E_CPU1_P2_RX_BUF_DP<5>")
	)
	(segment
		(start 133.846316 -408.188414)
		(end 133.846316 -408.615134)
		(width 0.14224)
		(layer "In15.Cu")
		(net "P5E_CPU1_P2_RX_BUF_DP<5>")
	)
	(segment
		(start 140.10894 -401.616926)
		(end 139.931902 -401.537424)
		(width 0.14224)
		(layer "In15.Cu")
		(net "P5E_CPU1_P2_RX_BUF_DP<5>")
	)
	(segment
		(start 133.676898 -411.075632)
		(end 133.506464 -411.254194)
		(width 0.14224)
		(layer "In15.Cu")
		(net "P5E_CPU1_P2_RX_BUF_DP<5>")
	)
	(segment
		(start 139.533376 -401.689316)
		(end 139.453874 -401.866608)
		(width 0.14224)
		(layer "In15.Cu")
		(net "P5E_CPU1_P2_RX_BUF_DP<5>")
	)
	(segment
		(start 139.05484 -402.0185)
		(end 138.877802 -401.938998)
		(width 0.14224)
		(layer "In15.Cu")
		(net "P5E_CPU1_P2_RX_BUF_DP<5>")
	)
	(segment
		(start 132.43179 -414.133538)
		(end 134.06501 -415.766758)
		(width 0.14224)
		(layer "In15.Cu")
		(net "P5E_CPU1_P2_RX_BUF_DP<5>")
	)
	(segment
		(start 133.983476 -407.624534)
		(end 133.983476 -408.051254)
		(width 0.14224)
		(layer "In15.Cu")
		(net "P5E_CPU1_P2_RX_BUF_DP<5>")
	)
	(segment
		(start 133.983476 -408.051254)
		(end 133.846316 -408.188414)
		(width 0.14224)
		(layer "In15.Cu")
		(net "P5E_CPU1_P2_RX_BUF_DP<5>")
	)
	(segment
		(start 151.041608 -397.284194)
		(end 150.395686 -397.814546)
		(width 0.14224)
		(layer "In15.Cu")
		(net "P5E_CPU1_P2_RX_BUF_DP<5>")
	)
	(segment
		(start 132.314696 -411.967934)
		(end 132.314696 -413.850836)
		(width 0.14224)
		(layer "In15.Cu")
		(net "P5E_CPU1_P2_RX_BUF_DP<5>")
	)
	(segment
		(start 133.983476 -409.179014)
		(end 133.846316 -409.316174)
		(width 0.14224)
		(layer "In15.Cu")
		(net "P5E_CPU1_P2_RX_BUF_DP<5>")
	)
	(segment
		(start 140.986002 -401.13585)
		(end 140.587476 -401.287742)
		(width 0.14224)
		(layer "In15.Cu")
		(net "P5E_CPU1_P2_RX_BUF_DP<5>")
	)
	(segment
		(start 141.562074 -401.06346)
		(end 141.16304 -401.215352)
		(width 0.14224)
		(layer "In15.Cu")
		(net "P5E_CPU1_P2_RX_BUF_DP<5>")
	)
	(segment
		(start 152.985216 -395.125448)
		(end 152.833324 -395.492224)
		(width 0.14224)
		(layer "In15.Cu")
		(net "P5E_CPU1_P2_RX_BUF_DP<5>")
	)
	(segment
		(start 153.444194 -393.144756)
		(end 153.317194 -393.017756)
		(width 0.14224)
		(layer "In15.Cu")
		(net "P5E_CPU1_P2_RX_BUF_DP<5>")
	)
	(segment
		(start 135.377936 -404.09622)
		(end 135.377936 -404.924514)
		(width 0.14224)
		(layer "In15.Cu")
		(net "P5E_CPU1_P2_RX_BUF_DP<5>")
	)
	(segment
		(start 153.127456 -393.017756)
		(end 152.985216 -393.159996)
		(width 0.14224)
		(layer "In15.Cu")
		(net "P5E_CPU1_P2_RX_BUF_DP<5>")
	)
	(segment
		(start 133.983476 -408.752294)
		(end 133.983476 -409.179014)
		(width 0.14224)
		(layer "In15.Cu")
		(net "P5E_CPU1_P2_RX_BUF_DP<5>")
	)
	(segment
		(start 135.082788 -417.024058)
		(end 135.082788 -438.148984)
		(width 0.14224)
		(layer "In15.Cu")
		(net "P5E_CPU1_P2_RX_BUF_DP<5>")
	)
	(segment
		(start 135.175498 -405.413464)
		(end 135.028686 -405.560276)
		(width 0.14224)
		(layer "In15.Cu")
		(net "P5E_CPU1_P2_RX_BUF_DP<5>")
	)
	(segment
		(start 137.823702 -402.340572)
		(end 137.425176 -402.492464)
		(width 0.14224)
		(layer "In15.Cu")
		(net "P5E_CPU1_P2_RX_BUF_DP<5>")
	)
	(segment
		(start 142.21714 -400.813778)
		(end 142.040102 -400.734276)
		(width 0.14224)
		(layer "In15.Cu")
		(net "P5E_CPU1_P2_RX_BUF_DP<5>")
	)
	(segment
		(start 138.00074 -402.420074)
		(end 137.823702 -402.340572)
		(width 0.14224)
		(layer "In15.Cu")
		(net "P5E_CPU1_P2_RX_BUF_DP<5>")
	)
	(segment
		(start 133.846316 -408.615134)
		(end 133.983476 -408.752294)
		(width 0.14224)
		(layer "In15.Cu")
		(net "P5E_CPU1_P2_RX_BUF_DP<5>")
	)
	(segment
		(start 134.561072 -416.068764)
		(end 134.561072 -416.26282)
		(width 0.14224)
		(layer "In15.Cu")
		(net "P5E_CPU1_P2_RX_BUF_DP<5>")
	)
	(segment
		(start 135.599678 -438.341262)
		(end 135.749792 -438.191148)
		(width 0.14224)
		(layer "In15.Cu")
		(net "P5E_CPU1_P2_RX_BUF_DP<5>")
	)
	(segment
		(start 142.040102 -400.734276)
		(end 141.641576 -400.886168)
		(width 0.14224)
		(layer "In15.Cu")
		(net "P5E_CPU1_P2_RX_BUF_DP<5>")
	)
	(segment
		(start 138.479276 -402.09089)
		(end 138.399774 -402.268182)
		(width 0.14224)
		(layer "In15.Cu")
		(net "P5E_CPU1_P2_RX_BUF_DP<5>")
	)
	(segment
		(start 149.143212 -398.49679)
		(end 147.457414 -398.83207)
		(width 0.14224)
		(layer "In15.Cu")
		(net "P5E_CPU1_P2_RX_BUF_DP<5>")
	)
	(segment
		(start 135.749792 -438.191148)
		(end 135.749792 -437.889904)
		(width 0.14224)
		(layer "In15.Cu")
		(net "P5E_CPU1_P2_RX_BUF_DP<5>")
	)
	(segment
		(start 135.082788 -438.148984)
		(end 135.275066 -438.341262)
		(width 0.14224)
		(layer "In15.Cu")
		(net "P5E_CPU1_P2_RX_BUF_DP<5>")
	)
	(segment
		(start 137.425176 -402.492464)
		(end 136.38149 -403.060662)
		(width 0.14224)
		(layer "In15.Cu")
		(net "P5E_CPU1_P2_RX_BUF_DP<5>")
	)
	(segment
		(start 134.259066 -415.766758)
		(end 134.561072 -416.068764)
		(width 0.14224)
		(layer "In15.Cu")
		(net "P5E_CPU1_P2_RX_BUF_DP<5>")
	)
	(segment
		(start 152.833324 -395.492224)
		(end 151.041608 -397.284194)
		(width 0.14224)
		(layer "In15.Cu")
		(net "P5E_CPU1_P2_RX_BUF_DP<5>")
	)
	(segment
		(start 153.444194 -393.292838)
		(end 153.444194 -393.144756)
		(width 0.14224)
		(layer "In15.Cu")
		(net "P5E_CPU1_P2_RX_BUF_DP<5>")
	)
	(segment
		(start 140.507974 -401.465034)
		(end 140.10894 -401.616926)
		(width 0.14224)
		(layer "In15.Cu")
		(net "P5E_CPU1_P2_RX_BUF_DP<5>")
	)
	(arc
		(start 134.91337 -416.615118)
		(mid 135.038736 -416.802741)
		(end 135.082788 -417.024058)
		(width 0.14224)
		(layer "In15.Cu")
		(net "P5E_CPU1_P2_RX_BUF_DP<5>")
	)
	(arc
		(start 134.437628 -405.885142)
		(mid 134.231746 -405.995288)
		(end 134.051294 -406.14346)
		(width 0.14224)
		(layer "In15.Cu")
		(net "P5E_CPU1_P2_RX_BUF_DP<5>")
	)
	(arc
		(start 133.846316 -410.652722)
		(mid 133.802444 -410.880543)
		(end 133.676898 -411.075632)
		(width 0.14224)
		(layer "In15.Cu")
		(net "P5E_CPU1_P2_RX_BUF_DP<5>")
	)
	(arc
		(start 134.051294 -406.14346)
		(mid 133.899531 -406.370445)
		(end 133.846316 -406.638252)
		(width 0.14224)
		(layer "In15.Cu")
		(net "P5E_CPU1_P2_RX_BUF_DP<5>")
	)
	(arc
		(start 135.377936 -404.924514)
		(mid 135.325322 -405.189111)
		(end 135.175498 -405.413464)
		(width 0.14224)
		(layer "In15.Cu")
		(net "P5E_CPU1_P2_RX_BUF_DP<5>")
	)
	(arc
		(start 132.335016 -411.842966)
		(mid 132.319791 -411.904626)
		(end 132.314696 -411.967934)
		(width 0.14224)
		(layer "In15.Cu")
		(net "P5E_CPU1_P2_RX_BUF_DP<5>")
	)
	(arc
		(start 132.527294 -411.624526)
		(mid 132.46971 -411.65214)
		(end 132.421376 -411.693868)
		(width 0.14224)
		(layer "In15.Cu")
		(net "P5E_CPU1_P2_RX_BUF_DP<5>")
	)
	(arc
		(start 136.38149 -403.060662)
		(mid 136.018429 -403.293596)
		(end 135.692388 -403.576028)
		(width 0.14224)
		(layer "In15.Cu")
		(net "P5E_CPU1_P2_RX_BUF_DP<5>")
	)
	(arc
		(start 133.506464 -411.254194)
		(mid 133.428478 -411.317891)
		(end 133.3373 -411.36062)
		(width 0.14224)
		(layer "In15.Cu")
		(net "P5E_CPU1_P2_RX_BUF_DP<5>")
	)
	(arc
		(start 135.523478 -403.744938)
		(mid 135.415788 -403.906108)
		(end 135.377936 -404.09622)
		(width 0.14224)
		(layer "In15.Cu")
		(net "P5E_CPU1_P2_RX_BUF_DP<5>")
	)
	(arc
		(start 132.421376 -411.693868)
		(mid 132.370643 -411.764041)
		(end 132.335016 -411.842966)
		(width 0.14224)
		(layer "In15.Cu")
		(net "P5E_CPU1_P2_RX_BUF_DP<5>")
	)
	(arc
		(start 132.314696 -413.850836)
		(mid 132.345129 -414.003831)
		(end 132.43179 -414.133538)
		(width 0.14224)
		(layer "In15.Cu")
		(net "P5E_CPU1_P2_RX_BUF_DP<5>")
	)
	(segment
		(start 151.63038 -391.488676)
		(end 151.541734 -391.577322)
		(width 0.1016)
		(layer "F.Cu")
		(net "P5E_CPU1_P2_RX_BUF_DP<4>")
	)
	(segment
		(start 151.541734 -391.577322)
		(end 151.541734 -392.723878)
		(width 0.1016)
		(layer "F.Cu")
		(net "P5E_CPU1_P2_RX_BUF_DP<4>")
	)
	(segment
		(start 151.794972 -392.977116)
		(end 152.105614 -392.977116)
		(width 0.1016)
		(layer "F.Cu")
		(net "P5E_CPU1_P2_RX_BUF_DP<4>")
	)
	(segment
		(start 152.244298 -393.1158)
		(end 152.244298 -393.292838)
		(width 0.1016)
		(layer "F.Cu")
		(net "P5E_CPU1_P2_RX_BUF_DP<4>")
	)
	(segment
		(start 151.545798 -391.281158)
		(end 151.63038 -391.36574)
		(width 0.1016)
		(layer "F.Cu")
		(net "P5E_CPU1_P2_RX_BUF_DP<4>")
	)
	(segment
		(start 151.541734 -392.723878)
		(end 151.794972 -392.977116)
		(width 0.1016)
		(layer "F.Cu")
		(net "P5E_CPU1_P2_RX_BUF_DP<4>")
	)
	(segment
		(start 152.105614 -392.977116)
		(end 152.244298 -393.1158)
		(width 0.1016)
		(layer "F.Cu")
		(net "P5E_CPU1_P2_RX_BUF_DP<4>")
	)
	(segment
		(start 151.63038 -391.36574)
		(end 151.63038 -391.488676)
		(width 0.1016)
		(layer "F.Cu")
		(net "P5E_CPU1_P2_RX_BUF_DP<4>")
	)
	(segment
		(start 133.599682 -437.341264)
		(end 133.749796 -437.19115)
		(width 0.14224)
		(layer "In15.Cu")
		(net "P5E_CPU1_P2_RX_BUF_DP<4>")
	)
	(segment
		(start 152.244298 -393.144756)
		(end 152.117298 -393.017756)
		(width 0.14224)
		(layer "In15.Cu")
		(net "P5E_CPU1_P2_RX_BUF_DP<4>")
	)
	(segment
		(start 151.325072 -395.632432)
		(end 150.183596 -396.773908)
		(width 0.14224)
		(layer "In15.Cu")
		(net "P5E_CPU1_P2_RX_BUF_DP<4>")
	)
	(segment
		(start 140.130022 -400.274028)
		(end 139.724638 -400.40814)
		(width 0.14224)
		(layer "In15.Cu")
		(net "P5E_CPU1_P2_RX_BUF_DP<4>")
	)
	(segment
		(start 130.783076 -408.796744)
		(end 130.920236 -408.933904)
		(width 0.14224)
		(layer "In15.Cu")
		(net "P5E_CPU1_P2_RX_BUF_DP<4>")
	)
	(segment
		(start 131.423664 -415.36493)
		(end 131.72567 -415.666936)
		(width 0.14224)
		(layer "In15.Cu")
		(net "P5E_CPU1_P2_RX_BUF_DP<4>")
	)
	(segment
		(start 131.72567 -415.860992)
		(end 132.027168 -416.16249)
		(width 0.14224)
		(layer "In15.Cu")
		(net "P5E_CPU1_P2_RX_BUF_DP<4>")
	)
	(segment
		(start 136.161018 -401.734528)
		(end 135.768842 -401.902422)
		(width 0.14224)
		(layer "In15.Cu")
		(net "P5E_CPU1_P2_RX_BUF_DP<4>")
	)
	(segment
		(start 130.783076 -409.497784)
		(end 130.783076 -410.697172)
		(width 0.14224)
		(layer "In15.Cu")
		(net "P5E_CPU1_P2_RX_BUF_DP<4>")
	)
	(segment
		(start 132.221224 -416.16249)
		(end 132.52323 -416.464496)
		(width 0.14224)
		(layer "In15.Cu")
		(net "P5E_CPU1_P2_RX_BUF_DP<4>")
	)
	(segment
		(start 151.92756 -393.017756)
		(end 151.78532 -393.159996)
		(width 0.14224)
		(layer "In15.Cu")
		(net "P5E_CPU1_P2_RX_BUF_DP<4>")
	)
	(segment
		(start 135.768842 -401.902422)
		(end 135.696706 -402.082762)
		(width 0.14224)
		(layer "In15.Cu")
		(net "P5E_CPU1_P2_RX_BUF_DP<4>")
	)
	(segment
		(start 134.659878 -402.527008)
		(end 134.267448 -402.694902)
		(width 0.14224)
		(layer "In15.Cu")
		(net "P5E_CPU1_P2_RX_BUF_DP<4>")
	)
	(segment
		(start 152.117298 -393.017756)
		(end 151.92756 -393.017756)
		(width 0.14224)
		(layer "In15.Cu")
		(net "P5E_CPU1_P2_RX_BUF_DP<4>")
	)
	(segment
		(start 135.12419 -402.178774)
		(end 134.732014 -402.346668)
		(width 0.14224)
		(layer "In15.Cu")
		(net "P5E_CPU1_P2_RX_BUF_DP<4>")
	)
	(segment
		(start 134.267448 -402.694902)
		(end 134.087362 -402.62302)
		(width 0.14224)
		(layer "In15.Cu")
		(net "P5E_CPU1_P2_RX_BUF_DP<4>")
	)
	(segment
		(start 132.52323 -416.464496)
		(end 132.52323 -416.658552)
		(width 0.14224)
		(layer "In15.Cu")
		(net "P5E_CPU1_P2_RX_BUF_DP<4>")
	)
	(segment
		(start 132.112258 -405.413464)
		(end 131.965446 -405.560276)
		(width 0.14224)
		(layer "In15.Cu")
		(net "P5E_CPU1_P2_RX_BUF_DP<4>")
	)
	(segment
		(start 151.595582 -395.227556)
		(end 151.325072 -395.632432)
		(width 0.14224)
		(layer "In15.Cu")
		(net "P5E_CPU1_P2_RX_BUF_DP<4>")
	)
	(segment
		(start 152.244298 -393.292838)
		(end 152.244298 -393.144756)
		(width 0.14224)
		(layer "In15.Cu")
		(net "P5E_CPU1_P2_RX_BUF_DP<4>")
	)
	(segment
		(start 131.72567 -415.666936)
		(end 131.72567 -415.860992)
		(width 0.14224)
		(layer "In15.Cu")
		(net "P5E_CPU1_P2_RX_BUF_DP<4>")
	)
	(segment
		(start 134.087362 -402.62302)
		(end 133.695186 -402.790914)
		(width 0.14224)
		(layer "In15.Cu")
		(net "P5E_CPU1_P2_RX_BUF_DP<4>")
	)
	(segment
		(start 148.970746 -397.483838)
		(end 147.990814 -397.678656)
		(width 0.14224)
		(layer "In15.Cu")
		(net "P5E_CPU1_P2_RX_BUF_DP<4>")
	)
	(segment
		(start 147.990814 -397.678656)
		(end 145.721324 -398.277588)
		(width 0.14224)
		(layer "In15.Cu")
		(net "P5E_CPU1_P2_RX_BUF_DP<4>")
	)
	(segment
		(start 130.783076 -408.32659)
		(end 130.783076 -408.796744)
		(width 0.14224)
		(layer "In15.Cu")
		(net "P5E_CPU1_P2_RX_BUF_DP<4>")
	)
	(segment
		(start 137.770362 -401.19427)
		(end 137.377932 -401.362164)
		(width 0.14224)
		(layer "In15.Cu")
		(net "P5E_CPU1_P2_RX_BUF_DP<4>")
	)
	(segment
		(start 130.920236 -408.18943)
		(end 130.783076 -408.32659)
		(width 0.14224)
		(layer "In15.Cu")
		(net "P5E_CPU1_P2_RX_BUF_DP<4>")
	)
	(segment
		(start 132.52323 -416.658552)
		(end 132.786374 -416.921696)
		(width 0.14224)
		(layer "In15.Cu")
		(net "P5E_CPU1_P2_RX_BUF_DP<4>")
	)
	(segment
		(start 129.251456 -411.853126)
		(end 129.251456 -413.287464)
		(width 0.14224)
		(layer "In15.Cu")
		(net "P5E_CPU1_P2_RX_BUF_DP<4>")
	)
	(segment
		(start 131.229608 -415.36493)
		(end 131.423664 -415.36493)
		(width 0.14224)
		(layer "In15.Cu")
		(net "P5E_CPU1_P2_RX_BUF_DP<4>")
	)
	(segment
		(start 139.724638 -400.40814)
		(end 139.551156 -400.321018)
		(width 0.14224)
		(layer "In15.Cu")
		(net "P5E_CPU1_P2_RX_BUF_DP<4>")
	)
	(segment
		(start 136.80567 -401.458176)
		(end 136.733534 -401.638516)
		(width 0.14224)
		(layer "In15.Cu")
		(net "P5E_CPU1_P2_RX_BUF_DP<4>")
	)
	(segment
		(start 150.183596 -396.773908)
		(end 149.365716 -397.320262)
		(width 0.14224)
		(layer "In15.Cu")
		(net "P5E_CPU1_P2_RX_BUF_DP<4>")
	)
	(segment
		(start 137.197846 -401.290282)
		(end 136.80567 -401.458176)
		(width 0.14224)
		(layer "In15.Cu")
		(net "P5E_CPU1_P2_RX_BUF_DP<4>")
	)
	(segment
		(start 132.314696 -404.07844)
		(end 132.314696 -404.924514)
		(width 0.14224)
		(layer "In15.Cu")
		(net "P5E_CPU1_P2_RX_BUF_DP<4>")
	)
	(segment
		(start 149.365716 -397.320262)
		(end 148.970746 -397.483838)
		(width 0.14224)
		(layer "In15.Cu")
		(net "P5E_CPU1_P2_RX_BUF_DP<4>")
	)
	(segment
		(start 131.965446 -405.560276)
		(end 131.649978 -405.771096)
		(width 0.14224)
		(layer "In15.Cu")
		(net "P5E_CPU1_P2_RX_BUF_DP<4>")
	)
	(segment
		(start 130.783076 -406.638252)
		(end 130.783076 -407.62555)
		(width 0.14224)
		(layer "In15.Cu")
		(net "P5E_CPU1_P2_RX_BUF_DP<4>")
	)
	(segment
		(start 130.920236 -407.76271)
		(end 130.920236 -408.18943)
		(width 0.14224)
		(layer "In15.Cu")
		(net "P5E_CPU1_P2_RX_BUF_DP<4>")
	)
	(segment
		(start 137.842498 -401.01393)
		(end 137.770362 -401.19427)
		(width 0.14224)
		(layer "In15.Cu")
		(net "P5E_CPU1_P2_RX_BUF_DP<4>")
	)
	(segment
		(start 151.78532 -394.769594)
		(end 151.595582 -395.227556)
		(width 0.14224)
		(layer "In15.Cu")
		(net "P5E_CPU1_P2_RX_BUF_DP<4>")
	)
	(segment
		(start 134.732014 -402.346668)
		(end 134.659878 -402.527008)
		(width 0.14224)
		(layer "In15.Cu")
		(net "P5E_CPU1_P2_RX_BUF_DP<4>")
	)
	(segment
		(start 130.291586 -411.31998)
		(end 129.345436 -411.71241)
		(width 0.14224)
		(layer "In15.Cu")
		(net "P5E_CPU1_P2_RX_BUF_DP<4>")
	)
	(segment
		(start 139.14628 -400.45513)
		(end 137.842498 -401.01393)
		(width 0.14224)
		(layer "In15.Cu")
		(net "P5E_CPU1_P2_RX_BUF_DP<4>")
	)
	(segment
		(start 133.071108 -417.60902)
		(end 133.071108 -437.204104)
		(width 0.14224)
		(layer "In15.Cu")
		(net "P5E_CPU1_P2_RX_BUF_DP<4>")
	)
	(segment
		(start 132.027168 -416.16249)
		(end 132.221224 -416.16249)
		(width 0.14224)
		(layer "In15.Cu")
		(net "P5E_CPU1_P2_RX_BUF_DP<4>")
	)
	(segment
		(start 137.377932 -401.362164)
		(end 137.197846 -401.290282)
		(width 0.14224)
		(layer "In15.Cu")
		(net "P5E_CPU1_P2_RX_BUF_DP<4>")
	)
	(segment
		(start 130.920236 -409.360624)
		(end 130.783076 -409.497784)
		(width 0.14224)
		(layer "In15.Cu")
		(net "P5E_CPU1_P2_RX_BUF_DP<4>")
	)
	(segment
		(start 145.721324 -398.277588)
		(end 140.21689 -400.100546)
		(width 0.14224)
		(layer "In15.Cu")
		(net "P5E_CPU1_P2_RX_BUF_DP<4>")
	)
	(segment
		(start 132.570982 -403.551644)
		(end 132.505958 -403.616668)
		(width 0.14224)
		(layer "In15.Cu")
		(net "P5E_CPU1_P2_RX_BUF_DP<4>")
	)
	(segment
		(start 139.551156 -400.321018)
		(end 139.14628 -400.45513)
		(width 0.14224)
		(layer "In15.Cu")
		(net "P5E_CPU1_P2_RX_BUF_DP<4>")
	)
	(segment
		(start 133.071108 -437.204104)
		(end 133.208268 -437.341264)
		(width 0.14224)
		(layer "In15.Cu")
		(net "P5E_CPU1_P2_RX_BUF_DP<4>")
	)
	(segment
		(start 130.920236 -408.933904)
		(end 130.920236 -409.360624)
		(width 0.14224)
		(layer "In15.Cu")
		(net "P5E_CPU1_P2_RX_BUF_DP<4>")
	)
	(segment
		(start 133.208268 -437.341264)
		(end 133.599682 -437.341264)
		(width 0.14224)
		(layer "In15.Cu")
		(net "P5E_CPU1_P2_RX_BUF_DP<4>")
	)
	(segment
		(start 140.21689 -400.100546)
		(end 140.130022 -400.274028)
		(width 0.14224)
		(layer "In15.Cu")
		(net "P5E_CPU1_P2_RX_BUF_DP<4>")
	)
	(segment
		(start 151.78532 -393.159996)
		(end 151.78532 -394.769594)
		(width 0.14224)
		(layer "In15.Cu")
		(net "P5E_CPU1_P2_RX_BUF_DP<4>")
	)
	(segment
		(start 131.649978 -405.771096)
		(end 131.374388 -405.885142)
		(width 0.14224)
		(layer "In15.Cu")
		(net "P5E_CPU1_P2_RX_BUF_DP<4>")
	)
	(segment
		(start 135.696706 -402.082762)
		(end 135.304276 -402.250656)
		(width 0.14224)
		(layer "In15.Cu")
		(net "P5E_CPU1_P2_RX_BUF_DP<4>")
	)
	(segment
		(start 130.783076 -407.62555)
		(end 130.920236 -407.76271)
		(width 0.14224)
		(layer "In15.Cu")
		(net "P5E_CPU1_P2_RX_BUF_DP<4>")
	)
	(segment
		(start 133.749796 -437.19115)
		(end 133.749796 -436.889906)
		(width 0.14224)
		(layer "In15.Cu")
		(net "P5E_CPU1_P2_RX_BUF_DP<4>")
	)
	(segment
		(start 135.304276 -402.250656)
		(end 135.12419 -402.178774)
		(width 0.14224)
		(layer "In15.Cu")
		(net "P5E_CPU1_P2_RX_BUF_DP<4>")
	)
	(segment
		(start 136.341104 -401.80641)
		(end 136.161018 -401.734528)
		(width 0.14224)
		(layer "In15.Cu")
		(net "P5E_CPU1_P2_RX_BUF_DP<4>")
	)
	(segment
		(start 129.32156 -413.456882)
		(end 131.229608 -415.36493)
		(width 0.14224)
		(layer "In15.Cu")
		(net "P5E_CPU1_P2_RX_BUF_DP<4>")
	)
	(segment
		(start 136.733534 -401.638516)
		(end 136.341104 -401.80641)
		(width 0.14224)
		(layer "In15.Cu")
		(net "P5E_CPU1_P2_RX_BUF_DP<4>")
	)
	(arc
		(start 130.783076 -410.697172)
		(mid 130.737424 -410.910581)
		(end 130.608324 -411.086554)
		(width 0.14224)
		(layer "In15.Cu")
		(net "P5E_CPU1_P2_RX_BUF_DP<4>")
	)
	(arc
		(start 130.608324 -411.086554)
		(mid 130.464238 -411.222646)
		(end 130.291586 -411.31998)
		(width 0.14224)
		(layer "In15.Cu")
		(net "P5E_CPU1_P2_RX_BUF_DP<4>")
	)
	(arc
		(start 132.314696 -404.924514)
		(mid 132.262082 -405.189111)
		(end 132.112258 -405.413464)
		(width 0.14224)
		(layer "In15.Cu")
		(net "P5E_CPU1_P2_RX_BUF_DP<4>")
	)
	(arc
		(start 129.345436 -411.71241)
		(mid 129.277138 -411.76853)
		(end 129.251456 -411.853126)
		(width 0.14224)
		(layer "In15.Cu")
		(net "P5E_CPU1_P2_RX_BUF_DP<4>")
	)
	(arc
		(start 133.695186 -402.790914)
		(mid 133.096785 -403.117634)
		(end 132.570982 -403.551644)
		(width 0.14224)
		(layer "In15.Cu")
		(net "P5E_CPU1_P2_RX_BUF_DP<4>")
	)
	(arc
		(start 132.786374 -416.921696)
		(mid 132.997082 -417.237043)
		(end 133.071108 -417.60902)
		(width 0.14224)
		(layer "In15.Cu")
		(net "P5E_CPU1_P2_RX_BUF_DP<4>")
	)
	(arc
		(start 129.251456 -413.287464)
		(mid 129.269674 -413.379139)
		(end 129.32156 -413.456882)
		(width 0.14224)
		(layer "In15.Cu")
		(net "P5E_CPU1_P2_RX_BUF_DP<4>")
	)
	(arc
		(start 132.505958 -403.616668)
		(mid 132.364396 -403.828531)
		(end 132.314696 -404.07844)
		(width 0.14224)
		(layer "In15.Cu")
		(net "P5E_CPU1_P2_RX_BUF_DP<4>")
	)
	(arc
		(start 131.374388 -405.885142)
		(mid 131.168506 -405.995288)
		(end 130.988054 -406.14346)
		(width 0.14224)
		(layer "In15.Cu")
		(net "P5E_CPU1_P2_RX_BUF_DP<4>")
	)
	(arc
		(start 130.988054 -406.14346)
		(mid 130.836291 -406.370445)
		(end 130.783076 -406.638252)
		(width 0.14224)
		(layer "In15.Cu")
		(net "P5E_CPU1_P2_RX_BUF_DP<4>")
	)
	(segment
		(start 150.354792 -392.723878)
		(end 150.60803 -392.977116)
		(width 0.1016)
		(layer "F.Cu")
		(net "P5E_CPU1_P2_RX_BUF_DP<3>")
	)
	(segment
		(start 150.354792 -391.564114)
		(end 150.354792 -392.723878)
		(width 0.1016)
		(layer "F.Cu")
		(net "P5E_CPU1_P2_RX_BUF_DP<3>")
	)
	(segment
		(start 151.044148 -393.1158)
		(end 151.044148 -393.292838)
		(width 0.1016)
		(layer "F.Cu")
		(net "P5E_CPU1_P2_RX_BUF_DP<3>")
	)
	(segment
		(start 150.905464 -392.977116)
		(end 151.044148 -393.1158)
		(width 0.1016)
		(layer "F.Cu")
		(net "P5E_CPU1_P2_RX_BUF_DP<3>")
	)
	(segment
		(start 150.43023 -391.36574)
		(end 150.43023 -391.488676)
		(width 0.1016)
		(layer "F.Cu")
		(net "P5E_CPU1_P2_RX_BUF_DP<3>")
	)
	(segment
		(start 150.43023 -391.488676)
		(end 150.354792 -391.564114)
		(width 0.1016)
		(layer "F.Cu")
		(net "P5E_CPU1_P2_RX_BUF_DP<3>")
	)
	(segment
		(start 150.60803 -392.977116)
		(end 150.905464 -392.977116)
		(width 0.1016)
		(layer "F.Cu")
		(net "P5E_CPU1_P2_RX_BUF_DP<3>")
	)
	(segment
		(start 150.345648 -391.281158)
		(end 150.43023 -391.36574)
		(width 0.1016)
		(layer "F.Cu")
		(net "P5E_CPU1_P2_RX_BUF_DP<3>")
	)
	(segment
		(start 131.071112 -419.249606)
		(end 131.208272 -419.112446)
		(width 0.14224)
		(layer "In15.Cu")
		(net "P5E_CPU1_P2_RX_BUF_DP<3>")
	)
	(segment
		(start 132.5118 -402.086572)
		(end 132.910326 -401.933156)
		(width 0.14224)
		(layer "In15.Cu")
		(net "P5E_CPU1_P2_RX_BUF_DP<3>")
	)
	(segment
		(start 127.719836 -408.451558)
		(end 127.856996 -408.314398)
		(width 0.14224)
		(layer "In15.Cu")
		(net "P5E_CPU1_P2_RX_BUF_DP<3>")
	)
	(segment
		(start 132.334508 -402.008086)
		(end 132.5118 -402.086572)
		(width 0.14224)
		(layer "In15.Cu")
		(net "P5E_CPU1_P2_RX_BUF_DP<3>")
	)
	(segment
		(start 133.777736 -401.598384)
		(end 134.176262 -401.444968)
		(width 0.14224)
		(layer "In15.Cu")
		(net "P5E_CPU1_P2_RX_BUF_DP<3>")
	)
	(segment
		(start 150.357332 -395.214602)
		(end 150.58517 -394.664692)
		(width 0.14224)
		(layer "In15.Cu")
		(net "P5E_CPU1_P2_RX_BUF_DP<3>")
	)
	(segment
		(start 129.491994 -415.914586)
		(end 129.298192 -415.914586)
		(width 0.14224)
		(layer "In15.Cu")
		(net "P5E_CPU1_P2_RX_BUF_DP<3>")
	)
	(segment
		(start 131.071112 -418.548566)
		(end 131.071112 -417.954968)
		(width 0.14224)
		(layer "In15.Cu")
		(net "P5E_CPU1_P2_RX_BUF_DP<3>")
	)
	(segment
		(start 134.176262 -401.444968)
		(end 134.255002 -401.267422)
		(width 0.14224)
		(layer "In15.Cu")
		(net "P5E_CPU1_P2_RX_BUF_DP<3>")
	)
	(segment
		(start 128.996694 -415.419032)
		(end 128.694688 -415.117026)
		(width 0.14224)
		(layer "In15.Cu")
		(net "P5E_CPU1_P2_RX_BUF_DP<3>")
	)
	(segment
		(start 127.856996 -409.015438)
		(end 127.719836 -408.878278)
		(width 0.14224)
		(layer "In15.Cu")
		(net "P5E_CPU1_P2_RX_BUF_DP<3>")
	)
	(segment
		(start 131.7498 -438.191148)
		(end 131.599686 -438.341262)
		(width 0.14224)
		(layer "In15.Cu")
		(net "P5E_CPU1_P2_RX_BUF_DP<3>")
	)
	(segment
		(start 131.713986 -402.2471)
		(end 132.334508 -402.008086)
		(width 0.14224)
		(layer "In15.Cu")
		(net "P5E_CPU1_P2_RX_BUF_DP<3>")
	)
	(segment
		(start 128.996694 -415.613088)
		(end 128.996694 -415.419032)
		(width 0.14224)
		(layer "In15.Cu")
		(net "P5E_CPU1_P2_RX_BUF_DP<3>")
	)
	(segment
		(start 126.537466 -413.746442)
		(end 126.315216 -413.524192)
		(width 0.14224)
		(layer "In15.Cu")
		(net "P5E_CPU1_P2_RX_BUF_DP<3>")
	)
	(segment
		(start 129.298192 -415.914586)
		(end 128.996694 -415.613088)
		(width 0.14224)
		(layer "In15.Cu")
		(net "P5E_CPU1_P2_RX_BUF_DP<3>")
	)
	(segment
		(start 132.988812 -401.75561)
		(end 133.600444 -401.519898)
		(width 0.14224)
		(layer "In15.Cu")
		(net "P5E_CPU1_P2_RX_BUF_DP<3>")
	)
	(segment
		(start 130.113786 -402.864066)
		(end 131.059428 -402.499576)
		(width 0.14224)
		(layer "In15.Cu")
		(net "P5E_CPU1_P2_RX_BUF_DP<3>")
	)
	(segment
		(start 130.881882 -417.498276)
		(end 129.794 -416.410394)
		(width 0.14224)
		(layer "In15.Cu")
		(net "P5E_CPU1_P2_RX_BUF_DP<3>")
	)
	(segment
		(start 129.251456 -404.924514)
		(end 129.251456 -403.724872)
		(width 0.14224)
		(layer "In15.Cu")
		(net "P5E_CPU1_P2_RX_BUF_DP<3>")
	)
	(segment
		(start 128.311148 -405.885142)
		(end 128.586738 -405.771096)
		(width 0.14224)
		(layer "In15.Cu")
		(net "P5E_CPU1_P2_RX_BUF_DP<3>")
	)
	(segment
		(start 149.075902 -396.340076)
		(end 149.63775 -395.934184)
		(width 0.14224)
		(layer "In15.Cu")
		(net "P5E_CPU1_P2_RX_BUF_DP<3>")
	)
	(segment
		(start 127.856996 -407.887678)
		(end 127.719836 -407.750518)
		(width 0.14224)
		(layer "In15.Cu")
		(net "P5E_CPU1_P2_RX_BUF_DP<3>")
	)
	(segment
		(start 131.599686 -438.341262)
		(end 131.208272 -438.341262)
		(width 0.14224)
		(layer "In15.Cu")
		(net "P5E_CPU1_P2_RX_BUF_DP<3>")
	)
	(segment
		(start 131.236974 -402.578062)
		(end 131.635246 -402.424646)
		(width 0.14224)
		(layer "In15.Cu")
		(net "P5E_CPU1_P2_RX_BUF_DP<3>")
	)
	(segment
		(start 127.856996 -408.314398)
		(end 127.856996 -407.887678)
		(width 0.14224)
		(layer "In15.Cu")
		(net "P5E_CPU1_P2_RX_BUF_DP<3>")
	)
	(segment
		(start 128.500632 -415.117026)
		(end 127.460248 -414.076642)
		(width 0.14224)
		(layer "In15.Cu")
		(net "P5E_CPU1_P2_RX_BUF_DP<3>")
	)
	(segment
		(start 127.719836 -410.741876)
		(end 127.719836 -409.579318)
		(width 0.14224)
		(layer "In15.Cu")
		(net "P5E_CPU1_P2_RX_BUF_DP<3>")
	)
	(segment
		(start 132.910326 -401.933156)
		(end 132.988812 -401.75561)
		(width 0.14224)
		(layer "In15.Cu")
		(net "P5E_CPU1_P2_RX_BUF_DP<3>")
	)
	(segment
		(start 139.22883 -399.349976)
		(end 145.043144 -397.468852)
		(width 0.14224)
		(layer "In15.Cu")
		(net "P5E_CPU1_P2_RX_BUF_DP<3>")
	)
	(segment
		(start 126.295912 -411.706568)
		(end 127.209804 -411.3276)
		(width 0.14224)
		(layer "In15.Cu")
		(net "P5E_CPU1_P2_RX_BUF_DP<3>")
	)
	(segment
		(start 127.719836 -407.750518)
		(end 127.719836 -406.638252)
		(width 0.14224)
		(layer "In15.Cu")
		(net "P5E_CPU1_P2_RX_BUF_DP<3>")
	)
	(segment
		(start 131.059428 -402.499576)
		(end 131.236974 -402.578062)
		(width 0.14224)
		(layer "In15.Cu")
		(net "P5E_CPU1_P2_RX_BUF_DP<3>")
	)
	(segment
		(start 129.794 -416.216592)
		(end 129.491994 -415.914586)
		(width 0.14224)
		(layer "In15.Cu")
		(net "P5E_CPU1_P2_RX_BUF_DP<3>")
	)
	(segment
		(start 127.856996 -409.442158)
		(end 127.856996 -409.015438)
		(width 0.14224)
		(layer "In15.Cu")
		(net "P5E_CPU1_P2_RX_BUF_DP<3>")
	)
	(segment
		(start 131.208272 -438.341262)
		(end 131.071112 -438.204102)
		(width 0.14224)
		(layer "In15.Cu")
		(net "P5E_CPU1_P2_RX_BUF_DP<3>")
	)
	(segment
		(start 127.39116 -411.21711)
		(end 127.56769 -411.06852)
		(width 0.14224)
		(layer "In15.Cu")
		(net "P5E_CPU1_P2_RX_BUF_DP<3>")
	)
	(segment
		(start 133.600444 -401.519898)
		(end 133.777736 -401.598384)
		(width 0.14224)
		(layer "In15.Cu")
		(net "P5E_CPU1_P2_RX_BUF_DP<3>")
	)
	(segment
		(start 135.494014 -400.936714)
		(end 135.89254 -400.783298)
		(width 0.14224)
		(layer "In15.Cu")
		(net "P5E_CPU1_P2_RX_BUF_DP<3>")
	)
	(segment
		(start 127.719836 -408.878278)
		(end 127.719836 -408.451558)
		(width 0.14224)
		(layer "In15.Cu")
		(net "P5E_CPU1_P2_RX_BUF_DP<3>")
	)
	(segment
		(start 148.802344 -396.477744)
		(end 149.075902 -396.340076)
		(width 0.14224)
		(layer "In15.Cu")
		(net "P5E_CPU1_P2_RX_BUF_DP<3>")
	)
	(segment
		(start 126.188216 -413.217868)
		(end 126.188216 -411.868112)
		(width 0.14224)
		(layer "In15.Cu")
		(net "P5E_CPU1_P2_RX_BUF_DP<3>")
	)
	(segment
		(start 126.87935 -413.836104)
		(end 126.753874 -413.836104)
		(width 0.14224)
		(layer "In15.Cu")
		(net "P5E_CPU1_P2_RX_BUF_DP<3>")
	)
	(segment
		(start 135.97128 -400.605752)
		(end 139.22883 -399.349976)
		(width 0.14224)
		(layer "In15.Cu")
		(net "P5E_CPU1_P2_RX_BUF_DP<3>")
	)
	(segment
		(start 127.719836 -409.579318)
		(end 127.856996 -409.442158)
		(width 0.14224)
		(layer "In15.Cu")
		(net "P5E_CPU1_P2_RX_BUF_DP<3>")
	)
	(segment
		(start 149.63775 -395.934184)
		(end 150.357332 -395.214602)
		(width 0.14224)
		(layer "In15.Cu")
		(net "P5E_CPU1_P2_RX_BUF_DP<3>")
	)
	(segment
		(start 129.794 -416.410394)
		(end 129.794 -416.216592)
		(width 0.14224)
		(layer "In15.Cu")
		(net "P5E_CPU1_P2_RX_BUF_DP<3>")
	)
	(segment
		(start 131.208272 -419.112446)
		(end 131.208272 -418.685726)
		(width 0.14224)
		(layer "In15.Cu")
		(net "P5E_CPU1_P2_RX_BUF_DP<3>")
	)
	(segment
		(start 131.208272 -418.685726)
		(end 131.071112 -418.548566)
		(width 0.14224)
		(layer "In15.Cu")
		(net "P5E_CPU1_P2_RX_BUF_DP<3>")
	)
	(segment
		(start 150.72741 -393.017756)
		(end 150.917148 -393.017756)
		(width 0.14224)
		(layer "In15.Cu")
		(net "P5E_CPU1_P2_RX_BUF_DP<3>")
	)
	(segment
		(start 131.7498 -437.889904)
		(end 131.7498 -438.191148)
		(width 0.14224)
		(layer "In15.Cu")
		(net "P5E_CPU1_P2_RX_BUF_DP<3>")
	)
	(segment
		(start 131.071112 -438.204102)
		(end 131.071112 -419.249606)
		(width 0.14224)
		(layer "In15.Cu")
		(net "P5E_CPU1_P2_RX_BUF_DP<3>")
	)
	(segment
		(start 151.044148 -393.144756)
		(end 151.044148 -393.292838)
		(width 0.14224)
		(layer "In15.Cu")
		(net "P5E_CPU1_P2_RX_BUF_DP<3>")
	)
	(segment
		(start 135.316722 -400.858228)
		(end 135.494014 -400.936714)
		(width 0.14224)
		(layer "In15.Cu")
		(net "P5E_CPU1_P2_RX_BUF_DP<3>")
	)
	(segment
		(start 150.58517 -394.664692)
		(end 150.58517 -393.159996)
		(width 0.14224)
		(layer "In15.Cu")
		(net "P5E_CPU1_P2_RX_BUF_DP<3>")
	)
	(segment
		(start 150.58517 -393.159996)
		(end 150.72741 -393.017756)
		(width 0.14224)
		(layer "In15.Cu")
		(net "P5E_CPU1_P2_RX_BUF_DP<3>")
	)
	(segment
		(start 131.635246 -402.424646)
		(end 131.713986 -402.2471)
		(width 0.14224)
		(layer "In15.Cu")
		(net "P5E_CPU1_P2_RX_BUF_DP<3>")
	)
	(segment
		(start 150.917148 -393.017756)
		(end 151.044148 -393.144756)
		(width 0.14224)
		(layer "In15.Cu")
		(net "P5E_CPU1_P2_RX_BUF_DP<3>")
	)
	(segment
		(start 128.694688 -415.117026)
		(end 128.500632 -415.117026)
		(width 0.14224)
		(layer "In15.Cu")
		(net "P5E_CPU1_P2_RX_BUF_DP<3>")
	)
	(segment
		(start 135.89254 -400.783298)
		(end 135.97128 -400.605752)
		(width 0.14224)
		(layer "In15.Cu")
		(net "P5E_CPU1_P2_RX_BUF_DP<3>")
	)
	(segment
		(start 134.255002 -401.267422)
		(end 135.316722 -400.858228)
		(width 0.14224)
		(layer "In15.Cu")
		(net "P5E_CPU1_P2_RX_BUF_DP<3>")
	)
	(segment
		(start 128.902206 -405.560276)
		(end 129.049018 -405.413464)
		(width 0.14224)
		(layer "In15.Cu")
		(net "P5E_CPU1_P2_RX_BUF_DP<3>")
	)
	(segment
		(start 128.586738 -405.771096)
		(end 128.902206 -405.560276)
		(width 0.14224)
		(layer "In15.Cu")
		(net "P5E_CPU1_P2_RX_BUF_DP<3>")
	)
	(segment
		(start 145.043144 -397.468852)
		(end 148.802344 -396.477744)
		(width 0.14224)
		(layer "In15.Cu")
		(net "P5E_CPU1_P2_RX_BUF_DP<3>")
	)
	(arc
		(start 126.315216 -413.524192)
		(mid 126.221225 -413.383664)
		(end 126.188216 -413.217868)
		(width 0.14224)
		(layer "In15.Cu")
		(net "P5E_CPU1_P2_RX_BUF_DP<3>")
	)
	(arc
		(start 126.188216 -411.868112)
		(mid 126.217608 -411.771036)
		(end 126.295912 -411.706568)
		(width 0.14224)
		(layer "In15.Cu")
		(net "P5E_CPU1_P2_RX_BUF_DP<3>")
	)
	(arc
		(start 127.56769 -411.06852)
		(mid 127.67989 -410.922024)
		(end 127.719836 -410.741876)
		(width 0.14224)
		(layer "In15.Cu")
		(net "P5E_CPU1_P2_RX_BUF_DP<3>")
	)
	(arc
		(start 127.460248 -414.076642)
		(mid 127.193716 -413.898614)
		(end 126.87935 -413.836104)
		(width 0.14224)
		(layer "In15.Cu")
		(net "P5E_CPU1_P2_RX_BUF_DP<3>")
	)
	(arc
		(start 131.071112 -417.954968)
		(mid 131.021929 -417.707799)
		(end 130.881882 -417.498276)
		(width 0.14224)
		(layer "In15.Cu")
		(net "P5E_CPU1_P2_RX_BUF_DP<3>")
	)
	(arc
		(start 129.251456 -403.724872)
		(mid 129.293768 -403.50917)
		(end 129.41427 -403.32533)
		(width 0.14224)
		(layer "In15.Cu")
		(net "P5E_CPU1_P2_RX_BUF_DP<3>")
	)
	(arc
		(start 126.753874 -413.836104)
		(mid 126.636746 -413.812806)
		(end 126.537466 -413.746442)
		(width 0.14224)
		(layer "In15.Cu")
		(net "P5E_CPU1_P2_RX_BUF_DP<3>")
	)
	(arc
		(start 127.209804 -411.3276)
		(mid 127.304737 -411.279337)
		(end 127.39116 -411.21711)
		(width 0.14224)
		(layer "In15.Cu")
		(net "P5E_CPU1_P2_RX_BUF_DP<3>")
	)
	(arc
		(start 129.049018 -405.413464)
		(mid 129.198858 -405.189118)
		(end 129.251456 -404.924514)
		(width 0.14224)
		(layer "In15.Cu")
		(net "P5E_CPU1_P2_RX_BUF_DP<3>")
	)
	(arc
		(start 127.924814 -406.14346)
		(mid 128.105284 -405.995314)
		(end 128.311148 -405.885142)
		(width 0.14224)
		(layer "In15.Cu")
		(net "P5E_CPU1_P2_RX_BUF_DP<3>")
	)
	(arc
		(start 127.719836 -406.638252)
		(mid 127.773065 -406.370451)
		(end 127.924814 -406.14346)
		(width 0.14224)
		(layer "In15.Cu")
		(net "P5E_CPU1_P2_RX_BUF_DP<3>")
	)
	(arc
		(start 129.41427 -403.32533)
		(mid 129.745801 -403.067055)
		(end 130.113786 -402.864066)
		(width 0.14224)
		(layer "In15.Cu")
		(net "P5E_CPU1_P2_RX_BUF_DP<3>")
	)
	(segment
		(start 149.141688 -391.577322)
		(end 149.141688 -392.723878)
		(width 0.1016)
		(layer "F.Cu")
		(net "P5E_CPU1_P2_RX_BUF_DP<2>")
	)
	(segment
		(start 149.230334 -391.36574)
		(end 149.230334 -391.488676)
		(width 0.1016)
		(layer "F.Cu")
		(net "P5E_CPU1_P2_RX_BUF_DP<2>")
	)
	(segment
		(start 149.141688 -392.723878)
		(end 149.394926 -392.977116)
		(width 0.1016)
		(layer "F.Cu")
		(net "P5E_CPU1_P2_RX_BUF_DP<2>")
	)
	(segment
		(start 149.844252 -393.1158)
		(end 149.844252 -393.292838)
		(width 0.1016)
		(layer "F.Cu")
		(net "P5E_CPU1_P2_RX_BUF_DP<2>")
	)
	(segment
		(start 149.394926 -392.977116)
		(end 149.705568 -392.977116)
		(width 0.1016)
		(layer "F.Cu")
		(net "P5E_CPU1_P2_RX_BUF_DP<2>")
	)
	(segment
		(start 149.145752 -391.281158)
		(end 149.230334 -391.36574)
		(width 0.1016)
		(layer "F.Cu")
		(net "P5E_CPU1_P2_RX_BUF_DP<2>")
	)
	(segment
		(start 149.230334 -391.488676)
		(end 149.141688 -391.577322)
		(width 0.1016)
		(layer "F.Cu")
		(net "P5E_CPU1_P2_RX_BUF_DP<2>")
	)
	(segment
		(start 149.705568 -392.977116)
		(end 149.844252 -393.1158)
		(width 0.1016)
		(layer "F.Cu")
		(net "P5E_CPU1_P2_RX_BUF_DP<2>")
	)
	(segment
		(start 146.385534 -396.077186)
		(end 144.776952 -396.448534)
		(width 0.14224)
		(layer "In15.Cu")
		(net "P5E_CPU1_P2_RX_BUF_DP<2>")
	)
	(segment
		(start 123.938792 -411.33649)
		(end 123.49226 -411.521402)
		(width 0.14224)
		(layer "In15.Cu")
		(net "P5E_CPU1_P2_RX_BUF_DP<2>")
	)
	(segment
		(start 135.810498 -399.660618)
		(end 135.63219 -399.584418)
		(width 0.14224)
		(layer "In15.Cu")
		(net "P5E_CPU1_P2_RX_BUF_DP<2>")
	)
	(segment
		(start 123.447556 -411.552136)
		(end 123.305062 -411.702758)
		(width 0.14224)
		(layer "In15.Cu")
		(net "P5E_CPU1_P2_RX_BUF_DP<2>")
	)
	(segment
		(start 144.776952 -396.448534)
		(end 141.81836 -397.244062)
		(width 0.14224)
		(layer "In15.Cu")
		(net "P5E_CPU1_P2_RX_BUF_DP<2>")
	)
	(segment
		(start 148.842222 -395.29766)
		(end 148.327618 -395.572996)
		(width 0.14224)
		(layer "In15.Cu")
		(net "P5E_CPU1_P2_RX_BUF_DP<2>")
	)
	(segment
		(start 127.497332 -415.783268)
		(end 127.497332 -415.977324)
		(width 0.14224)
		(layer "In15.Cu")
		(net "P5E_CPU1_P2_RX_BUF_DP<2>")
	)
	(segment
		(start 141.309344 -397.523208)
		(end 141.141196 -397.426434)
		(width 0.14224)
		(layer "In15.Cu")
		(net "P5E_CPU1_P2_RX_BUF_DP<2>")
	)
	(segment
		(start 127.378206 -402.907754)
		(end 126.67742 -403.189694)
		(width 0.14224)
		(layer "In15.Cu")
		(net "P5E_CPU1_P2_RX_BUF_DP<2>")
	)
	(segment
		(start 124.656596 -408.99334)
		(end 124.793756 -409.1305)
		(width 0.14224)
		(layer "In15.Cu")
		(net "P5E_CPU1_P2_RX_BUF_DP<2>")
	)
	(segment
		(start 136.282684 -399.322544)
		(end 136.206738 -399.501106)
		(width 0.14224)
		(layer "In15.Cu")
		(net "P5E_CPU1_P2_RX_BUF_DP<2>")
	)
	(segment
		(start 126.5682 -403.253194)
		(end 126.389892 -403.394926)
		(width 0.14224)
		(layer "In15.Cu")
		(net "P5E_CPU1_P2_RX_BUF_DP<2>")
	)
	(segment
		(start 149.844252 -393.144756)
		(end 149.717252 -393.017756)
		(width 0.14224)
		(layer "In15.Cu")
		(net "P5E_CPU1_P2_RX_BUF_DP<2>")
	)
	(segment
		(start 124.656596 -406.638252)
		(end 124.656596 -407.86558)
		(width 0.14224)
		(layer "In15.Cu")
		(net "P5E_CPU1_P2_RX_BUF_DP<2>")
	)
	(segment
		(start 127.00127 -415.481262)
		(end 127.195326 -415.481262)
		(width 0.14224)
		(layer "In15.Cu")
		(net "P5E_CPU1_P2_RX_BUF_DP<2>")
	)
	(segment
		(start 128.294892 -416.580828)
		(end 128.294892 -416.774884)
		(width 0.14224)
		(layer "In15.Cu")
		(net "P5E_CPU1_P2_RX_BUF_DP<2>")
	)
	(segment
		(start 129.749804 -437.19115)
		(end 129.749804 -436.889906)
		(width 0.14224)
		(layer "In15.Cu")
		(net "P5E_CPU1_P2_RX_BUF_DP<2>")
	)
	(segment
		(start 123.124976 -412.155386)
		(end 123.124976 -413.06496)
		(width 0.14224)
		(layer "In15.Cu")
		(net "P5E_CPU1_P2_RX_BUF_DP<2>")
	)
	(segment
		(start 126.188216 -404.028656)
		(end 126.188216 -404.924514)
		(width 0.14224)
		(layer "In15.Cu")
		(net "P5E_CPU1_P2_RX_BUF_DP<2>")
	)
	(segment
		(start 127.992886 -416.278822)
		(end 128.294892 -416.580828)
		(width 0.14224)
		(layer "In15.Cu")
		(net "P5E_CPU1_P2_RX_BUF_DP<2>")
	)
	(segment
		(start 129.208276 -437.341264)
		(end 129.59969 -437.341264)
		(width 0.14224)
		(layer "In15.Cu")
		(net "P5E_CPU1_P2_RX_BUF_DP<2>")
	)
	(segment
		(start 126.77648 -415.256472)
		(end 127.00127 -415.481262)
		(width 0.14224)
		(layer "In15.Cu")
		(net "P5E_CPU1_P2_RX_BUF_DP<2>")
	)
	(segment
		(start 137.8458 -398.693132)
		(end 137.769854 -398.871948)
		(width 0.14224)
		(layer "In15.Cu")
		(net "P5E_CPU1_P2_RX_BUF_DP<2>")
	)
	(segment
		(start 137.373614 -399.031206)
		(end 137.195052 -398.95526)
		(width 0.14224)
		(layer "In15.Cu")
		(net "P5E_CPU1_P2_RX_BUF_DP<2>")
	)
	(segment
		(start 127.79883 -416.278822)
		(end 127.992886 -416.278822)
		(width 0.14224)
		(layer "In15.Cu")
		(net "P5E_CPU1_P2_RX_BUF_DP<2>")
	)
	(segment
		(start 149.527514 -393.017756)
		(end 149.385274 -393.159996)
		(width 0.14224)
		(layer "In15.Cu")
		(net "P5E_CPU1_P2_RX_BUF_DP<2>")
	)
	(segment
		(start 127.497332 -415.977324)
		(end 127.79883 -416.278822)
		(width 0.14224)
		(layer "In15.Cu")
		(net "P5E_CPU1_P2_RX_BUF_DP<2>")
	)
	(segment
		(start 139.510516 -398.170908)
		(end 139.114276 -398.33042)
		(width 0.14224)
		(layer "In15.Cu")
		(net "P5E_CPU1_P2_RX_BUF_DP<2>")
	)
	(segment
		(start 123.300744 -413.489394)
		(end 124.812552 -415.001202)
		(width 0.14224)
		(layer "In15.Cu")
		(net "P5E_CPU1_P2_RX_BUF_DP<2>")
	)
	(segment
		(start 148.327618 -395.572996)
		(end 148.021548 -395.699742)
		(width 0.14224)
		(layer "In15.Cu")
		(net "P5E_CPU1_P2_RX_BUF_DP<2>")
	)
	(segment
		(start 124.656596 -409.69438)
		(end 124.656596 -410.551122)
		(width 0.14224)
		(layer "In15.Cu")
		(net "P5E_CPU1_P2_RX_BUF_DP<2>")
	)
	(segment
		(start 126.28626 -403.551136)
		(end 126.221744 -403.783546)
		(width 0.14224)
		(layer "In15.Cu")
		(net "P5E_CPU1_P2_RX_BUF_DP<2>")
	)
	(segment
		(start 124.656596 -408.56662)
		(end 124.656596 -408.99334)
		(width 0.14224)
		(layer "In15.Cu")
		(net "P5E_CPU1_P2_RX_BUF_DP<2>")
	)
	(segment
		(start 124.793756 -408.42946)
		(end 124.656596 -408.56662)
		(width 0.14224)
		(layer "In15.Cu")
		(net "P5E_CPU1_P2_RX_BUF_DP<2>")
	)
	(segment
		(start 141.141196 -397.426434)
		(end 140.693902 -397.546576)
		(width 0.14224)
		(layer "In15.Cu")
		(net "P5E_CPU1_P2_RX_BUF_DP<2>")
	)
	(segment
		(start 149.844252 -393.292838)
		(end 149.844252 -393.144756)
		(width 0.14224)
		(layer "In15.Cu")
		(net "P5E_CPU1_P2_RX_BUF_DP<2>")
	)
	(segment
		(start 124.793756 -409.55722)
		(end 124.656596 -409.69438)
		(width 0.14224)
		(layer "In15.Cu")
		(net "P5E_CPU1_P2_RX_BUF_DP<2>")
	)
	(segment
		(start 124.793756 -409.1305)
		(end 124.793756 -409.55722)
		(width 0.14224)
		(layer "In15.Cu")
		(net "P5E_CPU1_P2_RX_BUF_DP<2>")
	)
	(segment
		(start 128.0287 -402.645626)
		(end 127.952754 -402.824442)
		(width 0.14224)
		(layer "In15.Cu")
		(net "P5E_CPU1_P2_RX_BUF_DP<2>")
	)
	(segment
		(start 129.071116 -437.204104)
		(end 129.208276 -437.341264)
		(width 0.14224)
		(layer "In15.Cu")
		(net "P5E_CPU1_P2_RX_BUF_DP<2>")
	)
	(segment
		(start 149.13737 -395.100556)
		(end 148.842222 -395.29766)
		(width 0.14224)
		(layer "In15.Cu")
		(net "P5E_CPU1_P2_RX_BUF_DP<2>")
	)
	(segment
		(start 139.586462 -397.992346)
		(end 139.510516 -398.170908)
		(width 0.14224)
		(layer "In15.Cu")
		(net "P5E_CPU1_P2_RX_BUF_DP<2>")
	)
	(segment
		(start 135.63219 -399.584418)
		(end 128.0287 -402.645626)
		(width 0.14224)
		(layer "In15.Cu")
		(net "P5E_CPU1_P2_RX_BUF_DP<2>")
	)
	(segment
		(start 125.838966 -405.560276)
		(end 125.523498 -405.771096)
		(width 0.14224)
		(layer "In15.Cu")
		(net "P5E_CPU1_P2_RX_BUF_DP<2>")
	)
	(segment
		(start 139.114276 -398.33042)
		(end 138.935968 -398.254474)
		(width 0.14224)
		(layer "In15.Cu")
		(net "P5E_CPU1_P2_RX_BUF_DP<2>")
	)
	(segment
		(start 129.071116 -417.72078)
		(end 129.071116 -437.204104)
		(width 0.14224)
		(layer "In15.Cu")
		(net "P5E_CPU1_P2_RX_BUF_DP<2>")
	)
	(segment
		(start 125.523498 -405.771096)
		(end 125.247908 -405.885142)
		(width 0.14224)
		(layer "In15.Cu")
		(net "P5E_CPU1_P2_RX_BUF_DP<2>")
	)
	(segment
		(start 149.385274 -394.636752)
		(end 149.13737 -395.100556)
		(width 0.14224)
		(layer "In15.Cu")
		(net "P5E_CPU1_P2_RX_BUF_DP<2>")
	)
	(segment
		(start 127.195326 -415.481262)
		(end 127.497332 -415.783268)
		(width 0.14224)
		(layer "In15.Cu")
		(net "P5E_CPU1_P2_RX_BUF_DP<2>")
	)
	(segment
		(start 141.721586 -397.412464)
		(end 141.309344 -397.523208)
		(width 0.14224)
		(layer "In15.Cu")
		(net "P5E_CPU1_P2_RX_BUF_DP<2>")
	)
	(segment
		(start 124.970286 -415.06648)
		(end 126.317756 -415.06648)
		(width 0.14224)
		(layer "In15.Cu")
		(net "P5E_CPU1_P2_RX_BUF_DP<2>")
	)
	(segment
		(start 124.52096 -410.878782)
		(end 124.315474 -411.084268)
		(width 0.14224)
		(layer "In15.Cu")
		(net "P5E_CPU1_P2_RX_BUF_DP<2>")
	)
	(segment
		(start 140.693902 -397.546576)
		(end 139.586462 -397.992346)
		(width 0.14224)
		(layer "In15.Cu")
		(net "P5E_CPU1_P2_RX_BUF_DP<2>")
	)
	(segment
		(start 141.81836 -397.244062)
		(end 141.721586 -397.412464)
		(width 0.14224)
		(layer "In15.Cu")
		(net "P5E_CPU1_P2_RX_BUF_DP<2>")
	)
	(segment
		(start 137.195052 -398.95526)
		(end 136.282684 -399.322544)
		(width 0.14224)
		(layer "In15.Cu")
		(net "P5E_CPU1_P2_RX_BUF_DP<2>")
	)
	(segment
		(start 127.556514 -402.9837)
		(end 127.378206 -402.907754)
		(width 0.14224)
		(layer "In15.Cu")
		(net "P5E_CPU1_P2_RX_BUF_DP<2>")
	)
	(segment
		(start 136.206738 -399.501106)
		(end 135.810498 -399.660618)
		(width 0.14224)
		(layer "In15.Cu")
		(net "P5E_CPU1_P2_RX_BUF_DP<2>")
	)
	(segment
		(start 149.717252 -393.017756)
		(end 149.527514 -393.017756)
		(width 0.14224)
		(layer "In15.Cu")
		(net "P5E_CPU1_P2_RX_BUF_DP<2>")
	)
	(segment
		(start 128.294892 -416.774884)
		(end 128.951228 -417.43122)
		(width 0.14224)
		(layer "In15.Cu")
		(net "P5E_CPU1_P2_RX_BUF_DP<2>")
	)
	(segment
		(start 148.021548 -395.699742)
		(end 146.385534 -396.077186)
		(width 0.14224)
		(layer "In15.Cu")
		(net "P5E_CPU1_P2_RX_BUF_DP<2>")
	)
	(segment
		(start 138.935968 -398.254474)
		(end 137.8458 -398.693132)
		(width 0.14224)
		(layer "In15.Cu")
		(net "P5E_CPU1_P2_RX_BUF_DP<2>")
	)
	(segment
		(start 124.656596 -407.86558)
		(end 124.793756 -408.00274)
		(width 0.14224)
		(layer "In15.Cu")
		(net "P5E_CPU1_P2_RX_BUF_DP<2>")
	)
	(segment
		(start 129.59969 -437.341264)
		(end 129.749804 -437.19115)
		(width 0.14224)
		(layer "In15.Cu")
		(net "P5E_CPU1_P2_RX_BUF_DP<2>")
	)
	(segment
		(start 124.793756 -408.00274)
		(end 124.793756 -408.42946)
		(width 0.14224)
		(layer "In15.Cu")
		(net "P5E_CPU1_P2_RX_BUF_DP<2>")
	)
	(segment
		(start 137.769854 -398.871948)
		(end 137.373614 -399.031206)
		(width 0.14224)
		(layer "In15.Cu")
		(net "P5E_CPU1_P2_RX_BUF_DP<2>")
	)
	(segment
		(start 149.385274 -393.159996)
		(end 149.385274 -394.636752)
		(width 0.14224)
		(layer "In15.Cu")
		(net "P5E_CPU1_P2_RX_BUF_DP<2>")
	)
	(segment
		(start 127.952754 -402.824442)
		(end 127.556514 -402.9837)
		(width 0.14224)
		(layer "In15.Cu")
		(net "P5E_CPU1_P2_RX_BUF_DP<2>")
	)
	(segment
		(start 125.985778 -405.413464)
		(end 125.838966 -405.560276)
		(width 0.14224)
		(layer "In15.Cu")
		(net "P5E_CPU1_P2_RX_BUF_DP<2>")
	)
	(arc
		(start 126.317756 -415.06648)
		(mid 126.566009 -415.115861)
		(end 126.77648 -415.256472)
		(width 0.14224)
		(layer "In15.Cu")
		(net "P5E_CPU1_P2_RX_BUF_DP<2>")
	)
	(arc
		(start 124.812552 -415.001202)
		(mid 124.884935 -415.049504)
		(end 124.970286 -415.06648)
		(width 0.14224)
		(layer "In15.Cu")
		(net "P5E_CPU1_P2_RX_BUF_DP<2>")
	)
	(arc
		(start 123.305062 -411.702758)
		(mid 123.171634 -411.911807)
		(end 123.124976 -412.155386)
		(width 0.14224)
		(layer "In15.Cu")
		(net "P5E_CPU1_P2_RX_BUF_DP<2>")
	)
	(arc
		(start 123.49226 -411.521402)
		(mid 123.468282 -411.534407)
		(end 123.447556 -411.552136)
		(width 0.14224)
		(layer "In15.Cu")
		(net "P5E_CPU1_P2_RX_BUF_DP<2>")
	)
	(arc
		(start 126.67742 -403.189694)
		(mid 126.620526 -403.217512)
		(end 126.5682 -403.253194)
		(width 0.14224)
		(layer "In15.Cu")
		(net "P5E_CPU1_P2_RX_BUF_DP<2>")
	)
	(arc
		(start 126.221744 -403.783546)
		(mid 126.196648 -403.904961)
		(end 126.188216 -404.028656)
		(width 0.14224)
		(layer "In15.Cu")
		(net "P5E_CPU1_P2_RX_BUF_DP<2>")
	)
	(arc
		(start 123.124976 -413.06496)
		(mid 123.170649 -413.294662)
		(end 123.300744 -413.489394)
		(width 0.14224)
		(layer "In15.Cu")
		(net "P5E_CPU1_P2_RX_BUF_DP<2>")
	)
	(arc
		(start 124.656596 -410.551122)
		(mid 124.621345 -410.728432)
		(end 124.52096 -410.878782)
		(width 0.14224)
		(layer "In15.Cu")
		(net "P5E_CPU1_P2_RX_BUF_DP<2>")
	)
	(arc
		(start 124.315474 -411.084268)
		(mid 124.139518 -411.228872)
		(end 123.938792 -411.33649)
		(width 0.14224)
		(layer "In15.Cu")
		(net "P5E_CPU1_P2_RX_BUF_DP<2>")
	)
	(arc
		(start 126.389892 -403.394926)
		(mid 126.325754 -403.464847)
		(end 126.28626 -403.551136)
		(width 0.14224)
		(layer "In15.Cu")
		(net "P5E_CPU1_P2_RX_BUF_DP<2>")
	)
	(arc
		(start 126.188216 -404.924514)
		(mid 126.135602 -405.189111)
		(end 125.985778 -405.413464)
		(width 0.14224)
		(layer "In15.Cu")
		(net "P5E_CPU1_P2_RX_BUF_DP<2>")
	)
	(arc
		(start 128.951228 -417.43122)
		(mid 129.039943 -417.564085)
		(end 129.071116 -417.72078)
		(width 0.14224)
		(layer "In15.Cu")
		(net "P5E_CPU1_P2_RX_BUF_DP<2>")
	)
	(arc
		(start 125.247908 -405.885142)
		(mid 125.042026 -405.995288)
		(end 124.861574 -406.14346)
		(width 0.14224)
		(layer "In15.Cu")
		(net "P5E_CPU1_P2_RX_BUF_DP<2>")
	)
	(arc
		(start 124.861574 -406.14346)
		(mid 124.709811 -406.370445)
		(end 124.656596 -406.638252)
		(width 0.14224)
		(layer "In15.Cu")
		(net "P5E_CPU1_P2_RX_BUF_DP<2>")
	)
	(segment
		(start 148.194776 -392.977116)
		(end 148.505418 -392.977116)
		(width 0.1016)
		(layer "F.Cu")
		(net "P5E_CPU1_P2_RX_BUF_DP<1>")
	)
	(segment
		(start 147.941538 -392.723878)
		(end 148.194776 -392.977116)
		(width 0.1016)
		(layer "F.Cu")
		(net "P5E_CPU1_P2_RX_BUF_DP<1>")
	)
	(segment
		(start 148.644102 -393.1158)
		(end 148.644102 -393.292838)
		(width 0.1016)
		(layer "F.Cu")
		(net "P5E_CPU1_P2_RX_BUF_DP<1>")
	)
	(segment
		(start 147.941538 -391.577322)
		(end 147.941538 -392.723878)
		(width 0.1016)
		(layer "F.Cu")
		(net "P5E_CPU1_P2_RX_BUF_DP<1>")
	)
	(segment
		(start 147.945602 -391.281158)
		(end 148.030184 -391.36574)
		(width 0.1016)
		(layer "F.Cu")
		(net "P5E_CPU1_P2_RX_BUF_DP<1>")
	)
	(segment
		(start 148.030184 -391.488676)
		(end 147.941538 -391.577322)
		(width 0.1016)
		(layer "F.Cu")
		(net "P5E_CPU1_P2_RX_BUF_DP<1>")
	)
	(segment
		(start 148.030184 -391.36574)
		(end 148.030184 -391.488676)
		(width 0.1016)
		(layer "F.Cu")
		(net "P5E_CPU1_P2_RX_BUF_DP<1>")
	)
	(segment
		(start 148.505418 -392.977116)
		(end 148.644102 -393.1158)
		(width 0.1016)
		(layer "F.Cu")
		(net "P5E_CPU1_P2_RX_BUF_DP<1>")
	)
	(segment
		(start 135.659114 -398.400778)
		(end 135.132572 -398.618456)
		(width 0.14224)
		(layer "In15.Cu")
		(net "P5E_CPU1_P2_RX_BUF_DP<1>")
	)
	(segment
		(start 121.101866 -411.31998)
		(end 120.149366 -411.71495)
		(width 0.14224)
		(layer "In15.Cu")
		(net "P5E_CPU1_P2_RX_BUF_DP<1>")
	)
	(segment
		(start 121.593356 -406.638252)
		(end 121.593356 -407.404062)
		(width 0.14224)
		(layer "In15.Cu")
		(net "P5E_CPU1_P2_RX_BUF_DP<1>")
	)
	(segment
		(start 124.933964 -402.837142)
		(end 123.498356 -403.43074)
		(width 0.14224)
		(layer "In15.Cu")
		(net "P5E_CPU1_P2_RX_BUF_DP<1>")
	)
	(segment
		(start 121.908824 -415.170874)
		(end 122.210322 -415.472372)
		(width 0.14224)
		(layer "In15.Cu")
		(net "P5E_CPU1_P2_RX_BUF_DP<1>")
	)
	(segment
		(start 120.809258 -413.877252)
		(end 121.111264 -414.179258)
		(width 0.14224)
		(layer "In15.Cu")
		(net "P5E_CPU1_P2_RX_BUF_DP<1>")
	)
	(segment
		(start 134.484618 -398.88668)
		(end 125.581918 -402.568918)
		(width 0.14224)
		(layer "In15.Cu")
		(net "P5E_CPU1_P2_RX_BUF_DP<1>")
	)
	(segment
		(start 121.111264 -414.373314)
		(end 121.412762 -414.674812)
		(width 0.14224)
		(layer "In15.Cu")
		(net "P5E_CPU1_P2_RX_BUF_DP<1>")
	)
	(segment
		(start 122.210322 -415.472372)
		(end 122.404378 -415.472372)
		(width 0.14224)
		(layer "In15.Cu")
		(net "P5E_CPU1_P2_RX_BUF_DP<1>")
	)
	(segment
		(start 136.733534 -397.956278)
		(end 136.307322 -398.132554)
		(width 0.14224)
		(layer "In15.Cu")
		(net "P5E_CPU1_P2_RX_BUF_DP<1>")
	)
	(segment
		(start 121.730516 -407.541222)
		(end 121.730516 -407.967942)
		(width 0.14224)
		(layer "In15.Cu")
		(net "P5E_CPU1_P2_RX_BUF_DP<1>")
	)
	(segment
		(start 121.593356 -409.302458)
		(end 121.593356 -410.697172)
		(width 0.14224)
		(layer "In15.Cu")
		(net "P5E_CPU1_P2_RX_BUF_DP<1>")
	)
	(segment
		(start 148.644102 -393.292838)
		(end 148.644102 -393.144756)
		(width 0.14224)
		(layer "In15.Cu")
		(net "P5E_CPU1_P2_RX_BUF_DP<1>")
	)
	(segment
		(start 148.185124 -393.159996)
		(end 148.185124 -394.50264)
		(width 0.14224)
		(layer "In15.Cu")
		(net "P5E_CPU1_P2_RX_BUF_DP<1>")
	)
	(segment
		(start 127.749808 -438.191148)
		(end 127.749808 -437.889904)
		(width 0.14224)
		(layer "In15.Cu")
		(net "P5E_CPU1_P2_RX_BUF_DP<1>")
	)
	(segment
		(start 148.517102 -393.017756)
		(end 148.327364 -393.017756)
		(width 0.14224)
		(layer "In15.Cu")
		(net "P5E_CPU1_P2_RX_BUF_DP<1>")
	)
	(segment
		(start 122.922538 -405.413464)
		(end 122.775726 -405.560276)
		(width 0.14224)
		(layer "In15.Cu")
		(net "P5E_CPU1_P2_RX_BUF_DP<1>")
	)
	(segment
		(start 121.730516 -409.165298)
		(end 121.593356 -409.302458)
		(width 0.14224)
		(layer "In15.Cu")
		(net "P5E_CPU1_P2_RX_BUF_DP<1>")
	)
	(segment
		(start 127.19939 -438.337198)
		(end 127.603758 -438.337198)
		(width 0.14224)
		(layer "In15.Cu")
		(net "P5E_CPU1_P2_RX_BUF_DP<1>")
	)
	(segment
		(start 136.307322 -398.132554)
		(end 136.2329 -398.311878)
		(width 0.14224)
		(layer "In15.Cu")
		(net "P5E_CPU1_P2_RX_BUF_DP<1>")
	)
	(segment
		(start 137.775696 -397.524986)
		(end 137.381488 -397.688054)
		(width 0.14224)
		(layer "In15.Cu")
		(net "P5E_CPU1_P2_RX_BUF_DP<1>")
	)
	(segment
		(start 135.058404 -398.79778)
		(end 134.663688 -398.961102)
		(width 0.14224)
		(layer "In15.Cu")
		(net "P5E_CPU1_P2_RX_BUF_DP<1>")
	)
	(segment
		(start 134.663688 -398.961102)
		(end 134.484618 -398.88668)
		(width 0.14224)
		(layer "In15.Cu")
		(net "P5E_CPU1_P2_RX_BUF_DP<1>")
	)
	(segment
		(start 140.677392 -396.547594)
		(end 137.775696 -397.524986)
		(width 0.14224)
		(layer "In15.Cu")
		(net "P5E_CPU1_P2_RX_BUF_DP<1>")
	)
	(segment
		(start 137.307066 -397.867378)
		(end 136.912604 -398.030446)
		(width 0.14224)
		(layer "In15.Cu")
		(net "P5E_CPU1_P2_RX_BUF_DP<1>")
	)
	(segment
		(start 121.469658 -411.006798)
		(end 121.302272 -411.18282)
		(width 0.14224)
		(layer "In15.Cu")
		(net "P5E_CPU1_P2_RX_BUF_DP<1>")
	)
	(segment
		(start 126.635764 -416.747706)
		(end 126.87554 -416.987482)
		(width 0.14224)
		(layer "In15.Cu")
		(net "P5E_CPU1_P2_RX_BUF_DP<1>")
	)
	(segment
		(start 121.593356 -408.601418)
		(end 121.730516 -408.738578)
		(width 0.14224)
		(layer "In15.Cu")
		(net "P5E_CPU1_P2_RX_BUF_DP<1>")
	)
	(segment
		(start 125.113034 -402.91131)
		(end 124.933964 -402.837142)
		(width 0.14224)
		(layer "In15.Cu")
		(net "P5E_CPU1_P2_RX_BUF_DP<1>")
	)
	(segment
		(start 127.07112 -438.208928)
		(end 127.19939 -438.337198)
		(width 0.14224)
		(layer "In15.Cu")
		(net "P5E_CPU1_P2_RX_BUF_DP<1>")
	)
	(segment
		(start 120.615202 -413.877252)
		(end 120.809258 -413.877252)
		(width 0.14224)
		(layer "In15.Cu")
		(net "P5E_CPU1_P2_RX_BUF_DP<1>")
	)
	(segment
		(start 122.460258 -405.771096)
		(end 122.184668 -405.885142)
		(width 0.14224)
		(layer "In15.Cu")
		(net "P5E_CPU1_P2_RX_BUF_DP<1>")
	)
	(segment
		(start 121.412762 -414.674812)
		(end 121.606818 -414.674812)
		(width 0.14224)
		(layer "In15.Cu")
		(net "P5E_CPU1_P2_RX_BUF_DP<1>")
	)
	(segment
		(start 123.419108 -416.565334)
		(end 126.195582 -416.565334)
		(width 0.14224)
		(layer "In15.Cu")
		(net "P5E_CPU1_P2_RX_BUF_DP<1>")
	)
	(segment
		(start 123.124976 -403.989286)
		(end 123.124976 -404.924514)
		(width 0.14224)
		(layer "In15.Cu")
		(net "P5E_CPU1_P2_RX_BUF_DP<1>")
	)
	(segment
		(start 148.327364 -393.017756)
		(end 148.185124 -393.159996)
		(width 0.14224)
		(layer "In15.Cu")
		(net "P5E_CPU1_P2_RX_BUF_DP<1>")
	)
	(segment
		(start 121.606818 -414.674812)
		(end 121.908824 -414.976818)
		(width 0.14224)
		(layer "In15.Cu")
		(net "P5E_CPU1_P2_RX_BUF_DP<1>")
	)
	(segment
		(start 148.644102 -393.144756)
		(end 148.517102 -393.017756)
		(width 0.14224)
		(layer "In15.Cu")
		(net "P5E_CPU1_P2_RX_BUF_DP<1>")
	)
	(segment
		(start 127.603758 -438.337198)
		(end 127.749808 -438.191148)
		(width 0.14224)
		(layer "In15.Cu")
		(net "P5E_CPU1_P2_RX_BUF_DP<1>")
	)
	(segment
		(start 147.93214 -394.720826)
		(end 147.801076 -394.778992)
		(width 0.14224)
		(layer "In15.Cu")
		(net "P5E_CPU1_P2_RX_BUF_DP<1>")
	)
	(segment
		(start 121.908824 -414.976818)
		(end 121.908824 -415.170874)
		(width 0.14224)
		(layer "In15.Cu")
		(net "P5E_CPU1_P2_RX_BUF_DP<1>")
	)
	(segment
		(start 125.507496 -402.748242)
		(end 125.113034 -402.91131)
		(width 0.14224)
		(layer "In15.Cu")
		(net "P5E_CPU1_P2_RX_BUF_DP<1>")
	)
	(segment
		(start 122.706384 -415.968434)
		(end 123.221242 -416.483292)
		(width 0.14224)
		(layer "In15.Cu")
		(net "P5E_CPU1_P2_RX_BUF_DP<1>")
	)
	(segment
		(start 143.447008 -395.768576)
		(end 140.677392 -396.547594)
		(width 0.14224)
		(layer "In15.Cu")
		(net "P5E_CPU1_P2_RX_BUF_DP<1>")
	)
	(segment
		(start 135.132572 -398.618456)
		(end 135.058404 -398.79778)
		(width 0.14224)
		(layer "In15.Cu")
		(net "P5E_CPU1_P2_RX_BUF_DP<1>")
	)
	(segment
		(start 121.730516 -407.967942)
		(end 121.593356 -408.105102)
		(width 0.14224)
		(layer "In15.Cu")
		(net "P5E_CPU1_P2_RX_BUF_DP<1>")
	)
	(segment
		(start 137.381488 -397.688054)
		(end 137.307066 -397.867378)
		(width 0.14224)
		(layer "In15.Cu")
		(net "P5E_CPU1_P2_RX_BUF_DP<1>")
	)
	(segment
		(start 120.124982 -413.387032)
		(end 120.615202 -413.877252)
		(width 0.14224)
		(layer "In15.Cu")
		(net "P5E_CPU1_P2_RX_BUF_DP<1>")
	)
	(segment
		(start 121.730516 -408.738578)
		(end 121.730516 -409.165298)
		(width 0.14224)
		(layer "In15.Cu")
		(net "P5E_CPU1_P2_RX_BUF_DP<1>")
	)
	(segment
		(start 127.07112 -417.459922)
		(end 127.07112 -438.208928)
		(width 0.14224)
		(layer "In15.Cu")
		(net "P5E_CPU1_P2_RX_BUF_DP<1>")
	)
	(segment
		(start 121.593356 -408.105102)
		(end 121.593356 -408.601418)
		(width 0.14224)
		(layer "In15.Cu")
		(net "P5E_CPU1_P2_RX_BUF_DP<1>")
	)
	(segment
		(start 122.404378 -415.472372)
		(end 122.706384 -415.774378)
		(width 0.14224)
		(layer "In15.Cu")
		(net "P5E_CPU1_P2_RX_BUF_DP<1>")
	)
	(segment
		(start 121.111264 -414.179258)
		(end 121.111264 -414.373314)
		(width 0.14224)
		(layer "In15.Cu")
		(net "P5E_CPU1_P2_RX_BUF_DP<1>")
	)
	(segment
		(start 136.2329 -398.311878)
		(end 135.838184 -398.4752)
		(width 0.14224)
		(layer "In15.Cu")
		(net "P5E_CPU1_P2_RX_BUF_DP<1>")
	)
	(segment
		(start 122.775726 -405.560276)
		(end 122.460258 -405.771096)
		(width 0.14224)
		(layer "In15.Cu")
		(net "P5E_CPU1_P2_RX_BUF_DP<1>")
	)
	(segment
		(start 120.061736 -411.846014)
		(end 120.061736 -413.234378)
		(width 0.14224)
		(layer "In15.Cu")
		(net "P5E_CPU1_P2_RX_BUF_DP<1>")
	)
	(segment
		(start 136.912604 -398.030446)
		(end 136.733534 -397.956278)
		(width 0.14224)
		(layer "In15.Cu")
		(net "P5E_CPU1_P2_RX_BUF_DP<1>")
	)
	(segment
		(start 135.838184 -398.4752)
		(end 135.659114 -398.400778)
		(width 0.14224)
		(layer "In15.Cu")
		(net "P5E_CPU1_P2_RX_BUF_DP<1>")
	)
	(segment
		(start 121.593356 -407.404062)
		(end 121.730516 -407.541222)
		(width 0.14224)
		(layer "In15.Cu")
		(net "P5E_CPU1_P2_RX_BUF_DP<1>")
	)
	(segment
		(start 148.185124 -394.50264)
		(end 147.93214 -394.720826)
		(width 0.14224)
		(layer "In15.Cu")
		(net "P5E_CPU1_P2_RX_BUF_DP<1>")
	)
	(segment
		(start 147.801076 -394.778992)
		(end 143.447008 -395.768576)
		(width 0.14224)
		(layer "In15.Cu")
		(net "P5E_CPU1_P2_RX_BUF_DP<1>")
	)
	(segment
		(start 122.706384 -415.774378)
		(end 122.706384 -415.968434)
		(width 0.14224)
		(layer "In15.Cu")
		(net "P5E_CPU1_P2_RX_BUF_DP<1>")
	)
	(segment
		(start 125.581918 -402.568918)
		(end 125.507496 -402.748242)
		(width 0.14224)
		(layer "In15.Cu")
		(net "P5E_CPU1_P2_RX_BUF_DP<1>")
	)
	(arc
		(start 120.061736 -413.234378)
		(mid 120.07817 -413.316999)
		(end 120.124982 -413.387032)
		(width 0.14224)
		(layer "In15.Cu")
		(net "P5E_CPU1_P2_RX_BUF_DP<1>")
	)
	(arc
		(start 121.798334 -406.14346)
		(mid 121.646571 -406.370445)
		(end 121.593356 -406.638252)
		(width 0.14224)
		(layer "In15.Cu")
		(net "P5E_CPU1_P2_RX_BUF_DP<1>")
	)
	(arc
		(start 126.87554 -416.987482)
		(mid 127.020319 -417.204254)
		(end 127.07112 -417.459922)
		(width 0.14224)
		(layer "In15.Cu")
		(net "P5E_CPU1_P2_RX_BUF_DP<1>")
	)
	(arc
		(start 120.149366 -411.71495)
		(mid 120.085621 -411.767167)
		(end 120.061736 -411.846014)
		(width 0.14224)
		(layer "In15.Cu")
		(net "P5E_CPU1_P2_RX_BUF_DP<1>")
	)
	(arc
		(start 123.124976 -404.924514)
		(mid 123.072362 -405.189111)
		(end 122.922538 -405.413464)
		(width 0.14224)
		(layer "In15.Cu")
		(net "P5E_CPU1_P2_RX_BUF_DP<1>")
	)
	(arc
		(start 122.184668 -405.885142)
		(mid 121.978786 -405.995288)
		(end 121.798334 -406.14346)
		(width 0.14224)
		(layer "In15.Cu")
		(net "P5E_CPU1_P2_RX_BUF_DP<1>")
	)
	(arc
		(start 123.498356 -403.43074)
		(mid 123.226943 -403.65337)
		(end 123.124976 -403.989286)
		(width 0.14224)
		(layer "In15.Cu")
		(net "P5E_CPU1_P2_RX_BUF_DP<1>")
	)
	(arc
		(start 126.195582 -416.565334)
		(mid 126.433809 -416.612738)
		(end 126.635764 -416.747706)
		(width 0.14224)
		(layer "In15.Cu")
		(net "P5E_CPU1_P2_RX_BUF_DP<1>")
	)
	(arc
		(start 121.593356 -410.697172)
		(mid 121.561391 -410.86393)
		(end 121.469658 -411.006798)
		(width 0.14224)
		(layer "In15.Cu")
		(net "P5E_CPU1_P2_RX_BUF_DP<1>")
	)
	(arc
		(start 121.302272 -411.18282)
		(mid 121.209254 -411.261897)
		(end 121.101866 -411.31998)
		(width 0.14224)
		(layer "In15.Cu")
		(net "P5E_CPU1_P2_RX_BUF_DP<1>")
	)
	(arc
		(start 123.221242 -416.483292)
		(mid 123.312009 -416.544004)
		(end 123.419108 -416.565334)
		(width 0.14224)
		(layer "In15.Cu")
		(net "P5E_CPU1_P2_RX_BUF_DP<1>")
	)
	(segment
		(start 165.44417 -393.13231)
		(end 165.44417 -393.292838)
		(width 0.1016)
		(layer "F.Cu")
		(net "P5E_CPU1_P2_RX_BUF_DP<15>")
	)
	(segment
		(start 164.741606 -391.577322)
		(end 164.741606 -392.723878)
		(width 0.1016)
		(layer "F.Cu")
		(net "P5E_CPU1_P2_RX_BUF_DP<15>")
	)
	(segment
		(start 164.994844 -392.977116)
		(end 165.288976 -392.977116)
		(width 0.1016)
		(layer "F.Cu")
		(net "P5E_CPU1_P2_RX_BUF_DP<15>")
	)
	(segment
		(start 164.741606 -392.723878)
		(end 164.994844 -392.977116)
		(width 0.1016)
		(layer "F.Cu")
		(net "P5E_CPU1_P2_RX_BUF_DP<15>")
	)
	(segment
		(start 164.830252 -391.488676)
		(end 164.741606 -391.577322)
		(width 0.1016)
		(layer "F.Cu")
		(net "P5E_CPU1_P2_RX_BUF_DP<15>")
	)
	(segment
		(start 164.830252 -391.36574)
		(end 164.830252 -391.488676)
		(width 0.1016)
		(layer "F.Cu")
		(net "P5E_CPU1_P2_RX_BUF_DP<15>")
	)
	(segment
		(start 164.74567 -391.281158)
		(end 164.830252 -391.36574)
		(width 0.1016)
		(layer "F.Cu")
		(net "P5E_CPU1_P2_RX_BUF_DP<15>")
	)
	(segment
		(start 165.288976 -392.977116)
		(end 165.44417 -393.13231)
		(width 0.1016)
		(layer "F.Cu")
		(net "P5E_CPU1_P2_RX_BUF_DP<15>")
	)
	(segment
		(start 164.985192 -397.778478)
		(end 165.122352 -397.641318)
		(width 0.14224)
		(layer "In15.Cu")
		(net "P5E_CPU1_P2_RX_BUF_DP<15>")
	)
	(segment
		(start 159.38119 -417.898326)
		(end 159.87395 -417.405566)
		(width 0.14224)
		(layer "In15.Cu")
		(net "P5E_CPU1_P2_RX_BUF_DP<15>")
	)
	(segment
		(start 164.985192 -409.237434)
		(end 164.985192 -397.778478)
		(width 0.14224)
		(layer "In15.Cu")
		(net "P5E_CPU1_P2_RX_BUF_DP<15>")
	)
	(segment
		(start 165.122352 -394.959078)
		(end 164.985192 -394.821918)
		(width 0.14224)
		(layer "In15.Cu")
		(net "P5E_CPU1_P2_RX_BUF_DP<15>")
	)
	(segment
		(start 164.300916 -411.374336)
		(end 164.473636 -410.983938)
		(width 0.14224)
		(layer "In15.Cu")
		(net "P5E_CPU1_P2_RX_BUF_DP<15>")
	)
	(segment
		(start 161.167572 -416.306)
		(end 161.167572 -416.111944)
		(width 0.14224)
		(layer "In15.Cu")
		(net "P5E_CPU1_P2_RX_BUF_DP<15>")
	)
	(segment
		(start 156.59989 -438.341262)
		(end 156.208476 -438.341262)
		(width 0.14224)
		(layer "In15.Cu")
		(net "P5E_CPU1_P2_RX_BUF_DP<15>")
	)
	(segment
		(start 160.67151 -416.608006)
		(end 160.865566 -416.608006)
		(width 0.14224)
		(layer "In15.Cu")
		(net "P5E_CPU1_P2_RX_BUF_DP<15>")
	)
	(segment
		(start 165.122352 -396.513558)
		(end 165.122352 -396.086838)
		(width 0.14224)
		(layer "In15.Cu")
		(net "P5E_CPU1_P2_RX_BUF_DP<15>")
	)
	(segment
		(start 164.044122 -411.614366)
		(end 164.11956 -411.444186)
		(width 0.14224)
		(layer "In15.Cu")
		(net "P5E_CPU1_P2_RX_BUF_DP<15>")
	)
	(segment
		(start 159.079184 -418.394388)
		(end 159.38119 -418.092382)
		(width 0.14224)
		(layer "In15.Cu")
		(net "P5E_CPU1_P2_RX_BUF_DP<15>")
	)
	(segment
		(start 165.122352 -397.214598)
		(end 164.985192 -397.077438)
		(width 0.14224)
		(layer "In15.Cu")
		(net "P5E_CPU1_P2_RX_BUF_DP<15>")
	)
	(segment
		(start 164.11956 -411.444186)
		(end 164.300916 -411.374336)
		(width 0.14224)
		(layer "In15.Cu")
		(net "P5E_CPU1_P2_RX_BUF_DP<15>")
	)
	(segment
		(start 160.370012 -417.10356)
		(end 160.370012 -416.909504)
		(width 0.14224)
		(layer "In15.Cu")
		(net "P5E_CPU1_P2_RX_BUF_DP<15>")
	)
	(segment
		(start 161.167572 -416.111944)
		(end 161.46907 -415.810446)
		(width 0.14224)
		(layer "In15.Cu")
		(net "P5E_CPU1_P2_RX_BUF_DP<15>")
	)
	(segment
		(start 164.985192 -393.159996)
		(end 165.127432 -393.017756)
		(width 0.14224)
		(layer "In15.Cu")
		(net "P5E_CPU1_P2_RX_BUF_DP<15>")
	)
	(segment
		(start 158.58363 -418.889942)
		(end 158.58363 -418.695886)
		(width 0.14224)
		(layer "In15.Cu")
		(net "P5E_CPU1_P2_RX_BUF_DP<15>")
	)
	(segment
		(start 164.473636 -410.983938)
		(end 164.403786 -410.802836)
		(width 0.14224)
		(layer "In15.Cu")
		(net "P5E_CPU1_P2_RX_BUF_DP<15>")
	)
	(segment
		(start 156.208476 -438.341262)
		(end 156.071062 -438.203848)
		(width 0.14224)
		(layer "In15.Cu")
		(net "P5E_CPU1_P2_RX_BUF_DP<15>")
	)
	(segment
		(start 158.281624 -419.191948)
		(end 158.58363 -418.889942)
		(width 0.14224)
		(layer "In15.Cu")
		(net "P5E_CPU1_P2_RX_BUF_DP<15>")
	)
	(segment
		(start 163.94684 -412.834328)
		(end 163.94684 -412.074614)
		(width 0.14224)
		(layer "In15.Cu")
		(net "P5E_CPU1_P2_RX_BUF_DP<15>")
	)
	(segment
		(start 160.865566 -416.608006)
		(end 161.167572 -416.306)
		(width 0.14224)
		(layer "In15.Cu")
		(net "P5E_CPU1_P2_RX_BUF_DP<15>")
	)
	(segment
		(start 159.38119 -418.092382)
		(end 159.38119 -417.898326)
		(width 0.14224)
		(layer "In15.Cu")
		(net "P5E_CPU1_P2_RX_BUF_DP<15>")
	)
	(segment
		(start 158.885128 -418.394388)
		(end 159.079184 -418.394388)
		(width 0.14224)
		(layer "In15.Cu")
		(net "P5E_CPU1_P2_RX_BUF_DP<15>")
	)
	(segment
		(start 164.985192 -395.522958)
		(end 165.122352 -395.385798)
		(width 0.14224)
		(layer "In15.Cu")
		(net "P5E_CPU1_P2_RX_BUF_DP<15>")
	)
	(segment
		(start 165.31717 -393.017756)
		(end 165.44417 -393.144756)
		(width 0.14224)
		(layer "In15.Cu")
		(net "P5E_CPU1_P2_RX_BUF_DP<15>")
	)
	(segment
		(start 161.46907 -415.810446)
		(end 161.663126 -415.810446)
		(width 0.14224)
		(layer "In15.Cu")
		(net "P5E_CPU1_P2_RX_BUF_DP<15>")
	)
	(segment
		(start 165.44417 -393.144756)
		(end 165.44417 -393.292838)
		(width 0.14224)
		(layer "In15.Cu")
		(net "P5E_CPU1_P2_RX_BUF_DP<15>")
	)
	(segment
		(start 164.985192 -394.821918)
		(end 164.985192 -393.159996)
		(width 0.14224)
		(layer "In15.Cu")
		(net "P5E_CPU1_P2_RX_BUF_DP<15>")
	)
	(segment
		(start 164.403786 -410.802836)
		(end 164.882322 -409.723082)
		(width 0.14224)
		(layer "In15.Cu")
		(net "P5E_CPU1_P2_RX_BUF_DP<15>")
	)
	(segment
		(start 158.58363 -418.695886)
		(end 158.885128 -418.394388)
		(width 0.14224)
		(layer "In15.Cu")
		(net "P5E_CPU1_P2_RX_BUF_DP<15>")
	)
	(segment
		(start 165.122352 -397.641318)
		(end 165.122352 -397.214598)
		(width 0.14224)
		(layer "In15.Cu")
		(net "P5E_CPU1_P2_RX_BUF_DP<15>")
	)
	(segment
		(start 164.985192 -395.949678)
		(end 164.985192 -395.522958)
		(width 0.14224)
		(layer "In15.Cu")
		(net "P5E_CPU1_P2_RX_BUF_DP<15>")
	)
	(segment
		(start 159.87395 -417.405566)
		(end 160.068006 -417.405566)
		(width 0.14224)
		(layer "In15.Cu")
		(net "P5E_CPU1_P2_RX_BUF_DP<15>")
	)
	(segment
		(start 158.087568 -419.191948)
		(end 158.281624 -419.191948)
		(width 0.14224)
		(layer "In15.Cu")
		(net "P5E_CPU1_P2_RX_BUF_DP<15>")
	)
	(segment
		(start 161.965132 -415.314384)
		(end 163.594542 -413.684974)
		(width 0.14224)
		(layer "In15.Cu")
		(net "P5E_CPU1_P2_RX_BUF_DP<15>")
	)
	(segment
		(start 165.127432 -393.017756)
		(end 165.31717 -393.017756)
		(width 0.14224)
		(layer "In15.Cu")
		(net "P5E_CPU1_P2_RX_BUF_DP<15>")
	)
	(segment
		(start 156.071062 -438.203848)
		(end 156.071062 -421.378126)
		(width 0.14224)
		(layer "In15.Cu")
		(net "P5E_CPU1_P2_RX_BUF_DP<15>")
	)
	(segment
		(start 156.19095 -421.088566)
		(end 158.087568 -419.191948)
		(width 0.14224)
		(layer "In15.Cu")
		(net "P5E_CPU1_P2_RX_BUF_DP<15>")
	)
	(segment
		(start 156.750004 -437.889904)
		(end 156.750004 -438.191148)
		(width 0.14224)
		(layer "In15.Cu")
		(net "P5E_CPU1_P2_RX_BUF_DP<15>")
	)
	(segment
		(start 160.068006 -417.405566)
		(end 160.370012 -417.10356)
		(width 0.14224)
		(layer "In15.Cu")
		(net "P5E_CPU1_P2_RX_BUF_DP<15>")
	)
	(segment
		(start 164.985192 -397.077438)
		(end 164.985192 -396.650718)
		(width 0.14224)
		(layer "In15.Cu")
		(net "P5E_CPU1_P2_RX_BUF_DP<15>")
	)
	(segment
		(start 156.750004 -438.191148)
		(end 156.59989 -438.341262)
		(width 0.14224)
		(layer "In15.Cu")
		(net "P5E_CPU1_P2_RX_BUF_DP<15>")
	)
	(segment
		(start 165.122352 -396.086838)
		(end 164.985192 -395.949678)
		(width 0.14224)
		(layer "In15.Cu")
		(net "P5E_CPU1_P2_RX_BUF_DP<15>")
	)
	(segment
		(start 165.122352 -395.385798)
		(end 165.122352 -394.959078)
		(width 0.14224)
		(layer "In15.Cu")
		(net "P5E_CPU1_P2_RX_BUF_DP<15>")
	)
	(segment
		(start 164.882322 -409.723082)
		(end 164.985192 -409.237434)
		(width 0.14224)
		(layer "In15.Cu")
		(net "P5E_CPU1_P2_RX_BUF_DP<15>")
	)
	(segment
		(start 161.965132 -415.50844)
		(end 161.965132 -415.314384)
		(width 0.14224)
		(layer "In15.Cu")
		(net "P5E_CPU1_P2_RX_BUF_DP<15>")
	)
	(segment
		(start 164.985192 -396.650718)
		(end 165.122352 -396.513558)
		(width 0.14224)
		(layer "In15.Cu")
		(net "P5E_CPU1_P2_RX_BUF_DP<15>")
	)
	(segment
		(start 160.370012 -416.909504)
		(end 160.67151 -416.608006)
		(width 0.14224)
		(layer "In15.Cu")
		(net "P5E_CPU1_P2_RX_BUF_DP<15>")
	)
	(segment
		(start 161.663126 -415.810446)
		(end 161.965132 -415.50844)
		(width 0.14224)
		(layer "In15.Cu")
		(net "P5E_CPU1_P2_RX_BUF_DP<15>")
	)
	(arc
		(start 163.594542 -413.684974)
		(mid 163.855265 -413.29468)
		(end 163.94684 -412.834328)
		(width 0.14224)
		(layer "In15.Cu")
		(net "P5E_CPU1_P2_RX_BUF_DP<15>")
	)
	(arc
		(start 163.94684 -412.074614)
		(mid 163.971396 -411.839398)
		(end 164.044122 -411.614366)
		(width 0.14224)
		(layer "In15.Cu")
		(net "P5E_CPU1_P2_RX_BUF_DP<15>")
	)
	(arc
		(start 156.071062 -421.378126)
		(mid 156.102214 -421.221423)
		(end 156.19095 -421.088566)
		(width 0.14224)
		(layer "In15.Cu")
		(net "P5E_CPU1_P2_RX_BUF_DP<15>")
	)
	(segment
		(start 164.087556 -392.977116)
		(end 164.244274 -393.133834)
		(width 0.1016)
		(layer "F.Cu")
		(net "P5E_CPU1_P2_RX_BUF_DP<14>")
	)
	(segment
		(start 163.545774 -391.281158)
		(end 163.630356 -391.36574)
		(width 0.1016)
		(layer "F.Cu")
		(net "P5E_CPU1_P2_RX_BUF_DP<14>")
	)
	(segment
		(start 163.54171 -392.723878)
		(end 163.794948 -392.977116)
		(width 0.1016)
		(layer "F.Cu")
		(net "P5E_CPU1_P2_RX_BUF_DP<14>")
	)
	(segment
		(start 164.244274 -393.133834)
		(end 164.244274 -393.292838)
		(width 0.1016)
		(layer "F.Cu")
		(net "P5E_CPU1_P2_RX_BUF_DP<14>")
	)
	(segment
		(start 163.630356 -391.488676)
		(end 163.54171 -391.577322)
		(width 0.1016)
		(layer "F.Cu")
		(net "P5E_CPU1_P2_RX_BUF_DP<14>")
	)
	(segment
		(start 163.630356 -391.36574)
		(end 163.630356 -391.488676)
		(width 0.1016)
		(layer "F.Cu")
		(net "P5E_CPU1_P2_RX_BUF_DP<14>")
	)
	(segment
		(start 163.794948 -392.977116)
		(end 164.087556 -392.977116)
		(width 0.1016)
		(layer "F.Cu")
		(net "P5E_CPU1_P2_RX_BUF_DP<14>")
	)
	(segment
		(start 163.54171 -391.577322)
		(end 163.54171 -392.723878)
		(width 0.1016)
		(layer "F.Cu")
		(net "P5E_CPU1_P2_RX_BUF_DP<14>")
	)
	(segment
		(start 155.12542 -419.94836)
		(end 154.823414 -420.250366)
		(width 0.14224)
		(layer "In15.Cu")
		(net "P5E_CPU1_P2_RX_BUF_DP<14>")
	)
	(segment
		(start 161.415476 -408.32532)
		(end 161.415476 -408.75204)
		(width 0.14224)
		(layer "In15.Cu")
		(net "P5E_CPU1_P2_RX_BUF_DP<14>")
	)
	(segment
		(start 164.244274 -393.292838)
		(end 164.244274 -393.144756)
		(width 0.14224)
		(layer "In15.Cu")
		(net "P5E_CPU1_P2_RX_BUF_DP<14>")
	)
	(segment
		(start 163.785296 -393.159996)
		(end 163.785296 -395.553946)
		(width 0.14224)
		(layer "In15.Cu")
		(net "P5E_CPU1_P2_RX_BUF_DP<14>")
	)
	(segment
		(start 163.489132 -399.42897)
		(end 163.612322 -399.57883)
		(width 0.14224)
		(layer "In15.Cu")
		(net "P5E_CPU1_P2_RX_BUF_DP<14>")
	)
	(segment
		(start 163.238942 -403.37105)
		(end 163.088828 -403.49424)
		(width 0.14224)
		(layer "In15.Cu")
		(net "P5E_CPU1_P2_RX_BUF_DP<14>")
	)
	(segment
		(start 164.117274 -393.017756)
		(end 163.927536 -393.017756)
		(width 0.14224)
		(layer "In15.Cu")
		(net "P5E_CPU1_P2_RX_BUF_DP<14>")
	)
	(segment
		(start 154.629358 -420.250366)
		(end 154.32786 -420.551864)
		(width 0.14224)
		(layer "In15.Cu")
		(net "P5E_CPU1_P2_RX_BUF_DP<14>")
	)
	(segment
		(start 163.501832 -400.701256)
		(end 163.459922 -401.126198)
		(width 0.14224)
		(layer "In15.Cu")
		(net "P5E_CPU1_P2_RX_BUF_DP<14>")
	)
	(segment
		(start 161.415476 -406.637744)
		(end 161.415476 -407.62428)
		(width 0.14224)
		(layer "In15.Cu")
		(net "P5E_CPU1_P2_RX_BUF_DP<14>")
	)
	(segment
		(start 161.552636 -408.8892)
		(end 161.552636 -409.31592)
		(width 0.14224)
		(layer "In15.Cu")
		(net "P5E_CPU1_P2_RX_BUF_DP<14>")
	)
	(segment
		(start 161.415476 -408.75204)
		(end 161.552636 -408.8892)
		(width 0.14224)
		(layer "In15.Cu")
		(net "P5E_CPU1_P2_RX_BUF_DP<14>")
	)
	(segment
		(start 162.978084 -404.616666)
		(end 162.936428 -405.0411)
		(width 0.14224)
		(layer "In15.Cu")
		(net "P5E_CPU1_P2_RX_BUF_DP<14>")
	)
	(segment
		(start 163.420298 -400.126962)
		(end 163.378642 -400.551396)
		(width 0.14224)
		(layer "In15.Cu")
		(net "P5E_CPU1_P2_RX_BUF_DP<14>")
	)
	(segment
		(start 154.599894 -437.341264)
		(end 154.750008 -437.19115)
		(width 0.14224)
		(layer "In15.Cu")
		(net "P5E_CPU1_P2_RX_BUF_DP<14>")
	)
	(segment
		(start 160.923986 -411.31998)
		(end 159.971486 -411.71495)
		(width 0.14224)
		(layer "In15.Cu")
		(net "P5E_CPU1_P2_RX_BUF_DP<14>")
	)
	(segment
		(start 155.620974 -419.452806)
		(end 155.426918 -419.452806)
		(width 0.14224)
		(layer "In15.Cu")
		(net "P5E_CPU1_P2_RX_BUF_DP<14>")
	)
	(segment
		(start 163.612322 -399.57883)
		(end 163.570412 -400.003772)
		(width 0.14224)
		(layer "In15.Cu")
		(net "P5E_CPU1_P2_RX_BUF_DP<14>")
	)
	(segment
		(start 163.309808 -401.249388)
		(end 163.268152 -401.673822)
		(width 0.14224)
		(layer "In15.Cu")
		(net "P5E_CPU1_P2_RX_BUF_DP<14>")
	)
	(segment
		(start 163.157662 -402.796248)
		(end 163.280852 -402.946108)
		(width 0.14224)
		(layer "In15.Cu")
		(net "P5E_CPU1_P2_RX_BUF_DP<14>")
	)
	(segment
		(start 164.244274 -393.144756)
		(end 164.117274 -393.017756)
		(width 0.14224)
		(layer "In15.Cu")
		(net "P5E_CPU1_P2_RX_BUF_DP<14>")
	)
	(segment
		(start 161.291778 -411.006798)
		(end 161.124392 -411.18282)
		(width 0.14224)
		(layer "In15.Cu")
		(net "P5E_CPU1_P2_RX_BUF_DP<14>")
	)
	(segment
		(start 163.088828 -403.49424)
		(end 163.047172 -403.918674)
		(width 0.14224)
		(layer "In15.Cu")
		(net "P5E_CPU1_P2_RX_BUF_DP<14>")
	)
	(segment
		(start 154.071066 -421.171878)
		(end 154.071066 -437.20385)
		(width 0.14224)
		(layer "In15.Cu")
		(net "P5E_CPU1_P2_RX_BUF_DP<14>")
	)
	(segment
		(start 154.823414 -420.250366)
		(end 154.629358 -420.250366)
		(width 0.14224)
		(layer "In15.Cu")
		(net "P5E_CPU1_P2_RX_BUF_DP<14>")
	)
	(segment
		(start 163.391342 -401.823682)
		(end 163.349432 -402.248624)
		(width 0.14224)
		(layer "In15.Cu")
		(net "P5E_CPU1_P2_RX_BUF_DP<14>")
	)
	(segment
		(start 155.426918 -419.452806)
		(end 155.12542 -419.754304)
		(width 0.14224)
		(layer "In15.Cu")
		(net "P5E_CPU1_P2_RX_BUF_DP<14>")
	)
	(segment
		(start 161.552636 -408.18816)
		(end 161.415476 -408.32532)
		(width 0.14224)
		(layer "In15.Cu")
		(net "P5E_CPU1_P2_RX_BUF_DP<14>")
	)
	(segment
		(start 155.12542 -419.754304)
		(end 155.12542 -419.94836)
		(width 0.14224)
		(layer "In15.Cu")
		(net "P5E_CPU1_P2_RX_BUF_DP<14>")
	)
	(segment
		(start 163.378642 -400.551396)
		(end 163.501832 -400.701256)
		(width 0.14224)
		(layer "In15.Cu")
		(net "P5E_CPU1_P2_RX_BUF_DP<14>")
	)
	(segment
		(start 161.415476 -409.45308)
		(end 161.415476 -410.697172)
		(width 0.14224)
		(layer "In15.Cu")
		(net "P5E_CPU1_P2_RX_BUF_DP<14>")
	)
	(segment
		(start 161.552636 -407.76144)
		(end 161.552636 -408.18816)
		(width 0.14224)
		(layer "In15.Cu")
		(net "P5E_CPU1_P2_RX_BUF_DP<14>")
	)
	(segment
		(start 163.927536 -393.017756)
		(end 163.785296 -393.159996)
		(width 0.14224)
		(layer "In15.Cu")
		(net "P5E_CPU1_P2_RX_BUF_DP<14>")
	)
	(segment
		(start 163.128198 -404.493476)
		(end 162.978084 -404.616666)
		(width 0.14224)
		(layer "In15.Cu")
		(net "P5E_CPU1_P2_RX_BUF_DP<14>")
	)
	(segment
		(start 163.280852 -402.946108)
		(end 163.238942 -403.37105)
		(width 0.14224)
		(layer "In15.Cu")
		(net "P5E_CPU1_P2_RX_BUF_DP<14>")
	)
	(segment
		(start 161.415476 -407.62428)
		(end 161.552636 -407.76144)
		(width 0.14224)
		(layer "In15.Cu")
		(net "P5E_CPU1_P2_RX_BUF_DP<14>")
	)
	(segment
		(start 159.62249 -415.257234)
		(end 155.92298 -418.956744)
		(width 0.14224)
		(layer "In15.Cu")
		(net "P5E_CPU1_P2_RX_BUF_DP<14>")
	)
	(segment
		(start 162.57397 -405.59228)
		(end 161.649918 -406.10409)
		(width 0.14224)
		(layer "In15.Cu")
		(net "P5E_CPU1_P2_RX_BUF_DP<14>")
	)
	(segment
		(start 163.047172 -403.918674)
		(end 163.170108 -404.068534)
		(width 0.14224)
		(layer "In15.Cu")
		(net "P5E_CPU1_P2_RX_BUF_DP<14>")
	)
	(segment
		(start 155.92298 -419.1508)
		(end 155.620974 -419.452806)
		(width 0.14224)
		(layer "In15.Cu")
		(net "P5E_CPU1_P2_RX_BUF_DP<14>")
	)
	(segment
		(start 163.349432 -402.248624)
		(end 163.199318 -402.371814)
		(width 0.14224)
		(layer "In15.Cu")
		(net "P5E_CPU1_P2_RX_BUF_DP<14>")
	)
	(segment
		(start 154.20848 -437.341264)
		(end 154.599894 -437.341264)
		(width 0.14224)
		(layer "In15.Cu")
		(net "P5E_CPU1_P2_RX_BUF_DP<14>")
	)
	(segment
		(start 155.92298 -418.956744)
		(end 155.92298 -419.1508)
		(width 0.14224)
		(layer "In15.Cu")
		(net "P5E_CPU1_P2_RX_BUF_DP<14>")
	)
	(segment
		(start 154.071066 -437.20385)
		(end 154.20848 -437.341264)
		(width 0.14224)
		(layer "In15.Cu")
		(net "P5E_CPU1_P2_RX_BUF_DP<14>")
	)
	(segment
		(start 154.750008 -437.19115)
		(end 154.750008 -436.889906)
		(width 0.14224)
		(layer "In15.Cu")
		(net "P5E_CPU1_P2_RX_BUF_DP<14>")
	)
	(segment
		(start 163.199318 -402.371814)
		(end 163.157662 -402.796248)
		(width 0.14224)
		(layer "In15.Cu")
		(net "P5E_CPU1_P2_RX_BUF_DP<14>")
	)
	(segment
		(start 163.459922 -401.126198)
		(end 163.309808 -401.249388)
		(width 0.14224)
		(layer "In15.Cu")
		(net "P5E_CPU1_P2_RX_BUF_DP<14>")
	)
	(segment
		(start 159.883856 -411.846268)
		(end 159.883856 -414.626298)
		(width 0.14224)
		(layer "In15.Cu")
		(net "P5E_CPU1_P2_RX_BUF_DP<14>")
	)
	(segment
		(start 163.268152 -401.673822)
		(end 163.391342 -401.823682)
		(width 0.14224)
		(layer "In15.Cu")
		(net "P5E_CPU1_P2_RX_BUF_DP<14>")
	)
	(segment
		(start 161.552636 -409.31592)
		(end 161.415476 -409.45308)
		(width 0.14224)
		(layer "In15.Cu")
		(net "P5E_CPU1_P2_RX_BUF_DP<14>")
	)
	(segment
		(start 163.70046 -397.281146)
		(end 163.489132 -399.42897)
		(width 0.14224)
		(layer "In15.Cu")
		(net "P5E_CPU1_P2_RX_BUF_DP<14>")
	)
	(segment
		(start 163.170108 -404.068534)
		(end 163.128198 -404.493476)
		(width 0.14224)
		(layer "In15.Cu")
		(net "P5E_CPU1_P2_RX_BUF_DP<14>")
	)
	(segment
		(start 163.570412 -400.003772)
		(end 163.420298 -400.126962)
		(width 0.14224)
		(layer "In15.Cu")
		(net "P5E_CPU1_P2_RX_BUF_DP<14>")
	)
	(arc
		(start 159.883856 -414.626298)
		(mid 159.815934 -414.967767)
		(end 159.62249 -415.257234)
		(width 0.14224)
		(layer "In15.Cu")
		(net "P5E_CPU1_P2_RX_BUF_DP<14>")
	)
	(arc
		(start 161.555938 -406.188926)
		(mid 161.451393 -406.402598)
		(end 161.415476 -406.637744)
		(width 0.14224)
		(layer "In15.Cu")
		(net "P5E_CPU1_P2_RX_BUF_DP<14>")
	)
	(arc
		(start 161.415476 -410.697172)
		(mid 161.383511 -410.86393)
		(end 161.291778 -411.006798)
		(width 0.14224)
		(layer "In15.Cu")
		(net "P5E_CPU1_P2_RX_BUF_DP<14>")
	)
	(arc
		(start 161.124392 -411.18282)
		(mid 161.031374 -411.261897)
		(end 160.923986 -411.31998)
		(width 0.14224)
		(layer "In15.Cu")
		(net "P5E_CPU1_P2_RX_BUF_DP<14>")
	)
	(arc
		(start 163.785296 -395.553946)
		(mid 163.764065 -396.418587)
		(end 163.70046 -397.281146)
		(width 0.14224)
		(layer "In15.Cu")
		(net "P5E_CPU1_P2_RX_BUF_DP<14>")
	)
	(arc
		(start 161.649918 -406.10409)
		(mid 161.598042 -406.141095)
		(end 161.555938 -406.188926)
		(width 0.14224)
		(layer "In15.Cu")
		(net "P5E_CPU1_P2_RX_BUF_DP<14>")
	)
	(arc
		(start 162.936428 -405.0411)
		(mid 162.823112 -405.361357)
		(end 162.57397 -405.59228)
		(width 0.14224)
		(layer "In15.Cu")
		(net "P5E_CPU1_P2_RX_BUF_DP<14>")
	)
	(arc
		(start 154.32786 -420.551864)
		(mid 154.137787 -420.836329)
		(end 154.071066 -421.171878)
		(width 0.14224)
		(layer "In15.Cu")
		(net "P5E_CPU1_P2_RX_BUF_DP<14>")
	)
	(arc
		(start 159.971486 -411.71495)
		(mid 159.907681 -411.767294)
		(end 159.883856 -411.846268)
		(width 0.14224)
		(layer "In15.Cu")
		(net "P5E_CPU1_P2_RX_BUF_DP<14>")
	)
	(segment
		(start 162.430206 -391.488676)
		(end 162.350196 -391.568686)
		(width 0.1016)
		(layer "F.Cu")
		(net "P5E_CPU1_P2_RX_BUF_DP<13>")
	)
	(segment
		(start 162.345624 -391.281158)
		(end 162.430206 -391.36574)
		(width 0.1016)
		(layer "F.Cu")
		(net "P5E_CPU1_P2_RX_BUF_DP<13>")
	)
	(segment
		(start 162.350196 -391.568686)
		(end 162.350196 -392.723878)
		(width 0.1016)
		(layer "F.Cu")
		(net "P5E_CPU1_P2_RX_BUF_DP<13>")
	)
	(segment
		(start 163.044124 -393.1158)
		(end 163.044124 -393.292838)
		(width 0.1016)
		(layer "F.Cu")
		(net "P5E_CPU1_P2_RX_BUF_DP<13>")
	)
	(segment
		(start 162.90544 -392.977116)
		(end 163.044124 -393.1158)
		(width 0.1016)
		(layer "F.Cu")
		(net "P5E_CPU1_P2_RX_BUF_DP<13>")
	)
	(segment
		(start 162.430206 -391.36574)
		(end 162.430206 -391.488676)
		(width 0.1016)
		(layer "F.Cu")
		(net "P5E_CPU1_P2_RX_BUF_DP<13>")
	)
	(segment
		(start 162.603434 -392.977116)
		(end 162.90544 -392.977116)
		(width 0.1016)
		(layer "F.Cu")
		(net "P5E_CPU1_P2_RX_BUF_DP<13>")
	)
	(segment
		(start 162.350196 -392.723878)
		(end 162.603434 -392.977116)
		(width 0.1016)
		(layer "F.Cu")
		(net "P5E_CPU1_P2_RX_BUF_DP<13>")
	)
	(segment
		(start 158.352236 -409.548584)
		(end 158.352236 -410.697172)
		(width 0.14224)
		(layer "In15.Cu")
		(net "P5E_CPU1_P2_RX_BUF_DP<13>")
	)
	(segment
		(start 161.750756 -397.311626)
		(end 161.606992 -397.7132)
		(width 0.14224)
		(layer "In15.Cu")
		(net "P5E_CPU1_P2_RX_BUF_DP<13>")
	)
	(segment
		(start 159.219138 -405.771096)
		(end 158.943548 -405.885142)
		(width 0.14224)
		(layer "In15.Cu")
		(net "P5E_CPU1_P2_RX_BUF_DP<13>")
	)
	(segment
		(start 158.489396 -408.984704)
		(end 158.489396 -409.411424)
		(width 0.14224)
		(layer "In15.Cu")
		(net "P5E_CPU1_P2_RX_BUF_DP<13>")
	)
	(segment
		(start 160.930082 -400.012408)
		(end 160.786318 -400.41449)
		(width 0.14224)
		(layer "In15.Cu")
		(net "P5E_CPU1_P2_RX_BUF_DP<13>")
	)
	(segment
		(start 152.599898 -438.341262)
		(end 152.750012 -438.191148)
		(width 0.14224)
		(layer "In15.Cu")
		(net "P5E_CPU1_P2_RX_BUF_DP<13>")
	)
	(segment
		(start 162.070034 -396.82674)
		(end 161.92627 -397.228568)
		(width 0.14224)
		(layer "In15.Cu")
		(net "P5E_CPU1_P2_RX_BUF_DP<13>")
	)
	(segment
		(start 163.044124 -393.144756)
		(end 162.917124 -393.017756)
		(width 0.14224)
		(layer "In15.Cu")
		(net "P5E_CPU1_P2_RX_BUF_DP<13>")
	)
	(segment
		(start 160.16986 -402.345652)
		(end 160.277556 -402.506942)
		(width 0.14224)
		(layer "In15.Cu")
		(net "P5E_CPU1_P2_RX_BUF_DP<13>")
	)
	(segment
		(start 160.277556 -402.506942)
		(end 160.194498 -402.925788)
		(width 0.14224)
		(layer "In15.Cu")
		(net "P5E_CPU1_P2_RX_BUF_DP<13>")
	)
	(segment
		(start 160.610804 -400.497548)
		(end 160.46704 -400.899122)
		(width 0.14224)
		(layer "In15.Cu")
		(net "P5E_CPU1_P2_RX_BUF_DP<13>")
	)
	(segment
		(start 161.227008 -398.775174)
		(end 161.310066 -398.950434)
		(width 0.14224)
		(layer "In15.Cu")
		(net "P5E_CPU1_P2_RX_BUF_DP<13>")
	)
	(segment
		(start 159.883856 -403.97557)
		(end 159.883856 -404.924514)
		(width 0.14224)
		(layer "In15.Cu")
		(net "P5E_CPU1_P2_RX_BUF_DP<13>")
	)
	(segment
		(start 152.07107 -438.199022)
		(end 152.21331 -438.341262)
		(width 0.14224)
		(layer "In15.Cu")
		(net "P5E_CPU1_P2_RX_BUF_DP<13>")
	)
	(segment
		(start 158.352236 -408.420824)
		(end 158.352236 -408.847544)
		(width 0.14224)
		(layer "In15.Cu")
		(net "P5E_CPU1_P2_RX_BUF_DP<13>")
	)
	(segment
		(start 163.044124 -393.292838)
		(end 163.044124 -393.144756)
		(width 0.14224)
		(layer "In15.Cu")
		(net "P5E_CPU1_P2_RX_BUF_DP<13>")
	)
	(segment
		(start 158.489396 -409.411424)
		(end 158.352236 -409.548584)
		(width 0.14224)
		(layer "In15.Cu")
		(net "P5E_CPU1_P2_RX_BUF_DP<13>")
	)
	(segment
		(start 161.310066 -398.950434)
		(end 161.166302 -399.352516)
		(width 0.14224)
		(layer "In15.Cu")
		(net "P5E_CPU1_P2_RX_BUF_DP<13>")
	)
	(segment
		(start 158.228538 -411.006798)
		(end 158.061152 -411.18282)
		(width 0.14224)
		(layer "In15.Cu")
		(net "P5E_CPU1_P2_RX_BUF_DP<13>")
	)
	(segment
		(start 162.585146 -393.159996)
		(end 162.585146 -394.26261)
		(width 0.14224)
		(layer "In15.Cu")
		(net "P5E_CPU1_P2_RX_BUF_DP<13>")
	)
	(segment
		(start 160.194498 -402.925788)
		(end 160.032954 -403.033484)
		(width 0.14224)
		(layer "In15.Cu")
		(net "P5E_CPU1_P2_RX_BUF_DP<13>")
	)
	(segment
		(start 153.02357 -418.008308)
		(end 152.358344 -418.673534)
		(width 0.14224)
		(layer "In15.Cu")
		(net "P5E_CPU1_P2_RX_BUF_DP<13>")
	)
	(segment
		(start 157.860746 -411.31998)
		(end 156.908246 -411.71495)
		(width 0.14224)
		(layer "In15.Cu")
		(net "P5E_CPU1_P2_RX_BUF_DP<13>")
	)
	(segment
		(start 161.92627 -397.228568)
		(end 161.750756 -397.311626)
		(width 0.14224)
		(layer "In15.Cu")
		(net "P5E_CPU1_P2_RX_BUF_DP<13>")
	)
	(segment
		(start 161.606992 -397.7132)
		(end 161.69005 -397.88846)
		(width 0.14224)
		(layer "In15.Cu")
		(net "P5E_CPU1_P2_RX_BUF_DP<13>")
	)
	(segment
		(start 158.352236 -407.719784)
		(end 158.489396 -407.856944)
		(width 0.14224)
		(layer "In15.Cu")
		(net "P5E_CPU1_P2_RX_BUF_DP<13>")
	)
	(segment
		(start 159.534606 -405.560276)
		(end 159.219138 -405.771096)
		(width 0.14224)
		(layer "In15.Cu")
		(net "P5E_CPU1_P2_RX_BUF_DP<13>")
	)
	(segment
		(start 160.847024 -399.837148)
		(end 160.930082 -400.012408)
		(width 0.14224)
		(layer "In15.Cu")
		(net "P5E_CPU1_P2_RX_BUF_DP<13>")
	)
	(segment
		(start 152.750012 -438.191148)
		(end 152.750012 -437.889904)
		(width 0.14224)
		(layer "In15.Cu")
		(net "P5E_CPU1_P2_RX_BUF_DP<13>")
	)
	(segment
		(start 162.573716 -394.38072)
		(end 162.30981 -395.708378)
		(width 0.14224)
		(layer "In15.Cu")
		(net "P5E_CPU1_P2_RX_BUF_DP<13>")
	)
	(segment
		(start 162.268662 -395.86408)
		(end 162.267138 -395.868652)
		(width 0.14224)
		(layer "In15.Cu")
		(net "P5E_CPU1_P2_RX_BUF_DP<13>")
	)
	(segment
		(start 161.69005 -397.88846)
		(end 161.546286 -398.290542)
		(width 0.14224)
		(layer "In15.Cu")
		(net "P5E_CPU1_P2_RX_BUF_DP<13>")
	)
	(segment
		(start 162.267138 -395.868652)
		(end 161.987738 -396.649702)
		(width 0.14224)
		(layer "In15.Cu")
		(net "P5E_CPU1_P2_RX_BUF_DP<13>")
	)
	(segment
		(start 158.352236 -408.847544)
		(end 158.489396 -408.984704)
		(width 0.14224)
		(layer "In15.Cu")
		(net "P5E_CPU1_P2_RX_BUF_DP<13>")
	)
	(segment
		(start 154.015186 -417.210748)
		(end 153.82113 -417.210748)
		(width 0.14224)
		(layer "In15.Cu")
		(net "P5E_CPU1_P2_RX_BUF_DP<13>")
	)
	(segment
		(start 158.489396 -407.856944)
		(end 158.489396 -408.283664)
		(width 0.14224)
		(layer "In15.Cu")
		(net "P5E_CPU1_P2_RX_BUF_DP<13>")
	)
	(segment
		(start 153.82113 -417.210748)
		(end 153.519632 -417.512246)
		(width 0.14224)
		(layer "In15.Cu")
		(net "P5E_CPU1_P2_RX_BUF_DP<13>")
	)
	(segment
		(start 160.786318 -400.41449)
		(end 160.610804 -400.497548)
		(width 0.14224)
		(layer "In15.Cu")
		(net "P5E_CPU1_P2_RX_BUF_DP<13>")
	)
	(segment
		(start 154.317192 -416.908742)
		(end 154.015186 -417.210748)
		(width 0.14224)
		(layer "In15.Cu")
		(net "P5E_CPU1_P2_RX_BUF_DP<13>")
	)
	(segment
		(start 154.317192 -416.714686)
		(end 154.317192 -416.908742)
		(width 0.14224)
		(layer "In15.Cu")
		(net "P5E_CPU1_P2_RX_BUF_DP<13>")
	)
	(segment
		(start 158.489396 -408.283664)
		(end 158.352236 -408.420824)
		(width 0.14224)
		(layer "In15.Cu")
		(net "P5E_CPU1_P2_RX_BUF_DP<13>")
	)
	(segment
		(start 153.217626 -418.008308)
		(end 153.02357 -418.008308)
		(width 0.14224)
		(layer "In15.Cu")
		(net "P5E_CPU1_P2_RX_BUF_DP<13>")
	)
	(segment
		(start 152.21331 -438.341262)
		(end 152.599898 -438.341262)
		(width 0.14224)
		(layer "In15.Cu")
		(net "P5E_CPU1_P2_RX_BUF_DP<13>")
	)
	(segment
		(start 162.727386 -393.017756)
		(end 162.585146 -393.159996)
		(width 0.14224)
		(layer "In15.Cu")
		(net "P5E_CPU1_P2_RX_BUF_DP<13>")
	)
	(segment
		(start 160.990788 -399.435574)
		(end 160.847024 -399.837148)
		(width 0.14224)
		(layer "In15.Cu")
		(net "P5E_CPU1_P2_RX_BUF_DP<13>")
	)
	(segment
		(start 161.987738 -396.649702)
		(end 161.98723 -396.651226)
		(width 0.14224)
		(layer "In15.Cu")
		(net "P5E_CPU1_P2_RX_BUF_DP<13>")
	)
	(segment
		(start 152.07107 -419.366954)
		(end 152.07107 -438.199022)
		(width 0.14224)
		(layer "In15.Cu")
		(net "P5E_CPU1_P2_RX_BUF_DP<13>")
	)
	(segment
		(start 156.820616 -411.846268)
		(end 156.820616 -413.725614)
		(width 0.14224)
		(layer "In15.Cu")
		(net "P5E_CPU1_P2_RX_BUF_DP<13>")
	)
	(segment
		(start 156.477208 -414.55467)
		(end 154.317192 -416.714686)
		(width 0.14224)
		(layer "In15.Cu")
		(net "P5E_CPU1_P2_RX_BUF_DP<13>")
	)
	(segment
		(start 158.352236 -406.638252)
		(end 158.352236 -407.719784)
		(width 0.14224)
		(layer "In15.Cu")
		(net "P5E_CPU1_P2_RX_BUF_DP<13>")
	)
	(segment
		(start 160.032954 -403.033484)
		(end 159.921448 -403.594316)
		(width 0.14224)
		(layer "In15.Cu")
		(net "P5E_CPU1_P2_RX_BUF_DP<13>")
	)
	(segment
		(start 153.519632 -417.512246)
		(end 153.519632 -417.706302)
		(width 0.14224)
		(layer "In15.Cu")
		(net "P5E_CPU1_P2_RX_BUF_DP<13>")
	)
	(segment
		(start 161.166302 -399.352516)
		(end 160.990788 -399.435574)
		(width 0.14224)
		(layer "In15.Cu")
		(net "P5E_CPU1_P2_RX_BUF_DP<13>")
	)
	(segment
		(start 160.433258 -401.021042)
		(end 160.16986 -402.345652)
		(width 0.14224)
		(layer "In15.Cu")
		(net "P5E_CPU1_P2_RX_BUF_DP<13>")
	)
	(segment
		(start 159.681418 -405.413464)
		(end 159.534606 -405.560276)
		(width 0.14224)
		(layer "In15.Cu")
		(net "P5E_CPU1_P2_RX_BUF_DP<13>")
	)
	(segment
		(start 161.546286 -398.290542)
		(end 161.370772 -398.3736)
		(width 0.14224)
		(layer "In15.Cu")
		(net "P5E_CPU1_P2_RX_BUF_DP<13>")
	)
	(segment
		(start 161.370772 -398.3736)
		(end 161.227008 -398.775174)
		(width 0.14224)
		(layer "In15.Cu")
		(net "P5E_CPU1_P2_RX_BUF_DP<13>")
	)
	(segment
		(start 153.519632 -417.706302)
		(end 153.217626 -418.008308)
		(width 0.14224)
		(layer "In15.Cu")
		(net "P5E_CPU1_P2_RX_BUF_DP<13>")
	)
	(segment
		(start 161.98723 -396.651226)
		(end 162.070034 -396.82674)
		(width 0.14224)
		(layer "In15.Cu")
		(net "P5E_CPU1_P2_RX_BUF_DP<13>")
	)
	(segment
		(start 162.917124 -393.017756)
		(end 162.727386 -393.017756)
		(width 0.14224)
		(layer "In15.Cu")
		(net "P5E_CPU1_P2_RX_BUF_DP<13>")
	)
	(arc
		(start 158.557214 -406.14346)
		(mid 158.405451 -406.370445)
		(end 158.352236 -406.638252)
		(width 0.14224)
		(layer "In15.Cu")
		(net "P5E_CPU1_P2_RX_BUF_DP<13>")
	)
	(arc
		(start 159.921448 -403.594316)
		(mid 159.893286 -403.784019)
		(end 159.883856 -403.97557)
		(width 0.14224)
		(layer "In15.Cu")
		(net "P5E_CPU1_P2_RX_BUF_DP<13>")
	)
	(arc
		(start 162.30981 -395.708378)
		(mid 162.291669 -395.786872)
		(end 162.268662 -395.86408)
		(width 0.14224)
		(layer "In15.Cu")
		(net "P5E_CPU1_P2_RX_BUF_DP<13>")
	)
	(arc
		(start 158.061152 -411.18282)
		(mid 157.968134 -411.261897)
		(end 157.860746 -411.31998)
		(width 0.14224)
		(layer "In15.Cu")
		(net "P5E_CPU1_P2_RX_BUF_DP<13>")
	)
	(arc
		(start 156.820616 -413.725614)
		(mid 156.731367 -414.174297)
		(end 156.477208 -414.55467)
		(width 0.14224)
		(layer "In15.Cu")
		(net "P5E_CPU1_P2_RX_BUF_DP<13>")
	)
	(arc
		(start 152.358344 -418.673534)
		(mid 152.145713 -418.991664)
		(end 152.07107 -419.366954)
		(width 0.14224)
		(layer "In15.Cu")
		(net "P5E_CPU1_P2_RX_BUF_DP<13>")
	)
	(arc
		(start 159.883856 -404.924514)
		(mid 159.831242 -405.189111)
		(end 159.681418 -405.413464)
		(width 0.14224)
		(layer "In15.Cu")
		(net "P5E_CPU1_P2_RX_BUF_DP<13>")
	)
	(arc
		(start 158.943548 -405.885142)
		(mid 158.737666 -405.995288)
		(end 158.557214 -406.14346)
		(width 0.14224)
		(layer "In15.Cu")
		(net "P5E_CPU1_P2_RX_BUF_DP<13>")
	)
	(arc
		(start 162.585146 -394.26261)
		(mid 162.582328 -394.321945)
		(end 162.573716 -394.38072)
		(width 0.14224)
		(layer "In15.Cu")
		(net "P5E_CPU1_P2_RX_BUF_DP<13>")
	)
	(arc
		(start 160.46704 -400.899122)
		(mid 160.447907 -400.959461)
		(end 160.433258 -401.021042)
		(width 0.14224)
		(layer "In15.Cu")
		(net "P5E_CPU1_P2_RX_BUF_DP<13>")
	)
	(arc
		(start 158.352236 -410.697172)
		(mid 158.320271 -410.86393)
		(end 158.228538 -411.006798)
		(width 0.14224)
		(layer "In15.Cu")
		(net "P5E_CPU1_P2_RX_BUF_DP<13>")
	)
	(arc
		(start 156.908246 -411.71495)
		(mid 156.844441 -411.767294)
		(end 156.820616 -411.846268)
		(width 0.14224)
		(layer "In15.Cu")
		(net "P5E_CPU1_P2_RX_BUF_DP<13>")
	)
	(segment
		(start 161.145728 -391.281158)
		(end 161.23031 -391.36574)
		(width 0.1016)
		(layer "F.Cu")
		(net "P5E_CPU1_P2_RX_BUF_DP<12>")
	)
	(segment
		(start 161.141664 -392.723878)
		(end 161.394902 -392.977116)
		(width 0.1016)
		(layer "F.Cu")
		(net "P5E_CPU1_P2_RX_BUF_DP<12>")
	)
	(segment
		(start 161.844228 -393.119102)
		(end 161.844228 -393.292838)
		(width 0.1016)
		(layer "F.Cu")
		(net "P5E_CPU1_P2_RX_BUF_DP<12>")
	)
	(segment
		(start 161.702242 -392.977116)
		(end 161.844228 -393.119102)
		(width 0.1016)
		(layer "F.Cu")
		(net "P5E_CPU1_P2_RX_BUF_DP<12>")
	)
	(segment
		(start 161.23031 -391.36574)
		(end 161.23031 -391.488676)
		(width 0.1016)
		(layer "F.Cu")
		(net "P5E_CPU1_P2_RX_BUF_DP<12>")
	)
	(segment
		(start 161.23031 -391.488676)
		(end 161.141664 -391.577322)
		(width 0.1016)
		(layer "F.Cu")
		(net "P5E_CPU1_P2_RX_BUF_DP<12>")
	)
	(segment
		(start 161.141664 -391.577322)
		(end 161.141664 -392.723878)
		(width 0.1016)
		(layer "F.Cu")
		(net "P5E_CPU1_P2_RX_BUF_DP<12>")
	)
	(segment
		(start 161.394902 -392.977116)
		(end 161.702242 -392.977116)
		(width 0.1016)
		(layer "F.Cu")
		(net "P5E_CPU1_P2_RX_BUF_DP<12>")
	)
	(segment
		(start 150.599902 -437.341264)
		(end 150.750016 -437.19115)
		(width 0.14224)
		(layer "In15.Cu")
		(net "P5E_CPU1_P2_RX_BUF_DP<12>")
	)
	(segment
		(start 156.618178 -405.413464)
		(end 156.471366 -405.560276)
		(width 0.14224)
		(layer "In15.Cu")
		(net "P5E_CPU1_P2_RX_BUF_DP<12>")
	)
	(segment
		(start 155.426156 -407.948384)
		(end 155.426156 -408.375104)
		(width 0.14224)
		(layer "In15.Cu")
		(net "P5E_CPU1_P2_RX_BUF_DP<12>")
	)
	(segment
		(start 150.071074 -437.20385)
		(end 150.208488 -437.341264)
		(width 0.14224)
		(layer "In15.Cu")
		(net "P5E_CPU1_P2_RX_BUF_DP<12>")
	)
	(segment
		(start 156.155898 -405.771096)
		(end 155.880308 -405.885142)
		(width 0.14224)
		(layer "In15.Cu")
		(net "P5E_CPU1_P2_RX_BUF_DP<12>")
	)
	(segment
		(start 161.844228 -393.292838)
		(end 161.844228 -393.144756)
		(width 0.14224)
		(layer "In15.Cu")
		(net "P5E_CPU1_P2_RX_BUF_DP<12>")
	)
	(segment
		(start 157.514544 -402.33981)
		(end 157.561788 -402.528024)
		(width 0.14224)
		(layer "In15.Cu")
		(net "P5E_CPU1_P2_RX_BUF_DP<12>")
	)
	(segment
		(start 158.47314 -400.740626)
		(end 158.253938 -401.106386)
		(width 0.14224)
		(layer "In15.Cu")
		(net "P5E_CPU1_P2_RX_BUF_DP<12>")
	)
	(segment
		(start 157.561788 -402.528024)
		(end 157.342332 -402.894292)
		(width 0.14224)
		(layer "In15.Cu")
		(net "P5E_CPU1_P2_RX_BUF_DP<12>")
	)
	(segment
		(start 158.83382 -400.1389)
		(end 158.881064 -400.327114)
		(width 0.14224)
		(layer "In15.Cu")
		(net "P5E_CPU1_P2_RX_BUF_DP<12>")
	)
	(segment
		(start 155.288996 -408.938984)
		(end 155.426156 -409.076144)
		(width 0.14224)
		(layer "In15.Cu")
		(net "P5E_CPU1_P2_RX_BUF_DP<12>")
	)
	(segment
		(start 152.7302 -415.137854)
		(end 152.7302 -415.33191)
		(width 0.14224)
		(layer "In15.Cu")
		(net "P5E_CPU1_P2_RX_BUF_DP<12>")
	)
	(segment
		(start 155.426156 -409.502864)
		(end 155.288996 -409.640024)
		(width 0.14224)
		(layer "In15.Cu")
		(net "P5E_CPU1_P2_RX_BUF_DP<12>")
	)
	(segment
		(start 155.165298 -411.006798)
		(end 154.997912 -411.18282)
		(width 0.14224)
		(layer "In15.Cu")
		(net "P5E_CPU1_P2_RX_BUF_DP<12>")
	)
	(segment
		(start 152.234138 -415.633916)
		(end 151.93264 -415.935414)
		(width 0.14224)
		(layer "In15.Cu")
		(net "P5E_CPU1_P2_RX_BUF_DP<12>")
	)
	(segment
		(start 150.208488 -437.341264)
		(end 150.599902 -437.341264)
		(width 0.14224)
		(layer "In15.Cu")
		(net "P5E_CPU1_P2_RX_BUF_DP<12>")
	)
	(segment
		(start 158.253938 -401.106386)
		(end 158.300928 -401.2946)
		(width 0.14224)
		(layer "In15.Cu")
		(net "P5E_CPU1_P2_RX_BUF_DP<12>")
	)
	(segment
		(start 150.639018 -417.229036)
		(end 150.33752 -417.530534)
		(width 0.14224)
		(layer "In15.Cu")
		(net "P5E_CPU1_P2_RX_BUF_DP<12>")
	)
	(segment
		(start 160.266634 -397.626332)
		(end 160.323022 -397.811752)
		(width 0.14224)
		(layer "In15.Cu")
		(net "P5E_CPU1_P2_RX_BUF_DP<12>")
	)
	(segment
		(start 155.426156 -409.076144)
		(end 155.426156 -409.502864)
		(width 0.14224)
		(layer "In15.Cu")
		(net "P5E_CPU1_P2_RX_BUF_DP<12>")
	)
	(segment
		(start 151.436578 -416.431476)
		(end 151.13508 -416.732974)
		(width 0.14224)
		(layer "In15.Cu")
		(net "P5E_CPU1_P2_RX_BUF_DP<12>")
	)
	(segment
		(start 160.323022 -397.811752)
		(end 160.121854 -398.188434)
		(width 0.14224)
		(layer "In15.Cu")
		(net "P5E_CPU1_P2_RX_BUF_DP<12>")
	)
	(segment
		(start 154.796744 -411.320742)
		(end 153.845006 -411.71495)
		(width 0.14224)
		(layer "In15.Cu")
		(net "P5E_CPU1_P2_RX_BUF_DP<12>")
	)
	(segment
		(start 160.121854 -398.188434)
		(end 159.93618 -398.244822)
		(width 0.14224)
		(layer "In15.Cu")
		(net "P5E_CPU1_P2_RX_BUF_DP<12>")
	)
	(segment
		(start 161.717228 -393.017756)
		(end 161.52749 -393.017756)
		(width 0.14224)
		(layer "In15.Cu")
		(net "P5E_CPU1_P2_RX_BUF_DP<12>")
	)
	(segment
		(start 151.93264 -416.12947)
		(end 151.630634 -416.431476)
		(width 0.14224)
		(layer "In15.Cu")
		(net "P5E_CPU1_P2_RX_BUF_DP<12>")
	)
	(segment
		(start 156.820616 -404.019258)
		(end 156.820616 -404.924514)
		(width 0.14224)
		(layer "In15.Cu")
		(net "P5E_CPU1_P2_RX_BUF_DP<12>")
	)
	(segment
		(start 156.893006 -403.425914)
		(end 156.829252 -403.89302)
		(width 0.14224)
		(layer "In15.Cu")
		(net "P5E_CPU1_P2_RX_BUF_DP<12>")
	)
	(segment
		(start 151.93264 -415.935414)
		(end 151.93264 -416.12947)
		(width 0.14224)
		(layer "In15.Cu")
		(net "P5E_CPU1_P2_RX_BUF_DP<12>")
	)
	(segment
		(start 155.288996 -407.811224)
		(end 155.426156 -407.948384)
		(width 0.14224)
		(layer "In15.Cu")
		(net "P5E_CPU1_P2_RX_BUF_DP<12>")
	)
	(segment
		(start 158.881064 -400.327114)
		(end 158.661608 -400.693382)
		(width 0.14224)
		(layer "In15.Cu")
		(net "P5E_CPU1_P2_RX_BUF_DP<12>")
	)
	(segment
		(start 161.38525 -395.200124)
		(end 160.864296 -396.457932)
		(width 0.14224)
		(layer "In15.Cu")
		(net "P5E_CPU1_P2_RX_BUF_DP<12>")
	)
	(segment
		(start 151.630634 -416.431476)
		(end 151.436578 -416.431476)
		(width 0.14224)
		(layer "In15.Cu")
		(net "P5E_CPU1_P2_RX_BUF_DP<12>")
	)
	(segment
		(start 157.342332 -402.894292)
		(end 157.153864 -402.941536)
		(width 0.14224)
		(layer "In15.Cu")
		(net "P5E_CPU1_P2_RX_BUF_DP<12>")
	)
	(segment
		(start 161.38525 -393.159996)
		(end 161.38525 -395.200124)
		(width 0.14224)
		(layer "In15.Cu")
		(net "P5E_CPU1_P2_RX_BUF_DP<12>")
	)
	(segment
		(start 156.471366 -405.560276)
		(end 156.155898 -405.771096)
		(width 0.14224)
		(layer "In15.Cu")
		(net "P5E_CPU1_P2_RX_BUF_DP<12>")
	)
	(segment
		(start 159.401764 -399.191226)
		(end 158.83382 -400.1389)
		(width 0.14224)
		(layer "In15.Cu")
		(net "P5E_CPU1_P2_RX_BUF_DP<12>")
	)
	(segment
		(start 161.52749 -393.017756)
		(end 161.38525 -393.159996)
		(width 0.14224)
		(layer "In15.Cu")
		(net "P5E_CPU1_P2_RX_BUF_DP<12>")
	)
	(segment
		(start 153.400506 -414.467548)
		(end 152.7302 -415.137854)
		(width 0.14224)
		(layer "In15.Cu")
		(net "P5E_CPU1_P2_RX_BUF_DP<12>")
	)
	(segment
		(start 155.288996 -408.512264)
		(end 155.288996 -408.938984)
		(width 0.14224)
		(layer "In15.Cu")
		(net "P5E_CPU1_P2_RX_BUF_DP<12>")
	)
	(segment
		(start 157.893258 -401.708112)
		(end 157.514544 -402.33981)
		(width 0.14224)
		(layer "In15.Cu")
		(net "P5E_CPU1_P2_RX_BUF_DP<12>")
	)
	(segment
		(start 158.300928 -401.2946)
		(end 158.081726 -401.660868)
		(width 0.14224)
		(layer "In15.Cu")
		(net "P5E_CPU1_P2_RX_BUF_DP<12>")
	)
	(segment
		(start 153.757376 -411.846014)
		(end 153.757376 -413.606234)
		(width 0.14224)
		(layer "In15.Cu")
		(net "P5E_CPU1_P2_RX_BUF_DP<12>")
	)
	(segment
		(start 155.426156 -408.375104)
		(end 155.288996 -408.512264)
		(width 0.14224)
		(layer "In15.Cu")
		(net "P5E_CPU1_P2_RX_BUF_DP<12>")
	)
	(segment
		(start 151.13508 -416.732974)
		(end 151.13508 -416.92703)
		(width 0.14224)
		(layer "In15.Cu")
		(net "P5E_CPU1_P2_RX_BUF_DP<12>")
	)
	(segment
		(start 159.93618 -398.244822)
		(end 159.898588 -398.314926)
		(width 0.14224)
		(layer "In15.Cu")
		(net "P5E_CPU1_P2_RX_BUF_DP<12>")
	)
	(segment
		(start 157.153864 -402.941536)
		(end 156.934662 -403.307296)
		(width 0.14224)
		(layer "In15.Cu")
		(net "P5E_CPU1_P2_RX_BUF_DP<12>")
	)
	(segment
		(start 152.428194 -415.633916)
		(end 152.234138 -415.633916)
		(width 0.14224)
		(layer "In15.Cu")
		(net "P5E_CPU1_P2_RX_BUF_DP<12>")
	)
	(segment
		(start 160.659572 -396.890494)
		(end 160.266634 -397.626332)
		(width 0.14224)
		(layer "In15.Cu")
		(net "P5E_CPU1_P2_RX_BUF_DP<12>")
	)
	(segment
		(start 161.844228 -393.144756)
		(end 161.717228 -393.017756)
		(width 0.14224)
		(layer "In15.Cu")
		(net "P5E_CPU1_P2_RX_BUF_DP<12>")
	)
	(segment
		(start 155.288996 -406.638252)
		(end 155.288996 -407.811224)
		(width 0.14224)
		(layer "In15.Cu")
		(net "P5E_CPU1_P2_RX_BUF_DP<12>")
	)
	(segment
		(start 158.661608 -400.693382)
		(end 158.47314 -400.740626)
		(width 0.14224)
		(layer "In15.Cu")
		(net "P5E_CPU1_P2_RX_BUF_DP<12>")
	)
	(segment
		(start 158.081726 -401.660868)
		(end 157.893258 -401.708112)
		(width 0.14224)
		(layer "In15.Cu")
		(net "P5E_CPU1_P2_RX_BUF_DP<12>")
	)
	(segment
		(start 150.833074 -417.229036)
		(end 150.639018 -417.229036)
		(width 0.14224)
		(layer "In15.Cu")
		(net "P5E_CPU1_P2_RX_BUF_DP<12>")
	)
	(segment
		(start 151.13508 -416.92703)
		(end 150.833074 -417.229036)
		(width 0.14224)
		(layer "In15.Cu")
		(net "P5E_CPU1_P2_RX_BUF_DP<12>")
	)
	(segment
		(start 152.7302 -415.33191)
		(end 152.428194 -415.633916)
		(width 0.14224)
		(layer "In15.Cu")
		(net "P5E_CPU1_P2_RX_BUF_DP<12>")
	)
	(segment
		(start 150.750016 -437.19115)
		(end 150.750016 -436.889906)
		(width 0.14224)
		(layer "In15.Cu")
		(net "P5E_CPU1_P2_RX_BUF_DP<12>")
	)
	(segment
		(start 150.071074 -418.173916)
		(end 150.071074 -437.20385)
		(width 0.14224)
		(layer "In15.Cu")
		(net "P5E_CPU1_P2_RX_BUF_DP<12>")
	)
	(segment
		(start 155.288996 -409.640024)
		(end 155.288996 -410.697172)
		(width 0.14224)
		(layer "In15.Cu")
		(net "P5E_CPU1_P2_RX_BUF_DP<12>")
	)
	(arc
		(start 150.33752 -417.530534)
		(mid 150.140337 -417.825734)
		(end 150.071074 -418.173916)
		(width 0.14224)
		(layer "In15.Cu")
		(net "P5E_CPU1_P2_RX_BUF_DP<12>")
	)
	(arc
		(start 156.820616 -404.924514)
		(mid 156.768002 -405.189111)
		(end 156.618178 -405.413464)
		(width 0.14224)
		(layer "In15.Cu")
		(net "P5E_CPU1_P2_RX_BUF_DP<12>")
	)
	(arc
		(start 159.898588 -398.314926)
		(mid 159.65556 -398.756128)
		(end 159.401764 -399.191226)
		(width 0.14224)
		(layer "In15.Cu")
		(net "P5E_CPU1_P2_RX_BUF_DP<12>")
	)
	(arc
		(start 154.997912 -411.18282)
		(mid 154.904554 -411.262321)
		(end 154.796744 -411.320742)
		(width 0.14224)
		(layer "In15.Cu")
		(net "P5E_CPU1_P2_RX_BUF_DP<12>")
	)
	(arc
		(start 155.288996 -410.697172)
		(mid 155.257031 -410.86393)
		(end 155.165298 -411.006798)
		(width 0.14224)
		(layer "In15.Cu")
		(net "P5E_CPU1_P2_RX_BUF_DP<12>")
	)
	(arc
		(start 155.493974 -406.14346)
		(mid 155.342211 -406.370445)
		(end 155.288996 -406.638252)
		(width 0.14224)
		(layer "In15.Cu")
		(net "P5E_CPU1_P2_RX_BUF_DP<12>")
	)
	(arc
		(start 155.880308 -405.885142)
		(mid 155.674426 -405.995288)
		(end 155.493974 -406.14346)
		(width 0.14224)
		(layer "In15.Cu")
		(net "P5E_CPU1_P2_RX_BUF_DP<12>")
	)
	(arc
		(start 153.845006 -411.71495)
		(mid 153.781369 -411.767211)
		(end 153.757376 -411.846014)
		(width 0.14224)
		(layer "In15.Cu")
		(net "P5E_CPU1_P2_RX_BUF_DP<12>")
	)
	(arc
		(start 156.934662 -403.307296)
		(mid 156.907815 -403.364492)
		(end 156.893006 -403.425914)
		(width 0.14224)
		(layer "In15.Cu")
		(net "P5E_CPU1_P2_RX_BUF_DP<12>")
	)
	(arc
		(start 160.864296 -396.457932)
		(mid 160.767229 -396.676719)
		(end 160.659572 -396.890494)
		(width 0.14224)
		(layer "In15.Cu")
		(net "P5E_CPU1_P2_RX_BUF_DP<12>")
	)
	(arc
		(start 153.757376 -413.606234)
		(mid 153.664632 -414.072399)
		(end 153.400506 -414.467548)
		(width 0.14224)
		(layer "In15.Cu")
		(net "P5E_CPU1_P2_RX_BUF_DP<12>")
	)
	(arc
		(start 156.829252 -403.89302)
		(mid 156.822783 -403.955992)
		(end 156.820616 -404.019258)
		(width 0.14224)
		(layer "In15.Cu")
		(net "P5E_CPU1_P2_RX_BUF_DP<12>")
	)
	(segment
		(start 160.644332 -393.116054)
		(end 160.644332 -393.292838)
		(width 0.1016)
		(layer "F.Cu")
		(net "P5E_CPU1_P2_RX_BUF_DP<11>")
	)
	(segment
		(start 160.03016 -391.488676)
		(end 159.941514 -391.577322)
		(width 0.1016)
		(layer "F.Cu")
		(net "P5E_CPU1_P2_RX_BUF_DP<11>")
	)
	(segment
		(start 160.194752 -392.977116)
		(end 160.505394 -392.977116)
		(width 0.1016)
		(layer "F.Cu")
		(net "P5E_CPU1_P2_RX_BUF_DP<11>")
	)
	(segment
		(start 159.941514 -391.577322)
		(end 159.941514 -392.723878)
		(width 0.1016)
		(layer "F.Cu")
		(net "P5E_CPU1_P2_RX_BUF_DP<11>")
	)
	(segment
		(start 159.941514 -392.723878)
		(end 160.194752 -392.977116)
		(width 0.1016)
		(layer "F.Cu")
		(net "P5E_CPU1_P2_RX_BUF_DP<11>")
	)
	(segment
		(start 160.03016 -391.36574)
		(end 160.03016 -391.488676)
		(width 0.1016)
		(layer "F.Cu")
		(net "P5E_CPU1_P2_RX_BUF_DP<11>")
	)
	(segment
		(start 159.945578 -391.281158)
		(end 160.03016 -391.36574)
		(width 0.1016)
		(layer "F.Cu")
		(net "P5E_CPU1_P2_RX_BUF_DP<11>")
	)
	(segment
		(start 160.505394 -392.977116)
		(end 160.644332 -393.116054)
		(width 0.1016)
		(layer "F.Cu")
		(net "P5E_CPU1_P2_RX_BUF_DP<11>")
	)
	(segment
		(start 148.071078 -419.205664)
		(end 148.071078 -438.203848)
		(width 0.14224)
		(layer "In15.Cu")
		(net "P5E_CPU1_P2_RX_BUF_DP<11>")
	)
	(segment
		(start 157.41777 -399.654522)
		(end 157.000956 -400.114516)
		(width 0.14224)
		(layer "In15.Cu")
		(net "P5E_CPU1_P2_RX_BUF_DP<11>")
	)
	(segment
		(start 160.185354 -395.224)
		(end 159.914844 -396.116302)
		(width 0.14224)
		(layer "In15.Cu")
		(net "P5E_CPU1_P2_RX_BUF_DP<11>")
	)
	(segment
		(start 154.257756 -403.14118)
		(end 153.959306 -403.470364)
		(width 0.14224)
		(layer "In15.Cu")
		(net "P5E_CPU1_P2_RX_BUF_DP<11>")
	)
	(segment
		(start 152.362916 -407.695654)
		(end 152.362916 -408.122374)
		(width 0.14224)
		(layer "In15.Cu")
		(net "P5E_CPU1_P2_RX_BUF_DP<11>")
	)
	(segment
		(start 155.96616 -401.460208)
		(end 155.772612 -401.46986)
		(width 0.14224)
		(layer "In15.Cu")
		(net "P5E_CPU1_P2_RX_BUF_DP<11>")
	)
	(segment
		(start 148.071078 -438.203848)
		(end 148.208492 -438.341262)
		(width 0.14224)
		(layer "In15.Cu")
		(net "P5E_CPU1_P2_RX_BUF_DP<11>")
	)
	(segment
		(start 156.243528 -400.950176)
		(end 156.25318 -401.143724)
		(width 0.14224)
		(layer "In15.Cu")
		(net "P5E_CPU1_P2_RX_BUF_DP<11>")
	)
	(segment
		(start 159.914844 -396.116302)
		(end 158.331662 -398.484852)
		(width 0.14224)
		(layer "In15.Cu")
		(net "P5E_CPU1_P2_RX_BUF_DP<11>")
	)
	(segment
		(start 148.826728 -416.812222)
		(end 148.632672 -416.812222)
		(width 0.14224)
		(layer "In15.Cu")
		(net "P5E_CPU1_P2_RX_BUF_DP<11>")
	)
	(segment
		(start 155.208732 -402.295868)
		(end 155.015184 -402.30552)
		(width 0.14224)
		(layer "In15.Cu")
		(net "P5E_CPU1_P2_RX_BUF_DP<11>")
	)
	(segment
		(start 154.738324 -402.815044)
		(end 154.451558 -403.131528)
		(width 0.14224)
		(layer "In15.Cu")
		(net "P5E_CPU1_P2_RX_BUF_DP<11>")
	)
	(segment
		(start 152.225756 -406.638252)
		(end 152.225756 -407.558494)
		(width 0.14224)
		(layer "In15.Cu")
		(net "P5E_CPU1_P2_RX_BUF_DP<11>")
	)
	(segment
		(start 152.362916 -408.122374)
		(end 152.225756 -408.259534)
		(width 0.14224)
		(layer "In15.Cu")
		(net "P5E_CPU1_P2_RX_BUF_DP<11>")
	)
	(segment
		(start 152.225756 -409.387294)
		(end 152.225756 -410.62148)
		(width 0.14224)
		(layer "In15.Cu")
		(net "P5E_CPU1_P2_RX_BUF_DP<11>")
	)
	(segment
		(start 155.772612 -401.46986)
		(end 155.4861 -401.785836)
		(width 0.14224)
		(layer "In15.Cu")
		(net "P5E_CPU1_P2_RX_BUF_DP<11>")
	)
	(segment
		(start 155.015184 -402.30552)
		(end 154.728672 -402.621496)
		(width 0.14224)
		(layer "In15.Cu")
		(net "P5E_CPU1_P2_RX_BUF_DP<11>")
	)
	(segment
		(start 149.926294 -415.712656)
		(end 149.624288 -416.014662)
		(width 0.14224)
		(layer "In15.Cu")
		(net "P5E_CPU1_P2_RX_BUF_DP<11>")
	)
	(segment
		(start 152.225756 -408.259534)
		(end 152.225756 -408.686254)
		(width 0.14224)
		(layer "In15.Cu")
		(net "P5E_CPU1_P2_RX_BUF_DP<11>")
	)
	(segment
		(start 153.092658 -405.771096)
		(end 152.817068 -405.885142)
		(width 0.14224)
		(layer "In15.Cu")
		(net "P5E_CPU1_P2_RX_BUF_DP<11>")
	)
	(segment
		(start 151.768048 -411.30601)
		(end 150.876508 -411.675834)
		(width 0.14224)
		(layer "In15.Cu")
		(net "P5E_CPU1_P2_RX_BUF_DP<11>")
	)
	(segment
		(start 157.010608 -400.308064)
		(end 156.723588 -400.624548)
		(width 0.14224)
		(layer "In15.Cu")
		(net "P5E_CPU1_P2_RX_BUF_DP<11>")
	)
	(segment
		(start 148.208492 -438.341262)
		(end 148.599906 -438.341262)
		(width 0.14224)
		(layer "In15.Cu")
		(net "P5E_CPU1_P2_RX_BUF_DP<11>")
	)
	(segment
		(start 157.000956 -400.114516)
		(end 157.010608 -400.308064)
		(width 0.14224)
		(layer "In15.Cu")
		(net "P5E_CPU1_P2_RX_BUF_DP<11>")
	)
	(segment
		(start 149.128734 -416.510216)
		(end 148.826728 -416.812222)
		(width 0.14224)
		(layer "In15.Cu")
		(net "P5E_CPU1_P2_RX_BUF_DP<11>")
	)
	(segment
		(start 148.75002 -438.191148)
		(end 148.75002 -437.889904)
		(width 0.14224)
		(layer "In15.Cu")
		(net "P5E_CPU1_P2_RX_BUF_DP<11>")
	)
	(segment
		(start 154.451558 -403.131528)
		(end 154.257756 -403.14118)
		(width 0.14224)
		(layer "In15.Cu")
		(net "P5E_CPU1_P2_RX_BUF_DP<11>")
	)
	(segment
		(start 160.644332 -393.292838)
		(end 160.644332 -393.144756)
		(width 0.14224)
		(layer "In15.Cu")
		(net "P5E_CPU1_P2_RX_BUF_DP<11>")
	)
	(segment
		(start 149.128734 -416.31616)
		(end 149.128734 -416.510216)
		(width 0.14224)
		(layer "In15.Cu")
		(net "P5E_CPU1_P2_RX_BUF_DP<11>")
	)
	(segment
		(start 149.430232 -416.014662)
		(end 149.128734 -416.31616)
		(width 0.14224)
		(layer "In15.Cu")
		(net "P5E_CPU1_P2_RX_BUF_DP<11>")
	)
	(segment
		(start 148.632672 -416.812222)
		(end 148.331174 -417.11372)
		(width 0.14224)
		(layer "In15.Cu")
		(net "P5E_CPU1_P2_RX_BUF_DP<11>")
	)
	(segment
		(start 148.599906 -438.341262)
		(end 148.75002 -438.191148)
		(width 0.14224)
		(layer "In15.Cu")
		(net "P5E_CPU1_P2_RX_BUF_DP<11>")
	)
	(segment
		(start 152.225756 -407.558494)
		(end 152.362916 -407.695654)
		(width 0.14224)
		(layer "In15.Cu")
		(net "P5E_CPU1_P2_RX_BUF_DP<11>")
	)
	(segment
		(start 150.694136 -411.94863)
		(end 150.694136 -414.360614)
		(width 0.14224)
		(layer "In15.Cu")
		(net "P5E_CPU1_P2_RX_BUF_DP<11>")
	)
	(segment
		(start 156.53004 -400.6342)
		(end 156.243528 -400.950176)
		(width 0.14224)
		(layer "In15.Cu")
		(net "P5E_CPU1_P2_RX_BUF_DP<11>")
	)
	(segment
		(start 150.418292 -415.026602)
		(end 149.926294 -415.5186)
		(width 0.14224)
		(layer "In15.Cu")
		(net "P5E_CPU1_P2_RX_BUF_DP<11>")
	)
	(segment
		(start 149.624288 -416.014662)
		(end 149.430232 -416.014662)
		(width 0.14224)
		(layer "In15.Cu")
		(net "P5E_CPU1_P2_RX_BUF_DP<11>")
	)
	(segment
		(start 153.757376 -404.087076)
		(end 153.757376 -404.924514)
		(width 0.14224)
		(layer "In15.Cu")
		(net "P5E_CPU1_P2_RX_BUF_DP<11>")
	)
	(segment
		(start 148.208238 -419.068504)
		(end 148.071078 -419.205664)
		(width 0.14224)
		(layer "In15.Cu")
		(net "P5E_CPU1_P2_RX_BUF_DP<11>")
	)
	(segment
		(start 155.495752 -401.979384)
		(end 155.208732 -402.295868)
		(width 0.14224)
		(layer "In15.Cu")
		(net "P5E_CPU1_P2_RX_BUF_DP<11>")
	)
	(segment
		(start 148.071078 -417.741608)
		(end 148.071078 -418.504624)
		(width 0.14224)
		(layer "In15.Cu")
		(net "P5E_CPU1_P2_RX_BUF_DP<11>")
	)
	(segment
		(start 149.926294 -415.5186)
		(end 149.926294 -415.712656)
		(width 0.14224)
		(layer "In15.Cu")
		(net "P5E_CPU1_P2_RX_BUF_DP<11>")
	)
	(segment
		(start 156.723588 -400.624548)
		(end 156.53004 -400.6342)
		(width 0.14224)
		(layer "In15.Cu")
		(net "P5E_CPU1_P2_RX_BUF_DP<11>")
	)
	(segment
		(start 160.644332 -393.144756)
		(end 160.517332 -393.017756)
		(width 0.14224)
		(layer "In15.Cu")
		(net "P5E_CPU1_P2_RX_BUF_DP<11>")
	)
	(segment
		(start 154.728672 -402.621496)
		(end 154.738324 -402.815044)
		(width 0.14224)
		(layer "In15.Cu")
		(net "P5E_CPU1_P2_RX_BUF_DP<11>")
	)
	(segment
		(start 152.362916 -408.823414)
		(end 152.362916 -409.250134)
		(width 0.14224)
		(layer "In15.Cu")
		(net "P5E_CPU1_P2_RX_BUF_DP<11>")
	)
	(segment
		(start 152.225756 -408.686254)
		(end 152.362916 -408.823414)
		(width 0.14224)
		(layer "In15.Cu")
		(net "P5E_CPU1_P2_RX_BUF_DP<11>")
	)
	(segment
		(start 153.88844 -403.574758)
		(end 153.821638 -403.71141)
		(width 0.14224)
		(layer "In15.Cu")
		(net "P5E_CPU1_P2_RX_BUF_DP<11>")
	)
	(segment
		(start 148.208238 -418.641784)
		(end 148.208238 -419.068504)
		(width 0.14224)
		(layer "In15.Cu")
		(net "P5E_CPU1_P2_RX_BUF_DP<11>")
	)
	(segment
		(start 152.362916 -409.250134)
		(end 152.225756 -409.387294)
		(width 0.14224)
		(layer "In15.Cu")
		(net "P5E_CPU1_P2_RX_BUF_DP<11>")
	)
	(segment
		(start 148.071078 -418.504624)
		(end 148.208238 -418.641784)
		(width 0.14224)
		(layer "In15.Cu")
		(net "P5E_CPU1_P2_RX_BUF_DP<11>")
	)
	(segment
		(start 160.327594 -393.017756)
		(end 160.185354 -393.159996)
		(width 0.14224)
		(layer "In15.Cu")
		(net "P5E_CPU1_P2_RX_BUF_DP<11>")
	)
	(segment
		(start 155.4861 -401.785836)
		(end 155.495752 -401.979384)
		(width 0.14224)
		(layer "In15.Cu")
		(net "P5E_CPU1_P2_RX_BUF_DP<11>")
	)
	(segment
		(start 156.25318 -401.143724)
		(end 155.96616 -401.460208)
		(width 0.14224)
		(layer "In15.Cu")
		(net "P5E_CPU1_P2_RX_BUF_DP<11>")
	)
	(segment
		(start 153.408126 -405.560276)
		(end 153.092658 -405.771096)
		(width 0.14224)
		(layer "In15.Cu")
		(net "P5E_CPU1_P2_RX_BUF_DP<11>")
	)
	(segment
		(start 153.554938 -405.413464)
		(end 153.408126 -405.560276)
		(width 0.14224)
		(layer "In15.Cu")
		(net "P5E_CPU1_P2_RX_BUF_DP<11>")
	)
	(segment
		(start 153.806144 -403.758654)
		(end 153.768806 -403.961092)
		(width 0.14224)
		(layer "In15.Cu")
		(net "P5E_CPU1_P2_RX_BUF_DP<11>")
	)
	(segment
		(start 160.185354 -393.159996)
		(end 160.185354 -395.224)
		(width 0.14224)
		(layer "In15.Cu")
		(net "P5E_CPU1_P2_RX_BUF_DP<11>")
	)
	(segment
		(start 160.517332 -393.017756)
		(end 160.327594 -393.017756)
		(width 0.14224)
		(layer "In15.Cu")
		(net "P5E_CPU1_P2_RX_BUF_DP<11>")
	)
	(arc
		(start 150.694136 -414.360614)
		(mid 150.622443 -414.721038)
		(end 150.418292 -415.026602)
		(width 0.14224)
		(layer "In15.Cu")
		(net "P5E_CPU1_P2_RX_BUF_DP<11>")
	)
	(arc
		(start 153.959306 -403.470364)
		(mid 153.920206 -403.520071)
		(end 153.88844 -403.574758)
		(width 0.14224)
		(layer "In15.Cu")
		(net "P5E_CPU1_P2_RX_BUF_DP<11>")
	)
	(arc
		(start 158.331662 -398.484852)
		(mid 157.89635 -399.08659)
		(end 157.41777 -399.654522)
		(width 0.14224)
		(layer "In15.Cu")
		(net "P5E_CPU1_P2_RX_BUF_DP<11>")
	)
	(arc
		(start 150.876508 -411.675834)
		(mid 150.7439 -411.784548)
		(end 150.694136 -411.94863)
		(width 0.14224)
		(layer "In15.Cu")
		(net "P5E_CPU1_P2_RX_BUF_DP<11>")
	)
	(arc
		(start 152.817068 -405.885142)
		(mid 152.611186 -405.995288)
		(end 152.430734 -406.14346)
		(width 0.14224)
		(layer "In15.Cu")
		(net "P5E_CPU1_P2_RX_BUF_DP<11>")
	)
	(arc
		(start 153.768806 -403.961092)
		(mid 153.760229 -404.023824)
		(end 153.757376 -404.087076)
		(width 0.14224)
		(layer "In15.Cu")
		(net "P5E_CPU1_P2_RX_BUF_DP<11>")
	)
	(arc
		(start 152.430734 -406.14346)
		(mid 152.278971 -406.370445)
		(end 152.225756 -406.638252)
		(width 0.14224)
		(layer "In15.Cu")
		(net "P5E_CPU1_P2_RX_BUF_DP<11>")
	)
	(arc
		(start 153.757376 -404.924514)
		(mid 153.704762 -405.189111)
		(end 153.554938 -405.413464)
		(width 0.14224)
		(layer "In15.Cu")
		(net "P5E_CPU1_P2_RX_BUF_DP<11>")
	)
	(arc
		(start 153.821638 -403.71141)
		(mid 153.812283 -403.734504)
		(end 153.806144 -403.758654)
		(width 0.14224)
		(layer "In15.Cu")
		(net "P5E_CPU1_P2_RX_BUF_DP<11>")
	)
	(arc
		(start 152.225756 -410.62148)
		(mid 152.100729 -411.033175)
		(end 151.768048 -411.30601)
		(width 0.14224)
		(layer "In15.Cu")
		(net "P5E_CPU1_P2_RX_BUF_DP<11>")
	)
	(arc
		(start 148.331174 -417.11372)
		(mid 148.138687 -417.401797)
		(end 148.071078 -417.741608)
		(width 0.14224)
		(layer "In15.Cu")
		(net "P5E_CPU1_P2_RX_BUF_DP<11>")
	)
	(segment
		(start 159.444436 -393.116054)
		(end 159.305498 -392.977116)
		(width 0.1016)
		(layer "F.Cu")
		(net "P5E_CPU1_P2_RX_BUF_DP<10>")
	)
	(segment
		(start 158.741618 -391.577322)
		(end 158.829756 -391.489184)
		(width 0.1016)
		(layer "F.Cu")
		(net "P5E_CPU1_P2_RX_BUF_DP<10>")
	)
	(segment
		(start 159.305498 -392.977116)
		(end 158.994856 -392.977116)
		(width 0.1016)
		(layer "F.Cu")
		(net "P5E_CPU1_P2_RX_BUF_DP<10>")
	)
	(segment
		(start 158.829756 -391.489184)
		(end 158.829756 -391.365232)
		(width 0.1016)
		(layer "F.Cu")
		(net "P5E_CPU1_P2_RX_BUF_DP<10>")
	)
	(segment
		(start 158.829756 -391.365232)
		(end 158.745682 -391.281158)
		(width 0.1016)
		(layer "F.Cu")
		(net "P5E_CPU1_P2_RX_BUF_DP<10>")
	)
	(segment
		(start 158.994856 -392.977116)
		(end 158.741618 -392.723878)
		(width 0.1016)
		(layer "F.Cu")
		(net "P5E_CPU1_P2_RX_BUF_DP<10>")
	)
	(segment
		(start 158.741618 -392.723878)
		(end 158.741618 -391.577322)
		(width 0.1016)
		(layer "F.Cu")
		(net "P5E_CPU1_P2_RX_BUF_DP<10>")
	)
	(segment
		(start 159.444436 -393.292838)
		(end 159.444436 -393.116054)
		(width 0.1016)
		(layer "F.Cu")
		(net "P5E_CPU1_P2_RX_BUF_DP<10>")
	)
	(segment
		(start 153.879296 -401.47494)
		(end 153.843482 -401.665694)
		(width 0.14224)
		(layer "In15.Cu")
		(net "P5E_CPU1_P2_RX_BUF_DP<10>")
	)
	(segment
		(start 152.559766 -402.543264)
		(end 152.369012 -402.50745)
		(width 0.14224)
		(layer "In15.Cu")
		(net "P5E_CPU1_P2_RX_BUF_DP<10>")
	)
	(segment
		(start 150.344886 -405.560276)
		(end 150.029418 -405.771096)
		(width 0.14224)
		(layer "In15.Cu")
		(net "P5E_CPU1_P2_RX_BUF_DP<10>")
	)
	(segment
		(start 155.408884 -400.08175)
		(end 155.107132 -400.383248)
		(width 0.14224)
		(layer "In15.Cu")
		(net "P5E_CPU1_P2_RX_BUF_DP<10>")
	)
	(segment
		(start 152.369012 -402.50745)
		(end 152.016968 -402.748242)
		(width 0.14224)
		(layer "In15.Cu")
		(net "P5E_CPU1_P2_RX_BUF_DP<10>")
	)
	(segment
		(start 153.49093 -401.90674)
		(end 153.300176 -401.870926)
		(width 0.14224)
		(layer "In15.Cu")
		(net "P5E_CPU1_P2_RX_BUF_DP<10>")
	)
	(segment
		(start 150.694136 -404.106888)
		(end 150.694136 -404.924514)
		(width 0.14224)
		(layer "In15.Cu")
		(net "P5E_CPU1_P2_RX_BUF_DP<10>")
	)
	(segment
		(start 157.435042 -397.78178)
		(end 157.468062 -397.972788)
		(width 0.14224)
		(layer "In15.Cu")
		(net "P5E_CPU1_P2_RX_BUF_DP<10>")
	)
	(segment
		(start 146.208242 -419.94455)
		(end 146.208242 -420.37127)
		(width 0.14224)
		(layer "In15.Cu")
		(net "P5E_CPU1_P2_RX_BUF_DP<10>")
	)
	(segment
		(start 155.107132 -400.577304)
		(end 154.805126 -400.87931)
		(width 0.14224)
		(layer "In15.Cu")
		(net "P5E_CPU1_P2_RX_BUF_DP<10>")
	)
	(segment
		(start 149.162516 -407.586434)
		(end 149.299676 -407.723594)
		(width 0.14224)
		(layer "In15.Cu")
		(net "P5E_CPU1_P2_RX_BUF_DP<10>")
	)
	(segment
		(start 155.602686 -400.08175)
		(end 155.408884 -400.08175)
		(width 0.14224)
		(layer "In15.Cu")
		(net "P5E_CPU1_P2_RX_BUF_DP<10>")
	)
	(segment
		(start 159.444436 -393.292838)
		(end 159.444436 -393.144756)
		(width 0.14224)
		(layer "In15.Cu")
		(net "P5E_CPU1_P2_RX_BUF_DP<10>")
	)
	(segment
		(start 146.071082 -417.113466)
		(end 146.071082 -418.67963)
		(width 0.14224)
		(layer "In15.Cu")
		(net "P5E_CPU1_P2_RX_BUF_DP<10>")
	)
	(segment
		(start 159.444436 -393.144756)
		(end 159.317436 -393.017756)
		(width 0.14224)
		(layer "In15.Cu")
		(net "P5E_CPU1_P2_RX_BUF_DP<10>")
	)
	(segment
		(start 150.792434 -403.821138)
		(end 150.720298 -403.983952)
		(width 0.14224)
		(layer "In15.Cu")
		(net "P5E_CPU1_P2_RX_BUF_DP<10>")
	)
	(segment
		(start 146.208242 -420.37127)
		(end 146.071082 -420.50843)
		(width 0.14224)
		(layer "In15.Cu")
		(net "P5E_CPU1_P2_RX_BUF_DP<10>")
	)
	(segment
		(start 157.468062 -397.972788)
		(end 157.22219 -398.322038)
		(width 0.14224)
		(layer "In15.Cu")
		(net "P5E_CPU1_P2_RX_BUF_DP<10>")
	)
	(segment
		(start 149.299676 -408.150314)
		(end 149.162516 -408.287474)
		(width 0.14224)
		(layer "In15.Cu")
		(net "P5E_CPU1_P2_RX_BUF_DP<10>")
	)
	(segment
		(start 149.299676 -408.851354)
		(end 149.299676 -409.278074)
		(width 0.14224)
		(layer "In15.Cu")
		(net "P5E_CPU1_P2_RX_BUF_DP<10>")
	)
	(segment
		(start 159.127698 -393.017756)
		(end 158.985458 -393.159996)
		(width 0.14224)
		(layer "In15.Cu")
		(net "P5E_CPU1_P2_RX_BUF_DP<10>")
	)
	(segment
		(start 146.071082 -418.67963)
		(end 146.208242 -418.81679)
		(width 0.14224)
		(layer "In15.Cu")
		(net "P5E_CPU1_P2_RX_BUF_DP<10>")
	)
	(segment
		(start 149.162516 -408.714194)
		(end 149.299676 -408.851354)
		(width 0.14224)
		(layer "In15.Cu")
		(net "P5E_CPU1_P2_RX_BUF_DP<10>")
	)
	(segment
		(start 152.948132 -402.111718)
		(end 152.912318 -402.302218)
		(width 0.14224)
		(layer "In15.Cu")
		(net "P5E_CPU1_P2_RX_BUF_DP<10>")
	)
	(segment
		(start 146.071082 -437.199024)
		(end 146.213322 -437.341264)
		(width 0.14224)
		(layer "In15.Cu")
		(net "P5E_CPU1_P2_RX_BUF_DP<10>")
	)
	(segment
		(start 155.107132 -400.383248)
		(end 155.107132 -400.577304)
		(width 0.14224)
		(layer "In15.Cu")
		(net "P5E_CPU1_P2_RX_BUF_DP<10>")
	)
	(segment
		(start 159.317436 -393.017756)
		(end 159.127698 -393.017756)
		(width 0.14224)
		(layer "In15.Cu")
		(net "P5E_CPU1_P2_RX_BUF_DP<10>")
	)
	(segment
		(start 152.912318 -402.302218)
		(end 152.559766 -402.543264)
		(width 0.14224)
		(layer "In15.Cu")
		(net "P5E_CPU1_P2_RX_BUF_DP<10>")
	)
	(segment
		(start 156.782516 -398.708118)
		(end 155.904692 -399.585688)
		(width 0.14224)
		(layer "In15.Cu")
		(net "P5E_CPU1_P2_RX_BUF_DP<10>")
	)
	(segment
		(start 154.805126 -400.87931)
		(end 154.611324 -400.87931)
		(width 0.14224)
		(layer "In15.Cu")
		(net "P5E_CPU1_P2_RX_BUF_DP<10>")
	)
	(segment
		(start 146.750024 -437.19115)
		(end 146.750024 -436.889906)
		(width 0.14224)
		(layer "In15.Cu")
		(net "P5E_CPU1_P2_RX_BUF_DP<10>")
	)
	(segment
		(start 157.030928 -398.355312)
		(end 156.782516 -398.708118)
		(width 0.14224)
		(layer "In15.Cu")
		(net "P5E_CPU1_P2_RX_BUF_DP<10>")
	)
	(segment
		(start 153.843482 -401.665694)
		(end 153.49093 -401.90674)
		(width 0.14224)
		(layer "In15.Cu")
		(net "P5E_CPU1_P2_RX_BUF_DP<10>")
	)
	(segment
		(start 158.985458 -393.159996)
		(end 158.985458 -395.580108)
		(width 0.14224)
		(layer "In15.Cu")
		(net "P5E_CPU1_P2_RX_BUF_DP<10>")
	)
	(segment
		(start 155.904692 -399.779744)
		(end 155.602686 -400.08175)
		(width 0.14224)
		(layer "In15.Cu")
		(net "P5E_CPU1_P2_RX_BUF_DP<10>")
	)
	(segment
		(start 146.071082 -420.50843)
		(end 146.071082 -437.199024)
		(width 0.14224)
		(layer "In15.Cu")
		(net "P5E_CPU1_P2_RX_BUF_DP<10>")
	)
	(segment
		(start 149.299676 -407.723594)
		(end 149.299676 -408.150314)
		(width 0.14224)
		(layer "In15.Cu")
		(net "P5E_CPU1_P2_RX_BUF_DP<10>")
	)
	(segment
		(start 146.213322 -437.341264)
		(end 146.59991 -437.341264)
		(width 0.14224)
		(layer "In15.Cu")
		(net "P5E_CPU1_P2_RX_BUF_DP<10>")
	)
	(segment
		(start 157.22219 -398.322038)
		(end 157.030928 -398.355312)
		(width 0.14224)
		(layer "In15.Cu")
		(net "P5E_CPU1_P2_RX_BUF_DP<10>")
	)
	(segment
		(start 148.671534 -411.31998)
		(end 147.820126 -411.67304)
		(width 0.14224)
		(layer "In15.Cu")
		(net "P5E_CPU1_P2_RX_BUF_DP<10>")
	)
	(segment
		(start 149.162516 -409.415234)
		(end 149.162516 -410.69768)
		(width 0.14224)
		(layer "In15.Cu")
		(net "P5E_CPU1_P2_RX_BUF_DP<10>")
	)
	(segment
		(start 150.491698 -405.413464)
		(end 150.344886 -405.560276)
		(width 0.14224)
		(layer "In15.Cu")
		(net "P5E_CPU1_P2_RX_BUF_DP<10>")
	)
	(segment
		(start 158.985458 -395.580108)
		(end 157.435042 -397.78178)
		(width 0.14224)
		(layer "In15.Cu")
		(net "P5E_CPU1_P2_RX_BUF_DP<10>")
	)
	(segment
		(start 150.029418 -405.771096)
		(end 149.753828 -405.885142)
		(width 0.14224)
		(layer "In15.Cu")
		(net "P5E_CPU1_P2_RX_BUF_DP<10>")
	)
	(segment
		(start 154.309572 -401.180808)
		(end 153.879296 -401.47494)
		(width 0.14224)
		(layer "In15.Cu")
		(net "P5E_CPU1_P2_RX_BUF_DP<10>")
	)
	(segment
		(start 151.915622 -402.824188)
		(end 151.616664 -403.069552)
		(width 0.14224)
		(layer "In15.Cu")
		(net "P5E_CPU1_P2_RX_BUF_DP<10>")
	)
	(segment
		(start 146.071082 -419.38067)
		(end 146.071082 -419.80739)
		(width 0.14224)
		(layer "In15.Cu")
		(net "P5E_CPU1_P2_RX_BUF_DP<10>")
	)
	(segment
		(start 154.611324 -400.87931)
		(end 154.309572 -401.180808)
		(width 0.14224)
		(layer "In15.Cu")
		(net "P5E_CPU1_P2_RX_BUF_DP<10>")
	)
	(segment
		(start 146.59991 -437.341264)
		(end 146.750024 -437.19115)
		(width 0.14224)
		(layer "In15.Cu")
		(net "P5E_CPU1_P2_RX_BUF_DP<10>")
	)
	(segment
		(start 149.162516 -406.638252)
		(end 149.162516 -407.586434)
		(width 0.14224)
		(layer "In15.Cu")
		(net "P5E_CPU1_P2_RX_BUF_DP<10>")
	)
	(segment
		(start 149.162516 -408.287474)
		(end 149.162516 -408.714194)
		(width 0.14224)
		(layer "In15.Cu")
		(net "P5E_CPU1_P2_RX_BUF_DP<10>")
	)
	(segment
		(start 149.299676 -409.278074)
		(end 149.162516 -409.415234)
		(width 0.14224)
		(layer "In15.Cu")
		(net "P5E_CPU1_P2_RX_BUF_DP<10>")
	)
	(segment
		(start 147.630896 -411.955996)
		(end 147.630896 -414.60674)
		(width 0.14224)
		(layer "In15.Cu")
		(net "P5E_CPU1_P2_RX_BUF_DP<10>")
	)
	(segment
		(start 147.288758 -415.433002)
		(end 146.398234 -416.323526)
		(width 0.14224)
		(layer "In15.Cu")
		(net "P5E_CPU1_P2_RX_BUF_DP<10>")
	)
	(segment
		(start 146.208242 -419.24351)
		(end 146.071082 -419.38067)
		(width 0.14224)
		(layer "In15.Cu")
		(net "P5E_CPU1_P2_RX_BUF_DP<10>")
	)
	(segment
		(start 153.300176 -401.870926)
		(end 152.948132 -402.111718)
		(width 0.14224)
		(layer "In15.Cu")
		(net "P5E_CPU1_P2_RX_BUF_DP<10>")
	)
	(segment
		(start 155.904692 -399.585688)
		(end 155.904692 -399.779744)
		(width 0.14224)
		(layer "In15.Cu")
		(net "P5E_CPU1_P2_RX_BUF_DP<10>")
	)
	(segment
		(start 146.208242 -418.81679)
		(end 146.208242 -419.24351)
		(width 0.14224)
		(layer "In15.Cu")
		(net "P5E_CPU1_P2_RX_BUF_DP<10>")
	)
	(segment
		(start 146.071082 -419.80739)
		(end 146.208242 -419.94455)
		(width 0.14224)
		(layer "In15.Cu")
		(net "P5E_CPU1_P2_RX_BUF_DP<10>")
	)
	(arc
		(start 150.720298 -403.983952)
		(mid 150.700753 -404.044046)
		(end 150.694136 -404.106888)
		(width 0.14224)
		(layer "In15.Cu")
		(net "P5E_CPU1_P2_RX_BUF_DP<10>")
	)
	(arc
		(start 152.016968 -402.748242)
		(mid 151.965464 -402.785106)
		(end 151.915622 -402.824188)
		(width 0.14224)
		(layer "In15.Cu")
		(net "P5E_CPU1_P2_RX_BUF_DP<10>")
	)
	(arc
		(start 149.753828 -405.885142)
		(mid 149.547946 -405.995288)
		(end 149.367494 -406.14346)
		(width 0.14224)
		(layer "In15.Cu")
		(net "P5E_CPU1_P2_RX_BUF_DP<10>")
	)
	(arc
		(start 151.300942 -403.33422)
		(mid 151.082274 -403.52455)
		(end 150.866602 -403.718268)
		(width 0.14224)
		(layer "In15.Cu")
		(net "P5E_CPU1_P2_RX_BUF_DP<10>")
	)
	(arc
		(start 147.630896 -414.60674)
		(mid 147.541972 -415.053882)
		(end 147.288758 -415.433002)
		(width 0.14224)
		(layer "In15.Cu")
		(net "P5E_CPU1_P2_RX_BUF_DP<10>")
	)
	(arc
		(start 151.616664 -403.069552)
		(mid 151.458102 -403.201049)
		(end 151.300942 -403.33422)
		(width 0.14224)
		(layer "In15.Cu")
		(net "P5E_CPU1_P2_RX_BUF_DP<10>")
	)
	(arc
		(start 149.367494 -406.14346)
		(mid 149.215731 -406.370445)
		(end 149.162516 -406.638252)
		(width 0.14224)
		(layer "In15.Cu")
		(net "P5E_CPU1_P2_RX_BUF_DP<10>")
	)
	(arc
		(start 147.820126 -411.67304)
		(mid 147.682532 -411.785801)
		(end 147.630896 -411.955996)
		(width 0.14224)
		(layer "In15.Cu")
		(net "P5E_CPU1_P2_RX_BUF_DP<10>")
	)
	(arc
		(start 149.001988 -411.090618)
		(mid 148.849034 -411.22298)
		(end 148.671534 -411.31998)
		(width 0.14224)
		(layer "In15.Cu")
		(net "P5E_CPU1_P2_RX_BUF_DP<10>")
	)
	(arc
		(start 146.398234 -416.323526)
		(mid 146.156121 -416.685968)
		(end 146.071082 -417.113466)
		(width 0.14224)
		(layer "In15.Cu")
		(net "P5E_CPU1_P2_RX_BUF_DP<10>")
	)
	(arc
		(start 149.162516 -410.69768)
		(mid 149.120778 -410.909882)
		(end 149.001988 -411.090618)
		(width 0.14224)
		(layer "In15.Cu")
		(net "P5E_CPU1_P2_RX_BUF_DP<10>")
	)
	(arc
		(start 150.694136 -404.924514)
		(mid 150.641522 -405.189111)
		(end 150.491698 -405.413464)
		(width 0.14224)
		(layer "In15.Cu")
		(net "P5E_CPU1_P2_RX_BUF_DP<10>")
	)
	(arc
		(start 150.866602 -403.718268)
		(mid 150.824192 -403.76586)
		(end 150.792434 -403.821138)
		(width 0.14224)
		(layer "In15.Cu")
		(net "P5E_CPU1_P2_RX_BUF_DP<10>")
	)
	(segment
		(start 146.745706 -391.281158)
		(end 146.830288 -391.36574)
		(width 0.1016)
		(layer "F.Cu")
		(net "P5E_CPU1_P2_RX_BUF_DP<0>")
	)
	(segment
		(start 147.305522 -392.977116)
		(end 147.444206 -393.1158)
		(width 0.1016)
		(layer "F.Cu")
		(net "P5E_CPU1_P2_RX_BUF_DP<0>")
	)
	(segment
		(start 146.830288 -391.488676)
		(end 146.71929 -391.599674)
		(width 0.1016)
		(layer "F.Cu")
		(net "P5E_CPU1_P2_RX_BUF_DP<0>")
	)
	(segment
		(start 147.444206 -393.1158)
		(end 147.444206 -393.292838)
		(width 0.1016)
		(layer "F.Cu")
		(net "P5E_CPU1_P2_RX_BUF_DP<0>")
	)
	(segment
		(start 146.71929 -391.599674)
		(end 146.71929 -392.701526)
		(width 0.1016)
		(layer "F.Cu")
		(net "P5E_CPU1_P2_RX_BUF_DP<0>")
	)
	(segment
		(start 146.71929 -392.701526)
		(end 146.99488 -392.977116)
		(width 0.1016)
		(layer "F.Cu")
		(net "P5E_CPU1_P2_RX_BUF_DP<0>")
	)
	(segment
		(start 146.99488 -392.977116)
		(end 147.305522 -392.977116)
		(width 0.1016)
		(layer "F.Cu")
		(net "P5E_CPU1_P2_RX_BUF_DP<0>")
	)
	(segment
		(start 146.830288 -391.36574)
		(end 146.830288 -391.488676)
		(width 0.1016)
		(layer "F.Cu")
		(net "P5E_CPU1_P2_RX_BUF_DP<0>")
	)
	(segment
		(start 118.530116 -408.080464)
		(end 118.667276 -407.943304)
		(width 0.14224)
		(layer "In15.Cu")
		(net "P5E_CPU1_P2_RX_BUF_DP<0>")
	)
	(segment
		(start 130.128518 -398.974818)
		(end 139.078208 -395.737842)
		(width 0.14224)
		(layer "In15.Cu")
		(net "P5E_CPU1_P2_RX_BUF_DP<0>")
	)
	(segment
		(start 119.121428 -405.885142)
		(end 119.397018 -405.771096)
		(width 0.14224)
		(layer "In15.Cu")
		(net "P5E_CPU1_P2_RX_BUF_DP<0>")
	)
	(segment
		(start 126.926848 -400.357848)
		(end 127.108204 -400.426174)
		(width 0.14224)
		(layer "In15.Cu")
		(net "P5E_CPU1_P2_RX_BUF_DP<0>")
	)
	(segment
		(start 118.530116 -410.721302)
		(end 118.530116 -409.208224)
		(width 0.14224)
		(layer "In15.Cu")
		(net "P5E_CPU1_P2_RX_BUF_DP<0>")
	)
	(segment
		(start 119.397018 -405.771096)
		(end 119.712486 -405.560276)
		(width 0.14224)
		(layer "In15.Cu")
		(net "P5E_CPU1_P2_RX_BUF_DP<0>")
	)
	(segment
		(start 119.42953 -416.37077)
		(end 119.128032 -416.069272)
		(width 0.14224)
		(layer "In15.Cu")
		(net "P5E_CPU1_P2_RX_BUF_DP<0>")
	)
	(segment
		(start 127.497332 -400.250406)
		(end 127.565912 -400.068796)
		(width 0.14224)
		(layer "In15.Cu")
		(net "P5E_CPU1_P2_RX_BUF_DP<0>")
	)
	(segment
		(start 122.813064 -419.754304)
		(end 122.813064 -419.560248)
		(width 0.14224)
		(layer "In15.Cu")
		(net "P5E_CPU1_P2_RX_BUF_DP<0>")
	)
	(segment
		(start 118.63197 -415.57321)
		(end 117.17909 -414.12033)
		(width 0.14224)
		(layer "In15.Cu")
		(net "P5E_CPU1_P2_RX_BUF_DP<0>")
	)
	(segment
		(start 122.015504 -418.956744)
		(end 122.015504 -418.762688)
		(width 0.14224)
		(layer "In15.Cu")
		(net "P5E_CPU1_P2_RX_BUF_DP<0>")
	)
	(segment
		(start 118.667276 -408.644344)
		(end 118.530116 -408.507184)
		(width 0.14224)
		(layer "In15.Cu")
		(net "P5E_CPU1_P2_RX_BUF_DP<0>")
	)
	(segment
		(start 121.713498 -418.460682)
		(end 121.519442 -418.460682)
		(width 0.14224)
		(layer "In15.Cu")
		(net "P5E_CPU1_P2_RX_BUF_DP<0>")
	)
	(segment
		(start 146.83613 -393.002008)
		(end 147.153376 -393.002008)
		(width 0.14224)
		(layer "In15.Cu")
		(net "P5E_CPU1_P2_RX_BUF_DP<0>")
	)
	(segment
		(start 127.108204 -400.426174)
		(end 127.497332 -400.250406)
		(width 0.14224)
		(layer "In15.Cu")
		(net "P5E_CPU1_P2_RX_BUF_DP<0>")
	)
	(segment
		(start 119.623332 -416.37077)
		(end 119.42953 -416.37077)
		(width 0.14224)
		(layer "In15.Cu")
		(net "P5E_CPU1_P2_RX_BUF_DP<0>")
	)
	(segment
		(start 116.998496 -413.684212)
		(end 116.998496 -411.829504)
		(width 0.14224)
		(layer "In15.Cu")
		(net "P5E_CPU1_P2_RX_BUF_DP<0>")
	)
	(segment
		(start 120.722898 -417.664138)
		(end 120.722898 -417.470082)
		(width 0.14224)
		(layer "In15.Cu")
		(net "P5E_CPU1_P2_RX_BUF_DP<0>")
	)
	(segment
		(start 144.472406 -394.01877)
		(end 145.720054 -393.434824)
		(width 0.14224)
		(layer "In15.Cu")
		(net "P5E_CPU1_P2_RX_BUF_DP<0>")
	)
	(segment
		(start 118.530116 -407.379424)
		(end 118.530116 -406.638252)
		(width 0.14224)
		(layer "In15.Cu")
		(net "P5E_CPU1_P2_RX_BUF_DP<0>")
	)
	(segment
		(start 119.712486 -405.560276)
		(end 119.859298 -405.413464)
		(width 0.14224)
		(layer "In15.Cu")
		(net "P5E_CPU1_P2_RX_BUF_DP<0>")
	)
	(segment
		(start 119.128032 -415.875216)
		(end 118.826026 -415.57321)
		(width 0.14224)
		(layer "In15.Cu")
		(net "P5E_CPU1_P2_RX_BUF_DP<0>")
	)
	(segment
		(start 124.23775 -421.17899)
		(end 123.61037 -420.55161)
		(width 0.14224)
		(layer "In15.Cu")
		(net "P5E_CPU1_P2_RX_BUF_DP<0>")
	)
	(segment
		(start 121.519442 -418.460682)
		(end 120.722898 -417.664138)
		(width 0.14224)
		(layer "In15.Cu")
		(net "P5E_CPU1_P2_RX_BUF_DP<0>")
	)
	(segment
		(start 120.061736 -404.924514)
		(end 120.061736 -404.06193)
		(width 0.14224)
		(layer "In15.Cu")
		(net "P5E_CPU1_P2_RX_BUF_DP<0>")
	)
	(segment
		(start 120.086374 -403.93874)
		(end 120.211596 -403.637242)
		(width 0.14224)
		(layer "In15.Cu")
		(net "P5E_CPU1_P2_RX_BUF_DP<0>")
	)
	(segment
		(start 118.667276 -407.516584)
		(end 118.530116 -407.379424)
		(width 0.14224)
		(layer "In15.Cu")
		(net "P5E_CPU1_P2_RX_BUF_DP<0>")
	)
	(segment
		(start 120.420892 -417.168076)
		(end 120.226836 -417.168076)
		(width 0.14224)
		(layer "In15.Cu")
		(net "P5E_CPU1_P2_RX_BUF_DP<0>")
	)
	(segment
		(start 123.114562 -420.055802)
		(end 122.813064 -419.754304)
		(width 0.14224)
		(layer "In15.Cu")
		(net "P5E_CPU1_P2_RX_BUF_DP<0>")
	)
	(segment
		(start 118.667276 -409.071064)
		(end 118.667276 -408.644344)
		(width 0.14224)
		(layer "In15.Cu")
		(net "P5E_CPU1_P2_RX_BUF_DP<0>")
	)
	(segment
		(start 122.813064 -419.560248)
		(end 122.511058 -419.258242)
		(width 0.14224)
		(layer "In15.Cu")
		(net "P5E_CPU1_P2_RX_BUF_DP<0>")
	)
	(segment
		(start 119.925338 -416.672776)
		(end 119.623332 -416.37077)
		(width 0.14224)
		(layer "In15.Cu")
		(net "P5E_CPU1_P2_RX_BUF_DP<0>")
	)
	(segment
		(start 120.722898 -417.470082)
		(end 120.420892 -417.168076)
		(width 0.14224)
		(layer "In15.Cu")
		(net "P5E_CPU1_P2_RX_BUF_DP<0>")
	)
	(segment
		(start 123.308364 -420.055802)
		(end 123.114562 -420.055802)
		(width 0.14224)
		(layer "In15.Cu")
		(net "P5E_CPU1_P2_RX_BUF_DP<0>")
	)
	(segment
		(start 124.590048 -436.849266)
		(end 124.590048 -422.029636)
		(width 0.14224)
		(layer "In15.Cu")
		(net "P5E_CPU1_P2_RX_BUF_DP<0>")
	)
	(segment
		(start 118.667276 -407.943304)
		(end 118.667276 -407.516584)
		(width 0.14224)
		(layer "In15.Cu")
		(net "P5E_CPU1_P2_RX_BUF_DP<0>")
	)
	(segment
		(start 125.603762 -437.3372)
		(end 125.077982 -437.3372)
		(width 0.14224)
		(layer "In15.Cu")
		(net "P5E_CPU1_P2_RX_BUF_DP<0>")
	)
	(segment
		(start 123.61037 -420.55161)
		(end 123.61037 -420.357808)
		(width 0.14224)
		(layer "In15.Cu")
		(net "P5E_CPU1_P2_RX_BUF_DP<0>")
	)
	(segment
		(start 127.565912 -400.068796)
		(end 128.722374 -399.546064)
		(width 0.14224)
		(layer "In15.Cu")
		(net "P5E_CPU1_P2_RX_BUF_DP<0>")
	)
	(segment
		(start 122.511058 -419.258242)
		(end 122.317002 -419.258242)
		(width 0.14224)
		(layer "In15.Cu")
		(net "P5E_CPU1_P2_RX_BUF_DP<0>")
	)
	(segment
		(start 147.153376 -393.002008)
		(end 147.444206 -393.292838)
		(width 0.14224)
		(layer "In15.Cu")
		(net "P5E_CPU1_P2_RX_BUF_DP<0>")
	)
	(segment
		(start 139.200636 -395.7066)
		(end 139.91463 -395.598142)
		(width 0.14224)
		(layer "In15.Cu")
		(net "P5E_CPU1_P2_RX_BUF_DP<0>")
	)
	(segment
		(start 118.826026 -415.57321)
		(end 118.63197 -415.57321)
		(width 0.14224)
		(layer "In15.Cu")
		(net "P5E_CPU1_P2_RX_BUF_DP<0>")
	)
	(segment
		(start 123.61037 -420.357808)
		(end 123.308364 -420.055802)
		(width 0.14224)
		(layer "In15.Cu")
		(net "P5E_CPU1_P2_RX_BUF_DP<0>")
	)
	(segment
		(start 117.076728 -411.712664)
		(end 118.170706 -411.259274)
		(width 0.14224)
		(layer "In15.Cu")
		(net "P5E_CPU1_P2_RX_BUF_DP<0>")
	)
	(segment
		(start 118.530116 -409.208224)
		(end 118.667276 -409.071064)
		(width 0.14224)
		(layer "In15.Cu")
		(net "P5E_CPU1_P2_RX_BUF_DP<0>")
	)
	(segment
		(start 125.749812 -436.889906)
		(end 125.749812 -437.19115)
		(width 0.14224)
		(layer "In15.Cu")
		(net "P5E_CPU1_P2_RX_BUF_DP<0>")
	)
	(segment
		(start 120.226836 -417.168076)
		(end 119.925338 -416.866578)
		(width 0.14224)
		(layer "In15.Cu")
		(net "P5E_CPU1_P2_RX_BUF_DP<0>")
	)
	(segment
		(start 118.530116 -408.507184)
		(end 118.530116 -408.080464)
		(width 0.14224)
		(layer "In15.Cu")
		(net "P5E_CPU1_P2_RX_BUF_DP<0>")
	)
	(segment
		(start 119.128032 -416.069272)
		(end 119.128032 -415.875216)
		(width 0.14224)
		(layer "In15.Cu")
		(net "P5E_CPU1_P2_RX_BUF_DP<0>")
	)
	(segment
		(start 145.98777 -393.308332)
		(end 146.83613 -393.002008)
		(width 0.14224)
		(layer "In15.Cu")
		(net "P5E_CPU1_P2_RX_BUF_DP<0>")
	)
	(segment
		(start 140.6144 -395.419834)
		(end 144.355312 -394.067284)
		(width 0.14224)
		(layer "In15.Cu")
		(net "P5E_CPU1_P2_RX_BUF_DP<0>")
	)
	(segment
		(start 122.015504 -418.762688)
		(end 121.713498 -418.460682)
		(width 0.14224)
		(layer "In15.Cu")
		(net "P5E_CPU1_P2_RX_BUF_DP<0>")
	)
	(segment
		(start 125.749812 -437.19115)
		(end 125.603762 -437.3372)
		(width 0.14224)
		(layer "In15.Cu")
		(net "P5E_CPU1_P2_RX_BUF_DP<0>")
	)
	(segment
		(start 119.925338 -416.866578)
		(end 119.925338 -416.672776)
		(width 0.14224)
		(layer "In15.Cu")
		(net "P5E_CPU1_P2_RX_BUF_DP<0>")
	)
	(segment
		(start 122.317002 -419.258242)
		(end 122.015504 -418.956744)
		(width 0.14224)
		(layer "In15.Cu")
		(net "P5E_CPU1_P2_RX_BUF_DP<0>")
	)
	(segment
		(start 120.28551 -403.535896)
		(end 120.679972 -403.201124)
		(width 0.14224)
		(layer "In15.Cu")
		(net "P5E_CPU1_P2_RX_BUF_DP<0>")
	)
	(segment
		(start 125.077982 -437.3372)
		(end 124.590048 -436.849266)
		(width 0.14224)
		(layer "In15.Cu")
		(net "P5E_CPU1_P2_RX_BUF_DP<0>")
	)
	(segment
		(start 120.7897 -403.131782)
		(end 126.926848 -400.357848)
		(width 0.14224)
		(layer "In15.Cu")
		(net "P5E_CPU1_P2_RX_BUF_DP<0>")
	)
	(arc
		(start 139.91463 -395.598142)
		(mid 140.268919 -395.526272)
		(end 140.6144 -395.419834)
		(width 0.14224)
		(layer "In15.Cu")
		(net "P5E_CPU1_P2_RX_BUF_DP<0>")
	)
	(arc
		(start 120.061736 -404.06193)
		(mid 120.06798 -403.99912)
		(end 120.086374 -403.93874)
		(width 0.14224)
		(layer "In15.Cu")
		(net "P5E_CPU1_P2_RX_BUF_DP<0>")
	)
	(arc
		(start 116.998496 -411.829504)
		(mid 117.019849 -411.759176)
		(end 117.076728 -411.712664)
		(width 0.14224)
		(layer "In15.Cu")
		(net "P5E_CPU1_P2_RX_BUF_DP<0>")
	)
	(arc
		(start 118.530116 -406.638252)
		(mid 118.583345 -406.370451)
		(end 118.735094 -406.14346)
		(width 0.14224)
		(layer "In15.Cu")
		(net "P5E_CPU1_P2_RX_BUF_DP<0>")
	)
	(arc
		(start 145.833084 -393.377674)
		(mid 145.909148 -393.340151)
		(end 145.98777 -393.308332)
		(width 0.14224)
		(layer "In15.Cu")
		(net "P5E_CPU1_P2_RX_BUF_DP<0>")
	)
	(arc
		(start 124.590048 -422.029636)
		(mid 124.498494 -421.569275)
		(end 124.23775 -421.17899)
		(width 0.14224)
		(layer "In15.Cu")
		(net "P5E_CPU1_P2_RX_BUF_DP<0>")
	)
	(arc
		(start 144.355312 -394.067284)
		(mid 144.414413 -394.044364)
		(end 144.472406 -394.01877)
		(width 0.14224)
		(layer "In15.Cu")
		(net "P5E_CPU1_P2_RX_BUF_DP<0>")
	)
	(arc
		(start 119.859298 -405.413464)
		(mid 120.009138 -405.189118)
		(end 120.061736 -404.924514)
		(width 0.14224)
		(layer "In15.Cu")
		(net "P5E_CPU1_P2_RX_BUF_DP<0>")
	)
	(arc
		(start 120.679972 -403.201124)
		(mid 120.732414 -403.162618)
		(end 120.7897 -403.131782)
		(width 0.14224)
		(layer "In15.Cu")
		(net "P5E_CPU1_P2_RX_BUF_DP<0>")
	)
	(arc
		(start 139.078208 -395.737842)
		(mid 139.138657 -395.719226)
		(end 139.200636 -395.7066)
		(width 0.14224)
		(layer "In15.Cu")
		(net "P5E_CPU1_P2_RX_BUF_DP<0>")
	)
	(arc
		(start 118.170706 -411.259274)
		(mid 118.431958 -411.044778)
		(end 118.530116 -410.721302)
		(width 0.14224)
		(layer "In15.Cu")
		(net "P5E_CPU1_P2_RX_BUF_DP<0>")
	)
	(arc
		(start 145.720054 -393.434824)
		(mid 145.77699 -393.407081)
		(end 145.833084 -393.377674)
		(width 0.14224)
		(layer "In15.Cu")
		(net "P5E_CPU1_P2_RX_BUF_DP<0>")
	)
	(arc
		(start 117.17909 -414.12033)
		(mid 117.045446 -413.920223)
		(end 116.998496 -413.684212)
		(width 0.14224)
		(layer "In15.Cu")
		(net "P5E_CPU1_P2_RX_BUF_DP<0>")
	)
	(arc
		(start 128.722374 -399.546064)
		(mid 129.419914 -399.246823)
		(end 130.128518 -398.974818)
		(width 0.14224)
		(layer "In15.Cu")
		(net "P5E_CPU1_P2_RX_BUF_DP<0>")
	)
	(arc
		(start 118.735094 -406.14346)
		(mid 118.915564 -405.995314)
		(end 119.121428 -405.885142)
		(width 0.14224)
		(layer "In15.Cu")
		(net "P5E_CPU1_P2_RX_BUF_DP<0>")
	)
	(arc
		(start 120.211596 -403.637242)
		(mid 120.242513 -403.582162)
		(end 120.28551 -403.535896)
		(width 0.14224)
		(layer "In15.Cu")
		(net "P5E_CPU1_P2_RX_BUF_DP<0>")
	)
	(segment
		(start 157.84576 -390.761474)
		(end 157.846268 -390.761982)
		(width 0.1016)
		(layer "F.Cu")
		(net "P5E_CPU1_P2_RX_BUF_DN<9>")
	)
	(segment
		(start 157.902148 -392.761216)
		(end 158.10357 -392.761216)
		(width 0.1016)
		(layer "F.Cu")
		(net "P5E_CPU1_P2_RX_BUF_DN<9>")
	)
	(segment
		(start 157.775148 -392.634216)
		(end 157.902148 -392.761216)
		(width 0.1016)
		(layer "F.Cu")
		(net "P5E_CPU1_P2_RX_BUF_DN<9>")
	)
	(segment
		(start 157.846268 -390.761982)
		(end 157.846268 -391.578338)
		(width 0.1016)
		(layer "F.Cu")
		(net "P5E_CPU1_P2_RX_BUF_DN<9>")
	)
	(segment
		(start 157.846268 -391.578338)
		(end 157.775148 -391.649458)
		(width 0.1016)
		(layer "F.Cu")
		(net "P5E_CPU1_P2_RX_BUF_DN<9>")
	)
	(segment
		(start 158.244286 -392.6205)
		(end 158.244286 -392.429238)
		(width 0.1016)
		(layer "F.Cu")
		(net "P5E_CPU1_P2_RX_BUF_DN<9>")
	)
	(segment
		(start 158.10357 -392.761216)
		(end 158.244286 -392.6205)
		(width 0.1016)
		(layer "F.Cu")
		(net "P5E_CPU1_P2_RX_BUF_DN<9>")
	)
	(segment
		(start 157.775148 -391.649458)
		(end 157.775148 -392.634216)
		(width 0.1016)
		(layer "F.Cu")
		(net "P5E_CPU1_P2_RX_BUF_DN<9>")
	)
	(segment
		(start 144.285716 -411.845506)
		(end 144.285716 -413.863282)
		(width 0.14224)
		(layer "In15.Cu")
		(net "P5E_CPU1_P2_RX_BUF_DN<9>")
	)
	(segment
		(start 144.60347 -438.623202)
		(end 144.750028 -438.76976)
		(width 0.14224)
		(layer "In15.Cu")
		(net "P5E_CPU1_P2_RX_BUF_DN<9>")
	)
	(segment
		(start 147.348956 -404.076154)
		(end 147.348956 -404.924514)
		(width 0.14224)
		(layer "In15.Cu")
		(net "P5E_CPU1_P2_RX_BUF_DN<9>")
	)
	(segment
		(start 144.09166 -438.623202)
		(end 144.60347 -438.623202)
		(width 0.14224)
		(layer "In15.Cu")
		(net "P5E_CPU1_P2_RX_BUF_DN<9>")
	)
	(segment
		(start 158.244286 -392.597386)
		(end 158.105856 -392.735816)
		(width 0.14224)
		(layer "In15.Cu")
		(net "P5E_CPU1_P2_RX_BUF_DN<9>")
	)
	(segment
		(start 145.817336 -406.638252)
		(end 145.817336 -410.697426)
		(width 0.14224)
		(layer "In15.Cu")
		(net "P5E_CPU1_P2_RX_BUF_DN<9>")
	)
	(segment
		(start 155.316428 -398.211548)
		(end 153.327354 -400.200114)
		(width 0.14224)
		(layer "In15.Cu")
		(net "P5E_CPU1_P2_RX_BUF_DN<9>")
	)
	(segment
		(start 144.750028 -438.76976)
		(end 144.750028 -439.0898)
		(width 0.14224)
		(layer "In15.Cu")
		(net "P5E_CPU1_P2_RX_BUF_DN<9>")
	)
	(segment
		(start 157.158436 -395.967712)
		(end 155.316428 -398.211548)
		(width 0.14224)
		(layer "In15.Cu")
		(net "P5E_CPU1_P2_RX_BUF_DN<9>")
	)
	(segment
		(start 157.503368 -393.043156)
		(end 157.503368 -395.451584)
		(width 0.14224)
		(layer "In15.Cu")
		(net "P5E_CPU1_P2_RX_BUF_DN<9>")
	)
	(segment
		(start 157.503368 -395.451584)
		(end 157.158436 -395.967712)
		(width 0.14224)
		(layer "In15.Cu")
		(net "P5E_CPU1_P2_RX_BUF_DN<9>")
	)
	(segment
		(start 151.635968 -401.364958)
		(end 148.717762 -402.573998)
		(width 0.14224)
		(layer "In15.Cu")
		(net "P5E_CPU1_P2_RX_BUF_DN<9>")
	)
	(segment
		(start 143.789146 -415.062162)
		(end 143.789146 -438.320688)
		(width 0.14224)
		(layer "In15.Cu")
		(net "P5E_CPU1_P2_RX_BUF_DN<9>")
	)
	(segment
		(start 152.040082 -401.144994)
		(end 151.74976 -401.309586)
		(width 0.14224)
		(layer "In15.Cu")
		(net "P5E_CPU1_P2_RX_BUF_DN<9>")
	)
	(segment
		(start 145.771362 -410.812234)
		(end 145.603722 -410.988256)
		(width 0.14224)
		(layer "In15.Cu")
		(net "P5E_CPU1_P2_RX_BUF_DN<9>")
	)
	(segment
		(start 145.50009 -411.059376)
		(end 144.547336 -411.454346)
		(width 0.14224)
		(layer "In15.Cu")
		(net "P5E_CPU1_P2_RX_BUF_DN<9>")
	)
	(segment
		(start 158.105856 -392.735816)
		(end 157.810708 -392.735816)
		(width 0.14224)
		(layer "In15.Cu")
		(net "P5E_CPU1_P2_RX_BUF_DN<9>")
	)
	(segment
		(start 153.327354 -400.200114)
		(end 152.146 -401.075906)
		(width 0.14224)
		(layer "In15.Cu")
		(net "P5E_CPU1_P2_RX_BUF_DN<9>")
	)
	(segment
		(start 147.229068 -405.214074)
		(end 147.101814 -405.341328)
		(width 0.14224)
		(layer "In15.Cu")
		(net "P5E_CPU1_P2_RX_BUF_DN<9>")
	)
	(segment
		(start 143.789146 -438.320688)
		(end 144.09166 -438.623202)
		(width 0.14224)
		(layer "In15.Cu")
		(net "P5E_CPU1_P2_RX_BUF_DN<9>")
	)
	(segment
		(start 148.26996 -402.873718)
		(end 147.546568 -403.59838)
		(width 0.14224)
		(layer "In15.Cu")
		(net "P5E_CPU1_P2_RX_BUF_DN<9>")
	)
	(segment
		(start 158.244286 -392.429238)
		(end 158.244286 -392.597386)
		(width 0.14224)
		(layer "In15.Cu")
		(net "P5E_CPU1_P2_RX_BUF_DN<9>")
	)
	(segment
		(start 147.101814 -405.341328)
		(end 146.832574 -405.52116)
		(width 0.14224)
		(layer "In15.Cu")
		(net "P5E_CPU1_P2_RX_BUF_DN<9>")
	)
	(segment
		(start 146.832574 -405.52116)
		(end 146.582638 -405.624538)
		(width 0.14224)
		(layer "In15.Cu")
		(net "P5E_CPU1_P2_RX_BUF_DN<9>")
	)
	(segment
		(start 157.810708 -392.735816)
		(end 157.503368 -393.043156)
		(width 0.14224)
		(layer "In15.Cu")
		(net "P5E_CPU1_P2_RX_BUF_DN<9>")
	)
	(arc
		(start 144.547336 -411.454346)
		(mid 144.35724 -411.610266)
		(end 144.285716 -411.845506)
		(width 0.14224)
		(layer "In15.Cu")
		(net "P5E_CPU1_P2_RX_BUF_DN<9>")
	)
	(arc
		(start 151.74976 -401.309586)
		(mid 151.693713 -401.339017)
		(end 151.635968 -401.364958)
		(width 0.14224)
		(layer "In15.Cu")
		(net "P5E_CPU1_P2_RX_BUF_DN<9>")
	)
	(arc
		(start 152.146 -401.075906)
		(mid 152.094098 -401.112071)
		(end 152.040082 -401.144994)
		(width 0.14224)
		(layer "In15.Cu")
		(net "P5E_CPU1_P2_RX_BUF_DN<9>")
	)
	(arc
		(start 146.582638 -405.624538)
		(mid 146.328034 -405.760803)
		(end 146.104864 -405.94407)
		(width 0.14224)
		(layer "In15.Cu")
		(net "P5E_CPU1_P2_RX_BUF_DN<9>")
	)
	(arc
		(start 147.348956 -404.924514)
		(mid 147.317804 -405.081217)
		(end 147.229068 -405.214074)
		(width 0.14224)
		(layer "In15.Cu")
		(net "P5E_CPU1_P2_RX_BUF_DN<9>")
	)
	(arc
		(start 146.104864 -405.94407)
		(mid 145.891975 -406.262536)
		(end 145.817336 -406.638252)
		(width 0.14224)
		(layer "In15.Cu")
		(net "P5E_CPU1_P2_RX_BUF_DN<9>")
	)
	(arc
		(start 144.285716 -413.863282)
		(mid 144.232643 -414.1301)
		(end 144.0815 -414.356296)
		(width 0.14224)
		(layer "In15.Cu")
		(net "P5E_CPU1_P2_RX_BUF_DN<9>")
	)
	(arc
		(start 145.603722 -410.988256)
		(mid 145.555633 -411.029248)
		(end 145.50009 -411.059376)
		(width 0.14224)
		(layer "In15.Cu")
		(net "P5E_CPU1_P2_RX_BUF_DN<9>")
	)
	(arc
		(start 144.0815 -414.356296)
		(mid 143.865108 -414.68015)
		(end 143.789146 -415.062162)
		(width 0.14224)
		(layer "In15.Cu")
		(net "P5E_CPU1_P2_RX_BUF_DN<9>")
	)
	(arc
		(start 147.546568 -403.59838)
		(mid 147.400261 -403.817627)
		(end 147.348956 -404.076154)
		(width 0.14224)
		(layer "In15.Cu")
		(net "P5E_CPU1_P2_RX_BUF_DN<9>")
	)
	(arc
		(start 145.817336 -410.697426)
		(mid 145.805417 -410.759263)
		(end 145.771362 -410.812234)
		(width 0.14224)
		(layer "In15.Cu")
		(net "P5E_CPU1_P2_RX_BUF_DN<9>")
	)
	(arc
		(start 148.717762 -402.573998)
		(mid 148.479067 -402.701754)
		(end 148.26996 -402.873718)
		(width 0.14224)
		(layer "In15.Cu")
		(net "P5E_CPU1_P2_RX_BUF_DN<9>")
	)
	(segment
		(start 156.684472 -392.761216)
		(end 156.557472 -392.634216)
		(width 0.1016)
		(layer "F.Cu")
		(net "P5E_CPU1_P2_RX_BUF_DN<8>")
	)
	(segment
		(start 157.04439 -392.429238)
		(end 157.04439 -392.620246)
		(width 0.1016)
		(layer "F.Cu")
		(net "P5E_CPU1_P2_RX_BUF_DN<8>")
	)
	(segment
		(start 156.646118 -390.761982)
		(end 156.64561 -390.761474)
		(width 0.1016)
		(layer "F.Cu")
		(net "P5E_CPU1_P2_RX_BUF_DN<8>")
	)
	(segment
		(start 157.04439 -392.620246)
		(end 156.90342 -392.761216)
		(width 0.1016)
		(layer "F.Cu")
		(net "P5E_CPU1_P2_RX_BUF_DN<8>")
	)
	(segment
		(start 156.646118 -391.578338)
		(end 156.646118 -390.761982)
		(width 0.1016)
		(layer "F.Cu")
		(net "P5E_CPU1_P2_RX_BUF_DN<8>")
	)
	(segment
		(start 156.557472 -392.634216)
		(end 156.557472 -391.666984)
		(width 0.1016)
		(layer "F.Cu")
		(net "P5E_CPU1_P2_RX_BUF_DN<8>")
	)
	(segment
		(start 156.557472 -391.666984)
		(end 156.646118 -391.578338)
		(width 0.1016)
		(layer "F.Cu")
		(net "P5E_CPU1_P2_RX_BUF_DN<8>")
	)
	(segment
		(start 156.90342 -392.761216)
		(end 156.684472 -392.761216)
		(width 0.1016)
		(layer "F.Cu")
		(net "P5E_CPU1_P2_RX_BUF_DN<8>")
	)
	(segment
		(start 142.59941 -437.61914)
		(end 142.750032 -437.769762)
		(width 0.14224)
		(layer "In15.Cu")
		(net "P5E_CPU1_P2_RX_BUF_DN<8>")
	)
	(segment
		(start 157.04439 -392.597386)
		(end 156.90596 -392.735816)
		(width 0.14224)
		(layer "In15.Cu")
		(net "P5E_CPU1_P2_RX_BUF_DN<8>")
	)
	(segment
		(start 144.285716 -404.05558)
		(end 144.285716 -404.924514)
		(width 0.14224)
		(layer "In15.Cu")
		(net "P5E_CPU1_P2_RX_BUF_DN<8>")
	)
	(segment
		(start 157.04439 -392.429238)
		(end 157.04439 -392.597386)
		(width 0.14224)
		(layer "In15.Cu")
		(net "P5E_CPU1_P2_RX_BUF_DN<8>")
	)
	(segment
		(start 142.43685 -411.059376)
		(end 141.484096 -411.454346)
		(width 0.14224)
		(layer "In15.Cu")
		(net "P5E_CPU1_P2_RX_BUF_DN<8>")
	)
	(segment
		(start 141.222476 -436.758842)
		(end 142.082774 -437.61914)
		(width 0.14224)
		(layer "In15.Cu")
		(net "P5E_CPU1_P2_RX_BUF_DN<8>")
	)
	(segment
		(start 151.777446 -400.158458)
		(end 151.386286 -400.438874)
		(width 0.14224)
		(layer "In15.Cu")
		(net "P5E_CPU1_P2_RX_BUF_DN<8>")
	)
	(segment
		(start 143.769334 -405.52116)
		(end 143.519398 -405.624538)
		(width 0.14224)
		(layer "In15.Cu")
		(net "P5E_CPU1_P2_RX_BUF_DN<8>")
	)
	(segment
		(start 144.165828 -405.214074)
		(end 144.038574 -405.341328)
		(width 0.14224)
		(layer "In15.Cu")
		(net "P5E_CPU1_P2_RX_BUF_DN<8>")
	)
	(segment
		(start 156.90596 -392.735816)
		(end 156.610812 -392.735816)
		(width 0.14224)
		(layer "In15.Cu")
		(net "P5E_CPU1_P2_RX_BUF_DN<8>")
	)
	(segment
		(start 144.038574 -405.341328)
		(end 143.769334 -405.52116)
		(width 0.14224)
		(layer "In15.Cu")
		(net "P5E_CPU1_P2_RX_BUF_DN<8>")
	)
	(segment
		(start 142.082774 -437.61914)
		(end 142.59941 -437.61914)
		(width 0.14224)
		(layer "In15.Cu")
		(net "P5E_CPU1_P2_RX_BUF_DN<8>")
	)
	(segment
		(start 142.708122 -410.812234)
		(end 142.540482 -410.988256)
		(width 0.14224)
		(layer "In15.Cu")
		(net "P5E_CPU1_P2_RX_BUF_DN<8>")
	)
	(segment
		(start 142.750032 -437.769762)
		(end 142.750032 -438.089802)
		(width 0.14224)
		(layer "In15.Cu")
		(net "P5E_CPU1_P2_RX_BUF_DN<8>")
	)
	(segment
		(start 154.952192 -397.085566)
		(end 153.359358 -398.843754)
		(width 0.14224)
		(layer "In15.Cu")
		(net "P5E_CPU1_P2_RX_BUF_DN<8>")
	)
	(segment
		(start 153.359358 -398.843754)
		(end 151.777446 -400.158458)
		(width 0.14224)
		(layer "In15.Cu")
		(net "P5E_CPU1_P2_RX_BUF_DN<8>")
	)
	(segment
		(start 151.386286 -400.438874)
		(end 150.461726 -400.840194)
		(width 0.14224)
		(layer "In15.Cu")
		(net "P5E_CPU1_P2_RX_BUF_DN<8>")
	)
	(segment
		(start 141.222476 -411.84576)
		(end 141.222476 -436.758842)
		(width 0.14224)
		(layer "In15.Cu")
		(net "P5E_CPU1_P2_RX_BUF_DN<8>")
	)
	(segment
		(start 150.461726 -400.840194)
		(end 150.218902 -400.931634)
		(width 0.14224)
		(layer "In15.Cu")
		(net "P5E_CPU1_P2_RX_BUF_DN<8>")
	)
	(segment
		(start 156.303472 -395.166596)
		(end 154.952192 -397.085566)
		(width 0.14224)
		(layer "In15.Cu")
		(net "P5E_CPU1_P2_RX_BUF_DN<8>")
	)
	(segment
		(start 156.303472 -393.043156)
		(end 156.303472 -395.166596)
		(width 0.14224)
		(layer "In15.Cu")
		(net "P5E_CPU1_P2_RX_BUF_DN<8>")
	)
	(segment
		(start 150.218902 -400.931634)
		(end 148.799296 -401.36191)
		(width 0.14224)
		(layer "In15.Cu")
		(net "P5E_CPU1_P2_RX_BUF_DN<8>")
	)
	(segment
		(start 148.799296 -401.36191)
		(end 146.111722 -402.4757)
		(width 0.14224)
		(layer "In15.Cu")
		(net "P5E_CPU1_P2_RX_BUF_DN<8>")
	)
	(segment
		(start 156.610812 -392.735816)
		(end 156.303472 -393.043156)
		(width 0.14224)
		(layer "In15.Cu")
		(net "P5E_CPU1_P2_RX_BUF_DN<8>")
	)
	(segment
		(start 142.754096 -406.638252)
		(end 142.754096 -410.697426)
		(width 0.14224)
		(layer "In15.Cu")
		(net "P5E_CPU1_P2_RX_BUF_DN<8>")
	)
	(arc
		(start 141.484096 -411.454346)
		(mid 141.293929 -411.610372)
		(end 141.222476 -411.84576)
		(width 0.14224)
		(layer "In15.Cu")
		(net "P5E_CPU1_P2_RX_BUF_DN<8>")
	)
	(arc
		(start 142.754096 -410.697426)
		(mid 142.742177 -410.759263)
		(end 142.708122 -410.812234)
		(width 0.14224)
		(layer "In15.Cu")
		(net "P5E_CPU1_P2_RX_BUF_DN<8>")
	)
	(arc
		(start 144.285716 -404.924514)
		(mid 144.254564 -405.081217)
		(end 144.165828 -405.214074)
		(width 0.14224)
		(layer "In15.Cu")
		(net "P5E_CPU1_P2_RX_BUF_DN<8>")
	)
	(arc
		(start 146.111722 -402.4757)
		(mid 145.257542 -402.956217)
		(end 144.48917 -403.564598)
		(width 0.14224)
		(layer "In15.Cu")
		(net "P5E_CPU1_P2_RX_BUF_DN<8>")
	)
	(arc
		(start 144.48917 -403.564598)
		(mid 144.338599 -403.789848)
		(end 144.285716 -404.05558)
		(width 0.14224)
		(layer "In15.Cu")
		(net "P5E_CPU1_P2_RX_BUF_DN<8>")
	)
	(arc
		(start 143.519398 -405.624538)
		(mid 143.264794 -405.760803)
		(end 143.041624 -405.94407)
		(width 0.14224)
		(layer "In15.Cu")
		(net "P5E_CPU1_P2_RX_BUF_DN<8>")
	)
	(arc
		(start 143.041624 -405.94407)
		(mid 142.828735 -406.262536)
		(end 142.754096 -406.638252)
		(width 0.14224)
		(layer "In15.Cu")
		(net "P5E_CPU1_P2_RX_BUF_DN<8>")
	)
	(arc
		(start 142.540482 -410.988256)
		(mid 142.492393 -411.029248)
		(end 142.43685 -411.059376)
		(width 0.14224)
		(layer "In15.Cu")
		(net "P5E_CPU1_P2_RX_BUF_DN<8>")
	)
	(segment
		(start 155.446222 -391.578338)
		(end 155.357576 -391.666984)
		(width 0.1016)
		(layer "F.Cu")
		(net "P5E_CPU1_P2_RX_BUF_DN<7>")
	)
	(segment
		(start 155.357576 -392.634216)
		(end 155.484576 -392.761216)
		(width 0.1016)
		(layer "F.Cu")
		(net "P5E_CPU1_P2_RX_BUF_DN<7>")
	)
	(segment
		(start 155.357576 -391.666984)
		(end 155.357576 -392.634216)
		(width 0.1016)
		(layer "F.Cu")
		(net "P5E_CPU1_P2_RX_BUF_DN<7>")
	)
	(segment
		(start 155.446222 -390.761982)
		(end 155.446222 -391.578338)
		(width 0.1016)
		(layer "F.Cu")
		(net "P5E_CPU1_P2_RX_BUF_DN<7>")
	)
	(segment
		(start 155.703524 -392.761216)
		(end 155.84424 -392.6205)
		(width 0.1016)
		(layer "F.Cu")
		(net "P5E_CPU1_P2_RX_BUF_DN<7>")
	)
	(segment
		(start 155.445714 -390.761474)
		(end 155.446222 -390.761982)
		(width 0.1016)
		(layer "F.Cu")
		(net "P5E_CPU1_P2_RX_BUF_DN<7>")
	)
	(segment
		(start 155.84424 -392.6205)
		(end 155.84424 -392.429238)
		(width 0.1016)
		(layer "F.Cu")
		(net "P5E_CPU1_P2_RX_BUF_DN<7>")
	)
	(segment
		(start 155.484576 -392.761216)
		(end 155.703524 -392.761216)
		(width 0.1016)
		(layer "F.Cu")
		(net "P5E_CPU1_P2_RX_BUF_DN<7>")
	)
	(segment
		(start 138.789156 -438.312052)
		(end 138.789156 -414.492948)
		(width 0.14224)
		(layer "In15.Cu")
		(net "P5E_CPU1_P2_RX_BUF_DN<7>")
	)
	(segment
		(start 143.434816 -402.336254)
		(end 143.43507 -402.336254)
		(width 0.14224)
		(layer "In15.Cu")
		(net "P5E_CPU1_P2_RX_BUF_DN<7>")
	)
	(segment
		(start 138.159236 -413.500824)
		(end 138.159236 -411.92196)
		(width 0.14224)
		(layer "In15.Cu")
		(net "P5E_CPU1_P2_RX_BUF_DN<7>")
	)
	(segment
		(start 153.709624 -397.060674)
		(end 154.43581 -396.18158)
		(width 0.14224)
		(layer "In15.Cu")
		(net "P5E_CPU1_P2_RX_BUF_DN<7>")
	)
	(segment
		(start 139.749784 -439.0898)
		(end 139.749784 -438.76976)
		(width 0.14224)
		(layer "In15.Cu")
		(net "P5E_CPU1_P2_RX_BUF_DN<7>")
	)
	(segment
		(start 140.975334 -405.341328)
		(end 141.102588 -405.214074)
		(width 0.14224)
		(layer "In15.Cu")
		(net "P5E_CPU1_P2_RX_BUF_DN<7>")
	)
	(segment
		(start 143.43507 -402.336254)
		(end 146.555714 -400.975322)
		(width 0.14224)
		(layer "In15.Cu")
		(net "P5E_CPU1_P2_RX_BUF_DN<7>")
	)
	(segment
		(start 140.347446 -405.670766)
		(end 140.705332 -405.521922)
		(width 0.14224)
		(layer "In15.Cu")
		(net "P5E_CPU1_P2_RX_BUF_DN<7>")
	)
	(segment
		(start 155.70581 -392.735816)
		(end 155.84424 -392.597386)
		(width 0.14224)
		(layer "In15.Cu")
		(net "P5E_CPU1_P2_RX_BUF_DN<7>")
	)
	(segment
		(start 140.705332 -405.521922)
		(end 140.975334 -405.341328)
		(width 0.14224)
		(layer "In15.Cu")
		(net "P5E_CPU1_P2_RX_BUF_DN<7>")
	)
	(segment
		(start 141.49832 -403.454616)
		(end 141.661642 -403.291294)
		(width 0.14224)
		(layer "In15.Cu")
		(net "P5E_CPU1_P2_RX_BUF_DN<7>")
	)
	(segment
		(start 152.213818 -398.537938)
		(end 153.709624 -397.060674)
		(width 0.14224)
		(layer "In15.Cu")
		(net "P5E_CPU1_P2_RX_BUF_DN<7>")
	)
	(segment
		(start 138.740388 -414.375346)
		(end 138.367008 -414.001966)
		(width 0.14224)
		(layer "In15.Cu")
		(net "P5E_CPU1_P2_RX_BUF_DN<7>")
	)
	(segment
		(start 139.690856 -410.51353)
		(end 139.690856 -406.643332)
		(width 0.14224)
		(layer "In15.Cu")
		(net "P5E_CPU1_P2_RX_BUF_DN<7>")
	)
	(segment
		(start 150.551388 -399.756122)
		(end 151.020018 -399.493994)
		(width 0.14224)
		(layer "In15.Cu")
		(net "P5E_CPU1_P2_RX_BUF_DN<7>")
	)
	(segment
		(start 139.749784 -438.76976)
		(end 139.599416 -438.619392)
		(width 0.14224)
		(layer "In15.Cu")
		(net "P5E_CPU1_P2_RX_BUF_DN<7>")
	)
	(segment
		(start 139.830302 -406.218898)
		(end 140.078714 -405.881586)
		(width 0.14224)
		(layer "In15.Cu")
		(net "P5E_CPU1_P2_RX_BUF_DN<7>")
	)
	(segment
		(start 139.096496 -438.619392)
		(end 138.789156 -438.312052)
		(width 0.14224)
		(layer "In15.Cu")
		(net "P5E_CPU1_P2_RX_BUF_DN<7>")
	)
	(segment
		(start 155.059634 -394.906246)
		(end 155.059634 -393.086844)
		(width 0.14224)
		(layer "In15.Cu")
		(net "P5E_CPU1_P2_RX_BUF_DN<7>")
	)
	(segment
		(start 146.555714 -400.975322)
		(end 148.711412 -400.349974)
		(width 0.14224)
		(layer "In15.Cu")
		(net "P5E_CPU1_P2_RX_BUF_DN<7>")
	)
	(segment
		(start 154.922474 -395.453362)
		(end 155.059634 -394.906246)
		(width 0.14224)
		(layer "In15.Cu")
		(net "P5E_CPU1_P2_RX_BUF_DN<7>")
	)
	(segment
		(start 155.059634 -393.086844)
		(end 155.410662 -392.735816)
		(width 0.14224)
		(layer "In15.Cu")
		(net "P5E_CPU1_P2_RX_BUF_DN<7>")
	)
	(segment
		(start 149.117812 -400.268948)
		(end 150.551388 -399.756122)
		(width 0.14224)
		(layer "In15.Cu")
		(net "P5E_CPU1_P2_RX_BUF_DN<7>")
	)
	(segment
		(start 139.445746 -410.972762)
		(end 139.655296 -410.637736)
		(width 0.14224)
		(layer "In15.Cu")
		(net "P5E_CPU1_P2_RX_BUF_DN<7>")
	)
	(segment
		(start 142.401036 -402.787104)
		(end 143.434816 -402.336254)
		(width 0.14224)
		(layer "In15.Cu")
		(net "P5E_CPU1_P2_RX_BUF_DN<7>")
	)
	(segment
		(start 155.84424 -392.597386)
		(end 155.84424 -392.429238)
		(width 0.14224)
		(layer "In15.Cu")
		(net "P5E_CPU1_P2_RX_BUF_DN<7>")
	)
	(segment
		(start 139.599416 -438.619392)
		(end 139.096496 -438.619392)
		(width 0.14224)
		(layer "In15.Cu")
		(net "P5E_CPU1_P2_RX_BUF_DN<7>")
	)
	(segment
		(start 141.222476 -404.924514)
		(end 141.222476 -404.120604)
		(width 0.14224)
		(layer "In15.Cu")
		(net "P5E_CPU1_P2_RX_BUF_DN<7>")
	)
	(segment
		(start 155.410662 -392.735816)
		(end 155.70581 -392.735816)
		(width 0.14224)
		(layer "In15.Cu")
		(net "P5E_CPU1_P2_RX_BUF_DN<7>")
	)
	(segment
		(start 151.020018 -399.493994)
		(end 152.213818 -398.537938)
		(width 0.14224)
		(layer "In15.Cu")
		(net "P5E_CPU1_P2_RX_BUF_DN<7>")
	)
	(segment
		(start 154.43581 -396.18158)
		(end 154.922474 -395.453362)
		(width 0.14224)
		(layer "In15.Cu")
		(net "P5E_CPU1_P2_RX_BUF_DN<7>")
	)
	(segment
		(start 148.711412 -400.349974)
		(end 149.117812 -400.268948)
		(width 0.14224)
		(layer "In15.Cu")
		(net "P5E_CPU1_P2_RX_BUF_DN<7>")
	)
	(segment
		(start 138.505184 -411.4038)
		(end 139.350496 -411.05328)
		(width 0.14224)
		(layer "In15.Cu")
		(net "P5E_CPU1_P2_RX_BUF_DN<7>")
	)
	(arc
		(start 139.690856 -406.643332)
		(mid 139.726556 -406.41993)
		(end 139.830302 -406.218898)
		(width 0.14224)
		(layer "In15.Cu")
		(net "P5E_CPU1_P2_RX_BUF_DN<7>")
	)
	(arc
		(start 138.159236 -411.92196)
		(mid 138.253741 -411.610497)
		(end 138.505184 -411.4038)
		(width 0.14224)
		(layer "In15.Cu")
		(net "P5E_CPU1_P2_RX_BUF_DN<7>")
	)
	(arc
		(start 139.350496 -411.05328)
		(mid 139.404382 -411.020435)
		(end 139.445746 -410.972762)
		(width 0.14224)
		(layer "In15.Cu")
		(net "P5E_CPU1_P2_RX_BUF_DN<7>")
	)
	(arc
		(start 138.789156 -414.492948)
		(mid 138.776477 -414.429295)
		(end 138.740388 -414.375346)
		(width 0.14224)
		(layer "In15.Cu")
		(net "P5E_CPU1_P2_RX_BUF_DN<7>")
	)
	(arc
		(start 141.222476 -404.120604)
		(mid 141.294169 -403.76018)
		(end 141.49832 -403.454616)
		(width 0.14224)
		(layer "In15.Cu")
		(net "P5E_CPU1_P2_RX_BUF_DN<7>")
	)
	(arc
		(start 140.078714 -405.881586)
		(mid 140.198736 -405.757887)
		(end 140.347446 -405.670766)
		(width 0.14224)
		(layer "In15.Cu")
		(net "P5E_CPU1_P2_RX_BUF_DN<7>")
	)
	(arc
		(start 141.661642 -403.291294)
		(mid 142.007672 -403.004492)
		(end 142.401036 -402.787104)
		(width 0.14224)
		(layer "In15.Cu")
		(net "P5E_CPU1_P2_RX_BUF_DN<7>")
	)
	(arc
		(start 138.367008 -414.001966)
		(mid 138.213293 -413.772055)
		(end 138.159236 -413.500824)
		(width 0.14224)
		(layer "In15.Cu")
		(net "P5E_CPU1_P2_RX_BUF_DN<7>")
	)
	(arc
		(start 139.655296 -410.637736)
		(mid 139.681783 -410.57813)
		(end 139.690856 -410.51353)
		(width 0.14224)
		(layer "In15.Cu")
		(net "P5E_CPU1_P2_RX_BUF_DN<7>")
	)
	(arc
		(start 141.102588 -405.214074)
		(mid 141.191303 -405.081209)
		(end 141.222476 -404.924514)
		(width 0.14224)
		(layer "In15.Cu")
		(net "P5E_CPU1_P2_RX_BUF_DN<7>")
	)
	(segment
		(start 154.644344 -392.6205)
		(end 154.644344 -392.429238)
		(width 0.1016)
		(layer "F.Cu")
		(net "P5E_CPU1_P2_RX_BUF_DN<6>")
	)
	(segment
		(start 154.166316 -392.634216)
		(end 154.293316 -392.761216)
		(width 0.1016)
		(layer "F.Cu")
		(net "P5E_CPU1_P2_RX_BUF_DN<6>")
	)
	(segment
		(start 154.245818 -390.761474)
		(end 154.246326 -390.761982)
		(width 0.1016)
		(layer "F.Cu")
		(net "P5E_CPU1_P2_RX_BUF_DN<6>")
	)
	(segment
		(start 154.293316 -392.761216)
		(end 154.503628 -392.761216)
		(width 0.1016)
		(layer "F.Cu")
		(net "P5E_CPU1_P2_RX_BUF_DN<6>")
	)
	(segment
		(start 154.246326 -390.761982)
		(end 154.246326 -391.365486)
		(width 0.1016)
		(layer "F.Cu")
		(net "P5E_CPU1_P2_RX_BUF_DN<6>")
	)
	(segment
		(start 154.246072 -391.36574)
		(end 154.246072 -391.578338)
		(width 0.1016)
		(layer "F.Cu")
		(net "P5E_CPU1_P2_RX_BUF_DN<6>")
	)
	(segment
		(start 154.503628 -392.761216)
		(end 154.644344 -392.6205)
		(width 0.1016)
		(layer "F.Cu")
		(net "P5E_CPU1_P2_RX_BUF_DN<6>")
	)
	(segment
		(start 154.246326 -391.365486)
		(end 154.246072 -391.36574)
		(width 0.1016)
		(layer "F.Cu")
		(net "P5E_CPU1_P2_RX_BUF_DN<6>")
	)
	(segment
		(start 154.166316 -391.658094)
		(end 154.166316 -392.634216)
		(width 0.1016)
		(layer "F.Cu")
		(net "P5E_CPU1_P2_RX_BUF_DN<6>")
	)
	(segment
		(start 154.246072 -391.578338)
		(end 154.166316 -391.658094)
		(width 0.1016)
		(layer "F.Cu")
		(net "P5E_CPU1_P2_RX_BUF_DN<6>")
	)
	(segment
		(start 154.644344 -392.597386)
		(end 154.505914 -392.735816)
		(width 0.14224)
		(layer "In15.Cu")
		(net "P5E_CPU1_P2_RX_BUF_DN<6>")
	)
	(segment
		(start 136.31037 -411.059376)
		(end 135.357616 -411.454346)
		(width 0.14224)
		(layer "In15.Cu")
		(net "P5E_CPU1_P2_RX_BUF_DN<6>")
	)
	(segment
		(start 138.323828 -403.697186)
		(end 138.23315 -403.8473)
		(width 0.14224)
		(layer "In15.Cu")
		(net "P5E_CPU1_P2_RX_BUF_DN<6>")
	)
	(segment
		(start 137.642854 -405.52116)
		(end 137.392918 -405.624538)
		(width 0.14224)
		(layer "In15.Cu")
		(net "P5E_CPU1_P2_RX_BUF_DN<6>")
	)
	(segment
		(start 153.741374 -395.36751)
		(end 153.405078 -395.870938)
		(width 0.14224)
		(layer "In15.Cu")
		(net "P5E_CPU1_P2_RX_BUF_DN<6>")
	)
	(segment
		(start 137.09142 -437.623204)
		(end 137.60323 -437.623204)
		(width 0.14224)
		(layer "In15.Cu")
		(net "P5E_CPU1_P2_RX_BUF_DN<6>")
	)
	(segment
		(start 150.94585 -398.330166)
		(end 150.263098 -398.78635)
		(width 0.14224)
		(layer "In15.Cu")
		(net "P5E_CPU1_P2_RX_BUF_DN<6>")
	)
	(segment
		(start 147.989798 -399.517362)
		(end 145.45564 -400.28622)
		(width 0.14224)
		(layer "In15.Cu")
		(net "P5E_CPU1_P2_RX_BUF_DN<6>")
	)
	(segment
		(start 138.039348 -405.214074)
		(end 137.912094 -405.341328)
		(width 0.14224)
		(layer "In15.Cu")
		(net "P5E_CPU1_P2_RX_BUF_DN<6>")
	)
	(segment
		(start 138.797538 -403.197568)
		(end 138.44651 -403.542246)
		(width 0.14224)
		(layer "In15.Cu")
		(net "P5E_CPU1_P2_RX_BUF_DN<6>")
	)
	(segment
		(start 137.749788 -437.769762)
		(end 137.749788 -438.089802)
		(width 0.14224)
		(layer "In15.Cu")
		(net "P5E_CPU1_P2_RX_BUF_DN<6>")
	)
	(segment
		(start 139.187428 -402.975572)
		(end 138.952732 -403.088602)
		(width 0.14224)
		(layer "In15.Cu")
		(net "P5E_CPU1_P2_RX_BUF_DN<6>")
	)
	(segment
		(start 135.27913 -413.610806)
		(end 136.676892 -415.008568)
		(width 0.14224)
		(layer "In15.Cu")
		(net "P5E_CPU1_P2_RX_BUF_DN<6>")
	)
	(segment
		(start 137.60323 -437.623204)
		(end 137.749788 -437.769762)
		(width 0.14224)
		(layer "In15.Cu")
		(net "P5E_CPU1_P2_RX_BUF_DN<6>")
	)
	(segment
		(start 153.903426 -393.043156)
		(end 153.903426 -394.976604)
		(width 0.14224)
		(layer "In15.Cu")
		(net "P5E_CPU1_P2_RX_BUF_DN<6>")
	)
	(segment
		(start 135.095996 -411.846014)
		(end 135.095996 -413.168592)
		(width 0.14224)
		(layer "In15.Cu")
		(net "P5E_CPU1_P2_RX_BUF_DN<6>")
	)
	(segment
		(start 150.263098 -398.78635)
		(end 149.548088 -399.082514)
		(width 0.14224)
		(layer "In15.Cu")
		(net "P5E_CPU1_P2_RX_BUF_DN<6>")
	)
	(segment
		(start 154.644344 -392.429238)
		(end 154.644344 -392.597386)
		(width 0.14224)
		(layer "In15.Cu")
		(net "P5E_CPU1_P2_RX_BUF_DN<6>")
	)
	(segment
		(start 136.581642 -410.812234)
		(end 136.414002 -410.988256)
		(width 0.14224)
		(layer "In15.Cu")
		(net "P5E_CPU1_P2_RX_BUF_DN<6>")
	)
	(segment
		(start 136.78916 -437.320944)
		(end 137.09142 -437.623204)
		(width 0.14224)
		(layer "In15.Cu")
		(net "P5E_CPU1_P2_RX_BUF_DN<6>")
	)
	(segment
		(start 149.548088 -399.082514)
		(end 147.989798 -399.517362)
		(width 0.14224)
		(layer "In15.Cu")
		(net "P5E_CPU1_P2_RX_BUF_DN<6>")
	)
	(segment
		(start 154.210766 -392.735816)
		(end 153.903426 -393.043156)
		(width 0.14224)
		(layer "In15.Cu")
		(net "P5E_CPU1_P2_RX_BUF_DN<6>")
	)
	(segment
		(start 138.159236 -404.113238)
		(end 138.159236 -404.924514)
		(width 0.14224)
		(layer "In15.Cu")
		(net "P5E_CPU1_P2_RX_BUF_DN<6>")
	)
	(segment
		(start 136.627616 -406.638252)
		(end 136.627616 -410.697426)
		(width 0.14224)
		(layer "In15.Cu")
		(net "P5E_CPU1_P2_RX_BUF_DN<6>")
	)
	(segment
		(start 154.505914 -392.735816)
		(end 154.210766 -392.735816)
		(width 0.14224)
		(layer "In15.Cu")
		(net "P5E_CPU1_P2_RX_BUF_DN<6>")
	)
	(segment
		(start 137.912094 -405.341328)
		(end 137.642854 -405.52116)
		(width 0.14224)
		(layer "In15.Cu")
		(net "P5E_CPU1_P2_RX_BUF_DN<6>")
	)
	(segment
		(start 145.45564 -400.28622)
		(end 139.30249 -402.923248)
		(width 0.14224)
		(layer "In15.Cu")
		(net "P5E_CPU1_P2_RX_BUF_DN<6>")
	)
	(segment
		(start 153.903426 -394.976604)
		(end 153.741374 -395.36751)
		(width 0.14224)
		(layer "In15.Cu")
		(net "P5E_CPU1_P2_RX_BUF_DN<6>")
	)
	(segment
		(start 153.405078 -395.870938)
		(end 150.94585 -398.330166)
		(width 0.14224)
		(layer "In15.Cu")
		(net "P5E_CPU1_P2_RX_BUF_DN<6>")
	)
	(segment
		(start 136.78916 -415.279586)
		(end 136.78916 -437.320944)
		(width 0.14224)
		(layer "In15.Cu")
		(net "P5E_CPU1_P2_RX_BUF_DN<6>")
	)
	(arc
		(start 137.392918 -405.624538)
		(mid 137.138314 -405.760803)
		(end 136.915144 -405.94407)
		(width 0.14224)
		(layer "In15.Cu")
		(net "P5E_CPU1_P2_RX_BUF_DN<6>")
	)
	(arc
		(start 138.23315 -403.8473)
		(mid 138.178058 -403.975229)
		(end 138.159236 -404.113238)
		(width 0.14224)
		(layer "In15.Cu")
		(net "P5E_CPU1_P2_RX_BUF_DN<6>")
	)
	(arc
		(start 138.44651 -403.542246)
		(mid 138.380305 -403.615864)
		(end 138.323828 -403.697186)
		(width 0.14224)
		(layer "In15.Cu")
		(net "P5E_CPU1_P2_RX_BUF_DN<6>")
	)
	(arc
		(start 135.357616 -411.454346)
		(mid 135.167378 -411.610478)
		(end 135.095996 -411.846014)
		(width 0.14224)
		(layer "In15.Cu")
		(net "P5E_CPU1_P2_RX_BUF_DN<6>")
	)
	(arc
		(start 139.30249 -402.923248)
		(mid 139.244673 -402.948781)
		(end 139.187428 -402.975572)
		(width 0.14224)
		(layer "In15.Cu")
		(net "P5E_CPU1_P2_RX_BUF_DN<6>")
	)
	(arc
		(start 135.095996 -413.168592)
		(mid 135.143598 -413.407902)
		(end 135.27913 -413.610806)
		(width 0.14224)
		(layer "In15.Cu")
		(net "P5E_CPU1_P2_RX_BUF_DN<6>")
	)
	(arc
		(start 136.627616 -410.697426)
		(mid 136.615697 -410.759263)
		(end 136.581642 -410.812234)
		(width 0.14224)
		(layer "In15.Cu")
		(net "P5E_CPU1_P2_RX_BUF_DN<6>")
	)
	(arc
		(start 136.414002 -410.988256)
		(mid 136.365913 -411.029248)
		(end 136.31037 -411.059376)
		(width 0.14224)
		(layer "In15.Cu")
		(net "P5E_CPU1_P2_RX_BUF_DN<6>")
	)
	(arc
		(start 138.952732 -403.088602)
		(mid 138.870673 -403.136729)
		(end 138.797538 -403.197568)
		(width 0.14224)
		(layer "In15.Cu")
		(net "P5E_CPU1_P2_RX_BUF_DN<6>")
	)
	(arc
		(start 136.915144 -405.94407)
		(mid 136.702255 -406.262536)
		(end 136.627616 -406.638252)
		(width 0.14224)
		(layer "In15.Cu")
		(net "P5E_CPU1_P2_RX_BUF_DN<6>")
	)
	(arc
		(start 138.159236 -404.924514)
		(mid 138.128084 -405.081217)
		(end 138.039348 -405.214074)
		(width 0.14224)
		(layer "In15.Cu")
		(net "P5E_CPU1_P2_RX_BUF_DN<6>")
	)
	(arc
		(start 136.676892 -415.008568)
		(mid 136.759976 -415.132912)
		(end 136.78916 -415.279586)
		(width 0.14224)
		(layer "In15.Cu")
		(net "P5E_CPU1_P2_RX_BUF_DN<6>")
	)
	(segment
		(start 153.045668 -390.761474)
		(end 153.046176 -390.761982)
		(width 0.1016)
		(layer "F.Cu")
		(net "P5E_CPU1_P2_RX_BUF_DN<5>")
	)
	(segment
		(start 153.046176 -391.578338)
		(end 152.95753 -391.666984)
		(width 0.1016)
		(layer "F.Cu")
		(net "P5E_CPU1_P2_RX_BUF_DN<5>")
	)
	(segment
		(start 153.444194 -392.6205)
		(end 153.444194 -392.429238)
		(width 0.1016)
		(layer "F.Cu")
		(net "P5E_CPU1_P2_RX_BUF_DN<5>")
	)
	(segment
		(start 152.95753 -392.634216)
		(end 153.08453 -392.761216)
		(width 0.1016)
		(layer "F.Cu")
		(net "P5E_CPU1_P2_RX_BUF_DN<5>")
	)
	(segment
		(start 153.303478 -392.761216)
		(end 153.444194 -392.6205)
		(width 0.1016)
		(layer "F.Cu")
		(net "P5E_CPU1_P2_RX_BUF_DN<5>")
	)
	(segment
		(start 153.08453 -392.761216)
		(end 153.303478 -392.761216)
		(width 0.1016)
		(layer "F.Cu")
		(net "P5E_CPU1_P2_RX_BUF_DN<5>")
	)
	(segment
		(start 153.046176 -390.761982)
		(end 153.046176 -391.578338)
		(width 0.1016)
		(layer "F.Cu")
		(net "P5E_CPU1_P2_RX_BUF_DN<5>")
	)
	(segment
		(start 152.95753 -391.666984)
		(end 152.95753 -392.634216)
		(width 0.1016)
		(layer "F.Cu")
		(net "P5E_CPU1_P2_RX_BUF_DN<5>")
	)
	(segment
		(start 149.060916 -398.225518)
		(end 147.385278 -398.558766)
		(width 0.14224)
		(layer "In15.Cu")
		(net "P5E_CPU1_P2_RX_BUF_DN<5>")
	)
	(segment
		(start 132.2324 -414.332928)
		(end 134.71398 -416.814508)
		(width 0.14224)
		(layer "In15.Cu")
		(net "P5E_CPU1_P2_RX_BUF_DN<5>")
	)
	(segment
		(start 147.385278 -398.558766)
		(end 144.1704 -399.620994)
		(width 0.14224)
		(layer "In15.Cu")
		(net "P5E_CPU1_P2_RX_BUF_DN<5>")
	)
	(segment
		(start 144.1704 -399.620994)
		(end 137.307066 -402.23567)
		(width 0.14224)
		(layer "In15.Cu")
		(net "P5E_CPU1_P2_RX_BUF_DN<5>")
	)
	(segment
		(start 135.492998 -403.376638)
		(end 135.324088 -403.545548)
		(width 0.14224)
		(layer "In15.Cu")
		(net "P5E_CPU1_P2_RX_BUF_DN<5>")
	)
	(segment
		(start 135.095996 -404.09622)
		(end 135.095996 -404.924514)
		(width 0.14224)
		(layer "In15.Cu")
		(net "P5E_CPU1_P2_RX_BUF_DN<5>")
	)
	(segment
		(start 152.59431 -395.332458)
		(end 150.85187 -397.074898)
		(width 0.14224)
		(layer "In15.Cu")
		(net "P5E_CPU1_P2_RX_BUF_DN<5>")
	)
	(segment
		(start 134.848854 -405.341328)
		(end 134.579614 -405.52116)
		(width 0.14224)
		(layer "In15.Cu")
		(net "P5E_CPU1_P2_RX_BUF_DN<5>")
	)
	(segment
		(start 153.444194 -392.429238)
		(end 153.444194 -392.597386)
		(width 0.14224)
		(layer "In15.Cu")
		(net "P5E_CPU1_P2_RX_BUF_DN<5>")
	)
	(segment
		(start 153.010616 -392.735816)
		(end 152.703276 -393.043156)
		(width 0.14224)
		(layer "In15.Cu")
		(net "P5E_CPU1_P2_RX_BUF_DN<5>")
	)
	(segment
		(start 133.564376 -406.638252)
		(end 133.564376 -410.652722)
		(width 0.14224)
		(layer "In15.Cu")
		(net "P5E_CPU1_P2_RX_BUF_DN<5>")
	)
	(segment
		(start 149.618192 -397.994886)
		(end 149.060916 -398.225518)
		(width 0.14224)
		(layer "In15.Cu")
		(net "P5E_CPU1_P2_RX_BUF_DN<5>")
	)
	(segment
		(start 153.444194 -392.597386)
		(end 153.305764 -392.735816)
		(width 0.14224)
		(layer "In15.Cu")
		(net "P5E_CPU1_P2_RX_BUF_DN<5>")
	)
	(segment
		(start 150.85187 -397.074898)
		(end 150.227538 -397.587724)
		(width 0.14224)
		(layer "In15.Cu")
		(net "P5E_CPU1_P2_RX_BUF_DN<5>")
	)
	(segment
		(start 134.800848 -417.024058)
		(end 134.800848 -438.265824)
		(width 0.14224)
		(layer "In15.Cu")
		(net "P5E_CPU1_P2_RX_BUF_DN<5>")
	)
	(segment
		(start 135.158226 -438.623202)
		(end 135.603234 -438.623202)
		(width 0.14224)
		(layer "In15.Cu")
		(net "P5E_CPU1_P2_RX_BUF_DN<5>")
	)
	(segment
		(start 150.227538 -397.587724)
		(end 149.618192 -397.994886)
		(width 0.14224)
		(layer "In15.Cu")
		(net "P5E_CPU1_P2_RX_BUF_DN<5>")
	)
	(segment
		(start 132.032756 -411.967934)
		(end 132.032756 -413.850836)
		(width 0.14224)
		(layer "In15.Cu")
		(net "P5E_CPU1_P2_RX_BUF_DN<5>")
	)
	(segment
		(start 133.472936 -410.880814)
		(end 133.302502 -411.059376)
		(width 0.14224)
		(layer "In15.Cu")
		(net "P5E_CPU1_P2_RX_BUF_DN<5>")
	)
	(segment
		(start 153.305764 -392.735816)
		(end 153.010616 -392.735816)
		(width 0.14224)
		(layer "In15.Cu")
		(net "P5E_CPU1_P2_RX_BUF_DN<5>")
	)
	(segment
		(start 134.976108 -405.214074)
		(end 134.848854 -405.341328)
		(width 0.14224)
		(layer "In15.Cu")
		(net "P5E_CPU1_P2_RX_BUF_DN<5>")
	)
	(segment
		(start 152.703276 -393.043156)
		(end 152.703276 -395.069314)
		(width 0.14224)
		(layer "In15.Cu")
		(net "P5E_CPU1_P2_RX_BUF_DN<5>")
	)
	(segment
		(start 135.603234 -438.623202)
		(end 135.749792 -438.76976)
		(width 0.14224)
		(layer "In15.Cu")
		(net "P5E_CPU1_P2_RX_BUF_DN<5>")
	)
	(segment
		(start 134.800848 -438.265824)
		(end 135.158226 -438.623202)
		(width 0.14224)
		(layer "In15.Cu")
		(net "P5E_CPU1_P2_RX_BUF_DN<5>")
	)
	(segment
		(start 133.249924 -411.092396)
		(end 132.436616 -411.357318)
		(width 0.14224)
		(layer "In15.Cu")
		(net "P5E_CPU1_P2_RX_BUF_DN<5>")
	)
	(segment
		(start 152.703276 -395.069314)
		(end 152.59431 -395.332458)
		(width 0.14224)
		(layer "In15.Cu")
		(net "P5E_CPU1_P2_RX_BUF_DN<5>")
	)
	(segment
		(start 134.579614 -405.52116)
		(end 134.329678 -405.624538)
		(width 0.14224)
		(layer "In15.Cu")
		(net "P5E_CPU1_P2_RX_BUF_DN<5>")
	)
	(segment
		(start 135.749792 -438.76976)
		(end 135.749792 -439.0898)
		(width 0.14224)
		(layer "In15.Cu")
		(net "P5E_CPU1_P2_RX_BUF_DN<5>")
	)
	(segment
		(start 137.307066 -402.23567)
		(end 136.246616 -402.813012)
		(width 0.14224)
		(layer "In15.Cu")
		(net "P5E_CPU1_P2_RX_BUF_DN<5>")
	)
	(arc
		(start 133.851904 -405.94407)
		(mid 133.639015 -406.262536)
		(end 133.564376 -406.638252)
		(width 0.14224)
		(layer "In15.Cu")
		(net "P5E_CPU1_P2_RX_BUF_DN<5>")
	)
	(arc
		(start 136.246616 -402.813012)
		(mid 135.849559 -403.067754)
		(end 135.492998 -403.376638)
		(width 0.14224)
		(layer "In15.Cu")
		(net "P5E_CPU1_P2_RX_BUF_DN<5>")
	)
	(arc
		(start 133.302502 -411.059376)
		(mid 133.278268 -411.079162)
		(end 133.249924 -411.092396)
		(width 0.14224)
		(layer "In15.Cu")
		(net "P5E_CPU1_P2_RX_BUF_DN<5>")
	)
	(arc
		(start 132.067554 -411.753558)
		(mid 132.041482 -411.859338)
		(end 132.032756 -411.967934)
		(width 0.14224)
		(layer "In15.Cu")
		(net "P5E_CPU1_P2_RX_BUF_DN<5>")
	)
	(arc
		(start 134.329678 -405.624538)
		(mid 134.075074 -405.760803)
		(end 133.851904 -405.94407)
		(width 0.14224)
		(layer "In15.Cu")
		(net "P5E_CPU1_P2_RX_BUF_DN<5>")
	)
	(arc
		(start 132.436616 -411.357318)
		(mid 132.313818 -411.417051)
		(end 132.210556 -411.506416)
		(width 0.14224)
		(layer "In15.Cu")
		(net "P5E_CPU1_P2_RX_BUF_DN<5>")
	)
	(arc
		(start 135.324088 -403.545548)
		(mid 135.155272 -403.798198)
		(end 135.095996 -404.09622)
		(width 0.14224)
		(layer "In15.Cu")
		(net "P5E_CPU1_P2_RX_BUF_DN<5>")
	)
	(arc
		(start 133.564376 -410.652722)
		(mid 133.540665 -410.775591)
		(end 133.472936 -410.880814)
		(width 0.14224)
		(layer "In15.Cu")
		(net "P5E_CPU1_P2_RX_BUF_DN<5>")
	)
	(arc
		(start 134.71398 -416.814508)
		(mid 134.778274 -416.910636)
		(end 134.800848 -417.024058)
		(width 0.14224)
		(layer "In15.Cu")
		(net "P5E_CPU1_P2_RX_BUF_DN<5>")
	)
	(arc
		(start 132.210556 -411.506416)
		(mid 132.126527 -411.622736)
		(end 132.067554 -411.753558)
		(width 0.14224)
		(layer "In15.Cu")
		(net "P5E_CPU1_P2_RX_BUF_DN<5>")
	)
	(arc
		(start 132.032756 -413.850836)
		(mid 132.084635 -414.111739)
		(end 132.2324 -414.332928)
		(width 0.14224)
		(layer "In15.Cu")
		(net "P5E_CPU1_P2_RX_BUF_DN<5>")
	)
	(arc
		(start 135.095996 -404.924514)
		(mid 135.064844 -405.081217)
		(end 134.976108 -405.214074)
		(width 0.14224)
		(layer "In15.Cu")
		(net "P5E_CPU1_P2_RX_BUF_DN<5>")
	)
	(segment
		(start 152.244298 -392.6205)
		(end 152.244298 -392.429238)
		(width 0.1016)
		(layer "F.Cu")
		(net "P5E_CPU1_P2_RX_BUF_DN<4>")
	)
	(segment
		(start 151.757634 -391.666984)
		(end 151.757634 -392.634216)
		(width 0.1016)
		(layer "F.Cu")
		(net "P5E_CPU1_P2_RX_BUF_DN<4>")
	)
	(segment
		(start 151.84628 -390.761982)
		(end 151.84628 -391.578338)
		(width 0.1016)
		(layer "F.Cu")
		(net "P5E_CPU1_P2_RX_BUF_DN<4>")
	)
	(segment
		(start 151.884634 -392.761216)
		(end 152.103582 -392.761216)
		(width 0.1016)
		(layer "F.Cu")
		(net "P5E_CPU1_P2_RX_BUF_DN<4>")
	)
	(segment
		(start 152.103582 -392.761216)
		(end 152.244298 -392.6205)
		(width 0.1016)
		(layer "F.Cu")
		(net "P5E_CPU1_P2_RX_BUF_DN<4>")
	)
	(segment
		(start 151.84628 -391.578338)
		(end 151.757634 -391.666984)
		(width 0.1016)
		(layer "F.Cu")
		(net "P5E_CPU1_P2_RX_BUF_DN<4>")
	)
	(segment
		(start 151.757634 -392.634216)
		(end 151.884634 -392.761216)
		(width 0.1016)
		(layer "F.Cu")
		(net "P5E_CPU1_P2_RX_BUF_DN<4>")
	)
	(segment
		(start 151.845772 -390.761474)
		(end 151.84628 -390.761982)
		(width 0.1016)
		(layer "F.Cu")
		(net "P5E_CPU1_P2_RX_BUF_DN<4>")
	)
	(segment
		(start 152.244298 -392.597386)
		(end 152.105868 -392.735816)
		(width 0.14224)
		(layer "In15.Cu")
		(net "P5E_CPU1_P2_RX_BUF_DN<4>")
	)
	(segment
		(start 131.516374 -405.52116)
		(end 131.266438 -405.624538)
		(width 0.14224)
		(layer "In15.Cu")
		(net "P5E_CPU1_P2_RX_BUF_DN<4>")
	)
	(segment
		(start 132.789168 -437.320944)
		(end 133.091428 -437.623204)
		(width 0.14224)
		(layer "In15.Cu")
		(net "P5E_CPU1_P2_RX_BUF_DN<4>")
	)
	(segment
		(start 131.912868 -405.214074)
		(end 131.785614 -405.341328)
		(width 0.14224)
		(layer "In15.Cu")
		(net "P5E_CPU1_P2_RX_BUF_DN<4>")
	)
	(segment
		(start 133.749796 -437.769762)
		(end 133.749796 -438.089802)
		(width 0.14224)
		(layer "In15.Cu")
		(net "P5E_CPU1_P2_RX_BUF_DN<4>")
	)
	(segment
		(start 151.106124 -395.4526)
		(end 150.003764 -396.55496)
		(width 0.14224)
		(layer "In15.Cu")
		(net "P5E_CPU1_P2_RX_BUF_DN<4>")
	)
	(segment
		(start 129.12217 -413.656272)
		(end 132.586984 -417.121086)
		(width 0.14224)
		(layer "In15.Cu")
		(net "P5E_CPU1_P2_RX_BUF_DN<4>")
	)
	(segment
		(start 151.345646 -395.093952)
		(end 151.106124 -395.4526)
		(width 0.14224)
		(layer "In15.Cu")
		(net "P5E_CPU1_P2_RX_BUF_DN<4>")
	)
	(segment
		(start 150.003764 -396.55496)
		(end 149.232112 -397.070326)
		(width 0.14224)
		(layer "In15.Cu")
		(net "P5E_CPU1_P2_RX_BUF_DN<4>")
	)
	(segment
		(start 132.032756 -404.07844)
		(end 132.032756 -404.924514)
		(width 0.14224)
		(layer "In15.Cu")
		(net "P5E_CPU1_P2_RX_BUF_DN<4>")
	)
	(segment
		(start 132.371592 -403.352254)
		(end 132.306568 -403.417278)
		(width 0.14224)
		(layer "In15.Cu")
		(net "P5E_CPU1_P2_RX_BUF_DN<4>")
	)
	(segment
		(start 132.789168 -417.60902)
		(end 132.789168 -437.320944)
		(width 0.14224)
		(layer "In15.Cu")
		(net "P5E_CPU1_P2_RX_BUF_DN<4>")
	)
	(segment
		(start 130.18389 -411.059376)
		(end 129.237232 -411.451806)
		(width 0.14224)
		(layer "In15.Cu")
		(net "P5E_CPU1_P2_RX_BUF_DN<4>")
	)
	(segment
		(start 151.50338 -393.043156)
		(end 151.50338 -394.71346)
		(width 0.14224)
		(layer "In15.Cu")
		(net "P5E_CPU1_P2_RX_BUF_DN<4>")
	)
	(segment
		(start 147.927314 -397.403574)
		(end 145.64106 -398.007078)
		(width 0.14224)
		(layer "In15.Cu")
		(net "P5E_CPU1_P2_RX_BUF_DN<4>")
	)
	(segment
		(start 128.969516 -411.853126)
		(end 128.969516 -413.287464)
		(width 0.14224)
		(layer "In15.Cu")
		(net "P5E_CPU1_P2_RX_BUF_DN<4>")
	)
	(segment
		(start 139.046204 -400.191224)
		(end 133.583934 -402.53158)
		(width 0.14224)
		(layer "In15.Cu")
		(net "P5E_CPU1_P2_RX_BUF_DN<4>")
	)
	(segment
		(start 151.81072 -392.735816)
		(end 151.50338 -393.043156)
		(width 0.14224)
		(layer "In15.Cu")
		(net "P5E_CPU1_P2_RX_BUF_DN<4>")
	)
	(segment
		(start 130.501136 -406.638252)
		(end 130.501136 -410.697426)
		(width 0.14224)
		(layer "In15.Cu")
		(net "P5E_CPU1_P2_RX_BUF_DN<4>")
	)
	(segment
		(start 133.091428 -437.623204)
		(end 133.603238 -437.623204)
		(width 0.14224)
		(layer "In15.Cu")
		(net "P5E_CPU1_P2_RX_BUF_DN<4>")
	)
	(segment
		(start 133.603238 -437.623204)
		(end 133.749796 -437.769762)
		(width 0.14224)
		(layer "In15.Cu")
		(net "P5E_CPU1_P2_RX_BUF_DN<4>")
	)
	(segment
		(start 151.50338 -394.71346)
		(end 151.345646 -395.093952)
		(width 0.14224)
		(layer "In15.Cu")
		(net "P5E_CPU1_P2_RX_BUF_DN<4>")
	)
	(segment
		(start 152.105868 -392.735816)
		(end 151.81072 -392.735816)
		(width 0.14224)
		(layer "In15.Cu")
		(net "P5E_CPU1_P2_RX_BUF_DN<4>")
	)
	(segment
		(start 152.244298 -392.429238)
		(end 152.244298 -392.597386)
		(width 0.14224)
		(layer "In15.Cu")
		(net "P5E_CPU1_P2_RX_BUF_DN<4>")
	)
	(segment
		(start 149.232112 -397.070326)
		(end 148.88845 -397.212566)
		(width 0.14224)
		(layer "In15.Cu")
		(net "P5E_CPU1_P2_RX_BUF_DN<4>")
	)
	(segment
		(start 148.88845 -397.212566)
		(end 147.927314 -397.403574)
		(width 0.14224)
		(layer "In15.Cu")
		(net "P5E_CPU1_P2_RX_BUF_DN<4>")
	)
	(segment
		(start 145.64106 -398.007078)
		(end 139.046204 -400.191224)
		(width 0.14224)
		(layer "In15.Cu")
		(net "P5E_CPU1_P2_RX_BUF_DN<4>")
	)
	(segment
		(start 131.785614 -405.341328)
		(end 131.516374 -405.52116)
		(width 0.14224)
		(layer "In15.Cu")
		(net "P5E_CPU1_P2_RX_BUF_DN<4>")
	)
	(arc
		(start 130.788664 -405.94407)
		(mid 130.575775 -406.262536)
		(end 130.501136 -406.638252)
		(width 0.14224)
		(layer "In15.Cu")
		(net "P5E_CPU1_P2_RX_BUF_DN<4>")
	)
	(arc
		(start 133.583934 -402.53158)
		(mid 132.938608 -402.884073)
		(end 132.371592 -403.352254)
		(width 0.14224)
		(layer "In15.Cu")
		(net "P5E_CPU1_P2_RX_BUF_DN<4>")
	)
	(arc
		(start 130.405632 -410.88818)
		(mid 130.306178 -410.988559)
		(end 130.18389 -411.059376)
		(width 0.14224)
		(layer "In15.Cu")
		(net "P5E_CPU1_P2_RX_BUF_DN<4>")
	)
	(arc
		(start 132.586984 -417.121086)
		(mid 132.73662 -417.344938)
		(end 132.789168 -417.60902)
		(width 0.14224)
		(layer "In15.Cu")
		(net "P5E_CPU1_P2_RX_BUF_DN<4>")
	)
	(arc
		(start 129.237232 -411.451806)
		(mid 129.04256 -411.611905)
		(end 128.969516 -411.853126)
		(width 0.14224)
		(layer "In15.Cu")
		(net "P5E_CPU1_P2_RX_BUF_DN<4>")
	)
	(arc
		(start 132.032756 -404.924514)
		(mid 132.001604 -405.081217)
		(end 131.912868 -405.214074)
		(width 0.14224)
		(layer "In15.Cu")
		(net "P5E_CPU1_P2_RX_BUF_DN<4>")
	)
	(arc
		(start 132.306568 -403.417278)
		(mid 132.103934 -403.720636)
		(end 132.032756 -404.07844)
		(width 0.14224)
		(layer "In15.Cu")
		(net "P5E_CPU1_P2_RX_BUF_DN<4>")
	)
	(arc
		(start 128.969516 -413.287464)
		(mid 129.009195 -413.487033)
		(end 129.12217 -413.656272)
		(width 0.14224)
		(layer "In15.Cu")
		(net "P5E_CPU1_P2_RX_BUF_DN<4>")
	)
	(arc
		(start 131.266438 -405.624538)
		(mid 131.011834 -405.760803)
		(end 130.788664 -405.94407)
		(width 0.14224)
		(layer "In15.Cu")
		(net "P5E_CPU1_P2_RX_BUF_DN<4>")
	)
	(arc
		(start 130.501136 -410.697426)
		(mid 130.475926 -410.804089)
		(end 130.405632 -410.88818)
		(width 0.14224)
		(layer "In15.Cu")
		(net "P5E_CPU1_P2_RX_BUF_DN<4>")
	)
	(segment
		(start 150.645622 -390.761474)
		(end 150.64613 -390.761982)
		(width 0.1016)
		(layer "F.Cu")
		(net "P5E_CPU1_P2_RX_BUF_DN<3>")
	)
	(segment
		(start 150.64613 -390.761982)
		(end 150.64613 -391.578338)
		(width 0.1016)
		(layer "F.Cu")
		(net "P5E_CPU1_P2_RX_BUF_DN<3>")
	)
	(segment
		(start 150.570692 -392.634216)
		(end 150.697692 -392.761216)
		(width 0.1016)
		(layer "F.Cu")
		(net "P5E_CPU1_P2_RX_BUF_DN<3>")
	)
	(segment
		(start 150.903432 -392.761216)
		(end 151.044148 -392.6205)
		(width 0.1016)
		(layer "F.Cu")
		(net "P5E_CPU1_P2_RX_BUF_DN<3>")
	)
	(segment
		(start 150.697692 -392.761216)
		(end 150.903432 -392.761216)
		(width 0.1016)
		(layer "F.Cu")
		(net "P5E_CPU1_P2_RX_BUF_DN<3>")
	)
	(segment
		(start 150.64613 -391.578338)
		(end 150.570692 -391.653776)
		(width 0.1016)
		(layer "F.Cu")
		(net "P5E_CPU1_P2_RX_BUF_DN<3>")
	)
	(segment
		(start 150.570692 -391.653776)
		(end 150.570692 -392.634216)
		(width 0.1016)
		(layer "F.Cu")
		(net "P5E_CPU1_P2_RX_BUF_DN<3>")
	)
	(segment
		(start 151.044148 -392.6205)
		(end 151.044148 -392.429238)
		(width 0.1016)
		(layer "F.Cu")
		(net "P5E_CPU1_P2_RX_BUF_DN<3>")
	)
	(segment
		(start 151.044148 -392.597386)
		(end 151.044148 -392.429238)
		(width 0.14224)
		(layer "In15.Cu")
		(net "P5E_CPU1_P2_RX_BUF_DN<3>")
	)
	(segment
		(start 131.091432 -438.623202)
		(end 130.789172 -438.320942)
		(width 0.14224)
		(layer "In15.Cu")
		(net "P5E_CPU1_P2_RX_BUF_DN<3>")
	)
	(segment
		(start 126.87935 -414.118044)
		(end 126.753874 -414.118044)
		(width 0.14224)
		(layer "In15.Cu")
		(net "P5E_CPU1_P2_RX_BUF_DN<3>")
	)
	(segment
		(start 144.963642 -397.198088)
		(end 148.702014 -396.212568)
		(width 0.14224)
		(layer "In15.Cu")
		(net "P5E_CPU1_P2_RX_BUF_DN<3>")
	)
	(segment
		(start 149.454362 -395.718792)
		(end 150.118318 -395.054836)
		(width 0.14224)
		(layer "In15.Cu")
		(net "P5E_CPU1_P2_RX_BUF_DN<3>")
	)
	(segment
		(start 126.338076 -413.945832)
		(end 126.115826 -413.723582)
		(width 0.14224)
		(layer "In15.Cu")
		(net "P5E_CPU1_P2_RX_BUF_DN<3>")
	)
	(segment
		(start 131.7498 -439.0898)
		(end 131.7498 -438.76976)
		(width 0.14224)
		(layer "In15.Cu")
		(net "P5E_CPU1_P2_RX_BUF_DN<3>")
	)
	(segment
		(start 128.969516 -404.924514)
		(end 128.969516 -403.724618)
		(width 0.14224)
		(layer "In15.Cu")
		(net "P5E_CPU1_P2_RX_BUF_DN<3>")
	)
	(segment
		(start 127.209296 -411.001464)
		(end 127.38608 -410.85262)
		(width 0.14224)
		(layer "In15.Cu")
		(net "P5E_CPU1_P2_RX_BUF_DN<3>")
	)
	(segment
		(start 148.92909 -396.098268)
		(end 149.454362 -395.718792)
		(width 0.14224)
		(layer "In15.Cu")
		(net "P5E_CPU1_P2_RX_BUF_DN<3>")
	)
	(segment
		(start 150.30323 -393.043156)
		(end 150.61057 -392.735816)
		(width 0.14224)
		(layer "In15.Cu")
		(net "P5E_CPU1_P2_RX_BUF_DN<3>")
	)
	(segment
		(start 130.005074 -402.603716)
		(end 139.134596 -399.084038)
		(width 0.14224)
		(layer "In15.Cu")
		(net "P5E_CPU1_P2_RX_BUF_DN<3>")
	)
	(segment
		(start 131.7498 -438.76976)
		(end 131.603242 -438.623202)
		(width 0.14224)
		(layer "In15.Cu")
		(net "P5E_CPU1_P2_RX_BUF_DN<3>")
	)
	(segment
		(start 130.682492 -417.697666)
		(end 127.260858 -414.276032)
		(width 0.14224)
		(layer "In15.Cu")
		(net "P5E_CPU1_P2_RX_BUF_DN<3>")
	)
	(segment
		(start 150.30323 -394.608558)
		(end 150.30323 -393.043156)
		(width 0.14224)
		(layer "In15.Cu")
		(net "P5E_CPU1_P2_RX_BUF_DN<3>")
	)
	(segment
		(start 150.905718 -392.735816)
		(end 151.044148 -392.597386)
		(width 0.14224)
		(layer "In15.Cu")
		(net "P5E_CPU1_P2_RX_BUF_DN<3>")
	)
	(segment
		(start 148.702014 -396.212568)
		(end 148.92909 -396.098268)
		(width 0.14224)
		(layer "In15.Cu")
		(net "P5E_CPU1_P2_RX_BUF_DN<3>")
	)
	(segment
		(start 128.203198 -405.624538)
		(end 128.453134 -405.52116)
		(width 0.14224)
		(layer "In15.Cu")
		(net "P5E_CPU1_P2_RX_BUF_DN<3>")
	)
	(segment
		(start 150.61057 -392.735816)
		(end 150.905718 -392.735816)
		(width 0.14224)
		(layer "In15.Cu")
		(net "P5E_CPU1_P2_RX_BUF_DN<3>")
	)
	(segment
		(start 130.789172 -438.320942)
		(end 130.789172 -417.954968)
		(width 0.14224)
		(layer "In15.Cu")
		(net "P5E_CPU1_P2_RX_BUF_DN<3>")
	)
	(segment
		(start 128.453134 -405.52116)
		(end 128.722374 -405.341328)
		(width 0.14224)
		(layer "In15.Cu")
		(net "P5E_CPU1_P2_RX_BUF_DN<3>")
	)
	(segment
		(start 128.722374 -405.341328)
		(end 128.849628 -405.214074)
		(width 0.14224)
		(layer "In15.Cu")
		(net "P5E_CPU1_P2_RX_BUF_DN<3>")
	)
	(segment
		(start 131.603242 -438.623202)
		(end 131.091432 -438.623202)
		(width 0.14224)
		(layer "In15.Cu")
		(net "P5E_CPU1_P2_RX_BUF_DN<3>")
	)
	(segment
		(start 150.118318 -395.054836)
		(end 150.30323 -394.608558)
		(width 0.14224)
		(layer "In15.Cu")
		(net "P5E_CPU1_P2_RX_BUF_DN<3>")
	)
	(segment
		(start 139.134596 -399.084038)
		(end 144.963642 -397.198088)
		(width 0.14224)
		(layer "In15.Cu")
		(net "P5E_CPU1_P2_RX_BUF_DN<3>")
	)
	(segment
		(start 127.437896 -410.741622)
		(end 127.437896 -406.638252)
		(width 0.14224)
		(layer "In15.Cu")
		(net "P5E_CPU1_P2_RX_BUF_DN<3>")
	)
	(segment
		(start 125.906276 -413.218122)
		(end 125.906276 -411.868112)
		(width 0.14224)
		(layer "In15.Cu")
		(net "P5E_CPU1_P2_RX_BUF_DN<3>")
	)
	(segment
		(start 126.187708 -411.446218)
		(end 127.1016 -411.06725)
		(width 0.14224)
		(layer "In15.Cu")
		(net "P5E_CPU1_P2_RX_BUF_DN<3>")
	)
	(arc
		(start 127.725424 -405.94407)
		(mid 127.948589 -405.760796)
		(end 128.203198 -405.624538)
		(width 0.14224)
		(layer "In15.Cu")
		(net "P5E_CPU1_P2_RX_BUF_DN<3>")
	)
	(arc
		(start 128.969516 -403.724618)
		(mid 129.034587 -403.397866)
		(end 129.219706 -403.12086)
		(width 0.14224)
		(layer "In15.Cu")
		(net "P5E_CPU1_P2_RX_BUF_DN<3>")
	)
	(arc
		(start 126.753874 -414.118044)
		(mid 126.528852 -414.073284)
		(end 126.338076 -413.945832)
		(width 0.14224)
		(layer "In15.Cu")
		(net "P5E_CPU1_P2_RX_BUF_DN<3>")
	)
	(arc
		(start 126.115826 -413.723582)
		(mid 125.960841 -413.491676)
		(end 125.906276 -413.218122)
		(width 0.14224)
		(layer "In15.Cu")
		(net "P5E_CPU1_P2_RX_BUF_DN<3>")
	)
	(arc
		(start 127.260858 -414.276032)
		(mid 127.085806 -414.159129)
		(end 126.87935 -414.118044)
		(width 0.14224)
		(layer "In15.Cu")
		(net "P5E_CPU1_P2_RX_BUF_DN<3>")
	)
	(arc
		(start 127.38608 -410.85262)
		(mid 127.424266 -410.802851)
		(end 127.437896 -410.741622)
		(width 0.14224)
		(layer "In15.Cu")
		(net "P5E_CPU1_P2_RX_BUF_DN<3>")
	)
	(arc
		(start 129.219706 -403.12086)
		(mid 129.591648 -402.830787)
		(end 130.005074 -402.603716)
		(width 0.14224)
		(layer "In15.Cu")
		(net "P5E_CPU1_P2_RX_BUF_DN<3>")
	)
	(arc
		(start 127.1016 -411.06725)
		(mid 127.157969 -411.038487)
		(end 127.209296 -411.001464)
		(width 0.14224)
		(layer "In15.Cu")
		(net "P5E_CPU1_P2_RX_BUF_DN<3>")
	)
	(arc
		(start 125.906276 -411.868112)
		(mid 125.98309 -411.614538)
		(end 126.187708 -411.446218)
		(width 0.14224)
		(layer "In15.Cu")
		(net "P5E_CPU1_P2_RX_BUF_DN<3>")
	)
	(arc
		(start 127.437896 -406.638252)
		(mid 127.512586 -406.262557)
		(end 127.725424 -405.94407)
		(width 0.14224)
		(layer "In15.Cu")
		(net "P5E_CPU1_P2_RX_BUF_DN<3>")
	)
	(arc
		(start 128.849628 -405.214074)
		(mid 128.938343 -405.081209)
		(end 128.969516 -404.924514)
		(width 0.14224)
		(layer "In15.Cu")
		(net "P5E_CPU1_P2_RX_BUF_DN<3>")
	)
	(arc
		(start 130.789172 -417.954968)
		(mid 130.76145 -417.815692)
		(end 130.682492 -417.697666)
		(width 0.14224)
		(layer "In15.Cu")
		(net "P5E_CPU1_P2_RX_BUF_DN<3>")
	)
	(segment
		(start 149.703536 -392.761216)
		(end 149.844252 -392.6205)
		(width 0.1016)
		(layer "F.Cu")
		(net "P5E_CPU1_P2_RX_BUF_DN<2>")
	)
	(segment
		(start 149.445726 -390.761474)
		(end 149.446234 -390.761982)
		(width 0.1016)
		(layer "F.Cu")
		(net "P5E_CPU1_P2_RX_BUF_DN<2>")
	)
	(segment
		(start 149.446234 -390.761982)
		(end 149.446234 -391.578338)
		(width 0.1016)
		(layer "F.Cu")
		(net "P5E_CPU1_P2_RX_BUF_DN<2>")
	)
	(segment
		(start 149.357588 -392.634216)
		(end 149.484588 -392.761216)
		(width 0.1016)
		(layer "F.Cu")
		(net "P5E_CPU1_P2_RX_BUF_DN<2>")
	)
	(segment
		(start 149.446234 -391.578338)
		(end 149.357588 -391.666984)
		(width 0.1016)
		(layer "F.Cu")
		(net "P5E_CPU1_P2_RX_BUF_DN<2>")
	)
	(segment
		(start 149.844252 -392.6205)
		(end 149.844252 -392.429238)
		(width 0.1016)
		(layer "F.Cu")
		(net "P5E_CPU1_P2_RX_BUF_DN<2>")
	)
	(segment
		(start 149.484588 -392.761216)
		(end 149.703536 -392.761216)
		(width 0.1016)
		(layer "F.Cu")
		(net "P5E_CPU1_P2_RX_BUF_DN<2>")
	)
	(segment
		(start 149.357588 -391.666984)
		(end 149.357588 -392.634216)
		(width 0.1016)
		(layer "F.Cu")
		(net "P5E_CPU1_P2_RX_BUF_DN<2>")
	)
	(segment
		(start 125.906276 -404.028402)
		(end 125.906276 -404.924514)
		(width 0.14224)
		(layer "In15.Cu")
		(net "P5E_CPU1_P2_RX_BUF_DN<2>")
	)
	(segment
		(start 149.844252 -392.597386)
		(end 149.705822 -392.735816)
		(width 0.14224)
		(layer "In15.Cu")
		(net "P5E_CPU1_P2_RX_BUF_DN<2>")
	)
	(segment
		(start 140.60424 -397.278606)
		(end 126.572264 -402.928074)
		(width 0.14224)
		(layer "In15.Cu")
		(net "P5E_CPU1_P2_RX_BUF_DN<2>")
	)
	(segment
		(start 124.32157 -410.679392)
		(end 124.116084 -410.884878)
		(width 0.14224)
		(layer "In15.Cu")
		(net "P5E_CPU1_P2_RX_BUF_DN<2>")
	)
	(segment
		(start 125.389894 -405.52116)
		(end 125.139958 -405.624538)
		(width 0.14224)
		(layer "In15.Cu")
		(net "P5E_CPU1_P2_RX_BUF_DN<2>")
	)
	(segment
		(start 148.696934 -395.055344)
		(end 148.206968 -395.317726)
		(width 0.14224)
		(layer "In15.Cu")
		(net "P5E_CPU1_P2_RX_BUF_DN<2>")
	)
	(segment
		(start 126.392686 -403.032214)
		(end 126.214378 -403.173946)
		(width 0.14224)
		(layer "In15.Cu")
		(net "P5E_CPU1_P2_RX_BUF_DN<2>")
	)
	(segment
		(start 123.101354 -413.688784)
		(end 124.613162 -415.200592)
		(width 0.14224)
		(layer "In15.Cu")
		(net "P5E_CPU1_P2_RX_BUF_DN<2>")
	)
	(segment
		(start 148.206968 -395.317726)
		(end 147.935188 -395.429994)
		(width 0.14224)
		(layer "In15.Cu")
		(net "P5E_CPU1_P2_RX_BUF_DN<2>")
	)
	(segment
		(start 125.659134 -405.341328)
		(end 125.389894 -405.52116)
		(width 0.14224)
		(layer "In15.Cu")
		(net "P5E_CPU1_P2_RX_BUF_DN<2>")
	)
	(segment
		(start 149.844252 -392.429238)
		(end 149.844252 -392.597386)
		(width 0.14224)
		(layer "In15.Cu")
		(net "P5E_CPU1_P2_RX_BUF_DN<2>")
	)
	(segment
		(start 148.921978 -394.90523)
		(end 148.696934 -395.055344)
		(width 0.14224)
		(layer "In15.Cu")
		(net "P5E_CPU1_P2_RX_BUF_DN<2>")
	)
	(segment
		(start 123.242578 -411.35808)
		(end 123.100084 -411.508956)
		(width 0.14224)
		(layer "In15.Cu")
		(net "P5E_CPU1_P2_RX_BUF_DN<2>")
	)
	(segment
		(start 126.57709 -415.455862)
		(end 128.751838 -417.63061)
		(width 0.14224)
		(layer "In15.Cu")
		(net "P5E_CPU1_P2_RX_BUF_DN<2>")
	)
	(segment
		(start 149.103334 -393.043156)
		(end 149.103334 -394.565886)
		(width 0.14224)
		(layer "In15.Cu")
		(net "P5E_CPU1_P2_RX_BUF_DN<2>")
	)
	(segment
		(start 149.705822 -392.735816)
		(end 149.410674 -392.735816)
		(width 0.14224)
		(layer "In15.Cu")
		(net "P5E_CPU1_P2_RX_BUF_DN<2>")
	)
	(segment
		(start 128.789176 -417.72078)
		(end 128.789176 -437.320944)
		(width 0.14224)
		(layer "In15.Cu")
		(net "P5E_CPU1_P2_RX_BUF_DN<2>")
	)
	(segment
		(start 125.786388 -405.214074)
		(end 125.659134 -405.341328)
		(width 0.14224)
		(layer "In15.Cu")
		(net "P5E_CPU1_P2_RX_BUF_DN<2>")
	)
	(segment
		(start 129.091436 -437.623204)
		(end 129.603246 -437.623204)
		(width 0.14224)
		(layer "In15.Cu")
		(net "P5E_CPU1_P2_RX_BUF_DN<2>")
	)
	(segment
		(start 147.935188 -395.429994)
		(end 144.708626 -396.174722)
		(width 0.14224)
		(layer "In15.Cu")
		(net "P5E_CPU1_P2_RX_BUF_DN<2>")
	)
	(segment
		(start 129.603246 -437.623204)
		(end 129.749804 -437.769762)
		(width 0.14224)
		(layer "In15.Cu")
		(net "P5E_CPU1_P2_RX_BUF_DN<2>")
	)
	(segment
		(start 126.01448 -403.475444)
		(end 125.949964 -403.707854)
		(width 0.14224)
		(layer "In15.Cu")
		(net "P5E_CPU1_P2_RX_BUF_DN<2>")
	)
	(segment
		(start 129.749804 -437.769762)
		(end 129.749804 -438.089802)
		(width 0.14224)
		(layer "In15.Cu")
		(net "P5E_CPU1_P2_RX_BUF_DN<2>")
	)
	(segment
		(start 124.374656 -406.638252)
		(end 124.374656 -410.551122)
		(width 0.14224)
		(layer "In15.Cu")
		(net "P5E_CPU1_P2_RX_BUF_DN<2>")
	)
	(segment
		(start 128.789176 -437.320944)
		(end 129.091436 -437.623204)
		(width 0.14224)
		(layer "In15.Cu")
		(net "P5E_CPU1_P2_RX_BUF_DN<2>")
	)
	(segment
		(start 124.970286 -415.34842)
		(end 126.317756 -415.34842)
		(width 0.14224)
		(layer "In15.Cu")
		(net "P5E_CPU1_P2_RX_BUF_DN<2>")
	)
	(segment
		(start 144.708626 -396.174722)
		(end 140.60424 -397.278606)
		(width 0.14224)
		(layer "In15.Cu")
		(net "P5E_CPU1_P2_RX_BUF_DN<2>")
	)
	(segment
		(start 149.103334 -394.565886)
		(end 148.921978 -394.90523)
		(width 0.14224)
		(layer "In15.Cu")
		(net "P5E_CPU1_P2_RX_BUF_DN<2>")
	)
	(segment
		(start 123.830588 -411.075886)
		(end 123.38431 -411.260798)
		(width 0.14224)
		(layer "In15.Cu")
		(net "P5E_CPU1_P2_RX_BUF_DN<2>")
	)
	(segment
		(start 149.410674 -392.735816)
		(end 149.103334 -393.043156)
		(width 0.14224)
		(layer "In15.Cu")
		(net "P5E_CPU1_P2_RX_BUF_DN<2>")
	)
	(segment
		(start 122.843036 -412.155386)
		(end 122.843036 -413.06496)
		(width 0.14224)
		(layer "In15.Cu")
		(net "P5E_CPU1_P2_RX_BUF_DN<2>")
	)
	(arc
		(start 125.139958 -405.624538)
		(mid 124.885354 -405.760803)
		(end 124.662184 -405.94407)
		(width 0.14224)
		(layer "In15.Cu")
		(net "P5E_CPU1_P2_RX_BUF_DN<2>")
	)
	(arc
		(start 124.613162 -415.200592)
		(mid 124.777026 -415.310019)
		(end 124.970286 -415.34842)
		(width 0.14224)
		(layer "In15.Cu")
		(net "P5E_CPU1_P2_RX_BUF_DN<2>")
	)
	(arc
		(start 128.751838 -417.63061)
		(mid 128.779481 -417.67198)
		(end 128.789176 -417.72078)
		(width 0.14224)
		(layer "In15.Cu")
		(net "P5E_CPU1_P2_RX_BUF_DN<2>")
	)
	(arc
		(start 122.843036 -413.06496)
		(mid 122.91017 -413.402555)
		(end 123.101354 -413.688784)
		(width 0.14224)
		(layer "In15.Cu")
		(net "P5E_CPU1_P2_RX_BUF_DN<2>")
	)
	(arc
		(start 124.116084 -410.884878)
		(mid 123.982726 -410.994419)
		(end 123.830588 -411.075886)
		(width 0.14224)
		(layer "In15.Cu")
		(net "P5E_CPU1_P2_RX_BUF_DN<2>")
	)
	(arc
		(start 124.374656 -410.551122)
		(mid 124.360866 -410.620538)
		(end 124.32157 -410.679392)
		(width 0.14224)
		(layer "In15.Cu")
		(net "P5E_CPU1_P2_RX_BUF_DN<2>")
	)
	(arc
		(start 126.572264 -402.928074)
		(mid 126.478713 -402.973656)
		(end 126.392686 -403.032214)
		(width 0.14224)
		(layer "In15.Cu")
		(net "P5E_CPU1_P2_RX_BUF_DN<2>")
	)
	(arc
		(start 123.100084 -411.508956)
		(mid 122.909611 -411.807531)
		(end 122.843036 -412.155386)
		(width 0.14224)
		(layer "In15.Cu")
		(net "P5E_CPU1_P2_RX_BUF_DN<2>")
	)
	(arc
		(start 126.317756 -415.34842)
		(mid 126.458115 -415.376339)
		(end 126.57709 -415.455862)
		(width 0.14224)
		(layer "In15.Cu")
		(net "P5E_CPU1_P2_RX_BUF_DN<2>")
	)
	(arc
		(start 124.662184 -405.94407)
		(mid 124.449295 -406.262536)
		(end 124.374656 -406.638252)
		(width 0.14224)
		(layer "In15.Cu")
		(net "P5E_CPU1_P2_RX_BUF_DN<2>")
	)
	(arc
		(start 126.214378 -403.173946)
		(mid 126.090573 -403.308876)
		(end 126.01448 -403.475444)
		(width 0.14224)
		(layer "In15.Cu")
		(net "P5E_CPU1_P2_RX_BUF_DN<2>")
	)
	(arc
		(start 125.906276 -404.924514)
		(mid 125.875124 -405.081217)
		(end 125.786388 -405.214074)
		(width 0.14224)
		(layer "In15.Cu")
		(net "P5E_CPU1_P2_RX_BUF_DN<2>")
	)
	(arc
		(start 125.949964 -403.707854)
		(mid 125.917207 -403.866642)
		(end 125.906276 -404.028402)
		(width 0.14224)
		(layer "In15.Cu")
		(net "P5E_CPU1_P2_RX_BUF_DN<2>")
	)
	(arc
		(start 123.38431 -411.260798)
		(mid 123.308325 -411.30198)
		(end 123.242578 -411.35808)
		(width 0.14224)
		(layer "In15.Cu")
		(net "P5E_CPU1_P2_RX_BUF_DN<2>")
	)
	(segment
		(start 148.157438 -392.634216)
		(end 148.284438 -392.761216)
		(width 0.1016)
		(layer "F.Cu")
		(net "P5E_CPU1_P2_RX_BUF_DN<1>")
	)
	(segment
		(start 148.246084 -390.761982)
		(end 148.246084 -391.578338)
		(width 0.1016)
		(layer "F.Cu")
		(net "P5E_CPU1_P2_RX_BUF_DN<1>")
	)
	(segment
		(start 148.246084 -391.578338)
		(end 148.157438 -391.666984)
		(width 0.1016)
		(layer "F.Cu")
		(net "P5E_CPU1_P2_RX_BUF_DN<1>")
	)
	(segment
		(start 148.284438 -392.761216)
		(end 148.503386 -392.761216)
		(width 0.1016)
		(layer "F.Cu")
		(net "P5E_CPU1_P2_RX_BUF_DN<1>")
	)
	(segment
		(start 148.503386 -392.761216)
		(end 148.644102 -392.6205)
		(width 0.1016)
		(layer "F.Cu")
		(net "P5E_CPU1_P2_RX_BUF_DN<1>")
	)
	(segment
		(start 148.245576 -390.761474)
		(end 148.246084 -390.761982)
		(width 0.1016)
		(layer "F.Cu")
		(net "P5E_CPU1_P2_RX_BUF_DN<1>")
	)
	(segment
		(start 148.157438 -391.666984)
		(end 148.157438 -392.634216)
		(width 0.1016)
		(layer "F.Cu")
		(net "P5E_CPU1_P2_RX_BUF_DN<1>")
	)
	(segment
		(start 148.644102 -392.6205)
		(end 148.644102 -392.429238)
		(width 0.1016)
		(layer "F.Cu")
		(net "P5E_CPU1_P2_RX_BUF_DN<1>")
	)
	(segment
		(start 122.843036 -403.989286)
		(end 122.843036 -404.924514)
		(width 0.14224)
		(layer "In15.Cu")
		(net "P5E_CPU1_P2_RX_BUF_DN<1>")
	)
	(segment
		(start 126.78918 -417.459922)
		(end 126.78918 -438.325768)
		(width 0.14224)
		(layer "In15.Cu")
		(net "P5E_CPU1_P2_RX_BUF_DN<1>")
	)
	(segment
		(start 137.676636 -397.260826)
		(end 123.39066 -403.170136)
		(width 0.14224)
		(layer "In15.Cu")
		(net "P5E_CPU1_P2_RX_BUF_DN<1>")
	)
	(segment
		(start 127.749808 -438.76976)
		(end 127.749808 -439.0898)
		(width 0.14224)
		(layer "In15.Cu")
		(net "P5E_CPU1_P2_RX_BUF_DN<1>")
	)
	(segment
		(start 121.311416 -406.638252)
		(end 121.311416 -410.697426)
		(width 0.14224)
		(layer "In15.Cu")
		(net "P5E_CPU1_P2_RX_BUF_DN<1>")
	)
	(segment
		(start 127.08255 -438.619138)
		(end 127.599186 -438.619138)
		(width 0.14224)
		(layer "In15.Cu")
		(net "P5E_CPU1_P2_RX_BUF_DN<1>")
	)
	(segment
		(start 147.779486 -394.47978)
		(end 147.711668 -394.510006)
		(width 0.14224)
		(layer "In15.Cu")
		(net "P5E_CPU1_P2_RX_BUF_DN<1>")
	)
	(segment
		(start 119.779796 -411.846014)
		(end 119.779796 -413.234378)
		(width 0.14224)
		(layer "In15.Cu")
		(net "P5E_CPU1_P2_RX_BUF_DN<1>")
	)
	(segment
		(start 119.925592 -413.586422)
		(end 123.021852 -416.682682)
		(width 0.14224)
		(layer "In15.Cu")
		(net "P5E_CPU1_P2_RX_BUF_DN<1>")
	)
	(segment
		(start 126.436374 -416.947096)
		(end 126.67615 -417.186872)
		(width 0.14224)
		(layer "In15.Cu")
		(net "P5E_CPU1_P2_RX_BUF_DN<1>")
	)
	(segment
		(start 122.595894 -405.341328)
		(end 122.326654 -405.52116)
		(width 0.14224)
		(layer "In15.Cu")
		(net "P5E_CPU1_P2_RX_BUF_DN<1>")
	)
	(segment
		(start 147.903184 -393.043156)
		(end 147.903184 -394.373354)
		(width 0.14224)
		(layer "In15.Cu")
		(net "P5E_CPU1_P2_RX_BUF_DN<1>")
	)
	(segment
		(start 123.419108 -416.847274)
		(end 126.195582 -416.847274)
		(width 0.14224)
		(layer "In15.Cu")
		(net "P5E_CPU1_P2_RX_BUF_DN<1>")
	)
	(segment
		(start 148.644102 -392.429238)
		(end 148.644102 -392.597386)
		(width 0.14224)
		(layer "In15.Cu")
		(net "P5E_CPU1_P2_RX_BUF_DN<1>")
	)
	(segment
		(start 143.377412 -395.495018)
		(end 140.59408 -396.2781)
		(width 0.14224)
		(layer "In15.Cu")
		(net "P5E_CPU1_P2_RX_BUF_DN<1>")
	)
	(segment
		(start 122.326654 -405.52116)
		(end 122.076718 -405.624538)
		(width 0.14224)
		(layer "In15.Cu")
		(net "P5E_CPU1_P2_RX_BUF_DN<1>")
	)
	(segment
		(start 148.644102 -392.597386)
		(end 148.505672 -392.735816)
		(width 0.14224)
		(layer "In15.Cu")
		(net "P5E_CPU1_P2_RX_BUF_DN<1>")
	)
	(segment
		(start 126.78918 -438.325768)
		(end 127.08255 -438.619138)
		(width 0.14224)
		(layer "In15.Cu")
		(net "P5E_CPU1_P2_RX_BUF_DN<1>")
	)
	(segment
		(start 140.59408 -396.2781)
		(end 137.676636 -397.260826)
		(width 0.14224)
		(layer "In15.Cu")
		(net "P5E_CPU1_P2_RX_BUF_DN<1>")
	)
	(segment
		(start 148.210524 -392.735816)
		(end 147.903184 -393.043156)
		(width 0.14224)
		(layer "In15.Cu")
		(net "P5E_CPU1_P2_RX_BUF_DN<1>")
	)
	(segment
		(start 121.265442 -410.812234)
		(end 121.097802 -410.988256)
		(width 0.14224)
		(layer "In15.Cu")
		(net "P5E_CPU1_P2_RX_BUF_DN<1>")
	)
	(segment
		(start 127.599186 -438.619138)
		(end 127.749808 -438.76976)
		(width 0.14224)
		(layer "In15.Cu")
		(net "P5E_CPU1_P2_RX_BUF_DN<1>")
	)
	(segment
		(start 147.711668 -394.510006)
		(end 143.377412 -395.495018)
		(width 0.14224)
		(layer "In15.Cu")
		(net "P5E_CPU1_P2_RX_BUF_DN<1>")
	)
	(segment
		(start 147.903184 -394.373354)
		(end 147.779486 -394.47978)
		(width 0.14224)
		(layer "In15.Cu")
		(net "P5E_CPU1_P2_RX_BUF_DN<1>")
	)
	(segment
		(start 122.723148 -405.214074)
		(end 122.595894 -405.341328)
		(width 0.14224)
		(layer "In15.Cu")
		(net "P5E_CPU1_P2_RX_BUF_DN<1>")
	)
	(segment
		(start 120.99417 -411.059376)
		(end 120.041416 -411.454346)
		(width 0.14224)
		(layer "In15.Cu")
		(net "P5E_CPU1_P2_RX_BUF_DN<1>")
	)
	(segment
		(start 148.505672 -392.735816)
		(end 148.210524 -392.735816)
		(width 0.14224)
		(layer "In15.Cu")
		(net "P5E_CPU1_P2_RX_BUF_DN<1>")
	)
	(arc
		(start 121.097802 -410.988256)
		(mid 121.049713 -411.029248)
		(end 120.99417 -411.059376)
		(width 0.14224)
		(layer "In15.Cu")
		(net "P5E_CPU1_P2_RX_BUF_DN<1>")
	)
	(arc
		(start 119.779796 -413.234378)
		(mid 119.817692 -413.424893)
		(end 119.925592 -413.586422)
		(width 0.14224)
		(layer "In15.Cu")
		(net "P5E_CPU1_P2_RX_BUF_DN<1>")
	)
	(arc
		(start 126.195582 -416.847274)
		(mid 126.325915 -416.873217)
		(end 126.436374 -416.947096)
		(width 0.14224)
		(layer "In15.Cu")
		(net "P5E_CPU1_P2_RX_BUF_DN<1>")
	)
	(arc
		(start 121.598944 -405.94407)
		(mid 121.386055 -406.262536)
		(end 121.311416 -406.638252)
		(width 0.14224)
		(layer "In15.Cu")
		(net "P5E_CPU1_P2_RX_BUF_DN<1>")
	)
	(arc
		(start 122.843036 -404.924514)
		(mid 122.811884 -405.081217)
		(end 122.723148 -405.214074)
		(width 0.14224)
		(layer "In15.Cu")
		(net "P5E_CPU1_P2_RX_BUF_DN<1>")
	)
	(arc
		(start 126.67615 -417.186872)
		(mid 126.759803 -417.312163)
		(end 126.78918 -417.459922)
		(width 0.14224)
		(layer "In15.Cu")
		(net "P5E_CPU1_P2_RX_BUF_DN<1>")
	)
	(arc
		(start 123.39066 -403.170136)
		(mid 122.992549 -403.496614)
		(end 122.843036 -403.989286)
		(width 0.14224)
		(layer "In15.Cu")
		(net "P5E_CPU1_P2_RX_BUF_DN<1>")
	)
	(arc
		(start 120.041416 -411.454346)
		(mid 119.851178 -411.610478)
		(end 119.779796 -411.846014)
		(width 0.14224)
		(layer "In15.Cu")
		(net "P5E_CPU1_P2_RX_BUF_DN<1>")
	)
	(arc
		(start 123.021852 -416.682682)
		(mid 123.2041 -416.80452)
		(end 123.419108 -416.847274)
		(width 0.14224)
		(layer "In15.Cu")
		(net "P5E_CPU1_P2_RX_BUF_DN<1>")
	)
	(arc
		(start 122.076718 -405.624538)
		(mid 121.822114 -405.760803)
		(end 121.598944 -405.94407)
		(width 0.14224)
		(layer "In15.Cu")
		(net "P5E_CPU1_P2_RX_BUF_DN<1>")
	)
	(arc
		(start 121.311416 -410.697426)
		(mid 121.299497 -410.759263)
		(end 121.265442 -410.812234)
		(width 0.14224)
		(layer "In15.Cu")
		(net "P5E_CPU1_P2_RX_BUF_DN<1>")
	)
	(segment
		(start 165.44417 -392.429238)
		(end 165.44417 -392.599926)
		(width 0.1016)
		(layer "F.Cu")
		(net "P5E_CPU1_P2_RX_BUF_DN<15>")
	)
	(segment
		(start 165.44417 -392.599926)
		(end 165.28288 -392.761216)
		(width 0.1016)
		(layer "F.Cu")
		(net "P5E_CPU1_P2_RX_BUF_DN<15>")
	)
	(segment
		(start 165.046152 -391.578338)
		(end 165.046152 -390.761982)
		(width 0.1016)
		(layer "F.Cu")
		(net "P5E_CPU1_P2_RX_BUF_DN<15>")
	)
	(segment
		(start 165.046152 -390.761982)
		(end 165.045644 -390.761474)
		(width 0.1016)
		(layer "F.Cu")
		(net "P5E_CPU1_P2_RX_BUF_DN<15>")
	)
	(segment
		(start 164.957506 -391.666984)
		(end 165.046152 -391.578338)
		(width 0.1016)
		(layer "F.Cu")
		(net "P5E_CPU1_P2_RX_BUF_DN<15>")
	)
	(segment
		(start 165.084506 -392.761216)
		(end 164.957506 -392.634216)
		(width 0.1016)
		(layer "F.Cu")
		(net "P5E_CPU1_P2_RX_BUF_DN<15>")
	)
	(segment
		(start 164.957506 -392.634216)
		(end 164.957506 -391.666984)
		(width 0.1016)
		(layer "F.Cu")
		(net "P5E_CPU1_P2_RX_BUF_DN<15>")
	)
	(segment
		(start 165.28288 -392.761216)
		(end 165.084506 -392.761216)
		(width 0.1016)
		(layer "F.Cu")
		(net "P5E_CPU1_P2_RX_BUF_DN<15>")
	)
	(segment
		(start 165.44417 -392.597386)
		(end 165.44417 -392.429238)
		(width 0.14224)
		(layer "In15.Cu")
		(net "P5E_CPU1_P2_RX_BUF_DN<15>")
	)
	(segment
		(start 155.99156 -420.889176)
		(end 163.395152 -413.485584)
		(width 0.14224)
		(layer "In15.Cu")
		(net "P5E_CPU1_P2_RX_BUF_DN<15>")
	)
	(segment
		(start 156.750004 -438.76976)
		(end 156.603446 -438.623202)
		(width 0.14224)
		(layer "In15.Cu")
		(net "P5E_CPU1_P2_RX_BUF_DN<15>")
	)
	(segment
		(start 163.786312 -411.500066)
		(end 163.908994 -411.222952)
		(width 0.14224)
		(layer "In15.Cu")
		(net "P5E_CPU1_P2_RX_BUF_DN<15>")
	)
	(segment
		(start 156.750004 -439.0898)
		(end 156.750004 -438.76976)
		(width 0.14224)
		(layer "In15.Cu")
		(net "P5E_CPU1_P2_RX_BUF_DN<15>")
	)
	(segment
		(start 163.6649 -412.834328)
		(end 163.6649 -412.074614)
		(width 0.14224)
		(layer "In15.Cu")
		(net "P5E_CPU1_P2_RX_BUF_DN<15>")
	)
	(segment
		(start 155.789122 -438.320688)
		(end 155.789122 -421.378126)
		(width 0.14224)
		(layer "In15.Cu")
		(net "P5E_CPU1_P2_RX_BUF_DN<15>")
	)
	(segment
		(start 156.091636 -438.623202)
		(end 155.789122 -438.320688)
		(width 0.14224)
		(layer "In15.Cu")
		(net "P5E_CPU1_P2_RX_BUF_DN<15>")
	)
	(segment
		(start 163.908994 -411.222952)
		(end 163.909248 -411.222952)
		(width 0.14224)
		(layer "In15.Cu")
		(net "P5E_CPU1_P2_RX_BUF_DN<15>")
	)
	(segment
		(start 165.30574 -392.735816)
		(end 165.44417 -392.597386)
		(width 0.14224)
		(layer "In15.Cu")
		(net "P5E_CPU1_P2_RX_BUF_DN<15>")
	)
	(segment
		(start 164.612574 -409.635706)
		(end 164.703252 -409.207716)
		(width 0.14224)
		(layer "In15.Cu")
		(net "P5E_CPU1_P2_RX_BUF_DN<15>")
	)
	(segment
		(start 163.909248 -411.222952)
		(end 164.612574 -409.635706)
		(width 0.14224)
		(layer "In15.Cu")
		(net "P5E_CPU1_P2_RX_BUF_DN<15>")
	)
	(segment
		(start 164.703252 -393.043156)
		(end 165.010592 -392.735816)
		(width 0.14224)
		(layer "In15.Cu")
		(net "P5E_CPU1_P2_RX_BUF_DN<15>")
	)
	(segment
		(start 165.010592 -392.735816)
		(end 165.30574 -392.735816)
		(width 0.14224)
		(layer "In15.Cu")
		(net "P5E_CPU1_P2_RX_BUF_DN<15>")
	)
	(segment
		(start 156.603446 -438.623202)
		(end 156.091636 -438.623202)
		(width 0.14224)
		(layer "In15.Cu")
		(net "P5E_CPU1_P2_RX_BUF_DN<15>")
	)
	(segment
		(start 164.703252 -409.207716)
		(end 164.703252 -393.043156)
		(width 0.14224)
		(layer "In15.Cu")
		(net "P5E_CPU1_P2_RX_BUF_DN<15>")
	)
	(arc
		(start 163.395152 -413.485584)
		(mid 163.594803 -413.186785)
		(end 163.6649 -412.834328)
		(width 0.14224)
		(layer "In15.Cu")
		(net "P5E_CPU1_P2_RX_BUF_DN<15>")
	)
	(arc
		(start 155.789122 -421.378126)
		(mid 155.841736 -421.113529)
		(end 155.99156 -420.889176)
		(width 0.14224)
		(layer "In15.Cu")
		(net "P5E_CPU1_P2_RX_BUF_DN<15>")
	)
	(arc
		(start 163.6649 -412.074614)
		(mid 163.695521 -411.78098)
		(end 163.786312 -411.500066)
		(width 0.14224)
		(layer "In15.Cu")
		(net "P5E_CPU1_P2_RX_BUF_DN<15>")
	)
	(segment
		(start 163.846256 -390.761982)
		(end 163.845748 -390.761474)
		(width 0.1016)
		(layer "F.Cu")
		(net "P5E_CPU1_P2_RX_BUF_DN<14>")
	)
	(segment
		(start 164.244274 -392.429238)
		(end 164.244274 -392.59383)
		(width 0.1016)
		(layer "F.Cu")
		(net "P5E_CPU1_P2_RX_BUF_DN<14>")
	)
	(segment
		(start 163.75761 -391.666984)
		(end 163.846256 -391.578338)
		(width 0.1016)
		(layer "F.Cu")
		(net "P5E_CPU1_P2_RX_BUF_DN<14>")
	)
	(segment
		(start 164.076888 -392.761216)
		(end 163.88461 -392.761216)
		(width 0.1016)
		(layer "F.Cu")
		(net "P5E_CPU1_P2_RX_BUF_DN<14>")
	)
	(segment
		(start 164.244274 -392.59383)
		(end 164.076888 -392.761216)
		(width 0.1016)
		(layer "F.Cu")
		(net "P5E_CPU1_P2_RX_BUF_DN<14>")
	)
	(segment
		(start 163.75761 -392.634216)
		(end 163.75761 -391.666984)
		(width 0.1016)
		(layer "F.Cu")
		(net "P5E_CPU1_P2_RX_BUF_DN<14>")
	)
	(segment
		(start 163.846256 -391.578338)
		(end 163.846256 -390.761982)
		(width 0.1016)
		(layer "F.Cu")
		(net "P5E_CPU1_P2_RX_BUF_DN<14>")
	)
	(segment
		(start 163.88461 -392.761216)
		(end 163.75761 -392.634216)
		(width 0.1016)
		(layer "F.Cu")
		(net "P5E_CPU1_P2_RX_BUF_DN<14>")
	)
	(segment
		(start 163.503356 -393.043156)
		(end 163.503356 -395.553692)
		(width 0.14224)
		(layer "In15.Cu")
		(net "P5E_CPU1_P2_RX_BUF_DN<14>")
	)
	(segment
		(start 161.133536 -406.637998)
		(end 161.133536 -410.697426)
		(width 0.14224)
		(layer "In15.Cu")
		(net "P5E_CPU1_P2_RX_BUF_DN<14>")
	)
	(segment
		(start 154.09164 -437.623204)
		(end 154.60345 -437.623204)
		(width 0.14224)
		(layer "In15.Cu")
		(net "P5E_CPU1_P2_RX_BUF_DN<14>")
	)
	(segment
		(start 164.244274 -392.597386)
		(end 164.105844 -392.735816)
		(width 0.14224)
		(layer "In15.Cu")
		(net "P5E_CPU1_P2_RX_BUF_DN<14>")
	)
	(segment
		(start 154.60345 -437.623204)
		(end 154.750008 -437.769762)
		(width 0.14224)
		(layer "In15.Cu")
		(net "P5E_CPU1_P2_RX_BUF_DN<14>")
	)
	(segment
		(start 162.437064 -405.345392)
		(end 161.513266 -405.857202)
		(width 0.14224)
		(layer "In15.Cu")
		(net "P5E_CPU1_P2_RX_BUF_DN<14>")
	)
	(segment
		(start 154.750008 -437.769762)
		(end 154.750008 -438.089802)
		(width 0.14224)
		(layer "In15.Cu")
		(net "P5E_CPU1_P2_RX_BUF_DN<14>")
	)
	(segment
		(start 164.244274 -392.429238)
		(end 164.244274 -392.597386)
		(width 0.14224)
		(layer "In15.Cu")
		(net "P5E_CPU1_P2_RX_BUF_DN<14>")
	)
	(segment
		(start 164.105844 -392.735816)
		(end 163.810696 -392.735816)
		(width 0.14224)
		(layer "In15.Cu")
		(net "P5E_CPU1_P2_RX_BUF_DN<14>")
	)
	(segment
		(start 161.087562 -410.812234)
		(end 160.919922 -410.988256)
		(width 0.14224)
		(layer "In15.Cu")
		(net "P5E_CPU1_P2_RX_BUF_DN<14>")
	)
	(segment
		(start 160.81629 -411.059376)
		(end 159.863536 -411.454346)
		(width 0.14224)
		(layer "In15.Cu")
		(net "P5E_CPU1_P2_RX_BUF_DN<14>")
	)
	(segment
		(start 153.789126 -421.171878)
		(end 153.789126 -437.32069)
		(width 0.14224)
		(layer "In15.Cu")
		(net "P5E_CPU1_P2_RX_BUF_DN<14>")
	)
	(segment
		(start 163.810696 -392.735816)
		(end 163.503356 -393.043156)
		(width 0.14224)
		(layer "In15.Cu")
		(net "P5E_CPU1_P2_RX_BUF_DN<14>")
	)
	(segment
		(start 163.41979 -397.25346)
		(end 162.655758 -405.013414)
		(width 0.14224)
		(layer "In15.Cu")
		(net "P5E_CPU1_P2_RX_BUF_DN<14>")
	)
	(segment
		(start 153.789126 -437.32069)
		(end 154.09164 -437.623204)
		(width 0.14224)
		(layer "In15.Cu")
		(net "P5E_CPU1_P2_RX_BUF_DN<14>")
	)
	(segment
		(start 159.4231 -415.057844)
		(end 154.12847 -420.352474)
		(width 0.14224)
		(layer "In15.Cu")
		(net "P5E_CPU1_P2_RX_BUF_DN<14>")
	)
	(segment
		(start 159.601916 -411.846014)
		(end 159.601916 -414.626298)
		(width 0.14224)
		(layer "In15.Cu")
		(net "P5E_CPU1_P2_RX_BUF_DN<14>")
	)
	(arc
		(start 162.655758 -405.013414)
		(mid 162.587337 -405.206382)
		(end 162.437064 -405.345392)
		(width 0.14224)
		(layer "In15.Cu")
		(net "P5E_CPU1_P2_RX_BUF_DN<14>")
	)
	(arc
		(start 160.919922 -410.988256)
		(mid 160.871833 -411.029248)
		(end 160.81629 -411.059376)
		(width 0.14224)
		(layer "In15.Cu")
		(net "P5E_CPU1_P2_RX_BUF_DN<14>")
	)
	(arc
		(start 161.513266 -405.857202)
		(mid 161.408954 -405.931808)
		(end 161.32429 -406.028144)
		(width 0.14224)
		(layer "In15.Cu")
		(net "P5E_CPU1_P2_RX_BUF_DN<14>")
	)
	(arc
		(start 161.32429 -406.028144)
		(mid 161.182254 -406.318482)
		(end 161.133536 -406.637998)
		(width 0.14224)
		(layer "In15.Cu")
		(net "P5E_CPU1_P2_RX_BUF_DN<14>")
	)
	(arc
		(start 163.503356 -395.553692)
		(mid 163.482435 -396.404602)
		(end 163.41979 -397.25346)
		(width 0.14224)
		(layer "In15.Cu")
		(net "P5E_CPU1_P2_RX_BUF_DN<14>")
	)
	(arc
		(start 159.863536 -411.454346)
		(mid 159.673298 -411.610478)
		(end 159.601916 -411.846014)
		(width 0.14224)
		(layer "In15.Cu")
		(net "P5E_CPU1_P2_RX_BUF_DN<14>")
	)
	(arc
		(start 154.12847 -420.352474)
		(mid 153.877325 -420.728434)
		(end 153.789126 -421.171878)
		(width 0.14224)
		(layer "In15.Cu")
		(net "P5E_CPU1_P2_RX_BUF_DN<14>")
	)
	(arc
		(start 161.133536 -410.697426)
		(mid 161.121617 -410.759263)
		(end 161.087562 -410.812234)
		(width 0.14224)
		(layer "In15.Cu")
		(net "P5E_CPU1_P2_RX_BUF_DN<14>")
	)
	(arc
		(start 159.601916 -414.626298)
		(mid 159.55544 -414.859859)
		(end 159.4231 -415.057844)
		(width 0.14224)
		(layer "In15.Cu")
		(net "P5E_CPU1_P2_RX_BUF_DN<14>")
	)
	(segment
		(start 162.566096 -391.658348)
		(end 162.566096 -392.634216)
		(width 0.1016)
		(layer "F.Cu")
		(net "P5E_CPU1_P2_RX_BUF_DN<13>")
	)
	(segment
		(start 162.693096 -392.761216)
		(end 162.903408 -392.761216)
		(width 0.1016)
		(layer "F.Cu")
		(net "P5E_CPU1_P2_RX_BUF_DN<13>")
	)
	(segment
		(start 162.566096 -392.634216)
		(end 162.693096 -392.761216)
		(width 0.1016)
		(layer "F.Cu")
		(net "P5E_CPU1_P2_RX_BUF_DN<13>")
	)
	(segment
		(start 163.044124 -392.6205)
		(end 163.044124 -392.429238)
		(width 0.1016)
		(layer "F.Cu")
		(net "P5E_CPU1_P2_RX_BUF_DN<13>")
	)
	(segment
		(start 162.646106 -391.578338)
		(end 162.566096 -391.658348)
		(width 0.1016)
		(layer "F.Cu")
		(net "P5E_CPU1_P2_RX_BUF_DN<13>")
	)
	(segment
		(start 162.903408 -392.761216)
		(end 163.044124 -392.6205)
		(width 0.1016)
		(layer "F.Cu")
		(net "P5E_CPU1_P2_RX_BUF_DN<13>")
	)
	(segment
		(start 162.645598 -390.761474)
		(end 162.646106 -390.761982)
		(width 0.1016)
		(layer "F.Cu")
		(net "P5E_CPU1_P2_RX_BUF_DN<13>")
	)
	(segment
		(start 162.646106 -390.761982)
		(end 162.646106 -391.578338)
		(width 0.1016)
		(layer "F.Cu")
		(net "P5E_CPU1_P2_RX_BUF_DN<13>")
	)
	(segment
		(start 162.905694 -392.735816)
		(end 162.610546 -392.735816)
		(width 0.14224)
		(layer "In15.Cu")
		(net "P5E_CPU1_P2_RX_BUF_DN<13>")
	)
	(segment
		(start 163.044124 -392.429238)
		(end 163.044124 -392.597386)
		(width 0.14224)
		(layer "In15.Cu")
		(net "P5E_CPU1_P2_RX_BUF_DN<13>")
	)
	(segment
		(start 159.085534 -405.52116)
		(end 158.835598 -405.624538)
		(width 0.14224)
		(layer "In15.Cu")
		(net "P5E_CPU1_P2_RX_BUF_DN<13>")
	)
	(segment
		(start 152.09647 -438.623202)
		(end 152.603454 -438.623202)
		(width 0.14224)
		(layer "In15.Cu")
		(net "P5E_CPU1_P2_RX_BUF_DN<13>")
	)
	(segment
		(start 156.277818 -414.35528)
		(end 152.158954 -418.474144)
		(width 0.14224)
		(layer "In15.Cu")
		(net "P5E_CPU1_P2_RX_BUF_DN<13>")
	)
	(segment
		(start 159.354774 -405.341328)
		(end 159.085534 -405.52116)
		(width 0.14224)
		(layer "In15.Cu")
		(net "P5E_CPU1_P2_RX_BUF_DN<13>")
	)
	(segment
		(start 162.610546 -392.735816)
		(end 162.303206 -393.043156)
		(width 0.14224)
		(layer "In15.Cu")
		(net "P5E_CPU1_P2_RX_BUF_DN<13>")
	)
	(segment
		(start 161.721292 -396.556484)
		(end 160.201356 -400.804126)
		(width 0.14224)
		(layer "In15.Cu")
		(net "P5E_CPU1_P2_RX_BUF_DN<13>")
	)
	(segment
		(start 162.000438 -395.77645)
		(end 161.721292 -396.556484)
		(width 0.14224)
		(layer "In15.Cu")
		(net "P5E_CPU1_P2_RX_BUF_DN<13>")
	)
	(segment
		(start 152.750012 -438.76976)
		(end 152.750012 -439.0898)
		(width 0.14224)
		(layer "In15.Cu")
		(net "P5E_CPU1_P2_RX_BUF_DN<13>")
	)
	(segment
		(start 156.538676 -411.846014)
		(end 156.538676 -413.725614)
		(width 0.14224)
		(layer "In15.Cu")
		(net "P5E_CPU1_P2_RX_BUF_DN<13>")
	)
	(segment
		(start 160.156652 -400.965924)
		(end 159.644842 -403.539452)
		(width 0.14224)
		(layer "In15.Cu")
		(net "P5E_CPU1_P2_RX_BUF_DN<13>")
	)
	(segment
		(start 159.482028 -405.214074)
		(end 159.354774 -405.341328)
		(width 0.14224)
		(layer "In15.Cu")
		(net "P5E_CPU1_P2_RX_BUF_DN<13>")
	)
	(segment
		(start 158.070296 -406.638252)
		(end 158.070296 -410.697426)
		(width 0.14224)
		(layer "In15.Cu")
		(net "P5E_CPU1_P2_RX_BUF_DN<13>")
	)
	(segment
		(start 159.601916 -403.975316)
		(end 159.601916 -404.924514)
		(width 0.14224)
		(layer "In15.Cu")
		(net "P5E_CPU1_P2_RX_BUF_DN<13>")
	)
	(segment
		(start 162.303206 -393.043156)
		(end 162.303206 -394.262864)
		(width 0.14224)
		(layer "In15.Cu")
		(net "P5E_CPU1_P2_RX_BUF_DN<13>")
	)
	(segment
		(start 158.024322 -410.812234)
		(end 157.856682 -410.988256)
		(width 0.14224)
		(layer "In15.Cu")
		(net "P5E_CPU1_P2_RX_BUF_DN<13>")
	)
	(segment
		(start 151.78913 -419.366954)
		(end 151.78913 -438.315862)
		(width 0.14224)
		(layer "In15.Cu")
		(net "P5E_CPU1_P2_RX_BUF_DN<13>")
	)
	(segment
		(start 152.603454 -438.623202)
		(end 152.750012 -438.76976)
		(width 0.14224)
		(layer "In15.Cu")
		(net "P5E_CPU1_P2_RX_BUF_DN<13>")
	)
	(segment
		(start 162.29711 -394.325856)
		(end 162.033204 -395.65326)
		(width 0.14224)
		(layer "In15.Cu")
		(net "P5E_CPU1_P2_RX_BUF_DN<13>")
	)
	(segment
		(start 162.000946 -395.774926)
		(end 162.000438 -395.77645)
		(width 0.14224)
		(layer "In15.Cu")
		(net "P5E_CPU1_P2_RX_BUF_DN<13>")
	)
	(segment
		(start 163.044124 -392.597386)
		(end 162.905694 -392.735816)
		(width 0.14224)
		(layer "In15.Cu")
		(net "P5E_CPU1_P2_RX_BUF_DN<13>")
	)
	(segment
		(start 157.75305 -411.059376)
		(end 156.800296 -411.454346)
		(width 0.14224)
		(layer "In15.Cu")
		(net "P5E_CPU1_P2_RX_BUF_DN<13>")
	)
	(segment
		(start 151.78913 -438.315862)
		(end 152.09647 -438.623202)
		(width 0.14224)
		(layer "In15.Cu")
		(net "P5E_CPU1_P2_RX_BUF_DN<13>")
	)
	(arc
		(start 158.070296 -410.697426)
		(mid 158.058377 -410.759263)
		(end 158.024322 -410.812234)
		(width 0.14224)
		(layer "In15.Cu")
		(net "P5E_CPU1_P2_RX_BUF_DN<13>")
	)
	(arc
		(start 159.644842 -403.539452)
		(mid 159.612683 -403.75633)
		(end 159.601916 -403.975316)
		(width 0.14224)
		(layer "In15.Cu")
		(net "P5E_CPU1_P2_RX_BUF_DN<13>")
	)
	(arc
		(start 160.201356 -400.804126)
		(mid 160.176033 -400.884204)
		(end 160.156652 -400.965924)
		(width 0.14224)
		(layer "In15.Cu")
		(net "P5E_CPU1_P2_RX_BUF_DN<13>")
	)
	(arc
		(start 157.856682 -410.988256)
		(mid 157.808593 -411.029248)
		(end 157.75305 -411.059376)
		(width 0.14224)
		(layer "In15.Cu")
		(net "P5E_CPU1_P2_RX_BUF_DN<13>")
	)
	(arc
		(start 152.158954 -418.474144)
		(mid 151.885252 -418.883769)
		(end 151.78913 -419.366954)
		(width 0.14224)
		(layer "In15.Cu")
		(net "P5E_CPU1_P2_RX_BUF_DN<13>")
	)
	(arc
		(start 156.800296 -411.454346)
		(mid 156.610058 -411.610478)
		(end 156.538676 -411.846014)
		(width 0.14224)
		(layer "In15.Cu")
		(net "P5E_CPU1_P2_RX_BUF_DN<13>")
	)
	(arc
		(start 158.357824 -405.94407)
		(mid 158.144935 -406.262536)
		(end 158.070296 -406.638252)
		(width 0.14224)
		(layer "In15.Cu")
		(net "P5E_CPU1_P2_RX_BUF_DN<13>")
	)
	(arc
		(start 156.538676 -413.725614)
		(mid 156.470874 -414.066389)
		(end 156.277818 -414.35528)
		(width 0.14224)
		(layer "In15.Cu")
		(net "P5E_CPU1_P2_RX_BUF_DN<13>")
	)
	(arc
		(start 162.033204 -395.65326)
		(mid 162.018975 -395.714597)
		(end 162.000946 -395.774926)
		(width 0.14224)
		(layer "In15.Cu")
		(net "P5E_CPU1_P2_RX_BUF_DN<13>")
	)
	(arc
		(start 159.601916 -404.924514)
		(mid 159.570764 -405.081217)
		(end 159.482028 -405.214074)
		(width 0.14224)
		(layer "In15.Cu")
		(net "P5E_CPU1_P2_RX_BUF_DN<13>")
	)
	(arc
		(start 158.835598 -405.624538)
		(mid 158.580994 -405.760803)
		(end 158.357824 -405.94407)
		(width 0.14224)
		(layer "In15.Cu")
		(net "P5E_CPU1_P2_RX_BUF_DN<13>")
	)
	(arc
		(start 162.303206 -394.262864)
		(mid 162.301701 -394.294509)
		(end 162.29711 -394.325856)
		(width 0.14224)
		(layer "In15.Cu")
		(net "P5E_CPU1_P2_RX_BUF_DN<13>")
	)
	(segment
		(start 161.844228 -392.429238)
		(end 161.844228 -392.595862)
		(width 0.1016)
		(layer "F.Cu")
		(net "P5E_CPU1_P2_RX_BUF_DN<12>")
	)
	(segment
		(start 161.844228 -392.595862)
		(end 161.678874 -392.761216)
		(width 0.1016)
		(layer "F.Cu")
		(net "P5E_CPU1_P2_RX_BUF_DN<12>")
	)
	(segment
		(start 161.678874 -392.761216)
		(end 161.484564 -392.761216)
		(width 0.1016)
		(layer "F.Cu")
		(net "P5E_CPU1_P2_RX_BUF_DN<12>")
	)
	(segment
		(start 161.44621 -391.578338)
		(end 161.44621 -390.761982)
		(width 0.1016)
		(layer "F.Cu")
		(net "P5E_CPU1_P2_RX_BUF_DN<12>")
	)
	(segment
		(start 161.357564 -391.666984)
		(end 161.44621 -391.578338)
		(width 0.1016)
		(layer "F.Cu")
		(net "P5E_CPU1_P2_RX_BUF_DN<12>")
	)
	(segment
		(start 161.44621 -390.761982)
		(end 161.445702 -390.761474)
		(width 0.1016)
		(layer "F.Cu")
		(net "P5E_CPU1_P2_RX_BUF_DN<12>")
	)
	(segment
		(start 161.357564 -392.634216)
		(end 161.357564 -391.666984)
		(width 0.1016)
		(layer "F.Cu")
		(net "P5E_CPU1_P2_RX_BUF_DN<12>")
	)
	(segment
		(start 161.484564 -392.761216)
		(end 161.357564 -392.634216)
		(width 0.1016)
		(layer "F.Cu")
		(net "P5E_CPU1_P2_RX_BUF_DN<12>")
	)
	(segment
		(start 154.688794 -411.060138)
		(end 153.737056 -411.454346)
		(width 0.14224)
		(layer "In15.Cu")
		(net "P5E_CPU1_P2_RX_BUF_DN<12>")
	)
	(segment
		(start 161.705798 -392.735816)
		(end 161.41065 -392.735816)
		(width 0.14224)
		(layer "In15.Cu")
		(net "P5E_CPU1_P2_RX_BUF_DN<12>")
	)
	(segment
		(start 161.10331 -393.043156)
		(end 161.10331 -395.14399)
		(width 0.14224)
		(layer "In15.Cu")
		(net "P5E_CPU1_P2_RX_BUF_DN<12>")
	)
	(segment
		(start 150.091648 -437.623204)
		(end 150.603458 -437.623204)
		(width 0.14224)
		(layer "In15.Cu")
		(net "P5E_CPU1_P2_RX_BUF_DN<12>")
	)
	(segment
		(start 160.017714 -397.493236)
		(end 159.649668 -398.18183)
		(width 0.14224)
		(layer "In15.Cu")
		(net "P5E_CPU1_P2_RX_BUF_DN<12>")
	)
	(segment
		(start 150.750016 -437.769762)
		(end 150.750016 -438.089802)
		(width 0.14224)
		(layer "In15.Cu")
		(net "P5E_CPU1_P2_RX_BUF_DN<12>")
	)
	(segment
		(start 159.159956 -399.046192)
		(end 156.692854 -403.162262)
		(width 0.14224)
		(layer "In15.Cu")
		(net "P5E_CPU1_P2_RX_BUF_DN<12>")
	)
	(segment
		(start 156.613606 -403.387814)
		(end 156.549852 -403.85492)
		(width 0.14224)
		(layer "In15.Cu")
		(net "P5E_CPU1_P2_RX_BUF_DN<12>")
	)
	(segment
		(start 156.022294 -405.52116)
		(end 155.772358 -405.624538)
		(width 0.14224)
		(layer "In15.Cu")
		(net "P5E_CPU1_P2_RX_BUF_DN<12>")
	)
	(segment
		(start 156.538676 -404.019004)
		(end 156.538676 -404.924514)
		(width 0.14224)
		(layer "In15.Cu")
		(net "P5E_CPU1_P2_RX_BUF_DN<12>")
	)
	(segment
		(start 150.603458 -437.623204)
		(end 150.750016 -437.769762)
		(width 0.14224)
		(layer "In15.Cu")
		(net "P5E_CPU1_P2_RX_BUF_DN<12>")
	)
	(segment
		(start 160.017968 -397.493236)
		(end 160.017714 -397.493236)
		(width 0.14224)
		(layer "In15.Cu")
		(net "P5E_CPU1_P2_RX_BUF_DN<12>")
	)
	(segment
		(start 160.410652 -396.757398)
		(end 160.017968 -397.493236)
		(width 0.14224)
		(layer "In15.Cu")
		(net "P5E_CPU1_P2_RX_BUF_DN<12>")
	)
	(segment
		(start 154.961082 -410.812234)
		(end 154.793442 -410.988256)
		(width 0.14224)
		(layer "In15.Cu")
		(net "P5E_CPU1_P2_RX_BUF_DN<12>")
	)
	(segment
		(start 161.844228 -392.597386)
		(end 161.705798 -392.735816)
		(width 0.14224)
		(layer "In15.Cu")
		(net "P5E_CPU1_P2_RX_BUF_DN<12>")
	)
	(segment
		(start 149.789134 -437.32069)
		(end 150.091648 -437.623204)
		(width 0.14224)
		(layer "In15.Cu")
		(net "P5E_CPU1_P2_RX_BUF_DN<12>")
	)
	(segment
		(start 149.789134 -418.173916)
		(end 149.789134 -437.32069)
		(width 0.14224)
		(layer "In15.Cu")
		(net "P5E_CPU1_P2_RX_BUF_DN<12>")
	)
	(segment
		(start 156.291534 -405.341328)
		(end 156.022294 -405.52116)
		(width 0.14224)
		(layer "In15.Cu")
		(net "P5E_CPU1_P2_RX_BUF_DN<12>")
	)
	(segment
		(start 161.844228 -392.429238)
		(end 161.844228 -392.597386)
		(width 0.14224)
		(layer "In15.Cu")
		(net "P5E_CPU1_P2_RX_BUF_DN<12>")
	)
	(segment
		(start 161.10331 -395.14399)
		(end 160.603692 -396.349982)
		(width 0.14224)
		(layer "In15.Cu")
		(net "P5E_CPU1_P2_RX_BUF_DN<12>")
	)
	(segment
		(start 161.41065 -392.735816)
		(end 161.10331 -393.043156)
		(width 0.14224)
		(layer "In15.Cu")
		(net "P5E_CPU1_P2_RX_BUF_DN<12>")
	)
	(segment
		(start 153.201116 -414.268158)
		(end 150.13813 -417.331144)
		(width 0.14224)
		(layer "In15.Cu")
		(net "P5E_CPU1_P2_RX_BUF_DN<12>")
	)
	(segment
		(start 153.475436 -411.84576)
		(end 153.475436 -413.606234)
		(width 0.14224)
		(layer "In15.Cu")
		(net "P5E_CPU1_P2_RX_BUF_DN<12>")
	)
	(segment
		(start 156.418788 -405.214074)
		(end 156.291534 -405.341328)
		(width 0.14224)
		(layer "In15.Cu")
		(net "P5E_CPU1_P2_RX_BUF_DN<12>")
	)
	(segment
		(start 155.007056 -406.638252)
		(end 155.007056 -410.697426)
		(width 0.14224)
		(layer "In15.Cu")
		(net "P5E_CPU1_P2_RX_BUF_DN<12>")
	)
	(arc
		(start 153.737056 -411.454346)
		(mid 153.546899 -411.610393)
		(end 153.475436 -411.84576)
		(width 0.14224)
		(layer "In15.Cu")
		(net "P5E_CPU1_P2_RX_BUF_DN<12>")
	)
	(arc
		(start 150.13813 -417.331144)
		(mid 149.879821 -417.717825)
		(end 149.789134 -418.173916)
		(width 0.14224)
		(layer "In15.Cu")
		(net "P5E_CPU1_P2_RX_BUF_DN<12>")
	)
	(arc
		(start 156.692854 -403.162262)
		(mid 156.641791 -403.271019)
		(end 156.613606 -403.387814)
		(width 0.14224)
		(layer "In15.Cu")
		(net "P5E_CPU1_P2_RX_BUF_DN<12>")
	)
	(arc
		(start 160.603692 -396.349982)
		(mid 160.512159 -396.556053)
		(end 160.410652 -396.757398)
		(width 0.14224)
		(layer "In15.Cu")
		(net "P5E_CPU1_P2_RX_BUF_DN<12>")
	)
	(arc
		(start 153.475436 -413.606234)
		(mid 153.404139 -413.964491)
		(end 153.201116 -414.268158)
		(width 0.14224)
		(layer "In15.Cu")
		(net "P5E_CPU1_P2_RX_BUF_DN<12>")
	)
	(arc
		(start 154.793442 -410.988256)
		(mid 154.7449 -411.029708)
		(end 154.688794 -411.060138)
		(width 0.14224)
		(layer "In15.Cu")
		(net "P5E_CPU1_P2_RX_BUF_DN<12>")
	)
	(arc
		(start 159.649668 -398.18183)
		(mid 159.410123 -398.61702)
		(end 159.159956 -399.046192)
		(width 0.14224)
		(layer "In15.Cu")
		(net "P5E_CPU1_P2_RX_BUF_DN<12>")
	)
	(arc
		(start 156.549852 -403.85492)
		(mid 156.541487 -403.936773)
		(end 156.538676 -404.019004)
		(width 0.14224)
		(layer "In15.Cu")
		(net "P5E_CPU1_P2_RX_BUF_DN<12>")
	)
	(arc
		(start 156.538676 -404.924514)
		(mid 156.507524 -405.081217)
		(end 156.418788 -405.214074)
		(width 0.14224)
		(layer "In15.Cu")
		(net "P5E_CPU1_P2_RX_BUF_DN<12>")
	)
	(arc
		(start 155.294584 -405.94407)
		(mid 155.081695 -406.262536)
		(end 155.007056 -406.638252)
		(width 0.14224)
		(layer "In15.Cu")
		(net "P5E_CPU1_P2_RX_BUF_DN<12>")
	)
	(arc
		(start 155.007056 -410.697426)
		(mid 154.995137 -410.759263)
		(end 154.961082 -410.812234)
		(width 0.14224)
		(layer "In15.Cu")
		(net "P5E_CPU1_P2_RX_BUF_DN<12>")
	)
	(arc
		(start 155.772358 -405.624538)
		(mid 155.517754 -405.760803)
		(end 155.294584 -405.94407)
		(width 0.14224)
		(layer "In15.Cu")
		(net "P5E_CPU1_P2_RX_BUF_DN<12>")
	)
	(segment
		(start 160.644332 -392.429238)
		(end 160.644332 -392.620246)
		(width 0.1016)
		(layer "F.Cu")
		(net "P5E_CPU1_P2_RX_BUF_DN<11>")
	)
	(segment
		(start 160.157414 -391.666984)
		(end 160.24606 -391.578338)
		(width 0.1016)
		(layer "F.Cu")
		(net "P5E_CPU1_P2_RX_BUF_DN<11>")
	)
	(segment
		(start 160.644332 -392.620246)
		(end 160.503362 -392.761216)
		(width 0.1016)
		(layer "F.Cu")
		(net "P5E_CPU1_P2_RX_BUF_DN<11>")
	)
	(segment
		(start 160.157414 -392.634216)
		(end 160.157414 -391.666984)
		(width 0.1016)
		(layer "F.Cu")
		(net "P5E_CPU1_P2_RX_BUF_DN<11>")
	)
	(segment
		(start 160.24606 -391.578338)
		(end 160.24606 -390.761728)
		(width 0.1016)
		(layer "F.Cu")
		(net "P5E_CPU1_P2_RX_BUF_DN<11>")
	)
	(segment
		(start 160.24606 -390.761728)
		(end 160.245806 -390.761474)
		(width 0.1016)
		(layer "F.Cu")
		(net "P5E_CPU1_P2_RX_BUF_DN<11>")
	)
	(segment
		(start 160.284414 -392.761216)
		(end 160.157414 -392.634216)
		(width 0.1016)
		(layer "F.Cu")
		(net "P5E_CPU1_P2_RX_BUF_DN<11>")
	)
	(segment
		(start 160.503362 -392.761216)
		(end 160.284414 -392.761216)
		(width 0.1016)
		(layer "F.Cu")
		(net "P5E_CPU1_P2_RX_BUF_DN<11>")
	)
	(segment
		(start 150.218902 -414.827212)
		(end 148.131784 -416.91433)
		(width 0.14224)
		(layer "In15.Cu")
		(net "P5E_CPU1_P2_RX_BUF_DN<11>")
	)
	(segment
		(start 147.789138 -417.741608)
		(end 147.789138 -438.320688)
		(width 0.14224)
		(layer "In15.Cu")
		(net "P5E_CPU1_P2_RX_BUF_DN<11>")
	)
	(segment
		(start 160.210754 -392.735816)
		(end 159.903414 -393.043156)
		(width 0.14224)
		(layer "In15.Cu")
		(net "P5E_CPU1_P2_RX_BUF_DN<11>")
	)
	(segment
		(start 152.959054 -405.52116)
		(end 152.709118 -405.624538)
		(width 0.14224)
		(layer "In15.Cu")
		(net "P5E_CPU1_P2_RX_BUF_DN<11>")
	)
	(segment
		(start 157.208982 -399.465038)
		(end 153.750264 -403.281134)
		(width 0.14224)
		(layer "In15.Cu")
		(net "P5E_CPU1_P2_RX_BUF_DN<11>")
	)
	(segment
		(start 159.657034 -395.994382)
		(end 158.09722 -398.328134)
		(width 0.14224)
		(layer "In15.Cu")
		(net "P5E_CPU1_P2_RX_BUF_DN<11>")
	)
	(segment
		(start 148.75002 -438.76976)
		(end 148.75002 -439.0898)
		(width 0.14224)
		(layer "In15.Cu")
		(net "P5E_CPU1_P2_RX_BUF_DN<11>")
	)
	(segment
		(start 153.635202 -403.450806)
		(end 153.5684 -403.587458)
		(width 0.14224)
		(layer "In15.Cu")
		(net "P5E_CPU1_P2_RX_BUF_DN<11>")
	)
	(segment
		(start 153.355548 -405.214074)
		(end 153.228294 -405.341328)
		(width 0.14224)
		(layer "In15.Cu")
		(net "P5E_CPU1_P2_RX_BUF_DN<11>")
	)
	(segment
		(start 153.475436 -404.08733)
		(end 153.475436 -404.924514)
		(width 0.14224)
		(layer "In15.Cu")
		(net "P5E_CPU1_P2_RX_BUF_DN<11>")
	)
	(segment
		(start 160.505902 -392.735816)
		(end 160.210754 -392.735816)
		(width 0.14224)
		(layer "In15.Cu")
		(net "P5E_CPU1_P2_RX_BUF_DN<11>")
	)
	(segment
		(start 153.228294 -405.341328)
		(end 152.959054 -405.52116)
		(width 0.14224)
		(layer "In15.Cu")
		(net "P5E_CPU1_P2_RX_BUF_DN<11>")
	)
	(segment
		(start 147.789138 -438.320688)
		(end 148.091652 -438.623202)
		(width 0.14224)
		(layer "In15.Cu")
		(net "P5E_CPU1_P2_RX_BUF_DN<11>")
	)
	(segment
		(start 148.091652 -438.623202)
		(end 148.603462 -438.623202)
		(width 0.14224)
		(layer "In15.Cu")
		(net "P5E_CPU1_P2_RX_BUF_DN<11>")
	)
	(segment
		(start 150.412196 -411.94863)
		(end 150.412196 -414.360614)
		(width 0.14224)
		(layer "In15.Cu")
		(net "P5E_CPU1_P2_RX_BUF_DN<11>")
	)
	(segment
		(start 160.644332 -392.597386)
		(end 160.505902 -392.735816)
		(width 0.14224)
		(layer "In15.Cu")
		(net "P5E_CPU1_P2_RX_BUF_DN<11>")
	)
	(segment
		(start 151.660098 -411.045406)
		(end 150.768558 -411.41523)
		(width 0.14224)
		(layer "In15.Cu")
		(net "P5E_CPU1_P2_RX_BUF_DN<11>")
	)
	(segment
		(start 153.528776 -403.707346)
		(end 153.491438 -403.910038)
		(width 0.14224)
		(layer "In15.Cu")
		(net "P5E_CPU1_P2_RX_BUF_DN<11>")
	)
	(segment
		(start 151.943816 -406.638252)
		(end 151.943816 -410.621226)
		(width 0.14224)
		(layer "In15.Cu")
		(net "P5E_CPU1_P2_RX_BUF_DN<11>")
	)
	(segment
		(start 148.603462 -438.623202)
		(end 148.75002 -438.76976)
		(width 0.14224)
		(layer "In15.Cu")
		(net "P5E_CPU1_P2_RX_BUF_DN<11>")
	)
	(segment
		(start 159.903414 -393.043156)
		(end 159.903414 -395.18209)
		(width 0.14224)
		(layer "In15.Cu")
		(net "P5E_CPU1_P2_RX_BUF_DN<11>")
	)
	(segment
		(start 159.903414 -395.18209)
		(end 159.657034 -395.994382)
		(width 0.14224)
		(layer "In15.Cu")
		(net "P5E_CPU1_P2_RX_BUF_DN<11>")
	)
	(segment
		(start 160.644332 -392.429238)
		(end 160.644332 -392.597386)
		(width 0.14224)
		(layer "In15.Cu")
		(net "P5E_CPU1_P2_RX_BUF_DN<11>")
	)
	(arc
		(start 150.768558 -411.41523)
		(mid 150.509469 -411.627879)
		(end 150.412196 -411.94863)
		(width 0.14224)
		(layer "In15.Cu")
		(net "P5E_CPU1_P2_RX_BUF_DN<11>")
	)
	(arc
		(start 158.09722 -398.328134)
		(mid 157.674131 -398.913016)
		(end 157.208982 -399.465038)
		(width 0.14224)
		(layer "In15.Cu")
		(net "P5E_CPU1_P2_RX_BUF_DN<11>")
	)
	(arc
		(start 152.709118 -405.624538)
		(mid 152.454514 -405.760803)
		(end 152.231344 -405.94407)
		(width 0.14224)
		(layer "In15.Cu")
		(net "P5E_CPU1_P2_RX_BUF_DN<11>")
	)
	(arc
		(start 152.231344 -405.94407)
		(mid 152.018455 -406.262536)
		(end 151.943816 -406.638252)
		(width 0.14224)
		(layer "In15.Cu")
		(net "P5E_CPU1_P2_RX_BUF_DN<11>")
	)
	(arc
		(start 153.475436 -404.924514)
		(mid 153.444284 -405.081217)
		(end 153.355548 -405.214074)
		(width 0.14224)
		(layer "In15.Cu")
		(net "P5E_CPU1_P2_RX_BUF_DN<11>")
	)
	(arc
		(start 151.943816 -410.621226)
		(mid 151.866276 -410.876325)
		(end 151.660098 -411.045406)
		(width 0.14224)
		(layer "In15.Cu")
		(net "P5E_CPU1_P2_RX_BUF_DN<11>")
	)
	(arc
		(start 150.412196 -414.360614)
		(mid 150.361965 -414.613144)
		(end 150.218902 -414.827212)
		(width 0.14224)
		(layer "In15.Cu")
		(net "P5E_CPU1_P2_RX_BUF_DN<11>")
	)
	(arc
		(start 153.491438 -403.910038)
		(mid 153.479403 -403.998319)
		(end 153.475436 -404.08733)
		(width 0.14224)
		(layer "In15.Cu")
		(net "P5E_CPU1_P2_RX_BUF_DN<11>")
	)
	(arc
		(start 153.5684 -403.587458)
		(mid 153.544491 -403.646048)
		(end 153.528776 -403.707346)
		(width 0.14224)
		(layer "In15.Cu")
		(net "P5E_CPU1_P2_RX_BUF_DN<11>")
	)
	(arc
		(start 148.131784 -416.91433)
		(mid 147.878171 -417.293888)
		(end 147.789138 -417.741608)
		(width 0.14224)
		(layer "In15.Cu")
		(net "P5E_CPU1_P2_RX_BUF_DN<11>")
	)
	(arc
		(start 153.750264 -403.281134)
		(mid 153.686763 -403.361922)
		(end 153.635202 -403.450806)
		(width 0.14224)
		(layer "In15.Cu")
		(net "P5E_CPU1_P2_RX_BUF_DN<11>")
	)
	(segment
		(start 159.084518 -392.761216)
		(end 158.957518 -392.634216)
		(width 0.1016)
		(layer "F.Cu")
		(net "P5E_CPU1_P2_RX_BUF_DN<10>")
	)
	(segment
		(start 159.045656 -391.578846)
		(end 159.045656 -390.761474)
		(width 0.1016)
		(layer "F.Cu")
		(net "P5E_CPU1_P2_RX_BUF_DN<10>")
	)
	(segment
		(start 158.957518 -391.666984)
		(end 159.045656 -391.578846)
		(width 0.1016)
		(layer "F.Cu")
		(net "P5E_CPU1_P2_RX_BUF_DN<10>")
	)
	(segment
		(start 158.957518 -392.634216)
		(end 158.957518 -391.666984)
		(width 0.1016)
		(layer "F.Cu")
		(net "P5E_CPU1_P2_RX_BUF_DN<10>")
	)
	(segment
		(start 159.303466 -392.761216)
		(end 159.084518 -392.761216)
		(width 0.1016)
		(layer "F.Cu")
		(net "P5E_CPU1_P2_RX_BUF_DN<10>")
	)
	(segment
		(start 159.444436 -392.620246)
		(end 159.303466 -392.761216)
		(width 0.1016)
		(layer "F.Cu")
		(net "P5E_CPU1_P2_RX_BUF_DN<10>")
	)
	(segment
		(start 159.444436 -392.429238)
		(end 159.444436 -392.620246)
		(width 0.1016)
		(layer "F.Cu")
		(net "P5E_CPU1_P2_RX_BUF_DN<10>")
	)
	(segment
		(start 146.096482 -437.623204)
		(end 146.603466 -437.623204)
		(width 0.14224)
		(layer "In15.Cu")
		(net "P5E_CPU1_P2_RX_BUF_DN<10>")
	)
	(segment
		(start 146.750024 -437.769762)
		(end 146.750024 -438.089802)
		(width 0.14224)
		(layer "In15.Cu")
		(net "P5E_CPU1_P2_RX_BUF_DN<10>")
	)
	(segment
		(start 159.444436 -392.597386)
		(end 159.306006 -392.735816)
		(width 0.14224)
		(layer "In15.Cu")
		(net "P5E_CPU1_P2_RX_BUF_DN<10>")
	)
	(segment
		(start 150.292308 -405.214074)
		(end 150.165054 -405.341328)
		(width 0.14224)
		(layer "In15.Cu")
		(net "P5E_CPU1_P2_RX_BUF_DN<10>")
	)
	(segment
		(start 158.703518 -393.043156)
		(end 158.703518 -395.4907)
		(width 0.14224)
		(layer "In15.Cu")
		(net "P5E_CPU1_P2_RX_BUF_DN<10>")
	)
	(segment
		(start 159.306006 -392.735816)
		(end 159.010858 -392.735816)
		(width 0.14224)
		(layer "In15.Cu")
		(net "P5E_CPU1_P2_RX_BUF_DN<10>")
	)
	(segment
		(start 150.534624 -403.706838)
		(end 150.462488 -403.869652)
		(width 0.14224)
		(layer "In15.Cu")
		(net "P5E_CPU1_P2_RX_BUF_DN<10>")
	)
	(segment
		(start 145.789142 -437.315864)
		(end 146.096482 -437.623204)
		(width 0.14224)
		(layer "In15.Cu")
		(net "P5E_CPU1_P2_RX_BUF_DN<10>")
	)
	(segment
		(start 147.089368 -415.233612)
		(end 146.198844 -416.124136)
		(width 0.14224)
		(layer "In15.Cu")
		(net "P5E_CPU1_P2_RX_BUF_DN<10>")
	)
	(segment
		(start 149.895814 -405.52116)
		(end 149.645878 -405.624538)
		(width 0.14224)
		(layer "In15.Cu")
		(net "P5E_CPU1_P2_RX_BUF_DN<10>")
	)
	(segment
		(start 147.348956 -411.955996)
		(end 147.348956 -414.60674)
		(width 0.14224)
		(layer "In15.Cu")
		(net "P5E_CPU1_P2_RX_BUF_DN<10>")
	)
	(segment
		(start 148.56333 -411.059376)
		(end 147.711922 -411.412436)
		(width 0.14224)
		(layer "In15.Cu")
		(net "P5E_CPU1_P2_RX_BUF_DN<10>")
	)
	(segment
		(start 154.128724 -400.962876)
		(end 151.85771 -402.515324)
		(width 0.14224)
		(layer "In15.Cu")
		(net "P5E_CPU1_P2_RX_BUF_DN<10>")
	)
	(segment
		(start 150.165054 -405.341328)
		(end 149.895814 -405.52116)
		(width 0.14224)
		(layer "In15.Cu")
		(net "P5E_CPU1_P2_RX_BUF_DN<10>")
	)
	(segment
		(start 146.603466 -437.623204)
		(end 146.750024 -437.769762)
		(width 0.14224)
		(layer "In15.Cu")
		(net "P5E_CPU1_P2_RX_BUF_DN<10>")
	)
	(segment
		(start 151.736552 -402.606002)
		(end 151.437594 -402.851366)
		(width 0.14224)
		(layer "In15.Cu")
		(net "P5E_CPU1_P2_RX_BUF_DN<10>")
	)
	(segment
		(start 159.010858 -392.735816)
		(end 158.703518 -393.043156)
		(width 0.14224)
		(layer "In15.Cu")
		(net "P5E_CPU1_P2_RX_BUF_DN<10>")
	)
	(segment
		(start 156.565854 -398.525746)
		(end 154.128724 -400.962876)
		(width 0.14224)
		(layer "In15.Cu")
		(net "P5E_CPU1_P2_RX_BUF_DN<10>")
	)
	(segment
		(start 159.444436 -392.429238)
		(end 159.444436 -392.597386)
		(width 0.14224)
		(layer "In15.Cu")
		(net "P5E_CPU1_P2_RX_BUF_DN<10>")
	)
	(segment
		(start 158.703518 -395.4907)
		(end 156.565854 -398.525746)
		(width 0.14224)
		(layer "In15.Cu")
		(net "P5E_CPU1_P2_RX_BUF_DN<10>")
	)
	(segment
		(start 145.789142 -417.113466)
		(end 145.789142 -437.315864)
		(width 0.14224)
		(layer "In15.Cu")
		(net "P5E_CPU1_P2_RX_BUF_DN<10>")
	)
	(segment
		(start 148.880576 -406.638252)
		(end 148.880576 -410.697426)
		(width 0.14224)
		(layer "In15.Cu")
		(net "P5E_CPU1_P2_RX_BUF_DN<10>")
	)
	(segment
		(start 150.412196 -404.106634)
		(end 150.412196 -404.924514)
		(width 0.14224)
		(layer "In15.Cu")
		(net "P5E_CPU1_P2_RX_BUF_DN<10>")
	)
	(arc
		(start 150.412196 -404.924514)
		(mid 150.381044 -405.081217)
		(end 150.292308 -405.214074)
		(width 0.14224)
		(layer "In15.Cu")
		(net "P5E_CPU1_P2_RX_BUF_DN<10>")
	)
	(arc
		(start 148.880576 -410.697426)
		(mid 148.859137 -410.804557)
		(end 148.79828 -410.895292)
		(width 0.14224)
		(layer "In15.Cu")
		(net "P5E_CPU1_P2_RX_BUF_DN<10>")
	)
	(arc
		(start 151.1173 -403.119844)
		(mid 150.895306 -403.313196)
		(end 150.676356 -403.509988)
		(width 0.14224)
		(layer "In15.Cu")
		(net "P5E_CPU1_P2_RX_BUF_DN<10>")
	)
	(arc
		(start 150.676356 -403.509988)
		(mid 150.595258 -403.601048)
		(end 150.534624 -403.706838)
		(width 0.14224)
		(layer "In15.Cu")
		(net "P5E_CPU1_P2_RX_BUF_DN<10>")
	)
	(arc
		(start 147.348956 -414.60674)
		(mid 147.281493 -414.945988)
		(end 147.089368 -415.233612)
		(width 0.14224)
		(layer "In15.Cu")
		(net "P5E_CPU1_P2_RX_BUF_DN<10>")
	)
	(arc
		(start 149.645878 -405.624538)
		(mid 149.391274 -405.760803)
		(end 149.168104 -405.94407)
		(width 0.14224)
		(layer "In15.Cu")
		(net "P5E_CPU1_P2_RX_BUF_DN<10>")
	)
	(arc
		(start 151.437594 -402.851366)
		(mid 151.276736 -402.984757)
		(end 151.1173 -403.119844)
		(width 0.14224)
		(layer "In15.Cu")
		(net "P5E_CPU1_P2_RX_BUF_DN<10>")
	)
	(arc
		(start 148.79828 -410.895292)
		(mid 148.689702 -410.990071)
		(end 148.56333 -411.059376)
		(width 0.14224)
		(layer "In15.Cu")
		(net "P5E_CPU1_P2_RX_BUF_DN<10>")
	)
	(arc
		(start 151.85771 -402.515324)
		(mid 151.79614 -402.559339)
		(end 151.736552 -402.606002)
		(width 0.14224)
		(layer "In15.Cu")
		(net "P5E_CPU1_P2_RX_BUF_DN<10>")
	)
	(arc
		(start 146.198844 -416.124136)
		(mid 145.895606 -416.578059)
		(end 145.789142 -417.113466)
		(width 0.14224)
		(layer "In15.Cu")
		(net "P5E_CPU1_P2_RX_BUF_DN<10>")
	)
	(arc
		(start 147.711922 -411.412436)
		(mid 147.448052 -411.629198)
		(end 147.348956 -411.955996)
		(width 0.14224)
		(layer "In15.Cu")
		(net "P5E_CPU1_P2_RX_BUF_DN<10>")
	)
	(arc
		(start 149.168104 -405.94407)
		(mid 148.955215 -406.262536)
		(end 148.880576 -406.638252)
		(width 0.14224)
		(layer "In15.Cu")
		(net "P5E_CPU1_P2_RX_BUF_DN<10>")
	)
	(arc
		(start 150.462488 -403.869652)
		(mid 150.424935 -403.98551)
		(end 150.412196 -404.106634)
		(width 0.14224)
		(layer "In15.Cu")
		(net "P5E_CPU1_P2_RX_BUF_DN<10>")
	)
	(segment
		(start 146.93519 -391.689336)
		(end 146.93519 -392.611864)
		(width 0.1016)
		(layer "F.Cu")
		(net "P5E_CPU1_P2_RX_BUF_DN<0>")
	)
	(segment
		(start 147.30349 -392.761216)
		(end 147.444206 -392.6205)
		(width 0.1016)
		(layer "F.Cu")
		(net "P5E_CPU1_P2_RX_BUF_DN<0>")
	)
	(segment
		(start 147.046188 -391.578338)
		(end 146.93519 -391.689336)
		(width 0.1016)
		(layer "F.Cu")
		(net "P5E_CPU1_P2_RX_BUF_DN<0>")
	)
	(segment
		(start 147.04568 -390.761474)
		(end 147.046188 -390.761982)
		(width 0.1016)
		(layer "F.Cu")
		(net "P5E_CPU1_P2_RX_BUF_DN<0>")
	)
	(segment
		(start 146.93519 -392.611864)
		(end 147.084542 -392.761216)
		(width 0.1016)
		(layer "F.Cu")
		(net "P5E_CPU1_P2_RX_BUF_DN<0>")
	)
	(segment
		(start 147.046188 -390.761982)
		(end 147.046188 -391.578338)
		(width 0.1016)
		(layer "F.Cu")
		(net "P5E_CPU1_P2_RX_BUF_DN<0>")
	)
	(segment
		(start 147.084542 -392.761216)
		(end 147.30349 -392.761216)
		(width 0.1016)
		(layer "F.Cu")
		(net "P5E_CPU1_P2_RX_BUF_DN<0>")
	)
	(segment
		(start 147.444206 -392.6205)
		(end 147.444206 -392.429238)
		(width 0.1016)
		(layer "F.Cu")
		(net "P5E_CPU1_P2_RX_BUF_DN<0>")
	)
	(segment
		(start 119.532654 -405.341328)
		(end 119.659908 -405.214074)
		(width 0.14224)
		(layer "In15.Cu")
		(net "P5E_CPU1_P2_RX_BUF_DN<0>")
	)
	(segment
		(start 119.263414 -405.52116)
		(end 119.532654 -405.341328)
		(width 0.14224)
		(layer "In15.Cu")
		(net "P5E_CPU1_P2_RX_BUF_DN<0>")
	)
	(segment
		(start 147.153376 -392.720068)
		(end 147.444206 -392.429238)
		(width 0.14224)
		(layer "In15.Cu")
		(net "P5E_CPU1_P2_RX_BUF_DN<0>")
	)
	(segment
		(start 139.158218 -395.427708)
		(end 139.872212 -395.31925)
		(width 0.14224)
		(layer "In15.Cu")
		(net "P5E_CPU1_P2_RX_BUF_DN<0>")
	)
	(segment
		(start 119.013478 -405.624538)
		(end 119.263414 -405.52116)
		(width 0.14224)
		(layer "In15.Cu")
		(net "P5E_CPU1_P2_RX_BUF_DN<0>")
	)
	(segment
		(start 124.308108 -436.966106)
		(end 124.308108 -422.029636)
		(width 0.14224)
		(layer "In15.Cu")
		(net "P5E_CPU1_P2_RX_BUF_DN<0>")
	)
	(segment
		(start 118.248176 -410.721302)
		(end 118.248176 -406.638252)
		(width 0.14224)
		(layer "In15.Cu")
		(net "P5E_CPU1_P2_RX_BUF_DN<0>")
	)
	(segment
		(start 124.03836 -421.37838)
		(end 116.9797 -414.31972)
		(width 0.14224)
		(layer "In15.Cu")
		(net "P5E_CPU1_P2_RX_BUF_DN<0>")
	)
	(segment
		(start 117.51564 -411.225238)
		(end 118.062502 -410.99867)
		(width 0.14224)
		(layer "In15.Cu")
		(net "P5E_CPU1_P2_RX_BUF_DN<0>")
	)
	(segment
		(start 119.826024 -403.830536)
		(end 119.951246 -403.529038)
		(width 0.14224)
		(layer "In15.Cu")
		(net "P5E_CPU1_P2_RX_BUF_DN<0>")
	)
	(segment
		(start 125.59919 -437.61914)
		(end 124.961142 -437.61914)
		(width 0.14224)
		(layer "In15.Cu")
		(net "P5E_CPU1_P2_RX_BUF_DN<0>")
	)
	(segment
		(start 119.779796 -404.924514)
		(end 119.779796 -404.061676)
		(width 0.14224)
		(layer "In15.Cu")
		(net "P5E_CPU1_P2_RX_BUF_DN<0>")
	)
	(segment
		(start 146.7866 -392.720068)
		(end 147.153376 -392.720068)
		(width 0.14224)
		(layer "In15.Cu")
		(net "P5E_CPU1_P2_RX_BUF_DN<0>")
	)
	(segment
		(start 116.716556 -413.684212)
		(end 116.716556 -411.82925)
		(width 0.14224)
		(layer "In15.Cu")
		(net "P5E_CPU1_P2_RX_BUF_DN<0>")
	)
	(segment
		(start 140.518388 -395.154658)
		(end 144.2593 -393.802108)
		(width 0.14224)
		(layer "In15.Cu")
		(net "P5E_CPU1_P2_RX_BUF_DN<0>")
	)
	(segment
		(start 130.032506 -398.709642)
		(end 138.982196 -395.472666)
		(width 0.14224)
		(layer "In15.Cu")
		(net "P5E_CPU1_P2_RX_BUF_DN<0>")
	)
	(segment
		(start 117.515894 -411.225238)
		(end 117.51564 -411.225238)
		(width 0.14224)
		(layer "In15.Cu")
		(net "P5E_CPU1_P2_RX_BUF_DN<0>")
	)
	(segment
		(start 125.749812 -438.089802)
		(end 125.749812 -437.769762)
		(width 0.14224)
		(layer "In15.Cu")
		(net "P5E_CPU1_P2_RX_BUF_DN<0>")
	)
	(segment
		(start 120.102884 -403.321012)
		(end 120.4976 -402.985986)
		(width 0.14224)
		(layer "In15.Cu")
		(net "P5E_CPU1_P2_RX_BUF_DN<0>")
	)
	(segment
		(start 120.673622 -402.874734)
		(end 128.606042 -399.289016)
		(width 0.14224)
		(layer "In15.Cu")
		(net "P5E_CPU1_P2_RX_BUF_DN<0>")
	)
	(segment
		(start 144.352772 -393.763246)
		(end 145.60042 -393.1793)
		(width 0.14224)
		(layer "In15.Cu")
		(net "P5E_CPU1_P2_RX_BUF_DN<0>")
	)
	(segment
		(start 145.891758 -393.043156)
		(end 146.7866 -392.720068)
		(width 0.14224)
		(layer "In15.Cu")
		(net "P5E_CPU1_P2_RX_BUF_DN<0>")
	)
	(segment
		(start 124.961142 -437.61914)
		(end 124.308108 -436.966106)
		(width 0.14224)
		(layer "In15.Cu")
		(net "P5E_CPU1_P2_RX_BUF_DN<0>")
	)
	(segment
		(start 116.968778 -411.45206)
		(end 117.515894 -411.225238)
		(width 0.14224)
		(layer "In15.Cu")
		(net "P5E_CPU1_P2_RX_BUF_DN<0>")
	)
	(segment
		(start 125.749812 -437.769762)
		(end 125.59919 -437.61914)
		(width 0.14224)
		(layer "In15.Cu")
		(net "P5E_CPU1_P2_RX_BUF_DN<0>")
	)
	(arc
		(start 124.308108 -422.029636)
		(mid 124.238001 -421.677183)
		(end 124.03836 -421.37838)
		(width 0.14224)
		(layer "In15.Cu")
		(net "P5E_CPU1_P2_RX_BUF_DN<0>")
	)
	(arc
		(start 145.60042 -393.1793)
		(mid 145.649934 -393.155259)
		(end 145.698718 -393.12977)
		(width 0.14224)
		(layer "In15.Cu")
		(net "P5E_CPU1_P2_RX_BUF_DN<0>")
	)
	(arc
		(start 119.951246 -403.529038)
		(mid 120.014698 -403.416008)
		(end 120.102884 -403.321012)
		(width 0.14224)
		(layer "In15.Cu")
		(net "P5E_CPU1_P2_RX_BUF_DN<0>")
	)
	(arc
		(start 118.248176 -406.638252)
		(mid 118.322866 -406.262557)
		(end 118.535704 -405.94407)
		(width 0.14224)
		(layer "In15.Cu")
		(net "P5E_CPU1_P2_RX_BUF_DN<0>")
	)
	(arc
		(start 128.606042 -399.289016)
		(mid 129.313663 -398.985514)
		(end 130.032506 -398.709642)
		(width 0.14224)
		(layer "In15.Cu")
		(net "P5E_CPU1_P2_RX_BUF_DN<0>")
	)
	(arc
		(start 118.062502 -410.99867)
		(mid 118.197477 -410.888176)
		(end 118.248176 -410.721302)
		(width 0.14224)
		(layer "In15.Cu")
		(net "P5E_CPU1_P2_RX_BUF_DN<0>")
	)
	(arc
		(start 116.9797 -414.31972)
		(mid 116.78493 -414.028132)
		(end 116.716556 -413.684212)
		(width 0.14224)
		(layer "In15.Cu")
		(net "P5E_CPU1_P2_RX_BUF_DN<0>")
	)
	(arc
		(start 119.779796 -404.061676)
		(mid 119.791515 -403.943827)
		(end 119.826024 -403.830536)
		(width 0.14224)
		(layer "In15.Cu")
		(net "P5E_CPU1_P2_RX_BUF_DN<0>")
	)
	(arc
		(start 120.4976 -402.985986)
		(mid 120.581727 -402.924212)
		(end 120.673622 -402.874734)
		(width 0.14224)
		(layer "In15.Cu")
		(net "P5E_CPU1_P2_RX_BUF_DN<0>")
	)
	(arc
		(start 145.698718 -393.12977)
		(mid 145.793639 -393.082901)
		(end 145.891758 -393.043156)
		(width 0.14224)
		(layer "In15.Cu")
		(net "P5E_CPU1_P2_RX_BUF_DN<0>")
	)
	(arc
		(start 118.535704 -405.94407)
		(mid 118.758869 -405.760796)
		(end 119.013478 -405.624538)
		(width 0.14224)
		(layer "In15.Cu")
		(net "P5E_CPU1_P2_RX_BUF_DN<0>")
	)
	(arc
		(start 139.872212 -395.31925)
		(mid 140.199372 -395.252936)
		(end 140.518388 -395.154658)
		(width 0.14224)
		(layer "In15.Cu")
		(net "P5E_CPU1_P2_RX_BUF_DN<0>")
	)
	(arc
		(start 144.2593 -393.802108)
		(mid 144.30648 -393.783745)
		(end 144.352772 -393.763246)
		(width 0.14224)
		(layer "In15.Cu")
		(net "P5E_CPU1_P2_RX_BUF_DN<0>")
	)
	(arc
		(start 138.982196 -395.472666)
		(mid 139.069103 -395.445866)
		(end 139.158218 -395.427708)
		(width 0.14224)
		(layer "In15.Cu")
		(net "P5E_CPU1_P2_RX_BUF_DN<0>")
	)
	(arc
		(start 119.659908 -405.214074)
		(mid 119.748623 -405.081209)
		(end 119.779796 -404.924514)
		(width 0.14224)
		(layer "In15.Cu")
		(net "P5E_CPU1_P2_RX_BUF_DN<0>")
	)
	(arc
		(start 116.716556 -411.82925)
		(mid 116.785494 -411.602435)
		(end 116.968778 -411.45206)
		(width 0.14224)
		(layer "In15.Cu")
		(net "P5E_CPU1_P2_RX_BUF_DN<0>")
	)
	(segment
		(start 90.998294 -389.467344)
		(end 91.518994 -389.467344)
		(width 0.127)
		(layer "F.Cu")
		(net "P5E_CPU1_P1_TX_BUF_DP<9>")
	)
	(segment
		(start 77.783944 -408.250644)
		(end 77.488034 -407.954734)
		(width 0.12954)
		(layer "B.Cu")
		(net "P5E_CPU1_P1_TX_BUF_DP<9>")
	)
	(segment
		(start 77.488034 -407.27503)
		(end 77.758544 -407.00452)
		(width 0.12954)
		(layer "B.Cu")
		(net "P5E_CPU1_P1_TX_BUF_DP<9>")
	)
	(segment
		(start 77.488034 -407.954734)
		(end 77.488034 -407.27503)
		(width 0.12954)
		(layer "B.Cu")
		(net "P5E_CPU1_P1_TX_BUF_DP<9>")
	)
	(segment
		(start 91.404186 -389.352536)
		(end 91.2241 -389.352536)
		(width 0.14224)
		(layer "In11.Cu")
		(net "P5E_CPU1_P1_TX_BUF_DP<9>")
	)
	(segment
		(start 79.339694 -402.747226)
		(end 78.963266 -402.948394)
		(width 0.14224)
		(layer "In11.Cu")
		(net "P5E_CPU1_P1_TX_BUF_DP<9>")
	)
	(segment
		(start 85.303868 -400.204686)
		(end 82.500978 -401.36572)
		(width 0.14224)
		(layer "In11.Cu")
		(net "P5E_CPU1_P1_TX_BUF_DP<9>")
	)
	(segment
		(start 91.518994 -389.467344)
		(end 91.404186 -389.352536)
		(width 0.14224)
		(layer "In11.Cu")
		(net "P5E_CPU1_P1_TX_BUF_DP<9>")
	)
	(segment
		(start 90.86088 -394.451586)
		(end 90.86088 -394.878306)
		(width 0.14224)
		(layer "In11.Cu")
		(net "P5E_CPU1_P1_TX_BUF_DP<9>")
	)
	(segment
		(start 91.138756 -389.43788)
		(end 91.138756 -389.525002)
		(width 0.14224)
		(layer "In11.Cu")
		(net "P5E_CPU1_P1_TX_BUF_DP<9>")
	)
	(segment
		(start 77.467714 -406.71369)
		(end 77.758544 -407.00452)
		(width 0.14224)
		(layer "In11.Cu")
		(net "P5E_CPU1_P1_TX_BUF_DP<9>")
	)
	(segment
		(start 81.480914 -401.876006)
		(end 81.305908 -401.79244)
		(width 0.14224)
		(layer "In11.Cu")
		(net "P5E_CPU1_P1_TX_BUF_DP<9>")
	)
	(segment
		(start 90.72372 -395.015466)
		(end 90.72372 -395.272768)
		(width 0.14224)
		(layer "In11.Cu")
		(net "P5E_CPU1_P1_TX_BUF_DP<9>")
	)
	(segment
		(start 91.495372 -390.171432)
		(end 91.495372 -390.623044)
		(width 0.14224)
		(layer "In11.Cu")
		(net "P5E_CPU1_P1_TX_BUF_DP<9>")
	)
	(segment
		(start 91.213686 -389.70585)
		(end 91.365578 -389.857742)
		(width 0.14224)
		(layer "In11.Cu")
		(net "P5E_CPU1_P1_TX_BUF_DP<9>")
	)
	(segment
		(start 81.883504 -401.733766)
		(end 81.480914 -401.876006)
		(width 0.14224)
		(layer "In11.Cu")
		(net "P5E_CPU1_P1_TX_BUF_DP<9>")
	)
	(segment
		(start 90.72372 -391.772394)
		(end 90.72372 -394.314426)
		(width 0.14224)
		(layer "In11.Cu")
		(net "P5E_CPU1_P1_TX_BUF_DP<9>")
	)
	(segment
		(start 91.275408 -391.153904)
		(end 90.770964 -391.658348)
		(width 0.14224)
		(layer "In11.Cu")
		(net "P5E_CPU1_P1_TX_BUF_DP<9>")
	)
	(segment
		(start 77.467714 -404.077932)
		(end 77.467714 -406.71369)
		(width 0.14224)
		(layer "In11.Cu")
		(net "P5E_CPU1_P1_TX_BUF_DP<9>")
	)
	(segment
		(start 81.305908 -401.79244)
		(end 79.911448 -402.285962)
		(width 0.14224)
		(layer "In11.Cu")
		(net "P5E_CPU1_P1_TX_BUF_DP<9>")
	)
	(segment
		(start 79.396082 -402.561552)
		(end 79.339694 -402.747226)
		(width 0.14224)
		(layer "In11.Cu")
		(net "P5E_CPU1_P1_TX_BUF_DP<9>")
	)
	(segment
		(start 79.911448 -402.285962)
		(end 79.396082 -402.561552)
		(width 0.14224)
		(layer "In11.Cu")
		(net "P5E_CPU1_P1_TX_BUF_DP<9>")
	)
	(segment
		(start 90.86088 -394.878306)
		(end 90.72372 -395.015466)
		(width 0.14224)
		(layer "In11.Cu")
		(net "P5E_CPU1_P1_TX_BUF_DP<9>")
	)
	(segment
		(start 82.369152 -401.416266)
		(end 81.96707 -401.558506)
		(width 0.14224)
		(layer "In11.Cu")
		(net "P5E_CPU1_P1_TX_BUF_DP<9>")
	)
	(segment
		(start 78.777592 -402.89226)
		(end 77.895958 -403.36343)
		(width 0.14224)
		(layer "In11.Cu")
		(net "P5E_CPU1_P1_TX_BUF_DP<9>")
	)
	(segment
		(start 78.963266 -402.948394)
		(end 78.777592 -402.89226)
		(width 0.14224)
		(layer "In11.Cu")
		(net "P5E_CPU1_P1_TX_BUF_DP<9>")
	)
	(segment
		(start 90.72372 -394.314426)
		(end 90.86088 -394.451586)
		(width 0.14224)
		(layer "In11.Cu")
		(net "P5E_CPU1_P1_TX_BUF_DP<9>")
	)
	(segment
		(start 90.603832 -395.562074)
		(end 87.285322 -398.880584)
		(width 0.14224)
		(layer "In11.Cu")
		(net "P5E_CPU1_P1_TX_BUF_DP<9>")
	)
	(segment
		(start 81.96707 -401.558506)
		(end 81.883504 -401.733766)
		(width 0.14224)
		(layer "In11.Cu")
		(net "P5E_CPU1_P1_TX_BUF_DP<9>")
	)
	(segment
		(start 91.2241 -389.352536)
		(end 91.138756 -389.43788)
		(width 0.14224)
		(layer "In11.Cu")
		(net "P5E_CPU1_P1_TX_BUF_DP<9>")
	)
	(arc
		(start 90.72372 -395.272768)
		(mid 90.692557 -395.429346)
		(end 90.603832 -395.562074)
		(width 0.14224)
		(layer "In11.Cu")
		(net "P5E_CPU1_P1_TX_BUF_DP<9>")
	)
	(arc
		(start 90.770964 -391.658348)
		(mid 90.736002 -391.710673)
		(end 90.72372 -391.772394)
		(width 0.14224)
		(layer "In11.Cu")
		(net "P5E_CPU1_P1_TX_BUF_DP<9>")
	)
	(arc
		(start 91.495372 -390.623044)
		(mid 91.438204 -390.910358)
		(end 91.275408 -391.153904)
		(width 0.14224)
		(layer "In11.Cu")
		(net "P5E_CPU1_P1_TX_BUF_DP<9>")
	)
	(arc
		(start 77.895958 -403.36343)
		(mid 77.583005 -403.661438)
		(end 77.467714 -404.077932)
		(width 0.14224)
		(layer "In11.Cu")
		(net "P5E_CPU1_P1_TX_BUF_DP<9>")
	)
	(arc
		(start 82.500978 -401.36572)
		(mid 82.435396 -401.391857)
		(end 82.369152 -401.416266)
		(width 0.14224)
		(layer "In11.Cu")
		(net "P5E_CPU1_P1_TX_BUF_DP<9>")
	)
	(arc
		(start 87.285322 -398.880584)
		(mid 86.359794 -399.640201)
		(end 85.303868 -400.204686)
		(width 0.14224)
		(layer "In11.Cu")
		(net "P5E_CPU1_P1_TX_BUF_DP<9>")
	)
	(arc
		(start 91.365578 -389.857742)
		(mid 91.461714 -390.001665)
		(end 91.495372 -390.171432)
		(width 0.14224)
		(layer "In11.Cu")
		(net "P5E_CPU1_P1_TX_BUF_DP<9>")
	)
	(arc
		(start 91.138756 -389.525002)
		(mid 91.158211 -389.622898)
		(end 91.213686 -389.70585)
		(width 0.14224)
		(layer "In11.Cu")
		(net "P5E_CPU1_P1_TX_BUF_DP<9>")
	)
	(segment
		(start 89.798398 -389.467344)
		(end 90.319098 -389.467344)
		(width 0.127)
		(layer "F.Cu")
		(net "P5E_CPU1_P1_TX_BUF_DP<8>")
	)
	(segment
		(start 74.424794 -407.954734)
		(end 74.424794 -407.27503)
		(width 0.12954)
		(layer "B.Cu")
		(net "P5E_CPU1_P1_TX_BUF_DP<8>")
	)
	(segment
		(start 74.720704 -408.250644)
		(end 74.424794 -407.954734)
		(width 0.12954)
		(layer "B.Cu")
		(net "P5E_CPU1_P1_TX_BUF_DP<8>")
	)
	(segment
		(start 74.424794 -407.27503)
		(end 74.695304 -407.00452)
		(width 0.12954)
		(layer "B.Cu")
		(net "P5E_CPU1_P1_TX_BUF_DP<8>")
	)
	(segment
		(start 88.99271 -395.693392)
		(end 86.1314 -398.554702)
		(width 0.14224)
		(layer "In11.Cu")
		(net "P5E_CPU1_P1_TX_BUF_DP<8>")
	)
	(segment
		(start 76.851002 -402.524214)
		(end 76.77658 -402.703538)
		(width 0.14224)
		(layer "In11.Cu")
		(net "P5E_CPU1_P1_TX_BUF_DP<8>")
	)
	(segment
		(start 76.77658 -402.703538)
		(end 76.382118 -402.86686)
		(width 0.14224)
		(layer "In11.Cu")
		(net "P5E_CPU1_P1_TX_BUF_DP<8>")
	)
	(segment
		(start 90.295476 -390.176512)
		(end 90.295476 -390.664192)
		(width 0.14224)
		(layer "In11.Cu")
		(net "P5E_CPU1_P1_TX_BUF_DP<8>")
	)
	(segment
		(start 74.404474 -406.71369)
		(end 74.695304 -407.00452)
		(width 0.14224)
		(layer "In11.Cu")
		(net "P5E_CPU1_P1_TX_BUF_DP<8>")
	)
	(segment
		(start 90.319098 -389.467344)
		(end 90.20429 -389.352536)
		(width 0.14224)
		(layer "In11.Cu")
		(net "P5E_CPU1_P1_TX_BUF_DP<8>")
	)
	(segment
		(start 74.766678 -403.38756)
		(end 74.659744 -403.494494)
		(width 0.14224)
		(layer "In11.Cu")
		(net "P5E_CPU1_P1_TX_BUF_DP<8>")
	)
	(segment
		(start 74.404474 -404.110698)
		(end 74.404474 -406.71369)
		(width 0.14224)
		(layer "In11.Cu")
		(net "P5E_CPU1_P1_TX_BUF_DP<8>")
	)
	(segment
		(start 75.734418 -403.135338)
		(end 75.339956 -403.29866)
		(width 0.14224)
		(layer "In11.Cu")
		(net "P5E_CPU1_P1_TX_BUF_DP<8>")
	)
	(segment
		(start 89.458038 -391.7696)
		(end 89.458038 -394.570204)
		(width 0.14224)
		(layer "In11.Cu")
		(net "P5E_CPU1_P1_TX_BUF_DP<8>")
	)
	(segment
		(start 90.024204 -389.352536)
		(end 89.934796 -389.441944)
		(width 0.14224)
		(layer "In11.Cu")
		(net "P5E_CPU1_P1_TX_BUF_DP<8>")
	)
	(segment
		(start 77.42428 -402.435314)
		(end 77.24521 -402.361146)
		(width 0.14224)
		(layer "In11.Cu")
		(net "P5E_CPU1_P1_TX_BUF_DP<8>")
	)
	(segment
		(start 89.934796 -389.441944)
		(end 89.934796 -389.485124)
		(width 0.14224)
		(layer "In11.Cu")
		(net "P5E_CPU1_P1_TX_BUF_DP<8>")
	)
	(segment
		(start 85.044788 -399.280634)
		(end 81.886298 -400.58848)
		(width 0.14224)
		(layer "In11.Cu")
		(net "P5E_CPU1_P1_TX_BUF_DP<8>")
	)
	(segment
		(start 76.382118 -402.86686)
		(end 76.203048 -402.792692)
		(width 0.14224)
		(layer "In11.Cu")
		(net "P5E_CPU1_P1_TX_BUF_DP<8>")
	)
	(segment
		(start 90.20429 -389.352536)
		(end 90.024204 -389.352536)
		(width 0.14224)
		(layer "In11.Cu")
		(net "P5E_CPU1_P1_TX_BUF_DP<8>")
	)
	(segment
		(start 77.893164 -402.092668)
		(end 77.818742 -402.271992)
		(width 0.14224)
		(layer "In11.Cu")
		(net "P5E_CPU1_P1_TX_BUF_DP<8>")
	)
	(segment
		(start 90.048842 -389.760206)
		(end 90.175588 -389.886952)
		(width 0.14224)
		(layer "In11.Cu")
		(net "P5E_CPU1_P1_TX_BUF_DP<8>")
	)
	(segment
		(start 75.160886 -403.224492)
		(end 74.766678 -403.38756)
		(width 0.14224)
		(layer "In11.Cu")
		(net "P5E_CPU1_P1_TX_BUF_DP<8>")
	)
	(segment
		(start 75.339956 -403.29866)
		(end 75.160886 -403.224492)
		(width 0.14224)
		(layer "In11.Cu")
		(net "P5E_CPU1_P1_TX_BUF_DP<8>")
	)
	(segment
		(start 77.24521 -402.361146)
		(end 76.851002 -402.524214)
		(width 0.14224)
		(layer "In11.Cu")
		(net "P5E_CPU1_P1_TX_BUF_DP<8>")
	)
	(segment
		(start 90.113358 -391.104374)
		(end 89.46515 -391.752582)
		(width 0.14224)
		(layer "In11.Cu")
		(net "P5E_CPU1_P1_TX_BUF_DP<8>")
	)
	(segment
		(start 80.534256 -400.99869)
		(end 77.893164 -402.092668)
		(width 0.14224)
		(layer "In11.Cu")
		(net "P5E_CPU1_P1_TX_BUF_DP<8>")
	)
	(segment
		(start 75.80884 -402.95576)
		(end 75.734418 -403.135338)
		(width 0.14224)
		(layer "In11.Cu")
		(net "P5E_CPU1_P1_TX_BUF_DP<8>")
	)
	(segment
		(start 77.818742 -402.271992)
		(end 77.42428 -402.435314)
		(width 0.14224)
		(layer "In11.Cu")
		(net "P5E_CPU1_P1_TX_BUF_DP<8>")
	)
	(segment
		(start 81.886298 -400.58848)
		(end 80.534256 -400.99869)
		(width 0.14224)
		(layer "In11.Cu")
		(net "P5E_CPU1_P1_TX_BUF_DP<8>")
	)
	(segment
		(start 76.203048 -402.792692)
		(end 75.80884 -402.95576)
		(width 0.14224)
		(layer "In11.Cu")
		(net "P5E_CPU1_P1_TX_BUF_DP<8>")
	)
	(arc
		(start 74.659744 -403.494494)
		(mid 74.470839 -403.777211)
		(end 74.404474 -404.110698)
		(width 0.14224)
		(layer "In11.Cu")
		(net "P5E_CPU1_P1_TX_BUF_DP<8>")
	)
	(arc
		(start 86.1314 -398.554702)
		(mid 85.623859 -398.971205)
		(end 85.044788 -399.280634)
		(width 0.14224)
		(layer "In11.Cu")
		(net "P5E_CPU1_P1_TX_BUF_DP<8>")
	)
	(arc
		(start 89.934796 -389.485124)
		(mid 89.964432 -389.634023)
		(end 90.048842 -389.760206)
		(width 0.14224)
		(layer "In11.Cu")
		(net "P5E_CPU1_P1_TX_BUF_DP<8>")
	)
	(arc
		(start 89.46515 -391.752582)
		(mid 89.459879 -391.760375)
		(end 89.458038 -391.7696)
		(width 0.14224)
		(layer "In11.Cu")
		(net "P5E_CPU1_P1_TX_BUF_DP<8>")
	)
	(arc
		(start 90.175588 -389.886952)
		(mid 90.264303 -390.019817)
		(end 90.295476 -390.176512)
		(width 0.14224)
		(layer "In11.Cu")
		(net "P5E_CPU1_P1_TX_BUF_DP<8>")
	)
	(arc
		(start 89.458038 -394.570204)
		(mid 89.337104 -395.178089)
		(end 88.99271 -395.693392)
		(width 0.14224)
		(layer "In11.Cu")
		(net "P5E_CPU1_P1_TX_BUF_DP<8>")
	)
	(arc
		(start 90.295476 -390.664192)
		(mid 90.248257 -390.902429)
		(end 90.113358 -391.104374)
		(width 0.14224)
		(layer "In11.Cu")
		(net "P5E_CPU1_P1_TX_BUF_DP<8>")
	)
	(segment
		(start 88.598248 -389.467344)
		(end 89.118948 -389.467344)
		(width 0.127)
		(layer "F.Cu")
		(net "P5E_CPU1_P1_TX_BUF_DP<7>")
	)
	(segment
		(start 71.361554 -407.27503)
		(end 71.632064 -407.00452)
		(width 0.12954)
		(layer "B.Cu")
		(net "P5E_CPU1_P1_TX_BUF_DP<7>")
	)
	(segment
		(start 71.361554 -407.954734)
		(end 71.361554 -407.27503)
		(width 0.12954)
		(layer "B.Cu")
		(net "P5E_CPU1_P1_TX_BUF_DP<7>")
	)
	(segment
		(start 71.657464 -408.250644)
		(end 71.361554 -407.954734)
		(width 0.12954)
		(layer "B.Cu")
		(net "P5E_CPU1_P1_TX_BUF_DP<7>")
	)
	(segment
		(start 72.979534 -403.038564)
		(end 72.579992 -403.18944)
		(width 0.14224)
		(layer "In11.Cu")
		(net "P5E_CPU1_P1_TX_BUF_DP<7>")
	)
	(segment
		(start 72.403208 -403.109684)
		(end 72.004174 -403.260306)
		(width 0.14224)
		(layer "In11.Cu")
		(net "P5E_CPU1_P1_TX_BUF_DP<7>")
	)
	(segment
		(start 78.73238 -400.64055)
		(end 76.59243 -401.52701)
		(width 0.14224)
		(layer "In11.Cu")
		(net "P5E_CPU1_P1_TX_BUF_DP<7>")
	)
	(segment
		(start 71.581772 -403.541738)
		(end 71.408798 -403.83333)
		(width 0.14224)
		(layer "In11.Cu")
		(net "P5E_CPU1_P1_TX_BUF_DP<7>")
	)
	(segment
		(start 74.690224 -402.392134)
		(end 74.51344 -402.312378)
		(width 0.14224)
		(layer "In11.Cu")
		(net "P5E_CPU1_P1_TX_BUF_DP<7>")
	)
	(segment
		(start 74.03465 -402.640038)
		(end 73.635108 -402.79066)
		(width 0.14224)
		(layer "In11.Cu")
		(net "P5E_CPU1_P1_TX_BUF_DP<7>")
	)
	(segment
		(start 72.004174 -403.260306)
		(end 71.704454 -403.423882)
		(width 0.14224)
		(layer "In11.Cu")
		(net "P5E_CPU1_P1_TX_BUF_DP<7>")
	)
	(segment
		(start 89.118948 -389.467344)
		(end 89.00414 -389.352536)
		(width 0.14224)
		(layer "In11.Cu")
		(net "P5E_CPU1_P1_TX_BUF_DP<7>")
	)
	(segment
		(start 76.59243 -401.52701)
		(end 75.169522 -402.064474)
		(width 0.14224)
		(layer "In11.Cu")
		(net "P5E_CPU1_P1_TX_BUF_DP<7>")
	)
	(segment
		(start 88.823546 -389.734806)
		(end 88.975692 -389.886698)
		(width 0.14224)
		(layer "In11.Cu")
		(net "P5E_CPU1_P1_TX_BUF_DP<7>")
	)
	(segment
		(start 89.00414 -389.352536)
		(end 88.824308 -389.352536)
		(width 0.14224)
		(layer "In11.Cu")
		(net "P5E_CPU1_P1_TX_BUF_DP<7>")
	)
	(segment
		(start 75.169522 -402.064474)
		(end 75.089766 -402.241512)
		(width 0.14224)
		(layer "In11.Cu")
		(net "P5E_CPU1_P1_TX_BUF_DP<7>")
	)
	(segment
		(start 81.679288 -399.664936)
		(end 80.134714 -400.137122)
		(width 0.14224)
		(layer "In11.Cu")
		(net "P5E_CPU1_P1_TX_BUF_DP<7>")
	)
	(segment
		(start 74.51344 -402.312378)
		(end 74.114406 -402.463)
		(width 0.14224)
		(layer "In11.Cu")
		(net "P5E_CPU1_P1_TX_BUF_DP<7>")
	)
	(segment
		(start 71.341234 -404.078948)
		(end 71.341234 -406.71369)
		(width 0.14224)
		(layer "In11.Cu")
		(net "P5E_CPU1_P1_TX_BUF_DP<7>")
	)
	(segment
		(start 73.458324 -402.710904)
		(end 73.05929 -402.861526)
		(width 0.14224)
		(layer "In11.Cu")
		(net "P5E_CPU1_P1_TX_BUF_DP<7>")
	)
	(segment
		(start 84.610448 -398.450054)
		(end 81.679288 -399.664936)
		(width 0.14224)
		(layer "In11.Cu")
		(net "P5E_CPU1_P1_TX_BUF_DP<7>")
	)
	(segment
		(start 89.09558 -390.176258)
		(end 89.09558 -390.572498)
		(width 0.14224)
		(layer "In11.Cu")
		(net "P5E_CPU1_P1_TX_BUF_DP<7>")
	)
	(segment
		(start 88.824308 -389.352536)
		(end 88.742012 -389.434832)
		(width 0.14224)
		(layer "In11.Cu")
		(net "P5E_CPU1_P1_TX_BUF_DP<7>")
	)
	(segment
		(start 88.742012 -389.434832)
		(end 88.742012 -389.537956)
		(width 0.14224)
		(layer "In11.Cu")
		(net "P5E_CPU1_P1_TX_BUF_DP<7>")
	)
	(segment
		(start 73.635108 -402.79066)
		(end 73.458324 -402.710904)
		(width 0.14224)
		(layer "In11.Cu")
		(net "P5E_CPU1_P1_TX_BUF_DP<7>")
	)
	(segment
		(start 87.992966 -395.318996)
		(end 85.36686 -397.944594)
		(width 0.14224)
		(layer "In11.Cu")
		(net "P5E_CPU1_P1_TX_BUF_DP<7>")
	)
	(segment
		(start 71.704454 -403.423882)
		(end 71.581772 -403.541738)
		(width 0.14224)
		(layer "In11.Cu")
		(net "P5E_CPU1_P1_TX_BUF_DP<7>")
	)
	(segment
		(start 88.337898 -391.691876)
		(end 88.337898 -394.48613)
		(width 0.14224)
		(layer "In11.Cu")
		(net "P5E_CPU1_P1_TX_BUF_DP<7>")
	)
	(segment
		(start 88.887046 -391.07618)
		(end 88.385142 -391.57783)
		(width 0.14224)
		(layer "In11.Cu")
		(net "P5E_CPU1_P1_TX_BUF_DP<7>")
	)
	(segment
		(start 75.089766 -402.241512)
		(end 74.690224 -402.392134)
		(width 0.14224)
		(layer "In11.Cu")
		(net "P5E_CPU1_P1_TX_BUF_DP<7>")
	)
	(segment
		(start 74.114406 -402.463)
		(end 74.03465 -402.640038)
		(width 0.14224)
		(layer "In11.Cu")
		(net "P5E_CPU1_P1_TX_BUF_DP<7>")
	)
	(segment
		(start 80.134714 -400.137122)
		(end 78.73238 -400.64055)
		(width 0.14224)
		(layer "In11.Cu")
		(net "P5E_CPU1_P1_TX_BUF_DP<7>")
	)
	(segment
		(start 73.05929 -402.861526)
		(end 72.979534 -403.038564)
		(width 0.14224)
		(layer "In11.Cu")
		(net "P5E_CPU1_P1_TX_BUF_DP<7>")
	)
	(segment
		(start 72.579992 -403.18944)
		(end 72.403208 -403.109684)
		(width 0.14224)
		(layer "In11.Cu")
		(net "P5E_CPU1_P1_TX_BUF_DP<7>")
	)
	(segment
		(start 71.341234 -406.71369)
		(end 71.632064 -407.00452)
		(width 0.14224)
		(layer "In11.Cu")
		(net "P5E_CPU1_P1_TX_BUF_DP<7>")
	)
	(arc
		(start 71.408798 -403.83333)
		(mid 71.358484 -403.95159)
		(end 71.341234 -404.078948)
		(width 0.14224)
		(layer "In11.Cu")
		(net "P5E_CPU1_P1_TX_BUF_DP<7>")
	)
	(arc
		(start 88.385142 -391.57783)
		(mid 88.350126 -391.63014)
		(end 88.337898 -391.691876)
		(width 0.14224)
		(layer "In11.Cu")
		(net "P5E_CPU1_P1_TX_BUF_DP<7>")
	)
	(arc
		(start 88.742012 -389.537956)
		(mid 88.763203 -389.644489)
		(end 88.823546 -389.734806)
		(width 0.14224)
		(layer "In11.Cu")
		(net "P5E_CPU1_P1_TX_BUF_DP<7>")
	)
	(arc
		(start 88.975692 -389.886698)
		(mid 89.064485 -390.019536)
		(end 89.09558 -390.176258)
		(width 0.14224)
		(layer "In11.Cu")
		(net "P5E_CPU1_P1_TX_BUF_DP<7>")
	)
	(arc
		(start 89.09558 -390.572498)
		(mid 89.041434 -390.845091)
		(end 88.887046 -391.07618)
		(width 0.14224)
		(layer "In11.Cu")
		(net "P5E_CPU1_P1_TX_BUF_DP<7>")
	)
	(arc
		(start 85.36686 -397.944594)
		(mid 85.013518 -398.234529)
		(end 84.610448 -398.450054)
		(width 0.14224)
		(layer "In11.Cu")
		(net "P5E_CPU1_P1_TX_BUF_DP<7>")
	)
	(arc
		(start 88.337898 -394.48613)
		(mid 88.248311 -394.936893)
		(end 87.992966 -395.318996)
		(width 0.14224)
		(layer "In11.Cu")
		(net "P5E_CPU1_P1_TX_BUF_DP<7>")
	)
	(segment
		(start 87.398352 -389.467344)
		(end 87.919052 -389.467344)
		(width 0.127)
		(layer "F.Cu")
		(net "P5E_CPU1_P1_TX_BUF_DP<6>")
	)
	(segment
		(start 68.298314 -407.27503)
		(end 68.568824 -407.00452)
		(width 0.12954)
		(layer "B.Cu")
		(net "P5E_CPU1_P1_TX_BUF_DP<6>")
	)
	(segment
		(start 68.298314 -407.954734)
		(end 68.298314 -407.27503)
		(width 0.12954)
		(layer "B.Cu")
		(net "P5E_CPU1_P1_TX_BUF_DP<6>")
	)
	(segment
		(start 68.594224 -408.250644)
		(end 68.298314 -407.954734)
		(width 0.12954)
		(layer "B.Cu")
		(net "P5E_CPU1_P1_TX_BUF_DP<6>")
	)
	(segment
		(start 70.581012 -402.7424)
		(end 70.176644 -402.87956)
		(width 0.14224)
		(layer "In11.Cu")
		(net "P5E_CPU1_P1_TX_BUF_DP<6>")
	)
	(segment
		(start 70.002654 -402.793962)
		(end 69.598794 -402.931122)
		(width 0.14224)
		(layer "In11.Cu")
		(net "P5E_CPU1_P1_TX_BUF_DP<6>")
	)
	(segment
		(start 69.108828 -403.242526)
		(end 68.934838 -403.156928)
		(width 0.14224)
		(layer "In11.Cu")
		(net "P5E_CPU1_P1_TX_BUF_DP<6>")
	)
	(segment
		(start 71.07047 -402.430996)
		(end 70.66661 -402.568156)
		(width 0.14224)
		(layer "In11.Cu")
		(net "P5E_CPU1_P1_TX_BUF_DP<6>")
	)
	(segment
		(start 75.800966 -400.823176)
		(end 71.734426 -402.20519)
		(width 0.14224)
		(layer "In11.Cu")
		(net "P5E_CPU1_P1_TX_BUF_DP<6>")
	)
	(segment
		(start 87.919052 -389.467344)
		(end 87.804244 -389.352536)
		(width 0.14224)
		(layer "In11.Cu")
		(net "P5E_CPU1_P1_TX_BUF_DP<6>")
	)
	(segment
		(start 68.277994 -406.71369)
		(end 68.568824 -407.00452)
		(width 0.14224)
		(layer "In11.Cu")
		(net "P5E_CPU1_P1_TX_BUF_DP<6>")
	)
	(segment
		(start 87.619586 -391.127996)
		(end 87.1474 -391.600182)
		(width 0.14224)
		(layer "In11.Cu")
		(net "P5E_CPU1_P1_TX_BUF_DP<6>")
	)
	(segment
		(start 87.093044 -391.7315)
		(end 87.093044 -394.410692)
		(width 0.14224)
		(layer "In11.Cu")
		(net "P5E_CPU1_P1_TX_BUF_DP<6>")
	)
	(segment
		(start 70.176644 -402.87956)
		(end 70.002654 -402.793962)
		(width 0.14224)
		(layer "In11.Cu")
		(net "P5E_CPU1_P1_TX_BUF_DP<6>")
	)
	(segment
		(start 87.615522 -389.726932)
		(end 87.775542 -389.886952)
		(width 0.14224)
		(layer "In11.Cu")
		(net "P5E_CPU1_P1_TX_BUF_DP<6>")
	)
	(segment
		(start 87.89543 -390.176512)
		(end 87.89543 -390.462262)
		(width 0.14224)
		(layer "In11.Cu")
		(net "P5E_CPU1_P1_TX_BUF_DP<6>")
	)
	(segment
		(start 68.277994 -403.97176)
		(end 68.277994 -406.71369)
		(width 0.14224)
		(layer "In11.Cu")
		(net "P5E_CPU1_P1_TX_BUF_DP<6>")
	)
	(segment
		(start 76.257912 -400.651218)
		(end 75.800966 -400.823176)
		(width 0.14224)
		(layer "In11.Cu")
		(net "P5E_CPU1_P1_TX_BUF_DP<6>")
	)
	(segment
		(start 87.624158 -389.352536)
		(end 87.53475 -389.441944)
		(width 0.14224)
		(layer "In11.Cu")
		(net "P5E_CPU1_P1_TX_BUF_DP<6>")
	)
	(segment
		(start 84.218018 -397.603472)
		(end 81.584292 -398.694402)
		(width 0.14224)
		(layer "In11.Cu")
		(net "P5E_CPU1_P1_TX_BUF_DP<6>")
	)
	(segment
		(start 81.584292 -398.694402)
		(end 79.307944 -399.387568)
		(width 0.14224)
		(layer "In11.Cu")
		(net "P5E_CPU1_P1_TX_BUF_DP<6>")
	)
	(segment
		(start 87.804244 -389.352536)
		(end 87.624158 -389.352536)
		(width 0.14224)
		(layer "In11.Cu")
		(net "P5E_CPU1_P1_TX_BUF_DP<6>")
	)
	(segment
		(start 86.778338 -395.170406)
		(end 84.601558 -397.347186)
		(width 0.14224)
		(layer "In11.Cu")
		(net "P5E_CPU1_P1_TX_BUF_DP<6>")
	)
	(segment
		(start 71.648828 -402.379434)
		(end 71.24446 -402.516594)
		(width 0.14224)
		(layer "In11.Cu")
		(net "P5E_CPU1_P1_TX_BUF_DP<6>")
	)
	(segment
		(start 71.24446 -402.516594)
		(end 71.07047 -402.430996)
		(width 0.14224)
		(layer "In11.Cu")
		(net "P5E_CPU1_P1_TX_BUF_DP<6>")
	)
	(segment
		(start 70.66661 -402.568156)
		(end 70.581012 -402.7424)
		(width 0.14224)
		(layer "In11.Cu")
		(net "P5E_CPU1_P1_TX_BUF_DP<6>")
	)
	(segment
		(start 87.53475 -389.441944)
		(end 87.53475 -389.532114)
		(width 0.14224)
		(layer "In11.Cu")
		(net "P5E_CPU1_P1_TX_BUF_DP<6>")
	)
	(segment
		(start 68.934838 -403.156928)
		(end 68.597272 -403.271482)
		(width 0.14224)
		(layer "In11.Cu")
		(net "P5E_CPU1_P1_TX_BUF_DP<6>")
	)
	(segment
		(start 79.307944 -399.387568)
		(end 76.257912 -400.651218)
		(width 0.14224)
		(layer "In11.Cu")
		(net "P5E_CPU1_P1_TX_BUF_DP<6>")
	)
	(segment
		(start 69.513196 -403.105366)
		(end 69.108828 -403.242526)
		(width 0.14224)
		(layer "In11.Cu")
		(net "P5E_CPU1_P1_TX_BUF_DP<6>")
	)
	(segment
		(start 69.598794 -402.931122)
		(end 69.513196 -403.105366)
		(width 0.14224)
		(layer "In11.Cu")
		(net "P5E_CPU1_P1_TX_BUF_DP<6>")
	)
	(segment
		(start 71.734426 -402.20519)
		(end 71.648828 -402.379434)
		(width 0.14224)
		(layer "In11.Cu")
		(net "P5E_CPU1_P1_TX_BUF_DP<6>")
	)
	(arc
		(start 68.597272 -403.271482)
		(mid 68.54033 -403.300921)
		(end 68.494656 -403.345904)
		(width 0.14224)
		(layer "In11.Cu")
		(net "P5E_CPU1_P1_TX_BUF_DP<6>")
	)
	(arc
		(start 87.89543 -390.462262)
		(mid 87.823742 -390.822574)
		(end 87.619586 -391.127996)
		(width 0.14224)
		(layer "In11.Cu")
		(net "P5E_CPU1_P1_TX_BUF_DP<6>")
	)
	(arc
		(start 84.601558 -397.347186)
		(mid 84.422406 -397.494211)
		(end 84.218018 -397.603472)
		(width 0.14224)
		(layer "In11.Cu")
		(net "P5E_CPU1_P1_TX_BUF_DP<6>")
	)
	(arc
		(start 87.093044 -394.410692)
		(mid 87.011259 -394.821855)
		(end 86.778338 -395.170406)
		(width 0.14224)
		(layer "In11.Cu")
		(net "P5E_CPU1_P1_TX_BUF_DP<6>")
	)
	(arc
		(start 68.494656 -403.345904)
		(mid 68.33783 -403.64204)
		(end 68.277994 -403.97176)
		(width 0.14224)
		(layer "In11.Cu")
		(net "P5E_CPU1_P1_TX_BUF_DP<6>")
	)
	(arc
		(start 87.1474 -391.600182)
		(mid 87.107196 -391.660445)
		(end 87.093044 -391.7315)
		(width 0.14224)
		(layer "In11.Cu")
		(net "P5E_CPU1_P1_TX_BUF_DP<6>")
	)
	(arc
		(start 87.775542 -389.886952)
		(mid 87.864257 -390.019817)
		(end 87.89543 -390.176512)
		(width 0.14224)
		(layer "In11.Cu")
		(net "P5E_CPU1_P1_TX_BUF_DP<6>")
	)
	(arc
		(start 87.53475 -389.532114)
		(mid 87.555743 -389.637563)
		(end 87.615522 -389.726932)
		(width 0.14224)
		(layer "In11.Cu")
		(net "P5E_CPU1_P1_TX_BUF_DP<6>")
	)
	(segment
		(start 86.198456 -389.467344)
		(end 86.719156 -389.467344)
		(width 0.127)
		(layer "F.Cu")
		(net "P5E_CPU1_P1_TX_BUF_DP<5>")
	)
	(segment
		(start 65.235074 -407.954734)
		(end 65.235074 -407.27503)
		(width 0.12954)
		(layer "B.Cu")
		(net "P5E_CPU1_P1_TX_BUF_DP<5>")
	)
	(segment
		(start 65.530984 -408.250644)
		(end 65.235074 -407.954734)
		(width 0.12954)
		(layer "B.Cu")
		(net "P5E_CPU1_P1_TX_BUF_DP<5>")
	)
	(segment
		(start 65.235074 -407.27503)
		(end 65.505584 -407.00452)
		(width 0.12954)
		(layer "B.Cu")
		(net "P5E_CPU1_P1_TX_BUF_DP<5>")
	)
	(segment
		(start 66.981578 -402.78558)
		(end 66.57467 -402.914358)
		(width 0.14224)
		(layer "In11.Cu")
		(net "P5E_CPU1_P1_TX_BUF_DP<5>")
	)
	(segment
		(start 85.634576 -394.92936)
		(end 83.883246 -396.68069)
		(width 0.14224)
		(layer "In11.Cu")
		(net "P5E_CPU1_P1_TX_BUF_DP<5>")
	)
	(segment
		(start 69.160136 -402.088096)
		(end 68.753228 -402.216874)
		(width 0.14224)
		(layer "In11.Cu")
		(net "P5E_CPU1_P1_TX_BUF_DP<5>")
	)
	(segment
		(start 69.245734 -401.92325)
		(end 69.160136 -402.088096)
		(width 0.14224)
		(layer "In11.Cu")
		(net "P5E_CPU1_P1_TX_BUF_DP<5>")
	)
	(segment
		(start 67.489324 -402.480526)
		(end 67.070986 -402.613114)
		(width 0.14224)
		(layer "In11.Cu")
		(net "P5E_CPU1_P1_TX_BUF_DP<5>")
	)
	(segment
		(start 67.668648 -402.57349)
		(end 67.489324 -402.480526)
		(width 0.14224)
		(layer "In11.Cu")
		(net "P5E_CPU1_P1_TX_BUF_DP<5>")
	)
	(segment
		(start 86.695534 -390.360408)
		(end 86.695534 -390.46277)
		(width 0.14224)
		(layer "In11.Cu")
		(net "P5E_CPU1_P1_TX_BUF_DP<5>")
	)
	(segment
		(start 75.21194 -399.951194)
		(end 71.68388 -401.150328)
		(width 0.14224)
		(layer "In11.Cu")
		(net "P5E_CPU1_P1_TX_BUF_DP<5>")
	)
	(segment
		(start 86.334854 -389.441944)
		(end 86.334854 -389.590026)
		(width 0.14224)
		(layer "In11.Cu")
		(net "P5E_CPU1_P1_TX_BUF_DP<5>")
	)
	(segment
		(start 66.402458 -402.825204)
		(end 66.401696 -402.82495)
		(width 0.14224)
		(layer "In11.Cu")
		(net "P5E_CPU1_P1_TX_BUF_DP<5>")
	)
	(segment
		(start 81.254854 -397.81988)
		(end 78.504034 -398.657064)
		(width 0.14224)
		(layer "In11.Cu")
		(net "P5E_CPU1_P1_TX_BUF_DP<5>")
	)
	(segment
		(start 66.401188 -402.824696)
		(end 66.369946 -402.834602)
		(width 0.14224)
		(layer "In11.Cu")
		(net "P5E_CPU1_P1_TX_BUF_DP<5>")
	)
	(segment
		(start 67.070986 -402.613114)
		(end 66.981578 -402.78558)
		(width 0.14224)
		(layer "In11.Cu")
		(net "P5E_CPU1_P1_TX_BUF_DP<5>")
	)
	(segment
		(start 71.68388 -401.150328)
		(end 69.245734 -401.92325)
		(width 0.14224)
		(layer "In11.Cu")
		(net "P5E_CPU1_P1_TX_BUF_DP<5>")
	)
	(segment
		(start 65.214754 -404.147528)
		(end 65.214754 -406.71369)
		(width 0.14224)
		(layer "In11.Cu")
		(net "P5E_CPU1_P1_TX_BUF_DP<5>")
	)
	(segment
		(start 68.168774 -402.26488)
		(end 68.075556 -402.444712)
		(width 0.14224)
		(layer "In11.Cu")
		(net "P5E_CPU1_P1_TX_BUF_DP<5>")
	)
	(segment
		(start 86.604348 -389.352536)
		(end 86.424262 -389.352536)
		(width 0.14224)
		(layer "In11.Cu")
		(net "P5E_CPU1_P1_TX_BUF_DP<5>")
	)
	(segment
		(start 83.678522 -396.817596)
		(end 81.590134 -397.682466)
		(width 0.14224)
		(layer "In11.Cu")
		(net "P5E_CPU1_P1_TX_BUF_DP<5>")
	)
	(segment
		(start 68.753228 -402.216874)
		(end 68.58889 -402.131784)
		(width 0.14224)
		(layer "In11.Cu")
		(net "P5E_CPU1_P1_TX_BUF_DP<5>")
	)
	(segment
		(start 66.401696 -402.82495)
		(end 66.401188 -402.824696)
		(width 0.14224)
		(layer "In11.Cu")
		(net "P5E_CPU1_P1_TX_BUF_DP<5>")
	)
	(segment
		(start 81.590134 -397.682466)
		(end 81.578704 -397.686022)
		(width 0.14224)
		(layer "In11.Cu")
		(net "P5E_CPU1_P1_TX_BUF_DP<5>")
	)
	(segment
		(start 68.58889 -402.131784)
		(end 68.168774 -402.26488)
		(width 0.14224)
		(layer "In11.Cu")
		(net "P5E_CPU1_P1_TX_BUF_DP<5>")
	)
	(segment
		(start 68.075556 -402.444712)
		(end 67.668648 -402.57349)
		(width 0.14224)
		(layer "In11.Cu")
		(net "P5E_CPU1_P1_TX_BUF_DP<5>")
	)
	(segment
		(start 77.821282 -398.89811)
		(end 75.21194 -399.951194)
		(width 0.14224)
		(layer "In11.Cu")
		(net "P5E_CPU1_P1_TX_BUF_DP<5>")
	)
	(segment
		(start 86.719156 -389.467344)
		(end 86.604348 -389.352536)
		(width 0.14224)
		(layer "In11.Cu")
		(net "P5E_CPU1_P1_TX_BUF_DP<5>")
	)
	(segment
		(start 81.578704 -397.686022)
		(end 81.254854 -397.81988)
		(width 0.14224)
		(layer "In11.Cu")
		(net "P5E_CPU1_P1_TX_BUF_DP<5>")
	)
	(segment
		(start 65.647062 -403.274276)
		(end 65.526666 -403.394672)
		(width 0.14224)
		(layer "In11.Cu")
		(net "P5E_CPU1_P1_TX_BUF_DP<5>")
	)
	(segment
		(start 86.424262 -389.352536)
		(end 86.334854 -389.441944)
		(width 0.14224)
		(layer "In11.Cu")
		(net "P5E_CPU1_P1_TX_BUF_DP<5>")
	)
	(segment
		(start 86.442804 -391.072878)
		(end 85.97011 -391.545572)
		(width 0.14224)
		(layer "In11.Cu")
		(net "P5E_CPU1_P1_TX_BUF_DP<5>")
	)
	(segment
		(start 65.214754 -406.71369)
		(end 65.505584 -407.00452)
		(width 0.14224)
		(layer "In11.Cu")
		(net "P5E_CPU1_P1_TX_BUF_DP<5>")
	)
	(segment
		(start 66.57467 -402.914358)
		(end 66.402458 -402.825204)
		(width 0.14224)
		(layer "In11.Cu")
		(net "P5E_CPU1_P1_TX_BUF_DP<5>")
	)
	(segment
		(start 85.896704 -391.722864)
		(end 85.896704 -394.296646)
		(width 0.14224)
		(layer "In11.Cu")
		(net "P5E_CPU1_P1_TX_BUF_DP<5>")
	)
	(segment
		(start 86.372192 -389.679942)
		(end 86.443058 -389.750808)
		(width 0.14224)
		(layer "In11.Cu")
		(net "P5E_CPU1_P1_TX_BUF_DP<5>")
	)
	(arc
		(start 86.334854 -389.590026)
		(mid 86.344556 -389.63871)
		(end 86.372192 -389.679942)
		(width 0.14224)
		(layer "In11.Cu")
		(net "P5E_CPU1_P1_TX_BUF_DP<5>")
	)
	(arc
		(start 65.526666 -403.394672)
		(mid 65.295815 -403.740071)
		(end 65.214754 -404.147528)
		(width 0.14224)
		(layer "In11.Cu")
		(net "P5E_CPU1_P1_TX_BUF_DP<5>")
	)
	(arc
		(start 66.369946 -402.834602)
		(mid 65.982134 -403.011077)
		(end 65.647062 -403.274276)
		(width 0.14224)
		(layer "In11.Cu")
		(net "P5E_CPU1_P1_TX_BUF_DP<5>")
	)
	(arc
		(start 78.504034 -398.657064)
		(mid 78.160001 -398.770061)
		(end 77.821282 -398.89811)
		(width 0.14224)
		(layer "In11.Cu")
		(net "P5E_CPU1_P1_TX_BUF_DP<5>")
	)
	(arc
		(start 83.883246 -396.68069)
		(mid 83.787618 -396.759209)
		(end 83.678522 -396.817596)
		(width 0.14224)
		(layer "In11.Cu")
		(net "P5E_CPU1_P1_TX_BUF_DP<5>")
	)
	(arc
		(start 85.896704 -394.296646)
		(mid 85.828573 -394.639073)
		(end 85.634576 -394.92936)
		(width 0.14224)
		(layer "In11.Cu")
		(net "P5E_CPU1_P1_TX_BUF_DP<5>")
	)
	(arc
		(start 86.443058 -389.750808)
		(mid 86.629939 -390.030495)
		(end 86.695534 -390.360408)
		(width 0.14224)
		(layer "In11.Cu")
		(net "P5E_CPU1_P1_TX_BUF_DP<5>")
	)
	(arc
		(start 86.695534 -390.46277)
		(mid 86.629854 -390.792964)
		(end 86.442804 -391.072878)
		(width 0.14224)
		(layer "In11.Cu")
		(net "P5E_CPU1_P1_TX_BUF_DP<5>")
	)
	(arc
		(start 85.97011 -391.545572)
		(mid 85.915759 -391.626914)
		(end 85.896704 -391.722864)
		(width 0.14224)
		(layer "In11.Cu")
		(net "P5E_CPU1_P1_TX_BUF_DP<5>")
	)
	(segment
		(start 84.998306 -389.467344)
		(end 85.519006 -389.467344)
		(width 0.127)
		(layer "F.Cu")
		(net "P5E_CPU1_P1_TX_BUF_DP<4>")
	)
	(segment
		(start 62.467744 -408.250644)
		(end 62.171834 -407.954734)
		(width 0.12954)
		(layer "B.Cu")
		(net "P5E_CPU1_P1_TX_BUF_DP<4>")
	)
	(segment
		(start 62.171834 -407.954734)
		(end 62.171834 -407.27503)
		(width 0.12954)
		(layer "B.Cu")
		(net "P5E_CPU1_P1_TX_BUF_DP<4>")
	)
	(segment
		(start 62.171834 -407.27503)
		(end 62.442344 -407.00452)
		(width 0.12954)
		(layer "B.Cu")
		(net "P5E_CPU1_P1_TX_BUF_DP<4>")
	)
	(segment
		(start 65.044828 -402.180806)
		(end 64.63919 -402.312632)
		(width 0.14224)
		(layer "In11.Cu")
		(net "P5E_CPU1_P1_TX_BUF_DP<4>")
	)
	(segment
		(start 65.623694 -402.136864)
		(end 65.217802 -402.268944)
		(width 0.14224)
		(layer "In11.Cu")
		(net "P5E_CPU1_P1_TX_BUF_DP<4>")
	)
	(segment
		(start 85.295486 -389.82269)
		(end 85.36559 -389.892794)
		(width 0.14224)
		(layer "In11.Cu")
		(net "P5E_CPU1_P1_TX_BUF_DP<4>")
	)
	(segment
		(start 85.36559 -390.866884)
		(end 84.762594 -391.46988)
		(width 0.14224)
		(layer "In11.Cu")
		(net "P5E_CPU1_P1_TX_BUF_DP<4>")
	)
	(segment
		(start 63.972186 -402.529802)
		(end 63.566548 -402.661628)
		(width 0.14224)
		(layer "In11.Cu")
		(net "P5E_CPU1_P1_TX_BUF_DP<4>")
	)
	(segment
		(start 85.16874 -389.352536)
		(end 85.134704 -389.386572)
		(width 0.14224)
		(layer "In11.Cu")
		(net "P5E_CPU1_P1_TX_BUF_DP<4>")
	)
	(segment
		(start 62.899544 -402.878798)
		(end 62.628526 -402.966682)
		(width 0.14224)
		(layer "In11.Cu")
		(net "P5E_CPU1_P1_TX_BUF_DP<4>")
	)
	(segment
		(start 79.35722 -397.385286)
		(end 78.786482 -397.596106)
		(width 0.14224)
		(layer "In11.Cu")
		(net "P5E_CPU1_P1_TX_BUF_DP<4>")
	)
	(segment
		(start 75.950318 -398.63522)
		(end 65.711324 -401.964652)
		(width 0.14224)
		(layer "In11.Cu")
		(net "P5E_CPU1_P1_TX_BUF_DP<4>")
	)
	(segment
		(start 63.566548 -402.661628)
		(end 63.47841 -402.834856)
		(width 0.14224)
		(layer "In11.Cu")
		(net "P5E_CPU1_P1_TX_BUF_DP<4>")
	)
	(segment
		(start 82.90433 -396.128748)
		(end 81.274412 -396.80388)
		(width 0.14224)
		(layer "In11.Cu")
		(net "P5E_CPU1_P1_TX_BUF_DP<4>")
	)
	(segment
		(start 81.274412 -396.80388)
		(end 79.55026 -397.32712)
		(width 0.14224)
		(layer "In11.Cu")
		(net "P5E_CPU1_P1_TX_BUF_DP<4>")
	)
	(segment
		(start 84.717636 -391.578592)
		(end 84.717636 -394.248894)
		(width 0.14224)
		(layer "In11.Cu")
		(net "P5E_CPU1_P1_TX_BUF_DP<4>")
	)
	(segment
		(start 64.551052 -402.48586)
		(end 64.14516 -402.617686)
		(width 0.14224)
		(layer "In11.Cu")
		(net "P5E_CPU1_P1_TX_BUF_DP<4>")
	)
	(segment
		(start 79.55026 -397.32712)
		(end 79.35722 -397.385286)
		(width 0.14224)
		(layer "In11.Cu")
		(net "P5E_CPU1_P1_TX_BUF_DP<4>")
	)
	(segment
		(start 63.47841 -402.834856)
		(end 63.072518 -402.966682)
		(width 0.14224)
		(layer "In11.Cu")
		(net "P5E_CPU1_P1_TX_BUF_DP<4>")
	)
	(segment
		(start 85.404198 -389.352536)
		(end 85.16874 -389.352536)
		(width 0.14224)
		(layer "In11.Cu")
		(net "P5E_CPU1_P1_TX_BUF_DP<4>")
	)
	(segment
		(start 85.519006 -389.467344)
		(end 85.404198 -389.352536)
		(width 0.14224)
		(layer "In11.Cu")
		(net "P5E_CPU1_P1_TX_BUF_DP<4>")
	)
	(segment
		(start 85.134704 -389.386572)
		(end 85.134704 -389.434578)
		(width 0.14224)
		(layer "In11.Cu")
		(net "P5E_CPU1_P1_TX_BUF_DP<4>")
	)
	(segment
		(start 65.217802 -402.268944)
		(end 65.044828 -402.180806)
		(width 0.14224)
		(layer "In11.Cu")
		(net "P5E_CPU1_P1_TX_BUF_DP<4>")
	)
	(segment
		(start 64.63919 -402.312632)
		(end 64.551052 -402.48586)
		(width 0.14224)
		(layer "In11.Cu")
		(net "P5E_CPU1_P1_TX_BUF_DP<4>")
	)
	(segment
		(start 65.711324 -401.964652)
		(end 65.623694 -402.136864)
		(width 0.14224)
		(layer "In11.Cu")
		(net "P5E_CPU1_P1_TX_BUF_DP<4>")
	)
	(segment
		(start 63.072518 -402.966682)
		(end 62.899544 -402.878798)
		(width 0.14224)
		(layer "In11.Cu")
		(net "P5E_CPU1_P1_TX_BUF_DP<4>")
	)
	(segment
		(start 84.554314 -394.643102)
		(end 83.39963 -395.797786)
		(width 0.14224)
		(layer "In11.Cu")
		(net "P5E_CPU1_P1_TX_BUF_DP<4>")
	)
	(segment
		(start 85.495384 -390.206484)
		(end 85.495384 -390.553448)
		(width 0.14224)
		(layer "In11.Cu")
		(net "P5E_CPU1_P1_TX_BUF_DP<4>")
	)
	(segment
		(start 77.847698 -397.881856)
		(end 75.950318 -398.63522)
		(width 0.14224)
		(layer "In11.Cu")
		(net "P5E_CPU1_P1_TX_BUF_DP<4>")
	)
	(segment
		(start 78.786482 -397.596106)
		(end 77.847698 -397.881856)
		(width 0.14224)
		(layer "In11.Cu")
		(net "P5E_CPU1_P1_TX_BUF_DP<4>")
	)
	(segment
		(start 62.151514 -406.71369)
		(end 62.442344 -407.00452)
		(width 0.14224)
		(layer "In11.Cu")
		(net "P5E_CPU1_P1_TX_BUF_DP<4>")
	)
	(segment
		(start 62.151514 -403.74443)
		(end 62.151514 -406.71369)
		(width 0.14224)
		(layer "In11.Cu")
		(net "P5E_CPU1_P1_TX_BUF_DP<4>")
	)
	(segment
		(start 64.14516 -402.617686)
		(end 63.972186 -402.529802)
		(width 0.14224)
		(layer "In11.Cu")
		(net "P5E_CPU1_P1_TX_BUF_DP<4>")
	)
	(arc
		(start 62.628526 -402.966682)
		(mid 62.480596 -403.039887)
		(end 62.359794 -403.152356)
		(width 0.14224)
		(layer "In11.Cu")
		(net "P5E_CPU1_P1_TX_BUF_DP<4>")
	)
	(arc
		(start 84.762594 -391.46988)
		(mid 84.729321 -391.519772)
		(end 84.717636 -391.578592)
		(width 0.14224)
		(layer "In11.Cu")
		(net "P5E_CPU1_P1_TX_BUF_DP<4>")
	)
	(arc
		(start 85.134704 -389.434578)
		(mid 85.176486 -389.644631)
		(end 85.295486 -389.82269)
		(width 0.14224)
		(layer "In11.Cu")
		(net "P5E_CPU1_P1_TX_BUF_DP<4>")
	)
	(arc
		(start 84.717636 -394.248894)
		(mid 84.675197 -394.462251)
		(end 84.554314 -394.643102)
		(width 0.14224)
		(layer "In11.Cu")
		(net "P5E_CPU1_P1_TX_BUF_DP<4>")
	)
	(arc
		(start 62.359794 -403.152356)
		(mid 62.205096 -403.430609)
		(end 62.151514 -403.74443)
		(width 0.14224)
		(layer "In11.Cu")
		(net "P5E_CPU1_P1_TX_BUF_DP<4>")
	)
	(arc
		(start 85.36559 -389.892794)
		(mid 85.461726 -390.036717)
		(end 85.495384 -390.206484)
		(width 0.14224)
		(layer "In11.Cu")
		(net "P5E_CPU1_P1_TX_BUF_DP<4>")
	)
	(arc
		(start 83.39963 -395.797786)
		(mid 83.168275 -395.987652)
		(end 82.90433 -396.128748)
		(width 0.14224)
		(layer "In11.Cu")
		(net "P5E_CPU1_P1_TX_BUF_DP<4>")
	)
	(arc
		(start 85.495384 -390.553448)
		(mid 85.46163 -390.723051)
		(end 85.36559 -390.866884)
		(width 0.14224)
		(layer "In11.Cu")
		(net "P5E_CPU1_P1_TX_BUF_DP<4>")
	)
	(segment
		(start 83.79841 -389.467344)
		(end 84.31911 -389.467344)
		(width 0.127)
		(layer "F.Cu")
		(net "P5E_CPU1_P1_TX_BUF_DP<3>")
	)
	(segment
		(start 59.108594 -407.27503)
		(end 59.379104 -407.00452)
		(width 0.12954)
		(layer "B.Cu")
		(net "P5E_CPU1_P1_TX_BUF_DP<3>")
	)
	(segment
		(start 59.108594 -407.954734)
		(end 59.108594 -407.27503)
		(width 0.12954)
		(layer "B.Cu")
		(net "P5E_CPU1_P1_TX_BUF_DP<3>")
	)
	(segment
		(start 59.404504 -408.250644)
		(end 59.108594 -407.954734)
		(width 0.12954)
		(layer "B.Cu")
		(net "P5E_CPU1_P1_TX_BUF_DP<3>")
	)
	(segment
		(start 84.295488 -390.176258)
		(end 84.295488 -390.365742)
		(width 0.14224)
		(layer "In11.Cu")
		(net "P5E_CPU1_P1_TX_BUF_DP<3>")
	)
	(segment
		(start 83.521296 -391.682224)
		(end 83.521296 -394.168884)
		(width 0.14224)
		(layer "In11.Cu")
		(net "P5E_CPU1_P1_TX_BUF_DP<3>")
	)
	(segment
		(start 59.088274 -406.71369)
		(end 59.379104 -407.00452)
		(width 0.14224)
		(layer "In11.Cu")
		(net "P5E_CPU1_P1_TX_BUF_DP<3>")
	)
	(segment
		(start 62.629034 -401.771612)
		(end 61.935614 -401.981416)
		(width 0.14224)
		(layer "In11.Cu")
		(net "P5E_CPU1_P1_TX_BUF_DP<3>")
	)
	(segment
		(start 84.097876 -390.842754)
		(end 83.707224 -391.233406)
		(width 0.14224)
		(layer "In11.Cu")
		(net "P5E_CPU1_P1_TX_BUF_DP<3>")
	)
	(segment
		(start 59.088274 -404.184104)
		(end 59.088274 -406.71369)
		(width 0.14224)
		(layer "In11.Cu")
		(net "P5E_CPU1_P1_TX_BUF_DP<3>")
	)
	(segment
		(start 61.935614 -401.981416)
		(end 61.286136 -402.252688)
		(width 0.14224)
		(layer "In11.Cu")
		(net "P5E_CPU1_P1_TX_BUF_DP<3>")
	)
	(segment
		(start 78.088998 -396.774924)
		(end 76.911454 -397.242538)
		(width 0.14224)
		(layer "In11.Cu")
		(net "P5E_CPU1_P1_TX_BUF_DP<3>")
	)
	(segment
		(start 60.129166 -402.880322)
		(end 59.754262 -403.083522)
		(width 0.14224)
		(layer "In11.Cu")
		(net "P5E_CPU1_P1_TX_BUF_DP<3>")
	)
	(segment
		(start 62.790578 -401.857972)
		(end 62.629034 -401.771612)
		(width 0.14224)
		(layer "In11.Cu")
		(net "P5E_CPU1_P1_TX_BUF_DP<3>")
	)
	(segment
		(start 84.027264 -389.738616)
		(end 84.1756 -389.886698)
		(width 0.14224)
		(layer "In11.Cu")
		(net "P5E_CPU1_P1_TX_BUF_DP<3>")
	)
	(segment
		(start 84.31911 -389.467344)
		(end 84.204302 -389.352536)
		(width 0.14224)
		(layer "In11.Cu")
		(net "P5E_CPU1_P1_TX_BUF_DP<3>")
	)
	(segment
		(start 81.201768 -395.82471)
		(end 78.088998 -396.774924)
		(width 0.14224)
		(layer "In11.Cu")
		(net "P5E_CPU1_P1_TX_BUF_DP<3>")
	)
	(segment
		(start 84.204302 -389.352536)
		(end 84.024216 -389.352536)
		(width 0.14224)
		(layer "In11.Cu")
		(net "P5E_CPU1_P1_TX_BUF_DP<3>")
	)
	(segment
		(start 70.181978 -399.48358)
		(end 65.459356 -400.914108)
		(width 0.14224)
		(layer "In11.Cu")
		(net "P5E_CPU1_P1_TX_BUF_DP<3>")
	)
	(segment
		(start 76.911454 -397.242538)
		(end 70.181978 -399.48358)
		(width 0.14224)
		(layer "In11.Cu")
		(net "P5E_CPU1_P1_TX_BUF_DP<3>")
	)
	(segment
		(start 64.94653 -401.202398)
		(end 64.788034 -401.117562)
		(width 0.14224)
		(layer "In11.Cu")
		(net "P5E_CPU1_P1_TX_BUF_DP<3>")
	)
	(segment
		(start 82.42173 -395.318742)
		(end 81.201768 -395.82471)
		(width 0.14224)
		(layer "In11.Cu")
		(net "P5E_CPU1_P1_TX_BUF_DP<3>")
	)
	(segment
		(start 64.788034 -401.117562)
		(end 64.379856 -401.241006)
		(width 0.14224)
		(layer "In11.Cu")
		(net "P5E_CPU1_P1_TX_BUF_DP<3>")
	)
	(segment
		(start 83.934808 -389.441944)
		(end 83.934808 -389.515604)
		(width 0.14224)
		(layer "In11.Cu")
		(net "P5E_CPU1_P1_TX_BUF_DP<3>")
	)
	(segment
		(start 61.286136 -402.252688)
		(end 60.745624 -402.545804)
		(width 0.14224)
		(layer "In11.Cu")
		(net "P5E_CPU1_P1_TX_BUF_DP<3>")
	)
	(segment
		(start 63.300356 -401.568158)
		(end 63.213742 -401.73021)
		(width 0.14224)
		(layer "In11.Cu")
		(net "P5E_CPU1_P1_TX_BUF_DP<3>")
	)
	(segment
		(start 65.374266 -401.072858)
		(end 64.94653 -401.202398)
		(width 0.14224)
		(layer "In11.Cu")
		(net "P5E_CPU1_P1_TX_BUF_DP<3>")
	)
	(segment
		(start 64.29248 -401.404328)
		(end 63.871348 -401.531836)
		(width 0.14224)
		(layer "In11.Cu")
		(net "P5E_CPU1_P1_TX_BUF_DP<3>")
	)
	(segment
		(start 60.745624 -402.545804)
		(end 60.69457 -402.718016)
		(width 0.14224)
		(layer "In11.Cu")
		(net "P5E_CPU1_P1_TX_BUF_DP<3>")
	)
	(segment
		(start 65.459356 -400.914108)
		(end 65.374266 -401.072858)
		(width 0.14224)
		(layer "In11.Cu")
		(net "P5E_CPU1_P1_TX_BUF_DP<3>")
	)
	(segment
		(start 84.024216 -389.352536)
		(end 83.934808 -389.441944)
		(width 0.14224)
		(layer "In11.Cu")
		(net "P5E_CPU1_P1_TX_BUF_DP<3>")
	)
	(segment
		(start 60.301124 -402.931376)
		(end 60.129166 -402.880322)
		(width 0.14224)
		(layer "In11.Cu")
		(net "P5E_CPU1_P1_TX_BUF_DP<3>")
	)
	(segment
		(start 63.708534 -401.444714)
		(end 63.300356 -401.568158)
		(width 0.14224)
		(layer "In11.Cu")
		(net "P5E_CPU1_P1_TX_BUF_DP<3>")
	)
	(segment
		(start 63.871348 -401.531836)
		(end 63.708534 -401.444714)
		(width 0.14224)
		(layer "In11.Cu")
		(net "P5E_CPU1_P1_TX_BUF_DP<3>")
	)
	(segment
		(start 63.213742 -401.73021)
		(end 62.790578 -401.857972)
		(width 0.14224)
		(layer "In11.Cu")
		(net "P5E_CPU1_P1_TX_BUF_DP<3>")
	)
	(segment
		(start 83.401408 -394.45819)
		(end 82.780886 -395.078712)
		(width 0.14224)
		(layer "In11.Cu")
		(net "P5E_CPU1_P1_TX_BUF_DP<3>")
	)
	(segment
		(start 60.69457 -402.718016)
		(end 60.301124 -402.931376)
		(width 0.14224)
		(layer "In11.Cu")
		(net "P5E_CPU1_P1_TX_BUF_DP<3>")
	)
	(segment
		(start 64.379856 -401.241006)
		(end 64.29248 -401.404328)
		(width 0.14224)
		(layer "In11.Cu")
		(net "P5E_CPU1_P1_TX_BUF_DP<3>")
	)
	(segment
		(start 59.754262 -403.083522)
		(end 59.395614 -403.44217)
		(width 0.14224)
		(layer "In11.Cu")
		(net "P5E_CPU1_P1_TX_BUF_DP<3>")
	)
	(arc
		(start 83.521296 -394.168884)
		(mid 83.490133 -394.325462)
		(end 83.401408 -394.45819)
		(width 0.14224)
		(layer "In11.Cu")
		(net "P5E_CPU1_P1_TX_BUF_DP<3>")
	)
	(arc
		(start 83.707224 -391.233406)
		(mid 83.569633 -391.439325)
		(end 83.521296 -391.682224)
		(width 0.14224)
		(layer "In11.Cu")
		(net "P5E_CPU1_P1_TX_BUF_DP<3>")
	)
	(arc
		(start 83.934808 -389.515604)
		(mid 83.958837 -389.636314)
		(end 84.027264 -389.738616)
		(width 0.14224)
		(layer "In11.Cu")
		(net "P5E_CPU1_P1_TX_BUF_DP<3>")
	)
	(arc
		(start 84.1756 -389.886698)
		(mid 84.264393 -390.019536)
		(end 84.295488 -390.176258)
		(width 0.14224)
		(layer "In11.Cu")
		(net "P5E_CPU1_P1_TX_BUF_DP<3>")
	)
	(arc
		(start 59.395614 -403.44217)
		(mid 59.168165 -403.782572)
		(end 59.088274 -404.184104)
		(width 0.14224)
		(layer "In11.Cu")
		(net "P5E_CPU1_P1_TX_BUF_DP<3>")
	)
	(arc
		(start 82.780886 -395.078712)
		(mid 82.613121 -395.216401)
		(end 82.42173 -395.318742)
		(width 0.14224)
		(layer "In11.Cu")
		(net "P5E_CPU1_P1_TX_BUF_DP<3>")
	)
	(arc
		(start 84.295488 -390.365742)
		(mid 84.244135 -390.623909)
		(end 84.097876 -390.842754)
		(width 0.14224)
		(layer "In11.Cu")
		(net "P5E_CPU1_P1_TX_BUF_DP<3>")
	)
	(segment
		(start 82.59826 -389.467344)
		(end 83.11896 -389.467344)
		(width 0.127)
		(layer "F.Cu")
		(net "P5E_CPU1_P1_TX_BUF_DP<2>")
	)
	(segment
		(start 56.045354 -407.954734)
		(end 56.045354 -407.27503)
		(width 0.12954)
		(layer "B.Cu")
		(net "P5E_CPU1_P1_TX_BUF_DP<2>")
	)
	(segment
		(start 56.045354 -407.27503)
		(end 56.315864 -407.00452)
		(width 0.12954)
		(layer "B.Cu")
		(net "P5E_CPU1_P1_TX_BUF_DP<2>")
	)
	(segment
		(start 56.341264 -408.250644)
		(end 56.045354 -407.954734)
		(width 0.12954)
		(layer "B.Cu")
		(net "P5E_CPU1_P1_TX_BUF_DP<2>")
	)
	(segment
		(start 57.611264 -402.489416)
		(end 57.189116 -402.633434)
		(width 0.14224)
		(layer "In11.Cu")
		(net "P5E_CPU1_P1_TX_BUF_DP<2>")
	)
	(segment
		(start 82.736436 -389.46836)
		(end 82.736436 -389.533892)
		(width 0.14224)
		(layer "In11.Cu")
		(net "P5E_CPU1_P1_TX_BUF_DP<2>")
	)
	(segment
		(start 83.032092 -390.146032)
		(end 83.032092 -390.372092)
		(width 0.14224)
		(layer "In11.Cu")
		(net "P5E_CPU1_P1_TX_BUF_DP<2>")
	)
	(segment
		(start 56.025034 -404.25751)
		(end 56.025034 -406.71369)
		(width 0.14224)
		(layer "In11.Cu")
		(net "P5E_CPU1_P1_TX_BUF_DP<2>")
	)
	(segment
		(start 60.324238 -401.707858)
		(end 59.920124 -401.84578)
		(width 0.14224)
		(layer "In11.Cu")
		(net "P5E_CPU1_P1_TX_BUF_DP<2>")
	)
	(segment
		(start 78.1939 -395.751812)
		(end 76.390246 -396.375636)
		(width 0.14224)
		(layer "In11.Cu")
		(net "P5E_CPU1_P1_TX_BUF_DP<2>")
	)
	(segment
		(start 61.40196 -401.16887)
		(end 61.061346 -401.31111)
		(width 0.14224)
		(layer "In11.Cu")
		(net "P5E_CPU1_P1_TX_BUF_DP<2>")
	)
	(segment
		(start 60.409582 -401.533614)
		(end 60.324238 -401.707858)
		(width 0.14224)
		(layer "In11.Cu")
		(net "P5E_CPU1_P1_TX_BUF_DP<2>")
	)
	(segment
		(start 56.025034 -406.71369)
		(end 56.315864 -407.00452)
		(width 0.14224)
		(layer "In11.Cu")
		(net "P5E_CPU1_P1_TX_BUF_DP<2>")
	)
	(segment
		(start 82.187034 -394.351002)
		(end 82.150712 -394.387324)
		(width 0.14224)
		(layer "In11.Cu")
		(net "P5E_CPU1_P1_TX_BUF_DP<2>")
	)
	(segment
		(start 59.342274 -401.898104)
		(end 59.256676 -402.072602)
		(width 0.14224)
		(layer "In11.Cu")
		(net "P5E_CPU1_P1_TX_BUF_DP<2>")
	)
	(segment
		(start 82.306668 -391.680954)
		(end 82.306668 -394.062458)
		(width 0.14224)
		(layer "In11.Cu")
		(net "P5E_CPU1_P1_TX_BUF_DP<2>")
	)
	(segment
		(start 69.745352 -398.641316)
		(end 61.40196 -401.16887)
		(width 0.14224)
		(layer "In11.Cu")
		(net "P5E_CPU1_P1_TX_BUF_DP<2>")
	)
	(segment
		(start 75.474068 -396.738348)
		(end 69.745352 -398.641316)
		(width 0.14224)
		(layer "In11.Cu")
		(net "P5E_CPU1_P1_TX_BUF_DP<2>")
	)
	(segment
		(start 80.972406 -394.908278)
		(end 78.1939 -395.751812)
		(width 0.14224)
		(layer "In11.Cu")
		(net "P5E_CPU1_P1_TX_BUF_DP<2>")
	)
	(segment
		(start 82.878676 -390.74217)
		(end 82.566256 -391.054336)
		(width 0.14224)
		(layer "In11.Cu")
		(net "P5E_CPU1_P1_TX_BUF_DP<2>")
	)
	(segment
		(start 56.769254 -402.895054)
		(end 56.46166 -403.202902)
		(width 0.14224)
		(layer "In11.Cu")
		(net "P5E_CPU1_P1_TX_BUF_DP<2>")
	)
	(segment
		(start 82.017616 -394.476224)
		(end 80.972406 -394.908278)
		(width 0.14224)
		(layer "In11.Cu")
		(net "P5E_CPU1_P1_TX_BUF_DP<2>")
	)
	(segment
		(start 59.920124 -401.84578)
		(end 59.74588 -401.760436)
		(width 0.14224)
		(layer "In11.Cu")
		(net "P5E_CPU1_P1_TX_BUF_DP<2>")
	)
	(segment
		(start 83.003136 -389.35152)
		(end 82.853276 -389.35152)
		(width 0.14224)
		(layer "In11.Cu")
		(net "P5E_CPU1_P1_TX_BUF_DP<2>")
	)
	(segment
		(start 76.390246 -396.375636)
		(end 75.474068 -396.738348)
		(width 0.14224)
		(layer "In11.Cu")
		(net "P5E_CPU1_P1_TX_BUF_DP<2>")
	)
	(segment
		(start 58.678572 -402.124926)
		(end 58.274966 -402.262594)
		(width 0.14224)
		(layer "In11.Cu")
		(net "P5E_CPU1_P1_TX_BUF_DP<2>")
	)
	(segment
		(start 59.74588 -401.760436)
		(end 59.342274 -401.898104)
		(width 0.14224)
		(layer "In11.Cu")
		(net "P5E_CPU1_P1_TX_BUF_DP<2>")
	)
	(segment
		(start 83.11896 -389.467344)
		(end 83.003136 -389.35152)
		(width 0.14224)
		(layer "In11.Cu")
		(net "P5E_CPU1_P1_TX_BUF_DP<2>")
	)
	(segment
		(start 58.852562 -402.210524)
		(end 58.678572 -402.124926)
		(width 0.14224)
		(layer "In11.Cu")
		(net "P5E_CPU1_P1_TX_BUF_DP<2>")
	)
	(segment
		(start 82.853276 -389.35152)
		(end 82.736436 -389.46836)
		(width 0.14224)
		(layer "In11.Cu")
		(net "P5E_CPU1_P1_TX_BUF_DP<2>")
	)
	(segment
		(start 58.274966 -402.262594)
		(end 58.189368 -402.437092)
		(width 0.14224)
		(layer "In11.Cu")
		(net "P5E_CPU1_P1_TX_BUF_DP<2>")
	)
	(segment
		(start 59.256676 -402.072602)
		(end 58.852562 -402.210524)
		(width 0.14224)
		(layer "In11.Cu")
		(net "P5E_CPU1_P1_TX_BUF_DP<2>")
	)
	(segment
		(start 61.061346 -401.31111)
		(end 60.409582 -401.533614)
		(width 0.14224)
		(layer "In11.Cu")
		(net "P5E_CPU1_P1_TX_BUF_DP<2>")
	)
	(segment
		(start 57.785254 -402.575014)
		(end 57.611264 -402.489416)
		(width 0.14224)
		(layer "In11.Cu")
		(net "P5E_CPU1_P1_TX_BUF_DP<2>")
	)
	(segment
		(start 58.189368 -402.437092)
		(end 57.785254 -402.575014)
		(width 0.14224)
		(layer "In11.Cu")
		(net "P5E_CPU1_P1_TX_BUF_DP<2>")
	)
	(segment
		(start 82.817208 -389.72871)
		(end 82.888582 -389.79983)
		(width 0.14224)
		(layer "In11.Cu")
		(net "P5E_CPU1_P1_TX_BUF_DP<2>")
	)
	(arc
		(start 82.566256 -391.054336)
		(mid 82.374134 -391.341817)
		(end 82.306668 -391.680954)
		(width 0.14224)
		(layer "In11.Cu")
		(net "P5E_CPU1_P1_TX_BUF_DP<2>")
	)
	(arc
		(start 82.306668 -394.062458)
		(mid 82.275529 -394.218622)
		(end 82.187034 -394.351002)
		(width 0.14224)
		(layer "In11.Cu")
		(net "P5E_CPU1_P1_TX_BUF_DP<2>")
	)
	(arc
		(start 83.032092 -390.372092)
		(mid 82.992175 -390.572385)
		(end 82.878676 -390.74217)
		(width 0.14224)
		(layer "In11.Cu")
		(net "P5E_CPU1_P1_TX_BUF_DP<2>")
	)
	(arc
		(start 82.150712 -394.387324)
		(mid 82.088543 -394.438327)
		(end 82.017616 -394.476224)
		(width 0.14224)
		(layer "In11.Cu")
		(net "P5E_CPU1_P1_TX_BUF_DP<2>")
	)
	(arc
		(start 57.189116 -402.633434)
		(mid 56.964157 -402.740129)
		(end 56.769254 -402.895054)
		(width 0.14224)
		(layer "In11.Cu")
		(net "P5E_CPU1_P1_TX_BUF_DP<2>")
	)
	(arc
		(start 82.736436 -389.533892)
		(mid 82.757429 -389.639341)
		(end 82.817208 -389.72871)
		(width 0.14224)
		(layer "In11.Cu")
		(net "P5E_CPU1_P1_TX_BUF_DP<2>")
	)
	(arc
		(start 56.46166 -403.202902)
		(mid 56.138542 -403.686816)
		(end 56.025034 -404.25751)
		(width 0.14224)
		(layer "In11.Cu")
		(net "P5E_CPU1_P1_TX_BUF_DP<2>")
	)
	(arc
		(start 82.888582 -389.79983)
		(mid 82.994822 -389.95864)
		(end 83.032092 -390.146032)
		(width 0.14224)
		(layer "In11.Cu")
		(net "P5E_CPU1_P1_TX_BUF_DP<2>")
	)
	(segment
		(start 81.398364 -389.467344)
		(end 81.919064 -389.467344)
		(width 0.127)
		(layer "F.Cu")
		(net "P5E_CPU1_P1_TX_BUF_DP<1>")
	)
	(segment
		(start 52.982114 -407.27503)
		(end 53.252624 -407.00452)
		(width 0.12954)
		(layer "B.Cu")
		(net "P5E_CPU1_P1_TX_BUF_DP<1>")
	)
	(segment
		(start 52.982114 -407.954734)
		(end 52.982114 -407.27503)
		(width 0.12954)
		(layer "B.Cu")
		(net "P5E_CPU1_P1_TX_BUF_DP<1>")
	)
	(segment
		(start 53.278024 -408.250644)
		(end 52.982114 -407.954734)
		(width 0.12954)
		(layer "B.Cu")
		(net "P5E_CPU1_P1_TX_BUF_DP<1>")
	)
	(segment
		(start 80.71739 -391.285984)
		(end 80.127856 -391.285984)
		(width 0.14224)
		(layer "In11.Cu")
		(net "P5E_CPU1_P1_TX_BUF_DP<1>")
	)
	(segment
		(start 55.408068 -402.001228)
		(end 54.648862 -402.230844)
		(width 0.14224)
		(layer "In11.Cu")
		(net "P5E_CPU1_P1_TX_BUF_DP<1>")
	)
	(segment
		(start 69.143118 -397.849344)
		(end 58.238898 -401.145502)
		(width 0.14224)
		(layer "In11.Cu")
		(net "P5E_CPU1_P1_TX_BUF_DP<1>")
	)
	(segment
		(start 57.567576 -401.348448)
		(end 57.159144 -401.471892)
		(width 0.14224)
		(layer "In11.Cu")
		(net "P5E_CPU1_P1_TX_BUF_DP<1>")
	)
	(segment
		(start 81.582006 -389.687816)
		(end 81.771998 -389.877808)
		(width 0.14224)
		(layer "In11.Cu")
		(net "P5E_CPU1_P1_TX_BUF_DP<1>")
	)
	(segment
		(start 58.238898 -401.145502)
		(end 58.147204 -401.316698)
		(width 0.14224)
		(layer "In11.Cu")
		(net "P5E_CPU1_P1_TX_BUF_DP<1>")
	)
	(segment
		(start 81.771998 -390.531096)
		(end 81.228438 -391.074402)
		(width 0.14224)
		(layer "In11.Cu")
		(net "P5E_CPU1_P1_TX_BUF_DP<1>")
	)
	(segment
		(start 52.961794 -404.184104)
		(end 52.961794 -406.71369)
		(width 0.14224)
		(layer "In11.Cu")
		(net "P5E_CPU1_P1_TX_BUF_DP<1>")
	)
	(segment
		(start 57.067704 -401.643088)
		(end 56.659018 -401.766532)
		(width 0.14224)
		(layer "In11.Cu")
		(net "P5E_CPU1_P1_TX_BUF_DP<1>")
	)
	(segment
		(start 57.738518 -401.440142)
		(end 57.567576 -401.348448)
		(width 0.14224)
		(layer "In11.Cu")
		(net "P5E_CPU1_P1_TX_BUF_DP<1>")
	)
	(segment
		(start 58.147204 -401.316698)
		(end 57.738518 -401.440142)
		(width 0.14224)
		(layer "In11.Cu")
		(net "P5E_CPU1_P1_TX_BUF_DP<1>")
	)
	(segment
		(start 56.659018 -401.766532)
		(end 56.487822 -401.674838)
		(width 0.14224)
		(layer "In11.Cu")
		(net "P5E_CPU1_P1_TX_BUF_DP<1>")
	)
	(segment
		(start 79.49057 -393.23645)
		(end 78.000352 -394.726668)
		(width 0.14224)
		(layer "In11.Cu")
		(net "P5E_CPU1_P1_TX_BUF_DP<1>")
	)
	(segment
		(start 81.919064 -389.467344)
		(end 81.804256 -389.352536)
		(width 0.14224)
		(layer "In11.Cu")
		(net "P5E_CPU1_P1_TX_BUF_DP<1>")
	)
	(segment
		(start 55.98795 -401.969478)
		(end 55.579264 -402.092922)
		(width 0.14224)
		(layer "In11.Cu")
		(net "P5E_CPU1_P1_TX_BUF_DP<1>")
	)
	(segment
		(start 53.581554 -402.869908)
		(end 53.45303 -402.998432)
		(width 0.14224)
		(layer "In11.Cu")
		(net "P5E_CPU1_P1_TX_BUF_DP<1>")
	)
	(segment
		(start 76.479908 -395.356588)
		(end 71.753984 -396.788132)
		(width 0.14224)
		(layer "In11.Cu")
		(net "P5E_CPU1_P1_TX_BUF_DP<1>")
	)
	(segment
		(start 81.62417 -389.352536)
		(end 81.534762 -389.441944)
		(width 0.14224)
		(layer "In11.Cu")
		(net "P5E_CPU1_P1_TX_BUF_DP<1>")
	)
	(segment
		(start 55.579264 -402.092922)
		(end 55.408068 -402.001228)
		(width 0.14224)
		(layer "In11.Cu")
		(net "P5E_CPU1_P1_TX_BUF_DP<1>")
	)
	(segment
		(start 78.000352 -394.726668)
		(end 76.479908 -395.356588)
		(width 0.14224)
		(layer "In11.Cu")
		(net "P5E_CPU1_P1_TX_BUF_DP<1>")
	)
	(segment
		(start 56.07939 -401.798282)
		(end 55.98795 -401.969478)
		(width 0.14224)
		(layer "In11.Cu")
		(net "P5E_CPU1_P1_TX_BUF_DP<1>")
	)
	(segment
		(start 71.753984 -396.788132)
		(end 69.143118 -397.849344)
		(width 0.14224)
		(layer "In11.Cu")
		(net "P5E_CPU1_P1_TX_BUF_DP<1>")
	)
	(segment
		(start 56.487822 -401.674838)
		(end 56.07939 -401.798282)
		(width 0.14224)
		(layer "In11.Cu")
		(net "P5E_CPU1_P1_TX_BUF_DP<1>")
	)
	(segment
		(start 79.714598 -391.898378)
		(end 79.714598 -392.695684)
		(width 0.14224)
		(layer "In11.Cu")
		(net "P5E_CPU1_P1_TX_BUF_DP<1>")
	)
	(segment
		(start 81.804256 -389.352536)
		(end 81.62417 -389.352536)
		(width 0.14224)
		(layer "In11.Cu")
		(net "P5E_CPU1_P1_TX_BUF_DP<1>")
	)
	(segment
		(start 57.159144 -401.471892)
		(end 57.067704 -401.643088)
		(width 0.14224)
		(layer "In11.Cu")
		(net "P5E_CPU1_P1_TX_BUF_DP<1>")
	)
	(segment
		(start 52.961794 -406.71369)
		(end 53.252624 -407.00452)
		(width 0.14224)
		(layer "In11.Cu")
		(net "P5E_CPU1_P1_TX_BUF_DP<1>")
	)
	(segment
		(start 81.534762 -389.441944)
		(end 81.534762 -389.57377)
		(width 0.14224)
		(layer "In11.Cu")
		(net "P5E_CPU1_P1_TX_BUF_DP<1>")
	)
	(arc
		(start 81.771998 -389.877808)
		(mid 81.907373 -390.204452)
		(end 81.771998 -390.531096)
		(width 0.14224)
		(layer "In11.Cu")
		(net "P5E_CPU1_P1_TX_BUF_DP<1>")
	)
	(arc
		(start 81.534762 -389.57377)
		(mid 81.547039 -389.635493)
		(end 81.582006 -389.687816)
		(width 0.14224)
		(layer "In11.Cu")
		(net "P5E_CPU1_P1_TX_BUF_DP<1>")
	)
	(arc
		(start 54.648862 -402.230844)
		(mid 54.075732 -402.484444)
		(end 53.581554 -402.869908)
		(width 0.14224)
		(layer "In11.Cu")
		(net "P5E_CPU1_P1_TX_BUF_DP<1>")
	)
	(arc
		(start 79.93507 -391.36574)
		(mid 79.771788 -391.610104)
		(end 79.714598 -391.898378)
		(width 0.14224)
		(layer "In11.Cu")
		(net "P5E_CPU1_P1_TX_BUF_DP<1>")
	)
	(arc
		(start 79.714598 -392.695684)
		(mid 79.656382 -392.988358)
		(end 79.49057 -393.23645)
		(width 0.14224)
		(layer "In11.Cu")
		(net "P5E_CPU1_P1_TX_BUF_DP<1>")
	)
	(arc
		(start 53.45303 -402.998432)
		(mid 53.089439 -403.542394)
		(end 52.961794 -404.184104)
		(width 0.14224)
		(layer "In11.Cu")
		(net "P5E_CPU1_P1_TX_BUF_DP<1>")
	)
	(arc
		(start 80.127856 -391.285984)
		(mid 80.023559 -391.30673)
		(end 79.93507 -391.36574)
		(width 0.14224)
		(layer "In11.Cu")
		(net "P5E_CPU1_P1_TX_BUF_DP<1>")
	)
	(arc
		(start 81.228438 -391.074402)
		(mid 80.993953 -391.231017)
		(end 80.71739 -391.285984)
		(width 0.14224)
		(layer "In11.Cu")
		(net "P5E_CPU1_P1_TX_BUF_DP<1>")
	)
	(segment
		(start 98.198432 -389.467344)
		(end 98.719132 -389.467344)
		(width 0.127)
		(layer "F.Cu")
		(net "P5E_CPU1_P1_TX_BUF_DP<15>")
	)
	(segment
		(start 96.163384 -408.250644)
		(end 95.867474 -407.954734)
		(width 0.12954)
		(layer "B.Cu")
		(net "P5E_CPU1_P1_TX_BUF_DP<15>")
	)
	(segment
		(start 95.867474 -407.27503)
		(end 96.137984 -407.00452)
		(width 0.12954)
		(layer "B.Cu")
		(net "P5E_CPU1_P1_TX_BUF_DP<15>")
	)
	(segment
		(start 95.867474 -407.954734)
		(end 95.867474 -407.27503)
		(width 0.12954)
		(layer "B.Cu")
		(net "P5E_CPU1_P1_TX_BUF_DP<15>")
	)
	(segment
		(start 96.926908 -401.059142)
		(end 96.759268 -401.159472)
		(width 0.14224)
		(layer "In11.Cu")
		(net "P5E_CPU1_P1_TX_BUF_DP<15>")
	)
	(segment
		(start 97.930462 -391.653014)
		(end 97.930462 -396.158974)
		(width 0.14224)
		(layer "In11.Cu")
		(net "P5E_CPU1_P1_TX_BUF_DP<15>")
	)
	(segment
		(start 95.829628 -406.696164)
		(end 96.137984 -407.00452)
		(width 0.14224)
		(layer "In11.Cu")
		(net "P5E_CPU1_P1_TX_BUF_DP<15>")
	)
	(segment
		(start 96.933258 -400.482562)
		(end 97.03054 -400.644868)
		(width 0.14224)
		(layer "In11.Cu")
		(net "P5E_CPU1_P1_TX_BUF_DP<15>")
	)
	(segment
		(start 98.33483 -389.441944)
		(end 98.33483 -389.47725)
		(width 0.14224)
		(layer "In11.Cu")
		(net "P5E_CPU1_P1_TX_BUF_DP<15>")
	)
	(segment
		(start 98.50247 -391.076688)
		(end 97.93351 -391.645648)
		(width 0.14224)
		(layer "In11.Cu")
		(net "P5E_CPU1_P1_TX_BUF_DP<15>")
	)
	(segment
		(start 96.759268 -401.159472)
		(end 95.829628 -404.870158)
		(width 0.14224)
		(layer "In11.Cu")
		(net "P5E_CPU1_P1_TX_BUF_DP<15>")
	)
	(segment
		(start 97.308416 -398.970754)
		(end 97.204784 -399.38452)
		(width 0.14224)
		(layer "In11.Cu")
		(net "P5E_CPU1_P1_TX_BUF_DP<15>")
	)
	(segment
		(start 97.204784 -399.38452)
		(end 97.304606 -399.55089)
		(width 0.14224)
		(layer "In11.Cu")
		(net "P5E_CPU1_P1_TX_BUF_DP<15>")
	)
	(segment
		(start 98.424238 -389.352536)
		(end 98.33483 -389.441944)
		(width 0.14224)
		(layer "In11.Cu")
		(net "P5E_CPU1_P1_TX_BUF_DP<15>")
	)
	(segment
		(start 98.604324 -389.352536)
		(end 98.424238 -389.352536)
		(width 0.14224)
		(layer "In11.Cu")
		(net "P5E_CPU1_P1_TX_BUF_DP<15>")
	)
	(segment
		(start 95.829628 -404.870158)
		(end 95.829628 -406.696164)
		(width 0.14224)
		(layer "In11.Cu")
		(net "P5E_CPU1_P1_TX_BUF_DP<15>")
	)
	(segment
		(start 97.038414 -400.062192)
		(end 96.933258 -400.482562)
		(width 0.14224)
		(layer "In11.Cu")
		(net "P5E_CPU1_P1_TX_BUF_DP<15>")
	)
	(segment
		(start 97.47504 -398.871186)
		(end 97.308416 -398.970754)
		(width 0.14224)
		(layer "In11.Cu")
		(net "P5E_CPU1_P1_TX_BUF_DP<15>")
	)
	(segment
		(start 97.578672 -398.456912)
		(end 97.47504 -398.871186)
		(width 0.14224)
		(layer "In11.Cu")
		(net "P5E_CPU1_P1_TX_BUF_DP<15>")
	)
	(segment
		(start 97.03054 -400.644868)
		(end 96.926908 -401.059142)
		(width 0.14224)
		(layer "In11.Cu")
		(net "P5E_CPU1_P1_TX_BUF_DP<15>")
	)
	(segment
		(start 97.850452 -396.806928)
		(end 97.47885 -398.290542)
		(width 0.14224)
		(layer "In11.Cu")
		(net "P5E_CPU1_P1_TX_BUF_DP<15>")
	)
	(segment
		(start 97.47885 -398.290542)
		(end 97.578672 -398.456912)
		(width 0.14224)
		(layer "In11.Cu")
		(net "P5E_CPU1_P1_TX_BUF_DP<15>")
	)
	(segment
		(start 98.454464 -389.765794)
		(end 98.575622 -389.886952)
		(width 0.14224)
		(layer "In11.Cu")
		(net "P5E_CPU1_P1_TX_BUF_DP<15>")
	)
	(segment
		(start 98.719132 -389.467344)
		(end 98.604324 -389.352536)
		(width 0.14224)
		(layer "In11.Cu")
		(net "P5E_CPU1_P1_TX_BUF_DP<15>")
	)
	(segment
		(start 98.69551 -390.176512)
		(end 98.69551 -390.610344)
		(width 0.14224)
		(layer "In11.Cu")
		(net "P5E_CPU1_P1_TX_BUF_DP<15>")
	)
	(segment
		(start 97.304606 -399.55089)
		(end 97.200974 -399.965164)
		(width 0.14224)
		(layer "In11.Cu")
		(net "P5E_CPU1_P1_TX_BUF_DP<15>")
	)
	(segment
		(start 97.200974 -399.965164)
		(end 97.038414 -400.062192)
		(width 0.14224)
		(layer "In11.Cu")
		(net "P5E_CPU1_P1_TX_BUF_DP<15>")
	)
	(arc
		(start 98.69551 -390.610344)
		(mid 98.645453 -390.862758)
		(end 98.50247 -391.076688)
		(width 0.14224)
		(layer "In11.Cu")
		(net "P5E_CPU1_P1_TX_BUF_DP<15>")
	)
	(arc
		(start 98.575622 -389.886952)
		(mid 98.664337 -390.019817)
		(end 98.69551 -390.176512)
		(width 0.14224)
		(layer "In11.Cu")
		(net "P5E_CPU1_P1_TX_BUF_DP<15>")
	)
	(arc
		(start 97.930462 -396.158974)
		(mid 97.910349 -396.485407)
		(end 97.850452 -396.806928)
		(width 0.14224)
		(layer "In11.Cu")
		(net "P5E_CPU1_P1_TX_BUF_DP<15>")
	)
	(arc
		(start 98.33483 -389.47725)
		(mid 98.365931 -389.633424)
		(end 98.454464 -389.765794)
		(width 0.14224)
		(layer "In11.Cu")
		(net "P5E_CPU1_P1_TX_BUF_DP<15>")
	)
	(arc
		(start 97.93351 -391.645648)
		(mid 97.931252 -391.649028)
		(end 97.930462 -391.653014)
		(width 0.14224)
		(layer "In11.Cu")
		(net "P5E_CPU1_P1_TX_BUF_DP<15>")
	)
	(segment
		(start 96.998282 -389.467344)
		(end 97.518982 -389.467344)
		(width 0.127)
		(layer "F.Cu")
		(net "P5E_CPU1_P1_TX_BUF_DP<14>")
	)
	(segment
		(start 92.804234 -407.27503)
		(end 93.074744 -407.00452)
		(width 0.12954)
		(layer "B.Cu")
		(net "P5E_CPU1_P1_TX_BUF_DP<14>")
	)
	(segment
		(start 92.804234 -407.954734)
		(end 92.804234 -407.27503)
		(width 0.12954)
		(layer "B.Cu")
		(net "P5E_CPU1_P1_TX_BUF_DP<14>")
	)
	(segment
		(start 93.100144 -408.250644)
		(end 92.804234 -407.954734)
		(width 0.12954)
		(layer "B.Cu")
		(net "P5E_CPU1_P1_TX_BUF_DP<14>")
	)
	(segment
		(start 92.783914 -406.71369)
		(end 93.074744 -407.00452)
		(width 0.14224)
		(layer "In11.Cu")
		(net "P5E_CPU1_P1_TX_BUF_DP<14>")
	)
	(segment
		(start 97.228152 -391.155682)
		(end 96.743012 -391.640822)
		(width 0.14224)
		(layer "In11.Cu")
		(net "P5E_CPU1_P1_TX_BUF_DP<14>")
	)
	(segment
		(start 95.887032 -397.720312)
		(end 95.95231 -397.902938)
		(width 0.14224)
		(layer "In11.Cu")
		(net "P5E_CPU1_P1_TX_BUF_DP<14>")
	)
	(segment
		(start 95.95231 -397.902938)
		(end 95.769938 -398.289018)
		(width 0.14224)
		(layer "In11.Cu")
		(net "P5E_CPU1_P1_TX_BUF_DP<14>")
	)
	(segment
		(start 95.470218 -398.922748)
		(end 95.287846 -399.308828)
		(width 0.14224)
		(layer "In11.Cu")
		(net "P5E_CPU1_P1_TX_BUF_DP<14>")
	)
	(segment
		(start 95.287846 -399.308828)
		(end 95.104966 -399.37436)
		(width 0.14224)
		(layer "In11.Cu")
		(net "P5E_CPU1_P1_TX_BUF_DP<14>")
	)
	(segment
		(start 95.587058 -398.35455)
		(end 95.40494 -398.740122)
		(width 0.14224)
		(layer "In11.Cu")
		(net "P5E_CPU1_P1_TX_BUF_DP<14>")
	)
	(segment
		(start 97.172272 -389.673338)
		(end 97.350326 -389.851138)
		(width 0.14224)
		(layer "In11.Cu")
		(net "P5E_CPU1_P1_TX_BUF_DP<14>")
	)
	(segment
		(start 97.518982 -389.467344)
		(end 97.404174 -389.352536)
		(width 0.14224)
		(layer "In11.Cu")
		(net "P5E_CPU1_P1_TX_BUF_DP<14>")
	)
	(segment
		(start 94.922848 -399.759932)
		(end 94.988126 -399.942558)
		(width 0.14224)
		(layer "In11.Cu")
		(net "P5E_CPU1_P1_TX_BUF_DP<14>")
	)
	(segment
		(start 94.988126 -399.942558)
		(end 94.805754 -400.328638)
		(width 0.14224)
		(layer "In11.Cu")
		(net "P5E_CPU1_P1_TX_BUF_DP<14>")
	)
	(segment
		(start 94.620334 -400.395186)
		(end 92.783914 -404.280624)
		(width 0.14224)
		(layer "In11.Cu")
		(net "P5E_CPU1_P1_TX_BUF_DP<14>")
	)
	(segment
		(start 95.40494 -398.740122)
		(end 95.470218 -398.922748)
		(width 0.14224)
		(layer "In11.Cu")
		(net "P5E_CPU1_P1_TX_BUF_DP<14>")
	)
	(segment
		(start 97.224342 -389.352536)
		(end 97.134934 -389.441944)
		(width 0.14224)
		(layer "In11.Cu")
		(net "P5E_CPU1_P1_TX_BUF_DP<14>")
	)
	(segment
		(start 92.783914 -404.280624)
		(end 92.783914 -406.71369)
		(width 0.14224)
		(layer "In11.Cu")
		(net "P5E_CPU1_P1_TX_BUF_DP<14>")
	)
	(segment
		(start 97.134934 -389.441944)
		(end 97.134934 -389.583422)
		(width 0.14224)
		(layer "In11.Cu")
		(net "P5E_CPU1_P1_TX_BUF_DP<14>")
	)
	(segment
		(start 96.730312 -391.671302)
		(end 96.730312 -395.423136)
		(width 0.14224)
		(layer "In11.Cu")
		(net "P5E_CPU1_P1_TX_BUF_DP<14>")
	)
	(segment
		(start 97.470214 -390.140698)
		(end 97.470214 -390.57072)
		(width 0.14224)
		(layer "In11.Cu")
		(net "P5E_CPU1_P1_TX_BUF_DP<14>")
	)
	(segment
		(start 97.404174 -389.352536)
		(end 97.224342 -389.352536)
		(width 0.14224)
		(layer "In11.Cu")
		(net "P5E_CPU1_P1_TX_BUF_DP<14>")
	)
	(segment
		(start 94.805754 -400.328638)
		(end 94.620334 -400.395186)
		(width 0.14224)
		(layer "In11.Cu")
		(net "P5E_CPU1_P1_TX_BUF_DP<14>")
	)
	(segment
		(start 96.06915 -397.33474)
		(end 95.887032 -397.720312)
		(width 0.14224)
		(layer "In11.Cu")
		(net "P5E_CPU1_P1_TX_BUF_DP<14>")
	)
	(segment
		(start 95.104966 -399.37436)
		(end 94.922848 -399.759932)
		(width 0.14224)
		(layer "In11.Cu")
		(net "P5E_CPU1_P1_TX_BUF_DP<14>")
	)
	(segment
		(start 95.769938 -398.289018)
		(end 95.587058 -398.35455)
		(width 0.14224)
		(layer "In11.Cu")
		(net "P5E_CPU1_P1_TX_BUF_DP<14>")
	)
	(arc
		(start 96.743012 -391.640822)
		(mid 96.733614 -391.654792)
		(end 96.730312 -391.671302)
		(width 0.14224)
		(layer "In11.Cu")
		(net "P5E_CPU1_P1_TX_BUF_DP<14>")
	)
	(arc
		(start 97.470214 -390.57072)
		(mid 97.407412 -390.887302)
		(end 97.228152 -391.155682)
		(width 0.14224)
		(layer "In11.Cu")
		(net "P5E_CPU1_P1_TX_BUF_DP<14>")
	)
	(arc
		(start 96.730312 -395.423136)
		(mid 96.560412 -396.434519)
		(end 96.06915 -397.33474)
		(width 0.14224)
		(layer "In11.Cu")
		(net "P5E_CPU1_P1_TX_BUF_DP<14>")
	)
	(arc
		(start 97.350326 -389.851138)
		(mid 97.439119 -389.983976)
		(end 97.470214 -390.140698)
		(width 0.14224)
		(layer "In11.Cu")
		(net "P5E_CPU1_P1_TX_BUF_DP<14>")
	)
	(arc
		(start 97.134934 -389.583422)
		(mid 97.144636 -389.632106)
		(end 97.172272 -389.673338)
		(width 0.14224)
		(layer "In11.Cu")
		(net "P5E_CPU1_P1_TX_BUF_DP<14>")
	)
	(segment
		(start 95.798386 -389.467344)
		(end 96.319086 -389.467344)
		(width 0.127)
		(layer "F.Cu")
		(net "P5E_CPU1_P1_TX_BUF_DP<13>")
	)
	(segment
		(start 90.036904 -408.250644)
		(end 89.740994 -407.954734)
		(width 0.12954)
		(layer "B.Cu")
		(net "P5E_CPU1_P1_TX_BUF_DP<13>")
	)
	(segment
		(start 89.740994 -407.27503)
		(end 90.011504 -407.00452)
		(width 0.12954)
		(layer "B.Cu")
		(net "P5E_CPU1_P1_TX_BUF_DP<13>")
	)
	(segment
		(start 89.740994 -407.954734)
		(end 89.740994 -407.27503)
		(width 0.12954)
		(layer "B.Cu")
		(net "P5E_CPU1_P1_TX_BUF_DP<13>")
	)
	(segment
		(start 89.720674 -404.173182)
		(end 89.720674 -406.71369)
		(width 0.14224)
		(layer "In11.Cu")
		(net "P5E_CPU1_P1_TX_BUF_DP<13>")
	)
	(segment
		(start 96.204278 -389.352536)
		(end 96.024192 -389.352536)
		(width 0.14224)
		(layer "In11.Cu")
		(net "P5E_CPU1_P1_TX_BUF_DP<13>")
	)
	(segment
		(start 96.352868 -390.365996)
		(end 96.352868 -390.425686)
		(width 0.14224)
		(layer "In11.Cu")
		(net "P5E_CPU1_P1_TX_BUF_DP<13>")
	)
	(segment
		(start 91.151456 -402.126196)
		(end 90.390726 -403.150324)
		(width 0.14224)
		(layer "In11.Cu")
		(net "P5E_CPU1_P1_TX_BUF_DP<13>")
	)
	(segment
		(start 96.088962 -391.062718)
		(end 95.57766 -391.57402)
		(width 0.14224)
		(layer "In11.Cu")
		(net "P5E_CPU1_P1_TX_BUF_DP<13>")
	)
	(segment
		(start 92.496386 -400.315176)
		(end 92.242132 -400.657568)
		(width 0.14224)
		(layer "In11.Cu")
		(net "P5E_CPU1_P1_TX_BUF_DP<13>")
	)
	(segment
		(start 91.343226 -402.098002)
		(end 91.151456 -402.126196)
		(width 0.14224)
		(layer "In11.Cu")
		(net "P5E_CPU1_P1_TX_BUF_DP<13>")
	)
	(segment
		(start 95.530416 -391.688066)
		(end 95.530416 -395.595094)
		(width 0.14224)
		(layer "In11.Cu")
		(net "P5E_CPU1_P1_TX_BUF_DP<13>")
	)
	(segment
		(start 96.024192 -389.352536)
		(end 95.934784 -389.441944)
		(width 0.14224)
		(layer "In11.Cu")
		(net "P5E_CPU1_P1_TX_BUF_DP<13>")
	)
	(segment
		(start 95.934784 -389.441944)
		(end 95.934784 -389.528304)
		(width 0.14224)
		(layer "In11.Cu")
		(net "P5E_CPU1_P1_TX_BUF_DP<13>")
	)
	(segment
		(start 96.01835 -389.72998)
		(end 96.139762 -389.851392)
		(width 0.14224)
		(layer "In11.Cu")
		(net "P5E_CPU1_P1_TX_BUF_DP<13>")
	)
	(segment
		(start 90.15222 -403.489414)
		(end 89.742264 -404.101808)
		(width 0.14224)
		(layer "In11.Cu")
		(net "P5E_CPU1_P1_TX_BUF_DP<13>")
	)
	(segment
		(start 91.597988 -401.755102)
		(end 91.343226 -402.098002)
		(width 0.14224)
		(layer "In11.Cu")
		(net "P5E_CPU1_P1_TX_BUF_DP<13>")
	)
	(segment
		(start 92.68841 -400.286728)
		(end 92.496386 -400.315176)
		(width 0.14224)
		(layer "In11.Cu")
		(net "P5E_CPU1_P1_TX_BUF_DP<13>")
	)
	(segment
		(start 96.319086 -389.467344)
		(end 96.204278 -389.352536)
		(width 0.14224)
		(layer "In11.Cu")
		(net "P5E_CPU1_P1_TX_BUF_DP<13>")
	)
	(segment
		(start 94.395036 -397.759174)
		(end 92.914724 -399.752058)
		(width 0.14224)
		(layer "In11.Cu")
		(net "P5E_CPU1_P1_TX_BUF_DP<13>")
	)
	(segment
		(start 92.270326 -400.849592)
		(end 92.015818 -401.192238)
		(width 0.14224)
		(layer "In11.Cu")
		(net "P5E_CPU1_P1_TX_BUF_DP<13>")
	)
	(segment
		(start 91.822778 -401.22094)
		(end 91.569286 -401.562062)
		(width 0.14224)
		(layer "In11.Cu")
		(net "P5E_CPU1_P1_TX_BUF_DP<13>")
	)
	(segment
		(start 91.569286 -401.562062)
		(end 91.597988 -401.755102)
		(width 0.14224)
		(layer "In11.Cu")
		(net "P5E_CPU1_P1_TX_BUF_DP<13>")
	)
	(segment
		(start 92.942918 -399.944082)
		(end 92.68841 -400.286728)
		(width 0.14224)
		(layer "In11.Cu")
		(net "P5E_CPU1_P1_TX_BUF_DP<13>")
	)
	(segment
		(start 92.015818 -401.192238)
		(end 91.822778 -401.22094)
		(width 0.14224)
		(layer "In11.Cu")
		(net "P5E_CPU1_P1_TX_BUF_DP<13>")
	)
	(segment
		(start 92.242132 -400.657568)
		(end 92.270326 -400.849592)
		(width 0.14224)
		(layer "In11.Cu")
		(net "P5E_CPU1_P1_TX_BUF_DP<13>")
	)
	(segment
		(start 89.720674 -406.71369)
		(end 90.011504 -407.00452)
		(width 0.14224)
		(layer "In11.Cu")
		(net "P5E_CPU1_P1_TX_BUF_DP<13>")
	)
	(segment
		(start 92.914724 -399.752058)
		(end 92.942918 -399.944082)
		(width 0.14224)
		(layer "In11.Cu")
		(net "P5E_CPU1_P1_TX_BUF_DP<13>")
	)
	(arc
		(start 96.352868 -390.425686)
		(mid 96.284235 -390.770435)
		(end 96.088962 -391.062718)
		(width 0.14224)
		(layer "In11.Cu")
		(net "P5E_CPU1_P1_TX_BUF_DP<13>")
	)
	(arc
		(start 96.139762 -389.851392)
		(mid 96.297467 -390.087509)
		(end 96.352868 -390.365996)
		(width 0.14224)
		(layer "In11.Cu")
		(net "P5E_CPU1_P1_TX_BUF_DP<13>")
	)
	(arc
		(start 95.530416 -395.595094)
		(mid 95.528203 -395.67434)
		(end 95.521526 -395.753336)
		(width 0.14224)
		(layer "In11.Cu")
		(net "P5E_CPU1_P1_TX_BUF_DP<13>")
	)
	(arc
		(start 95.350584 -396.39748)
		(mid 95.292912 -396.512298)
		(end 95.222822 -396.619984)
		(width 0.14224)
		(layer "In11.Cu")
		(net "P5E_CPU1_P1_TX_BUF_DP<13>")
	)
	(arc
		(start 89.742264 -404.101808)
		(mid 89.726128 -404.135886)
		(end 89.720674 -404.173182)
		(width 0.14224)
		(layer "In11.Cu")
		(net "P5E_CPU1_P1_TX_BUF_DP<13>")
	)
	(arc
		(start 95.57766 -391.57402)
		(mid 95.542698 -391.626345)
		(end 95.530416 -391.688066)
		(width 0.14224)
		(layer "In11.Cu")
		(net "P5E_CPU1_P1_TX_BUF_DP<13>")
	)
	(arc
		(start 95.934784 -389.528304)
		(mid 95.956497 -389.637461)
		(end 96.01835 -389.72998)
		(width 0.14224)
		(layer "In11.Cu")
		(net "P5E_CPU1_P1_TX_BUF_DP<13>")
	)
	(arc
		(start 90.390726 -403.150324)
		(mid 90.269431 -403.318433)
		(end 90.15222 -403.489414)
		(width 0.14224)
		(layer "In11.Cu")
		(net "P5E_CPU1_P1_TX_BUF_DP<13>")
	)
	(arc
		(start 95.222822 -396.619984)
		(mid 94.81174 -397.191621)
		(end 94.395036 -397.759174)
		(width 0.14224)
		(layer "In11.Cu")
		(net "P5E_CPU1_P1_TX_BUF_DP<13>")
	)
	(arc
		(start 95.521526 -395.753336)
		(mid 95.459775 -396.081704)
		(end 95.350584 -396.39748)
		(width 0.14224)
		(layer "In11.Cu")
		(net "P5E_CPU1_P1_TX_BUF_DP<13>")
	)
	(segment
		(start 94.598236 -389.467344)
		(end 95.118936 -389.467344)
		(width 0.127)
		(layer "F.Cu")
		(net "P5E_CPU1_P1_TX_BUF_DP<12>")
	)
	(segment
		(start 86.973664 -408.250644)
		(end 86.677754 -407.954734)
		(width 0.12954)
		(layer "B.Cu")
		(net "P5E_CPU1_P1_TX_BUF_DP<12>")
	)
	(segment
		(start 86.677754 -407.27503)
		(end 86.948264 -407.00452)
		(width 0.12954)
		(layer "B.Cu")
		(net "P5E_CPU1_P1_TX_BUF_DP<12>")
	)
	(segment
		(start 86.677754 -407.954734)
		(end 86.677754 -407.27503)
		(width 0.12954)
		(layer "B.Cu")
		(net "P5E_CPU1_P1_TX_BUF_DP<12>")
	)
	(segment
		(start 95.004128 -389.352536)
		(end 94.824296 -389.352536)
		(width 0.14224)
		(layer "In11.Cu")
		(net "P5E_CPU1_P1_TX_BUF_DP<12>")
	)
	(segment
		(start 94.330266 -395.018514)
		(end 94.330266 -395.445234)
		(width 0.14224)
		(layer "In11.Cu")
		(net "P5E_CPU1_P1_TX_BUF_DP<12>")
	)
	(segment
		(start 94.079314 -396.147036)
		(end 89.583514 -401.624292)
		(width 0.14224)
		(layer "In11.Cu")
		(net "P5E_CPU1_P1_TX_BUF_DP<12>")
	)
	(segment
		(start 94.734888 -389.441944)
		(end 94.734888 -389.521954)
		(width 0.14224)
		(layer "In11.Cu")
		(net "P5E_CPU1_P1_TX_BUF_DP<12>")
	)
	(segment
		(start 94.467426 -394.881354)
		(end 94.330266 -395.018514)
		(width 0.14224)
		(layer "In11.Cu")
		(net "P5E_CPU1_P1_TX_BUF_DP<12>")
	)
	(segment
		(start 88.85682 -402.185124)
		(end 88.829134 -402.3741)
		(width 0.14224)
		(layer "In11.Cu")
		(net "P5E_CPU1_P1_TX_BUF_DP<12>")
	)
	(segment
		(start 87.951564 -402.85416)
		(end 87.923116 -403.046184)
		(width 0.14224)
		(layer "In11.Cu")
		(net "P5E_CPU1_P1_TX_BUF_DP<12>")
	)
	(segment
		(start 95.118936 -389.467344)
		(end 95.004128 -389.352536)
		(width 0.14224)
		(layer "In11.Cu")
		(net "P5E_CPU1_P1_TX_BUF_DP<12>")
	)
	(segment
		(start 86.657434 -406.71369)
		(end 86.948264 -407.00452)
		(width 0.14224)
		(layer "In11.Cu")
		(net "P5E_CPU1_P1_TX_BUF_DP<12>")
	)
	(segment
		(start 94.86011 -391.096754)
		(end 94.37751 -391.579354)
		(width 0.14224)
		(layer "In11.Cu")
		(net "P5E_CPU1_P1_TX_BUF_DP<12>")
	)
	(segment
		(start 89.47912 -401.723606)
		(end 88.85682 -402.185124)
		(width 0.14224)
		(layer "In11.Cu")
		(net "P5E_CPU1_P1_TX_BUF_DP<12>")
	)
	(segment
		(start 94.467426 -394.454634)
		(end 94.467426 -394.881354)
		(width 0.14224)
		(layer "In11.Cu")
		(net "P5E_CPU1_P1_TX_BUF_DP<12>")
	)
	(segment
		(start 87.923116 -403.046184)
		(end 87.580216 -403.300438)
		(width 0.14224)
		(layer "In11.Cu")
		(net "P5E_CPU1_P1_TX_BUF_DP<12>")
	)
	(segment
		(start 94.81566 -389.716772)
		(end 94.95028 -389.851138)
		(width 0.14224)
		(layer "In11.Cu")
		(net "P5E_CPU1_P1_TX_BUF_DP<12>")
	)
	(segment
		(start 94.330266 -391.6934)
		(end 94.330266 -394.317474)
		(width 0.14224)
		(layer "In11.Cu")
		(net "P5E_CPU1_P1_TX_BUF_DP<12>")
	)
	(segment
		(start 87.388446 -403.272244)
		(end 87.0458 -403.526244)
		(width 0.14224)
		(layer "In11.Cu")
		(net "P5E_CPU1_P1_TX_BUF_DP<12>")
	)
	(segment
		(start 86.657434 -404.348188)
		(end 86.657434 -406.71369)
		(width 0.14224)
		(layer "In11.Cu")
		(net "P5E_CPU1_P1_TX_BUF_DP<12>")
	)
	(segment
		(start 94.330266 -394.317474)
		(end 94.467426 -394.454634)
		(width 0.14224)
		(layer "In11.Cu")
		(net "P5E_CPU1_P1_TX_BUF_DP<12>")
	)
	(segment
		(start 88.48598 -402.628608)
		(end 88.29421 -402.60016)
		(width 0.14224)
		(layer "In11.Cu")
		(net "P5E_CPU1_P1_TX_BUF_DP<12>")
	)
	(segment
		(start 94.824296 -389.352536)
		(end 94.734888 -389.441944)
		(width 0.14224)
		(layer "In11.Cu")
		(net "P5E_CPU1_P1_TX_BUF_DP<12>")
	)
	(segment
		(start 95.070168 -390.140698)
		(end 95.070168 -390.589008)
		(width 0.14224)
		(layer "In11.Cu")
		(net "P5E_CPU1_P1_TX_BUF_DP<12>")
	)
	(segment
		(start 88.29421 -402.60016)
		(end 87.951564 -402.85416)
		(width 0.14224)
		(layer "In11.Cu")
		(net "P5E_CPU1_P1_TX_BUF_DP<12>")
	)
	(segment
		(start 88.829134 -402.3741)
		(end 88.48598 -402.628608)
		(width 0.14224)
		(layer "In11.Cu")
		(net "P5E_CPU1_P1_TX_BUF_DP<12>")
	)
	(segment
		(start 87.580216 -403.300438)
		(end 87.388446 -403.272244)
		(width 0.14224)
		(layer "In11.Cu")
		(net "P5E_CPU1_P1_TX_BUF_DP<12>")
	)
	(arc
		(start 89.583514 -401.624292)
		(mid 89.534366 -401.677154)
		(end 89.47912 -401.723606)
		(width 0.14224)
		(layer "In11.Cu")
		(net "P5E_CPU1_P1_TX_BUF_DP<12>")
	)
	(arc
		(start 94.37751 -391.579354)
		(mid 94.342548 -391.631679)
		(end 94.330266 -391.6934)
		(width 0.14224)
		(layer "In11.Cu")
		(net "P5E_CPU1_P1_TX_BUF_DP<12>")
	)
	(arc
		(start 86.870286 -403.709632)
		(mid 86.740864 -403.954722)
		(end 86.66734 -404.22195)
		(width 0.14224)
		(layer "In11.Cu")
		(net "P5E_CPU1_P1_TX_BUF_DP<12>")
	)
	(arc
		(start 95.070168 -390.589008)
		(mid 95.015694 -390.863807)
		(end 94.86011 -391.096754)
		(width 0.14224)
		(layer "In11.Cu")
		(net "P5E_CPU1_P1_TX_BUF_DP<12>")
	)
	(arc
		(start 94.95028 -389.851138)
		(mid 95.039073 -389.983976)
		(end 95.070168 -390.140698)
		(width 0.14224)
		(layer "In11.Cu")
		(net "P5E_CPU1_P1_TX_BUF_DP<12>")
	)
	(arc
		(start 94.330266 -395.445234)
		(mid 94.265624 -395.81788)
		(end 94.079314 -396.147036)
		(width 0.14224)
		(layer "In11.Cu")
		(net "P5E_CPU1_P1_TX_BUF_DP<12>")
	)
	(arc
		(start 94.734888 -389.521954)
		(mid 94.755881 -389.627403)
		(end 94.81566 -389.716772)
		(width 0.14224)
		(layer "In11.Cu")
		(net "P5E_CPU1_P1_TX_BUF_DP<12>")
	)
	(arc
		(start 87.0458 -403.526244)
		(mid 86.950273 -403.610504)
		(end 86.870286 -403.709632)
		(width 0.14224)
		(layer "In11.Cu")
		(net "P5E_CPU1_P1_TX_BUF_DP<12>")
	)
	(arc
		(start 86.66734 -404.22195)
		(mid 86.65987 -404.284871)
		(end 86.657434 -404.348188)
		(width 0.14224)
		(layer "In11.Cu")
		(net "P5E_CPU1_P1_TX_BUF_DP<12>")
	)
	(segment
		(start 93.39834 -389.467344)
		(end 93.91904 -389.467344)
		(width 0.127)
		(layer "F.Cu")
		(net "P5E_CPU1_P1_TX_BUF_DP<11>")
	)
	(segment
		(start 83.614514 -407.954734)
		(end 83.614514 -407.27503)
		(width 0.12954)
		(layer "B.Cu")
		(net "P5E_CPU1_P1_TX_BUF_DP<11>")
	)
	(segment
		(start 83.614514 -407.27503)
		(end 83.885024 -407.00452)
		(width 0.12954)
		(layer "B.Cu")
		(net "P5E_CPU1_P1_TX_BUF_DP<11>")
	)
	(segment
		(start 83.910424 -408.250644)
		(end 83.614514 -407.954734)
		(width 0.12954)
		(layer "B.Cu")
		(net "P5E_CPU1_P1_TX_BUF_DP<11>")
	)
	(segment
		(start 91.14155 -397.732504)
		(end 91.141296 -397.92656)
		(width 0.14224)
		(layer "In11.Cu")
		(net "P5E_CPU1_P1_TX_BUF_DP<11>")
	)
	(segment
		(start 88.110822 -400.762978)
		(end 87.171784 -401.45208)
		(width 0.14224)
		(layer "In11.Cu")
		(net "P5E_CPU1_P1_TX_BUF_DP<11>")
	)
	(segment
		(start 91.141296 -397.92656)
		(end 90.839544 -398.228566)
		(width 0.14224)
		(layer "In11.Cu")
		(net "P5E_CPU1_P1_TX_BUF_DP<11>")
	)
	(segment
		(start 83.594194 -406.71369)
		(end 83.885024 -407.00452)
		(width 0.14224)
		(layer "In11.Cu")
		(net "P5E_CPU1_P1_TX_BUF_DP<11>")
	)
	(segment
		(start 87.171784 -401.45208)
		(end 86.061804 -402.15693)
		(width 0.14224)
		(layer "In11.Cu")
		(net "P5E_CPU1_P1_TX_BUF_DP<11>")
	)
	(segment
		(start 89.847928 -399.026126)
		(end 88.110822 -400.762978)
		(width 0.14224)
		(layer "In11.Cu")
		(net "P5E_CPU1_P1_TX_BUF_DP<11>")
	)
	(segment
		(start 93.804232 -389.352536)
		(end 93.624146 -389.352536)
		(width 0.14224)
		(layer "In11.Cu")
		(net "P5E_CPU1_P1_TX_BUF_DP<11>")
	)
	(segment
		(start 90.343736 -398.72412)
		(end 90.04173 -399.026126)
		(width 0.14224)
		(layer "In11.Cu")
		(net "P5E_CPU1_P1_TX_BUF_DP<11>")
	)
	(segment
		(start 93.60662 -389.718042)
		(end 93.77553 -389.886952)
		(width 0.14224)
		(layer "In11.Cu")
		(net "P5E_CPU1_P1_TX_BUF_DP<11>")
	)
	(segment
		(start 93.91904 -389.467344)
		(end 93.804232 -389.352536)
		(width 0.14224)
		(layer "In11.Cu")
		(net "P5E_CPU1_P1_TX_BUF_DP<11>")
	)
	(segment
		(start 90.04173 -399.026126)
		(end 89.847928 -399.026126)
		(width 0.14224)
		(layer "In11.Cu")
		(net "P5E_CPU1_P1_TX_BUF_DP<11>")
	)
	(segment
		(start 93.624146 -389.352536)
		(end 93.534738 -389.441944)
		(width 0.14224)
		(layer "In11.Cu")
		(net "P5E_CPU1_P1_TX_BUF_DP<11>")
	)
	(segment
		(start 93.895418 -390.176512)
		(end 93.895418 -390.554464)
		(width 0.14224)
		(layer "In11.Cu")
		(net "P5E_CPU1_P1_TX_BUF_DP<11>")
	)
	(segment
		(start 91.63685 -397.431006)
		(end 91.443048 -397.431006)
		(width 0.14224)
		(layer "In11.Cu")
		(net "P5E_CPU1_P1_TX_BUF_DP<11>")
	)
	(segment
		(start 90.839544 -398.228566)
		(end 90.645488 -398.228566)
		(width 0.14224)
		(layer "In11.Cu")
		(net "P5E_CPU1_P1_TX_BUF_DP<11>")
	)
	(segment
		(start 91.443048 -397.431006)
		(end 91.14155 -397.732504)
		(width 0.14224)
		(layer "In11.Cu")
		(net "P5E_CPU1_P1_TX_BUF_DP<11>")
	)
	(segment
		(start 91.938856 -396.935198)
		(end 91.938856 -397.129)
		(width 0.14224)
		(layer "In11.Cu")
		(net "P5E_CPU1_P1_TX_BUF_DP<11>")
	)
	(segment
		(start 90.34399 -398.530064)
		(end 90.343736 -398.72412)
		(width 0.14224)
		(layer "In11.Cu")
		(net "P5E_CPU1_P1_TX_BUF_DP<11>")
	)
	(segment
		(start 91.938856 -397.129)
		(end 91.63685 -397.431006)
		(width 0.14224)
		(layer "In11.Cu")
		(net "P5E_CPU1_P1_TX_BUF_DP<11>")
	)
	(segment
		(start 93.661484 -391.119614)
		(end 93.177614 -391.603484)
		(width 0.14224)
		(layer "In11.Cu")
		(net "P5E_CPU1_P1_TX_BUF_DP<11>")
	)
	(segment
		(start 84.579206 -403.008592)
		(end 83.873594 -403.435058)
		(width 0.14224)
		(layer "In11.Cu")
		(net "P5E_CPU1_P1_TX_BUF_DP<11>")
	)
	(segment
		(start 83.594194 -404.237444)
		(end 83.594194 -406.71369)
		(width 0.14224)
		(layer "In11.Cu")
		(net "P5E_CPU1_P1_TX_BUF_DP<11>")
	)
	(segment
		(start 90.645488 -398.228566)
		(end 90.34399 -398.530064)
		(width 0.14224)
		(layer "In11.Cu")
		(net "P5E_CPU1_P1_TX_BUF_DP<11>")
	)
	(segment
		(start 92.743528 -396.130526)
		(end 91.938856 -396.935198)
		(width 0.14224)
		(layer "In11.Cu")
		(net "P5E_CPU1_P1_TX_BUF_DP<11>")
	)
	(segment
		(start 93.534738 -389.441944)
		(end 93.534738 -389.544814)
		(width 0.14224)
		(layer "In11.Cu")
		(net "P5E_CPU1_P1_TX_BUF_DP<11>")
	)
	(segment
		(start 93.13037 -391.71753)
		(end 93.13037 -395.196822)
		(width 0.14224)
		(layer "In11.Cu")
		(net "P5E_CPU1_P1_TX_BUF_DP<11>")
	)
	(arc
		(start 93.77553 -389.886952)
		(mid 93.864245 -390.019817)
		(end 93.895418 -390.176512)
		(width 0.14224)
		(layer "In11.Cu")
		(net "P5E_CPU1_P1_TX_BUF_DP<11>")
	)
	(arc
		(start 93.13037 -395.196822)
		(mid 93.029834 -395.702159)
		(end 92.743528 -396.130526)
		(width 0.14224)
		(layer "In11.Cu")
		(net "P5E_CPU1_P1_TX_BUF_DP<11>")
	)
	(arc
		(start 86.061804 -402.15693)
		(mid 85.315717 -402.574427)
		(end 84.579206 -403.008592)
		(width 0.14224)
		(layer "In11.Cu")
		(net "P5E_CPU1_P1_TX_BUF_DP<11>")
	)
	(arc
		(start 83.873594 -403.435058)
		(mid 83.823396 -403.474762)
		(end 83.784694 -403.525736)
		(width 0.14224)
		(layer "In11.Cu")
		(net "P5E_CPU1_P1_TX_BUF_DP<11>")
	)
	(arc
		(start 93.895418 -390.554464)
		(mid 93.834727 -390.860339)
		(end 93.661484 -391.119614)
		(width 0.14224)
		(layer "In11.Cu")
		(net "P5E_CPU1_P1_TX_BUF_DP<11>")
	)
	(arc
		(start 93.534738 -389.544814)
		(mid 93.553426 -389.638585)
		(end 93.60662 -389.718042)
		(width 0.14224)
		(layer "In11.Cu")
		(net "P5E_CPU1_P1_TX_BUF_DP<11>")
	)
	(arc
		(start 83.784694 -403.525736)
		(mid 83.642561 -403.869043)
		(end 83.594194 -404.237444)
		(width 0.14224)
		(layer "In11.Cu")
		(net "P5E_CPU1_P1_TX_BUF_DP<11>")
	)
	(arc
		(start 93.177614 -391.603484)
		(mid 93.142652 -391.655809)
		(end 93.13037 -391.71753)
		(width 0.14224)
		(layer "In11.Cu")
		(net "P5E_CPU1_P1_TX_BUF_DP<11>")
	)
	(segment
		(start 92.198444 -389.467344)
		(end 92.719144 -389.467344)
		(width 0.127)
		(layer "F.Cu")
		(net "P5E_CPU1_P1_TX_BUF_DP<10>")
	)
	(segment
		(start 80.551274 -407.27503)
		(end 80.821784 -407.00452)
		(width 0.12954)
		(layer "B.Cu")
		(net "P5E_CPU1_P1_TX_BUF_DP<10>")
	)
	(segment
		(start 80.551274 -407.954734)
		(end 80.551274 -407.27503)
		(width 0.12954)
		(layer "B.Cu")
		(net "P5E_CPU1_P1_TX_BUF_DP<10>")
	)
	(segment
		(start 80.847184 -408.250644)
		(end 80.551274 -407.954734)
		(width 0.12954)
		(layer "B.Cu")
		(net "P5E_CPU1_P1_TX_BUF_DP<10>")
	)
	(segment
		(start 91.864434 -391.813034)
		(end 91.864434 -394.504418)
		(width 0.14224)
		(layer "In11.Cu")
		(net "P5E_CPU1_P1_TX_BUF_DP<10>")
	)
	(segment
		(start 82.6262 -402.621242)
		(end 82.243422 -402.809202)
		(width 0.14224)
		(layer "In11.Cu")
		(net "P5E_CPU1_P1_TX_BUF_DP<10>")
	)
	(segment
		(start 91.864434 -394.504418)
		(end 92.001594 -394.641578)
		(width 0.14224)
		(layer "In11.Cu")
		(net "P5E_CPU1_P1_TX_BUF_DP<10>")
	)
	(segment
		(start 92.456508 -389.767826)
		(end 92.575634 -389.886698)
		(width 0.14224)
		(layer "In11.Cu")
		(net "P5E_CPU1_P1_TX_BUF_DP<10>")
	)
	(segment
		(start 92.456508 -391.154158)
		(end 91.911678 -391.698988)
		(width 0.14224)
		(layer "In11.Cu")
		(net "P5E_CPU1_P1_TX_BUF_DP<10>")
	)
	(segment
		(start 83.193128 -402.495766)
		(end 82.809842 -402.683726)
		(width 0.14224)
		(layer "In11.Cu")
		(net "P5E_CPU1_P1_TX_BUF_DP<10>")
	)
	(segment
		(start 92.334842 -389.441944)
		(end 92.334842 -389.474202)
		(width 0.14224)
		(layer "In11.Cu")
		(net "P5E_CPU1_P1_TX_BUF_DP<10>")
	)
	(segment
		(start 91.744546 -395.75232)
		(end 87.779606 -399.717006)
		(width 0.14224)
		(layer "In11.Cu")
		(net "P5E_CPU1_P1_TX_BUF_DP<10>")
	)
	(segment
		(start 83.255866 -402.31187)
		(end 83.193128 -402.495766)
		(width 0.14224)
		(layer "In11.Cu")
		(net "P5E_CPU1_P1_TX_BUF_DP<10>")
	)
	(segment
		(start 92.604336 -389.352536)
		(end 92.42425 -389.352536)
		(width 0.14224)
		(layer "In11.Cu")
		(net "P5E_CPU1_P1_TX_BUF_DP<10>")
	)
	(segment
		(start 92.42425 -389.352536)
		(end 92.334842 -389.441944)
		(width 0.14224)
		(layer "In11.Cu")
		(net "P5E_CPU1_P1_TX_BUF_DP<10>")
	)
	(segment
		(start 92.695522 -390.176258)
		(end 92.695522 -390.576816)
		(width 0.14224)
		(layer "In11.Cu")
		(net "P5E_CPU1_P1_TX_BUF_DP<10>")
	)
	(segment
		(start 81.61401 -403.118574)
		(end 80.806544 -403.515068)
		(width 0.14224)
		(layer "In11.Cu")
		(net "P5E_CPU1_P1_TX_BUF_DP<10>")
	)
	(segment
		(start 92.001594 -395.068298)
		(end 91.864434 -395.205458)
		(width 0.14224)
		(layer "In11.Cu")
		(net "P5E_CPU1_P1_TX_BUF_DP<10>")
	)
	(segment
		(start 80.530954 -406.71369)
		(end 80.821784 -407.00452)
		(width 0.14224)
		(layer "In11.Cu")
		(net "P5E_CPU1_P1_TX_BUF_DP<10>")
	)
	(segment
		(start 86.116922 -400.906488)
		(end 83.255866 -402.31187)
		(width 0.14224)
		(layer "In11.Cu")
		(net "P5E_CPU1_P1_TX_BUF_DP<10>")
	)
	(segment
		(start 81.797652 -403.181058)
		(end 81.61401 -403.118574)
		(width 0.14224)
		(layer "In11.Cu")
		(net "P5E_CPU1_P1_TX_BUF_DP<10>")
	)
	(segment
		(start 91.864434 -395.205458)
		(end 91.864434 -395.463014)
		(width 0.14224)
		(layer "In11.Cu")
		(net "P5E_CPU1_P1_TX_BUF_DP<10>")
	)
	(segment
		(start 80.530954 -403.869652)
		(end 80.530954 -406.71369)
		(width 0.14224)
		(layer "In11.Cu")
		(net "P5E_CPU1_P1_TX_BUF_DP<10>")
	)
	(segment
		(start 92.001594 -394.641578)
		(end 92.001594 -395.068298)
		(width 0.14224)
		(layer "In11.Cu")
		(net "P5E_CPU1_P1_TX_BUF_DP<10>")
	)
	(segment
		(start 82.243422 -402.809202)
		(end 82.180938 -402.993098)
		(width 0.14224)
		(layer "In11.Cu")
		(net "P5E_CPU1_P1_TX_BUF_DP<10>")
	)
	(segment
		(start 92.719144 -389.467344)
		(end 92.604336 -389.352536)
		(width 0.14224)
		(layer "In11.Cu")
		(net "P5E_CPU1_P1_TX_BUF_DP<10>")
	)
	(segment
		(start 82.180938 -402.993098)
		(end 81.797652 -403.181058)
		(width 0.14224)
		(layer "In11.Cu")
		(net "P5E_CPU1_P1_TX_BUF_DP<10>")
	)
	(segment
		(start 82.809842 -402.683726)
		(end 82.6262 -402.621242)
		(width 0.14224)
		(layer "In11.Cu")
		(net "P5E_CPU1_P1_TX_BUF_DP<10>")
	)
	(arc
		(start 91.864434 -395.463014)
		(mid 91.833271 -395.619592)
		(end 91.744546 -395.75232)
		(width 0.14224)
		(layer "In11.Cu")
		(net "P5E_CPU1_P1_TX_BUF_DP<10>")
	)
	(arc
		(start 92.695522 -390.576816)
		(mid 92.633517 -390.889301)
		(end 92.456508 -391.154158)
		(width 0.14224)
		(layer "In11.Cu")
		(net "P5E_CPU1_P1_TX_BUF_DP<10>")
	)
	(arc
		(start 91.911678 -391.698988)
		(mid 91.876716 -391.751313)
		(end 91.864434 -391.813034)
		(width 0.14224)
		(layer "In11.Cu")
		(net "P5E_CPU1_P1_TX_BUF_DP<10>")
	)
	(arc
		(start 80.806544 -403.515068)
		(mid 80.689546 -403.59012)
		(end 80.592422 -403.689566)
		(width 0.14224)
		(layer "In11.Cu")
		(net "P5E_CPU1_P1_TX_BUF_DP<10>")
	)
	(arc
		(start 87.779606 -399.717006)
		(mid 86.997258 -400.380232)
		(end 86.116922 -400.906488)
		(width 0.14224)
		(layer "In11.Cu")
		(net "P5E_CPU1_P1_TX_BUF_DP<10>")
	)
	(arc
		(start 92.575634 -389.886698)
		(mid 92.664427 -390.019536)
		(end 92.695522 -390.176258)
		(width 0.14224)
		(layer "In11.Cu")
		(net "P5E_CPU1_P1_TX_BUF_DP<10>")
	)
	(arc
		(start 92.334842 -389.474202)
		(mid 92.366469 -389.633112)
		(end 92.456508 -389.767826)
		(width 0.14224)
		(layer "In11.Cu")
		(net "P5E_CPU1_P1_TX_BUF_DP<10>")
	)
	(arc
		(start 80.592422 -403.689566)
		(mid 80.546682 -403.774495)
		(end 80.530954 -403.869652)
		(width 0.14224)
		(layer "In11.Cu")
		(net "P5E_CPU1_P1_TX_BUF_DP<10>")
	)
	(segment
		(start 80.198468 -389.467344)
		(end 80.719168 -389.467344)
		(width 0.127)
		(layer "F.Cu")
		(net "P5E_CPU1_P1_TX_BUF_DP<0>")
	)
	(segment
		(start 49.918874 -407.954734)
		(end 49.918874 -407.27503)
		(width 0.12954)
		(layer "B.Cu")
		(net "P5E_CPU1_P1_TX_BUF_DP<0>")
	)
	(segment
		(start 49.918874 -407.27503)
		(end 50.189384 -407.00452)
		(width 0.12954)
		(layer "B.Cu")
		(net "P5E_CPU1_P1_TX_BUF_DP<0>")
	)
	(segment
		(start 50.214784 -408.250644)
		(end 49.918874 -407.954734)
		(width 0.12954)
		(layer "B.Cu")
		(net "P5E_CPU1_P1_TX_BUF_DP<0>")
	)
	(segment
		(start 54.698646 -401.17014)
		(end 54.288182 -401.287742)
		(width 0.14224)
		(layer "In11.Cu")
		(net "P5E_CPU1_P1_TX_BUF_DP<0>")
	)
	(segment
		(start 80.418686 -389.344662)
		(end 80.19669 -389.566658)
		(width 0.14224)
		(layer "In11.Cu")
		(net "P5E_CPU1_P1_TX_BUF_DP<0>")
	)
	(segment
		(start 55.372254 -400.976592)
		(end 55.202582 -400.882612)
		(width 0.14224)
		(layer "In11.Cu")
		(net "P5E_CPU1_P1_TX_BUF_DP<0>")
	)
	(segment
		(start 54.11851 -401.193762)
		(end 52.933092 -401.533868)
		(width 0.14224)
		(layer "In11.Cu")
		(net "P5E_CPU1_P1_TX_BUF_DP<0>")
	)
	(segment
		(start 54.288182 -401.287742)
		(end 54.11851 -401.193762)
		(width 0.14224)
		(layer "In11.Cu")
		(net "P5E_CPU1_P1_TX_BUF_DP<0>")
	)
	(segment
		(start 54.792626 -401.000214)
		(end 54.698646 -401.17014)
		(width 0.14224)
		(layer "In11.Cu")
		(net "P5E_CPU1_P1_TX_BUF_DP<0>")
	)
	(segment
		(start 80.596486 -389.344662)
		(end 80.418686 -389.344662)
		(width 0.14224)
		(layer "In11.Cu")
		(net "P5E_CPU1_P1_TX_BUF_DP<0>")
	)
	(segment
		(start 68.82003 -396.97279)
		(end 56.96077 -400.377406)
		(width 0.14224)
		(layer "In11.Cu")
		(net "P5E_CPU1_P1_TX_BUF_DP<0>")
	)
	(segment
		(start 79.907384 -389.686546)
		(end 79.753714 -389.686546)
		(width 0.14224)
		(layer "In11.Cu")
		(net "P5E_CPU1_P1_TX_BUF_DP<0>")
	)
	(segment
		(start 76.043536 -394.50264)
		(end 71.817738 -395.754352)
		(width 0.14224)
		(layer "In11.Cu")
		(net "P5E_CPU1_P1_TX_BUF_DP<0>")
	)
	(segment
		(start 71.817738 -395.754352)
		(end 68.82003 -396.97279)
		(width 0.14224)
		(layer "In11.Cu")
		(net "P5E_CPU1_P1_TX_BUF_DP<0>")
	)
	(segment
		(start 55.202582 -400.882612)
		(end 54.792626 -401.000214)
		(width 0.14224)
		(layer "In11.Cu")
		(net "P5E_CPU1_P1_TX_BUF_DP<0>")
	)
	(segment
		(start 56.456326 -400.665188)
		(end 56.286654 -400.571208)
		(width 0.14224)
		(layer "In11.Cu")
		(net "P5E_CPU1_P1_TX_BUF_DP<0>")
	)
	(segment
		(start 55.782718 -400.858736)
		(end 55.372254 -400.976592)
		(width 0.14224)
		(layer "In11.Cu")
		(net "P5E_CPU1_P1_TX_BUF_DP<0>")
	)
	(segment
		(start 78.59776 -392.000232)
		(end 78.59776 -392.43254)
		(width 0.14224)
		(layer "In11.Cu")
		(net "P5E_CPU1_P1_TX_BUF_DP<0>")
	)
	(segment
		(start 49.898554 -406.71369)
		(end 50.189384 -407.00452)
		(width 0.14224)
		(layer "In11.Cu")
		(net "P5E_CPU1_P1_TX_BUF_DP<0>")
	)
	(segment
		(start 52.12842 -401.901152)
		(end 50.61331 -402.887434)
		(width 0.14224)
		(layer "In11.Cu")
		(net "P5E_CPU1_P1_TX_BUF_DP<0>")
	)
	(segment
		(start 79.32166 -389.95858)
		(end 78.710536 -391.433812)
		(width 0.14224)
		(layer "In11.Cu")
		(net "P5E_CPU1_P1_TX_BUF_DP<0>")
	)
	(segment
		(start 79.480664 -389.799576)
		(end 79.32166 -389.95858)
		(width 0.14224)
		(layer "In11.Cu")
		(net "P5E_CPU1_P1_TX_BUF_DP<0>")
	)
	(segment
		(start 56.286654 -400.571208)
		(end 55.876698 -400.68881)
		(width 0.14224)
		(layer "In11.Cu")
		(net "P5E_CPU1_P1_TX_BUF_DP<0>")
	)
	(segment
		(start 49.898554 -404.205694)
		(end 49.898554 -406.71369)
		(width 0.14224)
		(layer "In11.Cu")
		(net "P5E_CPU1_P1_TX_BUF_DP<0>")
	)
	(segment
		(start 78.334616 -393.068048)
		(end 77.545692 -393.856972)
		(width 0.14224)
		(layer "In11.Cu")
		(net "P5E_CPU1_P1_TX_BUF_DP<0>")
	)
	(segment
		(start 77.410564 -393.946888)
		(end 76.043536 -394.50264)
		(width 0.14224)
		(layer "In11.Cu")
		(net "P5E_CPU1_P1_TX_BUF_DP<0>")
	)
	(segment
		(start 56.86679 -400.547332)
		(end 56.456326 -400.665188)
		(width 0.14224)
		(layer "In11.Cu")
		(net "P5E_CPU1_P1_TX_BUF_DP<0>")
	)
	(segment
		(start 80.719168 -389.467344)
		(end 80.596486 -389.344662)
		(width 0.14224)
		(layer "In11.Cu")
		(net "P5E_CPU1_P1_TX_BUF_DP<0>")
	)
	(segment
		(start 55.876698 -400.68881)
		(end 55.782718 -400.858736)
		(width 0.14224)
		(layer "In11.Cu")
		(net "P5E_CPU1_P1_TX_BUF_DP<0>")
	)
	(segment
		(start 56.96077 -400.377406)
		(end 56.86679 -400.547332)
		(width 0.14224)
		(layer "In11.Cu")
		(net "P5E_CPU1_P1_TX_BUF_DP<0>")
	)
	(arc
		(start 77.545692 -393.856972)
		(mid 77.482626 -393.908688)
		(end 77.410564 -393.946888)
		(width 0.14224)
		(layer "In11.Cu")
		(net "P5E_CPU1_P1_TX_BUF_DP<0>")
	)
	(arc
		(start 80.19669 -389.566658)
		(mid 80.06397 -389.655402)
		(end 79.907384 -389.686546)
		(width 0.14224)
		(layer "In11.Cu")
		(net "P5E_CPU1_P1_TX_BUF_DP<0>")
	)
	(arc
		(start 79.753714 -389.686546)
		(mid 79.605953 -389.71592)
		(end 79.480664 -389.799576)
		(width 0.14224)
		(layer "In11.Cu")
		(net "P5E_CPU1_P1_TX_BUF_DP<0>")
	)
	(arc
		(start 52.933092 -401.533868)
		(mid 52.517061 -401.687508)
		(end 52.12842 -401.901152)
		(width 0.14224)
		(layer "In11.Cu")
		(net "P5E_CPU1_P1_TX_BUF_DP<0>")
	)
	(arc
		(start 78.710536 -391.433812)
		(mid 78.626236 -391.711466)
		(end 78.59776 -392.000232)
		(width 0.14224)
		(layer "In11.Cu")
		(net "P5E_CPU1_P1_TX_BUF_DP<0>")
	)
	(arc
		(start 50.61331 -402.887434)
		(mid 50.088733 -403.455911)
		(end 49.898554 -404.205694)
		(width 0.14224)
		(layer "In11.Cu")
		(net "P5E_CPU1_P1_TX_BUF_DP<0>")
	)
	(arc
		(start 78.59776 -392.43254)
		(mid 78.529369 -392.776453)
		(end 78.334616 -393.068048)
		(width 0.14224)
		(layer "In11.Cu")
		(net "P5E_CPU1_P1_TX_BUF_DP<0>")
	)
	(segment
		(start 90.598244 -388.774432)
		(end 91.118944 -388.774432)
		(width 0.127)
		(layer "F.Cu")
		(net "P5E_CPU1_P1_TX_BUF_DN<9>")
	)
	(segment
		(start 77.165454 -407.954734)
		(end 77.165454 -407.27503)
		(width 0.12954)
		(layer "B.Cu")
		(net "P5E_CPU1_P1_TX_BUF_DN<9>")
	)
	(segment
		(start 77.165454 -407.27503)
		(end 76.894944 -407.00452)
		(width 0.12954)
		(layer "B.Cu")
		(net "P5E_CPU1_P1_TX_BUF_DN<9>")
	)
	(segment
		(start 76.869544 -408.250644)
		(end 77.165454 -407.954734)
		(width 0.12954)
		(layer "B.Cu")
		(net "P5E_CPU1_P1_TX_BUF_DN<9>")
	)
	(segment
		(start 91.171268 -389.006588)
		(end 90.856816 -389.32104)
		(width 0.14224)
		(layer "In11.Cu")
		(net "P5E_CPU1_P1_TX_BUF_DN<9>")
	)
	(segment
		(start 91.014296 -389.90524)
		(end 91.166188 -390.057132)
		(width 0.14224)
		(layer "In11.Cu")
		(net "P5E_CPU1_P1_TX_BUF_DN<9>")
	)
	(segment
		(start 77.185774 -404.077932)
		(end 77.185774 -406.71369)
		(width 0.14224)
		(layer "In11.Cu")
		(net "P5E_CPU1_P1_TX_BUF_DN<9>")
	)
	(segment
		(start 82.275172 -401.150328)
		(end 79.797148 -402.027136)
		(width 0.14224)
		(layer "In11.Cu")
		(net "P5E_CPU1_P1_TX_BUF_DN<9>")
	)
	(segment
		(start 90.404442 -395.362684)
		(end 87.085932 -398.681194)
		(width 0.14224)
		(layer "In11.Cu")
		(net "P5E_CPU1_P1_TX_BUF_DN<9>")
	)
	(segment
		(start 77.185774 -406.71369)
		(end 76.894944 -407.00452)
		(width 0.14224)
		(layer "In11.Cu")
		(net "P5E_CPU1_P1_TX_BUF_DN<9>")
	)
	(segment
		(start 79.797148 -402.027136)
		(end 77.762862 -403.11451)
		(width 0.14224)
		(layer "In11.Cu")
		(net "P5E_CPU1_P1_TX_BUF_DN<9>")
	)
	(segment
		(start 90.44178 -391.772648)
		(end 90.44178 -395.272768)
		(width 0.14224)
		(layer "In11.Cu")
		(net "P5E_CPU1_P1_TX_BUF_DN<9>")
	)
	(segment
		(start 90.856816 -389.32104)
		(end 90.856816 -389.525256)
		(width 0.14224)
		(layer "In11.Cu")
		(net "P5E_CPU1_P1_TX_BUF_DN<9>")
	)
	(segment
		(start 85.195918 -399.944082)
		(end 82.393028 -401.105116)
		(width 0.14224)
		(layer "In11.Cu")
		(net "P5E_CPU1_P1_TX_BUF_DN<9>")
	)
	(segment
		(start 91.171268 -388.826756)
		(end 91.171268 -389.006588)
		(width 0.14224)
		(layer "In11.Cu")
		(net "P5E_CPU1_P1_TX_BUF_DN<9>")
	)
	(segment
		(start 91.076018 -390.954514)
		(end 90.571574 -391.458958)
		(width 0.14224)
		(layer "In11.Cu")
		(net "P5E_CPU1_P1_TX_BUF_DN<9>")
	)
	(segment
		(start 91.213432 -390.171178)
		(end 91.213432 -390.623044)
		(width 0.14224)
		(layer "In11.Cu")
		(net "P5E_CPU1_P1_TX_BUF_DN<9>")
	)
	(segment
		(start 91.118944 -388.774432)
		(end 91.171268 -388.826756)
		(width 0.14224)
		(layer "In11.Cu")
		(net "P5E_CPU1_P1_TX_BUF_DN<9>")
	)
	(arc
		(start 90.44178 -395.272768)
		(mid 90.432078 -395.321452)
		(end 90.404442 -395.362684)
		(width 0.14224)
		(layer "In11.Cu")
		(net "P5E_CPU1_P1_TX_BUF_DN<9>")
	)
	(arc
		(start 87.085932 -398.681194)
		(mid 86.203117 -399.405716)
		(end 85.195918 -399.944082)
		(width 0.14224)
		(layer "In11.Cu")
		(net "P5E_CPU1_P1_TX_BUF_DN<9>")
	)
	(arc
		(start 77.762862 -403.11451)
		(mid 77.34098 -403.516362)
		(end 77.185774 -404.077932)
		(width 0.14224)
		(layer "In11.Cu")
		(net "P5E_CPU1_P1_TX_BUF_DN<9>")
	)
	(arc
		(start 90.571574 -391.458958)
		(mid 90.475438 -391.602881)
		(end 90.44178 -391.772648)
		(width 0.14224)
		(layer "In11.Cu")
		(net "P5E_CPU1_P1_TX_BUF_DN<9>")
	)
	(arc
		(start 91.213432 -390.623044)
		(mid 91.17771 -390.80245)
		(end 91.076018 -390.954514)
		(width 0.14224)
		(layer "In11.Cu")
		(net "P5E_CPU1_P1_TX_BUF_DN<9>")
	)
	(arc
		(start 91.166188 -390.057132)
		(mid 91.20115 -390.109457)
		(end 91.213432 -390.171178)
		(width 0.14224)
		(layer "In11.Cu")
		(net "P5E_CPU1_P1_TX_BUF_DN<9>")
	)
	(arc
		(start 90.856816 -389.525256)
		(mid 90.897781 -389.730909)
		(end 91.014296 -389.90524)
		(width 0.14224)
		(layer "In11.Cu")
		(net "P5E_CPU1_P1_TX_BUF_DN<9>")
	)
	(arc
		(start 82.393028 -401.105116)
		(mid 82.334397 -401.128497)
		(end 82.275172 -401.150328)
		(width 0.14224)
		(layer "In11.Cu")
		(net "P5E_CPU1_P1_TX_BUF_DN<9>")
	)
	(segment
		(start 89.398348 -388.774432)
		(end 89.919048 -388.774432)
		(width 0.127)
		(layer "F.Cu")
		(net "P5E_CPU1_P1_TX_BUF_DN<8>")
	)
	(segment
		(start 74.102214 -407.954734)
		(end 74.102214 -407.27503)
		(width 0.12954)
		(layer "B.Cu")
		(net "P5E_CPU1_P1_TX_BUF_DN<8>")
	)
	(segment
		(start 74.102214 -407.27503)
		(end 73.831704 -407.00452)
		(width 0.12954)
		(layer "B.Cu")
		(net "P5E_CPU1_P1_TX_BUF_DN<8>")
	)
	(segment
		(start 73.806304 -408.250644)
		(end 74.102214 -407.954734)
		(width 0.12954)
		(layer "B.Cu")
		(net "P5E_CPU1_P1_TX_BUF_DN<8>")
	)
	(segment
		(start 75.052936 -402.963634)
		(end 75.052936 -402.963888)
		(width 0.14224)
		(layer "In11.Cu")
		(net "P5E_CPU1_P1_TX_BUF_DN<8>")
	)
	(segment
		(start 89.919048 -388.774432)
		(end 89.971372 -388.826756)
		(width 0.14224)
		(layer "In11.Cu")
		(net "P5E_CPU1_P1_TX_BUF_DN<8>")
	)
	(segment
		(start 88.79332 -395.494002)
		(end 85.93201 -398.355312)
		(width 0.14224)
		(layer "In11.Cu")
		(net "P5E_CPU1_P1_TX_BUF_DN<8>")
	)
	(segment
		(start 90.013536 -390.176512)
		(end 90.013536 -390.664446)
		(width 0.14224)
		(layer "In11.Cu")
		(net "P5E_CPU1_P1_TX_BUF_DN<8>")
	)
	(segment
		(start 75.052936 -402.963888)
		(end 74.606912 -403.148292)
		(width 0.14224)
		(layer "In11.Cu")
		(net "P5E_CPU1_P1_TX_BUF_DN<8>")
	)
	(segment
		(start 89.176098 -391.7696)
		(end 89.176098 -394.570204)
		(width 0.14224)
		(layer "In11.Cu")
		(net "P5E_CPU1_P1_TX_BUF_DN<8>")
	)
	(segment
		(start 80.439006 -400.732752)
		(end 75.052936 -402.963634)
		(width 0.14224)
		(layer "In11.Cu")
		(net "P5E_CPU1_P1_TX_BUF_DN<8>")
	)
	(segment
		(start 89.849452 -389.959596)
		(end 89.976198 -390.086342)
		(width 0.14224)
		(layer "In11.Cu")
		(net "P5E_CPU1_P1_TX_BUF_DN<8>")
	)
	(segment
		(start 89.971372 -388.826756)
		(end 89.971372 -389.006588)
		(width 0.14224)
		(layer "In11.Cu")
		(net "P5E_CPU1_P1_TX_BUF_DN<8>")
	)
	(segment
		(start 89.913968 -390.904984)
		(end 89.26576 -391.553192)
		(width 0.14224)
		(layer "In11.Cu")
		(net "P5E_CPU1_P1_TX_BUF_DN<8>")
	)
	(segment
		(start 84.936838 -399.02003)
		(end 84.937092 -399.02003)
		(width 0.14224)
		(layer "In11.Cu")
		(net "P5E_CPU1_P1_TX_BUF_DN<8>")
	)
	(segment
		(start 74.122534 -404.110698)
		(end 74.122534 -406.71369)
		(width 0.14224)
		(layer "In11.Cu")
		(net "P5E_CPU1_P1_TX_BUF_DN<8>")
	)
	(segment
		(start 74.606912 -403.148292)
		(end 74.460354 -403.295104)
		(width 0.14224)
		(layer "In11.Cu")
		(net "P5E_CPU1_P1_TX_BUF_DN<8>")
	)
	(segment
		(start 89.971372 -389.006588)
		(end 89.652856 -389.325104)
		(width 0.14224)
		(layer "In11.Cu")
		(net "P5E_CPU1_P1_TX_BUF_DN<8>")
	)
	(segment
		(start 81.791048 -400.322542)
		(end 80.439006 -400.732752)
		(width 0.14224)
		(layer "In11.Cu")
		(net "P5E_CPU1_P1_TX_BUF_DN<8>")
	)
	(segment
		(start 84.937092 -399.02003)
		(end 81.791048 -400.322542)
		(width 0.14224)
		(layer "In11.Cu")
		(net "P5E_CPU1_P1_TX_BUF_DN<8>")
	)
	(segment
		(start 89.652856 -389.325104)
		(end 89.652856 -389.485124)
		(width 0.14224)
		(layer "In11.Cu")
		(net "P5E_CPU1_P1_TX_BUF_DN<8>")
	)
	(segment
		(start 74.122534 -406.71369)
		(end 73.831704 -407.00452)
		(width 0.14224)
		(layer "In11.Cu")
		(net "P5E_CPU1_P1_TX_BUF_DN<8>")
	)
	(arc
		(start 74.460354 -403.295104)
		(mid 74.210323 -403.669302)
		(end 74.122534 -404.110698)
		(width 0.14224)
		(layer "In11.Cu")
		(net "P5E_CPU1_P1_TX_BUF_DN<8>")
	)
	(arc
		(start 89.26576 -391.553192)
		(mid 89.199417 -391.652481)
		(end 89.176098 -391.7696)
		(width 0.14224)
		(layer "In11.Cu")
		(net "P5E_CPU1_P1_TX_BUF_DN<8>")
	)
	(arc
		(start 89.652856 -389.485124)
		(mid 89.703953 -389.741916)
		(end 89.849452 -389.959596)
		(width 0.14224)
		(layer "In11.Cu")
		(net "P5E_CPU1_P1_TX_BUF_DN<8>")
	)
	(arc
		(start 89.176098 -394.570204)
		(mid 89.076611 -395.070181)
		(end 88.79332 -395.494002)
		(width 0.14224)
		(layer "In11.Cu")
		(net "P5E_CPU1_P1_TX_BUF_DN<8>")
	)
	(arc
		(start 89.976198 -390.086342)
		(mid 90.003841 -390.127712)
		(end 90.013536 -390.176512)
		(width 0.14224)
		(layer "In11.Cu")
		(net "P5E_CPU1_P1_TX_BUF_DN<8>")
	)
	(arc
		(start 90.013536 -390.664446)
		(mid 89.987647 -390.794599)
		(end 89.913968 -390.904984)
		(width 0.14224)
		(layer "In11.Cu")
		(net "P5E_CPU1_P1_TX_BUF_DN<8>")
	)
	(arc
		(start 85.93201 -398.355312)
		(mid 85.467164 -398.736686)
		(end 84.936838 -399.02003)
		(width 0.14224)
		(layer "In11.Cu")
		(net "P5E_CPU1_P1_TX_BUF_DN<8>")
	)
	(segment
		(start 88.198452 -388.774432)
		(end 88.719152 -388.774432)
		(width 0.127)
		(layer "F.Cu")
		(net "P5E_CPU1_P1_TX_BUF_DN<7>")
	)
	(segment
		(start 71.038974 -407.954734)
		(end 71.038974 -407.27503)
		(width 0.12954)
		(layer "B.Cu")
		(net "P5E_CPU1_P1_TX_BUF_DN<7>")
	)
	(segment
		(start 71.038974 -407.27503)
		(end 70.768464 -407.00452)
		(width 0.12954)
		(layer "B.Cu")
		(net "P5E_CPU1_P1_TX_BUF_DN<7>")
	)
	(segment
		(start 70.743064 -408.250644)
		(end 71.038974 -407.954734)
		(width 0.12954)
		(layer "B.Cu")
		(net "P5E_CPU1_P1_TX_BUF_DN<7>")
	)
	(segment
		(start 88.055958 -391.69213)
		(end 88.055958 -394.48613)
		(width 0.14224)
		(layer "In11.Cu")
		(net "P5E_CPU1_P1_TX_BUF_DN<7>")
	)
	(segment
		(start 87.793576 -395.119606)
		(end 85.16747 -397.745204)
		(width 0.14224)
		(layer "In11.Cu")
		(net "P5E_CPU1_P1_TX_BUF_DN<7>")
	)
	(segment
		(start 71.886318 -403.003258)
		(end 71.536052 -403.194266)
		(width 0.14224)
		(layer "In11.Cu")
		(net "P5E_CPU1_P1_TX_BUF_DN<7>")
	)
	(segment
		(start 88.81364 -390.176258)
		(end 88.81364 -390.572498)
		(width 0.14224)
		(layer "In11.Cu")
		(net "P5E_CPU1_P1_TX_BUF_DN<7>")
	)
	(segment
		(start 76.488544 -401.264628)
		(end 71.886318 -403.003258)
		(width 0.14224)
		(layer "In11.Cu")
		(net "P5E_CPU1_P1_TX_BUF_DN<7>")
	)
	(segment
		(start 88.624156 -389.934196)
		(end 88.776302 -390.086342)
		(width 0.14224)
		(layer "In11.Cu")
		(net "P5E_CPU1_P1_TX_BUF_DN<7>")
	)
	(segment
		(start 78.63078 -400.377406)
		(end 76.488544 -401.264628)
		(width 0.14224)
		(layer "In11.Cu")
		(net "P5E_CPU1_P1_TX_BUF_DN<7>")
	)
	(segment
		(start 88.460072 -389.317992)
		(end 88.460072 -389.537956)
		(width 0.14224)
		(layer "In11.Cu")
		(net "P5E_CPU1_P1_TX_BUF_DN<7>")
	)
	(segment
		(start 71.059294 -406.71369)
		(end 70.768464 -407.00452)
		(width 0.14224)
		(layer "In11.Cu")
		(net "P5E_CPU1_P1_TX_BUF_DN<7>")
	)
	(segment
		(start 88.687656 -390.87679)
		(end 88.185752 -391.37844)
		(width 0.14224)
		(layer "In11.Cu")
		(net "P5E_CPU1_P1_TX_BUF_DN<7>")
	)
	(segment
		(start 88.771476 -388.826756)
		(end 88.771476 -389.006588)
		(width 0.14224)
		(layer "In11.Cu")
		(net "P5E_CPU1_P1_TX_BUF_DN<7>")
	)
	(segment
		(start 88.771476 -389.006588)
		(end 88.460072 -389.317992)
		(width 0.14224)
		(layer "In11.Cu")
		(net "P5E_CPU1_P1_TX_BUF_DN<7>")
	)
	(segment
		(start 71.536052 -403.194266)
		(end 71.35876 -403.364954)
		(width 0.14224)
		(layer "In11.Cu")
		(net "P5E_CPU1_P1_TX_BUF_DN<7>")
	)
	(segment
		(start 71.35876 -403.364954)
		(end 71.166228 -403.689312)
		(width 0.14224)
		(layer "In11.Cu")
		(net "P5E_CPU1_P1_TX_BUF_DN<7>")
	)
	(segment
		(start 88.719152 -388.774432)
		(end 88.771476 -388.826756)
		(width 0.14224)
		(layer "In11.Cu")
		(net "P5E_CPU1_P1_TX_BUF_DN<7>")
	)
	(segment
		(start 80.045814 -399.869406)
		(end 78.63078 -400.377406)
		(width 0.14224)
		(layer "In11.Cu")
		(net "P5E_CPU1_P1_TX_BUF_DN<7>")
	)
	(segment
		(start 71.059294 -404.078948)
		(end 71.059294 -406.71369)
		(width 0.14224)
		(layer "In11.Cu")
		(net "P5E_CPU1_P1_TX_BUF_DN<7>")
	)
	(segment
		(start 81.583784 -399.399252)
		(end 80.045814 -399.869406)
		(width 0.14224)
		(layer "In11.Cu")
		(net "P5E_CPU1_P1_TX_BUF_DN<7>")
	)
	(segment
		(start 84.502498 -398.18945)
		(end 81.583784 -399.399252)
		(width 0.14224)
		(layer "In11.Cu")
		(net "P5E_CPU1_P1_TX_BUF_DN<7>")
	)
	(arc
		(start 71.166228 -403.689312)
		(mid 71.086507 -403.876925)
		(end 71.059294 -404.078948)
		(width 0.14224)
		(layer "In11.Cu")
		(net "P5E_CPU1_P1_TX_BUF_DN<7>")
	)
	(arc
		(start 88.185752 -391.37844)
		(mid 88.089562 -391.522349)
		(end 88.055958 -391.69213)
		(width 0.14224)
		(layer "In11.Cu")
		(net "P5E_CPU1_P1_TX_BUF_DN<7>")
	)
	(arc
		(start 88.81364 -390.572498)
		(mid 88.780955 -390.737197)
		(end 88.687656 -390.87679)
		(width 0.14224)
		(layer "In11.Cu")
		(net "P5E_CPU1_P1_TX_BUF_DN<7>")
	)
	(arc
		(start 88.460072 -389.537956)
		(mid 88.502709 -389.752397)
		(end 88.624156 -389.934196)
		(width 0.14224)
		(layer "In11.Cu")
		(net "P5E_CPU1_P1_TX_BUF_DN<7>")
	)
	(arc
		(start 88.776302 -390.086342)
		(mid 88.803921 -390.127582)
		(end 88.81364 -390.176258)
		(width 0.14224)
		(layer "In11.Cu")
		(net "P5E_CPU1_P1_TX_BUF_DN<7>")
	)
	(arc
		(start 88.055958 -394.48613)
		(mid 87.98775 -394.828946)
		(end 87.793576 -395.119606)
		(width 0.14224)
		(layer "In11.Cu")
		(net "P5E_CPU1_P1_TX_BUF_DN<7>")
	)
	(arc
		(start 85.16747 -397.745204)
		(mid 84.856839 -398.000038)
		(end 84.502498 -398.18945)
		(width 0.14224)
		(layer "In11.Cu")
		(net "P5E_CPU1_P1_TX_BUF_DN<7>")
	)
	(segment
		(start 86.998302 -388.774432)
		(end 87.519002 -388.774432)
		(width 0.127)
		(layer "F.Cu")
		(net "P5E_CPU1_P1_TX_BUF_DN<6>")
	)
	(segment
		(start 67.975734 -407.954734)
		(end 67.975734 -407.27503)
		(width 0.12954)
		(layer "B.Cu")
		(net "P5E_CPU1_P1_TX_BUF_DN<6>")
	)
	(segment
		(start 67.679824 -408.250644)
		(end 67.975734 -407.954734)
		(width 0.12954)
		(layer "B.Cu")
		(net "P5E_CPU1_P1_TX_BUF_DN<6>")
	)
	(segment
		(start 67.975734 -407.27503)
		(end 67.705224 -407.00452)
		(width 0.12954)
		(layer "B.Cu")
		(net "P5E_CPU1_P1_TX_BUF_DN<6>")
	)
	(segment
		(start 79.212694 -399.12163)
		(end 76.15428 -400.388836)
		(width 0.14224)
		(layer "In11.Cu")
		(net "P5E_CPU1_P1_TX_BUF_DN<6>")
	)
	(segment
		(start 76.15428 -400.388836)
		(end 75.70597 -400.557492)
		(width 0.14224)
		(layer "In11.Cu")
		(net "P5E_CPU1_P1_TX_BUF_DN<6>")
	)
	(segment
		(start 87.61349 -390.176512)
		(end 87.61349 -390.462262)
		(width 0.14224)
		(layer "In11.Cu")
		(net "P5E_CPU1_P1_TX_BUF_DN<6>")
	)
	(segment
		(start 87.571326 -389.006588)
		(end 87.25281 -389.325104)
		(width 0.14224)
		(layer "In11.Cu")
		(net "P5E_CPU1_P1_TX_BUF_DN<6>")
	)
	(segment
		(start 87.416132 -389.926322)
		(end 87.576152 -390.086342)
		(width 0.14224)
		(layer "In11.Cu")
		(net "P5E_CPU1_P1_TX_BUF_DN<6>")
	)
	(segment
		(start 87.25281 -389.325104)
		(end 87.25281 -389.532114)
		(width 0.14224)
		(layer "In11.Cu")
		(net "P5E_CPU1_P1_TX_BUF_DN<6>")
	)
	(segment
		(start 86.811104 -391.7315)
		(end 86.811104 -394.410692)
		(width 0.14224)
		(layer "In11.Cu")
		(net "P5E_CPU1_P1_TX_BUF_DN<6>")
	)
	(segment
		(start 87.571326 -388.826756)
		(end 87.571326 -389.006588)
		(width 0.14224)
		(layer "In11.Cu")
		(net "P5E_CPU1_P1_TX_BUF_DN<6>")
	)
	(segment
		(start 75.705716 -400.557492)
		(end 68.507102 -403.004274)
		(width 0.14224)
		(layer "In11.Cu")
		(net "P5E_CPU1_P1_TX_BUF_DN<6>")
	)
	(segment
		(start 86.578948 -394.971016)
		(end 84.402168 -397.147796)
		(width 0.14224)
		(layer "In11.Cu")
		(net "P5E_CPU1_P1_TX_BUF_DN<6>")
	)
	(segment
		(start 75.70597 -400.557492)
		(end 75.705716 -400.557492)
		(width 0.14224)
		(layer "In11.Cu")
		(net "P5E_CPU1_P1_TX_BUF_DN<6>")
	)
	(segment
		(start 67.996054 -403.968204)
		(end 67.996054 -406.71369)
		(width 0.14224)
		(layer "In11.Cu")
		(net "P5E_CPU1_P1_TX_BUF_DN<6>")
	)
	(segment
		(start 81.489042 -398.428464)
		(end 79.212694 -399.12163)
		(width 0.14224)
		(layer "In11.Cu")
		(net "P5E_CPU1_P1_TX_BUF_DN<6>")
	)
	(segment
		(start 87.519002 -388.774432)
		(end 87.571326 -388.826756)
		(width 0.14224)
		(layer "In11.Cu")
		(net "P5E_CPU1_P1_TX_BUF_DN<6>")
	)
	(segment
		(start 67.996054 -406.71369)
		(end 67.705224 -407.00452)
		(width 0.14224)
		(layer "In11.Cu")
		(net "P5E_CPU1_P1_TX_BUF_DN<6>")
	)
	(segment
		(start 87.420196 -390.928606)
		(end 86.94801 -391.400792)
		(width 0.14224)
		(layer "In11.Cu")
		(net "P5E_CPU1_P1_TX_BUF_DN<6>")
	)
	(segment
		(start 84.110068 -397.342868)
		(end 81.489042 -398.428464)
		(width 0.14224)
		(layer "In11.Cu")
		(net "P5E_CPU1_P1_TX_BUF_DN<6>")
	)
	(arc
		(start 68.507102 -403.004274)
		(mid 68.377108 -403.070854)
		(end 68.272152 -403.172422)
		(width 0.14224)
		(layer "In11.Cu")
		(net "P5E_CPU1_P1_TX_BUF_DN<6>")
	)
	(arc
		(start 87.25281 -389.532114)
		(mid 87.295249 -389.745471)
		(end 87.416132 -389.926322)
		(width 0.14224)
		(layer "In11.Cu")
		(net "P5E_CPU1_P1_TX_BUF_DN<6>")
	)
	(arc
		(start 68.272152 -403.172422)
		(mid 68.07168 -403.548659)
		(end 67.996054 -403.968204)
		(width 0.14224)
		(layer "In11.Cu")
		(net "P5E_CPU1_P1_TX_BUF_DN<6>")
	)
	(arc
		(start 87.576152 -390.086342)
		(mid 87.603795 -390.127712)
		(end 87.61349 -390.176512)
		(width 0.14224)
		(layer "In11.Cu")
		(net "P5E_CPU1_P1_TX_BUF_DN<6>")
	)
	(arc
		(start 87.61349 -390.462262)
		(mid 87.563248 -390.714666)
		(end 87.420196 -390.928606)
		(width 0.14224)
		(layer "In11.Cu")
		(net "P5E_CPU1_P1_TX_BUF_DN<6>")
	)
	(arc
		(start 86.811104 -394.410692)
		(mid 86.750765 -394.713947)
		(end 86.578948 -394.971016)
		(width 0.14224)
		(layer "In11.Cu")
		(net "P5E_CPU1_P1_TX_BUF_DN<6>")
	)
	(arc
		(start 86.94801 -391.400792)
		(mid 86.846681 -391.552536)
		(end 86.811104 -391.7315)
		(width 0.14224)
		(layer "In11.Cu")
		(net "P5E_CPU1_P1_TX_BUF_DN<6>")
	)
	(arc
		(start 84.402168 -397.147796)
		(mid 84.265726 -397.25972)
		(end 84.110068 -397.342868)
		(width 0.14224)
		(layer "In11.Cu")
		(net "P5E_CPU1_P1_TX_BUF_DN<6>")
	)
	(segment
		(start 85.798406 -388.774432)
		(end 86.319106 -388.774432)
		(width 0.127)
		(layer "F.Cu")
		(net "P5E_CPU1_P1_TX_BUF_DN<5>")
	)
	(segment
		(start 64.616584 -408.250644)
		(end 64.912494 -407.954734)
		(width 0.12954)
		(layer "B.Cu")
		(net "P5E_CPU1_P1_TX_BUF_DN<5>")
	)
	(segment
		(start 64.912494 -407.954734)
		(end 64.912494 -407.27503)
		(width 0.12954)
		(layer "B.Cu")
		(net "P5E_CPU1_P1_TX_BUF_DN<5>")
	)
	(segment
		(start 64.912494 -407.27503)
		(end 64.641984 -407.00452)
		(width 0.12954)
		(layer "B.Cu")
		(net "P5E_CPU1_P1_TX_BUF_DN<5>")
	)
	(segment
		(start 86.37143 -388.826756)
		(end 86.37143 -389.006588)
		(width 0.14224)
		(layer "In11.Cu")
		(net "P5E_CPU1_P1_TX_BUF_DN<5>")
	)
	(segment
		(start 81.48574 -397.419576)
		(end 81.484978 -397.419576)
		(width 0.14224)
		(layer "In11.Cu")
		(net "P5E_CPU1_P1_TX_BUF_DN<5>")
	)
	(segment
		(start 86.37143 -389.006588)
		(end 86.052914 -389.325104)
		(width 0.14224)
		(layer "In11.Cu")
		(net "P5E_CPU1_P1_TX_BUF_DN<5>")
	)
	(segment
		(start 81.493868 -397.417036)
		(end 81.48574 -397.419576)
		(width 0.14224)
		(layer "In11.Cu")
		(net "P5E_CPU1_P1_TX_BUF_DN<5>")
	)
	(segment
		(start 85.435186 -394.72997)
		(end 83.683856 -396.4813)
		(width 0.14224)
		(layer "In11.Cu")
		(net "P5E_CPU1_P1_TX_BUF_DN<5>")
	)
	(segment
		(start 86.052914 -389.325104)
		(end 86.052914 -389.590026)
		(width 0.14224)
		(layer "In11.Cu")
		(net "P5E_CPU1_P1_TX_BUF_DN<5>")
	)
	(segment
		(start 75.113642 -399.68678)
		(end 71.595996 -400.882358)
		(width 0.14224)
		(layer "In11.Cu")
		(net "P5E_CPU1_P1_TX_BUF_DN<5>")
	)
	(segment
		(start 67.971924 -402.030946)
		(end 66.284602 -402.56587)
		(width 0.14224)
		(layer "In11.Cu")
		(net "P5E_CPU1_P1_TX_BUF_DN<5>")
	)
	(segment
		(start 86.413594 -390.360408)
		(end 86.413594 -390.46277)
		(width 0.14224)
		(layer "In11.Cu")
		(net "P5E_CPU1_P1_TX_BUF_DN<5>")
	)
	(segment
		(start 67.972178 -402.0312)
		(end 67.971924 -402.030946)
		(width 0.14224)
		(layer "In11.Cu")
		(net "P5E_CPU1_P1_TX_BUF_DN<5>")
	)
	(segment
		(start 81.159604 -397.553942)
		(end 78.421992 -398.387316)
		(width 0.14224)
		(layer "In11.Cu")
		(net "P5E_CPU1_P1_TX_BUF_DN<5>")
	)
	(segment
		(start 85.614764 -391.722864)
		(end 85.614764 -394.296646)
		(width 0.14224)
		(layer "In11.Cu")
		(net "P5E_CPU1_P1_TX_BUF_DN<5>")
	)
	(segment
		(start 68.509134 -401.86102)
		(end 67.972178 -402.0312)
		(width 0.14224)
		(layer "In11.Cu")
		(net "P5E_CPU1_P1_TX_BUF_DN<5>")
	)
	(segment
		(start 75.113388 -399.68678)
		(end 75.113642 -399.68678)
		(width 0.14224)
		(layer "In11.Cu")
		(net "P5E_CPU1_P1_TX_BUF_DN<5>")
	)
	(segment
		(start 68.509134 -401.860766)
		(end 68.509134 -401.86102)
		(width 0.14224)
		(layer "In11.Cu")
		(net "P5E_CPU1_P1_TX_BUF_DN<5>")
	)
	(segment
		(start 65.447672 -403.074886)
		(end 65.327276 -403.195282)
		(width 0.14224)
		(layer "In11.Cu")
		(net "P5E_CPU1_P1_TX_BUF_DN<5>")
	)
	(segment
		(start 86.243414 -390.873488)
		(end 85.77072 -391.346182)
		(width 0.14224)
		(layer "In11.Cu")
		(net "P5E_CPU1_P1_TX_BUF_DN<5>")
	)
	(segment
		(start 64.932814 -406.71369)
		(end 64.641984 -407.00452)
		(width 0.14224)
		(layer "In11.Cu")
		(net "P5E_CPU1_P1_TX_BUF_DN<5>")
	)
	(segment
		(start 86.319106 -388.774432)
		(end 86.37143 -388.826756)
		(width 0.14224)
		(layer "In11.Cu")
		(net "P5E_CPU1_P1_TX_BUF_DN<5>")
	)
	(segment
		(start 77.715618 -398.63649)
		(end 75.113388 -399.68678)
		(width 0.14224)
		(layer "In11.Cu")
		(net "P5E_CPU1_P1_TX_BUF_DN<5>")
	)
	(segment
		(start 81.484978 -397.419576)
		(end 81.159604 -397.553942)
		(width 0.14224)
		(layer "In11.Cu")
		(net "P5E_CPU1_P1_TX_BUF_DN<5>")
	)
	(segment
		(start 71.595996 -400.882358)
		(end 68.509134 -401.860766)
		(width 0.14224)
		(layer "In11.Cu")
		(net "P5E_CPU1_P1_TX_BUF_DN<5>")
	)
	(segment
		(start 83.570572 -396.556992)
		(end 81.493868 -397.417036)
		(width 0.14224)
		(layer "In11.Cu")
		(net "P5E_CPU1_P1_TX_BUF_DN<5>")
	)
	(segment
		(start 64.932814 -404.147528)
		(end 64.932814 -406.71369)
		(width 0.14224)
		(layer "In11.Cu")
		(net "P5E_CPU1_P1_TX_BUF_DN<5>")
	)
	(segment
		(start 86.172802 -389.879332)
		(end 86.243668 -389.950198)
		(width 0.14224)
		(layer "In11.Cu")
		(net "P5E_CPU1_P1_TX_BUF_DN<5>")
	)
	(arc
		(start 86.052914 -389.590026)
		(mid 86.084077 -389.746604)
		(end 86.172802 -389.879332)
		(width 0.14224)
		(layer "In11.Cu")
		(net "P5E_CPU1_P1_TX_BUF_DN<5>")
	)
	(arc
		(start 85.614764 -394.296646)
		(mid 85.568095 -394.531179)
		(end 85.435186 -394.72997)
		(width 0.14224)
		(layer "In11.Cu")
		(net "P5E_CPU1_P1_TX_BUF_DN<5>")
	)
	(arc
		(start 65.327276 -403.195282)
		(mid 65.035353 -403.632176)
		(end 64.932814 -404.147528)
		(width 0.14224)
		(layer "In11.Cu")
		(net "P5E_CPU1_P1_TX_BUF_DN<5>")
	)
	(arc
		(start 66.284602 -402.56587)
		(mid 65.835611 -402.770179)
		(end 65.447672 -403.074886)
		(width 0.14224)
		(layer "In11.Cu")
		(net "P5E_CPU1_P1_TX_BUF_DN<5>")
	)
	(arc
		(start 83.683856 -396.4813)
		(mid 83.630957 -396.524753)
		(end 83.570572 -396.556992)
		(width 0.14224)
		(layer "In11.Cu")
		(net "P5E_CPU1_P1_TX_BUF_DN<5>")
	)
	(arc
		(start 85.77072 -391.346182)
		(mid 85.655297 -391.519019)
		(end 85.614764 -391.722864)
		(width 0.14224)
		(layer "In11.Cu")
		(net "P5E_CPU1_P1_TX_BUF_DN<5>")
	)
	(arc
		(start 78.421992 -398.387316)
		(mid 78.066057 -398.504112)
		(end 77.715618 -398.63649)
		(width 0.14224)
		(layer "In11.Cu")
		(net "P5E_CPU1_P1_TX_BUF_DN<5>")
	)
	(arc
		(start 86.413594 -390.46277)
		(mid 86.369361 -390.685056)
		(end 86.243414 -390.873488)
		(width 0.14224)
		(layer "In11.Cu")
		(net "P5E_CPU1_P1_TX_BUF_DN<5>")
	)
	(arc
		(start 86.243668 -389.950198)
		(mid 86.369423 -390.138404)
		(end 86.413594 -390.360408)
		(width 0.14224)
		(layer "In11.Cu")
		(net "P5E_CPU1_P1_TX_BUF_DN<5>")
	)
	(segment
		(start 84.598256 -388.774432)
		(end 85.118956 -388.774432)
		(width 0.127)
		(layer "F.Cu")
		(net "P5E_CPU1_P1_TX_BUF_DN<4>")
	)
	(segment
		(start 61.849254 -407.954734)
		(end 61.849254 -407.27503)
		(width 0.12954)
		(layer "B.Cu")
		(net "P5E_CPU1_P1_TX_BUF_DN<4>")
	)
	(segment
		(start 61.553344 -408.250644)
		(end 61.849254 -407.954734)
		(width 0.12954)
		(layer "B.Cu")
		(net "P5E_CPU1_P1_TX_BUF_DN<4>")
	)
	(segment
		(start 61.849254 -407.27503)
		(end 61.578744 -407.00452)
		(width 0.12954)
		(layer "B.Cu")
		(net "P5E_CPU1_P1_TX_BUF_DN<4>")
	)
	(segment
		(start 85.213444 -390.20623)
		(end 85.213444 -390.553448)
		(width 0.14224)
		(layer "In11.Cu")
		(net "P5E_CPU1_P1_TX_BUF_DN<4>")
	)
	(segment
		(start 85.143594 -388.978902)
		(end 84.852764 -389.269732)
		(width 0.14224)
		(layer "In11.Cu")
		(net "P5E_CPU1_P1_TX_BUF_DN<4>")
	)
	(segment
		(start 82.79638 -395.868144)
		(end 81.179162 -396.537942)
		(width 0.14224)
		(layer "In11.Cu")
		(net "P5E_CPU1_P1_TX_BUF_DN<4>")
	)
	(segment
		(start 84.354924 -394.443712)
		(end 83.20024 -395.598396)
		(width 0.14224)
		(layer "In11.Cu")
		(net "P5E_CPU1_P1_TX_BUF_DN<4>")
	)
	(segment
		(start 61.869574 -403.74443)
		(end 61.869574 -406.71369)
		(width 0.14224)
		(layer "In11.Cu")
		(net "P5E_CPU1_P1_TX_BUF_DN<4>")
	)
	(segment
		(start 62.812168 -402.61032)
		(end 62.812422 -402.610574)
		(width 0.14224)
		(layer "In11.Cu")
		(net "P5E_CPU1_P1_TX_BUF_DN<4>")
	)
	(segment
		(start 61.869574 -406.71369)
		(end 61.578744 -407.00452)
		(width 0.14224)
		(layer "In11.Cu")
		(net "P5E_CPU1_P1_TX_BUF_DN<4>")
	)
	(segment
		(start 65.51295 -401.732496)
		(end 65.512696 -401.731988)
		(width 0.14224)
		(layer "In11.Cu")
		(net "P5E_CPU1_P1_TX_BUF_DN<4>")
	)
	(segment
		(start 81.179162 -396.537942)
		(end 79.267558 -397.117824)
		(width 0.14224)
		(layer "In11.Cu")
		(net "P5E_CPU1_P1_TX_BUF_DN<4>")
	)
	(segment
		(start 84.852764 -389.269732)
		(end 84.852764 -389.434578)
		(width 0.14224)
		(layer "In11.Cu")
		(net "P5E_CPU1_P1_TX_BUF_DN<4>")
	)
	(segment
		(start 78.696312 -397.328644)
		(end 77.75448 -397.61541)
		(width 0.14224)
		(layer "In11.Cu")
		(net "P5E_CPU1_P1_TX_BUF_DN<4>")
	)
	(segment
		(start 85.096096 -390.02208)
		(end 85.1662 -390.092184)
		(width 0.14224)
		(layer "In11.Cu")
		(net "P5E_CPU1_P1_TX_BUF_DN<4>")
	)
	(segment
		(start 77.75448 -397.61541)
		(end 75.85456 -398.36979)
		(width 0.14224)
		(layer "In11.Cu")
		(net "P5E_CPU1_P1_TX_BUF_DN<4>")
	)
	(segment
		(start 65.512696 -401.731988)
		(end 62.812168 -402.61032)
		(width 0.14224)
		(layer "In11.Cu")
		(net "P5E_CPU1_P1_TX_BUF_DN<4>")
	)
	(segment
		(start 75.85456 -398.36979)
		(end 65.51295 -401.732496)
		(width 0.14224)
		(layer "In11.Cu")
		(net "P5E_CPU1_P1_TX_BUF_DN<4>")
	)
	(segment
		(start 84.435696 -391.578592)
		(end 84.435696 -394.248894)
		(width 0.14224)
		(layer "In11.Cu")
		(net "P5E_CPU1_P1_TX_BUF_DN<4>")
	)
	(segment
		(start 85.118956 -388.774432)
		(end 85.143594 -388.79907)
		(width 0.14224)
		(layer "In11.Cu")
		(net "P5E_CPU1_P1_TX_BUF_DN<4>")
	)
	(segment
		(start 62.812422 -402.610574)
		(end 62.541404 -402.698458)
		(width 0.14224)
		(layer "In11.Cu")
		(net "P5E_CPU1_P1_TX_BUF_DN<4>")
	)
	(segment
		(start 85.143594 -388.79907)
		(end 85.143594 -388.978902)
		(width 0.14224)
		(layer "In11.Cu")
		(net "P5E_CPU1_P1_TX_BUF_DN<4>")
	)
	(segment
		(start 79.267558 -397.117824)
		(end 78.696312 -397.328644)
		(width 0.14224)
		(layer "In11.Cu")
		(net "P5E_CPU1_P1_TX_BUF_DN<4>")
	)
	(segment
		(start 85.1662 -390.667494)
		(end 84.56295 -391.27049)
		(width 0.14224)
		(layer "In11.Cu")
		(net "P5E_CPU1_P1_TX_BUF_DN<4>")
	)
	(arc
		(start 62.541404 -402.698458)
		(mid 62.32036 -402.807811)
		(end 62.13983 -402.975826)
		(width 0.14224)
		(layer "In11.Cu")
		(net "P5E_CPU1_P1_TX_BUF_DN<4>")
	)
	(arc
		(start 85.213444 -390.553448)
		(mid 85.201151 -390.615157)
		(end 85.1662 -390.667494)
		(width 0.14224)
		(layer "In11.Cu")
		(net "P5E_CPU1_P1_TX_BUF_DN<4>")
	)
	(arc
		(start 84.56295 -391.27049)
		(mid 84.468688 -391.411892)
		(end 84.435696 -391.578592)
		(width 0.14224)
		(layer "In11.Cu")
		(net "P5E_CPU1_P1_TX_BUF_DN<4>")
	)
	(arc
		(start 85.1662 -390.092184)
		(mid 85.201162 -390.144509)
		(end 85.213444 -390.20623)
		(width 0.14224)
		(layer "In11.Cu")
		(net "P5E_CPU1_P1_TX_BUF_DN<4>")
	)
	(arc
		(start 84.435696 -394.248894)
		(mid 84.414703 -394.354343)
		(end 84.354924 -394.443712)
		(width 0.14224)
		(layer "In11.Cu")
		(net "P5E_CPU1_P1_TX_BUF_DN<4>")
	)
	(arc
		(start 83.20024 -395.598396)
		(mid 83.011581 -395.753133)
		(end 82.79638 -395.868144)
		(width 0.14224)
		(layer "In11.Cu")
		(net "P5E_CPU1_P1_TX_BUF_DN<4>")
	)
	(arc
		(start 62.13983 -402.975826)
		(mid 61.939102 -403.337057)
		(end 61.869574 -403.74443)
		(width 0.14224)
		(layer "In11.Cu")
		(net "P5E_CPU1_P1_TX_BUF_DN<4>")
	)
	(arc
		(start 84.852764 -389.434578)
		(mid 84.916007 -389.752524)
		(end 85.096096 -390.02208)
		(width 0.14224)
		(layer "In11.Cu")
		(net "P5E_CPU1_P1_TX_BUF_DN<4>")
	)
	(segment
		(start 83.39836 -388.774432)
		(end 83.91906 -388.774432)
		(width 0.127)
		(layer "F.Cu")
		(net "P5E_CPU1_P1_TX_BUF_DN<3>")
	)
	(segment
		(start 58.786014 -407.954734)
		(end 58.786014 -407.27503)
		(width 0.12954)
		(layer "B.Cu")
		(net "P5E_CPU1_P1_TX_BUF_DN<3>")
	)
	(segment
		(start 58.490104 -408.250644)
		(end 58.786014 -407.954734)
		(width 0.12954)
		(layer "B.Cu")
		(net "P5E_CPU1_P1_TX_BUF_DN<3>")
	)
	(segment
		(start 58.786014 -407.27503)
		(end 58.515504 -407.00452)
		(width 0.12954)
		(layer "B.Cu")
		(net "P5E_CPU1_P1_TX_BUF_DN<3>")
	)
	(segment
		(start 81.106264 -395.558772)
		(end 77.995526 -396.508478)
		(width 0.14224)
		(layer "In11.Cu")
		(net "P5E_CPU1_P1_TX_BUF_DN<3>")
	)
	(segment
		(start 58.806334 -404.184104)
		(end 58.806334 -406.71369)
		(width 0.14224)
		(layer "In11.Cu")
		(net "P5E_CPU1_P1_TX_BUF_DN<3>")
	)
	(segment
		(start 83.202018 -394.2588)
		(end 82.581496 -394.879322)
		(width 0.14224)
		(layer "In11.Cu")
		(net "P5E_CPU1_P1_TX_BUF_DN<3>")
	)
	(segment
		(start 83.827874 -389.938006)
		(end 83.97621 -390.086342)
		(width 0.14224)
		(layer "In11.Cu")
		(net "P5E_CPU1_P1_TX_BUF_DN<3>")
	)
	(segment
		(start 58.806334 -406.71369)
		(end 58.515504 -407.00452)
		(width 0.14224)
		(layer "In11.Cu")
		(net "P5E_CPU1_P1_TX_BUF_DN<3>")
	)
	(segment
		(start 61.84011 -401.715732)
		(end 61.164216 -401.997926)
		(width 0.14224)
		(layer "In11.Cu")
		(net "P5E_CPU1_P1_TX_BUF_DN<3>")
	)
	(segment
		(start 76.81468 -396.977362)
		(end 70.09638 -399.214594)
		(width 0.14224)
		(layer "In11.Cu")
		(net "P5E_CPU1_P1_TX_BUF_DN<3>")
	)
	(segment
		(start 83.91906 -388.774432)
		(end 83.971384 -388.826756)
		(width 0.14224)
		(layer "In11.Cu")
		(net "P5E_CPU1_P1_TX_BUF_DN<3>")
	)
	(segment
		(start 70.09638 -399.214594)
		(end 61.84011 -401.715732)
		(width 0.14224)
		(layer "In11.Cu")
		(net "P5E_CPU1_P1_TX_BUF_DN<3>")
	)
	(segment
		(start 77.995526 -396.508478)
		(end 76.81468 -396.977362)
		(width 0.14224)
		(layer "In11.Cu")
		(net "P5E_CPU1_P1_TX_BUF_DN<3>")
	)
	(segment
		(start 83.898486 -390.643364)
		(end 83.507834 -391.034016)
		(width 0.14224)
		(layer "In11.Cu")
		(net "P5E_CPU1_P1_TX_BUF_DN<3>")
	)
	(segment
		(start 83.652868 -389.325104)
		(end 83.652868 -389.515604)
		(width 0.14224)
		(layer "In11.Cu")
		(net "P5E_CPU1_P1_TX_BUF_DN<3>")
	)
	(segment
		(start 84.013548 -390.176004)
		(end 84.013548 -390.365742)
		(width 0.14224)
		(layer "In11.Cu")
		(net "P5E_CPU1_P1_TX_BUF_DN<3>")
	)
	(segment
		(start 83.239356 -391.682224)
		(end 83.239356 -394.168884)
		(width 0.14224)
		(layer "In11.Cu")
		(net "P5E_CPU1_P1_TX_BUF_DN<3>")
	)
	(segment
		(start 59.583828 -402.855176)
		(end 59.196224 -403.24278)
		(width 0.14224)
		(layer "In11.Cu")
		(net "P5E_CPU1_P1_TX_BUF_DN<3>")
	)
	(segment
		(start 61.164216 -401.997926)
		(end 59.583828 -402.855176)
		(width 0.14224)
		(layer "In11.Cu")
		(net "P5E_CPU1_P1_TX_BUF_DN<3>")
	)
	(segment
		(start 82.31378 -395.058138)
		(end 81.106264 -395.558772)
		(width 0.14224)
		(layer "In11.Cu")
		(net "P5E_CPU1_P1_TX_BUF_DN<3>")
	)
	(segment
		(start 83.971384 -389.006588)
		(end 83.652868 -389.325104)
		(width 0.14224)
		(layer "In11.Cu")
		(net "P5E_CPU1_P1_TX_BUF_DN<3>")
	)
	(segment
		(start 83.971384 -388.826756)
		(end 83.971384 -389.006588)
		(width 0.14224)
		(layer "In11.Cu")
		(net "P5E_CPU1_P1_TX_BUF_DN<3>")
	)
	(arc
		(start 83.239356 -394.168884)
		(mid 83.229654 -394.217568)
		(end 83.202018 -394.2588)
		(width 0.14224)
		(layer "In11.Cu")
		(net "P5E_CPU1_P1_TX_BUF_DN<3>")
	)
	(arc
		(start 82.581496 -394.879322)
		(mid 82.456442 -394.98191)
		(end 82.31378 -395.058138)
		(width 0.14224)
		(layer "In11.Cu")
		(net "P5E_CPU1_P1_TX_BUF_DN<3>")
	)
	(arc
		(start 83.652868 -389.515604)
		(mid 83.698358 -389.744208)
		(end 83.827874 -389.938006)
		(width 0.14224)
		(layer "In11.Cu")
		(net "P5E_CPU1_P1_TX_BUF_DN<3>")
	)
	(arc
		(start 59.196224 -403.24278)
		(mid 58.907649 -403.674663)
		(end 58.806334 -404.184104)
		(width 0.14224)
		(layer "In11.Cu")
		(net "P5E_CPU1_P1_TX_BUF_DN<3>")
	)
	(arc
		(start 83.97621 -390.086342)
		(mid 84.00378 -390.127464)
		(end 84.013548 -390.176004)
		(width 0.14224)
		(layer "In11.Cu")
		(net "P5E_CPU1_P1_TX_BUF_DN<3>")
	)
	(arc
		(start 84.013548 -390.365742)
		(mid 83.983642 -390.516001)
		(end 83.898486 -390.643364)
		(width 0.14224)
		(layer "In11.Cu")
		(net "P5E_CPU1_P1_TX_BUF_DN<3>")
	)
	(arc
		(start 83.507834 -391.034016)
		(mid 83.309117 -391.331416)
		(end 83.239356 -391.682224)
		(width 0.14224)
		(layer "In11.Cu")
		(net "P5E_CPU1_P1_TX_BUF_DN<3>")
	)
	(segment
		(start 82.198464 -388.774432)
		(end 82.719164 -388.774432)
		(width 0.127)
		(layer "F.Cu")
		(net "P5E_CPU1_P1_TX_BUF_DN<2>")
	)
	(segment
		(start 55.722774 -407.27503)
		(end 55.452264 -407.00452)
		(width 0.12954)
		(layer "B.Cu")
		(net "P5E_CPU1_P1_TX_BUF_DN<2>")
	)
	(segment
		(start 55.722774 -407.954734)
		(end 55.722774 -407.27503)
		(width 0.12954)
		(layer "B.Cu")
		(net "P5E_CPU1_P1_TX_BUF_DN<2>")
	)
	(segment
		(start 55.426864 -408.250644)
		(end 55.722774 -407.954734)
		(width 0.12954)
		(layer "B.Cu")
		(net "P5E_CPU1_P1_TX_BUF_DN<2>")
	)
	(segment
		(start 82.719164 -388.774432)
		(end 82.770472 -388.82574)
		(width 0.14224)
		(layer "In11.Cu")
		(net "P5E_CPU1_P1_TX_BUF_DN<2>")
	)
	(segment
		(start 75.377548 -396.473172)
		(end 69.660008 -398.37233)
		(width 0.14224)
		(layer "In11.Cu")
		(net "P5E_CPU1_P1_TX_BUF_DN<2>")
	)
	(segment
		(start 61.306456 -400.903186)
		(end 60.96127 -401.047204)
		(width 0.14224)
		(layer "In11.Cu")
		(net "P5E_CPU1_P1_TX_BUF_DN<2>")
	)
	(segment
		(start 57.520078 -402.222208)
		(end 57.520332 -402.222462)
		(width 0.14224)
		(layer "In11.Cu")
		(net "P5E_CPU1_P1_TX_BUF_DN<2>")
	)
	(segment
		(start 76.292202 -396.110968)
		(end 75.377548 -396.473172)
		(width 0.14224)
		(layer "In11.Cu")
		(net "P5E_CPU1_P1_TX_BUF_DN<2>")
	)
	(segment
		(start 82.770472 -388.82574)
		(end 82.770472 -389.035544)
		(width 0.14224)
		(layer "In11.Cu")
		(net "P5E_CPU1_P1_TX_BUF_DN<2>")
	)
	(segment
		(start 82.770472 -389.035544)
		(end 82.454496 -389.35152)
		(width 0.14224)
		(layer "In11.Cu")
		(net "P5E_CPU1_P1_TX_BUF_DN<2>")
	)
	(segment
		(start 60.96127 -401.047204)
		(end 57.520078 -402.222208)
		(width 0.14224)
		(layer "In11.Cu")
		(net "P5E_CPU1_P1_TX_BUF_DN<2>")
	)
	(segment
		(start 82.454496 -389.35152)
		(end 82.454496 -389.533892)
		(width 0.14224)
		(layer "In11.Cu")
		(net "P5E_CPU1_P1_TX_BUF_DN<2>")
	)
	(segment
		(start 55.743094 -404.257256)
		(end 55.743094 -406.71369)
		(width 0.14224)
		(layer "In11.Cu")
		(net "P5E_CPU1_P1_TX_BUF_DN<2>")
	)
	(segment
		(start 57.520332 -402.222462)
		(end 57.098184 -402.36648)
		(width 0.14224)
		(layer "In11.Cu")
		(net "P5E_CPU1_P1_TX_BUF_DN<2>")
	)
	(segment
		(start 81.90992 -394.21562)
		(end 80.87741 -394.64234)
		(width 0.14224)
		(layer "In11.Cu")
		(net "P5E_CPU1_P1_TX_BUF_DN<2>")
	)
	(segment
		(start 78.106778 -395.483588)
		(end 76.292202 -396.110968)
		(width 0.14224)
		(layer "In11.Cu")
		(net "P5E_CPU1_P1_TX_BUF_DN<2>")
	)
	(segment
		(start 82.024728 -391.6807)
		(end 82.024728 -394.062204)
		(width 0.14224)
		(layer "In11.Cu")
		(net "P5E_CPU1_P1_TX_BUF_DN<2>")
	)
	(segment
		(start 81.987644 -394.151612)
		(end 81.951322 -394.187934)
		(width 0.14224)
		(layer "In11.Cu")
		(net "P5E_CPU1_P1_TX_BUF_DN<2>")
	)
	(segment
		(start 55.743094 -406.71369)
		(end 55.452264 -407.00452)
		(width 0.14224)
		(layer "In11.Cu")
		(net "P5E_CPU1_P1_TX_BUF_DN<2>")
	)
	(segment
		(start 82.750152 -390.146286)
		(end 82.750152 -390.371838)
		(width 0.14224)
		(layer "In11.Cu")
		(net "P5E_CPU1_P1_TX_BUF_DN<2>")
	)
	(segment
		(start 56.569864 -402.695664)
		(end 56.262016 -403.003512)
		(width 0.14224)
		(layer "In11.Cu")
		(net "P5E_CPU1_P1_TX_BUF_DN<2>")
	)
	(segment
		(start 69.660008 -398.37233)
		(end 61.306456 -400.903186)
		(width 0.14224)
		(layer "In11.Cu")
		(net "P5E_CPU1_P1_TX_BUF_DN<2>")
	)
	(segment
		(start 80.87741 -394.64234)
		(end 78.106778 -395.483588)
		(width 0.14224)
		(layer "In11.Cu")
		(net "P5E_CPU1_P1_TX_BUF_DN<2>")
	)
	(segment
		(start 82.679286 -390.54278)
		(end 82.366866 -390.854946)
		(width 0.14224)
		(layer "In11.Cu")
		(net "P5E_CPU1_P1_TX_BUF_DN<2>")
	)
	(segment
		(start 82.617818 -389.9281)
		(end 82.689192 -389.999474)
		(width 0.14224)
		(layer "In11.Cu")
		(net "P5E_CPU1_P1_TX_BUF_DN<2>")
	)
	(arc
		(start 81.951322 -394.187934)
		(mid 81.931979 -394.203805)
		(end 81.90992 -394.21562)
		(width 0.14224)
		(layer "In11.Cu")
		(net "P5E_CPU1_P1_TX_BUF_DN<2>")
	)
	(arc
		(start 82.024728 -394.062204)
		(mid 82.015099 -394.11061)
		(end 81.987644 -394.151612)
		(width 0.14224)
		(layer "In11.Cu")
		(net "P5E_CPU1_P1_TX_BUF_DN<2>")
	)
	(arc
		(start 82.750152 -390.371838)
		(mid 82.731745 -390.464374)
		(end 82.679286 -390.54278)
		(width 0.14224)
		(layer "In11.Cu")
		(net "P5E_CPU1_P1_TX_BUF_DN<2>")
	)
	(arc
		(start 82.366866 -390.854946)
		(mid 82.113667 -391.233791)
		(end 82.024728 -391.6807)
		(width 0.14224)
		(layer "In11.Cu")
		(net "P5E_CPU1_P1_TX_BUF_DN<2>")
	)
	(arc
		(start 56.262016 -403.003512)
		(mid 55.878011 -403.578833)
		(end 55.743094 -404.257256)
		(width 0.14224)
		(layer "In11.Cu")
		(net "P5E_CPU1_P1_TX_BUF_DN<2>")
	)
	(arc
		(start 57.098184 -402.36648)
		(mid 56.815108 -402.500718)
		(end 56.569864 -402.695664)
		(width 0.14224)
		(layer "In11.Cu")
		(net "P5E_CPU1_P1_TX_BUF_DN<2>")
	)
	(arc
		(start 82.454496 -389.533892)
		(mid 82.496935 -389.747249)
		(end 82.617818 -389.9281)
		(width 0.14224)
		(layer "In11.Cu")
		(net "P5E_CPU1_P1_TX_BUF_DN<2>")
	)
	(arc
		(start 82.689192 -389.999474)
		(mid 82.734307 -390.066803)
		(end 82.750152 -390.146286)
		(width 0.14224)
		(layer "In11.Cu")
		(net "P5E_CPU1_P1_TX_BUF_DN<2>")
	)
	(segment
		(start 80.998314 -388.774432)
		(end 81.519014 -388.774432)
		(width 0.127)
		(layer "F.Cu")
		(net "P5E_CPU1_P1_TX_BUF_DN<1>")
	)
	(segment
		(start 52.363624 -408.250644)
		(end 52.659534 -407.954734)
		(width 0.12954)
		(layer "B.Cu")
		(net "P5E_CPU1_P1_TX_BUF_DN<1>")
	)
	(segment
		(start 52.659534 -407.27503)
		(end 52.389024 -407.00452)
		(width 0.12954)
		(layer "B.Cu")
		(net "P5E_CPU1_P1_TX_BUF_DN<1>")
	)
	(segment
		(start 52.659534 -407.954734)
		(end 52.659534 -407.27503)
		(width 0.12954)
		(layer "B.Cu")
		(net "P5E_CPU1_P1_TX_BUF_DN<1>")
	)
	(segment
		(start 52.679854 -404.184104)
		(end 52.679854 -406.71369)
		(width 0.14224)
		(layer "In11.Cu")
		(net "P5E_CPU1_P1_TX_BUF_DN<1>")
	)
	(segment
		(start 77.840586 -394.487654)
		(end 76.384658 -395.09065)
		(width 0.14224)
		(layer "In11.Cu")
		(net "P5E_CPU1_P1_TX_BUF_DN<1>")
	)
	(segment
		(start 81.382616 -389.887206)
		(end 81.572608 -390.077198)
		(width 0.14224)
		(layer "In11.Cu")
		(net "P5E_CPU1_P1_TX_BUF_DN<1>")
	)
	(segment
		(start 81.252822 -389.325104)
		(end 81.252822 -389.57377)
		(width 0.14224)
		(layer "In11.Cu")
		(net "P5E_CPU1_P1_TX_BUF_DN<1>")
	)
	(segment
		(start 81.571338 -389.006588)
		(end 81.252822 -389.325104)
		(width 0.14224)
		(layer "In11.Cu")
		(net "P5E_CPU1_P1_TX_BUF_DN<1>")
	)
	(segment
		(start 76.384658 -395.09065)
		(end 71.65975 -396.52194)
		(width 0.14224)
		(layer "In11.Cu")
		(net "P5E_CPU1_P1_TX_BUF_DN<1>")
	)
	(segment
		(start 71.65975 -396.52194)
		(end 69.049138 -397.583152)
		(width 0.14224)
		(layer "In11.Cu")
		(net "P5E_CPU1_P1_TX_BUF_DN<1>")
	)
	(segment
		(start 81.519014 -388.774432)
		(end 81.571338 -388.826756)
		(width 0.14224)
		(layer "In11.Cu")
		(net "P5E_CPU1_P1_TX_BUF_DN<1>")
	)
	(segment
		(start 53.382164 -402.670518)
		(end 53.25364 -402.799042)
		(width 0.14224)
		(layer "In11.Cu")
		(net "P5E_CPU1_P1_TX_BUF_DN<1>")
	)
	(segment
		(start 69.049138 -397.583152)
		(end 54.567074 -401.960842)
		(width 0.14224)
		(layer "In11.Cu")
		(net "P5E_CPU1_P1_TX_BUF_DN<1>")
	)
	(segment
		(start 80.71739 -391.004044)
		(end 80.127856 -391.004044)
		(width 0.14224)
		(layer "In11.Cu")
		(net "P5E_CPU1_P1_TX_BUF_DN<1>")
	)
	(segment
		(start 81.572608 -390.331706)
		(end 81.029048 -390.874758)
		(width 0.14224)
		(layer "In11.Cu")
		(net "P5E_CPU1_P1_TX_BUF_DN<1>")
	)
	(segment
		(start 52.679854 -406.71369)
		(end 52.389024 -407.00452)
		(width 0.14224)
		(layer "In11.Cu")
		(net "P5E_CPU1_P1_TX_BUF_DN<1>")
	)
	(segment
		(start 79.29118 -393.03706)
		(end 77.840586 -394.487654)
		(width 0.14224)
		(layer "In11.Cu")
		(net "P5E_CPU1_P1_TX_BUF_DN<1>")
	)
	(segment
		(start 79.432658 -391.898632)
		(end 79.432658 -392.695684)
		(width 0.14224)
		(layer "In11.Cu")
		(net "P5E_CPU1_P1_TX_BUF_DN<1>")
	)
	(segment
		(start 81.571338 -388.826756)
		(end 81.571338 -389.006588)
		(width 0.14224)
		(layer "In11.Cu")
		(net "P5E_CPU1_P1_TX_BUF_DN<1>")
	)
	(arc
		(start 79.432658 -392.695684)
		(mid 79.395888 -392.88045)
		(end 79.29118 -393.03706)
		(width 0.14224)
		(layer "In11.Cu")
		(net "P5E_CPU1_P1_TX_BUF_DN<1>")
	)
	(arc
		(start 54.567074 -401.960842)
		(mid 53.930793 -402.2425)
		(end 53.382164 -402.670518)
		(width 0.14224)
		(layer "In11.Cu")
		(net "P5E_CPU1_P1_TX_BUF_DN<1>")
	)
	(arc
		(start 81.029048 -390.874758)
		(mid 80.886073 -390.970384)
		(end 80.71739 -391.004044)
		(width 0.14224)
		(layer "In11.Cu")
		(net "P5E_CPU1_P1_TX_BUF_DN<1>")
	)
	(arc
		(start 80.127856 -391.004044)
		(mid 79.915611 -391.046168)
		(end 79.73568 -391.16635)
		(width 0.14224)
		(layer "In11.Cu")
		(net "P5E_CPU1_P1_TX_BUF_DN<1>")
	)
	(arc
		(start 81.252822 -389.57377)
		(mid 81.286561 -389.743387)
		(end 81.382616 -389.887206)
		(width 0.14224)
		(layer "In11.Cu")
		(net "P5E_CPU1_P1_TX_BUF_DN<1>")
	)
	(arc
		(start 79.73568 -391.16635)
		(mid 79.511224 -391.502312)
		(end 79.432658 -391.898632)
		(width 0.14224)
		(layer "In11.Cu")
		(net "P5E_CPU1_P1_TX_BUF_DN<1>")
	)
	(arc
		(start 81.572608 -390.077198)
		(mid 81.625393 -390.204452)
		(end 81.572608 -390.331706)
		(width 0.14224)
		(layer "In11.Cu")
		(net "P5E_CPU1_P1_TX_BUF_DN<1>")
	)
	(arc
		(start 53.25364 -402.799042)
		(mid 52.828978 -403.4345)
		(end 52.679854 -404.184104)
		(width 0.14224)
		(layer "In11.Cu")
		(net "P5E_CPU1_P1_TX_BUF_DN<1>")
	)
	(segment
		(start 97.798382 -388.774432)
		(end 98.319082 -388.774432)
		(width 0.127)
		(layer "F.Cu")
		(net "P5E_CPU1_P1_TX_BUF_DN<15>")
	)
	(segment
		(start 95.544894 -407.954734)
		(end 95.544894 -407.27503)
		(width 0.12954)
		(layer "B.Cu")
		(net "P5E_CPU1_P1_TX_BUF_DN<15>")
	)
	(segment
		(start 95.248984 -408.250644)
		(end 95.544894 -407.954734)
		(width 0.12954)
		(layer "B.Cu")
		(net "P5E_CPU1_P1_TX_BUF_DN<15>")
	)
	(segment
		(start 95.544894 -407.27503)
		(end 95.274384 -407.00452)
		(width 0.12954)
		(layer "B.Cu")
		(net "P5E_CPU1_P1_TX_BUF_DN<15>")
	)
	(segment
		(start 96.790764 -399.876264)
		(end 96.793304 -399.880074)
		(width 0.14224)
		(layer "In11.Cu")
		(net "P5E_CPU1_P1_TX_BUF_DN<15>")
	)
	(segment
		(start 98.30308 -390.877298)
		(end 97.73412 -391.446258)
		(width 0.14224)
		(layer "In11.Cu")
		(net "P5E_CPU1_P1_TX_BUF_DN<15>")
	)
	(segment
		(start 95.547688 -406.731216)
		(end 95.274384 -407.00452)
		(width 0.14224)
		(layer "In11.Cu")
		(net "P5E_CPU1_P1_TX_BUF_DN<15>")
	)
	(segment
		(start 98.41357 -390.176512)
		(end 98.41357 -390.610598)
		(width 0.14224)
		(layer "In11.Cu")
		(net "P5E_CPU1_P1_TX_BUF_DN<15>")
	)
	(segment
		(start 96.793304 -399.880074)
		(end 96.660208 -400.411188)
		(width 0.14224)
		(layer "In11.Cu")
		(net "P5E_CPU1_P1_TX_BUF_DN<15>")
	)
	(segment
		(start 98.371406 -389.006588)
		(end 98.05289 -389.325104)
		(width 0.14224)
		(layer "In11.Cu")
		(net "P5E_CPU1_P1_TX_BUF_DN<15>")
	)
	(segment
		(start 98.319082 -388.774432)
		(end 98.371406 -388.826756)
		(width 0.14224)
		(layer "In11.Cu")
		(net "P5E_CPU1_P1_TX_BUF_DN<15>")
	)
	(segment
		(start 96.515428 -400.976338)
		(end 96.51365 -400.977354)
		(width 0.14224)
		(layer "In11.Cu")
		(net "P5E_CPU1_P1_TX_BUF_DN<15>")
	)
	(segment
		(start 98.371406 -388.826756)
		(end 98.371406 -389.006588)
		(width 0.14224)
		(layer "In11.Cu")
		(net "P5E_CPU1_P1_TX_BUF_DN<15>")
	)
	(segment
		(start 97.576894 -396.738348)
		(end 96.790764 -399.876264)
		(width 0.14224)
		(layer "In11.Cu")
		(net "P5E_CPU1_P1_TX_BUF_DN<15>")
	)
	(segment
		(start 97.648522 -391.653014)
		(end 97.648522 -396.15872)
		(width 0.14224)
		(layer "In11.Cu")
		(net "P5E_CPU1_P1_TX_BUF_DN<15>")
	)
	(segment
		(start 96.660208 -400.411188)
		(end 96.656652 -400.41322)
		(width 0.14224)
		(layer "In11.Cu")
		(net "P5E_CPU1_P1_TX_BUF_DN<15>")
	)
	(segment
		(start 96.513904 -400.977354)
		(end 95.547688 -404.83536)
		(width 0.14224)
		(layer "In11.Cu")
		(net "P5E_CPU1_P1_TX_BUF_DN<15>")
	)
	(segment
		(start 98.05289 -389.325104)
		(end 98.05289 -389.47725)
		(width 0.14224)
		(layer "In11.Cu")
		(net "P5E_CPU1_P1_TX_BUF_DN<15>")
	)
	(segment
		(start 96.51365 -400.977354)
		(end 96.513904 -400.977354)
		(width 0.14224)
		(layer "In11.Cu")
		(net "P5E_CPU1_P1_TX_BUF_DN<15>")
	)
	(segment
		(start 95.547688 -404.83536)
		(end 95.547688 -406.731216)
		(width 0.14224)
		(layer "In11.Cu")
		(net "P5E_CPU1_P1_TX_BUF_DN<15>")
	)
	(segment
		(start 96.656652 -400.41322)
		(end 96.515428 -400.976338)
		(width 0.14224)
		(layer "In11.Cu")
		(net "P5E_CPU1_P1_TX_BUF_DN<15>")
	)
	(segment
		(start 98.255074 -389.965184)
		(end 98.376232 -390.086342)
		(width 0.14224)
		(layer "In11.Cu")
		(net "P5E_CPU1_P1_TX_BUF_DN<15>")
	)
	(arc
		(start 98.376232 -390.086342)
		(mid 98.403875 -390.127712)
		(end 98.41357 -390.176512)
		(width 0.14224)
		(layer "In11.Cu")
		(net "P5E_CPU1_P1_TX_BUF_DN<15>")
	)
	(arc
		(start 98.05289 -389.47725)
		(mid 98.105437 -389.741332)
		(end 98.255074 -389.965184)
		(width 0.14224)
		(layer "In11.Cu")
		(net "P5E_CPU1_P1_TX_BUF_DN<15>")
	)
	(arc
		(start 97.648522 -396.15872)
		(mid 97.630517 -396.450735)
		(end 97.576894 -396.738348)
		(width 0.14224)
		(layer "In11.Cu")
		(net "P5E_CPU1_P1_TX_BUF_DN<15>")
	)
	(arc
		(start 98.41357 -390.610598)
		(mid 98.384843 -390.754928)
		(end 98.30308 -390.877298)
		(width 0.14224)
		(layer "In11.Cu")
		(net "P5E_CPU1_P1_TX_BUF_DN<15>")
	)
	(arc
		(start 97.73412 -391.446258)
		(mid 97.67079 -391.541133)
		(end 97.648522 -391.653014)
		(width 0.14224)
		(layer "In11.Cu")
		(net "P5E_CPU1_P1_TX_BUF_DN<15>")
	)
	(segment
		(start 96.598486 -388.774432)
		(end 97.119186 -388.774432)
		(width 0.127)
		(layer "F.Cu")
		(net "P5E_CPU1_P1_TX_BUF_DN<14>")
	)
	(segment
		(start 92.481654 -407.27503)
		(end 92.211144 -407.00452)
		(width 0.12954)
		(layer "B.Cu")
		(net "P5E_CPU1_P1_TX_BUF_DN<14>")
	)
	(segment
		(start 92.185744 -408.250644)
		(end 92.481654 -407.954734)
		(width 0.12954)
		(layer "B.Cu")
		(net "P5E_CPU1_P1_TX_BUF_DN<14>")
	)
	(segment
		(start 92.481654 -407.954734)
		(end 92.481654 -407.27503)
		(width 0.12954)
		(layer "B.Cu")
		(net "P5E_CPU1_P1_TX_BUF_DN<14>")
	)
	(segment
		(start 97.028762 -390.956292)
		(end 96.543622 -391.441432)
		(width 0.14224)
		(layer "In11.Cu")
		(net "P5E_CPU1_P1_TX_BUF_DN<14>")
	)
	(segment
		(start 97.17151 -388.826756)
		(end 97.17151 -389.006588)
		(width 0.14224)
		(layer "In11.Cu")
		(net "P5E_CPU1_P1_TX_BUF_DN<14>")
	)
	(segment
		(start 92.501974 -406.71369)
		(end 92.211144 -407.00452)
		(width 0.14224)
		(layer "In11.Cu")
		(net "P5E_CPU1_P1_TX_BUF_DN<14>")
	)
	(segment
		(start 97.188274 -390.140698)
		(end 97.188274 -390.570974)
		(width 0.14224)
		(layer "In11.Cu")
		(net "P5E_CPU1_P1_TX_BUF_DN<14>")
	)
	(segment
		(start 95.828104 -397.18488)
		(end 94.417896 -400.16811)
		(width 0.14224)
		(layer "In11.Cu")
		(net "P5E_CPU1_P1_TX_BUF_DN<14>")
	)
	(segment
		(start 94.415102 -400.169126)
		(end 92.501974 -404.217124)
		(width 0.14224)
		(layer "In11.Cu")
		(net "P5E_CPU1_P1_TX_BUF_DN<14>")
	)
	(segment
		(start 97.119186 -388.774432)
		(end 97.17151 -388.826756)
		(width 0.14224)
		(layer "In11.Cu")
		(net "P5E_CPU1_P1_TX_BUF_DN<14>")
	)
	(segment
		(start 92.501974 -404.217124)
		(end 92.501974 -406.71369)
		(width 0.14224)
		(layer "In11.Cu")
		(net "P5E_CPU1_P1_TX_BUF_DN<14>")
	)
	(segment
		(start 96.852994 -389.325104)
		(end 96.852994 -389.583422)
		(width 0.14224)
		(layer "In11.Cu")
		(net "P5E_CPU1_P1_TX_BUF_DN<14>")
	)
	(segment
		(start 97.17151 -389.006588)
		(end 96.852994 -389.325104)
		(width 0.14224)
		(layer "In11.Cu")
		(net "P5E_CPU1_P1_TX_BUF_DN<14>")
	)
	(segment
		(start 96.972882 -389.872728)
		(end 97.150936 -390.050782)
		(width 0.14224)
		(layer "In11.Cu")
		(net "P5E_CPU1_P1_TX_BUF_DN<14>")
	)
	(segment
		(start 96.448372 -391.671302)
		(end 96.448372 -395.423136)
		(width 0.14224)
		(layer "In11.Cu")
		(net "P5E_CPU1_P1_TX_BUF_DN<14>")
	)
	(segment
		(start 94.417896 -400.16811)
		(end 94.415102 -400.169126)
		(width 0.14224)
		(layer "In11.Cu")
		(net "P5E_CPU1_P1_TX_BUF_DN<14>")
	)
	(arc
		(start 96.543622 -391.441432)
		(mid 96.473152 -391.546897)
		(end 96.448372 -391.671302)
		(width 0.14224)
		(layer "In11.Cu")
		(net "P5E_CPU1_P1_TX_BUF_DN<14>")
	)
	(arc
		(start 96.448372 -395.423136)
		(mid 96.288762 -396.356998)
		(end 95.828104 -397.18488)
		(width 0.14224)
		(layer "In11.Cu")
		(net "P5E_CPU1_P1_TX_BUF_DN<14>")
	)
	(arc
		(start 97.150936 -390.050782)
		(mid 97.178555 -390.092022)
		(end 97.188274 -390.140698)
		(width 0.14224)
		(layer "In11.Cu")
		(net "P5E_CPU1_P1_TX_BUF_DN<14>")
	)
	(arc
		(start 97.188274 -390.570974)
		(mid 97.146801 -390.779471)
		(end 97.028762 -390.956292)
		(width 0.14224)
		(layer "In11.Cu")
		(net "P5E_CPU1_P1_TX_BUF_DN<14>")
	)
	(arc
		(start 96.852994 -389.583422)
		(mid 96.884157 -389.74)
		(end 96.972882 -389.872728)
		(width 0.14224)
		(layer "In11.Cu")
		(net "P5E_CPU1_P1_TX_BUF_DN<14>")
	)
	(segment
		(start 95.398336 -388.774432)
		(end 95.919036 -388.774432)
		(width 0.127)
		(layer "F.Cu")
		(net "P5E_CPU1_P1_TX_BUF_DN<13>")
	)
	(segment
		(start 89.122504 -408.250644)
		(end 89.418414 -407.954734)
		(width 0.12954)
		(layer "B.Cu")
		(net "P5E_CPU1_P1_TX_BUF_DN<13>")
	)
	(segment
		(start 89.418414 -407.954734)
		(end 89.418414 -407.27503)
		(width 0.12954)
		(layer "B.Cu")
		(net "P5E_CPU1_P1_TX_BUF_DN<13>")
	)
	(segment
		(start 89.418414 -407.27503)
		(end 89.147904 -407.00452)
		(width 0.12954)
		(layer "B.Cu")
		(net "P5E_CPU1_P1_TX_BUF_DN<13>")
	)
	(segment
		(start 89.917778 -403.332696)
		(end 89.507822 -403.94509)
		(width 0.14224)
		(layer "In11.Cu")
		(net "P5E_CPU1_P1_TX_BUF_DN<13>")
	)
	(segment
		(start 95.248476 -391.68832)
		(end 95.248476 -395.595094)
		(width 0.14224)
		(layer "In11.Cu")
		(net "P5E_CPU1_P1_TX_BUF_DN<13>")
	)
	(segment
		(start 91.273376 -401.48891)
		(end 90.164158 -402.98243)
		(width 0.14224)
		(layer "In11.Cu")
		(net "P5E_CPU1_P1_TX_BUF_DN<13>")
	)
	(segment
		(start 95.97136 -388.826756)
		(end 95.97136 -389.006588)
		(width 0.14224)
		(layer "In11.Cu")
		(net "P5E_CPU1_P1_TX_BUF_DN<13>")
	)
	(segment
		(start 93.428058 -398.587976)
		(end 91.667076 -400.958812)
		(width 0.14224)
		(layer "In11.Cu")
		(net "P5E_CPU1_P1_TX_BUF_DN<13>")
	)
	(segment
		(start 95.652844 -389.325104)
		(end 95.652844 -389.528304)
		(width 0.14224)
		(layer "In11.Cu")
		(net "P5E_CPU1_P1_TX_BUF_DN<13>")
	)
	(segment
		(start 91.665806 -400.959066)
		(end 91.273122 -401.487894)
		(width 0.14224)
		(layer "In11.Cu")
		(net "P5E_CPU1_P1_TX_BUF_DN<13>")
	)
	(segment
		(start 91.667076 -400.958812)
		(end 91.66606 -400.958812)
		(width 0.14224)
		(layer "In11.Cu")
		(net "P5E_CPU1_P1_TX_BUF_DN<13>")
	)
	(segment
		(start 95.97136 -389.006588)
		(end 95.652844 -389.325104)
		(width 0.14224)
		(layer "In11.Cu")
		(net "P5E_CPU1_P1_TX_BUF_DN<13>")
	)
	(segment
		(start 95.889572 -390.863328)
		(end 95.37827 -391.37463)
		(width 0.14224)
		(layer "In11.Cu")
		(net "P5E_CPU1_P1_TX_BUF_DN<13>")
	)
	(segment
		(start 89.438734 -406.71369)
		(end 89.147904 -407.00452)
		(width 0.14224)
		(layer "In11.Cu")
		(net "P5E_CPU1_P1_TX_BUF_DN<13>")
	)
	(segment
		(start 93.427804 -398.587976)
		(end 93.428058 -398.587976)
		(width 0.14224)
		(layer "In11.Cu")
		(net "P5E_CPU1_P1_TX_BUF_DN<13>")
	)
	(segment
		(start 91.273122 -401.487894)
		(end 91.273376 -401.48891)
		(width 0.14224)
		(layer "In11.Cu")
		(net "P5E_CPU1_P1_TX_BUF_DN<13>")
	)
	(segment
		(start 89.438734 -404.172928)
		(end 89.438734 -406.71369)
		(width 0.14224)
		(layer "In11.Cu")
		(net "P5E_CPU1_P1_TX_BUF_DN<13>")
	)
	(segment
		(start 95.919036 -388.774432)
		(end 95.97136 -388.826756)
		(width 0.14224)
		(layer "In11.Cu")
		(net "P5E_CPU1_P1_TX_BUF_DN<13>")
	)
	(segment
		(start 91.66606 -400.958812)
		(end 91.665806 -400.959066)
		(width 0.14224)
		(layer "In11.Cu")
		(net "P5E_CPU1_P1_TX_BUF_DN<13>")
	)
	(segment
		(start 95.81896 -389.92937)
		(end 95.940372 -390.050782)
		(width 0.14224)
		(layer "In11.Cu")
		(net "P5E_CPU1_P1_TX_BUF_DN<13>")
	)
	(segment
		(start 94.168468 -397.59128)
		(end 93.427804 -398.587976)
		(width 0.14224)
		(layer "In11.Cu")
		(net "P5E_CPU1_P1_TX_BUF_DN<13>")
	)
	(segment
		(start 96.070928 -390.365996)
		(end 96.070928 -390.425432)
		(width 0.14224)
		(layer "In11.Cu")
		(net "P5E_CPU1_P1_TX_BUF_DN<13>")
	)
	(arc
		(start 95.091758 -396.285466)
		(mid 95.047736 -396.372784)
		(end 94.994222 -396.45463)
		(width 0.14224)
		(layer "In11.Cu")
		(net "P5E_CPU1_P1_TX_BUF_DN<13>")
	)
	(arc
		(start 89.507822 -403.94509)
		(mid 89.456384 -404.053886)
		(end 89.438734 -404.172928)
		(width 0.14224)
		(layer "In11.Cu")
		(net "P5E_CPU1_P1_TX_BUF_DN<13>")
	)
	(arc
		(start 95.940372 -390.050782)
		(mid 96.037005 -390.195403)
		(end 96.070928 -390.365996)
		(width 0.14224)
		(layer "In11.Cu")
		(net "P5E_CPU1_P1_TX_BUF_DN<13>")
	)
	(arc
		(start 95.37827 -391.37463)
		(mid 95.282134 -391.518553)
		(end 95.248476 -391.68832)
		(width 0.14224)
		(layer "In11.Cu")
		(net "P5E_CPU1_P1_TX_BUF_DN<13>")
	)
	(arc
		(start 94.994222 -396.45463)
		(mid 94.584153 -397.024995)
		(end 94.168468 -397.59128)
		(width 0.14224)
		(layer "In11.Cu")
		(net "P5E_CPU1_P1_TX_BUF_DN<13>")
	)
	(arc
		(start 96.070928 -390.425432)
		(mid 96.023805 -390.662424)
		(end 95.889572 -390.863328)
		(width 0.14224)
		(layer "In11.Cu")
		(net "P5E_CPU1_P1_TX_BUF_DN<13>")
	)
	(arc
		(start 95.241364 -395.721586)
		(mid 95.187308 -396.009031)
		(end 95.091758 -396.285466)
		(width 0.14224)
		(layer "In11.Cu")
		(net "P5E_CPU1_P1_TX_BUF_DN<13>")
	)
	(arc
		(start 90.164158 -402.98243)
		(mid 90.03886 -403.15608)
		(end 89.917778 -403.332696)
		(width 0.14224)
		(layer "In11.Cu")
		(net "P5E_CPU1_P1_TX_BUF_DN<13>")
	)
	(arc
		(start 95.248476 -395.595094)
		(mid 95.246712 -395.658441)
		(end 95.241364 -395.721586)
		(width 0.14224)
		(layer "In11.Cu")
		(net "P5E_CPU1_P1_TX_BUF_DN<13>")
	)
	(arc
		(start 95.652844 -389.528304)
		(mid 95.696018 -389.745355)
		(end 95.81896 -389.92937)
		(width 0.14224)
		(layer "In11.Cu")
		(net "P5E_CPU1_P1_TX_BUF_DN<13>")
	)
	(segment
		(start 94.19844 -388.774432)
		(end 94.71914 -388.774432)
		(width 0.127)
		(layer "F.Cu")
		(net "P5E_CPU1_P1_TX_BUF_DN<12>")
	)
	(segment
		(start 86.355174 -407.27503)
		(end 86.084664 -407.00452)
		(width 0.12954)
		(layer "B.Cu")
		(net "P5E_CPU1_P1_TX_BUF_DN<12>")
	)
	(segment
		(start 86.059264 -408.250644)
		(end 86.355174 -407.954734)
		(width 0.12954)
		(layer "B.Cu")
		(net "P5E_CPU1_P1_TX_BUF_DN<12>")
	)
	(segment
		(start 86.355174 -407.954734)
		(end 86.355174 -407.27503)
		(width 0.12954)
		(layer "B.Cu")
		(net "P5E_CPU1_P1_TX_BUF_DN<12>")
	)
	(segment
		(start 88.593676 -402.026882)
		(end 86.877652 -403.299676)
		(width 0.14224)
		(layer "In11.Cu")
		(net "P5E_CPU1_P1_TX_BUF_DN<12>")
	)
	(segment
		(start 89.311226 -401.497038)
		(end 88.595962 -402.02739)
		(width 0.14224)
		(layer "In11.Cu")
		(net "P5E_CPU1_P1_TX_BUF_DN<12>")
	)
	(segment
		(start 88.595962 -402.02739)
		(end 88.593676 -402.026882)
		(width 0.14224)
		(layer "In11.Cu")
		(net "P5E_CPU1_P1_TX_BUF_DN<12>")
	)
	(segment
		(start 94.771464 -389.006588)
		(end 94.452948 -389.325104)
		(width 0.14224)
		(layer "In11.Cu")
		(net "P5E_CPU1_P1_TX_BUF_DN<12>")
	)
	(segment
		(start 86.375494 -404.348442)
		(end 86.375494 -406.71369)
		(width 0.14224)
		(layer "In11.Cu")
		(net "P5E_CPU1_P1_TX_BUF_DN<12>")
	)
	(segment
		(start 94.66072 -390.897364)
		(end 94.17812 -391.379964)
		(width 0.14224)
		(layer "In11.Cu")
		(net "P5E_CPU1_P1_TX_BUF_DN<12>")
	)
	(segment
		(start 86.375494 -406.71369)
		(end 86.084664 -407.00452)
		(width 0.14224)
		(layer "In11.Cu")
		(net "P5E_CPU1_P1_TX_BUF_DN<12>")
	)
	(segment
		(start 94.61627 -389.916162)
		(end 94.75089 -390.050782)
		(width 0.14224)
		(layer "In11.Cu")
		(net "P5E_CPU1_P1_TX_BUF_DN<12>")
	)
	(segment
		(start 94.71914 -388.774432)
		(end 94.771464 -388.826756)
		(width 0.14224)
		(layer "In11.Cu")
		(net "P5E_CPU1_P1_TX_BUF_DN<12>")
	)
	(segment
		(start 94.771464 -388.826756)
		(end 94.771464 -389.006588)
		(width 0.14224)
		(layer "In11.Cu")
		(net "P5E_CPU1_P1_TX_BUF_DN<12>")
	)
	(segment
		(start 94.452948 -389.325104)
		(end 94.452948 -389.521954)
		(width 0.14224)
		(layer "In11.Cu")
		(net "P5E_CPU1_P1_TX_BUF_DN<12>")
	)
	(segment
		(start 94.788228 -390.140698)
		(end 94.788228 -390.589262)
		(width 0.14224)
		(layer "In11.Cu")
		(net "P5E_CPU1_P1_TX_BUF_DN<12>")
	)
	(segment
		(start 94.048326 -391.693654)
		(end 94.048326 -395.44498)
		(width 0.14224)
		(layer "In11.Cu")
		(net "P5E_CPU1_P1_TX_BUF_DN<12>")
	)
	(segment
		(start 93.861128 -395.967966)
		(end 89.365328 -401.445222)
		(width 0.14224)
		(layer "In11.Cu")
		(net "P5E_CPU1_P1_TX_BUF_DN<12>")
	)
	(arc
		(start 94.788228 -390.589262)
		(mid 94.755084 -390.755977)
		(end 94.66072 -390.897364)
		(width 0.14224)
		(layer "In11.Cu")
		(net "P5E_CPU1_P1_TX_BUF_DN<12>")
	)
	(arc
		(start 89.365328 -401.445222)
		(mid 89.339864 -401.472787)
		(end 89.311226 -401.497038)
		(width 0.14224)
		(layer "In11.Cu")
		(net "P5E_CPU1_P1_TX_BUF_DN<12>")
	)
	(arc
		(start 94.75089 -390.050782)
		(mid 94.778509 -390.092022)
		(end 94.788228 -390.140698)
		(width 0.14224)
		(layer "In11.Cu")
		(net "P5E_CPU1_P1_TX_BUF_DN<12>")
	)
	(arc
		(start 94.452948 -389.521954)
		(mid 94.495387 -389.735311)
		(end 94.61627 -389.916162)
		(width 0.14224)
		(layer "In11.Cu")
		(net "P5E_CPU1_P1_TX_BUF_DN<12>")
	)
	(arc
		(start 86.388956 -404.177246)
		(mid 86.378802 -404.262575)
		(end 86.375494 -404.348442)
		(width 0.14224)
		(layer "In11.Cu")
		(net "P5E_CPU1_P1_TX_BUF_DN<12>")
	)
	(arc
		(start 86.636606 -403.551644)
		(mid 86.478631 -403.85093)
		(end 86.388956 -404.177246)
		(width 0.14224)
		(layer "In11.Cu")
		(net "P5E_CPU1_P1_TX_BUF_DN<12>")
	)
	(arc
		(start 94.17812 -391.379964)
		(mid 94.081984 -391.523887)
		(end 94.048326 -391.693654)
		(width 0.14224)
		(layer "In11.Cu")
		(net "P5E_CPU1_P1_TX_BUF_DN<12>")
	)
	(arc
		(start 94.048326 -395.44498)
		(mid 94.000133 -395.722733)
		(end 93.861128 -395.967966)
		(width 0.14224)
		(layer "In11.Cu")
		(net "P5E_CPU1_P1_TX_BUF_DN<12>")
	)
	(arc
		(start 86.877652 -403.299676)
		(mid 86.746476 -403.415467)
		(end 86.636606 -403.551644)
		(width 0.14224)
		(layer "In11.Cu")
		(net "P5E_CPU1_P1_TX_BUF_DN<12>")
	)
	(segment
		(start 92.99829 -388.774432)
		(end 93.51899 -388.774432)
		(width 0.127)
		(layer "F.Cu")
		(net "P5E_CPU1_P1_TX_BUF_DN<11>")
	)
	(segment
		(start 83.291934 -407.954734)
		(end 83.291934 -407.27503)
		(width 0.12954)
		(layer "B.Cu")
		(net "P5E_CPU1_P1_TX_BUF_DN<11>")
	)
	(segment
		(start 82.996024 -408.250644)
		(end 83.291934 -407.954734)
		(width 0.12954)
		(layer "B.Cu")
		(net "P5E_CPU1_P1_TX_BUF_DN<11>")
	)
	(segment
		(start 83.291934 -407.27503)
		(end 83.021424 -407.00452)
		(width 0.12954)
		(layer "B.Cu")
		(net "P5E_CPU1_P1_TX_BUF_DN<11>")
	)
	(segment
		(start 83.312254 -406.71369)
		(end 83.021424 -407.00452)
		(width 0.14224)
		(layer "In11.Cu")
		(net "P5E_CPU1_P1_TX_BUF_DN<11>")
	)
	(segment
		(start 92.84843 -391.717784)
		(end 92.84843 -395.196822)
		(width 0.14224)
		(layer "In11.Cu")
		(net "P5E_CPU1_P1_TX_BUF_DN<11>")
	)
	(segment
		(start 93.613478 -390.176512)
		(end 93.613478 -390.554718)
		(width 0.14224)
		(layer "In11.Cu")
		(net "P5E_CPU1_P1_TX_BUF_DN<11>")
	)
	(segment
		(start 93.462094 -390.920224)
		(end 92.978224 -391.404094)
		(width 0.14224)
		(layer "In11.Cu")
		(net "P5E_CPU1_P1_TX_BUF_DN<11>")
	)
	(segment
		(start 93.571314 -388.826756)
		(end 93.571314 -389.006588)
		(width 0.14224)
		(layer "In11.Cu")
		(net "P5E_CPU1_P1_TX_BUF_DN<11>")
	)
	(segment
		(start 87.012526 -401.219162)
		(end 85.918548 -401.913852)
		(width 0.14224)
		(layer "In11.Cu")
		(net "P5E_CPU1_P1_TX_BUF_DN<11>")
	)
	(segment
		(start 84.433156 -402.767038)
		(end 83.727544 -403.193504)
		(width 0.14224)
		(layer "In11.Cu")
		(net "P5E_CPU1_P1_TX_BUF_DN<11>")
	)
	(segment
		(start 93.252798 -389.325104)
		(end 93.252798 -389.544814)
		(width 0.14224)
		(layer "In11.Cu")
		(net "P5E_CPU1_P1_TX_BUF_DN<11>")
	)
	(segment
		(start 83.312254 -404.237698)
		(end 83.312254 -406.71369)
		(width 0.14224)
		(layer "In11.Cu")
		(net "P5E_CPU1_P1_TX_BUF_DN<11>")
	)
	(segment
		(start 87.926672 -400.548348)
		(end 87.012526 -401.219162)
		(width 0.14224)
		(layer "In11.Cu")
		(net "P5E_CPU1_P1_TX_BUF_DN<11>")
	)
	(segment
		(start 93.571314 -389.006588)
		(end 93.252798 -389.325104)
		(width 0.14224)
		(layer "In11.Cu")
		(net "P5E_CPU1_P1_TX_BUF_DN<11>")
	)
	(segment
		(start 93.51899 -388.774432)
		(end 93.571314 -388.826756)
		(width 0.14224)
		(layer "In11.Cu")
		(net "P5E_CPU1_P1_TX_BUF_DN<11>")
	)
	(segment
		(start 93.40723 -389.917432)
		(end 93.57614 -390.086342)
		(width 0.14224)
		(layer "In11.Cu")
		(net "P5E_CPU1_P1_TX_BUF_DN<11>")
	)
	(segment
		(start 92.544138 -395.931136)
		(end 87.926672 -400.548348)
		(width 0.14224)
		(layer "In11.Cu")
		(net "P5E_CPU1_P1_TX_BUF_DN<11>")
	)
	(arc
		(start 93.57614 -390.086342)
		(mid 93.603783 -390.127712)
		(end 93.613478 -390.176512)
		(width 0.14224)
		(layer "In11.Cu")
		(net "P5E_CPU1_P1_TX_BUF_DN<11>")
	)
	(arc
		(start 92.84843 -395.196822)
		(mid 92.769341 -395.594251)
		(end 92.544138 -395.931136)
		(width 0.14224)
		(layer "In11.Cu")
		(net "P5E_CPU1_P1_TX_BUF_DN<11>")
	)
	(arc
		(start 93.252798 -389.544814)
		(mid 93.292932 -389.746493)
		(end 93.40723 -389.917432)
		(width 0.14224)
		(layer "In11.Cu")
		(net "P5E_CPU1_P1_TX_BUF_DN<11>")
	)
	(arc
		(start 93.613478 -390.554718)
		(mid 93.574117 -390.752509)
		(end 93.462094 -390.920224)
		(width 0.14224)
		(layer "In11.Cu")
		(net "P5E_CPU1_P1_TX_BUF_DN<11>")
	)
	(arc
		(start 85.918548 -401.913852)
		(mid 85.171083 -402.332142)
		(end 84.433156 -402.767038)
		(width 0.14224)
		(layer "In11.Cu")
		(net "P5E_CPU1_P1_TX_BUF_DN<11>")
	)
	(arc
		(start 83.540346 -403.384766)
		(mid 83.370094 -403.796205)
		(end 83.312254 -404.237698)
		(width 0.14224)
		(layer "In11.Cu")
		(net "P5E_CPU1_P1_TX_BUF_DN<11>")
	)
	(arc
		(start 83.727544 -403.193504)
		(mid 83.621831 -403.277279)
		(end 83.540346 -403.384766)
		(width 0.14224)
		(layer "In11.Cu")
		(net "P5E_CPU1_P1_TX_BUF_DN<11>")
	)
	(arc
		(start 92.978224 -391.404094)
		(mid 92.882088 -391.548017)
		(end 92.84843 -391.717784)
		(width 0.14224)
		(layer "In11.Cu")
		(net "P5E_CPU1_P1_TX_BUF_DN<11>")
	)
	(segment
		(start 91.798394 -388.774432)
		(end 92.319094 -388.774432)
		(width 0.127)
		(layer "F.Cu")
		(net "P5E_CPU1_P1_TX_BUF_DN<10>")
	)
	(segment
		(start 80.228694 -407.27503)
		(end 79.958184 -407.00452)
		(width 0.12954)
		(layer "B.Cu")
		(net "P5E_CPU1_P1_TX_BUF_DN<10>")
	)
	(segment
		(start 80.228694 -407.954734)
		(end 80.228694 -407.27503)
		(width 0.12954)
		(layer "B.Cu")
		(net "P5E_CPU1_P1_TX_BUF_DN<10>")
	)
	(segment
		(start 79.932784 -408.250644)
		(end 80.228694 -407.954734)
		(width 0.12954)
		(layer "B.Cu")
		(net "P5E_CPU1_P1_TX_BUF_DN<10>")
	)
	(segment
		(start 81.48955 -402.86559)
		(end 80.682084 -403.26183)
		(width 0.14224)
		(layer "In11.Cu")
		(net "P5E_CPU1_P1_TX_BUF_DN<10>")
	)
	(segment
		(start 92.257118 -389.967216)
		(end 92.376244 -390.086342)
		(width 0.14224)
		(layer "In11.Cu")
		(net "P5E_CPU1_P1_TX_BUF_DN<10>")
	)
	(segment
		(start 92.371418 -389.006588)
		(end 92.052902 -389.325104)
		(width 0.14224)
		(layer "In11.Cu")
		(net "P5E_CPU1_P1_TX_BUF_DN<10>")
	)
	(segment
		(start 80.249014 -403.869906)
		(end 80.249014 -406.71369)
		(width 0.14224)
		(layer "In11.Cu")
		(net "P5E_CPU1_P1_TX_BUF_DN<10>")
	)
	(segment
		(start 91.582494 -391.813288)
		(end 91.582494 -395.463014)
		(width 0.14224)
		(layer "In11.Cu")
		(net "P5E_CPU1_P1_TX_BUF_DN<10>")
	)
	(segment
		(start 92.052902 -389.325104)
		(end 92.052902 -389.474202)
		(width 0.14224)
		(layer "In11.Cu")
		(net "P5E_CPU1_P1_TX_BUF_DN<10>")
	)
	(segment
		(start 92.413582 -390.176258)
		(end 92.413582 -390.57707)
		(width 0.14224)
		(layer "In11.Cu")
		(net "P5E_CPU1_P1_TX_BUF_DN<10>")
	)
	(segment
		(start 92.319094 -388.774432)
		(end 92.371418 -388.826756)
		(width 0.14224)
		(layer "In11.Cu")
		(net "P5E_CPU1_P1_TX_BUF_DN<10>")
	)
	(segment
		(start 81.48955 -402.865082)
		(end 81.48955 -402.86559)
		(width 0.14224)
		(layer "In11.Cu")
		(net "P5E_CPU1_P1_TX_BUF_DN<10>")
	)
	(segment
		(start 80.249014 -406.71369)
		(end 79.958184 -407.00452)
		(width 0.14224)
		(layer "In11.Cu")
		(net "P5E_CPU1_P1_TX_BUF_DN<10>")
	)
	(segment
		(start 92.371418 -388.826756)
		(end 92.371418 -389.006588)
		(width 0.14224)
		(layer "In11.Cu")
		(net "P5E_CPU1_P1_TX_BUF_DN<10>")
	)
	(segment
		(start 92.257118 -390.954768)
		(end 91.712288 -391.499598)
		(width 0.14224)
		(layer "In11.Cu")
		(net "P5E_CPU1_P1_TX_BUF_DN<10>")
	)
	(segment
		(start 85.992462 -400.65325)
		(end 81.48955 -402.865082)
		(width 0.14224)
		(layer "In11.Cu")
		(net "P5E_CPU1_P1_TX_BUF_DN<10>")
	)
	(segment
		(start 91.545156 -395.55293)
		(end 87.580216 -399.517616)
		(width 0.14224)
		(layer "In11.Cu")
		(net "P5E_CPU1_P1_TX_BUF_DN<10>")
	)
	(arc
		(start 80.36941 -403.516846)
		(mid 80.279813 -403.683357)
		(end 80.249014 -403.869906)
		(width 0.14224)
		(layer "In11.Cu")
		(net "P5E_CPU1_P1_TX_BUF_DN<10>")
	)
	(arc
		(start 92.413582 -390.57707)
		(mid 92.372906 -390.781471)
		(end 92.257118 -390.954768)
		(width 0.14224)
		(layer "In11.Cu")
		(net "P5E_CPU1_P1_TX_BUF_DN<10>")
	)
	(arc
		(start 91.712288 -391.499598)
		(mid 91.616152 -391.643521)
		(end 91.582494 -391.813288)
		(width 0.14224)
		(layer "In11.Cu")
		(net "P5E_CPU1_P1_TX_BUF_DN<10>")
	)
	(arc
		(start 87.580216 -399.517616)
		(mid 86.833118 -400.150837)
		(end 85.992462 -400.65325)
		(width 0.14224)
		(layer "In11.Cu")
		(net "P5E_CPU1_P1_TX_BUF_DN<10>")
	)
	(arc
		(start 92.376244 -390.086342)
		(mid 92.403863 -390.127582)
		(end 92.413582 -390.176258)
		(width 0.14224)
		(layer "In11.Cu")
		(net "P5E_CPU1_P1_TX_BUF_DN<10>")
	)
	(arc
		(start 92.052902 -389.474202)
		(mid 92.105975 -389.74102)
		(end 92.257118 -389.967216)
		(width 0.14224)
		(layer "In11.Cu")
		(net "P5E_CPU1_P1_TX_BUF_DN<10>")
	)
	(arc
		(start 91.582494 -395.463014)
		(mid 91.572792 -395.511698)
		(end 91.545156 -395.55293)
		(width 0.14224)
		(layer "In11.Cu")
		(net "P5E_CPU1_P1_TX_BUF_DN<10>")
	)
	(arc
		(start 80.682084 -403.26183)
		(mid 80.511177 -403.371478)
		(end 80.36941 -403.516846)
		(width 0.14224)
		(layer "In11.Cu")
		(net "P5E_CPU1_P1_TX_BUF_DN<10>")
	)
	(segment
		(start 79.798418 -388.774432)
		(end 80.319118 -388.774432)
		(width 0.127)
		(layer "F.Cu")
		(net "P5E_CPU1_P1_TX_BUF_DN<0>")
	)
	(segment
		(start 49.596294 -407.27503)
		(end 49.325784 -407.00452)
		(width 0.12954)
		(layer "B.Cu")
		(net "P5E_CPU1_P1_TX_BUF_DN<0>")
	)
	(segment
		(start 49.300384 -408.250644)
		(end 49.596294 -407.954734)
		(width 0.12954)
		(layer "B.Cu")
		(net "P5E_CPU1_P1_TX_BUF_DN<0>")
	)
	(segment
		(start 49.596294 -407.954734)
		(end 49.596294 -407.27503)
		(width 0.12954)
		(layer "B.Cu")
		(net "P5E_CPU1_P1_TX_BUF_DN<0>")
	)
	(segment
		(start 80.364584 -388.999984)
		(end 79.9973 -389.367268)
		(width 0.14224)
		(layer "In11.Cu")
		(net "P5E_CPU1_P1_TX_BUF_DN<0>")
	)
	(segment
		(start 54.040786 -400.922744)
		(end 52.855368 -401.262596)
		(width 0.14224)
		(layer "In11.Cu")
		(net "P5E_CPU1_P1_TX_BUF_DN<0>")
	)
	(segment
		(start 80.364584 -388.819898)
		(end 80.364584 -388.999984)
		(width 0.14224)
		(layer "In11.Cu")
		(net "P5E_CPU1_P1_TX_BUF_DN<0>")
	)
	(segment
		(start 51.974496 -401.664932)
		(end 50.459386 -402.651214)
		(width 0.14224)
		(layer "In11.Cu")
		(net "P5E_CPU1_P1_TX_BUF_DN<0>")
	)
	(segment
		(start 68.727828 -396.705836)
		(end 54.040532 -400.922236)
		(width 0.14224)
		(layer "In11.Cu")
		(net "P5E_CPU1_P1_TX_BUF_DN<0>")
	)
	(segment
		(start 77.304138 -393.685776)
		(end 75.950064 -394.236194)
		(width 0.14224)
		(layer "In11.Cu")
		(net "P5E_CPU1_P1_TX_BUF_DN<0>")
	)
	(segment
		(start 78.31582 -391.999978)
		(end 78.31582 -392.43254)
		(width 0.14224)
		(layer "In11.Cu")
		(net "P5E_CPU1_P1_TX_BUF_DN<0>")
	)
	(segment
		(start 71.724266 -395.487906)
		(end 68.727828 -396.705836)
		(width 0.14224)
		(layer "In11.Cu")
		(net "P5E_CPU1_P1_TX_BUF_DN<0>")
	)
	(segment
		(start 79.907384 -389.404606)
		(end 79.753714 -389.404606)
		(width 0.14224)
		(layer "In11.Cu")
		(net "P5E_CPU1_P1_TX_BUF_DN<0>")
	)
	(segment
		(start 49.616614 -404.205694)
		(end 49.616614 -406.71369)
		(width 0.14224)
		(layer "In11.Cu")
		(net "P5E_CPU1_P1_TX_BUF_DN<0>")
	)
	(segment
		(start 79.082646 -389.798814)
		(end 78.449932 -391.325862)
		(width 0.14224)
		(layer "In11.Cu")
		(net "P5E_CPU1_P1_TX_BUF_DN<0>")
	)
	(segment
		(start 78.135226 -392.868658)
		(end 77.346048 -393.657836)
		(width 0.14224)
		(layer "In11.Cu")
		(net "P5E_CPU1_P1_TX_BUF_DN<0>")
	)
	(segment
		(start 80.319118 -388.774432)
		(end 80.364584 -388.819898)
		(width 0.14224)
		(layer "In11.Cu")
		(net "P5E_CPU1_P1_TX_BUF_DN<0>")
	)
	(segment
		(start 54.040532 -400.922236)
		(end 54.040786 -400.922744)
		(width 0.14224)
		(layer "In11.Cu")
		(net "P5E_CPU1_P1_TX_BUF_DN<0>")
	)
	(segment
		(start 75.950064 -394.236194)
		(end 71.724266 -395.487906)
		(width 0.14224)
		(layer "In11.Cu")
		(net "P5E_CPU1_P1_TX_BUF_DN<0>")
	)
	(segment
		(start 79.281274 -389.600186)
		(end 79.082646 -389.798814)
		(width 0.14224)
		(layer "In11.Cu")
		(net "P5E_CPU1_P1_TX_BUF_DN<0>")
	)
	(segment
		(start 49.616614 -406.71369)
		(end 49.325784 -407.00452)
		(width 0.14224)
		(layer "In11.Cu")
		(net "P5E_CPU1_P1_TX_BUF_DN<0>")
	)
	(arc
		(start 50.459386 -402.651214)
		(mid 49.840851 -403.321571)
		(end 49.616614 -404.205694)
		(width 0.14224)
		(layer "In11.Cu")
		(net "P5E_CPU1_P1_TX_BUF_DN<0>")
	)
	(arc
		(start 52.855368 -401.262596)
		(mid 52.399932 -401.430923)
		(end 51.974496 -401.664932)
		(width 0.14224)
		(layer "In11.Cu")
		(net "P5E_CPU1_P1_TX_BUF_DN<0>")
	)
	(arc
		(start 79.753714 -389.404606)
		(mid 79.49806 -389.455441)
		(end 79.281274 -389.600186)
		(width 0.14224)
		(layer "In11.Cu")
		(net "P5E_CPU1_P1_TX_BUF_DN<0>")
	)
	(arc
		(start 77.346048 -393.657836)
		(mid 77.326482 -393.673886)
		(end 77.304138 -393.685776)
		(width 0.14224)
		(layer "In11.Cu")
		(net "P5E_CPU1_P1_TX_BUF_DN<0>")
	)
	(arc
		(start 78.449932 -391.325862)
		(mid 78.349699 -391.656318)
		(end 78.31582 -391.999978)
		(width 0.14224)
		(layer "In11.Cu")
		(net "P5E_CPU1_P1_TX_BUF_DN<0>")
	)
	(arc
		(start 79.9973 -389.367268)
		(mid 79.95606 -389.394887)
		(end 79.907384 -389.404606)
		(width 0.14224)
		(layer "In11.Cu")
		(net "P5E_CPU1_P1_TX_BUF_DN<0>")
	)
	(arc
		(start 78.31582 -392.43254)
		(mid 78.268891 -392.66856)
		(end 78.135226 -392.868658)
		(width 0.14224)
		(layer "In11.Cu")
		(net "P5E_CPU1_P1_TX_BUF_DN<0>")
	)
	(segment
		(start 77.488034 -409.079954)
		(end 77.488034 -409.759658)
		(width 0.12954)
		(layer "B.Cu")
		(net "P5E_CPU1_P1_TX_BUF_C_DP<9>")
	)
	(segment
		(start 77.488034 -409.759658)
		(end 77.758544 -410.030168)
		(width 0.12954)
		(layer "B.Cu")
		(net "P5E_CPU1_P1_TX_BUF_C_DP<9>")
	)
	(segment
		(start 77.783944 -408.784044)
		(end 77.488034 -409.079954)
		(width 0.12954)
		(layer "B.Cu")
		(net "P5E_CPU1_P1_TX_BUF_C_DP<9>")
	)
	(segment
		(start 77.604874 -411.75813)
		(end 77.604874 -411.33141)
		(width 0.14224)
		(layer "In6.Cu")
		(net "P5E_CPU1_P1_TX_BUF_C_DP<9>")
	)
	(segment
		(start 77.467714 -411.89529)
		(end 77.604874 -411.75813)
		(width 0.14224)
		(layer "In6.Cu")
		(net "P5E_CPU1_P1_TX_BUF_C_DP<9>")
	)
	(segment
		(start 77.56525 -413.836358)
		(end 77.434948 -413.692594)
		(width 0.14224)
		(layer "In6.Cu")
		(net "P5E_CPU1_P1_TX_BUF_C_DP<9>")
	)
	(segment
		(start 77.132434 -427.54296)
		(end 76.970128 -427.380654)
		(width 0.14224)
		(layer "In6.Cu")
		(net "P5E_CPU1_P1_TX_BUF_C_DP<9>")
	)
	(segment
		(start 77.467714 -411.19425)
		(end 77.467714 -410.320998)
		(width 0.14224)
		(layer "In6.Cu")
		(net "P5E_CPU1_P1_TX_BUF_C_DP<9>")
	)
	(segment
		(start 77.650086 -427.41596)
		(end 77.523086 -427.54296)
		(width 0.14224)
		(layer "In6.Cu")
		(net "P5E_CPU1_P1_TX_BUF_C_DP<9>")
	)
	(segment
		(start 77.467714 -413.022288)
		(end 77.467714 -411.89529)
		(width 0.14224)
		(layer "In6.Cu")
		(net "P5E_CPU1_P1_TX_BUF_C_DP<9>")
	)
	(segment
		(start 77.650086 -427.089824)
		(end 77.650086 -427.41596)
		(width 0.14224)
		(layer "In6.Cu")
		(net "P5E_CPU1_P1_TX_BUF_C_DP<9>")
	)
	(segment
		(start 77.454252 -416.089338)
		(end 77.32395 -415.945574)
		(width 0.14224)
		(layer "In6.Cu")
		(net "P5E_CPU1_P1_TX_BUF_C_DP<9>")
	)
	(segment
		(start 76.970128 -423.15257)
		(end 77.289406 -416.646106)
		(width 0.14224)
		(layer "In6.Cu")
		(net "P5E_CPU1_P1_TX_BUF_C_DP<9>")
	)
	(segment
		(start 77.289406 -416.646106)
		(end 77.433424 -416.515804)
		(width 0.14224)
		(layer "In6.Cu")
		(net "P5E_CPU1_P1_TX_BUF_C_DP<9>")
	)
	(segment
		(start 76.970128 -427.380654)
		(end 76.970128 -423.15257)
		(width 0.14224)
		(layer "In6.Cu")
		(net "P5E_CPU1_P1_TX_BUF_C_DP<9>")
	)
	(segment
		(start 77.488796 -415.389314)
		(end 77.509624 -414.962848)
		(width 0.14224)
		(layer "In6.Cu")
		(net "P5E_CPU1_P1_TX_BUF_C_DP<9>")
	)
	(segment
		(start 77.379322 -414.819084)
		(end 77.40015 -414.393126)
		(width 0.14224)
		(layer "In6.Cu")
		(net "P5E_CPU1_P1_TX_BUF_C_DP<9>")
	)
	(segment
		(start 77.523086 -427.54296)
		(end 77.132434 -427.54296)
		(width 0.14224)
		(layer "In6.Cu")
		(net "P5E_CPU1_P1_TX_BUF_C_DP<9>")
	)
	(segment
		(start 77.433424 -416.515804)
		(end 77.454252 -416.089338)
		(width 0.14224)
		(layer "In6.Cu")
		(net "P5E_CPU1_P1_TX_BUF_C_DP<9>")
	)
	(segment
		(start 77.32395 -415.945574)
		(end 77.344778 -415.519616)
		(width 0.14224)
		(layer "In6.Cu")
		(net "P5E_CPU1_P1_TX_BUF_C_DP<9>")
	)
	(segment
		(start 77.509624 -414.962848)
		(end 77.379322 -414.819084)
		(width 0.14224)
		(layer "In6.Cu")
		(net "P5E_CPU1_P1_TX_BUF_C_DP<9>")
	)
	(segment
		(start 77.344778 -415.519616)
		(end 77.488796 -415.389314)
		(width 0.14224)
		(layer "In6.Cu")
		(net "P5E_CPU1_P1_TX_BUF_C_DP<9>")
	)
	(segment
		(start 77.467714 -410.320998)
		(end 77.758544 -410.030168)
		(width 0.14224)
		(layer "In6.Cu")
		(net "P5E_CPU1_P1_TX_BUF_C_DP<9>")
	)
	(segment
		(start 77.544168 -414.262824)
		(end 77.56525 -413.836358)
		(width 0.14224)
		(layer "In6.Cu")
		(net "P5E_CPU1_P1_TX_BUF_C_DP<9>")
	)
	(segment
		(start 77.604874 -411.33141)
		(end 77.467714 -411.19425)
		(width 0.14224)
		(layer "In6.Cu")
		(net "P5E_CPU1_P1_TX_BUF_C_DP<9>")
	)
	(segment
		(start 77.40015 -414.393126)
		(end 77.544168 -414.262824)
		(width 0.14224)
		(layer "In6.Cu")
		(net "P5E_CPU1_P1_TX_BUF_C_DP<9>")
	)
	(segment
		(start 77.434948 -413.692594)
		(end 77.467714 -413.022288)
		(width 0.14224)
		(layer "In6.Cu")
		(net "P5E_CPU1_P1_TX_BUF_C_DP<9>")
	)
	(segment
		(start 74.424794 -409.079954)
		(end 74.424794 -409.759658)
		(width 0.12954)
		(layer "B.Cu")
		(net "P5E_CPU1_P1_TX_BUF_C_DP<8>")
	)
	(segment
		(start 74.720704 -408.784044)
		(end 74.424794 -409.079954)
		(width 0.12954)
		(layer "B.Cu")
		(net "P5E_CPU1_P1_TX_BUF_C_DP<8>")
	)
	(segment
		(start 74.424794 -409.759658)
		(end 74.695304 -410.030168)
		(width 0.12954)
		(layer "B.Cu")
		(net "P5E_CPU1_P1_TX_BUF_C_DP<8>")
	)
	(segment
		(start 74.541634 -411.781498)
		(end 74.541634 -411.354778)
		(width 0.14224)
		(layer "In6.Cu")
		(net "P5E_CPU1_P1_TX_BUF_C_DP<8>")
	)
	(segment
		(start 74.73569 -417.16706)
		(end 74.591672 -417.036758)
		(width 0.14224)
		(layer "In6.Cu")
		(net "P5E_CPU1_P1_TX_BUF_C_DP<8>")
	)
	(segment
		(start 74.541634 -411.354778)
		(end 74.404474 -411.217618)
		(width 0.14224)
		(layer "In6.Cu")
		(net "P5E_CPU1_P1_TX_BUF_C_DP<8>")
	)
	(segment
		(start 74.404474 -410.320998)
		(end 74.695304 -410.030168)
		(width 0.14224)
		(layer "In6.Cu")
		(net "P5E_CPU1_P1_TX_BUF_C_DP<8>")
	)
	(segment
		(start 74.701146 -416.467036)
		(end 74.680318 -416.04057)
		(width 0.14224)
		(layer "In6.Cu")
		(net "P5E_CPU1_P1_TX_BUF_C_DP<8>")
	)
	(segment
		(start 75.203812 -426.549058)
		(end 74.685398 -426.030644)
		(width 0.14224)
		(layer "In6.Cu")
		(net "P5E_CPU1_P1_TX_BUF_C_DP<8>")
	)
	(segment
		(start 74.756518 -417.593526)
		(end 74.73569 -417.16706)
		(width 0.14224)
		(layer "In6.Cu")
		(net "P5E_CPU1_P1_TX_BUF_C_DP<8>")
	)
	(segment
		(start 74.626216 -417.73729)
		(end 74.756518 -417.593526)
		(width 0.14224)
		(layer "In6.Cu")
		(net "P5E_CPU1_P1_TX_BUF_C_DP<8>")
	)
	(segment
		(start 74.645774 -415.340546)
		(end 74.624946 -414.91408)
		(width 0.14224)
		(layer "In6.Cu")
		(net "P5E_CPU1_P1_TX_BUF_C_DP<8>")
	)
	(segment
		(start 74.685398 -418.944044)
		(end 74.626216 -417.73729)
		(width 0.14224)
		(layer "In6.Cu")
		(net "P5E_CPU1_P1_TX_BUF_C_DP<8>")
	)
	(segment
		(start 74.570844 -416.6108)
		(end 74.701146 -416.467036)
		(width 0.14224)
		(layer "In6.Cu")
		(net "P5E_CPU1_P1_TX_BUF_C_DP<8>")
	)
	(segment
		(start 74.591672 -417.036758)
		(end 74.570844 -416.6108)
		(width 0.14224)
		(layer "In6.Cu")
		(net "P5E_CPU1_P1_TX_BUF_C_DP<8>")
	)
	(segment
		(start 74.404474 -411.918658)
		(end 74.541634 -411.781498)
		(width 0.14224)
		(layer "In6.Cu")
		(net "P5E_CPU1_P1_TX_BUF_C_DP<8>")
	)
	(segment
		(start 74.680318 -416.04057)
		(end 74.5363 -415.910268)
		(width 0.14224)
		(layer "In6.Cu")
		(net "P5E_CPU1_P1_TX_BUF_C_DP<8>")
	)
	(segment
		(start 74.5363 -415.910268)
		(end 74.515472 -415.48431)
		(width 0.14224)
		(layer "In6.Cu")
		(net "P5E_CPU1_P1_TX_BUF_C_DP<8>")
	)
	(segment
		(start 74.425556 -413.657288)
		(end 74.404728 -413.23133)
		(width 0.14224)
		(layer "In6.Cu")
		(net "P5E_CPU1_P1_TX_BUF_C_DP<8>")
	)
	(segment
		(start 74.4601 -414.35782)
		(end 74.590402 -414.214056)
		(width 0.14224)
		(layer "In6.Cu")
		(net "P5E_CPU1_P1_TX_BUF_C_DP<8>")
	)
	(segment
		(start 74.685398 -426.030644)
		(end 74.685398 -418.944044)
		(width 0.14224)
		(layer "In6.Cu")
		(net "P5E_CPU1_P1_TX_BUF_C_DP<8>")
	)
	(segment
		(start 74.569574 -413.78759)
		(end 74.425556 -413.657288)
		(width 0.14224)
		(layer "In6.Cu")
		(net "P5E_CPU1_P1_TX_BUF_C_DP<8>")
	)
	(segment
		(start 74.590402 -414.214056)
		(end 74.569574 -413.78759)
		(width 0.14224)
		(layer "In6.Cu")
		(net "P5E_CPU1_P1_TX_BUF_C_DP<8>")
	)
	(segment
		(start 75.65009 -426.42155)
		(end 75.522582 -426.549058)
		(width 0.14224)
		(layer "In6.Cu")
		(net "P5E_CPU1_P1_TX_BUF_C_DP<8>")
	)
	(segment
		(start 75.522582 -426.549058)
		(end 75.203812 -426.549058)
		(width 0.14224)
		(layer "In6.Cu")
		(net "P5E_CPU1_P1_TX_BUF_C_DP<8>")
	)
	(segment
		(start 74.480928 -414.783778)
		(end 74.4601 -414.35782)
		(width 0.14224)
		(layer "In6.Cu")
		(net "P5E_CPU1_P1_TX_BUF_C_DP<8>")
	)
	(segment
		(start 74.404728 -413.23133)
		(end 74.404474 -413.23133)
		(width 0.14224)
		(layer "In6.Cu")
		(net "P5E_CPU1_P1_TX_BUF_C_DP<8>")
	)
	(segment
		(start 75.65009 -426.089826)
		(end 75.65009 -426.42155)
		(width 0.14224)
		(layer "In6.Cu")
		(net "P5E_CPU1_P1_TX_BUF_C_DP<8>")
	)
	(segment
		(start 74.404474 -411.217618)
		(end 74.404474 -410.320998)
		(width 0.14224)
		(layer "In6.Cu")
		(net "P5E_CPU1_P1_TX_BUF_C_DP<8>")
	)
	(segment
		(start 74.515472 -415.48431)
		(end 74.645774 -415.340546)
		(width 0.14224)
		(layer "In6.Cu")
		(net "P5E_CPU1_P1_TX_BUF_C_DP<8>")
	)
	(segment
		(start 74.404474 -413.23133)
		(end 74.404474 -411.918658)
		(width 0.14224)
		(layer "In6.Cu")
		(net "P5E_CPU1_P1_TX_BUF_C_DP<8>")
	)
	(segment
		(start 74.624946 -414.91408)
		(end 74.480928 -414.783778)
		(width 0.14224)
		(layer "In6.Cu")
		(net "P5E_CPU1_P1_TX_BUF_C_DP<8>")
	)
	(segment
		(start 71.361554 -409.759658)
		(end 71.632064 -410.030168)
		(width 0.12954)
		(layer "B.Cu")
		(net "P5E_CPU1_P1_TX_BUF_C_DP<7>")
	)
	(segment
		(start 71.657464 -408.784044)
		(end 71.361554 -409.079954)
		(width 0.12954)
		(layer "B.Cu")
		(net "P5E_CPU1_P1_TX_BUF_C_DP<7>")
	)
	(segment
		(start 71.361554 -409.079954)
		(end 71.361554 -409.759658)
		(width 0.12954)
		(layer "B.Cu")
		(net "P5E_CPU1_P1_TX_BUF_C_DP<7>")
	)
	(segment
		(start 71.341234 -410.320998)
		(end 71.341234 -411.292548)
		(width 0.14224)
		(layer "In6.Cu")
		(net "P5E_CPU1_P1_TX_BUF_C_DP<7>")
	)
	(segment
		(start 71.685404 -415.165794)
		(end 71.727314 -415.590736)
		(width 0.14224)
		(layer "In6.Cu")
		(net "P5E_CPU1_P1_TX_BUF_C_DP<7>")
	)
	(segment
		(start 72.522588 -427.548802)
		(end 72.649842 -427.421548)
		(width 0.14224)
		(layer "In6.Cu")
		(net "P5E_CPU1_P1_TX_BUF_C_DP<7>")
	)
	(segment
		(start 71.478394 -411.429708)
		(end 71.478394 -411.856428)
		(width 0.14224)
		(layer "In6.Cu")
		(net "P5E_CPU1_P1_TX_BUF_C_DP<7>")
	)
	(segment
		(start 71.341234 -411.993588)
		(end 71.341234 -413.07258)
		(width 0.14224)
		(layer "In6.Cu")
		(net "P5E_CPU1_P1_TX_BUF_C_DP<7>")
	)
	(segment
		(start 72.138032 -427.548802)
		(end 72.522588 -427.548802)
		(width 0.14224)
		(layer "In6.Cu")
		(net "P5E_CPU1_P1_TX_BUF_C_DP<7>")
	)
	(segment
		(start 71.604124 -415.74085)
		(end 71.969884 -419.457124)
		(width 0.14224)
		(layer "In6.Cu")
		(net "P5E_CPU1_P1_TX_BUF_C_DP<7>")
	)
	(segment
		(start 71.341234 -411.292548)
		(end 71.478394 -411.429708)
		(width 0.14224)
		(layer "In6.Cu")
		(net "P5E_CPU1_P1_TX_BUF_C_DP<7>")
	)
	(segment
		(start 71.478394 -411.856428)
		(end 71.341234 -411.993588)
		(width 0.14224)
		(layer "In6.Cu")
		(net "P5E_CPU1_P1_TX_BUF_C_DP<7>")
	)
	(segment
		(start 71.572882 -414.023048)
		(end 71.614538 -414.44799)
		(width 0.14224)
		(layer "In6.Cu")
		(net "P5E_CPU1_P1_TX_BUF_C_DP<7>")
	)
	(segment
		(start 71.969884 -419.457124)
		(end 71.969884 -427.380654)
		(width 0.14224)
		(layer "In6.Cu")
		(net "P5E_CPU1_P1_TX_BUF_C_DP<7>")
	)
	(segment
		(start 71.969884 -427.380654)
		(end 72.138032 -427.548802)
		(width 0.14224)
		(layer "In6.Cu")
		(net "P5E_CPU1_P1_TX_BUF_C_DP<7>")
	)
	(segment
		(start 71.632064 -410.030168)
		(end 71.341234 -410.320998)
		(width 0.14224)
		(layer "In6.Cu")
		(net "P5E_CPU1_P1_TX_BUF_C_DP<7>")
	)
	(segment
		(start 71.491602 -414.598104)
		(end 71.53529 -415.042858)
		(width 0.14224)
		(layer "In6.Cu")
		(net "P5E_CPU1_P1_TX_BUF_C_DP<7>")
	)
	(segment
		(start 71.422514 -413.900112)
		(end 71.572882 -414.023048)
		(width 0.14224)
		(layer "In6.Cu")
		(net "P5E_CPU1_P1_TX_BUF_C_DP<7>")
	)
	(segment
		(start 71.614538 -414.44799)
		(end 71.491602 -414.598104)
		(width 0.14224)
		(layer "In6.Cu")
		(net "P5E_CPU1_P1_TX_BUF_C_DP<7>")
	)
	(segment
		(start 71.53529 -415.042858)
		(end 71.685404 -415.165794)
		(width 0.14224)
		(layer "In6.Cu")
		(net "P5E_CPU1_P1_TX_BUF_C_DP<7>")
	)
	(segment
		(start 71.727314 -415.590736)
		(end 71.604124 -415.74085)
		(width 0.14224)
		(layer "In6.Cu")
		(net "P5E_CPU1_P1_TX_BUF_C_DP<7>")
	)
	(segment
		(start 71.341234 -413.07258)
		(end 71.422514 -413.900112)
		(width 0.14224)
		(layer "In6.Cu")
		(net "P5E_CPU1_P1_TX_BUF_C_DP<7>")
	)
	(segment
		(start 72.649842 -427.421548)
		(end 72.649842 -427.089824)
		(width 0.14224)
		(layer "In6.Cu")
		(net "P5E_CPU1_P1_TX_BUF_C_DP<7>")
	)
	(segment
		(start 68.298314 -409.759658)
		(end 68.568824 -410.030168)
		(width 0.12954)
		(layer "B.Cu")
		(net "P5E_CPU1_P1_TX_BUF_C_DP<6>")
	)
	(segment
		(start 68.594224 -408.784044)
		(end 68.298314 -409.079954)
		(width 0.12954)
		(layer "B.Cu")
		(net "P5E_CPU1_P1_TX_BUF_C_DP<6>")
	)
	(segment
		(start 68.298314 -409.079954)
		(end 68.298314 -409.759658)
		(width 0.12954)
		(layer "B.Cu")
		(net "P5E_CPU1_P1_TX_BUF_C_DP<6>")
	)
	(segment
		(start 69.969888 -426.315378)
		(end 70.232778 -426.578268)
		(width 0.14224)
		(layer "In6.Cu")
		(net "P5E_CPU1_P1_TX_BUF_C_DP<6>")
	)
	(segment
		(start 68.77558 -414.285938)
		(end 68.91909 -414.687512)
		(width 0.14224)
		(layer "In6.Cu")
		(net "P5E_CPU1_P1_TX_BUF_C_DP<6>")
	)
	(segment
		(start 68.277994 -410.320998)
		(end 68.277994 -411.08884)
		(width 0.14224)
		(layer "In6.Cu")
		(net "P5E_CPU1_P1_TX_BUF_C_DP<6>")
	)
	(segment
		(start 69.969888 -417.623752)
		(end 69.969888 -426.315378)
		(width 0.14224)
		(layer "In6.Cu")
		(net "P5E_CPU1_P1_TX_BUF_C_DP<6>")
	)
	(segment
		(start 68.415154 -411.226)
		(end 68.415154 -411.65272)
		(width 0.14224)
		(layer "In6.Cu")
		(net "P5E_CPU1_P1_TX_BUF_C_DP<6>")
	)
	(segment
		(start 68.858384 -414.110678)
		(end 68.77558 -414.285938)
		(width 0.14224)
		(layer "In6.Cu")
		(net "P5E_CPU1_P1_TX_BUF_C_DP<6>")
	)
	(segment
		(start 68.539106 -413.625792)
		(end 68.71462 -413.708596)
		(width 0.14224)
		(layer "In6.Cu")
		(net "P5E_CPU1_P1_TX_BUF_C_DP<6>")
	)
	(segment
		(start 68.91909 -414.687512)
		(end 69.094858 -414.77057)
		(width 0.14224)
		(layer "In6.Cu")
		(net "P5E_CPU1_P1_TX_BUF_C_DP<6>")
	)
	(segment
		(start 69.094858 -414.77057)
		(end 69.238622 -415.172652)
		(width 0.14224)
		(layer "In6.Cu")
		(net "P5E_CPU1_P1_TX_BUF_C_DP<6>")
	)
	(segment
		(start 69.535548 -416.409886)
		(end 69.969888 -417.623752)
		(width 0.14224)
		(layer "In6.Cu")
		(net "P5E_CPU1_P1_TX_BUF_C_DP<6>")
	)
	(segment
		(start 68.277994 -411.08884)
		(end 68.415154 -411.226)
		(width 0.14224)
		(layer "In6.Cu")
		(net "P5E_CPU1_P1_TX_BUF_C_DP<6>")
	)
	(segment
		(start 69.618606 -416.234626)
		(end 69.535548 -416.409886)
		(width 0.14224)
		(layer "In6.Cu")
		(net "P5E_CPU1_P1_TX_BUF_C_DP<6>")
	)
	(segment
		(start 69.299074 -415.749486)
		(end 69.474842 -415.832544)
		(width 0.14224)
		(layer "In6.Cu")
		(net "P5E_CPU1_P1_TX_BUF_C_DP<6>")
	)
	(segment
		(start 70.493128 -426.578268)
		(end 70.649846 -426.42155)
		(width 0.14224)
		(layer "In6.Cu")
		(net "P5E_CPU1_P1_TX_BUF_C_DP<6>")
	)
	(segment
		(start 68.71462 -413.708596)
		(end 68.858384 -414.110678)
		(width 0.14224)
		(layer "In6.Cu")
		(net "P5E_CPU1_P1_TX_BUF_C_DP<6>")
	)
	(segment
		(start 68.568824 -410.030168)
		(end 68.277994 -410.320998)
		(width 0.14224)
		(layer "In6.Cu")
		(net "P5E_CPU1_P1_TX_BUF_C_DP<6>")
	)
	(segment
		(start 68.277994 -411.78988)
		(end 68.277994 -412.895796)
		(width 0.14224)
		(layer "In6.Cu")
		(net "P5E_CPU1_P1_TX_BUF_C_DP<6>")
	)
	(segment
		(start 69.155564 -415.347912)
		(end 69.299074 -415.749486)
		(width 0.14224)
		(layer "In6.Cu")
		(net "P5E_CPU1_P1_TX_BUF_C_DP<6>")
	)
	(segment
		(start 68.415154 -411.65272)
		(end 68.277994 -411.78988)
		(width 0.14224)
		(layer "In6.Cu")
		(net "P5E_CPU1_P1_TX_BUF_C_DP<6>")
	)
	(segment
		(start 70.649846 -426.42155)
		(end 70.649846 -426.089826)
		(width 0.14224)
		(layer "In6.Cu")
		(net "P5E_CPU1_P1_TX_BUF_C_DP<6>")
	)
	(segment
		(start 69.238622 -415.172652)
		(end 69.155564 -415.347912)
		(width 0.14224)
		(layer "In6.Cu")
		(net "P5E_CPU1_P1_TX_BUF_C_DP<6>")
	)
	(segment
		(start 69.474842 -415.832544)
		(end 69.618606 -416.234626)
		(width 0.14224)
		(layer "In6.Cu")
		(net "P5E_CPU1_P1_TX_BUF_C_DP<6>")
	)
	(segment
		(start 70.232778 -426.578268)
		(end 70.493128 -426.578268)
		(width 0.14224)
		(layer "In6.Cu")
		(net "P5E_CPU1_P1_TX_BUF_C_DP<6>")
	)
	(segment
		(start 68.277994 -412.895796)
		(end 68.539106 -413.625792)
		(width 0.14224)
		(layer "In6.Cu")
		(net "P5E_CPU1_P1_TX_BUF_C_DP<6>")
	)
	(segment
		(start 65.235074 -409.079954)
		(end 65.235074 -409.759658)
		(width 0.12954)
		(layer "B.Cu")
		(net "P5E_CPU1_P1_TX_BUF_C_DP<5>")
	)
	(segment
		(start 65.235074 -409.759658)
		(end 65.505584 -410.030168)
		(width 0.12954)
		(layer "B.Cu")
		(net "P5E_CPU1_P1_TX_BUF_C_DP<5>")
	)
	(segment
		(start 65.530984 -408.784044)
		(end 65.235074 -409.079954)
		(width 0.12954)
		(layer "B.Cu")
		(net "P5E_CPU1_P1_TX_BUF_C_DP<5>")
	)
	(segment
		(start 67.26936 -416.453574)
		(end 67.969892 -417.689792)
		(width 0.14224)
		(layer "In6.Cu")
		(net "P5E_CPU1_P1_TX_BUF_C_DP<5>")
	)
	(segment
		(start 66.157348 -414.490916)
		(end 66.36766 -414.86201)
		(width 0.14224)
		(layer "In6.Cu")
		(net "P5E_CPU1_P1_TX_BUF_C_DP<5>")
	)
	(segment
		(start 65.214754 -410.994098)
		(end 65.351914 -411.131258)
		(width 0.14224)
		(layer "In6.Cu")
		(net "P5E_CPU1_P1_TX_BUF_C_DP<5>")
	)
	(segment
		(start 68.52285 -427.54296)
		(end 68.64985 -427.41596)
		(width 0.14224)
		(layer "In6.Cu")
		(net "P5E_CPU1_P1_TX_BUF_C_DP<5>")
	)
	(segment
		(start 66.554858 -414.913826)
		(end 66.76517 -415.285174)
		(width 0.14224)
		(layer "In6.Cu")
		(net "P5E_CPU1_P1_TX_BUF_C_DP<5>")
	)
	(segment
		(start 66.923666 -415.843212)
		(end 67.110864 -415.895028)
		(width 0.14224)
		(layer "In6.Cu")
		(net "P5E_CPU1_P1_TX_BUF_C_DP<5>")
	)
	(segment
		(start 65.214754 -410.320998)
		(end 65.214754 -410.994098)
		(width 0.14224)
		(layer "In6.Cu")
		(net "P5E_CPU1_P1_TX_BUF_C_DP<5>")
	)
	(segment
		(start 65.214754 -412.82747)
		(end 65.811654 -413.880808)
		(width 0.14224)
		(layer "In6.Cu")
		(net "P5E_CPU1_P1_TX_BUF_C_DP<5>")
	)
	(segment
		(start 66.76517 -415.285174)
		(end 66.713354 -415.472118)
		(width 0.14224)
		(layer "In6.Cu")
		(net "P5E_CPU1_P1_TX_BUF_C_DP<5>")
	)
	(segment
		(start 65.351914 -411.131258)
		(end 65.351914 -411.557978)
		(width 0.14224)
		(layer "In6.Cu")
		(net "P5E_CPU1_P1_TX_BUF_C_DP<5>")
	)
	(segment
		(start 66.713354 -415.472118)
		(end 66.923666 -415.843212)
		(width 0.14224)
		(layer "In6.Cu")
		(net "P5E_CPU1_P1_TX_BUF_C_DP<5>")
	)
	(segment
		(start 67.321176 -416.266376)
		(end 67.26936 -416.453574)
		(width 0.14224)
		(layer "In6.Cu")
		(net "P5E_CPU1_P1_TX_BUF_C_DP<5>")
	)
	(segment
		(start 65.505584 -410.030168)
		(end 65.214754 -410.320998)
		(width 0.14224)
		(layer "In6.Cu")
		(net "P5E_CPU1_P1_TX_BUF_C_DP<5>")
	)
	(segment
		(start 67.110864 -415.895028)
		(end 67.321176 -416.266376)
		(width 0.14224)
		(layer "In6.Cu")
		(net "P5E_CPU1_P1_TX_BUF_C_DP<5>")
	)
	(segment
		(start 65.214754 -411.695138)
		(end 65.214754 -412.82747)
		(width 0.14224)
		(layer "In6.Cu")
		(net "P5E_CPU1_P1_TX_BUF_C_DP<5>")
	)
	(segment
		(start 67.969892 -427.380654)
		(end 68.132198 -427.54296)
		(width 0.14224)
		(layer "In6.Cu")
		(net "P5E_CPU1_P1_TX_BUF_C_DP<5>")
	)
	(segment
		(start 68.132198 -427.54296)
		(end 68.52285 -427.54296)
		(width 0.14224)
		(layer "In6.Cu")
		(net "P5E_CPU1_P1_TX_BUF_C_DP<5>")
	)
	(segment
		(start 67.969892 -417.689792)
		(end 67.969892 -427.380654)
		(width 0.14224)
		(layer "In6.Cu")
		(net "P5E_CPU1_P1_TX_BUF_C_DP<5>")
	)
	(segment
		(start 66.209164 -414.303972)
		(end 66.157348 -414.490916)
		(width 0.14224)
		(layer "In6.Cu")
		(net "P5E_CPU1_P1_TX_BUF_C_DP<5>")
	)
	(segment
		(start 66.36766 -414.86201)
		(end 66.554858 -414.913826)
		(width 0.14224)
		(layer "In6.Cu")
		(net "P5E_CPU1_P1_TX_BUF_C_DP<5>")
	)
	(segment
		(start 65.351914 -411.557978)
		(end 65.214754 -411.695138)
		(width 0.14224)
		(layer "In6.Cu")
		(net "P5E_CPU1_P1_TX_BUF_C_DP<5>")
	)
	(segment
		(start 65.998852 -413.932624)
		(end 66.209164 -414.303972)
		(width 0.14224)
		(layer "In6.Cu")
		(net "P5E_CPU1_P1_TX_BUF_C_DP<5>")
	)
	(segment
		(start 68.64985 -427.41596)
		(end 68.64985 -427.089824)
		(width 0.14224)
		(layer "In6.Cu")
		(net "P5E_CPU1_P1_TX_BUF_C_DP<5>")
	)
	(segment
		(start 65.811654 -413.880808)
		(end 65.998852 -413.932624)
		(width 0.14224)
		(layer "In6.Cu")
		(net "P5E_CPU1_P1_TX_BUF_C_DP<5>")
	)
	(segment
		(start 62.467744 -408.784044)
		(end 62.171834 -409.079954)
		(width 0.12954)
		(layer "B.Cu")
		(net "P5E_CPU1_P1_TX_BUF_C_DP<4>")
	)
	(segment
		(start 62.171834 -409.079954)
		(end 62.171834 -409.759658)
		(width 0.12954)
		(layer "B.Cu")
		(net "P5E_CPU1_P1_TX_BUF_C_DP<4>")
	)
	(segment
		(start 62.171834 -409.759658)
		(end 62.442344 -410.030168)
		(width 0.12954)
		(layer "B.Cu")
		(net "P5E_CPU1_P1_TX_BUF_C_DP<4>")
	)
	(segment
		(start 64.586612 -415.726626)
		(end 64.858646 -416.05581)
		(width 0.14224)
		(layer "In6.Cu")
		(net "P5E_CPU1_P1_TX_BUF_C_DP<4>")
	)
	(segment
		(start 64.121792 -415.379408)
		(end 64.393318 -415.708338)
		(width 0.14224)
		(layer "In6.Cu")
		(net "P5E_CPU1_P1_TX_BUF_C_DP<4>")
	)
	(segment
		(start 62.442344 -410.030168)
		(end 62.151514 -410.320998)
		(width 0.14224)
		(layer "In6.Cu")
		(net "P5E_CPU1_P1_TX_BUF_C_DP<4>")
	)
	(segment
		(start 63.149988 -413.987488)
		(end 63.421768 -414.316672)
		(width 0.14224)
		(layer "In6.Cu")
		(net "P5E_CPU1_P1_TX_BUF_C_DP<4>")
	)
	(segment
		(start 65.969896 -426.315378)
		(end 66.203576 -426.549058)
		(width 0.14224)
		(layer "In6.Cu")
		(net "P5E_CPU1_P1_TX_BUF_C_DP<4>")
	)
	(segment
		(start 63.421768 -414.316672)
		(end 63.40348 -414.509712)
		(width 0.14224)
		(layer "In6.Cu")
		(net "P5E_CPU1_P1_TX_BUF_C_DP<4>")
	)
	(segment
		(start 62.956694 -413.968946)
		(end 63.149988 -413.987488)
		(width 0.14224)
		(layer "In6.Cu")
		(net "P5E_CPU1_P1_TX_BUF_C_DP<4>")
	)
	(segment
		(start 66.203576 -426.549058)
		(end 66.522346 -426.549058)
		(width 0.14224)
		(layer "In6.Cu")
		(net "P5E_CPU1_P1_TX_BUF_C_DP<4>")
	)
	(segment
		(start 65.11163 -416.578034)
		(end 65.304924 -416.596322)
		(width 0.14224)
		(layer "In6.Cu")
		(net "P5E_CPU1_P1_TX_BUF_C_DP<4>")
	)
	(segment
		(start 62.151514 -410.320998)
		(end 62.151514 -411.125924)
		(width 0.14224)
		(layer "In6.Cu")
		(net "P5E_CPU1_P1_TX_BUF_C_DP<4>")
	)
	(segment
		(start 62.288674 -411.263084)
		(end 62.288674 -411.689804)
		(width 0.14224)
		(layer "In6.Cu")
		(net "P5E_CPU1_P1_TX_BUF_C_DP<4>")
	)
	(segment
		(start 63.8683 -414.85693)
		(end 64.14008 -415.186368)
		(width 0.14224)
		(layer "In6.Cu")
		(net "P5E_CPU1_P1_TX_BUF_C_DP<4>")
	)
	(segment
		(start 65.969896 -417.76396)
		(end 65.969896 -426.315378)
		(width 0.14224)
		(layer "In6.Cu")
		(net "P5E_CPU1_P1_TX_BUF_C_DP<4>")
	)
	(segment
		(start 64.840104 -416.249104)
		(end 65.11163 -416.578034)
		(width 0.14224)
		(layer "In6.Cu")
		(net "P5E_CPU1_P1_TX_BUF_C_DP<4>")
	)
	(segment
		(start 65.576958 -416.925506)
		(end 65.558416 -417.1188)
		(width 0.14224)
		(layer "In6.Cu")
		(net "P5E_CPU1_P1_TX_BUF_C_DP<4>")
	)
	(segment
		(start 64.393318 -415.708338)
		(end 64.586612 -415.726626)
		(width 0.14224)
		(layer "In6.Cu")
		(net "P5E_CPU1_P1_TX_BUF_C_DP<4>")
	)
	(segment
		(start 63.40348 -414.509712)
		(end 63.675006 -414.838642)
		(width 0.14224)
		(layer "In6.Cu")
		(net "P5E_CPU1_P1_TX_BUF_C_DP<4>")
	)
	(segment
		(start 62.186058 -413.036004)
		(end 62.956694 -413.968946)
		(width 0.14224)
		(layer "In6.Cu")
		(net "P5E_CPU1_P1_TX_BUF_C_DP<4>")
	)
	(segment
		(start 66.522346 -426.549058)
		(end 66.649854 -426.42155)
		(width 0.14224)
		(layer "In6.Cu")
		(net "P5E_CPU1_P1_TX_BUF_C_DP<4>")
	)
	(segment
		(start 65.558416 -417.1188)
		(end 65.87617 -417.503356)
		(width 0.14224)
		(layer "In6.Cu")
		(net "P5E_CPU1_P1_TX_BUF_C_DP<4>")
	)
	(segment
		(start 62.288674 -411.689804)
		(end 62.151514 -411.826964)
		(width 0.14224)
		(layer "In6.Cu")
		(net "P5E_CPU1_P1_TX_BUF_C_DP<4>")
	)
	(segment
		(start 64.14008 -415.186368)
		(end 64.121792 -415.379408)
		(width 0.14224)
		(layer "In6.Cu")
		(net "P5E_CPU1_P1_TX_BUF_C_DP<4>")
	)
	(segment
		(start 65.304924 -416.596322)
		(end 65.576958 -416.925506)
		(width 0.14224)
		(layer "In6.Cu")
		(net "P5E_CPU1_P1_TX_BUF_C_DP<4>")
	)
	(segment
		(start 62.151514 -411.125924)
		(end 62.288674 -411.263084)
		(width 0.14224)
		(layer "In6.Cu")
		(net "P5E_CPU1_P1_TX_BUF_C_DP<4>")
	)
	(segment
		(start 64.858646 -416.05581)
		(end 64.840104 -416.249104)
		(width 0.14224)
		(layer "In6.Cu")
		(net "P5E_CPU1_P1_TX_BUF_C_DP<4>")
	)
	(segment
		(start 66.649854 -426.42155)
		(end 66.649854 -426.089826)
		(width 0.14224)
		(layer "In6.Cu")
		(net "P5E_CPU1_P1_TX_BUF_C_DP<4>")
	)
	(segment
		(start 63.675006 -414.838642)
		(end 63.8683 -414.85693)
		(width 0.14224)
		(layer "In6.Cu")
		(net "P5E_CPU1_P1_TX_BUF_C_DP<4>")
	)
	(segment
		(start 62.151514 -411.826964)
		(end 62.151514 -412.939484)
		(width 0.14224)
		(layer "In6.Cu")
		(net "P5E_CPU1_P1_TX_BUF_C_DP<4>")
	)
	(arc
		(start 65.87617 -417.503356)
		(mid 65.945748 -417.625488)
		(end 65.969896 -417.76396)
		(width 0.14224)
		(layer "In6.Cu")
		(net "P5E_CPU1_P1_TX_BUF_C_DP<4>")
	)
	(arc
		(start 62.151514 -412.939484)
		(mid 62.16037 -412.990756)
		(end 62.186058 -413.036004)
		(width 0.14224)
		(layer "In6.Cu")
		(net "P5E_CPU1_P1_TX_BUF_C_DP<4>")
	)
	(segment
		(start 59.404504 -408.784044)
		(end 59.108594 -409.079954)
		(width 0.12954)
		(layer "B.Cu")
		(net "P5E_CPU1_P1_TX_BUF_C_DP<3>")
	)
	(segment
		(start 59.108594 -409.079954)
		(end 59.108594 -409.759658)
		(width 0.12954)
		(layer "B.Cu")
		(net "P5E_CPU1_P1_TX_BUF_C_DP<3>")
	)
	(segment
		(start 59.108594 -409.759658)
		(end 59.379104 -410.030168)
		(width 0.12954)
		(layer "B.Cu")
		(net "P5E_CPU1_P1_TX_BUF_C_DP<3>")
	)
	(segment
		(start 64.522604 -427.548802)
		(end 64.649858 -427.421548)
		(width 0.14224)
		(layer "In6.Cu")
		(net "P5E_CPU1_P1_TX_BUF_C_DP<3>")
	)
	(segment
		(start 60.948062 -414.639506)
		(end 61.262768 -414.928304)
		(width 0.14224)
		(layer "In6.Cu")
		(net "P5E_CPU1_P1_TX_BUF_C_DP<3>")
	)
	(segment
		(start 64.649858 -427.421548)
		(end 64.649858 -427.089824)
		(width 0.14224)
		(layer "In6.Cu")
		(net "P5E_CPU1_P1_TX_BUF_C_DP<3>")
	)
	(segment
		(start 60.75426 -414.647634)
		(end 60.948062 -414.639506)
		(width 0.14224)
		(layer "In6.Cu")
		(net "P5E_CPU1_P1_TX_BUF_C_DP<3>")
	)
	(segment
		(start 59.379104 -410.030168)
		(end 59.088274 -410.320998)
		(width 0.14224)
		(layer "In6.Cu")
		(net "P5E_CPU1_P1_TX_BUF_C_DP<3>")
	)
	(segment
		(start 60.440062 -414.359344)
		(end 60.75426 -414.647634)
		(width 0.14224)
		(layer "In6.Cu")
		(net "P5E_CPU1_P1_TX_BUF_C_DP<3>")
	)
	(segment
		(start 59.129422 -413.1564)
		(end 59.923426 -413.885126)
		(width 0.14224)
		(layer "In6.Cu")
		(net "P5E_CPU1_P1_TX_BUF_C_DP<3>")
	)
	(segment
		(start 63.9699 -417.778692)
		(end 63.9699 -427.380654)
		(width 0.14224)
		(layer "In6.Cu")
		(net "P5E_CPU1_P1_TX_BUF_C_DP<3>")
	)
	(segment
		(start 60.43168 -414.165542)
		(end 60.440062 -414.359344)
		(width 0.14224)
		(layer "In6.Cu")
		(net "P5E_CPU1_P1_TX_BUF_C_DP<3>")
	)
	(segment
		(start 63.9699 -427.380654)
		(end 64.138048 -427.548802)
		(width 0.14224)
		(layer "In6.Cu")
		(net "P5E_CPU1_P1_TX_BUF_C_DP<3>")
	)
	(segment
		(start 61.77915 -415.402268)
		(end 62.093856 -415.691066)
		(width 0.14224)
		(layer "In6.Cu")
		(net "P5E_CPU1_P1_TX_BUF_C_DP<3>")
	)
	(segment
		(start 59.923426 -413.885126)
		(end 60.117228 -413.876744)
		(width 0.14224)
		(layer "In6.Cu")
		(net "P5E_CPU1_P1_TX_BUF_C_DP<3>")
	)
	(segment
		(start 61.27115 -415.122106)
		(end 61.585348 -415.410396)
		(width 0.14224)
		(layer "In6.Cu")
		(net "P5E_CPU1_P1_TX_BUF_C_DP<3>")
	)
	(segment
		(start 64.138048 -427.548802)
		(end 64.522604 -427.548802)
		(width 0.14224)
		(layer "In6.Cu")
		(net "P5E_CPU1_P1_TX_BUF_C_DP<3>")
	)
	(segment
		(start 62.093856 -415.691066)
		(end 62.102238 -415.884868)
		(width 0.14224)
		(layer "In6.Cu")
		(net "P5E_CPU1_P1_TX_BUF_C_DP<3>")
	)
	(segment
		(start 62.102238 -415.884868)
		(end 63.837566 -417.477448)
		(width 0.14224)
		(layer "In6.Cu")
		(net "P5E_CPU1_P1_TX_BUF_C_DP<3>")
	)
	(segment
		(start 61.585348 -415.410396)
		(end 61.77915 -415.402268)
		(width 0.14224)
		(layer "In6.Cu")
		(net "P5E_CPU1_P1_TX_BUF_C_DP<3>")
	)
	(segment
		(start 59.088274 -410.320998)
		(end 59.088274 -413.062674)
		(width 0.14224)
		(layer "In6.Cu")
		(net "P5E_CPU1_P1_TX_BUF_C_DP<3>")
	)
	(segment
		(start 60.117228 -413.876744)
		(end 60.43168 -414.165542)
		(width 0.14224)
		(layer "In6.Cu")
		(net "P5E_CPU1_P1_TX_BUF_C_DP<3>")
	)
	(segment
		(start 61.262768 -414.928304)
		(end 61.27115 -415.122106)
		(width 0.14224)
		(layer "In6.Cu")
		(net "P5E_CPU1_P1_TX_BUF_C_DP<3>")
	)
	(arc
		(start 63.837566 -417.477448)
		(mid 63.935382 -417.614171)
		(end 63.9699 -417.778692)
		(width 0.14224)
		(layer "In6.Cu")
		(net "P5E_CPU1_P1_TX_BUF_C_DP<3>")
	)
	(arc
		(start 59.088274 -413.062674)
		(mid 59.099018 -413.11385)
		(end 59.129422 -413.1564)
		(width 0.14224)
		(layer "In6.Cu")
		(net "P5E_CPU1_P1_TX_BUF_C_DP<3>")
	)
	(segment
		(start 56.045354 -409.079954)
		(end 56.045354 -409.759658)
		(width 0.12954)
		(layer "B.Cu")
		(net "P5E_CPU1_P1_TX_BUF_C_DP<2>")
	)
	(segment
		(start 56.045354 -409.759658)
		(end 56.315864 -410.030168)
		(width 0.12954)
		(layer "B.Cu")
		(net "P5E_CPU1_P1_TX_BUF_C_DP<2>")
	)
	(segment
		(start 56.341264 -408.784044)
		(end 56.045354 -409.079954)
		(width 0.12954)
		(layer "B.Cu")
		(net "P5E_CPU1_P1_TX_BUF_C_DP<2>")
	)
	(segment
		(start 60.333128 -415.960306)
		(end 60.370974 -416.150552)
		(width 0.14224)
		(layer "In6.Cu")
		(net "P5E_CPU1_P1_TX_BUF_C_DP<2>")
	)
	(segment
		(start 60.370974 -416.150552)
		(end 61.677804 -417.023804)
		(width 0.14224)
		(layer "In6.Cu")
		(net "P5E_CPU1_P1_TX_BUF_C_DP<2>")
	)
	(segment
		(start 57.912254 -414.50768)
		(end 58.1025 -414.469834)
		(width 0.14224)
		(layer "In6.Cu")
		(net "P5E_CPU1_P1_TX_BUF_C_DP<2>")
	)
	(segment
		(start 58.850022 -415.134298)
		(end 59.040268 -415.096452)
		(width 0.14224)
		(layer "In6.Cu")
		(net "P5E_CPU1_P1_TX_BUF_C_DP<2>")
	)
	(segment
		(start 62.203584 -426.549058)
		(end 62.522354 -426.549058)
		(width 0.14224)
		(layer "In6.Cu")
		(net "P5E_CPU1_P1_TX_BUF_C_DP<2>")
	)
	(segment
		(start 62.649862 -426.42155)
		(end 62.649862 -426.089826)
		(width 0.14224)
		(layer "In6.Cu")
		(net "P5E_CPU1_P1_TX_BUF_C_DP<2>")
	)
	(segment
		(start 59.978036 -415.72307)
		(end 60.333128 -415.960306)
		(width 0.14224)
		(layer "In6.Cu")
		(net "P5E_CPU1_P1_TX_BUF_C_DP<2>")
	)
	(segment
		(start 56.081422 -413.284162)
		(end 56.97474 -413.881062)
		(width 0.14224)
		(layer "In6.Cu")
		(net "P5E_CPU1_P1_TX_BUF_C_DP<2>")
	)
	(segment
		(start 61.969904 -426.315378)
		(end 62.203584 -426.549058)
		(width 0.14224)
		(layer "In6.Cu")
		(net "P5E_CPU1_P1_TX_BUF_C_DP<2>")
	)
	(segment
		(start 57.519824 -414.080452)
		(end 57.55767 -414.270698)
		(width 0.14224)
		(layer "In6.Cu")
		(net "P5E_CPU1_P1_TX_BUF_C_DP<2>")
	)
	(segment
		(start 56.025034 -410.320998)
		(end 56.025034 -411.248606)
		(width 0.14224)
		(layer "In6.Cu")
		(net "P5E_CPU1_P1_TX_BUF_C_DP<2>")
	)
	(segment
		(start 56.025034 -411.949646)
		(end 56.025034 -413.178498)
		(width 0.14224)
		(layer "In6.Cu")
		(net "P5E_CPU1_P1_TX_BUF_C_DP<2>")
	)
	(segment
		(start 58.457592 -414.70707)
		(end 58.495438 -414.897316)
		(width 0.14224)
		(layer "In6.Cu")
		(net "P5E_CPU1_P1_TX_BUF_C_DP<2>")
	)
	(segment
		(start 58.1025 -414.469834)
		(end 58.457592 -414.70707)
		(width 0.14224)
		(layer "In6.Cu")
		(net "P5E_CPU1_P1_TX_BUF_C_DP<2>")
	)
	(segment
		(start 56.025034 -411.248606)
		(end 56.162194 -411.385766)
		(width 0.14224)
		(layer "In6.Cu")
		(net "P5E_CPU1_P1_TX_BUF_C_DP<2>")
	)
	(segment
		(start 59.39536 -415.333688)
		(end 59.433206 -415.523934)
		(width 0.14224)
		(layer "In6.Cu")
		(net "P5E_CPU1_P1_TX_BUF_C_DP<2>")
	)
	(segment
		(start 56.162194 -411.812486)
		(end 56.025034 -411.949646)
		(width 0.14224)
		(layer "In6.Cu")
		(net "P5E_CPU1_P1_TX_BUF_C_DP<2>")
	)
	(segment
		(start 56.315864 -410.030168)
		(end 56.025034 -410.320998)
		(width 0.14224)
		(layer "In6.Cu")
		(net "P5E_CPU1_P1_TX_BUF_C_DP<2>")
	)
	(segment
		(start 59.78779 -415.760916)
		(end 59.978036 -415.72307)
		(width 0.14224)
		(layer "In6.Cu")
		(net "P5E_CPU1_P1_TX_BUF_C_DP<2>")
	)
	(segment
		(start 56.97474 -413.881062)
		(end 57.164986 -413.843216)
		(width 0.14224)
		(layer "In6.Cu")
		(net "P5E_CPU1_P1_TX_BUF_C_DP<2>")
	)
	(segment
		(start 62.522354 -426.549058)
		(end 62.649862 -426.42155)
		(width 0.14224)
		(layer "In6.Cu")
		(net "P5E_CPU1_P1_TX_BUF_C_DP<2>")
	)
	(segment
		(start 59.433206 -415.523934)
		(end 59.78779 -415.760916)
		(width 0.14224)
		(layer "In6.Cu")
		(net "P5E_CPU1_P1_TX_BUF_C_DP<2>")
	)
	(segment
		(start 57.164986 -413.843216)
		(end 57.519824 -414.080452)
		(width 0.14224)
		(layer "In6.Cu")
		(net "P5E_CPU1_P1_TX_BUF_C_DP<2>")
	)
	(segment
		(start 56.162194 -411.385766)
		(end 56.162194 -411.812486)
		(width 0.14224)
		(layer "In6.Cu")
		(net "P5E_CPU1_P1_TX_BUF_C_DP<2>")
	)
	(segment
		(start 58.495438 -414.897316)
		(end 58.850022 -415.134298)
		(width 0.14224)
		(layer "In6.Cu")
		(net "P5E_CPU1_P1_TX_BUF_C_DP<2>")
	)
	(segment
		(start 57.55767 -414.270698)
		(end 57.912254 -414.50768)
		(width 0.14224)
		(layer "In6.Cu")
		(net "P5E_CPU1_P1_TX_BUF_C_DP<2>")
	)
	(segment
		(start 59.040268 -415.096452)
		(end 59.39536 -415.333688)
		(width 0.14224)
		(layer "In6.Cu")
		(net "P5E_CPU1_P1_TX_BUF_C_DP<2>")
	)
	(segment
		(start 61.969904 -417.570412)
		(end 61.969904 -426.315378)
		(width 0.14224)
		(layer "In6.Cu")
		(net "P5E_CPU1_P1_TX_BUF_C_DP<2>")
	)
	(arc
		(start 61.677804 -417.023804)
		(mid 61.892261 -417.260545)
		(end 61.969904 -417.570412)
		(width 0.14224)
		(layer "In6.Cu")
		(net "P5E_CPU1_P1_TX_BUF_C_DP<2>")
	)
	(arc
		(start 56.025034 -413.178498)
		(mid 56.040008 -413.238388)
		(end 56.081422 -413.284162)
		(width 0.14224)
		(layer "In6.Cu")
		(net "P5E_CPU1_P1_TX_BUF_C_DP<2>")
	)
	(segment
		(start 52.982114 -409.079954)
		(end 52.982114 -409.759658)
		(width 0.12954)
		(layer "B.Cu")
		(net "P5E_CPU1_P1_TX_BUF_C_DP<1>")
	)
	(segment
		(start 53.278024 -408.784044)
		(end 52.982114 -409.079954)
		(width 0.12954)
		(layer "B.Cu")
		(net "P5E_CPU1_P1_TX_BUF_C_DP<1>")
	)
	(segment
		(start 52.982114 -409.759658)
		(end 53.252624 -410.030168)
		(width 0.12954)
		(layer "B.Cu")
		(net "P5E_CPU1_P1_TX_BUF_C_DP<1>")
	)
	(segment
		(start 59.969908 -427.380654)
		(end 60.138056 -427.548802)
		(width 0.14224)
		(layer "In6.Cu")
		(net "P5E_CPU1_P1_TX_BUF_C_DP<1>")
	)
	(segment
		(start 55.707026 -414.621472)
		(end 55.76316 -414.807146)
		(width 0.14224)
		(layer "In6.Cu")
		(net "P5E_CPU1_P1_TX_BUF_C_DP<1>")
	)
	(segment
		(start 54.712108 -414.089596)
		(end 54.768496 -414.275524)
		(width 0.14224)
		(layer "In6.Cu")
		(net "P5E_CPU1_P1_TX_BUF_C_DP<1>")
	)
	(segment
		(start 54.33568 -413.888428)
		(end 54.712108 -414.089596)
		(width 0.14224)
		(layer "In6.Cu")
		(net "P5E_CPU1_P1_TX_BUF_C_DP<1>")
	)
	(segment
		(start 53.252624 -410.030168)
		(end 52.961794 -410.320998)
		(width 0.14224)
		(layer "In6.Cu")
		(net "P5E_CPU1_P1_TX_BUF_C_DP<1>")
	)
	(segment
		(start 53.105558 -413.386778)
		(end 54.149752 -413.944816)
		(width 0.14224)
		(layer "In6.Cu")
		(net "P5E_CPU1_P1_TX_BUF_C_DP<1>")
	)
	(segment
		(start 54.768496 -414.275524)
		(end 55.14467 -414.476438)
		(width 0.14224)
		(layer "In6.Cu")
		(net "P5E_CPU1_P1_TX_BUF_C_DP<1>")
	)
	(segment
		(start 59.969908 -417.440618)
		(end 59.969908 -427.380654)
		(width 0.14224)
		(layer "In6.Cu")
		(net "P5E_CPU1_P1_TX_BUF_C_DP<1>")
	)
	(segment
		(start 56.972454 -415.453576)
		(end 59.630818 -416.874198)
		(width 0.14224)
		(layer "In6.Cu")
		(net "P5E_CPU1_P1_TX_BUF_C_DP<1>")
	)
	(segment
		(start 56.539638 -415.06648)
		(end 56.91632 -415.267648)
		(width 0.14224)
		(layer "In6.Cu")
		(net "P5E_CPU1_P1_TX_BUF_C_DP<1>")
	)
	(segment
		(start 55.330344 -414.420304)
		(end 55.707026 -414.621472)
		(width 0.14224)
		(layer "In6.Cu")
		(net "P5E_CPU1_P1_TX_BUF_C_DP<1>")
	)
	(segment
		(start 52.961794 -410.320998)
		(end 52.961794 -413.147002)
		(width 0.14224)
		(layer "In6.Cu")
		(net "P5E_CPU1_P1_TX_BUF_C_DP<1>")
	)
	(segment
		(start 55.14467 -414.476438)
		(end 55.330344 -414.420304)
		(width 0.14224)
		(layer "In6.Cu")
		(net "P5E_CPU1_P1_TX_BUF_C_DP<1>")
	)
	(segment
		(start 56.353964 -415.122868)
		(end 56.539638 -415.06648)
		(width 0.14224)
		(layer "In6.Cu")
		(net "P5E_CPU1_P1_TX_BUF_C_DP<1>")
	)
	(segment
		(start 60.522612 -427.548802)
		(end 60.649866 -427.421548)
		(width 0.14224)
		(layer "In6.Cu")
		(net "P5E_CPU1_P1_TX_BUF_C_DP<1>")
	)
	(segment
		(start 56.91632 -415.267648)
		(end 56.972454 -415.453576)
		(width 0.14224)
		(layer "In6.Cu")
		(net "P5E_CPU1_P1_TX_BUF_C_DP<1>")
	)
	(segment
		(start 55.76316 -414.807146)
		(end 56.353964 -415.122868)
		(width 0.14224)
		(layer "In6.Cu")
		(net "P5E_CPU1_P1_TX_BUF_C_DP<1>")
	)
	(segment
		(start 60.649866 -427.421548)
		(end 60.649866 -427.089824)
		(width 0.14224)
		(layer "In6.Cu")
		(net "P5E_CPU1_P1_TX_BUF_C_DP<1>")
	)
	(segment
		(start 54.150006 -413.944816)
		(end 54.33568 -413.888428)
		(width 0.14224)
		(layer "In6.Cu")
		(net "P5E_CPU1_P1_TX_BUF_C_DP<1>")
	)
	(segment
		(start 54.149752 -413.944816)
		(end 54.150006 -413.944816)
		(width 0.14224)
		(layer "In6.Cu")
		(net "P5E_CPU1_P1_TX_BUF_C_DP<1>")
	)
	(segment
		(start 60.138056 -427.548802)
		(end 60.522612 -427.548802)
		(width 0.14224)
		(layer "In6.Cu")
		(net "P5E_CPU1_P1_TX_BUF_C_DP<1>")
	)
	(arc
		(start 59.630818 -416.874198)
		(mid 59.878749 -417.110489)
		(end 59.969908 -417.440618)
		(width 0.14224)
		(layer "In6.Cu")
		(net "P5E_CPU1_P1_TX_BUF_C_DP<1>")
	)
	(arc
		(start 52.961794 -413.147002)
		(mid 53.000494 -413.28678)
		(end 53.105558 -413.386778)
		(width 0.14224)
		(layer "In6.Cu")
		(net "P5E_CPU1_P1_TX_BUF_C_DP<1>")
	)
	(segment
		(start 95.867474 -409.759658)
		(end 96.137984 -410.030168)
		(width 0.12954)
		(layer "B.Cu")
		(net "P5E_CPU1_P1_TX_BUF_C_DP<15>")
	)
	(segment
		(start 95.867474 -409.079954)
		(end 95.867474 -409.759658)
		(width 0.12954)
		(layer "B.Cu")
		(net "P5E_CPU1_P1_TX_BUF_C_DP<15>")
	)
	(segment
		(start 96.163384 -408.784044)
		(end 95.867474 -409.079954)
		(width 0.12954)
		(layer "B.Cu")
		(net "P5E_CPU1_P1_TX_BUF_C_DP<15>")
	)
	(segment
		(start 94.234762 -416.201606)
		(end 93.997526 -416.556698)
		(width 0.14224)
		(layer "In6.Cu")
		(net "P5E_CPU1_P1_TX_BUF_C_DP<15>")
	)
	(segment
		(start 95.024194 -414.773364)
		(end 94.196916 -416.01136)
		(width 0.14224)
		(layer "In6.Cu")
		(net "P5E_CPU1_P1_TX_BUF_C_DP<15>")
	)
	(segment
		(start 88.970104 -427.380654)
		(end 89.138252 -427.548802)
		(width 0.14224)
		(layer "In6.Cu")
		(net "P5E_CPU1_P1_TX_BUF_C_DP<15>")
	)
	(segment
		(start 95.984314 -411.633416)
		(end 95.847154 -411.770576)
		(width 0.14224)
		(layer "In6.Cu")
		(net "P5E_CPU1_P1_TX_BUF_C_DP<15>")
	)
	(segment
		(start 89.650062 -427.421548)
		(end 89.650062 -427.089824)
		(width 0.14224)
		(layer "In6.Cu")
		(net "P5E_CPU1_P1_TX_BUF_C_DP<15>")
	)
	(segment
		(start 95.847154 -411.770576)
		(end 95.847154 -413.18815)
		(width 0.14224)
		(layer "In6.Cu")
		(net "P5E_CPU1_P1_TX_BUF_C_DP<15>")
	)
	(segment
		(start 95.847154 -410.320998)
		(end 95.847154 -411.069536)
		(width 0.14224)
		(layer "In6.Cu")
		(net "P5E_CPU1_P1_TX_BUF_C_DP<15>")
	)
	(segment
		(start 95.847154 -411.069536)
		(end 95.984314 -411.206696)
		(width 0.14224)
		(layer "In6.Cu")
		(net "P5E_CPU1_P1_TX_BUF_C_DP<15>")
	)
	(segment
		(start 94.196916 -416.01136)
		(end 94.234762 -416.201606)
		(width 0.14224)
		(layer "In6.Cu")
		(net "P5E_CPU1_P1_TX_BUF_C_DP<15>")
	)
	(segment
		(start 88.970104 -424.2562)
		(end 88.970104 -427.380654)
		(width 0.14224)
		(layer "In6.Cu")
		(net "P5E_CPU1_P1_TX_BUF_C_DP<15>")
	)
	(segment
		(start 95.650812 -413.835596)
		(end 95.41383 -414.19018)
		(width 0.14224)
		(layer "In6.Cu")
		(net "P5E_CPU1_P1_TX_BUF_C_DP<15>")
	)
	(segment
		(start 96.137984 -410.030168)
		(end 95.847154 -410.320998)
		(width 0.14224)
		(layer "In6.Cu")
		(net "P5E_CPU1_P1_TX_BUF_C_DP<15>")
	)
	(segment
		(start 95.451676 -414.380426)
		(end 95.21444 -414.735518)
		(width 0.14224)
		(layer "In6.Cu")
		(net "P5E_CPU1_P1_TX_BUF_C_DP<15>")
	)
	(segment
		(start 95.21444 -414.735518)
		(end 95.024194 -414.773364)
		(width 0.14224)
		(layer "In6.Cu")
		(net "P5E_CPU1_P1_TX_BUF_C_DP<15>")
	)
	(segment
		(start 95.847154 -413.18815)
		(end 95.650812 -413.835596)
		(width 0.14224)
		(layer "In6.Cu")
		(net "P5E_CPU1_P1_TX_BUF_C_DP<15>")
	)
	(segment
		(start 95.41383 -414.19018)
		(end 95.451676 -414.380426)
		(width 0.14224)
		(layer "In6.Cu")
		(net "P5E_CPU1_P1_TX_BUF_C_DP<15>")
	)
	(segment
		(start 89.522808 -427.548802)
		(end 89.650062 -427.421548)
		(width 0.14224)
		(layer "In6.Cu")
		(net "P5E_CPU1_P1_TX_BUF_C_DP<15>")
	)
	(segment
		(start 89.138252 -427.548802)
		(end 89.522808 -427.548802)
		(width 0.14224)
		(layer "In6.Cu")
		(net "P5E_CPU1_P1_TX_BUF_C_DP<15>")
	)
	(segment
		(start 93.997526 -416.556698)
		(end 93.80728 -416.594544)
		(width 0.14224)
		(layer "In6.Cu")
		(net "P5E_CPU1_P1_TX_BUF_C_DP<15>")
	)
	(segment
		(start 95.984314 -411.206696)
		(end 95.984314 -411.633416)
		(width 0.14224)
		(layer "In6.Cu")
		(net "P5E_CPU1_P1_TX_BUF_C_DP<15>")
	)
	(segment
		(start 93.80728 -416.594544)
		(end 89.204546 -423.483024)
		(width 0.14224)
		(layer "In6.Cu")
		(net "P5E_CPU1_P1_TX_BUF_C_DP<15>")
	)
	(arc
		(start 89.204546 -423.483024)
		(mid 89.030009 -423.852228)
		(end 88.970104 -424.2562)
		(width 0.14224)
		(layer "In6.Cu")
		(net "P5E_CPU1_P1_TX_BUF_C_DP<15>")
	)
	(segment
		(start 93.100144 -408.784044)
		(end 92.804234 -409.079954)
		(width 0.12954)
		(layer "B.Cu")
		(net "P5E_CPU1_P1_TX_BUF_C_DP<14>")
	)
	(segment
		(start 92.804234 -409.079954)
		(end 92.804234 -409.759658)
		(width 0.12954)
		(layer "B.Cu")
		(net "P5E_CPU1_P1_TX_BUF_C_DP<14>")
	)
	(segment
		(start 92.804234 -409.759658)
		(end 93.074744 -410.030168)
		(width 0.12954)
		(layer "B.Cu")
		(net "P5E_CPU1_P1_TX_BUF_C_DP<14>")
	)
	(segment
		(start 90.658442 -417.755578)
		(end 90.457274 -418.13226)
		(width 0.14224)
		(layer "In6.Cu")
		(net "P5E_CPU1_P1_TX_BUF_C_DP<14>")
	)
	(segment
		(start 91.190064 -416.760914)
		(end 90.988896 -417.137596)
		(width 0.14224)
		(layer "In6.Cu")
		(net "P5E_CPU1_P1_TX_BUF_C_DP<14>")
	)
	(segment
		(start 92.921074 -411.664404)
		(end 92.783914 -411.801564)
		(width 0.14224)
		(layer "In6.Cu")
		(net "P5E_CPU1_P1_TX_BUF_C_DP<14>")
	)
	(segment
		(start 91.665552 -415.580576)
		(end 91.72194 -415.76625)
		(width 0.14224)
		(layer "In6.Cu")
		(net "P5E_CPU1_P1_TX_BUF_C_DP<14>")
	)
	(segment
		(start 87.203788 -426.549058)
		(end 87.522558 -426.549058)
		(width 0.14224)
		(layer "In6.Cu")
		(net "P5E_CPU1_P1_TX_BUF_C_DP<14>")
	)
	(segment
		(start 92.583 -413.864298)
		(end 92.639134 -414.049972)
		(width 0.14224)
		(layer "In6.Cu")
		(net "P5E_CPU1_P1_TX_BUF_C_DP<14>")
	)
	(segment
		(start 90.602308 -417.569904)
		(end 90.658442 -417.755578)
		(width 0.14224)
		(layer "In6.Cu")
		(net "P5E_CPU1_P1_TX_BUF_C_DP<14>")
	)
	(segment
		(start 90.988896 -417.137596)
		(end 90.803222 -417.19373)
		(width 0.14224)
		(layer "In6.Cu")
		(net "P5E_CPU1_P1_TX_BUF_C_DP<14>")
	)
	(segment
		(start 90.2716 -418.188394)
		(end 87.125302 -424.075352)
		(width 0.14224)
		(layer "In6.Cu")
		(net "P5E_CPU1_P1_TX_BUF_C_DP<14>")
	)
	(segment
		(start 90.457274 -418.13226)
		(end 90.2716 -418.188394)
		(width 0.14224)
		(layer "In6.Cu")
		(net "P5E_CPU1_P1_TX_BUF_C_DP<14>")
	)
	(segment
		(start 92.783914 -413.488124)
		(end 92.583 -413.864298)
		(width 0.14224)
		(layer "In6.Cu")
		(net "P5E_CPU1_P1_TX_BUF_C_DP<14>")
	)
	(segment
		(start 86.970108 -424.694604)
		(end 86.970108 -426.315378)
		(width 0.14224)
		(layer "In6.Cu")
		(net "P5E_CPU1_P1_TX_BUF_C_DP<14>")
	)
	(segment
		(start 92.639134 -414.049972)
		(end 92.437966 -414.426654)
		(width 0.14224)
		(layer "In6.Cu")
		(net "P5E_CPU1_P1_TX_BUF_C_DP<14>")
	)
	(segment
		(start 87.650066 -426.42155)
		(end 87.650066 -426.089826)
		(width 0.14224)
		(layer "In6.Cu")
		(net "P5E_CPU1_P1_TX_BUF_C_DP<14>")
	)
	(segment
		(start 91.520772 -416.142678)
		(end 91.334844 -416.199066)
		(width 0.14224)
		(layer "In6.Cu")
		(net "P5E_CPU1_P1_TX_BUF_C_DP<14>")
	)
	(segment
		(start 93.074744 -410.030168)
		(end 92.783914 -410.320998)
		(width 0.14224)
		(layer "In6.Cu")
		(net "P5E_CPU1_P1_TX_BUF_C_DP<14>")
	)
	(segment
		(start 91.334844 -416.199066)
		(end 91.13393 -416.57524)
		(width 0.14224)
		(layer "In6.Cu")
		(net "P5E_CPU1_P1_TX_BUF_C_DP<14>")
	)
	(segment
		(start 92.437966 -414.426654)
		(end 92.252292 -414.482788)
		(width 0.14224)
		(layer "In6.Cu")
		(net "P5E_CPU1_P1_TX_BUF_C_DP<14>")
	)
	(segment
		(start 92.783914 -410.320998)
		(end 92.783914 -411.100524)
		(width 0.14224)
		(layer "In6.Cu")
		(net "P5E_CPU1_P1_TX_BUF_C_DP<14>")
	)
	(segment
		(start 92.783914 -411.100524)
		(end 92.921074 -411.237684)
		(width 0.14224)
		(layer "In6.Cu")
		(net "P5E_CPU1_P1_TX_BUF_C_DP<14>")
	)
	(segment
		(start 91.72194 -415.76625)
		(end 91.520772 -416.142678)
		(width 0.14224)
		(layer "In6.Cu")
		(net "P5E_CPU1_P1_TX_BUF_C_DP<14>")
	)
	(segment
		(start 91.13393 -416.57524)
		(end 91.190064 -416.760914)
		(width 0.14224)
		(layer "In6.Cu")
		(net "P5E_CPU1_P1_TX_BUF_C_DP<14>")
	)
	(segment
		(start 92.252292 -414.482788)
		(end 91.665552 -415.580576)
		(width 0.14224)
		(layer "In6.Cu")
		(net "P5E_CPU1_P1_TX_BUF_C_DP<14>")
	)
	(segment
		(start 92.921074 -411.237684)
		(end 92.921074 -411.664404)
		(width 0.14224)
		(layer "In6.Cu")
		(net "P5E_CPU1_P1_TX_BUF_C_DP<14>")
	)
	(segment
		(start 86.970108 -426.315378)
		(end 87.203788 -426.549058)
		(width 0.14224)
		(layer "In6.Cu")
		(net "P5E_CPU1_P1_TX_BUF_C_DP<14>")
	)
	(segment
		(start 87.522558 -426.549058)
		(end 87.650066 -426.42155)
		(width 0.14224)
		(layer "In6.Cu")
		(net "P5E_CPU1_P1_TX_BUF_C_DP<14>")
	)
	(segment
		(start 90.803222 -417.19373)
		(end 90.602308 -417.569904)
		(width 0.14224)
		(layer "In6.Cu")
		(net "P5E_CPU1_P1_TX_BUF_C_DP<14>")
	)
	(segment
		(start 92.783914 -411.801564)
		(end 92.783914 -413.488124)
		(width 0.14224)
		(layer "In6.Cu")
		(net "P5E_CPU1_P1_TX_BUF_C_DP<14>")
	)
	(arc
		(start 87.125302 -424.075352)
		(mid 87.009494 -424.375405)
		(end 86.970108 -424.694604)
		(width 0.14224)
		(layer "In6.Cu")
		(net "P5E_CPU1_P1_TX_BUF_C_DP<14>")
	)
	(segment
		(start 89.740994 -409.759658)
		(end 90.011504 -410.030168)
		(width 0.12954)
		(layer "B.Cu")
		(net "P5E_CPU1_P1_TX_BUF_C_DP<13>")
	)
	(segment
		(start 90.036904 -408.784044)
		(end 89.740994 -409.079954)
		(width 0.12954)
		(layer "B.Cu")
		(net "P5E_CPU1_P1_TX_BUF_C_DP<13>")
	)
	(segment
		(start 89.740994 -409.079954)
		(end 89.740994 -409.759658)
		(width 0.12954)
		(layer "B.Cu")
		(net "P5E_CPU1_P1_TX_BUF_C_DP<13>")
	)
	(segment
		(start 89.720674 -411.879796)
		(end 89.720674 -413.034988)
		(width 0.14224)
		(layer "In6.Cu")
		(net "P5E_CPU1_P1_TX_BUF_C_DP<13>")
	)
	(segment
		(start 88.269572 -416.32251)
		(end 88.106504 -416.716718)
		(width 0.14224)
		(layer "In6.Cu")
		(net "P5E_CPU1_P1_TX_BUF_C_DP<13>")
	)
	(segment
		(start 88.711278 -415.255964)
		(end 88.53805 -415.674556)
		(width 0.14224)
		(layer "In6.Cu")
		(net "P5E_CPU1_P1_TX_BUF_C_DP<13>")
	)
	(segment
		(start 85.65007 -427.421548)
		(end 85.65007 -427.089824)
		(width 0.14224)
		(layer "In6.Cu")
		(net "P5E_CPU1_P1_TX_BUF_C_DP<13>")
	)
	(segment
		(start 87.837772 -417.364672)
		(end 85.117178 -423.933112)
		(width 0.14224)
		(layer "In6.Cu")
		(net "P5E_CPU1_P1_TX_BUF_C_DP<13>")
	)
	(segment
		(start 88.180672 -416.895788)
		(end 88.01735 -417.290504)
		(width 0.14224)
		(layer "In6.Cu")
		(net "P5E_CPU1_P1_TX_BUF_C_DP<13>")
	)
	(segment
		(start 88.44915 -416.248342)
		(end 88.269572 -416.32251)
		(width 0.14224)
		(layer "In6.Cu")
		(net "P5E_CPU1_P1_TX_BUF_C_DP<13>")
	)
	(segment
		(start 89.857834 -411.315916)
		(end 89.857834 -411.742636)
		(width 0.14224)
		(layer "In6.Cu")
		(net "P5E_CPU1_P1_TX_BUF_C_DP<13>")
	)
	(segment
		(start 89.689432 -413.191706)
		(end 89.258902 -414.231074)
		(width 0.14224)
		(layer "In6.Cu")
		(net "P5E_CPU1_P1_TX_BUF_C_DP<13>")
	)
	(segment
		(start 85.522816 -427.548802)
		(end 85.65007 -427.421548)
		(width 0.14224)
		(layer "In6.Cu")
		(net "P5E_CPU1_P1_TX_BUF_C_DP<13>")
	)
	(segment
		(start 88.106504 -416.716718)
		(end 88.180672 -416.895788)
		(width 0.14224)
		(layer "In6.Cu")
		(net "P5E_CPU1_P1_TX_BUF_C_DP<13>")
	)
	(segment
		(start 85.13826 -427.548802)
		(end 85.522816 -427.548802)
		(width 0.14224)
		(layer "In6.Cu")
		(net "P5E_CPU1_P1_TX_BUF_C_DP<13>")
	)
	(segment
		(start 90.011504 -410.030168)
		(end 89.720674 -410.320998)
		(width 0.14224)
		(layer "In6.Cu")
		(net "P5E_CPU1_P1_TX_BUF_C_DP<13>")
	)
	(segment
		(start 88.612218 -415.85388)
		(end 88.44915 -416.248342)
		(width 0.14224)
		(layer "In6.Cu")
		(net "P5E_CPU1_P1_TX_BUF_C_DP<13>")
	)
	(segment
		(start 89.258902 -414.231074)
		(end 88.711278 -415.255964)
		(width 0.14224)
		(layer "In6.Cu")
		(net "P5E_CPU1_P1_TX_BUF_C_DP<13>")
	)
	(segment
		(start 88.53805 -415.674556)
		(end 88.612218 -415.85388)
		(width 0.14224)
		(layer "In6.Cu")
		(net "P5E_CPU1_P1_TX_BUF_C_DP<13>")
	)
	(segment
		(start 88.01735 -417.290504)
		(end 87.837772 -417.364672)
		(width 0.14224)
		(layer "In6.Cu")
		(net "P5E_CPU1_P1_TX_BUF_C_DP<13>")
	)
	(segment
		(start 84.970112 -424.671998)
		(end 84.970112 -427.380654)
		(width 0.14224)
		(layer "In6.Cu")
		(net "P5E_CPU1_P1_TX_BUF_C_DP<13>")
	)
	(segment
		(start 89.720674 -411.178756)
		(end 89.857834 -411.315916)
		(width 0.14224)
		(layer "In6.Cu")
		(net "P5E_CPU1_P1_TX_BUF_C_DP<13>")
	)
	(segment
		(start 89.857834 -411.742636)
		(end 89.720674 -411.879796)
		(width 0.14224)
		(layer "In6.Cu")
		(net "P5E_CPU1_P1_TX_BUF_C_DP<13>")
	)
	(segment
		(start 84.970112 -427.380654)
		(end 85.13826 -427.548802)
		(width 0.14224)
		(layer "In6.Cu")
		(net "P5E_CPU1_P1_TX_BUF_C_DP<13>")
	)
	(segment
		(start 89.720674 -410.320998)
		(end 89.720674 -411.178756)
		(width 0.14224)
		(layer "In6.Cu")
		(net "P5E_CPU1_P1_TX_BUF_C_DP<13>")
	)
	(arc
		(start 85.117178 -423.933112)
		(mid 85.007257 -424.295313)
		(end 84.970112 -424.671998)
		(width 0.14224)
		(layer "In6.Cu")
		(net "P5E_CPU1_P1_TX_BUF_C_DP<13>")
	)
	(arc
		(start 89.720674 -413.034988)
		(mid 89.712753 -413.11488)
		(end 89.689432 -413.191706)
		(width 0.14224)
		(layer "In6.Cu")
		(net "P5E_CPU1_P1_TX_BUF_C_DP<13>")
	)
	(segment
		(start 86.973664 -408.784044)
		(end 86.677754 -409.079954)
		(width 0.12954)
		(layer "B.Cu")
		(net "P5E_CPU1_P1_TX_BUF_C_DP<12>")
	)
	(segment
		(start 86.677754 -409.079954)
		(end 86.677754 -409.759658)
		(width 0.12954)
		(layer "B.Cu")
		(net "P5E_CPU1_P1_TX_BUF_C_DP<12>")
	)
	(segment
		(start 86.677754 -409.759658)
		(end 86.948264 -410.030168)
		(width 0.12954)
		(layer "B.Cu")
		(net "P5E_CPU1_P1_TX_BUF_C_DP<12>")
	)
	(segment
		(start 85.518498 -417.35248)
		(end 85.394546 -417.760912)
		(width 0.14224)
		(layer "In6.Cu")
		(net "P5E_CPU1_P1_TX_BUF_C_DP<12>")
	)
	(segment
		(start 85.946488 -415.46907)
		(end 85.754464 -416.102038)
		(width 0.14224)
		(layer "In6.Cu")
		(net "P5E_CPU1_P1_TX_BUF_C_DP<12>")
	)
	(segment
		(start 83.522566 -426.549058)
		(end 83.650074 -426.42155)
		(width 0.14224)
		(layer "In6.Cu")
		(net "P5E_CPU1_P1_TX_BUF_C_DP<12>")
	)
	(segment
		(start 86.569042 -413.889698)
		(end 86.445344 -414.298384)
		(width 0.14224)
		(layer "In6.Cu")
		(net "P5E_CPU1_P1_TX_BUF_C_DP<12>")
	)
	(segment
		(start 85.550756 -416.773106)
		(end 85.427312 -417.180522)
		(width 0.14224)
		(layer "In6.Cu")
		(net "P5E_CPU1_P1_TX_BUF_C_DP<12>")
	)
	(segment
		(start 86.794594 -411.3784)
		(end 86.794594 -411.80512)
		(width 0.14224)
		(layer "In6.Cu")
		(net "P5E_CPU1_P1_TX_BUF_C_DP<12>")
	)
	(segment
		(start 86.657434 -411.94228)
		(end 86.657434 -413.02813)
		(width 0.14224)
		(layer "In6.Cu")
		(net "P5E_CPU1_P1_TX_BUF_C_DP<12>")
	)
	(segment
		(start 85.722206 -416.681666)
		(end 85.550756 -416.773106)
		(width 0.14224)
		(layer "In6.Cu")
		(net "P5E_CPU1_P1_TX_BUF_C_DP<12>")
	)
	(segment
		(start 86.628986 -413.220408)
		(end 86.477602 -413.718502)
		(width 0.14224)
		(layer "In6.Cu")
		(net "P5E_CPU1_P1_TX_BUF_C_DP<12>")
	)
	(segment
		(start 86.241636 -414.969198)
		(end 86.117684 -415.37763)
		(width 0.14224)
		(layer "In6.Cu")
		(net "P5E_CPU1_P1_TX_BUF_C_DP<12>")
	)
	(segment
		(start 86.948264 -410.030168)
		(end 86.657434 -410.320998)
		(width 0.14224)
		(layer "In6.Cu")
		(net "P5E_CPU1_P1_TX_BUF_C_DP<12>")
	)
	(segment
		(start 83.650074 -426.42155)
		(end 83.650074 -426.089826)
		(width 0.14224)
		(layer "In6.Cu")
		(net "P5E_CPU1_P1_TX_BUF_C_DP<12>")
	)
	(segment
		(start 82.970116 -425.228258)
		(end 82.970116 -426.315378)
		(width 0.14224)
		(layer "In6.Cu")
		(net "P5E_CPU1_P1_TX_BUF_C_DP<12>")
	)
	(segment
		(start 85.214714 -417.856924)
		(end 83.60537 -423.162984)
		(width 0.14224)
		(layer "In6.Cu")
		(net "P5E_CPU1_P1_TX_BUF_C_DP<12>")
	)
	(segment
		(start 85.394546 -417.760912)
		(end 85.214714 -417.856924)
		(width 0.14224)
		(layer "In6.Cu")
		(net "P5E_CPU1_P1_TX_BUF_C_DP<12>")
	)
	(segment
		(start 86.657434 -410.320998)
		(end 86.657434 -411.24124)
		(width 0.14224)
		(layer "In6.Cu")
		(net "P5E_CPU1_P1_TX_BUF_C_DP<12>")
	)
	(segment
		(start 83.203796 -426.549058)
		(end 83.522566 -426.549058)
		(width 0.14224)
		(layer "In6.Cu")
		(net "P5E_CPU1_P1_TX_BUF_C_DP<12>")
	)
	(segment
		(start 86.794594 -411.80512)
		(end 86.657434 -411.94228)
		(width 0.14224)
		(layer "In6.Cu")
		(net "P5E_CPU1_P1_TX_BUF_C_DP<12>")
	)
	(segment
		(start 86.150196 -414.798002)
		(end 86.241636 -414.969198)
		(width 0.14224)
		(layer "In6.Cu")
		(net "P5E_CPU1_P1_TX_BUF_C_DP<12>")
	)
	(segment
		(start 86.117684 -415.37763)
		(end 85.946488 -415.46907)
		(width 0.14224)
		(layer "In6.Cu")
		(net "P5E_CPU1_P1_TX_BUF_C_DP<12>")
	)
	(segment
		(start 86.445344 -414.298384)
		(end 86.273894 -414.389824)
		(width 0.14224)
		(layer "In6.Cu")
		(net "P5E_CPU1_P1_TX_BUF_C_DP<12>")
	)
	(segment
		(start 86.657434 -411.24124)
		(end 86.794594 -411.3784)
		(width 0.14224)
		(layer "In6.Cu")
		(net "P5E_CPU1_P1_TX_BUF_C_DP<12>")
	)
	(segment
		(start 85.427058 -417.181284)
		(end 85.518498 -417.35248)
		(width 0.14224)
		(layer "In6.Cu")
		(net "P5E_CPU1_P1_TX_BUF_C_DP<12>")
	)
	(segment
		(start 86.477602 -413.718502)
		(end 86.569042 -413.889698)
		(width 0.14224)
		(layer "In6.Cu")
		(net "P5E_CPU1_P1_TX_BUF_C_DP<12>")
	)
	(segment
		(start 83.60537 -423.162984)
		(end 83.173316 -424.205908)
		(width 0.14224)
		(layer "In6.Cu")
		(net "P5E_CPU1_P1_TX_BUF_C_DP<12>")
	)
	(segment
		(start 85.427312 -417.180522)
		(end 85.427058 -417.181284)
		(width 0.14224)
		(layer "In6.Cu")
		(net "P5E_CPU1_P1_TX_BUF_C_DP<12>")
	)
	(segment
		(start 82.970116 -426.315378)
		(end 83.203796 -426.549058)
		(width 0.14224)
		(layer "In6.Cu")
		(net "P5E_CPU1_P1_TX_BUF_C_DP<12>")
	)
	(segment
		(start 85.754464 -416.102038)
		(end 85.845904 -416.273234)
		(width 0.14224)
		(layer "In6.Cu")
		(net "P5E_CPU1_P1_TX_BUF_C_DP<12>")
	)
	(segment
		(start 86.273894 -414.389824)
		(end 86.150196 -414.798002)
		(width 0.14224)
		(layer "In6.Cu")
		(net "P5E_CPU1_P1_TX_BUF_C_DP<12>")
	)
	(segment
		(start 85.845904 -416.273234)
		(end 85.722206 -416.681666)
		(width 0.14224)
		(layer "In6.Cu")
		(net "P5E_CPU1_P1_TX_BUF_C_DP<12>")
	)
	(arc
		(start 83.173316 -424.205908)
		(mid 83.021364 -424.707076)
		(end 82.970116 -425.228258)
		(width 0.14224)
		(layer "In6.Cu")
		(net "P5E_CPU1_P1_TX_BUF_C_DP<12>")
	)
	(arc
		(start 86.657434 -413.02813)
		(mid 86.650295 -413.125316)
		(end 86.628986 -413.220408)
		(width 0.14224)
		(layer "In6.Cu")
		(net "P5E_CPU1_P1_TX_BUF_C_DP<12>")
	)
	(segment
		(start 83.614514 -409.759658)
		(end 83.885024 -410.030168)
		(width 0.12954)
		(layer "B.Cu")
		(net "P5E_CPU1_P1_TX_BUF_C_DP<11>")
	)
	(segment
		(start 83.614514 -409.079954)
		(end 83.614514 -409.759658)
		(width 0.12954)
		(layer "B.Cu")
		(net "P5E_CPU1_P1_TX_BUF_C_DP<11>")
	)
	(segment
		(start 83.910424 -408.784044)
		(end 83.614514 -409.079954)
		(width 0.12954)
		(layer "B.Cu")
		(net "P5E_CPU1_P1_TX_BUF_C_DP<11>")
	)
	(segment
		(start 83.490562 -413.784796)
		(end 83.590384 -413.951166)
		(width 0.14224)
		(layer "In6.Cu")
		(net "P5E_CPU1_P1_TX_BUF_C_DP<11>")
	)
	(segment
		(start 83.216496 -414.878774)
		(end 83.316318 -415.045144)
		(width 0.14224)
		(layer "In6.Cu")
		(net "P5E_CPU1_P1_TX_BUF_C_DP<11>")
	)
	(segment
		(start 80.97012 -427.380654)
		(end 81.138268 -427.548802)
		(width 0.14224)
		(layer "In6.Cu")
		(net "P5E_CPU1_P1_TX_BUF_C_DP<11>")
	)
	(segment
		(start 83.590384 -413.951166)
		(end 83.486752 -414.36544)
		(width 0.14224)
		(layer "In6.Cu")
		(net "P5E_CPU1_P1_TX_BUF_C_DP<11>")
	)
	(segment
		(start 82.668364 -417.06673)
		(end 82.768186 -417.2331)
		(width 0.14224)
		(layer "In6.Cu")
		(net "P5E_CPU1_P1_TX_BUF_C_DP<11>")
	)
	(segment
		(start 83.541362 -413.58185)
		(end 83.490562 -413.784796)
		(width 0.14224)
		(layer "In6.Cu")
		(net "P5E_CPU1_P1_TX_BUF_C_DP<11>")
	)
	(segment
		(start 83.320128 -414.465008)
		(end 83.216496 -414.878774)
		(width 0.14224)
		(layer "In6.Cu")
		(net "P5E_CPU1_P1_TX_BUF_C_DP<11>")
	)
	(segment
		(start 83.486752 -414.36544)
		(end 83.320128 -414.465008)
		(width 0.14224)
		(layer "In6.Cu")
		(net "P5E_CPU1_P1_TX_BUF_C_DP<11>")
	)
	(segment
		(start 83.042252 -416.139122)
		(end 82.93862 -416.553396)
		(width 0.14224)
		(layer "In6.Cu")
		(net "P5E_CPU1_P1_TX_BUF_C_DP<11>")
	)
	(segment
		(start 82.768186 -417.2331)
		(end 82.664554 -417.647374)
		(width 0.14224)
		(layer "In6.Cu")
		(net "P5E_CPU1_P1_TX_BUF_C_DP<11>")
	)
	(segment
		(start 83.594194 -410.320998)
		(end 83.594194 -413.154368)
		(width 0.14224)
		(layer "In6.Cu")
		(net "P5E_CPU1_P1_TX_BUF_C_DP<11>")
	)
	(segment
		(start 83.885024 -410.030168)
		(end 83.594194 -410.320998)
		(width 0.14224)
		(layer "In6.Cu")
		(net "P5E_CPU1_P1_TX_BUF_C_DP<11>")
	)
	(segment
		(start 83.316318 -415.045144)
		(end 83.212686 -415.459418)
		(width 0.14224)
		(layer "In6.Cu")
		(net "P5E_CPU1_P1_TX_BUF_C_DP<11>")
	)
	(segment
		(start 81.522824 -427.548802)
		(end 81.650078 -427.421548)
		(width 0.14224)
		(layer "In6.Cu")
		(net "P5E_CPU1_P1_TX_BUF_C_DP<11>")
	)
	(segment
		(start 83.046062 -415.558986)
		(end 82.94243 -415.972752)
		(width 0.14224)
		(layer "In6.Cu")
		(net "P5E_CPU1_P1_TX_BUF_C_DP<11>")
	)
	(segment
		(start 83.212686 -415.459418)
		(end 83.046062 -415.558986)
		(width 0.14224)
		(layer "In6.Cu")
		(net "P5E_CPU1_P1_TX_BUF_C_DP<11>")
	)
	(segment
		(start 81.138268 -427.548802)
		(end 81.522824 -427.548802)
		(width 0.14224)
		(layer "In6.Cu")
		(net "P5E_CPU1_P1_TX_BUF_C_DP<11>")
	)
	(segment
		(start 82.49793 -417.746942)
		(end 81.03489 -423.588688)
		(width 0.14224)
		(layer "In6.Cu")
		(net "P5E_CPU1_P1_TX_BUF_C_DP<11>")
	)
	(segment
		(start 81.650078 -427.421548)
		(end 81.650078 -427.089824)
		(width 0.14224)
		(layer "In6.Cu")
		(net "P5E_CPU1_P1_TX_BUF_C_DP<11>")
	)
	(segment
		(start 82.771996 -416.652964)
		(end 82.668364 -417.06673)
		(width 0.14224)
		(layer "In6.Cu")
		(net "P5E_CPU1_P1_TX_BUF_C_DP<11>")
	)
	(segment
		(start 82.94243 -415.972752)
		(end 83.042252 -416.139122)
		(width 0.14224)
		(layer "In6.Cu")
		(net "P5E_CPU1_P1_TX_BUF_C_DP<11>")
	)
	(segment
		(start 82.93862 -416.553396)
		(end 82.771996 -416.652964)
		(width 0.14224)
		(layer "In6.Cu")
		(net "P5E_CPU1_P1_TX_BUF_C_DP<11>")
	)
	(segment
		(start 82.664554 -417.647374)
		(end 82.49793 -417.746942)
		(width 0.14224)
		(layer "In6.Cu")
		(net "P5E_CPU1_P1_TX_BUF_C_DP<11>")
	)
	(segment
		(start 80.97012 -424.113452)
		(end 80.97012 -427.380654)
		(width 0.14224)
		(layer "In6.Cu")
		(net "P5E_CPU1_P1_TX_BUF_C_DP<11>")
	)
	(arc
		(start 83.594194 -413.154368)
		(mid 83.580921 -413.369733)
		(end 83.541362 -413.58185)
		(width 0.14224)
		(layer "In6.Cu")
		(net "P5E_CPU1_P1_TX_BUF_C_DP<11>")
	)
	(arc
		(start 81.03489 -423.588688)
		(mid 80.986384 -423.84908)
		(end 80.97012 -424.113452)
		(width 0.14224)
		(layer "In6.Cu")
		(net "P5E_CPU1_P1_TX_BUF_C_DP<11>")
	)
	(segment
		(start 80.847184 -408.784044)
		(end 80.551274 -409.079954)
		(width 0.12954)
		(layer "B.Cu")
		(net "P5E_CPU1_P1_TX_BUF_C_DP<10>")
	)
	(segment
		(start 80.551274 -409.079954)
		(end 80.551274 -409.759658)
		(width 0.12954)
		(layer "B.Cu")
		(net "P5E_CPU1_P1_TX_BUF_C_DP<10>")
	)
	(segment
		(start 80.551274 -409.759658)
		(end 80.821784 -410.030168)
		(width 0.12954)
		(layer "B.Cu")
		(net "P5E_CPU1_P1_TX_BUF_C_DP<10>")
	)
	(segment
		(start 80.519524 -414.260792)
		(end 80.582262 -413.83839)
		(width 0.14224)
		(layer "In6.Cu")
		(net "P5E_CPU1_P1_TX_BUF_C_DP<10>")
	)
	(segment
		(start 80.530954 -410.320998)
		(end 80.821784 -410.030168)
		(width 0.14224)
		(layer "In6.Cu")
		(net "P5E_CPU1_P1_TX_BUF_C_DP<10>")
	)
	(segment
		(start 79.663798 -419.090348)
		(end 79.664306 -419.08984)
		(width 0.14224)
		(layer "In6.Cu")
		(net "P5E_CPU1_P1_TX_BUF_C_DP<10>")
	)
	(segment
		(start 80.409542 -415.001456)
		(end 80.293972 -414.845754)
		(width 0.14224)
		(layer "In6.Cu")
		(net "P5E_CPU1_P1_TX_BUF_C_DP<10>")
	)
	(segment
		(start 80.15097 -416.743642)
		(end 80.213708 -416.32124)
		(width 0.14224)
		(layer "In6.Cu")
		(net "P5E_CPU1_P1_TX_BUF_C_DP<10>")
	)
	(segment
		(start 80.668114 -411.687772)
		(end 80.668114 -411.261052)
		(width 0.14224)
		(layer "In6.Cu")
		(net "P5E_CPU1_P1_TX_BUF_C_DP<10>")
	)
	(segment
		(start 79.995014 -416.859212)
		(end 80.15097 -416.743642)
		(width 0.14224)
		(layer "In6.Cu")
		(net "P5E_CPU1_P1_TX_BUF_C_DP<10>")
	)
	(segment
		(start 80.293972 -414.845754)
		(end 80.363568 -414.376108)
		(width 0.14224)
		(layer "In6.Cu")
		(net "P5E_CPU1_P1_TX_BUF_C_DP<10>")
	)
	(segment
		(start 80.668114 -411.261052)
		(end 80.530954 -411.123892)
		(width 0.14224)
		(layer "In6.Cu")
		(net "P5E_CPU1_P1_TX_BUF_C_DP<10>")
	)
	(segment
		(start 79.829406 -417.97478)
		(end 79.985616 -417.859464)
		(width 0.14224)
		(layer "In6.Cu")
		(net "P5E_CPU1_P1_TX_BUF_C_DP<10>")
	)
	(segment
		(start 80.213708 -416.32124)
		(end 80.098138 -416.165538)
		(width 0.14224)
		(layer "In6.Cu")
		(net "P5E_CPU1_P1_TX_BUF_C_DP<10>")
	)
	(segment
		(start 80.098138 -416.165538)
		(end 80.190848 -415.539428)
		(width 0.14224)
		(layer "In6.Cu")
		(net "P5E_CPU1_P1_TX_BUF_C_DP<10>")
	)
	(segment
		(start 78.970124 -423.770806)
		(end 79.663798 -419.090348)
		(width 0.14224)
		(layer "In6.Cu")
		(net "P5E_CPU1_P1_TX_BUF_C_DP<10>")
	)
	(segment
		(start 79.650082 -426.42155)
		(end 79.522574 -426.549058)
		(width 0.14224)
		(layer "In6.Cu")
		(net "P5E_CPU1_P1_TX_BUF_C_DP<10>")
	)
	(segment
		(start 79.203804 -426.549058)
		(end 78.970124 -426.315378)
		(width 0.14224)
		(layer "In6.Cu")
		(net "P5E_CPU1_P1_TX_BUF_C_DP<10>")
	)
	(segment
		(start 80.190848 -415.539428)
		(end 80.347058 -415.423858)
		(width 0.14224)
		(layer "In6.Cu")
		(net "P5E_CPU1_P1_TX_BUF_C_DP<10>")
	)
	(segment
		(start 80.530954 -411.824932)
		(end 80.668114 -411.687772)
		(width 0.14224)
		(layer "In6.Cu")
		(net "P5E_CPU1_P1_TX_BUF_C_DP<10>")
	)
	(segment
		(start 80.582262 -413.83839)
		(end 80.466692 -413.682434)
		(width 0.14224)
		(layer "In6.Cu")
		(net "P5E_CPU1_P1_TX_BUF_C_DP<10>")
	)
	(segment
		(start 79.93253 -417.281106)
		(end 79.995014 -416.859212)
		(width 0.14224)
		(layer "In6.Cu")
		(net "P5E_CPU1_P1_TX_BUF_C_DP<10>")
	)
	(segment
		(start 79.664306 -419.08984)
		(end 79.829406 -417.97478)
		(width 0.14224)
		(layer "In6.Cu")
		(net "P5E_CPU1_P1_TX_BUF_C_DP<10>")
	)
	(segment
		(start 80.363568 -414.376108)
		(end 80.519524 -414.260792)
		(width 0.14224)
		(layer "In6.Cu")
		(net "P5E_CPU1_P1_TX_BUF_C_DP<10>")
	)
	(segment
		(start 78.970124 -426.315378)
		(end 78.970124 -423.770806)
		(width 0.14224)
		(layer "In6.Cu")
		(net "P5E_CPU1_P1_TX_BUF_C_DP<10>")
	)
	(segment
		(start 79.522574 -426.549058)
		(end 79.203804 -426.549058)
		(width 0.14224)
		(layer "In6.Cu")
		(net "P5E_CPU1_P1_TX_BUF_C_DP<10>")
	)
	(segment
		(start 80.0481 -417.437062)
		(end 79.93253 -417.281106)
		(width 0.14224)
		(layer "In6.Cu")
		(net "P5E_CPU1_P1_TX_BUF_C_DP<10>")
	)
	(segment
		(start 80.530954 -413.248348)
		(end 80.530954 -411.824932)
		(width 0.14224)
		(layer "In6.Cu")
		(net "P5E_CPU1_P1_TX_BUF_C_DP<10>")
	)
	(segment
		(start 79.650082 -426.089826)
		(end 79.650082 -426.42155)
		(width 0.14224)
		(layer "In6.Cu")
		(net "P5E_CPU1_P1_TX_BUF_C_DP<10>")
	)
	(segment
		(start 80.530954 -411.123892)
		(end 80.530954 -410.320998)
		(width 0.14224)
		(layer "In6.Cu")
		(net "P5E_CPU1_P1_TX_BUF_C_DP<10>")
	)
	(segment
		(start 79.985616 -417.859464)
		(end 80.0481 -417.437062)
		(width 0.14224)
		(layer "In6.Cu")
		(net "P5E_CPU1_P1_TX_BUF_C_DP<10>")
	)
	(segment
		(start 80.347058 -415.423858)
		(end 80.409542 -415.001456)
		(width 0.14224)
		(layer "In6.Cu")
		(net "P5E_CPU1_P1_TX_BUF_C_DP<10>")
	)
	(segment
		(start 80.466692 -413.682434)
		(end 80.530954 -413.248348)
		(width 0.14224)
		(layer "In6.Cu")
		(net "P5E_CPU1_P1_TX_BUF_C_DP<10>")
	)
	(segment
		(start 49.918874 -409.759658)
		(end 50.189384 -410.030168)
		(width 0.12954)
		(layer "B.Cu")
		(net "P5E_CPU1_P1_TX_BUF_C_DP<0>")
	)
	(segment
		(start 49.918874 -409.079954)
		(end 49.918874 -409.759658)
		(width 0.12954)
		(layer "B.Cu")
		(net "P5E_CPU1_P1_TX_BUF_C_DP<0>")
	)
	(segment
		(start 50.214784 -408.784044)
		(end 49.918874 -409.079954)
		(width 0.12954)
		(layer "B.Cu")
		(net "P5E_CPU1_P1_TX_BUF_C_DP<0>")
	)
	(segment
		(start 51.25593 -415.169096)
		(end 51.227482 -415.36112)
		(width 0.14224)
		(layer "In6.Cu")
		(net "P5E_CPU1_P1_TX_BUF_C_DP<0>")
	)
	(segment
		(start 50.189384 -410.030168)
		(end 49.898554 -410.320998)
		(width 0.14224)
		(layer "In6.Cu")
		(net "P5E_CPU1_P1_TX_BUF_C_DP<0>")
	)
	(segment
		(start 49.898554 -410.320998)
		(end 49.898554 -411.183582)
		(width 0.14224)
		(layer "In6.Cu")
		(net "P5E_CPU1_P1_TX_BUF_C_DP<0>")
	)
	(segment
		(start 50.035714 -411.320742)
		(end 50.035714 -411.747462)
		(width 0.14224)
		(layer "In6.Cu")
		(net "P5E_CPU1_P1_TX_BUF_C_DP<0>")
	)
	(segment
		(start 51.768502 -416.090354)
		(end 51.960272 -416.118802)
		(width 0.14224)
		(layer "In6.Cu")
		(net "P5E_CPU1_P1_TX_BUF_C_DP<0>")
	)
	(segment
		(start 51.001422 -414.826196)
		(end 51.25593 -415.169096)
		(width 0.14224)
		(layer "In6.Cu")
		(net "P5E_CPU1_P1_TX_BUF_C_DP<0>")
	)
	(segment
		(start 49.996852 -413.702246)
		(end 50.809652 -414.797748)
		(width 0.14224)
		(layer "In6.Cu")
		(net "P5E_CPU1_P1_TX_BUF_C_DP<0>")
	)
	(segment
		(start 50.035714 -411.747462)
		(end 49.898554 -411.884622)
		(width 0.14224)
		(layer "In6.Cu")
		(net "P5E_CPU1_P1_TX_BUF_C_DP<0>")
	)
	(segment
		(start 53.062632 -417.604702)
		(end 53.034184 -417.796472)
		(width 0.14224)
		(layer "In6.Cu")
		(net "P5E_CPU1_P1_TX_BUF_C_DP<0>")
	)
	(segment
		(start 58.64987 -426.42155)
		(end 58.64987 -426.089826)
		(width 0.14224)
		(layer "In6.Cu")
		(net "P5E_CPU1_P1_TX_BUF_C_DP<0>")
	)
	(segment
		(start 53.712872 -418.71138)
		(end 54.330854 -419.90264)
		(width 0.14224)
		(layer "In6.Cu")
		(net "P5E_CPU1_P1_TX_BUF_C_DP<0>")
	)
	(segment
		(start 53.034184 -417.796472)
		(end 53.712872 -418.71138)
		(width 0.14224)
		(layer "In6.Cu")
		(net "P5E_CPU1_P1_TX_BUF_C_DP<0>")
	)
	(segment
		(start 51.227482 -415.36112)
		(end 51.768502 -416.090354)
		(width 0.14224)
		(layer "In6.Cu")
		(net "P5E_CPU1_P1_TX_BUF_C_DP<0>")
	)
	(segment
		(start 52.808124 -417.261802)
		(end 53.062632 -417.604702)
		(width 0.14224)
		(layer "In6.Cu")
		(net "P5E_CPU1_P1_TX_BUF_C_DP<0>")
	)
	(segment
		(start 52.6161 -417.233354)
		(end 52.808124 -417.261802)
		(width 0.14224)
		(layer "In6.Cu")
		(net "P5E_CPU1_P1_TX_BUF_C_DP<0>")
	)
	(segment
		(start 58.522362 -426.549058)
		(end 58.64987 -426.42155)
		(width 0.14224)
		(layer "In6.Cu")
		(net "P5E_CPU1_P1_TX_BUF_C_DP<0>")
	)
	(segment
		(start 49.898554 -411.183582)
		(end 50.035714 -411.320742)
		(width 0.14224)
		(layer "In6.Cu")
		(net "P5E_CPU1_P1_TX_BUF_C_DP<0>")
	)
	(segment
		(start 54.51602 -419.961314)
		(end 54.712616 -420.340282)
		(width 0.14224)
		(layer "In6.Cu")
		(net "P5E_CPU1_P1_TX_BUF_C_DP<0>")
	)
	(segment
		(start 52.186332 -416.653726)
		(end 52.6161 -417.233354)
		(width 0.14224)
		(layer "In6.Cu")
		(net "P5E_CPU1_P1_TX_BUF_C_DP<0>")
	)
	(segment
		(start 54.712616 -420.340282)
		(end 54.653942 -420.525194)
		(width 0.14224)
		(layer "In6.Cu")
		(net "P5E_CPU1_P1_TX_BUF_C_DP<0>")
	)
	(segment
		(start 51.960272 -416.118802)
		(end 52.21478 -416.461956)
		(width 0.14224)
		(layer "In6.Cu")
		(net "P5E_CPU1_P1_TX_BUF_C_DP<0>")
	)
	(segment
		(start 49.898554 -411.884622)
		(end 49.898554 -413.404304)
		(width 0.14224)
		(layer "In6.Cu")
		(net "P5E_CPU1_P1_TX_BUF_C_DP<0>")
	)
	(segment
		(start 50.809652 -414.797748)
		(end 51.001422 -414.826196)
		(width 0.14224)
		(layer "In6.Cu")
		(net "P5E_CPU1_P1_TX_BUF_C_DP<0>")
	)
	(segment
		(start 57.85612 -426.549058)
		(end 58.522362 -426.549058)
		(width 0.14224)
		(layer "In6.Cu")
		(net "P5E_CPU1_P1_TX_BUF_C_DP<0>")
	)
	(segment
		(start 54.330854 -419.90264)
		(end 54.51602 -419.961314)
		(width 0.14224)
		(layer "In6.Cu")
		(net "P5E_CPU1_P1_TX_BUF_C_DP<0>")
	)
	(segment
		(start 54.653942 -420.525194)
		(end 57.743344 -426.480478)
		(width 0.14224)
		(layer "In6.Cu")
		(net "P5E_CPU1_P1_TX_BUF_C_DP<0>")
	)
	(segment
		(start 52.21478 -416.461956)
		(end 52.186332 -416.653726)
		(width 0.14224)
		(layer "In6.Cu")
		(net "P5E_CPU1_P1_TX_BUF_C_DP<0>")
	)
	(arc
		(start 57.743344 -426.480478)
		(mid 57.790122 -426.530573)
		(end 57.85612 -426.549058)
		(width 0.14224)
		(layer "In6.Cu")
		(net "P5E_CPU1_P1_TX_BUF_C_DP<0>")
	)
	(arc
		(start 49.898554 -413.404304)
		(mid 49.923726 -413.561185)
		(end 49.996852 -413.702246)
		(width 0.14224)
		(layer "In6.Cu")
		(net "P5E_CPU1_P1_TX_BUF_C_DP<0>")
	)
	(segment
		(start 77.165454 -409.079954)
		(end 77.165454 -409.759658)
		(width 0.12954)
		(layer "B.Cu")
		(net "P5E_CPU1_P1_TX_BUF_C_DN<9>")
	)
	(segment
		(start 76.869544 -408.784044)
		(end 77.165454 -409.079954)
		(width 0.12954)
		(layer "B.Cu")
		(net "P5E_CPU1_P1_TX_BUF_C_DN<9>")
	)
	(segment
		(start 77.165454 -409.759658)
		(end 76.894944 -410.030168)
		(width 0.12954)
		(layer "B.Cu")
		(net "P5E_CPU1_P1_TX_BUF_C_DN<9>")
	)
	(segment
		(start 77.185774 -413.015176)
		(end 77.185774 -410.320998)
		(width 0.14224)
		(layer "In6.Cu")
		(net "P5E_CPU1_P1_TX_BUF_C_DN<9>")
	)
	(segment
		(start 77.650086 -427.957996)
		(end 77.51699 -427.8249)
		(width 0.14224)
		(layer "In6.Cu")
		(net "P5E_CPU1_P1_TX_BUF_C_DN<9>")
	)
	(segment
		(start 77.007974 -416.634422)
		(end 77.185774 -413.015176)
		(width 0.14224)
		(layer "In6.Cu")
		(net "P5E_CPU1_P1_TX_BUF_C_DN<9>")
	)
	(segment
		(start 77.51699 -427.8249)
		(end 77.015594 -427.8249)
		(width 0.14224)
		(layer "In6.Cu")
		(net "P5E_CPU1_P1_TX_BUF_C_DN<9>")
	)
	(segment
		(start 77.007466 -416.634676)
		(end 77.007974 -416.634422)
		(width 0.14224)
		(layer "In6.Cu")
		(net "P5E_CPU1_P1_TX_BUF_C_DN<9>")
	)
	(segment
		(start 77.015594 -427.8249)
		(end 76.688188 -427.497494)
		(width 0.14224)
		(layer "In6.Cu")
		(net "P5E_CPU1_P1_TX_BUF_C_DN<9>")
	)
	(segment
		(start 77.650086 -428.28972)
		(end 77.650086 -427.957996)
		(width 0.14224)
		(layer "In6.Cu")
		(net "P5E_CPU1_P1_TX_BUF_C_DN<9>")
	)
	(segment
		(start 76.688188 -427.497494)
		(end 76.688188 -423.145458)
		(width 0.14224)
		(layer "In6.Cu")
		(net "P5E_CPU1_P1_TX_BUF_C_DN<9>")
	)
	(segment
		(start 77.185774 -410.320998)
		(end 76.894944 -410.030168)
		(width 0.14224)
		(layer "In6.Cu")
		(net "P5E_CPU1_P1_TX_BUF_C_DN<9>")
	)
	(segment
		(start 76.688188 -423.145458)
		(end 77.007466 -416.634676)
		(width 0.14224)
		(layer "In6.Cu")
		(net "P5E_CPU1_P1_TX_BUF_C_DN<9>")
	)
	(segment
		(start 74.102214 -409.759658)
		(end 73.831704 -410.030168)
		(width 0.12954)
		(layer "B.Cu")
		(net "P5E_CPU1_P1_TX_BUF_C_DN<8>")
	)
	(segment
		(start 74.102214 -409.079954)
		(end 74.102214 -409.759658)
		(width 0.12954)
		(layer "B.Cu")
		(net "P5E_CPU1_P1_TX_BUF_C_DN<8>")
	)
	(segment
		(start 73.806304 -408.784044)
		(end 74.102214 -409.079954)
		(width 0.12954)
		(layer "B.Cu")
		(net "P5E_CPU1_P1_TX_BUF_C_DN<8>")
	)
	(segment
		(start 74.34453 -417.751006)
		(end 74.344022 -417.750752)
		(width 0.14224)
		(layer "In6.Cu")
		(net "P5E_CPU1_P1_TX_BUF_C_DN<8>")
	)
	(segment
		(start 75.522836 -426.830998)
		(end 75.086972 -426.830998)
		(width 0.14224)
		(layer "In6.Cu")
		(net "P5E_CPU1_P1_TX_BUF_C_DN<8>")
	)
	(segment
		(start 75.65009 -427.289976)
		(end 75.65009 -426.958252)
		(width 0.14224)
		(layer "In6.Cu")
		(net "P5E_CPU1_P1_TX_BUF_C_DN<8>")
	)
	(segment
		(start 75.65009 -426.958252)
		(end 75.522836 -426.830998)
		(width 0.14224)
		(layer "In6.Cu")
		(net "P5E_CPU1_P1_TX_BUF_C_DN<8>")
	)
	(segment
		(start 74.403458 -426.147484)
		(end 74.403458 -418.951156)
		(width 0.14224)
		(layer "In6.Cu")
		(net "P5E_CPU1_P1_TX_BUF_C_DN<8>")
	)
	(segment
		(start 75.086972 -426.830998)
		(end 74.403458 -426.147484)
		(width 0.14224)
		(layer "In6.Cu")
		(net "P5E_CPU1_P1_TX_BUF_C_DN<8>")
	)
	(segment
		(start 74.122534 -413.244538)
		(end 74.122534 -410.320998)
		(width 0.14224)
		(layer "In6.Cu")
		(net "P5E_CPU1_P1_TX_BUF_C_DN<8>")
	)
	(segment
		(start 74.403458 -418.951156)
		(end 74.34453 -417.751006)
		(width 0.14224)
		(layer "In6.Cu")
		(net "P5E_CPU1_P1_TX_BUF_C_DN<8>")
	)
	(segment
		(start 74.344022 -417.750752)
		(end 74.123042 -413.245046)
		(width 0.14224)
		(layer "In6.Cu")
		(net "P5E_CPU1_P1_TX_BUF_C_DN<8>")
	)
	(segment
		(start 74.123042 -413.245046)
		(end 74.122534 -413.244538)
		(width 0.14224)
		(layer "In6.Cu")
		(net "P5E_CPU1_P1_TX_BUF_C_DN<8>")
	)
	(segment
		(start 74.122534 -410.320998)
		(end 73.831704 -410.030168)
		(width 0.14224)
		(layer "In6.Cu")
		(net "P5E_CPU1_P1_TX_BUF_C_DN<8>")
	)
	(segment
		(start 71.038974 -409.079954)
		(end 71.038974 -409.759658)
		(width 0.12954)
		(layer "B.Cu")
		(net "P5E_CPU1_P1_TX_BUF_C_DN<7>")
	)
	(segment
		(start 70.743064 -408.784044)
		(end 71.038974 -409.079954)
		(width 0.12954)
		(layer "B.Cu")
		(net "P5E_CPU1_P1_TX_BUF_C_DN<7>")
	)
	(segment
		(start 71.038974 -409.759658)
		(end 70.768464 -410.030168)
		(width 0.12954)
		(layer "B.Cu")
		(net "P5E_CPU1_P1_TX_BUF_C_DN<7>")
	)
	(segment
		(start 71.059294 -413.08655)
		(end 71.059294 -410.320998)
		(width 0.14224)
		(layer "In6.Cu")
		(net "P5E_CPU1_P1_TX_BUF_C_DN<7>")
	)
	(segment
		(start 72.649842 -427.957996)
		(end 72.522588 -427.830742)
		(width 0.14224)
		(layer "In6.Cu")
		(net "P5E_CPU1_P1_TX_BUF_C_DN<7>")
	)
	(segment
		(start 71.687944 -427.497494)
		(end 71.687944 -419.471094)
		(width 0.14224)
		(layer "In6.Cu")
		(net "P5E_CPU1_P1_TX_BUF_C_DN<7>")
	)
	(segment
		(start 71.687944 -419.471094)
		(end 71.059294 -413.08655)
		(width 0.14224)
		(layer "In6.Cu")
		(net "P5E_CPU1_P1_TX_BUF_C_DN<7>")
	)
	(segment
		(start 72.021192 -427.830742)
		(end 71.687944 -427.497494)
		(width 0.14224)
		(layer "In6.Cu")
		(net "P5E_CPU1_P1_TX_BUF_C_DN<7>")
	)
	(segment
		(start 72.522588 -427.830742)
		(end 72.021192 -427.830742)
		(width 0.14224)
		(layer "In6.Cu")
		(net "P5E_CPU1_P1_TX_BUF_C_DN<7>")
	)
	(segment
		(start 72.649842 -428.28972)
		(end 72.649842 -427.957996)
		(width 0.14224)
		(layer "In6.Cu")
		(net "P5E_CPU1_P1_TX_BUF_C_DN<7>")
	)
	(segment
		(start 71.059294 -410.320998)
		(end 70.768464 -410.030168)
		(width 0.14224)
		(layer "In6.Cu")
		(net "P5E_CPU1_P1_TX_BUF_C_DN<7>")
	)
	(segment
		(start 67.975734 -409.759658)
		(end 67.705224 -410.030168)
		(width 0.12954)
		(layer "B.Cu")
		(net "P5E_CPU1_P1_TX_BUF_C_DN<6>")
	)
	(segment
		(start 67.679824 -408.784044)
		(end 67.975734 -409.079954)
		(width 0.12954)
		(layer "B.Cu")
		(net "P5E_CPU1_P1_TX_BUF_C_DN<6>")
	)
	(segment
		(start 67.975734 -409.079954)
		(end 67.975734 -409.759658)
		(width 0.12954)
		(layer "B.Cu")
		(net "P5E_CPU1_P1_TX_BUF_C_DN<6>")
	)
	(segment
		(start 70.522846 -426.860208)
		(end 70.115938 -426.860208)
		(width 0.14224)
		(layer "In6.Cu")
		(net "P5E_CPU1_P1_TX_BUF_C_DN<6>")
	)
	(segment
		(start 70.115938 -426.860208)
		(end 69.687948 -426.432218)
		(width 0.14224)
		(layer "In6.Cu")
		(net "P5E_CPU1_P1_TX_BUF_C_DN<6>")
	)
	(segment
		(start 67.996054 -412.944818)
		(end 67.996054 -410.320998)
		(width 0.14224)
		(layer "In6.Cu")
		(net "P5E_CPU1_P1_TX_BUF_C_DN<6>")
	)
	(segment
		(start 70.649846 -427.289976)
		(end 70.649846 -426.987208)
		(width 0.14224)
		(layer "In6.Cu")
		(net "P5E_CPU1_P1_TX_BUF_C_DN<6>")
	)
	(segment
		(start 67.996054 -410.320998)
		(end 67.705224 -410.030168)
		(width 0.14224)
		(layer "In6.Cu")
		(net "P5E_CPU1_P1_TX_BUF_C_DN<6>")
	)
	(segment
		(start 69.687948 -417.672774)
		(end 67.996054 -412.944818)
		(width 0.14224)
		(layer "In6.Cu")
		(net "P5E_CPU1_P1_TX_BUF_C_DN<6>")
	)
	(segment
		(start 69.687948 -426.432218)
		(end 69.687948 -417.672774)
		(width 0.14224)
		(layer "In6.Cu")
		(net "P5E_CPU1_P1_TX_BUF_C_DN<6>")
	)
	(segment
		(start 70.649846 -426.987208)
		(end 70.522846 -426.860208)
		(width 0.14224)
		(layer "In6.Cu")
		(net "P5E_CPU1_P1_TX_BUF_C_DN<6>")
	)
	(segment
		(start 64.912494 -409.759658)
		(end 64.641984 -410.030168)
		(width 0.12954)
		(layer "B.Cu")
		(net "P5E_CPU1_P1_TX_BUF_C_DN<5>")
	)
	(segment
		(start 64.912494 -409.079954)
		(end 64.912494 -409.759658)
		(width 0.12954)
		(layer "B.Cu")
		(net "P5E_CPU1_P1_TX_BUF_C_DN<5>")
	)
	(segment
		(start 64.616584 -408.784044)
		(end 64.912494 -409.079954)
		(width 0.12954)
		(layer "B.Cu")
		(net "P5E_CPU1_P1_TX_BUF_C_DN<5>")
	)
	(segment
		(start 67.687952 -417.764214)
		(end 64.932814 -412.901892)
		(width 0.14224)
		(layer "In6.Cu")
		(net "P5E_CPU1_P1_TX_BUF_C_DN<5>")
	)
	(segment
		(start 68.64985 -428.28972)
		(end 68.64985 -427.957996)
		(width 0.14224)
		(layer "In6.Cu")
		(net "P5E_CPU1_P1_TX_BUF_C_DN<5>")
	)
	(segment
		(start 64.932814 -412.901892)
		(end 64.932814 -410.320998)
		(width 0.14224)
		(layer "In6.Cu")
		(net "P5E_CPU1_P1_TX_BUF_C_DN<5>")
	)
	(segment
		(start 68.015358 -427.8249)
		(end 67.687952 -427.497494)
		(width 0.14224)
		(layer "In6.Cu")
		(net "P5E_CPU1_P1_TX_BUF_C_DN<5>")
	)
	(segment
		(start 68.516754 -427.8249)
		(end 68.015358 -427.8249)
		(width 0.14224)
		(layer "In6.Cu")
		(net "P5E_CPU1_P1_TX_BUF_C_DN<5>")
	)
	(segment
		(start 67.687952 -427.497494)
		(end 67.687952 -417.764214)
		(width 0.14224)
		(layer "In6.Cu")
		(net "P5E_CPU1_P1_TX_BUF_C_DN<5>")
	)
	(segment
		(start 64.932814 -410.320998)
		(end 64.641984 -410.030168)
		(width 0.14224)
		(layer "In6.Cu")
		(net "P5E_CPU1_P1_TX_BUF_C_DN<5>")
	)
	(segment
		(start 68.64985 -427.957996)
		(end 68.516754 -427.8249)
		(width 0.14224)
		(layer "In6.Cu")
		(net "P5E_CPU1_P1_TX_BUF_C_DN<5>")
	)
	(segment
		(start 61.553344 -408.784044)
		(end 61.849254 -409.079954)
		(width 0.12954)
		(layer "B.Cu")
		(net "P5E_CPU1_P1_TX_BUF_C_DN<4>")
	)
	(segment
		(start 61.849254 -409.079954)
		(end 61.849254 -409.759658)
		(width 0.12954)
		(layer "B.Cu")
		(net "P5E_CPU1_P1_TX_BUF_C_DN<4>")
	)
	(segment
		(start 61.849254 -409.759658)
		(end 61.578744 -410.030168)
		(width 0.12954)
		(layer "B.Cu")
		(net "P5E_CPU1_P1_TX_BUF_C_DN<4>")
	)
	(segment
		(start 61.96838 -413.215582)
		(end 65.658746 -417.682934)
		(width 0.14224)
		(layer "In6.Cu")
		(net "P5E_CPU1_P1_TX_BUF_C_DN<4>")
	)
	(segment
		(start 61.578744 -410.030168)
		(end 61.869574 -410.320998)
		(width 0.14224)
		(layer "In6.Cu")
		(net "P5E_CPU1_P1_TX_BUF_C_DN<4>")
	)
	(segment
		(start 66.5226 -426.830998)
		(end 66.649854 -426.958252)
		(width 0.14224)
		(layer "In6.Cu")
		(net "P5E_CPU1_P1_TX_BUF_C_DN<4>")
	)
	(segment
		(start 66.086736 -426.830998)
		(end 66.5226 -426.830998)
		(width 0.14224)
		(layer "In6.Cu")
		(net "P5E_CPU1_P1_TX_BUF_C_DN<4>")
	)
	(segment
		(start 66.649854 -426.958252)
		(end 66.649854 -427.289976)
		(width 0.14224)
		(layer "In6.Cu")
		(net "P5E_CPU1_P1_TX_BUF_C_DN<4>")
	)
	(segment
		(start 61.869574 -410.320998)
		(end 61.869574 -412.939484)
		(width 0.14224)
		(layer "In6.Cu")
		(net "P5E_CPU1_P1_TX_BUF_C_DN<4>")
	)
	(segment
		(start 65.687956 -417.76396)
		(end 65.687956 -426.432218)
		(width 0.14224)
		(layer "In6.Cu")
		(net "P5E_CPU1_P1_TX_BUF_C_DN<4>")
	)
	(segment
		(start 65.687956 -426.432218)
		(end 66.086736 -426.830998)
		(width 0.14224)
		(layer "In6.Cu")
		(net "P5E_CPU1_P1_TX_BUF_C_DN<4>")
	)
	(arc
		(start 61.869574 -412.939484)
		(mid 61.894944 -413.08613)
		(end 61.96838 -413.215582)
		(width 0.14224)
		(layer "In6.Cu")
		(net "P5E_CPU1_P1_TX_BUF_C_DN<4>")
	)
	(arc
		(start 65.658746 -417.682934)
		(mid 65.680428 -417.720895)
		(end 65.687956 -417.76396)
		(width 0.14224)
		(layer "In6.Cu")
		(net "P5E_CPU1_P1_TX_BUF_C_DN<4>")
	)
	(segment
		(start 58.786014 -409.759658)
		(end 58.515504 -410.030168)
		(width 0.12954)
		(layer "B.Cu")
		(net "P5E_CPU1_P1_TX_BUF_C_DN<3>")
	)
	(segment
		(start 58.786014 -409.079954)
		(end 58.786014 -409.759658)
		(width 0.12954)
		(layer "B.Cu")
		(net "P5E_CPU1_P1_TX_BUF_C_DN<3>")
	)
	(segment
		(start 58.490104 -408.784044)
		(end 58.786014 -409.079954)
		(width 0.12954)
		(layer "B.Cu")
		(net "P5E_CPU1_P1_TX_BUF_C_DN<3>")
	)
	(segment
		(start 58.806334 -410.320998)
		(end 58.806334 -413.062674)
		(width 0.14224)
		(layer "In6.Cu")
		(net "P5E_CPU1_P1_TX_BUF_C_DN<3>")
	)
	(segment
		(start 58.938668 -413.364172)
		(end 63.646812 -417.68522)
		(width 0.14224)
		(layer "In6.Cu")
		(net "P5E_CPU1_P1_TX_BUF_C_DN<3>")
	)
	(segment
		(start 63.68796 -427.497494)
		(end 64.021208 -427.830742)
		(width 0.14224)
		(layer "In6.Cu")
		(net "P5E_CPU1_P1_TX_BUF_C_DN<3>")
	)
	(segment
		(start 64.021208 -427.830742)
		(end 64.522604 -427.830742)
		(width 0.14224)
		(layer "In6.Cu")
		(net "P5E_CPU1_P1_TX_BUF_C_DN<3>")
	)
	(segment
		(start 63.68796 -417.778692)
		(end 63.68796 -427.497494)
		(width 0.14224)
		(layer "In6.Cu")
		(net "P5E_CPU1_P1_TX_BUF_C_DN<3>")
	)
	(segment
		(start 58.515504 -410.030168)
		(end 58.806334 -410.320998)
		(width 0.14224)
		(layer "In6.Cu")
		(net "P5E_CPU1_P1_TX_BUF_C_DN<3>")
	)
	(segment
		(start 64.649858 -427.957996)
		(end 64.649858 -428.28972)
		(width 0.14224)
		(layer "In6.Cu")
		(net "P5E_CPU1_P1_TX_BUF_C_DN<3>")
	)
	(segment
		(start 64.522604 -427.830742)
		(end 64.649858 -427.957996)
		(width 0.14224)
		(layer "In6.Cu")
		(net "P5E_CPU1_P1_TX_BUF_C_DN<3>")
	)
	(arc
		(start 58.806334 -413.062674)
		(mid 58.840815 -413.227336)
		(end 58.938668 -413.364172)
		(width 0.14224)
		(layer "In6.Cu")
		(net "P5E_CPU1_P1_TX_BUF_C_DN<3>")
	)
	(arc
		(start 63.646812 -417.68522)
		(mid 63.677243 -417.727629)
		(end 63.68796 -417.778692)
		(width 0.14224)
		(layer "In6.Cu")
		(net "P5E_CPU1_P1_TX_BUF_C_DN<3>")
	)
	(segment
		(start 55.722774 -409.759658)
		(end 55.452264 -410.030168)
		(width 0.12954)
		(layer "B.Cu")
		(net "P5E_CPU1_P1_TX_BUF_C_DN<2>")
	)
	(segment
		(start 55.722774 -409.079954)
		(end 55.722774 -409.759658)
		(width 0.12954)
		(layer "B.Cu")
		(net "P5E_CPU1_P1_TX_BUF_C_DN<2>")
	)
	(segment
		(start 55.426864 -408.784044)
		(end 55.722774 -409.079954)
		(width 0.12954)
		(layer "B.Cu")
		(net "P5E_CPU1_P1_TX_BUF_C_DN<2>")
	)
	(segment
		(start 61.687964 -417.570412)
		(end 61.687964 -426.432218)
		(width 0.14224)
		(layer "In6.Cu")
		(net "P5E_CPU1_P1_TX_BUF_C_DN<2>")
	)
	(segment
		(start 62.086744 -426.830998)
		(end 62.522608 -426.830998)
		(width 0.14224)
		(layer "In6.Cu")
		(net "P5E_CPU1_P1_TX_BUF_C_DN<2>")
	)
	(segment
		(start 55.743094 -410.320998)
		(end 55.743094 -413.178498)
		(width 0.14224)
		(layer "In6.Cu")
		(net "P5E_CPU1_P1_TX_BUF_C_DN<2>")
	)
	(segment
		(start 62.649862 -426.958252)
		(end 62.649862 -427.289976)
		(width 0.14224)
		(layer "In6.Cu")
		(net "P5E_CPU1_P1_TX_BUF_C_DN<2>")
	)
	(segment
		(start 62.522608 -426.830998)
		(end 62.649862 -426.958252)
		(width 0.14224)
		(layer "In6.Cu")
		(net "P5E_CPU1_P1_TX_BUF_C_DN<2>")
	)
	(segment
		(start 61.687964 -426.432218)
		(end 62.086744 -426.830998)
		(width 0.14224)
		(layer "In6.Cu")
		(net "P5E_CPU1_P1_TX_BUF_C_DN<2>")
	)
	(segment
		(start 55.924704 -413.518604)
		(end 61.521086 -417.258246)
		(width 0.14224)
		(layer "In6.Cu")
		(net "P5E_CPU1_P1_TX_BUF_C_DN<2>")
	)
	(segment
		(start 55.452264 -410.030168)
		(end 55.743094 -410.320998)
		(width 0.14224)
		(layer "In6.Cu")
		(net "P5E_CPU1_P1_TX_BUF_C_DN<2>")
	)
	(arc
		(start 61.521086 -417.258246)
		(mid 61.643626 -417.393426)
		(end 61.687964 -417.570412)
		(width 0.14224)
		(layer "In6.Cu")
		(net "P5E_CPU1_P1_TX_BUF_C_DN<2>")
	)
	(arc
		(start 55.743094 -413.178498)
		(mid 55.791346 -413.371269)
		(end 55.924704 -413.518604)
		(width 0.14224)
		(layer "In6.Cu")
		(net "P5E_CPU1_P1_TX_BUF_C_DN<2>")
	)
	(segment
		(start 52.659534 -409.759658)
		(end 52.389024 -410.030168)
		(width 0.12954)
		(layer "B.Cu")
		(net "P5E_CPU1_P1_TX_BUF_C_DN<1>")
	)
	(segment
		(start 52.659534 -409.079954)
		(end 52.659534 -409.759658)
		(width 0.12954)
		(layer "B.Cu")
		(net "P5E_CPU1_P1_TX_BUF_C_DN<1>")
	)
	(segment
		(start 52.363624 -408.784044)
		(end 52.659534 -409.079954)
		(width 0.12954)
		(layer "B.Cu")
		(net "P5E_CPU1_P1_TX_BUF_C_DN<1>")
	)
	(segment
		(start 56.839358 -415.702496)
		(end 56.839358 -415.702242)
		(width 0.14224)
		(layer "In6.Cu")
		(net "P5E_CPU1_P1_TX_BUF_C_DN<1>")
	)
	(segment
		(start 56.839358 -415.702242)
		(end 59.497722 -417.123118)
		(width 0.14224)
		(layer "In6.Cu")
		(net "P5E_CPU1_P1_TX_BUF_C_DN<1>")
	)
	(segment
		(start 60.522612 -427.830742)
		(end 60.649866 -427.957996)
		(width 0.14224)
		(layer "In6.Cu")
		(net "P5E_CPU1_P1_TX_BUF_C_DN<1>")
	)
	(segment
		(start 52.972462 -413.635444)
		(end 56.839358 -415.702496)
		(width 0.14224)
		(layer "In6.Cu")
		(net "P5E_CPU1_P1_TX_BUF_C_DN<1>")
	)
	(segment
		(start 59.687968 -427.497494)
		(end 60.021216 -427.830742)
		(width 0.14224)
		(layer "In6.Cu")
		(net "P5E_CPU1_P1_TX_BUF_C_DN<1>")
	)
	(segment
		(start 60.021216 -427.830742)
		(end 60.522612 -427.830742)
		(width 0.14224)
		(layer "In6.Cu")
		(net "P5E_CPU1_P1_TX_BUF_C_DN<1>")
	)
	(segment
		(start 59.687968 -417.440618)
		(end 59.687968 -427.497494)
		(width 0.14224)
		(layer "In6.Cu")
		(net "P5E_CPU1_P1_TX_BUF_C_DN<1>")
	)
	(segment
		(start 60.649866 -427.957996)
		(end 60.649866 -428.28972)
		(width 0.14224)
		(layer "In6.Cu")
		(net "P5E_CPU1_P1_TX_BUF_C_DN<1>")
	)
	(segment
		(start 52.679854 -410.320998)
		(end 52.679854 -413.147002)
		(width 0.14224)
		(layer "In6.Cu")
		(net "P5E_CPU1_P1_TX_BUF_C_DN<1>")
	)
	(segment
		(start 52.389024 -410.030168)
		(end 52.679854 -410.320998)
		(width 0.14224)
		(layer "In6.Cu")
		(net "P5E_CPU1_P1_TX_BUF_C_DN<1>")
	)
	(arc
		(start 59.497722 -417.123118)
		(mid 59.636724 -417.255566)
		(end 59.687968 -417.440618)
		(width 0.14224)
		(layer "In6.Cu")
		(net "P5E_CPU1_P1_TX_BUF_C_DN<1>")
	)
	(arc
		(start 52.679854 -413.147002)
		(mid 52.758603 -413.431692)
		(end 52.972462 -413.635444)
		(width 0.14224)
		(layer "In6.Cu")
		(net "P5E_CPU1_P1_TX_BUF_C_DN<1>")
	)
	(segment
		(start 95.544894 -409.079954)
		(end 95.544894 -409.759658)
		(width 0.12954)
		(layer "B.Cu")
		(net "P5E_CPU1_P1_TX_BUF_C_DN<15>")
	)
	(segment
		(start 95.544894 -409.759658)
		(end 95.274384 -410.030168)
		(width 0.12954)
		(layer "B.Cu")
		(net "P5E_CPU1_P1_TX_BUF_C_DN<15>")
	)
	(segment
		(start 95.248984 -408.784044)
		(end 95.544894 -409.079954)
		(width 0.12954)
		(layer "B.Cu")
		(net "P5E_CPU1_P1_TX_BUF_C_DN<15>")
	)
	(segment
		(start 95.565214 -410.320998)
		(end 95.565214 -413.14624)
		(width 0.14224)
		(layer "In6.Cu")
		(net "P5E_CPU1_P1_TX_BUF_C_DN<15>")
	)
	(segment
		(start 88.688164 -427.497494)
		(end 89.021412 -427.830742)
		(width 0.14224)
		(layer "In6.Cu")
		(net "P5E_CPU1_P1_TX_BUF_C_DN<15>")
	)
	(segment
		(start 89.650062 -427.957996)
		(end 89.650062 -428.28972)
		(width 0.14224)
		(layer "In6.Cu")
		(net "P5E_CPU1_P1_TX_BUF_C_DN<15>")
	)
	(segment
		(start 89.021412 -427.830742)
		(end 89.522808 -427.830742)
		(width 0.14224)
		(layer "In6.Cu")
		(net "P5E_CPU1_P1_TX_BUF_C_DN<15>")
	)
	(segment
		(start 88.688164 -424.256454)
		(end 88.688164 -427.497494)
		(width 0.14224)
		(layer "In6.Cu")
		(net "P5E_CPU1_P1_TX_BUF_C_DN<15>")
	)
	(segment
		(start 95.565214 -413.14624)
		(end 95.393002 -413.713676)
		(width 0.14224)
		(layer "In6.Cu")
		(net "P5E_CPU1_P1_TX_BUF_C_DN<15>")
	)
	(segment
		(start 95.393002 -413.713676)
		(end 88.970104 -423.326306)
		(width 0.14224)
		(layer "In6.Cu")
		(net "P5E_CPU1_P1_TX_BUF_C_DN<15>")
	)
	(segment
		(start 95.274384 -410.030168)
		(end 95.565214 -410.320998)
		(width 0.14224)
		(layer "In6.Cu")
		(net "P5E_CPU1_P1_TX_BUF_C_DN<15>")
	)
	(segment
		(start 89.522808 -427.830742)
		(end 89.650062 -427.957996)
		(width 0.14224)
		(layer "In6.Cu")
		(net "P5E_CPU1_P1_TX_BUF_C_DN<15>")
	)
	(arc
		(start 88.970104 -423.326306)
		(mid 88.760124 -423.770462)
		(end 88.688164 -424.256454)
		(width 0.14224)
		(layer "In6.Cu")
		(net "P5E_CPU1_P1_TX_BUF_C_DN<15>")
	)
	(segment
		(start 92.481654 -409.759658)
		(end 92.211144 -410.030168)
		(width 0.12954)
		(layer "B.Cu")
		(net "P5E_CPU1_P1_TX_BUF_C_DN<14>")
	)
	(segment
		(start 92.481654 -409.079954)
		(end 92.481654 -409.759658)
		(width 0.12954)
		(layer "B.Cu")
		(net "P5E_CPU1_P1_TX_BUF_C_DN<14>")
	)
	(segment
		(start 92.185744 -408.784044)
		(end 92.481654 -409.079954)
		(width 0.12954)
		(layer "B.Cu")
		(net "P5E_CPU1_P1_TX_BUF_C_DN<14>")
	)
	(segment
		(start 92.501974 -413.417258)
		(end 86.876382 -423.942256)
		(width 0.14224)
		(layer "In6.Cu")
		(net "P5E_CPU1_P1_TX_BUF_C_DN<14>")
	)
	(segment
		(start 86.688168 -426.432218)
		(end 87.086948 -426.830998)
		(width 0.14224)
		(layer "In6.Cu")
		(net "P5E_CPU1_P1_TX_BUF_C_DN<14>")
	)
	(segment
		(start 87.650066 -426.958252)
		(end 87.650066 -427.289976)
		(width 0.14224)
		(layer "In6.Cu")
		(net "P5E_CPU1_P1_TX_BUF_C_DN<14>")
	)
	(segment
		(start 87.522812 -426.830998)
		(end 87.650066 -426.958252)
		(width 0.14224)
		(layer "In6.Cu")
		(net "P5E_CPU1_P1_TX_BUF_C_DN<14>")
	)
	(segment
		(start 86.688168 -424.69435)
		(end 86.688168 -426.432218)
		(width 0.14224)
		(layer "In6.Cu")
		(net "P5E_CPU1_P1_TX_BUF_C_DN<14>")
	)
	(segment
		(start 92.501974 -410.320998)
		(end 92.501974 -413.417258)
		(width 0.14224)
		(layer "In6.Cu")
		(net "P5E_CPU1_P1_TX_BUF_C_DN<14>")
	)
	(segment
		(start 87.086948 -426.830998)
		(end 87.522812 -426.830998)
		(width 0.14224)
		(layer "In6.Cu")
		(net "P5E_CPU1_P1_TX_BUF_C_DN<14>")
	)
	(segment
		(start 92.211144 -410.030168)
		(end 92.501974 -410.320998)
		(width 0.14224)
		(layer "In6.Cu")
		(net "P5E_CPU1_P1_TX_BUF_C_DN<14>")
	)
	(arc
		(start 86.876382 -423.942256)
		(mid 86.735916 -424.306701)
		(end 86.688168 -424.69435)
		(width 0.14224)
		(layer "In6.Cu")
		(net "P5E_CPU1_P1_TX_BUF_C_DN<14>")
	)
	(segment
		(start 89.122504 -408.784044)
		(end 89.418414 -409.079954)
		(width 0.12954)
		(layer "B.Cu")
		(net "P5E_CPU1_P1_TX_BUF_C_DN<13>")
	)
	(segment
		(start 89.418414 -409.759658)
		(end 89.147904 -410.030168)
		(width 0.12954)
		(layer "B.Cu")
		(net "P5E_CPU1_P1_TX_BUF_C_DN<13>")
	)
	(segment
		(start 89.418414 -409.079954)
		(end 89.418414 -409.759658)
		(width 0.12954)
		(layer "B.Cu")
		(net "P5E_CPU1_P1_TX_BUF_C_DN<13>")
	)
	(segment
		(start 89.003632 -414.110424)
		(end 88.456008 -415.135314)
		(width 0.14224)
		(layer "In6.Cu")
		(net "P5E_CPU1_P1_TX_BUF_C_DN<13>")
	)
	(segment
		(start 85.65007 -427.957996)
		(end 85.65007 -428.28972)
		(width 0.14224)
		(layer "In6.Cu")
		(net "P5E_CPU1_P1_TX_BUF_C_DN<13>")
	)
	(segment
		(start 89.147904 -410.030168)
		(end 89.438734 -410.320998)
		(width 0.14224)
		(layer "In6.Cu")
		(net "P5E_CPU1_P1_TX_BUF_C_DN<13>")
	)
	(segment
		(start 84.688172 -427.497494)
		(end 85.02142 -427.830742)
		(width 0.14224)
		(layer "In6.Cu")
		(net "P5E_CPU1_P1_TX_BUF_C_DN<13>")
	)
	(segment
		(start 85.02142 -427.830742)
		(end 85.522816 -427.830742)
		(width 0.14224)
		(layer "In6.Cu")
		(net "P5E_CPU1_P1_TX_BUF_C_DN<13>")
	)
	(segment
		(start 89.428828 -413.083502)
		(end 89.428828 -413.083756)
		(width 0.14224)
		(layer "In6.Cu")
		(net "P5E_CPU1_P1_TX_BUF_C_DN<13>")
	)
	(segment
		(start 89.438734 -410.320998)
		(end 89.438734 -413.034734)
		(width 0.14224)
		(layer "In6.Cu")
		(net "P5E_CPU1_P1_TX_BUF_C_DN<13>")
	)
	(segment
		(start 84.688172 -424.671744)
		(end 84.688172 -427.497494)
		(width 0.14224)
		(layer "In6.Cu")
		(net "P5E_CPU1_P1_TX_BUF_C_DN<13>")
	)
	(segment
		(start 85.522816 -427.830742)
		(end 85.65007 -427.957996)
		(width 0.14224)
		(layer "In6.Cu")
		(net "P5E_CPU1_P1_TX_BUF_C_DN<13>")
	)
	(segment
		(start 89.428828 -413.083756)
		(end 89.003632 -414.110424)
		(width 0.14224)
		(layer "In6.Cu")
		(net "P5E_CPU1_P1_TX_BUF_C_DN<13>")
	)
	(segment
		(start 88.456008 -415.135314)
		(end 84.856574 -423.825162)
		(width 0.14224)
		(layer "In6.Cu")
		(net "P5E_CPU1_P1_TX_BUF_C_DN<13>")
	)
	(arc
		(start 89.438734 -413.034734)
		(mid 89.436184 -413.059606)
		(end 89.428828 -413.083502)
		(width 0.14224)
		(layer "In6.Cu")
		(net "P5E_CPU1_P1_TX_BUF_C_DN<13>")
	)
	(arc
		(start 84.856574 -423.825162)
		(mid 84.730673 -424.24016)
		(end 84.688172 -424.671744)
		(width 0.14224)
		(layer "In6.Cu")
		(net "P5E_CPU1_P1_TX_BUF_C_DN<13>")
	)
	(segment
		(start 86.059264 -408.784044)
		(end 86.355174 -409.079954)
		(width 0.12954)
		(layer "B.Cu")
		(net "P5E_CPU1_P1_TX_BUF_C_DN<12>")
	)
	(segment
		(start 86.355174 -409.759658)
		(end 86.084664 -410.030168)
		(width 0.12954)
		(layer "B.Cu")
		(net "P5E_CPU1_P1_TX_BUF_C_DN<12>")
	)
	(segment
		(start 86.355174 -409.079954)
		(end 86.355174 -409.759658)
		(width 0.12954)
		(layer "B.Cu")
		(net "P5E_CPU1_P1_TX_BUF_C_DN<12>")
	)
	(segment
		(start 84.978748 -417.663122)
		(end 83.339432 -423.067734)
		(width 0.14224)
		(layer "In6.Cu")
		(net "P5E_CPU1_P1_TX_BUF_C_DN<12>")
	)
	(segment
		(start 83.52282 -426.830998)
		(end 83.650074 -426.958252)
		(width 0.14224)
		(layer "In6.Cu")
		(net "P5E_CPU1_P1_TX_BUF_C_DN<12>")
	)
	(segment
		(start 82.688176 -426.432218)
		(end 83.086956 -426.830998)
		(width 0.14224)
		(layer "In6.Cu")
		(net "P5E_CPU1_P1_TX_BUF_C_DN<12>")
	)
	(segment
		(start 86.358984 -413.138366)
		(end 85.15731 -417.098988)
		(width 0.14224)
		(layer "In6.Cu")
		(net "P5E_CPU1_P1_TX_BUF_C_DN<12>")
	)
	(segment
		(start 83.650074 -426.958252)
		(end 83.650074 -427.289976)
		(width 0.14224)
		(layer "In6.Cu")
		(net "P5E_CPU1_P1_TX_BUF_C_DN<12>")
	)
	(segment
		(start 84.987638 -417.658296)
		(end 84.978748 -417.663122)
		(width 0.14224)
		(layer "In6.Cu")
		(net "P5E_CPU1_P1_TX_BUF_C_DN<12>")
	)
	(segment
		(start 85.15731 -417.098988)
		(end 85.157056 -417.09975)
		(width 0.14224)
		(layer "In6.Cu")
		(net "P5E_CPU1_P1_TX_BUF_C_DN<12>")
	)
	(segment
		(start 83.339432 -423.067734)
		(end 82.912712 -424.097958)
		(width 0.14224)
		(layer "In6.Cu")
		(net "P5E_CPU1_P1_TX_BUF_C_DN<12>")
	)
	(segment
		(start 83.086956 -426.830998)
		(end 83.52282 -426.830998)
		(width 0.14224)
		(layer "In6.Cu")
		(net "P5E_CPU1_P1_TX_BUF_C_DN<12>")
	)
	(segment
		(start 82.688176 -425.228512)
		(end 82.688176 -426.432218)
		(width 0.14224)
		(layer "In6.Cu")
		(net "P5E_CPU1_P1_TX_BUF_C_DN<12>")
	)
	(segment
		(start 86.084664 -410.030168)
		(end 86.375494 -410.320998)
		(width 0.14224)
		(layer "In6.Cu")
		(net "P5E_CPU1_P1_TX_BUF_C_DN<12>")
	)
	(segment
		(start 85.157056 -417.09975)
		(end 84.987638 -417.658296)
		(width 0.14224)
		(layer "In6.Cu")
		(net "P5E_CPU1_P1_TX_BUF_C_DN<12>")
	)
	(segment
		(start 86.375494 -413.028384)
		(end 86.37524 -413.028384)
		(width 0.14224)
		(layer "In6.Cu")
		(net "P5E_CPU1_P1_TX_BUF_C_DN<12>")
	)
	(segment
		(start 86.375494 -410.320998)
		(end 86.375494 -413.028384)
		(width 0.14224)
		(layer "In6.Cu")
		(net "P5E_CPU1_P1_TX_BUF_C_DN<12>")
	)
	(arc
		(start 82.912712 -424.097958)
		(mid 82.744778 -424.652178)
		(end 82.688176 -425.228512)
		(width 0.14224)
		(layer "In6.Cu")
		(net "P5E_CPU1_P1_TX_BUF_C_DN<12>")
	)
	(arc
		(start 86.37524 -413.028384)
		(mid 86.371147 -413.08397)
		(end 86.358984 -413.138366)
		(width 0.14224)
		(layer "In6.Cu")
		(net "P5E_CPU1_P1_TX_BUF_C_DN<12>")
	)
	(segment
		(start 83.291934 -409.079954)
		(end 83.291934 -409.759658)
		(width 0.12954)
		(layer "B.Cu")
		(net "P5E_CPU1_P1_TX_BUF_C_DN<11>")
	)
	(segment
		(start 83.291934 -409.759658)
		(end 83.021424 -410.030168)
		(width 0.12954)
		(layer "B.Cu")
		(net "P5E_CPU1_P1_TX_BUF_C_DN<11>")
	)
	(segment
		(start 82.996024 -408.784044)
		(end 83.291934 -409.079954)
		(width 0.12954)
		(layer "B.Cu")
		(net "P5E_CPU1_P1_TX_BUF_C_DN<11>")
	)
	(segment
		(start 81.021428 -427.830742)
		(end 81.522824 -427.830742)
		(width 0.14224)
		(layer "In6.Cu")
		(net "P5E_CPU1_P1_TX_BUF_C_DN<11>")
	)
	(segment
		(start 80.68818 -427.497494)
		(end 81.021428 -427.830742)
		(width 0.14224)
		(layer "In6.Cu")
		(net "P5E_CPU1_P1_TX_BUF_C_DN<11>")
	)
	(segment
		(start 83.312254 -410.320998)
		(end 83.312254 -413.154114)
		(width 0.14224)
		(layer "In6.Cu")
		(net "P5E_CPU1_P1_TX_BUF_C_DN<11>")
	)
	(segment
		(start 80.68818 -424.113198)
		(end 80.68818 -427.497494)
		(width 0.14224)
		(layer "In6.Cu")
		(net "P5E_CPU1_P1_TX_BUF_C_DN<11>")
	)
	(segment
		(start 81.522824 -427.830742)
		(end 81.650078 -427.957996)
		(width 0.14224)
		(layer "In6.Cu")
		(net "P5E_CPU1_P1_TX_BUF_C_DN<11>")
	)
	(segment
		(start 81.650078 -427.957996)
		(end 81.650078 -428.28972)
		(width 0.14224)
		(layer "In6.Cu")
		(net "P5E_CPU1_P1_TX_BUF_C_DN<11>")
	)
	(segment
		(start 83.021424 -410.030168)
		(end 83.312254 -410.320998)
		(width 0.14224)
		(layer "In6.Cu")
		(net "P5E_CPU1_P1_TX_BUF_C_DN<11>")
	)
	(segment
		(start 83.268566 -413.50819)
		(end 80.761586 -423.517314)
		(width 0.14224)
		(layer "In6.Cu")
		(net "P5E_CPU1_P1_TX_BUF_C_DN<11>")
	)
	(arc
		(start 83.312254 -413.154114)
		(mid 83.301296 -413.332496)
		(end 83.268566 -413.50819)
		(width 0.14224)
		(layer "In6.Cu")
		(net "P5E_CPU1_P1_TX_BUF_C_DN<11>")
	)
	(arc
		(start 80.761586 -423.517314)
		(mid 80.706566 -423.813)
		(end 80.68818 -424.113198)
		(width 0.14224)
		(layer "In6.Cu")
		(net "P5E_CPU1_P1_TX_BUF_C_DN<11>")
	)
	(segment
		(start 79.932784 -408.784044)
		(end 80.228694 -409.079954)
		(width 0.12954)
		(layer "B.Cu")
		(net "P5E_CPU1_P1_TX_BUF_C_DN<10>")
	)
	(segment
		(start 80.228694 -409.759658)
		(end 79.958184 -410.030168)
		(width 0.12954)
		(layer "B.Cu")
		(net "P5E_CPU1_P1_TX_BUF_C_DN<10>")
	)
	(segment
		(start 80.228694 -409.079954)
		(end 80.228694 -409.759658)
		(width 0.12954)
		(layer "B.Cu")
		(net "P5E_CPU1_P1_TX_BUF_C_DN<10>")
	)
	(segment
		(start 79.551022 -417.933124)
		(end 80.249014 -413.22752)
		(width 0.14224)
		(layer "In6.Cu")
		(net "P5E_CPU1_P1_TX_BUF_C_DN<10>")
	)
	(segment
		(start 80.249014 -410.320998)
		(end 79.958184 -410.030168)
		(width 0.14224)
		(layer "In6.Cu")
		(net "P5E_CPU1_P1_TX_BUF_C_DN<10>")
	)
	(segment
		(start 80.249014 -413.22752)
		(end 80.249014 -410.320998)
		(width 0.14224)
		(layer "In6.Cu")
		(net "P5E_CPU1_P1_TX_BUF_C_DN<10>")
	)
	(segment
		(start 79.650082 -426.958252)
		(end 79.522828 -426.830998)
		(width 0.14224)
		(layer "In6.Cu")
		(net "P5E_CPU1_P1_TX_BUF_C_DN<10>")
	)
	(segment
		(start 79.398876 -418.956236)
		(end 79.550514 -417.933378)
		(width 0.14224)
		(layer "In6.Cu")
		(net "P5E_CPU1_P1_TX_BUF_C_DN<10>")
	)
	(segment
		(start 78.688184 -423.749978)
		(end 79.398368 -418.956744)
		(width 0.14224)
		(layer "In6.Cu")
		(net "P5E_CPU1_P1_TX_BUF_C_DN<10>")
	)
	(segment
		(start 79.086964 -426.830998)
		(end 78.688184 -426.432218)
		(width 0.14224)
		(layer "In6.Cu")
		(net "P5E_CPU1_P1_TX_BUF_C_DN<10>")
	)
	(segment
		(start 79.522828 -426.830998)
		(end 79.086964 -426.830998)
		(width 0.14224)
		(layer "In6.Cu")
		(net "P5E_CPU1_P1_TX_BUF_C_DN<10>")
	)
	(segment
		(start 78.688184 -426.432218)
		(end 78.688184 -423.749978)
		(width 0.14224)
		(layer "In6.Cu")
		(net "P5E_CPU1_P1_TX_BUF_C_DN<10>")
	)
	(segment
		(start 79.650082 -427.289976)
		(end 79.650082 -426.958252)
		(width 0.14224)
		(layer "In6.Cu")
		(net "P5E_CPU1_P1_TX_BUF_C_DN<10>")
	)
	(segment
		(start 79.398368 -418.956744)
		(end 79.398876 -418.956236)
		(width 0.14224)
		(layer "In6.Cu")
		(net "P5E_CPU1_P1_TX_BUF_C_DN<10>")
	)
	(segment
		(start 79.550514 -417.933378)
		(end 79.551022 -417.933124)
		(width 0.14224)
		(layer "In6.Cu")
		(net "P5E_CPU1_P1_TX_BUF_C_DN<10>")
	)
	(segment
		(start 49.596294 -409.079954)
		(end 49.596294 -409.759658)
		(width 0.12954)
		(layer "B.Cu")
		(net "P5E_CPU1_P1_TX_BUF_C_DN<0>")
	)
	(segment
		(start 49.596294 -409.759658)
		(end 49.325784 -410.030168)
		(width 0.12954)
		(layer "B.Cu")
		(net "P5E_CPU1_P1_TX_BUF_C_DN<0>")
	)
	(segment
		(start 49.300384 -408.784044)
		(end 49.596294 -409.079954)
		(width 0.12954)
		(layer "B.Cu")
		(net "P5E_CPU1_P1_TX_BUF_C_DN<0>")
	)
	(segment
		(start 49.616614 -410.320998)
		(end 49.616614 -413.404304)
		(width 0.14224)
		(layer "In6.Cu")
		(net "P5E_CPU1_P1_TX_BUF_C_DN<0>")
	)
	(segment
		(start 58.64987 -426.958252)
		(end 58.64987 -427.289976)
		(width 0.14224)
		(layer "In6.Cu")
		(net "P5E_CPU1_P1_TX_BUF_C_DN<0>")
	)
	(segment
		(start 52.807616 -417.964874)
		(end 52.80787 -417.96462)
		(width 0.14224)
		(layer "In6.Cu")
		(net "P5E_CPU1_P1_TX_BUF_C_DN<0>")
	)
	(segment
		(start 58.522616 -426.830998)
		(end 58.64987 -426.958252)
		(width 0.14224)
		(layer "In6.Cu")
		(net "P5E_CPU1_P1_TX_BUF_C_DN<0>")
	)
	(segment
		(start 52.80787 -417.96462)
		(end 53.472842 -418.861494)
		(width 0.14224)
		(layer "In6.Cu")
		(net "P5E_CPU1_P1_TX_BUF_C_DN<0>")
	)
	(segment
		(start 49.770284 -413.87014)
		(end 52.807616 -417.964874)
		(width 0.14224)
		(layer "In6.Cu")
		(net "P5E_CPU1_P1_TX_BUF_C_DN<0>")
	)
	(segment
		(start 53.472842 -418.861494)
		(end 57.4929 -426.610526)
		(width 0.14224)
		(layer "In6.Cu")
		(net "P5E_CPU1_P1_TX_BUF_C_DN<0>")
	)
	(segment
		(start 57.85612 -426.830998)
		(end 58.522616 -426.830998)
		(width 0.14224)
		(layer "In6.Cu")
		(net "P5E_CPU1_P1_TX_BUF_C_DN<0>")
	)
	(segment
		(start 49.325784 -410.030168)
		(end 49.616614 -410.320998)
		(width 0.14224)
		(layer "In6.Cu")
		(net "P5E_CPU1_P1_TX_BUF_C_DN<0>")
	)
	(arc
		(start 57.4929 -426.610526)
		(mid 57.64366 -426.77156)
		(end 57.85612 -426.830998)
		(width 0.14224)
		(layer "In6.Cu")
		(net "P5E_CPU1_P1_TX_BUF_C_DN<0>")
	)
	(arc
		(start 49.616614 -413.404304)
		(mid 49.655987 -413.649579)
		(end 49.770284 -413.87014)
		(width 0.14224)
		(layer "In6.Cu")
		(net "P5E_CPU1_P1_TX_BUF_C_DN<0>")
	)
	(segment
		(start 90.530426 -391.36574)
		(end 90.530426 -391.488676)
		(width 0.1016)
		(layer "F.Cu")
		(net "P5E_CPU1_P1_RX_BUF_DP<9>")
	)
	(segment
		(start 91.00566 -392.977116)
		(end 91.144344 -393.1158)
		(width 0.1016)
		(layer "F.Cu")
		(net "P5E_CPU1_P1_RX_BUF_DP<9>")
	)
	(segment
		(start 90.459306 -392.723878)
		(end 90.712544 -392.977116)
		(width 0.1016)
		(layer "F.Cu")
		(net "P5E_CPU1_P1_RX_BUF_DP<9>")
	)
	(segment
		(start 90.445844 -391.281158)
		(end 90.530426 -391.36574)
		(width 0.1016)
		(layer "F.Cu")
		(net "P5E_CPU1_P1_RX_BUF_DP<9>")
	)
	(segment
		(start 90.530426 -391.488676)
		(end 90.459306 -391.559796)
		(width 0.1016)
		(layer "F.Cu")
		(net "P5E_CPU1_P1_RX_BUF_DP<9>")
	)
	(segment
		(start 90.459306 -391.559796)
		(end 90.459306 -392.723878)
		(width 0.1016)
		(layer "F.Cu")
		(net "P5E_CPU1_P1_RX_BUF_DP<9>")
	)
	(segment
		(start 91.144344 -393.1158)
		(end 91.144344 -393.292838)
		(width 0.1016)
		(layer "F.Cu")
		(net "P5E_CPU1_P1_RX_BUF_DP<9>")
	)
	(segment
		(start 90.712544 -392.977116)
		(end 91.00566 -392.977116)
		(width 0.1016)
		(layer "F.Cu")
		(net "P5E_CPU1_P1_RX_BUF_DP<9>")
	)
	(segment
		(start 78.999334 -407.532078)
		(end 78.999334 -406.638252)
		(width 0.14224)
		(layer "In13.Cu")
		(net "P5E_CPU1_P1_RX_BUF_DP<9>")
	)
	(segment
		(start 90.685366 -393.159996)
		(end 90.827606 -393.017756)
		(width 0.14224)
		(layer "In13.Cu")
		(net "P5E_CPU1_P1_RX_BUF_DP<9>")
	)
	(segment
		(start 76.971144 -417.09086)
		(end 76.971144 -415.062162)
		(width 0.14224)
		(layer "In13.Cu")
		(net "P5E_CPU1_P1_RX_BUF_DP<9>")
	)
	(segment
		(start 87.209884 -399.810732)
		(end 87.209884 -399.61693)
		(width 0.14224)
		(layer "In13.Cu")
		(net "P5E_CPU1_P1_RX_BUF_DP<9>")
	)
	(segment
		(start 88.007444 -398.81937)
		(end 88.425782 -398.401286)
		(width 0.14224)
		(layer "In13.Cu")
		(net "P5E_CPU1_P1_RX_BUF_DP<9>")
	)
	(segment
		(start 79.136494 -407.669238)
		(end 78.999334 -407.532078)
		(width 0.14224)
		(layer "In13.Cu")
		(net "P5E_CPU1_P1_RX_BUF_DP<9>")
	)
	(segment
		(start 82.119978 -402.67128)
		(end 82.299048 -402.745702)
		(width 0.14224)
		(layer "In13.Cu")
		(net "P5E_CPU1_P1_RX_BUF_DP<9>")
	)
	(segment
		(start 88.889332 -398.052544)
		(end 89.16035 -397.722598)
		(width 0.14224)
		(layer "In13.Cu")
		(net "P5E_CPU1_P1_RX_BUF_DP<9>")
	)
	(segment
		(start 91.017344 -393.017756)
		(end 91.144344 -393.144756)
		(width 0.14224)
		(layer "In13.Cu")
		(net "P5E_CPU1_P1_RX_BUF_DP<9>")
	)
	(segment
		(start 83.839304 -401.95881)
		(end 84.643722 -401.625562)
		(width 0.14224)
		(layer "In13.Cu")
		(net "P5E_CPU1_P1_RX_BUF_DP<9>")
	)
	(segment
		(start 77.275182 -434.756814)
		(end 76.976478 -434.45811)
		(width 0.14224)
		(layer "In13.Cu")
		(net "P5E_CPU1_P1_RX_BUF_DP<9>")
	)
	(segment
		(start 85.213952 -401.302474)
		(end 86.41207 -400.414236)
		(width 0.14224)
		(layer "In13.Cu")
		(net "P5E_CPU1_P1_RX_BUF_DP<9>")
	)
	(segment
		(start 83.191604 -402.227288)
		(end 83.370674 -402.301456)
		(width 0.14224)
		(layer "In13.Cu")
		(net "P5E_CPU1_P1_RX_BUF_DP<9>")
	)
	(segment
		(start 76.971144 -418.83838)
		(end 77.108304 -418.70122)
		(width 0.14224)
		(layer "In13.Cu")
		(net "P5E_CPU1_P1_RX_BUF_DP<9>")
	)
	(segment
		(start 87.209884 -399.61693)
		(end 87.511636 -399.315432)
		(width 0.14224)
		(layer "In13.Cu")
		(net "P5E_CPU1_P1_RX_BUF_DP<9>")
	)
	(segment
		(start 76.971144 -426.873162)
		(end 76.971144 -419.88486)
		(width 0.14224)
		(layer "In13.Cu")
		(net "P5E_CPU1_P1_RX_BUF_DP<9>")
	)
	(segment
		(start 77.650086 -434.618638)
		(end 77.51191 -434.756814)
		(width 0.14224)
		(layer "In13.Cu")
		(net "P5E_CPU1_P1_RX_BUF_DP<9>")
	)
	(segment
		(start 90.827606 -393.017756)
		(end 91.017344 -393.017756)
		(width 0.14224)
		(layer "In13.Cu")
		(net "P5E_CPU1_P1_RX_BUF_DP<9>")
	)
	(segment
		(start 91.144344 -393.144756)
		(end 91.144344 -393.292838)
		(width 0.14224)
		(layer "In13.Cu")
		(net "P5E_CPU1_P1_RX_BUF_DP<9>")
	)
	(segment
		(start 76.976478 -426.878496)
		(end 76.971144 -426.873162)
		(width 0.14224)
		(layer "In13.Cu")
		(net "P5E_CPU1_P1_RX_BUF_DP<9>")
	)
	(segment
		(start 79.136494 -408.095958)
		(end 79.136494 -407.669238)
		(width 0.14224)
		(layer "In13.Cu")
		(net "P5E_CPU1_P1_RX_BUF_DP<9>")
	)
	(segment
		(start 77.108304 -418.70122)
		(end 77.108304 -418.31514)
		(width 0.14224)
		(layer "In13.Cu")
		(net "P5E_CPU1_P1_RX_BUF_DP<9>")
	)
	(segment
		(start 77.555344 -411.71495)
		(end 78.507844 -411.31998)
		(width 0.14224)
		(layer "In13.Cu")
		(net "P5E_CPU1_P1_RX_BUF_DP<9>")
	)
	(segment
		(start 77.108304 -418.31514)
		(end 76.971144 -418.17798)
		(width 0.14224)
		(layer "In13.Cu")
		(net "P5E_CPU1_P1_RX_BUF_DP<9>")
	)
	(segment
		(start 84.788756 -401.55495)
		(end 85.079332 -401.390358)
		(width 0.14224)
		(layer "In13.Cu")
		(net "P5E_CPU1_P1_RX_BUF_DP<9>")
	)
	(segment
		(start 79.866236 -405.771096)
		(end 80.181704 -405.560276)
		(width 0.14224)
		(layer "In13.Cu")
		(net "P5E_CPU1_P1_RX_BUF_DP<9>")
	)
	(segment
		(start 78.70825 -411.18282)
		(end 78.875636 -411.006798)
		(width 0.14224)
		(layer "In13.Cu")
		(net "P5E_CPU1_P1_RX_BUF_DP<9>")
	)
	(segment
		(start 78.999334 -409.360878)
		(end 79.136494 -409.223718)
		(width 0.14224)
		(layer "In13.Cu")
		(net "P5E_CPU1_P1_RX_BUF_DP<9>")
	)
	(segment
		(start 80.530954 -404.924514)
		(end 80.530954 -404.076154)
		(width 0.14224)
		(layer "In13.Cu")
		(net "P5E_CPU1_P1_RX_BUF_DP<9>")
	)
	(segment
		(start 81.72577 -402.834602)
		(end 82.119978 -402.67128)
		(width 0.14224)
		(layer "In13.Cu")
		(net "P5E_CPU1_P1_RX_BUF_DP<9>")
	)
	(segment
		(start 88.696292 -398.071594)
		(end 88.889332 -398.052544)
		(width 0.14224)
		(layer "In13.Cu")
		(net "P5E_CPU1_P1_RX_BUF_DP<9>")
	)
	(segment
		(start 89.16035 -397.722598)
		(end 89.141554 -397.529558)
		(width 0.14224)
		(layer "In13.Cu")
		(net "P5E_CPU1_P1_RX_BUF_DP<9>")
	)
	(segment
		(start 87.511636 -399.315432)
		(end 87.705438 -399.315432)
		(width 0.14224)
		(layer "In13.Cu")
		(net "P5E_CPU1_P1_RX_BUF_DP<9>")
	)
	(segment
		(start 77.108304 -419.36162)
		(end 76.971144 -419.22446)
		(width 0.14224)
		(layer "In13.Cu")
		(net "P5E_CPU1_P1_RX_BUF_DP<9>")
	)
	(segment
		(start 77.108304 -417.65474)
		(end 77.108304 -417.22802)
		(width 0.14224)
		(layer "In13.Cu")
		(net "P5E_CPU1_P1_RX_BUF_DP<9>")
	)
	(segment
		(start 90.285316 -396.13586)
		(end 90.616532 -395.64056)
		(width 0.14224)
		(layer "In13.Cu")
		(net "P5E_CPU1_P1_RX_BUF_DP<9>")
	)
	(segment
		(start 77.650086 -434.289962)
		(end 77.650086 -434.618638)
		(width 0.14224)
		(layer "In13.Cu")
		(net "P5E_CPU1_P1_RX_BUF_DP<9>")
	)
	(segment
		(start 76.971144 -419.88486)
		(end 77.108304 -419.7477)
		(width 0.14224)
		(layer "In13.Cu")
		(net "P5E_CPU1_P1_RX_BUF_DP<9>")
	)
	(segment
		(start 86.907624 -400.112738)
		(end 87.209884 -399.810732)
		(width 0.14224)
		(layer "In13.Cu")
		(net "P5E_CPU1_P1_RX_BUF_DP<9>")
	)
	(segment
		(start 90.685366 -395.41323)
		(end 90.685366 -393.159996)
		(width 0.14224)
		(layer "In13.Cu")
		(net "P5E_CPU1_P1_RX_BUF_DP<9>")
	)
	(segment
		(start 76.971144 -417.7919)
		(end 77.108304 -417.65474)
		(width 0.14224)
		(layer "In13.Cu")
		(net "P5E_CPU1_P1_RX_BUF_DP<9>")
	)
	(segment
		(start 77.108304 -419.7477)
		(end 77.108304 -419.36162)
		(width 0.14224)
		(layer "In13.Cu")
		(net "P5E_CPU1_P1_RX_BUF_DP<9>")
	)
	(segment
		(start 86.41207 -400.414236)
		(end 86.713822 -400.112738)
		(width 0.14224)
		(layer "In13.Cu")
		(net "P5E_CPU1_P1_RX_BUF_DP<9>")
	)
	(segment
		(start 78.999334 -408.659838)
		(end 78.999334 -408.233118)
		(width 0.14224)
		(layer "In13.Cu")
		(net "P5E_CPU1_P1_RX_BUF_DP<9>")
	)
	(segment
		(start 88.007444 -399.013426)
		(end 88.007444 -398.81937)
		(width 0.14224)
		(layer "In13.Cu")
		(net "P5E_CPU1_P1_RX_BUF_DP<9>")
	)
	(segment
		(start 77.467714 -413.863282)
		(end 77.467714 -411.84576)
		(width 0.14224)
		(layer "In13.Cu")
		(net "P5E_CPU1_P1_RX_BUF_DP<9>")
	)
	(segment
		(start 82.767678 -402.402802)
		(end 83.191604 -402.227288)
		(width 0.14224)
		(layer "In13.Cu")
		(net "P5E_CPU1_P1_RX_BUF_DP<9>")
	)
	(segment
		(start 77.51191 -434.756814)
		(end 77.275182 -434.756814)
		(width 0.14224)
		(layer "In13.Cu")
		(net "P5E_CPU1_P1_RX_BUF_DP<9>")
	)
	(segment
		(start 77.108304 -417.22802)
		(end 76.971144 -417.09086)
		(width 0.14224)
		(layer "In13.Cu")
		(net "P5E_CPU1_P1_RX_BUF_DP<9>")
	)
	(segment
		(start 79.136494 -409.223718)
		(end 79.136494 -408.796998)
		(width 0.14224)
		(layer "In13.Cu")
		(net "P5E_CPU1_P1_RX_BUF_DP<9>")
	)
	(segment
		(start 78.999334 -408.233118)
		(end 79.136494 -408.095958)
		(width 0.14224)
		(layer "In13.Cu")
		(net "P5E_CPU1_P1_RX_BUF_DP<9>")
	)
	(segment
		(start 89.141554 -397.529558)
		(end 90.285316 -396.13586)
		(width 0.14224)
		(layer "In13.Cu")
		(net "P5E_CPU1_P1_RX_BUF_DP<9>")
	)
	(segment
		(start 79.136494 -408.796998)
		(end 78.999334 -408.659838)
		(width 0.14224)
		(layer "In13.Cu")
		(net "P5E_CPU1_P1_RX_BUF_DP<9>")
	)
	(segment
		(start 76.971144 -418.17798)
		(end 76.971144 -417.7919)
		(width 0.14224)
		(layer "In13.Cu")
		(net "P5E_CPU1_P1_RX_BUF_DP<9>")
	)
	(segment
		(start 83.765136 -402.138134)
		(end 83.839304 -401.95881)
		(width 0.14224)
		(layer "In13.Cu")
		(net "P5E_CPU1_P1_RX_BUF_DP<9>")
	)
	(segment
		(start 80.181704 -405.560276)
		(end 80.328516 -405.413464)
		(width 0.14224)
		(layer "In13.Cu")
		(net "P5E_CPU1_P1_RX_BUF_DP<9>")
	)
	(segment
		(start 78.999334 -410.697172)
		(end 78.999334 -409.360878)
		(width 0.14224)
		(layer "In13.Cu")
		(net "P5E_CPU1_P1_RX_BUF_DP<9>")
	)
	(segment
		(start 76.976478 -434.45811)
		(end 76.976478 -426.878496)
		(width 0.14224)
		(layer "In13.Cu")
		(net "P5E_CPU1_P1_RX_BUF_DP<9>")
	)
	(segment
		(start 82.299048 -402.745702)
		(end 82.69351 -402.58238)
		(width 0.14224)
		(layer "In13.Cu")
		(net "P5E_CPU1_P1_RX_BUF_DP<9>")
	)
	(segment
		(start 83.370674 -402.301456)
		(end 83.765136 -402.138134)
		(width 0.14224)
		(layer "In13.Cu")
		(net "P5E_CPU1_P1_RX_BUF_DP<9>")
	)
	(segment
		(start 80.64627 -403.797516)
		(end 81.369662 -403.072854)
		(width 0.14224)
		(layer "In13.Cu")
		(net "P5E_CPU1_P1_RX_BUF_DP<9>")
	)
	(segment
		(start 88.425782 -398.401286)
		(end 88.696292 -398.071594)
		(width 0.14224)
		(layer "In13.Cu")
		(net "P5E_CPU1_P1_RX_BUF_DP<9>")
	)
	(segment
		(start 87.705438 -399.315432)
		(end 88.007444 -399.013426)
		(width 0.14224)
		(layer "In13.Cu")
		(net "P5E_CPU1_P1_RX_BUF_DP<9>")
	)
	(segment
		(start 85.212174 -401.303744)
		(end 85.213952 -401.302474)
		(width 0.14224)
		(layer "In13.Cu")
		(net "P5E_CPU1_P1_RX_BUF_DP<9>")
	)
	(segment
		(start 79.590646 -405.885142)
		(end 79.866236 -405.771096)
		(width 0.14224)
		(layer "In13.Cu")
		(net "P5E_CPU1_P1_RX_BUF_DP<9>")
	)
	(segment
		(start 86.713822 -400.112738)
		(end 86.907624 -400.112738)
		(width 0.14224)
		(layer "In13.Cu")
		(net "P5E_CPU1_P1_RX_BUF_DP<9>")
	)
	(segment
		(start 82.69351 -402.58238)
		(end 82.767678 -402.402802)
		(width 0.14224)
		(layer "In13.Cu")
		(net "P5E_CPU1_P1_RX_BUF_DP<9>")
	)
	(segment
		(start 76.971144 -419.22446)
		(end 76.971144 -418.83838)
		(width 0.14224)
		(layer "In13.Cu")
		(net "P5E_CPU1_P1_RX_BUF_DP<9>")
	)
	(arc
		(start 81.369662 -403.072854)
		(mid 81.535963 -402.936164)
		(end 81.72577 -402.834602)
		(width 0.14224)
		(layer "In13.Cu")
		(net "P5E_CPU1_P1_RX_BUF_DP<9>")
	)
	(arc
		(start 78.999334 -406.638252)
		(mid 79.052563 -406.370451)
		(end 79.204312 -406.14346)
		(width 0.14224)
		(layer "In13.Cu")
		(net "P5E_CPU1_P1_RX_BUF_DP<9>")
	)
	(arc
		(start 78.507844 -411.31998)
		(mid 78.615242 -411.261911)
		(end 78.70825 -411.18282)
		(width 0.14224)
		(layer "In13.Cu")
		(net "P5E_CPU1_P1_RX_BUF_DP<9>")
	)
	(arc
		(start 79.204312 -406.14346)
		(mid 79.384782 -405.995314)
		(end 79.590646 -405.885142)
		(width 0.14224)
		(layer "In13.Cu")
		(net "P5E_CPU1_P1_RX_BUF_DP<9>")
	)
	(arc
		(start 78.875636 -411.006798)
		(mid 78.967312 -410.863907)
		(end 78.999334 -410.697172)
		(width 0.14224)
		(layer "In13.Cu")
		(net "P5E_CPU1_P1_RX_BUF_DP<9>")
	)
	(arc
		(start 76.971144 -415.062162)
		(mid 77.025668 -414.788054)
		(end 77.180948 -414.555686)
		(width 0.14224)
		(layer "In13.Cu")
		(net "P5E_CPU1_P1_RX_BUF_DP<9>")
	)
	(arc
		(start 77.467714 -411.84576)
		(mid 77.491718 -411.767095)
		(end 77.555344 -411.71495)
		(width 0.14224)
		(layer "In13.Cu")
		(net "P5E_CPU1_P1_RX_BUF_DP<9>")
	)
	(arc
		(start 84.643722 -401.625562)
		(mid 84.717328 -401.592492)
		(end 84.788756 -401.55495)
		(width 0.14224)
		(layer "In13.Cu")
		(net "P5E_CPU1_P1_RX_BUF_DP<9>")
	)
	(arc
		(start 90.616532 -395.64056)
		(mid 90.667819 -395.532003)
		(end 90.685366 -395.41323)
		(width 0.14224)
		(layer "In13.Cu")
		(net "P5E_CPU1_P1_RX_BUF_DP<9>")
	)
	(arc
		(start 77.180948 -414.555686)
		(mid 77.393213 -414.238008)
		(end 77.467714 -413.863282)
		(width 0.14224)
		(layer "In13.Cu")
		(net "P5E_CPU1_P1_RX_BUF_DP<9>")
	)
	(arc
		(start 80.530954 -404.076154)
		(mid 80.560912 -403.925366)
		(end 80.64627 -403.797516)
		(width 0.14224)
		(layer "In13.Cu")
		(net "P5E_CPU1_P1_RX_BUF_DP<9>")
	)
	(arc
		(start 80.328516 -405.413464)
		(mid 80.478356 -405.189118)
		(end 80.530954 -404.924514)
		(width 0.14224)
		(layer "In13.Cu")
		(net "P5E_CPU1_P1_RX_BUF_DP<9>")
	)
	(arc
		(start 85.079332 -401.390358)
		(mid 85.14706 -401.349055)
		(end 85.212174 -401.303744)
		(width 0.14224)
		(layer "In13.Cu")
		(net "P5E_CPU1_P1_RX_BUF_DP<9>")
	)
	(segment
		(start 89.330276 -391.488676)
		(end 89.24163 -391.577322)
		(width 0.1016)
		(layer "F.Cu")
		(net "P5E_CPU1_P1_RX_BUF_DP<8>")
	)
	(segment
		(start 89.494868 -392.977116)
		(end 89.80551 -392.977116)
		(width 0.1016)
		(layer "F.Cu")
		(net "P5E_CPU1_P1_RX_BUF_DP<8>")
	)
	(segment
		(start 89.245694 -391.281158)
		(end 89.330276 -391.36574)
		(width 0.1016)
		(layer "F.Cu")
		(net "P5E_CPU1_P1_RX_BUF_DP<8>")
	)
	(segment
		(start 89.944448 -393.116054)
		(end 89.944448 -393.292838)
		(width 0.1016)
		(layer "F.Cu")
		(net "P5E_CPU1_P1_RX_BUF_DP<8>")
	)
	(segment
		(start 89.24163 -391.577322)
		(end 89.24163 -392.723878)
		(width 0.1016)
		(layer "F.Cu")
		(net "P5E_CPU1_P1_RX_BUF_DP<8>")
	)
	(segment
		(start 89.80551 -392.977116)
		(end 89.944448 -393.116054)
		(width 0.1016)
		(layer "F.Cu")
		(net "P5E_CPU1_P1_RX_BUF_DP<8>")
	)
	(segment
		(start 89.330276 -391.36574)
		(end 89.330276 -391.488676)
		(width 0.1016)
		(layer "F.Cu")
		(net "P5E_CPU1_P1_RX_BUF_DP<8>")
	)
	(segment
		(start 89.24163 -392.723878)
		(end 89.494868 -392.977116)
		(width 0.1016)
		(layer "F.Cu")
		(net "P5E_CPU1_P1_RX_BUF_DP<8>")
	)
	(segment
		(start 74.541634 -423.027602)
		(end 74.541634 -422.600882)
		(width 0.14224)
		(layer "In13.Cu")
		(net "P5E_CPU1_P1_RX_BUF_DP<8>")
	)
	(segment
		(start 79.519272 -402.570696)
		(end 79.698342 -402.645118)
		(width 0.14224)
		(layer "In13.Cu")
		(net "P5E_CPU1_P1_RX_BUF_DP<8>")
	)
	(segment
		(start 84.84997 -400.381724)
		(end 85.360256 -399.957798)
		(width 0.14224)
		(layer "In13.Cu")
		(net "P5E_CPU1_P1_RX_BUF_DP<8>")
	)
	(segment
		(start 74.404474 -421.335962)
		(end 74.404474 -420.949882)
		(width 0.14224)
		(layer "In13.Cu")
		(net "P5E_CPU1_P1_RX_BUF_DP<8>")
	)
	(segment
		(start 80.808322 -402.185124)
		(end 81.202784 -402.021548)
		(width 0.14224)
		(layer "In13.Cu")
		(net "P5E_CPU1_P1_RX_BUF_DP<8>")
	)
	(segment
		(start 88.835992 -396.178278)
		(end 89.027254 -396.145004)
		(width 0.14224)
		(layer "In13.Cu")
		(net "P5E_CPU1_P1_RX_BUF_DP<8>")
	)
	(segment
		(start 74.404474 -422.037002)
		(end 74.541634 -421.899842)
		(width 0.14224)
		(layer "In13.Cu")
		(net "P5E_CPU1_P1_RX_BUF_DP<8>")
	)
	(segment
		(start 89.62771 -393.017756)
		(end 89.817448 -393.017756)
		(width 0.14224)
		(layer "In13.Cu")
		(net "P5E_CPU1_P1_RX_BUF_DP<8>")
	)
	(segment
		(start 76.073254 -408.304238)
		(end 76.073254 -407.877518)
		(width 0.14224)
		(layer "In13.Cu")
		(net "P5E_CPU1_P1_RX_BUF_DP<8>")
	)
	(segment
		(start 75.936094 -408.441398)
		(end 76.073254 -408.304238)
		(width 0.14224)
		(layer "In13.Cu")
		(net "P5E_CPU1_P1_RX_BUF_DP<8>")
	)
	(segment
		(start 79.125064 -402.734018)
		(end 79.519272 -402.570696)
		(width 0.14224)
		(layer "In13.Cu")
		(net "P5E_CPU1_P1_RX_BUF_DP<8>")
	)
	(segment
		(start 89.239852 -395.604746)
		(end 89.411048 -395.361668)
		(width 0.14224)
		(layer "In13.Cu")
		(net "P5E_CPU1_P1_RX_BUF_DP<8>")
	)
	(segment
		(start 75.65009 -433.289964)
		(end 75.65009 -433.61864)
		(width 0.14224)
		(layer "In13.Cu")
		(net "P5E_CPU1_P1_RX_BUF_DP<8>")
	)
	(segment
		(start 86.454996 -399.04797)
		(end 88.072976 -397.262096)
		(width 0.14224)
		(layer "In13.Cu")
		(net "P5E_CPU1_P1_RX_BUF_DP<8>")
	)
	(segment
		(start 74.404474 -420.289482)
		(end 74.404474 -419.903402)
		(width 0.14224)
		(layer "In13.Cu")
		(net "P5E_CPU1_P1_RX_BUF_DP<8>")
	)
	(segment
		(start 81.276952 -401.842224)
		(end 81.794604 -401.627848)
		(width 0.14224)
		(layer "In13.Cu")
		(net "P5E_CPU1_P1_RX_BUF_DP<8>")
	)
	(segment
		(start 80.092804 -402.481542)
		(end 80.166972 -402.302218)
		(width 0.14224)
		(layer "In13.Cu")
		(net "P5E_CPU1_P1_RX_BUF_DP<8>")
	)
	(segment
		(start 74.404474 -424.292522)
		(end 74.541634 -424.155362)
		(width 0.14224)
		(layer "In13.Cu")
		(net "P5E_CPU1_P1_RX_BUF_DP<8>")
	)
	(segment
		(start 85.445854 -399.965672)
		(end 85.891878 -399.594832)
		(width 0.14224)
		(layer "In13.Cu")
		(net "P5E_CPU1_P1_RX_BUF_DP<8>")
	)
	(segment
		(start 83.209638 -401.198842)
		(end 84.479638 -400.647408)
		(width 0.14224)
		(layer "In13.Cu")
		(net "P5E_CPU1_P1_RX_BUF_DP<8>")
	)
	(segment
		(start 74.541634 -419.380162)
		(end 74.404474 -419.243002)
		(width 0.14224)
		(layer "In13.Cu")
		(net "P5E_CPU1_P1_RX_BUF_DP<8>")
	)
	(segment
		(start 74.541634 -422.600882)
		(end 74.404474 -422.463722)
		(width 0.14224)
		(layer "In13.Cu")
		(net "P5E_CPU1_P1_RX_BUF_DP<8>")
	)
	(segment
		(start 89.48547 -393.159996)
		(end 89.62771 -393.017756)
		(width 0.14224)
		(layer "In13.Cu")
		(net "P5E_CPU1_P1_RX_BUF_DP<8>")
	)
	(segment
		(start 74.404474 -423.591482)
		(end 74.404474 -423.164762)
		(width 0.14224)
		(layer "In13.Cu")
		(net "P5E_CPU1_P1_RX_BUF_DP<8>")
	)
	(segment
		(start 77.118464 -405.560276)
		(end 77.265276 -405.413464)
		(width 0.14224)
		(layer "In13.Cu")
		(net "P5E_CPU1_P1_RX_BUF_DP<8>")
	)
	(segment
		(start 75.511914 -433.756816)
		(end 75.275186 -433.756816)
		(width 0.14224)
		(layer "In13.Cu")
		(net "P5E_CPU1_P1_RX_BUF_DP<8>")
	)
	(segment
		(start 74.404474 -419.243002)
		(end 74.404474 -411.84576)
		(width 0.14224)
		(layer "In13.Cu")
		(net "P5E_CPU1_P1_RX_BUF_DP<8>")
	)
	(segment
		(start 75.936094 -407.740358)
		(end 75.936094 -406.638252)
		(width 0.14224)
		(layer "In13.Cu")
		(net "P5E_CPU1_P1_RX_BUF_DP<8>")
	)
	(segment
		(start 74.404474 -419.903402)
		(end 74.541634 -419.766242)
		(width 0.14224)
		(layer "In13.Cu")
		(net "P5E_CPU1_P1_RX_BUF_DP<8>")
	)
	(segment
		(start 81.794604 -401.627848)
		(end 83.209638 -401.198842)
		(width 0.14224)
		(layer "In13.Cu")
		(net "P5E_CPU1_P1_RX_BUF_DP<8>")
	)
	(segment
		(start 75.936094 -409.569158)
		(end 76.073254 -409.431998)
		(width 0.14224)
		(layer "In13.Cu")
		(net "P5E_CPU1_P1_RX_BUF_DP<8>")
	)
	(segment
		(start 89.48547 -395.12621)
		(end 89.48547 -393.159996)
		(width 0.14224)
		(layer "In13.Cu")
		(net "P5E_CPU1_P1_RX_BUF_DP<8>")
	)
	(segment
		(start 74.541634 -424.155362)
		(end 74.541634 -423.728642)
		(width 0.14224)
		(layer "In13.Cu")
		(net "P5E_CPU1_P1_RX_BUF_DP<8>")
	)
	(segment
		(start 74.541634 -419.766242)
		(end 74.541634 -419.380162)
		(width 0.14224)
		(layer "In13.Cu")
		(net "P5E_CPU1_P1_RX_BUF_DP<8>")
	)
	(segment
		(start 75.64501 -411.18282)
		(end 75.812396 -411.006798)
		(width 0.14224)
		(layer "In13.Cu")
		(net "P5E_CPU1_P1_RX_BUF_DP<8>")
	)
	(segment
		(start 74.404474 -423.164762)
		(end 74.541634 -423.027602)
		(width 0.14224)
		(layer "In13.Cu")
		(net "P5E_CPU1_P1_RX_BUF_DP<8>")
	)
	(segment
		(start 88.072976 -397.262096)
		(end 88.835992 -396.178278)
		(width 0.14224)
		(layer "In13.Cu")
		(net "P5E_CPU1_P1_RX_BUF_DP<8>")
	)
	(segment
		(start 74.541634 -421.473122)
		(end 74.404474 -421.335962)
		(width 0.14224)
		(layer "In13.Cu")
		(net "P5E_CPU1_P1_RX_BUF_DP<8>")
	)
	(segment
		(start 81.202784 -402.021548)
		(end 81.276952 -401.842224)
		(width 0.14224)
		(layer "In13.Cu")
		(net "P5E_CPU1_P1_RX_BUF_DP<8>")
	)
	(segment
		(start 74.404474 -432.886104)
		(end 74.404474 -424.292522)
		(width 0.14224)
		(layer "In13.Cu")
		(net "P5E_CPU1_P1_RX_BUF_DP<8>")
	)
	(segment
		(start 89.027254 -396.145004)
		(end 89.273126 -395.796008)
		(width 0.14224)
		(layer "In13.Cu")
		(net "P5E_CPU1_P1_RX_BUF_DP<8>")
	)
	(segment
		(start 74.541634 -420.812722)
		(end 74.541634 -420.426642)
		(width 0.14224)
		(layer "In13.Cu")
		(net "P5E_CPU1_P1_RX_BUF_DP<8>")
	)
	(segment
		(start 80.166972 -402.302218)
		(end 80.629252 -402.110702)
		(width 0.14224)
		(layer "In13.Cu")
		(net "P5E_CPU1_P1_RX_BUF_DP<8>")
	)
	(segment
		(start 74.541634 -420.426642)
		(end 74.404474 -420.289482)
		(width 0.14224)
		(layer "In13.Cu")
		(net "P5E_CPU1_P1_RX_BUF_DP<8>")
	)
	(segment
		(start 89.817448 -393.017756)
		(end 89.944448 -393.144756)
		(width 0.14224)
		(layer "In13.Cu")
		(net "P5E_CPU1_P1_RX_BUF_DP<8>")
	)
	(segment
		(start 76.073254 -409.431998)
		(end 76.073254 -409.005278)
		(width 0.14224)
		(layer "In13.Cu")
		(net "P5E_CPU1_P1_RX_BUF_DP<8>")
	)
	(segment
		(start 74.404474 -422.463722)
		(end 74.404474 -422.037002)
		(width 0.14224)
		(layer "In13.Cu")
		(net "P5E_CPU1_P1_RX_BUF_DP<8>")
	)
	(segment
		(start 75.275186 -433.756816)
		(end 74.404474 -432.886104)
		(width 0.14224)
		(layer "In13.Cu")
		(net "P5E_CPU1_P1_RX_BUF_DP<8>")
	)
	(segment
		(start 89.273126 -395.796008)
		(end 89.239852 -395.604746)
		(width 0.14224)
		(layer "In13.Cu")
		(net "P5E_CPU1_P1_RX_BUF_DP<8>")
	)
	(segment
		(start 74.492104 -411.71495)
		(end 75.444604 -411.31998)
		(width 0.14224)
		(layer "In13.Cu")
		(net "P5E_CPU1_P1_RX_BUF_DP<8>")
	)
	(segment
		(start 75.936094 -410.697172)
		(end 75.936094 -409.569158)
		(width 0.14224)
		(layer "In13.Cu")
		(net "P5E_CPU1_P1_RX_BUF_DP<8>")
	)
	(segment
		(start 76.802996 -405.771096)
		(end 77.118464 -405.560276)
		(width 0.14224)
		(layer "In13.Cu")
		(net "P5E_CPU1_P1_RX_BUF_DP<8>")
	)
	(segment
		(start 85.891878 -399.594832)
		(end 85.899752 -399.509488)
		(width 0.14224)
		(layer "In13.Cu")
		(net "P5E_CPU1_P1_RX_BUF_DP<8>")
	)
	(segment
		(start 74.541634 -421.899842)
		(end 74.541634 -421.473122)
		(width 0.14224)
		(layer "In13.Cu")
		(net "P5E_CPU1_P1_RX_BUF_DP<8>")
	)
	(segment
		(start 74.541634 -423.728642)
		(end 74.404474 -423.591482)
		(width 0.14224)
		(layer "In13.Cu")
		(net "P5E_CPU1_P1_RX_BUF_DP<8>")
	)
	(segment
		(start 89.944448 -393.144756)
		(end 89.944448 -393.292838)
		(width 0.14224)
		(layer "In13.Cu")
		(net "P5E_CPU1_P1_RX_BUF_DP<8>")
	)
	(segment
		(start 85.899752 -399.509488)
		(end 86.454996 -399.04797)
		(width 0.14224)
		(layer "In13.Cu")
		(net "P5E_CPU1_P1_RX_BUF_DP<8>")
	)
	(segment
		(start 76.527406 -405.885142)
		(end 76.802996 -405.771096)
		(width 0.14224)
		(layer "In13.Cu")
		(net "P5E_CPU1_P1_RX_BUF_DP<8>")
	)
	(segment
		(start 76.073254 -409.005278)
		(end 75.936094 -408.868118)
		(width 0.14224)
		(layer "In13.Cu")
		(net "P5E_CPU1_P1_RX_BUF_DP<8>")
	)
	(segment
		(start 85.360256 -399.957798)
		(end 85.445854 -399.965672)
		(width 0.14224)
		(layer "In13.Cu")
		(net "P5E_CPU1_P1_RX_BUF_DP<8>")
	)
	(segment
		(start 79.698342 -402.645118)
		(end 80.092804 -402.481542)
		(width 0.14224)
		(layer "In13.Cu")
		(net "P5E_CPU1_P1_RX_BUF_DP<8>")
	)
	(segment
		(start 74.404474 -420.949882)
		(end 74.541634 -420.812722)
		(width 0.14224)
		(layer "In13.Cu")
		(net "P5E_CPU1_P1_RX_BUF_DP<8>")
	)
	(segment
		(start 80.629252 -402.110702)
		(end 80.808322 -402.185124)
		(width 0.14224)
		(layer "In13.Cu")
		(net "P5E_CPU1_P1_RX_BUF_DP<8>")
	)
	(segment
		(start 76.073254 -407.877518)
		(end 75.936094 -407.740358)
		(width 0.14224)
		(layer "In13.Cu")
		(net "P5E_CPU1_P1_RX_BUF_DP<8>")
	)
	(segment
		(start 75.65009 -433.61864)
		(end 75.511914 -433.756816)
		(width 0.14224)
		(layer "In13.Cu")
		(net "P5E_CPU1_P1_RX_BUF_DP<8>")
	)
	(segment
		(start 75.936094 -408.868118)
		(end 75.936094 -408.441398)
		(width 0.14224)
		(layer "In13.Cu")
		(net "P5E_CPU1_P1_RX_BUF_DP<8>")
	)
	(segment
		(start 84.479638 -400.647408)
		(end 84.84997 -400.381724)
		(width 0.14224)
		(layer "In13.Cu")
		(net "P5E_CPU1_P1_RX_BUF_DP<8>")
	)
	(segment
		(start 77.467714 -404.924514)
		(end 77.467714 -404.05558)
		(width 0.14224)
		(layer "In13.Cu")
		(net "P5E_CPU1_P1_RX_BUF_DP<8>")
	)
	(arc
		(start 89.411048 -395.361668)
		(mid 89.466451 -395.24969)
		(end 89.48547 -395.12621)
		(width 0.14224)
		(layer "In13.Cu")
		(net "P5E_CPU1_P1_RX_BUF_DP<8>")
	)
	(arc
		(start 77.585316 -403.767544)
		(mid 78.31471 -403.190475)
		(end 79.125064 -402.734018)
		(width 0.14224)
		(layer "In13.Cu")
		(net "P5E_CPU1_P1_RX_BUF_DP<8>")
	)
	(arc
		(start 75.812396 -411.006798)
		(mid 75.904072 -410.863907)
		(end 75.936094 -410.697172)
		(width 0.14224)
		(layer "In13.Cu")
		(net "P5E_CPU1_P1_RX_BUF_DP<8>")
	)
	(arc
		(start 77.265276 -405.413464)
		(mid 77.415116 -405.189118)
		(end 77.467714 -404.924514)
		(width 0.14224)
		(layer "In13.Cu")
		(net "P5E_CPU1_P1_RX_BUF_DP<8>")
	)
	(arc
		(start 77.467714 -404.05558)
		(mid 77.498303 -403.900049)
		(end 77.585316 -403.767544)
		(width 0.14224)
		(layer "In13.Cu")
		(net "P5E_CPU1_P1_RX_BUF_DP<8>")
	)
	(arc
		(start 75.936094 -406.638252)
		(mid 75.989323 -406.370451)
		(end 76.141072 -406.14346)
		(width 0.14224)
		(layer "In13.Cu")
		(net "P5E_CPU1_P1_RX_BUF_DP<8>")
	)
	(arc
		(start 75.444604 -411.31998)
		(mid 75.552002 -411.261911)
		(end 75.64501 -411.18282)
		(width 0.14224)
		(layer "In13.Cu")
		(net "P5E_CPU1_P1_RX_BUF_DP<8>")
	)
	(arc
		(start 74.404474 -411.84576)
		(mid 74.428478 -411.767095)
		(end 74.492104 -411.71495)
		(width 0.14224)
		(layer "In13.Cu")
		(net "P5E_CPU1_P1_RX_BUF_DP<8>")
	)
	(arc
		(start 76.141072 -406.14346)
		(mid 76.321542 -405.995314)
		(end 76.527406 -405.885142)
		(width 0.14224)
		(layer "In13.Cu")
		(net "P5E_CPU1_P1_RX_BUF_DP<8>")
	)
	(segment
		(start 88.294972 -392.977116)
		(end 88.605614 -392.977116)
		(width 0.1016)
		(layer "F.Cu")
		(net "P5E_CPU1_P1_RX_BUF_DP<7>")
	)
	(segment
		(start 88.13038 -391.488676)
		(end 88.041734 -391.577322)
		(width 0.1016)
		(layer "F.Cu")
		(net "P5E_CPU1_P1_RX_BUF_DP<7>")
	)
	(segment
		(start 88.045798 -391.281158)
		(end 88.13038 -391.36574)
		(width 0.1016)
		(layer "F.Cu")
		(net "P5E_CPU1_P1_RX_BUF_DP<7>")
	)
	(segment
		(start 88.13038 -391.36574)
		(end 88.13038 -391.488676)
		(width 0.1016)
		(layer "F.Cu")
		(net "P5E_CPU1_P1_RX_BUF_DP<7>")
	)
	(segment
		(start 88.041734 -391.577322)
		(end 88.041734 -392.723878)
		(width 0.1016)
		(layer "F.Cu")
		(net "P5E_CPU1_P1_RX_BUF_DP<7>")
	)
	(segment
		(start 88.605614 -392.977116)
		(end 88.744298 -393.1158)
		(width 0.1016)
		(layer "F.Cu")
		(net "P5E_CPU1_P1_RX_BUF_DP<7>")
	)
	(segment
		(start 88.041734 -392.723878)
		(end 88.294972 -392.977116)
		(width 0.1016)
		(layer "F.Cu")
		(net "P5E_CPU1_P1_RX_BUF_DP<7>")
	)
	(segment
		(start 88.744298 -393.1158)
		(end 88.744298 -393.292838)
		(width 0.1016)
		(layer "F.Cu")
		(net "P5E_CPU1_P1_RX_BUF_DP<7>")
	)
	(segment
		(start 73.010014 -407.8478)
		(end 72.872854 -407.71064)
		(width 0.14224)
		(layer "In13.Cu")
		(net "P5E_CPU1_P1_RX_BUF_DP<7>")
	)
	(segment
		(start 73.739248 -405.771858)
		(end 74.055224 -405.560276)
		(width 0.14224)
		(layer "In13.Cu")
		(net "P5E_CPU1_P1_RX_BUF_DP<7>")
	)
	(segment
		(start 88.276176 -394.802106)
		(end 88.276176 -393.16914)
		(width 0.14224)
		(layer "In13.Cu")
		(net "P5E_CPU1_P1_RX_BUF_DP<7>")
	)
	(segment
		(start 71.971154 -416.216846)
		(end 72.108314 -416.079686)
		(width 0.14224)
		(layer "In13.Cu")
		(net "P5E_CPU1_P1_RX_BUF_DP<7>")
	)
	(segment
		(start 79.785718 -401.289012)
		(end 80.139794 -401.134834)
		(width 0.14224)
		(layer "In13.Cu")
		(net "P5E_CPU1_P1_RX_BUF_DP<7>")
	)
	(segment
		(start 72.584818 -411.122368)
		(end 72.794622 -410.787342)
		(width 0.14224)
		(layer "In13.Cu")
		(net "P5E_CPU1_P1_RX_BUF_DP<7>")
	)
	(segment
		(start 77.26172 -402.389848)
		(end 77.332586 -402.209)
		(width 0.14224)
		(layer "In13.Cu")
		(net "P5E_CPU1_P1_RX_BUF_DP<7>")
	)
	(segment
		(start 78.645766 -401.636484)
		(end 78.82636 -401.70735)
		(width 0.14224)
		(layer "In13.Cu")
		(net "P5E_CPU1_P1_RX_BUF_DP<7>")
	)
	(segment
		(start 78.291944 -401.790662)
		(end 78.645766 -401.636484)
		(width 0.14224)
		(layer "In13.Cu")
		(net "P5E_CPU1_P1_RX_BUF_DP<7>")
	)
	(segment
		(start 72.872854 -407.71064)
		(end 72.872854 -406.643332)
		(width 0.14224)
		(layer "In13.Cu")
		(net "P5E_CPU1_P1_RX_BUF_DP<7>")
	)
	(segment
		(start 80.139794 -401.134834)
		(end 80.21066 -400.953986)
		(width 0.14224)
		(layer "In13.Cu")
		(net "P5E_CPU1_P1_RX_BUF_DP<7>")
	)
	(segment
		(start 72.108314 -417.126166)
		(end 72.108314 -416.740086)
		(width 0.14224)
		(layer "In13.Cu")
		(net "P5E_CPU1_P1_RX_BUF_DP<7>")
	)
	(segment
		(start 87.755222 -396.061184)
		(end 88.084152 -395.56944)
		(width 0.14224)
		(layer "In13.Cu")
		(net "P5E_CPU1_P1_RX_BUF_DP<7>")
	)
	(segment
		(start 73.010014 -408.27452)
		(end 73.010014 -407.8478)
		(width 0.14224)
		(layer "In13.Cu")
		(net "P5E_CPU1_P1_RX_BUF_DP<7>")
	)
	(segment
		(start 72.957436 -406.38603)
		(end 73.205848 -406.048972)
		(width 0.14224)
		(layer "In13.Cu")
		(net "P5E_CPU1_P1_RX_BUF_DP<7>")
	)
	(segment
		(start 84.242148 -399.518124)
		(end 84.918296 -399.066258)
		(width 0.14224)
		(layer "In13.Cu")
		(net "P5E_CPU1_P1_RX_BUF_DP<7>")
	)
	(segment
		(start 75.41387 -403.045676)
		(end 75.767692 -402.891498)
		(width 0.14224)
		(layer "In13.Cu")
		(net "P5E_CPU1_P1_RX_BUF_DP<7>")
	)
	(segment
		(start 79.605124 -401.218146)
		(end 79.785718 -401.289012)
		(width 0.14224)
		(layer "In13.Cu")
		(net "P5E_CPU1_P1_RX_BUF_DP<7>")
	)
	(segment
		(start 78.82636 -401.70735)
		(end 79.180436 -401.553172)
		(width 0.14224)
		(layer "In13.Cu")
		(net "P5E_CPU1_P1_RX_BUF_DP<7>")
	)
	(segment
		(start 74.055224 -405.560276)
		(end 74.202036 -405.413464)
		(width 0.14224)
		(layer "In13.Cu")
		(net "P5E_CPU1_P1_RX_BUF_DP<7>")
	)
	(segment
		(start 84.918296 -399.066258)
		(end 85.259164 -398.786604)
		(width 0.14224)
		(layer "In13.Cu")
		(net "P5E_CPU1_P1_RX_BUF_DP<7>")
	)
	(segment
		(start 72.649842 -434.618638)
		(end 72.511666 -434.756814)
		(width 0.14224)
		(layer "In13.Cu")
		(net "P5E_CPU1_P1_RX_BUF_DP<7>")
	)
	(segment
		(start 85.280754 -398.765522)
		(end 87.755222 -396.061184)
		(width 0.14224)
		(layer "In13.Cu")
		(net "P5E_CPU1_P1_RX_BUF_DP<7>")
	)
	(segment
		(start 76.302362 -402.808186)
		(end 76.373228 -402.627338)
		(width 0.14224)
		(layer "In13.Cu")
		(net "P5E_CPU1_P1_RX_BUF_DP<7>")
	)
	(segment
		(start 71.976234 -434.45811)
		(end 71.976234 -426.878242)
		(width 0.14224)
		(layer "In13.Cu")
		(net "P5E_CPU1_P1_RX_BUF_DP<7>")
	)
	(segment
		(start 72.108314 -415.693606)
		(end 71.971154 -415.556446)
		(width 0.14224)
		(layer "In13.Cu")
		(net "P5E_CPU1_P1_RX_BUF_DP<7>")
	)
	(segment
		(start 77.332586 -402.209)
		(end 77.686408 -402.054822)
		(width 0.14224)
		(layer "In13.Cu")
		(net "P5E_CPU1_P1_RX_BUF_DP<7>")
	)
	(segment
		(start 71.513446 -411.66415)
		(end 72.358504 -411.313884)
		(width 0.14224)
		(layer "In13.Cu")
		(net "P5E_CPU1_P1_RX_BUF_DP<7>")
	)
	(segment
		(start 75.948286 -402.962364)
		(end 76.302362 -402.808186)
		(width 0.14224)
		(layer "In13.Cu")
		(net "P5E_CPU1_P1_RX_BUF_DP<7>")
	)
	(segment
		(start 80.21066 -400.953986)
		(end 80.923384 -400.643344)
		(width 0.14224)
		(layer "In13.Cu")
		(net "P5E_CPU1_P1_RX_BUF_DP<7>")
	)
	(segment
		(start 72.108314 -414.647126)
		(end 71.971154 -414.509966)
		(width 0.14224)
		(layer "In13.Cu")
		(net "P5E_CPU1_P1_RX_BUF_DP<7>")
	)
	(segment
		(start 72.108314 -416.079686)
		(end 72.108314 -415.693606)
		(width 0.14224)
		(layer "In13.Cu")
		(net "P5E_CPU1_P1_RX_BUF_DP<7>")
	)
	(segment
		(start 76.72705 -402.47316)
		(end 76.907644 -402.544026)
		(width 0.14224)
		(layer "In13.Cu")
		(net "P5E_CPU1_P1_RX_BUF_DP<7>")
	)
	(segment
		(start 79.251302 -401.372324)
		(end 79.605124 -401.218146)
		(width 0.14224)
		(layer "In13.Cu")
		(net "P5E_CPU1_P1_RX_BUF_DP<7>")
	)
	(segment
		(start 73.010014 -409.40228)
		(end 73.010014 -408.97556)
		(width 0.14224)
		(layer "In13.Cu")
		(net "P5E_CPU1_P1_RX_BUF_DP<7>")
	)
	(segment
		(start 72.511666 -434.756814)
		(end 72.274938 -434.756814)
		(width 0.14224)
		(layer "In13.Cu")
		(net "P5E_CPU1_P1_RX_BUF_DP<7>")
	)
	(segment
		(start 85.259164 -398.786604)
		(end 85.27034 -398.775936)
		(width 0.14224)
		(layer "In13.Cu")
		(net "P5E_CPU1_P1_RX_BUF_DP<7>")
	)
	(segment
		(start 83.395312 -399.86839)
		(end 84.242148 -399.518124)
		(width 0.14224)
		(layer "In13.Cu")
		(net "P5E_CPU1_P1_RX_BUF_DP<7>")
	)
	(segment
		(start 71.341234 -413.22371)
		(end 71.341234 -411.92196)
		(width 0.14224)
		(layer "In13.Cu")
		(net "P5E_CPU1_P1_RX_BUF_DP<7>")
	)
	(segment
		(start 88.744298 -393.144756)
		(end 88.744298 -393.292838)
		(width 0.14224)
		(layer "In13.Cu")
		(net "P5E_CPU1_P1_RX_BUF_DP<7>")
	)
	(segment
		(start 71.851266 -413.787082)
		(end 71.378826 -413.314642)
		(width 0.14224)
		(layer "In13.Cu")
		(net "P5E_CPU1_P1_RX_BUF_DP<7>")
	)
	(segment
		(start 88.276176 -393.16914)
		(end 88.42756 -393.017756)
		(width 0.14224)
		(layer "In13.Cu")
		(net "P5E_CPU1_P1_RX_BUF_DP<7>")
	)
	(segment
		(start 71.971154 -426.873162)
		(end 71.971154 -417.263326)
		(width 0.14224)
		(layer "In13.Cu")
		(net "P5E_CPU1_P1_RX_BUF_DP<7>")
	)
	(segment
		(start 71.341234 -411.92196)
		(end 71.341488 -411.922214)
		(width 0.14224)
		(layer "In13.Cu")
		(net "P5E_CPU1_P1_RX_BUF_DP<7>")
	)
	(segment
		(start 75.767692 -402.891498)
		(end 75.948286 -402.962364)
		(width 0.14224)
		(layer "In13.Cu")
		(net "P5E_CPU1_P1_RX_BUF_DP<7>")
	)
	(segment
		(start 72.872854 -409.53944)
		(end 73.010014 -409.40228)
		(width 0.14224)
		(layer "In13.Cu")
		(net "P5E_CPU1_P1_RX_BUF_DP<7>")
	)
	(segment
		(start 72.872854 -408.41168)
		(end 73.010014 -408.27452)
		(width 0.14224)
		(layer "In13.Cu")
		(net "P5E_CPU1_P1_RX_BUF_DP<7>")
	)
	(segment
		(start 76.373228 -402.627338)
		(end 76.72705 -402.47316)
		(width 0.14224)
		(layer "In13.Cu")
		(net "P5E_CPU1_P1_RX_BUF_DP<7>")
	)
	(segment
		(start 72.108314 -416.740086)
		(end 71.971154 -416.602926)
		(width 0.14224)
		(layer "In13.Cu")
		(net "P5E_CPU1_P1_RX_BUF_DP<7>")
	)
	(segment
		(start 88.617298 -393.017756)
		(end 88.744298 -393.144756)
		(width 0.14224)
		(layer "In13.Cu")
		(net "P5E_CPU1_P1_RX_BUF_DP<7>")
	)
	(segment
		(start 71.971154 -416.602926)
		(end 71.971154 -416.216846)
		(width 0.14224)
		(layer "In13.Cu")
		(net "P5E_CPU1_P1_RX_BUF_DP<7>")
	)
	(segment
		(start 88.084152 -395.56944)
		(end 88.276176 -394.802106)
		(width 0.14224)
		(layer "In13.Cu")
		(net "P5E_CPU1_P1_RX_BUF_DP<7>")
	)
	(segment
		(start 73.355962 -405.931116)
		(end 73.739248 -405.771858)
		(width 0.14224)
		(layer "In13.Cu")
		(net "P5E_CPU1_P1_RX_BUF_DP<7>")
	)
	(segment
		(start 73.010014 -408.97556)
		(end 72.872854 -408.8384)
		(width 0.14224)
		(layer "In13.Cu")
		(net "P5E_CPU1_P1_RX_BUF_DP<7>")
	)
	(segment
		(start 82.747104 -400.13636)
		(end 82.926428 -400.210782)
		(width 0.14224)
		(layer "In13.Cu")
		(net "P5E_CPU1_P1_RX_BUF_DP<7>")
	)
	(segment
		(start 74.597768 -403.654006)
		(end 74.76109 -403.490684)
		(width 0.14224)
		(layer "In13.Cu")
		(net "P5E_CPU1_P1_RX_BUF_DP<7>")
	)
	(segment
		(start 77.686408 -402.054822)
		(end 77.867002 -402.125688)
		(width 0.14224)
		(layer "In13.Cu")
		(net "P5E_CPU1_P1_RX_BUF_DP<7>")
	)
	(segment
		(start 85.27034 -398.775936)
		(end 85.280754 -398.765522)
		(width 0.14224)
		(layer "In13.Cu")
		(net "P5E_CPU1_P1_RX_BUF_DP<7>")
	)
	(segment
		(start 80.923384 -400.643344)
		(end 82.128868 -400.392138)
		(width 0.14224)
		(layer "In13.Cu")
		(net "P5E_CPU1_P1_RX_BUF_DP<7>")
	)
	(segment
		(start 82.128868 -400.392138)
		(end 82.747104 -400.13636)
		(width 0.14224)
		(layer "In13.Cu")
		(net "P5E_CPU1_P1_RX_BUF_DP<7>")
	)
	(segment
		(start 72.108314 -415.033206)
		(end 72.108314 -414.647126)
		(width 0.14224)
		(layer "In13.Cu")
		(net "P5E_CPU1_P1_RX_BUF_DP<7>")
	)
	(segment
		(start 71.976234 -426.878242)
		(end 71.971154 -426.873162)
		(width 0.14224)
		(layer "In13.Cu")
		(net "P5E_CPU1_P1_RX_BUF_DP<7>")
	)
	(segment
		(start 72.872854 -408.8384)
		(end 72.872854 -408.41168)
		(width 0.14224)
		(layer "In13.Cu")
		(net "P5E_CPU1_P1_RX_BUF_DP<7>")
	)
	(segment
		(start 78.221078 -401.97151)
		(end 78.291944 -401.790662)
		(width 0.14224)
		(layer "In13.Cu")
		(net "P5E_CPU1_P1_RX_BUF_DP<7>")
	)
	(segment
		(start 71.971154 -417.263326)
		(end 72.108314 -417.126166)
		(width 0.14224)
		(layer "In13.Cu")
		(net "P5E_CPU1_P1_RX_BUF_DP<7>")
	)
	(segment
		(start 82.926428 -400.210782)
		(end 83.32089 -400.047714)
		(width 0.14224)
		(layer "In13.Cu")
		(net "P5E_CPU1_P1_RX_BUF_DP<7>")
	)
	(segment
		(start 71.971154 -415.170366)
		(end 72.108314 -415.033206)
		(width 0.14224)
		(layer "In13.Cu")
		(net "P5E_CPU1_P1_RX_BUF_DP<7>")
	)
	(segment
		(start 83.32089 -400.047714)
		(end 83.395312 -399.86839)
		(width 0.14224)
		(layer "In13.Cu")
		(net "P5E_CPU1_P1_RX_BUF_DP<7>")
	)
	(segment
		(start 76.907644 -402.544026)
		(end 77.26172 -402.389848)
		(width 0.14224)
		(layer "In13.Cu")
		(net "P5E_CPU1_P1_RX_BUF_DP<7>")
	)
	(segment
		(start 74.404474 -404.924514)
		(end 74.404474 -404.120604)
		(width 0.14224)
		(layer "In13.Cu")
		(net "P5E_CPU1_P1_RX_BUF_DP<7>")
	)
	(segment
		(start 72.274938 -434.756814)
		(end 71.976234 -434.45811)
		(width 0.14224)
		(layer "In13.Cu")
		(net "P5E_CPU1_P1_RX_BUF_DP<7>")
	)
	(segment
		(start 77.867002 -402.125688)
		(end 78.221078 -401.97151)
		(width 0.14224)
		(layer "In13.Cu")
		(net "P5E_CPU1_P1_RX_BUF_DP<7>")
	)
	(segment
		(start 71.971154 -415.556446)
		(end 71.971154 -415.170366)
		(width 0.14224)
		(layer "In13.Cu")
		(net "P5E_CPU1_P1_RX_BUF_DP<7>")
	)
	(segment
		(start 79.180436 -401.553172)
		(end 79.251302 -401.372324)
		(width 0.14224)
		(layer "In13.Cu")
		(net "P5E_CPU1_P1_RX_BUF_DP<7>")
	)
	(segment
		(start 72.872854 -410.51353)
		(end 72.872854 -409.53944)
		(width 0.14224)
		(layer "In13.Cu")
		(net "P5E_CPU1_P1_RX_BUF_DP<7>")
	)
	(segment
		(start 88.42756 -393.017756)
		(end 88.617298 -393.017756)
		(width 0.14224)
		(layer "In13.Cu")
		(net "P5E_CPU1_P1_RX_BUF_DP<7>")
	)
	(segment
		(start 71.971154 -414.509966)
		(end 71.971154 -414.076642)
		(width 0.14224)
		(layer "In13.Cu")
		(net "P5E_CPU1_P1_RX_BUF_DP<7>")
	)
	(segment
		(start 72.649842 -434.289962)
		(end 72.649842 -434.618638)
		(width 0.14224)
		(layer "In13.Cu")
		(net "P5E_CPU1_P1_RX_BUF_DP<7>")
	)
	(arc
		(start 71.378826 -413.314642)
		(mid 71.35095 -413.272922)
		(end 71.341234 -413.22371)
		(width 0.14224)
		(layer "In13.Cu")
		(net "P5E_CPU1_P1_RX_BUF_DP<7>")
	)
	(arc
		(start 74.76109 -403.490684)
		(mid 75.066578 -403.237517)
		(end 75.41387 -403.045676)
		(width 0.14224)
		(layer "In13.Cu")
		(net "P5E_CPU1_P1_RX_BUF_DP<7>")
	)
	(arc
		(start 71.971154 -414.076642)
		(mid 71.940002 -413.919939)
		(end 71.851266 -413.787082)
		(width 0.14224)
		(layer "In13.Cu")
		(net "P5E_CPU1_P1_RX_BUF_DP<7>")
	)
	(arc
		(start 72.358504 -411.313884)
		(mid 72.486616 -411.235794)
		(end 72.584818 -411.122368)
		(width 0.14224)
		(layer "In13.Cu")
		(net "P5E_CPU1_P1_RX_BUF_DP<7>")
	)
	(arc
		(start 72.794622 -410.787342)
		(mid 72.853024 -410.655942)
		(end 72.872854 -410.51353)
		(width 0.14224)
		(layer "In13.Cu")
		(net "P5E_CPU1_P1_RX_BUF_DP<7>")
	)
	(arc
		(start 71.341488 -411.922214)
		(mid 71.388337 -411.767091)
		(end 71.513446 -411.66415)
		(width 0.14224)
		(layer "In13.Cu")
		(net "P5E_CPU1_P1_RX_BUF_DP<7>")
	)
	(arc
		(start 74.202036 -405.413464)
		(mid 74.351876 -405.189118)
		(end 74.404474 -404.924514)
		(width 0.14224)
		(layer "In13.Cu")
		(net "P5E_CPU1_P1_RX_BUF_DP<7>")
	)
	(arc
		(start 73.205848 -406.048972)
		(mid 73.272901 -405.979852)
		(end 73.355962 -405.931116)
		(width 0.14224)
		(layer "In13.Cu")
		(net "P5E_CPU1_P1_RX_BUF_DP<7>")
	)
	(arc
		(start 72.872854 -406.643332)
		(mid 72.894484 -406.507882)
		(end 72.957436 -406.38603)
		(width 0.14224)
		(layer "In13.Cu")
		(net "P5E_CPU1_P1_RX_BUF_DP<7>")
	)
	(arc
		(start 74.404474 -404.120604)
		(mid 74.454705 -403.868074)
		(end 74.597768 -403.654006)
		(width 0.14224)
		(layer "In13.Cu")
		(net "P5E_CPU1_P1_RX_BUF_DP<7>")
	)
	(segment
		(start 86.850474 -392.723878)
		(end 87.103712 -392.977116)
		(width 0.1016)
		(layer "F.Cu")
		(net "P5E_CPU1_P1_RX_BUF_DP<6>")
	)
	(segment
		(start 87.405464 -392.977116)
		(end 87.544402 -393.116054)
		(width 0.1016)
		(layer "F.Cu")
		(net "P5E_CPU1_P1_RX_BUF_DP<6>")
	)
	(segment
		(start 86.93023 -391.488676)
		(end 86.850474 -391.568432)
		(width 0.1016)
		(layer "F.Cu")
		(net "P5E_CPU1_P1_RX_BUF_DP<6>")
	)
	(segment
		(start 87.103712 -392.977116)
		(end 87.405464 -392.977116)
		(width 0.1016)
		(layer "F.Cu")
		(net "P5E_CPU1_P1_RX_BUF_DP<6>")
	)
	(segment
		(start 86.850474 -391.568432)
		(end 86.850474 -392.723878)
		(width 0.1016)
		(layer "F.Cu")
		(net "P5E_CPU1_P1_RX_BUF_DP<6>")
	)
	(segment
		(start 86.845648 -391.281158)
		(end 86.93023 -391.36574)
		(width 0.1016)
		(layer "F.Cu")
		(net "P5E_CPU1_P1_RX_BUF_DP<6>")
	)
	(segment
		(start 86.93023 -391.36574)
		(end 86.93023 -391.488676)
		(width 0.1016)
		(layer "F.Cu")
		(net "P5E_CPU1_P1_RX_BUF_DP<6>")
	)
	(segment
		(start 87.544402 -393.116054)
		(end 87.544402 -393.292838)
		(width 0.1016)
		(layer "F.Cu")
		(net "P5E_CPU1_P1_RX_BUF_DP<6>")
	)
	(segment
		(start 72.3138 -403.182582)
		(end 72.705976 -403.014688)
		(width 0.14224)
		(layer "In13.Cu")
		(net "P5E_CPU1_P1_RX_BUF_DP<6>")
	)
	(segment
		(start 69.976238 -426.878242)
		(end 69.971158 -426.873162)
		(width 0.14224)
		(layer "In13.Cu")
		(net "P5E_CPU1_P1_RX_BUF_DP<6>")
	)
	(segment
		(start 69.946774 -407.753058)
		(end 69.809614 -407.615898)
		(width 0.14224)
		(layer "In13.Cu")
		(net "P5E_CPU1_P1_RX_BUF_DP<6>")
	)
	(segment
		(start 70.108318 -416.546792)
		(end 70.108318 -416.120072)
		(width 0.14224)
		(layer "In13.Cu")
		(net "P5E_CPU1_P1_RX_BUF_DP<6>")
	)
	(segment
		(start 69.19722 -414.036002)
		(end 69.003164 -414.036002)
		(width 0.14224)
		(layer "In13.Cu")
		(net "P5E_CPU1_P1_RX_BUF_DP<6>")
	)
	(segment
		(start 69.971158 -415.982912)
		(end 69.971158 -415.279586)
		(width 0.14224)
		(layer "In13.Cu")
		(net "P5E_CPU1_P1_RX_BUF_DP<6>")
	)
	(segment
		(start 82.03946 -399.232374)
		(end 82.215482 -399.313654)
		(width 0.14224)
		(layer "In13.Cu")
		(net "P5E_CPU1_P1_RX_BUF_DP<6>")
	)
	(segment
		(start 74.779378 -402.125942)
		(end 74.959464 -402.197824)
		(width 0.14224)
		(layer "In13.Cu")
		(net "P5E_CPU1_P1_RX_BUF_DP<6>")
	)
	(segment
		(start 69.946774 -408.880818)
		(end 69.809614 -408.743658)
		(width 0.14224)
		(layer "In13.Cu")
		(net "P5E_CPU1_P1_RX_BUF_DP<6>")
	)
	(segment
		(start 73.922636 -402.64207)
		(end 74.315066 -402.474176)
		(width 0.14224)
		(layer "In13.Cu")
		(net "P5E_CPU1_P1_RX_BUF_DP<6>")
	)
	(segment
		(start 77.548232 -400.939254)
		(end 78.321662 -400.607784)
		(width 0.14224)
		(layer "In13.Cu")
		(net "P5E_CPU1_P1_RX_BUF_DP<6>")
	)
	(segment
		(start 69.809614 -407.615898)
		(end 69.809614 -406.638252)
		(width 0.14224)
		(layer "In13.Cu")
		(net "P5E_CPU1_P1_RX_BUF_DP<6>")
	)
	(segment
		(start 70.274942 -433.756816)
		(end 69.976238 -433.458112)
		(width 0.14224)
		(layer "In13.Cu")
		(net "P5E_CPU1_P1_RX_BUF_DP<6>")
	)
	(segment
		(start 87.227664 -393.017756)
		(end 87.417402 -393.017756)
		(width 0.14224)
		(layer "In13.Cu")
		(net "P5E_CPU1_P1_RX_BUF_DP<6>")
	)
	(segment
		(start 87.544402 -393.144756)
		(end 87.544402 -393.292838)
		(width 0.14224)
		(layer "In13.Cu")
		(net "P5E_CPU1_P1_RX_BUF_DP<6>")
	)
	(segment
		(start 69.809614 -408.316938)
		(end 69.946774 -408.179778)
		(width 0.14224)
		(layer "In13.Cu")
		(net "P5E_CPU1_P1_RX_BUF_DP<6>")
	)
	(segment
		(start 87.085424 -393.159996)
		(end 87.227664 -393.017756)
		(width 0.14224)
		(layer "In13.Cu")
		(net "P5E_CPU1_P1_RX_BUF_DP<6>")
	)
	(segment
		(start 69.499226 -414.532064)
		(end 69.499226 -414.338008)
		(width 0.14224)
		(layer "In13.Cu")
		(net "P5E_CPU1_P1_RX_BUF_DP<6>")
	)
	(segment
		(start 69.946774 -409.307538)
		(end 69.946774 -408.880818)
		(width 0.14224)
		(layer "In13.Cu")
		(net "P5E_CPU1_P1_RX_BUF_DP<6>")
	)
	(segment
		(start 77.083666 -401.287488)
		(end 77.476096 -401.119594)
		(width 0.14224)
		(layer "In13.Cu")
		(net "P5E_CPU1_P1_RX_BUF_DP<6>")
	)
	(segment
		(start 73.74255 -402.570188)
		(end 73.922636 -402.64207)
		(width 0.14224)
		(layer "In13.Cu")
		(net "P5E_CPU1_P1_RX_BUF_DP<6>")
	)
	(segment
		(start 70.991984 -405.560276)
		(end 71.138796 -405.413464)
		(width 0.14224)
		(layer "In13.Cu")
		(net "P5E_CPU1_P1_RX_BUF_DP<6>")
	)
	(segment
		(start 77.476096 -401.119594)
		(end 77.548232 -400.939254)
		(width 0.14224)
		(layer "In13.Cu")
		(net "P5E_CPU1_P1_RX_BUF_DP<6>")
	)
	(segment
		(start 83.942428 -398.47774)
		(end 84.224114 -398.289018)
		(width 0.14224)
		(layer "In13.Cu")
		(net "P5E_CPU1_P1_RX_BUF_DP<6>")
	)
	(segment
		(start 69.809614 -410.697172)
		(end 69.809614 -409.444698)
		(width 0.14224)
		(layer "In13.Cu")
		(net "P5E_CPU1_P1_RX_BUF_DP<6>")
	)
	(segment
		(start 69.499226 -414.338008)
		(end 69.19722 -414.036002)
		(width 0.14224)
		(layer "In13.Cu")
		(net "P5E_CPU1_P1_RX_BUF_DP<6>")
	)
	(segment
		(start 69.976238 -433.458112)
		(end 69.976238 -426.878242)
		(width 0.14224)
		(layer "In13.Cu")
		(net "P5E_CPU1_P1_RX_BUF_DP<6>")
	)
	(segment
		(start 70.676516 -405.771096)
		(end 70.991984 -405.560276)
		(width 0.14224)
		(layer "In13.Cu")
		(net "P5E_CPU1_P1_RX_BUF_DP<6>")
	)
	(segment
		(start 75.42403 -401.84959)
		(end 75.866752 -401.659852)
		(width 0.14224)
		(layer "In13.Cu")
		(net "P5E_CPU1_P1_RX_BUF_DP<6>")
	)
	(segment
		(start 76.439268 -401.56384)
		(end 76.511404 -401.3835)
		(width 0.14224)
		(layer "In13.Cu")
		(net "P5E_CPU1_P1_RX_BUF_DP<6>")
	)
	(segment
		(start 71.54418 -403.743414)
		(end 71.895208 -403.39899)
		(width 0.14224)
		(layer "In13.Cu")
		(net "P5E_CPU1_P1_RX_BUF_DP<6>")
	)
	(segment
		(start 70.649846 -433.289964)
		(end 70.649846 -433.61864)
		(width 0.14224)
		(layer "In13.Cu")
		(net "P5E_CPU1_P1_RX_BUF_DP<6>")
	)
	(segment
		(start 70.400926 -405.885142)
		(end 70.676516 -405.771096)
		(width 0.14224)
		(layer "In13.Cu")
		(net "P5E_CPU1_P1_RX_BUF_DP<6>")
	)
	(segment
		(start 87.417402 -393.017756)
		(end 87.544402 -393.144756)
		(width 0.14224)
		(layer "In13.Cu")
		(net "P5E_CPU1_P1_RX_BUF_DP<6>")
	)
	(segment
		(start 69.809614 -409.444698)
		(end 69.946774 -409.307538)
		(width 0.14224)
		(layer "In13.Cu")
		(net "P5E_CPU1_P1_RX_BUF_DP<6>")
	)
	(segment
		(start 69.003164 -414.036002)
		(end 68.378578 -413.411416)
		(width 0.14224)
		(layer "In13.Cu")
		(net "P5E_CPU1_P1_RX_BUF_DP<6>")
	)
	(segment
		(start 74.315066 -402.474176)
		(end 74.387202 -402.293836)
		(width 0.14224)
		(layer "In13.Cu")
		(net "P5E_CPU1_P1_RX_BUF_DP<6>")
	)
	(segment
		(start 72.705976 -403.014688)
		(end 72.886062 -403.08657)
		(width 0.14224)
		(layer "In13.Cu")
		(net "P5E_CPU1_P1_RX_BUF_DP<6>")
	)
	(segment
		(start 82.69732 -398.98955)
		(end 83.572858 -398.666462)
		(width 0.14224)
		(layer "In13.Cu")
		(net "P5E_CPU1_P1_RX_BUF_DP<6>")
	)
	(segment
		(start 84.57184 -398.003014)
		(end 86.101174 -396.47368)
		(width 0.14224)
		(layer "In13.Cu")
		(net "P5E_CPU1_P1_RX_BUF_DP<6>")
	)
	(segment
		(start 73.278492 -402.918676)
		(end 73.350374 -402.738082)
		(width 0.14224)
		(layer "In13.Cu")
		(net "P5E_CPU1_P1_RX_BUF_DP<6>")
	)
	(segment
		(start 68.365624 -411.71495)
		(end 69.318124 -411.31998)
		(width 0.14224)
		(layer "In13.Cu")
		(net "P5E_CPU1_P1_RX_BUF_DP<6>")
	)
	(segment
		(start 70.51167 -433.756816)
		(end 70.274942 -433.756816)
		(width 0.14224)
		(layer "In13.Cu")
		(net "P5E_CPU1_P1_RX_BUF_DP<6>")
	)
	(segment
		(start 75.866752 -401.659852)
		(end 76.046838 -401.731988)
		(width 0.14224)
		(layer "In13.Cu")
		(net "P5E_CPU1_P1_RX_BUF_DP<6>")
	)
	(segment
		(start 75.351894 -402.02993)
		(end 75.42403 -401.84959)
		(width 0.14224)
		(layer "In13.Cu")
		(net "P5E_CPU1_P1_RX_BUF_DP<6>")
	)
	(segment
		(start 82.215482 -399.313654)
		(end 82.61604 -399.165826)
		(width 0.14224)
		(layer "In13.Cu")
		(net "P5E_CPU1_P1_RX_BUF_DP<6>")
	)
	(segment
		(start 70.108318 -416.120072)
		(end 69.971158 -415.982912)
		(width 0.14224)
		(layer "In13.Cu")
		(net "P5E_CPU1_P1_RX_BUF_DP<6>")
	)
	(segment
		(start 71.374762 -403.993096)
		(end 71.465186 -403.843236)
		(width 0.14224)
		(layer "In13.Cu")
		(net "P5E_CPU1_P1_RX_BUF_DP<6>")
	)
	(segment
		(start 74.959464 -402.197824)
		(end 75.351894 -402.02993)
		(width 0.14224)
		(layer "In13.Cu")
		(net "P5E_CPU1_P1_RX_BUF_DP<6>")
	)
	(segment
		(start 68.277994 -413.168592)
		(end 68.277994 -411.846014)
		(width 0.14224)
		(layer "In13.Cu")
		(net "P5E_CPU1_P1_RX_BUF_DP<6>")
	)
	(segment
		(start 78.439264 -400.561048)
		(end 82.03946 -399.232374)
		(width 0.14224)
		(layer "In13.Cu")
		(net "P5E_CPU1_P1_RX_BUF_DP<6>")
	)
	(segment
		(start 69.971158 -426.873162)
		(end 69.971158 -416.683952)
		(width 0.14224)
		(layer "In13.Cu")
		(net "P5E_CPU1_P1_RX_BUF_DP<6>")
	)
	(segment
		(start 69.77634 -414.809178)
		(end 69.499226 -414.532064)
		(width 0.14224)
		(layer "In13.Cu")
		(net "P5E_CPU1_P1_RX_BUF_DP<6>")
	)
	(segment
		(start 76.046838 -401.731988)
		(end 76.439268 -401.56384)
		(width 0.14224)
		(layer "In13.Cu")
		(net "P5E_CPU1_P1_RX_BUF_DP<6>")
	)
	(segment
		(start 70.649846 -433.61864)
		(end 70.51167 -433.756816)
		(width 0.14224)
		(layer "In13.Cu")
		(net "P5E_CPU1_P1_RX_BUF_DP<6>")
	)
	(segment
		(start 73.350374 -402.738082)
		(end 73.74255 -402.570188)
		(width 0.14224)
		(layer "In13.Cu")
		(net "P5E_CPU1_P1_RX_BUF_DP<6>")
	)
	(segment
		(start 71.975218 -403.342856)
		(end 72.209914 -403.229826)
		(width 0.14224)
		(layer "In13.Cu")
		(net "P5E_CPU1_P1_RX_BUF_DP<6>")
	)
	(segment
		(start 76.511404 -401.3835)
		(end 76.90358 -401.215606)
		(width 0.14224)
		(layer "In13.Cu")
		(net "P5E_CPU1_P1_RX_BUF_DP<6>")
	)
	(segment
		(start 87.085424 -395.023848)
		(end 87.085424 -393.159996)
		(width 0.14224)
		(layer "In13.Cu")
		(net "P5E_CPU1_P1_RX_BUF_DP<6>")
	)
	(segment
		(start 74.387202 -402.293836)
		(end 74.779378 -402.125942)
		(width 0.14224)
		(layer "In13.Cu")
		(net "P5E_CPU1_P1_RX_BUF_DP<6>")
	)
	(segment
		(start 69.971158 -416.683952)
		(end 70.108318 -416.546792)
		(width 0.14224)
		(layer "In13.Cu")
		(net "P5E_CPU1_P1_RX_BUF_DP<6>")
	)
	(segment
		(start 76.90358 -401.215606)
		(end 77.083666 -401.287488)
		(width 0.14224)
		(layer "In13.Cu")
		(net "P5E_CPU1_P1_RX_BUF_DP<6>")
	)
	(segment
		(start 69.946774 -408.179778)
		(end 69.946774 -407.753058)
		(width 0.14224)
		(layer "In13.Cu")
		(net "P5E_CPU1_P1_RX_BUF_DP<6>")
	)
	(segment
		(start 69.51853 -411.18282)
		(end 69.685916 -411.006798)
		(width 0.14224)
		(layer "In13.Cu")
		(net "P5E_CPU1_P1_RX_BUF_DP<6>")
	)
	(segment
		(start 86.629748 -395.82979)
		(end 87.01659 -395.251178)
		(width 0.14224)
		(layer "In13.Cu")
		(net "P5E_CPU1_P1_RX_BUF_DP<6>")
	)
	(segment
		(start 82.61604 -399.165826)
		(end 82.69732 -398.98955)
		(width 0.14224)
		(layer "In13.Cu")
		(net "P5E_CPU1_P1_RX_BUF_DP<6>")
	)
	(segment
		(start 71.341234 -404.924514)
		(end 71.341234 -404.113492)
		(width 0.14224)
		(layer "In13.Cu")
		(net "P5E_CPU1_P1_RX_BUF_DP<6>")
	)
	(segment
		(start 69.809614 -408.743658)
		(end 69.809614 -408.316938)
		(width 0.14224)
		(layer "In13.Cu")
		(net "P5E_CPU1_P1_RX_BUF_DP<6>")
	)
	(segment
		(start 72.886062 -403.08657)
		(end 73.278492 -402.918676)
		(width 0.14224)
		(layer "In13.Cu")
		(net "P5E_CPU1_P1_RX_BUF_DP<6>")
	)
	(arc
		(start 84.224114 -398.289018)
		(mid 84.404962 -398.15451)
		(end 84.57184 -398.003014)
		(width 0.14224)
		(layer "In13.Cu")
		(net "P5E_CPU1_P1_RX_BUF_DP<6>")
	)
	(arc
		(start 71.895208 -403.39899)
		(mid 71.932902 -403.367626)
		(end 71.975218 -403.342856)
		(width 0.14224)
		(layer "In13.Cu")
		(net "P5E_CPU1_P1_RX_BUF_DP<6>")
	)
	(arc
		(start 68.277994 -411.846014)
		(mid 68.301928 -411.7672)
		(end 68.365624 -411.71495)
		(width 0.14224)
		(layer "In13.Cu")
		(net "P5E_CPU1_P1_RX_BUF_DP<6>")
	)
	(arc
		(start 69.685916 -411.006798)
		(mid 69.777592 -410.863907)
		(end 69.809614 -410.697172)
		(width 0.14224)
		(layer "In13.Cu")
		(net "P5E_CPU1_P1_RX_BUF_DP<6>")
	)
	(arc
		(start 71.138796 -405.413464)
		(mid 71.288636 -405.189118)
		(end 71.341234 -404.924514)
		(width 0.14224)
		(layer "In13.Cu")
		(net "P5E_CPU1_P1_RX_BUF_DP<6>")
	)
	(arc
		(start 83.572858 -398.666462)
		(mid 83.763237 -398.583056)
		(end 83.942428 -398.47774)
		(width 0.14224)
		(layer "In13.Cu")
		(net "P5E_CPU1_P1_RX_BUF_DP<6>")
	)
	(arc
		(start 87.01659 -395.251178)
		(mid 87.067846 -395.142615)
		(end 87.085424 -395.023848)
		(width 0.14224)
		(layer "In13.Cu")
		(net "P5E_CPU1_P1_RX_BUF_DP<6>")
	)
	(arc
		(start 70.014592 -406.14346)
		(mid 70.195062 -405.995314)
		(end 70.400926 -405.885142)
		(width 0.14224)
		(layer "In13.Cu")
		(net "P5E_CPU1_P1_RX_BUF_DP<6>")
	)
	(arc
		(start 68.378578 -413.411416)
		(mid 68.304137 -413.300007)
		(end 68.277994 -413.168592)
		(width 0.14224)
		(layer "In13.Cu")
		(net "P5E_CPU1_P1_RX_BUF_DP<6>")
	)
	(arc
		(start 69.318124 -411.31998)
		(mid 69.425522 -411.261911)
		(end 69.51853 -411.18282)
		(width 0.14224)
		(layer "In13.Cu")
		(net "P5E_CPU1_P1_RX_BUF_DP<6>")
	)
	(arc
		(start 86.101174 -396.47368)
		(mid 86.38128 -396.164722)
		(end 86.629748 -395.82979)
		(width 0.14224)
		(layer "In13.Cu")
		(net "P5E_CPU1_P1_RX_BUF_DP<6>")
	)
	(arc
		(start 72.209914 -403.229826)
		(mid 72.261599 -403.205637)
		(end 72.3138 -403.182582)
		(width 0.14224)
		(layer "In13.Cu")
		(net "P5E_CPU1_P1_RX_BUF_DP<6>")
	)
	(arc
		(start 71.341234 -404.113492)
		(mid 71.349765 -404.050999)
		(end 71.374762 -403.993096)
		(width 0.14224)
		(layer "In13.Cu")
		(net "P5E_CPU1_P1_RX_BUF_DP<6>")
	)
	(arc
		(start 71.465186 -403.843236)
		(mid 71.501528 -403.790827)
		(end 71.54418 -403.743414)
		(width 0.14224)
		(layer "In13.Cu")
		(net "P5E_CPU1_P1_RX_BUF_DP<6>")
	)
	(arc
		(start 69.809614 -406.638252)
		(mid 69.862843 -406.370451)
		(end 70.014592 -406.14346)
		(width 0.14224)
		(layer "In13.Cu")
		(net "P5E_CPU1_P1_RX_BUF_DP<6>")
	)
	(arc
		(start 78.321662 -400.607784)
		(mid 78.380163 -400.583661)
		(end 78.439264 -400.561048)
		(width 0.14224)
		(layer "In13.Cu")
		(net "P5E_CPU1_P1_RX_BUF_DP<6>")
	)
	(arc
		(start 69.971158 -415.279586)
		(mid 69.920521 -415.025015)
		(end 69.77634 -414.809178)
		(width 0.14224)
		(layer "In13.Cu")
		(net "P5E_CPU1_P1_RX_BUF_DP<6>")
	)
	(segment
		(start 85.730334 -391.36574)
		(end 85.730334 -391.488676)
		(width 0.1016)
		(layer "F.Cu")
		(net "P5E_CPU1_P1_RX_BUF_DP<5>")
	)
	(segment
		(start 85.730334 -391.488676)
		(end 85.641688 -391.577322)
		(width 0.1016)
		(layer "F.Cu")
		(net "P5E_CPU1_P1_RX_BUF_DP<5>")
	)
	(segment
		(start 86.344252 -393.1158)
		(end 86.344252 -393.292838)
		(width 0.1016)
		(layer "F.Cu")
		(net "P5E_CPU1_P1_RX_BUF_DP<5>")
	)
	(segment
		(start 85.641688 -391.577322)
		(end 85.641688 -392.723878)
		(width 0.1016)
		(layer "F.Cu")
		(net "P5E_CPU1_P1_RX_BUF_DP<5>")
	)
	(segment
		(start 85.894926 -392.977116)
		(end 86.205568 -392.977116)
		(width 0.1016)
		(layer "F.Cu")
		(net "P5E_CPU1_P1_RX_BUF_DP<5>")
	)
	(segment
		(start 85.645752 -391.281158)
		(end 85.730334 -391.36574)
		(width 0.1016)
		(layer "F.Cu")
		(net "P5E_CPU1_P1_RX_BUF_DP<5>")
	)
	(segment
		(start 86.205568 -392.977116)
		(end 86.344252 -393.1158)
		(width 0.1016)
		(layer "F.Cu")
		(net "P5E_CPU1_P1_RX_BUF_DP<5>")
	)
	(segment
		(start 85.641688 -392.723878)
		(end 85.894926 -392.977116)
		(width 0.1016)
		(layer "F.Cu")
		(net "P5E_CPU1_P1_RX_BUF_DP<5>")
	)
	(segment
		(start 68.423536 -403.744938)
		(end 68.592446 -403.576028)
		(width 0.14224)
		(layer "In13.Cu")
		(net "P5E_CPU1_P1_RX_BUF_DP<5>")
	)
	(segment
		(start 66.746374 -410.652722)
		(end 66.746374 -409.316174)
		(width 0.14224)
		(layer "In13.Cu")
		(net "P5E_CPU1_P1_RX_BUF_DP<5>")
	)
	(segment
		(start 66.406522 -411.254194)
		(end 66.576956 -411.075632)
		(width 0.14224)
		(layer "In13.Cu")
		(net "P5E_CPU1_P1_RX_BUF_DP<5>")
	)
	(segment
		(start 67.976242 -426.996606)
		(end 67.982846 -426.990002)
		(width 0.14224)
		(layer "In13.Cu")
		(net "P5E_CPU1_P1_RX_BUF_DP<5>")
	)
	(segment
		(start 86.344252 -393.144756)
		(end 86.344252 -393.292838)
		(width 0.14224)
		(layer "In13.Cu")
		(net "P5E_CPU1_P1_RX_BUF_DP<5>")
	)
	(segment
		(start 74.462132 -401.06346)
		(end 74.541634 -400.886168)
		(width 0.14224)
		(layer "In13.Cu")
		(net "P5E_CPU1_P1_RX_BUF_DP<5>")
	)
	(segment
		(start 72.353932 -401.866608)
		(end 72.433434 -401.689316)
		(width 0.14224)
		(layer "In13.Cu")
		(net "P5E_CPU1_P1_RX_BUF_DP<5>")
	)
	(segment
		(start 67.976242 -434.45811)
		(end 67.976242 -426.996606)
		(width 0.14224)
		(layer "In13.Cu")
		(net "P5E_CPU1_P1_RX_BUF_DP<5>")
	)
	(segment
		(start 74.063098 -401.215352)
		(end 74.462132 -401.06346)
		(width 0.14224)
		(layer "In13.Cu")
		(net "P5E_CPU1_P1_RX_BUF_DP<5>")
	)
	(segment
		(start 67.613276 -405.771096)
		(end 67.928744 -405.560276)
		(width 0.14224)
		(layer "In13.Cu")
		(net "P5E_CPU1_P1_RX_BUF_DP<5>")
	)
	(segment
		(start 76.586588 -400.254216)
		(end 76.665836 -400.076924)
		(width 0.14224)
		(layer "In13.Cu")
		(net "P5E_CPU1_P1_RX_BUF_DP<5>")
	)
	(segment
		(start 75.117198 -400.813778)
		(end 75.516232 -400.661886)
		(width 0.14224)
		(layer "In13.Cu")
		(net "P5E_CPU1_P1_RX_BUF_DP<5>")
	)
	(segment
		(start 66.527172 -415.134806)
		(end 66.333116 -415.134806)
		(width 0.14224)
		(layer "In13.Cu")
		(net "P5E_CPU1_P1_RX_BUF_DP<5>")
	)
	(segment
		(start 68.511674 -434.756814)
		(end 68.274946 -434.756814)
		(width 0.14224)
		(layer "In13.Cu")
		(net "P5E_CPU1_P1_RX_BUF_DP<5>")
	)
	(segment
		(start 66.333116 -415.134806)
		(end 66.06032 -414.86201)
		(width 0.14224)
		(layer "In13.Cu")
		(net "P5E_CPU1_P1_RX_BUF_DP<5>")
	)
	(segment
		(start 67.982846 -426.990002)
		(end 67.982846 -417.024058)
		(width 0.14224)
		(layer "In13.Cu")
		(net "P5E_CPU1_P1_RX_BUF_DP<5>")
	)
	(segment
		(start 66.06032 -414.667954)
		(end 65.787016 -414.39465)
		(width 0.14224)
		(layer "In13.Cu")
		(net "P5E_CPU1_P1_RX_BUF_DP<5>")
	)
	(segment
		(start 67.337686 -405.885142)
		(end 67.613276 -405.771096)
		(width 0.14224)
		(layer "In13.Cu")
		(net "P5E_CPU1_P1_RX_BUF_DP<5>")
	)
	(segment
		(start 65.214754 -413.963612)
		(end 65.214754 -411.967934)
		(width 0.14224)
		(layer "In13.Cu")
		(net "P5E_CPU1_P1_RX_BUF_DP<5>")
	)
	(segment
		(start 66.800476 -415.602166)
		(end 66.800476 -415.40811)
		(width 0.14224)
		(layer "In13.Cu")
		(net "P5E_CPU1_P1_RX_BUF_DP<5>")
	)
	(segment
		(start 67.267328 -415.874962)
		(end 67.073272 -415.874962)
		(width 0.14224)
		(layer "In13.Cu")
		(net "P5E_CPU1_P1_RX_BUF_DP<5>")
	)
	(segment
		(start 85.885274 -393.159996)
		(end 86.027514 -393.017756)
		(width 0.14224)
		(layer "In13.Cu")
		(net "P5E_CPU1_P1_RX_BUF_DP<5>")
	)
	(segment
		(start 67.540632 -416.148266)
		(end 67.267328 -415.874962)
		(width 0.14224)
		(layer "In13.Cu")
		(net "P5E_CPU1_P1_RX_BUF_DP<5>")
	)
	(segment
		(start 68.274946 -434.756814)
		(end 67.976242 -434.45811)
		(width 0.14224)
		(layer "In13.Cu")
		(net "P5E_CPU1_P1_RX_BUF_DP<5>")
	)
	(segment
		(start 67.540632 -416.342322)
		(end 67.540632 -416.148266)
		(width 0.14224)
		(layer "In13.Cu")
		(net "P5E_CPU1_P1_RX_BUF_DP<5>")
	)
	(segment
		(start 83.798918 -397.426942)
		(end 85.234018 -395.991842)
		(width 0.14224)
		(layer "In13.Cu")
		(net "P5E_CPU1_P1_RX_BUF_DP<5>")
	)
	(segment
		(start 85.349334 -395.851634)
		(end 85.801708 -395.1732)
		(width 0.14224)
		(layer "In13.Cu")
		(net "P5E_CPU1_P1_RX_BUF_DP<5>")
	)
	(segment
		(start 71.299832 -402.268182)
		(end 71.379334 -402.09089)
		(width 0.14224)
		(layer "In13.Cu")
		(net "P5E_CPU1_P1_RX_BUF_DP<5>")
	)
	(segment
		(start 86.217252 -393.017756)
		(end 86.344252 -393.144756)
		(width 0.14224)
		(layer "In13.Cu")
		(net "P5E_CPU1_P1_RX_BUF_DP<5>")
	)
	(segment
		(start 66.800476 -415.40811)
		(end 66.527172 -415.134806)
		(width 0.14224)
		(layer "In13.Cu")
		(net "P5E_CPU1_P1_RX_BUF_DP<5>")
	)
	(segment
		(start 66.746374 -408.615134)
		(end 66.746374 -408.188414)
		(width 0.14224)
		(layer "In13.Cu")
		(net "P5E_CPU1_P1_RX_BUF_DP<5>")
	)
	(segment
		(start 71.379334 -402.09089)
		(end 71.77786 -401.938998)
		(width 0.14224)
		(layer "In13.Cu")
		(net "P5E_CPU1_P1_RX_BUF_DP<5>")
	)
	(segment
		(start 70.72376 -402.340572)
		(end 70.900798 -402.420074)
		(width 0.14224)
		(layer "In13.Cu")
		(net "P5E_CPU1_P1_RX_BUF_DP<5>")
	)
	(segment
		(start 85.801708 -395.173454)
		(end 85.801962 -395.172946)
		(width 0.14224)
		(layer "In13.Cu")
		(net "P5E_CPU1_P1_RX_BUF_DP<5>")
	)
	(segment
		(start 65.59296 -414.39465)
		(end 65.252092 -414.053782)
		(width 0.14224)
		(layer "In13.Cu")
		(net "P5E_CPU1_P1_RX_BUF_DP<5>")
	)
	(segment
		(start 77.164946 -399.886932)
		(end 80.592422 -398.7546)
		(width 0.14224)
		(layer "In13.Cu")
		(net "P5E_CPU1_P1_RX_BUF_DP<5>")
	)
	(segment
		(start 72.433434 -401.689316)
		(end 72.83196 -401.537424)
		(width 0.14224)
		(layer "In13.Cu")
		(net "P5E_CPU1_P1_RX_BUF_DP<5>")
	)
	(segment
		(start 65.787016 -414.39465)
		(end 65.59296 -414.39465)
		(width 0.14224)
		(layer "In13.Cu")
		(net "P5E_CPU1_P1_RX_BUF_DP<5>")
	)
	(segment
		(start 80.592422 -398.7546)
		(end 83.798918 -397.426942)
		(width 0.14224)
		(layer "In13.Cu")
		(net "P5E_CPU1_P1_RX_BUF_DP<5>")
	)
	(segment
		(start 85.801708 -395.1732)
		(end 85.801708 -395.173454)
		(width 0.14224)
		(layer "In13.Cu")
		(net "P5E_CPU1_P1_RX_BUF_DP<5>")
	)
	(segment
		(start 67.073272 -415.874962)
		(end 66.800476 -415.602166)
		(width 0.14224)
		(layer "In13.Cu")
		(net "P5E_CPU1_P1_RX_BUF_DP<5>")
	)
	(segment
		(start 66.883534 -408.051254)
		(end 66.883534 -407.624534)
		(width 0.14224)
		(layer "In13.Cu")
		(net "P5E_CPU1_P1_RX_BUF_DP<5>")
	)
	(segment
		(start 76.010516 -400.326606)
		(end 76.187554 -400.406108)
		(width 0.14224)
		(layer "In13.Cu")
		(net "P5E_CPU1_P1_RX_BUF_DP<5>")
	)
	(segment
		(start 76.187554 -400.406108)
		(end 76.586588 -400.254216)
		(width 0.14224)
		(layer "In13.Cu")
		(net "P5E_CPU1_P1_RX_BUF_DP<5>")
	)
	(segment
		(start 75.516232 -400.661886)
		(end 75.595734 -400.484594)
		(width 0.14224)
		(layer "In13.Cu")
		(net "P5E_CPU1_P1_RX_BUF_DP<5>")
	)
	(segment
		(start 67.928744 -405.560276)
		(end 68.075556 -405.413464)
		(width 0.14224)
		(layer "In13.Cu")
		(net "P5E_CPU1_P1_RX_BUF_DP<5>")
	)
	(segment
		(start 66.06032 -414.86201)
		(end 66.06032 -414.667954)
		(width 0.14224)
		(layer "In13.Cu")
		(net "P5E_CPU1_P1_RX_BUF_DP<5>")
	)
	(segment
		(start 66.746374 -407.487374)
		(end 66.746374 -406.638252)
		(width 0.14224)
		(layer "In13.Cu")
		(net "P5E_CPU1_P1_RX_BUF_DP<5>")
	)
	(segment
		(start 86.027514 -393.017756)
		(end 86.217252 -393.017756)
		(width 0.14224)
		(layer "In13.Cu")
		(net "P5E_CPU1_P1_RX_BUF_DP<5>")
	)
	(segment
		(start 73.008998 -401.616926)
		(end 73.408032 -401.465034)
		(width 0.14224)
		(layer "In13.Cu")
		(net "P5E_CPU1_P1_RX_BUF_DP<5>")
	)
	(segment
		(start 69.281548 -403.060662)
		(end 70.325234 -402.492464)
		(width 0.14224)
		(layer "In13.Cu")
		(net "P5E_CPU1_P1_RX_BUF_DP<5>")
	)
	(segment
		(start 73.408032 -401.465034)
		(end 73.487534 -401.287742)
		(width 0.14224)
		(layer "In13.Cu")
		(net "P5E_CPU1_P1_RX_BUF_DP<5>")
	)
	(segment
		(start 70.325234 -402.492464)
		(end 70.72376 -402.340572)
		(width 0.14224)
		(layer "In13.Cu")
		(net "P5E_CPU1_P1_RX_BUF_DP<5>")
	)
	(segment
		(start 65.427352 -411.624526)
		(end 66.237358 -411.36062)
		(width 0.14224)
		(layer "In13.Cu")
		(net "P5E_CPU1_P1_RX_BUF_DP<5>")
	)
	(segment
		(start 68.64985 -434.618638)
		(end 68.511674 -434.756814)
		(width 0.14224)
		(layer "In13.Cu")
		(net "P5E_CPU1_P1_RX_BUF_DP<5>")
	)
	(segment
		(start 67.813428 -416.615118)
		(end 67.540632 -416.342322)
		(width 0.14224)
		(layer "In13.Cu")
		(net "P5E_CPU1_P1_RX_BUF_DP<5>")
	)
	(segment
		(start 75.595734 -400.484594)
		(end 76.010516 -400.326606)
		(width 0.14224)
		(layer "In13.Cu")
		(net "P5E_CPU1_P1_RX_BUF_DP<5>")
	)
	(segment
		(start 74.541634 -400.886168)
		(end 74.94016 -400.734276)
		(width 0.14224)
		(layer "In13.Cu")
		(net "P5E_CPU1_P1_RX_BUF_DP<5>")
	)
	(segment
		(start 74.94016 -400.734276)
		(end 75.117198 -400.813778)
		(width 0.14224)
		(layer "In13.Cu")
		(net "P5E_CPU1_P1_RX_BUF_DP<5>")
	)
	(segment
		(start 70.900798 -402.420074)
		(end 71.299832 -402.268182)
		(width 0.14224)
		(layer "In13.Cu")
		(net "P5E_CPU1_P1_RX_BUF_DP<5>")
	)
	(segment
		(start 71.954898 -402.0185)
		(end 72.353932 -401.866608)
		(width 0.14224)
		(layer "In13.Cu")
		(net "P5E_CPU1_P1_RX_BUF_DP<5>")
	)
	(segment
		(start 72.83196 -401.537424)
		(end 73.008998 -401.616926)
		(width 0.14224)
		(layer "In13.Cu")
		(net "P5E_CPU1_P1_RX_BUF_DP<5>")
	)
	(segment
		(start 73.88606 -401.13585)
		(end 74.063098 -401.215352)
		(width 0.14224)
		(layer "In13.Cu")
		(net "P5E_CPU1_P1_RX_BUF_DP<5>")
	)
	(segment
		(start 85.885274 -394.896594)
		(end 85.885274 -393.159996)
		(width 0.14224)
		(layer "In13.Cu")
		(net "P5E_CPU1_P1_RX_BUF_DP<5>")
	)
	(segment
		(start 68.277994 -404.924514)
		(end 68.277994 -404.09622)
		(width 0.14224)
		(layer "In13.Cu")
		(net "P5E_CPU1_P1_RX_BUF_DP<5>")
	)
	(segment
		(start 66.746374 -408.188414)
		(end 66.883534 -408.051254)
		(width 0.14224)
		(layer "In13.Cu")
		(net "P5E_CPU1_P1_RX_BUF_DP<5>")
	)
	(segment
		(start 68.64985 -434.289962)
		(end 68.64985 -434.618638)
		(width 0.14224)
		(layer "In13.Cu")
		(net "P5E_CPU1_P1_RX_BUF_DP<5>")
	)
	(segment
		(start 71.77786 -401.938998)
		(end 71.954898 -402.0185)
		(width 0.14224)
		(layer "In13.Cu")
		(net "P5E_CPU1_P1_RX_BUF_DP<5>")
	)
	(segment
		(start 66.746374 -409.316174)
		(end 66.883534 -409.179014)
		(width 0.14224)
		(layer "In13.Cu")
		(net "P5E_CPU1_P1_RX_BUF_DP<5>")
	)
	(segment
		(start 66.883534 -408.752294)
		(end 66.746374 -408.615134)
		(width 0.14224)
		(layer "In13.Cu")
		(net "P5E_CPU1_P1_RX_BUF_DP<5>")
	)
	(segment
		(start 66.883534 -409.179014)
		(end 66.883534 -408.752294)
		(width 0.14224)
		(layer "In13.Cu")
		(net "P5E_CPU1_P1_RX_BUF_DP<5>")
	)
	(segment
		(start 66.883534 -407.624534)
		(end 66.746374 -407.487374)
		(width 0.14224)
		(layer "In13.Cu")
		(net "P5E_CPU1_P1_RX_BUF_DP<5>")
	)
	(segment
		(start 76.665836 -400.076924)
		(end 77.164946 -399.886932)
		(width 0.14224)
		(layer "In13.Cu")
		(net "P5E_CPU1_P1_RX_BUF_DP<5>")
	)
	(segment
		(start 73.487534 -401.287742)
		(end 73.88606 -401.13585)
		(width 0.14224)
		(layer "In13.Cu")
		(net "P5E_CPU1_P1_RX_BUF_DP<5>")
	)
	(arc
		(start 68.075556 -405.413464)
		(mid 68.225396 -405.189118)
		(end 68.277994 -404.924514)
		(width 0.14224)
		(layer "In13.Cu")
		(net "P5E_CPU1_P1_RX_BUF_DP<5>")
	)
	(arc
		(start 66.746374 -406.638252)
		(mid 66.799603 -406.370451)
		(end 66.951352 -406.14346)
		(width 0.14224)
		(layer "In13.Cu")
		(net "P5E_CPU1_P1_RX_BUF_DP<5>")
	)
	(arc
		(start 65.235074 -411.842966)
		(mid 65.270674 -411.764025)
		(end 65.321434 -411.693868)
		(width 0.14224)
		(layer "In13.Cu")
		(net "P5E_CPU1_P1_RX_BUF_DP<5>")
	)
	(arc
		(start 66.237358 -411.36062)
		(mid 66.328537 -411.317893)
		(end 66.406522 -411.254194)
		(width 0.14224)
		(layer "In13.Cu")
		(net "P5E_CPU1_P1_RX_BUF_DP<5>")
	)
	(arc
		(start 65.321434 -411.693868)
		(mid 65.369803 -411.652194)
		(end 65.427352 -411.624526)
		(width 0.14224)
		(layer "In13.Cu")
		(net "P5E_CPU1_P1_RX_BUF_DP<5>")
	)
	(arc
		(start 67.982846 -417.024058)
		(mid 67.938821 -416.80273)
		(end 67.813428 -416.615118)
		(width 0.14224)
		(layer "In13.Cu")
		(net "P5E_CPU1_P1_RX_BUF_DP<5>")
	)
	(arc
		(start 85.801962 -395.172946)
		(mid 85.864118 -395.040948)
		(end 85.885274 -394.896594)
		(width 0.14224)
		(layer "In13.Cu")
		(net "P5E_CPU1_P1_RX_BUF_DP<5>")
	)
	(arc
		(start 68.592446 -403.576028)
		(mid 68.918494 -403.293605)
		(end 69.281548 -403.060662)
		(width 0.14224)
		(layer "In13.Cu")
		(net "P5E_CPU1_P1_RX_BUF_DP<5>")
	)
	(arc
		(start 85.234018 -395.991842)
		(mid 85.29512 -395.924571)
		(end 85.349334 -395.851634)
		(width 0.14224)
		(layer "In13.Cu")
		(net "P5E_CPU1_P1_RX_BUF_DP<5>")
	)
	(arc
		(start 66.576956 -411.075632)
		(mid 66.702446 -410.88052)
		(end 66.746374 -410.652722)
		(width 0.14224)
		(layer "In13.Cu")
		(net "P5E_CPU1_P1_RX_BUF_DP<5>")
	)
	(arc
		(start 65.214754 -411.967934)
		(mid 65.219846 -411.904626)
		(end 65.235074 -411.842966)
		(width 0.14224)
		(layer "In13.Cu")
		(net "P5E_CPU1_P1_RX_BUF_DP<5>")
	)
	(arc
		(start 68.277994 -404.09622)
		(mid 68.315812 -403.906094)
		(end 68.423536 -403.744938)
		(width 0.14224)
		(layer "In13.Cu")
		(net "P5E_CPU1_P1_RX_BUF_DP<5>")
	)
	(arc
		(start 65.252092 -414.053782)
		(mid 65.224449 -414.012412)
		(end 65.214754 -413.963612)
		(width 0.14224)
		(layer "In13.Cu")
		(net "P5E_CPU1_P1_RX_BUF_DP<5>")
	)
	(arc
		(start 66.951352 -406.14346)
		(mid 67.131822 -405.995314)
		(end 67.337686 -405.885142)
		(width 0.14224)
		(layer "In13.Cu")
		(net "P5E_CPU1_P1_RX_BUF_DP<5>")
	)
	(segment
		(start 84.530438 -391.488676)
		(end 84.441792 -391.577322)
		(width 0.1016)
		(layer "F.Cu")
		(net "P5E_CPU1_P1_RX_BUF_DP<4>")
	)
	(segment
		(start 84.445856 -391.281158)
		(end 84.530438 -391.36574)
		(width 0.1016)
		(layer "F.Cu")
		(net "P5E_CPU1_P1_RX_BUF_DP<4>")
	)
	(segment
		(start 85.005672 -392.977116)
		(end 85.144356 -393.1158)
		(width 0.1016)
		(layer "F.Cu")
		(net "P5E_CPU1_P1_RX_BUF_DP<4>")
	)
	(segment
		(start 84.441792 -392.723878)
		(end 84.69503 -392.977116)
		(width 0.1016)
		(layer "F.Cu")
		(net "P5E_CPU1_P1_RX_BUF_DP<4>")
	)
	(segment
		(start 84.441792 -391.577322)
		(end 84.441792 -392.723878)
		(width 0.1016)
		(layer "F.Cu")
		(net "P5E_CPU1_P1_RX_BUF_DP<4>")
	)
	(segment
		(start 84.69503 -392.977116)
		(end 85.005672 -392.977116)
		(width 0.1016)
		(layer "F.Cu")
		(net "P5E_CPU1_P1_RX_BUF_DP<4>")
	)
	(segment
		(start 85.144356 -393.1158)
		(end 85.144356 -393.292838)
		(width 0.1016)
		(layer "F.Cu")
		(net "P5E_CPU1_P1_RX_BUF_DP<4>")
	)
	(segment
		(start 84.530438 -391.36574)
		(end 84.530438 -391.488676)
		(width 0.1016)
		(layer "F.Cu")
		(net "P5E_CPU1_P1_RX_BUF_DP<4>")
	)
	(segment
		(start 74.010774 -399.949162)
		(end 74.097896 -399.77568)
		(width 0.14224)
		(layer "In13.Cu")
		(net "P5E_CPU1_P1_RX_BUF_DP<4>")
	)
	(segment
		(start 68.204334 -402.250656)
		(end 68.596764 -402.082762)
		(width 0.14224)
		(layer "In13.Cu")
		(net "P5E_CPU1_P1_RX_BUF_DP<4>")
	)
	(segment
		(start 63.683134 -409.497784)
		(end 63.820294 -409.360624)
		(width 0.14224)
		(layer "In13.Cu")
		(net "P5E_CPU1_P1_RX_BUF_DP<4>")
	)
	(segment
		(start 63.116714 -414.157922)
		(end 62.84341 -413.884618)
		(width 0.14224)
		(layer "In13.Cu")
		(net "P5E_CPU1_P1_RX_BUF_DP<4>")
	)
	(segment
		(start 72.046338 -400.45513)
		(end 73.432162 -399.996152)
		(width 0.14224)
		(layer "In13.Cu")
		(net "P5E_CPU1_P1_RX_BUF_DP<4>")
	)
	(segment
		(start 65.971166 -426.873162)
		(end 65.971166 -417.60902)
		(width 0.14224)
		(layer "In13.Cu")
		(net "P5E_CPU1_P1_RX_BUF_DP<4>")
	)
	(segment
		(start 69.241162 -401.80641)
		(end 69.633592 -401.638516)
		(width 0.14224)
		(layer "In13.Cu")
		(net "P5E_CPU1_P1_RX_BUF_DP<4>")
	)
	(segment
		(start 63.683134 -410.697172)
		(end 63.683134 -409.497784)
		(width 0.14224)
		(layer "In13.Cu")
		(net "P5E_CPU1_P1_RX_BUF_DP<4>")
	)
	(segment
		(start 62.151514 -413.287464)
		(end 62.151514 -411.853126)
		(width 0.14224)
		(layer "In13.Cu")
		(net "P5E_CPU1_P1_RX_BUF_DP<4>")
	)
	(segment
		(start 74.097896 -399.77568)
		(end 78.621382 -398.277588)
		(width 0.14224)
		(layer "In13.Cu")
		(net "P5E_CPU1_P1_RX_BUF_DP<4>")
	)
	(segment
		(start 63.583566 -414.624774)
		(end 63.38951 -414.624774)
		(width 0.14224)
		(layer "In13.Cu")
		(net "P5E_CPU1_P1_RX_BUF_DP<4>")
	)
	(segment
		(start 67.559936 -402.527008)
		(end 67.632072 -402.346668)
		(width 0.14224)
		(layer "In13.Cu")
		(net "P5E_CPU1_P1_RX_BUF_DP<4>")
	)
	(segment
		(start 80.435704 -397.793972)
		(end 83.215988 -396.641574)
		(width 0.14224)
		(layer "In13.Cu")
		(net "P5E_CPU1_P1_RX_BUF_DP<4>")
	)
	(segment
		(start 62.245494 -411.71241)
		(end 63.191644 -411.31998)
		(width 0.14224)
		(layer "In13.Cu")
		(net "P5E_CPU1_P1_RX_BUF_DP<4>")
	)
	(segment
		(start 78.621382 -398.277588)
		(end 80.368902 -397.816578)
		(width 0.14224)
		(layer "In13.Cu")
		(net "P5E_CPU1_P1_RX_BUF_DP<4>")
	)
	(segment
		(start 68.596764 -402.082762)
		(end 68.6689 -401.902422)
		(width 0.14224)
		(layer "In13.Cu")
		(net "P5E_CPU1_P1_RX_BUF_DP<4>")
	)
	(segment
		(start 85.144356 -393.144756)
		(end 85.144356 -393.292838)
		(width 0.14224)
		(layer "In13.Cu")
		(net "P5E_CPU1_P1_RX_BUF_DP<4>")
	)
	(segment
		(start 66.98742 -402.62302)
		(end 67.167506 -402.694902)
		(width 0.14224)
		(layer "In13.Cu")
		(net "P5E_CPU1_P1_RX_BUF_DP<4>")
	)
	(segment
		(start 63.820294 -408.933904)
		(end 63.683134 -408.796744)
		(width 0.14224)
		(layer "In13.Cu")
		(net "P5E_CPU1_P1_RX_BUF_DP<4>")
	)
	(segment
		(start 62.84341 -413.884618)
		(end 62.649354 -413.884618)
		(width 0.14224)
		(layer "In13.Cu")
		(net "P5E_CPU1_P1_RX_BUF_DP<4>")
	)
	(segment
		(start 65.686432 -416.921696)
		(end 65.423288 -416.658552)
		(width 0.14224)
		(layer "In13.Cu")
		(net "P5E_CPU1_P1_RX_BUF_DP<4>")
	)
	(segment
		(start 80.368902 -397.816578)
		(end 80.435704 -397.793972)
		(width 0.14224)
		(layer "In13.Cu")
		(net "P5E_CPU1_P1_RX_BUF_DP<4>")
	)
	(segment
		(start 73.432162 -399.996152)
		(end 73.60539 -400.083274)
		(width 0.14224)
		(layer "In13.Cu")
		(net "P5E_CPU1_P1_RX_BUF_DP<4>")
	)
	(segment
		(start 67.632072 -402.346668)
		(end 68.024248 -402.178774)
		(width 0.14224)
		(layer "In13.Cu")
		(net "P5E_CPU1_P1_RX_BUF_DP<4>")
	)
	(segment
		(start 69.633592 -401.638516)
		(end 69.705728 -401.458176)
		(width 0.14224)
		(layer "In13.Cu")
		(net "P5E_CPU1_P1_RX_BUF_DP<4>")
	)
	(segment
		(start 63.683134 -407.62555)
		(end 63.683134 -406.638252)
		(width 0.14224)
		(layer "In13.Cu")
		(net "P5E_CPU1_P1_RX_BUF_DP<4>")
	)
	(segment
		(start 63.85687 -414.898078)
		(end 63.583566 -414.624774)
		(width 0.14224)
		(layer "In13.Cu")
		(net "P5E_CPU1_P1_RX_BUF_DP<4>")
	)
	(segment
		(start 64.865504 -405.560276)
		(end 65.012316 -405.413464)
		(width 0.14224)
		(layer "In13.Cu")
		(net "P5E_CPU1_P1_RX_BUF_DP<4>")
	)
	(segment
		(start 64.625728 -415.860992)
		(end 64.625728 -415.666936)
		(width 0.14224)
		(layer "In13.Cu")
		(net "P5E_CPU1_P1_RX_BUF_DP<4>")
	)
	(segment
		(start 65.214754 -404.924514)
		(end 65.214754 -404.07844)
		(width 0.14224)
		(layer "In13.Cu")
		(net "P5E_CPU1_P1_RX_BUF_DP<4>")
	)
	(segment
		(start 69.705728 -401.458176)
		(end 72.046338 -400.45513)
		(width 0.14224)
		(layer "In13.Cu")
		(net "P5E_CPU1_P1_RX_BUF_DP<4>")
	)
	(segment
		(start 65.423288 -416.658552)
		(end 65.423288 -416.464496)
		(width 0.14224)
		(layer "In13.Cu")
		(net "P5E_CPU1_P1_RX_BUF_DP<4>")
	)
	(segment
		(start 63.820294 -408.18943)
		(end 63.820294 -407.76271)
		(width 0.14224)
		(layer "In13.Cu")
		(net "P5E_CPU1_P1_RX_BUF_DP<4>")
	)
	(segment
		(start 67.167506 -402.694902)
		(end 67.559936 -402.527008)
		(width 0.14224)
		(layer "In13.Cu")
		(net "P5E_CPU1_P1_RX_BUF_DP<4>")
	)
	(segment
		(start 64.129666 -415.36493)
		(end 63.85687 -415.092134)
		(width 0.14224)
		(layer "In13.Cu")
		(net "P5E_CPU1_P1_RX_BUF_DP<4>")
	)
	(segment
		(start 64.927226 -416.16249)
		(end 64.625728 -415.860992)
		(width 0.14224)
		(layer "In13.Cu")
		(net "P5E_CPU1_P1_RX_BUF_DP<4>")
	)
	(segment
		(start 66.649854 -433.289964)
		(end 66.649854 -433.61864)
		(width 0.14224)
		(layer "In13.Cu")
		(net "P5E_CPU1_P1_RX_BUF_DP<4>")
	)
	(segment
		(start 85.017356 -393.017756)
		(end 85.144356 -393.144756)
		(width 0.14224)
		(layer "In13.Cu")
		(net "P5E_CPU1_P1_RX_BUF_DP<4>")
	)
	(segment
		(start 63.85687 -415.092134)
		(end 63.85687 -414.898078)
		(width 0.14224)
		(layer "In13.Cu")
		(net "P5E_CPU1_P1_RX_BUF_DP<4>")
	)
	(segment
		(start 63.683134 -408.32659)
		(end 63.820294 -408.18943)
		(width 0.14224)
		(layer "In13.Cu")
		(net "P5E_CPU1_P1_RX_BUF_DP<4>")
	)
	(segment
		(start 84.685378 -394.769594)
		(end 84.685378 -393.159996)
		(width 0.14224)
		(layer "In13.Cu")
		(net "P5E_CPU1_P1_RX_BUF_DP<4>")
	)
	(segment
		(start 65.976246 -426.878242)
		(end 65.971166 -426.873162)
		(width 0.14224)
		(layer "In13.Cu")
		(net "P5E_CPU1_P1_RX_BUF_DP<4>")
	)
	(segment
		(start 65.976246 -433.458112)
		(end 65.976246 -426.878242)
		(width 0.14224)
		(layer "In13.Cu")
		(net "P5E_CPU1_P1_RX_BUF_DP<4>")
	)
	(segment
		(start 66.511678 -433.756816)
		(end 66.27495 -433.756816)
		(width 0.14224)
		(layer "In13.Cu")
		(net "P5E_CPU1_P1_RX_BUF_DP<4>")
	)
	(segment
		(start 84.685378 -393.159996)
		(end 84.827618 -393.017756)
		(width 0.14224)
		(layer "In13.Cu")
		(net "P5E_CPU1_P1_RX_BUF_DP<4>")
	)
	(segment
		(start 66.649854 -433.61864)
		(end 66.511678 -433.756816)
		(width 0.14224)
		(layer "In13.Cu")
		(net "P5E_CPU1_P1_RX_BUF_DP<4>")
	)
	(segment
		(start 69.061076 -401.734528)
		(end 69.241162 -401.80641)
		(width 0.14224)
		(layer "In13.Cu")
		(net "P5E_CPU1_P1_RX_BUF_DP<4>")
	)
	(segment
		(start 63.820294 -409.360624)
		(end 63.820294 -408.933904)
		(width 0.14224)
		(layer "In13.Cu")
		(net "P5E_CPU1_P1_RX_BUF_DP<4>")
	)
	(segment
		(start 64.625728 -415.666936)
		(end 64.323722 -415.36493)
		(width 0.14224)
		(layer "In13.Cu")
		(net "P5E_CPU1_P1_RX_BUF_DP<4>")
	)
	(segment
		(start 84.22513 -395.632432)
		(end 84.49564 -395.22781)
		(width 0.14224)
		(layer "In13.Cu")
		(net "P5E_CPU1_P1_RX_BUF_DP<4>")
	)
	(segment
		(start 68.6689 -401.902422)
		(end 69.061076 -401.734528)
		(width 0.14224)
		(layer "In13.Cu")
		(net "P5E_CPU1_P1_RX_BUF_DP<4>")
	)
	(segment
		(start 83.215988 -396.641574)
		(end 84.22513 -395.632432)
		(width 0.14224)
		(layer "In13.Cu")
		(net "P5E_CPU1_P1_RX_BUF_DP<4>")
	)
	(segment
		(start 62.649354 -413.884618)
		(end 62.221618 -413.456882)
		(width 0.14224)
		(layer "In13.Cu")
		(net "P5E_CPU1_P1_RX_BUF_DP<4>")
	)
	(segment
		(start 65.121282 -416.16249)
		(end 64.927226 -416.16249)
		(width 0.14224)
		(layer "In13.Cu")
		(net "P5E_CPU1_P1_RX_BUF_DP<4>")
	)
	(segment
		(start 84.49564 -395.22781)
		(end 84.685378 -394.769594)
		(width 0.14224)
		(layer "In13.Cu")
		(net "P5E_CPU1_P1_RX_BUF_DP<4>")
	)
	(segment
		(start 65.423288 -416.464496)
		(end 65.121282 -416.16249)
		(width 0.14224)
		(layer "In13.Cu")
		(net "P5E_CPU1_P1_RX_BUF_DP<4>")
	)
	(segment
		(start 64.323722 -415.36493)
		(end 64.129666 -415.36493)
		(width 0.14224)
		(layer "In13.Cu")
		(net "P5E_CPU1_P1_RX_BUF_DP<4>")
	)
	(segment
		(start 64.550036 -405.771096)
		(end 64.865504 -405.560276)
		(width 0.14224)
		(layer "In13.Cu")
		(net "P5E_CPU1_P1_RX_BUF_DP<4>")
	)
	(segment
		(start 64.274446 -405.885142)
		(end 64.550036 -405.771096)
		(width 0.14224)
		(layer "In13.Cu")
		(net "P5E_CPU1_P1_RX_BUF_DP<4>")
	)
	(segment
		(start 63.38951 -414.624774)
		(end 63.116714 -414.351978)
		(width 0.14224)
		(layer "In13.Cu")
		(net "P5E_CPU1_P1_RX_BUF_DP<4>")
	)
	(segment
		(start 65.406016 -403.616668)
		(end 65.47104 -403.551644)
		(width 0.14224)
		(layer "In13.Cu")
		(net "P5E_CPU1_P1_RX_BUF_DP<4>")
	)
	(segment
		(start 63.116714 -414.351978)
		(end 63.116714 -414.157922)
		(width 0.14224)
		(layer "In13.Cu")
		(net "P5E_CPU1_P1_RX_BUF_DP<4>")
	)
	(segment
		(start 84.827618 -393.017756)
		(end 85.017356 -393.017756)
		(width 0.14224)
		(layer "In13.Cu")
		(net "P5E_CPU1_P1_RX_BUF_DP<4>")
	)
	(segment
		(start 68.024248 -402.178774)
		(end 68.204334 -402.250656)
		(width 0.14224)
		(layer "In13.Cu")
		(net "P5E_CPU1_P1_RX_BUF_DP<4>")
	)
	(segment
		(start 63.683134 -408.796744)
		(end 63.683134 -408.32659)
		(width 0.14224)
		(layer "In13.Cu")
		(net "P5E_CPU1_P1_RX_BUF_DP<4>")
	)
	(segment
		(start 63.820294 -407.76271)
		(end 63.683134 -407.62555)
		(width 0.14224)
		(layer "In13.Cu")
		(net "P5E_CPU1_P1_RX_BUF_DP<4>")
	)
	(segment
		(start 66.595244 -402.790914)
		(end 66.98742 -402.62302)
		(width 0.14224)
		(layer "In13.Cu")
		(net "P5E_CPU1_P1_RX_BUF_DP<4>")
	)
	(segment
		(start 73.60539 -400.083274)
		(end 74.010774 -399.949162)
		(width 0.14224)
		(layer "In13.Cu")
		(net "P5E_CPU1_P1_RX_BUF_DP<4>")
	)
	(segment
		(start 66.27495 -433.756816)
		(end 65.976246 -433.458112)
		(width 0.14224)
		(layer "In13.Cu")
		(net "P5E_CPU1_P1_RX_BUF_DP<4>")
	)
	(arc
		(start 65.214754 -404.07844)
		(mid 65.264463 -403.828535)
		(end 65.406016 -403.616668)
		(width 0.14224)
		(layer "In13.Cu")
		(net "P5E_CPU1_P1_RX_BUF_DP<4>")
	)
	(arc
		(start 62.151514 -411.853126)
		(mid 62.177164 -411.768508)
		(end 62.245494 -411.71241)
		(width 0.14224)
		(layer "In13.Cu")
		(net "P5E_CPU1_P1_RX_BUF_DP<4>")
	)
	(arc
		(start 63.191644 -411.31998)
		(mid 63.364307 -411.222661)
		(end 63.508382 -411.086554)
		(width 0.14224)
		(layer "In13.Cu")
		(net "P5E_CPU1_P1_RX_BUF_DP<4>")
	)
	(arc
		(start 65.012316 -405.413464)
		(mid 65.162156 -405.189118)
		(end 65.214754 -404.924514)
		(width 0.14224)
		(layer "In13.Cu")
		(net "P5E_CPU1_P1_RX_BUF_DP<4>")
	)
	(arc
		(start 63.888112 -406.14346)
		(mid 64.068582 -405.995314)
		(end 64.274446 -405.885142)
		(width 0.14224)
		(layer "In13.Cu")
		(net "P5E_CPU1_P1_RX_BUF_DP<4>")
	)
	(arc
		(start 63.683134 -406.638252)
		(mid 63.736363 -406.370451)
		(end 63.888112 -406.14346)
		(width 0.14224)
		(layer "In13.Cu")
		(net "P5E_CPU1_P1_RX_BUF_DP<4>")
	)
	(arc
		(start 62.221618 -413.456882)
		(mid 62.169734 -413.379138)
		(end 62.151514 -413.287464)
		(width 0.14224)
		(layer "In13.Cu")
		(net "P5E_CPU1_P1_RX_BUF_DP<4>")
	)
	(arc
		(start 63.508382 -411.086554)
		(mid 63.637535 -410.910605)
		(end 63.683134 -410.697172)
		(width 0.14224)
		(layer "In13.Cu")
		(net "P5E_CPU1_P1_RX_BUF_DP<4>")
	)
	(arc
		(start 65.47104 -403.551644)
		(mid 65.99683 -403.117616)
		(end 66.595244 -402.790914)
		(width 0.14224)
		(layer "In13.Cu")
		(net "P5E_CPU1_P1_RX_BUF_DP<4>")
	)
	(arc
		(start 65.971166 -417.60902)
		(mid 65.897172 -417.23703)
		(end 65.686432 -416.921696)
		(width 0.14224)
		(layer "In13.Cu")
		(net "P5E_CPU1_P1_RX_BUF_DP<4>")
	)
	(segment
		(start 83.805522 -392.977116)
		(end 83.944206 -393.1158)
		(width 0.1016)
		(layer "F.Cu")
		(net "P5E_CPU1_P1_RX_BUF_DP<3>")
	)
	(segment
		(start 83.25485 -391.564114)
		(end 83.25485 -392.723878)
		(width 0.1016)
		(layer "F.Cu")
		(net "P5E_CPU1_P1_RX_BUF_DP<3>")
	)
	(segment
		(start 83.330288 -391.488676)
		(end 83.25485 -391.564114)
		(width 0.1016)
		(layer "F.Cu")
		(net "P5E_CPU1_P1_RX_BUF_DP<3>")
	)
	(segment
		(start 83.245706 -391.281158)
		(end 83.330288 -391.36574)
		(width 0.1016)
		(layer "F.Cu")
		(net "P5E_CPU1_P1_RX_BUF_DP<3>")
	)
	(segment
		(start 83.944206 -393.1158)
		(end 83.944206 -393.292838)
		(width 0.1016)
		(layer "F.Cu")
		(net "P5E_CPU1_P1_RX_BUF_DP<3>")
	)
	(segment
		(start 83.508088 -392.977116)
		(end 83.805522 -392.977116)
		(width 0.1016)
		(layer "F.Cu")
		(net "P5E_CPU1_P1_RX_BUF_DP<3>")
	)
	(segment
		(start 83.25485 -392.723878)
		(end 83.508088 -392.977116)
		(width 0.1016)
		(layer "F.Cu")
		(net "P5E_CPU1_P1_RX_BUF_DP<3>")
	)
	(segment
		(start 83.330288 -391.36574)
		(end 83.330288 -391.488676)
		(width 0.1016)
		(layer "F.Cu")
		(net "P5E_CPU1_P1_RX_BUF_DP<3>")
	)
	(segment
		(start 63.959486 -402.499576)
		(end 64.137032 -402.578062)
		(width 0.14224)
		(layer "In13.Cu")
		(net "P5E_CPU1_P1_RX_BUF_DP<3>")
	)
	(segment
		(start 64.511682 -434.756814)
		(end 64.274954 -434.756814)
		(width 0.14224)
		(layer "In13.Cu")
		(net "P5E_CPU1_P1_RX_BUF_DP<3>")
	)
	(segment
		(start 63.97625 -434.45811)
		(end 63.97625 -426.878242)
		(width 0.14224)
		(layer "In13.Cu")
		(net "P5E_CPU1_P1_RX_BUF_DP<3>")
	)
	(segment
		(start 62.19825 -415.914586)
		(end 61.896752 -415.613088)
		(width 0.14224)
		(layer "In13.Cu")
		(net "P5E_CPU1_P1_RX_BUF_DP<3>")
	)
	(segment
		(start 66.500502 -401.519898)
		(end 66.677794 -401.598384)
		(width 0.14224)
		(layer "In13.Cu")
		(net "P5E_CPU1_P1_RX_BUF_DP<3>")
	)
	(segment
		(start 60.85459 -414.37687)
		(end 60.660534 -414.37687)
		(width 0.14224)
		(layer "In13.Cu")
		(net "P5E_CPU1_P1_RX_BUF_DP<3>")
	)
	(segment
		(start 74.1934 -398.748758)
		(end 74.740008 -398.571974)
		(width 0.14224)
		(layer "In13.Cu")
		(net "P5E_CPU1_P1_RX_BUF_DP<3>")
	)
	(segment
		(start 64.649858 -434.618638)
		(end 64.511682 -434.756814)
		(width 0.14224)
		(layer "In13.Cu")
		(net "P5E_CPU1_P1_RX_BUF_DP<3>")
	)
	(segment
		(start 61.896752 -415.419032)
		(end 61.594746 -415.117026)
		(width 0.14224)
		(layer "In13.Cu")
		(net "P5E_CPU1_P1_RX_BUF_DP<3>")
	)
	(segment
		(start 61.802264 -405.560276)
		(end 61.949076 -405.413464)
		(width 0.14224)
		(layer "In13.Cu")
		(net "P5E_CPU1_P1_RX_BUF_DP<3>")
	)
	(segment
		(start 81.488788 -396.348204)
		(end 82.38998 -395.950694)
		(width 0.14224)
		(layer "In13.Cu")
		(net "P5E_CPU1_P1_RX_BUF_DP<3>")
	)
	(segment
		(start 77.943202 -397.468852)
		(end 79.876142 -396.959328)
		(width 0.14224)
		(layer "In13.Cu")
		(net "P5E_CPU1_P1_RX_BUF_DP<3>")
	)
	(segment
		(start 82.38998 -395.950694)
		(end 82.761582 -395.71041)
		(width 0.14224)
		(layer "In13.Cu")
		(net "P5E_CPU1_P1_RX_BUF_DP<3>")
	)
	(segment
		(start 65.234566 -402.008086)
		(end 65.411858 -402.086572)
		(width 0.14224)
		(layer "In13.Cu")
		(net "P5E_CPU1_P1_RX_BUF_DP<3>")
	)
	(segment
		(start 61.594746 -415.117026)
		(end 61.40069 -415.117026)
		(width 0.14224)
		(layer "In13.Cu")
		(net "P5E_CPU1_P1_RX_BUF_DP<3>")
	)
	(segment
		(start 59.779408 -413.836104)
		(end 59.653932 -413.836104)
		(width 0.14224)
		(layer "In13.Cu")
		(net "P5E_CPU1_P1_RX_BUF_DP<3>")
	)
	(segment
		(start 62.694058 -416.216592)
		(end 62.392052 -415.914586)
		(width 0.14224)
		(layer "In13.Cu")
		(net "P5E_CPU1_P1_RX_BUF_DP<3>")
	)
	(segment
		(start 72.128888 -399.349976)
		(end 74.113644 -398.707864)
		(width 0.14224)
		(layer "In13.Cu")
		(net "P5E_CPU1_P1_RX_BUF_DP<3>")
	)
	(segment
		(start 64.614044 -402.2471)
		(end 65.234566 -402.008086)
		(width 0.14224)
		(layer "In13.Cu")
		(net "P5E_CPU1_P1_RX_BUF_DP<3>")
	)
	(segment
		(start 74.740008 -398.571974)
		(end 74.780902 -398.491964)
		(width 0.14224)
		(layer "In13.Cu")
		(net "P5E_CPU1_P1_RX_BUF_DP<3>")
	)
	(segment
		(start 61.211206 -405.885142)
		(end 61.486796 -405.771096)
		(width 0.14224)
		(layer "In13.Cu")
		(net "P5E_CPU1_P1_RX_BUF_DP<3>")
	)
	(segment
		(start 64.535304 -402.424646)
		(end 64.614044 -402.2471)
		(width 0.14224)
		(layer "In13.Cu")
		(net "P5E_CPU1_P1_RX_BUF_DP<3>")
	)
	(segment
		(start 60.619894 -408.451558)
		(end 60.757054 -408.314398)
		(width 0.14224)
		(layer "In13.Cu")
		(net "P5E_CPU1_P1_RX_BUF_DP<3>")
	)
	(segment
		(start 83.817206 -393.017756)
		(end 83.944206 -393.144756)
		(width 0.14224)
		(layer "In13.Cu")
		(net "P5E_CPU1_P1_RX_BUF_DP<3>")
	)
	(segment
		(start 67.07632 -401.444968)
		(end 67.15506 -401.267422)
		(width 0.14224)
		(layer "In13.Cu")
		(net "P5E_CPU1_P1_RX_BUF_DP<3>")
	)
	(segment
		(start 66.677794 -401.598384)
		(end 67.07632 -401.444968)
		(width 0.14224)
		(layer "In13.Cu")
		(net "P5E_CPU1_P1_RX_BUF_DP<3>")
	)
	(segment
		(start 65.810384 -401.933156)
		(end 65.88887 -401.75561)
		(width 0.14224)
		(layer "In13.Cu")
		(net "P5E_CPU1_P1_RX_BUF_DP<3>")
	)
	(segment
		(start 59.088274 -413.217868)
		(end 59.088274 -411.868112)
		(width 0.14224)
		(layer "In13.Cu")
		(net "P5E_CPU1_P1_RX_BUF_DP<3>")
	)
	(segment
		(start 59.437524 -413.746442)
		(end 59.215274 -413.524192)
		(width 0.14224)
		(layer "In13.Cu")
		(net "P5E_CPU1_P1_RX_BUF_DP<3>")
	)
	(segment
		(start 63.013844 -402.864066)
		(end 63.959486 -402.499576)
		(width 0.14224)
		(layer "In13.Cu")
		(net "P5E_CPU1_P1_RX_BUF_DP<3>")
	)
	(segment
		(start 83.944206 -393.144756)
		(end 83.944206 -393.292838)
		(width 0.14224)
		(layer "In13.Cu")
		(net "P5E_CPU1_P1_RX_BUF_DP<3>")
	)
	(segment
		(start 60.291218 -411.21711)
		(end 60.467748 -411.06852)
		(width 0.14224)
		(layer "In13.Cu")
		(net "P5E_CPU1_P1_RX_BUF_DP<3>")
	)
	(segment
		(start 67.15506 -401.267422)
		(end 68.21678 -400.858228)
		(width 0.14224)
		(layer "In13.Cu")
		(net "P5E_CPU1_P1_RX_BUF_DP<3>")
	)
	(segment
		(start 60.757054 -409.015438)
		(end 60.619894 -408.878278)
		(width 0.14224)
		(layer "In13.Cu")
		(net "P5E_CPU1_P1_RX_BUF_DP<3>")
	)
	(segment
		(start 62.151514 -404.924514)
		(end 62.151514 -403.724872)
		(width 0.14224)
		(layer "In13.Cu")
		(net "P5E_CPU1_P1_RX_BUF_DP<3>")
	)
	(segment
		(start 63.479172 -417.195508)
		(end 63.479172 -417.001706)
		(width 0.14224)
		(layer "In13.Cu")
		(net "P5E_CPU1_P1_RX_BUF_DP<3>")
	)
	(segment
		(start 64.649858 -434.289962)
		(end 64.649858 -434.618638)
		(width 0.14224)
		(layer "In13.Cu")
		(net "P5E_CPU1_P1_RX_BUF_DP<3>")
	)
	(segment
		(start 61.486796 -405.771096)
		(end 61.802264 -405.560276)
		(width 0.14224)
		(layer "In13.Cu")
		(net "P5E_CPU1_P1_RX_BUF_DP<3>")
	)
	(segment
		(start 59.19597 -411.706568)
		(end 60.109862 -411.3276)
		(width 0.14224)
		(layer "In13.Cu")
		(net "P5E_CPU1_P1_RX_BUF_DP<3>")
	)
	(segment
		(start 62.392052 -415.914586)
		(end 62.19825 -415.914586)
		(width 0.14224)
		(layer "In13.Cu")
		(net "P5E_CPU1_P1_RX_BUF_DP<3>")
	)
	(segment
		(start 60.757054 -407.887678)
		(end 60.619894 -407.750518)
		(width 0.14224)
		(layer "In13.Cu")
		(net "P5E_CPU1_P1_RX_BUF_DP<3>")
	)
	(segment
		(start 63.012066 -416.728402)
		(end 62.694058 -416.410394)
		(width 0.14224)
		(layer "In13.Cu")
		(net "P5E_CPU1_P1_RX_BUF_DP<3>")
	)
	(segment
		(start 60.619894 -409.579318)
		(end 60.757054 -409.442158)
		(width 0.14224)
		(layer "In13.Cu")
		(net "P5E_CPU1_P1_RX_BUF_DP<3>")
	)
	(segment
		(start 63.205868 -416.728402)
		(end 63.012066 -416.728402)
		(width 0.14224)
		(layer "In13.Cu")
		(net "P5E_CPU1_P1_RX_BUF_DP<3>")
	)
	(segment
		(start 83.25739 -395.214602)
		(end 83.485228 -394.664692)
		(width 0.14224)
		(layer "In13.Cu")
		(net "P5E_CPU1_P1_RX_BUF_DP<3>")
	)
	(segment
		(start 65.88887 -401.75561)
		(end 66.500502 -401.519898)
		(width 0.14224)
		(layer "In13.Cu")
		(net "P5E_CPU1_P1_RX_BUF_DP<3>")
	)
	(segment
		(start 79.876142 -396.959328)
		(end 81.488788 -396.348204)
		(width 0.14224)
		(layer "In13.Cu")
		(net "P5E_CPU1_P1_RX_BUF_DP<3>")
	)
	(segment
		(start 61.127894 -414.650174)
		(end 60.85459 -414.37687)
		(width 0.14224)
		(layer "In13.Cu")
		(net "P5E_CPU1_P1_RX_BUF_DP<3>")
	)
	(segment
		(start 60.619894 -408.878278)
		(end 60.619894 -408.451558)
		(width 0.14224)
		(layer "In13.Cu")
		(net "P5E_CPU1_P1_RX_BUF_DP<3>")
	)
	(segment
		(start 63.97117 -426.873162)
		(end 63.97117 -417.954968)
		(width 0.14224)
		(layer "In13.Cu")
		(net "P5E_CPU1_P1_RX_BUF_DP<3>")
	)
	(segment
		(start 68.871338 -400.605752)
		(end 72.128888 -399.349976)
		(width 0.14224)
		(layer "In13.Cu")
		(net "P5E_CPU1_P1_RX_BUF_DP<3>")
	)
	(segment
		(start 83.627468 -393.017756)
		(end 83.817206 -393.017756)
		(width 0.14224)
		(layer "In13.Cu")
		(net "P5E_CPU1_P1_RX_BUF_DP<3>")
	)
	(segment
		(start 61.127894 -414.84423)
		(end 61.127894 -414.650174)
		(width 0.14224)
		(layer "In13.Cu")
		(net "P5E_CPU1_P1_RX_BUF_DP<3>")
	)
	(segment
		(start 60.619894 -407.750518)
		(end 60.619894 -406.638252)
		(width 0.14224)
		(layer "In13.Cu")
		(net "P5E_CPU1_P1_RX_BUF_DP<3>")
	)
	(segment
		(start 68.394072 -400.936714)
		(end 68.792598 -400.783298)
		(width 0.14224)
		(layer "In13.Cu")
		(net "P5E_CPU1_P1_RX_BUF_DP<3>")
	)
	(segment
		(start 74.113644 -398.707864)
		(end 74.1934 -398.748758)
		(width 0.14224)
		(layer "In13.Cu")
		(net "P5E_CPU1_P1_RX_BUF_DP<3>")
	)
	(segment
		(start 63.479172 -417.001706)
		(end 63.205868 -416.728402)
		(width 0.14224)
		(layer "In13.Cu")
		(net "P5E_CPU1_P1_RX_BUF_DP<3>")
	)
	(segment
		(start 83.485228 -394.664692)
		(end 83.485228 -393.159996)
		(width 0.14224)
		(layer "In13.Cu")
		(net "P5E_CPU1_P1_RX_BUF_DP<3>")
	)
	(segment
		(start 60.619894 -410.741876)
		(end 60.619894 -409.579318)
		(width 0.14224)
		(layer "In13.Cu")
		(net "P5E_CPU1_P1_RX_BUF_DP<3>")
	)
	(segment
		(start 62.694058 -416.410394)
		(end 62.694058 -416.216592)
		(width 0.14224)
		(layer "In13.Cu")
		(net "P5E_CPU1_P1_RX_BUF_DP<3>")
	)
	(segment
		(start 65.411858 -402.086572)
		(end 65.810384 -401.933156)
		(width 0.14224)
		(layer "In13.Cu")
		(net "P5E_CPU1_P1_RX_BUF_DP<3>")
	)
	(segment
		(start 60.757054 -409.442158)
		(end 60.757054 -409.015438)
		(width 0.14224)
		(layer "In13.Cu")
		(net "P5E_CPU1_P1_RX_BUF_DP<3>")
	)
	(segment
		(start 64.274954 -434.756814)
		(end 63.97625 -434.45811)
		(width 0.14224)
		(layer "In13.Cu")
		(net "P5E_CPU1_P1_RX_BUF_DP<3>")
	)
	(segment
		(start 63.97625 -426.878242)
		(end 63.97117 -426.873162)
		(width 0.14224)
		(layer "In13.Cu")
		(net "P5E_CPU1_P1_RX_BUF_DP<3>")
	)
	(segment
		(start 61.896752 -415.613088)
		(end 61.896752 -415.419032)
		(width 0.14224)
		(layer "In13.Cu")
		(net "P5E_CPU1_P1_RX_BUF_DP<3>")
	)
	(segment
		(start 60.660534 -414.37687)
		(end 60.360306 -414.076642)
		(width 0.14224)
		(layer "In13.Cu")
		(net "P5E_CPU1_P1_RX_BUF_DP<3>")
	)
	(segment
		(start 60.757054 -408.314398)
		(end 60.757054 -407.887678)
		(width 0.14224)
		(layer "In13.Cu")
		(net "P5E_CPU1_P1_RX_BUF_DP<3>")
	)
	(segment
		(start 74.780902 -398.491964)
		(end 77.943202 -397.468852)
		(width 0.14224)
		(layer "In13.Cu")
		(net "P5E_CPU1_P1_RX_BUF_DP<3>")
	)
	(segment
		(start 61.40069 -415.117026)
		(end 61.127894 -414.84423)
		(width 0.14224)
		(layer "In13.Cu")
		(net "P5E_CPU1_P1_RX_BUF_DP<3>")
	)
	(segment
		(start 68.792598 -400.783298)
		(end 68.871338 -400.605752)
		(width 0.14224)
		(layer "In13.Cu")
		(net "P5E_CPU1_P1_RX_BUF_DP<3>")
	)
	(segment
		(start 63.78194 -417.498276)
		(end 63.479172 -417.195508)
		(width 0.14224)
		(layer "In13.Cu")
		(net "P5E_CPU1_P1_RX_BUF_DP<3>")
	)
	(segment
		(start 83.485228 -393.159996)
		(end 83.627468 -393.017756)
		(width 0.14224)
		(layer "In13.Cu")
		(net "P5E_CPU1_P1_RX_BUF_DP<3>")
	)
	(segment
		(start 64.137032 -402.578062)
		(end 64.535304 -402.424646)
		(width 0.14224)
		(layer "In13.Cu")
		(net "P5E_CPU1_P1_RX_BUF_DP<3>")
	)
	(segment
		(start 68.21678 -400.858228)
		(end 68.394072 -400.936714)
		(width 0.14224)
		(layer "In13.Cu")
		(net "P5E_CPU1_P1_RX_BUF_DP<3>")
	)
	(segment
		(start 82.761582 -395.71041)
		(end 83.25739 -395.214602)
		(width 0.14224)
		(layer "In13.Cu")
		(net "P5E_CPU1_P1_RX_BUF_DP<3>")
	)
	(arc
		(start 62.314328 -403.32533)
		(mid 62.645859 -403.067055)
		(end 63.013844 -402.864066)
		(width 0.14224)
		(layer "In13.Cu")
		(net "P5E_CPU1_P1_RX_BUF_DP<3>")
	)
	(arc
		(start 60.109862 -411.3276)
		(mid 60.204795 -411.279337)
		(end 60.291218 -411.21711)
		(width 0.14224)
		(layer "In13.Cu")
		(net "P5E_CPU1_P1_RX_BUF_DP<3>")
	)
	(arc
		(start 60.467748 -411.06852)
		(mid 60.579948 -410.922024)
		(end 60.619894 -410.741876)
		(width 0.14224)
		(layer "In13.Cu")
		(net "P5E_CPU1_P1_RX_BUF_DP<3>")
	)
	(arc
		(start 59.653932 -413.836104)
		(mid 59.536804 -413.812806)
		(end 59.437524 -413.746442)
		(width 0.14224)
		(layer "In13.Cu")
		(net "P5E_CPU1_P1_RX_BUF_DP<3>")
	)
	(arc
		(start 59.215274 -413.524192)
		(mid 59.121283 -413.383664)
		(end 59.088274 -413.217868)
		(width 0.14224)
		(layer "In13.Cu")
		(net "P5E_CPU1_P1_RX_BUF_DP<3>")
	)
	(arc
		(start 60.824872 -406.14346)
		(mid 61.005342 -405.995314)
		(end 61.211206 -405.885142)
		(width 0.14224)
		(layer "In13.Cu")
		(net "P5E_CPU1_P1_RX_BUF_DP<3>")
	)
	(arc
		(start 60.619894 -406.638252)
		(mid 60.673123 -406.370451)
		(end 60.824872 -406.14346)
		(width 0.14224)
		(layer "In13.Cu")
		(net "P5E_CPU1_P1_RX_BUF_DP<3>")
	)
	(arc
		(start 62.151514 -403.724872)
		(mid 62.193826 -403.50917)
		(end 62.314328 -403.32533)
		(width 0.14224)
		(layer "In13.Cu")
		(net "P5E_CPU1_P1_RX_BUF_DP<3>")
	)
	(arc
		(start 63.97117 -417.954968)
		(mid 63.921987 -417.707799)
		(end 63.78194 -417.498276)
		(width 0.14224)
		(layer "In13.Cu")
		(net "P5E_CPU1_P1_RX_BUF_DP<3>")
	)
	(arc
		(start 61.949076 -405.413464)
		(mid 62.098916 -405.189118)
		(end 62.151514 -404.924514)
		(width 0.14224)
		(layer "In13.Cu")
		(net "P5E_CPU1_P1_RX_BUF_DP<3>")
	)
	(arc
		(start 59.088274 -411.868112)
		(mid 59.117666 -411.771036)
		(end 59.19597 -411.706568)
		(width 0.14224)
		(layer "In13.Cu")
		(net "P5E_CPU1_P1_RX_BUF_DP<3>")
	)
	(arc
		(start 60.360306 -414.076642)
		(mid 60.093774 -413.898614)
		(end 59.779408 -413.836104)
		(width 0.14224)
		(layer "In13.Cu")
		(net "P5E_CPU1_P1_RX_BUF_DP<3>")
	)
	(segment
		(start 82.041746 -392.723878)
		(end 82.294984 -392.977116)
		(width 0.1016)
		(layer "F.Cu")
		(net "P5E_CPU1_P1_RX_BUF_DP<2>")
	)
	(segment
		(start 82.294984 -392.977116)
		(end 82.605626 -392.977116)
		(width 0.1016)
		(layer "F.Cu")
		(net "P5E_CPU1_P1_RX_BUF_DP<2>")
	)
	(segment
		(start 82.605626 -392.977116)
		(end 82.74431 -393.1158)
		(width 0.1016)
		(layer "F.Cu")
		(net "P5E_CPU1_P1_RX_BUF_DP<2>")
	)
	(segment
		(start 82.04581 -391.281158)
		(end 82.130392 -391.36574)
		(width 0.1016)
		(layer "F.Cu")
		(net "P5E_CPU1_P1_RX_BUF_DP<2>")
	)
	(segment
		(start 82.74431 -393.1158)
		(end 82.74431 -393.292838)
		(width 0.1016)
		(layer "F.Cu")
		(net "P5E_CPU1_P1_RX_BUF_DP<2>")
	)
	(segment
		(start 82.130392 -391.488676)
		(end 82.041746 -391.577322)
		(width 0.1016)
		(layer "F.Cu")
		(net "P5E_CPU1_P1_RX_BUF_DP<2>")
	)
	(segment
		(start 82.041746 -391.577322)
		(end 82.041746 -392.723878)
		(width 0.1016)
		(layer "F.Cu")
		(net "P5E_CPU1_P1_RX_BUF_DP<2>")
	)
	(segment
		(start 82.130392 -391.36574)
		(end 82.130392 -391.488676)
		(width 0.1016)
		(layer "F.Cu")
		(net "P5E_CPU1_P1_RX_BUF_DP<2>")
	)
	(segment
		(start 62.511686 -433.756816)
		(end 62.274958 -433.756816)
		(width 0.14224)
		(layer "In13.Cu")
		(net "P5E_CPU1_P1_RX_BUF_DP<2>")
	)
	(segment
		(start 70.273672 -399.031206)
		(end 70.669912 -398.871948)
		(width 0.14224)
		(layer "In13.Cu")
		(net "P5E_CPU1_P1_RX_BUF_DP<2>")
	)
	(segment
		(start 57.556654 -408.99334)
		(end 57.556654 -408.56662)
		(width 0.14224)
		(layer "In13.Cu")
		(net "P5E_CPU1_P1_RX_BUF_DP<2>")
	)
	(segment
		(start 59.121802 -403.783546)
		(end 59.186318 -403.551136)
		(width 0.14224)
		(layer "In13.Cu")
		(net "P5E_CPU1_P1_RX_BUF_DP<2>")
	)
	(segment
		(start 59.28995 -403.394926)
		(end 59.468258 -403.253194)
		(width 0.14224)
		(layer "In13.Cu")
		(net "P5E_CPU1_P1_RX_BUF_DP<2>")
	)
	(segment
		(start 61.976254 -433.458112)
		(end 61.976254 -426.878242)
		(width 0.14224)
		(layer "In13.Cu")
		(net "P5E_CPU1_P1_RX_BUF_DP<2>")
	)
	(segment
		(start 60.928758 -402.645626)
		(end 68.532248 -399.584418)
		(width 0.14224)
		(layer "In13.Cu")
		(net "P5E_CPU1_P1_RX_BUF_DP<2>")
	)
	(segment
		(start 82.74431 -393.144756)
		(end 82.74431 -393.292838)
		(width 0.14224)
		(layer "In13.Cu")
		(net "P5E_CPU1_P1_RX_BUF_DP<2>")
	)
	(segment
		(start 60.892944 -416.278822)
		(end 60.698888 -416.278822)
		(width 0.14224)
		(layer "In13.Cu")
		(net "P5E_CPU1_P1_RX_BUF_DP<2>")
	)
	(segment
		(start 68.532248 -399.584418)
		(end 68.710556 -399.660618)
		(width 0.14224)
		(layer "In13.Cu")
		(net "P5E_CPU1_P1_RX_BUF_DP<2>")
	)
	(segment
		(start 69.182742 -399.322544)
		(end 70.09511 -398.95526)
		(width 0.14224)
		(layer "In13.Cu")
		(net "P5E_CPU1_P1_RX_BUF_DP<2>")
	)
	(segment
		(start 70.09511 -398.95526)
		(end 70.273672 -399.031206)
		(width 0.14224)
		(layer "In13.Cu")
		(net "P5E_CPU1_P1_RX_BUF_DP<2>")
	)
	(segment
		(start 62.274958 -433.756816)
		(end 61.976254 -433.458112)
		(width 0.14224)
		(layer "In13.Cu")
		(net "P5E_CPU1_P1_RX_BUF_DP<2>")
	)
	(segment
		(start 61.851286 -417.43122)
		(end 61.19495 -416.774884)
		(width 0.14224)
		(layer "In13.Cu")
		(net "P5E_CPU1_P1_RX_BUF_DP<2>")
	)
	(segment
		(start 57.693814 -408.42946)
		(end 57.693814 -408.00274)
		(width 0.14224)
		(layer "In13.Cu")
		(net "P5E_CPU1_P1_RX_BUF_DP<2>")
	)
	(segment
		(start 72.014334 -398.33042)
		(end 72.410574 -398.170908)
		(width 0.14224)
		(layer "In13.Cu")
		(net "P5E_CPU1_P1_RX_BUF_DP<2>")
	)
	(segment
		(start 58.147966 -405.885142)
		(end 58.423556 -405.771096)
		(width 0.14224)
		(layer "In13.Cu")
		(net "P5E_CPU1_P1_RX_BUF_DP<2>")
	)
	(segment
		(start 57.556654 -407.86558)
		(end 57.556654 -406.638252)
		(width 0.14224)
		(layer "In13.Cu")
		(net "P5E_CPU1_P1_RX_BUF_DP<2>")
	)
	(segment
		(start 56.392318 -411.521402)
		(end 56.83885 -411.33649)
		(width 0.14224)
		(layer "In13.Cu")
		(net "P5E_CPU1_P1_RX_BUF_DP<2>")
	)
	(segment
		(start 77.67701 -396.448534)
		(end 79.586836 -396.007844)
		(width 0.14224)
		(layer "In13.Cu")
		(net "P5E_CPU1_P1_RX_BUF_DP<2>")
	)
	(segment
		(start 70.745858 -398.693132)
		(end 71.836026 -398.254474)
		(width 0.14224)
		(layer "In13.Cu")
		(net "P5E_CPU1_P1_RX_BUF_DP<2>")
	)
	(segment
		(start 60.456572 -402.9837)
		(end 60.852812 -402.824442)
		(width 0.14224)
		(layer "In13.Cu")
		(net "P5E_CPU1_P1_RX_BUF_DP<2>")
	)
	(segment
		(start 57.215532 -411.084268)
		(end 57.421018 -410.878782)
		(width 0.14224)
		(layer "In13.Cu")
		(net "P5E_CPU1_P1_RX_BUF_DP<2>")
	)
	(segment
		(start 57.16651 -414.261046)
		(end 56.972454 -414.261046)
		(width 0.14224)
		(layer "In13.Cu")
		(net "P5E_CPU1_P1_RX_BUF_DP<2>")
	)
	(segment
		(start 57.693814 -409.55722)
		(end 57.693814 -409.1305)
		(width 0.14224)
		(layer "In13.Cu")
		(net "P5E_CPU1_P1_RX_BUF_DP<2>")
	)
	(segment
		(start 58.739024 -405.560276)
		(end 58.885836 -405.413464)
		(width 0.14224)
		(layer "In13.Cu")
		(net "P5E_CPU1_P1_RX_BUF_DP<2>")
	)
	(segment
		(start 81.219294 -395.440408)
		(end 82.071464 -395.037056)
		(width 0.14224)
		(layer "In13.Cu")
		(net "P5E_CPU1_P1_RX_BUF_DP<2>")
	)
	(segment
		(start 57.693814 -408.00274)
		(end 57.556654 -407.86558)
		(width 0.14224)
		(layer "In13.Cu")
		(net "P5E_CPU1_P1_RX_BUF_DP<2>")
	)
	(segment
		(start 57.693814 -409.1305)
		(end 57.556654 -408.99334)
		(width 0.14224)
		(layer "In13.Cu")
		(net "P5E_CPU1_P1_RX_BUF_DP<2>")
	)
	(segment
		(start 59.901328 -415.481262)
		(end 59.676538 -415.256472)
		(width 0.14224)
		(layer "In13.Cu")
		(net "P5E_CPU1_P1_RX_BUF_DP<2>")
	)
	(segment
		(start 82.285332 -394.636752)
		(end 82.285332 -393.159996)
		(width 0.14224)
		(layer "In13.Cu")
		(net "P5E_CPU1_P1_RX_BUF_DP<2>")
	)
	(segment
		(start 60.095384 -415.481262)
		(end 59.901328 -415.481262)
		(width 0.14224)
		(layer "In13.Cu")
		(net "P5E_CPU1_P1_RX_BUF_DP<2>")
	)
	(segment
		(start 72.410574 -398.170908)
		(end 72.48652 -397.992346)
		(width 0.14224)
		(layer "In13.Cu")
		(net "P5E_CPU1_P1_RX_BUF_DP<2>")
	)
	(segment
		(start 57.556654 -408.56662)
		(end 57.693814 -408.42946)
		(width 0.14224)
		(layer "In13.Cu")
		(net "P5E_CPU1_P1_RX_BUF_DP<2>")
	)
	(segment
		(start 73.59396 -397.546576)
		(end 75.181968 -397.119602)
		(width 0.14224)
		(layer "In13.Cu")
		(net "P5E_CPU1_P1_RX_BUF_DP<2>")
	)
	(segment
		(start 72.48652 -397.992346)
		(end 73.59396 -397.546576)
		(width 0.14224)
		(layer "In13.Cu")
		(net "P5E_CPU1_P1_RX_BUF_DP<2>")
	)
	(segment
		(start 79.586836 -396.007844)
		(end 81.219294 -395.440408)
		(width 0.14224)
		(layer "In13.Cu")
		(net "P5E_CPU1_P1_RX_BUF_DP<2>")
	)
	(segment
		(start 82.071464 -395.037056)
		(end 82.285332 -394.636752)
		(width 0.14224)
		(layer "In13.Cu")
		(net "P5E_CPU1_P1_RX_BUF_DP<2>")
	)
	(segment
		(start 75.181968 -397.119602)
		(end 75.350116 -397.216376)
		(width 0.14224)
		(layer "In13.Cu")
		(net "P5E_CPU1_P1_RX_BUF_DP<2>")
	)
	(segment
		(start 61.971174 -426.873162)
		(end 61.971174 -417.72078)
		(width 0.14224)
		(layer "In13.Cu")
		(net "P5E_CPU1_P1_RX_BUF_DP<2>")
	)
	(segment
		(start 61.976254 -426.878242)
		(end 61.971174 -426.873162)
		(width 0.14224)
		(layer "In13.Cu")
		(net "P5E_CPU1_P1_RX_BUF_DP<2>")
	)
	(segment
		(start 59.217814 -415.06648)
		(end 57.870344 -415.06648)
		(width 0.14224)
		(layer "In13.Cu")
		(net "P5E_CPU1_P1_RX_BUF_DP<2>")
	)
	(segment
		(start 82.285332 -393.159996)
		(end 82.427572 -393.017756)
		(width 0.14224)
		(layer "In13.Cu")
		(net "P5E_CPU1_P1_RX_BUF_DP<2>")
	)
	(segment
		(start 57.439814 -414.53435)
		(end 57.16651 -414.261046)
		(width 0.14224)
		(layer "In13.Cu")
		(net "P5E_CPU1_P1_RX_BUF_DP<2>")
	)
	(segment
		(start 82.427572 -393.017756)
		(end 82.61731 -393.017756)
		(width 0.14224)
		(layer "In13.Cu")
		(net "P5E_CPU1_P1_RX_BUF_DP<2>")
	)
	(segment
		(start 60.39739 -415.977324)
		(end 60.39739 -415.783268)
		(width 0.14224)
		(layer "In13.Cu")
		(net "P5E_CPU1_P1_RX_BUF_DP<2>")
	)
	(segment
		(start 57.439814 -414.728406)
		(end 57.439814 -414.53435)
		(width 0.14224)
		(layer "In13.Cu")
		(net "P5E_CPU1_P1_RX_BUF_DP<2>")
	)
	(segment
		(start 60.278264 -402.907754)
		(end 60.456572 -402.9837)
		(width 0.14224)
		(layer "In13.Cu")
		(net "P5E_CPU1_P1_RX_BUF_DP<2>")
	)
	(segment
		(start 62.649862 -433.289964)
		(end 62.649862 -433.61864)
		(width 0.14224)
		(layer "In13.Cu")
		(net "P5E_CPU1_P1_RX_BUF_DP<2>")
	)
	(segment
		(start 75.350116 -397.216376)
		(end 75.762358 -397.105632)
		(width 0.14224)
		(layer "In13.Cu")
		(net "P5E_CPU1_P1_RX_BUF_DP<2>")
	)
	(segment
		(start 58.423556 -405.771096)
		(end 58.739024 -405.560276)
		(width 0.14224)
		(layer "In13.Cu")
		(net "P5E_CPU1_P1_RX_BUF_DP<2>")
	)
	(segment
		(start 75.859132 -396.93723)
		(end 77.67701 -396.448534)
		(width 0.14224)
		(layer "In13.Cu")
		(net "P5E_CPU1_P1_RX_BUF_DP<2>")
	)
	(segment
		(start 59.088274 -404.924514)
		(end 59.088274 -404.028656)
		(width 0.14224)
		(layer "In13.Cu")
		(net "P5E_CPU1_P1_RX_BUF_DP<2>")
	)
	(segment
		(start 62.649862 -433.61864)
		(end 62.511686 -433.756816)
		(width 0.14224)
		(layer "In13.Cu")
		(net "P5E_CPU1_P1_RX_BUF_DP<2>")
	)
	(segment
		(start 57.556654 -410.551122)
		(end 57.556654 -409.69438)
		(width 0.14224)
		(layer "In13.Cu")
		(net "P5E_CPU1_P1_RX_BUF_DP<2>")
	)
	(segment
		(start 60.39739 -415.783268)
		(end 60.095384 -415.481262)
		(width 0.14224)
		(layer "In13.Cu")
		(net "P5E_CPU1_P1_RX_BUF_DP<2>")
	)
	(segment
		(start 60.852812 -402.824442)
		(end 60.928758 -402.645626)
		(width 0.14224)
		(layer "In13.Cu")
		(net "P5E_CPU1_P1_RX_BUF_DP<2>")
	)
	(segment
		(start 57.556654 -409.69438)
		(end 57.693814 -409.55722)
		(width 0.14224)
		(layer "In13.Cu")
		(net "P5E_CPU1_P1_RX_BUF_DP<2>")
	)
	(segment
		(start 61.19495 -416.774884)
		(end 61.19495 -416.580828)
		(width 0.14224)
		(layer "In13.Cu")
		(net "P5E_CPU1_P1_RX_BUF_DP<2>")
	)
	(segment
		(start 68.710556 -399.660618)
		(end 69.106796 -399.501106)
		(width 0.14224)
		(layer "In13.Cu")
		(net "P5E_CPU1_P1_RX_BUF_DP<2>")
	)
	(segment
		(start 71.836026 -398.254474)
		(end 72.014334 -398.33042)
		(width 0.14224)
		(layer "In13.Cu")
		(net "P5E_CPU1_P1_RX_BUF_DP<2>")
	)
	(segment
		(start 56.20512 -411.702758)
		(end 56.347614 -411.552136)
		(width 0.14224)
		(layer "In13.Cu")
		(net "P5E_CPU1_P1_RX_BUF_DP<2>")
	)
	(segment
		(start 82.61731 -393.017756)
		(end 82.74431 -393.144756)
		(width 0.14224)
		(layer "In13.Cu")
		(net "P5E_CPU1_P1_RX_BUF_DP<2>")
	)
	(segment
		(start 56.972454 -414.261046)
		(end 56.200802 -413.489394)
		(width 0.14224)
		(layer "In13.Cu")
		(net "P5E_CPU1_P1_RX_BUF_DP<2>")
	)
	(segment
		(start 61.19495 -416.580828)
		(end 60.892944 -416.278822)
		(width 0.14224)
		(layer "In13.Cu")
		(net "P5E_CPU1_P1_RX_BUF_DP<2>")
	)
	(segment
		(start 57.71261 -415.001202)
		(end 57.439814 -414.728406)
		(width 0.14224)
		(layer "In13.Cu")
		(net "P5E_CPU1_P1_RX_BUF_DP<2>")
	)
	(segment
		(start 59.577478 -403.189694)
		(end 60.278264 -402.907754)
		(width 0.14224)
		(layer "In13.Cu")
		(net "P5E_CPU1_P1_RX_BUF_DP<2>")
	)
	(segment
		(start 75.762358 -397.105632)
		(end 75.859132 -396.93723)
		(width 0.14224)
		(layer "In13.Cu")
		(net "P5E_CPU1_P1_RX_BUF_DP<2>")
	)
	(segment
		(start 56.025034 -413.06496)
		(end 56.025034 -412.155386)
		(width 0.14224)
		(layer "In13.Cu")
		(net "P5E_CPU1_P1_RX_BUF_DP<2>")
	)
	(segment
		(start 70.669912 -398.871948)
		(end 70.745858 -398.693132)
		(width 0.14224)
		(layer "In13.Cu")
		(net "P5E_CPU1_P1_RX_BUF_DP<2>")
	)
	(segment
		(start 60.698888 -416.278822)
		(end 60.39739 -415.977324)
		(width 0.14224)
		(layer "In13.Cu")
		(net "P5E_CPU1_P1_RX_BUF_DP<2>")
	)
	(segment
		(start 69.106796 -399.501106)
		(end 69.182742 -399.322544)
		(width 0.14224)
		(layer "In13.Cu")
		(net "P5E_CPU1_P1_RX_BUF_DP<2>")
	)
	(arc
		(start 57.761632 -406.14346)
		(mid 57.942102 -405.995314)
		(end 58.147966 -405.885142)
		(width 0.14224)
		(layer "In13.Cu")
		(net "P5E_CPU1_P1_RX_BUF_DP<2>")
	)
	(arc
		(start 59.468258 -403.253194)
		(mid 59.520562 -403.217474)
		(end 59.577478 -403.189694)
		(width 0.14224)
		(layer "In13.Cu")
		(net "P5E_CPU1_P1_RX_BUF_DP<2>")
	)
	(arc
		(start 56.83885 -411.33649)
		(mid 57.039595 -411.228901)
		(end 57.215532 -411.084268)
		(width 0.14224)
		(layer "In13.Cu")
		(net "P5E_CPU1_P1_RX_BUF_DP<2>")
	)
	(arc
		(start 56.347614 -411.552136)
		(mid 56.368354 -411.534427)
		(end 56.392318 -411.521402)
		(width 0.14224)
		(layer "In13.Cu")
		(net "P5E_CPU1_P1_RX_BUF_DP<2>")
	)
	(arc
		(start 57.556654 -406.638252)
		(mid 57.609883 -406.370451)
		(end 57.761632 -406.14346)
		(width 0.14224)
		(layer "In13.Cu")
		(net "P5E_CPU1_P1_RX_BUF_DP<2>")
	)
	(arc
		(start 59.186318 -403.551136)
		(mid 59.22573 -403.464793)
		(end 59.28995 -403.394926)
		(width 0.14224)
		(layer "In13.Cu")
		(net "P5E_CPU1_P1_RX_BUF_DP<2>")
	)
	(arc
		(start 61.971174 -417.72078)
		(mid 61.940022 -417.564077)
		(end 61.851286 -417.43122)
		(width 0.14224)
		(layer "In13.Cu")
		(net "P5E_CPU1_P1_RX_BUF_DP<2>")
	)
	(arc
		(start 59.676538 -415.256472)
		(mid 59.466074 -415.115844)
		(end 59.217814 -415.06648)
		(width 0.14224)
		(layer "In13.Cu")
		(net "P5E_CPU1_P1_RX_BUF_DP<2>")
	)
	(arc
		(start 57.870344 -415.06648)
		(mid 57.784987 -415.049519)
		(end 57.71261 -415.001202)
		(width 0.14224)
		(layer "In13.Cu")
		(net "P5E_CPU1_P1_RX_BUF_DP<2>")
	)
	(arc
		(start 56.025034 -412.155386)
		(mid 56.071655 -411.911792)
		(end 56.20512 -411.702758)
		(width 0.14224)
		(layer "In13.Cu")
		(net "P5E_CPU1_P1_RX_BUF_DP<2>")
	)
	(arc
		(start 56.200802 -413.489394)
		(mid 56.07074 -413.294648)
		(end 56.025034 -413.06496)
		(width 0.14224)
		(layer "In13.Cu")
		(net "P5E_CPU1_P1_RX_BUF_DP<2>")
	)
	(arc
		(start 57.421018 -410.878782)
		(mid 57.521413 -410.728436)
		(end 57.556654 -410.551122)
		(width 0.14224)
		(layer "In13.Cu")
		(net "P5E_CPU1_P1_RX_BUF_DP<2>")
	)
	(arc
		(start 58.885836 -405.413464)
		(mid 59.035676 -405.189118)
		(end 59.088274 -404.924514)
		(width 0.14224)
		(layer "In13.Cu")
		(net "P5E_CPU1_P1_RX_BUF_DP<2>")
	)
	(arc
		(start 59.088274 -404.028656)
		(mid 59.096691 -403.904959)
		(end 59.121802 -403.783546)
		(width 0.14224)
		(layer "In13.Cu")
		(net "P5E_CPU1_P1_RX_BUF_DP<2>")
	)
	(segment
		(start 81.405476 -392.977116)
		(end 81.54416 -393.1158)
		(width 0.1016)
		(layer "F.Cu")
		(net "P5E_CPU1_P1_RX_BUF_DP<1>")
	)
	(segment
		(start 80.84566 -391.281158)
		(end 80.930242 -391.36574)
		(width 0.1016)
		(layer "F.Cu")
		(net "P5E_CPU1_P1_RX_BUF_DP<1>")
	)
	(segment
		(start 80.930242 -391.488676)
		(end 80.841596 -391.577322)
		(width 0.1016)
		(layer "F.Cu")
		(net "P5E_CPU1_P1_RX_BUF_DP<1>")
	)
	(segment
		(start 81.094834 -392.977116)
		(end 81.405476 -392.977116)
		(width 0.1016)
		(layer "F.Cu")
		(net "P5E_CPU1_P1_RX_BUF_DP<1>")
	)
	(segment
		(start 80.841596 -392.723878)
		(end 81.094834 -392.977116)
		(width 0.1016)
		(layer "F.Cu")
		(net "P5E_CPU1_P1_RX_BUF_DP<1>")
	)
	(segment
		(start 81.54416 -393.1158)
		(end 81.54416 -393.292838)
		(width 0.1016)
		(layer "F.Cu")
		(net "P5E_CPU1_P1_RX_BUF_DP<1>")
	)
	(segment
		(start 80.930242 -391.36574)
		(end 80.930242 -391.488676)
		(width 0.1016)
		(layer "F.Cu")
		(net "P5E_CPU1_P1_RX_BUF_DP<1>")
	)
	(segment
		(start 80.841596 -391.577322)
		(end 80.841596 -392.723878)
		(width 0.1016)
		(layer "F.Cu")
		(net "P5E_CPU1_P1_RX_BUF_DP<1>")
	)
	(segment
		(start 58.18632 -416.428174)
		(end 58.04916 -416.565334)
		(width 0.14224)
		(layer "In13.Cu")
		(net "P5E_CPU1_P1_RX_BUF_DP<1>")
	)
	(segment
		(start 56.1213 -416.483292)
		(end 55.606442 -415.968434)
		(width 0.14224)
		(layer "In13.Cu")
		(net "P5E_CPU1_P1_RX_BUF_DP<1>")
	)
	(segment
		(start 60.274962 -434.756814)
		(end 59.976258 -434.45811)
		(width 0.14224)
		(layer "In13.Cu")
		(net "P5E_CPU1_P1_RX_BUF_DP<1>")
	)
	(segment
		(start 70.207124 -397.867378)
		(end 70.281546 -397.688054)
		(width 0.14224)
		(layer "In13.Cu")
		(net "P5E_CPU1_P1_RX_BUF_DP<1>")
	)
	(segment
		(start 53.049424 -411.71495)
		(end 54.001924 -411.31998)
		(width 0.14224)
		(layer "In13.Cu")
		(net "P5E_CPU1_P1_RX_BUF_DP<1>")
	)
	(segment
		(start 54.808882 -414.976818)
		(end 54.506876 -414.674812)
		(width 0.14224)
		(layer "In13.Cu")
		(net "P5E_CPU1_P1_RX_BUF_DP<1>")
	)
	(segment
		(start 69.20738 -398.132554)
		(end 69.633592 -397.956278)
		(width 0.14224)
		(layer "In13.Cu")
		(net "P5E_CPU1_P1_RX_BUF_DP<1>")
	)
	(segment
		(start 54.630574 -409.165298)
		(end 54.630574 -408.738578)
		(width 0.14224)
		(layer "In13.Cu")
		(net "P5E_CPU1_P1_RX_BUF_DP<1>")
	)
	(segment
		(start 81.227422 -393.017756)
		(end 81.41716 -393.017756)
		(width 0.14224)
		(layer "In13.Cu")
		(net "P5E_CPU1_P1_RX_BUF_DP<1>")
	)
	(segment
		(start 57.13984 -416.428174)
		(end 57.00268 -416.565334)
		(width 0.14224)
		(layer "In13.Cu")
		(net "P5E_CPU1_P1_RX_BUF_DP<1>")
	)
	(segment
		(start 58.013092 -402.91131)
		(end 58.407554 -402.748242)
		(width 0.14224)
		(layer "In13.Cu")
		(net "P5E_CPU1_P1_RX_BUF_DP<1>")
	)
	(segment
		(start 54.630574 -407.967942)
		(end 54.630574 -407.541222)
		(width 0.14224)
		(layer "In13.Cu")
		(net "P5E_CPU1_P1_RX_BUF_DP<1>")
	)
	(segment
		(start 54.011322 -414.373314)
		(end 54.011322 -414.179258)
		(width 0.14224)
		(layer "In13.Cu")
		(net "P5E_CPU1_P1_RX_BUF_DP<1>")
	)
	(segment
		(start 67.69608 -398.906238)
		(end 68.090542 -398.74317)
		(width 0.14224)
		(layer "In13.Cu")
		(net "P5E_CPU1_P1_RX_BUF_DP<1>")
	)
	(segment
		(start 56.398414 -403.43074)
		(end 57.834022 -402.837142)
		(width 0.14224)
		(layer "In13.Cu")
		(net "P5E_CPU1_P1_RX_BUF_DP<1>")
	)
	(segment
		(start 57.00268 -416.565334)
		(end 56.319166 -416.565334)
		(width 0.14224)
		(layer "In13.Cu")
		(net "P5E_CPU1_P1_RX_BUF_DP<1>")
	)
	(segment
		(start 52.961794 -413.234378)
		(end 52.961794 -411.846014)
		(width 0.14224)
		(layer "In13.Cu")
		(net "P5E_CPU1_P1_RX_BUF_DP<1>")
	)
	(segment
		(start 54.011322 -414.179258)
		(end 53.709316 -413.877252)
		(width 0.14224)
		(layer "In13.Cu")
		(net "P5E_CPU1_P1_RX_BUF_DP<1>")
	)
	(segment
		(start 81.41716 -393.017756)
		(end 81.54416 -393.144756)
		(width 0.14224)
		(layer "In13.Cu")
		(net "P5E_CPU1_P1_RX_BUF_DP<1>")
	)
	(segment
		(start 68.090542 -398.74317)
		(end 68.164964 -398.563846)
		(width 0.14224)
		(layer "In13.Cu")
		(net "P5E_CPU1_P1_RX_BUF_DP<1>")
	)
	(segment
		(start 54.630574 -408.738578)
		(end 54.493414 -408.601418)
		(width 0.14224)
		(layer "In13.Cu")
		(net "P5E_CPU1_P1_RX_BUF_DP<1>")
	)
	(segment
		(start 54.630574 -407.541222)
		(end 54.493414 -407.404062)
		(width 0.14224)
		(layer "In13.Cu")
		(net "P5E_CPU1_P1_RX_BUF_DP<1>")
	)
	(segment
		(start 58.481976 -402.568918)
		(end 67.51701 -398.83207)
		(width 0.14224)
		(layer "In13.Cu")
		(net "P5E_CPU1_P1_RX_BUF_DP<1>")
	)
	(segment
		(start 60.51169 -434.756814)
		(end 60.274962 -434.756814)
		(width 0.14224)
		(layer "In13.Cu")
		(net "P5E_CPU1_P1_RX_BUF_DP<1>")
	)
	(segment
		(start 69.812662 -398.030446)
		(end 70.207124 -397.867378)
		(width 0.14224)
		(layer "In13.Cu")
		(net "P5E_CPU1_P1_RX_BUF_DP<1>")
	)
	(segment
		(start 81.085182 -393.159996)
		(end 81.227422 -393.017756)
		(width 0.14224)
		(layer "In13.Cu")
		(net "P5E_CPU1_P1_RX_BUF_DP<1>")
	)
	(segment
		(start 54.31282 -414.674812)
		(end 54.011322 -414.373314)
		(width 0.14224)
		(layer "In13.Cu")
		(net "P5E_CPU1_P1_RX_BUF_DP<1>")
	)
	(segment
		(start 59.976258 -426.878242)
		(end 59.971178 -426.873162)
		(width 0.14224)
		(layer "In13.Cu")
		(net "P5E_CPU1_P1_RX_BUF_DP<1>")
	)
	(segment
		(start 80.677258 -394.62075)
		(end 81.085182 -394.269722)
		(width 0.14224)
		(layer "In13.Cu")
		(net "P5E_CPU1_P1_RX_BUF_DP<1>")
	)
	(segment
		(start 73.57745 -396.547594)
		(end 76.347066 -395.768576)
		(width 0.14224)
		(layer "In13.Cu")
		(net "P5E_CPU1_P1_RX_BUF_DP<1>")
	)
	(segment
		(start 58.04916 -416.565334)
		(end 57.66308 -416.565334)
		(width 0.14224)
		(layer "In13.Cu")
		(net "P5E_CPU1_P1_RX_BUF_DP<1>")
	)
	(segment
		(start 81.085182 -394.269722)
		(end 81.085182 -393.159996)
		(width 0.14224)
		(layer "In13.Cu")
		(net "P5E_CPU1_P1_RX_BUF_DP<1>")
	)
	(segment
		(start 81.54416 -393.144756)
		(end 81.54416 -393.292838)
		(width 0.14224)
		(layer "In13.Cu")
		(net "P5E_CPU1_P1_RX_BUF_DP<1>")
	)
	(segment
		(start 54.493414 -409.302458)
		(end 54.630574 -409.165298)
		(width 0.14224)
		(layer "In13.Cu")
		(net "P5E_CPU1_P1_RX_BUF_DP<1>")
	)
	(segment
		(start 57.66308 -416.565334)
		(end 57.52592 -416.428174)
		(width 0.14224)
		(layer "In13.Cu")
		(net "P5E_CPU1_P1_RX_BUF_DP<1>")
	)
	(segment
		(start 56.025034 -404.924514)
		(end 56.025034 -403.989286)
		(width 0.14224)
		(layer "In13.Cu")
		(net "P5E_CPU1_P1_RX_BUF_DP<1>")
	)
	(segment
		(start 54.20233 -411.18282)
		(end 54.369716 -411.006798)
		(width 0.14224)
		(layer "In13.Cu")
		(net "P5E_CPU1_P1_RX_BUF_DP<1>")
	)
	(segment
		(start 59.971178 -426.873162)
		(end 59.971178 -417.459922)
		(width 0.14224)
		(layer "In13.Cu")
		(net "P5E_CPU1_P1_RX_BUF_DP<1>")
	)
	(segment
		(start 55.606442 -415.968434)
		(end 55.606442 -415.774378)
		(width 0.14224)
		(layer "In13.Cu")
		(net "P5E_CPU1_P1_RX_BUF_DP<1>")
	)
	(segment
		(start 60.649866 -434.289962)
		(end 60.649866 -434.618638)
		(width 0.14224)
		(layer "In13.Cu")
		(net "P5E_CPU1_P1_RX_BUF_DP<1>")
	)
	(segment
		(start 54.808882 -415.170874)
		(end 54.808882 -414.976818)
		(width 0.14224)
		(layer "In13.Cu")
		(net "P5E_CPU1_P1_RX_BUF_DP<1>")
	)
	(segment
		(start 55.304436 -415.472372)
		(end 55.11038 -415.472372)
		(width 0.14224)
		(layer "In13.Cu")
		(net "P5E_CPU1_P1_RX_BUF_DP<1>")
	)
	(segment
		(start 53.709316 -413.877252)
		(end 53.51526 -413.877252)
		(width 0.14224)
		(layer "In13.Cu")
		(net "P5E_CPU1_P1_RX_BUF_DP<1>")
	)
	(segment
		(start 55.084726 -405.885142)
		(end 55.360316 -405.771096)
		(width 0.14224)
		(layer "In13.Cu")
		(net "P5E_CPU1_P1_RX_BUF_DP<1>")
	)
	(segment
		(start 58.407554 -402.748242)
		(end 58.481976 -402.568918)
		(width 0.14224)
		(layer "In13.Cu")
		(net "P5E_CPU1_P1_RX_BUF_DP<1>")
	)
	(segment
		(start 58.70956 -416.565334)
		(end 58.5724 -416.428174)
		(width 0.14224)
		(layer "In13.Cu")
		(net "P5E_CPU1_P1_RX_BUF_DP<1>")
	)
	(segment
		(start 55.360316 -405.771096)
		(end 55.675784 -405.560276)
		(width 0.14224)
		(layer "In13.Cu")
		(net "P5E_CPU1_P1_RX_BUF_DP<1>")
	)
	(segment
		(start 54.506876 -414.674812)
		(end 54.31282 -414.674812)
		(width 0.14224)
		(layer "In13.Cu")
		(net "P5E_CPU1_P1_RX_BUF_DP<1>")
	)
	(segment
		(start 55.606442 -415.774378)
		(end 55.304436 -415.472372)
		(width 0.14224)
		(layer "In13.Cu")
		(net "P5E_CPU1_P1_RX_BUF_DP<1>")
	)
	(segment
		(start 57.52592 -416.428174)
		(end 57.13984 -416.428174)
		(width 0.14224)
		(layer "In13.Cu")
		(net "P5E_CPU1_P1_RX_BUF_DP<1>")
	)
	(segment
		(start 53.51526 -413.877252)
		(end 53.02504 -413.387032)
		(width 0.14224)
		(layer "In13.Cu")
		(net "P5E_CPU1_P1_RX_BUF_DP<1>")
	)
	(segment
		(start 54.493414 -410.697172)
		(end 54.493414 -409.302458)
		(width 0.14224)
		(layer "In13.Cu")
		(net "P5E_CPU1_P1_RX_BUF_DP<1>")
	)
	(segment
		(start 54.493414 -408.105102)
		(end 54.630574 -407.967942)
		(width 0.14224)
		(layer "In13.Cu")
		(net "P5E_CPU1_P1_RX_BUF_DP<1>")
	)
	(segment
		(start 60.649866 -434.618638)
		(end 60.51169 -434.756814)
		(width 0.14224)
		(layer "In13.Cu")
		(net "P5E_CPU1_P1_RX_BUF_DP<1>")
	)
	(segment
		(start 70.675754 -397.524986)
		(end 73.57745 -396.547594)
		(width 0.14224)
		(layer "In13.Cu")
		(net "P5E_CPU1_P1_RX_BUF_DP<1>")
	)
	(segment
		(start 68.559172 -398.400778)
		(end 68.738242 -398.4752)
		(width 0.14224)
		(layer "In13.Cu")
		(net "P5E_CPU1_P1_RX_BUF_DP<1>")
	)
	(segment
		(start 69.633592 -397.956278)
		(end 69.812662 -398.030446)
		(width 0.14224)
		(layer "In13.Cu")
		(net "P5E_CPU1_P1_RX_BUF_DP<1>")
	)
	(segment
		(start 55.675784 -405.560276)
		(end 55.822596 -405.413464)
		(width 0.14224)
		(layer "In13.Cu")
		(net "P5E_CPU1_P1_RX_BUF_DP<1>")
	)
	(segment
		(start 76.347066 -395.768576)
		(end 79.441802 -395.064996)
		(width 0.14224)
		(layer "In13.Cu")
		(net "P5E_CPU1_P1_RX_BUF_DP<1>")
	)
	(segment
		(start 70.281546 -397.688054)
		(end 70.675754 -397.524986)
		(width 0.14224)
		(layer "In13.Cu")
		(net "P5E_CPU1_P1_RX_BUF_DP<1>")
	)
	(segment
		(start 59.775598 -416.987482)
		(end 59.535822 -416.747706)
		(width 0.14224)
		(layer "In13.Cu")
		(net "P5E_CPU1_P1_RX_BUF_DP<1>")
	)
	(segment
		(start 68.738242 -398.4752)
		(end 69.132958 -398.311878)
		(width 0.14224)
		(layer "In13.Cu")
		(net "P5E_CPU1_P1_RX_BUF_DP<1>")
	)
	(segment
		(start 68.164964 -398.563846)
		(end 68.559172 -398.400778)
		(width 0.14224)
		(layer "In13.Cu")
		(net "P5E_CPU1_P1_RX_BUF_DP<1>")
	)
	(segment
		(start 57.834022 -402.837142)
		(end 58.013092 -402.91131)
		(width 0.14224)
		(layer "In13.Cu")
		(net "P5E_CPU1_P1_RX_BUF_DP<1>")
	)
	(segment
		(start 58.5724 -416.428174)
		(end 58.18632 -416.428174)
		(width 0.14224)
		(layer "In13.Cu")
		(net "P5E_CPU1_P1_RX_BUF_DP<1>")
	)
	(segment
		(start 54.493414 -407.404062)
		(end 54.493414 -406.638252)
		(width 0.14224)
		(layer "In13.Cu")
		(net "P5E_CPU1_P1_RX_BUF_DP<1>")
	)
	(segment
		(start 59.976258 -434.45811)
		(end 59.976258 -426.878242)
		(width 0.14224)
		(layer "In13.Cu")
		(net "P5E_CPU1_P1_RX_BUF_DP<1>")
	)
	(segment
		(start 79.441802 -395.064996)
		(end 80.677258 -394.62075)
		(width 0.14224)
		(layer "In13.Cu")
		(net "P5E_CPU1_P1_RX_BUF_DP<1>")
	)
	(segment
		(start 67.51701 -398.83207)
		(end 67.69608 -398.906238)
		(width 0.14224)
		(layer "In13.Cu")
		(net "P5E_CPU1_P1_RX_BUF_DP<1>")
	)
	(segment
		(start 54.493414 -408.601418)
		(end 54.493414 -408.105102)
		(width 0.14224)
		(layer "In13.Cu")
		(net "P5E_CPU1_P1_RX_BUF_DP<1>")
	)
	(segment
		(start 59.09564 -416.565334)
		(end 58.70956 -416.565334)
		(width 0.14224)
		(layer "In13.Cu")
		(net "P5E_CPU1_P1_RX_BUF_DP<1>")
	)
	(segment
		(start 55.11038 -415.472372)
		(end 54.808882 -415.170874)
		(width 0.14224)
		(layer "In13.Cu")
		(net "P5E_CPU1_P1_RX_BUF_DP<1>")
	)
	(segment
		(start 69.132958 -398.311878)
		(end 69.20738 -398.132554)
		(width 0.14224)
		(layer "In13.Cu")
		(net "P5E_CPU1_P1_RX_BUF_DP<1>")
	)
	(arc
		(start 52.961794 -411.846014)
		(mid 52.985728 -411.7672)
		(end 53.049424 -411.71495)
		(width 0.14224)
		(layer "In13.Cu")
		(net "P5E_CPU1_P1_RX_BUF_DP<1>")
	)
	(arc
		(start 53.02504 -413.387032)
		(mid 52.978242 -413.316994)
		(end 52.961794 -413.234378)
		(width 0.14224)
		(layer "In13.Cu")
		(net "P5E_CPU1_P1_RX_BUF_DP<1>")
	)
	(arc
		(start 54.698392 -406.14346)
		(mid 54.878862 -405.995314)
		(end 55.084726 -405.885142)
		(width 0.14224)
		(layer "In13.Cu")
		(net "P5E_CPU1_P1_RX_BUF_DP<1>")
	)
	(arc
		(start 56.319166 -416.565334)
		(mid 56.212064 -416.544012)
		(end 56.1213 -416.483292)
		(width 0.14224)
		(layer "In13.Cu")
		(net "P5E_CPU1_P1_RX_BUF_DP<1>")
	)
	(arc
		(start 59.971178 -417.459922)
		(mid 59.920343 -417.204268)
		(end 59.775598 -416.987482)
		(width 0.14224)
		(layer "In13.Cu")
		(net "P5E_CPU1_P1_RX_BUF_DP<1>")
	)
	(arc
		(start 54.369716 -411.006798)
		(mid 54.461392 -410.863907)
		(end 54.493414 -410.697172)
		(width 0.14224)
		(layer "In13.Cu")
		(net "P5E_CPU1_P1_RX_BUF_DP<1>")
	)
	(arc
		(start 54.493414 -406.638252)
		(mid 54.546643 -406.370451)
		(end 54.698392 -406.14346)
		(width 0.14224)
		(layer "In13.Cu")
		(net "P5E_CPU1_P1_RX_BUF_DP<1>")
	)
	(arc
		(start 59.535822 -416.747706)
		(mid 59.333879 -416.612709)
		(end 59.09564 -416.565334)
		(width 0.14224)
		(layer "In13.Cu")
		(net "P5E_CPU1_P1_RX_BUF_DP<1>")
	)
	(arc
		(start 55.822596 -405.413464)
		(mid 55.972436 -405.189118)
		(end 56.025034 -404.924514)
		(width 0.14224)
		(layer "In13.Cu")
		(net "P5E_CPU1_P1_RX_BUF_DP<1>")
	)
	(arc
		(start 56.025034 -403.989286)
		(mid 56.12697 -403.653349)
		(end 56.398414 -403.43074)
		(width 0.14224)
		(layer "In13.Cu")
		(net "P5E_CPU1_P1_RX_BUF_DP<1>")
	)
	(arc
		(start 54.001924 -411.31998)
		(mid 54.109322 -411.261911)
		(end 54.20233 -411.18282)
		(width 0.14224)
		(layer "In13.Cu")
		(net "P5E_CPU1_P1_RX_BUF_DP<1>")
	)
	(segment
		(start 97.641664 -391.577322)
		(end 97.641664 -392.723878)
		(width 0.1016)
		(layer "F.Cu")
		(net "P5E_CPU1_P1_RX_BUF_DP<15>")
	)
	(segment
		(start 97.641664 -392.723878)
		(end 97.894902 -392.977116)
		(width 0.1016)
		(layer "F.Cu")
		(net "P5E_CPU1_P1_RX_BUF_DP<15>")
	)
	(segment
		(start 98.189034 -392.977116)
		(end 98.344228 -393.13231)
		(width 0.1016)
		(layer "F.Cu")
		(net "P5E_CPU1_P1_RX_BUF_DP<15>")
	)
	(segment
		(start 97.73031 -391.488676)
		(end 97.641664 -391.577322)
		(width 0.1016)
		(layer "F.Cu")
		(net "P5E_CPU1_P1_RX_BUF_DP<15>")
	)
	(segment
		(start 97.73031 -391.36574)
		(end 97.73031 -391.488676)
		(width 0.1016)
		(layer "F.Cu")
		(net "P5E_CPU1_P1_RX_BUF_DP<15>")
	)
	(segment
		(start 97.894902 -392.977116)
		(end 98.189034 -392.977116)
		(width 0.1016)
		(layer "F.Cu")
		(net "P5E_CPU1_P1_RX_BUF_DP<15>")
	)
	(segment
		(start 98.344228 -393.13231)
		(end 98.344228 -393.292838)
		(width 0.1016)
		(layer "F.Cu")
		(net "P5E_CPU1_P1_RX_BUF_DP<15>")
	)
	(segment
		(start 97.645728 -391.281158)
		(end 97.73031 -391.36574)
		(width 0.1016)
		(layer "F.Cu")
		(net "P5E_CPU1_P1_RX_BUF_DP<15>")
	)
	(segment
		(start 98.02241 -407.119074)
		(end 98.02241 -407.545794)
		(width 0.14224)
		(layer "In13.Cu")
		(net "P5E_CPU1_P1_RX_BUF_DP<15>")
	)
	(segment
		(start 89.586562 -420.787068)
		(end 89.392506 -420.787068)
		(width 0.14224)
		(layer "In13.Cu")
		(net "P5E_CPU1_P1_RX_BUF_DP<15>")
	)
	(segment
		(start 88.976454 -434.45811)
		(end 89.257886 -434.739542)
		(width 0.14224)
		(layer "In13.Cu")
		(net "P5E_CPU1_P1_RX_BUF_DP<15>")
	)
	(segment
		(start 90.686128 -419.687502)
		(end 90.384122 -419.989508)
		(width 0.14224)
		(layer "In13.Cu")
		(net "P5E_CPU1_P1_RX_BUF_DP<15>")
	)
	(segment
		(start 98.217228 -393.017756)
		(end 98.02749 -393.017756)
		(width 0.14224)
		(layer "In13.Cu")
		(net "P5E_CPU1_P1_RX_BUF_DP<15>")
	)
	(segment
		(start 97.303844 -410.802836)
		(end 97.373694 -410.983938)
		(width 0.14224)
		(layer "In13.Cu")
		(net "P5E_CPU1_P1_RX_BUF_DP<15>")
	)
	(segment
		(start 93.021404 -417.15817)
		(end 93.021404 -417.352226)
		(width 0.14224)
		(layer "In13.Cu")
		(net "P5E_CPU1_P1_RX_BUF_DP<15>")
	)
	(segment
		(start 93.76156 -416.418014)
		(end 93.76156 -416.61207)
		(width 0.14224)
		(layer "In13.Cu")
		(net "P5E_CPU1_P1_RX_BUF_DP<15>")
	)
	(segment
		(start 96.4946 -413.684974)
		(end 93.76156 -416.418014)
		(width 0.14224)
		(layer "In13.Cu")
		(net "P5E_CPU1_P1_RX_BUF_DP<15>")
	)
	(segment
		(start 98.02749 -393.017756)
		(end 97.88525 -393.159996)
		(width 0.14224)
		(layer "In13.Cu")
		(net "P5E_CPU1_P1_RX_BUF_DP<15>")
	)
	(segment
		(start 88.976454 -426.878496)
		(end 88.976454 -434.45811)
		(width 0.14224)
		(layer "In13.Cu")
		(net "P5E_CPU1_P1_RX_BUF_DP<15>")
	)
	(segment
		(start 97.88525 -393.159996)
		(end 97.88525 -405.854154)
		(width 0.14224)
		(layer "In13.Cu")
		(net "P5E_CPU1_P1_RX_BUF_DP<15>")
	)
	(segment
		(start 90.686128 -419.493446)
		(end 90.686128 -419.687502)
		(width 0.14224)
		(layer "In13.Cu")
		(net "P5E_CPU1_P1_RX_BUF_DP<15>")
	)
	(segment
		(start 88.97112 -421.378126)
		(end 88.97112 -426.873162)
		(width 0.14224)
		(layer "In13.Cu")
		(net "P5E_CPU1_P1_RX_BUF_DP<15>")
	)
	(segment
		(start 98.02241 -407.545794)
		(end 97.88525 -407.682954)
		(width 0.14224)
		(layer "In13.Cu")
		(net "P5E_CPU1_P1_RX_BUF_DP<15>")
	)
	(segment
		(start 98.02241 -406.418034)
		(end 97.88525 -406.555194)
		(width 0.14224)
		(layer "In13.Cu")
		(net "P5E_CPU1_P1_RX_BUF_DP<15>")
	)
	(segment
		(start 98.02241 -408.246834)
		(end 98.02241 -408.673554)
		(width 0.14224)
		(layer "In13.Cu")
		(net "P5E_CPU1_P1_RX_BUF_DP<15>")
	)
	(segment
		(start 96.846898 -412.074614)
		(end 96.846898 -412.834328)
		(width 0.14224)
		(layer "In13.Cu")
		(net "P5E_CPU1_P1_RX_BUF_DP<15>")
	)
	(segment
		(start 92.281248 -417.898326)
		(end 92.281248 -418.092382)
		(width 0.14224)
		(layer "In13.Cu")
		(net "P5E_CPU1_P1_RX_BUF_DP<15>")
	)
	(segment
		(start 88.97112 -426.873162)
		(end 88.976454 -426.878496)
		(width 0.14224)
		(layer "In13.Cu")
		(net "P5E_CPU1_P1_RX_BUF_DP<15>")
	)
	(segment
		(start 97.88525 -406.555194)
		(end 97.88525 -406.981914)
		(width 0.14224)
		(layer "In13.Cu")
		(net "P5E_CPU1_P1_RX_BUF_DP<15>")
	)
	(segment
		(start 90.987626 -419.191948)
		(end 90.686128 -419.493446)
		(width 0.14224)
		(layer "In13.Cu")
		(net "P5E_CPU1_P1_RX_BUF_DP<15>")
	)
	(segment
		(start 98.344228 -393.144756)
		(end 98.217228 -393.017756)
		(width 0.14224)
		(layer "In13.Cu")
		(net "P5E_CPU1_P1_RX_BUF_DP<15>")
	)
	(segment
		(start 90.190066 -419.989508)
		(end 89.888568 -420.291006)
		(width 0.14224)
		(layer "In13.Cu")
		(net "P5E_CPU1_P1_RX_BUF_DP<15>")
	)
	(segment
		(start 97.88525 -406.981914)
		(end 98.02241 -407.119074)
		(width 0.14224)
		(layer "In13.Cu")
		(net "P5E_CPU1_P1_RX_BUF_DP<15>")
	)
	(segment
		(start 98.02241 -408.673554)
		(end 97.88525 -408.810714)
		(width 0.14224)
		(layer "In13.Cu")
		(net "P5E_CPU1_P1_RX_BUF_DP<15>")
	)
	(segment
		(start 89.529158 -434.739542)
		(end 89.650062 -434.618638)
		(width 0.14224)
		(layer "In13.Cu")
		(net "P5E_CPU1_P1_RX_BUF_DP<15>")
	)
	(segment
		(start 97.373694 -410.983938)
		(end 97.200974 -411.374336)
		(width 0.14224)
		(layer "In13.Cu")
		(net "P5E_CPU1_P1_RX_BUF_DP<15>")
	)
	(segment
		(start 91.483688 -418.889942)
		(end 91.181682 -419.191948)
		(width 0.14224)
		(layer "In13.Cu")
		(net "P5E_CPU1_P1_RX_BUF_DP<15>")
	)
	(segment
		(start 97.88525 -407.682954)
		(end 97.88525 -408.109674)
		(width 0.14224)
		(layer "In13.Cu")
		(net "P5E_CPU1_P1_RX_BUF_DP<15>")
	)
	(segment
		(start 98.02241 -405.991314)
		(end 98.02241 -406.418034)
		(width 0.14224)
		(layer "In13.Cu")
		(net "P5E_CPU1_P1_RX_BUF_DP<15>")
	)
	(segment
		(start 97.88525 -408.109674)
		(end 98.02241 -408.246834)
		(width 0.14224)
		(layer "In13.Cu")
		(net "P5E_CPU1_P1_RX_BUF_DP<15>")
	)
	(segment
		(start 89.650062 -434.618638)
		(end 89.650062 -434.289962)
		(width 0.14224)
		(layer "In13.Cu")
		(net "P5E_CPU1_P1_RX_BUF_DP<15>")
	)
	(segment
		(start 92.281248 -418.092382)
		(end 91.979242 -418.394388)
		(width 0.14224)
		(layer "In13.Cu")
		(net "P5E_CPU1_P1_RX_BUF_DP<15>")
	)
	(segment
		(start 91.483688 -418.695886)
		(end 91.483688 -418.889942)
		(width 0.14224)
		(layer "In13.Cu")
		(net "P5E_CPU1_P1_RX_BUF_DP<15>")
	)
	(segment
		(start 92.7481 -417.62553)
		(end 92.554044 -417.62553)
		(width 0.14224)
		(layer "In13.Cu")
		(net "P5E_CPU1_P1_RX_BUF_DP<15>")
	)
	(segment
		(start 89.888568 -420.485062)
		(end 89.586562 -420.787068)
		(width 0.14224)
		(layer "In13.Cu")
		(net "P5E_CPU1_P1_RX_BUF_DP<15>")
	)
	(segment
		(start 93.2942 -416.885374)
		(end 93.021404 -417.15817)
		(width 0.14224)
		(layer "In13.Cu")
		(net "P5E_CPU1_P1_RX_BUF_DP<15>")
	)
	(segment
		(start 89.888568 -420.291006)
		(end 89.888568 -420.485062)
		(width 0.14224)
		(layer "In13.Cu")
		(net "P5E_CPU1_P1_RX_BUF_DP<15>")
	)
	(segment
		(start 98.344228 -393.292838)
		(end 98.344228 -393.144756)
		(width 0.14224)
		(layer "In13.Cu")
		(net "P5E_CPU1_P1_RX_BUF_DP<15>")
	)
	(segment
		(start 89.392506 -420.787068)
		(end 89.091008 -421.088566)
		(width 0.14224)
		(layer "In13.Cu")
		(net "P5E_CPU1_P1_RX_BUF_DP<15>")
	)
	(segment
		(start 97.78238 -409.723082)
		(end 97.303844 -410.802836)
		(width 0.14224)
		(layer "In13.Cu")
		(net "P5E_CPU1_P1_RX_BUF_DP<15>")
	)
	(segment
		(start 93.021404 -417.352226)
		(end 92.7481 -417.62553)
		(width 0.14224)
		(layer "In13.Cu")
		(net "P5E_CPU1_P1_RX_BUF_DP<15>")
	)
	(segment
		(start 97.88525 -408.810714)
		(end 97.88525 -409.237434)
		(width 0.14224)
		(layer "In13.Cu")
		(net "P5E_CPU1_P1_RX_BUF_DP<15>")
	)
	(segment
		(start 97.88525 -405.854154)
		(end 98.02241 -405.991314)
		(width 0.14224)
		(layer "In13.Cu")
		(net "P5E_CPU1_P1_RX_BUF_DP<15>")
	)
	(segment
		(start 90.384122 -419.989508)
		(end 90.190066 -419.989508)
		(width 0.14224)
		(layer "In13.Cu")
		(net "P5E_CPU1_P1_RX_BUF_DP<15>")
	)
	(segment
		(start 93.488256 -416.885374)
		(end 93.2942 -416.885374)
		(width 0.14224)
		(layer "In13.Cu")
		(net "P5E_CPU1_P1_RX_BUF_DP<15>")
	)
	(segment
		(start 97.019618 -411.444186)
		(end 96.94418 -411.614366)
		(width 0.14224)
		(layer "In13.Cu")
		(net "P5E_CPU1_P1_RX_BUF_DP<15>")
	)
	(segment
		(start 89.257886 -434.739542)
		(end 89.529158 -434.739542)
		(width 0.14224)
		(layer "In13.Cu")
		(net "P5E_CPU1_P1_RX_BUF_DP<15>")
	)
	(segment
		(start 91.785186 -418.394388)
		(end 91.483688 -418.695886)
		(width 0.14224)
		(layer "In13.Cu")
		(net "P5E_CPU1_P1_RX_BUF_DP<15>")
	)
	(segment
		(start 92.554044 -417.62553)
		(end 92.281248 -417.898326)
		(width 0.14224)
		(layer "In13.Cu")
		(net "P5E_CPU1_P1_RX_BUF_DP<15>")
	)
	(segment
		(start 91.979242 -418.394388)
		(end 91.785186 -418.394388)
		(width 0.14224)
		(layer "In13.Cu")
		(net "P5E_CPU1_P1_RX_BUF_DP<15>")
	)
	(segment
		(start 93.76156 -416.61207)
		(end 93.488256 -416.885374)
		(width 0.14224)
		(layer "In13.Cu")
		(net "P5E_CPU1_P1_RX_BUF_DP<15>")
	)
	(segment
		(start 91.181682 -419.191948)
		(end 90.987626 -419.191948)
		(width 0.14224)
		(layer "In13.Cu")
		(net "P5E_CPU1_P1_RX_BUF_DP<15>")
	)
	(segment
		(start 97.200974 -411.374336)
		(end 97.019618 -411.444186)
		(width 0.14224)
		(layer "In13.Cu")
		(net "P5E_CPU1_P1_RX_BUF_DP<15>")
	)
	(segment
		(start 97.88525 -409.237434)
		(end 97.78238 -409.723082)
		(width 0.14224)
		(layer "In13.Cu")
		(net "P5E_CPU1_P1_RX_BUF_DP<15>")
	)
	(arc
		(start 96.846898 -412.834328)
		(mid 96.755344 -413.294689)
		(end 96.4946 -413.684974)
		(width 0.14224)
		(layer "In13.Cu")
		(net "P5E_CPU1_P1_RX_BUF_DP<15>")
	)
	(arc
		(start 96.94418 -411.614366)
		(mid 96.871472 -411.839402)
		(end 96.846898 -412.074614)
		(width 0.14224)
		(layer "In13.Cu")
		(net "P5E_CPU1_P1_RX_BUF_DP<15>")
	)
	(arc
		(start 89.091008 -421.088566)
		(mid 89.002293 -421.221431)
		(end 88.97112 -421.378126)
		(width 0.14224)
		(layer "In13.Cu")
		(net "P5E_CPU1_P1_RX_BUF_DP<15>")
	)
	(segment
		(start 96.441768 -392.723878)
		(end 96.695006 -392.977116)
		(width 0.1016)
		(layer "F.Cu")
		(net "P5E_CPU1_P1_RX_BUF_DP<14>")
	)
	(segment
		(start 97.144332 -393.133834)
		(end 97.144332 -393.292838)
		(width 0.1016)
		(layer "F.Cu")
		(net "P5E_CPU1_P1_RX_BUF_DP<14>")
	)
	(segment
		(start 96.987614 -392.977116)
		(end 97.144332 -393.133834)
		(width 0.1016)
		(layer "F.Cu")
		(net "P5E_CPU1_P1_RX_BUF_DP<14>")
	)
	(segment
		(start 96.445832 -391.281158)
		(end 96.530414 -391.36574)
		(width 0.1016)
		(layer "F.Cu")
		(net "P5E_CPU1_P1_RX_BUF_DP<14>")
	)
	(segment
		(start 96.441768 -391.577322)
		(end 96.441768 -392.723878)
		(width 0.1016)
		(layer "F.Cu")
		(net "P5E_CPU1_P1_RX_BUF_DP<14>")
	)
	(segment
		(start 96.530414 -391.36574)
		(end 96.530414 -391.488676)
		(width 0.1016)
		(layer "F.Cu")
		(net "P5E_CPU1_P1_RX_BUF_DP<14>")
	)
	(segment
		(start 96.695006 -392.977116)
		(end 96.987614 -392.977116)
		(width 0.1016)
		(layer "F.Cu")
		(net "P5E_CPU1_P1_RX_BUF_DP<14>")
	)
	(segment
		(start 96.530414 -391.488676)
		(end 96.441768 -391.577322)
		(width 0.1016)
		(layer "F.Cu")
		(net "P5E_CPU1_P1_RX_BUF_DP<14>")
	)
	(segment
		(start 96.16821 -401.673822)
		(end 96.2914 -401.823682)
		(width 0.14224)
		(layer "In13.Cu")
		(net "P5E_CPU1_P1_RX_BUF_DP<14>")
	)
	(segment
		(start 96.320356 -400.126962)
		(end 96.2787 -400.551396)
		(width 0.14224)
		(layer "In13.Cu")
		(net "P5E_CPU1_P1_RX_BUF_DP<14>")
	)
	(segment
		(start 88.326976 -419.452806)
		(end 88.025478 -419.754304)
		(width 0.14224)
		(layer "In13.Cu")
		(net "P5E_CPU1_P1_RX_BUF_DP<14>")
	)
	(segment
		(start 94.315534 -409.45308)
		(end 94.315534 -410.697172)
		(width 0.14224)
		(layer "In13.Cu")
		(net "P5E_CPU1_P1_RX_BUF_DP<14>")
	)
	(segment
		(start 92.783914 -411.846268)
		(end 92.783914 -414.626298)
		(width 0.14224)
		(layer "In13.Cu")
		(net "P5E_CPU1_P1_RX_BUF_DP<14>")
	)
	(segment
		(start 88.025478 -419.754304)
		(end 88.025478 -419.94836)
		(width 0.14224)
		(layer "In13.Cu")
		(net "P5E_CPU1_P1_RX_BUF_DP<14>")
	)
	(segment
		(start 96.685354 -393.159996)
		(end 96.685354 -395.553946)
		(width 0.14224)
		(layer "In13.Cu")
		(net "P5E_CPU1_P1_RX_BUF_DP<14>")
	)
	(segment
		(start 89.28989 -418.683948)
		(end 89.095834 -418.683948)
		(width 0.14224)
		(layer "In13.Cu")
		(net "P5E_CPU1_P1_RX_BUF_DP<14>")
	)
	(segment
		(start 86.971124 -426.873162)
		(end 86.976458 -426.878496)
		(width 0.14224)
		(layer "In13.Cu")
		(net "P5E_CPU1_P1_RX_BUF_DP<14>")
	)
	(segment
		(start 87.519764 -433.748942)
		(end 87.650066 -433.61864)
		(width 0.14224)
		(layer "In13.Cu")
		(net "P5E_CPU1_P1_RX_BUF_DP<14>")
	)
	(segment
		(start 94.452694 -408.8892)
		(end 94.452694 -409.31592)
		(width 0.14224)
		(layer "In13.Cu")
		(net "P5E_CPU1_P1_RX_BUF_DP<14>")
	)
	(segment
		(start 94.315534 -408.32532)
		(end 94.315534 -408.75204)
		(width 0.14224)
		(layer "In13.Cu")
		(net "P5E_CPU1_P1_RX_BUF_DP<14>")
	)
	(segment
		(start 94.315534 -408.75204)
		(end 94.452694 -408.8892)
		(width 0.14224)
		(layer "In13.Cu")
		(net "P5E_CPU1_P1_RX_BUF_DP<14>")
	)
	(segment
		(start 94.452694 -408.18816)
		(end 94.315534 -408.32532)
		(width 0.14224)
		(layer "In13.Cu")
		(net "P5E_CPU1_P1_RX_BUF_DP<14>")
	)
	(segment
		(start 92.522548 -415.257234)
		(end 90.360754 -417.419028)
		(width 0.14224)
		(layer "In13.Cu")
		(net "P5E_CPU1_P1_RX_BUF_DP<14>")
	)
	(segment
		(start 96.47047 -400.003772)
		(end 96.320356 -400.126962)
		(width 0.14224)
		(layer "In13.Cu")
		(net "P5E_CPU1_P1_RX_BUF_DP<14>")
	)
	(segment
		(start 89.095834 -418.683948)
		(end 88.823038 -418.956744)
		(width 0.14224)
		(layer "In13.Cu")
		(net "P5E_CPU1_P1_RX_BUF_DP<14>")
	)
	(segment
		(start 94.452694 -409.31592)
		(end 94.315534 -409.45308)
		(width 0.14224)
		(layer "In13.Cu")
		(net "P5E_CPU1_P1_RX_BUF_DP<14>")
	)
	(segment
		(start 88.823038 -418.956744)
		(end 88.823038 -419.1508)
		(width 0.14224)
		(layer "In13.Cu")
		(net "P5E_CPU1_P1_RX_BUF_DP<14>")
	)
	(segment
		(start 94.191836 -411.006798)
		(end 94.02445 -411.18282)
		(width 0.14224)
		(layer "In13.Cu")
		(net "P5E_CPU1_P1_RX_BUF_DP<14>")
	)
	(segment
		(start 93.824044 -411.31998)
		(end 92.871544 -411.71495)
		(width 0.14224)
		(layer "In13.Cu")
		(net "P5E_CPU1_P1_RX_BUF_DP<14>")
	)
	(segment
		(start 89.563194 -418.410644)
		(end 89.28989 -418.683948)
		(width 0.14224)
		(layer "In13.Cu")
		(net "P5E_CPU1_P1_RX_BUF_DP<14>")
	)
	(segment
		(start 96.40189 -400.701256)
		(end 96.35998 -401.126198)
		(width 0.14224)
		(layer "In13.Cu")
		(net "P5E_CPU1_P1_RX_BUF_DP<14>")
	)
	(segment
		(start 90.360754 -417.419028)
		(end 90.360754 -417.613084)
		(width 0.14224)
		(layer "In13.Cu")
		(net "P5E_CPU1_P1_RX_BUF_DP<14>")
	)
	(segment
		(start 96.139 -403.37105)
		(end 95.988886 -403.49424)
		(width 0.14224)
		(layer "In13.Cu")
		(net "P5E_CPU1_P1_RX_BUF_DP<14>")
	)
	(segment
		(start 94.452694 -407.76144)
		(end 94.452694 -408.18816)
		(width 0.14224)
		(layer "In13.Cu")
		(net "P5E_CPU1_P1_RX_BUF_DP<14>")
	)
	(segment
		(start 95.988886 -403.49424)
		(end 95.94723 -403.918674)
		(width 0.14224)
		(layer "In13.Cu")
		(net "P5E_CPU1_P1_RX_BUF_DP<14>")
	)
	(segment
		(start 87.650066 -433.61864)
		(end 87.650066 -433.289964)
		(width 0.14224)
		(layer "In13.Cu")
		(net "P5E_CPU1_P1_RX_BUF_DP<14>")
	)
	(segment
		(start 96.209866 -401.249388)
		(end 96.16821 -401.673822)
		(width 0.14224)
		(layer "In13.Cu")
		(net "P5E_CPU1_P1_RX_BUF_DP<14>")
	)
	(segment
		(start 96.827594 -393.017756)
		(end 96.685354 -393.159996)
		(width 0.14224)
		(layer "In13.Cu")
		(net "P5E_CPU1_P1_RX_BUF_DP<14>")
	)
	(segment
		(start 86.976458 -426.878496)
		(end 86.976458 -433.458112)
		(width 0.14224)
		(layer "In13.Cu")
		(net "P5E_CPU1_P1_RX_BUF_DP<14>")
	)
	(segment
		(start 88.521032 -419.452806)
		(end 88.326976 -419.452806)
		(width 0.14224)
		(layer "In13.Cu")
		(net "P5E_CPU1_P1_RX_BUF_DP<14>")
	)
	(segment
		(start 96.600518 -397.281146)
		(end 96.38919 -399.42897)
		(width 0.14224)
		(layer "In13.Cu")
		(net "P5E_CPU1_P1_RX_BUF_DP<14>")
	)
	(segment
		(start 96.05772 -402.796248)
		(end 96.18091 -402.946108)
		(width 0.14224)
		(layer "In13.Cu")
		(net "P5E_CPU1_P1_RX_BUF_DP<14>")
	)
	(segment
		(start 94.315534 -407.62428)
		(end 94.452694 -407.76144)
		(width 0.14224)
		(layer "In13.Cu")
		(net "P5E_CPU1_P1_RX_BUF_DP<14>")
	)
	(segment
		(start 86.976458 -433.458112)
		(end 87.267288 -433.748942)
		(width 0.14224)
		(layer "In13.Cu")
		(net "P5E_CPU1_P1_RX_BUF_DP<14>")
	)
	(segment
		(start 96.028256 -404.493476)
		(end 95.878142 -404.616666)
		(width 0.14224)
		(layer "In13.Cu")
		(net "P5E_CPU1_P1_RX_BUF_DP<14>")
	)
	(segment
		(start 95.878142 -404.616666)
		(end 95.836486 -405.0411)
		(width 0.14224)
		(layer "In13.Cu")
		(net "P5E_CPU1_P1_RX_BUF_DP<14>")
	)
	(segment
		(start 96.070166 -404.068534)
		(end 96.028256 -404.493476)
		(width 0.14224)
		(layer "In13.Cu")
		(net "P5E_CPU1_P1_RX_BUF_DP<14>")
	)
	(segment
		(start 96.2787 -400.551396)
		(end 96.40189 -400.701256)
		(width 0.14224)
		(layer "In13.Cu")
		(net "P5E_CPU1_P1_RX_BUF_DP<14>")
	)
	(segment
		(start 96.099376 -402.371814)
		(end 96.05772 -402.796248)
		(width 0.14224)
		(layer "In13.Cu")
		(net "P5E_CPU1_P1_RX_BUF_DP<14>")
	)
	(segment
		(start 86.971124 -421.171878)
		(end 86.971124 -426.873162)
		(width 0.14224)
		(layer "In13.Cu")
		(net "P5E_CPU1_P1_RX_BUF_DP<14>")
	)
	(segment
		(start 96.24949 -402.248624)
		(end 96.099376 -402.371814)
		(width 0.14224)
		(layer "In13.Cu")
		(net "P5E_CPU1_P1_RX_BUF_DP<14>")
	)
	(segment
		(start 87.723472 -420.250366)
		(end 87.529416 -420.250366)
		(width 0.14224)
		(layer "In13.Cu")
		(net "P5E_CPU1_P1_RX_BUF_DP<14>")
	)
	(segment
		(start 97.144332 -393.144756)
		(end 97.017332 -393.017756)
		(width 0.14224)
		(layer "In13.Cu")
		(net "P5E_CPU1_P1_RX_BUF_DP<14>")
	)
	(segment
		(start 96.51238 -399.57883)
		(end 96.47047 -400.003772)
		(width 0.14224)
		(layer "In13.Cu")
		(net "P5E_CPU1_P1_RX_BUF_DP<14>")
	)
	(segment
		(start 96.35998 -401.126198)
		(end 96.209866 -401.249388)
		(width 0.14224)
		(layer "In13.Cu")
		(net "P5E_CPU1_P1_RX_BUF_DP<14>")
	)
	(segment
		(start 87.529416 -420.250366)
		(end 87.227918 -420.551864)
		(width 0.14224)
		(layer "In13.Cu")
		(net "P5E_CPU1_P1_RX_BUF_DP<14>")
	)
	(segment
		(start 95.94723 -403.918674)
		(end 96.070166 -404.068534)
		(width 0.14224)
		(layer "In13.Cu")
		(net "P5E_CPU1_P1_RX_BUF_DP<14>")
	)
	(segment
		(start 87.267288 -433.748942)
		(end 87.519764 -433.748942)
		(width 0.14224)
		(layer "In13.Cu")
		(net "P5E_CPU1_P1_RX_BUF_DP<14>")
	)
	(segment
		(start 96.18091 -402.946108)
		(end 96.139 -403.37105)
		(width 0.14224)
		(layer "In13.Cu")
		(net "P5E_CPU1_P1_RX_BUF_DP<14>")
	)
	(segment
		(start 89.864692 -417.91509)
		(end 89.563194 -418.216588)
		(width 0.14224)
		(layer "In13.Cu")
		(net "P5E_CPU1_P1_RX_BUF_DP<14>")
	)
	(segment
		(start 90.360754 -417.613084)
		(end 90.058748 -417.91509)
		(width 0.14224)
		(layer "In13.Cu")
		(net "P5E_CPU1_P1_RX_BUF_DP<14>")
	)
	(segment
		(start 96.38919 -399.42897)
		(end 96.51238 -399.57883)
		(width 0.14224)
		(layer "In13.Cu")
		(net "P5E_CPU1_P1_RX_BUF_DP<14>")
	)
	(segment
		(start 88.025478 -419.94836)
		(end 87.723472 -420.250366)
		(width 0.14224)
		(layer "In13.Cu")
		(net "P5E_CPU1_P1_RX_BUF_DP<14>")
	)
	(segment
		(start 94.315534 -406.637744)
		(end 94.315534 -407.62428)
		(width 0.14224)
		(layer "In13.Cu")
		(net "P5E_CPU1_P1_RX_BUF_DP<14>")
	)
	(segment
		(start 90.058748 -417.91509)
		(end 89.864692 -417.91509)
		(width 0.14224)
		(layer "In13.Cu")
		(net "P5E_CPU1_P1_RX_BUF_DP<14>")
	)
	(segment
		(start 97.017332 -393.017756)
		(end 96.827594 -393.017756)
		(width 0.14224)
		(layer "In13.Cu")
		(net "P5E_CPU1_P1_RX_BUF_DP<14>")
	)
	(segment
		(start 97.144332 -393.292838)
		(end 97.144332 -393.144756)
		(width 0.14224)
		(layer "In13.Cu")
		(net "P5E_CPU1_P1_RX_BUF_DP<14>")
	)
	(segment
		(start 89.563194 -418.216588)
		(end 89.563194 -418.410644)
		(width 0.14224)
		(layer "In13.Cu")
		(net "P5E_CPU1_P1_RX_BUF_DP<14>")
	)
	(segment
		(start 96.2914 -401.823682)
		(end 96.24949 -402.248624)
		(width 0.14224)
		(layer "In13.Cu")
		(net "P5E_CPU1_P1_RX_BUF_DP<14>")
	)
	(segment
		(start 88.823038 -419.1508)
		(end 88.521032 -419.452806)
		(width 0.14224)
		(layer "In13.Cu")
		(net "P5E_CPU1_P1_RX_BUF_DP<14>")
	)
	(segment
		(start 95.474028 -405.59228)
		(end 94.549976 -406.10409)
		(width 0.14224)
		(layer "In13.Cu")
		(net "P5E_CPU1_P1_RX_BUF_DP<14>")
	)
	(arc
		(start 92.871544 -411.71495)
		(mid 92.807739 -411.767294)
		(end 92.783914 -411.846268)
		(width 0.14224)
		(layer "In13.Cu")
		(net "P5E_CPU1_P1_RX_BUF_DP<14>")
	)
	(arc
		(start 94.315534 -410.697172)
		(mid 94.283569 -410.86393)
		(end 94.191836 -411.006798)
		(width 0.14224)
		(layer "In13.Cu")
		(net "P5E_CPU1_P1_RX_BUF_DP<14>")
	)
	(arc
		(start 96.685354 -395.553946)
		(mid 96.664123 -396.418587)
		(end 96.600518 -397.281146)
		(width 0.14224)
		(layer "In13.Cu")
		(net "P5E_CPU1_P1_RX_BUF_DP<14>")
	)
	(arc
		(start 94.549976 -406.10409)
		(mid 94.4981 -406.141095)
		(end 94.455996 -406.188926)
		(width 0.14224)
		(layer "In13.Cu")
		(net "P5E_CPU1_P1_RX_BUF_DP<14>")
	)
	(arc
		(start 92.783914 -414.626298)
		(mid 92.715992 -414.967767)
		(end 92.522548 -415.257234)
		(width 0.14224)
		(layer "In13.Cu")
		(net "P5E_CPU1_P1_RX_BUF_DP<14>")
	)
	(arc
		(start 95.836486 -405.0411)
		(mid 95.72317 -405.361357)
		(end 95.474028 -405.59228)
		(width 0.14224)
		(layer "In13.Cu")
		(net "P5E_CPU1_P1_RX_BUF_DP<14>")
	)
	(arc
		(start 94.455996 -406.188926)
		(mid 94.351451 -406.402598)
		(end 94.315534 -406.637744)
		(width 0.14224)
		(layer "In13.Cu")
		(net "P5E_CPU1_P1_RX_BUF_DP<14>")
	)
	(arc
		(start 94.02445 -411.18282)
		(mid 93.931432 -411.261897)
		(end 93.824044 -411.31998)
		(width 0.14224)
		(layer "In13.Cu")
		(net "P5E_CPU1_P1_RX_BUF_DP<14>")
	)
	(arc
		(start 87.227918 -420.551864)
		(mid 87.037845 -420.836329)
		(end 86.971124 -421.171878)
		(width 0.14224)
		(layer "In13.Cu")
		(net "P5E_CPU1_P1_RX_BUF_DP<14>")
	)
	(segment
		(start 95.944182 -393.1158)
		(end 95.944182 -393.292838)
		(width 0.1016)
		(layer "F.Cu")
		(net "P5E_CPU1_P1_RX_BUF_DP<13>")
	)
	(segment
		(start 95.330264 -391.488676)
		(end 95.250254 -391.568686)
		(width 0.1016)
		(layer "F.Cu")
		(net "P5E_CPU1_P1_RX_BUF_DP<13>")
	)
	(segment
		(start 95.330264 -391.36574)
		(end 95.330264 -391.488676)
		(width 0.1016)
		(layer "F.Cu")
		(net "P5E_CPU1_P1_RX_BUF_DP<13>")
	)
	(segment
		(start 95.250254 -391.568686)
		(end 95.250254 -392.723878)
		(width 0.1016)
		(layer "F.Cu")
		(net "P5E_CPU1_P1_RX_BUF_DP<13>")
	)
	(segment
		(start 95.250254 -392.723878)
		(end 95.503492 -392.977116)
		(width 0.1016)
		(layer "F.Cu")
		(net "P5E_CPU1_P1_RX_BUF_DP<13>")
	)
	(segment
		(start 95.503492 -392.977116)
		(end 95.805498 -392.977116)
		(width 0.1016)
		(layer "F.Cu")
		(net "P5E_CPU1_P1_RX_BUF_DP<13>")
	)
	(segment
		(start 95.805498 -392.977116)
		(end 95.944182 -393.1158)
		(width 0.1016)
		(layer "F.Cu")
		(net "P5E_CPU1_P1_RX_BUF_DP<13>")
	)
	(segment
		(start 95.245682 -391.281158)
		(end 95.330264 -391.36574)
		(width 0.1016)
		(layer "F.Cu")
		(net "P5E_CPU1_P1_RX_BUF_DP<13>")
	)
	(segment
		(start 94.590108 -397.88846)
		(end 94.446344 -398.290542)
		(width 0.14224)
		(layer "In13.Cu")
		(net "P5E_CPU1_P1_RX_BUF_DP<13>")
	)
	(segment
		(start 93.83014 -400.012408)
		(end 93.686376 -400.41449)
		(width 0.14224)
		(layer "In13.Cu")
		(net "P5E_CPU1_P1_RX_BUF_DP<13>")
	)
	(segment
		(start 93.177614 -402.506942)
		(end 93.094556 -402.925788)
		(width 0.14224)
		(layer "In13.Cu")
		(net "P5E_CPU1_P1_RX_BUF_DP<13>")
	)
	(segment
		(start 94.887288 -396.651226)
		(end 94.970092 -396.82674)
		(width 0.14224)
		(layer "In13.Cu")
		(net "P5E_CPU1_P1_RX_BUF_DP<13>")
	)
	(segment
		(start 94.650814 -397.311626)
		(end 94.50705 -397.7132)
		(width 0.14224)
		(layer "In13.Cu")
		(net "P5E_CPU1_P1_RX_BUF_DP<13>")
	)
	(segment
		(start 87.900002 -416.22599)
		(end 87.626698 -416.499294)
		(width 0.14224)
		(layer "In13.Cu")
		(net "P5E_CPU1_P1_RX_BUF_DP<13>")
	)
	(segment
		(start 86.41969 -417.706302)
		(end 86.117684 -418.008308)
		(width 0.14224)
		(layer "In13.Cu")
		(net "P5E_CPU1_P1_RX_BUF_DP<13>")
	)
	(segment
		(start 95.485204 -393.159996)
		(end 95.485204 -394.26261)
		(width 0.14224)
		(layer "In13.Cu")
		(net "P5E_CPU1_P1_RX_BUF_DP<13>")
	)
	(segment
		(start 87.159846 -416.966146)
		(end 86.886542 -417.23945)
		(width 0.14224)
		(layer "In13.Cu")
		(net "P5E_CPU1_P1_RX_BUF_DP<13>")
	)
	(segment
		(start 94.06636 -399.352516)
		(end 93.890846 -399.435574)
		(width 0.14224)
		(layer "In13.Cu")
		(net "P5E_CPU1_P1_RX_BUF_DP<13>")
	)
	(segment
		(start 91.252294 -409.548584)
		(end 91.252294 -410.697172)
		(width 0.14224)
		(layer "In13.Cu")
		(net "P5E_CPU1_P1_RX_BUF_DP<13>")
	)
	(segment
		(start 95.167196 -395.868652)
		(end 94.887796 -396.649702)
		(width 0.14224)
		(layer "In13.Cu")
		(net "P5E_CPU1_P1_RX_BUF_DP<13>")
	)
	(segment
		(start 84.976462 -426.878496)
		(end 84.976462 -434.45811)
		(width 0.14224)
		(layer "In13.Cu")
		(net "P5E_CPU1_P1_RX_BUF_DP<13>")
	)
	(segment
		(start 93.686376 -400.41449)
		(end 93.510862 -400.497548)
		(width 0.14224)
		(layer "In13.Cu")
		(net "P5E_CPU1_P1_RX_BUF_DP<13>")
	)
	(segment
		(start 94.446344 -398.290542)
		(end 94.27083 -398.3736)
		(width 0.14224)
		(layer "In13.Cu")
		(net "P5E_CPU1_P1_RX_BUF_DP<13>")
	)
	(segment
		(start 93.333316 -401.021042)
		(end 93.069918 -402.345652)
		(width 0.14224)
		(layer "In13.Cu")
		(net "P5E_CPU1_P1_RX_BUF_DP<13>")
	)
	(segment
		(start 91.252294 -406.638252)
		(end 91.252294 -407.719784)
		(width 0.14224)
		(layer "In13.Cu")
		(net "P5E_CPU1_P1_RX_BUF_DP<13>")
	)
	(segment
		(start 92.581476 -405.413464)
		(end 92.434664 -405.560276)
		(width 0.14224)
		(layer "In13.Cu")
		(net "P5E_CPU1_P1_RX_BUF_DP<13>")
	)
	(segment
		(start 93.747082 -399.837148)
		(end 93.83014 -400.012408)
		(width 0.14224)
		(layer "In13.Cu")
		(net "P5E_CPU1_P1_RX_BUF_DP<13>")
	)
	(segment
		(start 92.933012 -403.033484)
		(end 92.821506 -403.594316)
		(width 0.14224)
		(layer "In13.Cu")
		(net "P5E_CPU1_P1_RX_BUF_DP<13>")
	)
	(segment
		(start 92.119196 -405.771096)
		(end 91.843606 -405.885142)
		(width 0.14224)
		(layer "In13.Cu")
		(net "P5E_CPU1_P1_RX_BUF_DP<13>")
	)
	(segment
		(start 94.127066 -398.775174)
		(end 94.210124 -398.950434)
		(width 0.14224)
		(layer "In13.Cu")
		(net "P5E_CPU1_P1_RX_BUF_DP<13>")
	)
	(segment
		(start 91.252294 -408.420824)
		(end 91.252294 -408.847544)
		(width 0.14224)
		(layer "In13.Cu")
		(net "P5E_CPU1_P1_RX_BUF_DP<13>")
	)
	(segment
		(start 94.50705 -397.7132)
		(end 94.590108 -397.88846)
		(width 0.14224)
		(layer "In13.Cu")
		(net "P5E_CPU1_P1_RX_BUF_DP<13>")
	)
	(segment
		(start 90.760804 -411.31998)
		(end 89.808304 -411.71495)
		(width 0.14224)
		(layer "In13.Cu")
		(net "P5E_CPU1_P1_RX_BUF_DP<13>")
	)
	(segment
		(start 93.094556 -402.925788)
		(end 92.933012 -403.033484)
		(width 0.14224)
		(layer "In13.Cu")
		(net "P5E_CPU1_P1_RX_BUF_DP<13>")
	)
	(segment
		(start 86.692486 -417.23945)
		(end 86.41969 -417.512246)
		(width 0.14224)
		(layer "In13.Cu")
		(net "P5E_CPU1_P1_RX_BUF_DP<13>")
	)
	(segment
		(start 89.377266 -414.55467)
		(end 87.900002 -416.031934)
		(width 0.14224)
		(layer "In13.Cu")
		(net "P5E_CPU1_P1_RX_BUF_DP<13>")
	)
	(segment
		(start 95.473774 -394.38072)
		(end 95.209868 -395.708378)
		(width 0.14224)
		(layer "In13.Cu")
		(net "P5E_CPU1_P1_RX_BUF_DP<13>")
	)
	(segment
		(start 92.434664 -405.560276)
		(end 92.119196 -405.771096)
		(width 0.14224)
		(layer "In13.Cu")
		(net "P5E_CPU1_P1_RX_BUF_DP<13>")
	)
	(segment
		(start 85.923628 -418.008308)
		(end 85.258402 -418.673534)
		(width 0.14224)
		(layer "In13.Cu")
		(net "P5E_CPU1_P1_RX_BUF_DP<13>")
	)
	(segment
		(start 91.389454 -408.984704)
		(end 91.389454 -409.411424)
		(width 0.14224)
		(layer "In13.Cu")
		(net "P5E_CPU1_P1_RX_BUF_DP<13>")
	)
	(segment
		(start 94.210124 -398.950434)
		(end 94.06636 -399.352516)
		(width 0.14224)
		(layer "In13.Cu")
		(net "P5E_CPU1_P1_RX_BUF_DP<13>")
	)
	(segment
		(start 85.528912 -434.739796)
		(end 85.65007 -434.618638)
		(width 0.14224)
		(layer "In13.Cu")
		(net "P5E_CPU1_P1_RX_BUF_DP<13>")
	)
	(segment
		(start 84.971128 -419.366954)
		(end 84.971128 -426.873162)
		(width 0.14224)
		(layer "In13.Cu")
		(net "P5E_CPU1_P1_RX_BUF_DP<13>")
	)
	(segment
		(start 85.65007 -434.618638)
		(end 85.65007 -434.289962)
		(width 0.14224)
		(layer "In13.Cu")
		(net "P5E_CPU1_P1_RX_BUF_DP<13>")
	)
	(segment
		(start 85.258148 -434.739796)
		(end 85.528912 -434.739796)
		(width 0.14224)
		(layer "In13.Cu")
		(net "P5E_CPU1_P1_RX_BUF_DP<13>")
	)
	(segment
		(start 91.389454 -408.283664)
		(end 91.252294 -408.420824)
		(width 0.14224)
		(layer "In13.Cu")
		(net "P5E_CPU1_P1_RX_BUF_DP<13>")
	)
	(segment
		(start 95.16872 -395.86408)
		(end 95.167196 -395.868652)
		(width 0.14224)
		(layer "In13.Cu")
		(net "P5E_CPU1_P1_RX_BUF_DP<13>")
	)
	(segment
		(start 91.252294 -408.847544)
		(end 91.389454 -408.984704)
		(width 0.14224)
		(layer "In13.Cu")
		(net "P5E_CPU1_P1_RX_BUF_DP<13>")
	)
	(segment
		(start 91.389454 -407.856944)
		(end 91.389454 -408.283664)
		(width 0.14224)
		(layer "In13.Cu")
		(net "P5E_CPU1_P1_RX_BUF_DP<13>")
	)
	(segment
		(start 87.900002 -416.031934)
		(end 87.900002 -416.22599)
		(width 0.14224)
		(layer "In13.Cu")
		(net "P5E_CPU1_P1_RX_BUF_DP<13>")
	)
	(segment
		(start 86.117684 -418.008308)
		(end 85.923628 -418.008308)
		(width 0.14224)
		(layer "In13.Cu")
		(net "P5E_CPU1_P1_RX_BUF_DP<13>")
	)
	(segment
		(start 87.626698 -416.499294)
		(end 87.432642 -416.499294)
		(width 0.14224)
		(layer "In13.Cu")
		(net "P5E_CPU1_P1_RX_BUF_DP<13>")
	)
	(segment
		(start 95.944182 -393.292838)
		(end 95.944182 -393.144756)
		(width 0.14224)
		(layer "In13.Cu")
		(net "P5E_CPU1_P1_RX_BUF_DP<13>")
	)
	(segment
		(start 95.817182 -393.017756)
		(end 95.627444 -393.017756)
		(width 0.14224)
		(layer "In13.Cu")
		(net "P5E_CPU1_P1_RX_BUF_DP<13>")
	)
	(segment
		(start 87.432642 -416.499294)
		(end 87.159846 -416.77209)
		(width 0.14224)
		(layer "In13.Cu")
		(net "P5E_CPU1_P1_RX_BUF_DP<13>")
	)
	(segment
		(start 86.886542 -417.23945)
		(end 86.692486 -417.23945)
		(width 0.14224)
		(layer "In13.Cu")
		(net "P5E_CPU1_P1_RX_BUF_DP<13>")
	)
	(segment
		(start 92.783914 -403.97557)
		(end 92.783914 -404.924514)
		(width 0.14224)
		(layer "In13.Cu")
		(net "P5E_CPU1_P1_RX_BUF_DP<13>")
	)
	(segment
		(start 93.890846 -399.435574)
		(end 93.747082 -399.837148)
		(width 0.14224)
		(layer "In13.Cu")
		(net "P5E_CPU1_P1_RX_BUF_DP<13>")
	)
	(segment
		(start 93.510862 -400.497548)
		(end 93.367098 -400.899122)
		(width 0.14224)
		(layer "In13.Cu")
		(net "P5E_CPU1_P1_RX_BUF_DP<13>")
	)
	(segment
		(start 95.944182 -393.144756)
		(end 95.817182 -393.017756)
		(width 0.14224)
		(layer "In13.Cu")
		(net "P5E_CPU1_P1_RX_BUF_DP<13>")
	)
	(segment
		(start 89.720674 -411.846268)
		(end 89.720674 -413.725614)
		(width 0.14224)
		(layer "In13.Cu")
		(net "P5E_CPU1_P1_RX_BUF_DP<13>")
	)
	(segment
		(start 95.627444 -393.017756)
		(end 95.485204 -393.159996)
		(width 0.14224)
		(layer "In13.Cu")
		(net "P5E_CPU1_P1_RX_BUF_DP<13>")
	)
	(segment
		(start 93.069918 -402.345652)
		(end 93.177614 -402.506942)
		(width 0.14224)
		(layer "In13.Cu")
		(net "P5E_CPU1_P1_RX_BUF_DP<13>")
	)
	(segment
		(start 87.159846 -416.77209)
		(end 87.159846 -416.966146)
		(width 0.14224)
		(layer "In13.Cu")
		(net "P5E_CPU1_P1_RX_BUF_DP<13>")
	)
	(segment
		(start 94.826328 -397.228568)
		(end 94.650814 -397.311626)
		(width 0.14224)
		(layer "In13.Cu")
		(net "P5E_CPU1_P1_RX_BUF_DP<13>")
	)
	(segment
		(start 94.27083 -398.3736)
		(end 94.127066 -398.775174)
		(width 0.14224)
		(layer "In13.Cu")
		(net "P5E_CPU1_P1_RX_BUF_DP<13>")
	)
	(segment
		(start 91.128596 -411.006798)
		(end 90.96121 -411.18282)
		(width 0.14224)
		(layer "In13.Cu")
		(net "P5E_CPU1_P1_RX_BUF_DP<13>")
	)
	(segment
		(start 84.976462 -434.45811)
		(end 85.258148 -434.739796)
		(width 0.14224)
		(layer "In13.Cu")
		(net "P5E_CPU1_P1_RX_BUF_DP<13>")
	)
	(segment
		(start 84.971128 -426.873162)
		(end 84.976462 -426.878496)
		(width 0.14224)
		(layer "In13.Cu")
		(net "P5E_CPU1_P1_RX_BUF_DP<13>")
	)
	(segment
		(start 94.887796 -396.649702)
		(end 94.887288 -396.651226)
		(width 0.14224)
		(layer "In13.Cu")
		(net "P5E_CPU1_P1_RX_BUF_DP<13>")
	)
	(segment
		(start 91.389454 -409.411424)
		(end 91.252294 -409.548584)
		(width 0.14224)
		(layer "In13.Cu")
		(net "P5E_CPU1_P1_RX_BUF_DP<13>")
	)
	(segment
		(start 86.41969 -417.512246)
		(end 86.41969 -417.706302)
		(width 0.14224)
		(layer "In13.Cu")
		(net "P5E_CPU1_P1_RX_BUF_DP<13>")
	)
	(segment
		(start 91.252294 -407.719784)
		(end 91.389454 -407.856944)
		(width 0.14224)
		(layer "In13.Cu")
		(net "P5E_CPU1_P1_RX_BUF_DP<13>")
	)
	(segment
		(start 94.970092 -396.82674)
		(end 94.826328 -397.228568)
		(width 0.14224)
		(layer "In13.Cu")
		(net "P5E_CPU1_P1_RX_BUF_DP<13>")
	)
	(arc
		(start 90.96121 -411.18282)
		(mid 90.868192 -411.261897)
		(end 90.760804 -411.31998)
		(width 0.14224)
		(layer "In13.Cu")
		(net "P5E_CPU1_P1_RX_BUF_DP<13>")
	)
	(arc
		(start 91.843606 -405.885142)
		(mid 91.637724 -405.995288)
		(end 91.457272 -406.14346)
		(width 0.14224)
		(layer "In13.Cu")
		(net "P5E_CPU1_P1_RX_BUF_DP<13>")
	)
	(arc
		(start 85.258402 -418.673534)
		(mid 85.045771 -418.991664)
		(end 84.971128 -419.366954)
		(width 0.14224)
		(layer "In13.Cu")
		(net "P5E_CPU1_P1_RX_BUF_DP<13>")
	)
	(arc
		(start 95.209868 -395.708378)
		(mid 95.191727 -395.786872)
		(end 95.16872 -395.86408)
		(width 0.14224)
		(layer "In13.Cu")
		(net "P5E_CPU1_P1_RX_BUF_DP<13>")
	)
	(arc
		(start 89.808304 -411.71495)
		(mid 89.744499 -411.767294)
		(end 89.720674 -411.846268)
		(width 0.14224)
		(layer "In13.Cu")
		(net "P5E_CPU1_P1_RX_BUF_DP<13>")
	)
	(arc
		(start 95.485204 -394.26261)
		(mid 95.482386 -394.321945)
		(end 95.473774 -394.38072)
		(width 0.14224)
		(layer "In13.Cu")
		(net "P5E_CPU1_P1_RX_BUF_DP<13>")
	)
	(arc
		(start 91.457272 -406.14346)
		(mid 91.305509 -406.370445)
		(end 91.252294 -406.638252)
		(width 0.14224)
		(layer "In13.Cu")
		(net "P5E_CPU1_P1_RX_BUF_DP<13>")
	)
	(arc
		(start 92.821506 -403.594316)
		(mid 92.793344 -403.784019)
		(end 92.783914 -403.97557)
		(width 0.14224)
		(layer "In13.Cu")
		(net "P5E_CPU1_P1_RX_BUF_DP<13>")
	)
	(arc
		(start 92.783914 -404.924514)
		(mid 92.7313 -405.189111)
		(end 92.581476 -405.413464)
		(width 0.14224)
		(layer "In13.Cu")
		(net "P5E_CPU1_P1_RX_BUF_DP<13>")
	)
	(arc
		(start 89.720674 -413.725614)
		(mid 89.631425 -414.174297)
		(end 89.377266 -414.55467)
		(width 0.14224)
		(layer "In13.Cu")
		(net "P5E_CPU1_P1_RX_BUF_DP<13>")
	)
	(arc
		(start 93.367098 -400.899122)
		(mid 93.347965 -400.959461)
		(end 93.333316 -401.021042)
		(width 0.14224)
		(layer "In13.Cu")
		(net "P5E_CPU1_P1_RX_BUF_DP<13>")
	)
	(arc
		(start 91.252294 -410.697172)
		(mid 91.220329 -410.86393)
		(end 91.128596 -411.006798)
		(width 0.14224)
		(layer "In13.Cu")
		(net "P5E_CPU1_P1_RX_BUF_DP<13>")
	)
	(segment
		(start 94.744286 -393.119102)
		(end 94.744286 -393.292838)
		(width 0.1016)
		(layer "F.Cu")
		(net "P5E_CPU1_P1_RX_BUF_DP<12>")
	)
	(segment
		(start 94.130368 -391.36574)
		(end 94.130368 -391.488676)
		(width 0.1016)
		(layer "F.Cu")
		(net "P5E_CPU1_P1_RX_BUF_DP<12>")
	)
	(segment
		(start 94.041722 -391.577322)
		(end 94.041722 -392.723878)
		(width 0.1016)
		(layer "F.Cu")
		(net "P5E_CPU1_P1_RX_BUF_DP<12>")
	)
	(segment
		(start 94.29496 -392.977116)
		(end 94.6023 -392.977116)
		(width 0.1016)
		(layer "F.Cu")
		(net "P5E_CPU1_P1_RX_BUF_DP<12>")
	)
	(segment
		(start 94.130368 -391.488676)
		(end 94.041722 -391.577322)
		(width 0.1016)
		(layer "F.Cu")
		(net "P5E_CPU1_P1_RX_BUF_DP<12>")
	)
	(segment
		(start 94.041722 -392.723878)
		(end 94.29496 -392.977116)
		(width 0.1016)
		(layer "F.Cu")
		(net "P5E_CPU1_P1_RX_BUF_DP<12>")
	)
	(segment
		(start 94.045786 -391.281158)
		(end 94.130368 -391.36574)
		(width 0.1016)
		(layer "F.Cu")
		(net "P5E_CPU1_P1_RX_BUF_DP<12>")
	)
	(segment
		(start 94.6023 -392.977116)
		(end 94.744286 -393.119102)
		(width 0.1016)
		(layer "F.Cu")
		(net "P5E_CPU1_P1_RX_BUF_DP<12>")
	)
	(segment
		(start 89.720674 -404.924514)
		(end 89.720674 -404.019258)
		(width 0.14224)
		(layer "In13.Cu")
		(net "P5E_CPU1_P1_RX_BUF_DP<12>")
	)
	(segment
		(start 82.976466 -426.878496)
		(end 82.971132 -426.873162)
		(width 0.14224)
		(layer "In13.Cu")
		(net "P5E_CPU1_P1_RX_BUF_DP<12>")
	)
	(segment
		(start 93.782896 -396.444724)
		(end 94.165928 -395.519656)
		(width 0.14224)
		(layer "In13.Cu")
		(net "P5E_CPU1_P1_RX_BUF_DP<12>")
	)
	(segment
		(start 90.414602 -402.33981)
		(end 90.793316 -401.708112)
		(width 0.14224)
		(layer "In13.Cu")
		(net "P5E_CPU1_P1_RX_BUF_DP<12>")
	)
	(segment
		(start 93.166692 -397.626332)
		(end 93.664024 -396.69466)
		(width 0.14224)
		(layer "In13.Cu")
		(net "P5E_CPU1_P1_RX_BUF_DP<12>")
	)
	(segment
		(start 83.108292 -419.258242)
		(end 83.108292 -418.872162)
		(width 0.14224)
		(layer "In13.Cu")
		(net "P5E_CPU1_P1_RX_BUF_DP<12>")
	)
	(segment
		(start 89.72931 -403.89302)
		(end 89.793064 -403.425914)
		(width 0.14224)
		(layer "In13.Cu")
		(net "P5E_CPU1_P1_RX_BUF_DP<12>")
	)
	(segment
		(start 88.326214 -409.502864)
		(end 88.326214 -409.076144)
		(width 0.14224)
		(layer "In13.Cu")
		(net "P5E_CPU1_P1_RX_BUF_DP<12>")
	)
	(segment
		(start 88.780366 -405.885142)
		(end 89.055956 -405.771096)
		(width 0.14224)
		(layer "In13.Cu")
		(net "P5E_CPU1_P1_RX_BUF_DP<12>")
	)
	(segment
		(start 88.326214 -409.076144)
		(end 88.189054 -408.938984)
		(width 0.14224)
		(layer "In13.Cu")
		(net "P5E_CPU1_P1_RX_BUF_DP<12>")
	)
	(segment
		(start 83.650074 -433.61864)
		(end 83.503262 -433.765452)
		(width 0.14224)
		(layer "In13.Cu")
		(net "P5E_CPU1_P1_RX_BUF_DP<12>")
	)
	(segment
		(start 91.781122 -400.327114)
		(end 91.733878 -400.1389)
		(width 0.14224)
		(layer "In13.Cu")
		(net "P5E_CPU1_P1_RX_BUF_DP<12>")
	)
	(segment
		(start 90.053922 -402.941536)
		(end 90.24239 -402.894292)
		(width 0.14224)
		(layer "In13.Cu")
		(net "P5E_CPU1_P1_RX_BUF_DP<12>")
	)
	(segment
		(start 83.108292 -420.386002)
		(end 83.108292 -419.959282)
		(width 0.14224)
		(layer "In13.Cu")
		(net "P5E_CPU1_P1_RX_BUF_DP<12>")
	)
	(segment
		(start 90.461846 -402.528024)
		(end 90.414602 -402.33981)
		(width 0.14224)
		(layer "In13.Cu")
		(net "P5E_CPU1_P1_RX_BUF_DP<12>")
	)
	(segment
		(start 94.744286 -393.144756)
		(end 94.744286 -393.292838)
		(width 0.14224)
		(layer "In13.Cu")
		(net "P5E_CPU1_P1_RX_BUF_DP<12>")
	)
	(segment
		(start 84.832698 -415.935414)
		(end 85.134196 -415.633916)
		(width 0.14224)
		(layer "In13.Cu")
		(net "P5E_CPU1_P1_RX_BUF_DP<12>")
	)
	(segment
		(start 83.650074 -433.289964)
		(end 83.650074 -433.61864)
		(width 0.14224)
		(layer "In13.Cu")
		(net "P5E_CPU1_P1_RX_BUF_DP<12>")
	)
	(segment
		(start 88.189054 -408.512264)
		(end 88.326214 -408.375104)
		(width 0.14224)
		(layer "In13.Cu")
		(net "P5E_CPU1_P1_RX_BUF_DP<12>")
	)
	(segment
		(start 84.035138 -416.92703)
		(end 84.035138 -416.732974)
		(width 0.14224)
		(layer "In13.Cu")
		(net "P5E_CPU1_P1_RX_BUF_DP<12>")
	)
	(segment
		(start 82.971132 -419.395402)
		(end 83.108292 -419.258242)
		(width 0.14224)
		(layer "In13.Cu")
		(net "P5E_CPU1_P1_RX_BUF_DP<12>")
	)
	(segment
		(start 86.657434 -413.606234)
		(end 86.657434 -411.846014)
		(width 0.14224)
		(layer "In13.Cu")
		(net "P5E_CPU1_P1_RX_BUF_DP<12>")
	)
	(segment
		(start 88.326214 -407.948384)
		(end 88.189054 -407.811224)
		(width 0.14224)
		(layer "In13.Cu")
		(net "P5E_CPU1_P1_RX_BUF_DP<12>")
	)
	(segment
		(start 82.971132 -426.873162)
		(end 82.971132 -420.523162)
		(width 0.14224)
		(layer "In13.Cu")
		(net "P5E_CPU1_P1_RX_BUF_DP<12>")
	)
	(segment
		(start 83.733132 -417.229036)
		(end 84.035138 -416.92703)
		(width 0.14224)
		(layer "In13.Cu")
		(net "P5E_CPU1_P1_RX_BUF_DP<12>")
	)
	(segment
		(start 91.200986 -401.2946)
		(end 91.153996 -401.106386)
		(width 0.14224)
		(layer "In13.Cu")
		(net "P5E_CPU1_P1_RX_BUF_DP<12>")
	)
	(segment
		(start 83.108292 -418.872162)
		(end 82.971132 -418.735002)
		(width 0.14224)
		(layer "In13.Cu")
		(net "P5E_CPU1_P1_RX_BUF_DP<12>")
	)
	(segment
		(start 88.189054 -410.697172)
		(end 88.189054 -409.640024)
		(width 0.14224)
		(layer "In13.Cu")
		(net "P5E_CPU1_P1_RX_BUF_DP<12>")
	)
	(segment
		(start 93.22308 -397.811752)
		(end 93.166692 -397.626332)
		(width 0.14224)
		(layer "In13.Cu")
		(net "P5E_CPU1_P1_RX_BUF_DP<12>")
	)
	(segment
		(start 92.798646 -398.314926)
		(end 92.836238 -398.244822)
		(width 0.14224)
		(layer "In13.Cu")
		(net "P5E_CPU1_P1_RX_BUF_DP<12>")
	)
	(segment
		(start 89.055956 -405.771096)
		(end 89.371424 -405.560276)
		(width 0.14224)
		(layer "In13.Cu")
		(net "P5E_CPU1_P1_RX_BUF_DP<12>")
	)
	(segment
		(start 83.237578 -417.530534)
		(end 83.539076 -417.229036)
		(width 0.14224)
		(layer "In13.Cu")
		(net "P5E_CPU1_P1_RX_BUF_DP<12>")
	)
	(segment
		(start 83.539076 -417.229036)
		(end 83.733132 -417.229036)
		(width 0.14224)
		(layer "In13.Cu")
		(net "P5E_CPU1_P1_RX_BUF_DP<12>")
	)
	(segment
		(start 91.153996 -401.106386)
		(end 91.373198 -400.740626)
		(width 0.14224)
		(layer "In13.Cu")
		(net "P5E_CPU1_P1_RX_BUF_DP<12>")
	)
	(segment
		(start 88.189054 -407.811224)
		(end 88.189054 -406.638252)
		(width 0.14224)
		(layer "In13.Cu")
		(net "P5E_CPU1_P1_RX_BUF_DP<12>")
	)
	(segment
		(start 90.981784 -401.660868)
		(end 91.200986 -401.2946)
		(width 0.14224)
		(layer "In13.Cu")
		(net "P5E_CPU1_P1_RX_BUF_DP<12>")
	)
	(segment
		(start 91.561666 -400.693382)
		(end 91.781122 -400.327114)
		(width 0.14224)
		(layer "In13.Cu")
		(net "P5E_CPU1_P1_RX_BUF_DP<12>")
	)
	(segment
		(start 84.035138 -416.732974)
		(end 84.336636 -416.431476)
		(width 0.14224)
		(layer "In13.Cu")
		(net "P5E_CPU1_P1_RX_BUF_DP<12>")
	)
	(segment
		(start 88.189054 -409.640024)
		(end 88.326214 -409.502864)
		(width 0.14224)
		(layer "In13.Cu")
		(net "P5E_CPU1_P1_RX_BUF_DP<12>")
	)
	(segment
		(start 85.630258 -415.137854)
		(end 86.300564 -414.467548)
		(width 0.14224)
		(layer "In13.Cu")
		(net "P5E_CPU1_P1_RX_BUF_DP<12>")
	)
	(segment
		(start 83.503262 -433.765452)
		(end 83.283806 -433.765452)
		(width 0.14224)
		(layer "In13.Cu")
		(net "P5E_CPU1_P1_RX_BUF_DP<12>")
	)
	(segment
		(start 93.021912 -398.188434)
		(end 93.22308 -397.811752)
		(width 0.14224)
		(layer "In13.Cu")
		(net "P5E_CPU1_P1_RX_BUF_DP<12>")
	)
	(segment
		(start 94.617286 -393.017756)
		(end 94.744286 -393.144756)
		(width 0.14224)
		(layer "In13.Cu")
		(net "P5E_CPU1_P1_RX_BUF_DP<12>")
	)
	(segment
		(start 88.189054 -408.938984)
		(end 88.189054 -408.512264)
		(width 0.14224)
		(layer "In13.Cu")
		(net "P5E_CPU1_P1_RX_BUF_DP<12>")
	)
	(segment
		(start 90.24239 -402.894292)
		(end 90.461846 -402.528024)
		(width 0.14224)
		(layer "In13.Cu")
		(net "P5E_CPU1_P1_RX_BUF_DP<12>")
	)
	(segment
		(start 89.371424 -405.560276)
		(end 89.518236 -405.413464)
		(width 0.14224)
		(layer "In13.Cu")
		(net "P5E_CPU1_P1_RX_BUF_DP<12>")
	)
	(segment
		(start 83.283806 -433.765452)
		(end 82.976466 -433.458112)
		(width 0.14224)
		(layer "In13.Cu")
		(net "P5E_CPU1_P1_RX_BUF_DP<12>")
	)
	(segment
		(start 84.832698 -416.12947)
		(end 84.832698 -415.935414)
		(width 0.14224)
		(layer "In13.Cu")
		(net "P5E_CPU1_P1_RX_BUF_DP<12>")
	)
	(segment
		(start 83.108292 -419.959282)
		(end 82.971132 -419.822122)
		(width 0.14224)
		(layer "In13.Cu")
		(net "P5E_CPU1_P1_RX_BUF_DP<12>")
	)
	(segment
		(start 90.793316 -401.708112)
		(end 90.981784 -401.660868)
		(width 0.14224)
		(layer "In13.Cu")
		(net "P5E_CPU1_P1_RX_BUF_DP<12>")
	)
	(segment
		(start 94.285308 -393.159996)
		(end 94.427548 -393.017756)
		(width 0.14224)
		(layer "In13.Cu")
		(net "P5E_CPU1_P1_RX_BUF_DP<12>")
	)
	(segment
		(start 82.971132 -418.735002)
		(end 82.971132 -418.173916)
		(width 0.14224)
		(layer "In13.Cu")
		(net "P5E_CPU1_P1_RX_BUF_DP<12>")
	)
	(segment
		(start 86.745064 -411.71495)
		(end 87.696802 -411.320742)
		(width 0.14224)
		(layer "In13.Cu")
		(net "P5E_CPU1_P1_RX_BUF_DP<12>")
	)
	(segment
		(start 82.971132 -419.822122)
		(end 82.971132 -419.395402)
		(width 0.14224)
		(layer "In13.Cu")
		(net "P5E_CPU1_P1_RX_BUF_DP<12>")
	)
	(segment
		(start 85.328252 -415.633916)
		(end 85.630258 -415.33191)
		(width 0.14224)
		(layer "In13.Cu")
		(net "P5E_CPU1_P1_RX_BUF_DP<12>")
	)
	(segment
		(start 94.285308 -394.9192)
		(end 94.285308 -393.159996)
		(width 0.14224)
		(layer "In13.Cu")
		(net "P5E_CPU1_P1_RX_BUF_DP<12>")
	)
	(segment
		(start 84.530692 -416.431476)
		(end 84.832698 -416.12947)
		(width 0.14224)
		(layer "In13.Cu")
		(net "P5E_CPU1_P1_RX_BUF_DP<12>")
	)
	(segment
		(start 85.134196 -415.633916)
		(end 85.328252 -415.633916)
		(width 0.14224)
		(layer "In13.Cu")
		(net "P5E_CPU1_P1_RX_BUF_DP<12>")
	)
	(segment
		(start 88.326214 -408.375104)
		(end 88.326214 -407.948384)
		(width 0.14224)
		(layer "In13.Cu")
		(net "P5E_CPU1_P1_RX_BUF_DP<12>")
	)
	(segment
		(start 85.630258 -415.33191)
		(end 85.630258 -415.137854)
		(width 0.14224)
		(layer "In13.Cu")
		(net "P5E_CPU1_P1_RX_BUF_DP<12>")
	)
	(segment
		(start 91.733878 -400.1389)
		(end 92.301822 -399.191226)
		(width 0.14224)
		(layer "In13.Cu")
		(net "P5E_CPU1_P1_RX_BUF_DP<12>")
	)
	(segment
		(start 84.336636 -416.431476)
		(end 84.530692 -416.431476)
		(width 0.14224)
		(layer "In13.Cu")
		(net "P5E_CPU1_P1_RX_BUF_DP<12>")
	)
	(segment
		(start 82.971132 -420.523162)
		(end 83.108292 -420.386002)
		(width 0.14224)
		(layer "In13.Cu")
		(net "P5E_CPU1_P1_RX_BUF_DP<12>")
	)
	(segment
		(start 82.976466 -433.458112)
		(end 82.976466 -426.878496)
		(width 0.14224)
		(layer "In13.Cu")
		(net "P5E_CPU1_P1_RX_BUF_DP<12>")
	)
	(segment
		(start 87.89797 -411.18282)
		(end 88.065356 -411.006798)
		(width 0.14224)
		(layer "In13.Cu")
		(net "P5E_CPU1_P1_RX_BUF_DP<12>")
	)
	(segment
		(start 91.373198 -400.740626)
		(end 91.561666 -400.693382)
		(width 0.14224)
		(layer "In13.Cu")
		(net "P5E_CPU1_P1_RX_BUF_DP<12>")
	)
	(segment
		(start 89.83472 -403.307296)
		(end 90.053922 -402.941536)
		(width 0.14224)
		(layer "In13.Cu")
		(net "P5E_CPU1_P1_RX_BUF_DP<12>")
	)
	(segment
		(start 94.427548 -393.017756)
		(end 94.617286 -393.017756)
		(width 0.14224)
		(layer "In13.Cu")
		(net "P5E_CPU1_P1_RX_BUF_DP<12>")
	)
	(segment
		(start 92.836238 -398.244822)
		(end 93.021912 -398.188434)
		(width 0.14224)
		(layer "In13.Cu")
		(net "P5E_CPU1_P1_RX_BUF_DP<12>")
	)
	(arc
		(start 88.065356 -411.006798)
		(mid 88.157032 -410.863907)
		(end 88.189054 -410.697172)
		(width 0.14224)
		(layer "In13.Cu")
		(net "P5E_CPU1_P1_RX_BUF_DP<12>")
	)
	(arc
		(start 88.189054 -406.638252)
		(mid 88.242283 -406.370451)
		(end 88.394032 -406.14346)
		(width 0.14224)
		(layer "In13.Cu")
		(net "P5E_CPU1_P1_RX_BUF_DP<12>")
	)
	(arc
		(start 86.300564 -414.467548)
		(mid 86.564665 -414.072388)
		(end 86.657434 -413.606234)
		(width 0.14224)
		(layer "In13.Cu")
		(net "P5E_CPU1_P1_RX_BUF_DP<12>")
	)
	(arc
		(start 93.664024 -396.69466)
		(mid 93.726676 -396.571221)
		(end 93.782896 -396.444724)
		(width 0.14224)
		(layer "In13.Cu")
		(net "P5E_CPU1_P1_RX_BUF_DP<12>")
	)
	(arc
		(start 86.657434 -411.846014)
		(mid 86.681346 -411.767157)
		(end 86.745064 -411.71495)
		(width 0.14224)
		(layer "In13.Cu")
		(net "P5E_CPU1_P1_RX_BUF_DP<12>")
	)
	(arc
		(start 94.165928 -395.519656)
		(mid 94.255177 -395.225305)
		(end 94.285308 -394.9192)
		(width 0.14224)
		(layer "In13.Cu")
		(net "P5E_CPU1_P1_RX_BUF_DP<12>")
	)
	(arc
		(start 89.518236 -405.413464)
		(mid 89.668076 -405.189118)
		(end 89.720674 -404.924514)
		(width 0.14224)
		(layer "In13.Cu")
		(net "P5E_CPU1_P1_RX_BUF_DP<12>")
	)
	(arc
		(start 82.971132 -418.173916)
		(mid 83.040374 -417.825726)
		(end 83.237578 -417.530534)
		(width 0.14224)
		(layer "In13.Cu")
		(net "P5E_CPU1_P1_RX_BUF_DP<12>")
	)
	(arc
		(start 92.301822 -399.191226)
		(mid 92.555616 -398.756127)
		(end 92.798646 -398.314926)
		(width 0.14224)
		(layer "In13.Cu")
		(net "P5E_CPU1_P1_RX_BUF_DP<12>")
	)
	(arc
		(start 89.793064 -403.425914)
		(mid 89.807888 -403.364497)
		(end 89.83472 -403.307296)
		(width 0.14224)
		(layer "In13.Cu")
		(net "P5E_CPU1_P1_RX_BUF_DP<12>")
	)
	(arc
		(start 87.696802 -411.320742)
		(mid 87.804615 -411.262325)
		(end 87.89797 -411.18282)
		(width 0.14224)
		(layer "In13.Cu")
		(net "P5E_CPU1_P1_RX_BUF_DP<12>")
	)
	(arc
		(start 88.394032 -406.14346)
		(mid 88.574502 -405.995314)
		(end 88.780366 -405.885142)
		(width 0.14224)
		(layer "In13.Cu")
		(net "P5E_CPU1_P1_RX_BUF_DP<12>")
	)
	(arc
		(start 89.720674 -404.019258)
		(mid 89.722857 -403.955993)
		(end 89.72931 -403.89302)
		(width 0.14224)
		(layer "In13.Cu")
		(net "P5E_CPU1_P1_RX_BUF_DP<12>")
	)
	(segment
		(start 93.405452 -392.977116)
		(end 93.54439 -393.116054)
		(width 0.1016)
		(layer "F.Cu")
		(net "P5E_CPU1_P1_RX_BUF_DP<11>")
	)
	(segment
		(start 92.930218 -391.488676)
		(end 92.841572 -391.577322)
		(width 0.1016)
		(layer "F.Cu")
		(net "P5E_CPU1_P1_RX_BUF_DP<11>")
	)
	(segment
		(start 93.09481 -392.977116)
		(end 93.405452 -392.977116)
		(width 0.1016)
		(layer "F.Cu")
		(net "P5E_CPU1_P1_RX_BUF_DP<11>")
	)
	(segment
		(start 92.845636 -391.281158)
		(end 92.930218 -391.36574)
		(width 0.1016)
		(layer "F.Cu")
		(net "P5E_CPU1_P1_RX_BUF_DP<11>")
	)
	(segment
		(start 92.841572 -392.723878)
		(end 93.09481 -392.977116)
		(width 0.1016)
		(layer "F.Cu")
		(net "P5E_CPU1_P1_RX_BUF_DP<11>")
	)
	(segment
		(start 92.930218 -391.36574)
		(end 92.930218 -391.488676)
		(width 0.1016)
		(layer "F.Cu")
		(net "P5E_CPU1_P1_RX_BUF_DP<11>")
	)
	(segment
		(start 93.54439 -393.116054)
		(end 93.54439 -393.292838)
		(width 0.1016)
		(layer "F.Cu")
		(net "P5E_CPU1_P1_RX_BUF_DP<11>")
	)
	(segment
		(start 92.841572 -391.577322)
		(end 92.841572 -392.723878)
		(width 0.1016)
		(layer "F.Cu")
		(net "P5E_CPU1_P1_RX_BUF_DP<11>")
	)
	(segment
		(start 85.125814 -408.259534)
		(end 85.262974 -408.122374)
		(width 0.14224)
		(layer "In13.Cu")
		(net "P5E_CPU1_P1_RX_BUF_DP<11>")
	)
	(segment
		(start 93.085412 -393.159996)
		(end 93.227652 -393.017756)
		(width 0.14224)
		(layer "In13.Cu")
		(net "P5E_CPU1_P1_RX_BUF_DP<11>")
	)
	(segment
		(start 86.657434 -404.924514)
		(end 86.657434 -404.087076)
		(width 0.14224)
		(layer "In13.Cu")
		(net "P5E_CPU1_P1_RX_BUF_DP<11>")
	)
	(segment
		(start 88.10879 -402.295868)
		(end 88.39581 -401.979384)
		(width 0.14224)
		(layer "In13.Cu")
		(net "P5E_CPU1_P1_RX_BUF_DP<11>")
	)
	(segment
		(start 85.262974 -409.250134)
		(end 85.262974 -408.823414)
		(width 0.14224)
		(layer "In13.Cu")
		(net "P5E_CPU1_P1_RX_BUF_DP<11>")
	)
	(segment
		(start 83.776566 -411.675834)
		(end 84.668106 -411.30601)
		(width 0.14224)
		(layer "In13.Cu")
		(net "P5E_CPU1_P1_RX_BUF_DP<11>")
	)
	(segment
		(start 80.971136 -419.296088)
		(end 80.971136 -418.910008)
		(width 0.14224)
		(layer "In13.Cu")
		(net "P5E_CPU1_P1_RX_BUF_DP<11>")
	)
	(segment
		(start 87.915242 -402.30552)
		(end 88.10879 -402.295868)
		(width 0.14224)
		(layer "In13.Cu")
		(net "P5E_CPU1_P1_RX_BUF_DP<11>")
	)
	(segment
		(start 86.668864 -403.961092)
		(end 86.706202 -403.758654)
		(width 0.14224)
		(layer "In13.Cu")
		(net "P5E_CPU1_P1_RX_BUF_DP<11>")
	)
	(segment
		(start 80.97647 -434.45811)
		(end 80.97647 -426.878496)
		(width 0.14224)
		(layer "In13.Cu")
		(net "P5E_CPU1_P1_RX_BUF_DP<11>")
	)
	(segment
		(start 81.265776 -434.747416)
		(end 80.97647 -434.45811)
		(width 0.14224)
		(layer "In13.Cu")
		(net "P5E_CPU1_P1_RX_BUF_DP<11>")
	)
	(segment
		(start 86.859364 -403.470364)
		(end 87.157814 -403.14118)
		(width 0.14224)
		(layer "In13.Cu")
		(net "P5E_CPU1_P1_RX_BUF_DP<11>")
	)
	(segment
		(start 80.971136 -426.873162)
		(end 80.971136 -419.956488)
		(width 0.14224)
		(layer "In13.Cu")
		(net "P5E_CPU1_P1_RX_BUF_DP<11>")
	)
	(segment
		(start 81.650078 -434.618638)
		(end 81.5213 -434.747416)
		(width 0.14224)
		(layer "In13.Cu")
		(net "P5E_CPU1_P1_RX_BUF_DP<11>")
	)
	(segment
		(start 81.5213 -434.747416)
		(end 81.265776 -434.747416)
		(width 0.14224)
		(layer "In13.Cu")
		(net "P5E_CPU1_P1_RX_BUF_DP<11>")
	)
	(segment
		(start 89.623646 -400.624548)
		(end 89.910666 -400.308064)
		(width 0.14224)
		(layer "In13.Cu")
		(net "P5E_CPU1_P1_RX_BUF_DP<11>")
	)
	(segment
		(start 82.524346 -416.014662)
		(end 82.826352 -415.712656)
		(width 0.14224)
		(layer "In13.Cu")
		(net "P5E_CPU1_P1_RX_BUF_DP<11>")
	)
	(segment
		(start 87.157814 -403.14118)
		(end 87.351616 -403.131528)
		(width 0.14224)
		(layer "In13.Cu")
		(net "P5E_CPU1_P1_RX_BUF_DP<11>")
	)
	(segment
		(start 81.108296 -419.819328)
		(end 81.108296 -419.433248)
		(width 0.14224)
		(layer "In13.Cu")
		(net "P5E_CPU1_P1_RX_BUF_DP<11>")
	)
	(segment
		(start 85.262974 -408.122374)
		(end 85.262974 -407.695654)
		(width 0.14224)
		(layer "In13.Cu")
		(net "P5E_CPU1_P1_RX_BUF_DP<11>")
	)
	(segment
		(start 92.814902 -396.116302)
		(end 93.053916 -395.32814)
		(width 0.14224)
		(layer "In13.Cu")
		(net "P5E_CPU1_P1_RX_BUF_DP<11>")
	)
	(segment
		(start 81.108296 -418.386768)
		(end 80.971136 -418.249608)
		(width 0.14224)
		(layer "In13.Cu")
		(net "P5E_CPU1_P1_RX_BUF_DP<11>")
	)
	(segment
		(start 89.153238 -401.143724)
		(end 89.143586 -400.950176)
		(width 0.14224)
		(layer "In13.Cu")
		(net "P5E_CPU1_P1_RX_BUF_DP<11>")
	)
	(segment
		(start 82.028792 -416.31616)
		(end 82.33029 -416.014662)
		(width 0.14224)
		(layer "In13.Cu")
		(net "P5E_CPU1_P1_RX_BUF_DP<11>")
	)
	(segment
		(start 89.430098 -400.6342)
		(end 89.623646 -400.624548)
		(width 0.14224)
		(layer "In13.Cu")
		(net "P5E_CPU1_P1_RX_BUF_DP<11>")
	)
	(segment
		(start 89.901014 -400.114516)
		(end 90.317828 -399.654522)
		(width 0.14224)
		(layer "In13.Cu")
		(net "P5E_CPU1_P1_RX_BUF_DP<11>")
	)
	(segment
		(start 86.721696 -403.71141)
		(end 86.788498 -403.574758)
		(width 0.14224)
		(layer "In13.Cu")
		(net "P5E_CPU1_P1_RX_BUF_DP<11>")
	)
	(segment
		(start 89.910666 -400.308064)
		(end 89.901014 -400.114516)
		(width 0.14224)
		(layer "In13.Cu")
		(net "P5E_CPU1_P1_RX_BUF_DP<11>")
	)
	(segment
		(start 85.262974 -408.823414)
		(end 85.125814 -408.686254)
		(width 0.14224)
		(layer "In13.Cu")
		(net "P5E_CPU1_P1_RX_BUF_DP<11>")
	)
	(segment
		(start 88.67267 -401.46986)
		(end 88.866218 -401.460208)
		(width 0.14224)
		(layer "In13.Cu")
		(net "P5E_CPU1_P1_RX_BUF_DP<11>")
	)
	(segment
		(start 88.386158 -401.785836)
		(end 88.67267 -401.46986)
		(width 0.14224)
		(layer "In13.Cu")
		(net "P5E_CPU1_P1_RX_BUF_DP<11>")
	)
	(segment
		(start 91.23172 -398.484852)
		(end 92.814902 -396.116302)
		(width 0.14224)
		(layer "In13.Cu")
		(net "P5E_CPU1_P1_RX_BUF_DP<11>")
	)
	(segment
		(start 81.108296 -418.772848)
		(end 81.108296 -418.386768)
		(width 0.14224)
		(layer "In13.Cu")
		(net "P5E_CPU1_P1_RX_BUF_DP<11>")
	)
	(segment
		(start 81.650078 -434.289962)
		(end 81.650078 -434.618638)
		(width 0.14224)
		(layer "In13.Cu")
		(net "P5E_CPU1_P1_RX_BUF_DP<11>")
	)
	(segment
		(start 83.594194 -414.360614)
		(end 83.594194 -411.94863)
		(width 0.14224)
		(layer "In13.Cu")
		(net "P5E_CPU1_P1_RX_BUF_DP<11>")
	)
	(segment
		(start 93.41739 -393.017756)
		(end 93.54439 -393.144756)
		(width 0.14224)
		(layer "In13.Cu")
		(net "P5E_CPU1_P1_RX_BUF_DP<11>")
	)
	(segment
		(start 87.638382 -402.815044)
		(end 87.62873 -402.621496)
		(width 0.14224)
		(layer "In13.Cu")
		(net "P5E_CPU1_P1_RX_BUF_DP<11>")
	)
	(segment
		(start 89.143586 -400.950176)
		(end 89.430098 -400.6342)
		(width 0.14224)
		(layer "In13.Cu")
		(net "P5E_CPU1_P1_RX_BUF_DP<11>")
	)
	(segment
		(start 81.53273 -416.812222)
		(end 81.726786 -416.812222)
		(width 0.14224)
		(layer "In13.Cu")
		(net "P5E_CPU1_P1_RX_BUF_DP<11>")
	)
	(segment
		(start 81.726786 -416.812222)
		(end 82.028792 -416.510216)
		(width 0.14224)
		(layer "In13.Cu")
		(net "P5E_CPU1_P1_RX_BUF_DP<11>")
	)
	(segment
		(start 86.308184 -405.560276)
		(end 86.454996 -405.413464)
		(width 0.14224)
		(layer "In13.Cu")
		(net "P5E_CPU1_P1_RX_BUF_DP<11>")
	)
	(segment
		(start 82.826352 -415.712656)
		(end 82.826352 -415.5186)
		(width 0.14224)
		(layer "In13.Cu")
		(net "P5E_CPU1_P1_RX_BUF_DP<11>")
	)
	(segment
		(start 93.085412 -395.115796)
		(end 93.085412 -393.159996)
		(width 0.14224)
		(layer "In13.Cu")
		(net "P5E_CPU1_P1_RX_BUF_DP<11>")
	)
	(segment
		(start 87.351616 -403.131528)
		(end 87.638382 -402.815044)
		(width 0.14224)
		(layer "In13.Cu")
		(net "P5E_CPU1_P1_RX_BUF_DP<11>")
	)
	(segment
		(start 81.231232 -417.11372)
		(end 81.53273 -416.812222)
		(width 0.14224)
		(layer "In13.Cu")
		(net "P5E_CPU1_P1_RX_BUF_DP<11>")
	)
	(segment
		(start 80.97647 -426.878496)
		(end 80.971136 -426.873162)
		(width 0.14224)
		(layer "In13.Cu")
		(net "P5E_CPU1_P1_RX_BUF_DP<11>")
	)
	(segment
		(start 85.717126 -405.885142)
		(end 85.992716 -405.771096)
		(width 0.14224)
		(layer "In13.Cu")
		(net "P5E_CPU1_P1_RX_BUF_DP<11>")
	)
	(segment
		(start 85.992716 -405.771096)
		(end 86.308184 -405.560276)
		(width 0.14224)
		(layer "In13.Cu")
		(net "P5E_CPU1_P1_RX_BUF_DP<11>")
	)
	(segment
		(start 85.125814 -407.558494)
		(end 85.125814 -406.638252)
		(width 0.14224)
		(layer "In13.Cu")
		(net "P5E_CPU1_P1_RX_BUF_DP<11>")
	)
	(segment
		(start 82.028792 -416.510216)
		(end 82.028792 -416.31616)
		(width 0.14224)
		(layer "In13.Cu")
		(net "P5E_CPU1_P1_RX_BUF_DP<11>")
	)
	(segment
		(start 81.108296 -419.433248)
		(end 80.971136 -419.296088)
		(width 0.14224)
		(layer "In13.Cu")
		(net "P5E_CPU1_P1_RX_BUF_DP<11>")
	)
	(segment
		(start 85.262974 -407.695654)
		(end 85.125814 -407.558494)
		(width 0.14224)
		(layer "In13.Cu")
		(net "P5E_CPU1_P1_RX_BUF_DP<11>")
	)
	(segment
		(start 88.866218 -401.460208)
		(end 89.153238 -401.143724)
		(width 0.14224)
		(layer "In13.Cu")
		(net "P5E_CPU1_P1_RX_BUF_DP<11>")
	)
	(segment
		(start 80.971136 -419.956488)
		(end 81.108296 -419.819328)
		(width 0.14224)
		(layer "In13.Cu")
		(net "P5E_CPU1_P1_RX_BUF_DP<11>")
	)
	(segment
		(start 85.125814 -410.62148)
		(end 85.125814 -409.387294)
		(width 0.14224)
		(layer "In13.Cu")
		(net "P5E_CPU1_P1_RX_BUF_DP<11>")
	)
	(segment
		(start 85.125814 -409.387294)
		(end 85.262974 -409.250134)
		(width 0.14224)
		(layer "In13.Cu")
		(net "P5E_CPU1_P1_RX_BUF_DP<11>")
	)
	(segment
		(start 82.33029 -416.014662)
		(end 82.524346 -416.014662)
		(width 0.14224)
		(layer "In13.Cu")
		(net "P5E_CPU1_P1_RX_BUF_DP<11>")
	)
	(segment
		(start 93.54439 -393.144756)
		(end 93.54439 -393.292838)
		(width 0.14224)
		(layer "In13.Cu")
		(net "P5E_CPU1_P1_RX_BUF_DP<11>")
	)
	(segment
		(start 80.971136 -418.249608)
		(end 80.971136 -417.741608)
		(width 0.14224)
		(layer "In13.Cu")
		(net "P5E_CPU1_P1_RX_BUF_DP<11>")
	)
	(segment
		(start 88.39581 -401.979384)
		(end 88.386158 -401.785836)
		(width 0.14224)
		(layer "In13.Cu")
		(net "P5E_CPU1_P1_RX_BUF_DP<11>")
	)
	(segment
		(start 80.971136 -418.910008)
		(end 81.108296 -418.772848)
		(width 0.14224)
		(layer "In13.Cu")
		(net "P5E_CPU1_P1_RX_BUF_DP<11>")
	)
	(segment
		(start 93.227652 -393.017756)
		(end 93.41739 -393.017756)
		(width 0.14224)
		(layer "In13.Cu")
		(net "P5E_CPU1_P1_RX_BUF_DP<11>")
	)
	(segment
		(start 85.125814 -408.686254)
		(end 85.125814 -408.259534)
		(width 0.14224)
		(layer "In13.Cu")
		(net "P5E_CPU1_P1_RX_BUF_DP<11>")
	)
	(segment
		(start 82.826352 -415.5186)
		(end 83.31835 -415.026602)
		(width 0.14224)
		(layer "In13.Cu")
		(net "P5E_CPU1_P1_RX_BUF_DP<11>")
	)
	(segment
		(start 87.62873 -402.621496)
		(end 87.915242 -402.30552)
		(width 0.14224)
		(layer "In13.Cu")
		(net "P5E_CPU1_P1_RX_BUF_DP<11>")
	)
	(arc
		(start 86.706202 -403.758654)
		(mid 86.712329 -403.7345)
		(end 86.721696 -403.71141)
		(width 0.14224)
		(layer "In13.Cu")
		(net "P5E_CPU1_P1_RX_BUF_DP<11>")
	)
	(arc
		(start 90.317828 -399.654522)
		(mid 90.796417 -399.086597)
		(end 91.23172 -398.484852)
		(width 0.14224)
		(layer "In13.Cu")
		(net "P5E_CPU1_P1_RX_BUF_DP<11>")
	)
	(arc
		(start 93.053916 -395.32814)
		(mid 93.077496 -395.22313)
		(end 93.085412 -395.115796)
		(width 0.14224)
		(layer "In13.Cu")
		(net "P5E_CPU1_P1_RX_BUF_DP<11>")
	)
	(arc
		(start 86.788498 -403.574758)
		(mid 86.820255 -403.520065)
		(end 86.859364 -403.470364)
		(width 0.14224)
		(layer "In13.Cu")
		(net "P5E_CPU1_P1_RX_BUF_DP<11>")
	)
	(arc
		(start 83.594194 -411.94863)
		(mid 83.643992 -411.78457)
		(end 83.776566 -411.675834)
		(width 0.14224)
		(layer "In13.Cu")
		(net "P5E_CPU1_P1_RX_BUF_DP<11>")
	)
	(arc
		(start 83.31835 -415.026602)
		(mid 83.522517 -414.721044)
		(end 83.594194 -414.360614)
		(width 0.14224)
		(layer "In13.Cu")
		(net "P5E_CPU1_P1_RX_BUF_DP<11>")
	)
	(arc
		(start 86.657434 -404.087076)
		(mid 86.66027 -404.023822)
		(end 86.668864 -403.961092)
		(width 0.14224)
		(layer "In13.Cu")
		(net "P5E_CPU1_P1_RX_BUF_DP<11>")
	)
	(arc
		(start 85.330792 -406.14346)
		(mid 85.511262 -405.995314)
		(end 85.717126 -405.885142)
		(width 0.14224)
		(layer "In13.Cu")
		(net "P5E_CPU1_P1_RX_BUF_DP<11>")
	)
	(arc
		(start 86.454996 -405.413464)
		(mid 86.604836 -405.189118)
		(end 86.657434 -404.924514)
		(width 0.14224)
		(layer "In13.Cu")
		(net "P5E_CPU1_P1_RX_BUF_DP<11>")
	)
	(arc
		(start 85.125814 -406.638252)
		(mid 85.179043 -406.370451)
		(end 85.330792 -406.14346)
		(width 0.14224)
		(layer "In13.Cu")
		(net "P5E_CPU1_P1_RX_BUF_DP<11>")
	)
	(arc
		(start 84.668106 -411.30601)
		(mid 85.000756 -411.033154)
		(end 85.125814 -410.62148)
		(width 0.14224)
		(layer "In13.Cu")
		(net "P5E_CPU1_P1_RX_BUF_DP<11>")
	)
	(arc
		(start 80.971136 -417.741608)
		(mid 81.03873 -417.401791)
		(end 81.231232 -417.11372)
		(width 0.14224)
		(layer "In13.Cu")
		(net "P5E_CPU1_P1_RX_BUF_DP<11>")
	)
	(segment
		(start 91.729814 -391.365232)
		(end 91.64574 -391.281158)
		(width 0.1016)
		(layer "F.Cu")
		(net "P5E_CPU1_P1_RX_BUF_DP<10>")
	)
	(segment
		(start 91.641676 -392.723878)
		(end 91.641676 -391.577322)
		(width 0.1016)
		(layer "F.Cu")
		(net "P5E_CPU1_P1_RX_BUF_DP<10>")
	)
	(segment
		(start 92.344494 -393.116054)
		(end 92.205556 -392.977116)
		(width 0.1016)
		(layer "F.Cu")
		(net "P5E_CPU1_P1_RX_BUF_DP<10>")
	)
	(segment
		(start 91.894914 -392.977116)
		(end 91.641676 -392.723878)
		(width 0.1016)
		(layer "F.Cu")
		(net "P5E_CPU1_P1_RX_BUF_DP<10>")
	)
	(segment
		(start 92.344494 -393.292838)
		(end 92.344494 -393.116054)
		(width 0.1016)
		(layer "F.Cu")
		(net "P5E_CPU1_P1_RX_BUF_DP<10>")
	)
	(segment
		(start 91.641676 -391.577322)
		(end 91.729814 -391.489184)
		(width 0.1016)
		(layer "F.Cu")
		(net "P5E_CPU1_P1_RX_BUF_DP<10>")
	)
	(segment
		(start 92.205556 -392.977116)
		(end 91.894914 -392.977116)
		(width 0.1016)
		(layer "F.Cu")
		(net "P5E_CPU1_P1_RX_BUF_DP<10>")
	)
	(segment
		(start 91.729814 -391.489184)
		(end 91.729814 -391.365232)
		(width 0.1016)
		(layer "F.Cu")
		(net "P5E_CPU1_P1_RX_BUF_DP<10>")
	)
	(segment
		(start 80.530954 -414.60674)
		(end 80.530954 -411.955996)
		(width 0.14224)
		(layer "In13.Cu")
		(net "P5E_CPU1_P1_RX_BUF_DP<10>")
	)
	(segment
		(start 82.062574 -408.714194)
		(end 82.062574 -408.287474)
		(width 0.14224)
		(layer "In13.Cu")
		(net "P5E_CPU1_P1_RX_BUF_DP<10>")
	)
	(segment
		(start 82.062574 -410.69768)
		(end 82.062574 -409.415234)
		(width 0.14224)
		(layer "In13.Cu")
		(net "P5E_CPU1_P1_RX_BUF_DP<10>")
	)
	(segment
		(start 92.344494 -393.144756)
		(end 92.344494 -393.292838)
		(width 0.14224)
		(layer "In13.Cu")
		(net "P5E_CPU1_P1_RX_BUF_DP<10>")
	)
	(segment
		(start 80.720184 -411.67304)
		(end 81.571592 -411.31998)
		(width 0.14224)
		(layer "In13.Cu")
		(net "P5E_CPU1_P1_RX_BUF_DP<10>")
	)
	(segment
		(start 79.163418 -418.64153)
		(end 79.163418 -416.649154)
		(width 0.14224)
		(layer "In13.Cu")
		(net "P5E_CPU1_P1_RX_BUF_DP<10>")
	)
	(segment
		(start 82.653886 -405.885142)
		(end 82.929476 -405.771096)
		(width 0.14224)
		(layer "In13.Cu")
		(net "P5E_CPU1_P1_RX_BUF_DP<10>")
	)
	(segment
		(start 88.80475 -399.585688)
		(end 89.682574 -398.708118)
		(width 0.14224)
		(layer "In13.Cu")
		(net "P5E_CPU1_P1_RX_BUF_DP<10>")
	)
	(segment
		(start 88.308942 -400.08175)
		(end 88.502744 -400.08175)
		(width 0.14224)
		(layer "In13.Cu")
		(net "P5E_CPU1_P1_RX_BUF_DP<10>")
	)
	(segment
		(start 91.017598 -397.050768)
		(end 90.984578 -396.859506)
		(width 0.14224)
		(layer "In13.Cu")
		(net "P5E_CPU1_P1_RX_BUF_DP<10>")
	)
	(segment
		(start 90.580718 -397.433038)
		(end 90.771726 -397.399764)
		(width 0.14224)
		(layer "In13.Cu")
		(net "P5E_CPU1_P1_RX_BUF_DP<10>")
	)
	(segment
		(start 78.97114 -423.829988)
		(end 79.163418 -423.365676)
		(width 0.14224)
		(layer "In13.Cu")
		(net "P5E_CPU1_P1_RX_BUF_DP<10>")
	)
	(segment
		(start 86.390988 -401.90674)
		(end 86.74354 -401.665694)
		(width 0.14224)
		(layer "In13.Cu")
		(net "P5E_CPU1_P1_RX_BUF_DP<10>")
	)
	(segment
		(start 87.20963 -401.180808)
		(end 87.511382 -400.87931)
		(width 0.14224)
		(layer "In13.Cu")
		(net "P5E_CPU1_P1_RX_BUF_DP<10>")
	)
	(segment
		(start 88.80475 -399.779744)
		(end 88.80475 -399.585688)
		(width 0.14224)
		(layer "In13.Cu")
		(net "P5E_CPU1_P1_RX_BUF_DP<10>")
	)
	(segment
		(start 89.930986 -398.355312)
		(end 90.122248 -398.322038)
		(width 0.14224)
		(layer "In13.Cu")
		(net "P5E_CPU1_P1_RX_BUF_DP<10>")
	)
	(segment
		(start 79.300578 -421.37965)
		(end 79.300578 -420.99357)
		(width 0.14224)
		(layer "In13.Cu")
		(net "P5E_CPU1_P1_RX_BUF_DP<10>")
	)
	(segment
		(start 84.516722 -403.069552)
		(end 84.81568 -402.824188)
		(width 0.14224)
		(layer "In13.Cu")
		(net "P5E_CPU1_P1_RX_BUF_DP<10>")
	)
	(segment
		(start 83.244944 -405.560276)
		(end 83.391756 -405.413464)
		(width 0.14224)
		(layer "In13.Cu")
		(net "P5E_CPU1_P1_RX_BUF_DP<10>")
	)
	(segment
		(start 86.779354 -401.47494)
		(end 87.20963 -401.180808)
		(width 0.14224)
		(layer "In13.Cu")
		(net "P5E_CPU1_P1_RX_BUF_DP<10>")
	)
	(segment
		(start 83.620356 -403.983952)
		(end 83.692492 -403.821138)
		(width 0.14224)
		(layer "In13.Cu")
		(net "P5E_CPU1_P1_RX_BUF_DP<10>")
	)
	(segment
		(start 78.976474 -433.458112)
		(end 78.976474 -426.969936)
		(width 0.14224)
		(layer "In13.Cu")
		(net "P5E_CPU1_P1_RX_BUF_DP<10>")
	)
	(segment
		(start 90.984578 -396.859506)
		(end 90.984578 -396.859252)
		(width 0.14224)
		(layer "In13.Cu")
		(net "P5E_CPU1_P1_RX_BUF_DP<10>")
	)
	(segment
		(start 78.97114 -426.964602)
		(end 78.97114 -423.829988)
		(width 0.14224)
		(layer "In13.Cu")
		(net "P5E_CPU1_P1_RX_BUF_DP<10>")
	)
	(segment
		(start 82.062574 -408.287474)
		(end 82.199734 -408.150314)
		(width 0.14224)
		(layer "In13.Cu")
		(net "P5E_CPU1_P1_RX_BUF_DP<10>")
	)
	(segment
		(start 90.36812 -397.972788)
		(end 90.3351 -397.78178)
		(width 0.14224)
		(layer "In13.Cu")
		(net "P5E_CPU1_P1_RX_BUF_DP<10>")
	)
	(segment
		(start 82.199734 -407.723594)
		(end 82.062574 -407.586434)
		(width 0.14224)
		(layer "In13.Cu")
		(net "P5E_CPU1_P1_RX_BUF_DP<10>")
	)
	(segment
		(start 90.3351 -397.78178)
		(end 90.580718 -397.433038)
		(width 0.14224)
		(layer "In13.Cu")
		(net "P5E_CPU1_P1_RX_BUF_DP<10>")
	)
	(segment
		(start 84.917026 -402.748242)
		(end 86.200234 -401.870926)
		(width 0.14224)
		(layer "In13.Cu")
		(net "P5E_CPU1_P1_RX_BUF_DP<10>")
	)
	(segment
		(start 82.199734 -408.851354)
		(end 82.062574 -408.714194)
		(width 0.14224)
		(layer "In13.Cu")
		(net "P5E_CPU1_P1_RX_BUF_DP<10>")
	)
	(segment
		(start 79.163418 -420.47033)
		(end 79.300578 -420.33317)
		(width 0.14224)
		(layer "In13.Cu")
		(net "P5E_CPU1_P1_RX_BUF_DP<10>")
	)
	(segment
		(start 79.650082 -433.289964)
		(end 79.650082 -433.61864)
		(width 0.14224)
		(layer "In13.Cu")
		(net "P5E_CPU1_P1_RX_BUF_DP<10>")
	)
	(segment
		(start 86.200234 -401.870926)
		(end 86.390988 -401.90674)
		(width 0.14224)
		(layer "In13.Cu")
		(net "P5E_CPU1_P1_RX_BUF_DP<10>")
	)
	(segment
		(start 79.300578 -420.33317)
		(end 79.300578 -419.90645)
		(width 0.14224)
		(layer "In13.Cu")
		(net "P5E_CPU1_P1_RX_BUF_DP<10>")
	)
	(segment
		(start 82.199734 -409.278074)
		(end 82.199734 -408.851354)
		(width 0.14224)
		(layer "In13.Cu")
		(net "P5E_CPU1_P1_RX_BUF_DP<10>")
	)
	(segment
		(start 92.217494 -393.017756)
		(end 92.344494 -393.144756)
		(width 0.14224)
		(layer "In13.Cu")
		(net "P5E_CPU1_P1_RX_BUF_DP<10>")
	)
	(segment
		(start 79.163418 -421.95496)
		(end 79.163418 -421.51681)
		(width 0.14224)
		(layer "In13.Cu")
		(net "P5E_CPU1_P1_RX_BUF_DP<10>")
	)
	(segment
		(start 90.122248 -398.322038)
		(end 90.36812 -397.972788)
		(width 0.14224)
		(layer "In13.Cu")
		(net "P5E_CPU1_P1_RX_BUF_DP<10>")
	)
	(segment
		(start 79.163418 -423.365676)
		(end 79.163418 -422.61536)
		(width 0.14224)
		(layer "In13.Cu")
		(net "P5E_CPU1_P1_RX_BUF_DP<10>")
	)
	(segment
		(start 82.062574 -407.586434)
		(end 82.062574 -406.638252)
		(width 0.14224)
		(layer "In13.Cu")
		(net "P5E_CPU1_P1_RX_BUF_DP<10>")
	)
	(segment
		(start 79.163418 -421.51681)
		(end 79.300578 -421.37965)
		(width 0.14224)
		(layer "In13.Cu")
		(net "P5E_CPU1_P1_RX_BUF_DP<10>")
	)
	(segment
		(start 90.771726 -397.399764)
		(end 91.017598 -397.050768)
		(width 0.14224)
		(layer "In13.Cu")
		(net "P5E_CPU1_P1_RX_BUF_DP<10>")
	)
	(segment
		(start 79.163418 -419.34257)
		(end 79.300578 -419.20541)
		(width 0.14224)
		(layer "In13.Cu")
		(net "P5E_CPU1_P1_RX_BUF_DP<10>")
	)
	(segment
		(start 79.251302 -433.73294)
		(end 78.976474 -433.458112)
		(width 0.14224)
		(layer "In13.Cu")
		(net "P5E_CPU1_P1_RX_BUF_DP<10>")
	)
	(segment
		(start 79.300578 -420.99357)
		(end 79.163418 -420.85641)
		(width 0.14224)
		(layer "In13.Cu")
		(net "P5E_CPU1_P1_RX_BUF_DP<10>")
	)
	(segment
		(start 90.984578 -396.859252)
		(end 91.811094 -395.685264)
		(width 0.14224)
		(layer "In13.Cu")
		(net "P5E_CPU1_P1_RX_BUF_DP<10>")
	)
	(segment
		(start 79.163418 -422.61536)
		(end 79.300578 -422.4782)
		(width 0.14224)
		(layer "In13.Cu")
		(net "P5E_CPU1_P1_RX_BUF_DP<10>")
	)
	(segment
		(start 88.502744 -400.08175)
		(end 88.80475 -399.779744)
		(width 0.14224)
		(layer "In13.Cu")
		(net "P5E_CPU1_P1_RX_BUF_DP<10>")
	)
	(segment
		(start 79.300578 -419.90645)
		(end 79.163418 -419.76929)
		(width 0.14224)
		(layer "In13.Cu")
		(net "P5E_CPU1_P1_RX_BUF_DP<10>")
	)
	(segment
		(start 79.300578 -422.09212)
		(end 79.163418 -421.95496)
		(width 0.14224)
		(layer "In13.Cu")
		(net "P5E_CPU1_P1_RX_BUF_DP<10>")
	)
	(segment
		(start 83.594194 -404.924514)
		(end 83.594194 -404.106888)
		(width 0.14224)
		(layer "In13.Cu")
		(net "P5E_CPU1_P1_RX_BUF_DP<10>")
	)
	(segment
		(start 88.00719 -400.577304)
		(end 88.00719 -400.383248)
		(width 0.14224)
		(layer "In13.Cu")
		(net "P5E_CPU1_P1_RX_BUF_DP<10>")
	)
	(segment
		(start 79.163418 -420.85641)
		(end 79.163418 -420.47033)
		(width 0.14224)
		(layer "In13.Cu")
		(net "P5E_CPU1_P1_RX_BUF_DP<10>")
	)
	(segment
		(start 91.885516 -393.159996)
		(end 92.027756 -393.017756)
		(width 0.14224)
		(layer "In13.Cu")
		(net "P5E_CPU1_P1_RX_BUF_DP<10>")
	)
	(segment
		(start 82.929476 -405.771096)
		(end 83.244944 -405.560276)
		(width 0.14224)
		(layer "In13.Cu")
		(net "P5E_CPU1_P1_RX_BUF_DP<10>")
	)
	(segment
		(start 87.705184 -400.87931)
		(end 88.00719 -400.577304)
		(width 0.14224)
		(layer "In13.Cu")
		(net "P5E_CPU1_P1_RX_BUF_DP<10>")
	)
	(segment
		(start 79.535782 -433.73294)
		(end 79.251302 -433.73294)
		(width 0.14224)
		(layer "In13.Cu")
		(net "P5E_CPU1_P1_RX_BUF_DP<10>")
	)
	(segment
		(start 79.298292 -416.323526)
		(end 80.188816 -415.433002)
		(width 0.14224)
		(layer "In13.Cu")
		(net "P5E_CPU1_P1_RX_BUF_DP<10>")
	)
	(segment
		(start 78.976474 -426.969936)
		(end 78.97114 -426.964602)
		(width 0.14224)
		(layer "In13.Cu")
		(net "P5E_CPU1_P1_RX_BUF_DP<10>")
	)
	(segment
		(start 79.163418 -419.76929)
		(end 79.163418 -419.34257)
		(width 0.14224)
		(layer "In13.Cu")
		(net "P5E_CPU1_P1_RX_BUF_DP<10>")
	)
	(segment
		(start 82.199734 -408.150314)
		(end 82.199734 -407.723594)
		(width 0.14224)
		(layer "In13.Cu")
		(net "P5E_CPU1_P1_RX_BUF_DP<10>")
	)
	(segment
		(start 79.300578 -422.4782)
		(end 79.300578 -422.09212)
		(width 0.14224)
		(layer "In13.Cu")
		(net "P5E_CPU1_P1_RX_BUF_DP<10>")
	)
	(segment
		(start 92.027756 -393.017756)
		(end 92.217494 -393.017756)
		(width 0.14224)
		(layer "In13.Cu")
		(net "P5E_CPU1_P1_RX_BUF_DP<10>")
	)
	(segment
		(start 86.74354 -401.665694)
		(end 86.779354 -401.47494)
		(width 0.14224)
		(layer "In13.Cu")
		(net "P5E_CPU1_P1_RX_BUF_DP<10>")
	)
	(segment
		(start 79.300578 -419.20541)
		(end 79.300578 -418.77869)
		(width 0.14224)
		(layer "In13.Cu")
		(net "P5E_CPU1_P1_RX_BUF_DP<10>")
	)
	(segment
		(start 82.062574 -409.415234)
		(end 82.199734 -409.278074)
		(width 0.14224)
		(layer "In13.Cu")
		(net "P5E_CPU1_P1_RX_BUF_DP<10>")
	)
	(segment
		(start 79.300578 -418.77869)
		(end 79.163418 -418.64153)
		(width 0.14224)
		(layer "In13.Cu")
		(net "P5E_CPU1_P1_RX_BUF_DP<10>")
	)
	(segment
		(start 89.682574 -398.708118)
		(end 89.930986 -398.355312)
		(width 0.14224)
		(layer "In13.Cu")
		(net "P5E_CPU1_P1_RX_BUF_DP<10>")
	)
	(segment
		(start 88.00719 -400.383248)
		(end 88.308942 -400.08175)
		(width 0.14224)
		(layer "In13.Cu")
		(net "P5E_CPU1_P1_RX_BUF_DP<10>")
	)
	(segment
		(start 87.511382 -400.87931)
		(end 87.705184 -400.87931)
		(width 0.14224)
		(layer "In13.Cu")
		(net "P5E_CPU1_P1_RX_BUF_DP<10>")
	)
	(segment
		(start 91.885516 -395.449806)
		(end 91.885516 -393.159996)
		(width 0.14224)
		(layer "In13.Cu")
		(net "P5E_CPU1_P1_RX_BUF_DP<10>")
	)
	(segment
		(start 79.650082 -433.61864)
		(end 79.535782 -433.73294)
		(width 0.14224)
		(layer "In13.Cu")
		(net "P5E_CPU1_P1_RX_BUF_DP<10>")
	)
	(arc
		(start 80.188816 -415.433002)
		(mid 80.442064 -415.053896)
		(end 80.530954 -414.60674)
		(width 0.14224)
		(layer "In13.Cu")
		(net "P5E_CPU1_P1_RX_BUF_DP<10>")
	)
	(arc
		(start 84.201 -403.33422)
		(mid 84.358161 -403.20105)
		(end 84.516722 -403.069552)
		(width 0.14224)
		(layer "In13.Cu")
		(net "P5E_CPU1_P1_RX_BUF_DP<10>")
	)
	(arc
		(start 83.391756 -405.413464)
		(mid 83.541596 -405.189118)
		(end 83.594194 -404.924514)
		(width 0.14224)
		(layer "In13.Cu")
		(net "P5E_CPU1_P1_RX_BUF_DP<10>")
	)
	(arc
		(start 83.76666 -403.718268)
		(mid 83.982331 -403.524549)
		(end 84.201 -403.33422)
		(width 0.14224)
		(layer "In13.Cu")
		(net "P5E_CPU1_P1_RX_BUF_DP<10>")
	)
	(arc
		(start 81.902046 -411.090618)
		(mid 82.02089 -410.909904)
		(end 82.062574 -410.69768)
		(width 0.14224)
		(layer "In13.Cu")
		(net "P5E_CPU1_P1_RX_BUF_DP<10>")
	)
	(arc
		(start 91.811094 -395.685264)
		(mid 91.866533 -395.573289)
		(end 91.885516 -395.449806)
		(width 0.14224)
		(layer "In13.Cu")
		(net "P5E_CPU1_P1_RX_BUF_DP<10>")
	)
	(arc
		(start 82.062574 -406.638252)
		(mid 82.115803 -406.370451)
		(end 82.267552 -406.14346)
		(width 0.14224)
		(layer "In13.Cu")
		(net "P5E_CPU1_P1_RX_BUF_DP<10>")
	)
	(arc
		(start 81.571592 -411.31998)
		(mid 81.749101 -411.222993)
		(end 81.902046 -411.090618)
		(width 0.14224)
		(layer "In13.Cu")
		(net "P5E_CPU1_P1_RX_BUF_DP<10>")
	)
	(arc
		(start 83.594194 -404.106888)
		(mid 83.60084 -404.044052)
		(end 83.620356 -403.983952)
		(width 0.14224)
		(layer "In13.Cu")
		(net "P5E_CPU1_P1_RX_BUF_DP<10>")
	)
	(arc
		(start 79.163418 -416.649154)
		(mid 79.198472 -416.472928)
		(end 79.298292 -416.323526)
		(width 0.14224)
		(layer "In13.Cu")
		(net "P5E_CPU1_P1_RX_BUF_DP<10>")
	)
	(arc
		(start 80.530954 -411.955996)
		(mid 80.582705 -411.785877)
		(end 80.720184 -411.67304)
		(width 0.14224)
		(layer "In13.Cu")
		(net "P5E_CPU1_P1_RX_BUF_DP<10>")
	)
	(arc
		(start 83.692492 -403.821138)
		(mid 83.724214 -403.765834)
		(end 83.76666 -403.718268)
		(width 0.14224)
		(layer "In13.Cu")
		(net "P5E_CPU1_P1_RX_BUF_DP<10>")
	)
	(arc
		(start 82.267552 -406.14346)
		(mid 82.448022 -405.995314)
		(end 82.653886 -405.885142)
		(width 0.14224)
		(layer "In13.Cu")
		(net "P5E_CPU1_P1_RX_BUF_DP<10>")
	)
	(arc
		(start 84.81568 -402.824188)
		(mid 84.865525 -402.78511)
		(end 84.917026 -402.748242)
		(width 0.14224)
		(layer "In13.Cu")
		(net "P5E_CPU1_P1_RX_BUF_DP<10>")
	)
	(segment
		(start 79.894938 -392.977116)
		(end 80.20558 -392.977116)
		(width 0.1016)
		(layer "F.Cu")
		(net "P5E_CPU1_P1_RX_BUF_DP<0>")
	)
	(segment
		(start 80.344264 -393.1158)
		(end 80.344264 -393.292838)
		(width 0.1016)
		(layer "F.Cu")
		(net "P5E_CPU1_P1_RX_BUF_DP<0>")
	)
	(segment
		(start 79.730346 -391.36574)
		(end 79.730346 -391.488676)
		(width 0.1016)
		(layer "F.Cu")
		(net "P5E_CPU1_P1_RX_BUF_DP<0>")
	)
	(segment
		(start 79.645764 -391.281158)
		(end 79.730346 -391.36574)
		(width 0.1016)
		(layer "F.Cu")
		(net "P5E_CPU1_P1_RX_BUF_DP<0>")
	)
	(segment
		(start 79.730346 -391.488676)
		(end 79.619348 -391.599674)
		(width 0.1016)
		(layer "F.Cu")
		(net "P5E_CPU1_P1_RX_BUF_DP<0>")
	)
	(segment
		(start 79.619348 -392.701526)
		(end 79.894938 -392.977116)
		(width 0.1016)
		(layer "F.Cu")
		(net "P5E_CPU1_P1_RX_BUF_DP<0>")
	)
	(segment
		(start 79.619348 -391.599674)
		(end 79.619348 -392.701526)
		(width 0.1016)
		(layer "F.Cu")
		(net "P5E_CPU1_P1_RX_BUF_DP<0>")
	)
	(segment
		(start 80.20558 -392.977116)
		(end 80.344264 -393.1158)
		(width 0.1016)
		(layer "F.Cu")
		(net "P5E_CPU1_P1_RX_BUF_DP<0>")
	)
	(segment
		(start 52.02809 -415.875216)
		(end 51.726084 -415.57321)
		(width 0.14224)
		(layer "In13.Cu")
		(net "P5E_CPU1_P1_RX_BUF_DP<0>")
	)
	(segment
		(start 52.825396 -416.672776)
		(end 52.52339 -416.37077)
		(width 0.14224)
		(layer "In13.Cu")
		(net "P5E_CPU1_P1_RX_BUF_DP<0>")
	)
	(segment
		(start 55.713122 -419.754304)
		(end 55.713122 -419.560248)
		(width 0.14224)
		(layer "In13.Cu")
		(net "P5E_CPU1_P1_RX_BUF_DP<0>")
	)
	(segment
		(start 49.898554 -413.684212)
		(end 49.898554 -411.829504)
		(width 0.14224)
		(layer "In13.Cu")
		(net "P5E_CPU1_P1_RX_BUF_DP<0>")
	)
	(segment
		(start 50.791872 -414.833054)
		(end 50.079148 -414.12033)
		(width 0.14224)
		(layer "In13.Cu")
		(net "P5E_CPU1_P1_RX_BUF_DP<0>")
	)
	(segment
		(start 54.915562 -418.762688)
		(end 54.613556 -418.460682)
		(width 0.14224)
		(layer "In13.Cu")
		(net "P5E_CPU1_P1_RX_BUF_DP<0>")
	)
	(segment
		(start 76.782168 -394.453872)
		(end 77.183742 -394.308584)
		(width 0.14224)
		(layer "In13.Cu")
		(net "P5E_CPU1_P1_RX_BUF_DP<0>")
	)
	(segment
		(start 57.490106 -432.971956)
		(end 57.490106 -422.029636)
		(width 0.14224)
		(layer "In13.Cu")
		(net "P5E_CPU1_P1_RX_BUF_DP<0>")
	)
	(segment
		(start 53.185568 -403.535896)
		(end 53.58003 -403.201124)
		(width 0.14224)
		(layer "In13.Cu")
		(net "P5E_CPU1_P1_RX_BUF_DP<0>")
	)
	(segment
		(start 52.02809 -416.069272)
		(end 52.02809 -415.875216)
		(width 0.14224)
		(layer "In13.Cu")
		(net "P5E_CPU1_P1_RX_BUF_DP<0>")
	)
	(segment
		(start 51.567334 -407.943304)
		(end 51.567334 -407.516584)
		(width 0.14224)
		(layer "In13.Cu")
		(net "P5E_CPU1_P1_RX_BUF_DP<0>")
	)
	(segment
		(start 78.725522 -393.262866)
		(end 79.446882 -393.002008)
		(width 0.14224)
		(layer "In13.Cu")
		(net "P5E_CPU1_P1_RX_BUF_DP<0>")
	)
	(segment
		(start 51.567334 -409.071064)
		(end 51.567334 -408.644344)
		(width 0.14224)
		(layer "In13.Cu")
		(net "P5E_CPU1_P1_RX_BUF_DP<0>")
	)
	(segment
		(start 55.21706 -419.258242)
		(end 54.915562 -418.956744)
		(width 0.14224)
		(layer "In13.Cu")
		(net "P5E_CPU1_P1_RX_BUF_DP<0>")
	)
	(segment
		(start 51.430174 -410.721302)
		(end 51.430174 -409.208224)
		(width 0.14224)
		(layer "In13.Cu")
		(net "P5E_CPU1_P1_RX_BUF_DP<0>")
	)
	(segment
		(start 52.986432 -403.93874)
		(end 53.111654 -403.637242)
		(width 0.14224)
		(layer "In13.Cu")
		(net "P5E_CPU1_P1_RX_BUF_DP<0>")
	)
	(segment
		(start 54.613556 -418.460682)
		(end 54.4195 -418.460682)
		(width 0.14224)
		(layer "In13.Cu")
		(net "P5E_CPU1_P1_RX_BUF_DP<0>")
	)
	(segment
		(start 58.64987 -433.289964)
		(end 58.64987 -433.61864)
		(width 0.14224)
		(layer "In13.Cu")
		(net "P5E_CPU1_P1_RX_BUF_DP<0>")
	)
	(segment
		(start 73.480676 -395.159738)
		(end 75.11288 -394.91158)
		(width 0.14224)
		(layer "In13.Cu")
		(net "P5E_CPU1_P1_RX_BUF_DP<0>")
	)
	(segment
		(start 79.446882 -393.002008)
		(end 80.053434 -393.002008)
		(width 0.14224)
		(layer "In13.Cu")
		(net "P5E_CPU1_P1_RX_BUF_DP<0>")
	)
	(segment
		(start 51.430174 -407.379424)
		(end 51.430174 -406.638252)
		(width 0.14224)
		(layer "In13.Cu")
		(net "P5E_CPU1_P1_RX_BUF_DP<0>")
	)
	(segment
		(start 75.11288 -394.91158)
		(end 76.606654 -394.371322)
		(width 0.14224)
		(layer "In13.Cu")
		(net "P5E_CPU1_P1_RX_BUF_DP<0>")
	)
	(segment
		(start 52.961794 -404.924514)
		(end 52.961794 -404.06193)
		(width 0.14224)
		(layer "In13.Cu")
		(net "P5E_CPU1_P1_RX_BUF_DP<0>")
	)
	(segment
		(start 58.274966 -433.756816)
		(end 57.490106 -432.971956)
		(width 0.14224)
		(layer "In13.Cu")
		(net "P5E_CPU1_P1_RX_BUF_DP<0>")
	)
	(segment
		(start 53.622956 -417.664138)
		(end 53.622956 -417.470082)
		(width 0.14224)
		(layer "In13.Cu")
		(net "P5E_CPU1_P1_RX_BUF_DP<0>")
	)
	(segment
		(start 66.282062 -397.762984)
		(end 73.480676 -395.159738)
		(width 0.14224)
		(layer "In13.Cu")
		(net "P5E_CPU1_P1_RX_BUF_DP<0>")
	)
	(segment
		(start 55.411116 -419.258242)
		(end 55.21706 -419.258242)
		(width 0.14224)
		(layer "In13.Cu")
		(net "P5E_CPU1_P1_RX_BUF_DP<0>")
	)
	(segment
		(start 53.126894 -417.168076)
		(end 52.825396 -416.866578)
		(width 0.14224)
		(layer "In13.Cu")
		(net "P5E_CPU1_P1_RX_BUF_DP<0>")
	)
	(segment
		(start 77.74305 -393.96035)
		(end 78.078838 -393.653518)
		(width 0.14224)
		(layer "In13.Cu")
		(net "P5E_CPU1_P1_RX_BUF_DP<0>")
	)
	(segment
		(start 51.726084 -415.57321)
		(end 51.532028 -415.57321)
		(width 0.14224)
		(layer "In13.Cu")
		(net "P5E_CPU1_P1_RX_BUF_DP<0>")
	)
	(segment
		(start 51.430174 -409.208224)
		(end 51.567334 -409.071064)
		(width 0.14224)
		(layer "In13.Cu")
		(net "P5E_CPU1_P1_RX_BUF_DP<0>")
	)
	(segment
		(start 51.259232 -415.106358)
		(end 50.985928 -414.833054)
		(width 0.14224)
		(layer "In13.Cu")
		(net "P5E_CPU1_P1_RX_BUF_DP<0>")
	)
	(segment
		(start 56.208422 -420.055802)
		(end 56.01462 -420.055802)
		(width 0.14224)
		(layer "In13.Cu")
		(net "P5E_CPU1_P1_RX_BUF_DP<0>")
	)
	(segment
		(start 52.329588 -416.37077)
		(end 52.02809 -416.069272)
		(width 0.14224)
		(layer "In13.Cu")
		(net "P5E_CPU1_P1_RX_BUF_DP<0>")
	)
	(segment
		(start 51.259232 -415.300414)
		(end 51.259232 -415.106358)
		(width 0.14224)
		(layer "In13.Cu")
		(net "P5E_CPU1_P1_RX_BUF_DP<0>")
	)
	(segment
		(start 56.01462 -420.055802)
		(end 55.713122 -419.754304)
		(width 0.14224)
		(layer "In13.Cu")
		(net "P5E_CPU1_P1_RX_BUF_DP<0>")
	)
	(segment
		(start 58.64987 -433.61864)
		(end 58.511694 -433.756816)
		(width 0.14224)
		(layer "In13.Cu")
		(net "P5E_CPU1_P1_RX_BUF_DP<0>")
	)
	(segment
		(start 53.622956 -417.470082)
		(end 53.32095 -417.168076)
		(width 0.14224)
		(layer "In13.Cu")
		(net "P5E_CPU1_P1_RX_BUF_DP<0>")
	)
	(segment
		(start 56.510428 -420.55161)
		(end 56.510428 -420.357808)
		(width 0.14224)
		(layer "In13.Cu")
		(net "P5E_CPU1_P1_RX_BUF_DP<0>")
	)
	(segment
		(start 51.567334 -407.516584)
		(end 51.430174 -407.379424)
		(width 0.14224)
		(layer "In13.Cu")
		(net "P5E_CPU1_P1_RX_BUF_DP<0>")
	)
	(segment
		(start 57.137808 -421.17899)
		(end 56.510428 -420.55161)
		(width 0.14224)
		(layer "In13.Cu")
		(net "P5E_CPU1_P1_RX_BUF_DP<0>")
	)
	(segment
		(start 51.430174 -408.507184)
		(end 51.430174 -408.080464)
		(width 0.14224)
		(layer "In13.Cu")
		(net "P5E_CPU1_P1_RX_BUF_DP<0>")
	)
	(segment
		(start 80.053434 -393.002008)
		(end 80.344264 -393.292838)
		(width 0.14224)
		(layer "In13.Cu")
		(net "P5E_CPU1_P1_RX_BUF_DP<0>")
	)
	(segment
		(start 52.612544 -405.560276)
		(end 52.759356 -405.413464)
		(width 0.14224)
		(layer "In13.Cu")
		(net "P5E_CPU1_P1_RX_BUF_DP<0>")
	)
	(segment
		(start 51.567334 -408.644344)
		(end 51.430174 -408.507184)
		(width 0.14224)
		(layer "In13.Cu")
		(net "P5E_CPU1_P1_RX_BUF_DP<0>")
	)
	(segment
		(start 77.183742 -394.308584)
		(end 77.266038 -394.132816)
		(width 0.14224)
		(layer "In13.Cu")
		(net "P5E_CPU1_P1_RX_BUF_DP<0>")
	)
	(segment
		(start 77.266038 -394.132816)
		(end 77.74305 -393.96035)
		(width 0.14224)
		(layer "In13.Cu")
		(net "P5E_CPU1_P1_RX_BUF_DP<0>")
	)
	(segment
		(start 56.510428 -420.357808)
		(end 56.208422 -420.055802)
		(width 0.14224)
		(layer "In13.Cu")
		(net "P5E_CPU1_P1_RX_BUF_DP<0>")
	)
	(segment
		(start 55.713122 -419.560248)
		(end 55.411116 -419.258242)
		(width 0.14224)
		(layer "In13.Cu")
		(net "P5E_CPU1_P1_RX_BUF_DP<0>")
	)
	(segment
		(start 54.4195 -418.460682)
		(end 53.622956 -417.664138)
		(width 0.14224)
		(layer "In13.Cu")
		(net "P5E_CPU1_P1_RX_BUF_DP<0>")
	)
	(segment
		(start 54.915562 -418.956744)
		(end 54.915562 -418.762688)
		(width 0.14224)
		(layer "In13.Cu")
		(net "P5E_CPU1_P1_RX_BUF_DP<0>")
	)
	(segment
		(start 51.430174 -408.080464)
		(end 51.567334 -407.943304)
		(width 0.14224)
		(layer "In13.Cu")
		(net "P5E_CPU1_P1_RX_BUF_DP<0>")
	)
	(segment
		(start 50.985928 -414.833054)
		(end 50.791872 -414.833054)
		(width 0.14224)
		(layer "In13.Cu")
		(net "P5E_CPU1_P1_RX_BUF_DP<0>")
	)
	(segment
		(start 52.52339 -416.37077)
		(end 52.329588 -416.37077)
		(width 0.14224)
		(layer "In13.Cu")
		(net "P5E_CPU1_P1_RX_BUF_DP<0>")
	)
	(segment
		(start 52.021486 -405.885142)
		(end 52.297076 -405.771096)
		(width 0.14224)
		(layer "In13.Cu")
		(net "P5E_CPU1_P1_RX_BUF_DP<0>")
	)
	(segment
		(start 53.689758 -403.131782)
		(end 59.240674 -400.62277)
		(width 0.14224)
		(layer "In13.Cu")
		(net "P5E_CPU1_P1_RX_BUF_DP<0>")
	)
	(segment
		(start 49.976786 -411.712664)
		(end 51.070764 -411.259274)
		(width 0.14224)
		(layer "In13.Cu")
		(net "P5E_CPU1_P1_RX_BUF_DP<0>")
	)
	(segment
		(start 51.532028 -415.57321)
		(end 51.259232 -415.300414)
		(width 0.14224)
		(layer "In13.Cu")
		(net "P5E_CPU1_P1_RX_BUF_DP<0>")
	)
	(segment
		(start 52.297076 -405.771096)
		(end 52.612544 -405.560276)
		(width 0.14224)
		(layer "In13.Cu")
		(net "P5E_CPU1_P1_RX_BUF_DP<0>")
	)
	(segment
		(start 52.825396 -416.866578)
		(end 52.825396 -416.672776)
		(width 0.14224)
		(layer "In13.Cu")
		(net "P5E_CPU1_P1_RX_BUF_DP<0>")
	)
	(segment
		(start 58.511694 -433.756816)
		(end 58.274966 -433.756816)
		(width 0.14224)
		(layer "In13.Cu")
		(net "P5E_CPU1_P1_RX_BUF_DP<0>")
	)
	(segment
		(start 53.32095 -417.168076)
		(end 53.126894 -417.168076)
		(width 0.14224)
		(layer "In13.Cu")
		(net "P5E_CPU1_P1_RX_BUF_DP<0>")
	)
	(segment
		(start 76.606654 -394.371322)
		(end 76.782168 -394.453872)
		(width 0.14224)
		(layer "In13.Cu")
		(net "P5E_CPU1_P1_RX_BUF_DP<0>")
	)
	(arc
		(start 51.635152 -406.14346)
		(mid 51.815622 -405.995314)
		(end 52.021486 -405.885142)
		(width 0.14224)
		(layer "In13.Cu")
		(net "P5E_CPU1_P1_RX_BUF_DP<0>")
	)
	(arc
		(start 49.898554 -411.829504)
		(mid 49.919907 -411.759176)
		(end 49.976786 -411.712664)
		(width 0.14224)
		(layer "In13.Cu")
		(net "P5E_CPU1_P1_RX_BUF_DP<0>")
	)
	(arc
		(start 52.759356 -405.413464)
		(mid 52.909196 -405.189118)
		(end 52.961794 -404.924514)
		(width 0.14224)
		(layer "In13.Cu")
		(net "P5E_CPU1_P1_RX_BUF_DP<0>")
	)
	(arc
		(start 51.430174 -406.638252)
		(mid 51.483403 -406.370451)
		(end 51.635152 -406.14346)
		(width 0.14224)
		(layer "In13.Cu")
		(net "P5E_CPU1_P1_RX_BUF_DP<0>")
	)
	(arc
		(start 52.961794 -404.06193)
		(mid 52.968038 -403.99912)
		(end 52.986432 -403.93874)
		(width 0.14224)
		(layer "In13.Cu")
		(net "P5E_CPU1_P1_RX_BUF_DP<0>")
	)
	(arc
		(start 59.240674 -400.62277)
		(mid 62.733653 -399.124638)
		(end 66.282062 -397.762984)
		(width 0.14224)
		(layer "In13.Cu")
		(net "P5E_CPU1_P1_RX_BUF_DP<0>")
	)
	(arc
		(start 51.070764 -411.259274)
		(mid 51.332016 -411.044778)
		(end 51.430174 -410.721302)
		(width 0.14224)
		(layer "In13.Cu")
		(net "P5E_CPU1_P1_RX_BUF_DP<0>")
	)
	(arc
		(start 53.111654 -403.637242)
		(mid 53.142571 -403.582162)
		(end 53.185568 -403.535896)
		(width 0.14224)
		(layer "In13.Cu")
		(net "P5E_CPU1_P1_RX_BUF_DP<0>")
	)
	(arc
		(start 78.078838 -393.653518)
		(mid 78.382915 -393.426301)
		(end 78.725522 -393.262866)
		(width 0.14224)
		(layer "In13.Cu")
		(net "P5E_CPU1_P1_RX_BUF_DP<0>")
	)
	(arc
		(start 50.079148 -414.12033)
		(mid 49.945504 -413.920223)
		(end 49.898554 -413.684212)
		(width 0.14224)
		(layer "In13.Cu")
		(net "P5E_CPU1_P1_RX_BUF_DP<0>")
	)
	(arc
		(start 53.58003 -403.201124)
		(mid 53.632472 -403.162618)
		(end 53.689758 -403.131782)
		(width 0.14224)
		(layer "In13.Cu")
		(net "P5E_CPU1_P1_RX_BUF_DP<0>")
	)
	(arc
		(start 57.490106 -422.029636)
		(mid 57.398552 -421.569275)
		(end 57.137808 -421.17899)
		(width 0.14224)
		(layer "In13.Cu")
		(net "P5E_CPU1_P1_RX_BUF_DP<0>")
	)
	(segment
		(start 90.746326 -390.761982)
		(end 90.746326 -391.578338)
		(width 0.1016)
		(layer "F.Cu")
		(net "P5E_CPU1_P1_RX_BUF_DN<9>")
	)
	(segment
		(start 91.003628 -392.761216)
		(end 91.144344 -392.6205)
		(width 0.1016)
		(layer "F.Cu")
		(net "P5E_CPU1_P1_RX_BUF_DN<9>")
	)
	(segment
		(start 90.745818 -390.761474)
		(end 90.746326 -390.761982)
		(width 0.1016)
		(layer "F.Cu")
		(net "P5E_CPU1_P1_RX_BUF_DN<9>")
	)
	(segment
		(start 90.675206 -391.649458)
		(end 90.675206 -392.634216)
		(width 0.1016)
		(layer "F.Cu")
		(net "P5E_CPU1_P1_RX_BUF_DN<9>")
	)
	(segment
		(start 90.802206 -392.761216)
		(end 91.003628 -392.761216)
		(width 0.1016)
		(layer "F.Cu")
		(net "P5E_CPU1_P1_RX_BUF_DN<9>")
	)
	(segment
		(start 90.746326 -391.578338)
		(end 90.675206 -391.649458)
		(width 0.1016)
		(layer "F.Cu")
		(net "P5E_CPU1_P1_RX_BUF_DN<9>")
	)
	(segment
		(start 91.144344 -392.6205)
		(end 91.144344 -392.429238)
		(width 0.1016)
		(layer "F.Cu")
		(net "P5E_CPU1_P1_RX_BUF_DN<9>")
	)
	(segment
		(start 90.675206 -392.634216)
		(end 90.802206 -392.761216)
		(width 0.1016)
		(layer "F.Cu")
		(net "P5E_CPU1_P1_RX_BUF_DN<9>")
	)
	(segment
		(start 80.446626 -403.59838)
		(end 81.170018 -402.873718)
		(width 0.14224)
		(layer "In13.Cu")
		(net "P5E_CPU1_P1_RX_BUF_DN<9>")
	)
	(segment
		(start 88.216486 -398.211548)
		(end 90.058494 -395.967458)
		(width 0.14224)
		(layer "In13.Cu")
		(net "P5E_CPU1_P1_RX_BUF_DN<9>")
	)
	(segment
		(start 80.249014 -404.924514)
		(end 80.249014 -404.076154)
		(width 0.14224)
		(layer "In13.Cu")
		(net "P5E_CPU1_P1_RX_BUF_DN<9>")
	)
	(segment
		(start 78.50378 -410.988256)
		(end 78.67142 -410.812234)
		(width 0.14224)
		(layer "In13.Cu")
		(net "P5E_CPU1_P1_RX_BUF_DN<9>")
	)
	(segment
		(start 77.523086 -435.038754)
		(end 77.158342 -435.038754)
		(width 0.14224)
		(layer "In13.Cu")
		(net "P5E_CPU1_P1_RX_BUF_DN<9>")
	)
	(segment
		(start 76.694538 -434.57495)
		(end 76.694538 -426.995336)
		(width 0.14224)
		(layer "In13.Cu")
		(net "P5E_CPU1_P1_RX_BUF_DN<9>")
	)
	(segment
		(start 91.144344 -392.597386)
		(end 91.144344 -392.429238)
		(width 0.14224)
		(layer "In13.Cu")
		(net "P5E_CPU1_P1_RX_BUF_DN<9>")
	)
	(segment
		(start 86.227412 -400.200114)
		(end 88.216486 -398.211548)
		(width 0.14224)
		(layer "In13.Cu")
		(net "P5E_CPU1_P1_RX_BUF_DN<9>")
	)
	(segment
		(start 79.482696 -405.624538)
		(end 79.732632 -405.52116)
		(width 0.14224)
		(layer "In13.Cu")
		(net "P5E_CPU1_P1_RX_BUF_DN<9>")
	)
	(segment
		(start 76.694538 -426.995336)
		(end 76.689204 -426.990002)
		(width 0.14224)
		(layer "In13.Cu")
		(net "P5E_CPU1_P1_RX_BUF_DN<9>")
	)
	(segment
		(start 80.001872 -405.341328)
		(end 80.129126 -405.214074)
		(width 0.14224)
		(layer "In13.Cu")
		(net "P5E_CPU1_P1_RX_BUF_DN<9>")
	)
	(segment
		(start 77.447394 -411.454346)
		(end 78.400148 -411.059376)
		(width 0.14224)
		(layer "In13.Cu")
		(net "P5E_CPU1_P1_RX_BUF_DN<9>")
	)
	(segment
		(start 79.732632 -405.52116)
		(end 80.001872 -405.341328)
		(width 0.14224)
		(layer "In13.Cu")
		(net "P5E_CPU1_P1_RX_BUF_DN<9>")
	)
	(segment
		(start 91.005914 -392.735816)
		(end 91.144344 -392.597386)
		(width 0.14224)
		(layer "In13.Cu")
		(net "P5E_CPU1_P1_RX_BUF_DN<9>")
	)
	(segment
		(start 84.649818 -401.309586)
		(end 84.94014 -401.144994)
		(width 0.14224)
		(layer "In13.Cu")
		(net "P5E_CPU1_P1_RX_BUF_DN<9>")
	)
	(segment
		(start 77.185774 -413.863282)
		(end 77.185774 -411.845506)
		(width 0.14224)
		(layer "In13.Cu")
		(net "P5E_CPU1_P1_RX_BUF_DN<9>")
	)
	(segment
		(start 77.650086 -435.489858)
		(end 77.650086 -435.165754)
		(width 0.14224)
		(layer "In13.Cu")
		(net "P5E_CPU1_P1_RX_BUF_DN<9>")
	)
	(segment
		(start 90.710766 -392.735816)
		(end 91.005914 -392.735816)
		(width 0.14224)
		(layer "In13.Cu")
		(net "P5E_CPU1_P1_RX_BUF_DN<9>")
	)
	(segment
		(start 78.717394 -410.697426)
		(end 78.717394 -406.638252)
		(width 0.14224)
		(layer "In13.Cu")
		(net "P5E_CPU1_P1_RX_BUF_DN<9>")
	)
	(segment
		(start 77.650086 -435.165754)
		(end 77.523086 -435.038754)
		(width 0.14224)
		(layer "In13.Cu")
		(net "P5E_CPU1_P1_RX_BUF_DN<9>")
	)
	(segment
		(start 85.046058 -401.075906)
		(end 86.227412 -400.200114)
		(width 0.14224)
		(layer "In13.Cu")
		(net "P5E_CPU1_P1_RX_BUF_DN<9>")
	)
	(segment
		(start 77.158342 -435.038754)
		(end 76.694538 -434.57495)
		(width 0.14224)
		(layer "In13.Cu")
		(net "P5E_CPU1_P1_RX_BUF_DN<9>")
	)
	(segment
		(start 90.403426 -393.043156)
		(end 90.710766 -392.735816)
		(width 0.14224)
		(layer "In13.Cu")
		(net "P5E_CPU1_P1_RX_BUF_DN<9>")
	)
	(segment
		(start 81.61782 -402.573998)
		(end 84.536026 -401.364958)
		(width 0.14224)
		(layer "In13.Cu")
		(net "P5E_CPU1_P1_RX_BUF_DN<9>")
	)
	(segment
		(start 76.689204 -426.990002)
		(end 76.689204 -415.062162)
		(width 0.14224)
		(layer "In13.Cu")
		(net "P5E_CPU1_P1_RX_BUF_DN<9>")
	)
	(segment
		(start 90.058494 -395.967458)
		(end 90.38209 -395.483842)
		(width 0.14224)
		(layer "In13.Cu")
		(net "P5E_CPU1_P1_RX_BUF_DN<9>")
	)
	(segment
		(start 90.403426 -395.413484)
		(end 90.403426 -393.043156)
		(width 0.14224)
		(layer "In13.Cu")
		(net "P5E_CPU1_P1_RX_BUF_DN<9>")
	)
	(arc
		(start 90.38209 -395.483842)
		(mid 90.397935 -395.450237)
		(end 90.403426 -395.413484)
		(width 0.14224)
		(layer "In13.Cu")
		(net "P5E_CPU1_P1_RX_BUF_DN<9>")
	)
	(arc
		(start 79.004922 -405.94407)
		(mid 79.228087 -405.760796)
		(end 79.482696 -405.624538)
		(width 0.14224)
		(layer "In13.Cu")
		(net "P5E_CPU1_P1_RX_BUF_DN<9>")
	)
	(arc
		(start 81.170018 -402.873718)
		(mid 81.379119 -402.701744)
		(end 81.61782 -402.573998)
		(width 0.14224)
		(layer "In13.Cu")
		(net "P5E_CPU1_P1_RX_BUF_DN<9>")
	)
	(arc
		(start 84.536026 -401.364958)
		(mid 84.593773 -401.339022)
		(end 84.649818 -401.309586)
		(width 0.14224)
		(layer "In13.Cu")
		(net "P5E_CPU1_P1_RX_BUF_DN<9>")
	)
	(arc
		(start 76.981558 -414.356296)
		(mid 77.132698 -414.130099)
		(end 77.185774 -413.863282)
		(width 0.14224)
		(layer "In13.Cu")
		(net "P5E_CPU1_P1_RX_BUF_DN<9>")
	)
	(arc
		(start 80.129126 -405.214074)
		(mid 80.217841 -405.081209)
		(end 80.249014 -404.924514)
		(width 0.14224)
		(layer "In13.Cu")
		(net "P5E_CPU1_P1_RX_BUF_DN<9>")
	)
	(arc
		(start 76.689204 -415.062162)
		(mid 76.765189 -414.68016)
		(end 76.981558 -414.356296)
		(width 0.14224)
		(layer "In13.Cu")
		(net "P5E_CPU1_P1_RX_BUF_DN<9>")
	)
	(arc
		(start 78.717394 -406.638252)
		(mid 78.792084 -406.262557)
		(end 79.004922 -405.94407)
		(width 0.14224)
		(layer "In13.Cu")
		(net "P5E_CPU1_P1_RX_BUF_DN<9>")
	)
	(arc
		(start 78.67142 -410.812234)
		(mid 78.705467 -410.75926)
		(end 78.717394 -410.697426)
		(width 0.14224)
		(layer "In13.Cu")
		(net "P5E_CPU1_P1_RX_BUF_DN<9>")
	)
	(arc
		(start 84.94014 -401.144994)
		(mid 84.994154 -401.112067)
		(end 85.046058 -401.075906)
		(width 0.14224)
		(layer "In13.Cu")
		(net "P5E_CPU1_P1_RX_BUF_DN<9>")
	)
	(arc
		(start 77.185774 -411.845506)
		(mid 77.257266 -411.610245)
		(end 77.447394 -411.454346)
		(width 0.14224)
		(layer "In13.Cu")
		(net "P5E_CPU1_P1_RX_BUF_DN<9>")
	)
	(arc
		(start 78.400148 -411.059376)
		(mid 78.455686 -411.02924)
		(end 78.50378 -410.988256)
		(width 0.14224)
		(layer "In13.Cu")
		(net "P5E_CPU1_P1_RX_BUF_DN<9>")
	)
	(arc
		(start 80.249014 -404.076154)
		(mid 80.30038 -403.817652)
		(end 80.446626 -403.59838)
		(width 0.14224)
		(layer "In13.Cu")
		(net "P5E_CPU1_P1_RX_BUF_DN<9>")
	)
	(segment
		(start 89.944448 -392.620246)
		(end 89.803478 -392.761216)
		(width 0.1016)
		(layer "F.Cu")
		(net "P5E_CPU1_P1_RX_BUF_DN<8>")
	)
	(segment
		(start 89.58453 -392.761216)
		(end 89.45753 -392.634216)
		(width 0.1016)
		(layer "F.Cu")
		(net "P5E_CPU1_P1_RX_BUF_DN<8>")
	)
	(segment
		(start 89.803478 -392.761216)
		(end 89.58453 -392.761216)
		(width 0.1016)
		(layer "F.Cu")
		(net "P5E_CPU1_P1_RX_BUF_DN<8>")
	)
	(segment
		(start 89.546176 -391.578338)
		(end 89.546176 -390.761982)
		(width 0.1016)
		(layer "F.Cu")
		(net "P5E_CPU1_P1_RX_BUF_DN<8>")
	)
	(segment
		(start 89.45753 -392.634216)
		(end 89.45753 -391.666984)
		(width 0.1016)
		(layer "F.Cu")
		(net "P5E_CPU1_P1_RX_BUF_DN<8>")
	)
	(segment
		(start 89.45753 -391.666984)
		(end 89.546176 -391.578338)
		(width 0.1016)
		(layer "F.Cu")
		(net "P5E_CPU1_P1_RX_BUF_DN<8>")
	)
	(segment
		(start 89.546176 -390.761982)
		(end 89.545668 -390.761474)
		(width 0.1016)
		(layer "F.Cu")
		(net "P5E_CPU1_P1_RX_BUF_DN<8>")
	)
	(segment
		(start 89.944448 -392.429238)
		(end 89.944448 -392.620246)
		(width 0.1016)
		(layer "F.Cu")
		(net "P5E_CPU1_P1_RX_BUF_DN<8>")
	)
	(segment
		(start 89.009474 -395.442186)
		(end 89.180416 -395.199362)
		(width 0.14224)
		(layer "In13.Cu")
		(net "P5E_CPU1_P1_RX_BUF_DN<8>")
	)
	(segment
		(start 89.20353 -395.126464)
		(end 89.20353 -393.043156)
		(width 0.14224)
		(layer "In13.Cu")
		(net "P5E_CPU1_P1_RX_BUF_DN<8>")
	)
	(segment
		(start 86.259162 -398.843754)
		(end 87.85225 -397.085566)
		(width 0.14224)
		(layer "In13.Cu")
		(net "P5E_CPU1_P1_RX_BUF_DN<8>")
	)
	(segment
		(start 75.65009 -434.48986)
		(end 75.65009 -434.165756)
		(width 0.14224)
		(layer "In13.Cu")
		(net "P5E_CPU1_P1_RX_BUF_DN<8>")
	)
	(segment
		(start 89.20353 -393.043156)
		(end 89.51087 -392.735816)
		(width 0.14224)
		(layer "In13.Cu")
		(net "P5E_CPU1_P1_RX_BUF_DN<8>")
	)
	(segment
		(start 79.01178 -402.4757)
		(end 81.169002 -401.58162)
		(width 0.14224)
		(layer "In13.Cu")
		(net "P5E_CPU1_P1_RX_BUF_DN<8>")
	)
	(segment
		(start 75.52309 -434.038756)
		(end 75.158346 -434.038756)
		(width 0.14224)
		(layer "In13.Cu")
		(net "P5E_CPU1_P1_RX_BUF_DN<8>")
	)
	(segment
		(start 81.699354 -401.36191)
		(end 83.112356 -400.933666)
		(width 0.14224)
		(layer "In13.Cu")
		(net "P5E_CPU1_P1_RX_BUF_DN<8>")
	)
	(segment
		(start 74.384154 -411.454346)
		(end 75.336908 -411.059376)
		(width 0.14224)
		(layer "In13.Cu")
		(net "P5E_CPU1_P1_RX_BUF_DN<8>")
	)
	(segment
		(start 75.65009 -434.165756)
		(end 75.52309 -434.038756)
		(width 0.14224)
		(layer "In13.Cu")
		(net "P5E_CPU1_P1_RX_BUF_DN<8>")
	)
	(segment
		(start 75.654154 -410.697426)
		(end 75.654154 -406.638252)
		(width 0.14224)
		(layer "In13.Cu")
		(net "P5E_CPU1_P1_RX_BUF_DN<8>")
	)
	(segment
		(start 77.185774 -404.924514)
		(end 77.185774 -404.05558)
		(width 0.14224)
		(layer "In13.Cu")
		(net "P5E_CPU1_P1_RX_BUF_DN<8>")
	)
	(segment
		(start 81.169256 -401.58162)
		(end 81.699354 -401.36191)
		(width 0.14224)
		(layer "In13.Cu")
		(net "P5E_CPU1_P1_RX_BUF_DN<8>")
	)
	(segment
		(start 89.806018 -392.735816)
		(end 89.944448 -392.597386)
		(width 0.14224)
		(layer "In13.Cu")
		(net "P5E_CPU1_P1_RX_BUF_DN<8>")
	)
	(segment
		(start 76.669392 -405.52116)
		(end 76.938632 -405.341328)
		(width 0.14224)
		(layer "In13.Cu")
		(net "P5E_CPU1_P1_RX_BUF_DN<8>")
	)
	(segment
		(start 89.51087 -392.735816)
		(end 89.806018 -392.735816)
		(width 0.14224)
		(layer "In13.Cu")
		(net "P5E_CPU1_P1_RX_BUF_DN<8>")
	)
	(segment
		(start 89.944448 -392.597386)
		(end 89.944448 -392.429238)
		(width 0.14224)
		(layer "In13.Cu")
		(net "P5E_CPU1_P1_RX_BUF_DN<8>")
	)
	(segment
		(start 81.169002 -401.58162)
		(end 81.169256 -401.58162)
		(width 0.14224)
		(layer "In13.Cu")
		(net "P5E_CPU1_P1_RX_BUF_DN<8>")
	)
	(segment
		(start 74.122534 -433.002944)
		(end 74.122534 -411.84576)
		(width 0.14224)
		(layer "In13.Cu")
		(net "P5E_CPU1_P1_RX_BUF_DN<8>")
	)
	(segment
		(start 76.938632 -405.341328)
		(end 77.065886 -405.214074)
		(width 0.14224)
		(layer "In13.Cu")
		(net "P5E_CPU1_P1_RX_BUF_DN<8>")
	)
	(segment
		(start 89.00922 -395.44244)
		(end 89.009474 -395.442186)
		(width 0.14224)
		(layer "In13.Cu")
		(net "P5E_CPU1_P1_RX_BUF_DN<8>")
	)
	(segment
		(start 75.44054 -410.988256)
		(end 75.60818 -410.812234)
		(width 0.14224)
		(layer "In13.Cu")
		(net "P5E_CPU1_P1_RX_BUF_DN<8>")
	)
	(segment
		(start 84.677504 -400.158458)
		(end 86.259162 -398.843754)
		(width 0.14224)
		(layer "In13.Cu")
		(net "P5E_CPU1_P1_RX_BUF_DN<8>")
	)
	(segment
		(start 76.419456 -405.624538)
		(end 76.669392 -405.52116)
		(width 0.14224)
		(layer "In13.Cu")
		(net "P5E_CPU1_P1_RX_BUF_DN<8>")
	)
	(segment
		(start 75.158346 -434.038756)
		(end 74.122534 -433.002944)
		(width 0.14224)
		(layer "In13.Cu")
		(net "P5E_CPU1_P1_RX_BUF_DN<8>")
	)
	(segment
		(start 87.85225 -397.085566)
		(end 89.00922 -395.44244)
		(width 0.14224)
		(layer "In13.Cu")
		(net "P5E_CPU1_P1_RX_BUF_DN<8>")
	)
	(segment
		(start 84.339684 -400.400774)
		(end 84.677504 -400.158458)
		(width 0.14224)
		(layer "In13.Cu")
		(net "P5E_CPU1_P1_RX_BUF_DN<8>")
	)
	(segment
		(start 83.112356 -400.933666)
		(end 84.339684 -400.400774)
		(width 0.14224)
		(layer "In13.Cu")
		(net "P5E_CPU1_P1_RX_BUF_DN<8>")
	)
	(arc
		(start 75.941682 -405.94407)
		(mid 76.164847 -405.760796)
		(end 76.419456 -405.624538)
		(width 0.14224)
		(layer "In13.Cu")
		(net "P5E_CPU1_P1_RX_BUF_DN<8>")
	)
	(arc
		(start 89.180416 -395.199362)
		(mid 89.197617 -395.164698)
		(end 89.20353 -395.126464)
		(width 0.14224)
		(layer "In13.Cu")
		(net "P5E_CPU1_P1_RX_BUF_DN<8>")
	)
	(arc
		(start 77.065886 -405.214074)
		(mid 77.154601 -405.081209)
		(end 77.185774 -404.924514)
		(width 0.14224)
		(layer "In13.Cu")
		(net "P5E_CPU1_P1_RX_BUF_DN<8>")
	)
	(arc
		(start 75.60818 -410.812234)
		(mid 75.642227 -410.75926)
		(end 75.654154 -410.697426)
		(width 0.14224)
		(layer "In13.Cu")
		(net "P5E_CPU1_P1_RX_BUF_DN<8>")
	)
	(arc
		(start 75.654154 -406.638252)
		(mid 75.728844 -406.262557)
		(end 75.941682 -405.94407)
		(width 0.14224)
		(layer "In13.Cu")
		(net "P5E_CPU1_P1_RX_BUF_DN<8>")
	)
	(arc
		(start 77.185774 -404.05558)
		(mid 77.23865 -403.789845)
		(end 77.389228 -403.564598)
		(width 0.14224)
		(layer "In13.Cu")
		(net "P5E_CPU1_P1_RX_BUF_DN<8>")
	)
	(arc
		(start 77.389228 -403.564598)
		(mid 78.157587 -402.956198)
		(end 79.01178 -402.4757)
		(width 0.14224)
		(layer "In13.Cu")
		(net "P5E_CPU1_P1_RX_BUF_DN<8>")
	)
	(arc
		(start 74.122534 -411.84576)
		(mid 74.193955 -411.610351)
		(end 74.384154 -411.454346)
		(width 0.14224)
		(layer "In13.Cu")
		(net "P5E_CPU1_P1_RX_BUF_DN<8>")
	)
	(arc
		(start 75.336908 -411.059376)
		(mid 75.392446 -411.02924)
		(end 75.44054 -410.988256)
		(width 0.14224)
		(layer "In13.Cu")
		(net "P5E_CPU1_P1_RX_BUF_DN<8>")
	)
	(segment
		(start 88.257634 -391.666984)
		(end 88.257634 -392.634216)
		(width 0.1016)
		(layer "F.Cu")
		(net "P5E_CPU1_P1_RX_BUF_DN<7>")
	)
	(segment
		(start 88.34628 -390.761982)
		(end 88.34628 -391.578338)
		(width 0.1016)
		(layer "F.Cu")
		(net "P5E_CPU1_P1_RX_BUF_DN<7>")
	)
	(segment
		(start 88.34628 -391.578338)
		(end 88.257634 -391.666984)
		(width 0.1016)
		(layer "F.Cu")
		(net "P5E_CPU1_P1_RX_BUF_DN<7>")
	)
	(segment
		(start 88.384634 -392.761216)
		(end 88.603582 -392.761216)
		(width 0.1016)
		(layer "F.Cu")
		(net "P5E_CPU1_P1_RX_BUF_DN<7>")
	)
	(segment
		(start 88.257634 -392.634216)
		(end 88.384634 -392.761216)
		(width 0.1016)
		(layer "F.Cu")
		(net "P5E_CPU1_P1_RX_BUF_DN<7>")
	)
	(segment
		(start 88.603582 -392.761216)
		(end 88.744298 -392.6205)
		(width 0.1016)
		(layer "F.Cu")
		(net "P5E_CPU1_P1_RX_BUF_DN<7>")
	)
	(segment
		(start 88.744298 -392.6205)
		(end 88.744298 -392.429238)
		(width 0.1016)
		(layer "F.Cu")
		(net "P5E_CPU1_P1_RX_BUF_DN<7>")
	)
	(segment
		(start 88.345772 -390.761474)
		(end 88.34628 -390.761982)
		(width 0.1016)
		(layer "F.Cu")
		(net "P5E_CPU1_P1_RX_BUF_DN<7>")
	)
	(segment
		(start 73.875392 -405.341328)
		(end 74.002646 -405.214074)
		(width 0.14224)
		(layer "In13.Cu")
		(net "P5E_CPU1_P1_RX_BUF_DN<7>")
	)
	(segment
		(start 74.398378 -403.454616)
		(end 74.5617 -403.291294)
		(width 0.14224)
		(layer "In13.Cu")
		(net "P5E_CPU1_P1_RX_BUF_DN<7>")
	)
	(segment
		(start 72.649842 -435.165754)
		(end 72.522842 -435.038754)
		(width 0.14224)
		(layer "In13.Cu")
		(net "P5E_CPU1_P1_RX_BUF_DN<7>")
	)
	(segment
		(start 72.158098 -435.038754)
		(end 71.694294 -434.57495)
		(width 0.14224)
		(layer "In13.Cu")
		(net "P5E_CPU1_P1_RX_BUF_DN<7>")
	)
	(segment
		(start 84.108544 -399.267934)
		(end 84.750148 -398.839436)
		(width 0.14224)
		(layer "In13.Cu")
		(net "P5E_CPU1_P1_RX_BUF_DN<7>")
	)
	(segment
		(start 72.590914 -410.51353)
		(end 72.590914 -406.643332)
		(width 0.14224)
		(layer "In13.Cu")
		(net "P5E_CPU1_P1_RX_BUF_DN<7>")
	)
	(segment
		(start 72.649842 -435.489858)
		(end 72.649842 -435.165754)
		(width 0.14224)
		(layer "In13.Cu")
		(net "P5E_CPU1_P1_RX_BUF_DN<7>")
	)
	(segment
		(start 88.605868 -392.735816)
		(end 88.744298 -392.597386)
		(width 0.14224)
		(layer "In13.Cu")
		(net "P5E_CPU1_P1_RX_BUF_DN<7>")
	)
	(segment
		(start 84.750148 -398.839436)
		(end 85.072728 -398.574514)
		(width 0.14224)
		(layer "In13.Cu")
		(net "P5E_CPU1_P1_RX_BUF_DN<7>")
	)
	(segment
		(start 71.405242 -411.4038)
		(end 72.250554 -411.05328)
		(width 0.14224)
		(layer "In13.Cu")
		(net "P5E_CPU1_P1_RX_BUF_DN<7>")
	)
	(segment
		(start 71.059294 -413.223964)
		(end 71.059294 -411.922214)
		(width 0.14224)
		(layer "In13.Cu")
		(net "P5E_CPU1_P1_RX_BUF_DN<7>")
	)
	(segment
		(start 73.247504 -405.670766)
		(end 73.60539 -405.521922)
		(width 0.14224)
		(layer "In13.Cu")
		(net "P5E_CPU1_P1_RX_BUF_DN<7>")
	)
	(segment
		(start 85.072728 -398.574514)
		(end 85.077046 -398.57045)
		(width 0.14224)
		(layer "In13.Cu")
		(net "P5E_CPU1_P1_RX_BUF_DN<7>")
	)
	(segment
		(start 74.122534 -404.924514)
		(end 74.122534 -404.120604)
		(width 0.14224)
		(layer "In13.Cu")
		(net "P5E_CPU1_P1_RX_BUF_DN<7>")
	)
	(segment
		(start 82.045302 -400.121374)
		(end 84.108544 -399.267934)
		(width 0.14224)
		(layer "In13.Cu")
		(net "P5E_CPU1_P1_RX_BUF_DN<7>")
	)
	(segment
		(start 80.837278 -400.373088)
		(end 82.045302 -400.121374)
		(width 0.14224)
		(layer "In13.Cu")
		(net "P5E_CPU1_P1_RX_BUF_DN<7>")
	)
	(segment
		(start 71.694294 -434.57495)
		(end 71.694294 -426.995082)
		(width 0.14224)
		(layer "In13.Cu")
		(net "P5E_CPU1_P1_RX_BUF_DN<7>")
	)
	(segment
		(start 87.532718 -395.886686)
		(end 87.822532 -395.453362)
		(width 0.14224)
		(layer "In13.Cu")
		(net "P5E_CPU1_P1_RX_BUF_DN<7>")
	)
	(segment
		(start 87.822532 -395.453362)
		(end 87.994236 -394.767308)
		(width 0.14224)
		(layer "In13.Cu")
		(net "P5E_CPU1_P1_RX_BUF_DN<7>")
	)
	(segment
		(start 87.994236 -394.767308)
		(end 87.994236 -393.0523)
		(width 0.14224)
		(layer "In13.Cu")
		(net "P5E_CPU1_P1_RX_BUF_DN<7>")
	)
	(segment
		(start 72.73036 -406.218898)
		(end 72.978772 -405.881586)
		(width 0.14224)
		(layer "In13.Cu")
		(net "P5E_CPU1_P1_RX_BUF_DN<7>")
	)
	(segment
		(start 71.694294 -426.995082)
		(end 71.689214 -426.990002)
		(width 0.14224)
		(layer "In13.Cu")
		(net "P5E_CPU1_P1_RX_BUF_DN<7>")
	)
	(segment
		(start 73.60539 -405.521922)
		(end 73.875392 -405.341328)
		(width 0.14224)
		(layer "In13.Cu")
		(net "P5E_CPU1_P1_RX_BUF_DN<7>")
	)
	(segment
		(start 72.522842 -435.038754)
		(end 72.158098 -435.038754)
		(width 0.14224)
		(layer "In13.Cu")
		(net "P5E_CPU1_P1_RX_BUF_DN<7>")
	)
	(segment
		(start 85.077046 -398.57045)
		(end 87.532718 -395.886686)
		(width 0.14224)
		(layer "In13.Cu")
		(net "P5E_CPU1_P1_RX_BUF_DN<7>")
	)
	(segment
		(start 75.301094 -402.787104)
		(end 80.837278 -400.373088)
		(width 0.14224)
		(layer "In13.Cu")
		(net "P5E_CPU1_P1_RX_BUF_DN<7>")
	)
	(segment
		(start 72.345804 -410.972762)
		(end 72.555354 -410.637736)
		(width 0.14224)
		(layer "In13.Cu")
		(net "P5E_CPU1_P1_RX_BUF_DN<7>")
	)
	(segment
		(start 87.994236 -393.0523)
		(end 88.31072 -392.735816)
		(width 0.14224)
		(layer "In13.Cu")
		(net "P5E_CPU1_P1_RX_BUF_DN<7>")
	)
	(segment
		(start 71.689214 -426.990002)
		(end 71.689214 -414.076642)
		(width 0.14224)
		(layer "In13.Cu")
		(net "P5E_CPU1_P1_RX_BUF_DN<7>")
	)
	(segment
		(start 88.744298 -392.597386)
		(end 88.744298 -392.429238)
		(width 0.14224)
		(layer "In13.Cu")
		(net "P5E_CPU1_P1_RX_BUF_DN<7>")
	)
	(segment
		(start 88.31072 -392.735816)
		(end 88.605868 -392.735816)
		(width 0.14224)
		(layer "In13.Cu")
		(net "P5E_CPU1_P1_RX_BUF_DN<7>")
	)
	(segment
		(start 71.651876 -413.986472)
		(end 71.179436 -413.514032)
		(width 0.14224)
		(layer "In13.Cu")
		(net "P5E_CPU1_P1_RX_BUF_DN<7>")
	)
	(arc
		(start 72.250554 -411.05328)
		(mid 72.30444 -411.020435)
		(end 72.345804 -410.972762)
		(width 0.14224)
		(layer "In13.Cu")
		(net "P5E_CPU1_P1_RX_BUF_DN<7>")
	)
	(arc
		(start 74.5617 -403.291294)
		(mid 74.90773 -403.004492)
		(end 75.301094 -402.787104)
		(width 0.14224)
		(layer "In13.Cu")
		(net "P5E_CPU1_P1_RX_BUF_DN<7>")
	)
	(arc
		(start 74.122534 -404.120604)
		(mid 74.194227 -403.76018)
		(end 74.398378 -403.454616)
		(width 0.14224)
		(layer "In13.Cu")
		(net "P5E_CPU1_P1_RX_BUF_DN<7>")
	)
	(arc
		(start 72.555354 -410.637736)
		(mid 72.581841 -410.57813)
		(end 72.590914 -410.51353)
		(width 0.14224)
		(layer "In13.Cu")
		(net "P5E_CPU1_P1_RX_BUF_DN<7>")
	)
	(arc
		(start 74.002646 -405.214074)
		(mid 74.091361 -405.081209)
		(end 74.122534 -404.924514)
		(width 0.14224)
		(layer "In13.Cu")
		(net "P5E_CPU1_P1_RX_BUF_DN<7>")
	)
	(arc
		(start 71.059294 -411.922214)
		(mid 71.153728 -411.610603)
		(end 71.405242 -411.4038)
		(width 0.14224)
		(layer "In13.Cu")
		(net "P5E_CPU1_P1_RX_BUF_DN<7>")
	)
	(arc
		(start 71.689214 -414.076642)
		(mid 71.679508 -414.027847)
		(end 71.651876 -413.986472)
		(width 0.14224)
		(layer "In13.Cu")
		(net "P5E_CPU1_P1_RX_BUF_DN<7>")
	)
	(arc
		(start 72.590914 -406.643332)
		(mid 72.626614 -406.41993)
		(end 72.73036 -406.218898)
		(width 0.14224)
		(layer "In13.Cu")
		(net "P5E_CPU1_P1_RX_BUF_DN<7>")
	)
	(arc
		(start 71.179436 -413.514032)
		(mid 71.090566 -413.380933)
		(end 71.059294 -413.223964)
		(width 0.14224)
		(layer "In13.Cu")
		(net "P5E_CPU1_P1_RX_BUF_DN<7>")
	)
	(arc
		(start 72.978772 -405.881586)
		(mid 73.098794 -405.757887)
		(end 73.247504 -405.670766)
		(width 0.14224)
		(layer "In13.Cu")
		(net "P5E_CPU1_P1_RX_BUF_DN<7>")
	)
	(segment
		(start 87.146384 -391.365486)
		(end 87.14613 -391.36574)
		(width 0.1016)
		(layer "F.Cu")
		(net "P5E_CPU1_P1_RX_BUF_DN<6>")
	)
	(segment
		(start 87.14613 -391.578338)
		(end 87.066374 -391.658094)
		(width 0.1016)
		(layer "F.Cu")
		(net "P5E_CPU1_P1_RX_BUF_DN<6>")
	)
	(segment
		(start 87.544402 -392.6205)
		(end 87.544402 -392.429238)
		(width 0.1016)
		(layer "F.Cu")
		(net "P5E_CPU1_P1_RX_BUF_DN<6>")
	)
	(segment
		(start 87.066374 -392.634216)
		(end 87.193374 -392.761216)
		(width 0.1016)
		(layer "F.Cu")
		(net "P5E_CPU1_P1_RX_BUF_DN<6>")
	)
	(segment
		(start 87.193374 -392.761216)
		(end 87.403686 -392.761216)
		(width 0.1016)
		(layer "F.Cu")
		(net "P5E_CPU1_P1_RX_BUF_DN<6>")
	)
	(segment
		(start 87.146384 -390.761982)
		(end 87.146384 -391.365486)
		(width 0.1016)
		(layer "F.Cu")
		(net "P5E_CPU1_P1_RX_BUF_DN<6>")
	)
	(segment
		(start 87.14613 -391.36574)
		(end 87.14613 -391.578338)
		(width 0.1016)
		(layer "F.Cu")
		(net "P5E_CPU1_P1_RX_BUF_DN<6>")
	)
	(segment
		(start 87.403686 -392.761216)
		(end 87.544402 -392.6205)
		(width 0.1016)
		(layer "F.Cu")
		(net "P5E_CPU1_P1_RX_BUF_DN<6>")
	)
	(segment
		(start 87.145876 -390.761474)
		(end 87.146384 -390.761982)
		(width 0.1016)
		(layer "F.Cu")
		(net "P5E_CPU1_P1_RX_BUF_DN<6>")
	)
	(segment
		(start 87.066374 -391.658094)
		(end 87.066374 -392.634216)
		(width 0.1016)
		(layer "F.Cu")
		(net "P5E_CPU1_P1_RX_BUF_DN<6>")
	)
	(segment
		(start 69.694298 -433.574952)
		(end 69.694298 -426.995082)
		(width 0.14224)
		(layer "In13.Cu")
		(net "P5E_CPU1_P1_RX_BUF_DN<6>")
	)
	(segment
		(start 78.341728 -400.29638)
		(end 83.475068 -398.401794)
		(width 0.14224)
		(layer "In13.Cu")
		(net "P5E_CPU1_P1_RX_BUF_DN<6>")
	)
	(segment
		(start 69.694298 -426.995082)
		(end 69.689218 -426.990002)
		(width 0.14224)
		(layer "In13.Cu")
		(net "P5E_CPU1_P1_RX_BUF_DN<6>")
	)
	(segment
		(start 70.649846 -434.48986)
		(end 70.649846 -434.165756)
		(width 0.14224)
		(layer "In13.Cu")
		(net "P5E_CPU1_P1_RX_BUF_DN<6>")
	)
	(segment
		(start 78.339188 -400.297396)
		(end 78.341728 -400.29638)
		(width 0.14224)
		(layer "In13.Cu")
		(net "P5E_CPU1_P1_RX_BUF_DN<6>")
	)
	(segment
		(start 72.202548 -402.923248)
		(end 77.43698 -400.67992)
		(width 0.14224)
		(layer "In13.Cu")
		(net "P5E_CPU1_P1_RX_BUF_DN<6>")
	)
	(segment
		(start 70.542912 -405.52116)
		(end 70.812152 -405.341328)
		(width 0.14224)
		(layer "In13.Cu")
		(net "P5E_CPU1_P1_RX_BUF_DN<6>")
	)
	(segment
		(start 87.405972 -392.735816)
		(end 87.544402 -392.597386)
		(width 0.14224)
		(layer "In13.Cu")
		(net "P5E_CPU1_P1_RX_BUF_DN<6>")
	)
	(segment
		(start 86.395306 -395.673072)
		(end 86.781894 -395.09446)
		(width 0.14224)
		(layer "In13.Cu")
		(net "P5E_CPU1_P1_RX_BUF_DN<6>")
	)
	(segment
		(start 70.649846 -434.165756)
		(end 70.522846 -434.038756)
		(width 0.14224)
		(layer "In13.Cu")
		(net "P5E_CPU1_P1_RX_BUF_DN<6>")
	)
	(segment
		(start 84.37245 -397.803624)
		(end 85.901784 -396.27429)
		(width 0.14224)
		(layer "In13.Cu")
		(net "P5E_CPU1_P1_RX_BUF_DN<6>")
	)
	(segment
		(start 70.292976 -405.624538)
		(end 70.542912 -405.52116)
		(width 0.14224)
		(layer "In13.Cu")
		(net "P5E_CPU1_P1_RX_BUF_DN<6>")
	)
	(segment
		(start 86.803484 -393.043156)
		(end 87.110824 -392.735816)
		(width 0.14224)
		(layer "In13.Cu")
		(net "P5E_CPU1_P1_RX_BUF_DN<6>")
	)
	(segment
		(start 86.803484 -395.024102)
		(end 86.803484 -393.043156)
		(width 0.14224)
		(layer "In13.Cu")
		(net "P5E_CPU1_P1_RX_BUF_DN<6>")
	)
	(segment
		(start 71.85279 -403.088602)
		(end 72.087486 -402.975572)
		(width 0.14224)
		(layer "In13.Cu")
		(net "P5E_CPU1_P1_RX_BUF_DN<6>")
	)
	(segment
		(start 71.059294 -404.924514)
		(end 71.059294 -404.113238)
		(width 0.14224)
		(layer "In13.Cu")
		(net "P5E_CPU1_P1_RX_BUF_DN<6>")
	)
	(segment
		(start 71.133208 -403.8473)
		(end 71.223886 -403.697186)
		(width 0.14224)
		(layer "In13.Cu")
		(net "P5E_CPU1_P1_RX_BUF_DN<6>")
	)
	(segment
		(start 69.31406 -410.988256)
		(end 69.4817 -410.812234)
		(width 0.14224)
		(layer "In13.Cu")
		(net "P5E_CPU1_P1_RX_BUF_DN<6>")
	)
	(segment
		(start 69.689218 -426.990002)
		(end 69.689218 -415.279586)
		(width 0.14224)
		(layer "In13.Cu")
		(net "P5E_CPU1_P1_RX_BUF_DN<6>")
	)
	(segment
		(start 87.544402 -392.597386)
		(end 87.544402 -392.429238)
		(width 0.14224)
		(layer "In13.Cu")
		(net "P5E_CPU1_P1_RX_BUF_DN<6>")
	)
	(segment
		(start 70.522846 -434.038756)
		(end 70.158102 -434.038756)
		(width 0.14224)
		(layer "In13.Cu")
		(net "P5E_CPU1_P1_RX_BUF_DN<6>")
	)
	(segment
		(start 77.43698 -400.680174)
		(end 78.210918 -400.34845)
		(width 0.14224)
		(layer "In13.Cu")
		(net "P5E_CPU1_P1_RX_BUF_DN<6>")
	)
	(segment
		(start 67.996054 -413.168592)
		(end 67.996054 -411.846014)
		(width 0.14224)
		(layer "In13.Cu")
		(net "P5E_CPU1_P1_RX_BUF_DN<6>")
	)
	(segment
		(start 83.785202 -398.243298)
		(end 84.066888 -398.054576)
		(width 0.14224)
		(layer "In13.Cu")
		(net "P5E_CPU1_P1_RX_BUF_DN<6>")
	)
	(segment
		(start 69.527674 -410.697426)
		(end 69.527674 -406.638252)
		(width 0.14224)
		(layer "In13.Cu")
		(net "P5E_CPU1_P1_RX_BUF_DN<6>")
	)
	(segment
		(start 70.158102 -434.038756)
		(end 69.694298 -433.574952)
		(width 0.14224)
		(layer "In13.Cu")
		(net "P5E_CPU1_P1_RX_BUF_DN<6>")
	)
	(segment
		(start 70.812152 -405.341328)
		(end 70.939406 -405.214074)
		(width 0.14224)
		(layer "In13.Cu")
		(net "P5E_CPU1_P1_RX_BUF_DN<6>")
	)
	(segment
		(start 69.57695 -415.008568)
		(end 68.179188 -413.610806)
		(width 0.14224)
		(layer "In13.Cu")
		(net "P5E_CPU1_P1_RX_BUF_DN<6>")
	)
	(segment
		(start 87.110824 -392.735816)
		(end 87.405972 -392.735816)
		(width 0.14224)
		(layer "In13.Cu")
		(net "P5E_CPU1_P1_RX_BUF_DN<6>")
	)
	(segment
		(start 71.346568 -403.542246)
		(end 71.697596 -403.197568)
		(width 0.14224)
		(layer "In13.Cu")
		(net "P5E_CPU1_P1_RX_BUF_DN<6>")
	)
	(segment
		(start 68.257674 -411.454346)
		(end 69.210428 -411.059376)
		(width 0.14224)
		(layer "In13.Cu")
		(net "P5E_CPU1_P1_RX_BUF_DN<6>")
	)
	(segment
		(start 77.43698 -400.67992)
		(end 77.43698 -400.680174)
		(width 0.14224)
		(layer "In13.Cu")
		(net "P5E_CPU1_P1_RX_BUF_DN<6>")
	)
	(arc
		(start 71.697596 -403.197568)
		(mid 71.770723 -403.136717)
		(end 71.85279 -403.088602)
		(width 0.14224)
		(layer "In13.Cu")
		(net "P5E_CPU1_P1_RX_BUF_DN<6>")
	)
	(arc
		(start 70.939406 -405.214074)
		(mid 71.028121 -405.081209)
		(end 71.059294 -404.924514)
		(width 0.14224)
		(layer "In13.Cu")
		(net "P5E_CPU1_P1_RX_BUF_DN<6>")
	)
	(arc
		(start 86.781894 -395.09446)
		(mid 86.797905 -395.06088)
		(end 86.803484 -395.024102)
		(width 0.14224)
		(layer "In13.Cu")
		(net "P5E_CPU1_P1_RX_BUF_DN<6>")
	)
	(arc
		(start 68.179188 -413.610806)
		(mid 68.043622 -413.407916)
		(end 67.996054 -413.168592)
		(width 0.14224)
		(layer "In13.Cu")
		(net "P5E_CPU1_P1_RX_BUF_DN<6>")
	)
	(arc
		(start 78.210918 -400.34845)
		(mid 78.274733 -400.322119)
		(end 78.339188 -400.297396)
		(width 0.14224)
		(layer "In13.Cu")
		(net "P5E_CPU1_P1_RX_BUF_DN<6>")
	)
	(arc
		(start 71.059294 -404.113238)
		(mid 71.078116 -403.975229)
		(end 71.133208 -403.8473)
		(width 0.14224)
		(layer "In13.Cu")
		(net "P5E_CPU1_P1_RX_BUF_DN<6>")
	)
	(arc
		(start 67.996054 -411.846014)
		(mid 68.067405 -411.610456)
		(end 68.257674 -411.454346)
		(width 0.14224)
		(layer "In13.Cu")
		(net "P5E_CPU1_P1_RX_BUF_DN<6>")
	)
	(arc
		(start 85.901784 -396.27429)
		(mid 86.163325 -395.985813)
		(end 86.395306 -395.673072)
		(width 0.14224)
		(layer "In13.Cu")
		(net "P5E_CPU1_P1_RX_BUF_DN<6>")
	)
	(arc
		(start 69.815202 -405.94407)
		(mid 70.038367 -405.760796)
		(end 70.292976 -405.624538)
		(width 0.14224)
		(layer "In13.Cu")
		(net "P5E_CPU1_P1_RX_BUF_DN<6>")
	)
	(arc
		(start 69.689218 -415.279586)
		(mid 69.660042 -415.132909)
		(end 69.57695 -415.008568)
		(width 0.14224)
		(layer "In13.Cu")
		(net "P5E_CPU1_P1_RX_BUF_DN<6>")
	)
	(arc
		(start 71.223886 -403.697186)
		(mid 71.280356 -403.615859)
		(end 71.346568 -403.542246)
		(width 0.14224)
		(layer "In13.Cu")
		(net "P5E_CPU1_P1_RX_BUF_DN<6>")
	)
	(arc
		(start 83.475068 -398.401794)
		(mid 83.634831 -398.331735)
		(end 83.785202 -398.243298)
		(width 0.14224)
		(layer "In13.Cu")
		(net "P5E_CPU1_P1_RX_BUF_DN<6>")
	)
	(arc
		(start 69.4817 -410.812234)
		(mid 69.515747 -410.75926)
		(end 69.527674 -410.697426)
		(width 0.14224)
		(layer "In13.Cu")
		(net "P5E_CPU1_P1_RX_BUF_DN<6>")
	)
	(arc
		(start 69.527674 -406.638252)
		(mid 69.602364 -406.262557)
		(end 69.815202 -405.94407)
		(width 0.14224)
		(layer "In13.Cu")
		(net "P5E_CPU1_P1_RX_BUF_DN<6>")
	)
	(arc
		(start 84.066888 -398.054576)
		(mid 84.225806 -397.936573)
		(end 84.37245 -397.803624)
		(width 0.14224)
		(layer "In13.Cu")
		(net "P5E_CPU1_P1_RX_BUF_DN<6>")
	)
	(arc
		(start 69.210428 -411.059376)
		(mid 69.265966 -411.02924)
		(end 69.31406 -410.988256)
		(width 0.14224)
		(layer "In13.Cu")
		(net "P5E_CPU1_P1_RX_BUF_DN<6>")
	)
	(arc
		(start 72.087486 -402.975572)
		(mid 72.144733 -402.948785)
		(end 72.202548 -402.923248)
		(width 0.14224)
		(layer "In13.Cu")
		(net "P5E_CPU1_P1_RX_BUF_DN<6>")
	)
	(segment
		(start 85.984588 -392.761216)
		(end 86.203536 -392.761216)
		(width 0.1016)
		(layer "F.Cu")
		(net "P5E_CPU1_P1_RX_BUF_DN<5>")
	)
	(segment
		(start 86.344252 -392.6205)
		(end 86.344252 -392.429238)
		(width 0.1016)
		(layer "F.Cu")
		(net "P5E_CPU1_P1_RX_BUF_DN<5>")
	)
	(segment
		(start 85.857588 -391.666984)
		(end 85.857588 -392.634216)
		(width 0.1016)
		(layer "F.Cu")
		(net "P5E_CPU1_P1_RX_BUF_DN<5>")
	)
	(segment
		(start 86.203536 -392.761216)
		(end 86.344252 -392.6205)
		(width 0.1016)
		(layer "F.Cu")
		(net "P5E_CPU1_P1_RX_BUF_DN<5>")
	)
	(segment
		(start 85.945726 -390.761474)
		(end 85.946234 -390.761982)
		(width 0.1016)
		(layer "F.Cu")
		(net "P5E_CPU1_P1_RX_BUF_DN<5>")
	)
	(segment
		(start 85.857588 -392.634216)
		(end 85.984588 -392.761216)
		(width 0.1016)
		(layer "F.Cu")
		(net "P5E_CPU1_P1_RX_BUF_DN<5>")
	)
	(segment
		(start 85.946234 -391.578338)
		(end 85.857588 -391.666984)
		(width 0.1016)
		(layer "F.Cu")
		(net "P5E_CPU1_P1_RX_BUF_DN<5>")
	)
	(segment
		(start 85.946234 -390.761982)
		(end 85.946234 -391.578338)
		(width 0.1016)
		(layer "F.Cu")
		(net "P5E_CPU1_P1_RX_BUF_DN<5>")
	)
	(segment
		(start 86.205822 -392.735816)
		(end 86.344252 -392.597386)
		(width 0.14224)
		(layer "In13.Cu")
		(net "P5E_CPU1_P1_RX_BUF_DN<5>")
	)
	(segment
		(start 67.614038 -416.814508)
		(end 65.052702 -414.253172)
		(width 0.14224)
		(layer "In13.Cu")
		(net "P5E_CPU1_P1_RX_BUF_DN<5>")
	)
	(segment
		(start 85.603334 -393.043156)
		(end 85.910674 -392.735816)
		(width 0.14224)
		(layer "In13.Cu")
		(net "P5E_CPU1_P1_RX_BUF_DN<5>")
	)
	(segment
		(start 67.229736 -405.624538)
		(end 67.479672 -405.52116)
		(width 0.14224)
		(layer "In13.Cu")
		(net "P5E_CPU1_P1_RX_BUF_DN<5>")
	)
	(segment
		(start 64.932814 -413.963612)
		(end 64.932814 -411.967934)
		(width 0.14224)
		(layer "In13.Cu")
		(net "P5E_CPU1_P1_RX_BUF_DN<5>")
	)
	(segment
		(start 85.603334 -394.896848)
		(end 85.603334 -393.043156)
		(width 0.14224)
		(layer "In13.Cu")
		(net "P5E_CPU1_P1_RX_BUF_DN<5>")
	)
	(segment
		(start 68.64985 -435.489858)
		(end 68.64985 -435.165754)
		(width 0.14224)
		(layer "In13.Cu")
		(net "P5E_CPU1_P1_RX_BUF_DN<5>")
	)
	(segment
		(start 86.344252 -392.597386)
		(end 86.344252 -392.429238)
		(width 0.14224)
		(layer "In13.Cu")
		(net "P5E_CPU1_P1_RX_BUF_DN<5>")
	)
	(segment
		(start 67.479672 -405.52116)
		(end 67.748912 -405.341328)
		(width 0.14224)
		(layer "In13.Cu")
		(net "P5E_CPU1_P1_RX_BUF_DN<5>")
	)
	(segment
		(start 67.996054 -404.924514)
		(end 67.996054 -404.09622)
		(width 0.14224)
		(layer "In13.Cu")
		(net "P5E_CPU1_P1_RX_BUF_DN<5>")
	)
	(segment
		(start 66.20256 -411.059376)
		(end 66.372994 -410.880814)
		(width 0.14224)
		(layer "In13.Cu")
		(net "P5E_CPU1_P1_RX_BUF_DN<5>")
	)
	(segment
		(start 80.494124 -398.489932)
		(end 83.639152 -397.187928)
		(width 0.14224)
		(layer "In13.Cu")
		(net "P5E_CPU1_P1_RX_BUF_DN<5>")
	)
	(segment
		(start 68.64985 -435.165754)
		(end 68.52285 -435.038754)
		(width 0.14224)
		(layer "In13.Cu")
		(net "P5E_CPU1_P1_RX_BUF_DN<5>")
	)
	(segment
		(start 68.158106 -435.038754)
		(end 67.694302 -434.57495)
		(width 0.14224)
		(layer "In13.Cu")
		(net "P5E_CPU1_P1_RX_BUF_DN<5>")
	)
	(segment
		(start 66.464434 -410.652722)
		(end 66.464434 -406.638252)
		(width 0.14224)
		(layer "In13.Cu")
		(net "P5E_CPU1_P1_RX_BUF_DN<5>")
	)
	(segment
		(start 67.700906 -426.873162)
		(end 67.700906 -417.024058)
		(width 0.14224)
		(layer "In13.Cu")
		(net "P5E_CPU1_P1_RX_BUF_DN<5>")
	)
	(segment
		(start 75.49515 -400.220942)
		(end 75.49515 -400.221196)
		(width 0.14224)
		(layer "In13.Cu")
		(net "P5E_CPU1_P1_RX_BUF_DN<5>")
	)
	(segment
		(start 83.639152 -397.187928)
		(end 85.034628 -395.792198)
		(width 0.14224)
		(layer "In13.Cu")
		(net "P5E_CPU1_P1_RX_BUF_DN<5>")
	)
	(segment
		(start 85.910674 -392.735816)
		(end 86.205822 -392.735816)
		(width 0.14224)
		(layer "In13.Cu")
		(net "P5E_CPU1_P1_RX_BUF_DN<5>")
	)
	(segment
		(start 67.694302 -426.879766)
		(end 67.700906 -426.873162)
		(width 0.14224)
		(layer "In13.Cu")
		(net "P5E_CPU1_P1_RX_BUF_DN<5>")
	)
	(segment
		(start 67.694302 -434.57495)
		(end 67.694302 -426.879766)
		(width 0.14224)
		(layer "In13.Cu")
		(net "P5E_CPU1_P1_RX_BUF_DN<5>")
	)
	(segment
		(start 85.034628 -395.792198)
		(end 85.034882 -395.792198)
		(width 0.14224)
		(layer "In13.Cu")
		(net "P5E_CPU1_P1_RX_BUF_DN<5>")
	)
	(segment
		(start 68.52285 -435.038754)
		(end 68.158106 -435.038754)
		(width 0.14224)
		(layer "In13.Cu")
		(net "P5E_CPU1_P1_RX_BUF_DN<5>")
	)
	(segment
		(start 70.207124 -402.23567)
		(end 75.49515 -400.220942)
		(width 0.14224)
		(layer "In13.Cu")
		(net "P5E_CPU1_P1_RX_BUF_DN<5>")
	)
	(segment
		(start 65.336674 -411.357318)
		(end 66.149982 -411.092396)
		(width 0.14224)
		(layer "In13.Cu")
		(net "P5E_CPU1_P1_RX_BUF_DN<5>")
	)
	(segment
		(start 75.49515 -400.221196)
		(end 77.070458 -399.620994)
		(width 0.14224)
		(layer "In13.Cu")
		(net "P5E_CPU1_P1_RX_BUF_DN<5>")
	)
	(segment
		(start 68.224146 -403.545548)
		(end 68.393056 -403.376638)
		(width 0.14224)
		(layer "In13.Cu")
		(net "P5E_CPU1_P1_RX_BUF_DN<5>")
	)
	(segment
		(start 77.070458 -399.620994)
		(end 80.494124 -398.489932)
		(width 0.14224)
		(layer "In13.Cu")
		(net "P5E_CPU1_P1_RX_BUF_DN<5>")
	)
	(segment
		(start 69.146674 -402.813012)
		(end 70.207124 -402.23567)
		(width 0.14224)
		(layer "In13.Cu")
		(net "P5E_CPU1_P1_RX_BUF_DN<5>")
	)
	(segment
		(start 85.114638 -395.694916)
		(end 85.567266 -395.016482)
		(width 0.14224)
		(layer "In13.Cu")
		(net "P5E_CPU1_P1_RX_BUF_DN<5>")
	)
	(segment
		(start 67.748912 -405.341328)
		(end 67.876166 -405.214074)
		(width 0.14224)
		(layer "In13.Cu")
		(net "P5E_CPU1_P1_RX_BUF_DN<5>")
	)
	(arc
		(start 66.149982 -411.092396)
		(mid 66.178304 -411.079128)
		(end 66.20256 -411.059376)
		(width 0.14224)
		(layer "In13.Cu")
		(net "P5E_CPU1_P1_RX_BUF_DN<5>")
	)
	(arc
		(start 67.996054 -404.09622)
		(mid 68.055334 -403.7982)
		(end 68.224146 -403.545548)
		(width 0.14224)
		(layer "In13.Cu")
		(net "P5E_CPU1_P1_RX_BUF_DN<5>")
	)
	(arc
		(start 65.110614 -411.506416)
		(mid 65.213845 -411.417004)
		(end 65.336674 -411.357318)
		(width 0.14224)
		(layer "In13.Cu")
		(net "P5E_CPU1_P1_RX_BUF_DN<5>")
	)
	(arc
		(start 67.700906 -417.024058)
		(mid 67.678327 -416.910638)
		(end 67.614038 -416.814508)
		(width 0.14224)
		(layer "In13.Cu")
		(net "P5E_CPU1_P1_RX_BUF_DN<5>")
	)
	(arc
		(start 66.751962 -405.94407)
		(mid 66.975127 -405.760796)
		(end 67.229736 -405.624538)
		(width 0.14224)
		(layer "In13.Cu")
		(net "P5E_CPU1_P1_RX_BUF_DN<5>")
	)
	(arc
		(start 66.372994 -410.880814)
		(mid 66.440723 -410.775591)
		(end 66.464434 -410.652722)
		(width 0.14224)
		(layer "In13.Cu")
		(net "P5E_CPU1_P1_RX_BUF_DN<5>")
	)
	(arc
		(start 64.967612 -411.753558)
		(mid 65.026563 -411.622724)
		(end 65.110614 -411.506416)
		(width 0.14224)
		(layer "In13.Cu")
		(net "P5E_CPU1_P1_RX_BUF_DN<5>")
	)
	(arc
		(start 67.876166 -405.214074)
		(mid 67.964881 -405.081209)
		(end 67.996054 -404.924514)
		(width 0.14224)
		(layer "In13.Cu")
		(net "P5E_CPU1_P1_RX_BUF_DN<5>")
	)
	(arc
		(start 66.464434 -406.638252)
		(mid 66.539124 -406.262557)
		(end 66.751962 -405.94407)
		(width 0.14224)
		(layer "In13.Cu")
		(net "P5E_CPU1_P1_RX_BUF_DN<5>")
	)
	(arc
		(start 85.567266 -395.016482)
		(mid 85.594182 -394.95934)
		(end 85.603334 -394.896848)
		(width 0.14224)
		(layer "In13.Cu")
		(net "P5E_CPU1_P1_RX_BUF_DN<5>")
	)
	(arc
		(start 65.052702 -414.253172)
		(mid 64.963987 -414.120307)
		(end 64.932814 -413.963612)
		(width 0.14224)
		(layer "In13.Cu")
		(net "P5E_CPU1_P1_RX_BUF_DN<5>")
	)
	(arc
		(start 85.034882 -395.792198)
		(mid 85.077149 -395.745515)
		(end 85.114638 -395.694916)
		(width 0.14224)
		(layer "In13.Cu")
		(net "P5E_CPU1_P1_RX_BUF_DN<5>")
	)
	(arc
		(start 64.932814 -411.967934)
		(mid 64.941526 -411.859335)
		(end 64.967612 -411.753558)
		(width 0.14224)
		(layer "In13.Cu")
		(net "P5E_CPU1_P1_RX_BUF_DN<5>")
	)
	(arc
		(start 68.393056 -403.376638)
		(mid 68.749634 -403.067776)
		(end 69.146674 -402.813012)
		(width 0.14224)
		(layer "In13.Cu")
		(net "P5E_CPU1_P1_RX_BUF_DN<5>")
	)
	(segment
		(start 84.657692 -391.666984)
		(end 84.657692 -392.634216)
		(width 0.1016)
		(layer "F.Cu")
		(net "P5E_CPU1_P1_RX_BUF_DN<4>")
	)
	(segment
		(start 84.657692 -392.634216)
		(end 84.784692 -392.761216)
		(width 0.1016)
		(layer "F.Cu")
		(net "P5E_CPU1_P1_RX_BUF_DN<4>")
	)
	(segment
		(start 84.746338 -390.761982)
		(end 84.746338 -391.578338)
		(width 0.1016)
		(layer "F.Cu")
		(net "P5E_CPU1_P1_RX_BUF_DN<4>")
	)
	(segment
		(start 85.144356 -392.6205)
		(end 85.144356 -392.429238)
		(width 0.1016)
		(layer "F.Cu")
		(net "P5E_CPU1_P1_RX_BUF_DN<4>")
	)
	(segment
		(start 84.746338 -391.578338)
		(end 84.657692 -391.666984)
		(width 0.1016)
		(layer "F.Cu")
		(net "P5E_CPU1_P1_RX_BUF_DN<4>")
	)
	(segment
		(start 84.784692 -392.761216)
		(end 85.00364 -392.761216)
		(width 0.1016)
		(layer "F.Cu")
		(net "P5E_CPU1_P1_RX_BUF_DN<4>")
	)
	(segment
		(start 84.74583 -390.761474)
		(end 84.746338 -390.761982)
		(width 0.1016)
		(layer "F.Cu")
		(net "P5E_CPU1_P1_RX_BUF_DN<4>")
	)
	(segment
		(start 85.00364 -392.761216)
		(end 85.144356 -392.6205)
		(width 0.1016)
		(layer "F.Cu")
		(net "P5E_CPU1_P1_RX_BUF_DN<4>")
	)
	(segment
		(start 80.287622 -397.546322)
		(end 80.33639 -397.529812)
		(width 0.14224)
		(layer "In13.Cu")
		(net "P5E_CPU1_P1_RX_BUF_DN<4>")
	)
	(segment
		(start 65.689226 -426.990002)
		(end 65.689226 -417.60902)
		(width 0.14224)
		(layer "In13.Cu")
		(net "P5E_CPU1_P1_RX_BUF_DN<4>")
	)
	(segment
		(start 83.056222 -396.40256)
		(end 84.006182 -395.4526)
		(width 0.14224)
		(layer "In13.Cu")
		(net "P5E_CPU1_P1_RX_BUF_DN<4>")
	)
	(segment
		(start 66.649854 -434.48986)
		(end 66.649854 -434.165756)
		(width 0.14224)
		(layer "In13.Cu")
		(net "P5E_CPU1_P1_RX_BUF_DN<4>")
	)
	(segment
		(start 85.144356 -392.597386)
		(end 85.144356 -392.429238)
		(width 0.14224)
		(layer "In13.Cu")
		(net "P5E_CPU1_P1_RX_BUF_DN<4>")
	)
	(segment
		(start 65.694306 -426.995082)
		(end 65.689226 -426.990002)
		(width 0.14224)
		(layer "In13.Cu")
		(net "P5E_CPU1_P1_RX_BUF_DN<4>")
	)
	(segment
		(start 64.932814 -404.924514)
		(end 64.932814 -404.07844)
		(width 0.14224)
		(layer "In13.Cu")
		(net "P5E_CPU1_P1_RX_BUF_DN<4>")
	)
	(segment
		(start 64.166496 -405.624538)
		(end 64.416432 -405.52116)
		(width 0.14224)
		(layer "In13.Cu")
		(net "P5E_CPU1_P1_RX_BUF_DN<4>")
	)
	(segment
		(start 66.15811 -434.038756)
		(end 65.694306 -433.574952)
		(width 0.14224)
		(layer "In13.Cu")
		(net "P5E_CPU1_P1_RX_BUF_DN<4>")
	)
	(segment
		(start 84.403438 -394.71346)
		(end 84.403438 -393.043156)
		(width 0.14224)
		(layer "In13.Cu")
		(net "P5E_CPU1_P1_RX_BUF_DN<4>")
	)
	(segment
		(start 78.541118 -398.007078)
		(end 80.287622 -397.546322)
		(width 0.14224)
		(layer "In13.Cu")
		(net "P5E_CPU1_P1_RX_BUF_DN<4>")
	)
	(segment
		(start 71.946262 -400.191224)
		(end 78.541118 -398.007078)
		(width 0.14224)
		(layer "In13.Cu")
		(net "P5E_CPU1_P1_RX_BUF_DN<4>")
	)
	(segment
		(start 84.710778 -392.735816)
		(end 85.005926 -392.735816)
		(width 0.14224)
		(layer "In13.Cu")
		(net "P5E_CPU1_P1_RX_BUF_DN<4>")
	)
	(segment
		(start 84.245704 -395.093952)
		(end 84.403438 -394.71346)
		(width 0.14224)
		(layer "In13.Cu")
		(net "P5E_CPU1_P1_RX_BUF_DN<4>")
	)
	(segment
		(start 61.869574 -413.287464)
		(end 61.869574 -411.853126)
		(width 0.14224)
		(layer "In13.Cu")
		(net "P5E_CPU1_P1_RX_BUF_DN<4>")
	)
	(segment
		(start 84.006182 -395.4526)
		(end 84.245704 -395.093952)
		(width 0.14224)
		(layer "In13.Cu")
		(net "P5E_CPU1_P1_RX_BUF_DN<4>")
	)
	(segment
		(start 64.685672 -405.341328)
		(end 64.812926 -405.214074)
		(width 0.14224)
		(layer "In13.Cu")
		(net "P5E_CPU1_P1_RX_BUF_DN<4>")
	)
	(segment
		(start 85.005926 -392.735816)
		(end 85.144356 -392.597386)
		(width 0.14224)
		(layer "In13.Cu")
		(net "P5E_CPU1_P1_RX_BUF_DN<4>")
	)
	(segment
		(start 65.206626 -403.417278)
		(end 65.27165 -403.352254)
		(width 0.14224)
		(layer "In13.Cu")
		(net "P5E_CPU1_P1_RX_BUF_DN<4>")
	)
	(segment
		(start 84.403438 -393.043156)
		(end 84.710778 -392.735816)
		(width 0.14224)
		(layer "In13.Cu")
		(net "P5E_CPU1_P1_RX_BUF_DN<4>")
	)
	(segment
		(start 66.522854 -434.038756)
		(end 66.15811 -434.038756)
		(width 0.14224)
		(layer "In13.Cu")
		(net "P5E_CPU1_P1_RX_BUF_DN<4>")
	)
	(segment
		(start 65.694306 -433.574952)
		(end 65.694306 -426.995082)
		(width 0.14224)
		(layer "In13.Cu")
		(net "P5E_CPU1_P1_RX_BUF_DN<4>")
	)
	(segment
		(start 62.13729 -411.451806)
		(end 63.083948 -411.059376)
		(width 0.14224)
		(layer "In13.Cu")
		(net "P5E_CPU1_P1_RX_BUF_DN<4>")
	)
	(segment
		(start 80.33639 -397.529812)
		(end 83.056222 -396.40256)
		(width 0.14224)
		(layer "In13.Cu")
		(net "P5E_CPU1_P1_RX_BUF_DN<4>")
	)
	(segment
		(start 66.649854 -434.165756)
		(end 66.522854 -434.038756)
		(width 0.14224)
		(layer "In13.Cu")
		(net "P5E_CPU1_P1_RX_BUF_DN<4>")
	)
	(segment
		(start 63.401194 -410.697426)
		(end 63.401194 -406.638252)
		(width 0.14224)
		(layer "In13.Cu")
		(net "P5E_CPU1_P1_RX_BUF_DN<4>")
	)
	(segment
		(start 64.416432 -405.52116)
		(end 64.685672 -405.341328)
		(width 0.14224)
		(layer "In13.Cu")
		(net "P5E_CPU1_P1_RX_BUF_DN<4>")
	)
	(segment
		(start 65.487042 -417.121086)
		(end 62.022228 -413.656272)
		(width 0.14224)
		(layer "In13.Cu")
		(net "P5E_CPU1_P1_RX_BUF_DN<4>")
	)
	(segment
		(start 66.483992 -402.53158)
		(end 71.946262 -400.191224)
		(width 0.14224)
		(layer "In13.Cu")
		(net "P5E_CPU1_P1_RX_BUF_DN<4>")
	)
	(arc
		(start 62.022228 -413.656272)
		(mid 61.909219 -413.487047)
		(end 61.869574 -413.287464)
		(width 0.14224)
		(layer "In13.Cu")
		(net "P5E_CPU1_P1_RX_BUF_DN<4>")
	)
	(arc
		(start 63.688722 -405.94407)
		(mid 63.911887 -405.760796)
		(end 64.166496 -405.624538)
		(width 0.14224)
		(layer "In13.Cu")
		(net "P5E_CPU1_P1_RX_BUF_DN<4>")
	)
	(arc
		(start 63.30569 -410.88818)
		(mid 63.375984 -410.804089)
		(end 63.401194 -410.697426)
		(width 0.14224)
		(layer "In13.Cu")
		(net "P5E_CPU1_P1_RX_BUF_DN<4>")
	)
	(arc
		(start 61.869574 -411.853126)
		(mid 61.942651 -411.611927)
		(end 62.13729 -411.451806)
		(width 0.14224)
		(layer "In13.Cu")
		(net "P5E_CPU1_P1_RX_BUF_DN<4>")
	)
	(arc
		(start 65.689226 -417.60902)
		(mid 65.636679 -417.344938)
		(end 65.487042 -417.121086)
		(width 0.14224)
		(layer "In13.Cu")
		(net "P5E_CPU1_P1_RX_BUF_DN<4>")
	)
	(arc
		(start 63.401194 -406.638252)
		(mid 63.475884 -406.262557)
		(end 63.688722 -405.94407)
		(width 0.14224)
		(layer "In13.Cu")
		(net "P5E_CPU1_P1_RX_BUF_DN<4>")
	)
	(arc
		(start 64.812926 -405.214074)
		(mid 64.901641 -405.081209)
		(end 64.932814 -404.924514)
		(width 0.14224)
		(layer "In13.Cu")
		(net "P5E_CPU1_P1_RX_BUF_DN<4>")
	)
	(arc
		(start 63.083948 -411.059376)
		(mid 63.206277 -410.988612)
		(end 63.30569 -410.88818)
		(width 0.14224)
		(layer "In13.Cu")
		(net "P5E_CPU1_P1_RX_BUF_DN<4>")
	)
	(arc
		(start 64.932814 -404.07844)
		(mid 65.00397 -403.720627)
		(end 65.206626 -403.417278)
		(width 0.14224)
		(layer "In13.Cu")
		(net "P5E_CPU1_P1_RX_BUF_DN<4>")
	)
	(arc
		(start 65.27165 -403.352254)
		(mid 65.838652 -402.884052)
		(end 66.483992 -402.53158)
		(width 0.14224)
		(layer "In13.Cu")
		(net "P5E_CPU1_P1_RX_BUF_DN<4>")
	)
	(segment
		(start 83.546188 -390.761982)
		(end 83.546188 -391.578338)
		(width 0.1016)
		(layer "F.Cu")
		(net "P5E_CPU1_P1_RX_BUF_DN<3>")
	)
	(segment
		(start 83.80349 -392.761216)
		(end 83.944206 -392.6205)
		(width 0.1016)
		(layer "F.Cu")
		(net "P5E_CPU1_P1_RX_BUF_DN<3>")
	)
	(segment
		(start 83.59775 -392.761216)
		(end 83.80349 -392.761216)
		(width 0.1016)
		(layer "F.Cu")
		(net "P5E_CPU1_P1_RX_BUF_DN<3>")
	)
	(segment
		(start 83.54568 -390.761474)
		(end 83.546188 -390.761982)
		(width 0.1016)
		(layer "F.Cu")
		(net "P5E_CPU1_P1_RX_BUF_DN<3>")
	)
	(segment
		(start 83.546188 -391.578338)
		(end 83.47075 -391.653776)
		(width 0.1016)
		(layer "F.Cu")
		(net "P5E_CPU1_P1_RX_BUF_DN<3>")
	)
	(segment
		(start 83.47075 -391.653776)
		(end 83.47075 -392.634216)
		(width 0.1016)
		(layer "F.Cu")
		(net "P5E_CPU1_P1_RX_BUF_DN<3>")
	)
	(segment
		(start 83.47075 -392.634216)
		(end 83.59775 -392.761216)
		(width 0.1016)
		(layer "F.Cu")
		(net "P5E_CPU1_P1_RX_BUF_DN<3>")
	)
	(segment
		(start 83.944206 -392.6205)
		(end 83.944206 -392.429238)
		(width 0.1016)
		(layer "F.Cu")
		(net "P5E_CPU1_P1_RX_BUF_DN<3>")
	)
	(segment
		(start 82.583274 -395.489938)
		(end 83.018376 -395.054836)
		(width 0.14224)
		(layer "In13.Cu")
		(net "P5E_CPU1_P1_RX_BUF_DN<3>")
	)
	(segment
		(start 83.944206 -392.597386)
		(end 83.944206 -392.429238)
		(width 0.14224)
		(layer "In13.Cu")
		(net "P5E_CPU1_P1_RX_BUF_DN<3>")
	)
	(segment
		(start 72.034654 -399.084038)
		(end 77.8637 -397.198088)
		(width 0.14224)
		(layer "In13.Cu")
		(net "P5E_CPU1_P1_RX_BUF_DN<3>")
	)
	(segment
		(start 59.779408 -414.118044)
		(end 59.653932 -414.118044)
		(width 0.14224)
		(layer "In13.Cu")
		(net "P5E_CPU1_P1_RX_BUF_DN<3>")
	)
	(segment
		(start 64.649858 -435.489858)
		(end 64.649858 -435.165754)
		(width 0.14224)
		(layer "In13.Cu")
		(net "P5E_CPU1_P1_RX_BUF_DN<3>")
	)
	(segment
		(start 63.58255 -417.697666)
		(end 60.160916 -414.276032)
		(width 0.14224)
		(layer "In13.Cu")
		(net "P5E_CPU1_P1_RX_BUF_DN<3>")
	)
	(segment
		(start 83.805776 -392.735816)
		(end 83.944206 -392.597386)
		(width 0.14224)
		(layer "In13.Cu")
		(net "P5E_CPU1_P1_RX_BUF_DN<3>")
	)
	(segment
		(start 83.018376 -395.054836)
		(end 83.203288 -394.608558)
		(width 0.14224)
		(layer "In13.Cu")
		(net "P5E_CPU1_P1_RX_BUF_DN<3>")
	)
	(segment
		(start 63.69431 -426.995082)
		(end 63.68923 -426.990002)
		(width 0.14224)
		(layer "In13.Cu")
		(net "P5E_CPU1_P1_RX_BUF_DN<3>")
	)
	(segment
		(start 59.087766 -411.446218)
		(end 60.001658 -411.06725)
		(width 0.14224)
		(layer "In13.Cu")
		(net "P5E_CPU1_P1_RX_BUF_DN<3>")
	)
	(segment
		(start 60.337954 -410.741622)
		(end 60.337954 -406.638252)
		(width 0.14224)
		(layer "In13.Cu")
		(net "P5E_CPU1_P1_RX_BUF_DN<3>")
	)
	(segment
		(start 83.203288 -394.608558)
		(end 83.203288 -393.043156)
		(width 0.14224)
		(layer "In13.Cu")
		(net "P5E_CPU1_P1_RX_BUF_DN<3>")
	)
	(segment
		(start 83.203288 -393.043156)
		(end 83.510628 -392.735816)
		(width 0.14224)
		(layer "In13.Cu")
		(net "P5E_CPU1_P1_RX_BUF_DN<3>")
	)
	(segment
		(start 59.238134 -413.945832)
		(end 59.015884 -413.723582)
		(width 0.14224)
		(layer "In13.Cu")
		(net "P5E_CPU1_P1_RX_BUF_DN<3>")
	)
	(segment
		(start 63.69431 -434.57495)
		(end 63.69431 -426.995082)
		(width 0.14224)
		(layer "In13.Cu")
		(net "P5E_CPU1_P1_RX_BUF_DN<3>")
	)
	(segment
		(start 81.381854 -396.087092)
		(end 82.255614 -395.701774)
		(width 0.14224)
		(layer "In13.Cu")
		(net "P5E_CPU1_P1_RX_BUF_DN<3>")
	)
	(segment
		(start 83.510628 -392.735816)
		(end 83.805776 -392.735816)
		(width 0.14224)
		(layer "In13.Cu")
		(net "P5E_CPU1_P1_RX_BUF_DN<3>")
	)
	(segment
		(start 58.806334 -413.218122)
		(end 58.806334 -411.868112)
		(width 0.14224)
		(layer "In13.Cu")
		(net "P5E_CPU1_P1_RX_BUF_DN<3>")
	)
	(segment
		(start 64.158114 -435.038754)
		(end 63.69431 -434.57495)
		(width 0.14224)
		(layer "In13.Cu")
		(net "P5E_CPU1_P1_RX_BUF_DN<3>")
	)
	(segment
		(start 61.353192 -405.52116)
		(end 61.622432 -405.341328)
		(width 0.14224)
		(layer "In13.Cu")
		(net "P5E_CPU1_P1_RX_BUF_DN<3>")
	)
	(segment
		(start 79.790036 -396.690342)
		(end 81.381854 -396.087092)
		(width 0.14224)
		(layer "In13.Cu")
		(net "P5E_CPU1_P1_RX_BUF_DN<3>")
	)
	(segment
		(start 82.255614 -395.701774)
		(end 82.583274 -395.489938)
		(width 0.14224)
		(layer "In13.Cu")
		(net "P5E_CPU1_P1_RX_BUF_DN<3>")
	)
	(segment
		(start 61.869574 -404.924514)
		(end 61.869574 -403.724618)
		(width 0.14224)
		(layer "In13.Cu")
		(net "P5E_CPU1_P1_RX_BUF_DN<3>")
	)
	(segment
		(start 60.109354 -411.001464)
		(end 60.286138 -410.85262)
		(width 0.14224)
		(layer "In13.Cu")
		(net "P5E_CPU1_P1_RX_BUF_DN<3>")
	)
	(segment
		(start 77.8637 -397.198088)
		(end 79.790036 -396.690342)
		(width 0.14224)
		(layer "In13.Cu")
		(net "P5E_CPU1_P1_RX_BUF_DN<3>")
	)
	(segment
		(start 61.103256 -405.624538)
		(end 61.353192 -405.52116)
		(width 0.14224)
		(layer "In13.Cu")
		(net "P5E_CPU1_P1_RX_BUF_DN<3>")
	)
	(segment
		(start 64.522858 -435.038754)
		(end 64.158114 -435.038754)
		(width 0.14224)
		(layer "In13.Cu")
		(net "P5E_CPU1_P1_RX_BUF_DN<3>")
	)
	(segment
		(start 63.68923 -426.990002)
		(end 63.68923 -417.954968)
		(width 0.14224)
		(layer "In13.Cu")
		(net "P5E_CPU1_P1_RX_BUF_DN<3>")
	)
	(segment
		(start 61.622432 -405.341328)
		(end 61.749686 -405.214074)
		(width 0.14224)
		(layer "In13.Cu")
		(net "P5E_CPU1_P1_RX_BUF_DN<3>")
	)
	(segment
		(start 62.905132 -402.603716)
		(end 72.034654 -399.084038)
		(width 0.14224)
		(layer "In13.Cu")
		(net "P5E_CPU1_P1_RX_BUF_DN<3>")
	)
	(segment
		(start 64.649858 -435.165754)
		(end 64.522858 -435.038754)
		(width 0.14224)
		(layer "In13.Cu")
		(net "P5E_CPU1_P1_RX_BUF_DN<3>")
	)
	(arc
		(start 60.001658 -411.06725)
		(mid 60.058027 -411.038487)
		(end 60.109354 -411.001464)
		(width 0.14224)
		(layer "In13.Cu")
		(net "P5E_CPU1_P1_RX_BUF_DN<3>")
	)
	(arc
		(start 60.337954 -406.638252)
		(mid 60.412644 -406.262557)
		(end 60.625482 -405.94407)
		(width 0.14224)
		(layer "In13.Cu")
		(net "P5E_CPU1_P1_RX_BUF_DN<3>")
	)
	(arc
		(start 60.625482 -405.94407)
		(mid 60.848647 -405.760796)
		(end 61.103256 -405.624538)
		(width 0.14224)
		(layer "In13.Cu")
		(net "P5E_CPU1_P1_RX_BUF_DN<3>")
	)
	(arc
		(start 58.806334 -411.868112)
		(mid 58.883148 -411.614538)
		(end 59.087766 -411.446218)
		(width 0.14224)
		(layer "In13.Cu")
		(net "P5E_CPU1_P1_RX_BUF_DN<3>")
	)
	(arc
		(start 60.286138 -410.85262)
		(mid 60.324324 -410.802851)
		(end 60.337954 -410.741622)
		(width 0.14224)
		(layer "In13.Cu")
		(net "P5E_CPU1_P1_RX_BUF_DN<3>")
	)
	(arc
		(start 62.119764 -403.12086)
		(mid 62.491706 -402.830787)
		(end 62.905132 -402.603716)
		(width 0.14224)
		(layer "In13.Cu")
		(net "P5E_CPU1_P1_RX_BUF_DN<3>")
	)
	(arc
		(start 60.160916 -414.276032)
		(mid 59.985864 -414.159129)
		(end 59.779408 -414.118044)
		(width 0.14224)
		(layer "In13.Cu")
		(net "P5E_CPU1_P1_RX_BUF_DN<3>")
	)
	(arc
		(start 63.68923 -417.954968)
		(mid 63.661508 -417.815692)
		(end 63.58255 -417.697666)
		(width 0.14224)
		(layer "In13.Cu")
		(net "P5E_CPU1_P1_RX_BUF_DN<3>")
	)
	(arc
		(start 59.015884 -413.723582)
		(mid 58.860899 -413.491676)
		(end 58.806334 -413.218122)
		(width 0.14224)
		(layer "In13.Cu")
		(net "P5E_CPU1_P1_RX_BUF_DN<3>")
	)
	(arc
		(start 59.653932 -414.118044)
		(mid 59.42891 -414.073284)
		(end 59.238134 -413.945832)
		(width 0.14224)
		(layer "In13.Cu")
		(net "P5E_CPU1_P1_RX_BUF_DN<3>")
	)
	(arc
		(start 61.869574 -403.724618)
		(mid 61.934645 -403.397866)
		(end 62.119764 -403.12086)
		(width 0.14224)
		(layer "In13.Cu")
		(net "P5E_CPU1_P1_RX_BUF_DN<3>")
	)
	(arc
		(start 61.749686 -405.214074)
		(mid 61.838401 -405.081209)
		(end 61.869574 -404.924514)
		(width 0.14224)
		(layer "In13.Cu")
		(net "P5E_CPU1_P1_RX_BUF_DN<3>")
	)
	(segment
		(start 82.346292 -390.761982)
		(end 82.346292 -391.578338)
		(width 0.1016)
		(layer "F.Cu")
		(net "P5E_CPU1_P1_RX_BUF_DN<2>")
	)
	(segment
		(start 82.346292 -391.578338)
		(end 82.257646 -391.666984)
		(width 0.1016)
		(layer "F.Cu")
		(net "P5E_CPU1_P1_RX_BUF_DN<2>")
	)
	(segment
		(start 82.384646 -392.761216)
		(end 82.603594 -392.761216)
		(width 0.1016)
		(layer "F.Cu")
		(net "P5E_CPU1_P1_RX_BUF_DN<2>")
	)
	(segment
		(start 82.345784 -390.761474)
		(end 82.346292 -390.761982)
		(width 0.1016)
		(layer "F.Cu")
		(net "P5E_CPU1_P1_RX_BUF_DN<2>")
	)
	(segment
		(start 82.603594 -392.761216)
		(end 82.74431 -392.6205)
		(width 0.1016)
		(layer "F.Cu")
		(net "P5E_CPU1_P1_RX_BUF_DN<2>")
	)
	(segment
		(start 82.257646 -392.634216)
		(end 82.384646 -392.761216)
		(width 0.1016)
		(layer "F.Cu")
		(net "P5E_CPU1_P1_RX_BUF_DN<2>")
	)
	(segment
		(start 82.74431 -392.6205)
		(end 82.74431 -392.429238)
		(width 0.1016)
		(layer "F.Cu")
		(net "P5E_CPU1_P1_RX_BUF_DN<2>")
	)
	(segment
		(start 82.257646 -391.666984)
		(end 82.257646 -392.634216)
		(width 0.1016)
		(layer "F.Cu")
		(net "P5E_CPU1_P1_RX_BUF_DN<2>")
	)
	(segment
		(start 59.472322 -402.928074)
		(end 73.504298 -397.278606)
		(width 0.14224)
		(layer "In13.Cu")
		(net "P5E_CPU1_P1_RX_BUF_DN<2>")
	)
	(segment
		(start 73.504298 -397.278606)
		(end 77.608684 -396.174722)
		(width 0.14224)
		(layer "In13.Cu")
		(net "P5E_CPU1_P1_RX_BUF_DN<2>")
	)
	(segment
		(start 62.158118 -434.038756)
		(end 61.694314 -433.574952)
		(width 0.14224)
		(layer "In13.Cu")
		(net "P5E_CPU1_P1_RX_BUF_DN<2>")
	)
	(segment
		(start 57.274714 -410.551122)
		(end 57.274714 -406.638252)
		(width 0.14224)
		(layer "In13.Cu")
		(net "P5E_CPU1_P1_RX_BUF_DN<2>")
	)
	(segment
		(start 58.850022 -403.707854)
		(end 58.914538 -403.475444)
		(width 0.14224)
		(layer "In13.Cu")
		(net "P5E_CPU1_P1_RX_BUF_DN<2>")
	)
	(segment
		(start 61.694314 -426.995082)
		(end 61.689234 -426.990002)
		(width 0.14224)
		(layer "In13.Cu")
		(net "P5E_CPU1_P1_RX_BUF_DN<2>")
	)
	(segment
		(start 57.016142 -410.884878)
		(end 57.221628 -410.679392)
		(width 0.14224)
		(layer "In13.Cu")
		(net "P5E_CPU1_P1_RX_BUF_DN<2>")
	)
	(segment
		(start 62.649862 -434.165756)
		(end 62.522862 -434.038756)
		(width 0.14224)
		(layer "In13.Cu")
		(net "P5E_CPU1_P1_RX_BUF_DN<2>")
	)
	(segment
		(start 82.003392 -394.565886)
		(end 82.003392 -393.043156)
		(width 0.14224)
		(layer "In13.Cu")
		(net "P5E_CPU1_P1_RX_BUF_DN<2>")
	)
	(segment
		(start 62.649862 -434.48986)
		(end 62.649862 -434.165756)
		(width 0.14224)
		(layer "In13.Cu")
		(net "P5E_CPU1_P1_RX_BUF_DN<2>")
	)
	(segment
		(start 56.000142 -411.508956)
		(end 56.142636 -411.35808)
		(width 0.14224)
		(layer "In13.Cu")
		(net "P5E_CPU1_P1_RX_BUF_DN<2>")
	)
	(segment
		(start 59.217814 -415.34842)
		(end 57.870344 -415.34842)
		(width 0.14224)
		(layer "In13.Cu")
		(net "P5E_CPU1_P1_RX_BUF_DN<2>")
	)
	(segment
		(start 58.040016 -405.624538)
		(end 58.289952 -405.52116)
		(width 0.14224)
		(layer "In13.Cu")
		(net "P5E_CPU1_P1_RX_BUF_DN<2>")
	)
	(segment
		(start 81.11236 -395.179042)
		(end 81.866486 -394.821918)
		(width 0.14224)
		(layer "In13.Cu")
		(net "P5E_CPU1_P1_RX_BUF_DN<2>")
	)
	(segment
		(start 61.694314 -433.574952)
		(end 61.694314 -426.995082)
		(width 0.14224)
		(layer "In13.Cu")
		(net "P5E_CPU1_P1_RX_BUF_DN<2>")
	)
	(segment
		(start 81.866486 -394.821918)
		(end 82.003392 -394.565886)
		(width 0.14224)
		(layer "In13.Cu")
		(net "P5E_CPU1_P1_RX_BUF_DN<2>")
	)
	(segment
		(start 62.522862 -434.038756)
		(end 62.158118 -434.038756)
		(width 0.14224)
		(layer "In13.Cu")
		(net "P5E_CPU1_P1_RX_BUF_DN<2>")
	)
	(segment
		(start 61.651896 -417.63061)
		(end 59.477148 -415.455862)
		(width 0.14224)
		(layer "In13.Cu")
		(net "P5E_CPU1_P1_RX_BUF_DN<2>")
	)
	(segment
		(start 82.310732 -392.735816)
		(end 82.60588 -392.735816)
		(width 0.14224)
		(layer "In13.Cu")
		(net "P5E_CPU1_P1_RX_BUF_DN<2>")
	)
	(segment
		(start 82.003392 -393.043156)
		(end 82.310732 -392.735816)
		(width 0.14224)
		(layer "In13.Cu")
		(net "P5E_CPU1_P1_RX_BUF_DN<2>")
	)
	(segment
		(start 55.743094 -413.06496)
		(end 55.743094 -412.155386)
		(width 0.14224)
		(layer "In13.Cu")
		(net "P5E_CPU1_P1_RX_BUF_DN<2>")
	)
	(segment
		(start 61.689234 -426.990002)
		(end 61.689234 -417.72078)
		(width 0.14224)
		(layer "In13.Cu")
		(net "P5E_CPU1_P1_RX_BUF_DN<2>")
	)
	(segment
		(start 77.608684 -396.174722)
		(end 79.508604 -395.736318)
		(width 0.14224)
		(layer "In13.Cu")
		(net "P5E_CPU1_P1_RX_BUF_DN<2>")
	)
	(segment
		(start 58.559192 -405.341328)
		(end 58.686446 -405.214074)
		(width 0.14224)
		(layer "In13.Cu")
		(net "P5E_CPU1_P1_RX_BUF_DN<2>")
	)
	(segment
		(start 59.114436 -403.173946)
		(end 59.292744 -403.032214)
		(width 0.14224)
		(layer "In13.Cu")
		(net "P5E_CPU1_P1_RX_BUF_DN<2>")
	)
	(segment
		(start 57.51322 -415.200592)
		(end 56.001412 -413.688784)
		(width 0.14224)
		(layer "In13.Cu")
		(net "P5E_CPU1_P1_RX_BUF_DN<2>")
	)
	(segment
		(start 58.806334 -404.924514)
		(end 58.806334 -404.028402)
		(width 0.14224)
		(layer "In13.Cu")
		(net "P5E_CPU1_P1_RX_BUF_DN<2>")
	)
	(segment
		(start 82.60588 -392.735816)
		(end 82.74431 -392.597386)
		(width 0.14224)
		(layer "In13.Cu")
		(net "P5E_CPU1_P1_RX_BUF_DN<2>")
	)
	(segment
		(start 82.74431 -392.597386)
		(end 82.74431 -392.429238)
		(width 0.14224)
		(layer "In13.Cu")
		(net "P5E_CPU1_P1_RX_BUF_DN<2>")
	)
	(segment
		(start 58.289952 -405.52116)
		(end 58.559192 -405.341328)
		(width 0.14224)
		(layer "In13.Cu")
		(net "P5E_CPU1_P1_RX_BUF_DN<2>")
	)
	(segment
		(start 79.508604 -395.736318)
		(end 81.11236 -395.179042)
		(width 0.14224)
		(layer "In13.Cu")
		(net "P5E_CPU1_P1_RX_BUF_DN<2>")
	)
	(segment
		(start 56.284368 -411.260798)
		(end 56.730646 -411.075886)
		(width 0.14224)
		(layer "In13.Cu")
		(net "P5E_CPU1_P1_RX_BUF_DN<2>")
	)
	(arc
		(start 58.914538 -403.475444)
		(mid 58.990613 -403.308864)
		(end 59.114436 -403.173946)
		(width 0.14224)
		(layer "In13.Cu")
		(net "P5E_CPU1_P1_RX_BUF_DN<2>")
	)
	(arc
		(start 58.806334 -404.028402)
		(mid 58.817297 -403.866646)
		(end 58.850022 -403.707854)
		(width 0.14224)
		(layer "In13.Cu")
		(net "P5E_CPU1_P1_RX_BUF_DN<2>")
	)
	(arc
		(start 61.689234 -417.72078)
		(mid 61.679528 -417.671985)
		(end 61.651896 -417.63061)
		(width 0.14224)
		(layer "In13.Cu")
		(net "P5E_CPU1_P1_RX_BUF_DN<2>")
	)
	(arc
		(start 59.477148 -415.455862)
		(mid 59.358165 -415.37636)
		(end 59.217814 -415.34842)
		(width 0.14224)
		(layer "In13.Cu")
		(net "P5E_CPU1_P1_RX_BUF_DN<2>")
	)
	(arc
		(start 57.870344 -415.34842)
		(mid 57.677093 -415.309998)
		(end 57.51322 -415.200592)
		(width 0.14224)
		(layer "In13.Cu")
		(net "P5E_CPU1_P1_RX_BUF_DN<2>")
	)
	(arc
		(start 55.743094 -412.155386)
		(mid 55.80961 -411.807507)
		(end 56.000142 -411.508956)
		(width 0.14224)
		(layer "In13.Cu")
		(net "P5E_CPU1_P1_RX_BUF_DN<2>")
	)
	(arc
		(start 56.142636 -411.35808)
		(mid 56.208374 -411.301967)
		(end 56.284368 -411.260798)
		(width 0.14224)
		(layer "In13.Cu")
		(net "P5E_CPU1_P1_RX_BUF_DN<2>")
	)
	(arc
		(start 57.562242 -405.94407)
		(mid 57.785407 -405.760796)
		(end 58.040016 -405.624538)
		(width 0.14224)
		(layer "In13.Cu")
		(net "P5E_CPU1_P1_RX_BUF_DN<2>")
	)
	(arc
		(start 56.730646 -411.075886)
		(mid 56.882771 -410.9944)
		(end 57.016142 -410.884878)
		(width 0.14224)
		(layer "In13.Cu")
		(net "P5E_CPU1_P1_RX_BUF_DN<2>")
	)
	(arc
		(start 57.274714 -406.638252)
		(mid 57.349404 -406.262557)
		(end 57.562242 -405.94407)
		(width 0.14224)
		(layer "In13.Cu")
		(net "P5E_CPU1_P1_RX_BUF_DN<2>")
	)
	(arc
		(start 58.686446 -405.214074)
		(mid 58.775161 -405.081209)
		(end 58.806334 -404.924514)
		(width 0.14224)
		(layer "In13.Cu")
		(net "P5E_CPU1_P1_RX_BUF_DN<2>")
	)
	(arc
		(start 59.292744 -403.032214)
		(mid 59.378761 -402.973639)
		(end 59.472322 -402.928074)
		(width 0.14224)
		(layer "In13.Cu")
		(net "P5E_CPU1_P1_RX_BUF_DN<2>")
	)
	(arc
		(start 57.221628 -410.679392)
		(mid 57.260897 -410.620527)
		(end 57.274714 -410.551122)
		(width 0.14224)
		(layer "In13.Cu")
		(net "P5E_CPU1_P1_RX_BUF_DN<2>")
	)
	(arc
		(start 56.001412 -413.688784)
		(mid 55.810224 -413.402557)
		(end 55.743094 -413.06496)
		(width 0.14224)
		(layer "In13.Cu")
		(net "P5E_CPU1_P1_RX_BUF_DN<2>")
	)
	(segment
		(start 81.057496 -391.666984)
		(end 81.057496 -392.634216)
		(width 0.1016)
		(layer "F.Cu")
		(net "P5E_CPU1_P1_RX_BUF_DN<1>")
	)
	(segment
		(start 81.184496 -392.761216)
		(end 81.403444 -392.761216)
		(width 0.1016)
		(layer "F.Cu")
		(net "P5E_CPU1_P1_RX_BUF_DN<1>")
	)
	(segment
		(start 81.145634 -390.761474)
		(end 81.146142 -390.761982)
		(width 0.1016)
		(layer "F.Cu")
		(net "P5E_CPU1_P1_RX_BUF_DN<1>")
	)
	(segment
		(start 81.057496 -392.634216)
		(end 81.184496 -392.761216)
		(width 0.1016)
		(layer "F.Cu")
		(net "P5E_CPU1_P1_RX_BUF_DN<1>")
	)
	(segment
		(start 81.54416 -392.6205)
		(end 81.54416 -392.429238)
		(width 0.1016)
		(layer "F.Cu")
		(net "P5E_CPU1_P1_RX_BUF_DN<1>")
	)
	(segment
		(start 81.146142 -391.578338)
		(end 81.057496 -391.666984)
		(width 0.1016)
		(layer "F.Cu")
		(net "P5E_CPU1_P1_RX_BUF_DN<1>")
	)
	(segment
		(start 81.146142 -390.761982)
		(end 81.146142 -391.578338)
		(width 0.1016)
		(layer "F.Cu")
		(net "P5E_CPU1_P1_RX_BUF_DN<1>")
	)
	(segment
		(start 81.403444 -392.761216)
		(end 81.54416 -392.6205)
		(width 0.1016)
		(layer "F.Cu")
		(net "P5E_CPU1_P1_RX_BUF_DN<1>")
	)
	(segment
		(start 60.649866 -435.489858)
		(end 60.649866 -435.165754)
		(width 0.14224)
		(layer "In13.Cu")
		(net "P5E_CPU1_P1_RX_BUF_DN<1>")
	)
	(segment
		(start 52.941474 -411.454346)
		(end 53.894228 -411.059376)
		(width 0.14224)
		(layer "In13.Cu")
		(net "P5E_CPU1_P1_RX_BUF_DN<1>")
	)
	(segment
		(start 81.40573 -392.735816)
		(end 81.54416 -392.597386)
		(width 0.14224)
		(layer "In13.Cu")
		(net "P5E_CPU1_P1_RX_BUF_DN<1>")
	)
	(segment
		(start 81.54416 -392.597386)
		(end 81.54416 -392.429238)
		(width 0.14224)
		(layer "In13.Cu")
		(net "P5E_CPU1_P1_RX_BUF_DN<1>")
	)
	(segment
		(start 55.495952 -405.341328)
		(end 55.623206 -405.214074)
		(width 0.14224)
		(layer "In13.Cu")
		(net "P5E_CPU1_P1_RX_BUF_DN<1>")
	)
	(segment
		(start 52.679854 -413.234378)
		(end 52.679854 -411.846014)
		(width 0.14224)
		(layer "In13.Cu")
		(net "P5E_CPU1_P1_RX_BUF_DN<1>")
	)
	(segment
		(start 55.743094 -404.924514)
		(end 55.743094 -403.989286)
		(width 0.14224)
		(layer "In13.Cu")
		(net "P5E_CPU1_P1_RX_BUF_DN<1>")
	)
	(segment
		(start 55.226712 -405.52116)
		(end 55.495952 -405.341328)
		(width 0.14224)
		(layer "In13.Cu")
		(net "P5E_CPU1_P1_RX_BUF_DN<1>")
	)
	(segment
		(start 56.290718 -403.170136)
		(end 70.576694 -397.260826)
		(width 0.14224)
		(layer "In13.Cu")
		(net "P5E_CPU1_P1_RX_BUF_DN<1>")
	)
	(segment
		(start 79.362554 -394.793724)
		(end 80.532732 -394.372846)
		(width 0.14224)
		(layer "In13.Cu")
		(net "P5E_CPU1_P1_RX_BUF_DN<1>")
	)
	(segment
		(start 55.92191 -416.682682)
		(end 52.82565 -413.586422)
		(width 0.14224)
		(layer "In13.Cu")
		(net "P5E_CPU1_P1_RX_BUF_DN<1>")
	)
	(segment
		(start 60.158122 -435.038754)
		(end 59.694318 -434.57495)
		(width 0.14224)
		(layer "In13.Cu")
		(net "P5E_CPU1_P1_RX_BUF_DN<1>")
	)
	(segment
		(start 73.494138 -396.2781)
		(end 76.27747 -395.495018)
		(width 0.14224)
		(layer "In13.Cu")
		(net "P5E_CPU1_P1_RX_BUF_DN<1>")
	)
	(segment
		(start 80.803242 -394.140182)
		(end 80.803242 -393.043156)
		(width 0.14224)
		(layer "In13.Cu")
		(net "P5E_CPU1_P1_RX_BUF_DN<1>")
	)
	(segment
		(start 80.803242 -393.043156)
		(end 81.110582 -392.735816)
		(width 0.14224)
		(layer "In13.Cu")
		(net "P5E_CPU1_P1_RX_BUF_DN<1>")
	)
	(segment
		(start 54.211474 -410.697426)
		(end 54.211474 -406.638252)
		(width 0.14224)
		(layer "In13.Cu")
		(net "P5E_CPU1_P1_RX_BUF_DN<1>")
	)
	(segment
		(start 70.576694 -397.260826)
		(end 73.494138 -396.2781)
		(width 0.14224)
		(layer "In13.Cu")
		(net "P5E_CPU1_P1_RX_BUF_DN<1>")
	)
	(segment
		(start 53.99786 -410.988256)
		(end 54.1655 -410.812234)
		(width 0.14224)
		(layer "In13.Cu")
		(net "P5E_CPU1_P1_RX_BUF_DN<1>")
	)
	(segment
		(start 59.576208 -417.186872)
		(end 59.336432 -416.947096)
		(width 0.14224)
		(layer "In13.Cu")
		(net "P5E_CPU1_P1_RX_BUF_DN<1>")
	)
	(segment
		(start 80.532732 -394.372846)
		(end 80.803242 -394.140182)
		(width 0.14224)
		(layer "In13.Cu")
		(net "P5E_CPU1_P1_RX_BUF_DN<1>")
	)
	(segment
		(start 59.689238 -426.990002)
		(end 59.689238 -417.459922)
		(width 0.14224)
		(layer "In13.Cu")
		(net "P5E_CPU1_P1_RX_BUF_DN<1>")
	)
	(segment
		(start 59.694318 -434.57495)
		(end 59.694318 -426.995082)
		(width 0.14224)
		(layer "In13.Cu")
		(net "P5E_CPU1_P1_RX_BUF_DN<1>")
	)
	(segment
		(start 59.694318 -426.995082)
		(end 59.689238 -426.990002)
		(width 0.14224)
		(layer "In13.Cu")
		(net "P5E_CPU1_P1_RX_BUF_DN<1>")
	)
	(segment
		(start 60.522866 -435.038754)
		(end 60.158122 -435.038754)
		(width 0.14224)
		(layer "In13.Cu")
		(net "P5E_CPU1_P1_RX_BUF_DN<1>")
	)
	(segment
		(start 60.649866 -435.165754)
		(end 60.522866 -435.038754)
		(width 0.14224)
		(layer "In13.Cu")
		(net "P5E_CPU1_P1_RX_BUF_DN<1>")
	)
	(segment
		(start 76.27747 -395.495018)
		(end 79.362554 -394.793724)
		(width 0.14224)
		(layer "In13.Cu")
		(net "P5E_CPU1_P1_RX_BUF_DN<1>")
	)
	(segment
		(start 54.976776 -405.624538)
		(end 55.226712 -405.52116)
		(width 0.14224)
		(layer "In13.Cu")
		(net "P5E_CPU1_P1_RX_BUF_DN<1>")
	)
	(segment
		(start 81.110582 -392.735816)
		(end 81.40573 -392.735816)
		(width 0.14224)
		(layer "In13.Cu")
		(net "P5E_CPU1_P1_RX_BUF_DN<1>")
	)
	(segment
		(start 59.09564 -416.847274)
		(end 56.319166 -416.847274)
		(width 0.14224)
		(layer "In13.Cu")
		(net "P5E_CPU1_P1_RX_BUF_DN<1>")
	)
	(arc
		(start 54.211474 -406.638252)
		(mid 54.286164 -406.262557)
		(end 54.499002 -405.94407)
		(width 0.14224)
		(layer "In13.Cu")
		(net "P5E_CPU1_P1_RX_BUF_DN<1>")
	)
	(arc
		(start 53.894228 -411.059376)
		(mid 53.949766 -411.02924)
		(end 53.99786 -410.988256)
		(width 0.14224)
		(layer "In13.Cu")
		(net "P5E_CPU1_P1_RX_BUF_DN<1>")
	)
	(arc
		(start 59.689238 -417.459922)
		(mid 59.659864 -417.312161)
		(end 59.576208 -417.186872)
		(width 0.14224)
		(layer "In13.Cu")
		(net "P5E_CPU1_P1_RX_BUF_DN<1>")
	)
	(arc
		(start 56.319166 -416.847274)
		(mid 56.10417 -416.804491)
		(end 55.92191 -416.682682)
		(width 0.14224)
		(layer "In13.Cu")
		(net "P5E_CPU1_P1_RX_BUF_DN<1>")
	)
	(arc
		(start 59.336432 -416.947096)
		(mid 59.22597 -416.873224)
		(end 59.09564 -416.847274)
		(width 0.14224)
		(layer "In13.Cu")
		(net "P5E_CPU1_P1_RX_BUF_DN<1>")
	)
	(arc
		(start 54.499002 -405.94407)
		(mid 54.722167 -405.760796)
		(end 54.976776 -405.624538)
		(width 0.14224)
		(layer "In13.Cu")
		(net "P5E_CPU1_P1_RX_BUF_DN<1>")
	)
	(arc
		(start 55.743094 -403.989286)
		(mid 55.892609 -403.496616)
		(end 56.290718 -403.170136)
		(width 0.14224)
		(layer "In13.Cu")
		(net "P5E_CPU1_P1_RX_BUF_DN<1>")
	)
	(arc
		(start 54.1655 -410.812234)
		(mid 54.199547 -410.75926)
		(end 54.211474 -410.697426)
		(width 0.14224)
		(layer "In13.Cu")
		(net "P5E_CPU1_P1_RX_BUF_DN<1>")
	)
	(arc
		(start 52.82565 -413.586422)
		(mid 52.717726 -413.424903)
		(end 52.679854 -413.234378)
		(width 0.14224)
		(layer "In13.Cu")
		(net "P5E_CPU1_P1_RX_BUF_DN<1>")
	)
	(arc
		(start 55.623206 -405.214074)
		(mid 55.711921 -405.081209)
		(end 55.743094 -404.924514)
		(width 0.14224)
		(layer "In13.Cu")
		(net "P5E_CPU1_P1_RX_BUF_DN<1>")
	)
	(arc
		(start 52.679854 -411.846014)
		(mid 52.751205 -411.610456)
		(end 52.941474 -411.454346)
		(width 0.14224)
		(layer "In13.Cu")
		(net "P5E_CPU1_P1_RX_BUF_DN<1>")
	)
	(segment
		(start 98.182938 -392.761216)
		(end 97.984564 -392.761216)
		(width 0.1016)
		(layer "F.Cu")
		(net "P5E_CPU1_P1_RX_BUF_DN<15>")
	)
	(segment
		(start 97.94621 -390.761982)
		(end 97.945702 -390.761474)
		(width 0.1016)
		(layer "F.Cu")
		(net "P5E_CPU1_P1_RX_BUF_DN<15>")
	)
	(segment
		(start 97.984564 -392.761216)
		(end 97.857564 -392.634216)
		(width 0.1016)
		(layer "F.Cu")
		(net "P5E_CPU1_P1_RX_BUF_DN<15>")
	)
	(segment
		(start 97.857564 -391.666984)
		(end 97.94621 -391.578338)
		(width 0.1016)
		(layer "F.Cu")
		(net "P5E_CPU1_P1_RX_BUF_DN<15>")
	)
	(segment
		(start 97.94621 -391.578338)
		(end 97.94621 -390.761982)
		(width 0.1016)
		(layer "F.Cu")
		(net "P5E_CPU1_P1_RX_BUF_DN<15>")
	)
	(segment
		(start 98.344228 -392.599926)
		(end 98.182938 -392.761216)
		(width 0.1016)
		(layer "F.Cu")
		(net "P5E_CPU1_P1_RX_BUF_DN<15>")
	)
	(segment
		(start 98.344228 -392.429238)
		(end 98.344228 -392.599926)
		(width 0.1016)
		(layer "F.Cu")
		(net "P5E_CPU1_P1_RX_BUF_DN<15>")
	)
	(segment
		(start 97.857564 -392.634216)
		(end 97.857564 -391.666984)
		(width 0.1016)
		(layer "F.Cu")
		(net "P5E_CPU1_P1_RX_BUF_DN<15>")
	)
	(segment
		(start 98.344228 -392.429238)
		(end 98.344228 -392.597386)
		(width 0.14224)
		(layer "In13.Cu")
		(net "P5E_CPU1_P1_RX_BUF_DN<15>")
	)
	(segment
		(start 98.205798 -392.735816)
		(end 97.91065 -392.735816)
		(width 0.14224)
		(layer "In13.Cu")
		(net "P5E_CPU1_P1_RX_BUF_DN<15>")
	)
	(segment
		(start 97.60331 -409.207716)
		(end 97.512632 -409.635706)
		(width 0.14224)
		(layer "In13.Cu")
		(net "P5E_CPU1_P1_RX_BUF_DN<15>")
	)
	(segment
		(start 98.344228 -392.597386)
		(end 98.205798 -392.735816)
		(width 0.14224)
		(layer "In13.Cu")
		(net "P5E_CPU1_P1_RX_BUF_DN<15>")
	)
	(segment
		(start 89.50579 -435.021482)
		(end 89.650062 -435.165754)
		(width 0.14224)
		(layer "In13.Cu")
		(net "P5E_CPU1_P1_RX_BUF_DN<15>")
	)
	(segment
		(start 96.564958 -412.074614)
		(end 96.564958 -412.834328)
		(width 0.14224)
		(layer "In13.Cu")
		(net "P5E_CPU1_P1_RX_BUF_DN<15>")
	)
	(segment
		(start 96.809052 -411.222952)
		(end 96.68637 -411.500066)
		(width 0.14224)
		(layer "In13.Cu")
		(net "P5E_CPU1_P1_RX_BUF_DN<15>")
	)
	(segment
		(start 97.512632 -409.635706)
		(end 96.809306 -411.222952)
		(width 0.14224)
		(layer "In13.Cu")
		(net "P5E_CPU1_P1_RX_BUF_DN<15>")
	)
	(segment
		(start 96.29521 -413.485584)
		(end 88.891618 -420.889176)
		(width 0.14224)
		(layer "In13.Cu")
		(net "P5E_CPU1_P1_RX_BUF_DN<15>")
	)
	(segment
		(start 97.60331 -393.043156)
		(end 97.60331 -409.207716)
		(width 0.14224)
		(layer "In13.Cu")
		(net "P5E_CPU1_P1_RX_BUF_DN<15>")
	)
	(segment
		(start 89.141046 -435.021482)
		(end 89.50579 -435.021482)
		(width 0.14224)
		(layer "In13.Cu")
		(net "P5E_CPU1_P1_RX_BUF_DN<15>")
	)
	(segment
		(start 88.68918 -421.378126)
		(end 88.68918 -426.990002)
		(width 0.14224)
		(layer "In13.Cu")
		(net "P5E_CPU1_P1_RX_BUF_DN<15>")
	)
	(segment
		(start 89.650062 -435.165754)
		(end 89.650062 -435.489858)
		(width 0.14224)
		(layer "In13.Cu")
		(net "P5E_CPU1_P1_RX_BUF_DN<15>")
	)
	(segment
		(start 96.809306 -411.222952)
		(end 96.809052 -411.222952)
		(width 0.14224)
		(layer "In13.Cu")
		(net "P5E_CPU1_P1_RX_BUF_DN<15>")
	)
	(segment
		(start 97.91065 -392.735816)
		(end 97.60331 -393.043156)
		(width 0.14224)
		(layer "In13.Cu")
		(net "P5E_CPU1_P1_RX_BUF_DN<15>")
	)
	(segment
		(start 88.68918 -426.990002)
		(end 88.694514 -426.995336)
		(width 0.14224)
		(layer "In13.Cu")
		(net "P5E_CPU1_P1_RX_BUF_DN<15>")
	)
	(segment
		(start 88.694514 -426.995336)
		(end 88.694514 -434.57495)
		(width 0.14224)
		(layer "In13.Cu")
		(net "P5E_CPU1_P1_RX_BUF_DN<15>")
	)
	(segment
		(start 88.694514 -434.57495)
		(end 89.141046 -435.021482)
		(width 0.14224)
		(layer "In13.Cu")
		(net "P5E_CPU1_P1_RX_BUF_DN<15>")
	)
	(arc
		(start 96.68637 -411.500066)
		(mid 96.595628 -411.78099)
		(end 96.564958 -412.074614)
		(width 0.14224)
		(layer "In13.Cu")
		(net "P5E_CPU1_P1_RX_BUF_DN<15>")
	)
	(arc
		(start 88.891618 -420.889176)
		(mid 88.741778 -421.113522)
		(end 88.68918 -421.378126)
		(width 0.14224)
		(layer "In13.Cu")
		(net "P5E_CPU1_P1_RX_BUF_DN<15>")
	)
	(arc
		(start 96.564958 -412.834328)
		(mid 96.494851 -413.186781)
		(end 96.29521 -413.485584)
		(width 0.14224)
		(layer "In13.Cu")
		(net "P5E_CPU1_P1_RX_BUF_DN<15>")
	)
	(segment
		(start 96.657668 -392.634216)
		(end 96.657668 -391.666984)
		(width 0.1016)
		(layer "F.Cu")
		(net "P5E_CPU1_P1_RX_BUF_DN<14>")
	)
	(segment
		(start 96.746314 -390.761982)
		(end 96.745806 -390.761474)
		(width 0.1016)
		(layer "F.Cu")
		(net "P5E_CPU1_P1_RX_BUF_DN<14>")
	)
	(segment
		(start 97.144332 -392.429238)
		(end 97.144332 -392.59383)
		(width 0.1016)
		(layer "F.Cu")
		(net "P5E_CPU1_P1_RX_BUF_DN<14>")
	)
	(segment
		(start 96.784668 -392.761216)
		(end 96.657668 -392.634216)
		(width 0.1016)
		(layer "F.Cu")
		(net "P5E_CPU1_P1_RX_BUF_DN<14>")
	)
	(segment
		(start 96.746314 -391.578338)
		(end 96.746314 -390.761982)
		(width 0.1016)
		(layer "F.Cu")
		(net "P5E_CPU1_P1_RX_BUF_DN<14>")
	)
	(segment
		(start 97.144332 -392.59383)
		(end 96.976946 -392.761216)
		(width 0.1016)
		(layer "F.Cu")
		(net "P5E_CPU1_P1_RX_BUF_DN<14>")
	)
	(segment
		(start 96.657668 -391.666984)
		(end 96.746314 -391.578338)
		(width 0.1016)
		(layer "F.Cu")
		(net "P5E_CPU1_P1_RX_BUF_DN<14>")
	)
	(segment
		(start 96.976946 -392.761216)
		(end 96.784668 -392.761216)
		(width 0.1016)
		(layer "F.Cu")
		(net "P5E_CPU1_P1_RX_BUF_DN<14>")
	)
	(segment
		(start 92.501974 -411.846014)
		(end 92.501974 -414.626298)
		(width 0.14224)
		(layer "In13.Cu")
		(net "P5E_CPU1_P1_RX_BUF_DN<14>")
	)
	(segment
		(start 97.144332 -392.597386)
		(end 97.005902 -392.735816)
		(width 0.14224)
		(layer "In13.Cu")
		(net "P5E_CPU1_P1_RX_BUF_DN<14>")
	)
	(segment
		(start 86.694518 -433.574952)
		(end 87.150448 -434.030882)
		(width 0.14224)
		(layer "In13.Cu")
		(net "P5E_CPU1_P1_RX_BUF_DN<14>")
	)
	(segment
		(start 96.319848 -397.25346)
		(end 95.555816 -405.013414)
		(width 0.14224)
		(layer "In13.Cu")
		(net "P5E_CPU1_P1_RX_BUF_DN<14>")
	)
	(segment
		(start 95.337122 -405.345392)
		(end 94.413324 -405.857202)
		(width 0.14224)
		(layer "In13.Cu")
		(net "P5E_CPU1_P1_RX_BUF_DN<14>")
	)
	(segment
		(start 96.710754 -392.735816)
		(end 96.403414 -393.043156)
		(width 0.14224)
		(layer "In13.Cu")
		(net "P5E_CPU1_P1_RX_BUF_DN<14>")
	)
	(segment
		(start 87.150448 -434.030882)
		(end 87.515192 -434.030882)
		(width 0.14224)
		(layer "In13.Cu")
		(net "P5E_CPU1_P1_RX_BUF_DN<14>")
	)
	(segment
		(start 93.98762 -410.812234)
		(end 93.81998 -410.988256)
		(width 0.14224)
		(layer "In13.Cu")
		(net "P5E_CPU1_P1_RX_BUF_DN<14>")
	)
	(segment
		(start 94.033594 -406.637998)
		(end 94.033594 -410.697426)
		(width 0.14224)
		(layer "In13.Cu")
		(net "P5E_CPU1_P1_RX_BUF_DN<14>")
	)
	(segment
		(start 87.515192 -434.030882)
		(end 87.650066 -434.165756)
		(width 0.14224)
		(layer "In13.Cu")
		(net "P5E_CPU1_P1_RX_BUF_DN<14>")
	)
	(segment
		(start 97.144332 -392.429238)
		(end 97.144332 -392.597386)
		(width 0.14224)
		(layer "In13.Cu")
		(net "P5E_CPU1_P1_RX_BUF_DN<14>")
	)
	(segment
		(start 92.323158 -415.057844)
		(end 87.028528 -420.352474)
		(width 0.14224)
		(layer "In13.Cu")
		(net "P5E_CPU1_P1_RX_BUF_DN<14>")
	)
	(segment
		(start 86.689184 -421.171878)
		(end 86.689184 -426.990002)
		(width 0.14224)
		(layer "In13.Cu")
		(net "P5E_CPU1_P1_RX_BUF_DN<14>")
	)
	(segment
		(start 97.005902 -392.735816)
		(end 96.710754 -392.735816)
		(width 0.14224)
		(layer "In13.Cu")
		(net "P5E_CPU1_P1_RX_BUF_DN<14>")
	)
	(segment
		(start 86.689184 -426.990002)
		(end 86.694518 -426.995336)
		(width 0.14224)
		(layer "In13.Cu")
		(net "P5E_CPU1_P1_RX_BUF_DN<14>")
	)
	(segment
		(start 93.716348 -411.059376)
		(end 92.763594 -411.454346)
		(width 0.14224)
		(layer "In13.Cu")
		(net "P5E_CPU1_P1_RX_BUF_DN<14>")
	)
	(segment
		(start 87.650066 -434.165756)
		(end 87.650066 -434.48986)
		(width 0.14224)
		(layer "In13.Cu")
		(net "P5E_CPU1_P1_RX_BUF_DN<14>")
	)
	(segment
		(start 96.403414 -393.043156)
		(end 96.403414 -395.553692)
		(width 0.14224)
		(layer "In13.Cu")
		(net "P5E_CPU1_P1_RX_BUF_DN<14>")
	)
	(segment
		(start 86.694518 -426.995336)
		(end 86.694518 -433.574952)
		(width 0.14224)
		(layer "In13.Cu")
		(net "P5E_CPU1_P1_RX_BUF_DN<14>")
	)
	(arc
		(start 94.033594 -410.697426)
		(mid 94.021675 -410.759263)
		(end 93.98762 -410.812234)
		(width 0.14224)
		(layer "In13.Cu")
		(net "P5E_CPU1_P1_RX_BUF_DN<14>")
	)
	(arc
		(start 95.555816 -405.013414)
		(mid 95.487395 -405.206382)
		(end 95.337122 -405.345392)
		(width 0.14224)
		(layer "In13.Cu")
		(net "P5E_CPU1_P1_RX_BUF_DN<14>")
	)
	(arc
		(start 87.028528 -420.352474)
		(mid 86.777383 -420.728434)
		(end 86.689184 -421.171878)
		(width 0.14224)
		(layer "In13.Cu")
		(net "P5E_CPU1_P1_RX_BUF_DN<14>")
	)
	(arc
		(start 94.224348 -406.028144)
		(mid 94.082312 -406.318482)
		(end 94.033594 -406.637998)
		(width 0.14224)
		(layer "In13.Cu")
		(net "P5E_CPU1_P1_RX_BUF_DN<14>")
	)
	(arc
		(start 92.763594 -411.454346)
		(mid 92.573356 -411.610478)
		(end 92.501974 -411.846014)
		(width 0.14224)
		(layer "In13.Cu")
		(net "P5E_CPU1_P1_RX_BUF_DN<14>")
	)
	(arc
		(start 93.81998 -410.988256)
		(mid 93.771891 -411.029248)
		(end 93.716348 -411.059376)
		(width 0.14224)
		(layer "In13.Cu")
		(net "P5E_CPU1_P1_RX_BUF_DN<14>")
	)
	(arc
		(start 92.501974 -414.626298)
		(mid 92.455498 -414.859859)
		(end 92.323158 -415.057844)
		(width 0.14224)
		(layer "In13.Cu")
		(net "P5E_CPU1_P1_RX_BUF_DN<14>")
	)
	(arc
		(start 94.413324 -405.857202)
		(mid 94.309012 -405.931808)
		(end 94.224348 -406.028144)
		(width 0.14224)
		(layer "In13.Cu")
		(net "P5E_CPU1_P1_RX_BUF_DN<14>")
	)
	(arc
		(start 96.403414 -395.553692)
		(mid 96.382493 -396.404602)
		(end 96.319848 -397.25346)
		(width 0.14224)
		(layer "In13.Cu")
		(net "P5E_CPU1_P1_RX_BUF_DN<14>")
	)
	(segment
		(start 95.545656 -390.761474)
		(end 95.546164 -390.761982)
		(width 0.1016)
		(layer "F.Cu")
		(net "P5E_CPU1_P1_RX_BUF_DN<13>")
	)
	(segment
		(start 95.466154 -391.658348)
		(end 95.466154 -392.634216)
		(width 0.1016)
		(layer "F.Cu")
		(net "P5E_CPU1_P1_RX_BUF_DN<13>")
	)
	(segment
		(start 95.546164 -390.761982)
		(end 95.546164 -391.578338)
		(width 0.1016)
		(layer "F.Cu")
		(net "P5E_CPU1_P1_RX_BUF_DN<13>")
	)
	(segment
		(start 95.944182 -392.6205)
		(end 95.944182 -392.429238)
		(width 0.1016)
		(layer "F.Cu")
		(net "P5E_CPU1_P1_RX_BUF_DN<13>")
	)
	(segment
		(start 95.803466 -392.761216)
		(end 95.944182 -392.6205)
		(width 0.1016)
		(layer "F.Cu")
		(net "P5E_CPU1_P1_RX_BUF_DN<13>")
	)
	(segment
		(start 95.466154 -392.634216)
		(end 95.593154 -392.761216)
		(width 0.1016)
		(layer "F.Cu")
		(net "P5E_CPU1_P1_RX_BUF_DN<13>")
	)
	(segment
		(start 95.593154 -392.761216)
		(end 95.803466 -392.761216)
		(width 0.1016)
		(layer "F.Cu")
		(net "P5E_CPU1_P1_RX_BUF_DN<13>")
	)
	(segment
		(start 95.546164 -391.578338)
		(end 95.466154 -391.658348)
		(width 0.1016)
		(layer "F.Cu")
		(net "P5E_CPU1_P1_RX_BUF_DN<13>")
	)
	(segment
		(start 95.197168 -394.325856)
		(end 94.933262 -395.65326)
		(width 0.14224)
		(layer "In13.Cu")
		(net "P5E_CPU1_P1_RX_BUF_DN<13>")
	)
	(segment
		(start 92.382086 -405.214074)
		(end 92.254832 -405.341328)
		(width 0.14224)
		(layer "In13.Cu")
		(net "P5E_CPU1_P1_RX_BUF_DN<13>")
	)
	(segment
		(start 94.901004 -395.774926)
		(end 94.900496 -395.77645)
		(width 0.14224)
		(layer "In13.Cu")
		(net "P5E_CPU1_P1_RX_BUF_DN<13>")
	)
	(segment
		(start 89.177876 -414.35528)
		(end 85.059012 -418.474144)
		(width 0.14224)
		(layer "In13.Cu")
		(net "P5E_CPU1_P1_RX_BUF_DN<13>")
	)
	(segment
		(start 95.203264 -393.043156)
		(end 95.203264 -394.262864)
		(width 0.14224)
		(layer "In13.Cu")
		(net "P5E_CPU1_P1_RX_BUF_DN<13>")
	)
	(segment
		(start 95.510604 -392.735816)
		(end 95.203264 -393.043156)
		(width 0.14224)
		(layer "In13.Cu")
		(net "P5E_CPU1_P1_RX_BUF_DN<13>")
	)
	(segment
		(start 94.62135 -396.556484)
		(end 93.101414 -400.804126)
		(width 0.14224)
		(layer "In13.Cu")
		(net "P5E_CPU1_P1_RX_BUF_DN<13>")
	)
	(segment
		(start 90.970354 -406.638252)
		(end 90.970354 -410.697426)
		(width 0.14224)
		(layer "In13.Cu")
		(net "P5E_CPU1_P1_RX_BUF_DN<13>")
	)
	(segment
		(start 85.506052 -435.021736)
		(end 85.65007 -435.165754)
		(width 0.14224)
		(layer "In13.Cu")
		(net "P5E_CPU1_P1_RX_BUF_DN<13>")
	)
	(segment
		(start 85.141308 -435.021736)
		(end 85.506052 -435.021736)
		(width 0.14224)
		(layer "In13.Cu")
		(net "P5E_CPU1_P1_RX_BUF_DN<13>")
	)
	(segment
		(start 84.694522 -434.57495)
		(end 85.141308 -435.021736)
		(width 0.14224)
		(layer "In13.Cu")
		(net "P5E_CPU1_P1_RX_BUF_DN<13>")
	)
	(segment
		(start 90.92438 -410.812234)
		(end 90.75674 -410.988256)
		(width 0.14224)
		(layer "In13.Cu")
		(net "P5E_CPU1_P1_RX_BUF_DN<13>")
	)
	(segment
		(start 91.985592 -405.52116)
		(end 91.735656 -405.624538)
		(width 0.14224)
		(layer "In13.Cu")
		(net "P5E_CPU1_P1_RX_BUF_DN<13>")
	)
	(segment
		(start 84.694522 -426.995336)
		(end 84.694522 -434.57495)
		(width 0.14224)
		(layer "In13.Cu")
		(net "P5E_CPU1_P1_RX_BUF_DN<13>")
	)
	(segment
		(start 90.653108 -411.059376)
		(end 89.700354 -411.454346)
		(width 0.14224)
		(layer "In13.Cu")
		(net "P5E_CPU1_P1_RX_BUF_DN<13>")
	)
	(segment
		(start 94.900496 -395.77645)
		(end 94.62135 -396.556484)
		(width 0.14224)
		(layer "In13.Cu")
		(net "P5E_CPU1_P1_RX_BUF_DN<13>")
	)
	(segment
		(start 84.689188 -419.366954)
		(end 84.689188 -426.990002)
		(width 0.14224)
		(layer "In13.Cu")
		(net "P5E_CPU1_P1_RX_BUF_DN<13>")
	)
	(segment
		(start 84.689188 -426.990002)
		(end 84.694522 -426.995336)
		(width 0.14224)
		(layer "In13.Cu")
		(net "P5E_CPU1_P1_RX_BUF_DN<13>")
	)
	(segment
		(start 95.805752 -392.735816)
		(end 95.510604 -392.735816)
		(width 0.14224)
		(layer "In13.Cu")
		(net "P5E_CPU1_P1_RX_BUF_DN<13>")
	)
	(segment
		(start 89.438734 -411.846014)
		(end 89.438734 -413.725614)
		(width 0.14224)
		(layer "In13.Cu")
		(net "P5E_CPU1_P1_RX_BUF_DN<13>")
	)
	(segment
		(start 92.501974 -403.975316)
		(end 92.501974 -404.924514)
		(width 0.14224)
		(layer "In13.Cu")
		(net "P5E_CPU1_P1_RX_BUF_DN<13>")
	)
	(segment
		(start 92.254832 -405.341328)
		(end 91.985592 -405.52116)
		(width 0.14224)
		(layer "In13.Cu")
		(net "P5E_CPU1_P1_RX_BUF_DN<13>")
	)
	(segment
		(start 93.05671 -400.965924)
		(end 92.5449 -403.539452)
		(width 0.14224)
		(layer "In13.Cu")
		(net "P5E_CPU1_P1_RX_BUF_DN<13>")
	)
	(segment
		(start 95.944182 -392.429238)
		(end 95.944182 -392.597386)
		(width 0.14224)
		(layer "In13.Cu")
		(net "P5E_CPU1_P1_RX_BUF_DN<13>")
	)
	(segment
		(start 95.944182 -392.597386)
		(end 95.805752 -392.735816)
		(width 0.14224)
		(layer "In13.Cu")
		(net "P5E_CPU1_P1_RX_BUF_DN<13>")
	)
	(segment
		(start 85.65007 -435.165754)
		(end 85.65007 -435.489858)
		(width 0.14224)
		(layer "In13.Cu")
		(net "P5E_CPU1_P1_RX_BUF_DN<13>")
	)
	(arc
		(start 89.438734 -413.725614)
		(mid 89.370932 -414.066389)
		(end 89.177876 -414.35528)
		(width 0.14224)
		(layer "In13.Cu")
		(net "P5E_CPU1_P1_RX_BUF_DN<13>")
	)
	(arc
		(start 95.203264 -394.262864)
		(mid 95.201759 -394.294509)
		(end 95.197168 -394.325856)
		(width 0.14224)
		(layer "In13.Cu")
		(net "P5E_CPU1_P1_RX_BUF_DN<13>")
	)
	(arc
		(start 92.501974 -404.924514)
		(mid 92.470822 -405.081217)
		(end 92.382086 -405.214074)
		(width 0.14224)
		(layer "In13.Cu")
		(net "P5E_CPU1_P1_RX_BUF_DN<13>")
	)
	(arc
		(start 89.700354 -411.454346)
		(mid 89.510116 -411.610478)
		(end 89.438734 -411.846014)
		(width 0.14224)
		(layer "In13.Cu")
		(net "P5E_CPU1_P1_RX_BUF_DN<13>")
	)
	(arc
		(start 93.101414 -400.804126)
		(mid 93.076091 -400.884204)
		(end 93.05671 -400.965924)
		(width 0.14224)
		(layer "In13.Cu")
		(net "P5E_CPU1_P1_RX_BUF_DN<13>")
	)
	(arc
		(start 90.970354 -410.697426)
		(mid 90.958435 -410.759263)
		(end 90.92438 -410.812234)
		(width 0.14224)
		(layer "In13.Cu")
		(net "P5E_CPU1_P1_RX_BUF_DN<13>")
	)
	(arc
		(start 92.5449 -403.539452)
		(mid 92.512741 -403.75633)
		(end 92.501974 -403.975316)
		(width 0.14224)
		(layer "In13.Cu")
		(net "P5E_CPU1_P1_RX_BUF_DN<13>")
	)
	(arc
		(start 94.933262 -395.65326)
		(mid 94.919033 -395.714597)
		(end 94.901004 -395.774926)
		(width 0.14224)
		(layer "In13.Cu")
		(net "P5E_CPU1_P1_RX_BUF_DN<13>")
	)
	(arc
		(start 90.75674 -410.988256)
		(mid 90.708651 -411.029248)
		(end 90.653108 -411.059376)
		(width 0.14224)
		(layer "In13.Cu")
		(net "P5E_CPU1_P1_RX_BUF_DN<13>")
	)
	(arc
		(start 85.059012 -418.474144)
		(mid 84.78531 -418.883769)
		(end 84.689188 -419.366954)
		(width 0.14224)
		(layer "In13.Cu")
		(net "P5E_CPU1_P1_RX_BUF_DN<13>")
	)
	(arc
		(start 91.257882 -405.94407)
		(mid 91.044993 -406.262536)
		(end 90.970354 -406.638252)
		(width 0.14224)
		(layer "In13.Cu")
		(net "P5E_CPU1_P1_RX_BUF_DN<13>")
	)
	(arc
		(start 91.735656 -405.624538)
		(mid 91.481052 -405.760803)
		(end 91.257882 -405.94407)
		(width 0.14224)
		(layer "In13.Cu")
		(net "P5E_CPU1_P1_RX_BUF_DN<13>")
	)
	(segment
		(start 94.257622 -392.634216)
		(end 94.257622 -391.666984)
		(width 0.1016)
		(layer "F.Cu")
		(net "P5E_CPU1_P1_RX_BUF_DN<12>")
	)
	(segment
		(start 94.346268 -390.761982)
		(end 94.34576 -390.761474)
		(width 0.1016)
		(layer "F.Cu")
		(net "P5E_CPU1_P1_RX_BUF_DN<12>")
	)
	(segment
		(start 94.744286 -392.595862)
		(end 94.578932 -392.761216)
		(width 0.1016)
		(layer "F.Cu")
		(net "P5E_CPU1_P1_RX_BUF_DN<12>")
	)
	(segment
		(start 94.384622 -392.761216)
		(end 94.257622 -392.634216)
		(width 0.1016)
		(layer "F.Cu")
		(net "P5E_CPU1_P1_RX_BUF_DN<12>")
	)
	(segment
		(start 94.346268 -391.578338)
		(end 94.346268 -390.761982)
		(width 0.1016)
		(layer "F.Cu")
		(net "P5E_CPU1_P1_RX_BUF_DN<12>")
	)
	(segment
		(start 94.257622 -391.666984)
		(end 94.346268 -391.578338)
		(width 0.1016)
		(layer "F.Cu")
		(net "P5E_CPU1_P1_RX_BUF_DN<12>")
	)
	(segment
		(start 94.744286 -392.429238)
		(end 94.744286 -392.595862)
		(width 0.1016)
		(layer "F.Cu")
		(net "P5E_CPU1_P1_RX_BUF_DN<12>")
	)
	(segment
		(start 94.578932 -392.761216)
		(end 94.384622 -392.761216)
		(width 0.1016)
		(layer "F.Cu")
		(net "P5E_CPU1_P1_RX_BUF_DN<12>")
	)
	(segment
		(start 92.918026 -397.493236)
		(end 93.415358 -396.561056)
		(width 0.14224)
		(layer "In13.Cu")
		(net "P5E_CPU1_P1_RX_BUF_DN<12>")
	)
	(segment
		(start 94.310708 -392.735816)
		(end 94.605856 -392.735816)
		(width 0.14224)
		(layer "In13.Cu")
		(net "P5E_CPU1_P1_RX_BUF_DN<12>")
	)
	(segment
		(start 94.605856 -392.735816)
		(end 94.744286 -392.597386)
		(width 0.14224)
		(layer "In13.Cu")
		(net "P5E_CPU1_P1_RX_BUF_DN<12>")
	)
	(segment
		(start 82.689192 -426.990002)
		(end 82.689192 -418.173916)
		(width 0.14224)
		(layer "In13.Cu")
		(net "P5E_CPU1_P1_RX_BUF_DN<12>")
	)
	(segment
		(start 88.922352 -405.52116)
		(end 89.191592 -405.341328)
		(width 0.14224)
		(layer "In13.Cu")
		(net "P5E_CPU1_P1_RX_BUF_DN<12>")
	)
	(segment
		(start 82.694526 -426.995336)
		(end 82.689192 -426.990002)
		(width 0.14224)
		(layer "In13.Cu")
		(net "P5E_CPU1_P1_RX_BUF_DN<12>")
	)
	(segment
		(start 93.522292 -396.336774)
		(end 93.905324 -395.411706)
		(width 0.14224)
		(layer "In13.Cu")
		(net "P5E_CPU1_P1_RX_BUF_DN<12>")
	)
	(segment
		(start 94.003368 -394.9192)
		(end 94.003368 -393.043156)
		(width 0.14224)
		(layer "In13.Cu")
		(net "P5E_CPU1_P1_RX_BUF_DN<12>")
	)
	(segment
		(start 89.191592 -405.341328)
		(end 89.318846 -405.214074)
		(width 0.14224)
		(layer "In13.Cu")
		(net "P5E_CPU1_P1_RX_BUF_DN<12>")
	)
	(segment
		(start 92.917772 -397.493236)
		(end 92.918026 -397.493236)
		(width 0.14224)
		(layer "In13.Cu")
		(net "P5E_CPU1_P1_RX_BUF_DN<12>")
	)
	(segment
		(start 83.166966 -434.047392)
		(end 82.694526 -433.574952)
		(width 0.14224)
		(layer "In13.Cu")
		(net "P5E_CPU1_P1_RX_BUF_DN<12>")
	)
	(segment
		(start 87.907114 -410.697426)
		(end 87.907114 -406.638252)
		(width 0.14224)
		(layer "In13.Cu")
		(net "P5E_CPU1_P1_RX_BUF_DN<12>")
	)
	(segment
		(start 86.637114 -411.454346)
		(end 87.588852 -411.060138)
		(width 0.14224)
		(layer "In13.Cu")
		(net "P5E_CPU1_P1_RX_BUF_DN<12>")
	)
	(segment
		(start 83.650074 -434.165756)
		(end 83.53171 -434.047392)
		(width 0.14224)
		(layer "In13.Cu")
		(net "P5E_CPU1_P1_RX_BUF_DN<12>")
	)
	(segment
		(start 87.6935 -410.988256)
		(end 87.86114 -410.812234)
		(width 0.14224)
		(layer "In13.Cu")
		(net "P5E_CPU1_P1_RX_BUF_DN<12>")
	)
	(segment
		(start 83.650074 -434.48986)
		(end 83.650074 -434.165756)
		(width 0.14224)
		(layer "In13.Cu")
		(net "P5E_CPU1_P1_RX_BUF_DN<12>")
	)
	(segment
		(start 89.592912 -403.162262)
		(end 92.060014 -399.046192)
		(width 0.14224)
		(layer "In13.Cu")
		(net "P5E_CPU1_P1_RX_BUF_DN<12>")
	)
	(segment
		(start 92.549726 -398.18183)
		(end 92.917772 -397.493236)
		(width 0.14224)
		(layer "In13.Cu")
		(net "P5E_CPU1_P1_RX_BUF_DN<12>")
	)
	(segment
		(start 86.375494 -413.606234)
		(end 86.375494 -411.84576)
		(width 0.14224)
		(layer "In13.Cu")
		(net "P5E_CPU1_P1_RX_BUF_DN<12>")
	)
	(segment
		(start 94.744286 -392.597386)
		(end 94.744286 -392.429238)
		(width 0.14224)
		(layer "In13.Cu")
		(net "P5E_CPU1_P1_RX_BUF_DN<12>")
	)
	(segment
		(start 83.038188 -417.331144)
		(end 86.101174 -414.268158)
		(width 0.14224)
		(layer "In13.Cu")
		(net "P5E_CPU1_P1_RX_BUF_DN<12>")
	)
	(segment
		(start 88.672416 -405.624538)
		(end 88.922352 -405.52116)
		(width 0.14224)
		(layer "In13.Cu")
		(net "P5E_CPU1_P1_RX_BUF_DN<12>")
	)
	(segment
		(start 83.53171 -434.047392)
		(end 83.166966 -434.047392)
		(width 0.14224)
		(layer "In13.Cu")
		(net "P5E_CPU1_P1_RX_BUF_DN<12>")
	)
	(segment
		(start 93.415358 -396.561056)
		(end 93.415866 -396.560548)
		(width 0.14224)
		(layer "In13.Cu")
		(net "P5E_CPU1_P1_RX_BUF_DN<12>")
	)
	(segment
		(start 89.438734 -404.924514)
		(end 89.438734 -404.019004)
		(width 0.14224)
		(layer "In13.Cu")
		(net "P5E_CPU1_P1_RX_BUF_DN<12>")
	)
	(segment
		(start 89.44991 -403.85492)
		(end 89.513664 -403.387814)
		(width 0.14224)
		(layer "In13.Cu")
		(net "P5E_CPU1_P1_RX_BUF_DN<12>")
	)
	(segment
		(start 82.694526 -433.574952)
		(end 82.694526 -426.995336)
		(width 0.14224)
		(layer "In13.Cu")
		(net "P5E_CPU1_P1_RX_BUF_DN<12>")
	)
	(segment
		(start 94.003368 -393.043156)
		(end 94.310708 -392.735816)
		(width 0.14224)
		(layer "In13.Cu")
		(net "P5E_CPU1_P1_RX_BUF_DN<12>")
	)
	(arc
		(start 86.101174 -414.268158)
		(mid 86.304203 -413.964493)
		(end 86.375494 -413.606234)
		(width 0.14224)
		(layer "In13.Cu")
		(net "P5E_CPU1_P1_RX_BUF_DN<12>")
	)
	(arc
		(start 93.415866 -396.560548)
		(mid 93.471958 -396.45003)
		(end 93.522292 -396.336774)
		(width 0.14224)
		(layer "In13.Cu")
		(net "P5E_CPU1_P1_RX_BUF_DN<12>")
	)
	(arc
		(start 93.905324 -395.411706)
		(mid 93.978567 -395.170277)
		(end 94.003368 -394.9192)
		(width 0.14224)
		(layer "In13.Cu")
		(net "P5E_CPU1_P1_RX_BUF_DN<12>")
	)
	(arc
		(start 89.438734 -404.019004)
		(mid 89.441538 -403.936772)
		(end 89.44991 -403.85492)
		(width 0.14224)
		(layer "In13.Cu")
		(net "P5E_CPU1_P1_RX_BUF_DN<12>")
	)
	(arc
		(start 92.060014 -399.046192)
		(mid 92.310178 -398.617018)
		(end 92.549726 -398.18183)
		(width 0.14224)
		(layer "In13.Cu")
		(net "P5E_CPU1_P1_RX_BUF_DN<12>")
	)
	(arc
		(start 88.194642 -405.94407)
		(mid 88.417807 -405.760796)
		(end 88.672416 -405.624538)
		(width 0.14224)
		(layer "In13.Cu")
		(net "P5E_CPU1_P1_RX_BUF_DN<12>")
	)
	(arc
		(start 89.318846 -405.214074)
		(mid 89.407561 -405.081209)
		(end 89.438734 -404.924514)
		(width 0.14224)
		(layer "In13.Cu")
		(net "P5E_CPU1_P1_RX_BUF_DN<12>")
	)
	(arc
		(start 87.588852 -411.060138)
		(mid 87.644924 -411.029659)
		(end 87.6935 -410.988256)
		(width 0.14224)
		(layer "In13.Cu")
		(net "P5E_CPU1_P1_RX_BUF_DN<12>")
	)
	(arc
		(start 87.907114 -406.638252)
		(mid 87.981804 -406.262557)
		(end 88.194642 -405.94407)
		(width 0.14224)
		(layer "In13.Cu")
		(net "P5E_CPU1_P1_RX_BUF_DN<12>")
	)
	(arc
		(start 89.513664 -403.387814)
		(mid 89.541847 -403.271018)
		(end 89.592912 -403.162262)
		(width 0.14224)
		(layer "In13.Cu")
		(net "P5E_CPU1_P1_RX_BUF_DN<12>")
	)
	(arc
		(start 86.375494 -411.84576)
		(mid 86.44699 -411.610415)
		(end 86.637114 -411.454346)
		(width 0.14224)
		(layer "In13.Cu")
		(net "P5E_CPU1_P1_RX_BUF_DN<12>")
	)
	(arc
		(start 82.689192 -418.173916)
		(mid 82.779895 -417.717832)
		(end 83.038188 -417.331144)
		(width 0.14224)
		(layer "In13.Cu")
		(net "P5E_CPU1_P1_RX_BUF_DN<12>")
	)
	(arc
		(start 87.86114 -410.812234)
		(mid 87.895187 -410.75926)
		(end 87.907114 -410.697426)
		(width 0.14224)
		(layer "In13.Cu")
		(net "P5E_CPU1_P1_RX_BUF_DN<12>")
	)
	(segment
		(start 93.54439 -392.620246)
		(end 93.40342 -392.761216)
		(width 0.1016)
		(layer "F.Cu")
		(net "P5E_CPU1_P1_RX_BUF_DN<11>")
	)
	(segment
		(start 93.057472 -392.634216)
		(end 93.057472 -391.666984)
		(width 0.1016)
		(layer "F.Cu")
		(net "P5E_CPU1_P1_RX_BUF_DN<11>")
	)
	(segment
		(start 93.057472 -391.666984)
		(end 93.146118 -391.578338)
		(width 0.1016)
		(layer "F.Cu")
		(net "P5E_CPU1_P1_RX_BUF_DN<11>")
	)
	(segment
		(start 93.54439 -392.429238)
		(end 93.54439 -392.620246)
		(width 0.1016)
		(layer "F.Cu")
		(net "P5E_CPU1_P1_RX_BUF_DN<11>")
	)
	(segment
		(start 93.40342 -392.761216)
		(end 93.184472 -392.761216)
		(width 0.1016)
		(layer "F.Cu")
		(net "P5E_CPU1_P1_RX_BUF_DN<11>")
	)
	(segment
		(start 93.146118 -390.761728)
		(end 93.145864 -390.761474)
		(width 0.1016)
		(layer "F.Cu")
		(net "P5E_CPU1_P1_RX_BUF_DN<11>")
	)
	(segment
		(start 93.184472 -392.761216)
		(end 93.057472 -392.634216)
		(width 0.1016)
		(layer "F.Cu")
		(net "P5E_CPU1_P1_RX_BUF_DN<11>")
	)
	(segment
		(start 93.146118 -391.578338)
		(end 93.146118 -390.761728)
		(width 0.1016)
		(layer "F.Cu")
		(net "P5E_CPU1_P1_RX_BUF_DN<11>")
	)
	(segment
		(start 81.031842 -416.91433)
		(end 83.11896 -414.827212)
		(width 0.14224)
		(layer "In13.Cu")
		(net "P5E_CPU1_P1_RX_BUF_DN<11>")
	)
	(segment
		(start 81.148936 -435.029356)
		(end 80.69453 -434.57495)
		(width 0.14224)
		(layer "In13.Cu")
		(net "P5E_CPU1_P1_RX_BUF_DN<11>")
	)
	(segment
		(start 93.40596 -392.735816)
		(end 93.54439 -392.597386)
		(width 0.14224)
		(layer "In13.Cu")
		(net "P5E_CPU1_P1_RX_BUF_DN<11>")
	)
	(segment
		(start 81.650078 -435.489858)
		(end 81.650078 -435.165754)
		(width 0.14224)
		(layer "In13.Cu")
		(net "P5E_CPU1_P1_RX_BUF_DN<11>")
	)
	(segment
		(start 86.391496 -403.910038)
		(end 86.428834 -403.707346)
		(width 0.14224)
		(layer "In13.Cu")
		(net "P5E_CPU1_P1_RX_BUF_DN<11>")
	)
	(segment
		(start 86.375494 -404.924514)
		(end 86.375494 -404.08733)
		(width 0.14224)
		(layer "In13.Cu")
		(net "P5E_CPU1_P1_RX_BUF_DN<11>")
	)
	(segment
		(start 85.609176 -405.624538)
		(end 85.859112 -405.52116)
		(width 0.14224)
		(layer "In13.Cu")
		(net "P5E_CPU1_P1_RX_BUF_DN<11>")
	)
	(segment
		(start 93.110812 -392.735816)
		(end 93.40596 -392.735816)
		(width 0.14224)
		(layer "In13.Cu")
		(net "P5E_CPU1_P1_RX_BUF_DN<11>")
	)
	(segment
		(start 81.51368 -435.029356)
		(end 81.148936 -435.029356)
		(width 0.14224)
		(layer "In13.Cu")
		(net "P5E_CPU1_P1_RX_BUF_DN<11>")
	)
	(segment
		(start 92.557092 -395.994382)
		(end 92.783914 -395.246352)
		(width 0.14224)
		(layer "In13.Cu")
		(net "P5E_CPU1_P1_RX_BUF_DN<11>")
	)
	(segment
		(start 86.468458 -403.587458)
		(end 86.53526 -403.450806)
		(width 0.14224)
		(layer "In13.Cu")
		(net "P5E_CPU1_P1_RX_BUF_DN<11>")
	)
	(segment
		(start 80.69453 -434.57495)
		(end 80.69453 -426.995336)
		(width 0.14224)
		(layer "In13.Cu")
		(net "P5E_CPU1_P1_RX_BUF_DN<11>")
	)
	(segment
		(start 84.843874 -410.621226)
		(end 84.843874 -406.638252)
		(width 0.14224)
		(layer "In13.Cu")
		(net "P5E_CPU1_P1_RX_BUF_DN<11>")
	)
	(segment
		(start 92.803472 -395.115796)
		(end 92.803472 -393.043156)
		(width 0.14224)
		(layer "In13.Cu")
		(net "P5E_CPU1_P1_RX_BUF_DN<11>")
	)
	(segment
		(start 83.668616 -411.41523)
		(end 84.560156 -411.045406)
		(width 0.14224)
		(layer "In13.Cu")
		(net "P5E_CPU1_P1_RX_BUF_DN<11>")
	)
	(segment
		(start 83.312254 -414.360614)
		(end 83.312254 -411.94863)
		(width 0.14224)
		(layer "In13.Cu")
		(net "P5E_CPU1_P1_RX_BUF_DN<11>")
	)
	(segment
		(start 92.803472 -393.043156)
		(end 93.110812 -392.735816)
		(width 0.14224)
		(layer "In13.Cu")
		(net "P5E_CPU1_P1_RX_BUF_DN<11>")
	)
	(segment
		(start 93.54439 -392.597386)
		(end 93.54439 -392.429238)
		(width 0.14224)
		(layer "In13.Cu")
		(net "P5E_CPU1_P1_RX_BUF_DN<11>")
	)
	(segment
		(start 80.69453 -426.995336)
		(end 80.689196 -426.990002)
		(width 0.14224)
		(layer "In13.Cu")
		(net "P5E_CPU1_P1_RX_BUF_DN<11>")
	)
	(segment
		(start 80.689196 -426.990002)
		(end 80.689196 -417.741608)
		(width 0.14224)
		(layer "In13.Cu")
		(net "P5E_CPU1_P1_RX_BUF_DN<11>")
	)
	(segment
		(start 86.650322 -403.281134)
		(end 90.10904 -399.465038)
		(width 0.14224)
		(layer "In13.Cu")
		(net "P5E_CPU1_P1_RX_BUF_DN<11>")
	)
	(segment
		(start 85.859112 -405.52116)
		(end 86.128352 -405.341328)
		(width 0.14224)
		(layer "In13.Cu")
		(net "P5E_CPU1_P1_RX_BUF_DN<11>")
	)
	(segment
		(start 90.997278 -398.328134)
		(end 92.557092 -395.994382)
		(width 0.14224)
		(layer "In13.Cu")
		(net "P5E_CPU1_P1_RX_BUF_DN<11>")
	)
	(segment
		(start 81.650078 -435.165754)
		(end 81.51368 -435.029356)
		(width 0.14224)
		(layer "In13.Cu")
		(net "P5E_CPU1_P1_RX_BUF_DN<11>")
	)
	(segment
		(start 86.128352 -405.341328)
		(end 86.255606 -405.214074)
		(width 0.14224)
		(layer "In13.Cu")
		(net "P5E_CPU1_P1_RX_BUF_DN<11>")
	)
	(arc
		(start 84.560156 -411.045406)
		(mid 84.766384 -410.876359)
		(end 84.843874 -410.621226)
		(width 0.14224)
		(layer "In13.Cu")
		(net "P5E_CPU1_P1_RX_BUF_DN<11>")
	)
	(arc
		(start 83.11896 -414.827212)
		(mid 83.262002 -414.613135)
		(end 83.312254 -414.360614)
		(width 0.14224)
		(layer "In13.Cu")
		(net "P5E_CPU1_P1_RX_BUF_DN<11>")
	)
	(arc
		(start 84.843874 -406.638252)
		(mid 84.918564 -406.262557)
		(end 85.131402 -405.94407)
		(width 0.14224)
		(layer "In13.Cu")
		(net "P5E_CPU1_P1_RX_BUF_DN<11>")
	)
	(arc
		(start 92.783914 -395.246352)
		(mid 92.798497 -395.181795)
		(end 92.803472 -395.115796)
		(width 0.14224)
		(layer "In13.Cu")
		(net "P5E_CPU1_P1_RX_BUF_DN<11>")
	)
	(arc
		(start 86.255606 -405.214074)
		(mid 86.344321 -405.081209)
		(end 86.375494 -404.924514)
		(width 0.14224)
		(layer "In13.Cu")
		(net "P5E_CPU1_P1_RX_BUF_DN<11>")
	)
	(arc
		(start 86.428834 -403.707346)
		(mid 86.444561 -403.646052)
		(end 86.468458 -403.587458)
		(width 0.14224)
		(layer "In13.Cu")
		(net "P5E_CPU1_P1_RX_BUF_DN<11>")
	)
	(arc
		(start 80.689196 -417.741608)
		(mid 80.778251 -417.293897)
		(end 81.031842 -416.91433)
		(width 0.14224)
		(layer "In13.Cu")
		(net "P5E_CPU1_P1_RX_BUF_DN<11>")
	)
	(arc
		(start 90.10904 -399.465038)
		(mid 90.574195 -398.913021)
		(end 90.997278 -398.328134)
		(width 0.14224)
		(layer "In13.Cu")
		(net "P5E_CPU1_P1_RX_BUF_DN<11>")
	)
	(arc
		(start 85.131402 -405.94407)
		(mid 85.354567 -405.760796)
		(end 85.609176 -405.624538)
		(width 0.14224)
		(layer "In13.Cu")
		(net "P5E_CPU1_P1_RX_BUF_DN<11>")
	)
	(arc
		(start 86.53526 -403.450806)
		(mid 86.586831 -403.361929)
		(end 86.650322 -403.281134)
		(width 0.14224)
		(layer "In13.Cu")
		(net "P5E_CPU1_P1_RX_BUF_DN<11>")
	)
	(arc
		(start 86.375494 -404.08733)
		(mid 86.37944 -403.998317)
		(end 86.391496 -403.910038)
		(width 0.14224)
		(layer "In13.Cu")
		(net "P5E_CPU1_P1_RX_BUF_DN<11>")
	)
	(arc
		(start 83.312254 -411.94863)
		(mid 83.409544 -411.627891)
		(end 83.668616 -411.41523)
		(width 0.14224)
		(layer "In13.Cu")
		(net "P5E_CPU1_P1_RX_BUF_DN<11>")
	)
	(segment
		(start 91.945714 -391.578846)
		(end 91.945714 -390.761474)
		(width 0.1016)
		(layer "F.Cu")
		(net "P5E_CPU1_P1_RX_BUF_DN<10>")
	)
	(segment
		(start 92.344494 -392.429238)
		(end 92.344494 -392.620246)
		(width 0.1016)
		(layer "F.Cu")
		(net "P5E_CPU1_P1_RX_BUF_DN<10>")
	)
	(segment
		(start 92.344494 -392.620246)
		(end 92.203524 -392.761216)
		(width 0.1016)
		(layer "F.Cu")
		(net "P5E_CPU1_P1_RX_BUF_DN<10>")
	)
	(segment
		(start 91.857576 -391.666984)
		(end 91.945714 -391.578846)
		(width 0.1016)
		(layer "F.Cu")
		(net "P5E_CPU1_P1_RX_BUF_DN<10>")
	)
	(segment
		(start 91.857576 -392.634216)
		(end 91.857576 -391.666984)
		(width 0.1016)
		(layer "F.Cu")
		(net "P5E_CPU1_P1_RX_BUF_DN<10>")
	)
	(segment
		(start 92.203524 -392.761216)
		(end 91.984576 -392.761216)
		(width 0.1016)
		(layer "F.Cu")
		(net "P5E_CPU1_P1_RX_BUF_DN<10>")
	)
	(segment
		(start 91.984576 -392.761216)
		(end 91.857576 -392.634216)
		(width 0.1016)
		(layer "F.Cu")
		(net "P5E_CPU1_P1_RX_BUF_DN<10>")
	)
	(segment
		(start 79.499206 -434.01488)
		(end 79.134462 -434.01488)
		(width 0.14224)
		(layer "In13.Cu")
		(net "P5E_CPU1_P1_RX_BUF_DN<10>")
	)
	(segment
		(start 81.780634 -410.697426)
		(end 81.780634 -406.638252)
		(width 0.14224)
		(layer "In13.Cu")
		(net "P5E_CPU1_P1_RX_BUF_DN<10>")
	)
	(segment
		(start 84.757768 -402.515324)
		(end 87.028782 -400.962876)
		(width 0.14224)
		(layer "In13.Cu")
		(net "P5E_CPU1_P1_RX_BUF_DN<10>")
	)
	(segment
		(start 92.344494 -392.597386)
		(end 92.344494 -392.429238)
		(width 0.14224)
		(layer "In13.Cu")
		(net "P5E_CPU1_P1_RX_BUF_DN<10>")
	)
	(segment
		(start 89.465912 -398.525746)
		(end 91.580462 -395.522958)
		(width 0.14224)
		(layer "In13.Cu")
		(net "P5E_CPU1_P1_RX_BUF_DN<10>")
	)
	(segment
		(start 78.6892 -426.990002)
		(end 78.6892 -423.773854)
		(width 0.14224)
		(layer "In13.Cu")
		(net "P5E_CPU1_P1_RX_BUF_DN<10>")
	)
	(segment
		(start 78.694534 -426.995336)
		(end 78.6892 -426.990002)
		(width 0.14224)
		(layer "In13.Cu")
		(net "P5E_CPU1_P1_RX_BUF_DN<10>")
	)
	(segment
		(start 79.650082 -434.48986)
		(end 79.650082 -434.165756)
		(width 0.14224)
		(layer "In13.Cu")
		(net "P5E_CPU1_P1_RX_BUF_DN<10>")
	)
	(segment
		(start 83.065112 -405.341328)
		(end 83.192366 -405.214074)
		(width 0.14224)
		(layer "In13.Cu")
		(net "P5E_CPU1_P1_RX_BUF_DN<10>")
	)
	(segment
		(start 79.134462 -434.01488)
		(end 78.694534 -433.574952)
		(width 0.14224)
		(layer "In13.Cu")
		(net "P5E_CPU1_P1_RX_BUF_DN<10>")
	)
	(segment
		(start 83.312254 -404.924514)
		(end 83.312254 -404.106634)
		(width 0.14224)
		(layer "In13.Cu")
		(net "P5E_CPU1_P1_RX_BUF_DN<10>")
	)
	(segment
		(start 87.028782 -400.962876)
		(end 89.465912 -398.525746)
		(width 0.14224)
		(layer "In13.Cu")
		(net "P5E_CPU1_P1_RX_BUF_DN<10>")
	)
	(segment
		(start 91.603576 -395.449806)
		(end 91.603576 -393.043156)
		(width 0.14224)
		(layer "In13.Cu")
		(net "P5E_CPU1_P1_RX_BUF_DN<10>")
	)
	(segment
		(start 79.098902 -416.124136)
		(end 79.989426 -415.233612)
		(width 0.14224)
		(layer "In13.Cu")
		(net "P5E_CPU1_P1_RX_BUF_DN<10>")
	)
	(segment
		(start 78.694534 -433.574952)
		(end 78.694534 -426.995336)
		(width 0.14224)
		(layer "In13.Cu")
		(net "P5E_CPU1_P1_RX_BUF_DN<10>")
	)
	(segment
		(start 82.545936 -405.624538)
		(end 82.795872 -405.52116)
		(width 0.14224)
		(layer "In13.Cu")
		(net "P5E_CPU1_P1_RX_BUF_DN<10>")
	)
	(segment
		(start 80.61198 -411.412436)
		(end 81.463388 -411.059376)
		(width 0.14224)
		(layer "In13.Cu")
		(net "P5E_CPU1_P1_RX_BUF_DN<10>")
	)
	(segment
		(start 78.6892 -423.773854)
		(end 78.881478 -423.309542)
		(width 0.14224)
		(layer "In13.Cu")
		(net "P5E_CPU1_P1_RX_BUF_DN<10>")
	)
	(segment
		(start 91.603576 -393.043156)
		(end 91.910916 -392.735816)
		(width 0.14224)
		(layer "In13.Cu")
		(net "P5E_CPU1_P1_RX_BUF_DN<10>")
	)
	(segment
		(start 92.206064 -392.735816)
		(end 92.344494 -392.597386)
		(width 0.14224)
		(layer "In13.Cu")
		(net "P5E_CPU1_P1_RX_BUF_DN<10>")
	)
	(segment
		(start 79.650082 -434.165756)
		(end 79.499206 -434.01488)
		(width 0.14224)
		(layer "In13.Cu")
		(net "P5E_CPU1_P1_RX_BUF_DN<10>")
	)
	(segment
		(start 78.881478 -423.309542)
		(end 78.881478 -416.6489)
		(width 0.14224)
		(layer "In13.Cu")
		(net "P5E_CPU1_P1_RX_BUF_DN<10>")
	)
	(segment
		(start 82.795872 -405.52116)
		(end 83.065112 -405.341328)
		(width 0.14224)
		(layer "In13.Cu")
		(net "P5E_CPU1_P1_RX_BUF_DN<10>")
	)
	(segment
		(start 84.337652 -402.851366)
		(end 84.63661 -402.606002)
		(width 0.14224)
		(layer "In13.Cu")
		(net "P5E_CPU1_P1_RX_BUF_DN<10>")
	)
	(segment
		(start 91.910916 -392.735816)
		(end 92.206064 -392.735816)
		(width 0.14224)
		(layer "In13.Cu")
		(net "P5E_CPU1_P1_RX_BUF_DN<10>")
	)
	(segment
		(start 80.249014 -414.60674)
		(end 80.249014 -411.955996)
		(width 0.14224)
		(layer "In13.Cu")
		(net "P5E_CPU1_P1_RX_BUF_DN<10>")
	)
	(segment
		(start 83.362546 -403.869652)
		(end 83.434682 -403.706838)
		(width 0.14224)
		(layer "In13.Cu")
		(net "P5E_CPU1_P1_RX_BUF_DN<10>")
	)
	(arc
		(start 84.63661 -402.606002)
		(mid 84.696198 -402.559339)
		(end 84.757768 -402.515324)
		(width 0.14224)
		(layer "In13.Cu")
		(net "P5E_CPU1_P1_RX_BUF_DN<10>")
	)
	(arc
		(start 83.192366 -405.214074)
		(mid 83.281081 -405.081209)
		(end 83.312254 -404.924514)
		(width 0.14224)
		(layer "In13.Cu")
		(net "P5E_CPU1_P1_RX_BUF_DN<10>")
	)
	(arc
		(start 78.881478 -416.6489)
		(mid 78.938042 -416.364916)
		(end 79.098902 -416.124136)
		(width 0.14224)
		(layer "In13.Cu")
		(net "P5E_CPU1_P1_RX_BUF_DN<10>")
	)
	(arc
		(start 81.463388 -411.059376)
		(mid 81.589775 -410.990092)
		(end 81.698338 -410.895292)
		(width 0.14224)
		(layer "In13.Cu")
		(net "P5E_CPU1_P1_RX_BUF_DN<10>")
	)
	(arc
		(start 81.780634 -406.638252)
		(mid 81.855324 -406.262557)
		(end 82.068162 -405.94407)
		(width 0.14224)
		(layer "In13.Cu")
		(net "P5E_CPU1_P1_RX_BUF_DN<10>")
	)
	(arc
		(start 84.017358 -403.119844)
		(mid 84.176794 -402.984756)
		(end 84.337652 -402.851366)
		(width 0.14224)
		(layer "In13.Cu")
		(net "P5E_CPU1_P1_RX_BUF_DN<10>")
	)
	(arc
		(start 83.576414 -403.509988)
		(mid 83.795363 -403.313194)
		(end 84.017358 -403.119844)
		(width 0.14224)
		(layer "In13.Cu")
		(net "P5E_CPU1_P1_RX_BUF_DN<10>")
	)
	(arc
		(start 83.434682 -403.706838)
		(mid 83.495342 -403.601067)
		(end 83.576414 -403.509988)
		(width 0.14224)
		(layer "In13.Cu")
		(net "P5E_CPU1_P1_RX_BUF_DN<10>")
	)
	(arc
		(start 81.698338 -410.895292)
		(mid 81.759187 -410.804554)
		(end 81.780634 -410.697426)
		(width 0.14224)
		(layer "In13.Cu")
		(net "P5E_CPU1_P1_RX_BUF_DN<10>")
	)
	(arc
		(start 83.312254 -404.106634)
		(mid 83.324991 -403.985509)
		(end 83.362546 -403.869652)
		(width 0.14224)
		(layer "In13.Cu")
		(net "P5E_CPU1_P1_RX_BUF_DN<10>")
	)
	(arc
		(start 79.989426 -415.233612)
		(mid 80.181548 -414.945986)
		(end 80.249014 -414.60674)
		(width 0.14224)
		(layer "In13.Cu")
		(net "P5E_CPU1_P1_RX_BUF_DN<10>")
	)
	(arc
		(start 80.249014 -411.955996)
		(mid 80.348094 -411.629187)
		(end 80.61198 -411.412436)
		(width 0.14224)
		(layer "In13.Cu")
		(net "P5E_CPU1_P1_RX_BUF_DN<10>")
	)
	(arc
		(start 82.068162 -405.94407)
		(mid 82.291327 -405.760796)
		(end 82.545936 -405.624538)
		(width 0.14224)
		(layer "In13.Cu")
		(net "P5E_CPU1_P1_RX_BUF_DN<10>")
	)
	(arc
		(start 91.580462 -395.522958)
		(mid 91.597668 -395.488166)
		(end 91.603576 -395.449806)
		(width 0.14224)
		(layer "In13.Cu")
		(net "P5E_CPU1_P1_RX_BUF_DN<10>")
	)
	(segment
		(start 79.835248 -391.689336)
		(end 79.835248 -392.611864)
		(width 0.1016)
		(layer "F.Cu")
		(net "P5E_CPU1_P1_RX_BUF_DN<0>")
	)
	(segment
		(start 79.946246 -390.761982)
		(end 79.946246 -391.578338)
		(width 0.1016)
		(layer "F.Cu")
		(net "P5E_CPU1_P1_RX_BUF_DN<0>")
	)
	(segment
		(start 79.835248 -392.611864)
		(end 79.9846 -392.761216)
		(width 0.1016)
		(layer "F.Cu")
		(net "P5E_CPU1_P1_RX_BUF_DN<0>")
	)
	(segment
		(start 79.946246 -391.578338)
		(end 79.835248 -391.689336)
		(width 0.1016)
		(layer "F.Cu")
		(net "P5E_CPU1_P1_RX_BUF_DN<0>")
	)
	(segment
		(start 79.9846 -392.761216)
		(end 80.203548 -392.761216)
		(width 0.1016)
		(layer "F.Cu")
		(net "P5E_CPU1_P1_RX_BUF_DN<0>")
	)
	(segment
		(start 80.203548 -392.761216)
		(end 80.344264 -392.6205)
		(width 0.1016)
		(layer "F.Cu")
		(net "P5E_CPU1_P1_RX_BUF_DN<0>")
	)
	(segment
		(start 80.344264 -392.6205)
		(end 80.344264 -392.429238)
		(width 0.1016)
		(layer "F.Cu")
		(net "P5E_CPU1_P1_RX_BUF_DN<0>")
	)
	(segment
		(start 79.945738 -390.761474)
		(end 79.946246 -390.761982)
		(width 0.1016)
		(layer "F.Cu")
		(net "P5E_CPU1_P1_RX_BUF_DN<0>")
	)
	(segment
		(start 66.18605 -397.497808)
		(end 73.410826 -394.885164)
		(width 0.14224)
		(layer "In13.Cu")
		(net "P5E_CPU1_P1_RX_BUF_DN<0>")
	)
	(segment
		(start 75.04303 -394.637006)
		(end 77.594206 -393.71397)
		(width 0.14224)
		(layer "In13.Cu")
		(net "P5E_CPU1_P1_RX_BUF_DN<0>")
	)
	(segment
		(start 52.163472 -405.52116)
		(end 52.432712 -405.341328)
		(width 0.14224)
		(layer "In13.Cu")
		(net "P5E_CPU1_P1_RX_BUF_DN<0>")
	)
	(segment
		(start 49.868836 -411.45206)
		(end 50.415952 -411.225238)
		(width 0.14224)
		(layer "In13.Cu")
		(net "P5E_CPU1_P1_RX_BUF_DN<0>")
	)
	(segment
		(start 50.415952 -411.225238)
		(end 50.415698 -411.225238)
		(width 0.14224)
		(layer "In13.Cu")
		(net "P5E_CPU1_P1_RX_BUF_DN<0>")
	)
	(segment
		(start 77.594206 -393.71397)
		(end 77.888592 -393.445238)
		(width 0.14224)
		(layer "In13.Cu")
		(net "P5E_CPU1_P1_RX_BUF_DN<0>")
	)
	(segment
		(start 58.158126 -434.038756)
		(end 57.208166 -433.088796)
		(width 0.14224)
		(layer "In13.Cu")
		(net "P5E_CPU1_P1_RX_BUF_DN<0>")
	)
	(segment
		(start 53.002942 -403.321012)
		(end 53.397658 -402.985986)
		(width 0.14224)
		(layer "In13.Cu")
		(net "P5E_CPU1_P1_RX_BUF_DN<0>")
	)
	(segment
		(start 73.410826 -394.885164)
		(end 75.04303 -394.637006)
		(width 0.14224)
		(layer "In13.Cu")
		(net "P5E_CPU1_P1_RX_BUF_DN<0>")
	)
	(segment
		(start 58.64987 -434.165756)
		(end 58.52287 -434.038756)
		(width 0.14224)
		(layer "In13.Cu")
		(net "P5E_CPU1_P1_RX_BUF_DN<0>")
	)
	(segment
		(start 56.938418 -421.37838)
		(end 49.879758 -414.31972)
		(width 0.14224)
		(layer "In13.Cu")
		(net "P5E_CPU1_P1_RX_BUF_DN<0>")
	)
	(segment
		(start 78.62951 -392.997436)
		(end 79.397352 -392.720068)
		(width 0.14224)
		(layer "In13.Cu")
		(net "P5E_CPU1_P1_RX_BUF_DN<0>")
	)
	(segment
		(start 51.148234 -410.721302)
		(end 51.148234 -406.638252)
		(width 0.14224)
		(layer "In13.Cu")
		(net "P5E_CPU1_P1_RX_BUF_DN<0>")
	)
	(segment
		(start 50.415698 -411.225238)
		(end 50.96256 -410.99867)
		(width 0.14224)
		(layer "In13.Cu")
		(net "P5E_CPU1_P1_RX_BUF_DN<0>")
	)
	(segment
		(start 58.52287 -434.038756)
		(end 58.158126 -434.038756)
		(width 0.14224)
		(layer "In13.Cu")
		(net "P5E_CPU1_P1_RX_BUF_DN<0>")
	)
	(segment
		(start 58.64987 -434.48986)
		(end 58.64987 -434.165756)
		(width 0.14224)
		(layer "In13.Cu")
		(net "P5E_CPU1_P1_RX_BUF_DN<0>")
	)
	(segment
		(start 52.679854 -404.924514)
		(end 52.679854 -404.061676)
		(width 0.14224)
		(layer "In13.Cu")
		(net "P5E_CPU1_P1_RX_BUF_DN<0>")
	)
	(segment
		(start 51.913536 -405.624538)
		(end 52.163472 -405.52116)
		(width 0.14224)
		(layer "In13.Cu")
		(net "P5E_CPU1_P1_RX_BUF_DN<0>")
	)
	(segment
		(start 80.053434 -392.720068)
		(end 80.344264 -392.429238)
		(width 0.14224)
		(layer "In13.Cu")
		(net "P5E_CPU1_P1_RX_BUF_DN<0>")
	)
	(segment
		(start 52.432712 -405.341328)
		(end 52.559966 -405.214074)
		(width 0.14224)
		(layer "In13.Cu")
		(net "P5E_CPU1_P1_RX_BUF_DN<0>")
	)
	(segment
		(start 49.616614 -413.684212)
		(end 49.616614 -411.82925)
		(width 0.14224)
		(layer "In13.Cu")
		(net "P5E_CPU1_P1_RX_BUF_DN<0>")
	)
	(segment
		(start 57.208166 -433.088796)
		(end 57.208166 -422.029636)
		(width 0.14224)
		(layer "In13.Cu")
		(net "P5E_CPU1_P1_RX_BUF_DN<0>")
	)
	(segment
		(start 52.726082 -403.830536)
		(end 52.851304 -403.529038)
		(width 0.14224)
		(layer "In13.Cu")
		(net "P5E_CPU1_P1_RX_BUF_DN<0>")
	)
	(segment
		(start 79.397352 -392.720068)
		(end 80.053434 -392.720068)
		(width 0.14224)
		(layer "In13.Cu")
		(net "P5E_CPU1_P1_RX_BUF_DN<0>")
	)
	(segment
		(start 53.573426 -402.874734)
		(end 59.124342 -400.365722)
		(width 0.14224)
		(layer "In13.Cu")
		(net "P5E_CPU1_P1_RX_BUF_DN<0>")
	)
	(arc
		(start 53.397658 -402.985986)
		(mid 53.481663 -402.924231)
		(end 53.573426 -402.874734)
		(width 0.14224)
		(layer "In13.Cu")
		(net "P5E_CPU1_P1_RX_BUF_DN<0>")
	)
	(arc
		(start 59.124342 -400.365722)
		(mid 62.627401 -398.863324)
		(end 66.18605 -397.497808)
		(width 0.14224)
		(layer "In13.Cu")
		(net "P5E_CPU1_P1_RX_BUF_DN<0>")
	)
	(arc
		(start 50.96256 -410.99867)
		(mid 51.097535 -410.888176)
		(end 51.148234 -410.721302)
		(width 0.14224)
		(layer "In13.Cu")
		(net "P5E_CPU1_P1_RX_BUF_DN<0>")
	)
	(arc
		(start 52.679854 -404.061676)
		(mid 52.691573 -403.943827)
		(end 52.726082 -403.830536)
		(width 0.14224)
		(layer "In13.Cu")
		(net "P5E_CPU1_P1_RX_BUF_DN<0>")
	)
	(arc
		(start 49.879758 -414.31972)
		(mid 49.684988 -414.028132)
		(end 49.616614 -413.684212)
		(width 0.14224)
		(layer "In13.Cu")
		(net "P5E_CPU1_P1_RX_BUF_DN<0>")
	)
	(arc
		(start 52.851304 -403.529038)
		(mid 52.914756 -403.416008)
		(end 53.002942 -403.321012)
		(width 0.14224)
		(layer "In13.Cu")
		(net "P5E_CPU1_P1_RX_BUF_DN<0>")
	)
	(arc
		(start 49.616614 -411.82925)
		(mid 49.685552 -411.602435)
		(end 49.868836 -411.45206)
		(width 0.14224)
		(layer "In13.Cu")
		(net "P5E_CPU1_P1_RX_BUF_DN<0>")
	)
	(arc
		(start 57.208166 -422.029636)
		(mid 57.138059 -421.677183)
		(end 56.938418 -421.37838)
		(width 0.14224)
		(layer "In13.Cu")
		(net "P5E_CPU1_P1_RX_BUF_DN<0>")
	)
	(arc
		(start 51.435762 -405.94407)
		(mid 51.658927 -405.760796)
		(end 51.913536 -405.624538)
		(width 0.14224)
		(layer "In13.Cu")
		(net "P5E_CPU1_P1_RX_BUF_DN<0>")
	)
	(arc
		(start 77.888592 -393.445238)
		(mid 78.236976 -393.184816)
		(end 78.62951 -392.997436)
		(width 0.14224)
		(layer "In13.Cu")
		(net "P5E_CPU1_P1_RX_BUF_DN<0>")
	)
	(arc
		(start 51.148234 -406.638252)
		(mid 51.222924 -406.262557)
		(end 51.435762 -405.94407)
		(width 0.14224)
		(layer "In13.Cu")
		(net "P5E_CPU1_P1_RX_BUF_DN<0>")
	)
	(arc
		(start 52.559966 -405.214074)
		(mid 52.648681 -405.081209)
		(end 52.679854 -404.924514)
		(width 0.14224)
		(layer "In13.Cu")
		(net "P5E_CPU1_P1_RX_BUF_DN<0>")
	)
	(segment
		(start 75.956414 -407.954734)
		(end 75.956414 -404.73503)
		(width 0.12954)
		(layer "F.Cu")
		(net "P5E_CPU1_P0_TX_BUF_DP<9>")
	)
	(segment
		(start 76.252324 -408.250644)
		(end 75.956414 -407.954734)
		(width 0.12954)
		(layer "F.Cu")
		(net "P5E_CPU1_P0_TX_BUF_DP<9>")
	)
	(segment
		(start 58.470546 -389.467344)
		(end 58.991246 -389.467344)
		(width 0.127)
		(layer "F.Cu")
		(net "P5E_CPU1_P0_TX_BUF_DP<9>")
	)
	(segment
		(start 75.956414 -404.73503)
		(end 76.226924 -404.46452)
		(width 0.12954)
		(layer "F.Cu")
		(net "P5E_CPU1_P0_TX_BUF_DP<9>")
	)
	(segment
		(start 63.958724 -398.861534)
		(end 66.09588 -399.396966)
		(width 0.14224)
		(layer "In6.Cu")
		(net "P5E_CPU1_P0_TX_BUF_DP<9>")
	)
	(segment
		(start 58.967624 -390.176512)
		(end 58.967624 -390.382506)
		(width 0.14224)
		(layer "In6.Cu")
		(net "P5E_CPU1_P0_TX_BUF_DP<9>")
	)
	(segment
		(start 69.022976 -400.284696)
		(end 70.874128 -400.950684)
		(width 0.14224)
		(layer "In6.Cu")
		(net "P5E_CPU1_P0_TX_BUF_DP<9>")
	)
	(segment
		(start 74.336656 -402.26996)
		(end 74.521314 -402.389594)
		(width 0.14224)
		(layer "In6.Cu")
		(net "P5E_CPU1_P0_TX_BUF_DP<9>")
	)
	(segment
		(start 58.606944 -389.441944)
		(end 58.606944 -389.536686)
		(width 0.14224)
		(layer "In6.Cu")
		(net "P5E_CPU1_P0_TX_BUF_DP<9>")
	)
	(segment
		(start 71.049642 -400.868134)
		(end 71.413116 -400.99869)
		(width 0.14224)
		(layer "In6.Cu")
		(net "P5E_CPU1_P0_TX_BUF_DP<9>")
	)
	(segment
		(start 75.075796 -402.749766)
		(end 75.477116 -403.010116)
		(width 0.14224)
		(layer "In6.Cu")
		(net "P5E_CPU1_P0_TX_BUF_DP<9>")
	)
	(segment
		(start 58.991246 -389.467344)
		(end 58.876438 -389.352536)
		(width 0.14224)
		(layer "In6.Cu")
		(net "P5E_CPU1_P0_TX_BUF_DP<9>")
	)
	(segment
		(start 58.876438 -389.352536)
		(end 58.696352 -389.352536)
		(width 0.14224)
		(layer "In6.Cu")
		(net "P5E_CPU1_P0_TX_BUF_DP<9>")
	)
	(segment
		(start 59.628786 -396.096236)
		(end 61.5188 -397.98625)
		(width 0.14224)
		(layer "In6.Cu")
		(net "P5E_CPU1_P0_TX_BUF_DP<9>")
	)
	(segment
		(start 58.696352 -389.352536)
		(end 58.606944 -389.441944)
		(width 0.14224)
		(layer "In6.Cu")
		(net "P5E_CPU1_P0_TX_BUF_DP<9>")
	)
	(segment
		(start 62.681358 -398.607534)
		(end 63.958724 -398.861534)
		(width 0.14224)
		(layer "In6.Cu")
		(net "P5E_CPU1_P0_TX_BUF_DP<9>")
	)
	(segment
		(start 75.075288 -402.749512)
		(end 75.075796 -402.749766)
		(width 0.14224)
		(layer "In6.Cu")
		(net "P5E_CPU1_P0_TX_BUF_DP<9>")
	)
	(segment
		(start 75.936094 -403.654006)
		(end 75.936094 -404.17369)
		(width 0.14224)
		(layer "In6.Cu")
		(net "P5E_CPU1_P0_TX_BUF_DP<9>")
	)
	(segment
		(start 59.26201 -391.420604)
		(end 59.276996 -391.470134)
		(width 0.14224)
		(layer "In6.Cu")
		(net "P5E_CPU1_P0_TX_BUF_DP<9>")
	)
	(segment
		(start 74.521314 -402.389594)
		(end 74.710798 -402.349208)
		(width 0.14224)
		(layer "In6.Cu")
		(net "P5E_CPU1_P0_TX_BUF_DP<9>")
	)
	(segment
		(start 59.26201 -391.40892)
		(end 59.26201 -391.420604)
		(width 0.14224)
		(layer "In6.Cu")
		(net "P5E_CPU1_P0_TX_BUF_DP<9>")
	)
	(segment
		(start 72.816466 -401.649692)
		(end 72.99198 -401.566888)
		(width 0.14224)
		(layer "In6.Cu")
		(net "P5E_CPU1_P0_TX_BUF_DP<9>")
	)
	(segment
		(start 71.49592 -401.174458)
		(end 72.816466 -401.649692)
		(width 0.14224)
		(layer "In6.Cu")
		(net "P5E_CPU1_P0_TX_BUF_DP<9>")
	)
	(segment
		(start 71.413116 -400.99869)
		(end 71.49592 -401.174458)
		(width 0.14224)
		(layer "In6.Cu")
		(net "P5E_CPU1_P0_TX_BUF_DP<9>")
	)
	(segment
		(start 59.307222 -391.676382)
		(end 59.307222 -395.449552)
		(width 0.14224)
		(layer "In6.Cu")
		(net "P5E_CPU1_P0_TX_BUF_DP<9>")
	)
	(segment
		(start 72.99198 -401.566888)
		(end 73.355454 -401.697698)
		(width 0.14224)
		(layer "In6.Cu")
		(net "P5E_CPU1_P0_TX_BUF_DP<9>")
	)
	(segment
		(start 73.438004 -401.873466)
		(end 73.801224 -402.004022)
		(width 0.14224)
		(layer "In6.Cu")
		(net "P5E_CPU1_P0_TX_BUF_DP<9>")
	)
	(segment
		(start 58.684414 -389.72363)
		(end 58.847736 -389.886952)
		(width 0.14224)
		(layer "In6.Cu")
		(net "P5E_CPU1_P0_TX_BUF_DP<9>")
	)
	(segment
		(start 58.982864 -390.485376)
		(end 59.26201 -391.40892)
		(width 0.14224)
		(layer "In6.Cu")
		(net "P5E_CPU1_P0_TX_BUF_DP<9>")
	)
	(segment
		(start 75.936094 -404.17369)
		(end 76.226924 -404.46452)
		(width 0.14224)
		(layer "In6.Cu")
		(net "P5E_CPU1_P0_TX_BUF_DP<9>")
	)
	(segment
		(start 70.874128 -400.950684)
		(end 71.049642 -400.868134)
		(width 0.14224)
		(layer "In6.Cu")
		(net "P5E_CPU1_P0_TX_BUF_DP<9>")
	)
	(segment
		(start 75.477116 -403.010116)
		(end 75.822556 -403.370288)
		(width 0.14224)
		(layer "In6.Cu")
		(net "P5E_CPU1_P0_TX_BUF_DP<9>")
	)
	(segment
		(start 75.034902 -402.55952)
		(end 75.075288 -402.749512)
		(width 0.14224)
		(layer "In6.Cu")
		(net "P5E_CPU1_P0_TX_BUF_DP<9>")
	)
	(segment
		(start 66.09588 -399.396966)
		(end 69.022976 -400.284696)
		(width 0.14224)
		(layer "In6.Cu")
		(net "P5E_CPU1_P0_TX_BUF_DP<9>")
	)
	(segment
		(start 74.710798 -402.349208)
		(end 75.034902 -402.55952)
		(width 0.14224)
		(layer "In6.Cu")
		(net "P5E_CPU1_P0_TX_BUF_DP<9>")
	)
	(segment
		(start 73.355454 -401.697698)
		(end 73.438004 -401.873466)
		(width 0.14224)
		(layer "In6.Cu")
		(net "P5E_CPU1_P0_TX_BUF_DP<9>")
	)
	(arc
		(start 58.606944 -389.536686)
		(mid 58.627071 -389.637873)
		(end 58.684414 -389.72363)
		(width 0.14224)
		(layer "In6.Cu")
		(net "P5E_CPU1_P0_TX_BUF_DP<9>")
	)
	(arc
		(start 75.822556 -403.370288)
		(mid 75.906774 -403.50116)
		(end 75.936094 -403.654006)
		(width 0.14224)
		(layer "In6.Cu")
		(net "P5E_CPU1_P0_TX_BUF_DP<9>")
	)
	(arc
		(start 58.847736 -389.886952)
		(mid 58.936451 -390.019817)
		(end 58.967624 -390.176512)
		(width 0.14224)
		(layer "In6.Cu")
		(net "P5E_CPU1_P0_TX_BUF_DP<9>")
	)
	(arc
		(start 59.276996 -391.470134)
		(mid 59.29966 -391.57215)
		(end 59.307222 -391.676382)
		(width 0.14224)
		(layer "In6.Cu")
		(net "P5E_CPU1_P0_TX_BUF_DP<9>")
	)
	(arc
		(start 59.32424 -395.575028)
		(mid 59.442852 -395.8553)
		(end 59.628786 -396.096236)
		(width 0.14224)
		(layer "In6.Cu")
		(net "P5E_CPU1_P0_TX_BUF_DP<9>")
	)
	(arc
		(start 59.307222 -395.449552)
		(mid 59.311464 -395.512868)
		(end 59.32424 -395.575028)
		(width 0.14224)
		(layer "In6.Cu")
		(net "P5E_CPU1_P0_TX_BUF_DP<9>")
	)
	(arc
		(start 73.801224 -402.004022)
		(mid 74.076624 -402.121521)
		(end 74.336656 -402.26996)
		(width 0.14224)
		(layer "In6.Cu")
		(net "P5E_CPU1_P0_TX_BUF_DP<9>")
	)
	(arc
		(start 61.5188 -397.98625)
		(mid 62.053984 -398.383154)
		(end 62.681358 -398.607534)
		(width 0.14224)
		(layer "In6.Cu")
		(net "P5E_CPU1_P0_TX_BUF_DP<9>")
	)
	(arc
		(start 58.967624 -390.382506)
		(mid 58.971446 -390.434505)
		(end 58.982864 -390.485376)
		(width 0.14224)
		(layer "In6.Cu")
		(net "P5E_CPU1_P0_TX_BUF_DP<9>")
	)
	(segment
		(start 72.893174 -407.954734)
		(end 72.893174 -404.73503)
		(width 0.12954)
		(layer "F.Cu")
		(net "P5E_CPU1_P0_TX_BUF_DP<8>")
	)
	(segment
		(start 57.27065 -389.467344)
		(end 57.79135 -389.467344)
		(width 0.127)
		(layer "F.Cu")
		(net "P5E_CPU1_P0_TX_BUF_DP<8>")
	)
	(segment
		(start 72.893174 -404.73503)
		(end 73.163684 -404.46452)
		(width 0.12954)
		(layer "F.Cu")
		(net "P5E_CPU1_P0_TX_BUF_DP<8>")
	)
	(segment
		(start 73.189084 -408.250644)
		(end 72.893174 -407.954734)
		(width 0.12954)
		(layer "F.Cu")
		(net "P5E_CPU1_P0_TX_BUF_DP<8>")
	)
	(segment
		(start 63.77051 -399.780506)
		(end 64.958468 -400.07794)
		(width 0.14224)
		(layer "In6.Cu")
		(net "P5E_CPU1_P0_TX_BUF_DP<8>")
	)
	(segment
		(start 72.173338 -402.485098)
		(end 72.247506 -402.664676)
		(width 0.14224)
		(layer "In6.Cu")
		(net "P5E_CPU1_P0_TX_BUF_DP<8>")
	)
	(segment
		(start 58.28538 -396.079472)
		(end 60.921646 -398.715738)
		(width 0.14224)
		(layer "In6.Cu")
		(net "P5E_CPU1_P0_TX_BUF_DP<8>")
	)
	(segment
		(start 57.676542 -389.352536)
		(end 57.496456 -389.352536)
		(width 0.14224)
		(layer "In6.Cu")
		(net "P5E_CPU1_P0_TX_BUF_DP<8>")
	)
	(segment
		(start 57.496202 -389.735314)
		(end 57.64784 -389.886698)
		(width 0.14224)
		(layer "In6.Cu")
		(net "P5E_CPU1_P0_TX_BUF_DP<8>")
	)
	(segment
		(start 66.399664 -400.476974)
		(end 67.774058 -400.894296)
		(width 0.14224)
		(layer "In6.Cu")
		(net "P5E_CPU1_P0_TX_BUF_DP<8>")
	)
	(segment
		(start 57.78627 -390.429242)
		(end 58.095134 -391.449052)
		(width 0.14224)
		(layer "In6.Cu")
		(net "P5E_CPU1_P0_TX_BUF_DP<8>")
	)
	(segment
		(start 71.280528 -402.264118)
		(end 71.637144 -402.411692)
		(width 0.14224)
		(layer "In6.Cu")
		(net "P5E_CPU1_P0_TX_BUF_DP<8>")
	)
	(segment
		(start 62.394338 -399.503138)
		(end 63.621412 -399.746978)
		(width 0.14224)
		(layer "In6.Cu")
		(net "P5E_CPU1_P0_TX_BUF_DP<8>")
	)
	(segment
		(start 58.125614 -395.196822)
		(end 58.125614 -395.693646)
		(width 0.14224)
		(layer "In6.Cu")
		(net "P5E_CPU1_P0_TX_BUF_DP<8>")
	)
	(segment
		(start 72.872854 -403.266148)
		(end 72.872854 -404.17369)
		(width 0.14224)
		(layer "In6.Cu")
		(net "P5E_CPU1_P0_TX_BUF_DP<8>")
	)
	(segment
		(start 71.816468 -402.337524)
		(end 72.173338 -402.485098)
		(width 0.14224)
		(layer "In6.Cu")
		(net "P5E_CPU1_P0_TX_BUF_DP<8>")
	)
	(segment
		(start 58.125614 -394.495782)
		(end 58.262774 -394.632942)
		(width 0.14224)
		(layer "In6.Cu")
		(net "P5E_CPU1_P0_TX_BUF_DP<8>")
	)
	(segment
		(start 57.407048 -389.441944)
		(end 57.407048 -389.520176)
		(width 0.14224)
		(layer "In6.Cu")
		(net "P5E_CPU1_P0_TX_BUF_DP<8>")
	)
	(segment
		(start 70.670166 -402.011134)
		(end 70.84949 -401.936966)
		(width 0.14224)
		(layer "In6.Cu")
		(net "P5E_CPU1_P0_TX_BUF_DP<8>")
	)
	(segment
		(start 58.262774 -395.059662)
		(end 58.125614 -395.196822)
		(width 0.14224)
		(layer "In6.Cu")
		(net "P5E_CPU1_P0_TX_BUF_DP<8>")
	)
	(segment
		(start 71.20636 -402.08454)
		(end 71.280528 -402.264118)
		(width 0.14224)
		(layer "In6.Cu")
		(net "P5E_CPU1_P0_TX_BUF_DP<8>")
	)
	(segment
		(start 57.496456 -389.352536)
		(end 57.407048 -389.441944)
		(width 0.14224)
		(layer "In6.Cu")
		(net "P5E_CPU1_P0_TX_BUF_DP<8>")
	)
	(segment
		(start 57.767728 -390.17575)
		(end 57.767728 -390.304528)
		(width 0.14224)
		(layer "In6.Cu")
		(net "P5E_CPU1_P0_TX_BUF_DP<8>")
	)
	(segment
		(start 58.262774 -394.632942)
		(end 58.262774 -395.059662)
		(width 0.14224)
		(layer "In6.Cu")
		(net "P5E_CPU1_P0_TX_BUF_DP<8>")
	)
	(segment
		(start 58.125614 -391.6553)
		(end 58.125614 -394.495782)
		(width 0.14224)
		(layer "In6.Cu")
		(net "P5E_CPU1_P0_TX_BUF_DP<8>")
	)
	(segment
		(start 70.84949 -401.936966)
		(end 71.20636 -402.08454)
		(width 0.14224)
		(layer "In6.Cu")
		(net "P5E_CPU1_P0_TX_BUF_DP<8>")
	)
	(segment
		(start 57.79135 -389.467344)
		(end 57.676542 -389.352536)
		(width 0.14224)
		(layer "In6.Cu")
		(net "P5E_CPU1_P0_TX_BUF_DP<8>")
	)
	(segment
		(start 72.247506 -402.664676)
		(end 72.604122 -402.81225)
		(width 0.14224)
		(layer "In6.Cu")
		(net "P5E_CPU1_P0_TX_BUF_DP<8>")
	)
	(segment
		(start 69.245988 -401.421346)
		(end 70.670166 -402.011134)
		(width 0.14224)
		(layer "In6.Cu")
		(net "P5E_CPU1_P0_TX_BUF_DP<8>")
	)
	(segment
		(start 72.872854 -404.17369)
		(end 73.163684 -404.46452)
		(width 0.14224)
		(layer "In6.Cu")
		(net "P5E_CPU1_P0_TX_BUF_DP<8>")
	)
	(segment
		(start 71.637144 -402.411692)
		(end 71.816468 -402.337524)
		(width 0.14224)
		(layer "In6.Cu")
		(net "P5E_CPU1_P0_TX_BUF_DP<8>")
	)
	(arc
		(start 57.767728 -390.304528)
		(mid 57.772409 -390.367567)
		(end 57.78627 -390.429242)
		(width 0.14224)
		(layer "In6.Cu")
		(net "P5E_CPU1_P0_TX_BUF_DP<8>")
	)
	(arc
		(start 58.125614 -395.693646)
		(mid 58.167145 -395.902435)
		(end 58.28538 -396.079472)
		(width 0.14224)
		(layer "In6.Cu")
		(net "P5E_CPU1_P0_TX_BUF_DP<8>")
	)
	(arc
		(start 57.407048 -389.520176)
		(mid 57.430226 -389.636609)
		(end 57.496202 -389.735314)
		(width 0.14224)
		(layer "In6.Cu")
		(net "P5E_CPU1_P0_TX_BUF_DP<8>")
	)
	(arc
		(start 72.604122 -402.81225)
		(mid 72.761744 -402.926138)
		(end 72.851772 -403.098508)
		(width 0.14224)
		(layer "In6.Cu")
		(net "P5E_CPU1_P0_TX_BUF_DP<8>")
	)
	(arc
		(start 67.774058 -400.894296)
		(mid 68.516475 -401.139802)
		(end 69.245988 -401.421346)
		(width 0.14224)
		(layer "In6.Cu")
		(net "P5E_CPU1_P0_TX_BUF_DP<8>")
	)
	(arc
		(start 60.921646 -398.715738)
		(mid 61.599603 -399.218646)
		(end 62.394338 -399.503138)
		(width 0.14224)
		(layer "In6.Cu")
		(net "P5E_CPU1_P0_TX_BUF_DP<8>")
	)
	(arc
		(start 72.851772 -403.098508)
		(mid 72.867568 -403.181668)
		(end 72.872854 -403.266148)
		(width 0.14224)
		(layer "In6.Cu")
		(net "P5E_CPU1_P0_TX_BUF_DP<8>")
	)
	(arc
		(start 63.621412 -399.746978)
		(mid 63.696167 -399.762826)
		(end 63.77051 -399.780506)
		(width 0.14224)
		(layer "In6.Cu")
		(net "P5E_CPU1_P0_TX_BUF_DP<8>")
	)
	(arc
		(start 64.958468 -400.07794)
		(mid 65.681532 -400.268549)
		(end 66.399664 -400.476974)
		(width 0.14224)
		(layer "In6.Cu")
		(net "P5E_CPU1_P0_TX_BUF_DP<8>")
	)
	(arc
		(start 57.64784 -389.886698)
		(mid 57.736536 -390.019301)
		(end 57.767728 -390.17575)
		(width 0.14224)
		(layer "In6.Cu")
		(net "P5E_CPU1_P0_TX_BUF_DP<8>")
	)
	(arc
		(start 58.095134 -391.449052)
		(mid 58.117979 -391.551053)
		(end 58.125614 -391.6553)
		(width 0.14224)
		(layer "In6.Cu")
		(net "P5E_CPU1_P0_TX_BUF_DP<8>")
	)
	(segment
		(start 69.829934 -404.73503)
		(end 70.100444 -404.46452)
		(width 0.12954)
		(layer "F.Cu")
		(net "P5E_CPU1_P0_TX_BUF_DP<7>")
	)
	(segment
		(start 56.0705 -389.467344)
		(end 56.5912 -389.467344)
		(width 0.127)
		(layer "F.Cu")
		(net "P5E_CPU1_P0_TX_BUF_DP<7>")
	)
	(segment
		(start 70.125844 -408.250644)
		(end 69.829934 -407.954734)
		(width 0.12954)
		(layer "F.Cu")
		(net "P5E_CPU1_P0_TX_BUF_DP<7>")
	)
	(segment
		(start 69.829934 -407.954734)
		(end 69.829934 -404.73503)
		(width 0.12954)
		(layer "F.Cu")
		(net "P5E_CPU1_P0_TX_BUF_DP<7>")
	)
	(segment
		(start 67.306952 -401.939252)
		(end 67.479418 -401.850098)
		(width 0.14224)
		(layer "In6.Cu")
		(net "P5E_CPU1_P0_TX_BUF_DP<7>")
	)
	(segment
		(start 56.257698 -389.67537)
		(end 56.438038 -389.85571)
		(width 0.14224)
		(layer "In6.Cu")
		(net "P5E_CPU1_P0_TX_BUF_DP<7>")
	)
	(segment
		(start 66.93916 -401.822412)
		(end 67.306952 -401.939252)
		(width 0.14224)
		(layer "In6.Cu")
		(net "P5E_CPU1_P0_TX_BUF_DP<7>")
	)
	(segment
		(start 56.586374 -390.51865)
		(end 56.923432 -391.629138)
		(width 0.14224)
		(layer "In6.Cu")
		(net "P5E_CPU1_P0_TX_BUF_DP<7>")
	)
	(segment
		(start 56.953912 -395.205458)
		(end 56.953912 -395.926564)
		(width 0.14224)
		(layer "In6.Cu")
		(net "P5E_CPU1_P0_TX_BUF_DP<7>")
	)
	(segment
		(start 64.266572 -400.971766)
		(end 66.309494 -401.621752)
		(width 0.14224)
		(layer "In6.Cu")
		(net "P5E_CPU1_P0_TX_BUF_DP<7>")
	)
	(segment
		(start 69.46646 -402.674836)
		(end 69.678804 -402.88718)
		(width 0.14224)
		(layer "In6.Cu")
		(net "P5E_CPU1_P0_TX_BUF_DP<7>")
	)
	(segment
		(start 57.057036 -396.17523)
		(end 60.29833 -399.416524)
		(width 0.14224)
		(layer "In6.Cu")
		(net "P5E_CPU1_P0_TX_BUF_DP<7>")
	)
	(segment
		(start 56.953912 -391.83564)
		(end 56.953912 -394.504418)
		(width 0.14224)
		(layer "In6.Cu")
		(net "P5E_CPU1_P0_TX_BUF_DP<7>")
	)
	(segment
		(start 68.934076 -402.457158)
		(end 68.93433 -402.457412)
		(width 0.14224)
		(layer "In6.Cu")
		(net "P5E_CPU1_P0_TX_BUF_DP<7>")
	)
	(segment
		(start 56.567832 -390.1694)
		(end 56.567832 -390.393682)
		(width 0.14224)
		(layer "In6.Cu")
		(net "P5E_CPU1_P0_TX_BUF_DP<7>")
	)
	(segment
		(start 66.309494 -401.621752)
		(end 66.48196 -401.532598)
		(width 0.14224)
		(layer "In6.Cu")
		(net "P5E_CPU1_P0_TX_BUF_DP<7>")
	)
	(segment
		(start 57.091072 -395.068298)
		(end 56.953912 -395.205458)
		(width 0.14224)
		(layer "In6.Cu")
		(net "P5E_CPU1_P0_TX_BUF_DP<7>")
	)
	(segment
		(start 56.953912 -394.504418)
		(end 57.091072 -394.641578)
		(width 0.14224)
		(layer "In6.Cu")
		(net "P5E_CPU1_P0_TX_BUF_DP<7>")
	)
	(segment
		(start 68.844922 -402.284692)
		(end 68.934076 -402.457158)
		(width 0.14224)
		(layer "In6.Cu")
		(net "P5E_CPU1_P0_TX_BUF_DP<7>")
	)
	(segment
		(start 67.936618 -402.139912)
		(end 68.30441 -402.256752)
		(width 0.14224)
		(layer "In6.Cu")
		(net "P5E_CPU1_P0_TX_BUF_DP<7>")
	)
	(segment
		(start 62.147704 -400.405092)
		(end 64.266572 -400.971766)
		(width 0.14224)
		(layer "In6.Cu")
		(net "P5E_CPU1_P0_TX_BUF_DP<7>")
	)
	(segment
		(start 69.824854 -403.239986)
		(end 69.824854 -404.122128)
		(width 0.14224)
		(layer "In6.Cu")
		(net "P5E_CPU1_P0_TX_BUF_DP<7>")
	)
	(segment
		(start 68.476622 -402.167598)
		(end 68.844922 -402.284692)
		(width 0.14224)
		(layer "In6.Cu")
		(net "P5E_CPU1_P0_TX_BUF_DP<7>")
	)
	(segment
		(start 67.479418 -401.850098)
		(end 67.847464 -401.967192)
		(width 0.14224)
		(layer "In6.Cu")
		(net "P5E_CPU1_P0_TX_BUF_DP<7>")
	)
	(segment
		(start 67.847464 -401.967192)
		(end 67.936618 -402.139912)
		(width 0.14224)
		(layer "In6.Cu")
		(net "P5E_CPU1_P0_TX_BUF_DP<7>")
	)
	(segment
		(start 68.93433 -402.457412)
		(end 69.30136 -402.574252)
		(width 0.14224)
		(layer "In6.Cu")
		(net "P5E_CPU1_P0_TX_BUF_DP<7>")
	)
	(segment
		(start 56.309768 -389.352536)
		(end 56.200294 -389.46201)
		(width 0.14224)
		(layer "In6.Cu")
		(net "P5E_CPU1_P0_TX_BUF_DP<7>")
	)
	(segment
		(start 57.091072 -394.641578)
		(end 57.091072 -395.068298)
		(width 0.14224)
		(layer "In6.Cu")
		(net "P5E_CPU1_P0_TX_BUF_DP<7>")
	)
	(segment
		(start 56.200294 -389.46201)
		(end 56.200294 -389.536686)
		(width 0.14224)
		(layer "In6.Cu")
		(net "P5E_CPU1_P0_TX_BUF_DP<7>")
	)
	(segment
		(start 66.48196 -401.532598)
		(end 66.850006 -401.649692)
		(width 0.14224)
		(layer "In6.Cu")
		(net "P5E_CPU1_P0_TX_BUF_DP<7>")
	)
	(segment
		(start 66.850006 -401.649692)
		(end 66.93916 -401.822412)
		(width 0.14224)
		(layer "In6.Cu")
		(net "P5E_CPU1_P0_TX_BUF_DP<7>")
	)
	(segment
		(start 69.872098 -404.236174)
		(end 70.100444 -404.46452)
		(width 0.14224)
		(layer "In6.Cu")
		(net "P5E_CPU1_P0_TX_BUF_DP<7>")
	)
	(segment
		(start 56.476392 -389.352536)
		(end 56.309768 -389.352536)
		(width 0.14224)
		(layer "In6.Cu")
		(net "P5E_CPU1_P0_TX_BUF_DP<7>")
	)
	(segment
		(start 68.30441 -402.256752)
		(end 68.476622 -402.167598)
		(width 0.14224)
		(layer "In6.Cu")
		(net "P5E_CPU1_P0_TX_BUF_DP<7>")
	)
	(segment
		(start 56.5912 -389.467344)
		(end 56.476392 -389.352536)
		(width 0.14224)
		(layer "In6.Cu")
		(net "P5E_CPU1_P0_TX_BUF_DP<7>")
	)
	(arc
		(start 56.567832 -390.393682)
		(mid 56.572502 -390.456847)
		(end 56.586374 -390.51865)
		(width 0.14224)
		(layer "In6.Cu")
		(net "P5E_CPU1_P0_TX_BUF_DP<7>")
	)
	(arc
		(start 69.678804 -402.88718)
		(mid 69.786908 -403.049063)
		(end 69.824854 -403.239986)
		(width 0.14224)
		(layer "In6.Cu")
		(net "P5E_CPU1_P0_TX_BUF_DP<7>")
	)
	(arc
		(start 69.30136 -402.574252)
		(mid 69.389937 -402.614651)
		(end 69.46646 -402.674836)
		(width 0.14224)
		(layer "In6.Cu")
		(net "P5E_CPU1_P0_TX_BUF_DP<7>")
	)
	(arc
		(start 69.824854 -404.122128)
		(mid 69.837131 -404.183851)
		(end 69.872098 -404.236174)
		(width 0.14224)
		(layer "In6.Cu")
		(net "P5E_CPU1_P0_TX_BUF_DP<7>")
	)
	(arc
		(start 56.200294 -389.536686)
		(mid 56.21522 -389.611726)
		(end 56.257698 -389.67537)
		(width 0.14224)
		(layer "In6.Cu")
		(net "P5E_CPU1_P0_TX_BUF_DP<7>")
	)
	(arc
		(start 60.29833 -399.416524)
		(mid 61.149703 -400.047959)
		(end 62.147704 -400.405092)
		(width 0.14224)
		(layer "In6.Cu")
		(net "P5E_CPU1_P0_TX_BUF_DP<7>")
	)
	(arc
		(start 56.438038 -389.85571)
		(mid 56.534174 -389.999633)
		(end 56.567832 -390.1694)
		(width 0.14224)
		(layer "In6.Cu")
		(net "P5E_CPU1_P0_TX_BUF_DP<7>")
	)
	(arc
		(start 56.923432 -391.629138)
		(mid 56.946276 -391.731266)
		(end 56.953912 -391.83564)
		(width 0.14224)
		(layer "In6.Cu")
		(net "P5E_CPU1_P0_TX_BUF_DP<7>")
	)
	(arc
		(start 56.953912 -395.926564)
		(mid 56.980721 -396.06116)
		(end 57.057036 -396.17523)
		(width 0.14224)
		(layer "In6.Cu")
		(net "P5E_CPU1_P0_TX_BUF_DP<7>")
	)
	(segment
		(start 67.062604 -408.250644)
		(end 66.766694 -407.954734)
		(width 0.12954)
		(layer "F.Cu")
		(net "P5E_CPU1_P0_TX_BUF_DP<6>")
	)
	(segment
		(start 54.870604 -389.467344)
		(end 55.391304 -389.467344)
		(width 0.127)
		(layer "F.Cu")
		(net "P5E_CPU1_P0_TX_BUF_DP<6>")
	)
	(segment
		(start 66.766694 -404.73503)
		(end 67.037204 -404.46452)
		(width 0.12954)
		(layer "F.Cu")
		(net "P5E_CPU1_P0_TX_BUF_DP<6>")
	)
	(segment
		(start 66.766694 -407.954734)
		(end 66.766694 -404.73503)
		(width 0.12954)
		(layer "F.Cu")
		(net "P5E_CPU1_P0_TX_BUF_DP<6>")
	)
	(segment
		(start 61.896244 -401.351496)
		(end 62.82309 -401.583906)
		(width 0.14224)
		(layer "In6.Cu")
		(net "P5E_CPU1_P0_TX_BUF_DP<6>")
	)
	(segment
		(start 55.391304 -389.467344)
		(end 55.276496 -389.352536)
		(width 0.14224)
		(layer "In6.Cu")
		(net "P5E_CPU1_P0_TX_BUF_DP<6>")
	)
	(segment
		(start 66.746374 -403.514052)
		(end 66.746374 -404.17369)
		(width 0.14224)
		(layer "In6.Cu")
		(net "P5E_CPU1_P0_TX_BUF_DP<6>")
	)
	(segment
		(start 64.428878 -402.078444)
		(end 64.505332 -402.257006)
		(width 0.14224)
		(layer "In6.Cu")
		(net "P5E_CPU1_P0_TX_BUF_DP<6>")
	)
	(segment
		(start 64.505332 -402.257006)
		(end 64.863726 -402.400262)
		(width 0.14224)
		(layer "In6.Cu")
		(net "P5E_CPU1_P0_TX_BUF_DP<6>")
	)
	(segment
		(start 55.753762 -395.231874)
		(end 55.753762 -395.893798)
		(width 0.14224)
		(layer "In6.Cu")
		(net "P5E_CPU1_P0_TX_BUF_DP<6>")
	)
	(segment
		(start 64.07023 -401.935188)
		(end 64.428878 -402.078444)
		(width 0.14224)
		(layer "In6.Cu")
		(net "P5E_CPU1_P0_TX_BUF_DP<6>")
	)
	(segment
		(start 55.753762 -391.856214)
		(end 55.753762 -394.530834)
		(width 0.14224)
		(layer "In6.Cu")
		(net "P5E_CPU1_P0_TX_BUF_DP<6>")
	)
	(segment
		(start 65.400682 -402.467318)
		(end 65.477136 -402.64588)
		(width 0.14224)
		(layer "In6.Cu")
		(net "P5E_CPU1_P0_TX_BUF_DP<6>")
	)
	(segment
		(start 55.890922 -394.667994)
		(end 55.890922 -395.094714)
		(width 0.14224)
		(layer "In6.Cu")
		(net "P5E_CPU1_P0_TX_BUF_DP<6>")
	)
	(segment
		(start 65.477136 -402.64588)
		(end 66.411602 -403.019768)
		(width 0.14224)
		(layer "In6.Cu")
		(net "P5E_CPU1_P0_TX_BUF_DP<6>")
	)
	(segment
		(start 55.09641 -389.352536)
		(end 55.007002 -389.441944)
		(width 0.14224)
		(layer "In6.Cu")
		(net "P5E_CPU1_P0_TX_BUF_DP<6>")
	)
	(segment
		(start 55.276496 -389.352536)
		(end 55.09641 -389.352536)
		(width 0.14224)
		(layer "In6.Cu")
		(net "P5E_CPU1_P0_TX_BUF_DP<6>")
	)
	(segment
		(start 55.367682 -390.19099)
		(end 55.367682 -390.4361)
		(width 0.14224)
		(layer "In6.Cu")
		(net "P5E_CPU1_P0_TX_BUF_DP<6>")
	)
	(segment
		(start 56.028082 -396.555976)
		(end 59.421776 -399.94967)
		(width 0.14224)
		(layer "In6.Cu")
		(net "P5E_CPU1_P0_TX_BUF_DP<6>")
	)
	(segment
		(start 65.042034 -402.323808)
		(end 65.400682 -402.467318)
		(width 0.14224)
		(layer "In6.Cu")
		(net "P5E_CPU1_P0_TX_BUF_DP<6>")
	)
	(segment
		(start 64.863726 -402.400262)
		(end 65.042034 -402.323808)
		(width 0.14224)
		(layer "In6.Cu")
		(net "P5E_CPU1_P0_TX_BUF_DP<6>")
	)
	(segment
		(start 55.380128 -390.51865)
		(end 55.723282 -391.649712)
		(width 0.14224)
		(layer "In6.Cu")
		(net "P5E_CPU1_P0_TX_BUF_DP<6>")
	)
	(segment
		(start 62.82309 -401.583906)
		(end 63.891922 -402.011388)
		(width 0.14224)
		(layer "In6.Cu")
		(net "P5E_CPU1_P0_TX_BUF_DP<6>")
	)
	(segment
		(start 63.891922 -402.011388)
		(end 64.07023 -401.935188)
		(width 0.14224)
		(layer "In6.Cu")
		(net "P5E_CPU1_P0_TX_BUF_DP<6>")
	)
	(segment
		(start 55.007002 -389.441944)
		(end 55.007002 -389.46201)
		(width 0.14224)
		(layer "In6.Cu")
		(net "P5E_CPU1_P0_TX_BUF_DP<6>")
	)
	(segment
		(start 55.137558 -389.77697)
		(end 55.237888 -389.8773)
		(width 0.14224)
		(layer "In6.Cu")
		(net "P5E_CPU1_P0_TX_BUF_DP<6>")
	)
	(segment
		(start 66.746374 -404.17369)
		(end 67.037204 -404.46452)
		(width 0.14224)
		(layer "In6.Cu")
		(net "P5E_CPU1_P0_TX_BUF_DP<6>")
	)
	(segment
		(start 55.753762 -394.530834)
		(end 55.890922 -394.667994)
		(width 0.14224)
		(layer "In6.Cu")
		(net "P5E_CPU1_P0_TX_BUF_DP<6>")
	)
	(segment
		(start 55.890922 -395.094714)
		(end 55.753762 -395.231874)
		(width 0.14224)
		(layer "In6.Cu")
		(net "P5E_CPU1_P0_TX_BUF_DP<6>")
	)
	(arc
		(start 66.411602 -403.019768)
		(mid 66.654762 -403.215578)
		(end 66.746374 -403.514052)
		(width 0.14224)
		(layer "In6.Cu")
		(net "P5E_CPU1_P0_TX_BUF_DP<6>")
	)
	(arc
		(start 55.367682 -390.4361)
		(mid 55.370842 -390.477838)
		(end 55.380128 -390.51865)
		(width 0.14224)
		(layer "In6.Cu")
		(net "P5E_CPU1_P0_TX_BUF_DP<6>")
	)
	(arc
		(start 55.237888 -389.8773)
		(mid 55.334024 -390.021223)
		(end 55.367682 -390.19099)
		(width 0.14224)
		(layer "In6.Cu")
		(net "P5E_CPU1_P0_TX_BUF_DP<6>")
	)
	(arc
		(start 55.753762 -395.893798)
		(mid 55.825049 -396.25218)
		(end 56.028082 -396.555976)
		(width 0.14224)
		(layer "In6.Cu")
		(net "P5E_CPU1_P0_TX_BUF_DP<6>")
	)
	(arc
		(start 55.007002 -389.46201)
		(mid 55.04093 -389.632487)
		(end 55.137558 -389.77697)
		(width 0.14224)
		(layer "In6.Cu")
		(net "P5E_CPU1_P0_TX_BUF_DP<6>")
	)
	(arc
		(start 55.723282 -391.649712)
		(mid 55.746126 -391.75184)
		(end 55.753762 -391.856214)
		(width 0.14224)
		(layer "In6.Cu")
		(net "P5E_CPU1_P0_TX_BUF_DP<6>")
	)
	(arc
		(start 59.421776 -399.94967)
		(mid 60.563848 -400.818555)
		(end 61.896244 -401.351496)
		(width 0.14224)
		(layer "In6.Cu")
		(net "P5E_CPU1_P0_TX_BUF_DP<6>")
	)
	(segment
		(start 63.703454 -407.954734)
		(end 63.703454 -404.73503)
		(width 0.12954)
		(layer "F.Cu")
		(net "P5E_CPU1_P0_TX_BUF_DP<5>")
	)
	(segment
		(start 53.670708 -389.467344)
		(end 54.191408 -389.467344)
		(width 0.127)
		(layer "F.Cu")
		(net "P5E_CPU1_P0_TX_BUF_DP<5>")
	)
	(segment
		(start 63.703454 -404.73503)
		(end 63.973964 -404.46452)
		(width 0.12954)
		(layer "F.Cu")
		(net "P5E_CPU1_P0_TX_BUF_DP<5>")
	)
	(segment
		(start 63.999364 -408.250644)
		(end 63.703454 -407.954734)
		(width 0.12954)
		(layer "F.Cu")
		(net "P5E_CPU1_P0_TX_BUF_DP<5>")
	)
	(segment
		(start 63.334646 -402.972778)
		(end 63.55334 -403.191472)
		(width 0.14224)
		(layer "In6.Cu")
		(net "P5E_CPU1_P0_TX_BUF_DP<5>")
	)
	(segment
		(start 54.553866 -394.805154)
		(end 54.691026 -394.942314)
		(width 0.14224)
		(layer "In6.Cu")
		(net "P5E_CPU1_P0_TX_BUF_DP<5>")
	)
	(segment
		(start 61.28004 -402.223478)
		(end 62.320932 -402.430488)
		(width 0.14224)
		(layer "In6.Cu")
		(net "P5E_CPU1_P0_TX_BUF_DP<5>")
	)
	(segment
		(start 54.212236 -390.283192)
		(end 54.212236 -390.532112)
		(width 0.14224)
		(layer "In6.Cu")
		(net "P5E_CPU1_P0_TX_BUF_DP<5>")
	)
	(segment
		(start 55.42407 -397.467074)
		(end 55.617872 -397.467074)
		(width 0.14224)
		(layer "In6.Cu")
		(net "P5E_CPU1_P0_TX_BUF_DP<5>")
	)
	(segment
		(start 63.683134 -404.17369)
		(end 63.973964 -404.46452)
		(width 0.14224)
		(layer "In6.Cu")
		(net "P5E_CPU1_P0_TX_BUF_DP<5>")
	)
	(segment
		(start 54.948074 -396.991078)
		(end 55.42407 -397.467074)
		(width 0.14224)
		(layer "In6.Cu")
		(net "P5E_CPU1_P0_TX_BUF_DP<5>")
	)
	(segment
		(start 56.358028 -398.206976)
		(end 56.631332 -398.48028)
		(width 0.14224)
		(layer "In6.Cu")
		(net "P5E_CPU1_P0_TX_BUF_DP<5>")
	)
	(segment
		(start 53.807106 -389.441944)
		(end 53.807106 -389.473186)
		(width 0.14224)
		(layer "In6.Cu")
		(net "P5E_CPU1_P0_TX_BUF_DP<5>")
	)
	(segment
		(start 53.896514 -389.352536)
		(end 53.807106 -389.441944)
		(width 0.14224)
		(layer "In6.Cu")
		(net "P5E_CPU1_P0_TX_BUF_DP<5>")
	)
	(segment
		(start 54.230778 -390.656826)
		(end 54.553866 -391.723372)
		(width 0.14224)
		(layer "In6.Cu")
		(net "P5E_CPU1_P0_TX_BUF_DP<5>")
	)
	(segment
		(start 54.553866 -391.723372)
		(end 54.553866 -394.805154)
		(width 0.14224)
		(layer "In6.Cu")
		(net "P5E_CPU1_P0_TX_BUF_DP<5>")
	)
	(segment
		(start 54.553866 -395.506194)
		(end 54.553866 -396.03934)
		(width 0.14224)
		(layer "In6.Cu")
		(net "P5E_CPU1_P0_TX_BUF_DP<5>")
	)
	(segment
		(start 56.163972 -398.206976)
		(end 56.358028 -398.206976)
		(width 0.14224)
		(layer "In6.Cu")
		(net "P5E_CPU1_P0_TX_BUF_DP<5>")
	)
	(segment
		(start 55.891176 -397.740378)
		(end 55.891176 -397.93418)
		(width 0.14224)
		(layer "In6.Cu")
		(net "P5E_CPU1_P0_TX_BUF_DP<5>")
	)
	(segment
		(start 63.683134 -403.505162)
		(end 63.683134 -404.17369)
		(width 0.14224)
		(layer "In6.Cu")
		(net "P5E_CPU1_P0_TX_BUF_DP<5>")
	)
	(segment
		(start 60.444634 -401.965922)
		(end 61.157104 -402.191728)
		(width 0.14224)
		(layer "In6.Cu")
		(net "P5E_CPU1_P0_TX_BUF_DP<5>")
	)
	(segment
		(start 54.0766 -389.352536)
		(end 53.896514 -389.352536)
		(width 0.14224)
		(layer "In6.Cu")
		(net "P5E_CPU1_P0_TX_BUF_DP<5>")
	)
	(segment
		(start 54.691026 -395.369034)
		(end 54.553866 -395.506194)
		(width 0.14224)
		(layer "In6.Cu")
		(net "P5E_CPU1_P0_TX_BUF_DP<5>")
	)
	(segment
		(start 55.891176 -397.93418)
		(end 56.163972 -398.206976)
		(width 0.14224)
		(layer "In6.Cu")
		(net "P5E_CPU1_P0_TX_BUF_DP<5>")
	)
	(segment
		(start 53.929534 -389.768588)
		(end 54.047898 -389.886698)
		(width 0.14224)
		(layer "In6.Cu")
		(net "P5E_CPU1_P0_TX_BUF_DP<5>")
	)
	(segment
		(start 56.631332 -398.674336)
		(end 59.114436 -401.15744)
		(width 0.14224)
		(layer "In6.Cu")
		(net "P5E_CPU1_P0_TX_BUF_DP<5>")
	)
	(segment
		(start 54.191408 -389.467344)
		(end 54.0766 -389.352536)
		(width 0.14224)
		(layer "In6.Cu")
		(net "P5E_CPU1_P0_TX_BUF_DP<5>")
	)
	(segment
		(start 54.691026 -394.942314)
		(end 54.691026 -395.369034)
		(width 0.14224)
		(layer "In6.Cu")
		(net "P5E_CPU1_P0_TX_BUF_DP<5>")
	)
	(segment
		(start 55.617872 -397.467074)
		(end 55.891176 -397.740378)
		(width 0.14224)
		(layer "In6.Cu")
		(net "P5E_CPU1_P0_TX_BUF_DP<5>")
	)
	(segment
		(start 56.631332 -398.48028)
		(end 56.631332 -398.674336)
		(width 0.14224)
		(layer "In6.Cu")
		(net "P5E_CPU1_P0_TX_BUF_DP<5>")
	)
	(arc
		(start 62.320932 -402.430488)
		(mid 62.868029 -402.626412)
		(end 63.334646 -402.972778)
		(width 0.14224)
		(layer "In6.Cu")
		(net "P5E_CPU1_P0_TX_BUF_DP<5>")
	)
	(arc
		(start 59.114436 -401.15744)
		(mid 59.730943 -401.641626)
		(end 60.444634 -401.965922)
		(width 0.14224)
		(layer "In6.Cu")
		(net "P5E_CPU1_P0_TX_BUF_DP<5>")
	)
	(arc
		(start 54.047898 -389.886698)
		(mid 54.169502 -390.068597)
		(end 54.212236 -390.283192)
		(width 0.14224)
		(layer "In6.Cu")
		(net "P5E_CPU1_P0_TX_BUF_DP<5>")
	)
	(arc
		(start 54.553866 -396.03934)
		(mid 54.65632 -396.554411)
		(end 54.948074 -396.991078)
		(width 0.14224)
		(layer "In6.Cu")
		(net "P5E_CPU1_P0_TX_BUF_DP<5>")
	)
	(arc
		(start 63.55334 -403.191472)
		(mid 63.649476 -403.335395)
		(end 63.683134 -403.505162)
		(width 0.14224)
		(layer "In6.Cu")
		(net "P5E_CPU1_P0_TX_BUF_DP<5>")
	)
	(arc
		(start 53.807106 -389.473186)
		(mid 53.838926 -389.633068)
		(end 53.929534 -389.768588)
		(width 0.14224)
		(layer "In6.Cu")
		(net "P5E_CPU1_P0_TX_BUF_DP<5>")
	)
	(arc
		(start 61.157104 -402.191728)
		(mid 61.218132 -402.209307)
		(end 61.28004 -402.223478)
		(width 0.14224)
		(layer "In6.Cu")
		(net "P5E_CPU1_P0_TX_BUF_DP<5>")
	)
	(arc
		(start 54.212236 -390.532112)
		(mid 54.216917 -390.595151)
		(end 54.230778 -390.656826)
		(width 0.14224)
		(layer "In6.Cu")
		(net "P5E_CPU1_P0_TX_BUF_DP<5>")
	)
	(segment
		(start 60.640214 -404.73503)
		(end 60.910724 -404.46452)
		(width 0.12954)
		(layer "F.Cu")
		(net "P5E_CPU1_P0_TX_BUF_DP<4>")
	)
	(segment
		(start 52.470558 -389.467344)
		(end 52.991258 -389.467344)
		(width 0.127)
		(layer "F.Cu")
		(net "P5E_CPU1_P0_TX_BUF_DP<4>")
	)
	(segment
		(start 60.936124 -408.250644)
		(end 60.640214 -407.954734)
		(width 0.12954)
		(layer "F.Cu")
		(net "P5E_CPU1_P0_TX_BUF_DP<4>")
	)
	(segment
		(start 60.640214 -407.954734)
		(end 60.640214 -404.73503)
		(width 0.12954)
		(layer "F.Cu")
		(net "P5E_CPU1_P0_TX_BUF_DP<4>")
	)
	(segment
		(start 54.93639 -398.495012)
		(end 55.130446 -398.495012)
		(width 0.14224)
		(layer "In6.Cu")
		(net "P5E_CPU1_P0_TX_BUF_DP<4>")
	)
	(segment
		(start 53.01869 -390.77392)
		(end 53.353716 -391.879836)
		(width 0.14224)
		(layer "In6.Cu")
		(net "P5E_CPU1_P0_TX_BUF_DP<4>")
	)
	(segment
		(start 52.991258 -389.467344)
		(end 52.87645 -389.352536)
		(width 0.14224)
		(layer "In6.Cu")
		(net "P5E_CPU1_P0_TX_BUF_DP<4>")
	)
	(segment
		(start 54.663594 -398.02816)
		(end 54.663594 -398.222216)
		(width 0.14224)
		(layer "In6.Cu")
		(net "P5E_CPU1_P0_TX_BUF_DP<4>")
	)
	(segment
		(start 53.714142 -397.272764)
		(end 54.196234 -397.754856)
		(width 0.14224)
		(layer "In6.Cu")
		(net "P5E_CPU1_P0_TX_BUF_DP<4>")
	)
	(segment
		(start 53.490876 -395.103858)
		(end 53.353716 -395.241018)
		(width 0.14224)
		(layer "In6.Cu")
		(net "P5E_CPU1_P0_TX_BUF_DP<4>")
	)
	(segment
		(start 54.196234 -397.754856)
		(end 54.39029 -397.754856)
		(width 0.14224)
		(layer "In6.Cu")
		(net "P5E_CPU1_P0_TX_BUF_DP<4>")
	)
	(segment
		(start 52.87645 -389.352536)
		(end 52.696364 -389.352536)
		(width 0.14224)
		(layer "In6.Cu")
		(net "P5E_CPU1_P0_TX_BUF_DP<4>")
	)
	(segment
		(start 52.606956 -389.441944)
		(end 52.606956 -389.44677)
		(width 0.14224)
		(layer "In6.Cu")
		(net "P5E_CPU1_P0_TX_BUF_DP<4>")
	)
	(segment
		(start 55.40375 -398.768316)
		(end 55.40375 -398.962372)
		(width 0.14224)
		(layer "In6.Cu")
		(net "P5E_CPU1_P0_TX_BUF_DP<4>")
	)
	(segment
		(start 59.78398 -402.920962)
		(end 59.838336 -402.920962)
		(width 0.14224)
		(layer "In6.Cu")
		(net "P5E_CPU1_P0_TX_BUF_DP<4>")
	)
	(segment
		(start 54.39029 -397.754856)
		(end 54.663594 -398.02816)
		(width 0.14224)
		(layer "In6.Cu")
		(net "P5E_CPU1_P0_TX_BUF_DP<4>")
	)
	(segment
		(start 53.353716 -395.241018)
		(end 53.353716 -396.40256)
		(width 0.14224)
		(layer "In6.Cu")
		(net "P5E_CPU1_P0_TX_BUF_DP<4>")
	)
	(segment
		(start 53.353716 -391.879836)
		(end 53.353716 -394.539978)
		(width 0.14224)
		(layer "In6.Cu")
		(net "P5E_CPU1_P0_TX_BUF_DP<4>")
	)
	(segment
		(start 55.130446 -398.495012)
		(end 55.40375 -398.768316)
		(width 0.14224)
		(layer "In6.Cu")
		(net "P5E_CPU1_P0_TX_BUF_DP<4>")
	)
	(segment
		(start 60.619894 -404.17369)
		(end 60.910724 -404.46452)
		(width 0.14224)
		(layer "In6.Cu")
		(net "P5E_CPU1_P0_TX_BUF_DP<4>")
	)
	(segment
		(start 52.747926 -389.78713)
		(end 52.848002 -389.887206)
		(width 0.14224)
		(layer "In6.Cu")
		(net "P5E_CPU1_P0_TX_BUF_DP<4>")
	)
	(segment
		(start 52.96789 -390.176512)
		(end 52.96789 -390.430004)
		(width 0.14224)
		(layer "In6.Cu")
		(net "P5E_CPU1_P0_TX_BUF_DP<4>")
	)
	(segment
		(start 54.663594 -398.222216)
		(end 54.93639 -398.495012)
		(width 0.14224)
		(layer "In6.Cu")
		(net "P5E_CPU1_P0_TX_BUF_DP<4>")
	)
	(segment
		(start 53.490876 -394.677138)
		(end 53.490876 -395.103858)
		(width 0.14224)
		(layer "In6.Cu")
		(net "P5E_CPU1_P0_TX_BUF_DP<4>")
	)
	(segment
		(start 60.619894 -403.711664)
		(end 60.619894 -404.17369)
		(width 0.14224)
		(layer "In6.Cu")
		(net "P5E_CPU1_P0_TX_BUF_DP<4>")
	)
	(segment
		(start 53.353716 -394.539978)
		(end 53.490876 -394.677138)
		(width 0.14224)
		(layer "In6.Cu")
		(net "P5E_CPU1_P0_TX_BUF_DP<4>")
	)
	(segment
		(start 55.40375 -398.962372)
		(end 59.064144 -402.622766)
		(width 0.14224)
		(layer "In6.Cu")
		(net "P5E_CPU1_P0_TX_BUF_DP<4>")
	)
	(segment
		(start 52.696364 -389.352536)
		(end 52.606956 -389.441944)
		(width 0.14224)
		(layer "In6.Cu")
		(net "P5E_CPU1_P0_TX_BUF_DP<4>")
	)
	(arc
		(start 60.592716 -403.559264)
		(mid 60.613037 -403.634266)
		(end 60.619894 -403.711664)
		(width 0.14224)
		(layer "In6.Cu")
		(net "P5E_CPU1_P0_TX_BUF_DP<4>")
	)
	(arc
		(start 60.309252 -403.116034)
		(mid 60.475091 -403.322232)
		(end 60.592716 -403.559264)
		(width 0.14224)
		(layer "In6.Cu")
		(net "P5E_CPU1_P0_TX_BUF_DP<4>")
	)
	(arc
		(start 52.848002 -389.887206)
		(mid 52.936746 -390.019926)
		(end 52.96789 -390.176512)
		(width 0.14224)
		(layer "In6.Cu")
		(net "P5E_CPU1_P0_TX_BUF_DP<4>")
	)
	(arc
		(start 52.606956 -389.44677)
		(mid 52.643595 -389.630967)
		(end 52.747926 -389.78713)
		(width 0.14224)
		(layer "In6.Cu")
		(net "P5E_CPU1_P0_TX_BUF_DP<4>")
	)
	(arc
		(start 52.96789 -390.430004)
		(mid 52.980611 -390.603834)
		(end 53.01869 -390.77392)
		(width 0.14224)
		(layer "In6.Cu")
		(net "P5E_CPU1_P0_TX_BUF_DP<4>")
	)
	(arc
		(start 59.838336 -402.920962)
		(mid 60.093199 -402.971657)
		(end 60.309252 -403.116034)
		(width 0.14224)
		(layer "In6.Cu")
		(net "P5E_CPU1_P0_TX_BUF_DP<4>")
	)
	(arc
		(start 53.353716 -396.40256)
		(mid 53.447392 -396.873502)
		(end 53.714142 -397.272764)
		(width 0.14224)
		(layer "In6.Cu")
		(net "P5E_CPU1_P0_TX_BUF_DP<4>")
	)
	(arc
		(start 59.064144 -402.622766)
		(mid 59.394408 -402.843441)
		(end 59.78398 -402.920962)
		(width 0.14224)
		(layer "In6.Cu")
		(net "P5E_CPU1_P0_TX_BUF_DP<4>")
	)
	(segment
		(start 57.576974 -404.73503)
		(end 57.847484 -404.46452)
		(width 0.12954)
		(layer "F.Cu")
		(net "P5E_CPU1_P0_TX_BUF_DP<3>")
	)
	(segment
		(start 57.872884 -408.250644)
		(end 57.576974 -407.954734)
		(width 0.12954)
		(layer "F.Cu")
		(net "P5E_CPU1_P0_TX_BUF_DP<3>")
	)
	(segment
		(start 57.576974 -407.954734)
		(end 57.576974 -404.73503)
		(width 0.12954)
		(layer "F.Cu")
		(net "P5E_CPU1_P0_TX_BUF_DP<3>")
	)
	(segment
		(start 51.270662 -389.467344)
		(end 51.791362 -389.467344)
		(width 0.127)
		(layer "F.Cu")
		(net "P5E_CPU1_P0_TX_BUF_DP<3>")
	)
	(segment
		(start 52.15382 -395.002512)
		(end 52.15382 -395.429232)
		(width 0.14224)
		(layer "In6.Cu")
		(net "P5E_CPU1_P0_TX_BUF_DP<3>")
	)
	(segment
		(start 52.29098 -394.865352)
		(end 52.15382 -395.002512)
		(width 0.14224)
		(layer "In6.Cu")
		(net "P5E_CPU1_P0_TX_BUF_DP<3>")
	)
	(segment
		(start 51.496468 -389.352536)
		(end 51.40706 -389.441944)
		(width 0.14224)
		(layer "In6.Cu")
		(net "P5E_CPU1_P0_TX_BUF_DP<3>")
	)
	(segment
		(start 51.773328 -390.462008)
		(end 52.12334 -391.616692)
		(width 0.14224)
		(layer "In6.Cu")
		(net "P5E_CPU1_P0_TX_BUF_DP<3>")
	)
	(segment
		(start 57.693814 -402.997416)
		(end 57.693814 -403.383496)
		(width 0.14224)
		(layer "In6.Cu")
		(net "P5E_CPU1_P0_TX_BUF_DP<3>")
	)
	(segment
		(start 57.693814 -403.383496)
		(end 57.556654 -403.520656)
		(width 0.14224)
		(layer "In6.Cu")
		(net "P5E_CPU1_P0_TX_BUF_DP<3>")
	)
	(segment
		(start 52.401216 -397.281146)
		(end 57.42686 -402.30679)
		(width 0.14224)
		(layer "In6.Cu")
		(net "P5E_CPU1_P0_TX_BUF_DP<3>")
	)
	(segment
		(start 52.15382 -395.429232)
		(end 52.29098 -395.566392)
		(width 0.14224)
		(layer "In6.Cu")
		(net "P5E_CPU1_P0_TX_BUF_DP<3>")
	)
	(segment
		(start 52.29098 -394.438632)
		(end 52.29098 -394.865352)
		(width 0.14224)
		(layer "In6.Cu")
		(net "P5E_CPU1_P0_TX_BUF_DP<3>")
	)
	(segment
		(start 51.676554 -389.352536)
		(end 51.496468 -389.352536)
		(width 0.14224)
		(layer "In6.Cu")
		(net "P5E_CPU1_P0_TX_BUF_DP<3>")
	)
	(segment
		(start 51.40706 -389.441944)
		(end 51.40706 -389.46455)
		(width 0.14224)
		(layer "In6.Cu")
		(net "P5E_CPU1_P0_TX_BUF_DP<3>")
	)
	(segment
		(start 52.15382 -391.821924)
		(end 52.15382 -394.301472)
		(width 0.14224)
		(layer "In6.Cu")
		(net "P5E_CPU1_P0_TX_BUF_DP<3>")
	)
	(segment
		(start 57.556654 -404.17369)
		(end 57.847484 -404.46452)
		(width 0.14224)
		(layer "In6.Cu")
		(net "P5E_CPU1_P0_TX_BUF_DP<3>")
	)
	(segment
		(start 51.76774 -390.176512)
		(end 51.76774 -390.424924)
		(width 0.14224)
		(layer "In6.Cu")
		(net "P5E_CPU1_P0_TX_BUF_DP<3>")
	)
	(segment
		(start 57.556654 -403.520656)
		(end 57.556654 -404.17369)
		(width 0.14224)
		(layer "In6.Cu")
		(net "P5E_CPU1_P0_TX_BUF_DP<3>")
	)
	(segment
		(start 52.29098 -395.993112)
		(end 52.15382 -396.130272)
		(width 0.14224)
		(layer "In6.Cu")
		(net "P5E_CPU1_P0_TX_BUF_DP<3>")
	)
	(segment
		(start 52.15382 -396.130272)
		(end 52.15382 -396.683992)
		(width 0.14224)
		(layer "In6.Cu")
		(net "P5E_CPU1_P0_TX_BUF_DP<3>")
	)
	(segment
		(start 51.535584 -389.774684)
		(end 51.647852 -389.886952)
		(width 0.14224)
		(layer "In6.Cu")
		(net "P5E_CPU1_P0_TX_BUF_DP<3>")
	)
	(segment
		(start 51.791362 -389.467344)
		(end 51.676554 -389.352536)
		(width 0.14224)
		(layer "In6.Cu")
		(net "P5E_CPU1_P0_TX_BUF_DP<3>")
	)
	(segment
		(start 52.29098 -395.566392)
		(end 52.29098 -395.993112)
		(width 0.14224)
		(layer "In6.Cu")
		(net "P5E_CPU1_P0_TX_BUF_DP<3>")
	)
	(segment
		(start 57.556654 -402.860256)
		(end 57.693814 -402.997416)
		(width 0.14224)
		(layer "In6.Cu")
		(net "P5E_CPU1_P0_TX_BUF_DP<3>")
	)
	(segment
		(start 52.15382 -394.301472)
		(end 52.29098 -394.438632)
		(width 0.14224)
		(layer "In6.Cu")
		(net "P5E_CPU1_P0_TX_BUF_DP<3>")
	)
	(segment
		(start 57.556654 -402.62048)
		(end 57.556654 -402.860256)
		(width 0.14224)
		(layer "In6.Cu")
		(net "P5E_CPU1_P0_TX_BUF_DP<3>")
	)
	(arc
		(start 51.40706 -389.46455)
		(mid 51.440466 -389.632403)
		(end 51.535584 -389.774684)
		(width 0.14224)
		(layer "In6.Cu")
		(net "P5E_CPU1_P0_TX_BUF_DP<3>")
	)
	(arc
		(start 52.15382 -396.683992)
		(mid 52.218123 -397.007173)
		(end 52.401216 -397.281146)
		(width 0.14224)
		(layer "In6.Cu")
		(net "P5E_CPU1_P0_TX_BUF_DP<3>")
	)
	(arc
		(start 57.42686 -402.30679)
		(mid 57.522996 -402.450713)
		(end 57.556654 -402.62048)
		(width 0.14224)
		(layer "In6.Cu")
		(net "P5E_CPU1_P0_TX_BUF_DP<3>")
	)
	(arc
		(start 51.647852 -389.886952)
		(mid 51.736567 -390.019817)
		(end 51.76774 -390.176512)
		(width 0.14224)
		(layer "In6.Cu")
		(net "P5E_CPU1_P0_TX_BUF_DP<3>")
	)
	(arc
		(start 51.76774 -390.424924)
		(mid 51.769161 -390.443673)
		(end 51.773328 -390.462008)
		(width 0.14224)
		(layer "In6.Cu")
		(net "P5E_CPU1_P0_TX_BUF_DP<3>")
	)
	(arc
		(start 52.12334 -391.616692)
		(mid 52.146161 -391.718182)
		(end 52.15382 -391.821924)
		(width 0.14224)
		(layer "In6.Cu")
		(net "P5E_CPU1_P0_TX_BUF_DP<3>")
	)
	(segment
		(start 54.513734 -404.73503)
		(end 54.784244 -404.46452)
		(width 0.12954)
		(layer "F.Cu")
		(net "P5E_CPU1_P0_TX_BUF_DP<2>")
	)
	(segment
		(start 54.809644 -408.250644)
		(end 54.513734 -407.954734)
		(width 0.12954)
		(layer "F.Cu")
		(net "P5E_CPU1_P0_TX_BUF_DP<2>")
	)
	(segment
		(start 50.070512 -389.467344)
		(end 50.591212 -389.467344)
		(width 0.127)
		(layer "F.Cu")
		(net "P5E_CPU1_P0_TX_BUF_DP<2>")
	)
	(segment
		(start 54.513734 -407.954734)
		(end 54.513734 -404.73503)
		(width 0.12954)
		(layer "F.Cu")
		(net "P5E_CPU1_P0_TX_BUF_DP<2>")
	)
	(segment
		(start 50.953924 -395.028928)
		(end 50.953924 -395.455648)
		(width 0.14224)
		(layer "In6.Cu")
		(net "P5E_CPU1_P0_TX_BUF_DP<2>")
	)
	(segment
		(start 50.586132 -390.55802)
		(end 50.882042 -391.53465)
		(width 0.14224)
		(layer "In6.Cu")
		(net "P5E_CPU1_P0_TX_BUF_DP<2>")
	)
	(segment
		(start 50.292508 -389.732012)
		(end 50.437796 -389.8773)
		(width 0.14224)
		(layer "In6.Cu")
		(net "P5E_CPU1_P0_TX_BUF_DP<2>")
	)
	(segment
		(start 54.493414 -404.17369)
		(end 54.784244 -404.46452)
		(width 0.14224)
		(layer "In6.Cu")
		(net "P5E_CPU1_P0_TX_BUF_DP<2>")
	)
	(segment
		(start 50.320956 -389.352536)
		(end 50.20691 -389.466582)
		(width 0.14224)
		(layer "In6.Cu")
		(net "P5E_CPU1_P0_TX_BUF_DP<2>")
	)
	(segment
		(start 50.953924 -392.018774)
		(end 50.953924 -394.327888)
		(width 0.14224)
		(layer "In6.Cu")
		(net "P5E_CPU1_P0_TX_BUF_DP<2>")
	)
	(segment
		(start 54.493414 -402.749258)
		(end 54.630574 -402.886418)
		(width 0.14224)
		(layer "In6.Cu")
		(net "P5E_CPU1_P0_TX_BUF_DP<2>")
	)
	(segment
		(start 51.091084 -396.019528)
		(end 50.953924 -396.156688)
		(width 0.14224)
		(layer "In6.Cu")
		(net "P5E_CPU1_P0_TX_BUF_DP<2>")
	)
	(segment
		(start 51.153822 -397.255238)
		(end 54.16042 -400.918934)
		(width 0.14224)
		(layer "In6.Cu")
		(net "P5E_CPU1_P0_TX_BUF_DP<2>")
	)
	(segment
		(start 54.493414 -401.849844)
		(end 54.493414 -402.749258)
		(width 0.14224)
		(layer "In6.Cu")
		(net "P5E_CPU1_P0_TX_BUF_DP<2>")
	)
	(segment
		(start 54.630574 -403.272498)
		(end 54.493414 -403.409658)
		(width 0.14224)
		(layer "In6.Cu")
		(net "P5E_CPU1_P0_TX_BUF_DP<2>")
	)
	(segment
		(start 54.493414 -403.409658)
		(end 54.493414 -404.17369)
		(width 0.14224)
		(layer "In6.Cu")
		(net "P5E_CPU1_P0_TX_BUF_DP<2>")
	)
	(segment
		(start 51.091084 -394.465048)
		(end 51.091084 -394.891768)
		(width 0.14224)
		(layer "In6.Cu")
		(net "P5E_CPU1_P0_TX_BUF_DP<2>")
	)
	(segment
		(start 50.591212 -389.467344)
		(end 50.476404 -389.352536)
		(width 0.14224)
		(layer "In6.Cu")
		(net "P5E_CPU1_P0_TX_BUF_DP<2>")
	)
	(segment
		(start 50.953924 -396.156688)
		(end 50.953924 -396.697454)
		(width 0.14224)
		(layer "In6.Cu")
		(net "P5E_CPU1_P0_TX_BUF_DP<2>")
	)
	(segment
		(start 51.091084 -394.891768)
		(end 50.953924 -395.028928)
		(width 0.14224)
		(layer "In6.Cu")
		(net "P5E_CPU1_P0_TX_BUF_DP<2>")
	)
	(segment
		(start 50.20691 -389.466582)
		(end 50.20691 -389.52551)
		(width 0.14224)
		(layer "In6.Cu")
		(net "P5E_CPU1_P0_TX_BUF_DP<2>")
	)
	(segment
		(start 50.476404 -389.352536)
		(end 50.320956 -389.352536)
		(width 0.14224)
		(layer "In6.Cu")
		(net "P5E_CPU1_P0_TX_BUF_DP<2>")
	)
	(segment
		(start 50.953924 -395.455648)
		(end 51.091084 -395.592808)
		(width 0.14224)
		(layer "In6.Cu")
		(net "P5E_CPU1_P0_TX_BUF_DP<2>")
	)
	(segment
		(start 54.630574 -402.886418)
		(end 54.630574 -403.272498)
		(width 0.14224)
		(layer "In6.Cu")
		(net "P5E_CPU1_P0_TX_BUF_DP<2>")
	)
	(segment
		(start 51.091084 -395.592808)
		(end 51.091084 -396.019528)
		(width 0.14224)
		(layer "In6.Cu")
		(net "P5E_CPU1_P0_TX_BUF_DP<2>")
	)
	(segment
		(start 50.953924 -394.327888)
		(end 51.091084 -394.465048)
		(width 0.14224)
		(layer "In6.Cu")
		(net "P5E_CPU1_P0_TX_BUF_DP<2>")
	)
	(segment
		(start 50.56759 -390.19099)
		(end 50.56759 -390.43356)
		(width 0.14224)
		(layer "In6.Cu")
		(net "P5E_CPU1_P0_TX_BUF_DP<2>")
	)
	(arc
		(start 50.20691 -389.52551)
		(mid 50.22916 -389.637278)
		(end 50.292508 -389.732012)
		(width 0.14224)
		(layer "In6.Cu")
		(net "P5E_CPU1_P0_TX_BUF_DP<2>")
	)
	(arc
		(start 54.16042 -400.918934)
		(mid 54.407677 -401.355503)
		(end 54.493414 -401.849844)
		(width 0.14224)
		(layer "In6.Cu")
		(net "P5E_CPU1_P0_TX_BUF_DP<2>")
	)
	(arc
		(start 50.882042 -391.53465)
		(mid 50.935805 -391.774067)
		(end 50.953924 -392.018774)
		(width 0.14224)
		(layer "In6.Cu")
		(net "P5E_CPU1_P0_TX_BUF_DP<2>")
	)
	(arc
		(start 50.953924 -396.697454)
		(mid 51.005501 -396.993677)
		(end 51.153822 -397.255238)
		(width 0.14224)
		(layer "In6.Cu")
		(net "P5E_CPU1_P0_TX_BUF_DP<2>")
	)
	(arc
		(start 50.437796 -389.8773)
		(mid 50.533932 -390.021223)
		(end 50.56759 -390.19099)
		(width 0.14224)
		(layer "In6.Cu")
		(net "P5E_CPU1_P0_TX_BUF_DP<2>")
	)
	(arc
		(start 50.56759 -390.43356)
		(mid 50.572289 -390.496471)
		(end 50.586132 -390.55802)
		(width 0.14224)
		(layer "In6.Cu")
		(net "P5E_CPU1_P0_TX_BUF_DP<2>")
	)
	(segment
		(start 51.450494 -407.954734)
		(end 51.450494 -404.73503)
		(width 0.12954)
		(layer "F.Cu")
		(net "P5E_CPU1_P0_TX_BUF_DP<1>")
	)
	(segment
		(start 51.450494 -404.73503)
		(end 51.721004 -404.46452)
		(width 0.12954)
		(layer "F.Cu")
		(net "P5E_CPU1_P0_TX_BUF_DP<1>")
	)
	(segment
		(start 51.746404 -408.250644)
		(end 51.450494 -407.954734)
		(width 0.12954)
		(layer "F.Cu")
		(net "P5E_CPU1_P0_TX_BUF_DP<1>")
	)
	(segment
		(start 48.870616 -389.467344)
		(end 49.391316 -389.467344)
		(width 0.127)
		(layer "F.Cu")
		(net "P5E_CPU1_P0_TX_BUF_DP<1>")
	)
	(segment
		(start 51.318922 -399.799048)
		(end 51.253644 -399.981674)
		(width 0.14224)
		(layer "In6.Cu")
		(net "P5E_CPU1_P0_TX_BUF_DP<1>")
	)
	(segment
		(start 50.771298 -398.962118)
		(end 50.95367 -399.34769)
		(width 0.14224)
		(layer "In6.Cu")
		(net "P5E_CPU1_P0_TX_BUF_DP<1>")
	)
	(segment
		(start 49.007014 -389.441944)
		(end 49.007014 -389.514334)
		(width 0.14224)
		(layer "In6.Cu")
		(net "P5E_CPU1_P0_TX_BUF_DP<1>")
	)
	(segment
		(start 51.13655 -399.412968)
		(end 51.318922 -399.799048)
		(width 0.14224)
		(layer "In6.Cu")
		(net "P5E_CPU1_P0_TX_BUF_DP<1>")
	)
	(segment
		(start 51.567334 -402.708872)
		(end 51.430174 -402.846032)
		(width 0.14224)
		(layer "In6.Cu")
		(net "P5E_CPU1_P0_TX_BUF_DP<1>")
	)
	(segment
		(start 49.406048 -390.687052)
		(end 49.71796 -391.58799)
		(width 0.14224)
		(layer "In6.Cu")
		(net "P5E_CPU1_P0_TX_BUF_DP<1>")
	)
	(segment
		(start 50.471324 -398.328134)
		(end 50.654204 -398.393412)
		(width 0.14224)
		(layer "In6.Cu")
		(net "P5E_CPU1_P0_TX_BUF_DP<1>")
	)
	(segment
		(start 51.567334 -402.282152)
		(end 51.567334 -402.708872)
		(width 0.14224)
		(layer "In6.Cu")
		(net "P5E_CPU1_P0_TX_BUF_DP<1>")
	)
	(segment
		(start 51.430174 -402.144992)
		(end 51.567334 -402.282152)
		(width 0.14224)
		(layer "In6.Cu")
		(net "P5E_CPU1_P0_TX_BUF_DP<1>")
	)
	(segment
		(start 49.38522 -390.218168)
		(end 49.38522 -390.562846)
		(width 0.14224)
		(layer "In6.Cu")
		(net "P5E_CPU1_P0_TX_BUF_DP<1>")
	)
	(segment
		(start 51.430174 -404.17369)
		(end 51.721004 -404.46452)
		(width 0.14224)
		(layer "In6.Cu")
		(net "P5E_CPU1_P0_TX_BUF_DP<1>")
	)
	(segment
		(start 50.95367 -399.34769)
		(end 51.13655 -399.412968)
		(width 0.14224)
		(layer "In6.Cu")
		(net "P5E_CPU1_P0_TX_BUF_DP<1>")
	)
	(segment
		(start 49.754028 -391.804652)
		(end 49.754028 -396.593822)
		(width 0.14224)
		(layer "In6.Cu")
		(net "P5E_CPU1_P0_TX_BUF_DP<1>")
	)
	(segment
		(start 51.253644 -399.981674)
		(end 51.391058 -400.27225)
		(width 0.14224)
		(layer "In6.Cu")
		(net "P5E_CPU1_P0_TX_BUF_DP<1>")
	)
	(segment
		(start 49.276508 -389.352536)
		(end 49.096422 -389.352536)
		(width 0.14224)
		(layer "In6.Cu")
		(net "P5E_CPU1_P0_TX_BUF_DP<1>")
	)
	(segment
		(start 51.430174 -402.846032)
		(end 51.430174 -404.17369)
		(width 0.14224)
		(layer "In6.Cu")
		(net "P5E_CPU1_P0_TX_BUF_DP<1>")
	)
	(segment
		(start 49.847246 -397.00835)
		(end 50.471324 -398.328134)
		(width 0.14224)
		(layer "In6.Cu")
		(net "P5E_CPU1_P0_TX_BUF_DP<1>")
	)
	(segment
		(start 51.430174 -400.447256)
		(end 51.430174 -402.144992)
		(width 0.14224)
		(layer "In6.Cu")
		(net "P5E_CPU1_P0_TX_BUF_DP<1>")
	)
	(segment
		(start 50.836576 -398.779238)
		(end 50.771298 -398.962118)
		(width 0.14224)
		(layer "In6.Cu")
		(net "P5E_CPU1_P0_TX_BUF_DP<1>")
	)
	(segment
		(start 49.100232 -389.739378)
		(end 49.247806 -389.886698)
		(width 0.14224)
		(layer "In6.Cu")
		(net "P5E_CPU1_P0_TX_BUF_DP<1>")
	)
	(segment
		(start 49.391316 -389.467344)
		(end 49.276508 -389.352536)
		(width 0.14224)
		(layer "In6.Cu")
		(net "P5E_CPU1_P0_TX_BUF_DP<1>")
	)
	(segment
		(start 49.096422 -389.352536)
		(end 49.007014 -389.441944)
		(width 0.14224)
		(layer "In6.Cu")
		(net "P5E_CPU1_P0_TX_BUF_DP<1>")
	)
	(segment
		(start 50.654204 -398.393412)
		(end 50.836576 -398.779238)
		(width 0.14224)
		(layer "In6.Cu")
		(net "P5E_CPU1_P0_TX_BUF_DP<1>")
	)
	(arc
		(start 49.754028 -396.593822)
		(mid 49.777687 -396.806244)
		(end 49.847246 -397.00835)
		(width 0.14224)
		(layer "In6.Cu")
		(net "P5E_CPU1_P0_TX_BUF_DP<1>")
	)
	(arc
		(start 49.247806 -389.886698)
		(mid 49.349422 -390.038778)
		(end 49.38522 -390.218168)
		(width 0.14224)
		(layer "In6.Cu")
		(net "P5E_CPU1_P0_TX_BUF_DP<1>")
	)
	(arc
		(start 49.007014 -389.514334)
		(mid 49.03124 -389.636128)
		(end 49.100232 -389.739378)
		(width 0.14224)
		(layer "In6.Cu")
		(net "P5E_CPU1_P0_TX_BUF_DP<1>")
	)
	(arc
		(start 51.391058 -400.27225)
		(mid 51.420301 -400.357586)
		(end 51.430174 -400.447256)
		(width 0.14224)
		(layer "In6.Cu")
		(net "P5E_CPU1_P0_TX_BUF_DP<1>")
	)
	(arc
		(start 49.38522 -390.562846)
		(mid 49.390436 -390.625822)
		(end 49.406048 -390.687052)
		(width 0.14224)
		(layer "In6.Cu")
		(net "P5E_CPU1_P0_TX_BUF_DP<1>")
	)
	(arc
		(start 49.71796 -391.58799)
		(mid 49.745053 -391.694814)
		(end 49.754028 -391.804652)
		(width 0.14224)
		(layer "In6.Cu")
		(net "P5E_CPU1_P0_TX_BUF_DP<1>")
	)
	(segment
		(start 94.631764 -408.250644)
		(end 94.335854 -407.954734)
		(width 0.12954)
		(layer "F.Cu")
		(net "P5E_CPU1_P0_TX_BUF_DP<15>")
	)
	(segment
		(start 65.670684 -389.467344)
		(end 66.191384 -389.467344)
		(width 0.127)
		(layer "F.Cu")
		(net "P5E_CPU1_P0_TX_BUF_DP<15>")
	)
	(segment
		(start 94.335854 -407.954734)
		(end 94.335854 -404.73503)
		(width 0.12954)
		(layer "F.Cu")
		(net "P5E_CPU1_P0_TX_BUF_DP<15>")
	)
	(segment
		(start 94.335854 -404.73503)
		(end 94.606364 -404.46452)
		(width 0.12954)
		(layer "F.Cu")
		(net "P5E_CPU1_P0_TX_BUF_DP<15>")
	)
	(segment
		(start 66.769488 -392.049508)
		(end 67.158362 -392.988546)
		(width 0.14224)
		(layer "In6.Cu")
		(net "P5E_CPU1_P0_TX_BUF_DP<15>")
	)
	(segment
		(start 66.191384 -389.467344)
		(end 66.076576 -389.352536)
		(width 0.14224)
		(layer "In6.Cu")
		(net "P5E_CPU1_P0_TX_BUF_DP<15>")
	)
	(segment
		(start 78.983078 -396.776194)
		(end 79.151734 -396.680436)
		(width 0.14224)
		(layer "In6.Cu")
		(net "P5E_CPU1_P0_TX_BUF_DP<15>")
	)
	(segment
		(start 73.226676 -395.040612)
		(end 73.32218 -395.209522)
		(width 0.14224)
		(layer "In6.Cu")
		(net "P5E_CPU1_P0_TX_BUF_DP<15>")
	)
	(segment
		(start 66.076576 -389.352536)
		(end 65.89649 -389.352536)
		(width 0.14224)
		(layer "In6.Cu")
		(net "P5E_CPU1_P0_TX_BUF_DP<15>")
	)
	(segment
		(start 66.212212 -390.170162)
		(end 66.212212 -390.380728)
		(width 0.14224)
		(layer "In6.Cu")
		(net "P5E_CPU1_P0_TX_BUF_DP<15>")
	)
	(segment
		(start 81.718658 -397.533368)
		(end 81.887314 -397.43761)
		(width 0.14224)
		(layer "In6.Cu")
		(net "P5E_CPU1_P0_TX_BUF_DP<15>")
	)
	(segment
		(start 68.827396 -393.96543)
		(end 72.646286 -395.022324)
		(width 0.14224)
		(layer "In6.Cu")
		(net "P5E_CPU1_P0_TX_BUF_DP<15>")
	)
	(segment
		(start 65.913254 -389.752332)
		(end 66.076576 -389.9154)
		(width 0.14224)
		(layer "In6.Cu")
		(net "P5E_CPU1_P0_TX_BUF_DP<15>")
	)
	(segment
		(start 82.394552 -397.720566)
		(end 82.394552 -397.720312)
		(width 0.14224)
		(layer "In6.Cu")
		(net "P5E_CPU1_P0_TX_BUF_DP<15>")
	)
	(segment
		(start 79.563468 -396.794228)
		(end 79.658972 -396.963392)
		(width 0.14224)
		(layer "In6.Cu")
		(net "P5E_CPU1_P0_TX_BUF_DP<15>")
	)
	(segment
		(start 93.933772 -402.318982)
		(end 94.023942 -402.409152)
		(width 0.14224)
		(layer "In6.Cu")
		(net "P5E_CPU1_P0_TX_BUF_DP<15>")
	)
	(segment
		(start 83.959192 -398.153382)
		(end 93.80093 -402.230082)
		(width 0.14224)
		(layer "In6.Cu")
		(net "P5E_CPU1_P0_TX_BUF_DP<15>")
	)
	(segment
		(start 82.298794 -397.551402)
		(end 82.394552 -397.720566)
		(width 0.14224)
		(layer "In6.Cu")
		(net "P5E_CPU1_P0_TX_BUF_DP<15>")
	)
	(segment
		(start 94.315534 -403.11324)
		(end 94.315534 -404.17369)
		(width 0.14224)
		(layer "In6.Cu")
		(net "P5E_CPU1_P0_TX_BUF_DP<15>")
	)
	(segment
		(start 73.32218 -395.209522)
		(end 78.983078 -396.776194)
		(width 0.14224)
		(layer "In6.Cu")
		(net "P5E_CPU1_P0_TX_BUF_DP<15>")
	)
	(segment
		(start 79.658972 -396.963392)
		(end 79.659226 -396.963392)
		(width 0.14224)
		(layer "In6.Cu")
		(net "P5E_CPU1_P0_TX_BUF_DP<15>")
	)
	(segment
		(start 81.887314 -397.43761)
		(end 82.298794 -397.551402)
		(width 0.14224)
		(layer "In6.Cu")
		(net "P5E_CPU1_P0_TX_BUF_DP<15>")
	)
	(segment
		(start 79.659226 -396.963392)
		(end 81.718658 -397.533368)
		(width 0.14224)
		(layer "In6.Cu")
		(net "P5E_CPU1_P0_TX_BUF_DP<15>")
	)
	(segment
		(start 82.394552 -397.720312)
		(end 83.959192 -398.153382)
		(width 0.14224)
		(layer "In6.Cu")
		(net "P5E_CPU1_P0_TX_BUF_DP<15>")
	)
	(segment
		(start 72.815196 -394.92682)
		(end 73.226676 -395.040612)
		(width 0.14224)
		(layer "In6.Cu")
		(net "P5E_CPU1_P0_TX_BUF_DP<15>")
	)
	(segment
		(start 65.807082 -389.441944)
		(end 65.807082 -389.496046)
		(width 0.14224)
		(layer "In6.Cu")
		(net "P5E_CPU1_P0_TX_BUF_DP<15>")
	)
	(segment
		(start 94.315534 -404.17369)
		(end 94.606364 -404.46452)
		(width 0.14224)
		(layer "In6.Cu")
		(net "P5E_CPU1_P0_TX_BUF_DP<15>")
	)
	(segment
		(start 65.89649 -389.352536)
		(end 65.807082 -389.441944)
		(width 0.14224)
		(layer "In6.Cu")
		(net "P5E_CPU1_P0_TX_BUF_DP<15>")
	)
	(segment
		(start 66.221864 -390.429496)
		(end 66.655696 -391.477246)
		(width 0.14224)
		(layer "In6.Cu")
		(net "P5E_CPU1_P0_TX_BUF_DP<15>")
	)
	(segment
		(start 79.151734 -396.680436)
		(end 79.563468 -396.794228)
		(width 0.14224)
		(layer "In6.Cu")
		(net "P5E_CPU1_P0_TX_BUF_DP<15>")
	)
	(segment
		(start 72.646286 -395.022324)
		(end 72.815196 -394.92682)
		(width 0.14224)
		(layer "In6.Cu")
		(net "P5E_CPU1_P0_TX_BUF_DP<15>")
	)
	(arc
		(start 67.158362 -392.988546)
		(mid 67.189122 -393.044354)
		(end 67.231514 -393.091924)
		(width 0.14224)
		(layer "In6.Cu")
		(net "P5E_CPU1_P0_TX_BUF_DP<15>")
	)
	(arc
		(start 93.80093 -402.230082)
		(mid 93.871742 -402.267974)
		(end 93.933772 -402.318982)
		(width 0.14224)
		(layer "In6.Cu")
		(net "P5E_CPU1_P0_TX_BUF_DP<15>")
	)
	(arc
		(start 94.023942 -402.409152)
		(mid 94.239736 -402.732205)
		(end 94.315534 -403.11324)
		(width 0.14224)
		(layer "In6.Cu")
		(net "P5E_CPU1_P0_TX_BUF_DP<15>")
	)
	(arc
		(start 66.72834 -391.842752)
		(mid 66.738718 -391.948161)
		(end 66.769488 -392.049508)
		(width 0.14224)
		(layer "In6.Cu")
		(net "P5E_CPU1_P0_TX_BUF_DP<15>")
	)
	(arc
		(start 66.655696 -391.477246)
		(mid 66.709976 -391.656428)
		(end 66.72834 -391.842752)
		(width 0.14224)
		(layer "In6.Cu")
		(net "P5E_CPU1_P0_TX_BUF_DP<15>")
	)
	(arc
		(start 66.212212 -390.380728)
		(mid 66.214658 -390.405581)
		(end 66.221864 -390.429496)
		(width 0.14224)
		(layer "In6.Cu")
		(net "P5E_CPU1_P0_TX_BUF_DP<15>")
	)
	(arc
		(start 65.807082 -389.496046)
		(mid 65.834672 -389.634753)
		(end 65.913254 -389.752332)
		(width 0.14224)
		(layer "In6.Cu")
		(net "P5E_CPU1_P0_TX_BUF_DP<15>")
	)
	(arc
		(start 67.231514 -393.091924)
		(mid 67.978828 -393.62117)
		(end 68.827396 -393.96543)
		(width 0.14224)
		(layer "In6.Cu")
		(net "P5E_CPU1_P0_TX_BUF_DP<15>")
	)
	(arc
		(start 66.076576 -389.9154)
		(mid 66.163414 -390.032653)
		(end 66.212212 -390.170162)
		(width 0.14224)
		(layer "In6.Cu")
		(net "P5E_CPU1_P0_TX_BUF_DP<15>")
	)
	(segment
		(start 64.470534 -389.467344)
		(end 64.991234 -389.467344)
		(width 0.127)
		(layer "F.Cu")
		(net "P5E_CPU1_P0_TX_BUF_DP<14>")
	)
	(segment
		(start 91.272614 -404.73503)
		(end 91.543124 -404.46452)
		(width 0.12954)
		(layer "F.Cu")
		(net "P5E_CPU1_P0_TX_BUF_DP<14>")
	)
	(segment
		(start 91.568524 -408.250644)
		(end 91.272614 -407.954734)
		(width 0.12954)
		(layer "F.Cu")
		(net "P5E_CPU1_P0_TX_BUF_DP<14>")
	)
	(segment
		(start 91.272614 -407.954734)
		(end 91.272614 -404.73503)
		(width 0.12954)
		(layer "F.Cu")
		(net "P5E_CPU1_P0_TX_BUF_DP<14>")
	)
	(segment
		(start 65.353946 -391.719562)
		(end 65.353946 -394.080238)
		(width 0.14224)
		(layer "In6.Cu")
		(net "P5E_CPU1_P0_TX_BUF_DP<14>")
	)
	(segment
		(start 74.235818 -396.566898)
		(end 81.792064 -398.858486)
		(width 0.14224)
		(layer "In6.Cu")
		(net "P5E_CPU1_P0_TX_BUF_DP<14>")
	)
	(segment
		(start 82.357214 -398.92478)
		(end 82.42427 -399.050256)
		(width 0.14224)
		(layer "In6.Cu")
		(net "P5E_CPU1_P0_TX_BUF_DP<14>")
	)
	(segment
		(start 91.252294 -403.641306)
		(end 91.252294 -404.17369)
		(width 0.14224)
		(layer "In6.Cu")
		(net "P5E_CPU1_P0_TX_BUF_DP<14>")
	)
	(segment
		(start 70.081394 -395.52626)
		(end 74.235818 -396.566898)
		(width 0.14224)
		(layer "In6.Cu")
		(net "P5E_CPU1_P0_TX_BUF_DP<14>")
	)
	(segment
		(start 91.068144 -403.24278)
		(end 91.100656 -403.275292)
		(width 0.14224)
		(layer "In6.Cu")
		(net "P5E_CPU1_P0_TX_BUF_DP<14>")
	)
	(segment
		(start 83.029806 -399.233898)
		(end 86.892892 -400.83359)
		(width 0.14224)
		(layer "In6.Cu")
		(net "P5E_CPU1_P0_TX_BUF_DP<14>")
	)
	(segment
		(start 65.667128 -394.420344)
		(end 66.806572 -394.705586)
		(width 0.14224)
		(layer "In6.Cu")
		(net "P5E_CPU1_P0_TX_BUF_DP<14>")
	)
	(segment
		(start 87.503254 -401.086574)
		(end 88.392 -401.45462)
		(width 0.14224)
		(layer "In6.Cu")
		(net "P5E_CPU1_P0_TX_BUF_DP<14>")
	)
	(segment
		(start 64.599058 -389.435848)
		(end 64.599058 -389.47725)
		(width 0.14224)
		(layer "In6.Cu")
		(net "P5E_CPU1_P0_TX_BUF_DP<14>")
	)
	(segment
		(start 66.806572 -394.705586)
		(end 66.972942 -394.606018)
		(width 0.14224)
		(layer "In6.Cu")
		(net "P5E_CPU1_P0_TX_BUF_DP<14>")
	)
	(segment
		(start 86.892892 -400.83359)
		(end 87.034116 -400.77517)
		(width 0.14224)
		(layer "In6.Cu")
		(net "P5E_CPU1_P0_TX_BUF_DP<14>")
	)
	(segment
		(start 82.42427 -399.050256)
		(end 83.029806 -399.233898)
		(width 0.14224)
		(layer "In6.Cu")
		(net "P5E_CPU1_P0_TX_BUF_DP<14>")
	)
	(segment
		(start 87.44458 -400.945096)
		(end 87.503254 -401.086574)
		(width 0.14224)
		(layer "In6.Cu")
		(net "P5E_CPU1_P0_TX_BUF_DP<14>")
	)
	(segment
		(start 67.447414 -394.866368)
		(end 69.440298 -395.365478)
		(width 0.14224)
		(layer "In6.Cu")
		(net "P5E_CPU1_P0_TX_BUF_DP<14>")
	)
	(segment
		(start 91.252294 -404.17369)
		(end 91.543124 -404.46452)
		(width 0.14224)
		(layer "In6.Cu")
		(net "P5E_CPU1_P0_TX_BUF_DP<14>")
	)
	(segment
		(start 65.391284 -394.170154)
		(end 65.607946 -394.386816)
		(width 0.14224)
		(layer "In6.Cu")
		(net "P5E_CPU1_P0_TX_BUF_DP<14>")
	)
	(segment
		(start 81.792064 -398.858486)
		(end 81.91754 -398.79143)
		(width 0.14224)
		(layer "In6.Cu")
		(net "P5E_CPU1_P0_TX_BUF_DP<14>")
	)
	(segment
		(start 65.002918 -390.457944)
		(end 65.323466 -391.51306)
		(width 0.14224)
		(layer "In6.Cu")
		(net "P5E_CPU1_P0_TX_BUF_DP<14>")
	)
	(segment
		(start 69.981572 -395.359636)
		(end 70.081394 -395.52626)
		(width 0.14224)
		(layer "In6.Cu")
		(net "P5E_CPU1_P0_TX_BUF_DP<14>")
	)
	(segment
		(start 66.972942 -394.606018)
		(end 67.347592 -394.699744)
		(width 0.14224)
		(layer "In6.Cu")
		(net "P5E_CPU1_P0_TX_BUF_DP<14>")
	)
	(segment
		(start 87.034116 -400.77517)
		(end 87.44458 -400.945096)
		(width 0.14224)
		(layer "In6.Cu")
		(net "P5E_CPU1_P0_TX_BUF_DP<14>")
	)
	(segment
		(start 64.876426 -389.352536)
		(end 64.68237 -389.352536)
		(width 0.14224)
		(layer "In6.Cu")
		(net "P5E_CPU1_P0_TX_BUF_DP<14>")
	)
	(segment
		(start 64.68237 -389.352536)
		(end 64.599058 -389.435848)
		(width 0.14224)
		(layer "In6.Cu")
		(net "P5E_CPU1_P0_TX_BUF_DP<14>")
	)
	(segment
		(start 81.91754 -398.79143)
		(end 82.357214 -398.92478)
		(width 0.14224)
		(layer "In6.Cu")
		(net "P5E_CPU1_P0_TX_BUF_DP<14>")
	)
	(segment
		(start 69.440298 -395.365478)
		(end 69.606668 -395.26591)
		(width 0.14224)
		(layer "In6.Cu")
		(net "P5E_CPU1_P0_TX_BUF_DP<14>")
	)
	(segment
		(start 69.606668 -395.26591)
		(end 69.981572 -395.359636)
		(width 0.14224)
		(layer "In6.Cu")
		(net "P5E_CPU1_P0_TX_BUF_DP<14>")
	)
	(segment
		(start 64.713104 -389.752332)
		(end 64.830198 -389.869426)
		(width 0.14224)
		(layer "In6.Cu")
		(net "P5E_CPU1_P0_TX_BUF_DP<14>")
	)
	(segment
		(start 67.347592 -394.699744)
		(end 67.447414 -394.866368)
		(width 0.14224)
		(layer "In6.Cu")
		(net "P5E_CPU1_P0_TX_BUF_DP<14>")
	)
	(segment
		(start 64.991234 -389.467344)
		(end 64.876426 -389.352536)
		(width 0.14224)
		(layer "In6.Cu")
		(net "P5E_CPU1_P0_TX_BUF_DP<14>")
	)
	(arc
		(start 64.962024 -390.185402)
		(mid 64.97255 -390.323161)
		(end 65.002918 -390.457944)
		(width 0.14224)
		(layer "In6.Cu")
		(net "P5E_CPU1_P0_TX_BUF_DP<14>")
	)
	(arc
		(start 64.830198 -389.869426)
		(mid 64.927479 -390.014322)
		(end 64.962024 -390.185402)
		(width 0.14224)
		(layer "In6.Cu")
		(net "P5E_CPU1_P0_TX_BUF_DP<14>")
	)
	(arc
		(start 88.392 -401.45462)
		(mid 89.818144 -402.216891)
		(end 91.068144 -403.24278)
		(width 0.14224)
		(layer "In6.Cu")
		(net "P5E_CPU1_P0_TX_BUF_DP<14>")
	)
	(arc
		(start 91.100656 -403.275292)
		(mid 91.212862 -403.443221)
		(end 91.252294 -403.641306)
		(width 0.14224)
		(layer "In6.Cu")
		(net "P5E_CPU1_P0_TX_BUF_DP<14>")
	)
	(arc
		(start 64.599058 -389.47725)
		(mid 64.628694 -389.626149)
		(end 64.713104 -389.752332)
		(width 0.14224)
		(layer "In6.Cu")
		(net "P5E_CPU1_P0_TX_BUF_DP<14>")
	)
	(arc
		(start 65.607946 -394.386816)
		(mid 65.63526 -394.407598)
		(end 65.667128 -394.420344)
		(width 0.14224)
		(layer "In6.Cu")
		(net "P5E_CPU1_P0_TX_BUF_DP<14>")
	)
	(arc
		(start 65.323466 -391.51306)
		(mid 65.346326 -391.615186)
		(end 65.353946 -391.719562)
		(width 0.14224)
		(layer "In6.Cu")
		(net "P5E_CPU1_P0_TX_BUF_DP<14>")
	)
	(arc
		(start 65.353946 -394.080238)
		(mid 65.363648 -394.128922)
		(end 65.391284 -394.170154)
		(width 0.14224)
		(layer "In6.Cu")
		(net "P5E_CPU1_P0_TX_BUF_DP<14>")
	)
	(segment
		(start 63.270638 -389.467344)
		(end 63.791338 -389.467344)
		(width 0.127)
		(layer "F.Cu")
		(net "P5E_CPU1_P0_TX_BUF_DP<13>")
	)
	(segment
		(start 88.209374 -404.73503)
		(end 88.479884 -404.46452)
		(width 0.12954)
		(layer "F.Cu")
		(net "P5E_CPU1_P0_TX_BUF_DP<13>")
	)
	(segment
		(start 88.505284 -408.250644)
		(end 88.209374 -407.954734)
		(width 0.12954)
		(layer "F.Cu")
		(net "P5E_CPU1_P0_TX_BUF_DP<13>")
	)
	(segment
		(start 88.209374 -407.954734)
		(end 88.209374 -404.73503)
		(width 0.12954)
		(layer "F.Cu")
		(net "P5E_CPU1_P0_TX_BUF_DP<13>")
	)
	(segment
		(start 83.184746 -400.557492)
		(end 83.267804 -400.733006)
		(width 0.14224)
		(layer "In6.Cu")
		(net "P5E_CPU1_P0_TX_BUF_DP<13>")
	)
	(segment
		(start 79.10703 -399.098516)
		(end 79.190088 -399.27403)
		(width 0.14224)
		(layer "In6.Cu")
		(net "P5E_CPU1_P0_TX_BUF_DP<13>")
	)
	(segment
		(start 82.782664 -400.413728)
		(end 83.184746 -400.557492)
		(width 0.14224)
		(layer "In6.Cu")
		(net "P5E_CPU1_P0_TX_BUF_DP<13>")
	)
	(segment
		(start 85.284056 -401.454366)
		(end 87.380826 -402.322792)
		(width 0.14224)
		(layer "In6.Cu")
		(net "P5E_CPU1_P0_TX_BUF_DP<13>")
	)
	(segment
		(start 78.705202 -398.954752)
		(end 79.10703 -399.098516)
		(width 0.14224)
		(layer "In6.Cu")
		(net "P5E_CPU1_P0_TX_BUF_DP<13>")
	)
	(segment
		(start 63.67653 -389.352536)
		(end 63.496444 -389.352536)
		(width 0.14224)
		(layer "In6.Cu")
		(net "P5E_CPU1_P0_TX_BUF_DP<13>")
	)
	(segment
		(start 63.524638 -389.763762)
		(end 63.647828 -389.886952)
		(width 0.14224)
		(layer "In6.Cu")
		(net "P5E_CPU1_P0_TX_BUF_DP<13>")
	)
	(segment
		(start 88.189054 -403.348444)
		(end 88.189054 -404.17369)
		(width 0.14224)
		(layer "In6.Cu")
		(net "P5E_CPU1_P0_TX_BUF_DP<13>")
	)
	(segment
		(start 83.891882 -400.810476)
		(end 84.25561 -400.940524)
		(width 0.14224)
		(layer "In6.Cu")
		(net "P5E_CPU1_P0_TX_BUF_DP<13>")
	)
	(segment
		(start 64.208914 -394.507974)
		(end 64.667892 -394.966952)
		(width 0.14224)
		(layer "In6.Cu")
		(net "P5E_CPU1_P0_TX_BUF_DP<13>")
	)
	(segment
		(start 64.153796 -391.765536)
		(end 64.153796 -394.374878)
		(width 0.14224)
		(layer "In6.Cu")
		(net "P5E_CPU1_P0_TX_BUF_DP<13>")
	)
	(segment
		(start 87.839804 -402.629624)
		(end 87.927688 -402.717508)
		(width 0.14224)
		(layer "In6.Cu")
		(net "P5E_CPU1_P0_TX_BUF_DP<13>")
	)
	(segment
		(start 63.407036 -389.441944)
		(end 63.407036 -389.480044)
		(width 0.14224)
		(layer "In6.Cu")
		(net "P5E_CPU1_P0_TX_BUF_DP<13>")
	)
	(segment
		(start 82.607404 -400.496532)
		(end 82.782664 -400.413728)
		(width 0.14224)
		(layer "In6.Cu")
		(net "P5E_CPU1_P0_TX_BUF_DP<13>")
	)
	(segment
		(start 70.362572 -396.56004)
		(end 78.529688 -399.037556)
		(width 0.14224)
		(layer "In6.Cu")
		(net "P5E_CPU1_P0_TX_BUF_DP<13>")
	)
	(segment
		(start 83.716368 -400.893534)
		(end 83.891882 -400.810476)
		(width 0.14224)
		(layer "In6.Cu")
		(net "P5E_CPU1_P0_TX_BUF_DP<13>")
	)
	(segment
		(start 65.194942 -395.265402)
		(end 70.362572 -396.56004)
		(width 0.14224)
		(layer "In6.Cu")
		(net "P5E_CPU1_P0_TX_BUF_DP<13>")
	)
	(segment
		(start 63.791338 -389.467344)
		(end 63.67653 -389.352536)
		(width 0.14224)
		(layer "In6.Cu")
		(net "P5E_CPU1_P0_TX_BUF_DP<13>")
	)
	(segment
		(start 84.25561 -400.940524)
		(end 84.338414 -401.116038)
		(width 0.14224)
		(layer "In6.Cu")
		(net "P5E_CPU1_P0_TX_BUF_DP<13>")
	)
	(segment
		(start 63.496444 -389.352536)
		(end 63.407036 -389.441944)
		(width 0.14224)
		(layer "In6.Cu")
		(net "P5E_CPU1_P0_TX_BUF_DP<13>")
	)
	(segment
		(start 84.338414 -401.116038)
		(end 85.284056 -401.454366)
		(width 0.14224)
		(layer "In6.Cu")
		(net "P5E_CPU1_P0_TX_BUF_DP<13>")
	)
	(segment
		(start 83.267804 -400.733006)
		(end 83.716368 -400.893534)
		(width 0.14224)
		(layer "In6.Cu")
		(net "P5E_CPU1_P0_TX_BUF_DP<13>")
	)
	(segment
		(start 78.529688 -399.037556)
		(end 78.705202 -398.954752)
		(width 0.14224)
		(layer "In6.Cu")
		(net "P5E_CPU1_P0_TX_BUF_DP<13>")
	)
	(segment
		(start 63.786258 -390.446514)
		(end 64.123316 -391.559288)
		(width 0.14224)
		(layer "In6.Cu")
		(net "P5E_CPU1_P0_TX_BUF_DP<13>")
	)
	(segment
		(start 88.189054 -404.17369)
		(end 88.479884 -404.46452)
		(width 0.14224)
		(layer "In6.Cu")
		(net "P5E_CPU1_P0_TX_BUF_DP<13>")
	)
	(segment
		(start 79.190088 -399.27403)
		(end 82.607404 -400.496532)
		(width 0.14224)
		(layer "In6.Cu")
		(net "P5E_CPU1_P0_TX_BUF_DP<13>")
	)
	(segment
		(start 63.767716 -390.176512)
		(end 63.767716 -390.3218)
		(width 0.14224)
		(layer "In6.Cu")
		(net "P5E_CPU1_P0_TX_BUF_DP<13>")
	)
	(arc
		(start 63.647828 -389.886952)
		(mid 63.736543 -390.019817)
		(end 63.767716 -390.176512)
		(width 0.14224)
		(layer "In6.Cu")
		(net "P5E_CPU1_P0_TX_BUF_DP<13>")
	)
	(arc
		(start 63.767716 -390.3218)
		(mid 63.772397 -390.384839)
		(end 63.786258 -390.446514)
		(width 0.14224)
		(layer "In6.Cu")
		(net "P5E_CPU1_P0_TX_BUF_DP<13>")
	)
	(arc
		(start 87.927688 -402.717508)
		(mid 88.12111 -403.006984)
		(end 88.189054 -403.348444)
		(width 0.14224)
		(layer "In6.Cu")
		(net "P5E_CPU1_P0_TX_BUF_DP<13>")
	)
	(arc
		(start 87.380826 -402.322792)
		(mid 87.625422 -402.453608)
		(end 87.839804 -402.629624)
		(width 0.14224)
		(layer "In6.Cu")
		(net "P5E_CPU1_P0_TX_BUF_DP<13>")
	)
	(arc
		(start 63.407036 -389.480044)
		(mid 63.4376 -389.633608)
		(end 63.524638 -389.763762)
		(width 0.14224)
		(layer "In6.Cu")
		(net "P5E_CPU1_P0_TX_BUF_DP<13>")
	)
	(arc
		(start 64.667892 -394.966952)
		(mid 64.911166 -395.151927)
		(end 65.194942 -395.265402)
		(width 0.14224)
		(layer "In6.Cu")
		(net "P5E_CPU1_P0_TX_BUF_DP<13>")
	)
	(arc
		(start 64.123316 -391.559288)
		(mid 64.146161 -391.661289)
		(end 64.153796 -391.765536)
		(width 0.14224)
		(layer "In6.Cu")
		(net "P5E_CPU1_P0_TX_BUF_DP<13>")
	)
	(arc
		(start 64.153796 -394.374878)
		(mid 64.168123 -394.446904)
		(end 64.208914 -394.507974)
		(width 0.14224)
		(layer "In6.Cu")
		(net "P5E_CPU1_P0_TX_BUF_DP<13>")
	)
	(segment
		(start 85.146134 -407.954734)
		(end 85.146134 -404.73503)
		(width 0.12954)
		(layer "F.Cu")
		(net "P5E_CPU1_P0_TX_BUF_DP<12>")
	)
	(segment
		(start 62.070488 -389.467344)
		(end 62.591188 -389.467344)
		(width 0.127)
		(layer "F.Cu")
		(net "P5E_CPU1_P0_TX_BUF_DP<12>")
	)
	(segment
		(start 85.442044 -408.250644)
		(end 85.146134 -407.954734)
		(width 0.12954)
		(layer "F.Cu")
		(net "P5E_CPU1_P0_TX_BUF_DP<12>")
	)
	(segment
		(start 85.146134 -404.73503)
		(end 85.416644 -404.46452)
		(width 0.12954)
		(layer "F.Cu")
		(net "P5E_CPU1_P0_TX_BUF_DP<12>")
	)
	(segment
		(start 84.875878 -402.65477)
		(end 84.9884 -402.767292)
		(width 0.14224)
		(layer "In6.Cu")
		(net "P5E_CPU1_P0_TX_BUF_DP<12>")
	)
	(segment
		(start 62.567566 -390.176512)
		(end 62.567566 -390.366504)
		(width 0.14224)
		(layer "In6.Cu")
		(net "P5E_CPU1_P0_TX_BUF_DP<12>")
	)
	(segment
		(start 62.28588 -389.725154)
		(end 62.447678 -389.886952)
		(width 0.14224)
		(layer "In6.Cu")
		(net "P5E_CPU1_P0_TX_BUF_DP<12>")
	)
	(segment
		(start 82.539078 -401.65274)
		(end 82.539078 -401.652994)
		(width 0.14224)
		(layer "In6.Cu")
		(net "P5E_CPU1_P0_TX_BUF_DP<12>")
	)
	(segment
		(start 83.11261 -401.741894)
		(end 83.187032 -401.921472)
		(width 0.14224)
		(layer "In6.Cu")
		(net "P5E_CPU1_P0_TX_BUF_DP<12>")
	)
	(segment
		(start 63.255144 -395.151102)
		(end 63.4492 -395.151102)
		(width 0.14224)
		(layer "In6.Cu")
		(net "P5E_CPU1_P0_TX_BUF_DP<12>")
	)
	(segment
		(start 85.125814 -403.099016)
		(end 85.125814 -404.17369)
		(width 0.14224)
		(layer "In6.Cu")
		(net "P5E_CPU1_P0_TX_BUF_DP<12>")
	)
	(segment
		(start 69.864478 -397.44015)
		(end 79.2226 -400.279108)
		(width 0.14224)
		(layer "In6.Cu")
		(net "P5E_CPU1_P0_TX_BUF_DP<12>")
	)
	(segment
		(start 83.58124 -402.08454)
		(end 83.76031 -402.010372)
		(width 0.14224)
		(layer "In6.Cu")
		(net "P5E_CPU1_P0_TX_BUF_DP<12>")
	)
	(segment
		(start 83.76031 -402.010372)
		(end 84.154772 -402.173694)
		(width 0.14224)
		(layer "In6.Cu")
		(net "P5E_CPU1_P0_TX_BUF_DP<12>")
	)
	(segment
		(start 64.311276 -396.048484)
		(end 69.864478 -397.44015)
		(width 0.14224)
		(layer "In6.Cu")
		(net "P5E_CPU1_P0_TX_BUF_DP<12>")
	)
	(segment
		(start 62.47638 -389.352536)
		(end 62.313312 -389.352536)
		(width 0.14224)
		(layer "In6.Cu")
		(net "P5E_CPU1_P0_TX_BUF_DP<12>")
	)
	(segment
		(start 82.539078 -401.652994)
		(end 82.718148 -401.578572)
		(width 0.14224)
		(layer "In6.Cu")
		(net "P5E_CPU1_P0_TX_BUF_DP<12>")
	)
	(segment
		(start 83.187032 -401.921472)
		(end 83.58124 -402.08454)
		(width 0.14224)
		(layer "In6.Cu")
		(net "P5E_CPU1_P0_TX_BUF_DP<12>")
	)
	(segment
		(start 63.751206 -395.647164)
		(end 63.945008 -395.840966)
		(width 0.14224)
		(layer "In6.Cu")
		(net "P5E_CPU1_P0_TX_BUF_DP<12>")
	)
	(segment
		(start 63.4492 -395.151102)
		(end 63.751206 -395.453108)
		(width 0.14224)
		(layer "In6.Cu")
		(net "P5E_CPU1_P0_TX_BUF_DP<12>")
	)
	(segment
		(start 85.125814 -404.17369)
		(end 85.416644 -404.46452)
		(width 0.14224)
		(layer "In6.Cu")
		(net "P5E_CPU1_P0_TX_BUF_DP<12>")
	)
	(segment
		(start 62.588902 -390.510014)
		(end 62.953646 -391.711942)
		(width 0.14224)
		(layer "In6.Cu")
		(net "P5E_CPU1_P0_TX_BUF_DP<12>")
	)
	(segment
		(start 82.718148 -401.578572)
		(end 83.11261 -401.741894)
		(width 0.14224)
		(layer "In6.Cu")
		(net "P5E_CPU1_P0_TX_BUF_DP<12>")
	)
	(segment
		(start 63.050166 -394.946124)
		(end 63.255144 -395.151102)
		(width 0.14224)
		(layer "In6.Cu")
		(net "P5E_CPU1_P0_TX_BUF_DP<12>")
	)
	(segment
		(start 62.591188 -389.467344)
		(end 62.47638 -389.352536)
		(width 0.14224)
		(layer "In6.Cu")
		(net "P5E_CPU1_P0_TX_BUF_DP<12>")
	)
	(segment
		(start 84.154772 -402.173694)
		(end 84.22894 -402.353272)
		(width 0.14224)
		(layer "In6.Cu")
		(net "P5E_CPU1_P0_TX_BUF_DP<12>")
	)
	(segment
		(start 62.953646 -391.711942)
		(end 62.953646 -394.713206)
		(width 0.14224)
		(layer "In6.Cu")
		(net "P5E_CPU1_P0_TX_BUF_DP<12>")
	)
	(segment
		(start 84.22894 -402.352764)
		(end 84.743036 -402.56587)
		(width 0.14224)
		(layer "In6.Cu")
		(net "P5E_CPU1_P0_TX_BUF_DP<12>")
	)
	(segment
		(start 62.313312 -389.352536)
		(end 62.20714 -389.458708)
		(width 0.14224)
		(layer "In6.Cu")
		(net "P5E_CPU1_P0_TX_BUF_DP<12>")
	)
	(segment
		(start 63.751206 -395.453108)
		(end 63.751206 -395.647164)
		(width 0.14224)
		(layer "In6.Cu")
		(net "P5E_CPU1_P0_TX_BUF_DP<12>")
	)
	(segment
		(start 79.2226 -400.279108)
		(end 82.539078 -401.65274)
		(width 0.14224)
		(layer "In6.Cu")
		(net "P5E_CPU1_P0_TX_BUF_DP<12>")
	)
	(segment
		(start 62.20714 -389.458708)
		(end 62.20714 -389.535162)
		(width 0.14224)
		(layer "In6.Cu")
		(net "P5E_CPU1_P0_TX_BUF_DP<12>")
	)
	(segment
		(start 84.22894 -402.353272)
		(end 84.22894 -402.352764)
		(width 0.14224)
		(layer "In6.Cu")
		(net "P5E_CPU1_P0_TX_BUF_DP<12>")
	)
	(arc
		(start 84.9884 -402.767292)
		(mid 85.090094 -402.919488)
		(end 85.125814 -403.099016)
		(width 0.14224)
		(layer "In6.Cu")
		(net "P5E_CPU1_P0_TX_BUF_DP<12>")
	)
	(arc
		(start 62.953646 -394.713206)
		(mid 62.978738 -394.839262)
		(end 63.050166 -394.946124)
		(width 0.14224)
		(layer "In6.Cu")
		(net "P5E_CPU1_P0_TX_BUF_DP<12>")
	)
	(arc
		(start 62.447678 -389.886952)
		(mid 62.536393 -390.019817)
		(end 62.567566 -390.176512)
		(width 0.14224)
		(layer "In6.Cu")
		(net "P5E_CPU1_P0_TX_BUF_DP<12>")
	)
	(arc
		(start 62.567566 -390.366504)
		(mid 62.57293 -390.439048)
		(end 62.588902 -390.510014)
		(width 0.14224)
		(layer "In6.Cu")
		(net "P5E_CPU1_P0_TX_BUF_DP<12>")
	)
	(arc
		(start 62.20714 -389.535162)
		(mid 62.227611 -389.637987)
		(end 62.28588 -389.725154)
		(width 0.14224)
		(layer "In6.Cu")
		(net "P5E_CPU1_P0_TX_BUF_DP<12>")
	)
	(arc
		(start 84.743036 -402.56587)
		(mid 84.813848 -402.603762)
		(end 84.875878 -402.65477)
		(width 0.14224)
		(layer "In6.Cu")
		(net "P5E_CPU1_P0_TX_BUF_DP<12>")
	)
	(arc
		(start 63.945008 -395.840966)
		(mid 64.114055 -395.969586)
		(end 64.311276 -396.048484)
		(width 0.14224)
		(layer "In6.Cu")
		(net "P5E_CPU1_P0_TX_BUF_DP<12>")
	)
	(segment
		(start 82.378804 -408.250644)
		(end 82.082894 -407.954734)
		(width 0.12954)
		(layer "F.Cu")
		(net "P5E_CPU1_P0_TX_BUF_DP<11>")
	)
	(segment
		(start 82.082894 -404.73503)
		(end 82.353404 -404.46452)
		(width 0.12954)
		(layer "F.Cu")
		(net "P5E_CPU1_P0_TX_BUF_DP<11>")
	)
	(segment
		(start 82.082894 -407.954734)
		(end 82.082894 -404.73503)
		(width 0.12954)
		(layer "F.Cu")
		(net "P5E_CPU1_P0_TX_BUF_DP<11>")
	)
	(segment
		(start 60.870592 -389.467344)
		(end 61.391292 -389.467344)
		(width 0.127)
		(layer "F.Cu")
		(net "P5E_CPU1_P0_TX_BUF_DP<11>")
	)
	(segment
		(start 80.377284 -401.97405)
		(end 81.711546 -402.526754)
		(width 0.14224)
		(layer "In6.Cu")
		(net "P5E_CPU1_P0_TX_BUF_DP<11>")
	)
	(segment
		(start 62.578996 -396.057628)
		(end 62.578996 -396.251684)
		(width 0.14224)
		(layer "In6.Cu")
		(net "P5E_CPU1_P0_TX_BUF_DP<11>")
	)
	(segment
		(start 78.848458 -401.192238)
		(end 78.897226 -401.310094)
		(width 0.14224)
		(layer "In6.Cu")
		(net "P5E_CPU1_P0_TX_BUF_DP<11>")
	)
	(segment
		(start 62.082934 -395.755622)
		(end 62.27699 -395.755622)
		(width 0.14224)
		(layer "In6.Cu")
		(net "P5E_CPU1_P0_TX_BUF_DP<11>")
	)
	(segment
		(start 82.062574 -404.17369)
		(end 82.353404 -404.46452)
		(width 0.14224)
		(layer "In6.Cu")
		(net "P5E_CPU1_P0_TX_BUF_DP<11>")
	)
	(segment
		(start 78.084172 -401.024344)
		(end 78.274926 -401.103084)
		(width 0.14224)
		(layer "In6.Cu")
		(net "P5E_CPU1_P0_TX_BUF_DP<11>")
	)
	(segment
		(start 77.880718 -400.940016)
		(end 78.084172 -401.024344)
		(width 0.14224)
		(layer "In6.Cu")
		(net "P5E_CPU1_P0_TX_BUF_DP<11>")
	)
	(segment
		(start 68.085716 -397.96847)
		(end 77.880718 -400.940016)
		(width 0.14224)
		(layer "In6.Cu")
		(net "P5E_CPU1_P0_TX_BUF_DP<11>")
	)
	(segment
		(start 79.766668 -401.72132)
		(end 79.945992 -401.646898)
		(width 0.14224)
		(layer "In6.Cu")
		(net "P5E_CPU1_P0_TX_BUF_DP<11>")
	)
	(segment
		(start 78.453996 -401.028916)
		(end 78.848458 -401.192238)
		(width 0.14224)
		(layer "In6.Cu")
		(net "P5E_CPU1_P0_TX_BUF_DP<11>")
	)
	(segment
		(start 61.278262 -389.354314)
		(end 61.136276 -389.354314)
		(width 0.14224)
		(layer "In6.Cu")
		(net "P5E_CPU1_P0_TX_BUF_DP<11>")
	)
	(segment
		(start 62.578996 -396.251684)
		(end 62.941962 -396.61465)
		(width 0.14224)
		(layer "In6.Cu")
		(net "P5E_CPU1_P0_TX_BUF_DP<11>")
	)
	(segment
		(start 80.302862 -401.794726)
		(end 80.377284 -401.97405)
		(width 0.14224)
		(layer "In6.Cu")
		(net "P5E_CPU1_P0_TX_BUF_DP<11>")
	)
	(segment
		(start 62.27699 -395.755622)
		(end 62.578996 -396.057628)
		(width 0.14224)
		(layer "In6.Cu")
		(net "P5E_CPU1_P0_TX_BUF_DP<11>")
	)
	(segment
		(start 79.945992 -401.646898)
		(end 80.302862 -401.794726)
		(width 0.14224)
		(layer "In6.Cu")
		(net "P5E_CPU1_P0_TX_BUF_DP<11>")
	)
	(segment
		(start 61.391292 -389.467344)
		(end 61.278262 -389.354314)
		(width 0.14224)
		(layer "In6.Cu")
		(net "P5E_CPU1_P0_TX_BUF_DP<11>")
	)
	(segment
		(start 78.274926 -401.103084)
		(end 78.453996 -401.028916)
		(width 0.14224)
		(layer "In6.Cu")
		(net "P5E_CPU1_P0_TX_BUF_DP<11>")
	)
	(segment
		(start 82.062574 -403.110192)
		(end 82.062574 -404.17369)
		(width 0.14224)
		(layer "In6.Cu")
		(net "P5E_CPU1_P0_TX_BUF_DP<11>")
	)
	(segment
		(start 61.906658 -395.579346)
		(end 62.082934 -395.755622)
		(width 0.14224)
		(layer "In6.Cu")
		(net "P5E_CPU1_P0_TX_BUF_DP<11>")
	)
	(segment
		(start 61.386212 -390.421876)
		(end 61.72327 -391.53465)
		(width 0.14224)
		(layer "In6.Cu")
		(net "P5E_CPU1_P0_TX_BUF_DP<11>")
	)
	(segment
		(start 78.984348 -401.397216)
		(end 79.766668 -401.72132)
		(width 0.14224)
		(layer "In6.Cu")
		(net "P5E_CPU1_P0_TX_BUF_DP<11>")
	)
	(segment
		(start 61.75375 -391.740898)
		(end 61.75375 -395.210538)
		(width 0.14224)
		(layer "In6.Cu")
		(net "P5E_CPU1_P0_TX_BUF_DP<11>")
	)
	(segment
		(start 63.151004 -396.733014)
		(end 68.085716 -397.96847)
		(width 0.14224)
		(layer "In6.Cu")
		(net "P5E_CPU1_P0_TX_BUF_DP<11>")
	)
	(segment
		(start 61.136276 -389.354314)
		(end 61.111892 -389.378698)
		(width 0.14224)
		(layer "In6.Cu")
		(net "P5E_CPU1_P0_TX_BUF_DP<11>")
	)
	(arc
		(start 61.75375 -395.210538)
		(mid 61.793493 -395.410162)
		(end 61.906658 -395.579346)
		(width 0.14224)
		(layer "In6.Cu")
		(net "P5E_CPU1_P0_TX_BUF_DP<11>")
	)
	(arc
		(start 81.935066 -402.707602)
		(mid 82.028577 -402.899469)
		(end 82.062574 -403.110192)
		(width 0.14224)
		(layer "In6.Cu")
		(net "P5E_CPU1_P0_TX_BUF_DP<11>")
	)
	(arc
		(start 61.72327 -391.53465)
		(mid 61.746115 -391.636651)
		(end 61.75375 -391.740898)
		(width 0.14224)
		(layer "In6.Cu")
		(net "P5E_CPU1_P0_TX_BUF_DP<11>")
	)
	(arc
		(start 62.941962 -396.61465)
		(mid 63.038438 -396.688041)
		(end 63.151004 -396.733014)
		(width 0.14224)
		(layer "In6.Cu")
		(net "P5E_CPU1_P0_TX_BUF_DP<11>")
	)
	(arc
		(start 81.711546 -402.526754)
		(mid 81.836438 -402.600941)
		(end 81.935066 -402.707602)
		(width 0.14224)
		(layer "In6.Cu")
		(net "P5E_CPU1_P0_TX_BUF_DP<11>")
	)
	(arc
		(start 61.109098 -389.748522)
		(mid 61.29025 -390.015225)
		(end 61.36894 -390.327896)
		(width 0.14224)
		(layer "In6.Cu")
		(net "P5E_CPU1_P0_TX_BUF_DP<11>")
	)
	(arc
		(start 61.111892 -389.378698)
		(mid 61.034676 -389.563067)
		(end 61.109098 -389.748522)
		(width 0.14224)
		(layer "In6.Cu")
		(net "P5E_CPU1_P0_TX_BUF_DP<11>")
	)
	(arc
		(start 61.36894 -390.327896)
		(mid 61.374953 -390.375368)
		(end 61.386212 -390.421876)
		(width 0.14224)
		(layer "In6.Cu")
		(net "P5E_CPU1_P0_TX_BUF_DP<11>")
	)
	(arc
		(start 78.897226 -401.310094)
		(mid 78.932112 -401.36233)
		(end 78.984348 -401.397216)
		(width 0.14224)
		(layer "In6.Cu")
		(net "P5E_CPU1_P0_TX_BUF_DP<11>")
	)
	(segment
		(start 59.670696 -389.467344)
		(end 60.191396 -389.467344)
		(width 0.127)
		(layer "F.Cu")
		(net "P5E_CPU1_P0_TX_BUF_DP<10>")
	)
	(segment
		(start 79.019654 -404.73503)
		(end 79.290164 -404.46452)
		(width 0.12954)
		(layer "F.Cu")
		(net "P5E_CPU1_P0_TX_BUF_DP<10>")
	)
	(segment
		(start 79.019654 -407.954734)
		(end 79.019654 -404.73503)
		(width 0.12954)
		(layer "F.Cu")
		(net "P5E_CPU1_P0_TX_BUF_DP<10>")
	)
	(segment
		(start 79.315564 -408.250644)
		(end 79.019654 -407.954734)
		(width 0.12954)
		(layer "F.Cu")
		(net "P5E_CPU1_P0_TX_BUF_DP<10>")
	)
	(segment
		(start 59.92114 -389.760206)
		(end 60.047632 -389.886444)
		(width 0.14224)
		(layer "In6.Cu")
		(net "P5E_CPU1_P0_TX_BUF_DP<10>")
	)
	(segment
		(start 78.553564 -402.761196)
		(end 78.826868 -403.0345)
		(width 0.14224)
		(layer "In6.Cu")
		(net "P5E_CPU1_P0_TX_BUF_DP<10>")
	)
	(segment
		(start 76.513436 -401.644866)
		(end 76.587858 -401.82419)
		(width 0.14224)
		(layer "In6.Cu")
		(net "P5E_CPU1_P0_TX_BUF_DP<10>")
	)
	(segment
		(start 60.191396 -389.467344)
		(end 60.076588 -389.352536)
		(width 0.14224)
		(layer "In6.Cu")
		(net "P5E_CPU1_P0_TX_BUF_DP<10>")
	)
	(segment
		(start 78.826868 -403.0345)
		(end 78.826868 -403.228556)
		(width 0.14224)
		(layer "In6.Cu")
		(net "P5E_CPU1_P0_TX_BUF_DP<10>")
	)
	(segment
		(start 78.826868 -403.228556)
		(end 78.879446 -403.281134)
		(width 0.14224)
		(layer "In6.Cu")
		(net "P5E_CPU1_P0_TX_BUF_DP<10>")
	)
	(segment
		(start 78.359508 -402.761196)
		(end 78.553564 -402.761196)
		(width 0.14224)
		(layer "In6.Cu")
		(net "P5E_CPU1_P0_TX_BUF_DP<10>")
	)
	(segment
		(start 78.999334 -403.570694)
		(end 78.999334 -404.17369)
		(width 0.14224)
		(layer "In6.Cu")
		(net "P5E_CPU1_P0_TX_BUF_DP<10>")
	)
	(segment
		(start 77.123544 -401.897088)
		(end 77.480668 -402.044662)
		(width 0.14224)
		(layer "In6.Cu")
		(net "P5E_CPU1_P0_TX_BUF_DP<10>")
	)
	(segment
		(start 62.689232 -397.581628)
		(end 67.334384 -398.744948)
		(width 0.14224)
		(layer "In6.Cu")
		(net "P5E_CPU1_P0_TX_BUF_DP<10>")
	)
	(segment
		(start 74.10831 -400.799808)
		(end 75.977242 -401.571714)
		(width 0.14224)
		(layer "In6.Cu")
		(net "P5E_CPU1_P0_TX_BUF_DP<10>")
	)
	(segment
		(start 60.076588 -389.352536)
		(end 59.896502 -389.352536)
		(width 0.14224)
		(layer "In6.Cu")
		(net "P5E_CPU1_P0_TX_BUF_DP<10>")
	)
	(segment
		(start 77.480668 -402.044662)
		(end 77.55509 -402.223986)
		(width 0.14224)
		(layer "In6.Cu")
		(net "P5E_CPU1_P0_TX_BUF_DP<10>")
	)
	(segment
		(start 60.80887 -395.897862)
		(end 62.235842 -397.324834)
		(width 0.14224)
		(layer "In6.Cu")
		(net "P5E_CPU1_P0_TX_BUF_DP<10>")
	)
	(segment
		(start 60.173362 -390.467596)
		(end 60.515754 -391.597134)
		(width 0.14224)
		(layer "In6.Cu")
		(net "P5E_CPU1_P0_TX_BUF_DP<10>")
	)
	(segment
		(start 76.944474 -401.97151)
		(end 77.123544 -401.897088)
		(width 0.14224)
		(layer "In6.Cu")
		(net "P5E_CPU1_P0_TX_BUF_DP<10>")
	)
	(segment
		(start 78.999334 -404.17369)
		(end 79.290164 -404.46452)
		(width 0.14224)
		(layer "In6.Cu")
		(net "P5E_CPU1_P0_TX_BUF_DP<10>")
	)
	(segment
		(start 76.156312 -401.497292)
		(end 76.513436 -401.644866)
		(width 0.14224)
		(layer "In6.Cu")
		(net "P5E_CPU1_P0_TX_BUF_DP<10>")
	)
	(segment
		(start 75.977242 -401.571714)
		(end 76.156312 -401.497292)
		(width 0.14224)
		(layer "In6.Cu")
		(net "P5E_CPU1_P0_TX_BUF_DP<10>")
	)
	(segment
		(start 60.167774 -390.176004)
		(end 60.167774 -390.430512)
		(width 0.14224)
		(layer "In6.Cu")
		(net "P5E_CPU1_P0_TX_BUF_DP<10>")
	)
	(segment
		(start 67.334384 -398.744948)
		(end 74.10831 -400.799808)
		(width 0.14224)
		(layer "In6.Cu")
		(net "P5E_CPU1_P0_TX_BUF_DP<10>")
	)
	(segment
		(start 78.086712 -402.4884)
		(end 78.359508 -402.761196)
		(width 0.14224)
		(layer "In6.Cu")
		(net "P5E_CPU1_P0_TX_BUF_DP<10>")
	)
	(segment
		(start 76.587858 -401.82419)
		(end 76.944474 -401.97151)
		(width 0.14224)
		(layer "In6.Cu")
		(net "P5E_CPU1_P0_TX_BUF_DP<10>")
	)
	(segment
		(start 77.55509 -402.223986)
		(end 77.911706 -402.371306)
		(width 0.14224)
		(layer "In6.Cu")
		(net "P5E_CPU1_P0_TX_BUF_DP<10>")
	)
	(segment
		(start 59.896502 -389.352536)
		(end 59.807094 -389.441944)
		(width 0.14224)
		(layer "In6.Cu")
		(net "P5E_CPU1_P0_TX_BUF_DP<10>")
	)
	(segment
		(start 59.807094 -389.441944)
		(end 59.807094 -389.485124)
		(width 0.14224)
		(layer "In6.Cu")
		(net "P5E_CPU1_P0_TX_BUF_DP<10>")
	)
	(segment
		(start 60.515754 -391.597134)
		(end 60.515754 -395.190218)
		(width 0.14224)
		(layer "In6.Cu")
		(net "P5E_CPU1_P0_TX_BUF_DP<10>")
	)
	(arc
		(start 62.235842 -397.324834)
		(mid 62.445092 -397.484035)
		(end 62.689232 -397.581628)
		(width 0.14224)
		(layer "In6.Cu")
		(net "P5E_CPU1_P0_TX_BUF_DP<10>")
	)
	(arc
		(start 78.879446 -403.281134)
		(mid 78.968161 -403.413999)
		(end 78.999334 -403.570694)
		(width 0.14224)
		(layer "In6.Cu")
		(net "P5E_CPU1_P0_TX_BUF_DP<10>")
	)
	(arc
		(start 59.807094 -389.485124)
		(mid 59.83673 -389.634023)
		(end 59.92114 -389.760206)
		(width 0.14224)
		(layer "In6.Cu")
		(net "P5E_CPU1_P0_TX_BUF_DP<10>")
	)
	(arc
		(start 77.911706 -402.371306)
		(mid 78.004955 -402.421262)
		(end 78.086712 -402.4884)
		(width 0.14224)
		(layer "In6.Cu")
		(net "P5E_CPU1_P0_TX_BUF_DP<10>")
	)
	(arc
		(start 60.167774 -390.430512)
		(mid 60.169195 -390.449261)
		(end 60.173362 -390.467596)
		(width 0.14224)
		(layer "In6.Cu")
		(net "P5E_CPU1_P0_TX_BUF_DP<10>")
	)
	(arc
		(start 60.515754 -395.190218)
		(mid 60.591932 -395.573192)
		(end 60.80887 -395.897862)
		(width 0.14224)
		(layer "In6.Cu")
		(net "P5E_CPU1_P0_TX_BUF_DP<10>")
	)
	(arc
		(start 60.047632 -389.886444)
		(mid 60.136562 -390.019252)
		(end 60.167774 -390.176004)
		(width 0.14224)
		(layer "In6.Cu")
		(net "P5E_CPU1_P0_TX_BUF_DP<10>")
	)
	(segment
		(start 48.387254 -407.954734)
		(end 48.387254 -404.73503)
		(width 0.12954)
		(layer "F.Cu")
		(net "P5E_CPU1_P0_TX_BUF_DP<0>")
	)
	(segment
		(start 48.387254 -404.73503)
		(end 48.657764 -404.46452)
		(width 0.12954)
		(layer "F.Cu")
		(net "P5E_CPU1_P0_TX_BUF_DP<0>")
	)
	(segment
		(start 48.683164 -408.250644)
		(end 48.387254 -407.954734)
		(width 0.12954)
		(layer "F.Cu")
		(net "P5E_CPU1_P0_TX_BUF_DP<0>")
	)
	(segment
		(start 47.67072 -389.467344)
		(end 48.19142 -389.467344)
		(width 0.127)
		(layer "F.Cu")
		(net "P5E_CPU1_P0_TX_BUF_DP<0>")
	)
	(segment
		(start 48.553878 -398.691608)
		(end 48.553878 -399.118328)
		(width 0.14224)
		(layer "In6.Cu")
		(net "P5E_CPU1_P0_TX_BUF_DP<0>")
	)
	(segment
		(start 48.553878 -399.118328)
		(end 48.691038 -399.255488)
		(width 0.14224)
		(layer "In6.Cu")
		(net "P5E_CPU1_P0_TX_BUF_DP<0>")
	)
	(segment
		(start 48.167798 -390.176258)
		(end 48.167798 -390.513316)
		(width 0.14224)
		(layer "In6.Cu")
		(net "P5E_CPU1_P0_TX_BUF_DP<0>")
	)
	(segment
		(start 48.553878 -399.819368)
		(end 48.553878 -400.246088)
		(width 0.14224)
		(layer "In6.Cu")
		(net "P5E_CPU1_P0_TX_BUF_DP<0>")
	)
	(segment
		(start 48.553878 -402.35632)
		(end 48.366934 -403.296374)
		(width 0.14224)
		(layer "In6.Cu")
		(net "P5E_CPU1_P0_TX_BUF_DP<0>")
	)
	(segment
		(start 48.366934 -404.17369)
		(end 48.657764 -404.46452)
		(width 0.14224)
		(layer "In6.Cu")
		(net "P5E_CPU1_P0_TX_BUF_DP<0>")
	)
	(segment
		(start 47.896526 -389.352536)
		(end 47.840646 -389.408416)
		(width 0.14224)
		(layer "In6.Cu")
		(net "P5E_CPU1_P0_TX_BUF_DP<0>")
	)
	(segment
		(start 48.167798 -390.513316)
		(end 48.553878 -391.785602)
		(width 0.14224)
		(layer "In6.Cu")
		(net "P5E_CPU1_P0_TX_BUF_DP<0>")
	)
	(segment
		(start 48.691038 -399.255488)
		(end 48.691038 -399.682208)
		(width 0.14224)
		(layer "In6.Cu")
		(net "P5E_CPU1_P0_TX_BUF_DP<0>")
	)
	(segment
		(start 48.553878 -391.785602)
		(end 48.553878 -397.990568)
		(width 0.14224)
		(layer "In6.Cu")
		(net "P5E_CPU1_P0_TX_BUF_DP<0>")
	)
	(segment
		(start 47.807118 -389.489188)
		(end 47.807118 -389.564118)
		(width 0.14224)
		(layer "In6.Cu")
		(net "P5E_CPU1_P0_TX_BUF_DP<0>")
	)
	(segment
		(start 48.553878 -397.990568)
		(end 48.691038 -398.127728)
		(width 0.14224)
		(layer "In6.Cu")
		(net "P5E_CPU1_P0_TX_BUF_DP<0>")
	)
	(segment
		(start 48.691038 -398.554448)
		(end 48.553878 -398.691608)
		(width 0.14224)
		(layer "In6.Cu")
		(net "P5E_CPU1_P0_TX_BUF_DP<0>")
	)
	(segment
		(start 48.553878 -400.246088)
		(end 48.691038 -400.383248)
		(width 0.14224)
		(layer "In6.Cu")
		(net "P5E_CPU1_P0_TX_BUF_DP<0>")
	)
	(segment
		(start 48.691038 -400.809968)
		(end 48.553878 -400.947128)
		(width 0.14224)
		(layer "In6.Cu")
		(net "P5E_CPU1_P0_TX_BUF_DP<0>")
	)
	(segment
		(start 48.366934 -403.296374)
		(end 48.366934 -404.17369)
		(width 0.14224)
		(layer "In6.Cu")
		(net "P5E_CPU1_P0_TX_BUF_DP<0>")
	)
	(segment
		(start 48.076612 -389.352536)
		(end 47.896526 -389.352536)
		(width 0.14224)
		(layer "In6.Cu")
		(net "P5E_CPU1_P0_TX_BUF_DP<0>")
	)
	(segment
		(start 47.854362 -389.678164)
		(end 48.037242 -389.861044)
		(width 0.14224)
		(layer "In6.Cu")
		(net "P5E_CPU1_P0_TX_BUF_DP<0>")
	)
	(segment
		(start 48.19142 -389.467344)
		(end 48.076612 -389.352536)
		(width 0.14224)
		(layer "In6.Cu")
		(net "P5E_CPU1_P0_TX_BUF_DP<0>")
	)
	(segment
		(start 48.691038 -399.682208)
		(end 48.553878 -399.819368)
		(width 0.14224)
		(layer "In6.Cu")
		(net "P5E_CPU1_P0_TX_BUF_DP<0>")
	)
	(segment
		(start 48.691038 -398.127728)
		(end 48.691038 -398.554448)
		(width 0.14224)
		(layer "In6.Cu")
		(net "P5E_CPU1_P0_TX_BUF_DP<0>")
	)
	(segment
		(start 47.807118 -389.564118)
		(end 47.807372 -389.564118)
		(width 0.14224)
		(layer "In6.Cu")
		(net "P5E_CPU1_P0_TX_BUF_DP<0>")
	)
	(segment
		(start 48.691038 -400.383248)
		(end 48.691038 -400.809968)
		(width 0.14224)
		(layer "In6.Cu")
		(net "P5E_CPU1_P0_TX_BUF_DP<0>")
	)
	(segment
		(start 48.553878 -400.947128)
		(end 48.553878 -402.35632)
		(width 0.14224)
		(layer "In6.Cu")
		(net "P5E_CPU1_P0_TX_BUF_DP<0>")
	)
	(arc
		(start 48.037242 -389.861044)
		(mid 48.133875 -390.005665)
		(end 48.167798 -390.176258)
		(width 0.14224)
		(layer "In6.Cu")
		(net "P5E_CPU1_P0_TX_BUF_DP<0>")
	)
	(arc
		(start 47.807372 -389.564118)
		(mid 47.819547 -389.625798)
		(end 47.854362 -389.678164)
		(width 0.14224)
		(layer "In6.Cu")
		(net "P5E_CPU1_P0_TX_BUF_DP<0>")
	)
	(arc
		(start 47.840646 -389.408416)
		(mid 47.81583 -389.44546)
		(end 47.807118 -389.489188)
		(width 0.14224)
		(layer "In6.Cu")
		(net "P5E_CPU1_P0_TX_BUF_DP<0>")
	)
	(segment
		(start 75.633834 -407.954734)
		(end 75.633834 -404.73503)
		(width 0.12954)
		(layer "F.Cu")
		(net "P5E_CPU1_P0_TX_BUF_DN<9>")
	)
	(segment
		(start 58.070496 -388.774432)
		(end 58.591196 -388.774432)
		(width 0.127)
		(layer "F.Cu")
		(net "P5E_CPU1_P0_TX_BUF_DN<9>")
	)
	(segment
		(start 75.633834 -404.73503)
		(end 75.363324 -404.46452)
		(width 0.12954)
		(layer "F.Cu")
		(net "P5E_CPU1_P0_TX_BUF_DN<9>")
	)
	(segment
		(start 75.337924 -408.250644)
		(end 75.633834 -407.954734)
		(width 0.12954)
		(layer "F.Cu")
		(net "P5E_CPU1_P0_TX_BUF_DN<9>")
	)
	(segment
		(start 68.934076 -400.552666)
		(end 73.70572 -402.269452)
		(width 0.14224)
		(layer "In6.Cu")
		(net "P5E_CPU1_P0_TX_BUF_DN<9>")
	)
	(segment
		(start 74.921618 -402.985986)
		(end 74.922126 -402.98624)
		(width 0.14224)
		(layer "In6.Cu")
		(net "P5E_CPU1_P0_TX_BUF_DN<9>")
	)
	(segment
		(start 74.922126 -402.98624)
		(end 75.296014 -403.229064)
		(width 0.14224)
		(layer "In6.Cu")
		(net "P5E_CPU1_P0_TX_BUF_DN<9>")
	)
	(segment
		(start 75.296014 -403.229064)
		(end 75.618848 -403.565614)
		(width 0.14224)
		(layer "In6.Cu")
		(net "P5E_CPU1_P0_TX_BUF_DN<9>")
	)
	(segment
		(start 58.64352 -389.006588)
		(end 58.325004 -389.325104)
		(width 0.14224)
		(layer "In6.Cu")
		(net "P5E_CPU1_P0_TX_BUF_DN<9>")
	)
	(segment
		(start 58.325004 -389.325104)
		(end 58.325004 -389.536686)
		(width 0.14224)
		(layer "In6.Cu")
		(net "P5E_CPU1_P0_TX_BUF_DN<9>")
	)
	(segment
		(start 74.182986 -402.506434)
		(end 74.921618 -402.985986)
		(width 0.14224)
		(layer "In6.Cu")
		(net "P5E_CPU1_P0_TX_BUF_DN<9>")
	)
	(segment
		(start 58.98007 -391.45083)
		(end 58.98007 -391.46226)
		(width 0.14224)
		(layer "In6.Cu")
		(net "P5E_CPU1_P0_TX_BUF_DN<9>")
	)
	(segment
		(start 75.654154 -403.653752)
		(end 75.654154 -404.17369)
		(width 0.14224)
		(layer "In6.Cu")
		(net "P5E_CPU1_P0_TX_BUF_DN<9>")
	)
	(segment
		(start 58.64352 -388.826756)
		(end 58.64352 -389.006588)
		(width 0.14224)
		(layer "In6.Cu")
		(net "P5E_CPU1_P0_TX_BUF_DN<9>")
	)
	(segment
		(start 66.020696 -399.669)
		(end 68.934076 -400.552666)
		(width 0.14224)
		(layer "In6.Cu")
		(net "P5E_CPU1_P0_TX_BUF_DN<9>")
	)
	(segment
		(start 58.485024 -389.92302)
		(end 58.648346 -390.086342)
		(width 0.14224)
		(layer "In6.Cu")
		(net "P5E_CPU1_P0_TX_BUF_DN<9>")
	)
	(segment
		(start 59.429396 -396.295626)
		(end 61.31941 -398.18564)
		(width 0.14224)
		(layer "In6.Cu")
		(net "P5E_CPU1_P0_TX_BUF_DN<9>")
	)
	(segment
		(start 58.712862 -390.56691)
		(end 58.98007 -391.45083)
		(width 0.14224)
		(layer "In6.Cu")
		(net "P5E_CPU1_P0_TX_BUF_DN<9>")
	)
	(segment
		(start 58.98007 -391.46226)
		(end 59.006994 -391.551414)
		(width 0.14224)
		(layer "In6.Cu")
		(net "P5E_CPU1_P0_TX_BUF_DN<9>")
	)
	(segment
		(start 63.897002 -399.13687)
		(end 66.020696 -399.669)
		(width 0.14224)
		(layer "In6.Cu")
		(net "P5E_CPU1_P0_TX_BUF_DN<9>")
	)
	(segment
		(start 58.591196 -388.774432)
		(end 58.64352 -388.826756)
		(width 0.14224)
		(layer "In6.Cu")
		(net "P5E_CPU1_P0_TX_BUF_DN<9>")
	)
	(segment
		(start 62.62624 -398.88414)
		(end 63.897002 -399.13687)
		(width 0.14224)
		(layer "In6.Cu")
		(net "P5E_CPU1_P0_TX_BUF_DN<9>")
	)
	(segment
		(start 59.025282 -391.676128)
		(end 59.025282 -395.449552)
		(width 0.14224)
		(layer "In6.Cu")
		(net "P5E_CPU1_P0_TX_BUF_DN<9>")
	)
	(segment
		(start 58.685684 -390.176512)
		(end 58.685684 -390.38276)
		(width 0.14224)
		(layer "In6.Cu")
		(net "P5E_CPU1_P0_TX_BUF_DN<9>")
	)
	(segment
		(start 75.654154 -404.17369)
		(end 75.363324 -404.46452)
		(width 0.14224)
		(layer "In6.Cu")
		(net "P5E_CPU1_P0_TX_BUF_DN<9>")
	)
	(arc
		(start 73.70572 -402.269452)
		(mid 73.951202 -402.374151)
		(end 74.182986 -402.506434)
		(width 0.14224)
		(layer "In6.Cu")
		(net "P5E_CPU1_P0_TX_BUF_DN<9>")
	)
	(arc
		(start 58.648346 -390.086342)
		(mid 58.675989 -390.127712)
		(end 58.685684 -390.176512)
		(width 0.14224)
		(layer "In6.Cu")
		(net "P5E_CPU1_P0_TX_BUF_DN<9>")
	)
	(arc
		(start 59.006994 -391.551414)
		(mid 59.020715 -391.6131)
		(end 59.025282 -391.676128)
		(width 0.14224)
		(layer "In6.Cu")
		(net "P5E_CPU1_P0_TX_BUF_DN<9>")
	)
	(arc
		(start 59.025282 -395.449552)
		(mid 59.032016 -395.551063)
		(end 59.05246 -395.65072)
		(width 0.14224)
		(layer "In6.Cu")
		(net "P5E_CPU1_P0_TX_BUF_DN<9>")
	)
	(arc
		(start 58.685684 -390.38276)
		(mid 58.692514 -390.475833)
		(end 58.712862 -390.56691)
		(width 0.14224)
		(layer "In6.Cu")
		(net "P5E_CPU1_P0_TX_BUF_DN<9>")
	)
	(arc
		(start 59.05246 -395.65072)
		(mid 59.19929 -395.997507)
		(end 59.429396 -396.295626)
		(width 0.14224)
		(layer "In6.Cu")
		(net "P5E_CPU1_P0_TX_BUF_DN<9>")
	)
	(arc
		(start 58.325004 -389.536686)
		(mid 58.366593 -389.745767)
		(end 58.485024 -389.92302)
		(width 0.14224)
		(layer "In6.Cu")
		(net "P5E_CPU1_P0_TX_BUF_DN<9>")
	)
	(arc
		(start 61.31941 -398.18564)
		(mid 61.921017 -398.631816)
		(end 62.62624 -398.88414)
		(width 0.14224)
		(layer "In6.Cu")
		(net "P5E_CPU1_P0_TX_BUF_DN<9>")
	)
	(arc
		(start 75.618848 -403.565614)
		(mid 75.645 -403.606272)
		(end 75.654154 -403.653752)
		(width 0.14224)
		(layer "In6.Cu")
		(net "P5E_CPU1_P0_TX_BUF_DN<9>")
	)
	(segment
		(start 72.570594 -407.954734)
		(end 72.570594 -404.73503)
		(width 0.12954)
		(layer "F.Cu")
		(net "P5E_CPU1_P0_TX_BUF_DN<8>")
	)
	(segment
		(start 56.8706 -388.774432)
		(end 57.3913 -388.774432)
		(width 0.127)
		(layer "F.Cu")
		(net "P5E_CPU1_P0_TX_BUF_DN<8>")
	)
	(segment
		(start 72.570594 -404.73503)
		(end 72.300084 -404.46452)
		(width 0.12954)
		(layer "F.Cu")
		(net "P5E_CPU1_P0_TX_BUF_DN<8>")
	)
	(segment
		(start 72.274684 -408.250644)
		(end 72.570594 -407.954734)
		(width 0.12954)
		(layer "F.Cu")
		(net "P5E_CPU1_P0_TX_BUF_DN<8>")
	)
	(segment
		(start 57.125108 -389.325104)
		(end 57.125108 -389.520176)
		(width 0.14224)
		(layer "In6.Cu")
		(net "P5E_CPU1_P0_TX_BUF_DN<8>")
	)
	(segment
		(start 57.3913 -388.774432)
		(end 57.443624 -388.826756)
		(width 0.14224)
		(layer "In6.Cu")
		(net "P5E_CPU1_P0_TX_BUF_DN<8>")
	)
	(segment
		(start 57.516268 -390.510776)
		(end 57.825132 -391.53084)
		(width 0.14224)
		(layer "In6.Cu")
		(net "P5E_CPU1_P0_TX_BUF_DN<8>")
	)
	(segment
		(start 57.296812 -389.934704)
		(end 57.44845 -390.086342)
		(width 0.14224)
		(layer "In6.Cu")
		(net "P5E_CPU1_P0_TX_BUF_DN<8>")
	)
	(segment
		(start 58.08599 -396.278862)
		(end 60.722256 -398.915128)
		(width 0.14224)
		(layer "In6.Cu")
		(net "P5E_CPU1_P0_TX_BUF_DN<8>")
	)
	(segment
		(start 72.590914 -404.17369)
		(end 72.300084 -404.46452)
		(width 0.14224)
		(layer "In6.Cu")
		(net "P5E_CPU1_P0_TX_BUF_DN<8>")
	)
	(segment
		(start 57.843674 -391.655554)
		(end 57.843674 -395.693646)
		(width 0.14224)
		(layer "In6.Cu")
		(net "P5E_CPU1_P0_TX_BUF_DN<8>")
	)
	(segment
		(start 72.590914 -403.266402)
		(end 72.590914 -404.17369)
		(width 0.14224)
		(layer "In6.Cu")
		(net "P5E_CPU1_P0_TX_BUF_DN<8>")
	)
	(segment
		(start 69.138038 -401.68195)
		(end 72.495918 -403.072854)
		(width 0.14224)
		(layer "In6.Cu")
		(net "P5E_CPU1_P0_TX_BUF_DN<8>")
	)
	(segment
		(start 57.443624 -389.006588)
		(end 57.125108 -389.325104)
		(width 0.14224)
		(layer "In6.Cu")
		(net "P5E_CPU1_P0_TX_BUF_DN<8>")
	)
	(segment
		(start 57.485788 -390.176004)
		(end 57.485788 -390.304782)
		(width 0.14224)
		(layer "In6.Cu")
		(net "P5E_CPU1_P0_TX_BUF_DN<8>")
	)
	(segment
		(start 62.339474 -399.779744)
		(end 63.566548 -400.023584)
		(width 0.14224)
		(layer "In6.Cu")
		(net "P5E_CPU1_P0_TX_BUF_DN<8>")
	)
	(segment
		(start 66.317622 -400.746722)
		(end 67.692016 -401.164044)
		(width 0.14224)
		(layer "In6.Cu")
		(net "P5E_CPU1_P0_TX_BUF_DN<8>")
	)
	(segment
		(start 57.443624 -388.826756)
		(end 57.443624 -389.006588)
		(width 0.14224)
		(layer "In6.Cu")
		(net "P5E_CPU1_P0_TX_BUF_DN<8>")
	)
	(segment
		(start 63.702184 -400.054064)
		(end 64.889888 -400.351498)
		(width 0.14224)
		(layer "In6.Cu")
		(net "P5E_CPU1_P0_TX_BUF_DN<8>")
	)
	(arc
		(start 64.889888 -400.351498)
		(mid 65.606198 -400.540284)
		(end 66.317622 -400.746722)
		(width 0.14224)
		(layer "In6.Cu")
		(net "P5E_CPU1_P0_TX_BUF_DN<8>")
	)
	(arc
		(start 67.692016 -401.164044)
		(mid 68.421367 -401.405296)
		(end 69.138038 -401.68195)
		(width 0.14224)
		(layer "In6.Cu")
		(net "P5E_CPU1_P0_TX_BUF_DN<8>")
	)
	(arc
		(start 72.495918 -403.072854)
		(mid 72.548427 -403.110745)
		(end 72.578468 -403.168104)
		(width 0.14224)
		(layer "In6.Cu")
		(net "P5E_CPU1_P0_TX_BUF_DN<8>")
	)
	(arc
		(start 57.843674 -395.693646)
		(mid 57.906666 -396.010329)
		(end 58.08599 -396.278862)
		(width 0.14224)
		(layer "In6.Cu")
		(net "P5E_CPU1_P0_TX_BUF_DN<8>")
	)
	(arc
		(start 57.44845 -390.086342)
		(mid 57.47602 -390.127464)
		(end 57.485788 -390.176004)
		(width 0.14224)
		(layer "In6.Cu")
		(net "P5E_CPU1_P0_TX_BUF_DN<8>")
	)
	(arc
		(start 57.485788 -390.304782)
		(mid 57.493476 -390.408895)
		(end 57.516268 -390.510776)
		(width 0.14224)
		(layer "In6.Cu")
		(net "P5E_CPU1_P0_TX_BUF_DN<8>")
	)
	(arc
		(start 72.578468 -403.168104)
		(mid 72.587778 -403.216862)
		(end 72.590914 -403.266402)
		(width 0.14224)
		(layer "In6.Cu")
		(net "P5E_CPU1_P0_TX_BUF_DN<8>")
	)
	(arc
		(start 60.722256 -398.915128)
		(mid 61.466746 -399.467367)
		(end 62.339474 -399.779744)
		(width 0.14224)
		(layer "In6.Cu")
		(net "P5E_CPU1_P0_TX_BUF_DN<8>")
	)
	(arc
		(start 57.125108 -389.520176)
		(mid 57.169732 -389.744517)
		(end 57.296812 -389.934704)
		(width 0.14224)
		(layer "In6.Cu")
		(net "P5E_CPU1_P0_TX_BUF_DN<8>")
	)
	(arc
		(start 63.566548 -400.023584)
		(mid 63.634554 -400.037988)
		(end 63.702184 -400.054064)
		(width 0.14224)
		(layer "In6.Cu")
		(net "P5E_CPU1_P0_TX_BUF_DN<8>")
	)
	(arc
		(start 57.825132 -391.53084)
		(mid 57.838998 -391.592514)
		(end 57.843674 -391.655554)
		(width 0.14224)
		(layer "In6.Cu")
		(net "P5E_CPU1_P0_TX_BUF_DN<8>")
	)
	(segment
		(start 69.211444 -408.250644)
		(end 69.507354 -407.954734)
		(width 0.12954)
		(layer "F.Cu")
		(net "P5E_CPU1_P0_TX_BUF_DN<7>")
	)
	(segment
		(start 55.670704 -388.774432)
		(end 56.191404 -388.774432)
		(width 0.127)
		(layer "F.Cu")
		(net "P5E_CPU1_P0_TX_BUF_DN<7>")
	)
	(segment
		(start 69.507354 -404.73503)
		(end 69.236844 -404.46452)
		(width 0.12954)
		(layer "F.Cu")
		(net "P5E_CPU1_P0_TX_BUF_DN<7>")
	)
	(segment
		(start 69.507354 -407.954734)
		(end 69.507354 -404.73503)
		(width 0.12954)
		(layer "F.Cu")
		(net "P5E_CPU1_P0_TX_BUF_DN<7>")
	)
	(segment
		(start 67.33286 -402.243544)
		(end 69.215762 -402.842984)
		(width 0.14224)
		(layer "In6.Cu")
		(net "P5E_CPU1_P0_TX_BUF_DN<7>")
	)
	(segment
		(start 56.285892 -390.169146)
		(end 56.285892 -390.393428)
		(width 0.14224)
		(layer "In6.Cu")
		(net "P5E_CPU1_P0_TX_BUF_DN<7>")
	)
	(segment
		(start 62.083442 -400.67992)
		(end 64.187324 -401.24253)
		(width 0.14224)
		(layer "In6.Cu")
		(net "P5E_CPU1_P0_TX_BUF_DN<7>")
	)
	(segment
		(start 56.857646 -396.37462)
		(end 60.09894 -399.615914)
		(width 0.14224)
		(layer "In6.Cu")
		(net "P5E_CPU1_P0_TX_BUF_DN<7>")
	)
	(segment
		(start 56.316372 -390.600438)
		(end 56.65343 -391.71118)
		(width 0.14224)
		(layer "In6.Cu")
		(net "P5E_CPU1_P0_TX_BUF_DN<7>")
	)
	(segment
		(start 69.26707 -402.874226)
		(end 69.479414 -403.08657)
		(width 0.14224)
		(layer "In6.Cu")
		(net "P5E_CPU1_P0_TX_BUF_DN<7>")
	)
	(segment
		(start 56.243728 -388.826756)
		(end 56.243728 -389.019796)
		(width 0.14224)
		(layer "In6.Cu")
		(net "P5E_CPU1_P0_TX_BUF_DN<7>")
	)
	(segment
		(start 69.542914 -404.106888)
		(end 69.527674 -404.106888)
		(width 0.14224)
		(layer "In6.Cu")
		(net "P5E_CPU1_P0_TX_BUF_DN<7>")
	)
	(segment
		(start 56.671972 -391.835894)
		(end 56.671972 -395.926564)
		(width 0.14224)
		(layer "In6.Cu")
		(net "P5E_CPU1_P0_TX_BUF_DN<7>")
	)
	(segment
		(start 67.332606 -402.243544)
		(end 67.33286 -402.243544)
		(width 0.14224)
		(layer "In6.Cu")
		(net "P5E_CPU1_P0_TX_BUF_DN<7>")
	)
	(segment
		(start 64.187324 -401.24253)
		(end 67.332606 -402.243544)
		(width 0.14224)
		(layer "In6.Cu")
		(net "P5E_CPU1_P0_TX_BUF_DN<7>")
	)
	(segment
		(start 55.918354 -389.34517)
		(end 55.918354 -389.536686)
		(width 0.14224)
		(layer "In6.Cu")
		(net "P5E_CPU1_P0_TX_BUF_DN<7>")
	)
	(segment
		(start 56.191404 -388.774432)
		(end 56.243728 -388.826756)
		(width 0.14224)
		(layer "In6.Cu")
		(net "P5E_CPU1_P0_TX_BUF_DN<7>")
	)
	(segment
		(start 69.48043 -404.220934)
		(end 69.236844 -404.46452)
		(width 0.14224)
		(layer "In6.Cu")
		(net "P5E_CPU1_P0_TX_BUF_DN<7>")
	)
	(segment
		(start 69.542914 -403.239986)
		(end 69.542914 -404.106888)
		(width 0.14224)
		(layer "In6.Cu")
		(net "P5E_CPU1_P0_TX_BUF_DN<7>")
	)
	(segment
		(start 56.058308 -389.87476)
		(end 56.238648 -390.0551)
		(width 0.14224)
		(layer "In6.Cu")
		(net "P5E_CPU1_P0_TX_BUF_DN<7>")
	)
	(segment
		(start 56.243728 -389.019796)
		(end 55.918354 -389.34517)
		(width 0.14224)
		(layer "In6.Cu")
		(net "P5E_CPU1_P0_TX_BUF_DN<7>")
	)
	(arc
		(start 69.527674 -404.106888)
		(mid 69.515397 -404.168611)
		(end 69.48043 -404.220934)
		(width 0.14224)
		(layer "In6.Cu")
		(net "P5E_CPU1_P0_TX_BUF_DN<7>")
	)
	(arc
		(start 56.65343 -391.71118)
		(mid 56.667284 -391.772854)
		(end 56.671972 -391.835894)
		(width 0.14224)
		(layer "In6.Cu")
		(net "P5E_CPU1_P0_TX_BUF_DN<7>")
	)
	(arc
		(start 69.479414 -403.08657)
		(mid 69.526392 -403.156972)
		(end 69.542914 -403.239986)
		(width 0.14224)
		(layer "In6.Cu")
		(net "P5E_CPU1_P0_TX_BUF_DN<7>")
	)
	(arc
		(start 69.215762 -402.842984)
		(mid 69.243287 -402.855532)
		(end 69.26707 -402.874226)
		(width 0.14224)
		(layer "In6.Cu")
		(net "P5E_CPU1_P0_TX_BUF_DN<7>")
	)
	(arc
		(start 56.671972 -395.926564)
		(mid 56.720227 -396.169068)
		(end 56.857646 -396.37462)
		(width 0.14224)
		(layer "In6.Cu")
		(net "P5E_CPU1_P0_TX_BUF_DN<7>")
	)
	(arc
		(start 55.918354 -389.536686)
		(mid 55.954742 -389.719619)
		(end 56.058308 -389.87476)
		(width 0.14224)
		(layer "In6.Cu")
		(net "P5E_CPU1_P0_TX_BUF_DN<7>")
	)
	(arc
		(start 56.285892 -390.393428)
		(mid 56.293474 -390.498061)
		(end 56.316372 -390.600438)
		(width 0.14224)
		(layer "In6.Cu")
		(net "P5E_CPU1_P0_TX_BUF_DN<7>")
	)
	(arc
		(start 56.238648 -390.0551)
		(mid 56.27361 -390.107425)
		(end 56.285892 -390.169146)
		(width 0.14224)
		(layer "In6.Cu")
		(net "P5E_CPU1_P0_TX_BUF_DN<7>")
	)
	(arc
		(start 60.09894 -399.615914)
		(mid 61.012595 -400.294521)
		(end 62.083442 -400.67992)
		(width 0.14224)
		(layer "In6.Cu")
		(net "P5E_CPU1_P0_TX_BUF_DN<7>")
	)
	(segment
		(start 66.444114 -404.73503)
		(end 66.173604 -404.46452)
		(width 0.12954)
		(layer "F.Cu")
		(net "P5E_CPU1_P0_TX_BUF_DN<6>")
	)
	(segment
		(start 54.470554 -388.774432)
		(end 54.991254 -388.774432)
		(width 0.127)
		(layer "F.Cu")
		(net "P5E_CPU1_P0_TX_BUF_DN<6>")
	)
	(segment
		(start 66.148204 -408.250644)
		(end 66.444114 -407.954734)
		(width 0.12954)
		(layer "F.Cu")
		(net "P5E_CPU1_P0_TX_BUF_DN<6>")
	)
	(segment
		(start 66.444114 -407.954734)
		(end 66.444114 -404.73503)
		(width 0.12954)
		(layer "F.Cu")
		(net "P5E_CPU1_P0_TX_BUF_DN<6>")
	)
	(segment
		(start 55.043578 -389.006588)
		(end 54.725062 -389.325104)
		(width 0.14224)
		(layer "In6.Cu")
		(net "P5E_CPU1_P0_TX_BUF_DN<6>")
	)
	(segment
		(start 55.110126 -390.600692)
		(end 55.45328 -391.731754)
		(width 0.14224)
		(layer "In6.Cu")
		(net "P5E_CPU1_P0_TX_BUF_DN<6>")
	)
	(segment
		(start 55.471822 -391.856468)
		(end 55.471822 -395.893798)
		(width 0.14224)
		(layer "In6.Cu")
		(net "P5E_CPU1_P0_TX_BUF_DN<6>")
	)
	(segment
		(start 66.464434 -403.514052)
		(end 66.464434 -404.17369)
		(width 0.14224)
		(layer "In6.Cu")
		(net "P5E_CPU1_P0_TX_BUF_DN<6>")
	)
	(segment
		(start 54.725062 -389.325104)
		(end 54.725062 -389.46201)
		(width 0.14224)
		(layer "In6.Cu")
		(net "P5E_CPU1_P0_TX_BUF_DN<6>")
	)
	(segment
		(start 55.085742 -390.190736)
		(end 55.085742 -390.436354)
		(width 0.14224)
		(layer "In6.Cu")
		(net "P5E_CPU1_P0_TX_BUF_DN<6>")
	)
	(segment
		(start 55.828692 -396.755366)
		(end 59.222386 -400.14906)
		(width 0.14224)
		(layer "In6.Cu")
		(net "P5E_CPU1_P0_TX_BUF_DN<6>")
	)
	(segment
		(start 66.464434 -404.17369)
		(end 66.173604 -404.46452)
		(width 0.14224)
		(layer "In6.Cu")
		(net "P5E_CPU1_P0_TX_BUF_DN<6>")
	)
	(segment
		(start 54.991254 -388.774432)
		(end 55.043578 -388.826756)
		(width 0.14224)
		(layer "In6.Cu")
		(net "P5E_CPU1_P0_TX_BUF_DN<6>")
	)
	(segment
		(start 55.043578 -388.826756)
		(end 55.043578 -389.006588)
		(width 0.14224)
		(layer "In6.Cu")
		(net "P5E_CPU1_P0_TX_BUF_DN<6>")
	)
	(segment
		(start 61.827664 -401.625054)
		(end 62.735968 -401.852892)
		(width 0.14224)
		(layer "In6.Cu")
		(net "P5E_CPU1_P0_TX_BUF_DN<6>")
	)
	(segment
		(start 54.938168 -389.97636)
		(end 55.038498 -390.07669)
		(width 0.14224)
		(layer "In6.Cu")
		(net "P5E_CPU1_P0_TX_BUF_DN<6>")
	)
	(segment
		(start 62.735968 -401.852892)
		(end 66.306954 -403.281642)
		(width 0.14224)
		(layer "In6.Cu")
		(net "P5E_CPU1_P0_TX_BUF_DN<6>")
	)
	(arc
		(start 55.471822 -395.893798)
		(mid 55.56457 -396.360074)
		(end 55.828692 -396.755366)
		(width 0.14224)
		(layer "In6.Cu")
		(net "P5E_CPU1_P0_TX_BUF_DN<6>")
	)
	(arc
		(start 55.038498 -390.07669)
		(mid 55.07346 -390.129015)
		(end 55.085742 -390.190736)
		(width 0.14224)
		(layer "In6.Cu")
		(net "P5E_CPU1_P0_TX_BUF_DN<6>")
	)
	(arc
		(start 55.085742 -390.436354)
		(mid 55.091872 -390.519422)
		(end 55.110126 -390.600692)
		(width 0.14224)
		(layer "In6.Cu")
		(net "P5E_CPU1_P0_TX_BUF_DN<6>")
	)
	(arc
		(start 54.725062 -389.46201)
		(mid 54.780451 -389.740381)
		(end 54.938168 -389.97636)
		(width 0.14224)
		(layer "In6.Cu")
		(net "P5E_CPU1_P0_TX_BUF_DN<6>")
	)
	(arc
		(start 59.222386 -400.14906)
		(mid 60.424816 -401.06394)
		(end 61.827664 -401.625054)
		(width 0.14224)
		(layer "In6.Cu")
		(net "P5E_CPU1_P0_TX_BUF_DN<6>")
	)
	(arc
		(start 66.306954 -403.281642)
		(mid 66.421376 -403.373674)
		(end 66.464434 -403.514052)
		(width 0.14224)
		(layer "In6.Cu")
		(net "P5E_CPU1_P0_TX_BUF_DN<6>")
	)
	(arc
		(start 55.45328 -391.731754)
		(mid 55.467163 -391.793426)
		(end 55.471822 -391.856468)
		(width 0.14224)
		(layer "In6.Cu")
		(net "P5E_CPU1_P0_TX_BUF_DN<6>")
	)
	(segment
		(start 63.380874 -404.73503)
		(end 63.110364 -404.46452)
		(width 0.12954)
		(layer "F.Cu")
		(net "P5E_CPU1_P0_TX_BUF_DN<5>")
	)
	(segment
		(start 53.270658 -388.774432)
		(end 53.791358 -388.774432)
		(width 0.127)
		(layer "F.Cu")
		(net "P5E_CPU1_P0_TX_BUF_DN<5>")
	)
	(segment
		(start 63.084964 -408.250644)
		(end 63.380874 -407.954734)
		(width 0.12954)
		(layer "F.Cu")
		(net "P5E_CPU1_P0_TX_BUF_DN<5>")
	)
	(segment
		(start 63.380874 -407.954734)
		(end 63.380874 -404.73503)
		(width 0.12954)
		(layer "F.Cu")
		(net "P5E_CPU1_P0_TX_BUF_DN<5>")
	)
	(segment
		(start 53.930296 -390.283446)
		(end 53.930296 -390.532366)
		(width 0.14224)
		(layer "In6.Cu")
		(net "P5E_CPU1_P0_TX_BUF_DN<5>")
	)
	(segment
		(start 53.525166 -389.325104)
		(end 53.525166 -389.473186)
		(width 0.14224)
		(layer "In6.Cu")
		(net "P5E_CPU1_P0_TX_BUF_DN<5>")
	)
	(segment
		(start 63.401194 -403.504908)
		(end 63.401194 -404.17369)
		(width 0.14224)
		(layer "In6.Cu")
		(net "P5E_CPU1_P0_TX_BUF_DN<5>")
	)
	(segment
		(start 53.843682 -389.006588)
		(end 53.525166 -389.325104)
		(width 0.14224)
		(layer "In6.Cu")
		(net "P5E_CPU1_P0_TX_BUF_DN<5>")
	)
	(segment
		(start 53.730144 -389.967978)
		(end 53.848508 -390.086088)
		(width 0.14224)
		(layer "In6.Cu")
		(net "P5E_CPU1_P0_TX_BUF_DN<5>")
	)
	(segment
		(start 53.960776 -390.738614)
		(end 54.271926 -391.765282)
		(width 0.14224)
		(layer "In6.Cu")
		(net "P5E_CPU1_P0_TX_BUF_DN<5>")
	)
	(segment
		(start 63.135256 -403.172168)
		(end 63.35395 -403.390862)
		(width 0.14224)
		(layer "In6.Cu")
		(net "P5E_CPU1_P0_TX_BUF_DN<5>")
	)
	(segment
		(start 63.401194 -404.17369)
		(end 63.110364 -404.46452)
		(width 0.14224)
		(layer "In6.Cu")
		(net "P5E_CPU1_P0_TX_BUF_DN<5>")
	)
	(segment
		(start 53.791358 -388.774432)
		(end 53.843682 -388.826756)
		(width 0.14224)
		(layer "In6.Cu")
		(net "P5E_CPU1_P0_TX_BUF_DN<5>")
	)
	(segment
		(start 54.748684 -397.190468)
		(end 58.915046 -401.35683)
		(width 0.14224)
		(layer "In6.Cu")
		(net "P5E_CPU1_P0_TX_BUF_DN<5>")
	)
	(segment
		(start 53.843682 -388.826756)
		(end 53.843682 -389.006588)
		(width 0.14224)
		(layer "In6.Cu")
		(net "P5E_CPU1_P0_TX_BUF_DN<5>")
	)
	(segment
		(start 61.224922 -402.500084)
		(end 62.265814 -402.707094)
		(width 0.14224)
		(layer "In6.Cu")
		(net "P5E_CPU1_P0_TX_BUF_DN<5>")
	)
	(segment
		(start 54.271926 -391.765282)
		(end 54.271926 -396.03934)
		(width 0.14224)
		(layer "In6.Cu")
		(net "P5E_CPU1_P0_TX_BUF_DN<5>")
	)
	(segment
		(start 60.35929 -402.234908)
		(end 61.07176 -402.46046)
		(width 0.14224)
		(layer "In6.Cu")
		(net "P5E_CPU1_P0_TX_BUF_DN<5>")
	)
	(arc
		(start 63.35395 -403.390862)
		(mid 63.388912 -403.443187)
		(end 63.401194 -403.504908)
		(width 0.14224)
		(layer "In6.Cu")
		(net "P5E_CPU1_P0_TX_BUF_DN<5>")
	)
	(arc
		(start 53.525166 -389.473186)
		(mid 53.578433 -389.740976)
		(end 53.730144 -389.967978)
		(width 0.14224)
		(layer "In6.Cu")
		(net "P5E_CPU1_P0_TX_BUF_DN<5>")
	)
	(arc
		(start 61.07176 -402.46046)
		(mid 61.147791 -402.482396)
		(end 61.224922 -402.500084)
		(width 0.14224)
		(layer "In6.Cu")
		(net "P5E_CPU1_P0_TX_BUF_DN<5>")
	)
	(arc
		(start 54.271926 -396.03934)
		(mid 54.395826 -396.662319)
		(end 54.748684 -397.190468)
		(width 0.14224)
		(layer "In6.Cu")
		(net "P5E_CPU1_P0_TX_BUF_DN<5>")
	)
	(arc
		(start 62.265814 -402.707094)
		(mid 62.735033 -402.875131)
		(end 63.135256 -403.172168)
		(width 0.14224)
		(layer "In6.Cu")
		(net "P5E_CPU1_P0_TX_BUF_DN<5>")
	)
	(arc
		(start 53.848508 -390.086088)
		(mid 53.909035 -390.176623)
		(end 53.930296 -390.283446)
		(width 0.14224)
		(layer "In6.Cu")
		(net "P5E_CPU1_P0_TX_BUF_DN<5>")
	)
	(arc
		(start 53.930296 -390.532366)
		(mid 53.937966 -390.636607)
		(end 53.960776 -390.738614)
		(width 0.14224)
		(layer "In6.Cu")
		(net "P5E_CPU1_P0_TX_BUF_DN<5>")
	)
	(arc
		(start 58.915046 -401.35683)
		(mid 59.584387 -401.882684)
		(end 60.35929 -402.234908)
		(width 0.14224)
		(layer "In6.Cu")
		(net "P5E_CPU1_P0_TX_BUF_DN<5>")
	)
	(segment
		(start 52.070508 -388.774432)
		(end 52.591208 -388.774432)
		(width 0.127)
		(layer "F.Cu")
		(net "P5E_CPU1_P0_TX_BUF_DN<4>")
	)
	(segment
		(start 60.317634 -404.73503)
		(end 60.047124 -404.46452)
		(width 0.12954)
		(layer "F.Cu")
		(net "P5E_CPU1_P0_TX_BUF_DN<4>")
	)
	(segment
		(start 60.317634 -407.954734)
		(end 60.317634 -404.73503)
		(width 0.12954)
		(layer "F.Cu")
		(net "P5E_CPU1_P0_TX_BUF_DN<4>")
	)
	(segment
		(start 60.021724 -408.250644)
		(end 60.317634 -407.954734)
		(width 0.12954)
		(layer "F.Cu")
		(net "P5E_CPU1_P0_TX_BUF_DN<4>")
	)
	(segment
		(start 52.591208 -388.774432)
		(end 52.643532 -388.826756)
		(width 0.14224)
		(layer "In6.Cu")
		(net "P5E_CPU1_P0_TX_BUF_DN<4>")
	)
	(segment
		(start 52.643532 -388.826756)
		(end 52.643532 -389.006588)
		(width 0.14224)
		(layer "In6.Cu")
		(net "P5E_CPU1_P0_TX_BUF_DN<4>")
	)
	(segment
		(start 53.514752 -397.472154)
		(end 58.864754 -402.822156)
		(width 0.14224)
		(layer "In6.Cu")
		(net "P5E_CPU1_P0_TX_BUF_DN<4>")
	)
	(segment
		(start 53.071776 -391.921746)
		(end 53.071776 -396.40256)
		(width 0.14224)
		(layer "In6.Cu")
		(net "P5E_CPU1_P0_TX_BUF_DN<4>")
	)
	(segment
		(start 60.337954 -404.17369)
		(end 60.047124 -404.46452)
		(width 0.14224)
		(layer "In6.Cu")
		(net "P5E_CPU1_P0_TX_BUF_DN<4>")
	)
	(segment
		(start 52.548536 -389.98652)
		(end 52.648612 -390.086596)
		(width 0.14224)
		(layer "In6.Cu")
		(net "P5E_CPU1_P0_TX_BUF_DN<4>")
	)
	(segment
		(start 52.748688 -390.855708)
		(end 53.071776 -391.921746)
		(width 0.14224)
		(layer "In6.Cu")
		(net "P5E_CPU1_P0_TX_BUF_DN<4>")
	)
	(segment
		(start 59.78398 -403.202902)
		(end 59.838336 -403.202902)
		(width 0.14224)
		(layer "In6.Cu")
		(net "P5E_CPU1_P0_TX_BUF_DN<4>")
	)
	(segment
		(start 52.68595 -390.176512)
		(end 52.68595 -390.430004)
		(width 0.14224)
		(layer "In6.Cu")
		(net "P5E_CPU1_P0_TX_BUF_DN<4>")
	)
	(segment
		(start 52.325016 -389.325104)
		(end 52.325016 -389.44677)
		(width 0.14224)
		(layer "In6.Cu")
		(net "P5E_CPU1_P0_TX_BUF_DN<4>")
	)
	(segment
		(start 60.337954 -403.711918)
		(end 60.337954 -404.17369)
		(width 0.14224)
		(layer "In6.Cu")
		(net "P5E_CPU1_P0_TX_BUF_DN<4>")
	)
	(segment
		(start 52.643532 -389.006588)
		(end 52.325016 -389.325104)
		(width 0.14224)
		(layer "In6.Cu")
		(net "P5E_CPU1_P0_TX_BUF_DN<4>")
	)
	(arc
		(start 58.864754 -402.822156)
		(mid 59.286498 -403.103957)
		(end 59.78398 -403.202902)
		(width 0.14224)
		(layer "In6.Cu")
		(net "P5E_CPU1_P0_TX_BUF_DN<4>")
	)
	(arc
		(start 53.071776 -396.40256)
		(mid 53.186899 -396.98141)
		(end 53.514752 -397.472154)
		(width 0.14224)
		(layer "In6.Cu")
		(net "P5E_CPU1_P0_TX_BUF_DN<4>")
	)
	(arc
		(start 60.328048 -403.656546)
		(mid 60.33544 -403.683796)
		(end 60.337954 -403.711918)
		(width 0.14224)
		(layer "In6.Cu")
		(net "P5E_CPU1_P0_TX_BUF_DN<4>")
	)
	(arc
		(start 52.325016 -389.44677)
		(mid 52.383101 -389.738875)
		(end 52.548536 -389.98652)
		(width 0.14224)
		(layer "In6.Cu")
		(net "P5E_CPU1_P0_TX_BUF_DN<4>")
	)
	(arc
		(start 60.109862 -403.315424)
		(mid 60.237512 -403.474116)
		(end 60.328048 -403.656546)
		(width 0.14224)
		(layer "In6.Cu")
		(net "P5E_CPU1_P0_TX_BUF_DN<4>")
	)
	(arc
		(start 52.68595 -390.430004)
		(mid 52.701605 -390.645172)
		(end 52.748688 -390.855708)
		(width 0.14224)
		(layer "In6.Cu")
		(net "P5E_CPU1_P0_TX_BUF_DN<4>")
	)
	(arc
		(start 52.648612 -390.086596)
		(mid 52.676231 -390.127836)
		(end 52.68595 -390.176512)
		(width 0.14224)
		(layer "In6.Cu")
		(net "P5E_CPU1_P0_TX_BUF_DN<4>")
	)
	(arc
		(start 59.838336 -403.202902)
		(mid 59.985291 -403.232151)
		(end 60.109862 -403.315424)
		(width 0.14224)
		(layer "In6.Cu")
		(net "P5E_CPU1_P0_TX_BUF_DN<4>")
	)
	(segment
		(start 56.958484 -408.250644)
		(end 57.254394 -407.954734)
		(width 0.12954)
		(layer "F.Cu")
		(net "P5E_CPU1_P0_TX_BUF_DN<3>")
	)
	(segment
		(start 57.254394 -407.954734)
		(end 57.254394 -404.73503)
		(width 0.12954)
		(layer "F.Cu")
		(net "P5E_CPU1_P0_TX_BUF_DN<3>")
	)
	(segment
		(start 57.254394 -404.73503)
		(end 56.983884 -404.46452)
		(width 0.12954)
		(layer "F.Cu")
		(net "P5E_CPU1_P0_TX_BUF_DN<3>")
	)
	(segment
		(start 50.870612 -388.774432)
		(end 51.391312 -388.774432)
		(width 0.127)
		(layer "F.Cu")
		(net "P5E_CPU1_P0_TX_BUF_DN<3>")
	)
	(segment
		(start 57.274714 -404.17369)
		(end 56.983884 -404.46452)
		(width 0.14224)
		(layer "In6.Cu")
		(net "P5E_CPU1_P0_TX_BUF_DN<3>")
	)
	(segment
		(start 51.443636 -388.826756)
		(end 51.443636 -389.006588)
		(width 0.14224)
		(layer "In6.Cu")
		(net "P5E_CPU1_P0_TX_BUF_DN<3>")
	)
	(segment
		(start 51.50358 -390.54405)
		(end 51.853338 -391.698734)
		(width 0.14224)
		(layer "In6.Cu")
		(net "P5E_CPU1_P0_TX_BUF_DN<3>")
	)
	(segment
		(start 52.201826 -397.480536)
		(end 57.22747 -402.50618)
		(width 0.14224)
		(layer "In6.Cu")
		(net "P5E_CPU1_P0_TX_BUF_DN<3>")
	)
	(segment
		(start 51.12512 -389.325104)
		(end 51.12512 -389.46455)
		(width 0.14224)
		(layer "In6.Cu")
		(net "P5E_CPU1_P0_TX_BUF_DN<3>")
	)
	(segment
		(start 51.87188 -391.822178)
		(end 51.87188 -396.130272)
		(width 0.14224)
		(layer "In6.Cu")
		(net "P5E_CPU1_P0_TX_BUF_DN<3>")
	)
	(segment
		(start 51.87188 -396.130272)
		(end 51.871626 -396.683992)
		(width 0.14224)
		(layer "In6.Cu")
		(net "P5E_CPU1_P0_TX_BUF_DN<3>")
	)
	(segment
		(start 51.4858 -390.176512)
		(end 51.4858 -390.425178)
		(width 0.14224)
		(layer "In6.Cu")
		(net "P5E_CPU1_P0_TX_BUF_DN<3>")
	)
	(segment
		(start 51.336194 -389.974074)
		(end 51.448462 -390.086342)
		(width 0.14224)
		(layer "In6.Cu")
		(net "P5E_CPU1_P0_TX_BUF_DN<3>")
	)
	(segment
		(start 51.391312 -388.774432)
		(end 51.443636 -388.826756)
		(width 0.14224)
		(layer "In6.Cu")
		(net "P5E_CPU1_P0_TX_BUF_DN<3>")
	)
	(segment
		(start 51.443636 -389.006588)
		(end 51.12512 -389.325104)
		(width 0.14224)
		(layer "In6.Cu")
		(net "P5E_CPU1_P0_TX_BUF_DN<3>")
	)
	(segment
		(start 57.274714 -402.620226)
		(end 57.274714 -404.17369)
		(width 0.14224)
		(layer "In6.Cu")
		(net "P5E_CPU1_P0_TX_BUF_DN<3>")
	)
	(arc
		(start 51.448462 -390.086342)
		(mid 51.476105 -390.127712)
		(end 51.4858 -390.176512)
		(width 0.14224)
		(layer "In6.Cu")
		(net "P5E_CPU1_P0_TX_BUF_DN<3>")
	)
	(arc
		(start 51.12512 -389.46455)
		(mid 51.179972 -389.740311)
		(end 51.336194 -389.974074)
		(width 0.14224)
		(layer "In6.Cu")
		(net "P5E_CPU1_P0_TX_BUF_DN<3>")
	)
	(arc
		(start 51.871626 -396.683992)
		(mid 51.957492 -397.11511)
		(end 52.201826 -397.480536)
		(width 0.14224)
		(layer "In6.Cu")
		(net "P5E_CPU1_P0_TX_BUF_DN<3>")
	)
	(arc
		(start 57.22747 -402.50618)
		(mid 57.262432 -402.558505)
		(end 57.274714 -402.620226)
		(width 0.14224)
		(layer "In6.Cu")
		(net "P5E_CPU1_P0_TX_BUF_DN<3>")
	)
	(arc
		(start 51.4858 -390.425178)
		(mid 51.490306 -390.48527)
		(end 51.50358 -390.54405)
		(width 0.14224)
		(layer "In6.Cu")
		(net "P5E_CPU1_P0_TX_BUF_DN<3>")
	)
	(arc
		(start 51.853338 -391.698734)
		(mid 51.867162 -391.759771)
		(end 51.87188 -391.822178)
		(width 0.14224)
		(layer "In6.Cu")
		(net "P5E_CPU1_P0_TX_BUF_DN<3>")
	)
	(segment
		(start 49.670716 -388.774432)
		(end 50.191416 -388.774432)
		(width 0.127)
		(layer "F.Cu")
		(net "P5E_CPU1_P0_TX_BUF_DN<2>")
	)
	(segment
		(start 54.191154 -407.954734)
		(end 54.191154 -404.73503)
		(width 0.12954)
		(layer "F.Cu")
		(net "P5E_CPU1_P0_TX_BUF_DN<2>")
	)
	(segment
		(start 53.895244 -408.250644)
		(end 54.191154 -407.954734)
		(width 0.12954)
		(layer "F.Cu")
		(net "P5E_CPU1_P0_TX_BUF_DN<2>")
	)
	(segment
		(start 54.191154 -404.73503)
		(end 53.920644 -404.46452)
		(width 0.12954)
		(layer "F.Cu")
		(net "P5E_CPU1_P0_TX_BUF_DN<2>")
	)
	(segment
		(start 50.28565 -390.190736)
		(end 50.28565 -390.43356)
		(width 0.14224)
		(layer "In6.Cu")
		(net "P5E_CPU1_P0_TX_BUF_DN<2>")
	)
	(segment
		(start 50.671984 -392.019028)
		(end 50.671984 -396.697454)
		(width 0.14224)
		(layer "In6.Cu")
		(net "P5E_CPU1_P0_TX_BUF_DN<2>")
	)
	(segment
		(start 50.24374 -388.826756)
		(end 50.24374 -389.030972)
		(width 0.14224)
		(layer "In6.Cu")
		(net "P5E_CPU1_P0_TX_BUF_DN<2>")
	)
	(segment
		(start 54.211474 -404.17369)
		(end 53.920644 -404.46452)
		(width 0.14224)
		(layer "In6.Cu")
		(net "P5E_CPU1_P0_TX_BUF_DN<2>")
	)
	(segment
		(start 50.093118 -389.931402)
		(end 50.238406 -390.07669)
		(width 0.14224)
		(layer "In6.Cu")
		(net "P5E_CPU1_P0_TX_BUF_DN<2>")
	)
	(segment
		(start 50.24374 -389.030972)
		(end 49.92497 -389.349742)
		(width 0.14224)
		(layer "In6.Cu")
		(net "P5E_CPU1_P0_TX_BUF_DN<2>")
	)
	(segment
		(start 50.935636 -397.434308)
		(end 53.942234 -401.098004)
		(width 0.14224)
		(layer "In6.Cu")
		(net "P5E_CPU1_P0_TX_BUF_DN<2>")
	)
	(segment
		(start 50.31613 -390.639808)
		(end 50.61204 -391.616438)
		(width 0.14224)
		(layer "In6.Cu")
		(net "P5E_CPU1_P0_TX_BUF_DN<2>")
	)
	(segment
		(start 49.92497 -389.349742)
		(end 49.92497 -389.52551)
		(width 0.14224)
		(layer "In6.Cu")
		(net "P5E_CPU1_P0_TX_BUF_DN<2>")
	)
	(segment
		(start 54.211474 -401.850098)
		(end 54.211474 -404.17369)
		(width 0.14224)
		(layer "In6.Cu")
		(net "P5E_CPU1_P0_TX_BUF_DN<2>")
	)
	(segment
		(start 50.191416 -388.774432)
		(end 50.24374 -388.826756)
		(width 0.14224)
		(layer "In6.Cu")
		(net "P5E_CPU1_P0_TX_BUF_DN<2>")
	)
	(arc
		(start 49.92497 -389.52551)
		(mid 49.968666 -389.745186)
		(end 50.093118 -389.931402)
		(width 0.14224)
		(layer "In6.Cu")
		(net "P5E_CPU1_P0_TX_BUF_DN<2>")
	)
	(arc
		(start 50.238406 -390.07669)
		(mid 50.273368 -390.129015)
		(end 50.28565 -390.190736)
		(width 0.14224)
		(layer "In6.Cu")
		(net "P5E_CPU1_P0_TX_BUF_DN<2>")
	)
	(arc
		(start 50.671984 -396.697454)
		(mid 50.73988 -397.088757)
		(end 50.935636 -397.434308)
		(width 0.14224)
		(layer "In6.Cu")
		(net "P5E_CPU1_P0_TX_BUF_DN<2>")
	)
	(arc
		(start 50.61204 -391.616438)
		(mid 50.656824 -391.815528)
		(end 50.671984 -392.019028)
		(width 0.14224)
		(layer "In6.Cu")
		(net "P5E_CPU1_P0_TX_BUF_DN<2>")
	)
	(arc
		(start 50.28565 -390.43356)
		(mid 50.29332 -390.537801)
		(end 50.31613 -390.639808)
		(width 0.14224)
		(layer "In6.Cu")
		(net "P5E_CPU1_P0_TX_BUF_DN<2>")
	)
	(arc
		(start 53.942234 -401.098004)
		(mid 54.142112 -401.450692)
		(end 54.211474 -401.850098)
		(width 0.14224)
		(layer "In6.Cu")
		(net "P5E_CPU1_P0_TX_BUF_DN<2>")
	)
	(segment
		(start 51.127914 -404.73503)
		(end 50.857404 -404.46452)
		(width 0.12954)
		(layer "F.Cu")
		(net "P5E_CPU1_P0_TX_BUF_DN<1>")
	)
	(segment
		(start 51.127914 -407.954734)
		(end 51.127914 -404.73503)
		(width 0.12954)
		(layer "F.Cu")
		(net "P5E_CPU1_P0_TX_BUF_DN<1>")
	)
	(segment
		(start 50.832004 -408.250644)
		(end 51.127914 -407.954734)
		(width 0.12954)
		(layer "F.Cu")
		(net "P5E_CPU1_P0_TX_BUF_DN<1>")
	)
	(segment
		(start 48.470566 -388.774432)
		(end 48.991266 -388.774432)
		(width 0.127)
		(layer "F.Cu")
		(net "P5E_CPU1_P0_TX_BUF_DN<1>")
	)
	(segment
		(start 51.148234 -400.447002)
		(end 51.148234 -404.17369)
		(width 0.14224)
		(layer "In6.Cu")
		(net "P5E_CPU1_P0_TX_BUF_DN<1>")
	)
	(segment
		(start 49.04359 -389.006588)
		(end 48.725074 -389.325104)
		(width 0.14224)
		(layer "In6.Cu")
		(net "P5E_CPU1_P0_TX_BUF_DN<1>")
	)
	(segment
		(start 48.900842 -389.938768)
		(end 49.048416 -390.086088)
		(width 0.14224)
		(layer "In6.Cu")
		(net "P5E_CPU1_P0_TX_BUF_DN<1>")
	)
	(segment
		(start 48.991266 -388.774432)
		(end 49.04359 -388.826756)
		(width 0.14224)
		(layer "In6.Cu")
		(net "P5E_CPU1_P0_TX_BUF_DN<1>")
	)
	(segment
		(start 49.10328 -390.218422)
		(end 49.10328 -390.562846)
		(width 0.14224)
		(layer "In6.Cu")
		(net "P5E_CPU1_P0_TX_BUF_DN<1>")
	)
	(segment
		(start 49.59223 -397.129)
		(end 51.136042 -400.3929)
		(width 0.14224)
		(layer "In6.Cu")
		(net "P5E_CPU1_P0_TX_BUF_DN<1>")
	)
	(segment
		(start 51.136042 -400.3929)
		(end 51.136042 -400.392646)
		(width 0.14224)
		(layer "In6.Cu")
		(net "P5E_CPU1_P0_TX_BUF_DN<1>")
	)
	(segment
		(start 51.148234 -404.17369)
		(end 50.857404 -404.46452)
		(width 0.14224)
		(layer "In6.Cu")
		(net "P5E_CPU1_P0_TX_BUF_DN<1>")
	)
	(segment
		(start 49.04359 -388.826756)
		(end 49.04359 -389.006588)
		(width 0.14224)
		(layer "In6.Cu")
		(net "P5E_CPU1_P0_TX_BUF_DN<1>")
	)
	(segment
		(start 49.139602 -390.779254)
		(end 49.45126 -391.680192)
		(width 0.14224)
		(layer "In6.Cu")
		(net "P5E_CPU1_P0_TX_BUF_DN<1>")
	)
	(segment
		(start 49.472088 -391.804652)
		(end 49.472088 -396.593822)
		(width 0.14224)
		(layer "In6.Cu")
		(net "P5E_CPU1_P0_TX_BUF_DN<1>")
	)
	(segment
		(start 48.725074 -389.325104)
		(end 48.725074 -389.514334)
		(width 0.14224)
		(layer "In6.Cu")
		(net "P5E_CPU1_P0_TX_BUF_DN<1>")
	)
	(arc
		(start 49.472088 -396.593822)
		(mid 49.502495 -396.86807)
		(end 49.59223 -397.129)
		(width 0.14224)
		(layer "In6.Cu")
		(net "P5E_CPU1_P0_TX_BUF_DN<1>")
	)
	(arc
		(start 49.048416 -390.086088)
		(mid 49.089038 -390.146789)
		(end 49.10328 -390.218422)
		(width 0.14224)
		(layer "In6.Cu")
		(net "P5E_CPU1_P0_TX_BUF_DN<1>")
	)
	(arc
		(start 48.725074 -389.514334)
		(mid 48.770747 -389.744036)
		(end 48.900842 -389.938768)
		(width 0.14224)
		(layer "In6.Cu")
		(net "P5E_CPU1_P0_TX_BUF_DN<1>")
	)
	(arc
		(start 51.136042 -400.392646)
		(mid 51.145149 -400.419149)
		(end 51.148234 -400.447002)
		(width 0.14224)
		(layer "In6.Cu")
		(net "P5E_CPU1_P0_TX_BUF_DN<1>")
	)
	(arc
		(start 49.10328 -390.562846)
		(mid 49.112398 -390.672569)
		(end 49.139602 -390.779254)
		(width 0.14224)
		(layer "In6.Cu")
		(net "P5E_CPU1_P0_TX_BUF_DN<1>")
	)
	(arc
		(start 49.45126 -391.680192)
		(mid 49.466887 -391.741551)
		(end 49.472088 -391.804652)
		(width 0.14224)
		(layer "In6.Cu")
		(net "P5E_CPU1_P0_TX_BUF_DN<1>")
	)
	(segment
		(start 94.013274 -407.954734)
		(end 94.013274 -404.73503)
		(width 0.12954)
		(layer "F.Cu")
		(net "P5E_CPU1_P0_TX_BUF_DN<15>")
	)
	(segment
		(start 93.717364 -408.250644)
		(end 94.013274 -407.954734)
		(width 0.12954)
		(layer "F.Cu")
		(net "P5E_CPU1_P0_TX_BUF_DN<15>")
	)
	(segment
		(start 94.013274 -404.73503)
		(end 93.742764 -404.46452)
		(width 0.12954)
		(layer "F.Cu")
		(net "P5E_CPU1_P0_TX_BUF_DN<15>")
	)
	(segment
		(start 65.270634 -388.774432)
		(end 65.791334 -388.774432)
		(width 0.127)
		(layer "F.Cu")
		(net "P5E_CPU1_P0_TX_BUF_DN<15>")
	)
	(segment
		(start 65.791334 -388.774432)
		(end 65.843658 -388.826756)
		(width 0.14224)
		(layer "In6.Cu")
		(net "P5E_CPU1_P0_TX_BUF_DN<15>")
	)
	(segment
		(start 94.033594 -404.17369)
		(end 93.742764 -404.46452)
		(width 0.14224)
		(layer "In6.Cu")
		(net "P5E_CPU1_P0_TX_BUF_DN<15>")
	)
	(segment
		(start 65.525142 -389.325104)
		(end 65.525142 -389.496046)
		(width 0.14224)
		(layer "In6.Cu")
		(net "P5E_CPU1_P0_TX_BUF_DN<15>")
	)
	(segment
		(start 83.867244 -398.42059)
		(end 93.69298 -402.490686)
		(width 0.14224)
		(layer "In6.Cu")
		(net "P5E_CPU1_P0_TX_BUF_DN<15>")
	)
	(segment
		(start 94.033594 -403.11324)
		(end 94.033594 -404.17369)
		(width 0.14224)
		(layer "In6.Cu")
		(net "P5E_CPU1_P0_TX_BUF_DN<15>")
	)
	(segment
		(start 72.683624 -395.325346)
		(end 72.683624 -395.3256)
		(width 0.14224)
		(layer "In6.Cu")
		(net "P5E_CPU1_P0_TX_BUF_DN<15>")
	)
	(segment
		(start 65.843658 -388.826756)
		(end 65.843658 -389.006588)
		(width 0.14224)
		(layer "In6.Cu")
		(net "P5E_CPU1_P0_TX_BUF_DN<15>")
	)
	(segment
		(start 72.683624 -395.3256)
		(end 83.867244 -398.42059)
		(width 0.14224)
		(layer "In6.Cu")
		(net "P5E_CPU1_P0_TX_BUF_DN<15>")
	)
	(segment
		(start 66.508884 -392.157458)
		(end 66.897758 -393.096496)
		(width 0.14224)
		(layer "In6.Cu")
		(net "P5E_CPU1_P0_TX_BUF_DN<15>")
	)
	(segment
		(start 65.930272 -390.203436)
		(end 65.930272 -390.380728)
		(width 0.14224)
		(layer "In6.Cu")
		(net "P5E_CPU1_P0_TX_BUF_DN<15>")
	)
	(segment
		(start 68.752212 -394.23721)
		(end 72.683624 -395.325346)
		(width 0.14224)
		(layer "In6.Cu")
		(net "P5E_CPU1_P0_TX_BUF_DN<15>")
	)
	(segment
		(start 65.96126 -390.537192)
		(end 66.395092 -391.584942)
		(width 0.14224)
		(layer "In6.Cu")
		(net "P5E_CPU1_P0_TX_BUF_DN<15>")
	)
	(segment
		(start 65.843658 -389.006588)
		(end 65.525142 -389.325104)
		(width 0.14224)
		(layer "In6.Cu")
		(net "P5E_CPU1_P0_TX_BUF_DN<15>")
	)
	(segment
		(start 65.713864 -389.951722)
		(end 65.877186 -390.115044)
		(width 0.14224)
		(layer "In6.Cu")
		(net "P5E_CPU1_P0_TX_BUF_DN<15>")
	)
	(segment
		(start 93.734382 -402.518372)
		(end 93.824552 -402.608542)
		(width 0.14224)
		(layer "In6.Cu")
		(net "P5E_CPU1_P0_TX_BUF_DN<15>")
	)
	(arc
		(start 93.69298 -402.490686)
		(mid 93.715055 -402.502477)
		(end 93.734382 -402.518372)
		(width 0.14224)
		(layer "In6.Cu")
		(net "P5E_CPU1_P0_TX_BUF_DN<15>")
	)
	(arc
		(start 66.446146 -391.842752)
		(mid 66.461999 -392.0032)
		(end 66.508884 -392.157458)
		(width 0.14224)
		(layer "In6.Cu")
		(net "P5E_CPU1_P0_TX_BUF_DN<15>")
	)
	(arc
		(start 65.930272 -390.380728)
		(mid 65.938065 -390.460486)
		(end 65.96126 -390.537192)
		(width 0.14224)
		(layer "In6.Cu")
		(net "P5E_CPU1_P0_TX_BUF_DN<15>")
	)
	(arc
		(start 67.043046 -393.301728)
		(mid 67.843399 -393.868551)
		(end 68.752212 -394.23721)
		(width 0.14224)
		(layer "In6.Cu")
		(net "P5E_CPU1_P0_TX_BUF_DN<15>")
	)
	(arc
		(start 65.877186 -390.115044)
		(mid 65.909212 -390.155951)
		(end 65.930272 -390.203436)
		(width 0.14224)
		(layer "In6.Cu")
		(net "P5E_CPU1_P0_TX_BUF_DN<15>")
	)
	(arc
		(start 65.525142 -389.496046)
		(mid 65.574194 -389.742646)
		(end 65.713864 -389.951722)
		(width 0.14224)
		(layer "In6.Cu")
		(net "P5E_CPU1_P0_TX_BUF_DN<15>")
	)
	(arc
		(start 66.395092 -391.584942)
		(mid 66.433297 -391.711336)
		(end 66.446146 -391.842752)
		(width 0.14224)
		(layer "In6.Cu")
		(net "P5E_CPU1_P0_TX_BUF_DN<15>")
	)
	(arc
		(start 93.824552 -402.608542)
		(mid 93.979274 -402.840099)
		(end 94.033594 -403.11324)
		(width 0.14224)
		(layer "In6.Cu")
		(net "P5E_CPU1_P0_TX_BUF_DN<15>")
	)
	(arc
		(start 66.897758 -393.096496)
		(mid 66.958882 -393.20727)
		(end 67.043046 -393.301728)
		(width 0.14224)
		(layer "In6.Cu")
		(net "P5E_CPU1_P0_TX_BUF_DN<15>")
	)
	(segment
		(start 90.950034 -407.954734)
		(end 90.950034 -404.73503)
		(width 0.12954)
		(layer "F.Cu")
		(net "P5E_CPU1_P0_TX_BUF_DN<14>")
	)
	(segment
		(start 90.950034 -404.73503)
		(end 90.679524 -404.46452)
		(width 0.12954)
		(layer "F.Cu")
		(net "P5E_CPU1_P0_TX_BUF_DN<14>")
	)
	(segment
		(start 64.070738 -388.774432)
		(end 64.591438 -388.774432)
		(width 0.127)
		(layer "F.Cu")
		(net "P5E_CPU1_P0_TX_BUF_DN<14>")
	)
	(segment
		(start 90.654124 -408.250644)
		(end 90.950034 -407.954734)
		(width 0.12954)
		(layer "F.Cu")
		(net "P5E_CPU1_P0_TX_BUF_DN<14>")
	)
	(segment
		(start 64.317118 -389.319008)
		(end 64.317118 -389.47725)
		(width 0.14224)
		(layer "In6.Cu")
		(net "P5E_CPU1_P0_TX_BUF_DN<14>")
	)
	(segment
		(start 64.591438 -388.774432)
		(end 64.63665 -388.819644)
		(width 0.14224)
		(layer "In6.Cu")
		(net "P5E_CPU1_P0_TX_BUF_DN<14>")
	)
	(segment
		(start 82.934556 -399.499836)
		(end 88.28405 -401.715224)
		(width 0.14224)
		(layer "In6.Cu")
		(net "P5E_CPU1_P0_TX_BUF_DN<14>")
	)
	(segment
		(start 90.970354 -404.17369)
		(end 90.679524 -404.46452)
		(width 0.14224)
		(layer "In6.Cu")
		(net "P5E_CPU1_P0_TX_BUF_DN<14>")
	)
	(segment
		(start 64.63665 -388.999476)
		(end 64.317118 -389.319008)
		(width 0.14224)
		(layer "In6.Cu")
		(net "P5E_CPU1_P0_TX_BUF_DN<14>")
	)
	(segment
		(start 65.191894 -394.369544)
		(end 65.408556 -394.586206)
		(width 0.14224)
		(layer "In6.Cu")
		(net "P5E_CPU1_P0_TX_BUF_DN<14>")
	)
	(segment
		(start 64.732916 -390.539986)
		(end 65.053464 -391.595102)
		(width 0.14224)
		(layer "In6.Cu")
		(net "P5E_CPU1_P0_TX_BUF_DN<14>")
	)
	(segment
		(start 90.868754 -403.44217)
		(end 90.901266 -403.474682)
		(width 0.14224)
		(layer "In6.Cu")
		(net "P5E_CPU1_P0_TX_BUF_DN<14>")
	)
	(segment
		(start 65.072006 -391.719816)
		(end 65.072006 -394.080238)
		(width 0.14224)
		(layer "In6.Cu")
		(net "P5E_CPU1_P0_TX_BUF_DN<14>")
	)
	(segment
		(start 90.970354 -403.641306)
		(end 90.970354 -404.17369)
		(width 0.14224)
		(layer "In6.Cu")
		(net "P5E_CPU1_P0_TX_BUF_DN<14>")
	)
	(segment
		(start 74.160634 -396.838932)
		(end 82.934556 -399.499836)
		(width 0.14224)
		(layer "In6.Cu")
		(net "P5E_CPU1_P0_TX_BUF_DN<14>")
	)
	(segment
		(start 65.598548 -394.693902)
		(end 74.160634 -396.838932)
		(width 0.14224)
		(layer "In6.Cu")
		(net "P5E_CPU1_P0_TX_BUF_DN<14>")
	)
	(segment
		(start 64.63665 -388.819644)
		(end 64.63665 -388.999476)
		(width 0.14224)
		(layer "In6.Cu")
		(net "P5E_CPU1_P0_TX_BUF_DN<14>")
	)
	(segment
		(start 64.513714 -389.951722)
		(end 64.631062 -390.06907)
		(width 0.14224)
		(layer "In6.Cu")
		(net "P5E_CPU1_P0_TX_BUF_DN<14>")
	)
	(arc
		(start 65.408556 -394.586206)
		(mid 65.496249 -394.652932)
		(end 65.598548 -394.693902)
		(width 0.14224)
		(layer "In6.Cu")
		(net "P5E_CPU1_P0_TX_BUF_DN<14>")
	)
	(arc
		(start 90.901266 -403.474682)
		(mid 90.9524 -403.551115)
		(end 90.970354 -403.641306)
		(width 0.14224)
		(layer "In6.Cu")
		(net "P5E_CPU1_P0_TX_BUF_DN<14>")
	)
	(arc
		(start 88.28405 -401.715224)
		(mid 89.661472 -402.451376)
		(end 90.868754 -403.44217)
		(width 0.14224)
		(layer "In6.Cu")
		(net "P5E_CPU1_P0_TX_BUF_DN<14>")
	)
	(arc
		(start 65.072006 -394.080238)
		(mid 65.103169 -394.236816)
		(end 65.191894 -394.369544)
		(width 0.14224)
		(layer "In6.Cu")
		(net "P5E_CPU1_P0_TX_BUF_DN<14>")
	)
	(arc
		(start 64.317118 -389.47725)
		(mid 64.368215 -389.734042)
		(end 64.513714 -389.951722)
		(width 0.14224)
		(layer "In6.Cu")
		(net "P5E_CPU1_P0_TX_BUF_DN<14>")
	)
	(arc
		(start 65.053464 -391.595102)
		(mid 65.067327 -391.656775)
		(end 65.072006 -391.719816)
		(width 0.14224)
		(layer "In6.Cu")
		(net "P5E_CPU1_P0_TX_BUF_DN<14>")
	)
	(arc
		(start 64.67983 -390.186164)
		(mid 64.693475 -390.365009)
		(end 64.732916 -390.539986)
		(width 0.14224)
		(layer "In6.Cu")
		(net "P5E_CPU1_P0_TX_BUF_DN<14>")
	)
	(arc
		(start 64.631062 -390.06907)
		(mid 64.667124 -390.122763)
		(end 64.67983 -390.186164)
		(width 0.14224)
		(layer "In6.Cu")
		(net "P5E_CPU1_P0_TX_BUF_DN<14>")
	)
	(segment
		(start 87.886794 -404.73503)
		(end 87.616284 -404.46452)
		(width 0.12954)
		(layer "F.Cu")
		(net "P5E_CPU1_P0_TX_BUF_DN<13>")
	)
	(segment
		(start 87.886794 -407.954734)
		(end 87.886794 -404.73503)
		(width 0.12954)
		(layer "F.Cu")
		(net "P5E_CPU1_P0_TX_BUF_DN<13>")
	)
	(segment
		(start 62.870588 -388.774432)
		(end 63.391288 -388.774432)
		(width 0.127)
		(layer "F.Cu")
		(net "P5E_CPU1_P0_TX_BUF_DN<13>")
	)
	(segment
		(start 87.590884 -408.250644)
		(end 87.886794 -407.954734)
		(width 0.12954)
		(layer "F.Cu")
		(net "P5E_CPU1_P0_TX_BUF_DN<13>")
	)
	(segment
		(start 87.640414 -402.829014)
		(end 87.728298 -402.916898)
		(width 0.14224)
		(layer "In6.Cu")
		(net "P5E_CPU1_P0_TX_BUF_DN<13>")
	)
	(segment
		(start 83.173062 -400.99869)
		(end 85.182456 -401.71751)
		(width 0.14224)
		(layer "In6.Cu")
		(net "P5E_CPU1_P0_TX_BUF_DN<13>")
	)
	(segment
		(start 63.125096 -389.325104)
		(end 63.125096 -389.480044)
		(width 0.14224)
		(layer "In6.Cu")
		(net "P5E_CPU1_P0_TX_BUF_DN<13>")
	)
	(segment
		(start 63.516256 -390.528048)
		(end 63.853314 -391.641076)
		(width 0.14224)
		(layer "In6.Cu")
		(net "P5E_CPU1_P0_TX_BUF_DN<13>")
	)
	(segment
		(start 63.443612 -388.826756)
		(end 63.443612 -389.006588)
		(width 0.14224)
		(layer "In6.Cu")
		(net "P5E_CPU1_P0_TX_BUF_DN<13>")
	)
	(segment
		(start 64.009524 -394.707364)
		(end 64.468502 -395.166342)
		(width 0.14224)
		(layer "In6.Cu")
		(net "P5E_CPU1_P0_TX_BUF_DN<13>")
	)
	(segment
		(start 87.907114 -404.17369)
		(end 87.616284 -404.46452)
		(width 0.14224)
		(layer "In6.Cu")
		(net "P5E_CPU1_P0_TX_BUF_DN<13>")
	)
	(segment
		(start 70.287388 -396.832074)
		(end 78.42504 -399.3007)
		(width 0.14224)
		(layer "In6.Cu")
		(net "P5E_CPU1_P0_TX_BUF_DN<13>")
	)
	(segment
		(start 87.907114 -403.348444)
		(end 87.907114 -404.17369)
		(width 0.14224)
		(layer "In6.Cu")
		(net "P5E_CPU1_P0_TX_BUF_DN<13>")
	)
	(segment
		(start 63.443612 -389.006588)
		(end 63.125096 -389.325104)
		(width 0.14224)
		(layer "In6.Cu")
		(net "P5E_CPU1_P0_TX_BUF_DN<13>")
	)
	(segment
		(start 65.126362 -395.53896)
		(end 70.287388 -396.832074)
		(width 0.14224)
		(layer "In6.Cu")
		(net "P5E_CPU1_P0_TX_BUF_DN<13>")
	)
	(segment
		(start 63.485776 -390.176512)
		(end 63.485776 -390.322054)
		(width 0.14224)
		(layer "In6.Cu")
		(net "P5E_CPU1_P0_TX_BUF_DN<13>")
	)
	(segment
		(start 78.42504 -399.3007)
		(end 83.172808 -400.99869)
		(width 0.14224)
		(layer "In6.Cu")
		(net "P5E_CPU1_P0_TX_BUF_DN<13>")
	)
	(segment
		(start 63.325248 -389.963152)
		(end 63.448438 -390.086342)
		(width 0.14224)
		(layer "In6.Cu")
		(net "P5E_CPU1_P0_TX_BUF_DN<13>")
	)
	(segment
		(start 85.182456 -401.71751)
		(end 87.272876 -402.583396)
		(width 0.14224)
		(layer "In6.Cu")
		(net "P5E_CPU1_P0_TX_BUF_DN<13>")
	)
	(segment
		(start 63.871856 -391.76579)
		(end 63.871856 -394.374878)
		(width 0.14224)
		(layer "In6.Cu")
		(net "P5E_CPU1_P0_TX_BUF_DN<13>")
	)
	(segment
		(start 83.172808 -400.99869)
		(end 83.173062 -400.99869)
		(width 0.14224)
		(layer "In6.Cu")
		(net "P5E_CPU1_P0_TX_BUF_DN<13>")
	)
	(segment
		(start 63.391288 -388.774432)
		(end 63.443612 -388.826756)
		(width 0.14224)
		(layer "In6.Cu")
		(net "P5E_CPU1_P0_TX_BUF_DN<13>")
	)
	(arc
		(start 87.728298 -402.916898)
		(mid 87.860648 -403.114879)
		(end 87.907114 -403.348444)
		(width 0.14224)
		(layer "In6.Cu")
		(net "P5E_CPU1_P0_TX_BUF_DN<13>")
	)
	(arc
		(start 63.448438 -390.086342)
		(mid 63.476081 -390.127712)
		(end 63.485776 -390.176512)
		(width 0.14224)
		(layer "In6.Cu")
		(net "P5E_CPU1_P0_TX_BUF_DN<13>")
	)
	(arc
		(start 63.853314 -391.641076)
		(mid 63.86718 -391.70275)
		(end 63.871856 -391.76579)
		(width 0.14224)
		(layer "In6.Cu")
		(net "P5E_CPU1_P0_TX_BUF_DN<13>")
	)
	(arc
		(start 64.468502 -395.166342)
		(mid 64.772118 -395.39735)
		(end 65.126362 -395.53896)
		(width 0.14224)
		(layer "In6.Cu")
		(net "P5E_CPU1_P0_TX_BUF_DN<13>")
	)
	(arc
		(start 87.272876 -402.583396)
		(mid 87.46875 -402.688094)
		(end 87.640414 -402.829014)
		(width 0.14224)
		(layer "In6.Cu")
		(net "P5E_CPU1_P0_TX_BUF_DN<13>")
	)
	(arc
		(start 63.871856 -394.374878)
		(mid 63.907629 -394.554812)
		(end 64.009524 -394.707364)
		(width 0.14224)
		(layer "In6.Cu")
		(net "P5E_CPU1_P0_TX_BUF_DN<13>")
	)
	(arc
		(start 63.485776 -390.322054)
		(mid 63.493464 -390.426167)
		(end 63.516256 -390.528048)
		(width 0.14224)
		(layer "In6.Cu")
		(net "P5E_CPU1_P0_TX_BUF_DN<13>")
	)
	(arc
		(start 63.125096 -389.480044)
		(mid 63.177121 -389.741502)
		(end 63.325248 -389.963152)
		(width 0.14224)
		(layer "In6.Cu")
		(net "P5E_CPU1_P0_TX_BUF_DN<13>")
	)
	(segment
		(start 61.670692 -388.774432)
		(end 62.191392 -388.774432)
		(width 0.127)
		(layer "F.Cu")
		(net "P5E_CPU1_P0_TX_BUF_DN<12>")
	)
	(segment
		(start 84.527644 -408.250644)
		(end 84.823554 -407.954734)
		(width 0.12954)
		(layer "F.Cu")
		(net "P5E_CPU1_P0_TX_BUF_DN<12>")
	)
	(segment
		(start 84.823554 -404.73503)
		(end 84.553044 -404.46452)
		(width 0.12954)
		(layer "F.Cu")
		(net "P5E_CPU1_P0_TX_BUF_DN<12>")
	)
	(segment
		(start 84.823554 -407.954734)
		(end 84.823554 -404.73503)
		(width 0.12954)
		(layer "F.Cu")
		(net "P5E_CPU1_P0_TX_BUF_DN<12>")
	)
	(segment
		(start 64.242696 -396.322042)
		(end 69.789294 -397.712184)
		(width 0.14224)
		(layer "In6.Cu")
		(net "P5E_CPU1_P0_TX_BUF_DN<12>")
	)
	(segment
		(start 62.850776 -395.145514)
		(end 63.745618 -396.040356)
		(width 0.14224)
		(layer "In6.Cu")
		(net "P5E_CPU1_P0_TX_BUF_DN<12>")
	)
	(segment
		(start 84.676488 -402.85416)
		(end 84.78901 -402.966682)
		(width 0.14224)
		(layer "In6.Cu")
		(net "P5E_CPU1_P0_TX_BUF_DN<12>")
	)
	(segment
		(start 62.671706 -391.753852)
		(end 62.671706 -394.713206)
		(width 0.14224)
		(layer "In6.Cu")
		(net "P5E_CPU1_P0_TX_BUF_DN<12>")
	)
	(segment
		(start 62.191392 -388.774432)
		(end 62.243716 -388.826756)
		(width 0.14224)
		(layer "In6.Cu")
		(net "P5E_CPU1_P0_TX_BUF_DN<12>")
	)
	(segment
		(start 84.843874 -403.099016)
		(end 84.843874 -404.17369)
		(width 0.14224)
		(layer "In6.Cu")
		(net "P5E_CPU1_P0_TX_BUF_DN<12>")
	)
	(segment
		(start 69.789294 -397.712184)
		(end 79.12735 -400.545046)
		(width 0.14224)
		(layer "In6.Cu")
		(net "P5E_CPU1_P0_TX_BUF_DN<12>")
	)
	(segment
		(start 84.843874 -404.17369)
		(end 84.553044 -404.46452)
		(width 0.14224)
		(layer "In6.Cu")
		(net "P5E_CPU1_P0_TX_BUF_DN<12>")
	)
	(segment
		(start 62.285626 -390.176512)
		(end 62.285626 -390.366758)
		(width 0.14224)
		(layer "In6.Cu")
		(net "P5E_CPU1_P0_TX_BUF_DN<12>")
	)
	(segment
		(start 62.243716 -388.826756)
		(end 62.243716 -389.023352)
		(width 0.14224)
		(layer "In6.Cu")
		(net "P5E_CPU1_P0_TX_BUF_DN<12>")
	)
	(segment
		(start 62.319154 -390.592056)
		(end 62.671706 -391.753852)
		(width 0.14224)
		(layer "In6.Cu")
		(net "P5E_CPU1_P0_TX_BUF_DN<12>")
	)
	(segment
		(start 61.9252 -389.341868)
		(end 61.9252 -389.535162)
		(width 0.14224)
		(layer "In6.Cu")
		(net "P5E_CPU1_P0_TX_BUF_DN<12>")
	)
	(segment
		(start 62.243716 -389.023352)
		(end 61.9252 -389.341868)
		(width 0.14224)
		(layer "In6.Cu")
		(net "P5E_CPU1_P0_TX_BUF_DN<12>")
	)
	(segment
		(start 62.08649 -389.924544)
		(end 62.248288 -390.086342)
		(width 0.14224)
		(layer "In6.Cu")
		(net "P5E_CPU1_P0_TX_BUF_DN<12>")
	)
	(segment
		(start 79.12735 -400.545046)
		(end 84.635086 -402.826474)
		(width 0.14224)
		(layer "In6.Cu")
		(net "P5E_CPU1_P0_TX_BUF_DN<12>")
	)
	(arc
		(start 62.285626 -390.366758)
		(mid 62.294075 -390.480644)
		(end 62.319154 -390.592056)
		(width 0.14224)
		(layer "In6.Cu")
		(net "P5E_CPU1_P0_TX_BUF_DN<12>")
	)
	(arc
		(start 84.78901 -402.966682)
		(mid 84.829632 -403.027383)
		(end 84.843874 -403.099016)
		(width 0.14224)
		(layer "In6.Cu")
		(net "P5E_CPU1_P0_TX_BUF_DN<12>")
	)
	(arc
		(start 62.248288 -390.086342)
		(mid 62.275931 -390.127712)
		(end 62.285626 -390.176512)
		(width 0.14224)
		(layer "In6.Cu")
		(net "P5E_CPU1_P0_TX_BUF_DN<12>")
	)
	(arc
		(start 61.9252 -389.535162)
		(mid 61.967117 -389.745895)
		(end 62.08649 -389.924544)
		(width 0.14224)
		(layer "In6.Cu")
		(net "P5E_CPU1_P0_TX_BUF_DN<12>")
	)
	(arc
		(start 62.671706 -394.713206)
		(mid 62.718244 -394.94717)
		(end 62.850776 -395.145514)
		(width 0.14224)
		(layer "In6.Cu")
		(net "P5E_CPU1_P0_TX_BUF_DN<12>")
	)
	(arc
		(start 84.635086 -402.826474)
		(mid 84.657148 -402.838282)
		(end 84.676488 -402.85416)
		(width 0.14224)
		(layer "In6.Cu")
		(net "P5E_CPU1_P0_TX_BUF_DN<12>")
	)
	(arc
		(start 63.745618 -396.040356)
		(mid 63.975023 -396.21497)
		(end 64.242696 -396.322042)
		(width 0.14224)
		(layer "In6.Cu")
		(net "P5E_CPU1_P0_TX_BUF_DN<12>")
	)
	(segment
		(start 81.760314 -407.954734)
		(end 81.760314 -404.73503)
		(width 0.12954)
		(layer "F.Cu")
		(net "P5E_CPU1_P0_TX_BUF_DN<11>")
	)
	(segment
		(start 81.464404 -408.250644)
		(end 81.760314 -407.954734)
		(width 0.12954)
		(layer "F.Cu")
		(net "P5E_CPU1_P0_TX_BUF_DN<11>")
	)
	(segment
		(start 81.760314 -404.73503)
		(end 81.489804 -404.46452)
		(width 0.12954)
		(layer "F.Cu")
		(net "P5E_CPU1_P0_TX_BUF_DN<11>")
	)
	(segment
		(start 60.470542 -388.774432)
		(end 60.991242 -388.774432)
		(width 0.127)
		(layer "F.Cu")
		(net "P5E_CPU1_P0_TX_BUF_DN<11>")
	)
	(segment
		(start 81.780634 -403.112478)
		(end 81.780634 -404.17369)
		(width 0.14224)
		(layer "In6.Cu")
		(net "P5E_CPU1_P0_TX_BUF_DN<11>")
	)
	(segment
		(start 68.010532 -398.240504)
		(end 77.785468 -401.205954)
		(width 0.14224)
		(layer "In6.Cu")
		(net "P5E_CPU1_P0_TX_BUF_DN<11>")
	)
	(segment
		(start 77.785468 -401.205954)
		(end 78.876398 -401.65782)
		(width 0.14224)
		(layer "In6.Cu")
		(net "P5E_CPU1_P0_TX_BUF_DN<11>")
	)
	(segment
		(start 61.47181 -391.741152)
		(end 61.47181 -395.210538)
		(width 0.14224)
		(layer "In6.Cu")
		(net "P5E_CPU1_P0_TX_BUF_DN<11>")
	)
	(segment
		(start 63.082424 -397.006572)
		(end 68.010532 -398.240504)
		(width 0.14224)
		(layer "In6.Cu")
		(net "P5E_CPU1_P0_TX_BUF_DN<11>")
	)
	(segment
		(start 81.780634 -404.17369)
		(end 81.489804 -404.46452)
		(width 0.14224)
		(layer "In6.Cu")
		(net "P5E_CPU1_P0_TX_BUF_DN<11>")
	)
	(segment
		(start 78.876398 -401.65782)
		(end 81.60385 -402.787358)
		(width 0.14224)
		(layer "In6.Cu")
		(net "P5E_CPU1_P0_TX_BUF_DN<11>")
	)
	(segment
		(start 60.991242 -388.774432)
		(end 60.991242 -389.100568)
		(width 0.14224)
		(layer "In6.Cu")
		(net "P5E_CPU1_P0_TX_BUF_DN<11>")
	)
	(segment
		(start 61.11621 -390.50341)
		(end 61.453268 -391.616438)
		(width 0.14224)
		(layer "In6.Cu")
		(net "P5E_CPU1_P0_TX_BUF_DN<11>")
	)
	(segment
		(start 61.707268 -395.778736)
		(end 62.742572 -396.81404)
		(width 0.14224)
		(layer "In6.Cu")
		(net "P5E_CPU1_P0_TX_BUF_DN<11>")
	)
	(segment
		(start 60.991242 -389.100568)
		(end 60.912248 -389.179308)
		(width 0.14224)
		(layer "In6.Cu")
		(net "P5E_CPU1_P0_TX_BUF_DN<11>")
	)
	(arc
		(start 61.47181 -395.210538)
		(mid 61.533 -395.51807)
		(end 61.707268 -395.778736)
		(width 0.14224)
		(layer "In6.Cu")
		(net "P5E_CPU1_P0_TX_BUF_DN<11>")
	)
	(arc
		(start 61.087508 -390.347962)
		(mid 61.097533 -390.426485)
		(end 61.11621 -390.50341)
		(width 0.14224)
		(layer "In6.Cu")
		(net "P5E_CPU1_P0_TX_BUF_DN<11>")
	)
	(arc
		(start 60.906914 -389.945118)
		(mid 61.0329 -390.130547)
		(end 61.087508 -390.347962)
		(width 0.14224)
		(layer "In6.Cu")
		(net "P5E_CPU1_P0_TX_BUF_DN<11>")
	)
	(arc
		(start 62.742572 -396.81404)
		(mid 62.899427 -396.933375)
		(end 63.082424 -397.006572)
		(width 0.14224)
		(layer "In6.Cu")
		(net "P5E_CPU1_P0_TX_BUF_DN<11>")
	)
	(arc
		(start 61.453268 -391.616438)
		(mid 61.467134 -391.678112)
		(end 61.47181 -391.741152)
		(width 0.14224)
		(layer "In6.Cu")
		(net "P5E_CPU1_P0_TX_BUF_DN<11>")
	)
	(arc
		(start 81.702402 -402.867114)
		(mid 81.759531 -402.984049)
		(end 81.780634 -403.112478)
		(width 0.14224)
		(layer "In6.Cu")
		(net "P5E_CPU1_P0_TX_BUF_DN<11>")
	)
	(arc
		(start 81.60385 -402.787358)
		(mid 81.658945 -402.820051)
		(end 81.702402 -402.867114)
		(width 0.14224)
		(layer "In6.Cu")
		(net "P5E_CPU1_P0_TX_BUF_DN<11>")
	)
	(arc
		(start 60.912248 -389.179308)
		(mid 60.752701 -389.561109)
		(end 60.906914 -389.945118)
		(width 0.14224)
		(layer "In6.Cu")
		(net "P5E_CPU1_P0_TX_BUF_DN<11>")
	)
	(segment
		(start 78.697074 -404.73503)
		(end 78.426564 -404.46452)
		(width 0.12954)
		(layer "F.Cu")
		(net "P5E_CPU1_P0_TX_BUF_DN<10>")
	)
	(segment
		(start 59.270646 -388.774432)
		(end 59.791346 -388.774432)
		(width 0.127)
		(layer "F.Cu")
		(net "P5E_CPU1_P0_TX_BUF_DN<10>")
	)
	(segment
		(start 78.401164 -408.250644)
		(end 78.697074 -407.954734)
		(width 0.12954)
		(layer "F.Cu")
		(net "P5E_CPU1_P0_TX_BUF_DN<10>")
	)
	(segment
		(start 78.697074 -407.954734)
		(end 78.697074 -404.73503)
		(width 0.12954)
		(layer "F.Cu")
		(net "P5E_CPU1_P0_TX_BUF_DN<10>")
	)
	(segment
		(start 59.525154 -389.325104)
		(end 59.525154 -389.485124)
		(width 0.14224)
		(layer "In6.Cu")
		(net "P5E_CPU1_P0_TX_BUF_DN<10>")
	)
	(segment
		(start 78.717394 -404.17369)
		(end 78.426564 -404.46452)
		(width 0.14224)
		(layer "In6.Cu")
		(net "P5E_CPU1_P0_TX_BUF_DN<10>")
	)
	(segment
		(start 62.620652 -397.855186)
		(end 67.2592 -399.016982)
		(width 0.14224)
		(layer "In6.Cu")
		(net "P5E_CPU1_P0_TX_BUF_DN<10>")
	)
	(segment
		(start 60.233814 -391.639044)
		(end 60.233814 -395.190218)
		(width 0.14224)
		(layer "In6.Cu")
		(net "P5E_CPU1_P0_TX_BUF_DN<10>")
	)
	(segment
		(start 59.903614 -390.549638)
		(end 60.233814 -391.639044)
		(width 0.14224)
		(layer "In6.Cu")
		(net "P5E_CPU1_P0_TX_BUF_DN<10>")
	)
	(segment
		(start 59.72175 -389.959596)
		(end 59.848496 -390.086088)
		(width 0.14224)
		(layer "In6.Cu")
		(net "P5E_CPU1_P0_TX_BUF_DN<10>")
	)
	(segment
		(start 59.791346 -388.774432)
		(end 59.84367 -388.826756)
		(width 0.14224)
		(layer "In6.Cu")
		(net "P5E_CPU1_P0_TX_BUF_DN<10>")
	)
	(segment
		(start 77.887322 -402.68779)
		(end 78.680056 -403.480524)
		(width 0.14224)
		(layer "In6.Cu")
		(net "P5E_CPU1_P0_TX_BUF_DN<10>")
	)
	(segment
		(start 78.717394 -403.570694)
		(end 78.717394 -404.17369)
		(width 0.14224)
		(layer "In6.Cu")
		(net "P5E_CPU1_P0_TX_BUF_DN<10>")
	)
	(segment
		(start 74.013314 -401.065746)
		(end 77.803756 -402.63191)
		(width 0.14224)
		(layer "In6.Cu")
		(net "P5E_CPU1_P0_TX_BUF_DN<10>")
	)
	(segment
		(start 60.60948 -396.097252)
		(end 62.036452 -397.524224)
		(width 0.14224)
		(layer "In6.Cu")
		(net "P5E_CPU1_P0_TX_BUF_DN<10>")
	)
	(segment
		(start 59.84367 -388.826756)
		(end 59.84367 -389.006588)
		(width 0.14224)
		(layer "In6.Cu")
		(net "P5E_CPU1_P0_TX_BUF_DN<10>")
	)
	(segment
		(start 59.84367 -389.006588)
		(end 59.525154 -389.325104)
		(width 0.14224)
		(layer "In6.Cu")
		(net "P5E_CPU1_P0_TX_BUF_DN<10>")
	)
	(segment
		(start 59.885834 -390.176004)
		(end 59.885834 -390.430766)
		(width 0.14224)
		(layer "In6.Cu")
		(net "P5E_CPU1_P0_TX_BUF_DN<10>")
	)
	(segment
		(start 67.2592 -399.016982)
		(end 74.013314 -401.065746)
		(width 0.14224)
		(layer "In6.Cu")
		(net "P5E_CPU1_P0_TX_BUF_DN<10>")
	)
	(arc
		(start 59.885834 -390.430766)
		(mid 59.89034 -390.490858)
		(end 59.903614 -390.549638)
		(width 0.14224)
		(layer "In6.Cu")
		(net "P5E_CPU1_P0_TX_BUF_DN<10>")
	)
	(arc
		(start 78.680056 -403.480524)
		(mid 78.707699 -403.521894)
		(end 78.717394 -403.570694)
		(width 0.14224)
		(layer "In6.Cu")
		(net "P5E_CPU1_P0_TX_BUF_DN<10>")
	)
	(arc
		(start 60.233814 -395.190218)
		(mid 60.331439 -395.6811)
		(end 60.60948 -396.097252)
		(width 0.14224)
		(layer "In6.Cu")
		(net "P5E_CPU1_P0_TX_BUF_DN<10>")
	)
	(arc
		(start 59.525154 -389.485124)
		(mid 59.576251 -389.741916)
		(end 59.72175 -389.959596)
		(width 0.14224)
		(layer "In6.Cu")
		(net "P5E_CPU1_P0_TX_BUF_DN<10>")
	)
	(arc
		(start 77.803756 -402.63191)
		(mid 77.848268 -402.655766)
		(end 77.887322 -402.68779)
		(width 0.14224)
		(layer "In6.Cu")
		(net "P5E_CPU1_P0_TX_BUF_DN<10>")
	)
	(arc
		(start 62.036452 -397.524224)
		(mid 62.30608 -397.729368)
		(end 62.620652 -397.855186)
		(width 0.14224)
		(layer "In6.Cu")
		(net "P5E_CPU1_P0_TX_BUF_DN<10>")
	)
	(arc
		(start 59.848496 -390.086088)
		(mid 59.876115 -390.127328)
		(end 59.885834 -390.176004)
		(width 0.14224)
		(layer "In6.Cu")
		(net "P5E_CPU1_P0_TX_BUF_DN<10>")
	)
	(segment
		(start 48.064674 -404.73503)
		(end 47.794164 -404.46452)
		(width 0.12954)
		(layer "F.Cu")
		(net "P5E_CPU1_P0_TX_BUF_DN<0>")
	)
	(segment
		(start 47.768764 -408.250644)
		(end 48.064674 -407.954734)
		(width 0.12954)
		(layer "F.Cu")
		(net "P5E_CPU1_P0_TX_BUF_DN<0>")
	)
	(segment
		(start 48.064674 -407.954734)
		(end 48.064674 -404.73503)
		(width 0.12954)
		(layer "F.Cu")
		(net "P5E_CPU1_P0_TX_BUF_DN<0>")
	)
	(segment
		(start 47.27067 -388.774432)
		(end 47.79137 -388.774432)
		(width 0.127)
		(layer "F.Cu")
		(net "P5E_CPU1_P0_TX_BUF_DN<0>")
	)
	(segment
		(start 47.843694 -388.826756)
		(end 47.843694 -389.006588)
		(width 0.14224)
		(layer "In6.Cu")
		(net "P5E_CPU1_P0_TX_BUF_DN<0>")
	)
	(segment
		(start 47.525178 -389.489188)
		(end 47.525178 -389.563864)
		(width 0.14224)
		(layer "In6.Cu")
		(net "P5E_CPU1_P0_TX_BUF_DN<0>")
	)
	(segment
		(start 48.271938 -402.32838)
		(end 48.084994 -403.268434)
		(width 0.14224)
		(layer "In6.Cu")
		(net "P5E_CPU1_P0_TX_BUF_DN<0>")
	)
	(segment
		(start 47.885858 -390.555226)
		(end 48.271938 -391.827512)
		(width 0.14224)
		(layer "In6.Cu")
		(net "P5E_CPU1_P0_TX_BUF_DN<0>")
	)
	(segment
		(start 47.885858 -390.176258)
		(end 47.885858 -390.555226)
		(width 0.14224)
		(layer "In6.Cu")
		(net "P5E_CPU1_P0_TX_BUF_DN<0>")
	)
	(segment
		(start 47.654972 -389.877554)
		(end 47.837852 -390.060434)
		(width 0.14224)
		(layer "In6.Cu")
		(net "P5E_CPU1_P0_TX_BUF_DN<0>")
	)
	(segment
		(start 48.084994 -404.17369)
		(end 47.794164 -404.46452)
		(width 0.14224)
		(layer "In6.Cu")
		(net "P5E_CPU1_P0_TX_BUF_DN<0>")
	)
	(segment
		(start 47.79137 -388.774432)
		(end 47.843694 -388.826756)
		(width 0.14224)
		(layer "In6.Cu")
		(net "P5E_CPU1_P0_TX_BUF_DN<0>")
	)
	(segment
		(start 48.271938 -391.827512)
		(end 48.271938 -402.32838)
		(width 0.14224)
		(layer "In6.Cu")
		(net "P5E_CPU1_P0_TX_BUF_DN<0>")
	)
	(segment
		(start 48.084994 -403.268434)
		(end 48.084994 -404.17369)
		(width 0.14224)
		(layer "In6.Cu")
		(net "P5E_CPU1_P0_TX_BUF_DN<0>")
	)
	(segment
		(start 47.843694 -389.006588)
		(end 47.641256 -389.209026)
		(width 0.14224)
		(layer "In6.Cu")
		(net "P5E_CPU1_P0_TX_BUF_DN<0>")
	)
	(arc
		(start 47.525178 -389.563864)
		(mid 47.558868 -389.733617)
		(end 47.654972 -389.877554)
		(width 0.14224)
		(layer "In6.Cu")
		(net "P5E_CPU1_P0_TX_BUF_DN<0>")
	)
	(arc
		(start 47.641256 -389.209026)
		(mid 47.555369 -389.337565)
		(end 47.525178 -389.489188)
		(width 0.14224)
		(layer "In6.Cu")
		(net "P5E_CPU1_P0_TX_BUF_DN<0>")
	)
	(arc
		(start 47.837852 -390.060434)
		(mid 47.873359 -390.113575)
		(end 47.885858 -390.176258)
		(width 0.14224)
		(layer "In6.Cu")
		(net "P5E_CPU1_P0_TX_BUF_DN<0>")
	)
	(segment
		(start 76.252324 -408.784044)
		(end 75.956414 -409.079954)
		(width 0.12954)
		(layer "F.Cu")
		(net "P5E_CPU1_P0_TX_BUF_C_DP<9>")
	)
	(segment
		(start 75.956414 -412.299658)
		(end 76.226924 -412.570168)
		(width 0.12954)
		(layer "F.Cu")
		(net "P5E_CPU1_P0_TX_BUF_C_DP<9>")
	)
	(segment
		(start 75.956414 -409.079954)
		(end 75.956414 -412.299658)
		(width 0.12954)
		(layer "F.Cu")
		(net "P5E_CPU1_P0_TX_BUF_C_DP<9>")
	)
	(segment
		(start 76.190094 -417.353242)
		(end 76.969112 -421.275002)
		(width 0.14224)
		(layer "In11.Cu")
		(net "P5E_CPU1_P0_TX_BUF_C_DP<9>")
	)
	(segment
		(start 75.936094 -414.776666)
		(end 75.97775 -415.2011)
		(width 0.14224)
		(layer "In11.Cu")
		(net "P5E_CPU1_P0_TX_BUF_C_DP<9>")
	)
	(segment
		(start 76.09332 -416.372294)
		(end 76.243434 -416.49523)
		(width 0.14224)
		(layer "In11.Cu")
		(net "P5E_CPU1_P0_TX_BUF_C_DP<9>")
	)
	(segment
		(start 76.128118 -415.32429)
		(end 76.169774 -415.749232)
		(width 0.14224)
		(layer "In11.Cu")
		(net "P5E_CPU1_P0_TX_BUF_C_DP<9>")
	)
	(segment
		(start 76.162154 -417.070032)
		(end 76.190094 -417.353242)
		(width 0.14224)
		(layer "In11.Cu")
		(net "P5E_CPU1_P0_TX_BUF_C_DP<9>")
	)
	(segment
		(start 77.117956 -431.148744)
		(end 77.522832 -431.148744)
		(width 0.14224)
		(layer "In11.Cu")
		(net "P5E_CPU1_P0_TX_BUF_C_DP<9>")
	)
	(segment
		(start 76.046838 -415.899092)
		(end 76.09332 -416.372294)
		(width 0.14224)
		(layer "In11.Cu")
		(net "P5E_CPU1_P0_TX_BUF_C_DP<9>")
	)
	(segment
		(start 75.97775 -415.2011)
		(end 76.128118 -415.32429)
		(width 0.14224)
		(layer "In11.Cu")
		(net "P5E_CPU1_P0_TX_BUF_C_DP<9>")
	)
	(segment
		(start 76.970128 -431.000916)
		(end 77.117956 -431.148744)
		(width 0.14224)
		(layer "In11.Cu")
		(net "P5E_CPU1_P0_TX_BUF_C_DP<9>")
	)
	(segment
		(start 75.936094 -412.860998)
		(end 75.936094 -414.776666)
		(width 0.14224)
		(layer "In11.Cu")
		(net "P5E_CPU1_P0_TX_BUF_C_DP<9>")
	)
	(segment
		(start 76.226924 -412.570168)
		(end 75.936094 -412.860998)
		(width 0.14224)
		(layer "In11.Cu")
		(net "P5E_CPU1_P0_TX_BUF_C_DP<9>")
	)
	(segment
		(start 76.169774 -415.749232)
		(end 76.046838 -415.899092)
		(width 0.14224)
		(layer "In11.Cu")
		(net "P5E_CPU1_P0_TX_BUF_C_DP<9>")
	)
	(segment
		(start 76.285344 -416.920172)
		(end 76.162154 -417.070032)
		(width 0.14224)
		(layer "In11.Cu")
		(net "P5E_CPU1_P0_TX_BUF_C_DP<9>")
	)
	(segment
		(start 77.522832 -431.148744)
		(end 77.650086 -431.02149)
		(width 0.14224)
		(layer "In11.Cu")
		(net "P5E_CPU1_P0_TX_BUF_C_DP<9>")
	)
	(segment
		(start 76.243434 -416.49523)
		(end 76.285344 -416.920172)
		(width 0.14224)
		(layer "In11.Cu")
		(net "P5E_CPU1_P0_TX_BUF_C_DP<9>")
	)
	(segment
		(start 76.970128 -421.30472)
		(end 76.970128 -431.000916)
		(width 0.14224)
		(layer "In11.Cu")
		(net "P5E_CPU1_P0_TX_BUF_C_DP<9>")
	)
	(segment
		(start 77.650086 -431.02149)
		(end 77.650086 -430.689766)
		(width 0.14224)
		(layer "In11.Cu")
		(net "P5E_CPU1_P0_TX_BUF_C_DP<9>")
	)
	(arc
		(start 76.969112 -421.275002)
		(mid 76.969894 -421.289852)
		(end 76.970128 -421.30472)
		(width 0.14224)
		(layer "In11.Cu")
		(net "P5E_CPU1_P0_TX_BUF_C_DP<9>")
	)
	(segment
		(start 72.893174 -409.079954)
		(end 72.893174 -412.299658)
		(width 0.12954)
		(layer "F.Cu")
		(net "P5E_CPU1_P0_TX_BUF_C_DP<8>")
	)
	(segment
		(start 73.189084 -408.784044)
		(end 72.893174 -409.079954)
		(width 0.12954)
		(layer "F.Cu")
		(net "P5E_CPU1_P0_TX_BUF_C_DP<8>")
	)
	(segment
		(start 72.893174 -412.299658)
		(end 73.163684 -412.570168)
		(width 0.12954)
		(layer "F.Cu")
		(net "P5E_CPU1_P0_TX_BUF_C_DP<8>")
	)
	(segment
		(start 73.838562 -415.917888)
		(end 74.136758 -417.41852)
		(width 0.14224)
		(layer "In11.Cu")
		(net "P5E_CPU1_P0_TX_BUF_C_DP<8>")
	)
	(segment
		(start 74.66584 -422.795192)
		(end 74.803254 -425.59605)
		(width 0.14224)
		(layer "In11.Cu")
		(net "P5E_CPU1_P0_TX_BUF_C_DP<8>")
	)
	(segment
		(start 75.52309 -430.125632)
		(end 75.65009 -429.998632)
		(width 0.14224)
		(layer "In11.Cu")
		(net "P5E_CPU1_P0_TX_BUF_C_DP<8>")
	)
	(segment
		(start 74.5363 -420.076122)
		(end 74.41311 -420.226236)
		(width 0.14224)
		(layer "In11.Cu")
		(net "P5E_CPU1_P0_TX_BUF_C_DP<8>")
	)
	(segment
		(start 74.803254 -425.59605)
		(end 74.970132 -427.290738)
		(width 0.14224)
		(layer "In11.Cu")
		(net "P5E_CPU1_P0_TX_BUF_C_DP<8>")
	)
	(segment
		(start 74.970132 -427.290738)
		(end 74.970132 -429.91532)
		(width 0.14224)
		(layer "In11.Cu")
		(net "P5E_CPU1_P0_TX_BUF_C_DP<8>")
	)
	(segment
		(start 73.749662 -415.344102)
		(end 73.912984 -415.738564)
		(width 0.14224)
		(layer "In11.Cu")
		(net "P5E_CPU1_P0_TX_BUF_C_DP<8>")
	)
	(segment
		(start 75.180444 -430.125632)
		(end 75.52309 -430.125632)
		(width 0.14224)
		(layer "In11.Cu")
		(net "P5E_CPU1_P0_TX_BUF_C_DP<8>")
	)
	(segment
		(start 73.570084 -415.269934)
		(end 73.749662 -415.344102)
		(width 0.14224)
		(layer "In11.Cu")
		(net "P5E_CPU1_P0_TX_BUF_C_DP<8>")
	)
	(segment
		(start 74.49439 -419.65118)
		(end 74.5363 -420.076122)
		(width 0.14224)
		(layer "In11.Cu")
		(net "P5E_CPU1_P0_TX_BUF_C_DP<8>")
	)
	(segment
		(start 75.65009 -429.998632)
		(end 75.65009 -429.689768)
		(width 0.14224)
		(layer "In11.Cu")
		(net "P5E_CPU1_P0_TX_BUF_C_DP<8>")
	)
	(segment
		(start 74.344276 -419.528244)
		(end 74.49439 -419.65118)
		(width 0.14224)
		(layer "In11.Cu")
		(net "P5E_CPU1_P0_TX_BUF_C_DP<8>")
	)
	(segment
		(start 74.36612 -418.347652)
		(end 74.40803 -418.772594)
		(width 0.14224)
		(layer "In11.Cu")
		(net "P5E_CPU1_P0_TX_BUF_C_DP<8>")
	)
	(segment
		(start 73.912984 -415.738564)
		(end 73.838562 -415.917888)
		(width 0.14224)
		(layer "In11.Cu")
		(net "P5E_CPU1_P0_TX_BUF_C_DP<8>")
	)
	(segment
		(start 74.136758 -417.41852)
		(end 74.216006 -418.224716)
		(width 0.14224)
		(layer "In11.Cu")
		(net "P5E_CPU1_P0_TX_BUF_C_DP<8>")
	)
	(segment
		(start 73.138284 -414.227772)
		(end 73.317862 -414.30194)
		(width 0.14224)
		(layer "In11.Cu")
		(net "P5E_CPU1_P0_TX_BUF_C_DP<8>")
	)
	(segment
		(start 73.317862 -414.30194)
		(end 73.481184 -414.696656)
		(width 0.14224)
		(layer "In11.Cu")
		(net "P5E_CPU1_P0_TX_BUF_C_DP<8>")
	)
	(segment
		(start 72.872854 -412.860998)
		(end 72.872854 -413.586676)
		(width 0.14224)
		(layer "In11.Cu")
		(net "P5E_CPU1_P0_TX_BUF_C_DP<8>")
	)
	(segment
		(start 73.407016 -414.875726)
		(end 73.570084 -415.269934)
		(width 0.14224)
		(layer "In11.Cu")
		(net "P5E_CPU1_P0_TX_BUF_C_DP<8>")
	)
	(segment
		(start 74.41311 -420.226236)
		(end 74.66584 -422.795192)
		(width 0.14224)
		(layer "In11.Cu")
		(net "P5E_CPU1_P0_TX_BUF_C_DP<8>")
	)
	(segment
		(start 74.40803 -418.772594)
		(end 74.28484 -418.922454)
		(width 0.14224)
		(layer "In11.Cu")
		(net "P5E_CPU1_P0_TX_BUF_C_DP<8>")
	)
	(segment
		(start 73.481184 -414.696656)
		(end 73.407016 -414.875726)
		(width 0.14224)
		(layer "In11.Cu")
		(net "P5E_CPU1_P0_TX_BUF_C_DP<8>")
	)
	(segment
		(start 73.163684 -412.570168)
		(end 72.872854 -412.860998)
		(width 0.14224)
		(layer "In11.Cu")
		(net "P5E_CPU1_P0_TX_BUF_C_DP<8>")
	)
	(segment
		(start 74.28484 -418.922454)
		(end 74.344276 -419.528244)
		(width 0.14224)
		(layer "In11.Cu")
		(net "P5E_CPU1_P0_TX_BUF_C_DP<8>")
	)
	(segment
		(start 74.970132 -429.91532)
		(end 75.180444 -430.125632)
		(width 0.14224)
		(layer "In11.Cu")
		(net "P5E_CPU1_P0_TX_BUF_C_DP<8>")
	)
	(segment
		(start 72.872854 -413.586676)
		(end 73.138284 -414.227772)
		(width 0.14224)
		(layer "In11.Cu")
		(net "P5E_CPU1_P0_TX_BUF_C_DP<8>")
	)
	(segment
		(start 74.216006 -418.224716)
		(end 74.36612 -418.347652)
		(width 0.14224)
		(layer "In11.Cu")
		(net "P5E_CPU1_P0_TX_BUF_C_DP<8>")
	)
	(segment
		(start 69.829934 -412.299658)
		(end 70.100444 -412.570168)
		(width 0.12954)
		(layer "F.Cu")
		(net "P5E_CPU1_P0_TX_BUF_C_DP<7>")
	)
	(segment
		(start 70.125844 -408.784044)
		(end 69.829934 -409.079954)
		(width 0.12954)
		(layer "F.Cu")
		(net "P5E_CPU1_P0_TX_BUF_C_DP<7>")
	)
	(segment
		(start 69.829934 -409.079954)
		(end 69.829934 -412.299658)
		(width 0.12954)
		(layer "F.Cu")
		(net "P5E_CPU1_P0_TX_BUF_C_DP<7>")
	)
	(segment
		(start 72.522588 -431.148744)
		(end 72.649842 -431.02149)
		(width 0.14224)
		(layer "In11.Cu")
		(net "P5E_CPU1_P0_TX_BUF_C_DP<7>")
	)
	(segment
		(start 72.649842 -431.02149)
		(end 72.649842 -430.689766)
		(width 0.14224)
		(layer "In11.Cu")
		(net "P5E_CPU1_P0_TX_BUF_C_DP<7>")
	)
	(segment
		(start 69.809614 -412.860998)
		(end 69.809614 -413.774128)
		(width 0.14224)
		(layer "In11.Cu")
		(net "P5E_CPU1_P0_TX_BUF_C_DP<7>")
	)
	(segment
		(start 70.644258 -414.826196)
		(end 70.881494 -415.181288)
		(width 0.14224)
		(layer "In11.Cu")
		(net "P5E_CPU1_P0_TX_BUF_C_DP<7>")
	)
	(segment
		(start 69.8373 -413.865822)
		(end 70.454012 -414.78835)
		(width 0.14224)
		(layer "In11.Cu")
		(net "P5E_CPU1_P0_TX_BUF_C_DP<7>")
	)
	(segment
		(start 71.470266 -416.309302)
		(end 71.711566 -416.67049)
		(width 0.14224)
		(layer "In11.Cu")
		(net "P5E_CPU1_P0_TX_BUF_C_DP<7>")
	)
	(segment
		(start 71.08063 -415.726118)
		(end 71.270876 -415.763964)
		(width 0.14224)
		(layer "In11.Cu")
		(net "P5E_CPU1_P0_TX_BUF_C_DP<7>")
	)
	(segment
		(start 71.969884 -417.522152)
		(end 71.969884 -431.000916)
		(width 0.14224)
		(layer "In11.Cu")
		(net "P5E_CPU1_P0_TX_BUF_C_DP<7>")
	)
	(segment
		(start 70.881494 -415.181288)
		(end 70.843648 -415.371534)
		(width 0.14224)
		(layer "In11.Cu")
		(net "P5E_CPU1_P0_TX_BUF_C_DP<7>")
	)
	(segment
		(start 71.270876 -415.763964)
		(end 71.508112 -416.119056)
		(width 0.14224)
		(layer "In11.Cu")
		(net "P5E_CPU1_P0_TX_BUF_C_DP<7>")
	)
	(segment
		(start 70.454012 -414.78835)
		(end 70.644258 -414.826196)
		(width 0.14224)
		(layer "In11.Cu")
		(net "P5E_CPU1_P0_TX_BUF_C_DP<7>")
	)
	(segment
		(start 71.969884 -431.000916)
		(end 72.117712 -431.148744)
		(width 0.14224)
		(layer "In11.Cu")
		(net "P5E_CPU1_P0_TX_BUF_C_DP<7>")
	)
	(segment
		(start 72.117712 -431.148744)
		(end 72.522588 -431.148744)
		(width 0.14224)
		(layer "In11.Cu")
		(net "P5E_CPU1_P0_TX_BUF_C_DP<7>")
	)
	(segment
		(start 70.100444 -412.570168)
		(end 69.809614 -412.860998)
		(width 0.14224)
		(layer "In11.Cu")
		(net "P5E_CPU1_P0_TX_BUF_C_DP<7>")
	)
	(segment
		(start 70.843648 -415.371534)
		(end 71.08063 -415.726118)
		(width 0.14224)
		(layer "In11.Cu")
		(net "P5E_CPU1_P0_TX_BUF_C_DP<7>")
	)
	(segment
		(start 71.508112 -416.119056)
		(end 71.470266 -416.309302)
		(width 0.14224)
		(layer "In11.Cu")
		(net "P5E_CPU1_P0_TX_BUF_C_DP<7>")
	)
	(arc
		(start 71.711566 -416.67049)
		(mid 71.903879 -417.077165)
		(end 71.969884 -417.522152)
		(width 0.14224)
		(layer "In11.Cu")
		(net "P5E_CPU1_P0_TX_BUF_C_DP<7>")
	)
	(arc
		(start 69.809614 -413.774128)
		(mid 69.81665 -413.82203)
		(end 69.8373 -413.865822)
		(width 0.14224)
		(layer "In11.Cu")
		(net "P5E_CPU1_P0_TX_BUF_C_DP<7>")
	)
	(segment
		(start 67.062604 -408.784044)
		(end 66.766694 -409.079954)
		(width 0.12954)
		(layer "F.Cu")
		(net "P5E_CPU1_P0_TX_BUF_C_DP<6>")
	)
	(segment
		(start 66.766694 -409.079954)
		(end 66.766694 -412.299658)
		(width 0.12954)
		(layer "F.Cu")
		(net "P5E_CPU1_P0_TX_BUF_C_DP<6>")
	)
	(segment
		(start 66.766694 -412.299658)
		(end 67.037204 -412.570168)
		(width 0.12954)
		(layer "F.Cu")
		(net "P5E_CPU1_P0_TX_BUF_C_DP<6>")
	)
	(segment
		(start 69.574918 -416.829748)
		(end 69.728334 -417.22802)
		(width 0.14224)
		(layer "In11.Cu")
		(net "P5E_CPU1_P0_TX_BUF_C_DP<6>")
	)
	(segment
		(start 66.779394 -413.633412)
		(end 67.032886 -413.91332)
		(width 0.14224)
		(layer "In11.Cu")
		(net "P5E_CPU1_P0_TX_BUF_C_DP<6>")
	)
	(segment
		(start 67.790314 -414.74898)
		(end 67.984116 -414.758632)
		(width 0.14224)
		(layer "In11.Cu")
		(net "P5E_CPU1_P0_TX_BUF_C_DP<6>")
	)
	(segment
		(start 69.969888 -429.91532)
		(end 70.1802 -430.125632)
		(width 0.14224)
		(layer "In11.Cu")
		(net "P5E_CPU1_P0_TX_BUF_C_DP<6>")
	)
	(segment
		(start 69.018658 -416.104324)
		(end 69.243956 -416.35299)
		(width 0.14224)
		(layer "In11.Cu")
		(net "P5E_CPU1_P0_TX_BUF_C_DP<6>")
	)
	(segment
		(start 68.547742 -415.58464)
		(end 68.741544 -415.594292)
		(width 0.14224)
		(layer "In11.Cu")
		(net "P5E_CPU1_P0_TX_BUF_C_DP<6>")
	)
	(segment
		(start 70.1802 -430.125632)
		(end 70.522846 -430.125632)
		(width 0.14224)
		(layer "In11.Cu")
		(net "P5E_CPU1_P0_TX_BUF_C_DP<6>")
	)
	(segment
		(start 69.728334 -417.22802)
		(end 69.649848 -417.405312)
		(width 0.14224)
		(layer "In11.Cu")
		(net "P5E_CPU1_P0_TX_BUF_C_DP<6>")
	)
	(segment
		(start 69.02831 -415.910522)
		(end 69.018658 -416.104324)
		(width 0.14224)
		(layer "In11.Cu")
		(net "P5E_CPU1_P0_TX_BUF_C_DP<6>")
	)
	(segment
		(start 70.522846 -430.125632)
		(end 70.649846 -429.998632)
		(width 0.14224)
		(layer "In11.Cu")
		(net "P5E_CPU1_P0_TX_BUF_C_DP<6>")
	)
	(segment
		(start 66.746374 -412.860998)
		(end 66.746374 -413.548068)
		(width 0.14224)
		(layer "In11.Cu")
		(net "P5E_CPU1_P0_TX_BUF_C_DP<6>")
	)
	(segment
		(start 67.984116 -414.758632)
		(end 68.270882 -415.074862)
		(width 0.14224)
		(layer "In11.Cu")
		(net "P5E_CPU1_P0_TX_BUF_C_DP<6>")
	)
	(segment
		(start 68.270882 -415.074862)
		(end 68.26123 -415.268664)
		(width 0.14224)
		(layer "In11.Cu")
		(net "P5E_CPU1_P0_TX_BUF_C_DP<6>")
	)
	(segment
		(start 67.037204 -412.570168)
		(end 66.746374 -412.860998)
		(width 0.14224)
		(layer "In11.Cu")
		(net "P5E_CPU1_P0_TX_BUF_C_DP<6>")
	)
	(segment
		(start 67.513454 -414.239202)
		(end 67.503802 -414.433004)
		(width 0.14224)
		(layer "In11.Cu")
		(net "P5E_CPU1_P0_TX_BUF_C_DP<6>")
	)
	(segment
		(start 69.649848 -417.405312)
		(end 69.799962 -417.794948)
		(width 0.14224)
		(layer "In11.Cu")
		(net "P5E_CPU1_P0_TX_BUF_C_DP<6>")
	)
	(segment
		(start 67.032886 -413.91332)
		(end 67.226688 -413.922972)
		(width 0.14224)
		(layer "In11.Cu")
		(net "P5E_CPU1_P0_TX_BUF_C_DP<6>")
	)
	(segment
		(start 68.741544 -415.594292)
		(end 69.02831 -415.910522)
		(width 0.14224)
		(layer "In11.Cu")
		(net "P5E_CPU1_P0_TX_BUF_C_DP<6>")
	)
	(segment
		(start 69.243956 -416.35299)
		(end 69.397372 -416.751008)
		(width 0.14224)
		(layer "In11.Cu")
		(net "P5E_CPU1_P0_TX_BUF_C_DP<6>")
	)
	(segment
		(start 67.226688 -413.922972)
		(end 67.513454 -414.239202)
		(width 0.14224)
		(layer "In11.Cu")
		(net "P5E_CPU1_P0_TX_BUF_C_DP<6>")
	)
	(segment
		(start 69.397372 -416.751008)
		(end 69.574918 -416.829748)
		(width 0.14224)
		(layer "In11.Cu")
		(net "P5E_CPU1_P0_TX_BUF_C_DP<6>")
	)
	(segment
		(start 67.503802 -414.433004)
		(end 67.790314 -414.74898)
		(width 0.14224)
		(layer "In11.Cu")
		(net "P5E_CPU1_P0_TX_BUF_C_DP<6>")
	)
	(segment
		(start 69.969888 -418.709094)
		(end 69.969888 -429.91532)
		(width 0.14224)
		(layer "In11.Cu")
		(net "P5E_CPU1_P0_TX_BUF_C_DP<6>")
	)
	(segment
		(start 68.26123 -415.268664)
		(end 68.547742 -415.58464)
		(width 0.14224)
		(layer "In11.Cu")
		(net "P5E_CPU1_P0_TX_BUF_C_DP<6>")
	)
	(segment
		(start 70.649846 -429.998632)
		(end 70.649846 -429.689768)
		(width 0.14224)
		(layer "In11.Cu")
		(net "P5E_CPU1_P0_TX_BUF_C_DP<6>")
	)
	(arc
		(start 69.799962 -417.794948)
		(mid 69.927074 -418.244188)
		(end 69.969888 -418.709094)
		(width 0.14224)
		(layer "In11.Cu")
		(net "P5E_CPU1_P0_TX_BUF_C_DP<6>")
	)
	(arc
		(start 66.746374 -413.548068)
		(mid 66.754906 -413.593832)
		(end 66.779394 -413.633412)
		(width 0.14224)
		(layer "In11.Cu")
		(net "P5E_CPU1_P0_TX_BUF_C_DP<6>")
	)
	(segment
		(start 63.703454 -409.079954)
		(end 63.703454 -412.299658)
		(width 0.12954)
		(layer "F.Cu")
		(net "P5E_CPU1_P0_TX_BUF_C_DP<5>")
	)
	(segment
		(start 63.999364 -408.784044)
		(end 63.703454 -409.079954)
		(width 0.12954)
		(layer "F.Cu")
		(net "P5E_CPU1_P0_TX_BUF_C_DP<5>")
	)
	(segment
		(start 63.703454 -412.299658)
		(end 63.973964 -412.570168)
		(width 0.12954)
		(layer "F.Cu")
		(net "P5E_CPU1_P0_TX_BUF_C_DP<5>")
	)
	(segment
		(start 68.11772 -431.148744)
		(end 68.522596 -431.148744)
		(width 0.14224)
		(layer "In11.Cu")
		(net "P5E_CPU1_P0_TX_BUF_C_DP<5>")
	)
	(segment
		(start 64.063118 -414.173416)
		(end 64.256158 -414.15462)
		(width 0.14224)
		(layer "In11.Cu")
		(net "P5E_CPU1_P0_TX_BUF_C_DP<5>")
	)
	(segment
		(start 67.80022 -417.244276)
		(end 67.87769 -417.339018)
		(width 0.14224)
		(layer "In11.Cu")
		(net "P5E_CPU1_P0_TX_BUF_C_DP<5>")
	)
	(segment
		(start 64.256158 -414.15462)
		(end 64.586104 -414.425638)
		(width 0.14224)
		(layer "In11.Cu")
		(net "P5E_CPU1_P0_TX_BUF_C_DP<5>")
	)
	(segment
		(start 65.476374 -415.334704)
		(end 67.80022 -417.244276)
		(width 0.14224)
		(layer "In11.Cu")
		(net "P5E_CPU1_P0_TX_BUF_C_DP<5>")
	)
	(segment
		(start 63.702692 -413.689546)
		(end 63.764922 -413.882586)
		(width 0.14224)
		(layer "In11.Cu")
		(net "P5E_CPU1_P0_TX_BUF_C_DP<5>")
	)
	(segment
		(start 67.969892 -431.000916)
		(end 68.11772 -431.148744)
		(width 0.14224)
		(layer "In11.Cu")
		(net "P5E_CPU1_P0_TX_BUF_C_DP<5>")
	)
	(segment
		(start 65.457578 -415.141664)
		(end 65.476374 -415.334704)
		(width 0.14224)
		(layer "In11.Cu")
		(net "P5E_CPU1_P0_TX_BUF_C_DP<5>")
	)
	(segment
		(start 67.969892 -417.598098)
		(end 67.969892 -431.000916)
		(width 0.14224)
		(layer "In11.Cu")
		(net "P5E_CPU1_P0_TX_BUF_C_DP<5>")
	)
	(segment
		(start 65.127632 -414.870646)
		(end 65.457578 -415.141664)
		(width 0.14224)
		(layer "In11.Cu")
		(net "P5E_CPU1_P0_TX_BUF_C_DP<5>")
	)
	(segment
		(start 68.64985 -431.02149)
		(end 68.64985 -430.689766)
		(width 0.14224)
		(layer "In11.Cu")
		(net "P5E_CPU1_P0_TX_BUF_C_DP<5>")
	)
	(segment
		(start 64.6049 -414.618678)
		(end 64.934592 -414.889442)
		(width 0.14224)
		(layer "In11.Cu")
		(net "P5E_CPU1_P0_TX_BUF_C_DP<5>")
	)
	(segment
		(start 68.522596 -431.148744)
		(end 68.64985 -431.02149)
		(width 0.14224)
		(layer "In11.Cu")
		(net "P5E_CPU1_P0_TX_BUF_C_DP<5>")
	)
	(segment
		(start 64.934592 -414.889442)
		(end 65.127632 -414.870646)
		(width 0.14224)
		(layer "In11.Cu")
		(net "P5E_CPU1_P0_TX_BUF_C_DP<5>")
	)
	(segment
		(start 64.586104 -414.425638)
		(end 64.6049 -414.618678)
		(width 0.14224)
		(layer "In11.Cu")
		(net "P5E_CPU1_P0_TX_BUF_C_DP<5>")
	)
	(segment
		(start 63.683134 -412.928054)
		(end 63.683134 -413.564832)
		(width 0.14224)
		(layer "In11.Cu")
		(net "P5E_CPU1_P0_TX_BUF_C_DP<5>")
	)
	(segment
		(start 63.973964 -412.570168)
		(end 63.730632 -412.8135)
		(width 0.14224)
		(layer "In11.Cu")
		(net "P5E_CPU1_P0_TX_BUF_C_DP<5>")
	)
	(segment
		(start 63.835026 -413.985964)
		(end 64.063118 -414.173416)
		(width 0.14224)
		(layer "In11.Cu")
		(net "P5E_CPU1_P0_TX_BUF_C_DP<5>")
	)
	(arc
		(start 63.683134 -413.564832)
		(mid 63.688029 -413.627956)
		(end 63.702692 -413.689546)
		(width 0.14224)
		(layer "In11.Cu")
		(net "P5E_CPU1_P0_TX_BUF_C_DP<5>")
	)
	(arc
		(start 63.764922 -413.882586)
		(mid 63.792543 -413.939312)
		(end 63.835026 -413.985964)
		(width 0.14224)
		(layer "In11.Cu")
		(net "P5E_CPU1_P0_TX_BUF_C_DP<5>")
	)
	(arc
		(start 67.87769 -417.339018)
		(mid 67.946185 -417.460587)
		(end 67.969892 -417.598098)
		(width 0.14224)
		(layer "In11.Cu")
		(net "P5E_CPU1_P0_TX_BUF_C_DP<5>")
	)
	(arc
		(start 63.730632 -412.8135)
		(mid 63.69546 -412.866044)
		(end 63.683134 -412.928054)
		(width 0.14224)
		(layer "In11.Cu")
		(net "P5E_CPU1_P0_TX_BUF_C_DP<5>")
	)
	(segment
		(start 60.640214 -409.079954)
		(end 60.640214 -412.299658)
		(width 0.12954)
		(layer "F.Cu")
		(net "P5E_CPU1_P0_TX_BUF_C_DP<4>")
	)
	(segment
		(start 60.640214 -412.299658)
		(end 60.910724 -412.570168)
		(width 0.12954)
		(layer "F.Cu")
		(net "P5E_CPU1_P0_TX_BUF_C_DP<4>")
	)
	(segment
		(start 60.936124 -408.784044)
		(end 60.640214 -409.079954)
		(width 0.12954)
		(layer "F.Cu")
		(net "P5E_CPU1_P0_TX_BUF_C_DP<4>")
	)
	(segment
		(start 66.180208 -430.125632)
		(end 66.522854 -430.125632)
		(width 0.14224)
		(layer "In11.Cu")
		(net "P5E_CPU1_P0_TX_BUF_C_DP<4>")
	)
	(segment
		(start 62.816232 -414.865058)
		(end 63.41364 -415.16554)
		(width 0.14224)
		(layer "In11.Cu")
		(net "P5E_CPU1_P0_TX_BUF_C_DP<4>")
	)
	(segment
		(start 60.657232 -413.707326)
		(end 60.800996 -413.85109)
		(width 0.14224)
		(layer "In11.Cu")
		(net "P5E_CPU1_P0_TX_BUF_C_DP<4>")
	)
	(segment
		(start 64.684402 -416.186874)
		(end 64.877442 -416.167824)
		(width 0.14224)
		(layer "In11.Cu")
		(net "P5E_CPU1_P0_TX_BUF_C_DP<4>")
	)
	(segment
		(start 66.649854 -429.998632)
		(end 66.649854 -429.689768)
		(width 0.14224)
		(layer "In11.Cu")
		(net "P5E_CPU1_P0_TX_BUF_C_DP<4>")
	)
	(segment
		(start 64.877442 -416.167824)
		(end 65.207642 -416.438842)
		(width 0.14224)
		(layer "In11.Cu")
		(net "P5E_CPU1_P0_TX_BUF_C_DP<4>")
	)
	(segment
		(start 62.755272 -414.680654)
		(end 62.816232 -414.865058)
		(width 0.14224)
		(layer "In11.Cu")
		(net "P5E_CPU1_P0_TX_BUF_C_DP<4>")
	)
	(segment
		(start 61.747654 -414.17367)
		(end 61.808614 -414.358074)
		(width 0.14224)
		(layer "In11.Cu")
		(net "P5E_CPU1_P0_TX_BUF_C_DP<4>")
	)
	(segment
		(start 60.800996 -413.85109)
		(end 61.181996 -414.04286)
		(width 0.14224)
		(layer "In11.Cu")
		(net "P5E_CPU1_P0_TX_BUF_C_DP<4>")
	)
	(segment
		(start 63.81242 -415.471102)
		(end 63.81242 -415.471356)
		(width 0.14224)
		(layer "In11.Cu")
		(net "P5E_CPU1_P0_TX_BUF_C_DP<4>")
	)
	(segment
		(start 60.910724 -412.570168)
		(end 60.619894 -412.860998)
		(width 0.14224)
		(layer "In11.Cu")
		(net "P5E_CPU1_P0_TX_BUF_C_DP<4>")
	)
	(segment
		(start 62.189614 -414.549844)
		(end 62.373764 -414.488884)
		(width 0.14224)
		(layer "In11.Cu")
		(net "P5E_CPU1_P0_TX_BUF_C_DP<4>")
	)
	(segment
		(start 60.619894 -412.860998)
		(end 60.619894 -413.617156)
		(width 0.14224)
		(layer "In11.Cu")
		(net "P5E_CPU1_P0_TX_BUF_C_DP<4>")
	)
	(segment
		(start 61.366146 -413.9819)
		(end 61.747654 -414.17367)
		(width 0.14224)
		(layer "In11.Cu")
		(net "P5E_CPU1_P0_TX_BUF_C_DP<4>")
	)
	(segment
		(start 64.35471 -415.916364)
		(end 64.684402 -416.186874)
		(width 0.14224)
		(layer "In11.Cu")
		(net "P5E_CPU1_P0_TX_BUF_C_DP<4>")
	)
	(segment
		(start 63.81242 -415.471356)
		(end 64.00546 -415.452306)
		(width 0.14224)
		(layer "In11.Cu")
		(net "P5E_CPU1_P0_TX_BUF_C_DP<4>")
	)
	(segment
		(start 61.808614 -414.358074)
		(end 62.189614 -414.549844)
		(width 0.14224)
		(layer "In11.Cu")
		(net "P5E_CPU1_P0_TX_BUF_C_DP<4>")
	)
	(segment
		(start 63.510668 -415.22396)
		(end 63.81242 -415.471102)
		(width 0.14224)
		(layer "In11.Cu")
		(net "P5E_CPU1_P0_TX_BUF_C_DP<4>")
	)
	(segment
		(start 65.226692 -416.631882)
		(end 65.608962 -416.945572)
		(width 0.14224)
		(layer "In11.Cu")
		(net "P5E_CPU1_P0_TX_BUF_C_DP<4>")
	)
	(segment
		(start 64.00546 -415.452306)
		(end 64.33566 -415.723324)
		(width 0.14224)
		(layer "In11.Cu")
		(net "P5E_CPU1_P0_TX_BUF_C_DP<4>")
	)
	(segment
		(start 62.373764 -414.488884)
		(end 62.755272 -414.680654)
		(width 0.14224)
		(layer "In11.Cu")
		(net "P5E_CPU1_P0_TX_BUF_C_DP<4>")
	)
	(segment
		(start 65.207642 -416.438842)
		(end 65.226692 -416.631882)
		(width 0.14224)
		(layer "In11.Cu")
		(net "P5E_CPU1_P0_TX_BUF_C_DP<4>")
	)
	(segment
		(start 65.969896 -429.91532)
		(end 66.180208 -430.125632)
		(width 0.14224)
		(layer "In11.Cu")
		(net "P5E_CPU1_P0_TX_BUF_C_DP<4>")
	)
	(segment
		(start 63.41364 -415.16554)
		(end 63.510668 -415.22396)
		(width 0.14224)
		(layer "In11.Cu")
		(net "P5E_CPU1_P0_TX_BUF_C_DP<4>")
	)
	(segment
		(start 64.33566 -415.723324)
		(end 64.35471 -415.916364)
		(width 0.14224)
		(layer "In11.Cu")
		(net "P5E_CPU1_P0_TX_BUF_C_DP<4>")
	)
	(segment
		(start 61.181996 -414.04286)
		(end 61.366146 -413.9819)
		(width 0.14224)
		(layer "In11.Cu")
		(net "P5E_CPU1_P0_TX_BUF_C_DP<4>")
	)
	(segment
		(start 66.522854 -430.125632)
		(end 66.649854 -429.998632)
		(width 0.14224)
		(layer "In11.Cu")
		(net "P5E_CPU1_P0_TX_BUF_C_DP<4>")
	)
	(segment
		(start 65.969896 -417.709604)
		(end 65.969896 -429.91532)
		(width 0.14224)
		(layer "In11.Cu")
		(net "P5E_CPU1_P0_TX_BUF_C_DP<4>")
	)
	(arc
		(start 60.619894 -413.617156)
		(mid 60.6296 -413.665951)
		(end 60.657232 -413.707326)
		(width 0.14224)
		(layer "In11.Cu")
		(net "P5E_CPU1_P0_TX_BUF_C_DP<4>")
	)
	(arc
		(start 65.608962 -416.945572)
		(mid 65.875245 -417.28706)
		(end 65.969896 -417.709604)
		(width 0.14224)
		(layer "In11.Cu")
		(net "P5E_CPU1_P0_TX_BUF_C_DP<4>")
	)
	(segment
		(start 57.872884 -408.784044)
		(end 57.576974 -409.079954)
		(width 0.12954)
		(layer "F.Cu")
		(net "P5E_CPU1_P0_TX_BUF_C_DP<3>")
	)
	(segment
		(start 57.576974 -412.299658)
		(end 57.847484 -412.570168)
		(width 0.12954)
		(layer "F.Cu")
		(net "P5E_CPU1_P0_TX_BUF_C_DP<3>")
	)
	(segment
		(start 57.576974 -409.079954)
		(end 57.576974 -412.299658)
		(width 0.12954)
		(layer "F.Cu")
		(net "P5E_CPU1_P0_TX_BUF_C_DP<3>")
	)
	(segment
		(start 59.339226 -414.633156)
		(end 60.220098 -414.900364)
		(width 0.14224)
		(layer "In11.Cu")
		(net "P5E_CPU1_P0_TX_BUF_C_DP<3>")
	)
	(segment
		(start 61.992764 -415.634932)
		(end 63.640208 -417.282376)
		(width 0.14224)
		(layer "In11.Cu")
		(net "P5E_CPU1_P0_TX_BUF_C_DP<3>")
	)
	(segment
		(start 58.25998 -414.305496)
		(end 58.668158 -414.429194)
		(width 0.14224)
		(layer "In11.Cu")
		(net "P5E_CPU1_P0_TX_BUF_C_DP<3>")
	)
	(segment
		(start 63.9699 -418.078412)
		(end 63.9699 -431.000916)
		(width 0.14224)
		(layer "In11.Cu")
		(net "P5E_CPU1_P0_TX_BUF_C_DP<3>")
	)
	(segment
		(start 57.556654 -412.860998)
		(end 57.556654 -413.617156)
		(width 0.14224)
		(layer "In11.Cu")
		(net "P5E_CPU1_P0_TX_BUF_C_DP<3>")
	)
	(segment
		(start 58.668158 -414.429194)
		(end 58.839354 -414.337754)
		(width 0.14224)
		(layer "In11.Cu")
		(net "P5E_CPU1_P0_TX_BUF_C_DP<3>")
	)
	(segment
		(start 59.247786 -414.461706)
		(end 59.339226 -414.633156)
		(width 0.14224)
		(layer "In11.Cu")
		(net "P5E_CPU1_P0_TX_BUF_C_DP<3>")
	)
	(segment
		(start 60.614306 -415.063686)
		(end 60.793376 -414.989264)
		(width 0.14224)
		(layer "In11.Cu")
		(net "P5E_CPU1_P0_TX_BUF_C_DP<3>")
	)
	(segment
		(start 57.76722 -414.042098)
		(end 58.25998 -414.305496)
		(width 0.14224)
		(layer "In11.Cu")
		(net "P5E_CPU1_P0_TX_BUF_C_DP<3>")
	)
	(segment
		(start 57.708292 -413.98317)
		(end 57.76722 -414.042098)
		(width 0.14224)
		(layer "In11.Cu")
		(net "P5E_CPU1_P0_TX_BUF_C_DP<3>")
	)
	(segment
		(start 64.522604 -431.148744)
		(end 64.649858 -431.02149)
		(width 0.14224)
		(layer "In11.Cu")
		(net "P5E_CPU1_P0_TX_BUF_C_DP<3>")
	)
	(segment
		(start 63.9699 -431.000916)
		(end 64.117728 -431.148744)
		(width 0.14224)
		(layer "In11.Cu")
		(net "P5E_CPU1_P0_TX_BUF_C_DP<3>")
	)
	(segment
		(start 57.847484 -412.570168)
		(end 57.556654 -412.860998)
		(width 0.14224)
		(layer "In11.Cu")
		(net "P5E_CPU1_P0_TX_BUF_C_DP<3>")
	)
	(segment
		(start 58.839354 -414.337754)
		(end 59.247786 -414.461706)
		(width 0.14224)
		(layer "In11.Cu")
		(net "P5E_CPU1_P0_TX_BUF_C_DP<3>")
	)
	(segment
		(start 64.117728 -431.148744)
		(end 64.522604 -431.148744)
		(width 0.14224)
		(layer "In11.Cu")
		(net "P5E_CPU1_P0_TX_BUF_C_DP<3>")
	)
	(segment
		(start 61.187838 -415.15284)
		(end 61.262006 -415.332164)
		(width 0.14224)
		(layer "In11.Cu")
		(net "P5E_CPU1_P0_TX_BUF_C_DP<3>")
	)
	(segment
		(start 60.220098 -414.900364)
		(end 60.614306 -415.063686)
		(width 0.14224)
		(layer "In11.Cu")
		(net "P5E_CPU1_P0_TX_BUF_C_DP<3>")
	)
	(segment
		(start 60.793376 -414.989264)
		(end 61.187838 -415.15284)
		(width 0.14224)
		(layer "In11.Cu")
		(net "P5E_CPU1_P0_TX_BUF_C_DP<3>")
	)
	(segment
		(start 64.649858 -431.02149)
		(end 64.649858 -430.689766)
		(width 0.14224)
		(layer "In11.Cu")
		(net "P5E_CPU1_P0_TX_BUF_C_DP<3>")
	)
	(segment
		(start 61.262006 -415.332164)
		(end 61.992764 -415.634932)
		(width 0.14224)
		(layer "In11.Cu")
		(net "P5E_CPU1_P0_TX_BUF_C_DP<3>")
	)
	(arc
		(start 63.640208 -417.282376)
		(mid 63.884243 -417.6476)
		(end 63.9699 -418.078412)
		(width 0.14224)
		(layer "In11.Cu")
		(net "P5E_CPU1_P0_TX_BUF_C_DP<3>")
	)
	(arc
		(start 57.556654 -413.617156)
		(mid 57.596058 -413.815253)
		(end 57.708292 -413.98317)
		(width 0.14224)
		(layer "In11.Cu")
		(net "P5E_CPU1_P0_TX_BUF_C_DP<3>")
	)
	(segment
		(start 54.513734 -412.299658)
		(end 54.784244 -412.570168)
		(width 0.12954)
		(layer "F.Cu")
		(net "P5E_CPU1_P0_TX_BUF_C_DP<2>")
	)
	(segment
		(start 54.809644 -408.784044)
		(end 54.513734 -409.079954)
		(width 0.12954)
		(layer "F.Cu")
		(net "P5E_CPU1_P0_TX_BUF_C_DP<2>")
	)
	(segment
		(start 54.513734 -409.079954)
		(end 54.513734 -412.299658)
		(width 0.12954)
		(layer "F.Cu")
		(net "P5E_CPU1_P0_TX_BUF_C_DP<2>")
	)
	(segment
		(start 58.347864 -415.57321)
		(end 58.51652 -415.477452)
		(width 0.14224)
		(layer "In11.Cu")
		(net "P5E_CPU1_P0_TX_BUF_C_DP<2>")
	)
	(segment
		(start 57.029858 -415.022284)
		(end 57.104026 -415.201862)
		(width 0.14224)
		(layer "In11.Cu")
		(net "P5E_CPU1_P0_TX_BUF_C_DP<2>")
	)
	(segment
		(start 55.581296 -414.42259)
		(end 55.975758 -414.585912)
		(width 0.14224)
		(layer "In11.Cu")
		(net "P5E_CPU1_P0_TX_BUF_C_DP<2>")
	)
	(segment
		(start 60.84697 -416.264598)
		(end 61.029088 -416.329876)
		(width 0.14224)
		(layer "In11.Cu")
		(net "P5E_CPU1_P0_TX_BUF_C_DP<2>")
	)
	(segment
		(start 54.889908 -414.284668)
		(end 55.402226 -414.496758)
		(width 0.14224)
		(layer "In11.Cu")
		(net "P5E_CPU1_P0_TX_BUF_C_DP<2>")
	)
	(segment
		(start 59.023758 -415.760408)
		(end 59.589162 -415.916618)
		(width 0.14224)
		(layer "In11.Cu")
		(net "P5E_CPU1_P0_TX_BUF_C_DP<2>")
	)
	(segment
		(start 59.589162 -415.916618)
		(end 59.757818 -415.821114)
		(width 0.14224)
		(layer "In11.Cu")
		(net "P5E_CPU1_P0_TX_BUF_C_DP<2>")
	)
	(segment
		(start 57.936638 -415.459418)
		(end 58.347864 -415.57321)
		(width 0.14224)
		(layer "In11.Cu")
		(net "P5E_CPU1_P0_TX_BUF_C_DP<2>")
	)
	(segment
		(start 54.493414 -413.777176)
		(end 54.64683 -414.064196)
		(width 0.14224)
		(layer "In11.Cu")
		(net "P5E_CPU1_P0_TX_BUF_C_DP<2>")
	)
	(segment
		(start 59.757818 -415.821114)
		(end 60.169298 -415.934652)
		(width 0.14224)
		(layer "In11.Cu")
		(net "P5E_CPU1_P0_TX_BUF_C_DP<2>")
	)
	(segment
		(start 54.493414 -412.860998)
		(end 54.493414 -413.777176)
		(width 0.14224)
		(layer "In11.Cu")
		(net "P5E_CPU1_P0_TX_BUF_C_DP<2>")
	)
	(segment
		(start 56.456072 -414.933384)
		(end 56.635396 -414.858962)
		(width 0.14224)
		(layer "In11.Cu")
		(net "P5E_CPU1_P0_TX_BUF_C_DP<2>")
	)
	(segment
		(start 61.969904 -417.777676)
		(end 61.969904 -429.91532)
		(width 0.14224)
		(layer "In11.Cu")
		(net "P5E_CPU1_P0_TX_BUF_C_DP<2>")
	)
	(segment
		(start 56.05018 -414.765236)
		(end 56.456072 -414.933384)
		(width 0.14224)
		(layer "In11.Cu")
		(net "P5E_CPU1_P0_TX_BUF_C_DP<2>")
	)
	(segment
		(start 62.649862 -429.998632)
		(end 62.649862 -429.689768)
		(width 0.14224)
		(layer "In11.Cu")
		(net "P5E_CPU1_P0_TX_BUF_C_DP<2>")
	)
	(segment
		(start 62.180216 -430.125632)
		(end 62.522862 -430.125632)
		(width 0.14224)
		(layer "In11.Cu")
		(net "P5E_CPU1_P0_TX_BUF_C_DP<2>")
	)
	(segment
		(start 55.402226 -414.496758)
		(end 55.581296 -414.42259)
		(width 0.14224)
		(layer "In11.Cu")
		(net "P5E_CPU1_P0_TX_BUF_C_DP<2>")
	)
	(segment
		(start 62.522862 -430.125632)
		(end 62.649862 -429.998632)
		(width 0.14224)
		(layer "In11.Cu")
		(net "P5E_CPU1_P0_TX_BUF_C_DP<2>")
	)
	(segment
		(start 57.104026 -415.201862)
		(end 57.531 -415.378646)
		(width 0.14224)
		(layer "In11.Cu")
		(net "P5E_CPU1_P0_TX_BUF_C_DP<2>")
	)
	(segment
		(start 60.265056 -416.103816)
		(end 60.84697 -416.264598)
		(width 0.14224)
		(layer "In11.Cu")
		(net "P5E_CPU1_P0_TX_BUF_C_DP<2>")
	)
	(segment
		(start 55.975758 -414.585912)
		(end 56.05018 -414.765236)
		(width 0.14224)
		(layer "In11.Cu")
		(net "P5E_CPU1_P0_TX_BUF_C_DP<2>")
	)
	(segment
		(start 61.969904 -429.91532)
		(end 62.180216 -430.125632)
		(width 0.14224)
		(layer "In11.Cu")
		(net "P5E_CPU1_P0_TX_BUF_C_DP<2>")
	)
	(segment
		(start 56.635396 -414.858962)
		(end 57.029858 -415.022284)
		(width 0.14224)
		(layer "In11.Cu")
		(net "P5E_CPU1_P0_TX_BUF_C_DP<2>")
	)
	(segment
		(start 60.169298 -415.934652)
		(end 60.265056 -416.103816)
		(width 0.14224)
		(layer "In11.Cu")
		(net "P5E_CPU1_P0_TX_BUF_C_DP<2>")
	)
	(segment
		(start 54.784244 -412.570168)
		(end 54.493414 -412.860998)
		(width 0.14224)
		(layer "In11.Cu")
		(net "P5E_CPU1_P0_TX_BUF_C_DP<2>")
	)
	(segment
		(start 57.531 -415.378646)
		(end 57.936638 -415.459418)
		(width 0.14224)
		(layer "In11.Cu")
		(net "P5E_CPU1_P0_TX_BUF_C_DP<2>")
	)
	(segment
		(start 61.029088 -416.329876)
		(end 61.61151 -416.912298)
		(width 0.14224)
		(layer "In11.Cu")
		(net "P5E_CPU1_P0_TX_BUF_C_DP<2>")
	)
	(segment
		(start 54.64683 -414.064196)
		(end 54.889908 -414.284668)
		(width 0.14224)
		(layer "In11.Cu")
		(net "P5E_CPU1_P0_TX_BUF_C_DP<2>")
	)
	(segment
		(start 58.51652 -415.477452)
		(end 58.928 -415.591244)
		(width 0.14224)
		(layer "In11.Cu")
		(net "P5E_CPU1_P0_TX_BUF_C_DP<2>")
	)
	(segment
		(start 58.928 -415.591244)
		(end 59.023758 -415.760408)
		(width 0.14224)
		(layer "In11.Cu")
		(net "P5E_CPU1_P0_TX_BUF_C_DP<2>")
	)
	(arc
		(start 61.61151 -416.912298)
		(mid 61.876749 -417.309351)
		(end 61.969904 -417.777676)
		(width 0.14224)
		(layer "In11.Cu")
		(net "P5E_CPU1_P0_TX_BUF_C_DP<2>")
	)
	(segment
		(start 51.450494 -409.079954)
		(end 51.450494 -412.299658)
		(width 0.12954)
		(layer "F.Cu")
		(net "P5E_CPU1_P0_TX_BUF_C_DP<1>")
	)
	(segment
		(start 51.746404 -408.784044)
		(end 51.450494 -409.079954)
		(width 0.12954)
		(layer "F.Cu")
		(net "P5E_CPU1_P0_TX_BUF_C_DP<1>")
	)
	(segment
		(start 51.450494 -412.299658)
		(end 51.721004 -412.570168)
		(width 0.12954)
		(layer "F.Cu")
		(net "P5E_CPU1_P0_TX_BUF_C_DP<1>")
	)
	(segment
		(start 52.902104 -414.996884)
		(end 53.09235 -414.959038)
		(width 0.14224)
		(layer "In11.Cu")
		(net "P5E_CPU1_P0_TX_BUF_C_DP<1>")
	)
	(segment
		(start 57.829196 -416.623754)
		(end 59.058556 -416.744658)
		(width 0.14224)
		(layer "In11.Cu")
		(net "P5E_CPU1_P0_TX_BUF_C_DP<1>")
	)
	(segment
		(start 51.430174 -412.860998)
		(end 51.430174 -413.616902)
		(width 0.14224)
		(layer "In11.Cu")
		(net "P5E_CPU1_P0_TX_BUF_C_DP<1>")
	)
	(segment
		(start 53.447442 -415.196274)
		(end 53.485288 -415.38652)
		(width 0.14224)
		(layer "In11.Cu")
		(net "P5E_CPU1_P0_TX_BUF_C_DP<1>")
	)
	(segment
		(start 60.522612 -431.148744)
		(end 60.649866 -431.02149)
		(width 0.14224)
		(layer "In11.Cu")
		(net "P5E_CPU1_P0_TX_BUF_C_DP<1>")
	)
	(segment
		(start 52.154582 -414.332166)
		(end 52.509674 -414.569656)
		(width 0.14224)
		(layer "In11.Cu")
		(net "P5E_CPU1_P0_TX_BUF_C_DP<1>")
	)
	(segment
		(start 60.649866 -431.02149)
		(end 60.649866 -430.689766)
		(width 0.14224)
		(layer "In11.Cu")
		(net "P5E_CPU1_P0_TX_BUF_C_DP<1>")
	)
	(segment
		(start 52.54752 -414.759902)
		(end 52.902104 -414.996884)
		(width 0.14224)
		(layer "In11.Cu")
		(net "P5E_CPU1_P0_TX_BUF_C_DP<1>")
	)
	(segment
		(start 53.839872 -415.623502)
		(end 57.829196 -416.623754)
		(width 0.14224)
		(layer "In11.Cu")
		(net "P5E_CPU1_P0_TX_BUF_C_DP<1>")
	)
	(segment
		(start 53.485288 -415.38652)
		(end 53.839872 -415.623502)
		(width 0.14224)
		(layer "In11.Cu")
		(net "P5E_CPU1_P0_TX_BUF_C_DP<1>")
	)
	(segment
		(start 51.759358 -414.233106)
		(end 51.964336 -414.370012)
		(width 0.14224)
		(layer "In11.Cu")
		(net "P5E_CPU1_P0_TX_BUF_C_DP<1>")
	)
	(segment
		(start 59.969908 -431.000916)
		(end 60.117736 -431.148744)
		(width 0.14224)
		(layer "In11.Cu")
		(net "P5E_CPU1_P0_TX_BUF_C_DP<1>")
	)
	(segment
		(start 52.509674 -414.569656)
		(end 52.54752 -414.759902)
		(width 0.14224)
		(layer "In11.Cu")
		(net "P5E_CPU1_P0_TX_BUF_C_DP<1>")
	)
	(segment
		(start 51.964336 -414.370012)
		(end 52.154582 -414.332166)
		(width 0.14224)
		(layer "In11.Cu")
		(net "P5E_CPU1_P0_TX_BUF_C_DP<1>")
	)
	(segment
		(start 59.969908 -417.915344)
		(end 59.969908 -431.000916)
		(width 0.14224)
		(layer "In11.Cu")
		(net "P5E_CPU1_P0_TX_BUF_C_DP<1>")
	)
	(segment
		(start 59.058556 -416.744658)
		(end 59.304682 -416.861244)
		(width 0.14224)
		(layer "In11.Cu")
		(net "P5E_CPU1_P0_TX_BUF_C_DP<1>")
	)
	(segment
		(start 53.09235 -414.959038)
		(end 53.447442 -415.196274)
		(width 0.14224)
		(layer "In11.Cu")
		(net "P5E_CPU1_P0_TX_BUF_C_DP<1>")
	)
	(segment
		(start 51.721004 -412.570168)
		(end 51.430174 -412.860998)
		(width 0.14224)
		(layer "In11.Cu")
		(net "P5E_CPU1_P0_TX_BUF_C_DP<1>")
	)
	(segment
		(start 60.117736 -431.148744)
		(end 60.522612 -431.148744)
		(width 0.14224)
		(layer "In11.Cu")
		(net "P5E_CPU1_P0_TX_BUF_C_DP<1>")
	)
	(segment
		(start 59.304682 -416.861244)
		(end 59.694826 -417.251388)
		(width 0.14224)
		(layer "In11.Cu")
		(net "P5E_CPU1_P0_TX_BUF_C_DP<1>")
	)
	(arc
		(start 51.430174 -413.616902)
		(mid 51.517548 -413.966275)
		(end 51.759358 -414.233106)
		(width 0.14224)
		(layer "In11.Cu")
		(net "P5E_CPU1_P0_TX_BUF_C_DP<1>")
	)
	(arc
		(start 59.694826 -417.251388)
		(mid 59.898424 -417.555999)
		(end 59.969908 -417.915344)
		(width 0.14224)
		(layer "In11.Cu")
		(net "P5E_CPU1_P0_TX_BUF_C_DP<1>")
	)
	(segment
		(start 94.631764 -408.784044)
		(end 94.335854 -409.079954)
		(width 0.12954)
		(layer "F.Cu")
		(net "P5E_CPU1_P0_TX_BUF_C_DP<15>")
	)
	(segment
		(start 94.335854 -409.079954)
		(end 94.335854 -412.299658)
		(width 0.12954)
		(layer "F.Cu")
		(net "P5E_CPU1_P0_TX_BUF_C_DP<15>")
	)
	(segment
		(start 94.335854 -412.299658)
		(end 94.606364 -412.570168)
		(width 0.12954)
		(layer "F.Cu")
		(net "P5E_CPU1_P0_TX_BUF_C_DP<15>")
	)
	(segment
		(start 91.603576 -420.23538)
		(end 89.12606 -423.943272)
		(width 0.14224)
		(layer "In11.Cu")
		(net "P5E_CPU1_P0_TX_BUF_C_DP<15>")
	)
	(segment
		(start 94.194884 -414.658048)
		(end 94.070932 -415.066734)
		(width 0.14224)
		(layer "In11.Cu")
		(net "P5E_CPU1_P0_TX_BUF_C_DP<15>")
	)
	(segment
		(start 93.250766 -417.07435)
		(end 93.067886 -417.139628)
		(width 0.14224)
		(layer "In11.Cu")
		(net "P5E_CPU1_P0_TX_BUF_C_DP<15>")
	)
	(segment
		(start 88.970104 -424.457622)
		(end 88.970104 -431.000916)
		(width 0.14224)
		(layer "In11.Cu")
		(net "P5E_CPU1_P0_TX_BUF_C_DP<15>")
	)
	(segment
		(start 93.711776 -415.778188)
		(end 93.36786 -416.505644)
		(width 0.14224)
		(layer "In11.Cu")
		(net "P5E_CPU1_P0_TX_BUF_C_DP<15>")
	)
	(segment
		(start 93.067886 -417.139628)
		(end 91.603576 -420.23538)
		(width 0.14224)
		(layer "In11.Cu")
		(net "P5E_CPU1_P0_TX_BUF_C_DP<15>")
	)
	(segment
		(start 89.117932 -431.148744)
		(end 89.522808 -431.148744)
		(width 0.14224)
		(layer "In11.Cu")
		(net "P5E_CPU1_P0_TX_BUF_C_DP<15>")
	)
	(segment
		(start 94.070932 -415.066734)
		(end 93.899736 -415.158174)
		(width 0.14224)
		(layer "In11.Cu")
		(net "P5E_CPU1_P0_TX_BUF_C_DP<15>")
	)
	(segment
		(start 93.433138 -416.68827)
		(end 93.250766 -417.07435)
		(width 0.14224)
		(layer "In11.Cu")
		(net "P5E_CPU1_P0_TX_BUF_C_DP<15>")
	)
	(segment
		(start 93.899736 -415.158174)
		(end 93.711776 -415.778188)
		(width 0.14224)
		(layer "In11.Cu")
		(net "P5E_CPU1_P0_TX_BUF_C_DP<15>")
	)
	(segment
		(start 94.291404 -413.867092)
		(end 94.103444 -414.486852)
		(width 0.14224)
		(layer "In11.Cu")
		(net "P5E_CPU1_P0_TX_BUF_C_DP<15>")
	)
	(segment
		(start 94.315534 -412.860998)
		(end 94.315534 -413.703516)
		(width 0.14224)
		(layer "In11.Cu")
		(net "P5E_CPU1_P0_TX_BUF_C_DP<15>")
	)
	(segment
		(start 89.522808 -431.148744)
		(end 89.650062 -431.02149)
		(width 0.14224)
		(layer "In11.Cu")
		(net "P5E_CPU1_P0_TX_BUF_C_DP<15>")
	)
	(segment
		(start 89.650062 -431.02149)
		(end 89.650062 -430.689766)
		(width 0.14224)
		(layer "In11.Cu")
		(net "P5E_CPU1_P0_TX_BUF_C_DP<15>")
	)
	(segment
		(start 94.103444 -414.486852)
		(end 94.194884 -414.658048)
		(width 0.14224)
		(layer "In11.Cu")
		(net "P5E_CPU1_P0_TX_BUF_C_DP<15>")
	)
	(segment
		(start 93.36786 -416.505644)
		(end 93.433138 -416.68827)
		(width 0.14224)
		(layer "In11.Cu")
		(net "P5E_CPU1_P0_TX_BUF_C_DP<15>")
	)
	(segment
		(start 94.606364 -412.570168)
		(end 94.315534 -412.860998)
		(width 0.14224)
		(layer "In11.Cu")
		(net "P5E_CPU1_P0_TX_BUF_C_DP<15>")
	)
	(segment
		(start 88.970104 -431.000916)
		(end 89.117932 -431.148744)
		(width 0.14224)
		(layer "In11.Cu")
		(net "P5E_CPU1_P0_TX_BUF_C_DP<15>")
	)
	(arc
		(start 89.12606 -423.943272)
		(mid 89.00991 -424.188877)
		(end 88.970104 -424.457622)
		(width 0.14224)
		(layer "In11.Cu")
		(net "P5E_CPU1_P0_TX_BUF_C_DP<15>")
	)
	(arc
		(start 94.315534 -413.703516)
		(mid 94.309515 -413.786197)
		(end 94.291404 -413.867092)
		(width 0.14224)
		(layer "In11.Cu")
		(net "P5E_CPU1_P0_TX_BUF_C_DP<15>")
	)
	(segment
		(start 91.272614 -409.079954)
		(end 91.272614 -412.299658)
		(width 0.12954)
		(layer "F.Cu")
		(net "P5E_CPU1_P0_TX_BUF_C_DP<14>")
	)
	(segment
		(start 91.272614 -412.299658)
		(end 91.543124 -412.570168)
		(width 0.12954)
		(layer "F.Cu")
		(net "P5E_CPU1_P0_TX_BUF_C_DP<14>")
	)
	(segment
		(start 91.568524 -408.784044)
		(end 91.272614 -409.079954)
		(width 0.12954)
		(layer "F.Cu")
		(net "P5E_CPU1_P0_TX_BUF_C_DP<14>")
	)
	(segment
		(start 89.381584 -418.634672)
		(end 88.925654 -419.647624)
		(width 0.14224)
		(layer "In11.Cu")
		(net "P5E_CPU1_P0_TX_BUF_C_DP<14>")
	)
	(segment
		(start 87.124286 -423.734484)
		(end 87.12454 -423.734484)
		(width 0.14224)
		(layer "In11.Cu")
		(net "P5E_CPU1_P0_TX_BUF_C_DP<14>")
	)
	(segment
		(start 86.970108 -429.91532)
		(end 87.18042 -430.125632)
		(width 0.14224)
		(layer "In11.Cu")
		(net "P5E_CPU1_P0_TX_BUF_C_DP<14>")
	)
	(segment
		(start 88.747346 -420.042086)
		(end 88.815926 -420.223442)
		(width 0.14224)
		(layer "In11.Cu")
		(net "P5E_CPU1_P0_TX_BUF_C_DP<14>")
	)
	(segment
		(start 90.456766 -415.847022)
		(end 90.30335 -416.24504)
		(width 0.14224)
		(layer "In11.Cu")
		(net "P5E_CPU1_P0_TX_BUF_C_DP<14>")
	)
	(segment
		(start 87.523066 -430.125632)
		(end 87.650066 -429.998632)
		(width 0.14224)
		(layer "In11.Cu")
		(net "P5E_CPU1_P0_TX_BUF_C_DP<14>")
	)
	(segment
		(start 86.970108 -424.509946)
		(end 86.970108 -429.91532)
		(width 0.14224)
		(layer "In11.Cu")
		(net "P5E_CPU1_P0_TX_BUF_C_DP<14>")
	)
	(segment
		(start 87.18042 -430.125632)
		(end 87.523066 -430.125632)
		(width 0.14224)
		(layer "In11.Cu")
		(net "P5E_CPU1_P0_TX_BUF_C_DP<14>")
	)
	(segment
		(start 89.637616 -417.975542)
		(end 89.633298 -417.981892)
		(width 0.14224)
		(layer "In11.Cu")
		(net "P5E_CPU1_P0_TX_BUF_C_DP<14>")
	)
	(segment
		(start 89.64549 -417.951666)
		(end 89.637616 -417.975542)
		(width 0.14224)
		(layer "In11.Cu")
		(net "P5E_CPU1_P0_TX_BUF_C_DP<14>")
	)
	(segment
		(start 88.640666 -420.612824)
		(end 88.459056 -420.681404)
		(width 0.14224)
		(layer "In11.Cu")
		(net "P5E_CPU1_P0_TX_BUF_C_DP<14>")
	)
	(segment
		(start 87.588344 -422.613836)
		(end 87.124286 -423.734484)
		(width 0.14224)
		(layer "In11.Cu")
		(net "P5E_CPU1_P0_TX_BUF_C_DP<14>")
	)
	(segment
		(start 88.924892 -419.647878)
		(end 88.747346 -420.042086)
		(width 0.14224)
		(layer "In11.Cu")
		(net "P5E_CPU1_P0_TX_BUF_C_DP<14>")
	)
	(segment
		(start 88.925654 -419.647624)
		(end 88.924892 -419.647878)
		(width 0.14224)
		(layer "In11.Cu")
		(net "P5E_CPU1_P0_TX_BUF_C_DP<14>")
	)
	(segment
		(start 89.822528 -417.87318)
		(end 89.64549 -417.951666)
		(width 0.14224)
		(layer "In11.Cu")
		(net "P5E_CPU1_P0_TX_BUF_C_DP<14>")
	)
	(segment
		(start 90.634312 -415.768536)
		(end 90.456766 -415.847022)
		(width 0.14224)
		(layer "In11.Cu")
		(net "P5E_CPU1_P0_TX_BUF_C_DP<14>")
	)
	(segment
		(start 91.171776 -413.994092)
		(end 90.709496 -415.191956)
		(width 0.14224)
		(layer "In11.Cu")
		(net "P5E_CPU1_P0_TX_BUF_C_DP<14>")
	)
	(segment
		(start 90.709242 -415.192718)
		(end 90.787982 -415.37001)
		(width 0.14224)
		(layer "In11.Cu")
		(net "P5E_CPU1_P0_TX_BUF_C_DP<14>")
	)
	(segment
		(start 87.12454 -423.734484)
		(end 87.124286 -423.734738)
		(width 0.14224)
		(layer "In11.Cu")
		(net "P5E_CPU1_P0_TX_BUF_C_DP<14>")
	)
	(segment
		(start 87.650066 -429.998632)
		(end 87.650066 -429.689768)
		(width 0.14224)
		(layer "In11.Cu")
		(net "P5E_CPU1_P0_TX_BUF_C_DP<14>")
	)
	(segment
		(start 89.633298 -417.981892)
		(end 89.381584 -418.634672)
		(width 0.14224)
		(layer "In11.Cu")
		(net "P5E_CPU1_P0_TX_BUF_C_DP<14>")
	)
	(segment
		(start 90.22842 -416.820858)
		(end 90.050874 -416.899344)
		(width 0.14224)
		(layer "In11.Cu")
		(net "P5E_CPU1_P0_TX_BUF_C_DP<14>")
	)
	(segment
		(start 89.897458 -417.297362)
		(end 89.975944 -417.474654)
		(width 0.14224)
		(layer "In11.Cu")
		(net "P5E_CPU1_P0_TX_BUF_C_DP<14>")
	)
	(segment
		(start 91.543124 -412.570168)
		(end 91.252294 -412.860998)
		(width 0.14224)
		(layer "In11.Cu")
		(net "P5E_CPU1_P0_TX_BUF_C_DP<14>")
	)
	(segment
		(start 91.252294 -412.860998)
		(end 91.252294 -413.561022)
		(width 0.14224)
		(layer "In11.Cu")
		(net "P5E_CPU1_P0_TX_BUF_C_DP<14>")
	)
	(segment
		(start 90.381836 -416.422332)
		(end 90.22842 -416.820858)
		(width 0.14224)
		(layer "In11.Cu")
		(net "P5E_CPU1_P0_TX_BUF_C_DP<14>")
	)
	(segment
		(start 89.975944 -417.474654)
		(end 89.822528 -417.87318)
		(width 0.14224)
		(layer "In11.Cu")
		(net "P5E_CPU1_P0_TX_BUF_C_DP<14>")
	)
	(segment
		(start 88.815926 -420.223442)
		(end 88.640666 -420.612824)
		(width 0.14224)
		(layer "In11.Cu")
		(net "P5E_CPU1_P0_TX_BUF_C_DP<14>")
	)
	(segment
		(start 90.709496 -415.191956)
		(end 90.709242 -415.192718)
		(width 0.14224)
		(layer "In11.Cu")
		(net "P5E_CPU1_P0_TX_BUF_C_DP<14>")
	)
	(segment
		(start 90.787982 -415.37001)
		(end 90.634312 -415.768536)
		(width 0.14224)
		(layer "In11.Cu")
		(net "P5E_CPU1_P0_TX_BUF_C_DP<14>")
	)
	(segment
		(start 90.30335 -416.24504)
		(end 90.381836 -416.422332)
		(width 0.14224)
		(layer "In11.Cu")
		(net "P5E_CPU1_P0_TX_BUF_C_DP<14>")
	)
	(segment
		(start 88.459056 -420.681404)
		(end 87.588344 -422.613836)
		(width 0.14224)
		(layer "In11.Cu")
		(net "P5E_CPU1_P0_TX_BUF_C_DP<14>")
	)
	(segment
		(start 90.050874 -416.899344)
		(end 89.897458 -417.297362)
		(width 0.14224)
		(layer "In11.Cu")
		(net "P5E_CPU1_P0_TX_BUF_C_DP<14>")
	)
	(arc
		(start 87.124286 -423.734738)
		(mid 87.009052 -424.114754)
		(end 86.970108 -424.509946)
		(width 0.14224)
		(layer "In11.Cu")
		(net "P5E_CPU1_P0_TX_BUF_C_DP<14>")
	)
	(arc
		(start 91.252294 -413.561022)
		(mid 91.232007 -413.781268)
		(end 91.171776 -413.994092)
		(width 0.14224)
		(layer "In11.Cu")
		(net "P5E_CPU1_P0_TX_BUF_C_DP<14>")
	)
	(segment
		(start 88.505284 -408.784044)
		(end 88.209374 -409.079954)
		(width 0.12954)
		(layer "F.Cu")
		(net "P5E_CPU1_P0_TX_BUF_C_DP<13>")
	)
	(segment
		(start 88.209374 -412.299658)
		(end 88.479884 -412.570168)
		(width 0.12954)
		(layer "F.Cu")
		(net "P5E_CPU1_P0_TX_BUF_C_DP<13>")
	)
	(segment
		(start 88.209374 -409.079954)
		(end 88.209374 -412.299658)
		(width 0.12954)
		(layer "F.Cu")
		(net "P5E_CPU1_P0_TX_BUF_C_DP<13>")
	)
	(segment
		(start 88.008968 -415.269426)
		(end 87.827612 -415.3662)
		(width 0.14224)
		(layer "In11.Cu")
		(net "P5E_CPU1_P0_TX_BUF_C_DP<13>")
	)
	(segment
		(start 84.970112 -424.931332)
		(end 84.970112 -430.980596)
		(width 0.14224)
		(layer "In11.Cu")
		(net "P5E_CPU1_P0_TX_BUF_C_DP<13>")
	)
	(segment
		(start 84.970366 -424.931586)
		(end 84.970112 -424.931332)
		(width 0.14224)
		(layer "In11.Cu")
		(net "P5E_CPU1_P0_TX_BUF_C_DP<13>")
	)
	(segment
		(start 88.04148 -414.689798)
		(end 88.13292 -414.860994)
		(width 0.14224)
		(layer "In11.Cu")
		(net "P5E_CPU1_P0_TX_BUF_C_DP<13>")
	)
	(segment
		(start 88.479884 -412.570168)
		(end 88.189054 -412.860998)
		(width 0.14224)
		(layer "In11.Cu")
		(net "P5E_CPU1_P0_TX_BUF_C_DP<13>")
	)
	(segment
		(start 87.544148 -416.801046)
		(end 87.372952 -416.892486)
		(width 0.14224)
		(layer "In11.Cu")
		(net "P5E_CPU1_P0_TX_BUF_C_DP<13>")
	)
	(segment
		(start 85.65007 -431.02149)
		(end 85.65007 -430.689766)
		(width 0.14224)
		(layer "In11.Cu")
		(net "P5E_CPU1_P0_TX_BUF_C_DP<13>")
	)
	(segment
		(start 87.372952 -416.892486)
		(end 87.372698 -416.892994)
		(width 0.14224)
		(layer "In11.Cu")
		(net "P5E_CPU1_P0_TX_BUF_C_DP<13>")
	)
	(segment
		(start 87.571326 -416.211512)
		(end 87.6681 -416.392614)
		(width 0.14224)
		(layer "In11.Cu")
		(net "P5E_CPU1_P0_TX_BUF_C_DP<13>")
	)
	(segment
		(start 86.584028 -419.493954)
		(end 85.28304 -423.129456)
		(width 0.14224)
		(layer "In11.Cu")
		(net "P5E_CPU1_P0_TX_BUF_C_DP<13>")
	)
	(segment
		(start 88.13292 -414.860994)
		(end 88.008968 -415.269426)
		(width 0.14224)
		(layer "In11.Cu")
		(net "P5E_CPU1_P0_TX_BUF_C_DP<13>")
	)
	(segment
		(start 88.144604 -414.349184)
		(end 88.04275 -414.685988)
		(width 0.14224)
		(layer "In11.Cu")
		(net "P5E_CPU1_P0_TX_BUF_C_DP<13>")
	)
	(segment
		(start 85.522816 -431.148744)
		(end 85.65007 -431.02149)
		(width 0.14224)
		(layer "In11.Cu")
		(net "P5E_CPU1_P0_TX_BUF_C_DP<13>")
	)
	(segment
		(start 88.04275 -414.685988)
		(end 88.04148 -414.689798)
		(width 0.14224)
		(layer "In11.Cu")
		(net "P5E_CPU1_P0_TX_BUF_C_DP<13>")
	)
	(segment
		(start 87.6681 -416.392614)
		(end 87.544148 -416.801046)
		(width 0.14224)
		(layer "In11.Cu")
		(net "P5E_CPU1_P0_TX_BUF_C_DP<13>")
	)
	(segment
		(start 87.827612 -415.3662)
		(end 87.571326 -416.211512)
		(width 0.14224)
		(layer "In11.Cu")
		(net "P5E_CPU1_P0_TX_BUF_C_DP<13>")
	)
	(segment
		(start 88.189054 -412.860998)
		(end 88.189054 -414.04921)
		(width 0.14224)
		(layer "In11.Cu")
		(net "P5E_CPU1_P0_TX_BUF_C_DP<13>")
	)
	(segment
		(start 84.970112 -430.980596)
		(end 85.13826 -431.148744)
		(width 0.14224)
		(layer "In11.Cu")
		(net "P5E_CPU1_P0_TX_BUF_C_DP<13>")
	)
	(segment
		(start 85.13826 -431.148744)
		(end 85.522816 -431.148744)
		(width 0.14224)
		(layer "In11.Cu")
		(net "P5E_CPU1_P0_TX_BUF_C_DP<13>")
	)
	(segment
		(start 87.372698 -416.892994)
		(end 86.584028 -419.493954)
		(width 0.14224)
		(layer "In11.Cu")
		(net "P5E_CPU1_P0_TX_BUF_C_DP<13>")
	)
	(arc
		(start 85.28304 -423.129456)
		(mid 85.049102 -424.017056)
		(end 84.970366 -424.931586)
		(width 0.14224)
		(layer "In11.Cu")
		(net "P5E_CPU1_P0_TX_BUF_C_DP<13>")
	)
	(arc
		(start 88.189054 -414.04921)
		(mid 88.177857 -414.20083)
		(end 88.144604 -414.349184)
		(width 0.14224)
		(layer "In11.Cu")
		(net "P5E_CPU1_P0_TX_BUF_C_DP<13>")
	)
	(segment
		(start 85.146134 -412.299658)
		(end 85.416644 -412.570168)
		(width 0.12954)
		(layer "F.Cu")
		(net "P5E_CPU1_P0_TX_BUF_C_DP<12>")
	)
	(segment
		(start 85.442044 -408.784044)
		(end 85.146134 -409.079954)
		(width 0.12954)
		(layer "F.Cu")
		(net "P5E_CPU1_P0_TX_BUF_C_DP<12>")
	)
	(segment
		(start 85.146134 -409.079954)
		(end 85.146134 -412.299658)
		(width 0.12954)
		(layer "F.Cu")
		(net "P5E_CPU1_P0_TX_BUF_C_DP<12>")
	)
	(segment
		(start 83.523074 -430.125632)
		(end 83.650074 -429.998632)
		(width 0.14224)
		(layer "In11.Cu")
		(net "P5E_CPU1_P0_TX_BUF_C_DP<12>")
	)
	(segment
		(start 83.650074 -429.998632)
		(end 83.650074 -429.689768)
		(width 0.14224)
		(layer "In11.Cu")
		(net "P5E_CPU1_P0_TX_BUF_C_DP<12>")
	)
	(segment
		(start 83.966812 -418.940488)
		(end 83.100926 -422.796462)
		(width 0.14224)
		(layer "In11.Cu")
		(net "P5E_CPU1_P0_TX_BUF_C_DP<12>")
	)
	(segment
		(start 85.416644 -412.570168)
		(end 85.125814 -412.860998)
		(width 0.14224)
		(layer "In11.Cu")
		(net "P5E_CPU1_P0_TX_BUF_C_DP<12>")
	)
	(segment
		(start 84.63153 -415.98088)
		(end 84.460334 -416.744404)
		(width 0.14224)
		(layer "In11.Cu")
		(net "P5E_CPU1_P0_TX_BUF_C_DP<12>")
	)
	(segment
		(start 85.032342 -414.196022)
		(end 85.136228 -414.359852)
		(width 0.14224)
		(layer "In11.Cu")
		(net "P5E_CPU1_P0_TX_BUF_C_DP<12>")
	)
	(segment
		(start 84.459826 -416.746436)
		(end 84.563458 -416.910266)
		(width 0.14224)
		(layer "In11.Cu")
		(net "P5E_CPU1_P0_TX_BUF_C_DP<12>")
	)
	(segment
		(start 85.112606 -413.83839)
		(end 85.032342 -414.196022)
		(width 0.14224)
		(layer "In11.Cu")
		(net "P5E_CPU1_P0_TX_BUF_C_DP<12>")
	)
	(segment
		(start 84.878672 -414.880298)
		(end 84.878418 -414.881314)
		(width 0.14224)
		(layer "In11.Cu")
		(net "P5E_CPU1_P0_TX_BUF_C_DP<12>")
	)
	(segment
		(start 84.120482 -418.256212)
		(end 84.224368 -418.420042)
		(width 0.14224)
		(layer "In11.Cu")
		(net "P5E_CPU1_P0_TX_BUF_C_DP<12>")
	)
	(segment
		(start 85.042756 -414.776412)
		(end 84.878672 -414.880298)
		(width 0.14224)
		(layer "In11.Cu")
		(net "P5E_CPU1_P0_TX_BUF_C_DP<12>")
	)
	(segment
		(start 84.305648 -417.431728)
		(end 84.120482 -418.256212)
		(width 0.14224)
		(layer "In11.Cu")
		(net "P5E_CPU1_P0_TX_BUF_C_DP<12>")
	)
	(segment
		(start 84.469986 -417.326826)
		(end 84.305902 -417.430712)
		(width 0.14224)
		(layer "In11.Cu")
		(net "P5E_CPU1_P0_TX_BUF_C_DP<12>")
	)
	(segment
		(start 84.795614 -415.876994)
		(end 84.63153 -415.98088)
		(width 0.14224)
		(layer "In11.Cu")
		(net "P5E_CPU1_P0_TX_BUF_C_DP<12>")
	)
	(segment
		(start 85.125814 -412.860998)
		(end 85.125814 -413.719518)
		(width 0.14224)
		(layer "In11.Cu")
		(net "P5E_CPU1_P0_TX_BUF_C_DP<12>")
	)
	(segment
		(start 84.130896 -418.836856)
		(end 83.966812 -418.940488)
		(width 0.14224)
		(layer "In11.Cu")
		(net "P5E_CPU1_P0_TX_BUF_C_DP<12>")
	)
	(segment
		(start 84.889086 -415.460434)
		(end 84.795614 -415.876994)
		(width 0.14224)
		(layer "In11.Cu")
		(net "P5E_CPU1_P0_TX_BUF_C_DP<12>")
	)
	(segment
		(start 84.563458 -416.910266)
		(end 84.469986 -417.326826)
		(width 0.14224)
		(layer "In11.Cu")
		(net "P5E_CPU1_P0_TX_BUF_C_DP<12>")
	)
	(segment
		(start 84.878418 -414.881314)
		(end 84.7852 -415.296604)
		(width 0.14224)
		(layer "In11.Cu")
		(net "P5E_CPU1_P0_TX_BUF_C_DP<12>")
	)
	(segment
		(start 82.970116 -429.91532)
		(end 83.180428 -430.125632)
		(width 0.14224)
		(layer "In11.Cu")
		(net "P5E_CPU1_P0_TX_BUF_C_DP<12>")
	)
	(segment
		(start 84.224368 -418.420042)
		(end 84.130896 -418.836856)
		(width 0.14224)
		(layer "In11.Cu")
		(net "P5E_CPU1_P0_TX_BUF_C_DP<12>")
	)
	(segment
		(start 84.460334 -416.744404)
		(end 84.459826 -416.746436)
		(width 0.14224)
		(layer "In11.Cu")
		(net "P5E_CPU1_P0_TX_BUF_C_DP<12>")
	)
	(segment
		(start 84.7852 -415.296604)
		(end 84.889086 -415.460434)
		(width 0.14224)
		(layer "In11.Cu")
		(net "P5E_CPU1_P0_TX_BUF_C_DP<12>")
	)
	(segment
		(start 85.136228 -414.359852)
		(end 85.042756 -414.776412)
		(width 0.14224)
		(layer "In11.Cu")
		(net "P5E_CPU1_P0_TX_BUF_C_DP<12>")
	)
	(segment
		(start 84.305902 -417.430712)
		(end 84.305648 -417.431728)
		(width 0.14224)
		(layer "In11.Cu")
		(net "P5E_CPU1_P0_TX_BUF_C_DP<12>")
	)
	(segment
		(start 82.970116 -423.975022)
		(end 82.970116 -429.91532)
		(width 0.14224)
		(layer "In11.Cu")
		(net "P5E_CPU1_P0_TX_BUF_C_DP<12>")
	)
	(segment
		(start 83.180428 -430.125632)
		(end 83.523074 -430.125632)
		(width 0.14224)
		(layer "In11.Cu")
		(net "P5E_CPU1_P0_TX_BUF_C_DP<12>")
	)
	(arc
		(start 85.125814 -413.719518)
		(mid 85.122508 -413.779321)
		(end 85.112606 -413.83839)
		(width 0.14224)
		(layer "In11.Cu")
		(net "P5E_CPU1_P0_TX_BUF_C_DP<12>")
	)
	(arc
		(start 83.100926 -422.796462)
		(mid 83.002932 -423.382125)
		(end 82.970116 -423.975022)
		(width 0.14224)
		(layer "In11.Cu")
		(net "P5E_CPU1_P0_TX_BUF_C_DP<12>")
	)
	(segment
		(start 82.378804 -408.784044)
		(end 82.082894 -409.079954)
		(width 0.12954)
		(layer "F.Cu")
		(net "P5E_CPU1_P0_TX_BUF_C_DP<11>")
	)
	(segment
		(start 82.082894 -412.299658)
		(end 82.353404 -412.570168)
		(width 0.12954)
		(layer "F.Cu")
		(net "P5E_CPU1_P0_TX_BUF_C_DP<11>")
	)
	(segment
		(start 82.082894 -409.079954)
		(end 82.082894 -412.299658)
		(width 0.12954)
		(layer "F.Cu")
		(net "P5E_CPU1_P0_TX_BUF_C_DP<11>")
	)
	(segment
		(start 81.726278 -417.438586)
		(end 81.876392 -417.31565)
		(width 0.14224)
		(layer "In11.Cu")
		(net "P5E_CPU1_P0_TX_BUF_C_DP<11>")
	)
	(segment
		(start 81.876392 -417.31565)
		(end 81.918302 -416.890708)
		(width 0.14224)
		(layer "In11.Cu")
		(net "P5E_CPU1_P0_TX_BUF_C_DP<11>")
	)
	(segment
		(start 82.062574 -414.02127)
		(end 82.062574 -412.860998)
		(width 0.14224)
		(layer "In11.Cu")
		(net "P5E_CPU1_P0_TX_BUF_C_DP<11>")
	)
	(segment
		(start 80.97012 -425.128944)
		(end 81.726278 -417.439602)
		(width 0.14224)
		(layer "In11.Cu")
		(net "P5E_CPU1_P0_TX_BUF_C_DP<11>")
	)
	(segment
		(start 80.97012 -431.000916)
		(end 80.97012 -425.128944)
		(width 0.14224)
		(layer "In11.Cu")
		(net "P5E_CPU1_P0_TX_BUF_C_DP<11>")
	)
	(segment
		(start 81.532222 -431.139346)
		(end 81.10855 -431.139346)
		(width 0.14224)
		(layer "In11.Cu")
		(net "P5E_CPU1_P0_TX_BUF_C_DP<11>")
	)
	(segment
		(start 82.039968 -415.653982)
		(end 82.081624 -415.22904)
		(width 0.14224)
		(layer "In11.Cu")
		(net "P5E_CPU1_P0_TX_BUF_C_DP<11>")
	)
	(segment
		(start 81.650078 -430.689766)
		(end 81.650078 -431.02149)
		(width 0.14224)
		(layer "In11.Cu")
		(net "P5E_CPU1_P0_TX_BUF_C_DP<11>")
	)
	(segment
		(start 81.889854 -415.776918)
		(end 82.039968 -415.653982)
		(width 0.14224)
		(layer "In11.Cu")
		(net "P5E_CPU1_P0_TX_BUF_C_DP<11>")
	)
	(segment
		(start 82.062574 -412.860998)
		(end 82.353404 -412.570168)
		(width 0.14224)
		(layer "In11.Cu")
		(net "P5E_CPU1_P0_TX_BUF_C_DP<11>")
	)
	(segment
		(start 81.726532 -417.438586)
		(end 81.726278 -417.438586)
		(width 0.14224)
		(layer "In11.Cu")
		(net "P5E_CPU1_P0_TX_BUF_C_DP<11>")
	)
	(segment
		(start 81.726278 -417.439602)
		(end 81.726532 -417.438586)
		(width 0.14224)
		(layer "In11.Cu")
		(net "P5E_CPU1_P0_TX_BUF_C_DP<11>")
	)
	(segment
		(start 81.918302 -416.890708)
		(end 81.795112 -416.740848)
		(width 0.14224)
		(layer "In11.Cu")
		(net "P5E_CPU1_P0_TX_BUF_C_DP<11>")
	)
	(segment
		(start 81.958688 -415.07918)
		(end 82.062574 -414.02127)
		(width 0.14224)
		(layer "In11.Cu")
		(net "P5E_CPU1_P0_TX_BUF_C_DP<11>")
	)
	(segment
		(start 81.795112 -416.740848)
		(end 81.889854 -415.776918)
		(width 0.14224)
		(layer "In11.Cu")
		(net "P5E_CPU1_P0_TX_BUF_C_DP<11>")
	)
	(segment
		(start 81.10855 -431.139346)
		(end 80.97012 -431.000916)
		(width 0.14224)
		(layer "In11.Cu")
		(net "P5E_CPU1_P0_TX_BUF_C_DP<11>")
	)
	(segment
		(start 82.081624 -415.22904)
		(end 81.958688 -415.07918)
		(width 0.14224)
		(layer "In11.Cu")
		(net "P5E_CPU1_P0_TX_BUF_C_DP<11>")
	)
	(segment
		(start 81.650078 -431.02149)
		(end 81.532222 -431.139346)
		(width 0.14224)
		(layer "In11.Cu")
		(net "P5E_CPU1_P0_TX_BUF_C_DP<11>")
	)
	(segment
		(start 79.019654 -412.299658)
		(end 79.290164 -412.570168)
		(width 0.12954)
		(layer "F.Cu")
		(net "P5E_CPU1_P0_TX_BUF_C_DP<10>")
	)
	(segment
		(start 79.019654 -409.079954)
		(end 79.019654 -412.299658)
		(width 0.12954)
		(layer "F.Cu")
		(net "P5E_CPU1_P0_TX_BUF_C_DP<10>")
	)
	(segment
		(start 79.315564 -408.784044)
		(end 79.019654 -409.079954)
		(width 0.12954)
		(layer "F.Cu")
		(net "P5E_CPU1_P0_TX_BUF_C_DP<10>")
	)
	(segment
		(start 79.523082 -430.125632)
		(end 79.180436 -430.125632)
		(width 0.14224)
		(layer "In11.Cu")
		(net "P5E_CPU1_P0_TX_BUF_C_DP<10>")
	)
	(segment
		(start 78.999334 -414.018984)
		(end 78.999334 -412.860998)
		(width 0.14224)
		(layer "In11.Cu")
		(net "P5E_CPU1_P0_TX_BUF_C_DP<10>")
	)
	(segment
		(start 79.194406 -417.986718)
		(end 79.165704 -417.400486)
		(width 0.14224)
		(layer "In11.Cu")
		(net "P5E_CPU1_P0_TX_BUF_C_DP<10>")
	)
	(segment
		(start 79.359252 -418.543232)
		(end 79.338424 -418.116766)
		(width 0.14224)
		(layer "In11.Cu")
		(net "P5E_CPU1_P0_TX_BUF_C_DP<10>")
	)
	(segment
		(start 78.970124 -423.617136)
		(end 79.297022 -420.076122)
		(width 0.14224)
		(layer "In11.Cu")
		(net "P5E_CPU1_P0_TX_BUF_C_DP<10>")
	)
	(segment
		(start 78.999334 -412.860998)
		(end 79.290164 -412.570168)
		(width 0.14224)
		(layer "In11.Cu")
		(net "P5E_CPU1_P0_TX_BUF_C_DP<10>")
	)
	(segment
		(start 79.110078 -416.271964)
		(end 79.24038 -416.1282)
		(width 0.14224)
		(layer "In11.Cu")
		(net "P5E_CPU1_P0_TX_BUF_C_DP<10>")
	)
	(segment
		(start 79.020162 -414.444942)
		(end 78.999334 -414.018984)
		(width 0.14224)
		(layer "In11.Cu")
		(net "P5E_CPU1_P0_TX_BUF_C_DP<10>")
	)
	(segment
		(start 79.165704 -417.400486)
		(end 79.296006 -417.256976)
		(width 0.14224)
		(layer "In11.Cu")
		(net "P5E_CPU1_P0_TX_BUF_C_DP<10>")
	)
	(segment
		(start 79.650082 -429.998632)
		(end 79.523082 -430.125632)
		(width 0.14224)
		(layer "In11.Cu")
		(net "P5E_CPU1_P0_TX_BUF_C_DP<10>")
	)
	(segment
		(start 79.24038 -416.1282)
		(end 79.219552 -415.701734)
		(width 0.14224)
		(layer "In11.Cu")
		(net "P5E_CPU1_P0_TX_BUF_C_DP<10>")
	)
	(segment
		(start 79.274924 -416.83051)
		(end 79.130906 -416.700208)
		(width 0.14224)
		(layer "In11.Cu")
		(net "P5E_CPU1_P0_TX_BUF_C_DP<10>")
	)
	(segment
		(start 79.219552 -415.701734)
		(end 79.075534 -415.571432)
		(width 0.14224)
		(layer "In11.Cu")
		(net "P5E_CPU1_P0_TX_BUF_C_DP<10>")
	)
	(segment
		(start 79.338424 -418.116766)
		(end 79.194406 -417.986718)
		(width 0.14224)
		(layer "In11.Cu")
		(net "P5E_CPU1_P0_TX_BUF_C_DP<10>")
	)
	(segment
		(start 79.075534 -415.571432)
		(end 79.054706 -415.145474)
		(width 0.14224)
		(layer "In11.Cu")
		(net "P5E_CPU1_P0_TX_BUF_C_DP<10>")
	)
	(segment
		(start 79.296006 -417.256976)
		(end 79.274924 -416.83051)
		(width 0.14224)
		(layer "In11.Cu")
		(net "P5E_CPU1_P0_TX_BUF_C_DP<10>")
	)
	(segment
		(start 79.180436 -430.125632)
		(end 78.970124 -429.91532)
		(width 0.14224)
		(layer "In11.Cu")
		(net "P5E_CPU1_P0_TX_BUF_C_DP<10>")
	)
	(segment
		(start 78.970124 -429.91532)
		(end 78.970124 -423.617136)
		(width 0.14224)
		(layer "In11.Cu")
		(net "P5E_CPU1_P0_TX_BUF_C_DP<10>")
	)
	(segment
		(start 79.22895 -418.686996)
		(end 79.359252 -418.543232)
		(width 0.14224)
		(layer "In11.Cu")
		(net "P5E_CPU1_P0_TX_BUF_C_DP<10>")
	)
	(segment
		(start 79.297022 -420.076122)
		(end 79.22895 -418.686996)
		(width 0.14224)
		(layer "In11.Cu")
		(net "P5E_CPU1_P0_TX_BUF_C_DP<10>")
	)
	(segment
		(start 79.185008 -415.00171)
		(end 79.16418 -414.575244)
		(width 0.14224)
		(layer "In11.Cu")
		(net "P5E_CPU1_P0_TX_BUF_C_DP<10>")
	)
	(segment
		(start 79.130906 -416.700208)
		(end 79.110078 -416.271964)
		(width 0.14224)
		(layer "In11.Cu")
		(net "P5E_CPU1_P0_TX_BUF_C_DP<10>")
	)
	(segment
		(start 79.16418 -414.575244)
		(end 79.020162 -414.444942)
		(width 0.14224)
		(layer "In11.Cu")
		(net "P5E_CPU1_P0_TX_BUF_C_DP<10>")
	)
	(segment
		(start 79.054706 -415.145474)
		(end 79.185008 -415.00171)
		(width 0.14224)
		(layer "In11.Cu")
		(net "P5E_CPU1_P0_TX_BUF_C_DP<10>")
	)
	(segment
		(start 79.650082 -429.689768)
		(end 79.650082 -429.998632)
		(width 0.14224)
		(layer "In11.Cu")
		(net "P5E_CPU1_P0_TX_BUF_C_DP<10>")
	)
	(segment
		(start 48.683164 -408.784044)
		(end 48.387254 -409.079954)
		(width 0.12954)
		(layer "F.Cu")
		(net "P5E_CPU1_P0_TX_BUF_C_DP<0>")
	)
	(segment
		(start 48.387254 -412.299658)
		(end 48.657764 -412.570168)
		(width 0.12954)
		(layer "F.Cu")
		(net "P5E_CPU1_P0_TX_BUF_C_DP<0>")
	)
	(segment
		(start 48.387254 -409.079954)
		(end 48.387254 -412.299658)
		(width 0.12954)
		(layer "F.Cu")
		(net "P5E_CPU1_P0_TX_BUF_C_DP<0>")
	)
	(segment
		(start 53.885338 -417.01847)
		(end 56.444388 -418.078412)
		(width 0.14224)
		(layer "In11.Cu")
		(net "P5E_CPU1_P0_TX_BUF_C_DP<0>")
	)
	(segment
		(start 58.52287 -430.125632)
		(end 58.64987 -429.998632)
		(width 0.14224)
		(layer "In11.Cu")
		(net "P5E_CPU1_P0_TX_BUF_C_DP<0>")
	)
	(segment
		(start 53.237638 -416.749738)
		(end 53.416708 -416.67557)
		(width 0.14224)
		(layer "In11.Cu")
		(net "P5E_CPU1_P0_TX_BUF_C_DP<0>")
	)
	(segment
		(start 57.969912 -419.85819)
		(end 57.969912 -429.91532)
		(width 0.14224)
		(layer "In11.Cu")
		(net "P5E_CPU1_P0_TX_BUF_C_DP<0>")
	)
	(segment
		(start 53.81117 -416.838892)
		(end 53.885338 -417.01847)
		(width 0.14224)
		(layer "In11.Cu")
		(net "P5E_CPU1_P0_TX_BUF_C_DP<0>")
	)
	(segment
		(start 48.657764 -412.570168)
		(end 48.366934 -412.860998)
		(width 0.14224)
		(layer "In11.Cu")
		(net "P5E_CPU1_P0_TX_BUF_C_DP<0>")
	)
	(segment
		(start 50.20056 -415.34334)
		(end 50.595022 -415.506662)
		(width 0.14224)
		(layer "In11.Cu")
		(net "P5E_CPU1_P0_TX_BUF_C_DP<0>")
	)
	(segment
		(start 52.84343 -416.58667)
		(end 53.237638 -416.749738)
		(width 0.14224)
		(layer "In11.Cu")
		(net "P5E_CPU1_P0_TX_BUF_C_DP<0>")
	)
	(segment
		(start 48.366934 -413.909256)
		(end 48.588676 -414.444688)
		(width 0.14224)
		(layer "In11.Cu")
		(net "P5E_CPU1_P0_TX_BUF_C_DP<0>")
	)
	(segment
		(start 50.669444 -415.68624)
		(end 51.124104 -415.874454)
		(width 0.14224)
		(layer "In11.Cu")
		(net "P5E_CPU1_P0_TX_BUF_C_DP<0>")
	)
	(segment
		(start 51.69789 -415.963608)
		(end 51.772058 -416.142932)
		(width 0.14224)
		(layer "In11.Cu")
		(net "P5E_CPU1_P0_TX_BUF_C_DP<0>")
	)
	(segment
		(start 51.772058 -416.142932)
		(end 52.195476 -416.318192)
		(width 0.14224)
		(layer "In11.Cu")
		(net "P5E_CPU1_P0_TX_BUF_C_DP<0>")
	)
	(segment
		(start 58.64987 -429.998632)
		(end 58.64987 -429.689768)
		(width 0.14224)
		(layer "In11.Cu")
		(net "P5E_CPU1_P0_TX_BUF_C_DP<0>")
	)
	(segment
		(start 52.769008 -416.407346)
		(end 52.84343 -416.58667)
		(width 0.14224)
		(layer "In11.Cu")
		(net "P5E_CPU1_P0_TX_BUF_C_DP<0>")
	)
	(segment
		(start 48.366934 -412.860998)
		(end 48.366934 -413.909256)
		(width 0.14224)
		(layer "In11.Cu")
		(net "P5E_CPU1_P0_TX_BUF_C_DP<0>")
	)
	(segment
		(start 48.588676 -414.444688)
		(end 48.937672 -414.793684)
		(width 0.14224)
		(layer "In11.Cu")
		(net "P5E_CPU1_P0_TX_BUF_C_DP<0>")
	)
	(segment
		(start 52.195476 -416.318192)
		(end 52.374546 -416.244024)
		(width 0.14224)
		(layer "In11.Cu")
		(net "P5E_CPU1_P0_TX_BUF_C_DP<0>")
	)
	(segment
		(start 51.124104 -415.874454)
		(end 51.303428 -415.800286)
		(width 0.14224)
		(layer "In11.Cu")
		(net "P5E_CPU1_P0_TX_BUF_C_DP<0>")
	)
	(segment
		(start 49.627282 -415.25444)
		(end 50.02149 -415.417508)
		(width 0.14224)
		(layer "In11.Cu")
		(net "P5E_CPU1_P0_TX_BUF_C_DP<0>")
	)
	(segment
		(start 51.303428 -415.800286)
		(end 51.69789 -415.963608)
		(width 0.14224)
		(layer "In11.Cu")
		(net "P5E_CPU1_P0_TX_BUF_C_DP<0>")
	)
	(segment
		(start 57.969912 -429.91532)
		(end 58.180224 -430.125632)
		(width 0.14224)
		(layer "In11.Cu")
		(net "P5E_CPU1_P0_TX_BUF_C_DP<0>")
	)
	(segment
		(start 58.180224 -430.125632)
		(end 58.52287 -430.125632)
		(width 0.14224)
		(layer "In11.Cu")
		(net "P5E_CPU1_P0_TX_BUF_C_DP<0>")
	)
	(segment
		(start 48.937672 -414.793684)
		(end 49.627282 -415.25444)
		(width 0.14224)
		(layer "In11.Cu")
		(net "P5E_CPU1_P0_TX_BUF_C_DP<0>")
	)
	(segment
		(start 50.595022 -415.506662)
		(end 50.669444 -415.68624)
		(width 0.14224)
		(layer "In11.Cu")
		(net "P5E_CPU1_P0_TX_BUF_C_DP<0>")
	)
	(segment
		(start 57.440068 -418.743638)
		(end 57.5564 -418.85997)
		(width 0.14224)
		(layer "In11.Cu")
		(net "P5E_CPU1_P0_TX_BUF_C_DP<0>")
	)
	(segment
		(start 53.416708 -416.67557)
		(end 53.81117 -416.838892)
		(width 0.14224)
		(layer "In11.Cu")
		(net "P5E_CPU1_P0_TX_BUF_C_DP<0>")
	)
	(segment
		(start 52.374546 -416.244024)
		(end 52.769008 -416.407346)
		(width 0.14224)
		(layer "In11.Cu")
		(net "P5E_CPU1_P0_TX_BUF_C_DP<0>")
	)
	(segment
		(start 50.02149 -415.417508)
		(end 50.20056 -415.34334)
		(width 0.14224)
		(layer "In11.Cu")
		(net "P5E_CPU1_P0_TX_BUF_C_DP<0>")
	)
	(arc
		(start 57.5564 -418.85997)
		(mid 57.862417 -419.317957)
		(end 57.969912 -419.85819)
		(width 0.14224)
		(layer "In11.Cu")
		(net "P5E_CPU1_P0_TX_BUF_C_DP<0>")
	)
	(arc
		(start 56.444388 -418.078412)
		(mid 56.974979 -418.362001)
		(end 57.440068 -418.743638)
		(width 0.14224)
		(layer "In11.Cu")
		(net "P5E_CPU1_P0_TX_BUF_C_DP<0>")
	)
	(segment
		(start 75.633834 -412.299658)
		(end 75.363324 -412.570168)
		(width 0.12954)
		(layer "F.Cu")
		(net "P5E_CPU1_P0_TX_BUF_C_DN<9>")
	)
	(segment
		(start 75.337924 -408.784044)
		(end 75.633834 -409.079954)
		(width 0.12954)
		(layer "F.Cu")
		(net "P5E_CPU1_P0_TX_BUF_C_DN<9>")
	)
	(segment
		(start 75.633834 -409.079954)
		(end 75.633834 -412.299658)
		(width 0.12954)
		(layer "F.Cu")
		(net "P5E_CPU1_P0_TX_BUF_C_DN<9>")
	)
	(segment
		(start 75.88123 -417.096448)
		(end 75.654154 -414.790636)
		(width 0.14224)
		(layer "In11.Cu")
		(net "P5E_CPU1_P0_TX_BUF_C_DN<9>")
	)
	(segment
		(start 75.881484 -417.097972)
		(end 75.881484 -417.097718)
		(width 0.14224)
		(layer "In11.Cu")
		(net "P5E_CPU1_P0_TX_BUF_C_DN<9>")
	)
	(segment
		(start 75.910694 -417.394644)
		(end 75.881484 -417.097972)
		(width 0.14224)
		(layer "In11.Cu")
		(net "P5E_CPU1_P0_TX_BUF_C_DN<9>")
	)
	(segment
		(start 75.654154 -414.790636)
		(end 75.654154 -412.860998)
		(width 0.14224)
		(layer "In11.Cu")
		(net "P5E_CPU1_P0_TX_BUF_C_DN<9>")
	)
	(segment
		(start 77.522578 -431.430684)
		(end 77.001116 -431.430684)
		(width 0.14224)
		(layer "In11.Cu")
		(net "P5E_CPU1_P0_TX_BUF_C_DN<9>")
	)
	(segment
		(start 77.650086 -431.558192)
		(end 77.522578 -431.430684)
		(width 0.14224)
		(layer "In11.Cu")
		(net "P5E_CPU1_P0_TX_BUF_C_DN<9>")
	)
	(segment
		(start 75.881484 -417.097718)
		(end 75.88123 -417.096448)
		(width 0.14224)
		(layer "In11.Cu")
		(net "P5E_CPU1_P0_TX_BUF_C_DN<9>")
	)
	(segment
		(start 77.650086 -431.889916)
		(end 77.650086 -431.558192)
		(width 0.14224)
		(layer "In11.Cu")
		(net "P5E_CPU1_P0_TX_BUF_C_DN<9>")
	)
	(segment
		(start 75.654154 -412.860998)
		(end 75.363324 -412.570168)
		(width 0.14224)
		(layer "In11.Cu")
		(net "P5E_CPU1_P0_TX_BUF_C_DN<9>")
	)
	(segment
		(start 77.001116 -431.430684)
		(end 76.688188 -431.117756)
		(width 0.14224)
		(layer "In11.Cu")
		(net "P5E_CPU1_P0_TX_BUF_C_DN<9>")
	)
	(segment
		(start 76.688188 -431.117756)
		(end 76.688188 -421.308022)
		(width 0.14224)
		(layer "In11.Cu")
		(net "P5E_CPU1_P0_TX_BUF_C_DN<9>")
	)
	(segment
		(start 76.688188 -421.308022)
		(end 75.910694 -417.394644)
		(width 0.14224)
		(layer "In11.Cu")
		(net "P5E_CPU1_P0_TX_BUF_C_DN<9>")
	)
	(segment
		(start 72.570594 -412.299658)
		(end 72.300084 -412.570168)
		(width 0.12954)
		(layer "F.Cu")
		(net "P5E_CPU1_P0_TX_BUF_C_DN<8>")
	)
	(segment
		(start 72.570594 -409.079954)
		(end 72.570594 -412.299658)
		(width 0.12954)
		(layer "F.Cu")
		(net "P5E_CPU1_P0_TX_BUF_C_DN<8>")
	)
	(segment
		(start 72.274684 -408.784044)
		(end 72.570594 -409.079954)
		(width 0.12954)
		(layer "F.Cu")
		(net "P5E_CPU1_P0_TX_BUF_C_DN<8>")
	)
	(segment
		(start 73.857358 -417.459922)
		(end 74.384408 -422.81602)
		(width 0.14224)
		(layer "In11.Cu")
		(net "P5E_CPU1_P0_TX_BUF_C_DN<8>")
	)
	(segment
		(start 75.65009 -430.558194)
		(end 75.65009 -430.889918)
		(width 0.14224)
		(layer "In11.Cu")
		(net "P5E_CPU1_P0_TX_BUF_C_DN<8>")
	)
	(segment
		(start 74.521822 -425.616878)
		(end 74.688192 -427.304708)
		(width 0.14224)
		(layer "In11.Cu")
		(net "P5E_CPU1_P0_TX_BUF_C_DN<8>")
	)
	(segment
		(start 74.688192 -430.03216)
		(end 75.063604 -430.407572)
		(width 0.14224)
		(layer "In11.Cu")
		(net "P5E_CPU1_P0_TX_BUF_C_DN<8>")
	)
	(segment
		(start 75.063604 -430.407572)
		(end 75.499468 -430.407572)
		(width 0.14224)
		(layer "In11.Cu")
		(net "P5E_CPU1_P0_TX_BUF_C_DN<8>")
	)
	(segment
		(start 72.590914 -413.64281)
		(end 73.56729 -416.000438)
		(width 0.14224)
		(layer "In11.Cu")
		(net "P5E_CPU1_P0_TX_BUF_C_DN<8>")
	)
	(segment
		(start 74.688192 -427.304708)
		(end 74.688192 -430.03216)
		(width 0.14224)
		(layer "In11.Cu")
		(net "P5E_CPU1_P0_TX_BUF_C_DN<8>")
	)
	(segment
		(start 72.300084 -412.570168)
		(end 72.590914 -412.860998)
		(width 0.14224)
		(layer "In11.Cu")
		(net "P5E_CPU1_P0_TX_BUF_C_DN<8>")
	)
	(segment
		(start 75.499468 -430.407572)
		(end 75.65009 -430.558194)
		(width 0.14224)
		(layer "In11.Cu")
		(net "P5E_CPU1_P0_TX_BUF_C_DN<8>")
	)
	(segment
		(start 73.56729 -416.000438)
		(end 73.857358 -417.459922)
		(width 0.14224)
		(layer "In11.Cu")
		(net "P5E_CPU1_P0_TX_BUF_C_DN<8>")
	)
	(segment
		(start 74.384408 -422.81602)
		(end 74.521822 -425.616878)
		(width 0.14224)
		(layer "In11.Cu")
		(net "P5E_CPU1_P0_TX_BUF_C_DN<8>")
	)
	(segment
		(start 72.590914 -412.860998)
		(end 72.590914 -413.64281)
		(width 0.14224)
		(layer "In11.Cu")
		(net "P5E_CPU1_P0_TX_BUF_C_DN<8>")
	)
	(segment
		(start 69.507354 -409.079954)
		(end 69.507354 -412.299658)
		(width 0.12954)
		(layer "F.Cu")
		(net "P5E_CPU1_P0_TX_BUF_C_DN<7>")
	)
	(segment
		(start 69.211444 -408.784044)
		(end 69.507354 -409.079954)
		(width 0.12954)
		(layer "F.Cu")
		(net "P5E_CPU1_P0_TX_BUF_C_DN<7>")
	)
	(segment
		(start 69.507354 -412.299658)
		(end 69.236844 -412.570168)
		(width 0.12954)
		(layer "F.Cu")
		(net "P5E_CPU1_P0_TX_BUF_C_DN<7>")
	)
	(segment
		(start 71.687944 -417.522152)
		(end 71.687944 -431.117756)
		(width 0.14224)
		(layer "In11.Cu")
		(net "P5E_CPU1_P0_TX_BUF_C_DN<7>")
	)
	(segment
		(start 72.649842 -431.558192)
		(end 72.649842 -431.889916)
		(width 0.14224)
		(layer "In11.Cu")
		(net "P5E_CPU1_P0_TX_BUF_C_DN<7>")
	)
	(segment
		(start 72.522334 -431.430684)
		(end 72.649842 -431.558192)
		(width 0.14224)
		(layer "In11.Cu")
		(net "P5E_CPU1_P0_TX_BUF_C_DN<7>")
	)
	(segment
		(start 69.527674 -412.860998)
		(end 69.527674 -413.774128)
		(width 0.14224)
		(layer "In11.Cu")
		(net "P5E_CPU1_P0_TX_BUF_C_DN<7>")
	)
	(segment
		(start 69.236844 -412.570168)
		(end 69.527674 -412.860998)
		(width 0.14224)
		(layer "In11.Cu")
		(net "P5E_CPU1_P0_TX_BUF_C_DN<7>")
	)
	(segment
		(start 69.602604 -414.02254)
		(end 71.477124 -416.827208)
		(width 0.14224)
		(layer "In11.Cu")
		(net "P5E_CPU1_P0_TX_BUF_C_DN<7>")
	)
	(segment
		(start 72.000872 -431.430684)
		(end 72.522334 -431.430684)
		(width 0.14224)
		(layer "In11.Cu")
		(net "P5E_CPU1_P0_TX_BUF_C_DN<7>")
	)
	(segment
		(start 71.687944 -431.117756)
		(end 72.000872 -431.430684)
		(width 0.14224)
		(layer "In11.Cu")
		(net "P5E_CPU1_P0_TX_BUF_C_DN<7>")
	)
	(arc
		(start 69.527674 -413.774128)
		(mid 69.546694 -413.903902)
		(end 69.602604 -414.02254)
		(width 0.14224)
		(layer "In11.Cu")
		(net "P5E_CPU1_P0_TX_BUF_C_DN<7>")
	)
	(arc
		(start 71.477124 -416.827208)
		(mid 71.634093 -417.15904)
		(end 71.687944 -417.522152)
		(width 0.14224)
		(layer "In11.Cu")
		(net "P5E_CPU1_P0_TX_BUF_C_DN<7>")
	)
	(segment
		(start 66.444114 -412.299658)
		(end 66.173604 -412.570168)
		(width 0.12954)
		(layer "F.Cu")
		(net "P5E_CPU1_P0_TX_BUF_C_DN<6>")
	)
	(segment
		(start 66.148204 -408.784044)
		(end 66.444114 -409.079954)
		(width 0.12954)
		(layer "F.Cu")
		(net "P5E_CPU1_P0_TX_BUF_C_DN<6>")
	)
	(segment
		(start 66.444114 -409.079954)
		(end 66.444114 -412.299658)
		(width 0.12954)
		(layer "F.Cu")
		(net "P5E_CPU1_P0_TX_BUF_C_DN<6>")
	)
	(segment
		(start 66.902076 -414.189418)
		(end 66.90233 -414.189672)
		(width 0.14224)
		(layer "In11.Cu")
		(net "P5E_CPU1_P0_TX_BUF_C_DN<6>")
	)
	(segment
		(start 66.464434 -412.860998)
		(end 66.464434 -413.548322)
		(width 0.14224)
		(layer "In11.Cu")
		(net "P5E_CPU1_P0_TX_BUF_C_DN<6>")
	)
	(segment
		(start 68.999608 -416.503612)
		(end 69.38645 -417.506658)
		(width 0.14224)
		(layer "In11.Cu")
		(net "P5E_CPU1_P0_TX_BUF_C_DN<6>")
	)
	(segment
		(start 70.499224 -430.407572)
		(end 70.649846 -430.558194)
		(width 0.14224)
		(layer "In11.Cu")
		(net "P5E_CPU1_P0_TX_BUF_C_DN<6>")
	)
	(segment
		(start 70.06336 -430.407572)
		(end 70.499224 -430.407572)
		(width 0.14224)
		(layer "In11.Cu")
		(net "P5E_CPU1_P0_TX_BUF_C_DN<6>")
	)
	(segment
		(start 69.386704 -417.506658)
		(end 69.536818 -417.896294)
		(width 0.14224)
		(layer "In11.Cu")
		(net "P5E_CPU1_P0_TX_BUF_C_DN<6>")
	)
	(segment
		(start 69.687948 -418.70884)
		(end 69.687948 -430.03216)
		(width 0.14224)
		(layer "In11.Cu")
		(net "P5E_CPU1_P0_TX_BUF_C_DN<6>")
	)
	(segment
		(start 69.38645 -417.506658)
		(end 69.386704 -417.506658)
		(width 0.14224)
		(layer "In11.Cu")
		(net "P5E_CPU1_P0_TX_BUF_C_DN<6>")
	)
	(segment
		(start 66.570606 -413.822896)
		(end 66.902076 -414.189418)
		(width 0.14224)
		(layer "In11.Cu")
		(net "P5E_CPU1_P0_TX_BUF_C_DN<6>")
	)
	(segment
		(start 69.687948 -430.03216)
		(end 70.06336 -430.407572)
		(width 0.14224)
		(layer "In11.Cu")
		(net "P5E_CPU1_P0_TX_BUF_C_DN<6>")
	)
	(segment
		(start 66.90233 -414.189672)
		(end 68.999608 -416.503612)
		(width 0.14224)
		(layer "In11.Cu")
		(net "P5E_CPU1_P0_TX_BUF_C_DN<6>")
	)
	(segment
		(start 69.687694 -418.709094)
		(end 69.687948 -418.70884)
		(width 0.14224)
		(layer "In11.Cu")
		(net "P5E_CPU1_P0_TX_BUF_C_DN<6>")
	)
	(segment
		(start 70.649846 -430.558194)
		(end 70.649846 -430.889918)
		(width 0.14224)
		(layer "In11.Cu")
		(net "P5E_CPU1_P0_TX_BUF_C_DN<6>")
	)
	(segment
		(start 66.173604 -412.570168)
		(end 66.464434 -412.860998)
		(width 0.14224)
		(layer "In11.Cu")
		(net "P5E_CPU1_P0_TX_BUF_C_DN<6>")
	)
	(arc
		(start 69.536818 -417.896294)
		(mid 69.649691 -418.295743)
		(end 69.687694 -418.709094)
		(width 0.14224)
		(layer "In11.Cu")
		(net "P5E_CPU1_P0_TX_BUF_C_DN<6>")
	)
	(arc
		(start 66.464434 -413.548322)
		(mid 66.491923 -413.695517)
		(end 66.570606 -413.822896)
		(width 0.14224)
		(layer "In11.Cu")
		(net "P5E_CPU1_P0_TX_BUF_C_DN<6>")
	)
	(segment
		(start 63.380874 -409.079954)
		(end 63.380874 -412.299658)
		(width 0.12954)
		(layer "F.Cu")
		(net "P5E_CPU1_P0_TX_BUF_C_DN<5>")
	)
	(segment
		(start 63.380874 -412.299658)
		(end 63.110364 -412.570168)
		(width 0.12954)
		(layer "F.Cu")
		(net "P5E_CPU1_P0_TX_BUF_C_DN<5>")
	)
	(segment
		(start 63.084964 -408.784044)
		(end 63.380874 -409.079954)
		(width 0.12954)
		(layer "F.Cu")
		(net "P5E_CPU1_P0_TX_BUF_C_DN<5>")
	)
	(segment
		(start 63.401194 -412.928054)
		(end 63.401194 -413.564832)
		(width 0.14224)
		(layer "In11.Cu")
		(net "P5E_CPU1_P0_TX_BUF_C_DN<5>")
	)
	(segment
		(start 63.110364 -412.570168)
		(end 63.353696 -412.8135)
		(width 0.14224)
		(layer "In11.Cu")
		(net "P5E_CPU1_P0_TX_BUF_C_DN<5>")
	)
	(segment
		(start 67.687952 -431.117756)
		(end 68.00088 -431.430684)
		(width 0.14224)
		(layer "In11.Cu")
		(net "P5E_CPU1_P0_TX_BUF_C_DN<5>")
	)
	(segment
		(start 68.00088 -431.430684)
		(end 68.522342 -431.430684)
		(width 0.14224)
		(layer "In11.Cu")
		(net "P5E_CPU1_P0_TX_BUF_C_DN<5>")
	)
	(segment
		(start 68.64985 -431.558192)
		(end 68.64985 -431.889916)
		(width 0.14224)
		(layer "In11.Cu")
		(net "P5E_CPU1_P0_TX_BUF_C_DN<5>")
	)
	(segment
		(start 68.522342 -431.430684)
		(end 68.64985 -431.558192)
		(width 0.14224)
		(layer "In11.Cu")
		(net "P5E_CPU1_P0_TX_BUF_C_DN<5>")
	)
	(segment
		(start 63.655702 -414.203642)
		(end 67.598798 -417.44392)
		(width 0.14224)
		(layer "In11.Cu")
		(net "P5E_CPU1_P0_TX_BUF_C_DN<5>")
	)
	(segment
		(start 67.687952 -417.598098)
		(end 67.687952 -431.117756)
		(width 0.14224)
		(layer "In11.Cu")
		(net "P5E_CPU1_P0_TX_BUF_C_DN<5>")
	)
	(segment
		(start 63.434214 -413.775906)
		(end 63.496444 -413.968946)
		(width 0.14224)
		(layer "In11.Cu")
		(net "P5E_CPU1_P0_TX_BUF_C_DN<5>")
	)
	(segment
		(start 67.598798 -417.44392)
		(end 67.59956 -417.444682)
		(width 0.14224)
		(layer "In11.Cu")
		(net "P5E_CPU1_P0_TX_BUF_C_DN<5>")
	)
	(segment
		(start 67.59956 -417.444682)
		(end 67.65925 -417.51758)
		(width 0.14224)
		(layer "In11.Cu")
		(net "P5E_CPU1_P0_TX_BUF_C_DN<5>")
	)
	(arc
		(start 63.353696 -412.8135)
		(mid 63.388868 -412.866044)
		(end 63.401194 -412.928054)
		(width 0.14224)
		(layer "In11.Cu")
		(net "P5E_CPU1_P0_TX_BUF_C_DN<5>")
	)
	(arc
		(start 63.401194 -413.564832)
		(mid 63.409457 -413.671659)
		(end 63.434214 -413.775906)
		(width 0.14224)
		(layer "In11.Cu")
		(net "P5E_CPU1_P0_TX_BUF_C_DN<5>")
	)
	(arc
		(start 63.496444 -413.968946)
		(mid 63.559215 -414.097731)
		(end 63.655702 -414.203642)
		(width 0.14224)
		(layer "In11.Cu")
		(net "P5E_CPU1_P0_TX_BUF_C_DN<5>")
	)
	(arc
		(start 67.65925 -417.51758)
		(mid 67.680568 -417.555356)
		(end 67.687952 -417.598098)
		(width 0.14224)
		(layer "In11.Cu")
		(net "P5E_CPU1_P0_TX_BUF_C_DN<5>")
	)
	(segment
		(start 60.021724 -408.784044)
		(end 60.317634 -409.079954)
		(width 0.12954)
		(layer "F.Cu")
		(net "P5E_CPU1_P0_TX_BUF_C_DN<4>")
	)
	(segment
		(start 60.317634 -412.299658)
		(end 60.047124 -412.570168)
		(width 0.12954)
		(layer "F.Cu")
		(net "P5E_CPU1_P0_TX_BUF_C_DN<4>")
	)
	(segment
		(start 60.317634 -409.079954)
		(end 60.317634 -412.299658)
		(width 0.12954)
		(layer "F.Cu")
		(net "P5E_CPU1_P0_TX_BUF_C_DN<4>")
	)
	(segment
		(start 63.277496 -415.412936)
		(end 63.347854 -415.4551)
		(width 0.14224)
		(layer "In11.Cu")
		(net "P5E_CPU1_P0_TX_BUF_C_DN<4>")
	)
	(segment
		(start 66.063368 -430.407572)
		(end 66.499232 -430.407572)
		(width 0.14224)
		(layer "In11.Cu")
		(net "P5E_CPU1_P0_TX_BUF_C_DN<4>")
	)
	(segment
		(start 60.047124 -412.570168)
		(end 60.337954 -412.860998)
		(width 0.14224)
		(layer "In11.Cu")
		(net "P5E_CPU1_P0_TX_BUF_C_DN<4>")
	)
	(segment
		(start 65.687956 -430.03216)
		(end 66.063368 -430.407572)
		(width 0.14224)
		(layer "In11.Cu")
		(net "P5E_CPU1_P0_TX_BUF_C_DN<4>")
	)
	(segment
		(start 60.457842 -413.906716)
		(end 60.63361 -414.082484)
		(width 0.14224)
		(layer "In11.Cu")
		(net "P5E_CPU1_P0_TX_BUF_C_DN<4>")
	)
	(segment
		(start 66.649854 -430.558194)
		(end 66.649854 -430.889918)
		(width 0.14224)
		(layer "In11.Cu")
		(net "P5E_CPU1_P0_TX_BUF_C_DN<4>")
	)
	(segment
		(start 66.499232 -430.407572)
		(end 66.649854 -430.558194)
		(width 0.14224)
		(layer "In11.Cu")
		(net "P5E_CPU1_P0_TX_BUF_C_DN<4>")
	)
	(segment
		(start 60.337954 -412.860998)
		(end 60.337954 -413.617156)
		(width 0.14224)
		(layer "In11.Cu")
		(net "P5E_CPU1_P0_TX_BUF_C_DN<4>")
	)
	(segment
		(start 63.347854 -415.4551)
		(end 65.429892 -417.163758)
		(width 0.14224)
		(layer "In11.Cu")
		(net "P5E_CPU1_P0_TX_BUF_C_DN<4>")
	)
	(segment
		(start 65.687956 -417.709604)
		(end 65.687956 -430.03216)
		(width 0.14224)
		(layer "In11.Cu")
		(net "P5E_CPU1_P0_TX_BUF_C_DN<4>")
	)
	(segment
		(start 60.63361 -414.082484)
		(end 63.277496 -415.412936)
		(width 0.14224)
		(layer "In11.Cu")
		(net "P5E_CPU1_P0_TX_BUF_C_DN<4>")
	)
	(arc
		(start 65.429892 -417.163758)
		(mid 65.620172 -417.407721)
		(end 65.687956 -417.709604)
		(width 0.14224)
		(layer "In11.Cu")
		(net "P5E_CPU1_P0_TX_BUF_C_DN<4>")
	)
	(arc
		(start 60.337954 -413.617156)
		(mid 60.369106 -413.773859)
		(end 60.457842 -413.906716)
		(width 0.14224)
		(layer "In11.Cu")
		(net "P5E_CPU1_P0_TX_BUF_C_DN<4>")
	)
	(segment
		(start 56.958484 -408.784044)
		(end 57.254394 -409.079954)
		(width 0.12954)
		(layer "F.Cu")
		(net "P5E_CPU1_P0_TX_BUF_C_DN<3>")
	)
	(segment
		(start 57.254394 -409.079954)
		(end 57.254394 -412.299658)
		(width 0.12954)
		(layer "F.Cu")
		(net "P5E_CPU1_P0_TX_BUF_C_DN<3>")
	)
	(segment
		(start 57.254394 -412.299658)
		(end 56.983884 -412.570168)
		(width 0.12954)
		(layer "F.Cu")
		(net "P5E_CPU1_P0_TX_BUF_C_DN<3>")
	)
	(segment
		(start 57.597294 -414.271206)
		(end 58.151522 -414.56737)
		(width 0.14224)
		(layer "In11.Cu")
		(net "P5E_CPU1_P0_TX_BUF_C_DN<3>")
	)
	(segment
		(start 64.649858 -431.558192)
		(end 64.649858 -431.889916)
		(width 0.14224)
		(layer "In11.Cu")
		(net "P5E_CPU1_P0_TX_BUF_C_DN<3>")
	)
	(segment
		(start 56.983884 -412.570168)
		(end 57.274714 -412.860998)
		(width 0.14224)
		(layer "In11.Cu")
		(net "P5E_CPU1_P0_TX_BUF_C_DN<3>")
	)
	(segment
		(start 60.124848 -415.166302)
		(end 61.832998 -415.873946)
		(width 0.14224)
		(layer "In11.Cu")
		(net "P5E_CPU1_P0_TX_BUF_C_DN<3>")
	)
	(segment
		(start 64.000888 -431.430684)
		(end 64.52235 -431.430684)
		(width 0.14224)
		(layer "In11.Cu")
		(net "P5E_CPU1_P0_TX_BUF_C_DN<3>")
	)
	(segment
		(start 63.68796 -418.078412)
		(end 63.68796 -431.117756)
		(width 0.14224)
		(layer "In11.Cu")
		(net "P5E_CPU1_P0_TX_BUF_C_DN<3>")
	)
	(segment
		(start 64.52235 -431.430684)
		(end 64.649858 -431.558192)
		(width 0.14224)
		(layer "In11.Cu")
		(net "P5E_CPU1_P0_TX_BUF_C_DN<3>")
	)
	(segment
		(start 58.151522 -414.56737)
		(end 58.382408 -414.637474)
		(width 0.14224)
		(layer "In11.Cu")
		(net "P5E_CPU1_P0_TX_BUF_C_DN<3>")
	)
	(segment
		(start 61.832998 -415.873946)
		(end 63.440818 -417.481766)
		(width 0.14224)
		(layer "In11.Cu")
		(net "P5E_CPU1_P0_TX_BUF_C_DN<3>")
	)
	(segment
		(start 57.508902 -414.18256)
		(end 57.597294 -414.271206)
		(width 0.14224)
		(layer "In11.Cu")
		(net "P5E_CPU1_P0_TX_BUF_C_DN<3>")
	)
	(segment
		(start 57.274714 -412.860998)
		(end 57.274714 -413.617156)
		(width 0.14224)
		(layer "In11.Cu")
		(net "P5E_CPU1_P0_TX_BUF_C_DN<3>")
	)
	(segment
		(start 63.68796 -431.117756)
		(end 64.000888 -431.430684)
		(width 0.14224)
		(layer "In11.Cu")
		(net "P5E_CPU1_P0_TX_BUF_C_DN<3>")
	)
	(segment
		(start 58.382408 -414.637474)
		(end 60.124848 -415.166302)
		(width 0.14224)
		(layer "In11.Cu")
		(net "P5E_CPU1_P0_TX_BUF_C_DN<3>")
	)
	(arc
		(start 57.274714 -413.617156)
		(mid 57.335579 -413.923147)
		(end 57.508902 -414.18256)
		(width 0.14224)
		(layer "In11.Cu")
		(net "P5E_CPU1_P0_TX_BUF_C_DN<3>")
	)
	(arc
		(start 63.440818 -417.481766)
		(mid 63.623728 -417.75551)
		(end 63.68796 -418.078412)
		(width 0.14224)
		(layer "In11.Cu")
		(net "P5E_CPU1_P0_TX_BUF_C_DN<3>")
	)
	(segment
		(start 54.191154 -409.079954)
		(end 54.191154 -412.299658)
		(width 0.12954)
		(layer "F.Cu")
		(net "P5E_CPU1_P0_TX_BUF_C_DN<2>")
	)
	(segment
		(start 54.191154 -412.299658)
		(end 53.920644 -412.570168)
		(width 0.12954)
		(layer "F.Cu")
		(net "P5E_CPU1_P0_TX_BUF_C_DN<2>")
	)
	(segment
		(start 53.895244 -408.784044)
		(end 54.191154 -409.079954)
		(width 0.12954)
		(layer "F.Cu")
		(net "P5E_CPU1_P0_TX_BUF_C_DN<2>")
	)
	(segment
		(start 58.948574 -416.032188)
		(end 60.76188 -416.533838)
		(width 0.14224)
		(layer "In11.Cu")
		(net "P5E_CPU1_P0_TX_BUF_C_DN<2>")
	)
	(segment
		(start 62.649862 -430.558194)
		(end 62.649862 -430.889918)
		(width 0.14224)
		(layer "In11.Cu")
		(net "P5E_CPU1_P0_TX_BUF_C_DN<2>")
	)
	(segment
		(start 62.49924 -430.407572)
		(end 62.649862 -430.558194)
		(width 0.14224)
		(layer "In11.Cu")
		(net "P5E_CPU1_P0_TX_BUF_C_DN<2>")
	)
	(segment
		(start 54.421024 -414.240472)
		(end 54.736746 -414.526476)
		(width 0.14224)
		(layer "In11.Cu")
		(net "P5E_CPU1_P0_TX_BUF_C_DN<2>")
	)
	(segment
		(start 62.063376 -430.407572)
		(end 62.49924 -430.407572)
		(width 0.14224)
		(layer "In11.Cu")
		(net "P5E_CPU1_P0_TX_BUF_C_DN<2>")
	)
	(segment
		(start 54.736746 -414.526476)
		(end 57.448704 -415.649918)
		(width 0.14224)
		(layer "In11.Cu")
		(net "P5E_CPU1_P0_TX_BUF_C_DN<2>")
	)
	(segment
		(start 61.687964 -430.03216)
		(end 62.063376 -430.407572)
		(width 0.14224)
		(layer "In11.Cu")
		(net "P5E_CPU1_P0_TX_BUF_C_DN<2>")
	)
	(segment
		(start 54.211474 -413.848042)
		(end 54.421024 -414.240472)
		(width 0.14224)
		(layer "In11.Cu")
		(net "P5E_CPU1_P0_TX_BUF_C_DN<2>")
	)
	(segment
		(start 57.448704 -415.649918)
		(end 57.87136 -415.733992)
		(width 0.14224)
		(layer "In11.Cu")
		(net "P5E_CPU1_P0_TX_BUF_C_DN<2>")
	)
	(segment
		(start 53.920644 -412.570168)
		(end 54.211474 -412.860998)
		(width 0.14224)
		(layer "In11.Cu")
		(net "P5E_CPU1_P0_TX_BUF_C_DN<2>")
	)
	(segment
		(start 54.211474 -412.860998)
		(end 54.211474 -413.848042)
		(width 0.14224)
		(layer "In11.Cu")
		(net "P5E_CPU1_P0_TX_BUF_C_DN<2>")
	)
	(segment
		(start 57.87136 -415.733992)
		(end 58.948574 -416.031934)
		(width 0.14224)
		(layer "In11.Cu")
		(net "P5E_CPU1_P0_TX_BUF_C_DN<2>")
	)
	(segment
		(start 60.874402 -416.57397)
		(end 61.41212 -417.111688)
		(width 0.14224)
		(layer "In11.Cu")
		(net "P5E_CPU1_P0_TX_BUF_C_DN<2>")
	)
	(segment
		(start 58.948574 -416.031934)
		(end 58.948574 -416.032188)
		(width 0.14224)
		(layer "In11.Cu")
		(net "P5E_CPU1_P0_TX_BUF_C_DN<2>")
	)
	(segment
		(start 60.76188 -416.533838)
		(end 60.874402 -416.57397)
		(width 0.14224)
		(layer "In11.Cu")
		(net "P5E_CPU1_P0_TX_BUF_C_DN<2>")
	)
	(segment
		(start 61.687964 -417.777676)
		(end 61.687964 -430.03216)
		(width 0.14224)
		(layer "In11.Cu")
		(net "P5E_CPU1_P0_TX_BUF_C_DN<2>")
	)
	(arc
		(start 61.41212 -417.111688)
		(mid 61.616287 -417.417246)
		(end 61.687964 -417.777676)
		(width 0.14224)
		(layer "In11.Cu")
		(net "P5E_CPU1_P0_TX_BUF_C_DN<2>")
	)
	(segment
		(start 50.832004 -408.784044)
		(end 51.127914 -409.079954)
		(width 0.12954)
		(layer "F.Cu")
		(net "P5E_CPU1_P0_TX_BUF_C_DN<1>")
	)
	(segment
		(start 51.127914 -409.079954)
		(end 51.127914 -412.299658)
		(width 0.12954)
		(layer "F.Cu")
		(net "P5E_CPU1_P0_TX_BUF_C_DN<1>")
	)
	(segment
		(start 51.127914 -412.299658)
		(end 50.857404 -412.570168)
		(width 0.12954)
		(layer "F.Cu")
		(net "P5E_CPU1_P0_TX_BUF_C_DN<1>")
	)
	(segment
		(start 57.780936 -416.902392)
		(end 58.982102 -417.020502)
		(width 0.14224)
		(layer "In11.Cu")
		(net "P5E_CPU1_P0_TX_BUF_C_DN<1>")
	)
	(segment
		(start 51.60264 -414.467548)
		(end 53.723794 -415.885122)
		(width 0.14224)
		(layer "In11.Cu")
		(net "P5E_CPU1_P0_TX_BUF_C_DN<1>")
	)
	(segment
		(start 59.687968 -431.117756)
		(end 60.000896 -431.430684)
		(width 0.14224)
		(layer "In11.Cu")
		(net "P5E_CPU1_P0_TX_BUF_C_DN<1>")
	)
	(segment
		(start 50.857404 -412.570168)
		(end 51.148234 -412.860998)
		(width 0.14224)
		(layer "In11.Cu")
		(net "P5E_CPU1_P0_TX_BUF_C_DN<1>")
	)
	(segment
		(start 59.687968 -417.915344)
		(end 59.687968 -431.117756)
		(width 0.14224)
		(layer "In11.Cu")
		(net "P5E_CPU1_P0_TX_BUF_C_DN<1>")
	)
	(segment
		(start 58.982102 -417.020502)
		(end 59.139836 -417.095178)
		(width 0.14224)
		(layer "In11.Cu")
		(net "P5E_CPU1_P0_TX_BUF_C_DN<1>")
	)
	(segment
		(start 59.139836 -417.095178)
		(end 59.495436 -417.450778)
		(width 0.14224)
		(layer "In11.Cu")
		(net "P5E_CPU1_P0_TX_BUF_C_DN<1>")
	)
	(segment
		(start 53.723794 -415.885122)
		(end 57.780936 -416.902392)
		(width 0.14224)
		(layer "In11.Cu")
		(net "P5E_CPU1_P0_TX_BUF_C_DN<1>")
	)
	(segment
		(start 60.000896 -431.430684)
		(end 60.522358 -431.430684)
		(width 0.14224)
		(layer "In11.Cu")
		(net "P5E_CPU1_P0_TX_BUF_C_DN<1>")
	)
	(segment
		(start 51.148234 -412.860998)
		(end 51.148234 -413.616902)
		(width 0.14224)
		(layer "In11.Cu")
		(net "P5E_CPU1_P0_TX_BUF_C_DN<1>")
	)
	(segment
		(start 60.649866 -431.558192)
		(end 60.649866 -431.889916)
		(width 0.14224)
		(layer "In11.Cu")
		(net "P5E_CPU1_P0_TX_BUF_C_DN<1>")
	)
	(segment
		(start 60.522358 -431.430684)
		(end 60.649866 -431.558192)
		(width 0.14224)
		(layer "In11.Cu")
		(net "P5E_CPU1_P0_TX_BUF_C_DN<1>")
	)
	(arc
		(start 59.495436 -417.450778)
		(mid 59.637908 -417.663908)
		(end 59.687968 -417.915344)
		(width 0.14224)
		(layer "In11.Cu")
		(net "P5E_CPU1_P0_TX_BUF_C_DN<1>")
	)
	(arc
		(start 51.148234 -413.616902)
		(mid 51.268885 -414.099155)
		(end 51.60264 -414.467548)
		(width 0.14224)
		(layer "In11.Cu")
		(net "P5E_CPU1_P0_TX_BUF_C_DN<1>")
	)
	(segment
		(start 94.013274 -412.299658)
		(end 93.742764 -412.570168)
		(width 0.12954)
		(layer "F.Cu")
		(net "P5E_CPU1_P0_TX_BUF_C_DN<15>")
	)
	(segment
		(start 93.717364 -408.784044)
		(end 94.013274 -409.079954)
		(width 0.12954)
		(layer "F.Cu")
		(net "P5E_CPU1_P0_TX_BUF_C_DN<15>")
	)
	(segment
		(start 94.013274 -409.079954)
		(end 94.013274 -412.299658)
		(width 0.12954)
		(layer "F.Cu")
		(net "P5E_CPU1_P0_TX_BUF_C_DN<15>")
	)
	(segment
		(start 91.35745 -420.095934)
		(end 88.891618 -423.786554)
		(width 0.14224)
		(layer "In11.Cu")
		(net "P5E_CPU1_P0_TX_BUF_C_DN<15>")
	)
	(segment
		(start 94.033594 -412.860998)
		(end 94.033594 -413.70377)
		(width 0.14224)
		(layer "In11.Cu")
		(net "P5E_CPU1_P0_TX_BUF_C_DN<15>")
	)
	(segment
		(start 88.688164 -424.457876)
		(end 88.688164 -431.117756)
		(width 0.14224)
		(layer "In11.Cu")
		(net "P5E_CPU1_P0_TX_BUF_C_DN<15>")
	)
	(segment
		(start 88.688164 -431.117756)
		(end 89.001092 -431.430684)
		(width 0.14224)
		(layer "In11.Cu")
		(net "P5E_CPU1_P0_TX_BUF_C_DN<15>")
	)
	(segment
		(start 89.001092 -431.430684)
		(end 89.522554 -431.430684)
		(width 0.14224)
		(layer "In11.Cu")
		(net "P5E_CPU1_P0_TX_BUF_C_DN<15>")
	)
	(segment
		(start 93.44787 -415.676334)
		(end 91.35745 -420.095934)
		(width 0.14224)
		(layer "In11.Cu")
		(net "P5E_CPU1_P0_TX_BUF_C_DN<15>")
	)
	(segment
		(start 89.650062 -431.558192)
		(end 89.650062 -431.889916)
		(width 0.14224)
		(layer "In11.Cu")
		(net "P5E_CPU1_P0_TX_BUF_C_DN<15>")
	)
	(segment
		(start 94.021402 -413.785304)
		(end 93.44787 -415.676334)
		(width 0.14224)
		(layer "In11.Cu")
		(net "P5E_CPU1_P0_TX_BUF_C_DN<15>")
	)
	(segment
		(start 94.033594 -413.70377)
		(end 94.03334 -413.70377)
		(width 0.14224)
		(layer "In11.Cu")
		(net "P5E_CPU1_P0_TX_BUF_C_DN<15>")
	)
	(segment
		(start 93.742764 -412.570168)
		(end 94.033594 -412.860998)
		(width 0.14224)
		(layer "In11.Cu")
		(net "P5E_CPU1_P0_TX_BUF_C_DN<15>")
	)
	(segment
		(start 89.522554 -431.430684)
		(end 89.650062 -431.558192)
		(width 0.14224)
		(layer "In11.Cu")
		(net "P5E_CPU1_P0_TX_BUF_C_DN<15>")
	)
	(arc
		(start 94.03334 -413.70377)
		(mid 94.030384 -413.744979)
		(end 94.021402 -413.785304)
		(width 0.14224)
		(layer "In11.Cu")
		(net "P5E_CPU1_P0_TX_BUF_C_DN<15>")
	)
	(arc
		(start 88.891618 -423.786554)
		(mid 88.740093 -424.107121)
		(end 88.688164 -424.457876)
		(width 0.14224)
		(layer "In11.Cu")
		(net "P5E_CPU1_P0_TX_BUF_C_DN<15>")
	)
	(segment
		(start 90.950034 -412.299658)
		(end 90.679524 -412.570168)
		(width 0.12954)
		(layer "F.Cu")
		(net "P5E_CPU1_P0_TX_BUF_C_DN<14>")
	)
	(segment
		(start 90.950034 -409.079954)
		(end 90.950034 -412.299658)
		(width 0.12954)
		(layer "F.Cu")
		(net "P5E_CPU1_P0_TX_BUF_C_DN<14>")
	)
	(segment
		(start 90.654124 -408.784044)
		(end 90.950034 -409.079954)
		(width 0.12954)
		(layer "F.Cu")
		(net "P5E_CPU1_P0_TX_BUF_C_DN<14>")
	)
	(segment
		(start 88.7095 -419.440106)
		(end 88.708992 -419.44036)
		(width 0.14224)
		(layer "In11.Cu")
		(net "P5E_CPU1_P0_TX_BUF_C_DN<14>")
	)
	(segment
		(start 90.908632 -413.892746)
		(end 90.446606 -415.08934)
		(width 0.14224)
		(layer "In11.Cu")
		(net "P5E_CPU1_P0_TX_BUF_C_DN<14>")
	)
	(segment
		(start 87.329264 -422.501822)
		(end 86.863682 -423.626788)
		(width 0.14224)
		(layer "In11.Cu")
		(net "P5E_CPU1_P0_TX_BUF_C_DN<14>")
	)
	(segment
		(start 87.650066 -430.558194)
		(end 87.650066 -430.889918)
		(width 0.14224)
		(layer "In11.Cu")
		(net "P5E_CPU1_P0_TX_BUF_C_DN<14>")
	)
	(segment
		(start 90.970354 -413.561276)
		(end 90.9701 -413.561022)
		(width 0.14224)
		(layer "In11.Cu")
		(net "P5E_CPU1_P0_TX_BUF_C_DN<14>")
	)
	(segment
		(start 87.06358 -430.407572)
		(end 87.499444 -430.407572)
		(width 0.14224)
		(layer "In11.Cu")
		(net "P5E_CPU1_P0_TX_BUF_C_DN<14>")
	)
	(segment
		(start 90.446606 -415.08934)
		(end 90.44686 -415.08934)
		(width 0.14224)
		(layer "In11.Cu")
		(net "P5E_CPU1_P0_TX_BUF_C_DN<14>")
	)
	(segment
		(start 89.78773 -416.798252)
		(end 89.382092 -417.849812)
		(width 0.14224)
		(layer "In11.Cu")
		(net "P5E_CPU1_P0_TX_BUF_C_DN<14>")
	)
	(segment
		(start 90.970354 -412.860998)
		(end 90.970354 -413.561276)
		(width 0.14224)
		(layer "In11.Cu")
		(net "P5E_CPU1_P0_TX_BUF_C_DN<14>")
	)
	(segment
		(start 89.38133 -417.851336)
		(end 89.121234 -418.52596)
		(width 0.14224)
		(layer "In11.Cu")
		(net "P5E_CPU1_P0_TX_BUF_C_DN<14>")
	)
	(segment
		(start 90.44686 -415.08934)
		(end 90.446098 -415.091626)
		(width 0.14224)
		(layer "In11.Cu")
		(net "P5E_CPU1_P0_TX_BUF_C_DN<14>")
	)
	(segment
		(start 89.382092 -417.849812)
		(end 89.381838 -417.850574)
		(width 0.14224)
		(layer "In11.Cu")
		(net "P5E_CPU1_P0_TX_BUF_C_DN<14>")
	)
	(segment
		(start 87.499444 -430.407572)
		(end 87.650066 -430.558194)
		(width 0.14224)
		(layer "In11.Cu")
		(net "P5E_CPU1_P0_TX_BUF_C_DN<14>")
	)
	(segment
		(start 89.381838 -417.850574)
		(end 89.38133 -417.851336)
		(width 0.14224)
		(layer "In11.Cu")
		(net "P5E_CPU1_P0_TX_BUF_C_DN<14>")
	)
	(segment
		(start 90.679524 -412.570168)
		(end 90.970354 -412.860998)
		(width 0.14224)
		(layer "In11.Cu")
		(net "P5E_CPU1_P0_TX_BUF_C_DN<14>")
	)
	(segment
		(start 89.787984 -416.79749)
		(end 89.78773 -416.798252)
		(width 0.14224)
		(layer "In11.Cu")
		(net "P5E_CPU1_P0_TX_BUF_C_DN<14>")
	)
	(segment
		(start 86.688168 -424.509692)
		(end 86.688168 -430.03216)
		(width 0.14224)
		(layer "In11.Cu")
		(net "P5E_CPU1_P0_TX_BUF_C_DN<14>")
	)
	(segment
		(start 88.708992 -419.44036)
		(end 87.329264 -422.501822)
		(width 0.14224)
		(layer "In11.Cu")
		(net "P5E_CPU1_P0_TX_BUF_C_DN<14>")
	)
	(segment
		(start 89.121234 -418.52596)
		(end 88.7095 -419.440106)
		(width 0.14224)
		(layer "In11.Cu")
		(net "P5E_CPU1_P0_TX_BUF_C_DN<14>")
	)
	(segment
		(start 90.446098 -415.091626)
		(end 89.787984 -416.79749)
		(width 0.14224)
		(layer "In11.Cu")
		(net "P5E_CPU1_P0_TX_BUF_C_DN<14>")
	)
	(segment
		(start 86.688168 -430.03216)
		(end 87.06358 -430.407572)
		(width 0.14224)
		(layer "In11.Cu")
		(net "P5E_CPU1_P0_TX_BUF_C_DN<14>")
	)
	(arc
		(start 90.9701 -413.561022)
		(mid 90.954706 -413.729728)
		(end 90.908632 -413.892746)
		(width 0.14224)
		(layer "In11.Cu")
		(net "P5E_CPU1_P0_TX_BUF_C_DN<14>")
	)
	(arc
		(start 86.863682 -423.626788)
		(mid 86.732481 -424.059603)
		(end 86.688168 -424.509692)
		(width 0.14224)
		(layer "In11.Cu")
		(net "P5E_CPU1_P0_TX_BUF_C_DN<14>")
	)
	(segment
		(start 87.886794 -412.299658)
		(end 87.616284 -412.570168)
		(width 0.12954)
		(layer "F.Cu")
		(net "P5E_CPU1_P0_TX_BUF_C_DN<13>")
	)
	(segment
		(start 87.590884 -408.784044)
		(end 87.886794 -409.079954)
		(width 0.12954)
		(layer "F.Cu")
		(net "P5E_CPU1_P0_TX_BUF_C_DN<13>")
	)
	(segment
		(start 87.886794 -409.079954)
		(end 87.886794 -412.299658)
		(width 0.12954)
		(layer "F.Cu")
		(net "P5E_CPU1_P0_TX_BUF_C_DN<13>")
	)
	(segment
		(start 84.688172 -431.097436)
		(end 85.02142 -431.430684)
		(width 0.14224)
		(layer "In11.Cu")
		(net "P5E_CPU1_P0_TX_BUF_C_DN<13>")
	)
	(segment
		(start 87.591646 -415.172398)
		(end 87.267542 -416.241484)
		(width 0.14224)
		(layer "In11.Cu")
		(net "P5E_CPU1_P0_TX_BUF_C_DN<13>")
	)
	(segment
		(start 87.601552 -415.167064)
		(end 87.591646 -415.172398)
		(width 0.14224)
		(layer "In11.Cu")
		(net "P5E_CPU1_P0_TX_BUF_C_DN<13>")
	)
	(segment
		(start 87.616284 -412.570168)
		(end 87.907114 -412.860998)
		(width 0.14224)
		(layer "In11.Cu")
		(net "P5E_CPU1_P0_TX_BUF_C_DN<13>")
	)
	(segment
		(start 84.688172 -424.931586)
		(end 84.688172 -431.097436)
		(width 0.14224)
		(layer "In11.Cu")
		(net "P5E_CPU1_P0_TX_BUF_C_DN<13>")
	)
	(segment
		(start 87.272622 -416.25139)
		(end 87.103204 -416.810444)
		(width 0.14224)
		(layer "In11.Cu")
		(net "P5E_CPU1_P0_TX_BUF_C_DN<13>")
	)
	(segment
		(start 87.772494 -414.604454)
		(end 87.771478 -414.607502)
		(width 0.14224)
		(layer "In11.Cu")
		(net "P5E_CPU1_P0_TX_BUF_C_DN<13>")
	)
	(segment
		(start 87.907114 -412.860998)
		(end 87.907114 -414.048956)
		(width 0.14224)
		(layer "In11.Cu")
		(net "P5E_CPU1_P0_TX_BUF_C_DN<13>")
	)
	(segment
		(start 85.65007 -431.558192)
		(end 85.65007 -431.889916)
		(width 0.14224)
		(layer "In11.Cu")
		(net "P5E_CPU1_P0_TX_BUF_C_DN<13>")
	)
	(segment
		(start 86.316058 -419.405308)
		(end 85.017356 -423.03446)
		(width 0.14224)
		(layer "In11.Cu")
		(net "P5E_CPU1_P0_TX_BUF_C_DN<13>")
	)
	(segment
		(start 85.522562 -431.430684)
		(end 85.65007 -431.558192)
		(width 0.14224)
		(layer "In11.Cu")
		(net "P5E_CPU1_P0_TX_BUF_C_DN<13>")
	)
	(segment
		(start 87.874602 -414.267396)
		(end 87.772494 -414.604454)
		(width 0.14224)
		(layer "In11.Cu")
		(net "P5E_CPU1_P0_TX_BUF_C_DN<13>")
	)
	(segment
		(start 87.267542 -416.241484)
		(end 87.272622 -416.25139)
		(width 0.14224)
		(layer "In11.Cu")
		(net "P5E_CPU1_P0_TX_BUF_C_DN<13>")
	)
	(segment
		(start 87.10295 -416.810952)
		(end 86.316058 -419.405308)
		(width 0.14224)
		(layer "In11.Cu")
		(net "P5E_CPU1_P0_TX_BUF_C_DN<13>")
	)
	(segment
		(start 87.771478 -414.607502)
		(end 87.601552 -415.167064)
		(width 0.14224)
		(layer "In11.Cu")
		(net "P5E_CPU1_P0_TX_BUF_C_DN<13>")
	)
	(segment
		(start 85.02142 -431.430684)
		(end 85.522562 -431.430684)
		(width 0.14224)
		(layer "In11.Cu")
		(net "P5E_CPU1_P0_TX_BUF_C_DN<13>")
	)
	(segment
		(start 87.103204 -416.810444)
		(end 87.10295 -416.810952)
		(width 0.14224)
		(layer "In11.Cu")
		(net "P5E_CPU1_P0_TX_BUF_C_DN<13>")
	)
	(arc
		(start 85.017356 -423.03446)
		(mid 84.771052 -423.968846)
		(end 84.688172 -424.931586)
		(width 0.14224)
		(layer "In11.Cu")
		(net "P5E_CPU1_P0_TX_BUF_C_DN<13>")
	)
	(arc
		(start 87.907114 -414.048956)
		(mid 87.898903 -414.159373)
		(end 87.874602 -414.267396)
		(width 0.14224)
		(layer "In11.Cu")
		(net "P5E_CPU1_P0_TX_BUF_C_DN<13>")
	)
	(segment
		(start 84.823554 -409.079954)
		(end 84.823554 -412.299658)
		(width 0.12954)
		(layer "F.Cu")
		(net "P5E_CPU1_P0_TX_BUF_C_DN<12>")
	)
	(segment
		(start 84.823554 -412.299658)
		(end 84.553044 -412.570168)
		(width 0.12954)
		(layer "F.Cu")
		(net "P5E_CPU1_P0_TX_BUF_C_DN<12>")
	)
	(segment
		(start 84.527644 -408.784044)
		(end 84.823554 -409.079954)
		(width 0.12954)
		(layer "F.Cu")
		(net "P5E_CPU1_P0_TX_BUF_C_DN<12>")
	)
	(segment
		(start 84.83727 -413.776668)
		(end 84.510118 -415.234374)
		(width 0.14224)
		(layer "In11.Cu")
		(net "P5E_CPU1_P0_TX_BUF_C_DN<12>")
	)
	(segment
		(start 84.510118 -415.234374)
		(end 84.509864 -415.23539)
		(width 0.14224)
		(layer "In11.Cu")
		(net "P5E_CPU1_P0_TX_BUF_C_DN<12>")
	)
	(segment
		(start 82.688176 -430.03216)
		(end 83.063588 -430.407572)
		(width 0.14224)
		(layer "In11.Cu")
		(net "P5E_CPU1_P0_TX_BUF_C_DN<12>")
	)
	(segment
		(start 83.063588 -430.407572)
		(end 83.499452 -430.407572)
		(width 0.14224)
		(layer "In11.Cu")
		(net "P5E_CPU1_P0_TX_BUF_C_DN<12>")
	)
	(segment
		(start 84.843874 -412.860998)
		(end 84.843874 -413.719264)
		(width 0.14224)
		(layer "In11.Cu")
		(net "P5E_CPU1_P0_TX_BUF_C_DN<12>")
	)
	(segment
		(start 84.184744 -416.68319)
		(end 84.03082 -417.368482)
		(width 0.14224)
		(layer "In11.Cu")
		(net "P5E_CPU1_P0_TX_BUF_C_DN<12>")
	)
	(segment
		(start 84.184998 -416.682174)
		(end 84.184744 -416.68319)
		(width 0.14224)
		(layer "In11.Cu")
		(net "P5E_CPU1_P0_TX_BUF_C_DN<12>")
	)
	(segment
		(start 84.83727 -413.776414)
		(end 84.83727 -413.776668)
		(width 0.14224)
		(layer "In11.Cu")
		(net "P5E_CPU1_P0_TX_BUF_C_DN<12>")
	)
	(segment
		(start 83.650074 -430.558194)
		(end 83.650074 -430.889918)
		(width 0.14224)
		(layer "In11.Cu")
		(net "P5E_CPU1_P0_TX_BUF_C_DN<12>")
	)
	(segment
		(start 84.030566 -417.369498)
		(end 82.82559 -422.73474)
		(width 0.14224)
		(layer "In11.Cu")
		(net "P5E_CPU1_P0_TX_BUF_C_DN<12>")
	)
	(segment
		(start 84.356448 -415.918396)
		(end 84.356194 -415.919412)
		(width 0.14224)
		(layer "In11.Cu")
		(net "P5E_CPU1_P0_TX_BUF_C_DN<12>")
	)
	(segment
		(start 82.688176 -423.974768)
		(end 82.688176 -430.03216)
		(width 0.14224)
		(layer "In11.Cu")
		(net "P5E_CPU1_P0_TX_BUF_C_DN<12>")
	)
	(segment
		(start 84.553044 -412.570168)
		(end 84.843874 -412.860998)
		(width 0.14224)
		(layer "In11.Cu")
		(net "P5E_CPU1_P0_TX_BUF_C_DN<12>")
	)
	(segment
		(start 84.509864 -415.23539)
		(end 84.356448 -415.918396)
		(width 0.14224)
		(layer "In11.Cu")
		(net "P5E_CPU1_P0_TX_BUF_C_DN<12>")
	)
	(segment
		(start 83.499452 -430.407572)
		(end 83.650074 -430.558194)
		(width 0.14224)
		(layer "In11.Cu")
		(net "P5E_CPU1_P0_TX_BUF_C_DN<12>")
	)
	(segment
		(start 84.03082 -417.368482)
		(end 84.030566 -417.369498)
		(width 0.14224)
		(layer "In11.Cu")
		(net "P5E_CPU1_P0_TX_BUF_C_DN<12>")
	)
	(segment
		(start 84.356194 -415.919412)
		(end 84.184998 -416.682174)
		(width 0.14224)
		(layer "In11.Cu")
		(net "P5E_CPU1_P0_TX_BUF_C_DN<12>")
	)
	(arc
		(start 84.843874 -413.719264)
		(mid 84.842142 -413.74802)
		(end 84.83727 -413.776414)
		(width 0.14224)
		(layer "In11.Cu")
		(net "P5E_CPU1_P0_TX_BUF_C_DN<12>")
	)
	(arc
		(start 82.82559 -422.73474)
		(mid 82.722606 -423.350956)
		(end 82.688176 -423.974768)
		(width 0.14224)
		(layer "In11.Cu")
		(net "P5E_CPU1_P0_TX_BUF_C_DN<12>")
	)
	(segment
		(start 81.760314 -412.299658)
		(end 81.489804 -412.570168)
		(width 0.12954)
		(layer "F.Cu")
		(net "P5E_CPU1_P0_TX_BUF_C_DN<11>")
	)
	(segment
		(start 81.464404 -408.784044)
		(end 81.760314 -409.079954)
		(width 0.12954)
		(layer "F.Cu")
		(net "P5E_CPU1_P0_TX_BUF_C_DN<11>")
	)
	(segment
		(start 81.760314 -409.079954)
		(end 81.760314 -412.299658)
		(width 0.12954)
		(layer "F.Cu")
		(net "P5E_CPU1_P0_TX_BUF_C_DN<11>")
	)
	(segment
		(start 81.650078 -431.558192)
		(end 81.513172 -431.421286)
		(width 0.14224)
		(layer "In11.Cu")
		(net "P5E_CPU1_P0_TX_BUF_C_DN<11>")
	)
	(segment
		(start 81.78038 -414.0073)
		(end 81.780634 -414.007046)
		(width 0.14224)
		(layer "In11.Cu")
		(net "P5E_CPU1_P0_TX_BUF_C_DN<11>")
	)
	(segment
		(start 80.68818 -431.117756)
		(end 80.68818 -425.114974)
		(width 0.14224)
		(layer "In11.Cu")
		(net "P5E_CPU1_P0_TX_BUF_C_DN<11>")
	)
	(segment
		(start 81.513172 -431.421286)
		(end 80.99171 -431.421286)
		(width 0.14224)
		(layer "In11.Cu")
		(net "P5E_CPU1_P0_TX_BUF_C_DN<11>")
	)
	(segment
		(start 81.780634 -414.007046)
		(end 81.780634 -412.860998)
		(width 0.14224)
		(layer "In11.Cu")
		(net "P5E_CPU1_P0_TX_BUF_C_DN<11>")
	)
	(segment
		(start 80.99171 -431.421286)
		(end 80.68818 -431.117756)
		(width 0.14224)
		(layer "In11.Cu")
		(net "P5E_CPU1_P0_TX_BUF_C_DN<11>")
	)
	(segment
		(start 80.68818 -425.114974)
		(end 81.78038 -414.0073)
		(width 0.14224)
		(layer "In11.Cu")
		(net "P5E_CPU1_P0_TX_BUF_C_DN<11>")
	)
	(segment
		(start 81.650078 -431.889916)
		(end 81.650078 -431.558192)
		(width 0.14224)
		(layer "In11.Cu")
		(net "P5E_CPU1_P0_TX_BUF_C_DN<11>")
	)
	(segment
		(start 81.780634 -412.860998)
		(end 81.489804 -412.570168)
		(width 0.14224)
		(layer "In11.Cu")
		(net "P5E_CPU1_P0_TX_BUF_C_DN<11>")
	)
	(segment
		(start 78.401164 -408.784044)
		(end 78.697074 -409.079954)
		(width 0.12954)
		(layer "F.Cu")
		(net "P5E_CPU1_P0_TX_BUF_C_DN<10>")
	)
	(segment
		(start 78.697074 -412.299658)
		(end 78.426564 -412.570168)
		(width 0.12954)
		(layer "F.Cu")
		(net "P5E_CPU1_P0_TX_BUF_C_DN<10>")
	)
	(segment
		(start 78.697074 -409.079954)
		(end 78.697074 -412.299658)
		(width 0.12954)
		(layer "F.Cu")
		(net "P5E_CPU1_P0_TX_BUF_C_DN<10>")
	)
	(segment
		(start 79.650082 -430.558194)
		(end 79.49946 -430.407572)
		(width 0.14224)
		(layer "In11.Cu")
		(net "P5E_CPU1_P0_TX_BUF_C_DN<10>")
	)
	(segment
		(start 78.717394 -414.026096)
		(end 78.717394 -412.860998)
		(width 0.14224)
		(layer "In11.Cu")
		(net "P5E_CPU1_P0_TX_BUF_C_DN<10>")
	)
	(segment
		(start 79.063596 -430.407572)
		(end 78.688184 -430.03216)
		(width 0.14224)
		(layer "In11.Cu")
		(net "P5E_CPU1_P0_TX_BUF_C_DN<10>")
	)
	(segment
		(start 79.49946 -430.407572)
		(end 79.063596 -430.407572)
		(width 0.14224)
		(layer "In11.Cu")
		(net "P5E_CPU1_P0_TX_BUF_C_DN<10>")
	)
	(segment
		(start 78.688184 -423.603928)
		(end 79.01432 -420.070026)
		(width 0.14224)
		(layer "In11.Cu")
		(net "P5E_CPU1_P0_TX_BUF_C_DN<10>")
	)
	(segment
		(start 79.01432 -420.070026)
		(end 78.717394 -414.026096)
		(width 0.14224)
		(layer "In11.Cu")
		(net "P5E_CPU1_P0_TX_BUF_C_DN<10>")
	)
	(segment
		(start 79.650082 -430.889918)
		(end 79.650082 -430.558194)
		(width 0.14224)
		(layer "In11.Cu")
		(net "P5E_CPU1_P0_TX_BUF_C_DN<10>")
	)
	(segment
		(start 78.688184 -430.03216)
		(end 78.688184 -423.603928)
		(width 0.14224)
		(layer "In11.Cu")
		(net "P5E_CPU1_P0_TX_BUF_C_DN<10>")
	)
	(segment
		(start 78.717394 -412.860998)
		(end 78.426564 -412.570168)
		(width 0.14224)
		(layer "In11.Cu")
		(net "P5E_CPU1_P0_TX_BUF_C_DN<10>")
	)
	(segment
		(start 48.064674 -412.299658)
		(end 47.794164 -412.570168)
		(width 0.12954)
		(layer "F.Cu")
		(net "P5E_CPU1_P0_TX_BUF_C_DN<0>")
	)
	(segment
		(start 48.064674 -409.079954)
		(end 48.064674 -412.299658)
		(width 0.12954)
		(layer "F.Cu")
		(net "P5E_CPU1_P0_TX_BUF_C_DN<0>")
	)
	(segment
		(start 47.768764 -408.784044)
		(end 48.064674 -409.079954)
		(width 0.12954)
		(layer "F.Cu")
		(net "P5E_CPU1_P0_TX_BUF_C_DN<0>")
	)
	(segment
		(start 53.453538 -417.144708)
		(end 53.777388 -417.27882)
		(width 0.14224)
		(layer "In11.Cu")
		(net "P5E_CPU1_P0_TX_BUF_C_DN<0>")
	)
	(segment
		(start 48.084994 -412.860998)
		(end 48.084994 -413.96539)
		(width 0.14224)
		(layer "In11.Cu")
		(net "P5E_CPU1_P0_TX_BUF_C_DN<0>")
	)
	(segment
		(start 54.101238 -417.413186)
		(end 54.101492 -417.41344)
		(width 0.14224)
		(layer "In11.Cu")
		(net "P5E_CPU1_P0_TX_BUF_C_DN<0>")
	)
	(segment
		(start 57.687972 -430.03216)
		(end 58.063384 -430.407572)
		(width 0.14224)
		(layer "In11.Cu")
		(net "P5E_CPU1_P0_TX_BUF_C_DN<0>")
	)
	(segment
		(start 48.084994 -413.96539)
		(end 48.349662 -414.604454)
		(width 0.14224)
		(layer "In11.Cu")
		(net "P5E_CPU1_P0_TX_BUF_C_DN<0>")
	)
	(segment
		(start 48.75784 -415.012632)
		(end 49.493678 -415.504376)
		(width 0.14224)
		(layer "In11.Cu")
		(net "P5E_CPU1_P0_TX_BUF_C_DN<0>")
	)
	(segment
		(start 53.777642 -417.279074)
		(end 54.101238 -417.413186)
		(width 0.14224)
		(layer "In11.Cu")
		(net "P5E_CPU1_P0_TX_BUF_C_DN<0>")
	)
	(segment
		(start 57.687972 -419.85819)
		(end 57.687972 -430.03216)
		(width 0.14224)
		(layer "In11.Cu")
		(net "P5E_CPU1_P0_TX_BUF_C_DN<0>")
	)
	(segment
		(start 57.240678 -418.943028)
		(end 57.35701 -419.05936)
		(width 0.14224)
		(layer "In11.Cu")
		(net "P5E_CPU1_P0_TX_BUF_C_DN<0>")
	)
	(segment
		(start 58.499248 -430.407572)
		(end 58.64987 -430.558194)
		(width 0.14224)
		(layer "In11.Cu")
		(net "P5E_CPU1_P0_TX_BUF_C_DN<0>")
	)
	(segment
		(start 58.64987 -430.558194)
		(end 58.64987 -430.889918)
		(width 0.14224)
		(layer "In11.Cu")
		(net "P5E_CPU1_P0_TX_BUF_C_DN<0>")
	)
	(segment
		(start 48.349662 -414.604454)
		(end 48.75784 -415.012632)
		(width 0.14224)
		(layer "In11.Cu")
		(net "P5E_CPU1_P0_TX_BUF_C_DN<0>")
	)
	(segment
		(start 47.794164 -412.570168)
		(end 48.084994 -412.860998)
		(width 0.14224)
		(layer "In11.Cu")
		(net "P5E_CPU1_P0_TX_BUF_C_DN<0>")
	)
	(segment
		(start 53.777388 -417.27882)
		(end 53.777642 -417.279074)
		(width 0.14224)
		(layer "In11.Cu")
		(net "P5E_CPU1_P0_TX_BUF_C_DN<0>")
	)
	(segment
		(start 54.101492 -417.41344)
		(end 56.336438 -418.339016)
		(width 0.14224)
		(layer "In11.Cu")
		(net "P5E_CPU1_P0_TX_BUF_C_DN<0>")
	)
	(segment
		(start 58.063384 -430.407572)
		(end 58.499248 -430.407572)
		(width 0.14224)
		(layer "In11.Cu")
		(net "P5E_CPU1_P0_TX_BUF_C_DN<0>")
	)
	(segment
		(start 49.493678 -415.504376)
		(end 53.453538 -417.144708)
		(width 0.14224)
		(layer "In11.Cu")
		(net "P5E_CPU1_P0_TX_BUF_C_DN<0>")
	)
	(arc
		(start 57.35701 -419.05936)
		(mid 57.601955 -419.425852)
		(end 57.687972 -419.85819)
		(width 0.14224)
		(layer "In11.Cu")
		(net "P5E_CPU1_P0_TX_BUF_C_DN<0>")
	)
	(arc
		(start 56.336438 -418.339016)
		(mid 56.818307 -418.596487)
		(end 57.240678 -418.943028)
		(width 0.14224)
		(layer "In11.Cu")
		(net "P5E_CPU1_P0_TX_BUF_C_DN<0>")
	)
	(segment
		(start 58.616596 -393.1158)
		(end 58.616596 -393.292838)
		(width 0.1016)
		(layer "F.Cu")
		(net "P5E_CPU1_P0_RX_BUF_DP<9>")
	)
	(segment
		(start 58.002678 -391.36574)
		(end 58.002678 -391.488676)
		(width 0.1016)
		(layer "F.Cu")
		(net "P5E_CPU1_P0_RX_BUF_DP<9>")
	)
	(segment
		(start 57.918096 -391.281158)
		(end 58.002678 -391.36574)
		(width 0.1016)
		(layer "F.Cu")
		(net "P5E_CPU1_P0_RX_BUF_DP<9>")
	)
	(segment
		(start 58.477912 -392.977116)
		(end 58.616596 -393.1158)
		(width 0.1016)
		(layer "F.Cu")
		(net "P5E_CPU1_P0_RX_BUF_DP<9>")
	)
	(segment
		(start 58.002678 -391.488676)
		(end 57.931558 -391.559796)
		(width 0.1016)
		(layer "F.Cu")
		(net "P5E_CPU1_P0_RX_BUF_DP<9>")
	)
	(segment
		(start 57.931558 -391.559796)
		(end 57.931558 -392.723878)
		(width 0.1016)
		(layer "F.Cu")
		(net "P5E_CPU1_P0_RX_BUF_DP<9>")
	)
	(segment
		(start 57.931558 -392.723878)
		(end 58.184796 -392.977116)
		(width 0.1016)
		(layer "F.Cu")
		(net "P5E_CPU1_P0_RX_BUF_DP<9>")
	)
	(segment
		(start 58.184796 -392.977116)
		(end 58.477912 -392.977116)
		(width 0.1016)
		(layer "F.Cu")
		(net "P5E_CPU1_P0_RX_BUF_DP<9>")
	)
	(segment
		(start 77.404722 -414.79851)
		(end 77.457808 -414.374838)
		(width 0.14224)
		(layer "In15.Cu")
		(net "P5E_CPU1_P0_RX_BUF_DP<9>")
	)
	(segment
		(start 58.157618 -395.153388)
		(end 58.157618 -393.138406)
		(width 0.14224)
		(layer "In15.Cu")
		(net "P5E_CPU1_P0_RX_BUF_DP<9>")
	)
	(segment
		(start 74.477118 -405.360378)
		(end 74.404474 -405.184864)
		(width 0.14224)
		(layer "In15.Cu")
		(net "P5E_CPU1_P0_RX_BUF_DP<9>")
	)
	(segment
		(start 58.955178 -396.884652)
		(end 58.653172 -396.582646)
		(width 0.14224)
		(layer "In15.Cu")
		(net "P5E_CPU1_P0_RX_BUF_DP<9>")
	)
	(segment
		(start 76.073254 -408.66314)
		(end 75.936094 -408.52598)
		(width 0.14224)
		(layer "In15.Cu")
		(net "P5E_CPU1_P0_RX_BUF_DP<9>")
	)
	(segment
		(start 77.650086 -438.191148)
		(end 77.499972 -438.341262)
		(width 0.14224)
		(layer "In15.Cu")
		(net "P5E_CPU1_P0_RX_BUF_DP<9>")
	)
	(segment
		(start 58.294778 -395.290548)
		(end 58.157618 -395.153388)
		(width 0.14224)
		(layer "In15.Cu")
		(net "P5E_CPU1_P0_RX_BUF_DP<9>")
	)
	(segment
		(start 77.108558 -438.341262)
		(end 76.97597 -438.208674)
		(width 0.14224)
		(layer "In15.Cu")
		(net "P5E_CPU1_P0_RX_BUF_DP<9>")
	)
	(segment
		(start 76.97597 -418.854128)
		(end 77.11313 -418.716968)
		(width 0.14224)
		(layer "In15.Cu")
		(net "P5E_CPU1_P0_RX_BUF_DP<9>")
	)
	(segment
		(start 76.016612 -410.7688)
		(end 75.936094 -410.57449)
		(width 0.14224)
		(layer "In15.Cu")
		(net "P5E_CPU1_P0_RX_BUF_DP<9>")
	)
	(segment
		(start 77.499972 -438.341262)
		(end 77.108558 -438.341262)
		(width 0.14224)
		(layer "In15.Cu")
		(net "P5E_CPU1_P0_RX_BUF_DP<9>")
	)
	(segment
		(start 60.507372 -398.630902)
		(end 59.752738 -397.876268)
		(width 0.14224)
		(layer "In15.Cu")
		(net "P5E_CPU1_P0_RX_BUF_DP<9>")
	)
	(segment
		(start 77.467714 -413.187134)
		(end 77.467714 -411.947106)
		(width 0.14224)
		(layer "In15.Cu")
		(net "P5E_CPU1_P0_RX_BUF_DP<9>")
	)
	(segment
		(start 77.239622 -416.119056)
		(end 77.292708 -415.695384)
		(width 0.14224)
		(layer "In15.Cu")
		(net "P5E_CPU1_P0_RX_BUF_DP<9>")
	)
	(segment
		(start 77.292708 -415.695384)
		(end 77.173582 -415.542222)
		(width 0.14224)
		(layer "In15.Cu")
		(net "P5E_CPU1_P0_RX_BUF_DP<9>")
	)
	(segment
		(start 75.245722 -405.574754)
		(end 74.733404 -405.574754)
		(width 0.14224)
		(layer "In15.Cu")
		(net "P5E_CPU1_P0_RX_BUF_DP<9>")
	)
	(segment
		(start 58.489596 -393.011406)
		(end 58.616596 -393.138406)
		(width 0.14224)
		(layer "In15.Cu")
		(net "P5E_CPU1_P0_RX_BUF_DP<9>")
	)
	(segment
		(start 77.022706 -416.748214)
		(end 77.08646 -416.238182)
		(width 0.14224)
		(layer "In15.Cu")
		(net "P5E_CPU1_P0_RX_BUF_DP<9>")
	)
	(segment
		(start 75.936094 -409.22702)
		(end 76.073254 -409.08986)
		(width 0.14224)
		(layer "In15.Cu")
		(net "P5E_CPU1_P0_RX_BUF_DP<9>")
	)
	(segment
		(start 77.11313 -418.716968)
		(end 77.11313 -418.290248)
		(width 0.14224)
		(layer "In15.Cu")
		(net "P5E_CPU1_P0_RX_BUF_DP<9>")
	)
	(segment
		(start 58.955178 -397.078708)
		(end 58.955178 -396.884652)
		(width 0.14224)
		(layer "In15.Cu")
		(net "P5E_CPU1_P0_RX_BUF_DP<9>")
	)
	(segment
		(start 75.730608 -405.92883)
		(end 75.469242 -405.667464)
		(width 0.14224)
		(layer "In15.Cu")
		(net "P5E_CPU1_P0_RX_BUF_DP<9>")
	)
	(segment
		(start 58.294778 -395.717268)
		(end 58.294778 -395.290548)
		(width 0.14224)
		(layer "In15.Cu")
		(net "P5E_CPU1_P0_RX_BUF_DP<9>")
	)
	(segment
		(start 75.469242 -405.667464)
		(end 75.245722 -405.574754)
		(width 0.14224)
		(layer "In15.Cu")
		(net "P5E_CPU1_P0_RX_BUF_DP<9>")
	)
	(segment
		(start 74.733404 -405.574754)
		(end 74.661776 -405.545036)
		(width 0.14224)
		(layer "In15.Cu")
		(net "P5E_CPU1_P0_RX_BUF_DP<9>")
	)
	(segment
		(start 77.11313 -418.290248)
		(end 76.97597 -418.153088)
		(width 0.14224)
		(layer "In15.Cu")
		(net "P5E_CPU1_P0_RX_BUF_DP<9>")
	)
	(segment
		(start 58.653172 -396.582646)
		(end 58.459116 -396.582646)
		(width 0.14224)
		(layer "In15.Cu")
		(net "P5E_CPU1_P0_RX_BUF_DP<9>")
	)
	(segment
		(start 77.338682 -414.221676)
		(end 77.467714 -413.187134)
		(width 0.14224)
		(layer "In15.Cu")
		(net "P5E_CPU1_P0_RX_BUF_DP<9>")
	)
	(segment
		(start 73.582022 -402.806154)
		(end 61.212222 -399.053304)
		(width 0.14224)
		(layer "In15.Cu")
		(net "P5E_CPU1_P0_RX_BUF_DP<9>")
	)
	(segment
		(start 59.450732 -397.380206)
		(end 59.256676 -397.380206)
		(width 0.14224)
		(layer "In15.Cu")
		(net "P5E_CPU1_P0_RX_BUF_DP<9>")
	)
	(segment
		(start 58.157618 -395.854428)
		(end 58.294778 -395.717268)
		(width 0.14224)
		(layer "In15.Cu")
		(net "P5E_CPU1_P0_RX_BUF_DP<9>")
	)
	(segment
		(start 77.467714 -411.947106)
		(end 77.354684 -411.674564)
		(width 0.14224)
		(layer "In15.Cu")
		(net "P5E_CPU1_P0_RX_BUF_DP<9>")
	)
	(segment
		(start 58.284618 -393.011406)
		(end 58.489596 -393.011406)
		(width 0.14224)
		(layer "In15.Cu")
		(net "P5E_CPU1_P0_RX_BUF_DP<9>")
	)
	(segment
		(start 77.14234 -411.35681)
		(end 76.234036 -410.980636)
		(width 0.14224)
		(layer "In15.Cu")
		(net "P5E_CPU1_P0_RX_BUF_DP<9>")
	)
	(segment
		(start 75.936094 -408.09926)
		(end 76.073254 -407.9621)
		(width 0.14224)
		(layer "In15.Cu")
		(net "P5E_CPU1_P0_RX_BUF_DP<9>")
	)
	(segment
		(start 76.217526 -410.969714)
		(end 76.016612 -410.7688)
		(width 0.14224)
		(layer "In15.Cu")
		(net "P5E_CPU1_P0_RX_BUF_DP<9>")
	)
	(segment
		(start 58.157618 -396.228316)
		(end 58.157618 -395.854428)
		(width 0.14224)
		(layer "In15.Cu")
		(net "P5E_CPU1_P0_RX_BUF_DP<9>")
	)
	(segment
		(start 74.661776 -405.545036)
		(end 74.477118 -405.360378)
		(width 0.14224)
		(layer "In15.Cu")
		(net "P5E_CPU1_P0_RX_BUF_DP<9>")
	)
	(segment
		(start 76.073254 -407.53538)
		(end 75.936094 -407.39822)
		(width 0.14224)
		(layer "In15.Cu")
		(net "P5E_CPU1_P0_RX_BUF_DP<9>")
	)
	(segment
		(start 74.404474 -403.436582)
		(end 74.136758 -403.036024)
		(width 0.14224)
		(layer "In15.Cu")
		(net "P5E_CPU1_P0_RX_BUF_DP<9>")
	)
	(segment
		(start 77.457808 -414.374838)
		(end 77.338682 -414.221676)
		(width 0.14224)
		(layer "In15.Cu")
		(net "P5E_CPU1_P0_RX_BUF_DP<9>")
	)
	(segment
		(start 74.404474 -405.184864)
		(end 74.404474 -403.436582)
		(width 0.14224)
		(layer "In15.Cu")
		(net "P5E_CPU1_P0_RX_BUF_DP<9>")
	)
	(segment
		(start 76.97597 -418.153088)
		(end 76.97597 -417.726368)
		(width 0.14224)
		(layer "In15.Cu")
		(net "P5E_CPU1_P0_RX_BUF_DP<9>")
	)
	(segment
		(start 76.234036 -410.980636)
		(end 76.217526 -410.969714)
		(width 0.14224)
		(layer "In15.Cu")
		(net "P5E_CPU1_P0_RX_BUF_DP<9>")
	)
	(segment
		(start 59.752738 -397.682212)
		(end 59.450732 -397.380206)
		(width 0.14224)
		(layer "In15.Cu")
		(net "P5E_CPU1_P0_RX_BUF_DP<9>")
	)
	(segment
		(start 75.936094 -407.39822)
		(end 75.936094 -406.424892)
		(width 0.14224)
		(layer "In15.Cu")
		(net "P5E_CPU1_P0_RX_BUF_DP<9>")
	)
	(segment
		(start 77.650086 -437.889904)
		(end 77.650086 -438.191148)
		(width 0.14224)
		(layer "In15.Cu")
		(net "P5E_CPU1_P0_RX_BUF_DP<9>")
	)
	(segment
		(start 59.256676 -397.380206)
		(end 58.955178 -397.078708)
		(width 0.14224)
		(layer "In15.Cu")
		(net "P5E_CPU1_P0_RX_BUF_DP<9>")
	)
	(segment
		(start 77.173582 -415.542222)
		(end 77.25156 -414.917636)
		(width 0.14224)
		(layer "In15.Cu")
		(net "P5E_CPU1_P0_RX_BUF_DP<9>")
	)
	(segment
		(start 76.073254 -409.08986)
		(end 76.073254 -408.66314)
		(width 0.14224)
		(layer "In15.Cu")
		(net "P5E_CPU1_P0_RX_BUF_DP<9>")
	)
	(segment
		(start 58.459116 -396.582646)
		(end 58.194956 -396.318486)
		(width 0.14224)
		(layer "In15.Cu")
		(net "P5E_CPU1_P0_RX_BUF_DP<9>")
	)
	(segment
		(start 77.08646 -416.238182)
		(end 77.239622 -416.119056)
		(width 0.14224)
		(layer "In15.Cu")
		(net "P5E_CPU1_P0_RX_BUF_DP<9>")
	)
	(segment
		(start 77.354684 -411.674564)
		(end 77.14234 -411.35681)
		(width 0.14224)
		(layer "In15.Cu")
		(net "P5E_CPU1_P0_RX_BUF_DP<9>")
	)
	(segment
		(start 76.97597 -438.208674)
		(end 76.97597 -418.854128)
		(width 0.14224)
		(layer "In15.Cu")
		(net "P5E_CPU1_P0_RX_BUF_DP<9>")
	)
	(segment
		(start 75.936094 -408.52598)
		(end 75.936094 -408.09926)
		(width 0.14224)
		(layer "In15.Cu")
		(net "P5E_CPU1_P0_RX_BUF_DP<9>")
	)
	(segment
		(start 59.752738 -397.876268)
		(end 59.752738 -397.682212)
		(width 0.14224)
		(layer "In15.Cu")
		(net "P5E_CPU1_P0_RX_BUF_DP<9>")
	)
	(segment
		(start 58.616596 -393.138406)
		(end 58.616596 -393.292838)
		(width 0.14224)
		(layer "In15.Cu")
		(net "P5E_CPU1_P0_RX_BUF_DP<9>")
	)
	(segment
		(start 75.936094 -410.57449)
		(end 75.936094 -409.22702)
		(width 0.14224)
		(layer "In15.Cu")
		(net "P5E_CPU1_P0_RX_BUF_DP<9>")
	)
	(segment
		(start 76.073254 -407.9621)
		(end 76.073254 -407.53538)
		(width 0.14224)
		(layer "In15.Cu")
		(net "P5E_CPU1_P0_RX_BUF_DP<9>")
	)
	(segment
		(start 74.136758 -403.036024)
		(end 73.582022 -402.806154)
		(width 0.14224)
		(layer "In15.Cu")
		(net "P5E_CPU1_P0_RX_BUF_DP<9>")
	)
	(segment
		(start 76.97597 -417.726368)
		(end 77.022706 -416.748214)
		(width 0.14224)
		(layer "In15.Cu")
		(net "P5E_CPU1_P0_RX_BUF_DP<9>")
	)
	(segment
		(start 58.157618 -393.138406)
		(end 58.284618 -393.011406)
		(width 0.14224)
		(layer "In15.Cu")
		(net "P5E_CPU1_P0_RX_BUF_DP<9>")
	)
	(segment
		(start 77.25156 -414.917636)
		(end 77.404722 -414.79851)
		(width 0.14224)
		(layer "In15.Cu")
		(net "P5E_CPU1_P0_RX_BUF_DP<9>")
	)
	(segment
		(start 75.936094 -406.424892)
		(end 75.730608 -405.92883)
		(width 0.14224)
		(layer "In15.Cu")
		(net "P5E_CPU1_P0_RX_BUF_DP<9>")
	)
	(arc
		(start 58.194956 -396.318486)
		(mid 58.167313 -396.277116)
		(end 58.157618 -396.228316)
		(width 0.14224)
		(layer "In15.Cu")
		(net "P5E_CPU1_P0_RX_BUF_DP<9>")
	)
	(arc
		(start 61.212222 -399.053304)
		(mid 60.833742 -398.885578)
		(end 60.507372 -398.630902)
		(width 0.14224)
		(layer "In15.Cu")
		(net "P5E_CPU1_P0_RX_BUF_DP<9>")
	)
	(segment
		(start 56.713882 -392.723878)
		(end 56.96712 -392.977116)
		(width 0.1016)
		(layer "F.Cu")
		(net "P5E_CPU1_P0_RX_BUF_DP<8>")
	)
	(segment
		(start 56.717946 -391.281158)
		(end 56.802528 -391.36574)
		(width 0.1016)
		(layer "F.Cu")
		(net "P5E_CPU1_P0_RX_BUF_DP<8>")
	)
	(segment
		(start 56.96712 -392.977116)
		(end 57.277762 -392.977116)
		(width 0.1016)
		(layer "F.Cu")
		(net "P5E_CPU1_P0_RX_BUF_DP<8>")
	)
	(segment
		(start 57.4167 -393.116054)
		(end 57.4167 -393.292838)
		(width 0.1016)
		(layer "F.Cu")
		(net "P5E_CPU1_P0_RX_BUF_DP<8>")
	)
	(segment
		(start 56.802528 -391.36574)
		(end 56.802528 -391.488676)
		(width 0.1016)
		(layer "F.Cu")
		(net "P5E_CPU1_P0_RX_BUF_DP<8>")
	)
	(segment
		(start 56.802528 -391.488676)
		(end 56.713882 -391.577322)
		(width 0.1016)
		(layer "F.Cu")
		(net "P5E_CPU1_P0_RX_BUF_DP<8>")
	)
	(segment
		(start 56.713882 -391.577322)
		(end 56.713882 -392.723878)
		(width 0.1016)
		(layer "F.Cu")
		(net "P5E_CPU1_P0_RX_BUF_DP<8>")
	)
	(segment
		(start 57.277762 -392.977116)
		(end 57.4167 -393.116054)
		(width 0.1016)
		(layer "F.Cu")
		(net "P5E_CPU1_P0_RX_BUF_DP<8>")
	)
	(segment
		(start 73.091548 -410.92755)
		(end 72.96785 -410.803852)
		(width 0.14224)
		(layer "In15.Cu")
		(net "P5E_CPU1_P0_RX_BUF_DP<8>")
	)
	(segment
		(start 73.010014 -408.336496)
		(end 73.010014 -407.909776)
		(width 0.14224)
		(layer "In15.Cu")
		(net "P5E_CPU1_P0_RX_BUF_DP<8>")
	)
	(segment
		(start 72.872854 -407.772616)
		(end 72.872854 -406.424892)
		(width 0.14224)
		(layer "In15.Cu")
		(net "P5E_CPU1_P0_RX_BUF_DP<8>")
	)
	(segment
		(start 57.097168 -392.989562)
		(end 57.277254 -392.989562)
		(width 0.14224)
		(layer "In15.Cu")
		(net "P5E_CPU1_P0_RX_BUF_DP<8>")
	)
	(segment
		(start 72.354694 -405.646128)
		(end 72.182482 -405.574754)
		(width 0.14224)
		(layer "In15.Cu")
		(net "P5E_CPU1_P0_RX_BUF_DP<8>")
	)
	(segment
		(start 59.048396 -398.623282)
		(end 58.854594 -398.623282)
		(width 0.14224)
		(layer "In15.Cu")
		(net "P5E_CPU1_P0_RX_BUF_DP<8>")
	)
	(segment
		(start 74.69124 -415.96564)
		(end 74.69124 -415.53892)
		(width 0.14224)
		(layer "In15.Cu")
		(net "P5E_CPU1_P0_RX_BUF_DP<8>")
	)
	(segment
		(start 70.938136 -402.995638)
		(end 59.970416 -399.668238)
		(width 0.14224)
		(layer "In15.Cu")
		(net "P5E_CPU1_P0_RX_BUF_DP<8>")
	)
	(segment
		(start 59.350402 -398.925288)
		(end 59.048396 -398.623282)
		(width 0.14224)
		(layer "In15.Cu")
		(net "P5E_CPU1_P0_RX_BUF_DP<8>")
	)
	(segment
		(start 56.957722 -395.598904)
		(end 56.957722 -395.172184)
		(width 0.14224)
		(layer "In15.Cu")
		(net "P5E_CPU1_P0_RX_BUF_DP<8>")
	)
	(segment
		(start 71.413878 -405.360378)
		(end 71.341234 -405.184864)
		(width 0.14224)
		(layer "In15.Cu")
		(net "P5E_CPU1_P0_RX_BUF_DP<8>")
	)
	(segment
		(start 72.872854 -409.601416)
		(end 73.010014 -409.464256)
		(width 0.14224)
		(layer "In15.Cu")
		(net "P5E_CPU1_P0_RX_BUF_DP<8>")
	)
	(segment
		(start 58.552842 -398.127728)
		(end 58.250836 -397.825722)
		(width 0.14224)
		(layer "In15.Cu")
		(net "P5E_CPU1_P0_RX_BUF_DP<8>")
	)
	(segment
		(start 74.404474 -411.947614)
		(end 74.258678 -411.595316)
		(width 0.14224)
		(layer "In15.Cu")
		(net "P5E_CPU1_P0_RX_BUF_DP<8>")
	)
	(segment
		(start 75.099672 -437.3372)
		(end 74.55408 -436.791608)
		(width 0.14224)
		(layer "In15.Cu")
		(net "P5E_CPU1_P0_RX_BUF_DP<8>")
	)
	(segment
		(start 71.341234 -403.39899)
		(end 70.938136 -402.995638)
		(width 0.14224)
		(layer "In15.Cu")
		(net "P5E_CPU1_P0_RX_BUF_DP<8>")
	)
	(segment
		(start 59.793886 -399.562574)
		(end 59.350402 -399.11909)
		(width 0.14224)
		(layer "In15.Cu")
		(net "P5E_CPU1_P0_RX_BUF_DP<8>")
	)
	(segment
		(start 74.258678 -411.595316)
		(end 73.978262 -411.3149)
		(width 0.14224)
		(layer "In15.Cu")
		(net "P5E_CPU1_P0_RX_BUF_DP<8>")
	)
	(segment
		(start 59.350402 -399.11909)
		(end 59.350402 -398.925288)
		(width 0.14224)
		(layer "In15.Cu")
		(net "P5E_CPU1_P0_RX_BUF_DP<8>")
	)
	(segment
		(start 56.957722 -394.471144)
		(end 56.957722 -393.129008)
		(width 0.14224)
		(layer "In15.Cu")
		(net "P5E_CPU1_P0_RX_BUF_DP<8>")
	)
	(segment
		(start 74.69124 -415.53892)
		(end 74.55408 -415.40176)
		(width 0.14224)
		(layer "In15.Cu")
		(net "P5E_CPU1_P0_RX_BUF_DP<8>")
	)
	(segment
		(start 74.55408 -416.52952)
		(end 74.55408 -416.1028)
		(width 0.14224)
		(layer "In15.Cu")
		(net "P5E_CPU1_P0_RX_BUF_DP<8>")
	)
	(segment
		(start 74.69124 -417.0934)
		(end 74.69124 -416.66668)
		(width 0.14224)
		(layer "In15.Cu")
		(net "P5E_CPU1_P0_RX_BUF_DP<8>")
	)
	(segment
		(start 72.872854 -406.424892)
		(end 72.68845 -405.979884)
		(width 0.14224)
		(layer "In15.Cu")
		(net "P5E_CPU1_P0_RX_BUF_DP<8>")
	)
	(segment
		(start 71.670164 -405.574754)
		(end 71.598536 -405.545036)
		(width 0.14224)
		(layer "In15.Cu")
		(net "P5E_CPU1_P0_RX_BUF_DP<8>")
	)
	(segment
		(start 56.957722 -396.299944)
		(end 57.094882 -396.162784)
		(width 0.14224)
		(layer "In15.Cu")
		(net "P5E_CPU1_P0_RX_BUF_DP<8>")
	)
	(segment
		(start 72.96785 -410.803852)
		(end 72.872854 -410.574744)
		(width 0.14224)
		(layer "In15.Cu")
		(net "P5E_CPU1_P0_RX_BUF_DP<8>")
	)
	(segment
		(start 57.094882 -394.608304)
		(end 56.957722 -394.471144)
		(width 0.14224)
		(layer "In15.Cu")
		(net "P5E_CPU1_P0_RX_BUF_DP<8>")
	)
	(segment
		(start 73.010014 -407.909776)
		(end 72.872854 -407.772616)
		(width 0.14224)
		(layer "In15.Cu")
		(net "P5E_CPU1_P0_RX_BUF_DP<8>")
	)
	(segment
		(start 58.057034 -397.825722)
		(end 57.755282 -397.524224)
		(width 0.14224)
		(layer "In15.Cu")
		(net "P5E_CPU1_P0_RX_BUF_DP<8>")
	)
	(segment
		(start 71.341234 -405.184864)
		(end 71.341234 -403.39899)
		(width 0.14224)
		(layer "In15.Cu")
		(net "P5E_CPU1_P0_RX_BUF_DP<8>")
	)
	(segment
		(start 71.598536 -405.545036)
		(end 71.413878 -405.360378)
		(width 0.14224)
		(layer "In15.Cu")
		(net "P5E_CPU1_P0_RX_BUF_DP<8>")
	)
	(segment
		(start 58.854594 -398.623282)
		(end 58.552842 -398.321784)
		(width 0.14224)
		(layer "In15.Cu")
		(net "P5E_CPU1_P0_RX_BUF_DP<8>")
	)
	(segment
		(start 57.453276 -397.028162)
		(end 57.25922 -397.028162)
		(width 0.14224)
		(layer "In15.Cu")
		(net "P5E_CPU1_P0_RX_BUF_DP<8>")
	)
	(segment
		(start 57.4167 -393.129008)
		(end 57.4167 -393.292838)
		(width 0.14224)
		(layer "In15.Cu")
		(net "P5E_CPU1_P0_RX_BUF_DP<8>")
	)
	(segment
		(start 73.978262 -411.3149)
		(end 73.170542 -410.980382)
		(width 0.14224)
		(layer "In15.Cu")
		(net "P5E_CPU1_P0_RX_BUF_DP<8>")
	)
	(segment
		(start 73.010014 -409.464256)
		(end 73.010014 -409.037536)
		(width 0.14224)
		(layer "In15.Cu")
		(net "P5E_CPU1_P0_RX_BUF_DP<8>")
	)
	(segment
		(start 74.55408 -417.23056)
		(end 74.69124 -417.0934)
		(width 0.14224)
		(layer "In15.Cu")
		(net "P5E_CPU1_P0_RX_BUF_DP<8>")
	)
	(segment
		(start 74.55408 -436.791608)
		(end 74.55408 -417.23056)
		(width 0.14224)
		(layer "In15.Cu")
		(net "P5E_CPU1_P0_RX_BUF_DP<8>")
	)
	(segment
		(start 74.55408 -414.750758)
		(end 74.404474 -413.23133)
		(width 0.14224)
		(layer "In15.Cu")
		(net "P5E_CPU1_P0_RX_BUF_DP<8>")
	)
	(segment
		(start 72.872854 -408.473656)
		(end 73.010014 -408.336496)
		(width 0.14224)
		(layer "In15.Cu")
		(net "P5E_CPU1_P0_RX_BUF_DP<8>")
	)
	(segment
		(start 56.957722 -396.673832)
		(end 56.957722 -396.299944)
		(width 0.14224)
		(layer "In15.Cu")
		(net "P5E_CPU1_P0_RX_BUF_DP<8>")
	)
	(segment
		(start 57.094882 -395.736064)
		(end 56.957722 -395.598904)
		(width 0.14224)
		(layer "In15.Cu")
		(net "P5E_CPU1_P0_RX_BUF_DP<8>")
	)
	(segment
		(start 72.872854 -410.574744)
		(end 72.872854 -409.601416)
		(width 0.14224)
		(layer "In15.Cu")
		(net "P5E_CPU1_P0_RX_BUF_DP<8>")
	)
	(segment
		(start 57.094882 -395.035024)
		(end 57.094882 -394.608304)
		(width 0.14224)
		(layer "In15.Cu")
		(net "P5E_CPU1_P0_RX_BUF_DP<8>")
	)
	(segment
		(start 57.25922 -397.028162)
		(end 56.99506 -396.764002)
		(width 0.14224)
		(layer "In15.Cu")
		(net "P5E_CPU1_P0_RX_BUF_DP<8>")
	)
	(segment
		(start 58.552842 -398.321784)
		(end 58.552842 -398.127728)
		(width 0.14224)
		(layer "In15.Cu")
		(net "P5E_CPU1_P0_RX_BUF_DP<8>")
	)
	(segment
		(start 57.755282 -397.330168)
		(end 57.453276 -397.028162)
		(width 0.14224)
		(layer "In15.Cu")
		(net "P5E_CPU1_P0_RX_BUF_DP<8>")
	)
	(segment
		(start 74.55408 -415.40176)
		(end 74.55408 -414.750758)
		(width 0.14224)
		(layer "In15.Cu")
		(net "P5E_CPU1_P0_RX_BUF_DP<8>")
	)
	(segment
		(start 74.404474 -413.23133)
		(end 74.404474 -411.947614)
		(width 0.14224)
		(layer "In15.Cu")
		(net "P5E_CPU1_P0_RX_BUF_DP<8>")
	)
	(segment
		(start 74.55408 -416.1028)
		(end 74.69124 -415.96564)
		(width 0.14224)
		(layer "In15.Cu")
		(net "P5E_CPU1_P0_RX_BUF_DP<8>")
	)
	(segment
		(start 75.50404 -437.3372)
		(end 75.099672 -437.3372)
		(width 0.14224)
		(layer "In15.Cu")
		(net "P5E_CPU1_P0_RX_BUF_DP<8>")
	)
	(segment
		(start 57.277254 -392.989562)
		(end 57.4167 -393.129008)
		(width 0.14224)
		(layer "In15.Cu")
		(net "P5E_CPU1_P0_RX_BUF_DP<8>")
	)
	(segment
		(start 57.094882 -396.162784)
		(end 57.094882 -395.736064)
		(width 0.14224)
		(layer "In15.Cu")
		(net "P5E_CPU1_P0_RX_BUF_DP<8>")
	)
	(segment
		(start 58.250836 -397.825722)
		(end 58.057034 -397.825722)
		(width 0.14224)
		(layer "In15.Cu")
		(net "P5E_CPU1_P0_RX_BUF_DP<8>")
	)
	(segment
		(start 73.010014 -409.037536)
		(end 72.872854 -408.900376)
		(width 0.14224)
		(layer "In15.Cu")
		(net "P5E_CPU1_P0_RX_BUF_DP<8>")
	)
	(segment
		(start 59.970416 -399.668238)
		(end 59.793886 -399.562574)
		(width 0.14224)
		(layer "In15.Cu")
		(net "P5E_CPU1_P0_RX_BUF_DP<8>")
	)
	(segment
		(start 72.872854 -408.900376)
		(end 72.872854 -408.473656)
		(width 0.14224)
		(layer "In15.Cu")
		(net "P5E_CPU1_P0_RX_BUF_DP<8>")
	)
	(segment
		(start 72.182482 -405.574754)
		(end 71.670164 -405.574754)
		(width 0.14224)
		(layer "In15.Cu")
		(net "P5E_CPU1_P0_RX_BUF_DP<8>")
	)
	(segment
		(start 75.65009 -437.19115)
		(end 75.50404 -437.3372)
		(width 0.14224)
		(layer "In15.Cu")
		(net "P5E_CPU1_P0_RX_BUF_DP<8>")
	)
	(segment
		(start 74.69124 -416.66668)
		(end 74.55408 -416.52952)
		(width 0.14224)
		(layer "In15.Cu")
		(net "P5E_CPU1_P0_RX_BUF_DP<8>")
	)
	(segment
		(start 75.65009 -436.889906)
		(end 75.65009 -437.19115)
		(width 0.14224)
		(layer "In15.Cu")
		(net "P5E_CPU1_P0_RX_BUF_DP<8>")
	)
	(segment
		(start 73.170542 -410.980382)
		(end 73.091548 -410.92755)
		(width 0.14224)
		(layer "In15.Cu")
		(net "P5E_CPU1_P0_RX_BUF_DP<8>")
	)
	(segment
		(start 57.755282 -397.524224)
		(end 57.755282 -397.330168)
		(width 0.14224)
		(layer "In15.Cu")
		(net "P5E_CPU1_P0_RX_BUF_DP<8>")
	)
	(segment
		(start 56.957722 -393.129008)
		(end 57.097168 -392.989562)
		(width 0.14224)
		(layer "In15.Cu")
		(net "P5E_CPU1_P0_RX_BUF_DP<8>")
	)
	(segment
		(start 72.68845 -405.979884)
		(end 72.354694 -405.646128)
		(width 0.14224)
		(layer "In15.Cu")
		(net "P5E_CPU1_P0_RX_BUF_DP<8>")
	)
	(segment
		(start 56.957722 -395.172184)
		(end 57.094882 -395.035024)
		(width 0.14224)
		(layer "In15.Cu")
		(net "P5E_CPU1_P0_RX_BUF_DP<8>")
	)
	(arc
		(start 56.99506 -396.764002)
		(mid 56.967417 -396.722632)
		(end 56.957722 -396.673832)
		(width 0.14224)
		(layer "In15.Cu")
		(net "P5E_CPU1_P0_RX_BUF_DP<8>")
	)
	(segment
		(start 55.602632 -391.488676)
		(end 55.513986 -391.577322)
		(width 0.1016)
		(layer "F.Cu")
		(net "P5E_CPU1_P0_RX_BUF_DP<7>")
	)
	(segment
		(start 55.602632 -391.36574)
		(end 55.602632 -391.488676)
		(width 0.1016)
		(layer "F.Cu")
		(net "P5E_CPU1_P0_RX_BUF_DP<7>")
	)
	(segment
		(start 56.21655 -393.1158)
		(end 56.21655 -393.292838)
		(width 0.1016)
		(layer "F.Cu")
		(net "P5E_CPU1_P0_RX_BUF_DP<7>")
	)
	(segment
		(start 55.51805 -391.281158)
		(end 55.602632 -391.36574)
		(width 0.1016)
		(layer "F.Cu")
		(net "P5E_CPU1_P0_RX_BUF_DP<7>")
	)
	(segment
		(start 55.513986 -391.577322)
		(end 55.513986 -392.723878)
		(width 0.1016)
		(layer "F.Cu")
		(net "P5E_CPU1_P0_RX_BUF_DP<7>")
	)
	(segment
		(start 55.767224 -392.977116)
		(end 56.077866 -392.977116)
		(width 0.1016)
		(layer "F.Cu")
		(net "P5E_CPU1_P0_RX_BUF_DP<7>")
	)
	(segment
		(start 55.513986 -392.723878)
		(end 55.767224 -392.977116)
		(width 0.1016)
		(layer "F.Cu")
		(net "P5E_CPU1_P0_RX_BUF_DP<7>")
	)
	(segment
		(start 56.077866 -392.977116)
		(end 56.21655 -393.1158)
		(width 0.1016)
		(layer "F.Cu")
		(net "P5E_CPU1_P0_RX_BUF_DP<7>")
	)
	(segment
		(start 64.18199 -401.929092)
		(end 62.407292 -401.390866)
		(width 0.14224)
		(layer "In15.Cu")
		(net "P5E_CPU1_P0_RX_BUF_DP<7>")
	)
	(segment
		(start 70.107302 -410.980382)
		(end 70.028308 -410.92755)
		(width 0.14224)
		(layer "In15.Cu")
		(net "P5E_CPU1_P0_RX_BUF_DP<7>")
	)
	(segment
		(start 68.038726 -403.228302)
		(end 67.507612 -403.008338)
		(width 0.14224)
		(layer "In15.Cu")
		(net "P5E_CPU1_P0_RX_BUF_DP<7>")
	)
	(segment
		(start 64.182244 -401.9296)
		(end 64.18199 -401.929092)
		(width 0.14224)
		(layer "In15.Cu")
		(net "P5E_CPU1_P0_RX_BUF_DP<7>")
	)
	(segment
		(start 72.649842 -437.889904)
		(end 72.649842 -438.191148)
		(width 0.14224)
		(layer "In15.Cu")
		(net "P5E_CPU1_P0_RX_BUF_DP<7>")
	)
	(segment
		(start 70.980808 -411.342078)
		(end 70.107302 -410.980382)
		(width 0.14224)
		(layer "In15.Cu")
		(net "P5E_CPU1_P0_RX_BUF_DP<7>")
	)
	(segment
		(start 55.757572 -397.03375)
		(end 55.757572 -396.279624)
		(width 0.14224)
		(layer "In15.Cu")
		(net "P5E_CPU1_P0_RX_BUF_DP<7>")
	)
	(segment
		(start 69.946774 -407.785062)
		(end 69.809614 -407.647902)
		(width 0.14224)
		(layer "In15.Cu")
		(net "P5E_CPU1_P0_RX_BUF_DP<7>")
	)
	(segment
		(start 55.757572 -396.279624)
		(end 55.894732 -396.142464)
		(width 0.14224)
		(layer "In15.Cu")
		(net "P5E_CPU1_P0_RX_BUF_DP<7>")
	)
	(segment
		(start 57.352692 -398.487646)
		(end 57.050686 -398.18564)
		(width 0.14224)
		(layer "In15.Cu")
		(net "P5E_CPU1_P0_RX_BUF_DP<7>")
	)
	(segment
		(start 71.705978 -416.08629)
		(end 71.458582 -414.417256)
		(width 0.14224)
		(layer "In15.Cu")
		(net "P5E_CPU1_P0_RX_BUF_DP<7>")
	)
	(segment
		(start 66.03492 -402.502624)
		(end 65.85585 -402.577046)
		(width 0.14224)
		(layer "In15.Cu")
		(net "P5E_CPU1_P0_RX_BUF_DP<7>")
	)
	(segment
		(start 55.757572 -393.129008)
		(end 55.897018 -392.989562)
		(width 0.14224)
		(layer "In15.Cu")
		(net "P5E_CPU1_P0_RX_BUF_DP<7>")
	)
	(segment
		(start 56.21655 -393.129008)
		(end 56.21655 -393.292838)
		(width 0.14224)
		(layer "In15.Cu")
		(net "P5E_CPU1_P0_RX_BUF_DP<7>")
	)
	(segment
		(start 71.924672 -416.624008)
		(end 71.862188 -416.201606)
		(width 0.14224)
		(layer "In15.Cu")
		(net "P5E_CPU1_P0_RX_BUF_DP<7>")
	)
	(segment
		(start 68.277994 -405.143462)
		(end 68.277994 -403.585934)
		(width 0.14224)
		(layer "In15.Cu")
		(net "P5E_CPU1_P0_RX_BUF_DP<7>")
	)
	(segment
		(start 55.897018 -392.989562)
		(end 56.077104 -392.989562)
		(width 0.14224)
		(layer "In15.Cu")
		(net "P5E_CPU1_P0_RX_BUF_DP<7>")
	)
	(segment
		(start 56.253126 -397.38808)
		(end 56.05907 -397.38808)
		(width 0.14224)
		(layer "In15.Cu")
		(net "P5E_CPU1_P0_RX_BUF_DP<7>")
	)
	(segment
		(start 56.856884 -398.18564)
		(end 56.555132 -397.884142)
		(width 0.14224)
		(layer "In15.Cu")
		(net "P5E_CPU1_P0_RX_BUF_DP<7>")
	)
	(segment
		(start 68.277994 -403.585934)
		(end 68.038726 -403.228302)
		(width 0.14224)
		(layer "In15.Cu")
		(net "P5E_CPU1_P0_RX_BUF_DP<7>")
	)
	(segment
		(start 69.809614 -408.775662)
		(end 69.809614 -408.348942)
		(width 0.14224)
		(layer "In15.Cu")
		(net "P5E_CPU1_P0_RX_BUF_DP<7>")
	)
	(segment
		(start 56.077104 -392.989562)
		(end 56.21655 -393.129008)
		(width 0.14224)
		(layer "In15.Cu")
		(net "P5E_CPU1_P0_RX_BUF_DP<7>")
	)
	(segment
		(start 57.352692 -398.681702)
		(end 57.352692 -398.487646)
		(width 0.14224)
		(layer "In15.Cu")
		(net "P5E_CPU1_P0_RX_BUF_DP<7>")
	)
	(segment
		(start 72.113394 -438.337452)
		(end 71.981568 -438.205626)
		(width 0.14224)
		(layer "In15.Cu")
		(net "P5E_CPU1_P0_RX_BUF_DP<7>")
	)
	(segment
		(start 69.291454 -405.646128)
		(end 69.119242 -405.574754)
		(width 0.14224)
		(layer "In15.Cu")
		(net "P5E_CPU1_P0_RX_BUF_DP<7>")
	)
	(segment
		(start 66.429636 -402.665946)
		(end 66.03492 -402.502624)
		(width 0.14224)
		(layer "In15.Cu")
		(net "P5E_CPU1_P0_RX_BUF_DP<7>")
	)
	(segment
		(start 56.555132 -397.884142)
		(end 56.555132 -397.690086)
		(width 0.14224)
		(layer "In15.Cu")
		(net "P5E_CPU1_P0_RX_BUF_DP<7>")
	)
	(segment
		(start 71.341234 -411.947614)
		(end 71.168006 -411.529276)
		(width 0.14224)
		(layer "In15.Cu")
		(net "P5E_CPU1_P0_RX_BUF_DP<7>")
	)
	(segment
		(start 55.757572 -394.450824)
		(end 55.757572 -393.129008)
		(width 0.14224)
		(layer "In15.Cu")
		(net "P5E_CPU1_P0_RX_BUF_DP<7>")
	)
	(segment
		(start 64.590422 -402.053298)
		(end 64.182244 -401.9296)
		(width 0.14224)
		(layer "In15.Cu")
		(net "P5E_CPU1_P0_RX_BUF_DP<7>")
	)
	(segment
		(start 69.946774 -408.912822)
		(end 69.809614 -408.775662)
		(width 0.14224)
		(layer "In15.Cu")
		(net "P5E_CPU1_P0_RX_BUF_DP<7>")
	)
	(segment
		(start 66.898012 -403.008338)
		(end 66.503804 -402.84527)
		(width 0.14224)
		(layer "In15.Cu")
		(net "P5E_CPU1_P0_RX_BUF_DP<7>")
	)
	(segment
		(start 69.809614 -407.647902)
		(end 69.809614 -406.424892)
		(width 0.14224)
		(layer "In15.Cu")
		(net "P5E_CPU1_P0_RX_BUF_DP<7>")
	)
	(segment
		(start 71.981568 -417.942014)
		(end 71.809356 -416.779964)
		(width 0.14224)
		(layer "In15.Cu")
		(net "P5E_CPU1_P0_RX_BUF_DP<7>")
	)
	(segment
		(start 71.341234 -413.225488)
		(end 71.341234 -411.947614)
		(width 0.14224)
		(layer "In15.Cu")
		(net "P5E_CPU1_P0_RX_BUF_DP<7>")
	)
	(segment
		(start 65.85585 -402.577046)
		(end 64.590422 -402.053298)
		(width 0.14224)
		(layer "In15.Cu")
		(net "P5E_CPU1_P0_RX_BUF_DP<7>")
	)
	(segment
		(start 57.654444 -398.9832)
		(end 57.352692 -398.681702)
		(width 0.14224)
		(layer "In15.Cu")
		(net "P5E_CPU1_P0_RX_BUF_DP<7>")
	)
	(segment
		(start 56.05907 -397.38808)
		(end 55.79491 -397.12392)
		(width 0.14224)
		(layer "In15.Cu")
		(net "P5E_CPU1_P0_RX_BUF_DP<7>")
	)
	(segment
		(start 62.407038 -401.390104)
		(end 59.307984 -400.450558)
		(width 0.14224)
		(layer "In15.Cu")
		(net "P5E_CPU1_P0_RX_BUF_DP<7>")
	)
	(segment
		(start 69.809614 -410.574744)
		(end 69.809614 -409.476702)
		(width 0.14224)
		(layer "In15.Cu")
		(net "P5E_CPU1_P0_RX_BUF_DP<7>")
	)
	(segment
		(start 55.757572 -395.151864)
		(end 55.894732 -395.014704)
		(width 0.14224)
		(layer "In15.Cu")
		(net "P5E_CPU1_P0_RX_BUF_DP<7>")
	)
	(segment
		(start 69.809614 -409.476702)
		(end 69.946774 -409.339542)
		(width 0.14224)
		(layer "In15.Cu")
		(net "P5E_CPU1_P0_RX_BUF_DP<7>")
	)
	(segment
		(start 58.150252 -399.285206)
		(end 57.848246 -398.9832)
		(width 0.14224)
		(layer "In15.Cu")
		(net "P5E_CPU1_P0_RX_BUF_DP<7>")
	)
	(segment
		(start 58.84291 -400.17192)
		(end 58.150252 -399.479262)
		(width 0.14224)
		(layer "In15.Cu")
		(net "P5E_CPU1_P0_RX_BUF_DP<7>")
	)
	(segment
		(start 71.981568 -438.205626)
		(end 71.981568 -417.942014)
		(width 0.14224)
		(layer "In15.Cu")
		(net "P5E_CPU1_P0_RX_BUF_DP<7>")
	)
	(segment
		(start 71.862188 -416.201606)
		(end 71.705978 -416.08629)
		(width 0.14224)
		(layer "In15.Cu")
		(net "P5E_CPU1_P0_RX_BUF_DP<7>")
	)
	(segment
		(start 66.503804 -402.84527)
		(end 66.429636 -402.665946)
		(width 0.14224)
		(layer "In15.Cu")
		(net "P5E_CPU1_P0_RX_BUF_DP<7>")
	)
	(segment
		(start 58.150252 -399.479262)
		(end 58.150252 -399.285206)
		(width 0.14224)
		(layer "In15.Cu")
		(net "P5E_CPU1_P0_RX_BUF_DP<7>")
	)
	(segment
		(start 69.90461 -410.803852)
		(end 69.809614 -410.574744)
		(width 0.14224)
		(layer "In15.Cu")
		(net "P5E_CPU1_P0_RX_BUF_DP<7>")
	)
	(segment
		(start 69.809614 -406.424892)
		(end 69.62521 -405.979884)
		(width 0.14224)
		(layer "In15.Cu")
		(net "P5E_CPU1_P0_RX_BUF_DP<7>")
	)
	(segment
		(start 70.028308 -410.92755)
		(end 69.90461 -410.803852)
		(width 0.14224)
		(layer "In15.Cu")
		(net "P5E_CPU1_P0_RX_BUF_DP<7>")
	)
	(segment
		(start 67.507612 -403.008338)
		(end 66.898012 -403.008338)
		(width 0.14224)
		(layer "In15.Cu")
		(net "P5E_CPU1_P0_RX_BUF_DP<7>")
	)
	(segment
		(start 69.62521 -405.979884)
		(end 69.291454 -405.646128)
		(width 0.14224)
		(layer "In15.Cu")
		(net "P5E_CPU1_P0_RX_BUF_DP<7>")
	)
	(segment
		(start 69.946774 -409.339542)
		(end 69.946774 -408.912822)
		(width 0.14224)
		(layer "In15.Cu")
		(net "P5E_CPU1_P0_RX_BUF_DP<7>")
	)
	(segment
		(start 62.407292 -401.390866)
		(end 62.407038 -401.390104)
		(width 0.14224)
		(layer "In15.Cu")
		(net "P5E_CPU1_P0_RX_BUF_DP<7>")
	)
	(segment
		(start 55.894732 -395.014704)
		(end 55.894732 -394.587984)
		(width 0.14224)
		(layer "In15.Cu")
		(net "P5E_CPU1_P0_RX_BUF_DP<7>")
	)
	(segment
		(start 57.848246 -398.9832)
		(end 57.654444 -398.9832)
		(width 0.14224)
		(layer "In15.Cu")
		(net "P5E_CPU1_P0_RX_BUF_DP<7>")
	)
	(segment
		(start 55.894732 -394.587984)
		(end 55.757572 -394.450824)
		(width 0.14224)
		(layer "In15.Cu")
		(net "P5E_CPU1_P0_RX_BUF_DP<7>")
	)
	(segment
		(start 55.894732 -395.715744)
		(end 55.757572 -395.578584)
		(width 0.14224)
		(layer "In15.Cu")
		(net "P5E_CPU1_P0_RX_BUF_DP<7>")
	)
	(segment
		(start 71.809356 -416.779964)
		(end 71.924672 -416.624008)
		(width 0.14224)
		(layer "In15.Cu")
		(net "P5E_CPU1_P0_RX_BUF_DP<7>")
	)
	(segment
		(start 57.050686 -398.18564)
		(end 56.856884 -398.18564)
		(width 0.14224)
		(layer "In15.Cu")
		(net "P5E_CPU1_P0_RX_BUF_DP<7>")
	)
	(segment
		(start 69.946774 -408.211782)
		(end 69.946774 -407.785062)
		(width 0.14224)
		(layer "In15.Cu")
		(net "P5E_CPU1_P0_RX_BUF_DP<7>")
	)
	(segment
		(start 71.168006 -411.529276)
		(end 70.980808 -411.342078)
		(width 0.14224)
		(layer "In15.Cu")
		(net "P5E_CPU1_P0_RX_BUF_DP<7>")
	)
	(segment
		(start 72.503538 -438.337452)
		(end 72.113394 -438.337452)
		(width 0.14224)
		(layer "In15.Cu")
		(net "P5E_CPU1_P0_RX_BUF_DP<7>")
	)
	(segment
		(start 55.757572 -395.578584)
		(end 55.757572 -395.151864)
		(width 0.14224)
		(layer "In15.Cu")
		(net "P5E_CPU1_P0_RX_BUF_DP<7>")
	)
	(segment
		(start 56.555132 -397.690086)
		(end 56.253126 -397.38808)
		(width 0.14224)
		(layer "In15.Cu")
		(net "P5E_CPU1_P0_RX_BUF_DP<7>")
	)
	(segment
		(start 55.894732 -396.142464)
		(end 55.894732 -395.715744)
		(width 0.14224)
		(layer "In15.Cu")
		(net "P5E_CPU1_P0_RX_BUF_DP<7>")
	)
	(segment
		(start 72.649842 -438.191148)
		(end 72.503538 -438.337452)
		(width 0.14224)
		(layer "In15.Cu")
		(net "P5E_CPU1_P0_RX_BUF_DP<7>")
	)
	(segment
		(start 71.458582 -414.417256)
		(end 71.341234 -413.225488)
		(width 0.14224)
		(layer "In15.Cu")
		(net "P5E_CPU1_P0_RX_BUF_DP<7>")
	)
	(segment
		(start 69.809614 -408.348942)
		(end 69.946774 -408.211782)
		(width 0.14224)
		(layer "In15.Cu")
		(net "P5E_CPU1_P0_RX_BUF_DP<7>")
	)
	(segment
		(start 69.119242 -405.574754)
		(end 68.709286 -405.574754)
		(width 0.14224)
		(layer "In15.Cu")
		(net "P5E_CPU1_P0_RX_BUF_DP<7>")
	)
	(arc
		(start 68.709286 -405.574754)
		(mid 68.404317 -405.448431)
		(end 68.277994 -405.143462)
		(width 0.14224)
		(layer "In15.Cu")
		(net "P5E_CPU1_P0_RX_BUF_DP<7>")
	)
	(arc
		(start 55.79491 -397.12392)
		(mid 55.767267 -397.08255)
		(end 55.757572 -397.03375)
		(width 0.14224)
		(layer "In15.Cu")
		(net "P5E_CPU1_P0_RX_BUF_DP<7>")
	)
	(arc
		(start 59.307984 -400.450558)
		(mid 59.058264 -400.339917)
		(end 58.84291 -400.17192)
		(width 0.14224)
		(layer "In15.Cu")
		(net "P5E_CPU1_P0_RX_BUF_DP<7>")
	)
	(segment
		(start 55.016654 -393.116054)
		(end 55.016654 -393.292838)
		(width 0.1016)
		(layer "F.Cu")
		(net "P5E_CPU1_P0_RX_BUF_DP<6>")
	)
	(segment
		(start 54.575964 -392.977116)
		(end 54.877716 -392.977116)
		(width 0.1016)
		(layer "F.Cu")
		(net "P5E_CPU1_P0_RX_BUF_DP<6>")
	)
	(segment
		(start 54.402482 -391.36574)
		(end 54.402482 -391.488676)
		(width 0.1016)
		(layer "F.Cu")
		(net "P5E_CPU1_P0_RX_BUF_DP<6>")
	)
	(segment
		(start 54.402482 -391.488676)
		(end 54.322726 -391.568432)
		(width 0.1016)
		(layer "F.Cu")
		(net "P5E_CPU1_P0_RX_BUF_DP<6>")
	)
	(segment
		(start 54.322726 -392.723878)
		(end 54.575964 -392.977116)
		(width 0.1016)
		(layer "F.Cu")
		(net "P5E_CPU1_P0_RX_BUF_DP<6>")
	)
	(segment
		(start 54.877716 -392.977116)
		(end 55.016654 -393.116054)
		(width 0.1016)
		(layer "F.Cu")
		(net "P5E_CPU1_P0_RX_BUF_DP<6>")
	)
	(segment
		(start 54.322726 -391.568432)
		(end 54.322726 -392.723878)
		(width 0.1016)
		(layer "F.Cu")
		(net "P5E_CPU1_P0_RX_BUF_DP<6>")
	)
	(segment
		(start 54.3179 -391.281158)
		(end 54.402482 -391.36574)
		(width 0.1016)
		(layer "F.Cu")
		(net "P5E_CPU1_P0_RX_BUF_DP<6>")
	)
	(segment
		(start 57.52592 -400.252438)
		(end 57.331864 -400.252438)
		(width 0.14224)
		(layer "In15.Cu")
		(net "P5E_CPU1_P0_RX_BUF_DP<6>")
	)
	(segment
		(start 65.005966 -403.405086)
		(end 64.452754 -403.01545)
		(width 0.14224)
		(layer "In15.Cu")
		(net "P5E_CPU1_P0_RX_BUF_DP<6>")
	)
	(segment
		(start 58.12282 -401.043394)
		(end 57.827926 -400.7485)
		(width 0.14224)
		(layer "In15.Cu")
		(net "P5E_CPU1_P0_RX_BUF_DP<6>")
	)
	(segment
		(start 56.950356 -399.676874)
		(end 56.64835 -399.374868)
		(width 0.14224)
		(layer "In15.Cu")
		(net "P5E_CPU1_P0_RX_BUF_DP<6>")
	)
	(segment
		(start 66.883534 -409.23464)
		(end 66.883534 -408.80792)
		(width 0.14224)
		(layer "In15.Cu")
		(net "P5E_CPU1_P0_RX_BUF_DP<6>")
	)
	(segment
		(start 70.110604 -437.341264)
		(end 69.983604 -437.214264)
		(width 0.14224)
		(layer "In15.Cu")
		(net "P5E_CPU1_P0_RX_BUF_DP<6>")
	)
	(segment
		(start 66.883534 -407.68016)
		(end 66.746374 -407.543)
		(width 0.14224)
		(layer "In15.Cu")
		(net "P5E_CPU1_P0_RX_BUF_DP<6>")
	)
	(segment
		(start 68.277994 -411.947868)
		(end 68.14185 -411.619192)
		(width 0.14224)
		(layer "In15.Cu")
		(net "P5E_CPU1_P0_RX_BUF_DP<6>")
	)
	(segment
		(start 54.557676 -395.712442)
		(end 54.694836 -395.575282)
		(width 0.14224)
		(layer "In15.Cu")
		(net "P5E_CPU1_P0_RX_BUF_DP<6>")
	)
	(segment
		(start 57.331864 -400.252438)
		(end 56.950356 -399.87093)
		(width 0.14224)
		(layer "In15.Cu")
		(net "P5E_CPU1_P0_RX_BUF_DP<6>")
	)
	(segment
		(start 70.649846 -436.889906)
		(end 70.649846 -437.19115)
		(width 0.14224)
		(layer "In15.Cu")
		(net "P5E_CPU1_P0_RX_BUF_DP<6>")
	)
	(segment
		(start 55.016654 -393.129008)
		(end 55.016654 -393.292838)
		(width 0.14224)
		(layer "In15.Cu")
		(net "P5E_CPU1_P0_RX_BUF_DP<6>")
	)
	(segment
		(start 54.557676 -397.266922)
		(end 54.557676 -396.840202)
		(width 0.14224)
		(layer "In15.Cu")
		(net "P5E_CPU1_P0_RX_BUF_DP<6>")
	)
	(segment
		(start 54.557676 -393.129008)
		(end 54.697122 -392.989562)
		(width 0.14224)
		(layer "In15.Cu")
		(net "P5E_CPU1_P0_RX_BUF_DP<6>")
	)
	(segment
		(start 66.883534 -408.80792)
		(end 66.746374 -408.67076)
		(width 0.14224)
		(layer "In15.Cu")
		(net "P5E_CPU1_P0_RX_BUF_DP<6>")
	)
	(segment
		(start 65.27673 -405.33447)
		(end 65.214754 -405.184864)
		(width 0.14224)
		(layer "In15.Cu")
		(net "P5E_CPU1_P0_RX_BUF_DP<6>")
	)
	(segment
		(start 70.649846 -437.19115)
		(end 70.499732 -437.341264)
		(width 0.14224)
		(layer "In15.Cu")
		(net "P5E_CPU1_P0_RX_BUF_DP<6>")
	)
	(segment
		(start 54.877208 -392.989562)
		(end 55.016654 -393.129008)
		(width 0.14224)
		(layer "In15.Cu")
		(net "P5E_CPU1_P0_RX_BUF_DP<6>")
	)
	(segment
		(start 66.746374 -407.543)
		(end 66.746374 -406.424892)
		(width 0.14224)
		(layer "In15.Cu")
		(net "P5E_CPU1_P0_RX_BUF_DP<6>")
	)
	(segment
		(start 66.965068 -410.92755)
		(end 66.84137 -410.803852)
		(width 0.14224)
		(layer "In15.Cu")
		(net "P5E_CPU1_P0_RX_BUF_DP<6>")
	)
	(segment
		(start 64.452754 -403.01545)
		(end 58.297318 -401.148042)
		(width 0.14224)
		(layer "In15.Cu")
		(net "P5E_CPU1_P0_RX_BUF_DP<6>")
	)
	(segment
		(start 66.883534 -408.10688)
		(end 66.883534 -407.68016)
		(width 0.14224)
		(layer "In15.Cu")
		(net "P5E_CPU1_P0_RX_BUF_DP<6>")
	)
	(segment
		(start 55.355236 -398.081754)
		(end 55.05323 -397.779748)
		(width 0.14224)
		(layer "In15.Cu")
		(net "P5E_CPU1_P0_RX_BUF_DP<6>")
	)
	(segment
		(start 66.746374 -408.24404)
		(end 66.883534 -408.10688)
		(width 0.14224)
		(layer "In15.Cu")
		(net "P5E_CPU1_P0_RX_BUF_DP<6>")
	)
	(segment
		(start 66.84137 -410.803852)
		(end 66.746374 -410.574744)
		(width 0.14224)
		(layer "In15.Cu")
		(net "P5E_CPU1_P0_RX_BUF_DP<6>")
	)
	(segment
		(start 54.859174 -397.779748)
		(end 54.707282 -397.627856)
		(width 0.14224)
		(layer "In15.Cu")
		(net "P5E_CPU1_P0_RX_BUF_DP<6>")
	)
	(segment
		(start 65.214754 -403.807676)
		(end 65.005966 -403.405086)
		(width 0.14224)
		(layer "In15.Cu")
		(net "P5E_CPU1_P0_RX_BUF_DP<6>")
	)
	(segment
		(start 56.950356 -399.87093)
		(end 56.950356 -399.676874)
		(width 0.14224)
		(layer "In15.Cu")
		(net "P5E_CPU1_P0_RX_BUF_DP<6>")
	)
	(segment
		(start 66.056002 -405.574754)
		(end 65.543684 -405.574754)
		(width 0.14224)
		(layer "In15.Cu")
		(net "P5E_CPU1_P0_RX_BUF_DP<6>")
	)
	(segment
		(start 66.56197 -405.979884)
		(end 66.228214 -405.646128)
		(width 0.14224)
		(layer "In15.Cu")
		(net "P5E_CPU1_P0_RX_BUF_DP<6>")
	)
	(segment
		(start 57.827926 -400.7485)
		(end 57.827926 -400.554444)
		(width 0.14224)
		(layer "In15.Cu")
		(net "P5E_CPU1_P0_RX_BUF_DP<6>")
	)
	(segment
		(start 54.697122 -392.989562)
		(end 54.877208 -392.989562)
		(width 0.14224)
		(layer "In15.Cu")
		(net "P5E_CPU1_P0_RX_BUF_DP<6>")
	)
	(segment
		(start 69.983604 -437.214264)
		(end 69.983604 -417.53409)
		(width 0.14224)
		(layer "In15.Cu")
		(net "P5E_CPU1_P0_RX_BUF_DP<6>")
	)
	(segment
		(start 54.557676 -396.840202)
		(end 54.694836 -396.703042)
		(width 0.14224)
		(layer "In15.Cu")
		(net "P5E_CPU1_P0_RX_BUF_DP<6>")
	)
	(segment
		(start 68.277994 -413.41548)
		(end 68.277994 -411.947868)
		(width 0.14224)
		(layer "In15.Cu")
		(net "P5E_CPU1_P0_RX_BUF_DP<6>")
	)
	(segment
		(start 67.044062 -410.980382)
		(end 66.965068 -410.92755)
		(width 0.14224)
		(layer "In15.Cu")
		(net "P5E_CPU1_P0_RX_BUF_DP<6>")
	)
	(segment
		(start 54.694836 -395.575282)
		(end 54.694836 -395.148562)
		(width 0.14224)
		(layer "In15.Cu")
		(net "P5E_CPU1_P0_RX_BUF_DP<6>")
	)
	(segment
		(start 54.557676 -396.139162)
		(end 54.557676 -395.712442)
		(width 0.14224)
		(layer "In15.Cu")
		(net "P5E_CPU1_P0_RX_BUF_DP<6>")
	)
	(segment
		(start 54.694836 -396.703042)
		(end 54.694836 -396.276322)
		(width 0.14224)
		(layer "In15.Cu")
		(net "P5E_CPU1_P0_RX_BUF_DP<6>")
	)
	(segment
		(start 70.499732 -437.341264)
		(end 70.110604 -437.341264)
		(width 0.14224)
		(layer "In15.Cu")
		(net "P5E_CPU1_P0_RX_BUF_DP<6>")
	)
	(segment
		(start 65.498218 -405.555958)
		(end 65.27673 -405.33447)
		(width 0.14224)
		(layer "In15.Cu")
		(net "P5E_CPU1_P0_RX_BUF_DP<6>")
	)
	(segment
		(start 55.85079 -398.577308)
		(end 55.656734 -398.577308)
		(width 0.14224)
		(layer "In15.Cu")
		(net "P5E_CPU1_P0_RX_BUF_DP<6>")
	)
	(segment
		(start 57.827926 -400.554444)
		(end 57.52592 -400.252438)
		(width 0.14224)
		(layer "In15.Cu")
		(net "P5E_CPU1_P0_RX_BUF_DP<6>")
	)
	(segment
		(start 66.228214 -405.646128)
		(end 66.056002 -405.574754)
		(width 0.14224)
		(layer "In15.Cu")
		(net "P5E_CPU1_P0_RX_BUF_DP<6>")
	)
	(segment
		(start 68.14185 -411.619192)
		(end 67.827398 -411.30474)
		(width 0.14224)
		(layer "In15.Cu")
		(net "P5E_CPU1_P0_RX_BUF_DP<6>")
	)
	(segment
		(start 69.983604 -417.53409)
		(end 68.277994 -413.41548)
		(width 0.14224)
		(layer "In15.Cu")
		(net "P5E_CPU1_P0_RX_BUF_DP<6>")
	)
	(segment
		(start 56.152796 -399.07337)
		(end 56.152796 -398.879314)
		(width 0.14224)
		(layer "In15.Cu")
		(net "P5E_CPU1_P0_RX_BUF_DP<6>")
	)
	(segment
		(start 56.152796 -398.879314)
		(end 55.85079 -398.577308)
		(width 0.14224)
		(layer "In15.Cu")
		(net "P5E_CPU1_P0_RX_BUF_DP<6>")
	)
	(segment
		(start 66.746374 -408.67076)
		(end 66.746374 -408.24404)
		(width 0.14224)
		(layer "In15.Cu")
		(net "P5E_CPU1_P0_RX_BUF_DP<6>")
	)
	(segment
		(start 55.355236 -398.27581)
		(end 55.355236 -398.081754)
		(width 0.14224)
		(layer "In15.Cu")
		(net "P5E_CPU1_P0_RX_BUF_DP<6>")
	)
	(segment
		(start 55.05323 -397.779748)
		(end 54.859174 -397.779748)
		(width 0.14224)
		(layer "In15.Cu")
		(net "P5E_CPU1_P0_RX_BUF_DP<6>")
	)
	(segment
		(start 65.214754 -405.184864)
		(end 65.214754 -403.807676)
		(width 0.14224)
		(layer "In15.Cu")
		(net "P5E_CPU1_P0_RX_BUF_DP<6>")
	)
	(segment
		(start 66.746374 -410.574744)
		(end 66.746374 -409.3718)
		(width 0.14224)
		(layer "In15.Cu")
		(net "P5E_CPU1_P0_RX_BUF_DP<6>")
	)
	(segment
		(start 54.694836 -395.148562)
		(end 54.557676 -395.011402)
		(width 0.14224)
		(layer "In15.Cu")
		(net "P5E_CPU1_P0_RX_BUF_DP<6>")
	)
	(segment
		(start 56.454294 -399.374868)
		(end 56.152796 -399.07337)
		(width 0.14224)
		(layer "In15.Cu")
		(net "P5E_CPU1_P0_RX_BUF_DP<6>")
	)
	(segment
		(start 66.746374 -409.3718)
		(end 66.883534 -409.23464)
		(width 0.14224)
		(layer "In15.Cu")
		(net "P5E_CPU1_P0_RX_BUF_DP<6>")
	)
	(segment
		(start 54.557676 -395.011402)
		(end 54.557676 -393.129008)
		(width 0.14224)
		(layer "In15.Cu")
		(net "P5E_CPU1_P0_RX_BUF_DP<6>")
	)
	(segment
		(start 55.656734 -398.577308)
		(end 55.355236 -398.27581)
		(width 0.14224)
		(layer "In15.Cu")
		(net "P5E_CPU1_P0_RX_BUF_DP<6>")
	)
	(segment
		(start 67.827398 -411.30474)
		(end 67.044062 -410.980382)
		(width 0.14224)
		(layer "In15.Cu")
		(net "P5E_CPU1_P0_RX_BUF_DP<6>")
	)
	(segment
		(start 56.64835 -399.374868)
		(end 56.454294 -399.374868)
		(width 0.14224)
		(layer "In15.Cu")
		(net "P5E_CPU1_P0_RX_BUF_DP<6>")
	)
	(segment
		(start 54.694836 -396.276322)
		(end 54.557676 -396.139162)
		(width 0.14224)
		(layer "In15.Cu")
		(net "P5E_CPU1_P0_RX_BUF_DP<6>")
	)
	(segment
		(start 66.746374 -406.424892)
		(end 66.56197 -405.979884)
		(width 0.14224)
		(layer "In15.Cu")
		(net "P5E_CPU1_P0_RX_BUF_DP<6>")
	)
	(segment
		(start 65.543684 -405.574754)
		(end 65.498218 -405.555958)
		(width 0.14224)
		(layer "In15.Cu")
		(net "P5E_CPU1_P0_RX_BUF_DP<6>")
	)
	(arc
		(start 54.707282 -397.627856)
		(mid 54.596579 -397.462272)
		(end 54.557676 -397.266922)
		(width 0.14224)
		(layer "In15.Cu")
		(net "P5E_CPU1_P0_RX_BUF_DP<6>")
	)
	(arc
		(start 58.297318 -401.148042)
		(mid 58.203624 -401.106468)
		(end 58.12282 -401.043394)
		(width 0.14224)
		(layer "In15.Cu")
		(net "P5E_CPU1_P0_RX_BUF_DP<6>")
	)
	(segment
		(start 53.67782 -392.977116)
		(end 53.816504 -393.1158)
		(width 0.1016)
		(layer "F.Cu")
		(net "P5E_CPU1_P0_RX_BUF_DP<5>")
	)
	(segment
		(start 53.816504 -393.1158)
		(end 53.816504 -393.292838)
		(width 0.1016)
		(layer "F.Cu")
		(net "P5E_CPU1_P0_RX_BUF_DP<5>")
	)
	(segment
		(start 53.118004 -391.281158)
		(end 53.202586 -391.36574)
		(width 0.1016)
		(layer "F.Cu")
		(net "P5E_CPU1_P0_RX_BUF_DP<5>")
	)
	(segment
		(start 53.202586 -391.36574)
		(end 53.202586 -391.488676)
		(width 0.1016)
		(layer "F.Cu")
		(net "P5E_CPU1_P0_RX_BUF_DP<5>")
	)
	(segment
		(start 53.11394 -392.723878)
		(end 53.367178 -392.977116)
		(width 0.1016)
		(layer "F.Cu")
		(net "P5E_CPU1_P0_RX_BUF_DP<5>")
	)
	(segment
		(start 53.11394 -391.577322)
		(end 53.11394 -392.723878)
		(width 0.1016)
		(layer "F.Cu")
		(net "P5E_CPU1_P0_RX_BUF_DP<5>")
	)
	(segment
		(start 53.202586 -391.488676)
		(end 53.11394 -391.577322)
		(width 0.1016)
		(layer "F.Cu")
		(net "P5E_CPU1_P0_RX_BUF_DP<5>")
	)
	(segment
		(start 53.367178 -392.977116)
		(end 53.67782 -392.977116)
		(width 0.1016)
		(layer "F.Cu")
		(net "P5E_CPU1_P0_RX_BUF_DP<5>")
	)
	(segment
		(start 63.901828 -410.92755)
		(end 63.77813 -410.803852)
		(width 0.14224)
		(layer "In15.Cu")
		(net "P5E_CPU1_P0_RX_BUF_DP<5>")
	)
	(segment
		(start 53.659024 -398.273778)
		(end 53.394864 -398.009618)
		(width 0.14224)
		(layer "In15.Cu")
		(net "P5E_CPU1_P0_RX_BUF_DP<5>")
	)
	(segment
		(start 56.051704 -400.666458)
		(end 55.750206 -400.36496)
		(width 0.14224)
		(layer "In15.Cu")
		(net "P5E_CPU1_P0_RX_BUF_DP<5>")
	)
	(segment
		(start 62.151514 -405.266906)
		(end 62.151514 -403.668738)
		(width 0.14224)
		(layer "In15.Cu")
		(net "P5E_CPU1_P0_RX_BUF_DP<5>")
	)
	(segment
		(start 63.820294 -409.656026)
		(end 63.820294 -409.229306)
		(width 0.14224)
		(layer "In15.Cu")
		(net "P5E_CPU1_P0_RX_BUF_DP<5>")
	)
	(segment
		(start 66.533776 -414.96615)
		(end 65.592706 -413.81934)
		(width 0.14224)
		(layer "In15.Cu")
		(net "P5E_CPU1_P0_RX_BUF_DP<5>")
	)
	(segment
		(start 54.155086 -398.575784)
		(end 53.85308 -398.273778)
		(width 0.14224)
		(layer "In15.Cu")
		(net "P5E_CPU1_P0_RX_BUF_DP<5>")
	)
	(segment
		(start 53.357526 -397.919448)
		(end 53.357526 -396.689072)
		(width 0.14224)
		(layer "In15.Cu")
		(net "P5E_CPU1_P0_RX_BUF_DP<5>")
	)
	(segment
		(start 61.46292 -403.106636)
		(end 57.557162 -401.922742)
		(width 0.14224)
		(layer "In15.Cu")
		(net "P5E_CPU1_P0_RX_BUF_DP<5>")
	)
	(segment
		(start 53.494686 -396.125192)
		(end 53.357526 -395.988032)
		(width 0.14224)
		(layer "In15.Cu")
		(net "P5E_CPU1_P0_RX_BUF_DP<5>")
	)
	(segment
		(start 54.456584 -399.071338)
		(end 54.155086 -398.76984)
		(width 0.14224)
		(layer "In15.Cu")
		(net "P5E_CPU1_P0_RX_BUF_DP<5>")
	)
	(segment
		(start 67.982846 -438.148984)
		(end 67.982846 -417.524184)
		(width 0.14224)
		(layer "In15.Cu")
		(net "P5E_CPU1_P0_RX_BUF_DP<5>")
	)
	(segment
		(start 62.151514 -403.668738)
		(end 61.985398 -403.421342)
		(width 0.14224)
		(layer "In15.Cu")
		(net "P5E_CPU1_P0_RX_BUF_DP<5>")
	)
	(segment
		(start 65.214754 -413.253682)
		(end 65.214754 -411.947868)
		(width 0.14224)
		(layer "In15.Cu")
		(net "P5E_CPU1_P0_RX_BUF_DP<5>")
	)
	(segment
		(start 54.65064 -399.071338)
		(end 54.456584 -399.071338)
		(width 0.14224)
		(layer "In15.Cu")
		(net "P5E_CPU1_P0_RX_BUF_DP<5>")
	)
	(segment
		(start 63.683134 -408.665426)
		(end 63.820294 -408.528266)
		(width 0.14224)
		(layer "In15.Cu")
		(net "P5E_CPU1_P0_RX_BUF_DP<5>")
	)
	(segment
		(start 54.952646 -399.5674)
		(end 54.952646 -399.373344)
		(width 0.14224)
		(layer "In15.Cu")
		(net "P5E_CPU1_P0_RX_BUF_DP<5>")
	)
	(segment
		(start 68.64985 -437.889904)
		(end 68.64985 -438.191148)
		(width 0.14224)
		(layer "In15.Cu")
		(net "P5E_CPU1_P0_RX_BUF_DP<5>")
	)
	(segment
		(start 63.164974 -405.646128)
		(end 62.992762 -405.574754)
		(width 0.14224)
		(layer "In15.Cu")
		(net "P5E_CPU1_P0_RX_BUF_DP<5>")
	)
	(segment
		(start 67.982846 -417.524184)
		(end 66.533776 -414.96615)
		(width 0.14224)
		(layer "In15.Cu")
		(net "P5E_CPU1_P0_RX_BUF_DP<5>")
	)
	(segment
		(start 61.985398 -403.421342)
		(end 61.46292 -403.106636)
		(width 0.14224)
		(layer "In15.Cu")
		(net "P5E_CPU1_P0_RX_BUF_DP<5>")
	)
	(segment
		(start 63.683134 -407.964386)
		(end 63.683134 -406.424892)
		(width 0.14224)
		(layer "In15.Cu")
		(net "P5E_CPU1_P0_RX_BUF_DP<5>")
	)
	(segment
		(start 65.085722 -411.636464)
		(end 64.746886 -411.297628)
		(width 0.14224)
		(layer "In15.Cu")
		(net "P5E_CPU1_P0_RX_BUF_DP<5>")
	)
	(segment
		(start 55.750206 -400.36496)
		(end 55.750206 -400.170904)
		(width 0.14224)
		(layer "In15.Cu")
		(net "P5E_CPU1_P0_RX_BUF_DP<5>")
	)
	(segment
		(start 63.683134 -409.793186)
		(end 63.820294 -409.656026)
		(width 0.14224)
		(layer "In15.Cu")
		(net "P5E_CPU1_P0_RX_BUF_DP<5>")
	)
	(segment
		(start 53.357526 -393.129008)
		(end 53.496972 -392.989562)
		(width 0.14224)
		(layer "In15.Cu")
		(net "P5E_CPU1_P0_RX_BUF_DP<5>")
	)
	(segment
		(start 54.952646 -399.373344)
		(end 54.65064 -399.071338)
		(width 0.14224)
		(layer "In15.Cu")
		(net "P5E_CPU1_P0_RX_BUF_DP<5>")
	)
	(segment
		(start 63.77813 -410.803852)
		(end 63.683134 -410.574744)
		(width 0.14224)
		(layer "In15.Cu")
		(net "P5E_CPU1_P0_RX_BUF_DP<5>")
	)
	(segment
		(start 56.93537 -401.550124)
		(end 56.547766 -401.16252)
		(width 0.14224)
		(layer "In15.Cu")
		(net "P5E_CPU1_P0_RX_BUF_DP<5>")
	)
	(segment
		(start 63.683134 -406.424892)
		(end 63.49873 -405.979884)
		(width 0.14224)
		(layer "In15.Cu")
		(net "P5E_CPU1_P0_RX_BUF_DP<5>")
	)
	(segment
		(start 64.746886 -411.297628)
		(end 63.980822 -410.980382)
		(width 0.14224)
		(layer "In15.Cu")
		(net "P5E_CPU1_P0_RX_BUF_DP<5>")
	)
	(segment
		(start 53.677058 -392.989562)
		(end 53.816504 -393.129008)
		(width 0.14224)
		(layer "In15.Cu")
		(net "P5E_CPU1_P0_RX_BUF_DP<5>")
	)
	(segment
		(start 68.175124 -438.341262)
		(end 67.982846 -438.148984)
		(width 0.14224)
		(layer "In15.Cu")
		(net "P5E_CPU1_P0_RX_BUF_DP<5>")
	)
	(segment
		(start 62.480444 -405.574754)
		(end 62.408816 -405.545036)
		(width 0.14224)
		(layer "In15.Cu")
		(net "P5E_CPU1_P0_RX_BUF_DP<5>")
	)
	(segment
		(start 53.357526 -396.689072)
		(end 53.494686 -396.551912)
		(width 0.14224)
		(layer "In15.Cu")
		(net "P5E_CPU1_P0_RX_BUF_DP<5>")
	)
	(segment
		(start 63.683134 -410.574744)
		(end 63.683134 -409.793186)
		(width 0.14224)
		(layer "In15.Cu")
		(net "P5E_CPU1_P0_RX_BUF_DP<5>")
	)
	(segment
		(start 56.24576 -400.666458)
		(end 56.051704 -400.666458)
		(width 0.14224)
		(layer "In15.Cu")
		(net "P5E_CPU1_P0_RX_BUF_DP<5>")
	)
	(segment
		(start 55.254144 -399.868898)
		(end 54.952646 -399.5674)
		(width 0.14224)
		(layer "In15.Cu")
		(net "P5E_CPU1_P0_RX_BUF_DP<5>")
	)
	(segment
		(start 65.592706 -413.81934)
		(end 65.214754 -413.253682)
		(width 0.14224)
		(layer "In15.Cu")
		(net "P5E_CPU1_P0_RX_BUF_DP<5>")
	)
	(segment
		(start 55.750206 -400.170904)
		(end 55.4482 -399.868898)
		(width 0.14224)
		(layer "In15.Cu")
		(net "P5E_CPU1_P0_RX_BUF_DP<5>")
	)
	(segment
		(start 53.494686 -394.923518)
		(end 53.357526 -394.786358)
		(width 0.14224)
		(layer "In15.Cu")
		(net "P5E_CPU1_P0_RX_BUF_DP<5>")
	)
	(segment
		(start 53.494686 -396.551912)
		(end 53.494686 -396.125192)
		(width 0.14224)
		(layer "In15.Cu")
		(net "P5E_CPU1_P0_RX_BUF_DP<5>")
	)
	(segment
		(start 54.155086 -398.76984)
		(end 54.155086 -398.575784)
		(width 0.14224)
		(layer "In15.Cu")
		(net "P5E_CPU1_P0_RX_BUF_DP<5>")
	)
	(segment
		(start 53.494686 -395.350238)
		(end 53.494686 -394.923518)
		(width 0.14224)
		(layer "In15.Cu")
		(net "P5E_CPU1_P0_RX_BUF_DP<5>")
	)
	(segment
		(start 62.408816 -405.545036)
		(end 62.166246 -405.302466)
		(width 0.14224)
		(layer "In15.Cu")
		(net "P5E_CPU1_P0_RX_BUF_DP<5>")
	)
	(segment
		(start 63.49873 -405.979884)
		(end 63.164974 -405.646128)
		(width 0.14224)
		(layer "In15.Cu")
		(net "P5E_CPU1_P0_RX_BUF_DP<5>")
	)
	(segment
		(start 53.357526 -395.487398)
		(end 53.494686 -395.350238)
		(width 0.14224)
		(layer "In15.Cu")
		(net "P5E_CPU1_P0_RX_BUF_DP<5>")
	)
	(segment
		(start 62.992762 -405.574754)
		(end 62.480444 -405.574754)
		(width 0.14224)
		(layer "In15.Cu")
		(net "P5E_CPU1_P0_RX_BUF_DP<5>")
	)
	(segment
		(start 63.683134 -409.092146)
		(end 63.683134 -408.665426)
		(width 0.14224)
		(layer "In15.Cu")
		(net "P5E_CPU1_P0_RX_BUF_DP<5>")
	)
	(segment
		(start 68.499736 -438.341262)
		(end 68.175124 -438.341262)
		(width 0.14224)
		(layer "In15.Cu")
		(net "P5E_CPU1_P0_RX_BUF_DP<5>")
	)
	(segment
		(start 63.980822 -410.980382)
		(end 63.901828 -410.92755)
		(width 0.14224)
		(layer "In15.Cu")
		(net "P5E_CPU1_P0_RX_BUF_DP<5>")
	)
	(segment
		(start 53.85308 -398.273778)
		(end 53.659024 -398.273778)
		(width 0.14224)
		(layer "In15.Cu")
		(net "P5E_CPU1_P0_RX_BUF_DP<5>")
	)
	(segment
		(start 53.357526 -395.988032)
		(end 53.357526 -395.487398)
		(width 0.14224)
		(layer "In15.Cu")
		(net "P5E_CPU1_P0_RX_BUF_DP<5>")
	)
	(segment
		(start 68.64985 -438.191148)
		(end 68.499736 -438.341262)
		(width 0.14224)
		(layer "In15.Cu")
		(net "P5E_CPU1_P0_RX_BUF_DP<5>")
	)
	(segment
		(start 53.357526 -394.786358)
		(end 53.357526 -393.129008)
		(width 0.14224)
		(layer "In15.Cu")
		(net "P5E_CPU1_P0_RX_BUF_DP<5>")
	)
	(segment
		(start 53.816504 -393.129008)
		(end 53.816504 -393.292838)
		(width 0.14224)
		(layer "In15.Cu")
		(net "P5E_CPU1_P0_RX_BUF_DP<5>")
	)
	(segment
		(start 56.547766 -400.968464)
		(end 56.24576 -400.666458)
		(width 0.14224)
		(layer "In15.Cu")
		(net "P5E_CPU1_P0_RX_BUF_DP<5>")
	)
	(segment
		(start 63.820294 -408.528266)
		(end 63.820294 -408.101546)
		(width 0.14224)
		(layer "In15.Cu")
		(net "P5E_CPU1_P0_RX_BUF_DP<5>")
	)
	(segment
		(start 63.820294 -409.229306)
		(end 63.683134 -409.092146)
		(width 0.14224)
		(layer "In15.Cu")
		(net "P5E_CPU1_P0_RX_BUF_DP<5>")
	)
	(segment
		(start 56.547766 -401.16252)
		(end 56.547766 -400.968464)
		(width 0.14224)
		(layer "In15.Cu")
		(net "P5E_CPU1_P0_RX_BUF_DP<5>")
	)
	(segment
		(start 65.214754 -411.947868)
		(end 65.085722 -411.636464)
		(width 0.14224)
		(layer "In15.Cu")
		(net "P5E_CPU1_P0_RX_BUF_DP<5>")
	)
	(segment
		(start 53.496972 -392.989562)
		(end 53.677058 -392.989562)
		(width 0.14224)
		(layer "In15.Cu")
		(net "P5E_CPU1_P0_RX_BUF_DP<5>")
	)
	(segment
		(start 63.820294 -408.101546)
		(end 63.683134 -407.964386)
		(width 0.14224)
		(layer "In15.Cu")
		(net "P5E_CPU1_P0_RX_BUF_DP<5>")
	)
	(segment
		(start 62.166246 -405.302466)
		(end 62.151514 -405.266906)
		(width 0.14224)
		(layer "In15.Cu")
		(net "P5E_CPU1_P0_RX_BUF_DP<5>")
	)
	(segment
		(start 55.4482 -399.868898)
		(end 55.254144 -399.868898)
		(width 0.14224)
		(layer "In15.Cu")
		(net "P5E_CPU1_P0_RX_BUF_DP<5>")
	)
	(arc
		(start 57.557162 -401.922742)
		(mid 57.223274 -401.774798)
		(end 56.93537 -401.550124)
		(width 0.14224)
		(layer "In15.Cu")
		(net "P5E_CPU1_P0_RX_BUF_DP<5>")
	)
	(arc
		(start 53.394864 -398.009618)
		(mid 53.367221 -397.968248)
		(end 53.357526 -397.919448)
		(width 0.14224)
		(layer "In15.Cu")
		(net "P5E_CPU1_P0_RX_BUF_DP<5>")
	)
	(segment
		(start 52.477924 -392.977116)
		(end 52.616608 -393.1158)
		(width 0.1016)
		(layer "F.Cu")
		(net "P5E_CPU1_P0_RX_BUF_DP<4>")
	)
	(segment
		(start 51.918108 -391.281158)
		(end 52.00269 -391.36574)
		(width 0.1016)
		(layer "F.Cu")
		(net "P5E_CPU1_P0_RX_BUF_DP<4>")
	)
	(segment
		(start 52.00269 -391.488676)
		(end 51.914044 -391.577322)
		(width 0.1016)
		(layer "F.Cu")
		(net "P5E_CPU1_P0_RX_BUF_DP<4>")
	)
	(segment
		(start 52.167282 -392.977116)
		(end 52.477924 -392.977116)
		(width 0.1016)
		(layer "F.Cu")
		(net "P5E_CPU1_P0_RX_BUF_DP<4>")
	)
	(segment
		(start 51.914044 -391.577322)
		(end 51.914044 -392.723878)
		(width 0.1016)
		(layer "F.Cu")
		(net "P5E_CPU1_P0_RX_BUF_DP<4>")
	)
	(segment
		(start 52.616608 -393.1158)
		(end 52.616608 -393.292838)
		(width 0.1016)
		(layer "F.Cu")
		(net "P5E_CPU1_P0_RX_BUF_DP<4>")
	)
	(segment
		(start 51.914044 -392.723878)
		(end 52.167282 -392.977116)
		(width 0.1016)
		(layer "F.Cu")
		(net "P5E_CPU1_P0_RX_BUF_DP<4>")
	)
	(segment
		(start 52.00269 -391.36574)
		(end 52.00269 -391.488676)
		(width 0.1016)
		(layer "F.Cu")
		(net "P5E_CPU1_P0_RX_BUF_DP<4>")
	)
	(segment
		(start 60.619894 -410.574744)
		(end 60.619894 -406.424638)
		(width 0.14224)
		(layer "In15.Cu")
		(net "P5E_CPU1_P0_RX_BUF_DP<4>")
	)
	(segment
		(start 56.190896 -402.241512)
		(end 55.88889 -401.939506)
		(width 0.14224)
		(layer "In15.Cu")
		(net "P5E_CPU1_P0_RX_BUF_DP<4>")
	)
	(segment
		(start 59.417204 -405.574754)
		(end 59.345576 -405.545036)
		(width 0.14224)
		(layer "In15.Cu")
		(net "P5E_CPU1_P0_RX_BUF_DP<4>")
	)
	(segment
		(start 58.639202 -403.263862)
		(end 58.335926 -403.138132)
		(width 0.14224)
		(layer "In15.Cu")
		(net "P5E_CPU1_P0_RX_BUF_DP<4>")
	)
	(segment
		(start 61.96076 -411.552136)
		(end 61.722508 -411.313884)
		(width 0.14224)
		(layer "In15.Cu")
		(net "P5E_CPU1_P0_RX_BUF_DP<4>")
	)
	(segment
		(start 52.95519 -399.005806)
		(end 52.653184 -398.7038)
		(width 0.14224)
		(layer "In15.Cu")
		(net "P5E_CPU1_P0_RX_BUF_DP<4>")
	)
	(segment
		(start 59.160918 -405.360378)
		(end 59.088274 -405.184864)
		(width 0.14224)
		(layer "In15.Cu")
		(net "P5E_CPU1_P0_RX_BUF_DP<4>")
	)
	(segment
		(start 52.15763 -397.298164)
		(end 52.29479 -397.161004)
		(width 0.14224)
		(layer "In15.Cu")
		(net "P5E_CPU1_P0_RX_BUF_DP<4>")
	)
	(segment
		(start 62.472062 -414.124648)
		(end 62.252098 -413.904684)
		(width 0.14224)
		(layer "In15.Cu")
		(net "P5E_CPU1_P0_RX_BUF_DP<4>")
	)
	(segment
		(start 60.619894 -406.424638)
		(end 60.43549 -405.979884)
		(width 0.14224)
		(layer "In15.Cu")
		(net "P5E_CPU1_P0_RX_BUF_DP<4>")
	)
	(segment
		(start 52.95519 -399.199862)
		(end 52.95519 -399.005806)
		(width 0.14224)
		(layer "In15.Cu")
		(net "P5E_CPU1_P0_RX_BUF_DP<4>")
	)
	(segment
		(start 52.15763 -394.341604)
		(end 52.15763 -393.129008)
		(width 0.14224)
		(layer "In15.Cu")
		(net "P5E_CPU1_P0_RX_BUF_DP<4>")
	)
	(segment
		(start 62.252098 -413.904684)
		(end 62.151514 -413.661606)
		(width 0.14224)
		(layer "In15.Cu")
		(net "P5E_CPU1_P0_RX_BUF_DP<4>")
	)
	(segment
		(start 52.29479 -395.606524)
		(end 52.15763 -395.469364)
		(width 0.14224)
		(layer "In15.Cu")
		(net "P5E_CPU1_P0_RX_BUF_DP<4>")
	)
	(segment
		(start 52.15763 -395.469364)
		(end 52.15763 -395.042644)
		(width 0.14224)
		(layer "In15.Cu")
		(net "P5E_CPU1_P0_RX_BUF_DP<4>")
	)
	(segment
		(start 55.88889 -401.939506)
		(end 55.694834 -401.939506)
		(width 0.14224)
		(layer "In15.Cu")
		(net "P5E_CPU1_P0_RX_BUF_DP<4>")
	)
	(segment
		(start 54.897274 -401.141946)
		(end 54.55031 -400.794982)
		(width 0.14224)
		(layer "In15.Cu")
		(net "P5E_CPU1_P0_RX_BUF_DP<4>")
	)
	(segment
		(start 54.248304 -400.29892)
		(end 54.054248 -400.29892)
		(width 0.14224)
		(layer "In15.Cu")
		(net "P5E_CPU1_P0_RX_BUF_DP<4>")
	)
	(segment
		(start 52.15763 -396.170404)
		(end 52.29479 -396.033244)
		(width 0.14224)
		(layer "In15.Cu")
		(net "P5E_CPU1_P0_RX_BUF_DP<4>")
	)
	(segment
		(start 58.335926 -403.138132)
		(end 56.572658 -402.787104)
		(width 0.14224)
		(layer "In15.Cu")
		(net "P5E_CPU1_P0_RX_BUF_DP<4>")
	)
	(segment
		(start 55.09133 -401.141946)
		(end 54.897274 -401.141946)
		(width 0.14224)
		(layer "In15.Cu")
		(net "P5E_CPU1_P0_RX_BUF_DP<4>")
	)
	(segment
		(start 54.054248 -400.29892)
		(end 53.75275 -399.997422)
		(width 0.14224)
		(layer "In15.Cu")
		(net "P5E_CPU1_P0_RX_BUF_DP<4>")
	)
	(segment
		(start 58.888884 -403.513544)
		(end 58.639202 -403.263862)
		(width 0.14224)
		(layer "In15.Cu")
		(net "P5E_CPU1_P0_RX_BUF_DP<4>")
	)
	(segment
		(start 52.15763 -393.129008)
		(end 52.297076 -392.989562)
		(width 0.14224)
		(layer "In15.Cu")
		(net "P5E_CPU1_P0_RX_BUF_DP<4>")
	)
	(segment
		(start 56.190896 -402.435568)
		(end 56.190896 -402.241512)
		(width 0.14224)
		(layer "In15.Cu")
		(net "P5E_CPU1_P0_RX_BUF_DP<4>")
	)
	(segment
		(start 60.861702 -410.943044)
		(end 60.709556 -410.790898)
		(width 0.14224)
		(layer "In15.Cu")
		(net "P5E_CPU1_P0_RX_BUF_DP<4>")
	)
	(segment
		(start 65.37198 -416.388296)
		(end 62.472062 -414.124648)
		(width 0.14224)
		(layer "In15.Cu")
		(net "P5E_CPU1_P0_RX_BUF_DP<4>")
	)
	(segment
		(start 66.649854 -437.19115)
		(end 66.49974 -437.341264)
		(width 0.14224)
		(layer "In15.Cu")
		(net "P5E_CPU1_P0_RX_BUF_DP<4>")
	)
	(segment
		(start 60.43549 -405.979884)
		(end 60.128658 -405.673052)
		(width 0.14224)
		(layer "In15.Cu")
		(net "P5E_CPU1_P0_RX_BUF_DP<4>")
	)
	(segment
		(start 54.55031 -400.600926)
		(end 54.248304 -400.29892)
		(width 0.14224)
		(layer "In15.Cu")
		(net "P5E_CPU1_P0_RX_BUF_DP<4>")
	)
	(segment
		(start 52.15763 -396.597124)
		(end 52.15763 -396.170404)
		(width 0.14224)
		(layer "In15.Cu")
		(net "P5E_CPU1_P0_RX_BUF_DP<4>")
	)
	(segment
		(start 66.649854 -436.889906)
		(end 66.649854 -437.19115)
		(width 0.14224)
		(layer "In15.Cu")
		(net "P5E_CPU1_P0_RX_BUF_DP<4>")
	)
	(segment
		(start 52.29479 -396.734284)
		(end 52.15763 -396.597124)
		(width 0.14224)
		(layer "In15.Cu")
		(net "P5E_CPU1_P0_RX_BUF_DP<4>")
	)
	(segment
		(start 59.345576 -405.545036)
		(end 59.160918 -405.360378)
		(width 0.14224)
		(layer "In15.Cu")
		(net "P5E_CPU1_P0_RX_BUF_DP<4>")
	)
	(segment
		(start 61.722508 -411.313884)
		(end 60.917328 -410.980128)
		(width 0.14224)
		(layer "In15.Cu")
		(net "P5E_CPU1_P0_RX_BUF_DP<4>")
	)
	(segment
		(start 59.088274 -405.184864)
		(end 59.088274 -403.994874)
		(width 0.14224)
		(layer "In15.Cu")
		(net "P5E_CPU1_P0_RX_BUF_DP<4>")
	)
	(segment
		(start 54.55031 -400.794982)
		(end 54.55031 -400.600926)
		(width 0.14224)
		(layer "In15.Cu")
		(net "P5E_CPU1_P0_RX_BUF_DP<4>")
	)
	(segment
		(start 55.393336 -401.443952)
		(end 55.09133 -401.141946)
		(width 0.14224)
		(layer "In15.Cu")
		(net "P5E_CPU1_P0_RX_BUF_DP<4>")
	)
	(segment
		(start 53.256688 -399.50136)
		(end 52.95519 -399.199862)
		(width 0.14224)
		(layer "In15.Cu")
		(net "P5E_CPU1_P0_RX_BUF_DP<4>")
	)
	(segment
		(start 65.98666 -417.453064)
		(end 65.721992 -416.814762)
		(width 0.14224)
		(layer "In15.Cu")
		(net "P5E_CPU1_P0_RX_BUF_DP<4>")
	)
	(segment
		(start 60.709556 -410.790898)
		(end 60.619894 -410.574744)
		(width 0.14224)
		(layer "In15.Cu")
		(net "P5E_CPU1_P0_RX_BUF_DP<4>")
	)
	(segment
		(start 53.450744 -399.50136)
		(end 53.256688 -399.50136)
		(width 0.14224)
		(layer "In15.Cu")
		(net "P5E_CPU1_P0_RX_BUF_DP<4>")
	)
	(segment
		(start 52.653184 -398.7038)
		(end 52.459128 -398.7038)
		(width 0.14224)
		(layer "In15.Cu")
		(net "P5E_CPU1_P0_RX_BUF_DP<4>")
	)
	(segment
		(start 56.507634 -402.752306)
		(end 56.190896 -402.435568)
		(width 0.14224)
		(layer "In15.Cu")
		(net "P5E_CPU1_P0_RX_BUF_DP<4>")
	)
	(segment
		(start 65.721992 -416.814762)
		(end 65.37198 -416.388296)
		(width 0.14224)
		(layer "In15.Cu")
		(net "P5E_CPU1_P0_RX_BUF_DP<4>")
	)
	(segment
		(start 52.616608 -393.129008)
		(end 52.616608 -393.292838)
		(width 0.14224)
		(layer "In15.Cu")
		(net "P5E_CPU1_P0_RX_BUF_DP<4>")
	)
	(segment
		(start 66.11366 -437.341264)
		(end 65.98666 -437.214264)
		(width 0.14224)
		(layer "In15.Cu")
		(net "P5E_CPU1_P0_RX_BUF_DP<4>")
	)
	(segment
		(start 53.75275 -399.803366)
		(end 53.450744 -399.50136)
		(width 0.14224)
		(layer "In15.Cu")
		(net "P5E_CPU1_P0_RX_BUF_DP<4>")
	)
	(segment
		(start 65.98666 -437.214264)
		(end 65.98666 -417.453064)
		(width 0.14224)
		(layer "In15.Cu")
		(net "P5E_CPU1_P0_RX_BUF_DP<4>")
	)
	(segment
		(start 52.15763 -398.332198)
		(end 52.15763 -397.298164)
		(width 0.14224)
		(layer "In15.Cu")
		(net "P5E_CPU1_P0_RX_BUF_DP<4>")
	)
	(segment
		(start 53.75275 -399.997422)
		(end 53.75275 -399.803366)
		(width 0.14224)
		(layer "In15.Cu")
		(net "P5E_CPU1_P0_RX_BUF_DP<4>")
	)
	(segment
		(start 52.459128 -398.7038)
		(end 52.20716 -398.451832)
		(width 0.14224)
		(layer "In15.Cu")
		(net "P5E_CPU1_P0_RX_BUF_DP<4>")
	)
	(segment
		(start 60.128658 -405.673052)
		(end 59.891422 -405.574754)
		(width 0.14224)
		(layer "In15.Cu")
		(net "P5E_CPU1_P0_RX_BUF_DP<4>")
	)
	(segment
		(start 59.891422 -405.574754)
		(end 59.417204 -405.574754)
		(width 0.14224)
		(layer "In15.Cu")
		(net "P5E_CPU1_P0_RX_BUF_DP<4>")
	)
	(segment
		(start 52.29479 -397.161004)
		(end 52.29479 -396.734284)
		(width 0.14224)
		(layer "In15.Cu")
		(net "P5E_CPU1_P0_RX_BUF_DP<4>")
	)
	(segment
		(start 60.917328 -410.980128)
		(end 60.861702 -410.943044)
		(width 0.14224)
		(layer "In15.Cu")
		(net "P5E_CPU1_P0_RX_BUF_DP<4>")
	)
	(segment
		(start 52.477162 -392.989562)
		(end 52.616608 -393.129008)
		(width 0.14224)
		(layer "In15.Cu")
		(net "P5E_CPU1_P0_RX_BUF_DP<4>")
	)
	(segment
		(start 52.297076 -392.989562)
		(end 52.477162 -392.989562)
		(width 0.14224)
		(layer "In15.Cu")
		(net "P5E_CPU1_P0_RX_BUF_DP<4>")
	)
	(segment
		(start 52.29479 -394.478764)
		(end 52.15763 -394.341604)
		(width 0.14224)
		(layer "In15.Cu")
		(net "P5E_CPU1_P0_RX_BUF_DP<4>")
	)
	(segment
		(start 52.15763 -395.042644)
		(end 52.29479 -394.905484)
		(width 0.14224)
		(layer "In15.Cu")
		(net "P5E_CPU1_P0_RX_BUF_DP<4>")
	)
	(segment
		(start 52.29479 -396.033244)
		(end 52.29479 -395.606524)
		(width 0.14224)
		(layer "In15.Cu")
		(net "P5E_CPU1_P0_RX_BUF_DP<4>")
	)
	(segment
		(start 66.49974 -437.341264)
		(end 66.11366 -437.341264)
		(width 0.14224)
		(layer "In15.Cu")
		(net "P5E_CPU1_P0_RX_BUF_DP<4>")
	)
	(segment
		(start 55.393336 -401.638008)
		(end 55.393336 -401.443952)
		(width 0.14224)
		(layer "In15.Cu")
		(net "P5E_CPU1_P0_RX_BUF_DP<4>")
	)
	(segment
		(start 52.29479 -394.905484)
		(end 52.29479 -394.478764)
		(width 0.14224)
		(layer "In15.Cu")
		(net "P5E_CPU1_P0_RX_BUF_DP<4>")
	)
	(segment
		(start 55.694834 -401.939506)
		(end 55.393336 -401.638008)
		(width 0.14224)
		(layer "In15.Cu")
		(net "P5E_CPU1_P0_RX_BUF_DP<4>")
	)
	(segment
		(start 62.151514 -412.014416)
		(end 61.96076 -411.552136)
		(width 0.14224)
		(layer "In15.Cu")
		(net "P5E_CPU1_P0_RX_BUF_DP<4>")
	)
	(segment
		(start 62.151514 -413.661606)
		(end 62.151514 -412.014416)
		(width 0.14224)
		(layer "In15.Cu")
		(net "P5E_CPU1_P0_RX_BUF_DP<4>")
	)
	(arc
		(start 56.572658 -402.787104)
		(mid 56.537564 -402.774528)
		(end 56.507634 -402.752306)
		(width 0.14224)
		(layer "In15.Cu")
		(net "P5E_CPU1_P0_RX_BUF_DP<4>")
	)
	(arc
		(start 59.088274 -403.994874)
		(mid 59.036457 -403.734374)
		(end 58.888884 -403.513544)
		(width 0.14224)
		(layer "In15.Cu")
		(net "P5E_CPU1_P0_RX_BUF_DP<4>")
	)
	(arc
		(start 52.20716 -398.451832)
		(mid 52.170485 -398.396943)
		(end 52.15763 -398.332198)
		(width 0.14224)
		(layer "In15.Cu")
		(net "P5E_CPU1_P0_RX_BUF_DP<4>")
	)
	(segment
		(start 50.727102 -391.564114)
		(end 50.727102 -392.723878)
		(width 0.1016)
		(layer "F.Cu")
		(net "P5E_CPU1_P0_RX_BUF_DP<3>")
	)
	(segment
		(start 51.277774 -392.977116)
		(end 51.416458 -393.1158)
		(width 0.1016)
		(layer "F.Cu")
		(net "P5E_CPU1_P0_RX_BUF_DP<3>")
	)
	(segment
		(start 50.727102 -392.723878)
		(end 50.98034 -392.977116)
		(width 0.1016)
		(layer "F.Cu")
		(net "P5E_CPU1_P0_RX_BUF_DP<3>")
	)
	(segment
		(start 50.80254 -391.36574)
		(end 50.80254 -391.488676)
		(width 0.1016)
		(layer "F.Cu")
		(net "P5E_CPU1_P0_RX_BUF_DP<3>")
	)
	(segment
		(start 50.80254 -391.488676)
		(end 50.727102 -391.564114)
		(width 0.1016)
		(layer "F.Cu")
		(net "P5E_CPU1_P0_RX_BUF_DP<3>")
	)
	(segment
		(start 51.416458 -393.1158)
		(end 51.416458 -393.292838)
		(width 0.1016)
		(layer "F.Cu")
		(net "P5E_CPU1_P0_RX_BUF_DP<3>")
	)
	(segment
		(start 50.98034 -392.977116)
		(end 51.277774 -392.977116)
		(width 0.1016)
		(layer "F.Cu")
		(net "P5E_CPU1_P0_RX_BUF_DP<3>")
	)
	(segment
		(start 50.717958 -391.281158)
		(end 50.80254 -391.36574)
		(width 0.1016)
		(layer "F.Cu")
		(net "P5E_CPU1_P0_RX_BUF_DP<3>")
	)
	(segment
		(start 50.95748 -397.001238)
		(end 51.09464 -396.864078)
		(width 0.14224)
		(layer "In15.Cu")
		(net "P5E_CPU1_P0_RX_BUF_DP<3>")
	)
	(segment
		(start 50.95748 -393.129008)
		(end 51.096926 -392.989562)
		(width 0.14224)
		(layer "In15.Cu")
		(net "P5E_CPU1_P0_RX_BUF_DP<3>")
	)
	(segment
		(start 54.14772 -401.92198)
		(end 54.14772 -401.727924)
		(width 0.14224)
		(layer "In15.Cu")
		(net "P5E_CPU1_P0_RX_BUF_DP<3>")
	)
	(segment
		(start 56.353964 -405.574754)
		(end 56.282336 -405.545036)
		(width 0.14224)
		(layer "In15.Cu")
		(net "P5E_CPU1_P0_RX_BUF_DP<3>")
	)
	(segment
		(start 51.453034 -399.033238)
		(end 51.258978 -399.033238)
		(width 0.14224)
		(layer "In15.Cu")
		(net "P5E_CPU1_P0_RX_BUF_DP<3>")
	)
	(segment
		(start 64.649858 -437.889904)
		(end 64.649858 -438.191148)
		(width 0.14224)
		(layer "In15.Cu")
		(net "P5E_CPU1_P0_RX_BUF_DP<3>")
	)
	(segment
		(start 50.95748 -396.300198)
		(end 50.95748 -395.873478)
		(width 0.14224)
		(layer "In15.Cu")
		(net "P5E_CPU1_P0_RX_BUF_DP<3>")
	)
	(segment
		(start 52.5526 -400.32686)
		(end 52.5526 -400.132804)
		(width 0.14224)
		(layer "In15.Cu")
		(net "P5E_CPU1_P0_RX_BUF_DP<3>")
	)
	(segment
		(start 50.95748 -395.873478)
		(end 51.09464 -395.736318)
		(width 0.14224)
		(layer "In15.Cu")
		(net "P5E_CPU1_P0_RX_BUF_DP<3>")
	)
	(segment
		(start 64.649858 -438.191148)
		(end 64.499744 -438.341262)
		(width 0.14224)
		(layer "In15.Cu")
		(net "P5E_CPU1_P0_RX_BUF_DP<3>")
	)
	(segment
		(start 51.75504 -399.5293)
		(end 51.75504 -399.335244)
		(width 0.14224)
		(layer "In15.Cu")
		(net "P5E_CPU1_P0_RX_BUF_DP<3>")
	)
	(segment
		(start 61.415676 -415.022284)
		(end 59.9567 -414.12287)
		(width 0.14224)
		(layer "In15.Cu")
		(net "P5E_CPU1_P0_RX_BUF_DP<3>")
	)
	(segment
		(start 57.775348 -410.92755)
		(end 57.65165 -410.803852)
		(width 0.14224)
		(layer "In15.Cu")
		(net "P5E_CPU1_P0_RX_BUF_DP<3>")
	)
	(segment
		(start 54.14772 -401.727924)
		(end 53.845714 -401.425918)
		(width 0.14224)
		(layer "In15.Cu")
		(net "P5E_CPU1_P0_RX_BUF_DP<3>")
	)
	(segment
		(start 57.417462 -406.089612)
		(end 56.902604 -405.574754)
		(width 0.14224)
		(layer "In15.Cu")
		(net "P5E_CPU1_P0_RX_BUF_DP<3>")
	)
	(segment
		(start 64.499744 -438.341262)
		(end 64.10833 -438.341262)
		(width 0.14224)
		(layer "In15.Cu")
		(net "P5E_CPU1_P0_RX_BUF_DP<3>")
	)
	(segment
		(start 59.088274 -411.947614)
		(end 58.940446 -411.591252)
		(width 0.14224)
		(layer "In15.Cu")
		(net "P5E_CPU1_P0_RX_BUF_DP<3>")
	)
	(segment
		(start 51.09464 -397.565118)
		(end 50.95748 -397.427958)
		(width 0.14224)
		(layer "In15.Cu")
		(net "P5E_CPU1_P0_RX_BUF_DP<3>")
	)
	(segment
		(start 50.95748 -395.172438)
		(end 50.95748 -394.745718)
		(width 0.14224)
		(layer "In15.Cu")
		(net "P5E_CPU1_P0_RX_BUF_DP<3>")
	)
	(segment
		(start 52.056538 -399.830798)
		(end 51.75504 -399.5293)
		(width 0.14224)
		(layer "In15.Cu")
		(net "P5E_CPU1_P0_RX_BUF_DP<3>")
	)
	(segment
		(start 56.025034 -405.185118)
		(end 56.025034 -404.052024)
		(width 0.14224)
		(layer "In15.Cu")
		(net "P5E_CPU1_P0_RX_BUF_DP<3>")
	)
	(segment
		(start 57.65165 -410.803852)
		(end 57.556654 -410.574744)
		(width 0.14224)
		(layer "In15.Cu")
		(net "P5E_CPU1_P0_RX_BUF_DP<3>")
	)
	(segment
		(start 51.258978 -399.033238)
		(end 50.994818 -398.769078)
		(width 0.14224)
		(layer "In15.Cu")
		(net "P5E_CPU1_P0_RX_BUF_DP<3>")
	)
	(segment
		(start 54.94528 -402.71954)
		(end 54.94528 -402.525484)
		(width 0.14224)
		(layer "In15.Cu")
		(net "P5E_CPU1_P0_RX_BUF_DP<3>")
	)
	(segment
		(start 53.35016 -401.12442)
		(end 53.35016 -400.930364)
		(width 0.14224)
		(layer "In15.Cu")
		(net "P5E_CPU1_P0_RX_BUF_DP<3>")
	)
	(segment
		(start 51.277012 -392.989562)
		(end 51.416458 -393.129008)
		(width 0.14224)
		(layer "In15.Cu")
		(net "P5E_CPU1_P0_RX_BUF_DP<3>")
	)
	(segment
		(start 53.048154 -400.628358)
		(end 52.854098 -400.628358)
		(width 0.14224)
		(layer "In15.Cu")
		(net "P5E_CPU1_P0_RX_BUF_DP<3>")
	)
	(segment
		(start 57.854342 -410.980382)
		(end 57.775348 -410.92755)
		(width 0.14224)
		(layer "In15.Cu")
		(net "P5E_CPU1_P0_RX_BUF_DP<3>")
	)
	(segment
		(start 56.902604 -405.574754)
		(end 56.353964 -405.574754)
		(width 0.14224)
		(layer "In15.Cu")
		(net "P5E_CPU1_P0_RX_BUF_DP<3>")
	)
	(segment
		(start 50.95748 -398.678908)
		(end 50.95748 -398.128998)
		(width 0.14224)
		(layer "In15.Cu")
		(net "P5E_CPU1_P0_RX_BUF_DP<3>")
	)
	(segment
		(start 51.09464 -394.608558)
		(end 51.09464 -394.181838)
		(width 0.14224)
		(layer "In15.Cu")
		(net "P5E_CPU1_P0_RX_BUF_DP<3>")
	)
	(segment
		(start 55.846218 -403.620478)
		(end 54.94528 -402.71954)
		(width 0.14224)
		(layer "In15.Cu")
		(net "P5E_CPU1_P0_RX_BUF_DP<3>")
	)
	(segment
		(start 50.95748 -394.044678)
		(end 50.95748 -393.129008)
		(width 0.14224)
		(layer "In15.Cu")
		(net "P5E_CPU1_P0_RX_BUF_DP<3>")
	)
	(segment
		(start 53.35016 -400.930364)
		(end 53.048154 -400.628358)
		(width 0.14224)
		(layer "In15.Cu")
		(net "P5E_CPU1_P0_RX_BUF_DP<3>")
	)
	(segment
		(start 51.09464 -396.864078)
		(end 51.09464 -396.437358)
		(width 0.14224)
		(layer "In15.Cu")
		(net "P5E_CPU1_P0_RX_BUF_DP<3>")
	)
	(segment
		(start 50.95748 -397.427958)
		(end 50.95748 -397.001238)
		(width 0.14224)
		(layer "In15.Cu")
		(net "P5E_CPU1_P0_RX_BUF_DP<3>")
	)
	(segment
		(start 63.971932 -417.201096)
		(end 63.462408 -416.704272)
		(width 0.14224)
		(layer "In15.Cu")
		(net "P5E_CPU1_P0_RX_BUF_DP<3>")
	)
	(segment
		(start 56.097678 -405.360378)
		(end 56.025034 -405.185118)
		(width 0.14224)
		(layer "In15.Cu")
		(net "P5E_CPU1_P0_RX_BUF_DP<3>")
	)
	(segment
		(start 58.940446 -411.591252)
		(end 58.665618 -411.316424)
		(width 0.14224)
		(layer "In15.Cu")
		(net "P5E_CPU1_P0_RX_BUF_DP<3>")
	)
	(segment
		(start 58.665618 -411.316424)
		(end 57.854342 -410.980382)
		(width 0.14224)
		(layer "In15.Cu")
		(net "P5E_CPU1_P0_RX_BUF_DP<3>")
	)
	(segment
		(start 51.09464 -397.991838)
		(end 51.09464 -397.565118)
		(width 0.14224)
		(layer "In15.Cu")
		(net "P5E_CPU1_P0_RX_BUF_DP<3>")
	)
	(segment
		(start 63.027052 -416.279838)
		(end 61.415676 -415.022284)
		(width 0.14224)
		(layer "In15.Cu")
		(net "P5E_CPU1_P0_RX_BUF_DP<3>")
	)
	(segment
		(start 59.9567 -414.12287)
		(end 59.414918 -413.741616)
		(width 0.14224)
		(layer "In15.Cu")
		(net "P5E_CPU1_P0_RX_BUF_DP<3>")
	)
	(segment
		(start 50.95748 -394.745718)
		(end 51.09464 -394.608558)
		(width 0.14224)
		(layer "In15.Cu")
		(net "P5E_CPU1_P0_RX_BUF_DP<3>")
	)
	(segment
		(start 59.414918 -413.741616)
		(end 59.088274 -413.414972)
		(width 0.14224)
		(layer "In15.Cu")
		(net "P5E_CPU1_P0_RX_BUF_DP<3>")
	)
	(segment
		(start 50.95748 -398.128998)
		(end 51.09464 -397.991838)
		(width 0.14224)
		(layer "In15.Cu")
		(net "P5E_CPU1_P0_RX_BUF_DP<3>")
	)
	(segment
		(start 57.556654 -410.574744)
		(end 57.556654 -406.424892)
		(width 0.14224)
		(layer "In15.Cu")
		(net "P5E_CPU1_P0_RX_BUF_DP<3>")
	)
	(segment
		(start 51.416458 -393.129008)
		(end 51.416458 -393.292838)
		(width 0.14224)
		(layer "In15.Cu")
		(net "P5E_CPU1_P0_RX_BUF_DP<3>")
	)
	(segment
		(start 63.971932 -438.204864)
		(end 63.971932 -417.201096)
		(width 0.14224)
		(layer "In15.Cu")
		(net "P5E_CPU1_P0_RX_BUF_DP<3>")
	)
	(segment
		(start 53.845714 -401.425918)
		(end 53.651658 -401.425918)
		(width 0.14224)
		(layer "In15.Cu")
		(net "P5E_CPU1_P0_RX_BUF_DP<3>")
	)
	(segment
		(start 56.282336 -405.545036)
		(end 56.097678 -405.360378)
		(width 0.14224)
		(layer "In15.Cu")
		(net "P5E_CPU1_P0_RX_BUF_DP<3>")
	)
	(segment
		(start 63.462408 -416.704272)
		(end 63.027052 -416.279838)
		(width 0.14224)
		(layer "In15.Cu")
		(net "P5E_CPU1_P0_RX_BUF_DP<3>")
	)
	(segment
		(start 53.651658 -401.425918)
		(end 53.35016 -401.12442)
		(width 0.14224)
		(layer "In15.Cu")
		(net "P5E_CPU1_P0_RX_BUF_DP<3>")
	)
	(segment
		(start 52.5526 -400.132804)
		(end 52.250594 -399.830798)
		(width 0.14224)
		(layer "In15.Cu")
		(net "P5E_CPU1_P0_RX_BUF_DP<3>")
	)
	(segment
		(start 52.854098 -400.628358)
		(end 52.5526 -400.32686)
		(width 0.14224)
		(layer "In15.Cu")
		(net "P5E_CPU1_P0_RX_BUF_DP<3>")
	)
	(segment
		(start 51.09464 -395.736318)
		(end 51.09464 -395.309598)
		(width 0.14224)
		(layer "In15.Cu")
		(net "P5E_CPU1_P0_RX_BUF_DP<3>")
	)
	(segment
		(start 54.643274 -402.223478)
		(end 54.449218 -402.223478)
		(width 0.14224)
		(layer "In15.Cu")
		(net "P5E_CPU1_P0_RX_BUF_DP<3>")
	)
	(segment
		(start 52.250594 -399.830798)
		(end 52.056538 -399.830798)
		(width 0.14224)
		(layer "In15.Cu")
		(net "P5E_CPU1_P0_RX_BUF_DP<3>")
	)
	(segment
		(start 51.75504 -399.335244)
		(end 51.453034 -399.033238)
		(width 0.14224)
		(layer "In15.Cu")
		(net "P5E_CPU1_P0_RX_BUF_DP<3>")
	)
	(segment
		(start 51.09464 -396.437358)
		(end 50.95748 -396.300198)
		(width 0.14224)
		(layer "In15.Cu")
		(net "P5E_CPU1_P0_RX_BUF_DP<3>")
	)
	(segment
		(start 64.10833 -438.341262)
		(end 63.971932 -438.204864)
		(width 0.14224)
		(layer "In15.Cu")
		(net "P5E_CPU1_P0_RX_BUF_DP<3>")
	)
	(segment
		(start 54.94528 -402.525484)
		(end 54.643274 -402.223478)
		(width 0.14224)
		(layer "In15.Cu")
		(net "P5E_CPU1_P0_RX_BUF_DP<3>")
	)
	(segment
		(start 51.096926 -392.989562)
		(end 51.277012 -392.989562)
		(width 0.14224)
		(layer "In15.Cu")
		(net "P5E_CPU1_P0_RX_BUF_DP<3>")
	)
	(segment
		(start 51.09464 -394.181838)
		(end 50.95748 -394.044678)
		(width 0.14224)
		(layer "In15.Cu")
		(net "P5E_CPU1_P0_RX_BUF_DP<3>")
	)
	(segment
		(start 59.088274 -413.414972)
		(end 59.088274 -411.947614)
		(width 0.14224)
		(layer "In15.Cu")
		(net "P5E_CPU1_P0_RX_BUF_DP<3>")
	)
	(segment
		(start 51.09464 -395.309598)
		(end 50.95748 -395.172438)
		(width 0.14224)
		(layer "In15.Cu")
		(net "P5E_CPU1_P0_RX_BUF_DP<3>")
	)
	(segment
		(start 54.449218 -402.223478)
		(end 54.14772 -401.92198)
		(width 0.14224)
		(layer "In15.Cu")
		(net "P5E_CPU1_P0_RX_BUF_DP<3>")
	)
	(segment
		(start 57.556654 -406.424892)
		(end 57.417462 -406.089612)
		(width 0.14224)
		(layer "In15.Cu")
		(net "P5E_CPU1_P0_RX_BUF_DP<3>")
	)
	(arc
		(start 50.994818 -398.769078)
		(mid 50.967175 -398.727708)
		(end 50.95748 -398.678908)
		(width 0.14224)
		(layer "In15.Cu")
		(net "P5E_CPU1_P0_RX_BUF_DP<3>")
	)
	(arc
		(start 56.025034 -404.052024)
		(mid 55.978558 -403.818463)
		(end 55.846218 -403.620478)
		(width 0.14224)
		(layer "In15.Cu")
		(net "P5E_CPU1_P0_RX_BUF_DP<3>")
	)
	(segment
		(start 49.513998 -391.577322)
		(end 49.513998 -392.723878)
		(width 0.1016)
		(layer "F.Cu")
		(net "P5E_CPU1_P0_RX_BUF_DP<2>")
	)
	(segment
		(start 49.518062 -391.281158)
		(end 49.602644 -391.36574)
		(width 0.1016)
		(layer "F.Cu")
		(net "P5E_CPU1_P0_RX_BUF_DP<2>")
	)
	(segment
		(start 49.602644 -391.36574)
		(end 49.602644 -391.488676)
		(width 0.1016)
		(layer "F.Cu")
		(net "P5E_CPU1_P0_RX_BUF_DP<2>")
	)
	(segment
		(start 49.602644 -391.488676)
		(end 49.513998 -391.577322)
		(width 0.1016)
		(layer "F.Cu")
		(net "P5E_CPU1_P0_RX_BUF_DP<2>")
	)
	(segment
		(start 50.216562 -393.1158)
		(end 50.216562 -393.292838)
		(width 0.1016)
		(layer "F.Cu")
		(net "P5E_CPU1_P0_RX_BUF_DP<2>")
	)
	(segment
		(start 49.513998 -392.723878)
		(end 49.767236 -392.977116)
		(width 0.1016)
		(layer "F.Cu")
		(net "P5E_CPU1_P0_RX_BUF_DP<2>")
	)
	(segment
		(start 50.077878 -392.977116)
		(end 50.216562 -393.1158)
		(width 0.1016)
		(layer "F.Cu")
		(net "P5E_CPU1_P0_RX_BUF_DP<2>")
	)
	(segment
		(start 49.767236 -392.977116)
		(end 50.077878 -392.977116)
		(width 0.1016)
		(layer "F.Cu")
		(net "P5E_CPU1_P0_RX_BUF_DP<2>")
	)
	(segment
		(start 54.493414 -406.424892)
		(end 54.30901 -405.979884)
		(width 0.14224)
		(layer "In15.Cu")
		(net "P5E_CPU1_P0_RX_BUF_DP<2>")
	)
	(segment
		(start 50.767234 -400.817842)
		(end 50.496724 -400.48815)
		(width 0.14224)
		(layer "In15.Cu")
		(net "P5E_CPU1_P0_RX_BUF_DP<2>")
	)
	(segment
		(start 49.894744 -395.80947)
		(end 49.757584 -395.67231)
		(width 0.14224)
		(layer "In15.Cu")
		(net "P5E_CPU1_P0_RX_BUF_DP<2>")
	)
	(segment
		(start 49.894744 -396.93723)
		(end 49.757584 -396.80007)
		(width 0.14224)
		(layer "In15.Cu")
		(net "P5E_CPU1_P0_RX_BUF_DP<2>")
	)
	(segment
		(start 51.212242 -401.360132)
		(end 51.231292 -401.167092)
		(width 0.14224)
		(layer "In15.Cu")
		(net "P5E_CPU1_P0_RX_BUF_DP<2>")
	)
	(segment
		(start 62.649862 -436.889906)
		(end 62.649862 -437.19115)
		(width 0.14224)
		(layer "In15.Cu")
		(net "P5E_CPU1_P0_RX_BUF_DP<2>")
	)
	(segment
		(start 49.894744 -396.23619)
		(end 49.894744 -395.80947)
		(width 0.14224)
		(layer "In15.Cu")
		(net "P5E_CPU1_P0_RX_BUF_DP<2>")
	)
	(segment
		(start 49.757584 -395.67231)
		(end 49.757584 -395.24559)
		(width 0.14224)
		(layer "In15.Cu")
		(net "P5E_CPU1_P0_RX_BUF_DP<2>")
	)
	(segment
		(start 54.493414 -410.574744)
		(end 54.493414 -408.458162)
		(width 0.14224)
		(layer "In15.Cu")
		(net "P5E_CPU1_P0_RX_BUF_DP<2>")
	)
	(segment
		(start 49.757584 -394.54455)
		(end 49.757584 -393.129008)
		(width 0.14224)
		(layer "In15.Cu")
		(net "P5E_CPU1_P0_RX_BUF_DP<2>")
	)
	(segment
		(start 49.894744 -398.06499)
		(end 49.757584 -397.92783)
		(width 0.14224)
		(layer "In15.Cu")
		(net "P5E_CPU1_P0_RX_BUF_DP<2>")
	)
	(segment
		(start 53.034438 -405.360378)
		(end 52.961794 -405.185118)
		(width 0.14224)
		(layer "In15.Cu")
		(net "P5E_CPU1_P0_RX_BUF_DP<2>")
	)
	(segment
		(start 54.712108 -410.92755)
		(end 54.58841 -410.803852)
		(width 0.14224)
		(layer "In15.Cu")
		(net "P5E_CPU1_P0_RX_BUF_DP<2>")
	)
	(segment
		(start 54.493414 -408.458162)
		(end 54.630574 -408.321002)
		(width 0.14224)
		(layer "In15.Cu")
		(net "P5E_CPU1_P0_RX_BUF_DP<2>")
	)
	(segment
		(start 61.996574 -417.078414)
		(end 61.58992 -416.469576)
		(width 0.14224)
		(layer "In15.Cu")
		(net "P5E_CPU1_P0_RX_BUF_DP<2>")
	)
	(segment
		(start 62.649862 -437.19115)
		(end 62.499748 -437.341264)
		(width 0.14224)
		(layer "In15.Cu")
		(net "P5E_CPU1_P0_RX_BUF_DP<2>")
	)
	(segment
		(start 53.290724 -405.574754)
		(end 53.219096 -405.545036)
		(width 0.14224)
		(layer "In15.Cu")
		(net "P5E_CPU1_P0_RX_BUF_DP<2>")
	)
	(segment
		(start 49.894744 -397.36395)
		(end 49.894744 -396.93723)
		(width 0.14224)
		(layer "In15.Cu")
		(net "P5E_CPU1_P0_RX_BUF_DP<2>")
	)
	(segment
		(start 56.447436 -413.938466)
		(end 56.176926 -413.776414)
		(width 0.14224)
		(layer "In15.Cu")
		(net "P5E_CPU1_P0_RX_BUF_DP<2>")
	)
	(segment
		(start 52.186078 -402.546566)
		(end 52.205128 -402.353526)
		(width 0.14224)
		(layer "In15.Cu")
		(net "P5E_CPU1_P0_RX_BUF_DP<2>")
	)
	(segment
		(start 49.757584 -396.37335)
		(end 49.894744 -396.23619)
		(width 0.14224)
		(layer "In15.Cu")
		(net "P5E_CPU1_P0_RX_BUF_DP<2>")
	)
	(segment
		(start 54.791102 -410.980382)
		(end 54.712108 -410.92755)
		(width 0.14224)
		(layer "In15.Cu")
		(net "P5E_CPU1_P0_RX_BUF_DP<2>")
	)
	(segment
		(start 54.630574 -407.894282)
		(end 54.493414 -407.757122)
		(width 0.14224)
		(layer "In15.Cu")
		(net "P5E_CPU1_P0_RX_BUF_DP<2>")
	)
	(segment
		(start 50.496724 -400.48815)
		(end 50.515774 -400.29511)
		(width 0.14224)
		(layer "In15.Cu")
		(net "P5E_CPU1_P0_RX_BUF_DP<2>")
	)
	(segment
		(start 49.757584 -399.478754)
		(end 49.757584 -398.62887)
		(width 0.14224)
		(layer "In15.Cu")
		(net "P5E_CPU1_P0_RX_BUF_DP<2>")
	)
	(segment
		(start 53.803042 -405.574754)
		(end 53.290724 -405.574754)
		(width 0.14224)
		(layer "In15.Cu")
		(net "P5E_CPU1_P0_RX_BUF_DP<2>")
	)
	(segment
		(start 52.961794 -405.185118)
		(end 52.961794 -403.77745)
		(width 0.14224)
		(layer "In15.Cu")
		(net "P5E_CPU1_P0_RX_BUF_DP<2>")
	)
	(segment
		(start 61.996574 -437.214264)
		(end 61.996574 -417.078414)
		(width 0.14224)
		(layer "In15.Cu")
		(net "P5E_CPU1_P0_RX_BUF_DP<2>")
	)
	(segment
		(start 49.894744 -395.10843)
		(end 49.894744 -394.68171)
		(width 0.14224)
		(layer "In15.Cu")
		(net "P5E_CPU1_P0_RX_BUF_DP<2>")
	)
	(segment
		(start 50.216562 -393.129008)
		(end 50.216562 -393.292838)
		(width 0.14224)
		(layer "In15.Cu")
		(net "P5E_CPU1_P0_RX_BUF_DP<2>")
	)
	(segment
		(start 56.176926 -413.776414)
		(end 56.084216 -413.683704)
		(width 0.14224)
		(layer "In15.Cu")
		(net "P5E_CPU1_P0_RX_BUF_DP<2>")
	)
	(segment
		(start 50.077116 -392.989562)
		(end 50.216562 -393.129008)
		(width 0.14224)
		(layer "In15.Cu")
		(net "P5E_CPU1_P0_RX_BUF_DP<2>")
	)
	(segment
		(start 50.960274 -400.836892)
		(end 50.767234 -400.817842)
		(width 0.14224)
		(layer "In15.Cu")
		(net "P5E_CPU1_P0_RX_BUF_DP<2>")
	)
	(segment
		(start 49.757584 -398.62887)
		(end 49.894744 -398.49171)
		(width 0.14224)
		(layer "In15.Cu")
		(net "P5E_CPU1_P0_RX_BUF_DP<2>")
	)
	(segment
		(start 55.896764 -411.638242)
		(end 55.555388 -411.296866)
		(width 0.14224)
		(layer "In15.Cu")
		(net "P5E_CPU1_P0_RX_BUF_DP<2>")
	)
	(segment
		(start 51.74107 -402.004276)
		(end 51.212242 -401.360132)
		(width 0.14224)
		(layer "In15.Cu")
		(net "P5E_CPU1_P0_RX_BUF_DP<2>")
	)
	(segment
		(start 50.515774 -400.29511)
		(end 50.24501 -399.965164)
		(width 0.14224)
		(layer "In15.Cu")
		(net "P5E_CPU1_P0_RX_BUF_DP<2>")
	)
	(segment
		(start 51.231292 -401.167092)
		(end 50.960274 -400.836892)
		(width 0.14224)
		(layer "In15.Cu")
		(net "P5E_CPU1_P0_RX_BUF_DP<2>")
	)
	(segment
		(start 49.757584 -393.129008)
		(end 49.89703 -392.989562)
		(width 0.14224)
		(layer "In15.Cu")
		(net "P5E_CPU1_P0_RX_BUF_DP<2>")
	)
	(segment
		(start 54.630574 -408.321002)
		(end 54.630574 -407.894282)
		(width 0.14224)
		(layer "In15.Cu")
		(net "P5E_CPU1_P0_RX_BUF_DP<2>")
	)
	(segment
		(start 52.7812 -403.271482)
		(end 52.186078 -402.546566)
		(width 0.14224)
		(layer "In15.Cu")
		(net "P5E_CPU1_P0_RX_BUF_DP<2>")
	)
	(segment
		(start 55.555388 -411.296866)
		(end 54.791102 -410.980382)
		(width 0.14224)
		(layer "In15.Cu")
		(net "P5E_CPU1_P0_RX_BUF_DP<2>")
	)
	(segment
		(start 56.084216 -413.683704)
		(end 56.025034 -413.540702)
		(width 0.14224)
		(layer "In15.Cu")
		(net "P5E_CPU1_P0_RX_BUF_DP<2>")
	)
	(segment
		(start 61.58992 -416.469576)
		(end 58.923936 -414.68929)
		(width 0.14224)
		(layer "In15.Cu")
		(net "P5E_CPU1_P0_RX_BUF_DP<2>")
	)
	(segment
		(start 49.757584 -397.92783)
		(end 49.757584 -397.50111)
		(width 0.14224)
		(layer "In15.Cu")
		(net "P5E_CPU1_P0_RX_BUF_DP<2>")
	)
	(segment
		(start 52.205128 -402.353526)
		(end 51.93411 -402.023326)
		(width 0.14224)
		(layer "In15.Cu")
		(net "P5E_CPU1_P0_RX_BUF_DP<2>")
	)
	(segment
		(start 49.89703 -392.989562)
		(end 50.077116 -392.989562)
		(width 0.14224)
		(layer "In15.Cu")
		(net "P5E_CPU1_P0_RX_BUF_DP<2>")
	)
	(segment
		(start 50.05197 -399.946114)
		(end 49.826418 -399.671032)
		(width 0.14224)
		(layer "In15.Cu")
		(net "P5E_CPU1_P0_RX_BUF_DP<2>")
	)
	(segment
		(start 54.58841 -410.803852)
		(end 54.493414 -410.574744)
		(width 0.14224)
		(layer "In15.Cu")
		(net "P5E_CPU1_P0_RX_BUF_DP<2>")
	)
	(segment
		(start 56.025034 -411.947868)
		(end 55.896764 -411.638242)
		(width 0.14224)
		(layer "In15.Cu")
		(net "P5E_CPU1_P0_RX_BUF_DP<2>")
	)
	(segment
		(start 49.757584 -397.50111)
		(end 49.894744 -397.36395)
		(width 0.14224)
		(layer "In15.Cu")
		(net "P5E_CPU1_P0_RX_BUF_DP<2>")
	)
	(segment
		(start 50.24501 -399.965164)
		(end 50.05197 -399.946114)
		(width 0.14224)
		(layer "In15.Cu")
		(net "P5E_CPU1_P0_RX_BUF_DP<2>")
	)
	(segment
		(start 56.025034 -413.540702)
		(end 56.025034 -411.947868)
		(width 0.14224)
		(layer "In15.Cu")
		(net "P5E_CPU1_P0_RX_BUF_DP<2>")
	)
	(segment
		(start 49.757584 -396.80007)
		(end 49.757584 -396.37335)
		(width 0.14224)
		(layer "In15.Cu")
		(net "P5E_CPU1_P0_RX_BUF_DP<2>")
	)
	(segment
		(start 54.30901 -405.979884)
		(end 53.975254 -405.646128)
		(width 0.14224)
		(layer "In15.Cu")
		(net "P5E_CPU1_P0_RX_BUF_DP<2>")
	)
	(segment
		(start 58.923936 -414.68929)
		(end 56.447436 -413.938466)
		(width 0.14224)
		(layer "In15.Cu")
		(net "P5E_CPU1_P0_RX_BUF_DP<2>")
	)
	(segment
		(start 49.894744 -398.49171)
		(end 49.894744 -398.06499)
		(width 0.14224)
		(layer "In15.Cu")
		(net "P5E_CPU1_P0_RX_BUF_DP<2>")
	)
	(segment
		(start 49.894744 -394.68171)
		(end 49.757584 -394.54455)
		(width 0.14224)
		(layer "In15.Cu")
		(net "P5E_CPU1_P0_RX_BUF_DP<2>")
	)
	(segment
		(start 54.493414 -407.757122)
		(end 54.493414 -406.424892)
		(width 0.14224)
		(layer "In15.Cu")
		(net "P5E_CPU1_P0_RX_BUF_DP<2>")
	)
	(segment
		(start 49.757584 -395.24559)
		(end 49.894744 -395.10843)
		(width 0.14224)
		(layer "In15.Cu")
		(net "P5E_CPU1_P0_RX_BUF_DP<2>")
	)
	(segment
		(start 51.93411 -402.023326)
		(end 51.74107 -402.004276)
		(width 0.14224)
		(layer "In15.Cu")
		(net "P5E_CPU1_P0_RX_BUF_DP<2>")
	)
	(segment
		(start 53.219096 -405.545036)
		(end 53.034438 -405.360378)
		(width 0.14224)
		(layer "In15.Cu")
		(net "P5E_CPU1_P0_RX_BUF_DP<2>")
	)
	(segment
		(start 62.499748 -437.341264)
		(end 62.123574 -437.341264)
		(width 0.14224)
		(layer "In15.Cu")
		(net "P5E_CPU1_P0_RX_BUF_DP<2>")
	)
	(segment
		(start 62.123574 -437.341264)
		(end 61.996574 -437.214264)
		(width 0.14224)
		(layer "In15.Cu")
		(net "P5E_CPU1_P0_RX_BUF_DP<2>")
	)
	(segment
		(start 53.975254 -405.646128)
		(end 53.803042 -405.574754)
		(width 0.14224)
		(layer "In15.Cu")
		(net "P5E_CPU1_P0_RX_BUF_DP<2>")
	)
	(arc
		(start 49.826418 -399.671032)
		(mid 49.77532 -399.580866)
		(end 49.757584 -399.478754)
		(width 0.14224)
		(layer "In15.Cu")
		(net "P5E_CPU1_P0_RX_BUF_DP<2>")
	)
	(arc
		(start 52.961794 -403.77745)
		(mid 52.915359 -403.508818)
		(end 52.7812 -403.271482)
		(width 0.14224)
		(layer "In15.Cu")
		(net "P5E_CPU1_P0_RX_BUF_DP<2>")
	)
	(segment
		(start 48.567086 -392.977116)
		(end 48.877728 -392.977116)
		(width 0.1016)
		(layer "F.Cu")
		(net "P5E_CPU1_P0_RX_BUF_DP<1>")
	)
	(segment
		(start 49.016412 -393.1158)
		(end 49.016412 -393.292838)
		(width 0.1016)
		(layer "F.Cu")
		(net "P5E_CPU1_P0_RX_BUF_DP<1>")
	)
	(segment
		(start 48.313848 -391.577322)
		(end 48.313848 -392.723878)
		(width 0.1016)
		(layer "F.Cu")
		(net "P5E_CPU1_P0_RX_BUF_DP<1>")
	)
	(segment
		(start 48.313848 -392.723878)
		(end 48.567086 -392.977116)
		(width 0.1016)
		(layer "F.Cu")
		(net "P5E_CPU1_P0_RX_BUF_DP<1>")
	)
	(segment
		(start 48.402494 -391.488676)
		(end 48.313848 -391.577322)
		(width 0.1016)
		(layer "F.Cu")
		(net "P5E_CPU1_P0_RX_BUF_DP<1>")
	)
	(segment
		(start 48.402494 -391.36574)
		(end 48.402494 -391.488676)
		(width 0.1016)
		(layer "F.Cu")
		(net "P5E_CPU1_P0_RX_BUF_DP<1>")
	)
	(segment
		(start 48.877728 -392.977116)
		(end 49.016412 -393.1158)
		(width 0.1016)
		(layer "F.Cu")
		(net "P5E_CPU1_P0_RX_BUF_DP<1>")
	)
	(segment
		(start 48.317912 -391.281158)
		(end 48.402494 -391.36574)
		(width 0.1016)
		(layer "F.Cu")
		(net "P5E_CPU1_P0_RX_BUF_DP<1>")
	)
	(segment
		(start 59.31535 -416.680396)
		(end 57.77738 -415.65322)
		(width 0.14224)
		(layer "In15.Cu")
		(net "P5E_CPU1_P0_RX_BUF_DP<1>")
	)
	(segment
		(start 50.970688 -405.704802)
		(end 50.656744 -405.574754)
		(width 0.14224)
		(layer "In15.Cu")
		(net "P5E_CPU1_P0_RX_BUF_DP<1>")
	)
	(segment
		(start 55.596536 -414.749996)
		(end 55.596536 -414.75025)
		(width 0.14224)
		(layer "In15.Cu")
		(net "P5E_CPU1_P0_RX_BUF_DP<1>")
	)
	(segment
		(start 48.557434 -400.312382)
		(end 48.557434 -399.53819)
		(width 0.14224)
		(layer "In15.Cu")
		(net "P5E_CPU1_P0_RX_BUF_DP<1>")
	)
	(segment
		(start 48.694594 -396.71879)
		(end 48.557434 -396.58163)
		(width 0.14224)
		(layer "In15.Cu")
		(net "P5E_CPU1_P0_RX_BUF_DP<1>")
	)
	(segment
		(start 59.969908 -417.402772)
		(end 59.31535 -416.680396)
		(width 0.14224)
		(layer "In15.Cu")
		(net "P5E_CPU1_P0_RX_BUF_DP<1>")
	)
	(segment
		(start 51.648868 -410.92755)
		(end 51.529742 -410.808424)
		(width 0.14224)
		(layer "In15.Cu")
		(net "P5E_CPU1_P0_RX_BUF_DP<1>")
	)
	(segment
		(start 49.063402 -401.20062)
		(end 48.90008 -400.806158)
		(width 0.14224)
		(layer "In15.Cu")
		(net "P5E_CPU1_P0_RX_BUF_DP<1>")
	)
	(segment
		(start 48.694594 -395.59103)
		(end 48.557434 -395.45387)
		(width 0.14224)
		(layer "In15.Cu")
		(net "P5E_CPU1_P0_RX_BUF_DP<1>")
	)
	(segment
		(start 49.152302 -401.774152)
		(end 48.989234 -401.379944)
		(width 0.14224)
		(layer "In15.Cu")
		(net "P5E_CPU1_P0_RX_BUF_DP<1>")
	)
	(segment
		(start 52.961794 -413.368744)
		(end 52.961794 -411.986222)
		(width 0.14224)
		(layer "In15.Cu")
		(net "P5E_CPU1_P0_RX_BUF_DP<1>")
	)
	(segment
		(start 48.557434 -394.32611)
		(end 48.557434 -393.129008)
		(width 0.14224)
		(layer "In15.Cu")
		(net "P5E_CPU1_P0_RX_BUF_DP<1>")
	)
	(segment
		(start 48.557434 -396.15491)
		(end 48.694594 -396.01775)
		(width 0.14224)
		(layer "In15.Cu")
		(net "P5E_CPU1_P0_RX_BUF_DP<1>")
	)
	(segment
		(start 60.099448 -438.337198)
		(end 59.969908 -438.207658)
		(width 0.14224)
		(layer "In15.Cu")
		(net "P5E_CPU1_P0_RX_BUF_DP<1>")
	)
	(segment
		(start 59.969908 -438.207658)
		(end 59.969908 -417.402772)
		(width 0.14224)
		(layer "In15.Cu")
		(net "P5E_CPU1_P0_RX_BUF_DP<1>")
	)
	(segment
		(start 48.69688 -392.989562)
		(end 48.876966 -392.989562)
		(width 0.14224)
		(layer "In15.Cu")
		(net "P5E_CPU1_P0_RX_BUF_DP<1>")
	)
	(segment
		(start 48.694594 -396.01775)
		(end 48.694594 -395.59103)
		(width 0.14224)
		(layer "In15.Cu")
		(net "P5E_CPU1_P0_RX_BUF_DP<1>")
	)
	(segment
		(start 51.24577 -405.979884)
		(end 50.970688 -405.704802)
		(width 0.14224)
		(layer "In15.Cu")
		(net "P5E_CPU1_P0_RX_BUF_DP<1>")
	)
	(segment
		(start 48.557434 -398.83715)
		(end 48.557434 -398.41043)
		(width 0.14224)
		(layer "In15.Cu")
		(net "P5E_CPU1_P0_RX_BUF_DP<1>")
	)
	(segment
		(start 50.227484 -405.574754)
		(end 50.155856 -405.545036)
		(width 0.14224)
		(layer "In15.Cu")
		(net "P5E_CPU1_P0_RX_BUF_DP<1>")
	)
	(segment
		(start 57.77738 -415.65322)
		(end 55.596536 -414.749996)
		(width 0.14224)
		(layer "In15.Cu")
		(net "P5E_CPU1_P0_RX_BUF_DP<1>")
	)
	(segment
		(start 48.694594 -394.88999)
		(end 48.694594 -394.46327)
		(width 0.14224)
		(layer "In15.Cu")
		(net "P5E_CPU1_P0_RX_BUF_DP<1>")
	)
	(segment
		(start 51.430174 -410.56814)
		(end 51.430174 -408.197304)
		(width 0.14224)
		(layer "In15.Cu")
		(net "P5E_CPU1_P0_RX_BUF_DP<1>")
	)
	(segment
		(start 60.649866 -438.191148)
		(end 60.503816 -438.337198)
		(width 0.14224)
		(layer "In15.Cu")
		(net "P5E_CPU1_P0_RX_BUF_DP<1>")
	)
	(segment
		(start 48.557434 -396.58163)
		(end 48.557434 -396.15491)
		(width 0.14224)
		(layer "In15.Cu")
		(net "P5E_CPU1_P0_RX_BUF_DP<1>")
	)
	(segment
		(start 51.430174 -408.197304)
		(end 51.567334 -408.060144)
		(width 0.14224)
		(layer "In15.Cu")
		(net "P5E_CPU1_P0_RX_BUF_DP<1>")
	)
	(segment
		(start 52.961794 -411.986222)
		(end 52.747672 -411.468062)
		(width 0.14224)
		(layer "In15.Cu")
		(net "P5E_CPU1_P0_RX_BUF_DP<1>")
	)
	(segment
		(start 49.898554 -403.575774)
		(end 49.42078 -402.422106)
		(width 0.14224)
		(layer "In15.Cu")
		(net "P5E_CPU1_P0_RX_BUF_DP<1>")
	)
	(segment
		(start 51.567334 -408.060144)
		(end 51.567334 -407.633424)
		(width 0.14224)
		(layer "In15.Cu")
		(net "P5E_CPU1_P0_RX_BUF_DP<1>")
	)
	(segment
		(start 51.529742 -410.808424)
		(end 51.430174 -410.56814)
		(width 0.14224)
		(layer "In15.Cu")
		(net "P5E_CPU1_P0_RX_BUF_DP<1>")
	)
	(segment
		(start 48.694594 -394.46327)
		(end 48.557434 -394.32611)
		(width 0.14224)
		(layer "In15.Cu")
		(net "P5E_CPU1_P0_RX_BUF_DP<1>")
	)
	(segment
		(start 49.971198 -405.360378)
		(end 49.898554 -405.185118)
		(width 0.14224)
		(layer "In15.Cu")
		(net "P5E_CPU1_P0_RX_BUF_DP<1>")
	)
	(segment
		(start 48.557434 -397.70939)
		(end 48.557434 -397.28267)
		(width 0.14224)
		(layer "In15.Cu")
		(net "P5E_CPU1_P0_RX_BUF_DP<1>")
	)
	(segment
		(start 48.694594 -398.27327)
		(end 48.694594 -397.84655)
		(width 0.14224)
		(layer "In15.Cu")
		(net "P5E_CPU1_P0_RX_BUF_DP<1>")
	)
	(segment
		(start 49.016412 -393.129008)
		(end 49.016412 -393.292838)
		(width 0.14224)
		(layer "In15.Cu")
		(net "P5E_CPU1_P0_RX_BUF_DP<1>")
	)
	(segment
		(start 48.694594 -397.14551)
		(end 48.694594 -396.71879)
		(width 0.14224)
		(layer "In15.Cu")
		(net "P5E_CPU1_P0_RX_BUF_DP<1>")
	)
	(segment
		(start 51.430174 -407.496264)
		(end 51.430174 -406.424892)
		(width 0.14224)
		(layer "In15.Cu")
		(net "P5E_CPU1_P0_RX_BUF_DP<1>")
	)
	(segment
		(start 48.694594 -399.40103)
		(end 48.694594 -398.97431)
		(width 0.14224)
		(layer "In15.Cu")
		(net "P5E_CPU1_P0_RX_BUF_DP<1>")
	)
	(segment
		(start 51.567334 -407.633424)
		(end 51.430174 -407.496264)
		(width 0.14224)
		(layer "In15.Cu")
		(net "P5E_CPU1_P0_RX_BUF_DP<1>")
	)
	(segment
		(start 51.766724 -411.00629)
		(end 51.648868 -410.92755)
		(width 0.14224)
		(layer "In15.Cu")
		(net "P5E_CPU1_P0_RX_BUF_DP<1>")
	)
	(segment
		(start 55.596536 -414.75025)
		(end 53.427884 -413.85236)
		(width 0.14224)
		(layer "In15.Cu")
		(net "P5E_CPU1_P0_RX_BUF_DP<1>")
	)
	(segment
		(start 53.083968 -413.663892)
		(end 52.961794 -413.368744)
		(width 0.14224)
		(layer "In15.Cu")
		(net "P5E_CPU1_P0_RX_BUF_DP<1>")
	)
	(segment
		(start 49.42078 -402.422106)
		(end 49.495202 -402.242782)
		(width 0.14224)
		(layer "In15.Cu")
		(net "P5E_CPU1_P0_RX_BUF_DP<1>")
	)
	(segment
		(start 49.898554 -405.185118)
		(end 49.898554 -403.575774)
		(width 0.14224)
		(layer "In15.Cu")
		(net "P5E_CPU1_P0_RX_BUF_DP<1>")
	)
	(segment
		(start 48.557434 -395.02715)
		(end 48.694594 -394.88999)
		(width 0.14224)
		(layer "In15.Cu")
		(net "P5E_CPU1_P0_RX_BUF_DP<1>")
	)
	(segment
		(start 52.747672 -411.468062)
		(end 52.65293 -411.37332)
		(width 0.14224)
		(layer "In15.Cu")
		(net "P5E_CPU1_P0_RX_BUF_DP<1>")
	)
	(segment
		(start 48.90008 -400.806158)
		(end 48.720502 -400.73199)
		(width 0.14224)
		(layer "In15.Cu")
		(net "P5E_CPU1_P0_RX_BUF_DP<1>")
	)
	(segment
		(start 48.876966 -392.989562)
		(end 49.016412 -393.129008)
		(width 0.14224)
		(layer "In15.Cu")
		(net "P5E_CPU1_P0_RX_BUF_DP<1>")
	)
	(segment
		(start 48.694594 -397.84655)
		(end 48.557434 -397.70939)
		(width 0.14224)
		(layer "In15.Cu")
		(net "P5E_CPU1_P0_RX_BUF_DP<1>")
	)
	(segment
		(start 48.694594 -398.97431)
		(end 48.557434 -398.83715)
		(width 0.14224)
		(layer "In15.Cu")
		(net "P5E_CPU1_P0_RX_BUF_DP<1>")
	)
	(segment
		(start 52.65293 -411.37332)
		(end 51.766724 -411.00629)
		(width 0.14224)
		(layer "In15.Cu")
		(net "P5E_CPU1_P0_RX_BUF_DP<1>")
	)
	(segment
		(start 48.720502 -400.73199)
		(end 48.567086 -400.36115)
		(width 0.14224)
		(layer "In15.Cu")
		(net "P5E_CPU1_P0_RX_BUF_DP<1>")
	)
	(segment
		(start 60.649866 -437.889904)
		(end 60.649866 -438.191148)
		(width 0.14224)
		(layer "In15.Cu")
		(net "P5E_CPU1_P0_RX_BUF_DP<1>")
	)
	(segment
		(start 50.155856 -405.545036)
		(end 49.971198 -405.360378)
		(width 0.14224)
		(layer "In15.Cu")
		(net "P5E_CPU1_P0_RX_BUF_DP<1>")
	)
	(segment
		(start 48.557434 -393.129008)
		(end 48.69688 -392.989562)
		(width 0.14224)
		(layer "In15.Cu")
		(net "P5E_CPU1_P0_RX_BUF_DP<1>")
	)
	(segment
		(start 48.557434 -398.41043)
		(end 48.694594 -398.27327)
		(width 0.14224)
		(layer "In15.Cu")
		(net "P5E_CPU1_P0_RX_BUF_DP<1>")
	)
	(segment
		(start 48.557434 -395.45387)
		(end 48.557434 -395.02715)
		(width 0.14224)
		(layer "In15.Cu")
		(net "P5E_CPU1_P0_RX_BUF_DP<1>")
	)
	(segment
		(start 48.989234 -401.379944)
		(end 49.063402 -401.20062)
		(width 0.14224)
		(layer "In15.Cu")
		(net "P5E_CPU1_P0_RX_BUF_DP<1>")
	)
	(segment
		(start 48.557434 -397.28267)
		(end 48.694594 -397.14551)
		(width 0.14224)
		(layer "In15.Cu")
		(net "P5E_CPU1_P0_RX_BUF_DP<1>")
	)
	(segment
		(start 51.430174 -406.424892)
		(end 51.24577 -405.979884)
		(width 0.14224)
		(layer "In15.Cu")
		(net "P5E_CPU1_P0_RX_BUF_DP<1>")
	)
	(segment
		(start 53.427884 -413.85236)
		(end 53.315616 -413.818832)
		(width 0.14224)
		(layer "In15.Cu")
		(net "P5E_CPU1_P0_RX_BUF_DP<1>")
	)
	(segment
		(start 50.656744 -405.574754)
		(end 50.227484 -405.574754)
		(width 0.14224)
		(layer "In15.Cu")
		(net "P5E_CPU1_P0_RX_BUF_DP<1>")
	)
	(segment
		(start 53.315616 -413.818832)
		(end 53.083968 -413.663892)
		(width 0.14224)
		(layer "In15.Cu")
		(net "P5E_CPU1_P0_RX_BUF_DP<1>")
	)
	(segment
		(start 60.503816 -438.337198)
		(end 60.099448 -438.337198)
		(width 0.14224)
		(layer "In15.Cu")
		(net "P5E_CPU1_P0_RX_BUF_DP<1>")
	)
	(segment
		(start 49.495202 -402.242782)
		(end 49.33188 -401.84832)
		(width 0.14224)
		(layer "In15.Cu")
		(net "P5E_CPU1_P0_RX_BUF_DP<1>")
	)
	(segment
		(start 48.557434 -399.53819)
		(end 48.694594 -399.40103)
		(width 0.14224)
		(layer "In15.Cu")
		(net "P5E_CPU1_P0_RX_BUF_DP<1>")
	)
	(segment
		(start 49.33188 -401.84832)
		(end 49.152302 -401.774152)
		(width 0.14224)
		(layer "In15.Cu")
		(net "P5E_CPU1_P0_RX_BUF_DP<1>")
	)
	(arc
		(start 48.567086 -400.36115)
		(mid 48.559841 -400.337243)
		(end 48.557434 -400.312382)
		(width 0.14224)
		(layer "In15.Cu")
		(net "P5E_CPU1_P0_RX_BUF_DP<1>")
	)
	(segment
		(start 65.113916 -392.723878)
		(end 65.367154 -392.977116)
		(width 0.1016)
		(layer "F.Cu")
		(net "P5E_CPU1_P0_RX_BUF_DP<15>")
	)
	(segment
		(start 65.202562 -391.488676)
		(end 65.113916 -391.577322)
		(width 0.1016)
		(layer "F.Cu")
		(net "P5E_CPU1_P0_RX_BUF_DP<15>")
	)
	(segment
		(start 65.367154 -392.977116)
		(end 65.661286 -392.977116)
		(width 0.1016)
		(layer "F.Cu")
		(net "P5E_CPU1_P0_RX_BUF_DP<15>")
	)
	(segment
		(start 65.81648 -393.13231)
		(end 65.81648 -393.292838)
		(width 0.1016)
		(layer "F.Cu")
		(net "P5E_CPU1_P0_RX_BUF_DP<15>")
	)
	(segment
		(start 65.113916 -391.577322)
		(end 65.113916 -392.723878)
		(width 0.1016)
		(layer "F.Cu")
		(net "P5E_CPU1_P0_RX_BUF_DP<15>")
	)
	(segment
		(start 65.11798 -391.281158)
		(end 65.202562 -391.36574)
		(width 0.1016)
		(layer "F.Cu")
		(net "P5E_CPU1_P0_RX_BUF_DP<15>")
	)
	(segment
		(start 65.202562 -391.36574)
		(end 65.202562 -391.488676)
		(width 0.1016)
		(layer "F.Cu")
		(net "P5E_CPU1_P0_RX_BUF_DP<15>")
	)
	(segment
		(start 65.661286 -392.977116)
		(end 65.81648 -393.13231)
		(width 0.1016)
		(layer "F.Cu")
		(net "P5E_CPU1_P0_RX_BUF_DP<15>")
	)
	(segment
		(start 92.856558 -405.360378)
		(end 92.783914 -405.185118)
		(width 0.14224)
		(layer "In15.Cu")
		(net "P5E_CPU1_P0_RX_BUF_DP<15>")
	)
	(segment
		(start 89.287604 -423.543476)
		(end 95.731838 -413.899096)
		(width 0.14224)
		(layer "In15.Cu")
		(net "P5E_CPU1_P0_RX_BUF_DP<15>")
	)
	(segment
		(start 80.675734 -396.506954)
		(end 80.514444 -396.61465)
		(width 0.14224)
		(layer "In15.Cu")
		(net "P5E_CPU1_P0_RX_BUF_DP<15>")
	)
	(segment
		(start 68.045584 -394.94968)
		(end 66.971418 -394.68171)
		(width 0.14224)
		(layer "In15.Cu")
		(net "P5E_CPU1_P0_RX_BUF_DP<15>")
	)
	(segment
		(start 65.677034 -392.989562)
		(end 65.81648 -393.129008)
		(width 0.14224)
		(layer "In15.Cu")
		(net "P5E_CPU1_P0_RX_BUF_DP<15>")
	)
	(segment
		(start 76.21143 -395.76629)
		(end 74.022966 -395.54912)
		(width 0.14224)
		(layer "In15.Cu")
		(net "P5E_CPU1_P0_RX_BUF_DP<15>")
	)
	(segment
		(start 73.90003 -395.399006)
		(end 73.475088 -395.356842)
		(width 0.14224)
		(layer "In15.Cu")
		(net "P5E_CPU1_P0_RX_BUF_DP<15>")
	)
	(segment
		(start 77.656436 -395.90599)
		(end 77.495146 -396.01394)
		(width 0.14224)
		(layer "In15.Cu")
		(net "P5E_CPU1_P0_RX_BUF_DP<15>")
	)
	(segment
		(start 73.324974 -395.479778)
		(end 71.417688 -395.290548)
		(width 0.14224)
		(layer "In15.Cu")
		(net "P5E_CPU1_P0_RX_BUF_DP<15>")
	)
	(segment
		(start 71.417688 -395.290548)
		(end 71.294752 -395.140434)
		(width 0.14224)
		(layer "In15.Cu")
		(net "P5E_CPU1_P0_RX_BUF_DP<15>")
	)
	(segment
		(start 93.797374 -405.646128)
		(end 93.625162 -405.574754)
		(width 0.14224)
		(layer "In15.Cu")
		(net "P5E_CPU1_P0_RX_BUF_DP<15>")
	)
	(segment
		(start 66.971418 -394.68171)
		(end 66.871596 -394.51534)
		(width 0.14224)
		(layer "In15.Cu")
		(net "P5E_CPU1_P0_RX_BUF_DP<15>")
	)
	(segment
		(start 94.41053 -410.803852)
		(end 94.315534 -410.574744)
		(width 0.14224)
		(layer "In15.Cu")
		(net "P5E_CPU1_P0_RX_BUF_DP<15>")
	)
	(segment
		(start 89.108534 -438.341262)
		(end 88.976454 -438.209182)
		(width 0.14224)
		(layer "In15.Cu")
		(net "P5E_CPU1_P0_RX_BUF_DP<15>")
	)
	(segment
		(start 65.81648 -393.129008)
		(end 65.81648 -393.292838)
		(width 0.14224)
		(layer "In15.Cu")
		(net "P5E_CPU1_P0_RX_BUF_DP<15>")
	)
	(segment
		(start 80.514444 -396.61465)
		(end 79.380842 -396.389098)
		(width 0.14224)
		(layer "In15.Cu")
		(net "P5E_CPU1_P0_RX_BUF_DP<15>")
	)
	(segment
		(start 88.976454 -424.569636)
		(end 88.976708 -424.56989)
		(width 0.14224)
		(layer "In15.Cu")
		(net "P5E_CPU1_P0_RX_BUF_DP<15>")
	)
	(segment
		(start 66.871596 -394.51534)
		(end 66.457322 -394.411962)
		(width 0.14224)
		(layer "In15.Cu")
		(net "P5E_CPU1_P0_RX_BUF_DP<15>")
	)
	(segment
		(start 78.69301 -396.252192)
		(end 78.182978 -396.150846)
		(width 0.14224)
		(layer "In15.Cu")
		(net "P5E_CPU1_P0_RX_BUF_DP<15>")
	)
	(segment
		(start 94.534228 -410.92755)
		(end 94.41053 -410.803852)
		(width 0.14224)
		(layer "In15.Cu")
		(net "P5E_CPU1_P0_RX_BUF_DP<15>")
	)
	(segment
		(start 94.315534 -406.424892)
		(end 94.13113 -405.979884)
		(width 0.14224)
		(layer "In15.Cu")
		(net "P5E_CPU1_P0_RX_BUF_DP<15>")
	)
	(segment
		(start 92.316046 -402.795994)
		(end 92.108782 -402.58873)
		(width 0.14224)
		(layer "In15.Cu")
		(net "P5E_CPU1_P0_RX_BUF_DP<15>")
	)
	(segment
		(start 88.976454 -438.209182)
		(end 88.976454 -424.569636)
		(width 0.14224)
		(layer "In15.Cu")
		(net "P5E_CPU1_P0_RX_BUF_DP<15>")
	)
	(segment
		(start 95.76435 -411.747716)
		(end 95.268288 -411.251654)
		(width 0.14224)
		(layer "In15.Cu")
		(net "P5E_CPU1_P0_RX_BUF_DP<15>")
	)
	(segment
		(start 94.315534 -408.739086)
		(end 94.452694 -408.601926)
		(width 0.14224)
		(layer "In15.Cu")
		(net "P5E_CPU1_P0_RX_BUF_DP<15>")
	)
	(segment
		(start 74.022966 -395.54912)
		(end 73.90003 -395.399006)
		(width 0.14224)
		(layer "In15.Cu")
		(net "P5E_CPU1_P0_RX_BUF_DP<15>")
	)
	(segment
		(start 95.847154 -413.518604)
		(end 95.847154 -411.947614)
		(width 0.14224)
		(layer "In15.Cu")
		(net "P5E_CPU1_P0_RX_BUF_DP<15>")
	)
	(segment
		(start 66.290952 -394.511784)
		(end 65.644776 -394.350748)
		(width 0.14224)
		(layer "In15.Cu")
		(net "P5E_CPU1_P0_RX_BUF_DP<15>")
	)
	(segment
		(start 94.613222 -410.980382)
		(end 94.534228 -410.92755)
		(width 0.14224)
		(layer "In15.Cu")
		(net "P5E_CPU1_P0_RX_BUF_DP<15>")
	)
	(segment
		(start 79.272892 -396.227554)
		(end 78.8543 -396.144496)
		(width 0.14224)
		(layer "In15.Cu")
		(net "P5E_CPU1_P0_RX_BUF_DP<15>")
	)
	(segment
		(start 92.759276 -403.745954)
		(end 92.447364 -402.993098)
		(width 0.14224)
		(layer "In15.Cu")
		(net "P5E_CPU1_P0_RX_BUF_DP<15>")
	)
	(segment
		(start 81.09458 -396.590012)
		(end 80.675734 -396.506954)
		(width 0.14224)
		(layer "In15.Cu")
		(net "P5E_CPU1_P0_RX_BUF_DP<15>")
	)
	(segment
		(start 66.457322 -394.411962)
		(end 66.290952 -394.511784)
		(width 0.14224)
		(layer "In15.Cu")
		(net "P5E_CPU1_P0_RX_BUF_DP<15>")
	)
	(segment
		(start 70.86981 -395.09827)
		(end 70.719696 -395.221206)
		(width 0.14224)
		(layer "In15.Cu")
		(net "P5E_CPU1_P0_RX_BUF_DP<15>")
	)
	(segment
		(start 78.8543 -396.144496)
		(end 78.69301 -396.252192)
		(width 0.14224)
		(layer "In15.Cu")
		(net "P5E_CPU1_P0_RX_BUF_DP<15>")
	)
	(segment
		(start 94.315534 -408.038046)
		(end 94.315534 -406.424892)
		(width 0.14224)
		(layer "In15.Cu")
		(net "P5E_CPU1_P0_RX_BUF_DP<15>")
	)
	(segment
		(start 84.779866 -397.67637)
		(end 84.425282 -397.439388)
		(width 0.14224)
		(layer "In15.Cu")
		(net "P5E_CPU1_P0_RX_BUF_DP<15>")
	)
	(segment
		(start 94.452694 -408.601926)
		(end 94.452694 -408.175206)
		(width 0.14224)
		(layer "In15.Cu")
		(net "P5E_CPU1_P0_RX_BUF_DP<15>")
	)
	(segment
		(start 95.731838 -413.899096)
		(end 95.847154 -413.518604)
		(width 0.14224)
		(layer "In15.Cu")
		(net "P5E_CPU1_P0_RX_BUF_DP<15>")
	)
	(segment
		(start 84.970112 -397.638524)
		(end 84.779866 -397.67637)
		(width 0.14224)
		(layer "In15.Cu")
		(net "P5E_CPU1_P0_RX_BUF_DP<15>")
	)
	(segment
		(start 94.13113 -405.979884)
		(end 93.797374 -405.646128)
		(width 0.14224)
		(layer "In15.Cu")
		(net "P5E_CPU1_P0_RX_BUF_DP<15>")
	)
	(segment
		(start 84.20735 -397.349472)
		(end 81.202276 -396.751556)
		(width 0.14224)
		(layer "In15.Cu")
		(net "P5E_CPU1_P0_RX_BUF_DP<15>")
	)
	(segment
		(start 77.495146 -396.01394)
		(end 76.364084 -395.788896)
		(width 0.14224)
		(layer "In15.Cu")
		(net "P5E_CPU1_P0_RX_BUF_DP<15>")
	)
	(segment
		(start 94.452694 -408.175206)
		(end 94.315534 -408.038046)
		(width 0.14224)
		(layer "In15.Cu")
		(net "P5E_CPU1_P0_RX_BUF_DP<15>")
	)
	(segment
		(start 65.357502 -393.129008)
		(end 65.496948 -392.989562)
		(width 0.14224)
		(layer "In15.Cu")
		(net "P5E_CPU1_P0_RX_BUF_DP<15>")
	)
	(segment
		(start 70.719696 -395.221206)
		(end 68.129404 -394.964158)
		(width 0.14224)
		(layer "In15.Cu")
		(net "P5E_CPU1_P0_RX_BUF_DP<15>")
	)
	(segment
		(start 93.112844 -405.574754)
		(end 93.041216 -405.545036)
		(width 0.14224)
		(layer "In15.Cu")
		(net "P5E_CPU1_P0_RX_BUF_DP<15>")
	)
	(segment
		(start 65.357502 -393.848844)
		(end 65.357502 -393.129008)
		(width 0.14224)
		(layer "In15.Cu")
		(net "P5E_CPU1_P0_RX_BUF_DP<15>")
	)
	(segment
		(start 94.315534 -410.574744)
		(end 94.315534 -408.739086)
		(width 0.14224)
		(layer "In15.Cu")
		(net "P5E_CPU1_P0_RX_BUF_DP<15>")
	)
	(segment
		(start 71.294752 -395.140434)
		(end 70.86981 -395.09827)
		(width 0.14224)
		(layer "In15.Cu")
		(net "P5E_CPU1_P0_RX_BUF_DP<15>")
	)
	(segment
		(start 65.496948 -392.989562)
		(end 65.677034 -392.989562)
		(width 0.14224)
		(layer "In15.Cu")
		(net "P5E_CPU1_P0_RX_BUF_DP<15>")
	)
	(segment
		(start 73.475088 -395.356842)
		(end 73.324974 -395.479778)
		(width 0.14224)
		(layer "In15.Cu")
		(net "P5E_CPU1_P0_RX_BUF_DP<15>")
	)
	(segment
		(start 89.650062 -438.191148)
		(end 89.499948 -438.341262)
		(width 0.14224)
		(layer "In15.Cu")
		(net "P5E_CPU1_P0_RX_BUF_DP<15>")
	)
	(segment
		(start 92.011246 -402.50872)
		(end 85.36305 -398.066006)
		(width 0.14224)
		(layer "In15.Cu")
		(net "P5E_CPU1_P0_RX_BUF_DP<15>")
	)
	(segment
		(start 78.075282 -395.989302)
		(end 77.656436 -395.90599)
		(width 0.14224)
		(layer "In15.Cu")
		(net "P5E_CPU1_P0_RX_BUF_DP<15>")
	)
	(segment
		(start 85.36305 -398.066006)
		(end 85.325204 -397.87576)
		(width 0.14224)
		(layer "In15.Cu")
		(net "P5E_CPU1_P0_RX_BUF_DP<15>")
	)
	(segment
		(start 89.499948 -438.341262)
		(end 89.108534 -438.341262)
		(width 0.14224)
		(layer "In15.Cu")
		(net "P5E_CPU1_P0_RX_BUF_DP<15>")
	)
	(segment
		(start 95.847154 -411.947614)
		(end 95.76435 -411.747716)
		(width 0.14224)
		(layer "In15.Cu")
		(net "P5E_CPU1_P0_RX_BUF_DP<15>")
	)
	(segment
		(start 78.182978 -396.150846)
		(end 78.075282 -395.989302)
		(width 0.14224)
		(layer "In15.Cu")
		(net "P5E_CPU1_P0_RX_BUF_DP<15>")
	)
	(segment
		(start 93.041216 -405.545036)
		(end 92.856558 -405.360378)
		(width 0.14224)
		(layer "In15.Cu")
		(net "P5E_CPU1_P0_RX_BUF_DP<15>")
	)
	(segment
		(start 92.783914 -405.185118)
		(end 92.783914 -403.869398)
		(width 0.14224)
		(layer "In15.Cu")
		(net "P5E_CPU1_P0_RX_BUF_DP<15>")
	)
	(segment
		(start 85.325204 -397.87576)
		(end 84.970112 -397.638524)
		(width 0.14224)
		(layer "In15.Cu")
		(net "P5E_CPU1_P0_RX_BUF_DP<15>")
	)
	(segment
		(start 89.650062 -437.889904)
		(end 89.650062 -438.191148)
		(width 0.14224)
		(layer "In15.Cu")
		(net "P5E_CPU1_P0_RX_BUF_DP<15>")
	)
	(segment
		(start 81.202276 -396.751556)
		(end 81.09458 -396.590012)
		(width 0.14224)
		(layer "In15.Cu")
		(net "P5E_CPU1_P0_RX_BUF_DP<15>")
	)
	(segment
		(start 95.268288 -411.251654)
		(end 94.613222 -410.980382)
		(width 0.14224)
		(layer "In15.Cu")
		(net "P5E_CPU1_P0_RX_BUF_DP<15>")
	)
	(segment
		(start 93.625162 -405.574754)
		(end 93.112844 -405.574754)
		(width 0.14224)
		(layer "In15.Cu")
		(net "P5E_CPU1_P0_RX_BUF_DP<15>")
	)
	(segment
		(start 79.380842 -396.389098)
		(end 79.272892 -396.227554)
		(width 0.14224)
		(layer "In15.Cu")
		(net "P5E_CPU1_P0_RX_BUF_DP<15>")
	)
	(arc
		(start 92.783914 -403.869398)
		(mid 92.77766 -403.806467)
		(end 92.759276 -403.745954)
		(width 0.14224)
		(layer "In15.Cu")
		(net "P5E_CPU1_P0_RX_BUF_DP<15>")
	)
	(arc
		(start 65.644776 -394.350748)
		(mid 65.585484 -394.326806)
		(end 65.535048 -394.287502)
		(width 0.14224)
		(layer "In15.Cu")
		(net "P5E_CPU1_P0_RX_BUF_DP<15>")
	)
	(arc
		(start 88.976708 -424.56989)
		(mid 89.056046 -424.033635)
		(end 89.287604 -423.543476)
		(width 0.14224)
		(layer "In15.Cu")
		(net "P5E_CPU1_P0_RX_BUF_DP<15>")
	)
	(arc
		(start 76.364084 -395.788896)
		(mid 76.288034 -395.775725)
		(end 76.21143 -395.76629)
		(width 0.14224)
		(layer "In15.Cu")
		(net "P5E_CPU1_P0_RX_BUF_DP<15>")
	)
	(arc
		(start 65.535048 -394.287502)
		(mid 65.403532 -394.085481)
		(end 65.357502 -393.848844)
		(width 0.14224)
		(layer "In15.Cu")
		(net "P5E_CPU1_P0_RX_BUF_DP<15>")
	)
	(arc
		(start 84.425282 -397.439388)
		(mid 84.320737 -397.383719)
		(end 84.20735 -397.349472)
		(width 0.14224)
		(layer "In15.Cu")
		(net "P5E_CPU1_P0_RX_BUF_DP<15>")
	)
	(arc
		(start 68.129404 -394.964158)
		(mid 68.087232 -394.958435)
		(end 68.045584 -394.94968)
		(width 0.14224)
		(layer "In15.Cu")
		(net "P5E_CPU1_P0_RX_BUF_DP<15>")
	)
	(arc
		(start 92.447364 -402.993098)
		(mid 92.391473 -402.888035)
		(end 92.316046 -402.795994)
		(width 0.14224)
		(layer "In15.Cu")
		(net "P5E_CPU1_P0_RX_BUF_DP<15>")
	)
	(arc
		(start 92.108782 -402.58873)
		(mid 92.06197 -402.546341)
		(end 92.011246 -402.50872)
		(width 0.14224)
		(layer "In15.Cu")
		(net "P5E_CPU1_P0_RX_BUF_DP<15>")
	)
	(segment
		(start 63.91402 -391.577322)
		(end 63.91402 -392.723878)
		(width 0.1016)
		(layer "F.Cu")
		(net "P5E_CPU1_P0_RX_BUF_DP<14>")
	)
	(segment
		(start 64.167258 -392.977116)
		(end 64.459866 -392.977116)
		(width 0.1016)
		(layer "F.Cu")
		(net "P5E_CPU1_P0_RX_BUF_DP<14>")
	)
	(segment
		(start 63.91402 -392.723878)
		(end 64.167258 -392.977116)
		(width 0.1016)
		(layer "F.Cu")
		(net "P5E_CPU1_P0_RX_BUF_DP<14>")
	)
	(segment
		(start 64.616584 -393.133834)
		(end 64.616584 -393.292838)
		(width 0.1016)
		(layer "F.Cu")
		(net "P5E_CPU1_P0_RX_BUF_DP<14>")
	)
	(segment
		(start 64.459866 -392.977116)
		(end 64.616584 -393.133834)
		(width 0.1016)
		(layer "F.Cu")
		(net "P5E_CPU1_P0_RX_BUF_DP<14>")
	)
	(segment
		(start 63.918084 -391.281158)
		(end 64.002666 -391.36574)
		(width 0.1016)
		(layer "F.Cu")
		(net "P5E_CPU1_P0_RX_BUF_DP<14>")
	)
	(segment
		(start 64.002666 -391.488676)
		(end 63.91402 -391.577322)
		(width 0.1016)
		(layer "F.Cu")
		(net "P5E_CPU1_P0_RX_BUF_DP<14>")
	)
	(segment
		(start 64.002666 -391.36574)
		(end 64.002666 -391.488676)
		(width 0.1016)
		(layer "F.Cu")
		(net "P5E_CPU1_P0_RX_BUF_DP<14>")
	)
	(segment
		(start 90.937334 -416.754818)
		(end 91.124532 -416.703002)
		(width 0.14224)
		(layer "In15.Cu")
		(net "P5E_CPU1_P0_RX_BUF_DP<14>")
	)
	(segment
		(start 79.408274 -397.575532)
		(end 79.252318 -397.691102)
		(width 0.14224)
		(layer "In15.Cu")
		(net "P5E_CPU1_P0_RX_BUF_DP<14>")
	)
	(segment
		(start 87.108538 -437.341264)
		(end 86.976458 -437.209184)
		(width 0.14224)
		(layer "In15.Cu")
		(net "P5E_CPU1_P0_RX_BUF_DP<14>")
	)
	(segment
		(start 89.720674 -405.185118)
		(end 89.720674 -403.865588)
		(width 0.14224)
		(layer "In15.Cu")
		(net "P5E_CPU1_P0_RX_BUF_DP<14>")
	)
	(segment
		(start 83.326732 -399.02511)
		(end 80.74787 -397.938498)
		(width 0.14224)
		(layer "In15.Cu")
		(net "P5E_CPU1_P0_RX_BUF_DP<14>")
	)
	(segment
		(start 89.720674 -403.865588)
		(end 89.610438 -403.599396)
		(width 0.14224)
		(layer "In15.Cu")
		(net "P5E_CPU1_P0_RX_BUF_DP<14>")
	)
	(segment
		(start 73.047098 -396.769844)
		(end 72.137016 -396.63497)
		(width 0.14224)
		(layer "In15.Cu")
		(net "P5E_CPU1_P0_RX_BUF_DP<14>")
	)
	(segment
		(start 79.906114 -397.740632)
		(end 79.830422 -397.63827)
		(width 0.14224)
		(layer "In15.Cu")
		(net "P5E_CPU1_P0_RX_BUF_DP<14>")
	)
	(segment
		(start 92.385388 -414.198562)
		(end 92.783914 -413.494982)
		(width 0.14224)
		(layer "In15.Cu")
		(net "P5E_CPU1_P0_RX_BUF_DP<14>")
	)
	(segment
		(start 64.616584 -393.129008)
		(end 64.616584 -393.292838)
		(width 0.14224)
		(layer "In15.Cu")
		(net "P5E_CPU1_P0_RX_BUF_DP<14>")
	)
	(segment
		(start 91.06789 -405.979884)
		(end 90.734134 -405.646128)
		(width 0.14224)
		(layer "In15.Cu")
		(net "P5E_CPU1_P0_RX_BUF_DP<14>")
	)
	(segment
		(start 87.650066 -437.19115)
		(end 87.499952 -437.341264)
		(width 0.14224)
		(layer "In15.Cu")
		(net "P5E_CPU1_P0_RX_BUF_DP<14>")
	)
	(segment
		(start 91.470988 -410.92755)
		(end 91.34729 -410.803852)
		(width 0.14224)
		(layer "In15.Cu")
		(net "P5E_CPU1_P0_RX_BUF_DP<14>")
	)
	(segment
		(start 79.252318 -397.691102)
		(end 78.210156 -397.53667)
		(width 0.14224)
		(layer "In15.Cu")
		(net "P5E_CPU1_P0_RX_BUF_DP<14>")
	)
	(segment
		(start 92.783914 -413.494982)
		(end 92.783914 -411.980634)
		(width 0.14224)
		(layer "In15.Cu")
		(net "P5E_CPU1_P0_RX_BUF_DP<14>")
	)
	(segment
		(start 88.562942 -402.33854)
		(end 88.563196 -402.338286)
		(width 0.14224)
		(layer "In15.Cu")
		(net "P5E_CPU1_P0_RX_BUF_DP<14>")
	)
	(segment
		(start 91.389454 -408.819096)
		(end 91.252294 -408.681936)
		(width 0.14224)
		(layer "In15.Cu")
		(net "P5E_CPU1_P0_RX_BUF_DP<14>")
	)
	(segment
		(start 91.252294 -407.554176)
		(end 91.252294 -406.424892)
		(width 0.14224)
		(layer "In15.Cu")
		(net "P5E_CPU1_P0_RX_BUF_DP<14>")
	)
	(segment
		(start 88.561926 -402.33727)
		(end 87.159592 -401.256754)
		(width 0.14224)
		(layer "In15.Cu")
		(net "P5E_CPU1_P0_RX_BUF_DP<14>")
	)
	(segment
		(start 91.252294 -410.574744)
		(end 91.252294 -409.382976)
		(width 0.14224)
		(layer "In15.Cu")
		(net "P5E_CPU1_P0_RX_BUF_DP<14>")
	)
	(segment
		(start 92.226892 -414.757108)
		(end 92.437204 -414.385506)
		(width 0.14224)
		(layer "In15.Cu")
		(net "P5E_CPU1_P0_RX_BUF_DP<14>")
	)
	(segment
		(start 87.499952 -437.341264)
		(end 87.108538 -437.341264)
		(width 0.14224)
		(layer "In15.Cu")
		(net "P5E_CPU1_P0_RX_BUF_DP<14>")
	)
	(segment
		(start 64.157606 -394.386308)
		(end 64.157606 -393.129008)
		(width 0.14224)
		(layer "In15.Cu")
		(net "P5E_CPU1_P0_RX_BUF_DP<14>")
	)
	(segment
		(start 91.252294 -408.255216)
		(end 91.389454 -408.118056)
		(width 0.14224)
		(layer "In15.Cu")
		(net "P5E_CPU1_P0_RX_BUF_DP<14>")
	)
	(segment
		(start 72.137016 -396.63497)
		(end 72.021446 -396.47876)
		(width 0.14224)
		(layer "In15.Cu")
		(net "P5E_CPU1_P0_RX_BUF_DP<14>")
	)
	(segment
		(start 75.777852 -397.175482)
		(end 75.662282 -397.019526)
		(width 0.14224)
		(layer "In15.Cu")
		(net "P5E_CPU1_P0_RX_BUF_DP<14>")
	)
	(segment
		(start 68.601844 -396.155418)
		(end 67.977766 -396.031466)
		(width 0.14224)
		(layer "In15.Cu")
		(net "P5E_CPU1_P0_RX_BUF_DP<14>")
	)
	(segment
		(start 78.094586 -397.38046)
		(end 77.672184 -397.317976)
		(width 0.14224)
		(layer "In15.Cu")
		(net "P5E_CPU1_P0_RX_BUF_DP<14>")
	)
	(segment
		(start 90.734134 -405.646128)
		(end 90.561922 -405.574754)
		(width 0.14224)
		(layer "In15.Cu")
		(net "P5E_CPU1_P0_RX_BUF_DP<14>")
	)
	(segment
		(start 73.625202 -396.717012)
		(end 73.2028 -396.654274)
		(width 0.14224)
		(layer "In15.Cu")
		(net "P5E_CPU1_P0_RX_BUF_DP<14>")
	)
	(segment
		(start 89.189814 -402.988526)
		(end 88.688672 -402.452586)
		(width 0.14224)
		(layer "In15.Cu")
		(net "P5E_CPU1_P0_RX_BUF_DP<14>")
	)
	(segment
		(start 89.793318 -405.360378)
		(end 89.720674 -405.185118)
		(width 0.14224)
		(layer "In15.Cu")
		(net "P5E_CPU1_P0_RX_BUF_DP<14>")
	)
	(segment
		(start 77.516482 -397.433546)
		(end 75.777852 -397.175482)
		(width 0.14224)
		(layer "In15.Cu")
		(net "P5E_CPU1_P0_RX_BUF_DP<14>")
	)
	(segment
		(start 64.157606 -393.129008)
		(end 64.297052 -392.989562)
		(width 0.14224)
		(layer "In15.Cu")
		(net "P5E_CPU1_P0_RX_BUF_DP<14>")
	)
	(segment
		(start 92.458286 -411.356556)
		(end 91.549982 -410.980382)
		(width 0.14224)
		(layer "In15.Cu")
		(net "P5E_CPU1_P0_RX_BUF_DP<14>")
	)
	(segment
		(start 91.283028 -416.144456)
		(end 92.039694 -414.80867)
		(width 0.14224)
		(layer "In15.Cu")
		(net "P5E_CPU1_P0_RX_BUF_DP<14>")
	)
	(segment
		(start 86.976458 -437.209184)
		(end 86.976458 -424.54957)
		(width 0.14224)
		(layer "In15.Cu")
		(net "P5E_CPU1_P0_RX_BUF_DP<14>")
	)
	(segment
		(start 91.389454 -409.245816)
		(end 91.389454 -408.819096)
		(width 0.14224)
		(layer "In15.Cu")
		(net "P5E_CPU1_P0_RX_BUF_DP<14>")
	)
	(segment
		(start 78.210156 -397.53667)
		(end 78.094586 -397.38046)
		(width 0.14224)
		(layer "In15.Cu")
		(net "P5E_CPU1_P0_RX_BUF_DP<14>")
	)
	(segment
		(start 89.610438 -403.599396)
		(end 89.268554 -403.08784)
		(width 0.14224)
		(layer "In15.Cu")
		(net "P5E_CPU1_P0_RX_BUF_DP<14>")
	)
	(segment
		(start 67.85483 -396.000732)
		(end 64.600582 -395.01318)
		(width 0.14224)
		(layer "In15.Cu")
		(net "P5E_CPU1_P0_RX_BUF_DP<14>")
	)
	(segment
		(start 80.558132 -397.885412)
		(end 80.012032 -397.804132)
		(width 0.14224)
		(layer "In15.Cu")
		(net "P5E_CPU1_P0_RX_BUF_DP<14>")
	)
	(segment
		(start 75.240134 -396.956788)
		(end 75.084178 -397.072358)
		(width 0.14224)
		(layer "In15.Cu")
		(net "P5E_CPU1_P0_RX_BUF_DP<14>")
	)
	(segment
		(start 64.477138 -392.989562)
		(end 64.616584 -393.129008)
		(width 0.14224)
		(layer "In15.Cu")
		(net "P5E_CPU1_P0_RX_BUF_DP<14>")
	)
	(segment
		(start 91.334844 -416.3314)
		(end 91.283028 -416.144456)
		(width 0.14224)
		(layer "In15.Cu")
		(net "P5E_CPU1_P0_RX_BUF_DP<14>")
	)
	(segment
		(start 91.34729 -410.803852)
		(end 91.252294 -410.574744)
		(width 0.14224)
		(layer "In15.Cu")
		(net "P5E_CPU1_P0_RX_BUF_DP<14>")
	)
	(segment
		(start 91.252294 -409.382976)
		(end 91.389454 -409.245816)
		(width 0.14224)
		(layer "In15.Cu")
		(net "P5E_CPU1_P0_RX_BUF_DP<14>")
	)
	(segment
		(start 91.252294 -406.424892)
		(end 91.06789 -405.979884)
		(width 0.14224)
		(layer "In15.Cu")
		(net "P5E_CPU1_P0_RX_BUF_DP<14>")
	)
	(segment
		(start 87.650066 -436.889906)
		(end 87.650066 -437.19115)
		(width 0.14224)
		(layer "In15.Cu")
		(net "P5E_CPU1_P0_RX_BUF_DP<14>")
	)
	(segment
		(start 91.124532 -416.703002)
		(end 91.334844 -416.3314)
		(width 0.14224)
		(layer "In15.Cu")
		(net "P5E_CPU1_P0_RX_BUF_DP<14>")
	)
	(segment
		(start 87.05469 -401.186142)
		(end 83.472528 -399.098008)
		(width 0.14224)
		(layer "In15.Cu")
		(net "P5E_CPU1_P0_RX_BUF_DP<14>")
	)
	(segment
		(start 71.443342 -396.531846)
		(end 70.144386 -396.33906)
		(width 0.14224)
		(layer "In15.Cu")
		(net "P5E_CPU1_P0_RX_BUF_DP<14>")
	)
	(segment
		(start 91.549982 -410.980382)
		(end 91.470988 -410.92755)
		(width 0.14224)
		(layer "In15.Cu")
		(net "P5E_CPU1_P0_RX_BUF_DP<14>")
	)
	(segment
		(start 75.084178 -397.072358)
		(end 73.740772 -396.872968)
		(width 0.14224)
		(layer "In15.Cu")
		(net "P5E_CPU1_P0_RX_BUF_DP<14>")
	)
	(segment
		(start 79.830422 -397.63827)
		(end 79.408274 -397.575532)
		(width 0.14224)
		(layer "In15.Cu")
		(net "P5E_CPU1_P0_RX_BUF_DP<14>")
	)
	(segment
		(start 91.389454 -407.691336)
		(end 91.252294 -407.554176)
		(width 0.14224)
		(layer "In15.Cu")
		(net "P5E_CPU1_P0_RX_BUF_DP<14>")
	)
	(segment
		(start 90.561922 -405.574754)
		(end 90.049604 -405.574754)
		(width 0.14224)
		(layer "In15.Cu")
		(net "P5E_CPU1_P0_RX_BUF_DP<14>")
	)
	(segment
		(start 71.599044 -396.416276)
		(end 71.443342 -396.531846)
		(width 0.14224)
		(layer "In15.Cu")
		(net "P5E_CPU1_P0_RX_BUF_DP<14>")
	)
	(segment
		(start 73.740772 -396.872968)
		(end 73.625202 -396.717012)
		(width 0.14224)
		(layer "In15.Cu")
		(net "P5E_CPU1_P0_RX_BUF_DP<14>")
	)
	(segment
		(start 73.2028 -396.654274)
		(end 73.047098 -396.769844)
		(width 0.14224)
		(layer "In15.Cu")
		(net "P5E_CPU1_P0_RX_BUF_DP<14>")
	)
	(segment
		(start 91.252294 -408.681936)
		(end 91.252294 -408.255216)
		(width 0.14224)
		(layer "In15.Cu")
		(net "P5E_CPU1_P0_RX_BUF_DP<14>")
	)
	(segment
		(start 64.297052 -392.989562)
		(end 64.477138 -392.989562)
		(width 0.14224)
		(layer "In15.Cu")
		(net "P5E_CPU1_P0_RX_BUF_DP<14>")
	)
	(segment
		(start 69.078094 -396.207234)
		(end 68.699888 -396.169896)
		(width 0.14224)
		(layer "In15.Cu")
		(net "P5E_CPU1_P0_RX_BUF_DP<14>")
	)
	(segment
		(start 72.021446 -396.47876)
		(end 71.599044 -396.416276)
		(width 0.14224)
		(layer "In15.Cu")
		(net "P5E_CPU1_P0_RX_BUF_DP<14>")
	)
	(segment
		(start 91.389454 -408.118056)
		(end 91.389454 -407.691336)
		(width 0.14224)
		(layer "In15.Cu")
		(net "P5E_CPU1_P0_RX_BUF_DP<14>")
	)
	(segment
		(start 92.437204 -414.385506)
		(end 92.385388 -414.198562)
		(width 0.14224)
		(layer "In15.Cu")
		(net "P5E_CPU1_P0_RX_BUF_DP<14>")
	)
	(segment
		(start 89.977976 -405.545036)
		(end 89.793318 -405.360378)
		(width 0.14224)
		(layer "In15.Cu")
		(net "P5E_CPU1_P0_RX_BUF_DP<14>")
	)
	(segment
		(start 90.049604 -405.574754)
		(end 89.977976 -405.545036)
		(width 0.14224)
		(layer "In15.Cu")
		(net "P5E_CPU1_P0_RX_BUF_DP<14>")
	)
	(segment
		(start 92.039694 -414.80867)
		(end 92.226892 -414.757108)
		(width 0.14224)
		(layer "In15.Cu")
		(net "P5E_CPU1_P0_RX_BUF_DP<14>")
	)
	(segment
		(start 75.662282 -397.019526)
		(end 75.240134 -396.956788)
		(width 0.14224)
		(layer "In15.Cu")
		(net "P5E_CPU1_P0_RX_BUF_DP<14>")
	)
	(segment
		(start 87.37219 -423.048176)
		(end 90.937334 -416.754818)
		(width 0.14224)
		(layer "In15.Cu")
		(net "P5E_CPU1_P0_RX_BUF_DP<14>")
	)
	(segment
		(start 92.783914 -411.980634)
		(end 92.573094 -411.471364)
		(width 0.14224)
		(layer "In15.Cu")
		(net "P5E_CPU1_P0_RX_BUF_DP<14>")
	)
	(segment
		(start 77.672184 -397.317976)
		(end 77.516482 -397.433546)
		(width 0.14224)
		(layer "In15.Cu")
		(net "P5E_CPU1_P0_RX_BUF_DP<14>")
	)
	(segment
		(start 92.573094 -411.471364)
		(end 92.458286 -411.356556)
		(width 0.14224)
		(layer "In15.Cu")
		(net "P5E_CPU1_P0_RX_BUF_DP<14>")
	)
	(segment
		(start 88.563196 -402.338286)
		(end 88.561926 -402.33727)
		(width 0.14224)
		(layer "In15.Cu")
		(net "P5E_CPU1_P0_RX_BUF_DP<14>")
	)
	(arc
		(start 88.688672 -402.452586)
		(mid 88.628089 -402.393047)
		(end 88.562942 -402.33854)
		(width 0.14224)
		(layer "In15.Cu")
		(net "P5E_CPU1_P0_RX_BUF_DP<14>")
	)
	(arc
		(start 89.268554 -403.08784)
		(mid 89.231219 -403.036569)
		(end 89.189814 -402.988526)
		(width 0.14224)
		(layer "In15.Cu")
		(net "P5E_CPU1_P0_RX_BUF_DP<14>")
	)
	(arc
		(start 83.472528 -399.098008)
		(mid 83.400808 -399.059202)
		(end 83.326732 -399.02511)
		(width 0.14224)
		(layer "In15.Cu")
		(net "P5E_CPU1_P0_RX_BUF_DP<14>")
	)
	(arc
		(start 86.976458 -424.54957)
		(mid 87.077053 -423.773235)
		(end 87.37219 -423.048176)
		(width 0.14224)
		(layer "In15.Cu")
		(net "P5E_CPU1_P0_RX_BUF_DP<14>")
	)
	(arc
		(start 87.159592 -401.256754)
		(mid 87.108279 -401.219757)
		(end 87.05469 -401.186142)
		(width 0.14224)
		(layer "In15.Cu")
		(net "P5E_CPU1_P0_RX_BUF_DP<14>")
	)
	(arc
		(start 68.699888 -396.169896)
		(mid 68.650689 -396.163856)
		(end 68.601844 -396.155418)
		(width 0.14224)
		(layer "In15.Cu")
		(net "P5E_CPU1_P0_RX_BUF_DP<14>")
	)
	(arc
		(start 80.012032 -397.804132)
		(mid 79.95275 -397.782927)
		(end 79.906114 -397.740632)
		(width 0.14224)
		(layer "In15.Cu")
		(net "P5E_CPU1_P0_RX_BUF_DP<14>")
	)
	(arc
		(start 80.74787 -397.938498)
		(mid 80.654669 -397.905996)
		(end 80.558132 -397.885412)
		(width 0.14224)
		(layer "In15.Cu")
		(net "P5E_CPU1_P0_RX_BUF_DP<14>")
	)
	(arc
		(start 64.171322 -394.533374)
		(mid 64.161061 -394.460158)
		(end 64.157606 -394.386308)
		(width 0.14224)
		(layer "In15.Cu")
		(net "P5E_CPU1_P0_RX_BUF_DP<14>")
	)
	(arc
		(start 67.977766 -396.031466)
		(mid 67.915919 -396.017615)
		(end 67.85483 -396.000732)
		(width 0.14224)
		(layer "In15.Cu")
		(net "P5E_CPU1_P0_RX_BUF_DP<14>")
	)
	(arc
		(start 64.600582 -395.01318)
		(mid 64.31875 -394.833392)
		(end 64.171322 -394.533374)
		(width 0.14224)
		(layer "In15.Cu")
		(net "P5E_CPU1_P0_RX_BUF_DP<14>")
	)
	(arc
		(start 70.144386 -396.33906)
		(mid 69.612048 -396.266615)
		(end 69.078094 -396.207234)
		(width 0.14224)
		(layer "In15.Cu")
		(net "P5E_CPU1_P0_RX_BUF_DP<14>")
	)
	(segment
		(start 62.802516 -391.488676)
		(end 62.722506 -391.568686)
		(width 0.1016)
		(layer "F.Cu")
		(net "P5E_CPU1_P0_RX_BUF_DP<13>")
	)
	(segment
		(start 62.975744 -392.977116)
		(end 63.27775 -392.977116)
		(width 0.1016)
		(layer "F.Cu")
		(net "P5E_CPU1_P0_RX_BUF_DP<13>")
	)
	(segment
		(start 63.416434 -393.1158)
		(end 63.416434 -393.292838)
		(width 0.1016)
		(layer "F.Cu")
		(net "P5E_CPU1_P0_RX_BUF_DP<13>")
	)
	(segment
		(start 62.722506 -392.723878)
		(end 62.975744 -392.977116)
		(width 0.1016)
		(layer "F.Cu")
		(net "P5E_CPU1_P0_RX_BUF_DP<13>")
	)
	(segment
		(start 62.717934 -391.281158)
		(end 62.802516 -391.36574)
		(width 0.1016)
		(layer "F.Cu")
		(net "P5E_CPU1_P0_RX_BUF_DP<13>")
	)
	(segment
		(start 62.722506 -391.568686)
		(end 62.722506 -392.723878)
		(width 0.1016)
		(layer "F.Cu")
		(net "P5E_CPU1_P0_RX_BUF_DP<13>")
	)
	(segment
		(start 62.802516 -391.36574)
		(end 62.802516 -391.488676)
		(width 0.1016)
		(layer "F.Cu")
		(net "P5E_CPU1_P0_RX_BUF_DP<13>")
	)
	(segment
		(start 63.27775 -392.977116)
		(end 63.416434 -393.1158)
		(width 0.1016)
		(layer "F.Cu")
		(net "P5E_CPU1_P0_RX_BUF_DP<13>")
	)
	(segment
		(start 85.086952 -401.948142)
		(end 84.73186 -401.710652)
		(width 0.14224)
		(layer "In15.Cu")
		(net "P5E_CPU1_P0_RX_BUF_DP<13>")
	)
	(segment
		(start 85.65007 -438.191148)
		(end 85.499956 -438.341262)
		(width 0.14224)
		(layer "In15.Cu")
		(net "P5E_CPU1_P0_RX_BUF_DP<13>")
	)
	(segment
		(start 88.407748 -410.92755)
		(end 88.28405 -410.803852)
		(width 0.14224)
		(layer "In15.Cu")
		(net "P5E_CPU1_P0_RX_BUF_DP<13>")
	)
	(segment
		(start 83.397344 -400.818604)
		(end 83.042506 -400.581368)
		(width 0.14224)
		(layer "In15.Cu")
		(net "P5E_CPU1_P0_RX_BUF_DP<13>")
	)
	(segment
		(start 71.65848 -397.786098)
		(end 71.54291 -397.630142)
		(width 0.14224)
		(layer "In15.Cu")
		(net "P5E_CPU1_P0_RX_BUF_DP<13>")
	)
	(segment
		(start 88.189054 -406.424892)
		(end 88.00465 -405.979884)
		(width 0.14224)
		(layer "In15.Cu")
		(net "P5E_CPU1_P0_RX_BUF_DP<13>")
	)
	(segment
		(start 87.498682 -405.574754)
		(end 86.986364 -405.574754)
		(width 0.14224)
		(layer "In15.Cu")
		(net "P5E_CPU1_P0_RX_BUF_DP<13>")
	)
	(segment
		(start 86.986364 -405.574754)
		(end 86.914736 -405.545036)
		(width 0.14224)
		(layer "In15.Cu")
		(net "P5E_CPU1_P0_RX_BUF_DP<13>")
	)
	(segment
		(start 86.730078 -405.360378)
		(end 86.657434 -405.184864)
		(width 0.14224)
		(layer "In15.Cu")
		(net "P5E_CPU1_P0_RX_BUF_DP<13>")
	)
	(segment
		(start 82.85226 -400.619214)
		(end 82.379566 -400.303238)
		(width 0.14224)
		(layer "In15.Cu")
		(net "P5E_CPU1_P0_RX_BUF_DP<13>")
	)
	(segment
		(start 88.824562 -415.29889)
		(end 88.768428 -415.113216)
		(width 0.14224)
		(layer "In15.Cu")
		(net "P5E_CPU1_P0_RX_BUF_DP<13>")
	)
	(segment
		(start 62.957456 -393.129008)
		(end 63.096902 -392.989562)
		(width 0.14224)
		(layer "In15.Cu")
		(net "P5E_CPU1_P0_RX_BUF_DP<13>")
	)
	(segment
		(start 78.507336 -398.802098)
		(end 75.638914 -398.376648)
		(width 0.14224)
		(layer "In15.Cu")
		(net "P5E_CPU1_P0_RX_BUF_DP<13>")
	)
	(segment
		(start 75.100942 -398.157954)
		(end 74.94524 -398.273524)
		(width 0.14224)
		(layer "In15.Cu")
		(net "P5E_CPU1_P0_RX_BUF_DP<13>")
	)
	(segment
		(start 75.638914 -398.376648)
		(end 75.523344 -398.220692)
		(width 0.14224)
		(layer "In15.Cu")
		(net "P5E_CPU1_P0_RX_BUF_DP<13>")
	)
	(segment
		(start 89.186258 -414.622742)
		(end 89.387426 -414.246314)
		(width 0.14224)
		(layer "In15.Cu")
		(net "P5E_CPU1_P0_RX_BUF_DP<13>")
	)
	(segment
		(start 63.877444 -395.78661)
		(end 63.741808 -395.70533)
		(width 0.14224)
		(layer "In15.Cu")
		(net "P5E_CPU1_P0_RX_BUF_DP<13>")
	)
	(segment
		(start 88.768428 -415.113216)
		(end 89.00033 -414.67913)
		(width 0.14224)
		(layer "In15.Cu")
		(net "P5E_CPU1_P0_RX_BUF_DP<13>")
	)
	(segment
		(start 73.985374 -397.992346)
		(end 73.829672 -398.107916)
		(width 0.14224)
		(layer "In15.Cu")
		(net "P5E_CPU1_P0_RX_BUF_DP<13>")
	)
	(segment
		(start 70.199758 -397.56969)
		(end 66.387726 -396.69212)
		(width 0.14224)
		(layer "In15.Cu")
		(net "P5E_CPU1_P0_RX_BUF_DP<13>")
	)
	(segment
		(start 84.73186 -401.710652)
		(end 84.541614 -401.748498)
		(width 0.14224)
		(layer "In15.Cu")
		(net "P5E_CPU1_P0_RX_BUF_DP<13>")
	)
	(segment
		(start 86.657434 -405.184864)
		(end 86.657434 -403.589744)
		(width 0.14224)
		(layer "In15.Cu")
		(net "P5E_CPU1_P0_RX_BUF_DP<13>")
	)
	(segment
		(start 63.741808 -395.70533)
		(end 63.14313 -395.106398)
		(width 0.14224)
		(layer "In15.Cu")
		(net "P5E_CPU1_P0_RX_BUF_DP<13>")
	)
	(segment
		(start 75.523344 -398.220692)
		(end 75.100942 -398.157954)
		(width 0.14224)
		(layer "In15.Cu")
		(net "P5E_CPU1_P0_RX_BUF_DP<13>")
	)
	(segment
		(start 63.289434 -392.989562)
		(end 63.416434 -393.116562)
		(width 0.14224)
		(layer "In15.Cu")
		(net "P5E_CPU1_P0_RX_BUF_DP<13>")
	)
	(segment
		(start 85.303614 -422.243758)
		(end 85.62594 -421.465756)
		(width 0.14224)
		(layer "In15.Cu")
		(net "P5E_CPU1_P0_RX_BUF_DP<13>")
	)
	(segment
		(start 85.944964 -402.68652)
		(end 85.124798 -402.138388)
		(width 0.14224)
		(layer "In15.Cu")
		(net "P5E_CPU1_P0_RX_BUF_DP<13>")
	)
	(segment
		(start 85.499956 -438.341262)
		(end 85.113368 -438.341262)
		(width 0.14224)
		(layer "In15.Cu")
		(net "P5E_CPU1_P0_RX_BUF_DP<13>")
	)
	(segment
		(start 88.29294 -416.293554)
		(end 88.236552 -416.10788)
		(width 0.14224)
		(layer "In15.Cu")
		(net "P5E_CPU1_P0_RX_BUF_DP<13>")
	)
	(segment
		(start 88.091772 -416.670236)
		(end 88.29294 -416.293554)
		(width 0.14224)
		(layer "In15.Cu")
		(net "P5E_CPU1_P0_RX_BUF_DP<13>")
	)
	(segment
		(start 85.62594 -421.465756)
		(end 85.626448 -421.465502)
		(width 0.14224)
		(layer "In15.Cu")
		(net "P5E_CPU1_P0_RX_BUF_DP<13>")
	)
	(segment
		(start 88.28405 -410.803852)
		(end 88.189054 -410.574744)
		(width 0.14224)
		(layer "In15.Cu")
		(net "P5E_CPU1_P0_RX_BUF_DP<13>")
	)
	(segment
		(start 82.379566 -400.303238)
		(end 80.011524 -399.218404)
		(width 0.14224)
		(layer "In15.Cu")
		(net "P5E_CPU1_P0_RX_BUF_DP<13>")
	)
	(segment
		(start 88.437466 -415.731706)
		(end 88.623394 -415.675318)
		(width 0.14224)
		(layer "In15.Cu")
		(net "P5E_CPU1_P0_RX_BUF_DP<13>")
	)
	(segment
		(start 80.011524 -399.218404)
		(end 78.507336 -398.802098)
		(width 0.14224)
		(layer "In15.Cu")
		(net "P5E_CPU1_P0_RX_BUF_DP<13>")
	)
	(segment
		(start 88.00465 -405.979884)
		(end 87.670894 -405.646128)
		(width 0.14224)
		(layer "In15.Cu")
		(net "P5E_CPU1_P0_RX_BUF_DP<13>")
	)
	(segment
		(start 63.416434 -393.116562)
		(end 63.416434 -393.292838)
		(width 0.14224)
		(layer "In15.Cu")
		(net "P5E_CPU1_P0_RX_BUF_DP<13>")
	)
	(segment
		(start 83.042506 -400.581368)
		(end 82.85226 -400.619214)
		(width 0.14224)
		(layer "In15.Cu")
		(net "P5E_CPU1_P0_RX_BUF_DP<13>")
	)
	(segment
		(start 88.486742 -410.980382)
		(end 88.407748 -410.92755)
		(width 0.14224)
		(layer "In15.Cu")
		(net "P5E_CPU1_P0_RX_BUF_DP<13>")
	)
	(segment
		(start 85.65007 -437.889904)
		(end 85.65007 -438.191148)
		(width 0.14224)
		(layer "In15.Cu")
		(net "P5E_CPU1_P0_RX_BUF_DP<13>")
	)
	(segment
		(start 87.905844 -416.72637)
		(end 88.091772 -416.670236)
		(width 0.14224)
		(layer "In15.Cu")
		(net "P5E_CPU1_P0_RX_BUF_DP<13>")
	)
	(segment
		(start 65.460372 -396.272258)
		(end 63.877444 -395.78661)
		(width 0.14224)
		(layer "In15.Cu")
		(net "P5E_CPU1_P0_RX_BUF_DP<13>")
	)
	(segment
		(start 74.94524 -398.273524)
		(end 74.523346 -398.21104)
		(width 0.14224)
		(layer "In15.Cu")
		(net "P5E_CPU1_P0_RX_BUF_DP<13>")
	)
	(segment
		(start 89.395046 -411.356556)
		(end 88.486742 -410.980382)
		(width 0.14224)
		(layer "In15.Cu")
		(net "P5E_CPU1_P0_RX_BUF_DP<13>")
	)
	(segment
		(start 85.124798 -402.138388)
		(end 85.086952 -401.948142)
		(width 0.14224)
		(layer "In15.Cu")
		(net "P5E_CPU1_P0_RX_BUF_DP<13>")
	)
	(segment
		(start 86.914736 -405.545036)
		(end 86.730078 -405.360378)
		(width 0.14224)
		(layer "In15.Cu")
		(net "P5E_CPU1_P0_RX_BUF_DP<13>")
	)
	(segment
		(start 73.829672 -398.107916)
		(end 71.65848 -397.786098)
		(width 0.14224)
		(layer "In15.Cu")
		(net "P5E_CPU1_P0_RX_BUF_DP<13>")
	)
	(segment
		(start 62.957456 -394.658342)
		(end 62.957456 -393.129008)
		(width 0.14224)
		(layer "In15.Cu")
		(net "P5E_CPU1_P0_RX_BUF_DP<13>")
	)
	(segment
		(start 74.407776 -398.055084)
		(end 73.985374 -397.992346)
		(width 0.14224)
		(layer "In15.Cu")
		(net "P5E_CPU1_P0_RX_BUF_DP<13>")
	)
	(segment
		(start 89.720674 -413.331406)
		(end 89.720674 -411.947614)
		(width 0.14224)
		(layer "In15.Cu")
		(net "P5E_CPU1_P0_RX_BUF_DP<13>")
	)
	(segment
		(start 89.00033 -414.67913)
		(end 89.186258 -414.622742)
		(width 0.14224)
		(layer "In15.Cu")
		(net "P5E_CPU1_P0_RX_BUF_DP<13>")
	)
	(segment
		(start 71.54291 -397.630142)
		(end 71.120762 -397.567404)
		(width 0.14224)
		(layer "In15.Cu")
		(net "P5E_CPU1_P0_RX_BUF_DP<13>")
	)
	(segment
		(start 83.43519 -401.009104)
		(end 83.397344 -400.818604)
		(width 0.14224)
		(layer "In15.Cu")
		(net "P5E_CPU1_P0_RX_BUF_DP<13>")
	)
	(segment
		(start 70.964806 -397.682974)
		(end 70.199758 -397.56969)
		(width 0.14224)
		(layer "In15.Cu")
		(net "P5E_CPU1_P0_RX_BUF_DP<13>")
	)
	(segment
		(start 65.800732 -396.406624)
		(end 65.460372 -396.272258)
		(width 0.14224)
		(layer "In15.Cu")
		(net "P5E_CPU1_P0_RX_BUF_DP<13>")
	)
	(segment
		(start 84.541614 -401.748498)
		(end 83.43519 -401.009104)
		(width 0.14224)
		(layer "In15.Cu")
		(net "P5E_CPU1_P0_RX_BUF_DP<13>")
	)
	(segment
		(start 84.976462 -423.888662)
		(end 84.976716 -423.888916)
		(width 0.14224)
		(layer "In15.Cu")
		(net "P5E_CPU1_P0_RX_BUF_DP<13>")
	)
	(segment
		(start 74.523346 -398.21104)
		(end 74.407776 -398.055084)
		(width 0.14224)
		(layer "In15.Cu")
		(net "P5E_CPU1_P0_RX_BUF_DP<13>")
	)
	(segment
		(start 87.670894 -405.646128)
		(end 87.498682 -405.574754)
		(width 0.14224)
		(layer "In15.Cu")
		(net "P5E_CPU1_P0_RX_BUF_DP<13>")
	)
	(segment
		(start 89.720674 -411.947614)
		(end 89.533222 -411.494732)
		(width 0.14224)
		(layer "In15.Cu")
		(net "P5E_CPU1_P0_RX_BUF_DP<13>")
	)
	(segment
		(start 88.623394 -415.675318)
		(end 88.824562 -415.29889)
		(width 0.14224)
		(layer "In15.Cu")
		(net "P5E_CPU1_P0_RX_BUF_DP<13>")
	)
	(segment
		(start 66.387726 -396.69212)
		(end 65.800732 -396.406624)
		(width 0.14224)
		(layer "In15.Cu")
		(net "P5E_CPU1_P0_RX_BUF_DP<13>")
	)
	(segment
		(start 88.236552 -416.10788)
		(end 88.437466 -415.731706)
		(width 0.14224)
		(layer "In15.Cu")
		(net "P5E_CPU1_P0_RX_BUF_DP<13>")
	)
	(segment
		(start 85.113368 -438.341262)
		(end 84.976462 -438.204356)
		(width 0.14224)
		(layer "In15.Cu")
		(net "P5E_CPU1_P0_RX_BUF_DP<13>")
	)
	(segment
		(start 89.331038 -414.06064)
		(end 89.720674 -413.331406)
		(width 0.14224)
		(layer "In15.Cu")
		(net "P5E_CPU1_P0_RX_BUF_DP<13>")
	)
	(segment
		(start 86.52256 -403.264116)
		(end 85.944964 -402.68652)
		(width 0.14224)
		(layer "In15.Cu")
		(net "P5E_CPU1_P0_RX_BUF_DP<13>")
	)
	(segment
		(start 86.49843 -419.359334)
		(end 87.905844 -416.72637)
		(width 0.14224)
		(layer "In15.Cu")
		(net "P5E_CPU1_P0_RX_BUF_DP<13>")
	)
	(segment
		(start 89.533222 -411.494732)
		(end 89.395046 -411.356556)
		(width 0.14224)
		(layer "In15.Cu")
		(net "P5E_CPU1_P0_RX_BUF_DP<13>")
	)
	(segment
		(start 71.120762 -397.567404)
		(end 70.964806 -397.682974)
		(width 0.14224)
		(layer "In15.Cu")
		(net "P5E_CPU1_P0_RX_BUF_DP<13>")
	)
	(segment
		(start 84.976462 -438.204356)
		(end 84.976462 -423.888662)
		(width 0.14224)
		(layer "In15.Cu")
		(net "P5E_CPU1_P0_RX_BUF_DP<13>")
	)
	(segment
		(start 85.626448 -421.465502)
		(end 86.49843 -419.359334)
		(width 0.14224)
		(layer "In15.Cu")
		(net "P5E_CPU1_P0_RX_BUF_DP<13>")
	)
	(segment
		(start 88.189054 -410.574744)
		(end 88.189054 -406.424892)
		(width 0.14224)
		(layer "In15.Cu")
		(net "P5E_CPU1_P0_RX_BUF_DP<13>")
	)
	(segment
		(start 63.096902 -392.989562)
		(end 63.289434 -392.989562)
		(width 0.14224)
		(layer "In15.Cu")
		(net "P5E_CPU1_P0_RX_BUF_DP<13>")
	)
	(segment
		(start 89.387426 -414.246314)
		(end 89.331038 -414.06064)
		(width 0.14224)
		(layer "In15.Cu")
		(net "P5E_CPU1_P0_RX_BUF_DP<13>")
	)
	(arc
		(start 86.657434 -403.589744)
		(mid 86.62238 -403.413518)
		(end 86.52256 -403.264116)
		(width 0.14224)
		(layer "In15.Cu")
		(net "P5E_CPU1_P0_RX_BUF_DP<13>")
	)
	(arc
		(start 63.14313 -395.106398)
		(mid 63.005719 -394.900842)
		(end 62.957456 -394.658342)
		(width 0.14224)
		(layer "In15.Cu")
		(net "P5E_CPU1_P0_RX_BUF_DP<13>")
	)
	(arc
		(start 84.976716 -423.888916)
		(mid 85.059136 -423.050237)
		(end 85.303614 -422.243758)
		(width 0.14224)
		(layer "In15.Cu")
		(net "P5E_CPU1_P0_RX_BUF_DP<13>")
	)
	(segment
		(start 61.513974 -391.577322)
		(end 61.513974 -392.723878)
		(width 0.1016)
		(layer "F.Cu")
		(net "P5E_CPU1_P0_RX_BUF_DP<12>")
	)
	(segment
		(start 62.216538 -393.119102)
		(end 62.216538 -393.292838)
		(width 0.1016)
		(layer "F.Cu")
		(net "P5E_CPU1_P0_RX_BUF_DP<12>")
	)
	(segment
		(start 62.074552 -392.977116)
		(end 62.216538 -393.119102)
		(width 0.1016)
		(layer "F.Cu")
		(net "P5E_CPU1_P0_RX_BUF_DP<12>")
	)
	(segment
		(start 61.518038 -391.281158)
		(end 61.60262 -391.36574)
		(width 0.1016)
		(layer "F.Cu")
		(net "P5E_CPU1_P0_RX_BUF_DP<12>")
	)
	(segment
		(start 61.767212 -392.977116)
		(end 62.074552 -392.977116)
		(width 0.1016)
		(layer "F.Cu")
		(net "P5E_CPU1_P0_RX_BUF_DP<12>")
	)
	(segment
		(start 61.60262 -391.488676)
		(end 61.513974 -391.577322)
		(width 0.1016)
		(layer "F.Cu")
		(net "P5E_CPU1_P0_RX_BUF_DP<12>")
	)
	(segment
		(start 61.60262 -391.36574)
		(end 61.60262 -391.488676)
		(width 0.1016)
		(layer "F.Cu")
		(net "P5E_CPU1_P0_RX_BUF_DP<12>")
	)
	(segment
		(start 61.513974 -392.723878)
		(end 61.767212 -392.977116)
		(width 0.1016)
		(layer "F.Cu")
		(net "P5E_CPU1_P0_RX_BUF_DP<12>")
	)
	(segment
		(start 86.657434 -413.284924)
		(end 86.657434 -411.947868)
		(width 0.14224)
		(layer "In15.Cu")
		(net "P5E_CPU1_P0_RX_BUF_DP<12>")
	)
	(segment
		(start 85.125814 -406.424892)
		(end 84.94141 -405.979884)
		(width 0.14224)
		(layer "In15.Cu")
		(net "P5E_CPU1_P0_RX_BUF_DP<12>")
	)
	(segment
		(start 84.94141 -405.979884)
		(end 84.607654 -405.646128)
		(width 0.14224)
		(layer "In15.Cu")
		(net "P5E_CPU1_P0_RX_BUF_DP<12>")
	)
	(segment
		(start 81.397348 -401.54479)
		(end 81.04251 -401.307554)
		(width 0.14224)
		(layer "In15.Cu")
		(net "P5E_CPU1_P0_RX_BUF_DP<12>")
	)
	(segment
		(start 61.75756 -393.129008)
		(end 61.897006 -392.989562)
		(width 0.14224)
		(layer "In15.Cu")
		(net "P5E_CPU1_P0_RX_BUF_DP<12>")
	)
	(segment
		(start 83.594194 -405.183594)
		(end 83.594194 -403.799802)
		(width 0.14224)
		(layer "In15.Cu")
		(net "P5E_CPU1_P0_RX_BUF_DP<12>")
	)
	(segment
		(start 62.216538 -393.129008)
		(end 62.216538 -393.292838)
		(width 0.14224)
		(layer "In15.Cu")
		(net "P5E_CPU1_P0_RX_BUF_DP<12>")
	)
	(segment
		(start 83.666838 -405.360378)
		(end 83.594194 -405.183594)
		(width 0.14224)
		(layer "In15.Cu")
		(net "P5E_CPU1_P0_RX_BUF_DP<12>")
	)
	(segment
		(start 85.262974 -407.785062)
		(end 85.125814 -407.647902)
		(width 0.14224)
		(layer "In15.Cu")
		(net "P5E_CPU1_P0_RX_BUF_DP<12>")
	)
	(segment
		(start 86.657434 -411.947868)
		(end 86.470236 -411.494986)
		(width 0.14224)
		(layer "In15.Cu")
		(net "P5E_CPU1_P0_RX_BUF_DP<12>")
	)
	(segment
		(start 85.41639 -416.2806)
		(end 85.595968 -416.206432)
		(width 0.14224)
		(layer "In15.Cu")
		(net "P5E_CPU1_P0_RX_BUF_DP<12>")
	)
	(segment
		(start 83.851496 -405.545036)
		(end 83.666838 -405.360378)
		(width 0.14224)
		(layer "In15.Cu")
		(net "P5E_CPU1_P0_RX_BUF_DP<12>")
	)
	(segment
		(start 86.470236 -411.494986)
		(end 86.331806 -411.356556)
		(width 0.14224)
		(layer "In15.Cu")
		(net "P5E_CPU1_P0_RX_BUF_DP<12>")
	)
	(segment
		(start 85.685122 -415.632646)
		(end 85.84819 -415.238438)
		(width 0.14224)
		(layer "In15.Cu")
		(net "P5E_CPU1_P0_RX_BUF_DP<12>")
	)
	(segment
		(start 83.49996 -437.341264)
		(end 83.108546 -437.341264)
		(width 0.14224)
		(layer "In15.Cu")
		(net "P5E_CPU1_P0_RX_BUF_DP<12>")
	)
	(segment
		(start 86.116668 -414.590484)
		(end 86.657434 -413.284924)
		(width 0.14224)
		(layer "In15.Cu")
		(net "P5E_CPU1_P0_RX_BUF_DP<12>")
	)
	(segment
		(start 61.75756 -394.83665)
		(end 61.89472 -394.69949)
		(width 0.14224)
		(layer "In15.Cu")
		(net "P5E_CPU1_P0_RX_BUF_DP<12>")
	)
	(segment
		(start 79.935578 -400.754088)
		(end 79.008732 -400.370548)
		(width 0.14224)
		(layer "In15.Cu")
		(net "P5E_CPU1_P0_RX_BUF_DP<12>")
	)
	(segment
		(start 82.976466 -437.209184)
		(end 82.976466 -423.118026)
		(width 0.14224)
		(layer "In15.Cu")
		(net "P5E_CPU1_P0_RX_BUF_DP<12>")
	)
	(segment
		(start 83.923124 -405.574754)
		(end 83.851496 -405.545036)
		(width 0.14224)
		(layer "In15.Cu")
		(net "P5E_CPU1_P0_RX_BUF_DP<12>")
	)
	(segment
		(start 85.262974 -408.211782)
		(end 85.262974 -407.785062)
		(width 0.14224)
		(layer "In15.Cu")
		(net "P5E_CPU1_P0_RX_BUF_DP<12>")
	)
	(segment
		(start 84.435442 -405.574754)
		(end 83.923124 -405.574754)
		(width 0.14224)
		(layer "In15.Cu")
		(net "P5E_CPU1_P0_RX_BUF_DP<12>")
	)
	(segment
		(start 85.262974 -408.912822)
		(end 85.125814 -408.775662)
		(width 0.14224)
		(layer "In15.Cu")
		(net "P5E_CPU1_P0_RX_BUF_DP<12>")
	)
	(segment
		(start 86.027768 -415.16427)
		(end 86.19109 -414.769808)
		(width 0.14224)
		(layer "In15.Cu")
		(net "P5E_CPU1_P0_RX_BUF_DP<12>")
	)
	(segment
		(start 83.108546 -437.341264)
		(end 82.976466 -437.209184)
		(width 0.14224)
		(layer "In15.Cu")
		(net "P5E_CPU1_P0_RX_BUF_DP<12>")
	)
	(segment
		(start 82.874612 -402.696934)
		(end 81.435194 -401.735036)
		(width 0.14224)
		(layer "In15.Cu")
		(net "P5E_CPU1_P0_RX_BUF_DP<12>")
	)
	(segment
		(start 80.852264 -401.3454)
		(end 80.095852 -400.83994)
		(width 0.14224)
		(layer "In15.Cu")
		(net "P5E_CPU1_P0_RX_BUF_DP<12>")
	)
	(segment
		(start 85.164422 -417.248594)
		(end 85.32749 -416.854132)
		(width 0.14224)
		(layer "In15.Cu")
		(net "P5E_CPU1_P0_RX_BUF_DP<12>")
	)
	(segment
		(start 86.19109 -414.769808)
		(end 86.116668 -414.590484)
		(width 0.14224)
		(layer "In15.Cu")
		(net "P5E_CPU1_P0_RX_BUF_DP<12>")
	)
	(segment
		(start 85.125814 -408.775662)
		(end 85.125814 -408.348942)
		(width 0.14224)
		(layer "In15.Cu")
		(net "P5E_CPU1_P0_RX_BUF_DP<12>")
	)
	(segment
		(start 85.84819 -415.238438)
		(end 86.027768 -415.16427)
		(width 0.14224)
		(layer "In15.Cu")
		(net "P5E_CPU1_P0_RX_BUF_DP<12>")
	)
	(segment
		(start 67.696588 -398.083786)
		(end 65.391792 -397.384524)
		(width 0.14224)
		(layer "In15.Cu")
		(net "P5E_CPU1_P0_RX_BUF_DP<12>")
	)
	(segment
		(start 85.125814 -410.57449)
		(end 85.125814 -409.476702)
		(width 0.14224)
		(layer "In15.Cu")
		(net "P5E_CPU1_P0_RX_BUF_DP<12>")
	)
	(segment
		(start 85.595968 -416.206432)
		(end 85.75929 -415.81197)
		(width 0.14224)
		(layer "In15.Cu")
		(net "P5E_CPU1_P0_RX_BUF_DP<12>")
	)
	(segment
		(start 85.125814 -407.647902)
		(end 85.125814 -406.424892)
		(width 0.14224)
		(layer "In15.Cu")
		(net "P5E_CPU1_P0_RX_BUF_DP<12>")
	)
	(segment
		(start 83.650074 -437.19115)
		(end 83.49996 -437.341264)
		(width 0.14224)
		(layer "In15.Cu")
		(net "P5E_CPU1_P0_RX_BUF_DP<12>")
	)
	(segment
		(start 62.634876 -395.946884)
		(end 62.33287 -395.644878)
		(width 0.14224)
		(layer "In15.Cu")
		(net "P5E_CPU1_P0_RX_BUF_DP<12>")
	)
	(segment
		(start 62.077092 -392.989562)
		(end 62.216538 -393.129008)
		(width 0.14224)
		(layer "In15.Cu")
		(net "P5E_CPU1_P0_RX_BUF_DP<12>")
	)
	(segment
		(start 85.253322 -416.674808)
		(end 85.41639 -416.2806)
		(width 0.14224)
		(layer "In15.Cu")
		(net "P5E_CPU1_P0_RX_BUF_DP<12>")
	)
	(segment
		(start 85.449664 -410.991304)
		(end 85.1916 -410.73324)
		(width 0.14224)
		(layer "In15.Cu")
		(net "P5E_CPU1_P0_RX_BUF_DP<12>")
	)
	(segment
		(start 83.31073 -403.115526)
		(end 82.972148 -402.776944)
		(width 0.14224)
		(layer "In15.Cu")
		(net "P5E_CPU1_P0_RX_BUF_DP<12>")
	)
	(segment
		(start 61.89472 -394.69949)
		(end 61.89472 -394.27277)
		(width 0.14224)
		(layer "In15.Cu")
		(net "P5E_CPU1_P0_RX_BUF_DP<12>")
	)
	(segment
		(start 84.607654 -405.646128)
		(end 84.435442 -405.574754)
		(width 0.14224)
		(layer "In15.Cu")
		(net "P5E_CPU1_P0_RX_BUF_DP<12>")
	)
	(segment
		(start 84.984844 -417.322762)
		(end 85.164422 -417.248594)
		(width 0.14224)
		(layer "In15.Cu")
		(net "P5E_CPU1_P0_RX_BUF_DP<12>")
	)
	(segment
		(start 81.04251 -401.307554)
		(end 80.852264 -401.3454)
		(width 0.14224)
		(layer "In15.Cu")
		(net "P5E_CPU1_P0_RX_BUF_DP<12>")
	)
	(segment
		(start 61.760862 -395.266672)
		(end 61.75756 -395.258798)
		(width 0.14224)
		(layer "In15.Cu")
		(net "P5E_CPU1_P0_RX_BUF_DP<12>")
	)
	(segment
		(start 63.07201 -396.57782)
		(end 62.634876 -396.140686)
		(width 0.14224)
		(layer "In15.Cu")
		(net "P5E_CPU1_P0_RX_BUF_DP<12>")
	)
	(segment
		(start 86.331806 -411.356556)
		(end 85.449664 -410.991304)
		(width 0.14224)
		(layer "In15.Cu")
		(net "P5E_CPU1_P0_RX_BUF_DP<12>")
	)
	(segment
		(start 61.75756 -394.13561)
		(end 61.75756 -393.129008)
		(width 0.14224)
		(layer "In15.Cu")
		(net "P5E_CPU1_P0_RX_BUF_DP<12>")
	)
	(segment
		(start 85.125814 -409.476702)
		(end 85.262974 -409.339542)
		(width 0.14224)
		(layer "In15.Cu")
		(net "P5E_CPU1_P0_RX_BUF_DP<12>")
	)
	(segment
		(start 63.409068 -396.782798)
		(end 63.07201 -396.57782)
		(width 0.14224)
		(layer "In15.Cu")
		(net "P5E_CPU1_P0_RX_BUF_DP<12>")
	)
	(segment
		(start 81.435194 -401.735036)
		(end 81.397348 -401.54479)
		(width 0.14224)
		(layer "In15.Cu")
		(net "P5E_CPU1_P0_RX_BUF_DP<12>")
	)
	(segment
		(start 64.89192 -397.089376)
		(end 64.720724 -397.180816)
		(width 0.14224)
		(layer "In15.Cu")
		(net "P5E_CPU1_P0_RX_BUF_DP<12>")
	)
	(segment
		(start 61.897006 -392.989562)
		(end 62.077092 -392.989562)
		(width 0.14224)
		(layer "In15.Cu")
		(net "P5E_CPU1_P0_RX_BUF_DP<12>")
	)
	(segment
		(start 83.338924 -421.296592)
		(end 84.984844 -417.322762)
		(width 0.14224)
		(layer "In15.Cu")
		(net "P5E_CPU1_P0_RX_BUF_DP<12>")
	)
	(segment
		(start 61.89472 -394.27277)
		(end 61.75756 -394.13561)
		(width 0.14224)
		(layer "In15.Cu")
		(net "P5E_CPU1_P0_RX_BUF_DP<12>")
	)
	(segment
		(start 78.718918 -400.282664)
		(end 67.819524 -398.11452)
		(width 0.14224)
		(layer "In15.Cu")
		(net "P5E_CPU1_P0_RX_BUF_DP<12>")
	)
	(segment
		(start 85.75929 -415.81197)
		(end 85.685122 -415.632646)
		(width 0.14224)
		(layer "In15.Cu")
		(net "P5E_CPU1_P0_RX_BUF_DP<12>")
	)
	(segment
		(start 85.1916 -410.73324)
		(end 85.125814 -410.57449)
		(width 0.14224)
		(layer "In15.Cu")
		(net "P5E_CPU1_P0_RX_BUF_DP<12>")
	)
	(segment
		(start 62.139068 -395.644878)
		(end 61.760862 -395.266672)
		(width 0.14224)
		(layer "In15.Cu")
		(net "P5E_CPU1_P0_RX_BUF_DP<12>")
	)
	(segment
		(start 85.125814 -408.348942)
		(end 85.262974 -408.211782)
		(width 0.14224)
		(layer "In15.Cu")
		(net "P5E_CPU1_P0_RX_BUF_DP<12>")
	)
	(segment
		(start 85.32749 -416.854132)
		(end 85.253322 -416.674808)
		(width 0.14224)
		(layer "In15.Cu")
		(net "P5E_CPU1_P0_RX_BUF_DP<12>")
	)
	(segment
		(start 62.33287 -395.644878)
		(end 62.139068 -395.644878)
		(width 0.14224)
		(layer "In15.Cu")
		(net "P5E_CPU1_P0_RX_BUF_DP<12>")
	)
	(segment
		(start 64.720724 -397.180816)
		(end 63.409068 -396.782798)
		(width 0.14224)
		(layer "In15.Cu")
		(net "P5E_CPU1_P0_RX_BUF_DP<12>")
	)
	(segment
		(start 65.300352 -397.213074)
		(end 64.89192 -397.089376)
		(width 0.14224)
		(layer "In15.Cu")
		(net "P5E_CPU1_P0_RX_BUF_DP<12>")
	)
	(segment
		(start 83.650074 -436.889906)
		(end 83.650074 -437.19115)
		(width 0.14224)
		(layer "In15.Cu")
		(net "P5E_CPU1_P0_RX_BUF_DP<12>")
	)
	(segment
		(start 61.75756 -395.258798)
		(end 61.75756 -394.83665)
		(width 0.14224)
		(layer "In15.Cu")
		(net "P5E_CPU1_P0_RX_BUF_DP<12>")
	)
	(segment
		(start 85.262974 -409.339542)
		(end 85.262974 -408.912822)
		(width 0.14224)
		(layer "In15.Cu")
		(net "P5E_CPU1_P0_RX_BUF_DP<12>")
	)
	(segment
		(start 65.391792 -397.384524)
		(end 65.300352 -397.213074)
		(width 0.14224)
		(layer "In15.Cu")
		(net "P5E_CPU1_P0_RX_BUF_DP<12>")
	)
	(segment
		(start 62.634876 -396.140686)
		(end 62.634876 -395.946884)
		(width 0.14224)
		(layer "In15.Cu")
		(net "P5E_CPU1_P0_RX_BUF_DP<12>")
	)
	(arc
		(start 82.972148 -402.776944)
		(mid 82.925347 -402.73454)
		(end 82.874612 -402.696934)
		(width 0.14224)
		(layer "In15.Cu")
		(net "P5E_CPU1_P0_RX_BUF_DP<12>")
	)
	(arc
		(start 80.095852 -400.83994)
		(mid 80.017826 -400.793073)
		(end 79.935578 -400.754088)
		(width 0.14224)
		(layer "In15.Cu")
		(net "P5E_CPU1_P0_RX_BUF_DP<12>")
	)
	(arc
		(start 82.976466 -423.118026)
		(mid 83.068016 -422.189465)
		(end 83.338924 -421.296592)
		(width 0.14224)
		(layer "In15.Cu")
		(net "P5E_CPU1_P0_RX_BUF_DP<12>")
	)
	(arc
		(start 83.594194 -403.799802)
		(mid 83.520529 -403.429464)
		(end 83.31073 -403.115526)
		(width 0.14224)
		(layer "In15.Cu")
		(net "P5E_CPU1_P0_RX_BUF_DP<12>")
	)
	(arc
		(start 79.008732 -400.370548)
		(mid 78.86597 -400.319532)
		(end 78.718918 -400.282664)
		(width 0.14224)
		(layer "In15.Cu")
		(net "P5E_CPU1_P0_RX_BUF_DP<12>")
	)
	(arc
		(start 67.819524 -398.11452)
		(mid 67.757677 -398.100669)
		(end 67.696588 -398.083786)
		(width 0.14224)
		(layer "In15.Cu")
		(net "P5E_CPU1_P0_RX_BUF_DP<12>")
	)
	(segment
		(start 60.317888 -391.281158)
		(end 60.40247 -391.36574)
		(width 0.1016)
		(layer "F.Cu")
		(net "P5E_CPU1_P0_RX_BUF_DP<11>")
	)
	(segment
		(start 60.40247 -391.488676)
		(end 60.313824 -391.577322)
		(width 0.1016)
		(layer "F.Cu")
		(net "P5E_CPU1_P0_RX_BUF_DP<11>")
	)
	(segment
		(start 60.313824 -391.577322)
		(end 60.313824 -392.723878)
		(width 0.1016)
		(layer "F.Cu")
		(net "P5E_CPU1_P0_RX_BUF_DP<11>")
	)
	(segment
		(start 60.313824 -392.723878)
		(end 60.567062 -392.977116)
		(width 0.1016)
		(layer "F.Cu")
		(net "P5E_CPU1_P0_RX_BUF_DP<11>")
	)
	(segment
		(start 60.40247 -391.36574)
		(end 60.40247 -391.488676)
		(width 0.1016)
		(layer "F.Cu")
		(net "P5E_CPU1_P0_RX_BUF_DP<11>")
	)
	(segment
		(start 61.016642 -393.116054)
		(end 61.016642 -393.292838)
		(width 0.1016)
		(layer "F.Cu")
		(net "P5E_CPU1_P0_RX_BUF_DP<11>")
	)
	(segment
		(start 60.877704 -392.977116)
		(end 61.016642 -393.116054)
		(width 0.1016)
		(layer "F.Cu")
		(net "P5E_CPU1_P0_RX_BUF_DP<11>")
	)
	(segment
		(start 60.567062 -392.977116)
		(end 60.877704 -392.977116)
		(width 0.1016)
		(layer "F.Cu")
		(net "P5E_CPU1_P0_RX_BUF_DP<11>")
	)
	(segment
		(start 72.894444 -400.100292)
		(end 72.477884 -400.00682)
		(width 0.14224)
		(layer "In15.Cu")
		(net "P5E_CPU1_P0_RX_BUF_DP<11>")
	)
	(segment
		(start 81.650078 -438.191148)
		(end 81.499964 -438.341262)
		(width 0.14224)
		(layer "In15.Cu")
		(net "P5E_CPU1_P0_RX_BUF_DP<11>")
	)
	(segment
		(start 72.99833 -400.264376)
		(end 72.894444 -400.100292)
		(width 0.14224)
		(layer "In15.Cu")
		(net "P5E_CPU1_P0_RX_BUF_DP<11>")
	)
	(segment
		(start 76.693776 -401.340828)
		(end 76.514452 -401.414996)
		(width 0.14224)
		(layer "In15.Cu")
		(net "P5E_CPU1_P0_RX_BUF_DP<11>")
	)
	(segment
		(start 83.406742 -411.494732)
		(end 83.268566 -411.356556)
		(width 0.14224)
		(layer "In15.Cu")
		(net "P5E_CPU1_P0_RX_BUF_DP<11>")
	)
	(segment
		(start 82.199734 -408.819096)
		(end 82.062574 -408.681936)
		(width 0.14224)
		(layer "In15.Cu")
		(net "P5E_CPU1_P0_RX_BUF_DP<11>")
	)
	(segment
		(start 80.859884 -405.574754)
		(end 80.788256 -405.545036)
		(width 0.14224)
		(layer "In15.Cu")
		(net "P5E_CPU1_P0_RX_BUF_DP<11>")
	)
	(segment
		(start 82.062574 -407.554176)
		(end 82.062574 -406.424892)
		(width 0.14224)
		(layer "In15.Cu")
		(net "P5E_CPU1_P0_RX_BUF_DP<11>")
	)
	(segment
		(start 80.97647 -438.209182)
		(end 80.97647 -424.38955)
		(width 0.14224)
		(layer "In15.Cu")
		(net "P5E_CPU1_P0_RX_BUF_DP<11>")
	)
	(segment
		(start 80.530954 -403.419056)
		(end 79.95031 -402.838412)
		(width 0.14224)
		(layer "In15.Cu")
		(net "P5E_CPU1_P0_RX_BUF_DP<11>")
	)
	(segment
		(start 82.062574 -409.382976)
		(end 82.199734 -409.245816)
		(width 0.14224)
		(layer "In15.Cu")
		(net "P5E_CPU1_P0_RX_BUF_DP<11>")
	)
	(segment
		(start 81.544414 -405.646128)
		(end 81.372202 -405.574754)
		(width 0.14224)
		(layer "In15.Cu")
		(net "P5E_CPU1_P0_RX_BUF_DP<11>")
	)
	(segment
		(start 60.694824 -394.636244)
		(end 60.557664 -394.499084)
		(width 0.14224)
		(layer "In15.Cu")
		(net "P5E_CPU1_P0_RX_BUF_DP<11>")
	)
	(segment
		(start 62.212474 -397.250666)
		(end 60.641484 -395.829282)
		(width 0.14224)
		(layer "In15.Cu")
		(net "P5E_CPU1_P0_RX_BUF_DP<11>")
	)
	(segment
		(start 60.557664 -395.626844)
		(end 60.557664 -395.200124)
		(width 0.14224)
		(layer "In15.Cu")
		(net "P5E_CPU1_P0_RX_BUF_DP<11>")
	)
	(segment
		(start 60.557664 -393.129008)
		(end 60.69711 -392.989562)
		(width 0.14224)
		(layer "In15.Cu")
		(net "P5E_CPU1_P0_RX_BUF_DP<11>")
	)
	(segment
		(start 80.530954 -405.120856)
		(end 80.530954 -403.419056)
		(width 0.14224)
		(layer "In15.Cu")
		(net "P5E_CPU1_P0_RX_BUF_DP<11>")
	)
	(segment
		(start 79.95031 -402.838412)
		(end 79.117698 -402.49348)
		(width 0.14224)
		(layer "In15.Cu")
		(net "P5E_CPU1_P0_RX_BUF_DP<11>")
	)
	(segment
		(start 82.199734 -407.691336)
		(end 82.062574 -407.554176)
		(width 0.14224)
		(layer "In15.Cu")
		(net "P5E_CPU1_P0_RX_BUF_DP<11>")
	)
	(segment
		(start 60.694824 -395.062964)
		(end 60.694824 -394.636244)
		(width 0.14224)
		(layer "In15.Cu")
		(net "P5E_CPU1_P0_RX_BUF_DP<11>")
	)
	(segment
		(start 75.607672 -400.89074)
		(end 75.21321 -400.727418)
		(width 0.14224)
		(layer "In15.Cu")
		(net "P5E_CPU1_P0_RX_BUF_DP<11>")
	)
	(segment
		(start 75.033886 -400.801586)
		(end 74.6125 -400.627088)
		(width 0.14224)
		(layer "In15.Cu")
		(net "P5E_CPU1_P0_RX_BUF_DP<11>")
	)
	(segment
		(start 78.648814 -402.150834)
		(end 78.469744 -402.225002)
		(width 0.14224)
		(layer "In15.Cu")
		(net "P5E_CPU1_P0_RX_BUF_DP<11>")
	)
	(segment
		(start 80.97647 -424.38955)
		(end 80.976724 -424.389804)
		(width 0.14224)
		(layer "In15.Cu")
		(net "P5E_CPU1_P0_RX_BUF_DP<11>")
	)
	(segment
		(start 82.15757 -410.803852)
		(end 82.062574 -410.574744)
		(width 0.14224)
		(layer "In15.Cu")
		(net "P5E_CPU1_P0_RX_BUF_DP<11>")
	)
	(segment
		(start 79.117698 -402.49348)
		(end 79.04353 -402.314156)
		(width 0.14224)
		(layer "In15.Cu")
		(net "P5E_CPU1_P0_RX_BUF_DP<11>")
	)
	(segment
		(start 61.016642 -393.129008)
		(end 61.016642 -393.292838)
		(width 0.14224)
		(layer "In15.Cu")
		(net "P5E_CPU1_P0_RX_BUF_DP<11>")
	)
	(segment
		(start 60.69711 -392.989562)
		(end 60.877196 -392.989562)
		(width 0.14224)
		(layer "In15.Cu")
		(net "P5E_CPU1_P0_RX_BUF_DP<11>")
	)
	(segment
		(start 79.04353 -402.314156)
		(end 78.648814 -402.150834)
		(width 0.14224)
		(layer "In15.Cu")
		(net "P5E_CPU1_P0_RX_BUF_DP<11>")
	)
	(segment
		(start 76.514452 -401.414996)
		(end 75.68184 -401.070064)
		(width 0.14224)
		(layer "In15.Cu")
		(net "P5E_CPU1_P0_RX_BUF_DP<11>")
	)
	(segment
		(start 75.68184 -401.070064)
		(end 75.607672 -400.89074)
		(width 0.14224)
		(layer "In15.Cu")
		(net "P5E_CPU1_P0_RX_BUF_DP<11>")
	)
	(segment
		(start 82.062574 -410.574744)
		(end 82.062574 -409.382976)
		(width 0.14224)
		(layer "In15.Cu")
		(net "P5E_CPU1_P0_RX_BUF_DP<11>")
	)
	(segment
		(start 82.199734 -409.245816)
		(end 82.199734 -408.819096)
		(width 0.14224)
		(layer "In15.Cu")
		(net "P5E_CPU1_P0_RX_BUF_DP<11>")
	)
	(segment
		(start 72.314054 -400.110452)
		(end 67.868292 -399.111724)
		(width 0.14224)
		(layer "In15.Cu")
		(net "P5E_CPU1_P0_RX_BUF_DP<11>")
	)
	(segment
		(start 81.372202 -405.574754)
		(end 80.859884 -405.574754)
		(width 0.14224)
		(layer "In15.Cu")
		(net "P5E_CPU1_P0_RX_BUF_DP<11>")
	)
	(segment
		(start 78.469744 -402.225002)
		(end 77.162406 -401.683474)
		(width 0.14224)
		(layer "In15.Cu")
		(net "P5E_CPU1_P0_RX_BUF_DP<11>")
	)
	(segment
		(start 82.062574 -408.255216)
		(end 82.199734 -408.118056)
		(width 0.14224)
		(layer "In15.Cu")
		(net "P5E_CPU1_P0_RX_BUF_DP<11>")
	)
	(segment
		(start 83.594194 -411.947614)
		(end 83.406742 -411.494732)
		(width 0.14224)
		(layer "In15.Cu")
		(net "P5E_CPU1_P0_RX_BUF_DP<11>")
	)
	(segment
		(start 82.199734 -408.118056)
		(end 82.199734 -407.691336)
		(width 0.14224)
		(layer "In15.Cu")
		(net "P5E_CPU1_P0_RX_BUF_DP<11>")
	)
	(segment
		(start 81.650078 -437.889904)
		(end 81.650078 -438.191148)
		(width 0.14224)
		(layer "In15.Cu")
		(net "P5E_CPU1_P0_RX_BUF_DP<11>")
	)
	(segment
		(start 81.6991 -420.395908)
		(end 81.60766 -420.224966)
		(width 0.14224)
		(layer "In15.Cu")
		(net "P5E_CPU1_P0_RX_BUF_DP<11>")
	)
	(segment
		(start 83.594194 -413.676846)
		(end 83.594194 -411.947614)
		(width 0.14224)
		(layer "In15.Cu")
		(net "P5E_CPU1_P0_RX_BUF_DP<11>")
	)
	(segment
		(start 74.6125 -400.627088)
		(end 72.99833 -400.264376)
		(width 0.14224)
		(layer "In15.Cu")
		(net "P5E_CPU1_P0_RX_BUF_DP<11>")
	)
	(segment
		(start 82.062574 -406.424892)
		(end 81.87817 -405.979884)
		(width 0.14224)
		(layer "In15.Cu")
		(net "P5E_CPU1_P0_RX_BUF_DP<11>")
	)
	(segment
		(start 80.788256 -405.545036)
		(end 80.649064 -405.405844)
		(width 0.14224)
		(layer "In15.Cu")
		(net "P5E_CPU1_P0_RX_BUF_DP<11>")
	)
	(segment
		(start 60.641484 -395.829282)
		(end 60.557664 -395.626844)
		(width 0.14224)
		(layer "In15.Cu")
		(net "P5E_CPU1_P0_RX_BUF_DP<11>")
	)
	(segment
		(start 83.268566 -411.356556)
		(end 82.360262 -410.980382)
		(width 0.14224)
		(layer "In15.Cu")
		(net "P5E_CPU1_P0_RX_BUF_DP<11>")
	)
	(segment
		(start 72.477884 -400.00682)
		(end 72.314054 -400.110452)
		(width 0.14224)
		(layer "In15.Cu")
		(net "P5E_CPU1_P0_RX_BUF_DP<11>")
	)
	(segment
		(start 75.21321 -400.727418)
		(end 75.033886 -400.801586)
		(width 0.14224)
		(layer "In15.Cu")
		(net "P5E_CPU1_P0_RX_BUF_DP<11>")
	)
	(segment
		(start 81.87817 -405.979884)
		(end 81.544414 -405.646128)
		(width 0.14224)
		(layer "In15.Cu")
		(net "P5E_CPU1_P0_RX_BUF_DP<11>")
	)
	(segment
		(start 82.062574 -408.681936)
		(end 82.062574 -408.255216)
		(width 0.14224)
		(layer "In15.Cu")
		(net "P5E_CPU1_P0_RX_BUF_DP<11>")
	)
	(segment
		(start 82.281268 -410.92755)
		(end 82.15757 -410.803852)
		(width 0.14224)
		(layer "In15.Cu")
		(net "P5E_CPU1_P0_RX_BUF_DP<11>")
	)
	(segment
		(start 60.557664 -394.499084)
		(end 60.557664 -393.129008)
		(width 0.14224)
		(layer "In15.Cu")
		(net "P5E_CPU1_P0_RX_BUF_DP<11>")
	)
	(segment
		(start 77.088238 -401.50415)
		(end 76.693776 -401.340828)
		(width 0.14224)
		(layer "In15.Cu")
		(net "P5E_CPU1_P0_RX_BUF_DP<11>")
	)
	(segment
		(start 81.575402 -420.804594)
		(end 81.6991 -420.395908)
		(width 0.14224)
		(layer "In15.Cu")
		(net "P5E_CPU1_P0_RX_BUF_DP<11>")
	)
	(segment
		(start 81.403952 -420.896034)
		(end 81.575402 -420.804594)
		(width 0.14224)
		(layer "In15.Cu")
		(net "P5E_CPU1_P0_RX_BUF_DP<11>")
	)
	(segment
		(start 60.557664 -395.200124)
		(end 60.694824 -395.062964)
		(width 0.14224)
		(layer "In15.Cu")
		(net "P5E_CPU1_P0_RX_BUF_DP<11>")
	)
	(segment
		(start 60.877196 -392.989562)
		(end 61.016642 -393.129008)
		(width 0.14224)
		(layer "In15.Cu")
		(net "P5E_CPU1_P0_RX_BUF_DP<11>")
	)
	(segment
		(start 82.360262 -410.980382)
		(end 82.281268 -410.92755)
		(width 0.14224)
		(layer "In15.Cu")
		(net "P5E_CPU1_P0_RX_BUF_DP<11>")
	)
	(segment
		(start 81.280254 -421.304212)
		(end 81.403952 -420.896034)
		(width 0.14224)
		(layer "In15.Cu")
		(net "P5E_CPU1_P0_RX_BUF_DP<11>")
	)
	(segment
		(start 81.60766 -420.224966)
		(end 83.594194 -413.676846)
		(width 0.14224)
		(layer "In15.Cu")
		(net "P5E_CPU1_P0_RX_BUF_DP<11>")
	)
	(segment
		(start 67.637406 -399.050764)
		(end 62.803024 -397.58366)
		(width 0.14224)
		(layer "In15.Cu")
		(net "P5E_CPU1_P0_RX_BUF_DP<11>")
	)
	(segment
		(start 77.162406 -401.683474)
		(end 77.088238 -401.50415)
		(width 0.14224)
		(layer "In15.Cu")
		(net "P5E_CPU1_P0_RX_BUF_DP<11>")
	)
	(segment
		(start 81.499964 -438.341262)
		(end 81.10855 -438.341262)
		(width 0.14224)
		(layer "In15.Cu")
		(net "P5E_CPU1_P0_RX_BUF_DP<11>")
	)
	(segment
		(start 81.10855 -438.341262)
		(end 80.97647 -438.209182)
		(width 0.14224)
		(layer "In15.Cu")
		(net "P5E_CPU1_P0_RX_BUF_DP<11>")
	)
	(arc
		(start 62.3189 -397.338296)
		(mid 62.264662 -397.295725)
		(end 62.212474 -397.250666)
		(width 0.14224)
		(layer "In15.Cu")
		(net "P5E_CPU1_P0_RX_BUF_DP<11>")
	)
	(arc
		(start 67.868292 -399.111724)
		(mid 67.752291 -399.083359)
		(end 67.637406 -399.050764)
		(width 0.14224)
		(layer "In15.Cu")
		(net "P5E_CPU1_P0_RX_BUF_DP<11>")
	)
	(arc
		(start 80.649064 -405.405844)
		(mid 80.561644 -405.275105)
		(end 80.530954 -405.120856)
		(width 0.14224)
		(layer "In15.Cu")
		(net "P5E_CPU1_P0_RX_BUF_DP<11>")
	)
	(arc
		(start 62.803024 -397.58366)
		(mid 62.550245 -397.482125)
		(end 62.3189 -397.338296)
		(width 0.14224)
		(layer "In15.Cu")
		(net "P5E_CPU1_P0_RX_BUF_DP<11>")
	)
	(arc
		(start 80.976724 -424.389804)
		(mid 81.052707 -422.839554)
		(end 81.280254 -421.304212)
		(width 0.14224)
		(layer "In15.Cu")
		(net "P5E_CPU1_P0_RX_BUF_DP<11>")
	)
	(segment
		(start 59.677808 -392.977116)
		(end 59.367166 -392.977116)
		(width 0.1016)
		(layer "F.Cu")
		(net "P5E_CPU1_P0_RX_BUF_DP<10>")
	)
	(segment
		(start 59.202066 -391.365232)
		(end 59.117992 -391.281158)
		(width 0.1016)
		(layer "F.Cu")
		(net "P5E_CPU1_P0_RX_BUF_DP<10>")
	)
	(segment
		(start 59.113928 -392.723878)
		(end 59.113928 -391.577322)
		(width 0.1016)
		(layer "F.Cu")
		(net "P5E_CPU1_P0_RX_BUF_DP<10>")
	)
	(segment
		(start 59.202066 -391.489184)
		(end 59.202066 -391.365232)
		(width 0.1016)
		(layer "F.Cu")
		(net "P5E_CPU1_P0_RX_BUF_DP<10>")
	)
	(segment
		(start 59.113928 -391.577322)
		(end 59.202066 -391.489184)
		(width 0.1016)
		(layer "F.Cu")
		(net "P5E_CPU1_P0_RX_BUF_DP<10>")
	)
	(segment
		(start 59.816746 -393.292838)
		(end 59.816746 -393.116054)
		(width 0.1016)
		(layer "F.Cu")
		(net "P5E_CPU1_P0_RX_BUF_DP<10>")
	)
	(segment
		(start 59.816746 -393.116054)
		(end 59.677808 -392.977116)
		(width 0.1016)
		(layer "F.Cu")
		(net "P5E_CPU1_P0_RX_BUF_DP<10>")
	)
	(segment
		(start 59.367166 -392.977116)
		(end 59.113928 -392.723878)
		(width 0.1016)
		(layer "F.Cu")
		(net "P5E_CPU1_P0_RX_BUF_DP<10>")
	)
	(segment
		(start 79.650082 -436.889906)
		(end 79.650082 -437.19115)
		(width 0.14224)
		(layer "In15.Cu")
		(net "P5E_CPU1_P0_RX_BUF_DP<10>")
	)
	(segment
		(start 61.585348 -398.069308)
		(end 61.29528 -397.842994)
		(width 0.14224)
		(layer "In15.Cu")
		(net "P5E_CPU1_P0_RX_BUF_DP<10>")
	)
	(segment
		(start 70.993 -400.901408)
		(end 70.584314 -400.77771)
		(width 0.14224)
		(layer "In15.Cu")
		(net "P5E_CPU1_P0_RX_BUF_DP<10>")
	)
	(segment
		(start 78.999334 -408.273504)
		(end 79.136494 -408.136344)
		(width 0.14224)
		(layer "In15.Cu")
		(net "P5E_CPU1_P0_RX_BUF_DP<10>")
	)
	(segment
		(start 78.308962 -405.574754)
		(end 77.796644 -405.574754)
		(width 0.14224)
		(layer "In15.Cu")
		(net "P5E_CPU1_P0_RX_BUF_DP<10>")
	)
	(segment
		(start 80.284574 -415.348166)
		(end 80.44053 -415.232596)
		(width 0.14224)
		(layer "In15.Cu")
		(net "P5E_CPU1_P0_RX_BUF_DP<10>")
	)
	(segment
		(start 78.999334 -406.424892)
		(end 78.81493 -405.979884)
		(width 0.14224)
		(layer "In15.Cu")
		(net "P5E_CPU1_P0_RX_BUF_DP<10>")
	)
	(segment
		(start 72.571864 -401.523962)
		(end 72.163686 -401.400264)
		(width 0.14224)
		(layer "In15.Cu")
		(net "P5E_CPU1_P0_RX_BUF_DP<10>")
	)
	(segment
		(start 79.082138 -423.4561)
		(end 80.284574 -415.348166)
		(width 0.14224)
		(layer "In15.Cu")
		(net "P5E_CPU1_P0_RX_BUF_DP<10>")
	)
	(segment
		(start 79.136494 -408.837384)
		(end 78.999334 -408.700224)
		(width 0.14224)
		(layer "In15.Cu")
		(net "P5E_CPU1_P0_RX_BUF_DP<10>")
	)
	(segment
		(start 67.917822 -400.112484)
		(end 67.917568 -400.111976)
		(width 0.14224)
		(layer "In15.Cu")
		(net "P5E_CPU1_P0_RX_BUF_DP<10>")
	)
	(segment
		(start 79.136494 -409.264104)
		(end 79.136494 -408.837384)
		(width 0.14224)
		(layer "In15.Cu")
		(net "P5E_CPU1_P0_RX_BUF_DP<10>")
	)
	(segment
		(start 74.390758 -401.93214)
		(end 74.219562 -402.02358)
		(width 0.14224)
		(layer "In15.Cu")
		(net "P5E_CPU1_P0_RX_BUF_DP<10>")
	)
	(segment
		(start 72.74306 -401.432522)
		(end 72.571864 -401.523962)
		(width 0.14224)
		(layer "In15.Cu")
		(net "P5E_CPU1_P0_RX_BUF_DP<10>")
	)
	(segment
		(start 59.494928 -394.775182)
		(end 59.357768 -394.638022)
		(width 0.14224)
		(layer "In15.Cu")
		(net "P5E_CPU1_P0_RX_BUF_DP<10>")
	)
	(segment
		(start 79.218028 -410.92755)
		(end 79.09433 -410.803852)
		(width 0.14224)
		(layer "In15.Cu")
		(net "P5E_CPU1_P0_RX_BUF_DP<10>")
	)
	(segment
		(start 79.09433 -410.803852)
		(end 78.999334 -410.574744)
		(width 0.14224)
		(layer "In15.Cu")
		(net "P5E_CPU1_P0_RX_BUF_DP<10>")
	)
	(segment
		(start 78.81493 -405.979884)
		(end 78.481174 -405.646128)
		(width 0.14224)
		(layer "In15.Cu")
		(net "P5E_CPU1_P0_RX_BUF_DP<10>")
	)
	(segment
		(start 75.299062 -402.350986)
		(end 74.890884 -402.227288)
		(width 0.14224)
		(layer "In15.Cu")
		(net "P5E_CPU1_P0_RX_BUF_DP<10>")
	)
	(segment
		(start 70.413372 -400.86915)
		(end 67.917822 -400.112484)
		(width 0.14224)
		(layer "In15.Cu")
		(net "P5E_CPU1_P0_RX_BUF_DP<10>")
	)
	(segment
		(start 79.11338 -437.341264)
		(end 78.971394 -437.199278)
		(width 0.14224)
		(layer "In15.Cu")
		(net "P5E_CPU1_P0_RX_BUF_DP<10>")
	)
	(segment
		(start 79.650082 -437.19115)
		(end 79.499968 -437.341264)
		(width 0.14224)
		(layer "In15.Cu")
		(net "P5E_CPU1_P0_RX_BUF_DP<10>")
	)
	(segment
		(start 59.494928 -395.201902)
		(end 59.494928 -394.775182)
		(width 0.14224)
		(layer "In15.Cu")
		(net "P5E_CPU1_P0_RX_BUF_DP<10>")
	)
	(segment
		(start 80.530954 -413.685736)
		(end 80.530954 -412.123128)
		(width 0.14224)
		(layer "In15.Cu")
		(net "P5E_CPU1_P0_RX_BUF_DP<10>")
	)
	(segment
		(start 78.971394 -424.9547)
		(end 79.082138 -423.4561)
		(width 0.14224)
		(layer "In15.Cu")
		(net "P5E_CPU1_P0_RX_BUF_DP<10>")
	)
	(segment
		(start 75.97013 -402.554694)
		(end 75.87869 -402.383498)
		(width 0.14224)
		(layer "In15.Cu")
		(net "P5E_CPU1_P0_RX_BUF_DP<10>")
	)
	(segment
		(start 59.357768 -393.129008)
		(end 59.497214 -392.989562)
		(width 0.14224)
		(layer "In15.Cu")
		(net "P5E_CPU1_P0_RX_BUF_DP<10>")
	)
	(segment
		(start 74.219562 -402.02358)
		(end 73.242932 -401.72767)
		(width 0.14224)
		(layer "In15.Cu")
		(net "P5E_CPU1_P0_RX_BUF_DP<10>")
	)
	(segment
		(start 78.999334 -409.401264)
		(end 79.136494 -409.264104)
		(width 0.14224)
		(layer "In15.Cu")
		(net "P5E_CPU1_P0_RX_BUF_DP<10>")
	)
	(segment
		(start 78.971394 -437.199278)
		(end 78.971394 -424.9547)
		(width 0.14224)
		(layer "In15.Cu")
		(net "P5E_CPU1_P0_RX_BUF_DP<10>")
	)
	(segment
		(start 79.136494 -407.709624)
		(end 78.999334 -407.572464)
		(width 0.14224)
		(layer "In15.Cu")
		(net "P5E_CPU1_P0_RX_BUF_DP<10>")
	)
	(segment
		(start 59.357768 -395.339062)
		(end 59.494928 -395.201902)
		(width 0.14224)
		(layer "In15.Cu")
		(net "P5E_CPU1_P0_RX_BUF_DP<10>")
	)
	(segment
		(start 71.66356 -401.105116)
		(end 71.492618 -401.196556)
		(width 0.14224)
		(layer "In15.Cu")
		(net "P5E_CPU1_P0_RX_BUF_DP<10>")
	)
	(segment
		(start 76.670408 -402.767038)
		(end 75.97013 -402.554694)
		(width 0.14224)
		(layer "In15.Cu")
		(net "P5E_CPU1_P0_RX_BUF_DP<10>")
	)
	(segment
		(start 77.467714 -405.184864)
		(end 77.467714 -403.500082)
		(width 0.14224)
		(layer "In15.Cu")
		(net "P5E_CPU1_P0_RX_BUF_DP<10>")
	)
	(segment
		(start 71.08444 -401.072858)
		(end 70.993 -400.901408)
		(width 0.14224)
		(layer "In15.Cu")
		(net "P5E_CPU1_P0_RX_BUF_DP<10>")
	)
	(segment
		(start 59.357768 -394.638022)
		(end 59.357768 -393.129008)
		(width 0.14224)
		(layer "In15.Cu")
		(net "P5E_CPU1_P0_RX_BUF_DP<10>")
	)
	(segment
		(start 61.29528 -397.842994)
		(end 59.446668 -395.994382)
		(width 0.14224)
		(layer "In15.Cu")
		(net "P5E_CPU1_P0_RX_BUF_DP<10>")
	)
	(segment
		(start 75.470004 -402.259546)
		(end 75.299062 -402.350986)
		(width 0.14224)
		(layer "In15.Cu")
		(net "P5E_CPU1_P0_RX_BUF_DP<10>")
	)
	(segment
		(start 70.584314 -400.77771)
		(end 70.413372 -400.86915)
		(width 0.14224)
		(layer "In15.Cu")
		(net "P5E_CPU1_P0_RX_BUF_DP<10>")
	)
	(segment
		(start 67.917568 -400.111976)
		(end 62.153546 -398.364202)
		(width 0.14224)
		(layer "In15.Cu")
		(net "P5E_CPU1_P0_RX_BUF_DP<10>")
	)
	(segment
		(start 73.151492 -401.556474)
		(end 72.74306 -401.432522)
		(width 0.14224)
		(layer "In15.Cu")
		(net "P5E_CPU1_P0_RX_BUF_DP<10>")
	)
	(segment
		(start 77.467714 -403.500082)
		(end 77.367638 -403.258782)
		(width 0.14224)
		(layer "In15.Cu")
		(net "P5E_CPU1_P0_RX_BUF_DP<10>")
	)
	(segment
		(start 75.87869 -402.383498)
		(end 75.470004 -402.259546)
		(width 0.14224)
		(layer "In15.Cu")
		(net "P5E_CPU1_P0_RX_BUF_DP<10>")
	)
	(segment
		(start 59.816746 -393.129008)
		(end 59.816746 -393.292838)
		(width 0.14224)
		(layer "In15.Cu")
		(net "P5E_CPU1_P0_RX_BUF_DP<10>")
	)
	(segment
		(start 74.890884 -402.227288)
		(end 74.799444 -402.056092)
		(width 0.14224)
		(layer "In15.Cu")
		(net "P5E_CPU1_P0_RX_BUF_DP<10>")
	)
	(segment
		(start 80.067912 -411.29966)
		(end 79.29753 -410.980636)
		(width 0.14224)
		(layer "In15.Cu")
		(net "P5E_CPU1_P0_RX_BUF_DP<10>")
	)
	(segment
		(start 72.072246 -401.229068)
		(end 71.66356 -401.105116)
		(width 0.14224)
		(layer "In15.Cu")
		(net "P5E_CPU1_P0_RX_BUF_DP<10>")
	)
	(segment
		(start 79.136494 -408.136344)
		(end 79.136494 -407.709624)
		(width 0.14224)
		(layer "In15.Cu")
		(net "P5E_CPU1_P0_RX_BUF_DP<10>")
	)
	(segment
		(start 77.540358 -405.360378)
		(end 77.467714 -405.184864)
		(width 0.14224)
		(layer "In15.Cu")
		(net "P5E_CPU1_P0_RX_BUF_DP<10>")
	)
	(segment
		(start 80.44053 -415.232596)
		(end 80.503014 -414.810194)
		(width 0.14224)
		(layer "In15.Cu")
		(net "P5E_CPU1_P0_RX_BUF_DP<10>")
	)
	(segment
		(start 77.725016 -405.545036)
		(end 77.540358 -405.360378)
		(width 0.14224)
		(layer "In15.Cu")
		(net "P5E_CPU1_P0_RX_BUF_DP<10>")
	)
	(segment
		(start 59.357768 -395.780006)
		(end 59.357768 -395.339062)
		(width 0.14224)
		(layer "In15.Cu")
		(net "P5E_CPU1_P0_RX_BUF_DP<10>")
	)
	(segment
		(start 80.387444 -414.654492)
		(end 80.530954 -413.685736)
		(width 0.14224)
		(layer "In15.Cu")
		(net "P5E_CPU1_P0_RX_BUF_DP<10>")
	)
	(segment
		(start 59.6773 -392.989562)
		(end 59.816746 -393.129008)
		(width 0.14224)
		(layer "In15.Cu")
		(net "P5E_CPU1_P0_RX_BUF_DP<10>")
	)
	(segment
		(start 78.999334 -407.572464)
		(end 78.999334 -406.424892)
		(width 0.14224)
		(layer "In15.Cu")
		(net "P5E_CPU1_P0_RX_BUF_DP<10>")
	)
	(segment
		(start 72.163686 -401.400264)
		(end 72.072246 -401.229068)
		(width 0.14224)
		(layer "In15.Cu")
		(net "P5E_CPU1_P0_RX_BUF_DP<10>")
	)
	(segment
		(start 78.481174 -405.646128)
		(end 78.308962 -405.574754)
		(width 0.14224)
		(layer "In15.Cu")
		(net "P5E_CPU1_P0_RX_BUF_DP<10>")
	)
	(segment
		(start 59.497214 -392.989562)
		(end 59.6773 -392.989562)
		(width 0.14224)
		(layer "In15.Cu")
		(net "P5E_CPU1_P0_RX_BUF_DP<10>")
	)
	(segment
		(start 78.999334 -408.700224)
		(end 78.999334 -408.273504)
		(width 0.14224)
		(layer "In15.Cu")
		(net "P5E_CPU1_P0_RX_BUF_DP<10>")
	)
	(segment
		(start 80.503014 -414.810194)
		(end 80.387444 -414.654492)
		(width 0.14224)
		(layer "In15.Cu")
		(net "P5E_CPU1_P0_RX_BUF_DP<10>")
	)
	(segment
		(start 77.199998 -403.064726)
		(end 76.797408 -402.823426)
		(width 0.14224)
		(layer "In15.Cu")
		(net "P5E_CPU1_P0_RX_BUF_DP<10>")
	)
	(segment
		(start 77.796644 -405.574754)
		(end 77.725016 -405.545036)
		(width 0.14224)
		(layer "In15.Cu")
		(net "P5E_CPU1_P0_RX_BUF_DP<10>")
	)
	(segment
		(start 79.499968 -437.341264)
		(end 79.11338 -437.341264)
		(width 0.14224)
		(layer "In15.Cu")
		(net "P5E_CPU1_P0_RX_BUF_DP<10>")
	)
	(segment
		(start 78.999334 -410.574744)
		(end 78.999334 -409.401264)
		(width 0.14224)
		(layer "In15.Cu")
		(net "P5E_CPU1_P0_RX_BUF_DP<10>")
	)
	(segment
		(start 71.492618 -401.196556)
		(end 71.08444 -401.072858)
		(width 0.14224)
		(layer "In15.Cu")
		(net "P5E_CPU1_P0_RX_BUF_DP<10>")
	)
	(segment
		(start 73.242932 -401.72767)
		(end 73.151492 -401.556474)
		(width 0.14224)
		(layer "In15.Cu")
		(net "P5E_CPU1_P0_RX_BUF_DP<10>")
	)
	(segment
		(start 74.799444 -402.056092)
		(end 74.390758 -401.93214)
		(width 0.14224)
		(layer "In15.Cu")
		(net "P5E_CPU1_P0_RX_BUF_DP<10>")
	)
	(segment
		(start 76.797408 -402.823426)
		(end 76.670408 -402.767038)
		(width 0.14224)
		(layer "In15.Cu")
		(net "P5E_CPU1_P0_RX_BUF_DP<10>")
	)
	(arc
		(start 62.153546 -398.364202)
		(mid 61.855829 -398.242991)
		(end 61.585348 -398.069308)
		(width 0.14224)
		(layer "In15.Cu")
		(net "P5E_CPU1_P0_RX_BUF_DP<10>")
	)
	(arc
		(start 80.38211 -411.618684)
		(mid 80.337615 -411.550264)
		(end 80.292448 -411.482286)
		(width 0.14224)
		(layer "In15.Cu")
		(net "P5E_CPU1_P0_RX_BUF_DP<10>")
	)
	(arc
		(start 79.29753 -410.980636)
		(mid 79.255173 -410.957998)
		(end 79.218028 -410.92755)
		(width 0.14224)
		(layer "In15.Cu")
		(net "P5E_CPU1_P0_RX_BUF_DP<10>")
	)
	(arc
		(start 80.530954 -412.123128)
		(mid 80.493032 -411.860138)
		(end 80.38211 -411.618684)
		(width 0.14224)
		(layer "In15.Cu")
		(net "P5E_CPU1_P0_RX_BUF_DP<10>")
	)
	(arc
		(start 77.367638 -403.258782)
		(mid 77.299399 -403.148301)
		(end 77.199998 -403.064726)
		(width 0.14224)
		(layer "In15.Cu")
		(net "P5E_CPU1_P0_RX_BUF_DP<10>")
	)
	(arc
		(start 80.292448 -411.482286)
		(mid 80.193614 -411.374461)
		(end 80.067912 -411.29966)
		(width 0.14224)
		(layer "In15.Cu")
		(net "P5E_CPU1_P0_RX_BUF_DP<10>")
	)
	(arc
		(start 59.446668 -395.994382)
		(mid 59.380895 -395.89604)
		(end 59.357768 -395.780006)
		(width 0.14224)
		(layer "In15.Cu")
		(net "P5E_CPU1_P0_RX_BUF_DP<10>")
	)
	(segment
		(start 47.202598 -391.36574)
		(end 47.202598 -391.488676)
		(width 0.1016)
		(layer "F.Cu")
		(net "P5E_CPU1_P0_RX_BUF_DP<0>")
	)
	(segment
		(start 47.677832 -392.977116)
		(end 47.816516 -393.1158)
		(width 0.1016)
		(layer "F.Cu")
		(net "P5E_CPU1_P0_RX_BUF_DP<0>")
	)
	(segment
		(start 47.0916 -391.599674)
		(end 47.0916 -392.701526)
		(width 0.1016)
		(layer "F.Cu")
		(net "P5E_CPU1_P0_RX_BUF_DP<0>")
	)
	(segment
		(start 47.118016 -391.281158)
		(end 47.202598 -391.36574)
		(width 0.1016)
		(layer "F.Cu")
		(net "P5E_CPU1_P0_RX_BUF_DP<0>")
	)
	(segment
		(start 47.816516 -393.1158)
		(end 47.816516 -393.292838)
		(width 0.1016)
		(layer "F.Cu")
		(net "P5E_CPU1_P0_RX_BUF_DP<0>")
	)
	(segment
		(start 47.202598 -391.488676)
		(end 47.0916 -391.599674)
		(width 0.1016)
		(layer "F.Cu")
		(net "P5E_CPU1_P0_RX_BUF_DP<0>")
	)
	(segment
		(start 47.36719 -392.977116)
		(end 47.677832 -392.977116)
		(width 0.1016)
		(layer "F.Cu")
		(net "P5E_CPU1_P0_RX_BUF_DP<0>")
	)
	(segment
		(start 47.0916 -392.701526)
		(end 47.36719 -392.977116)
		(width 0.1016)
		(layer "F.Cu")
		(net "P5E_CPU1_P0_RX_BUF_DP<0>")
	)
	(segment
		(start 47.494698 -398.86636)
		(end 47.494698 -398.43964)
		(width 0.14224)
		(layer "In15.Cu")
		(net "P5E_CPU1_P0_RX_BUF_DP<0>")
	)
	(segment
		(start 47.357538 -393.129008)
		(end 47.496984 -392.989562)
		(width 0.14224)
		(layer "In15.Cu")
		(net "P5E_CPU1_P0_RX_BUF_DP<0>")
	)
	(segment
		(start 49.898554 -411.948122)
		(end 49.71161 -411.495494)
		(width 0.14224)
		(layer "In15.Cu")
		(net "P5E_CPU1_P0_RX_BUF_DP<0>")
	)
	(segment
		(start 47.357538 -399.43024)
		(end 47.357538 -399.00352)
		(width 0.14224)
		(layer "In15.Cu")
		(net "P5E_CPU1_P0_RX_BUF_DP<0>")
	)
	(segment
		(start 46.756828 -404.424642)
		(end 46.865794 -403.878034)
		(width 0.14224)
		(layer "In15.Cu")
		(net "P5E_CPU1_P0_RX_BUF_DP<0>")
	)
	(segment
		(start 49.71161 -411.495494)
		(end 49.391062 -411.281118)
		(width 0.14224)
		(layer "In15.Cu")
		(net "P5E_CPU1_P0_RX_BUF_DP<0>")
	)
	(segment
		(start 48.46193 -410.803852)
		(end 48.366934 -410.574744)
		(width 0.14224)
		(layer "In15.Cu")
		(net "P5E_CPU1_P0_RX_BUF_DP<0>")
	)
	(segment
		(start 47.494698 -398.43964)
		(end 47.357538 -398.30248)
		(width 0.14224)
		(layer "In15.Cu")
		(net "P5E_CPU1_P0_RX_BUF_DP<0>")
	)
	(segment
		(start 47.045372 -403.160738)
		(end 47.211996 -403.06117)
		(width 0.14224)
		(layer "In15.Cu")
		(net "P5E_CPU1_P0_RX_BUF_DP<0>")
	)
	(segment
		(start 47.357538 -401.25904)
		(end 47.494698 -401.12188)
		(width 0.14224)
		(layer "In15.Cu")
		(net "P5E_CPU1_P0_RX_BUF_DP<0>")
	)
	(segment
		(start 48.504094 -407.989532)
		(end 48.504094 -407.562812)
		(width 0.14224)
		(layer "In15.Cu")
		(net "P5E_CPU1_P0_RX_BUF_DP<0>")
	)
	(segment
		(start 48.366934 -407.425652)
		(end 48.366934 -406.424892)
		(width 0.14224)
		(layer "In15.Cu")
		(net "P5E_CPU1_P0_RX_BUF_DP<0>")
	)
	(segment
		(start 50.12944 -413.881316)
		(end 49.898554 -413.323786)
		(width 0.14224)
		(layer "In15.Cu")
		(net "P5E_CPU1_P0_RX_BUF_DP<0>")
	)
	(segment
		(start 47.357538 -397.87576)
		(end 47.494698 -397.7386)
		(width 0.14224)
		(layer "In15.Cu")
		(net "P5E_CPU1_P0_RX_BUF_DP<0>")
	)
	(segment
		(start 47.494698 -395.05636)
		(end 47.357538 -394.9192)
		(width 0.14224)
		(layer "In15.Cu")
		(net "P5E_CPU1_P0_RX_BUF_DP<0>")
	)
	(segment
		(start 47.494698 -401.12188)
		(end 47.494698 -400.69516)
		(width 0.14224)
		(layer "In15.Cu")
		(net "P5E_CPU1_P0_RX_BUF_DP<0>")
	)
	(segment
		(start 47.494698 -397.31188)
		(end 47.357538 -397.17472)
		(width 0.14224)
		(layer "In15.Cu")
		(net "P5E_CPU1_P0_RX_BUF_DP<0>")
	)
	(segment
		(start 47.164244 -405.574754)
		(end 47.092616 -405.545036)
		(width 0.14224)
		(layer "In15.Cu")
		(net "P5E_CPU1_P0_RX_BUF_DP<0>")
	)
	(segment
		(start 47.357538 -394.9192)
		(end 47.357538 -393.129008)
		(width 0.14224)
		(layer "In15.Cu")
		(net "P5E_CPU1_P0_RX_BUF_DP<0>")
	)
	(segment
		(start 58.64987 -437.19115)
		(end 58.50382 -437.3372)
		(width 0.14224)
		(layer "In15.Cu")
		(net "P5E_CPU1_P0_RX_BUF_DP<0>")
	)
	(segment
		(start 47.494698 -399.99412)
		(end 47.494698 -399.5674)
		(width 0.14224)
		(layer "In15.Cu")
		(net "P5E_CPU1_P0_RX_BUF_DP<0>")
	)
	(segment
		(start 47.21606 -402.480526)
		(end 47.357538 -401.914868)
		(width 0.14224)
		(layer "In15.Cu")
		(net "P5E_CPU1_P0_RX_BUF_DP<0>")
	)
	(segment
		(start 49.391062 -411.281118)
		(end 48.664876 -410.980382)
		(width 0.14224)
		(layer "In15.Cu")
		(net "P5E_CPU1_P0_RX_BUF_DP<0>")
	)
	(segment
		(start 48.664876 -410.980382)
		(end 48.585628 -410.92755)
		(width 0.14224)
		(layer "In15.Cu")
		(net "P5E_CPU1_P0_RX_BUF_DP<0>")
	)
	(segment
		(start 47.816516 -393.129008)
		(end 47.816516 -393.292838)
		(width 0.14224)
		(layer "In15.Cu")
		(net "P5E_CPU1_P0_RX_BUF_DP<0>")
	)
	(segment
		(start 47.496984 -392.989562)
		(end 47.67707 -392.989562)
		(width 0.14224)
		(layer "In15.Cu")
		(net "P5E_CPU1_P0_RX_BUF_DP<0>")
	)
	(segment
		(start 49.898554 -413.323786)
		(end 49.898554 -411.948122)
		(width 0.14224)
		(layer "In15.Cu")
		(net "P5E_CPU1_P0_RX_BUF_DP<0>")
	)
	(segment
		(start 47.357538 -397.17472)
		(end 47.357538 -396.748)
		(width 0.14224)
		(layer "In15.Cu")
		(net "P5E_CPU1_P0_RX_BUF_DP<0>")
	)
	(segment
		(start 47.357538 -400.558)
		(end 47.357538 -400.13128)
		(width 0.14224)
		(layer "In15.Cu")
		(net "P5E_CPU1_P0_RX_BUF_DP<0>")
	)
	(segment
		(start 47.494698 -396.18412)
		(end 47.357538 -396.04696)
		(width 0.14224)
		(layer "In15.Cu")
		(net "P5E_CPU1_P0_RX_BUF_DP<0>")
	)
	(segment
		(start 47.357538 -398.30248)
		(end 47.357538 -397.87576)
		(width 0.14224)
		(layer "In15.Cu")
		(net "P5E_CPU1_P0_RX_BUF_DP<0>")
	)
	(segment
		(start 46.907958 -405.360378)
		(end 46.756828 -404.995888)
		(width 0.14224)
		(layer "In15.Cu")
		(net "P5E_CPU1_P0_RX_BUF_DP<0>")
	)
	(segment
		(start 47.494698 -400.69516)
		(end 47.357538 -400.558)
		(width 0.14224)
		(layer "In15.Cu")
		(net "P5E_CPU1_P0_RX_BUF_DP<0>")
	)
	(segment
		(start 57.490106 -436.849266)
		(end 57.490106 -419.811454)
		(width 0.14224)
		(layer "In15.Cu")
		(net "P5E_CPU1_P0_RX_BUF_DP<0>")
	)
	(segment
		(start 47.357538 -396.748)
		(end 47.494698 -396.61084)
		(width 0.14224)
		(layer "In15.Cu")
		(net "P5E_CPU1_P0_RX_BUF_DP<0>")
	)
	(segment
		(start 47.092616 -405.545036)
		(end 46.907958 -405.360378)
		(width 0.14224)
		(layer "In15.Cu")
		(net "P5E_CPU1_P0_RX_BUF_DP<0>")
	)
	(segment
		(start 47.357538 -396.04696)
		(end 47.357538 -395.62024)
		(width 0.14224)
		(layer "In15.Cu")
		(net "P5E_CPU1_P0_RX_BUF_DP<0>")
	)
	(segment
		(start 47.494698 -399.5674)
		(end 47.357538 -399.43024)
		(width 0.14224)
		(layer "In15.Cu")
		(net "P5E_CPU1_P0_RX_BUF_DP<0>")
	)
	(segment
		(start 46.756828 -404.995888)
		(end 46.756828 -404.424642)
		(width 0.14224)
		(layer "In15.Cu")
		(net "P5E_CPU1_P0_RX_BUF_DP<0>")
	)
	(segment
		(start 46.865794 -403.878034)
		(end 47.045372 -403.160738)
		(width 0.14224)
		(layer "In15.Cu")
		(net "P5E_CPU1_P0_RX_BUF_DP<0>")
	)
	(segment
		(start 48.366934 -408.126692)
		(end 48.504094 -407.989532)
		(width 0.14224)
		(layer "In15.Cu")
		(net "P5E_CPU1_P0_RX_BUF_DP<0>")
	)
	(segment
		(start 47.494698 -397.7386)
		(end 47.494698 -397.31188)
		(width 0.14224)
		(layer "In15.Cu")
		(net "P5E_CPU1_P0_RX_BUF_DP<0>")
	)
	(segment
		(start 47.357538 -400.13128)
		(end 47.494698 -399.99412)
		(width 0.14224)
		(layer "In15.Cu")
		(net "P5E_CPU1_P0_RX_BUF_DP<0>")
	)
	(segment
		(start 48.585628 -410.92755)
		(end 48.46193 -410.803852)
		(width 0.14224)
		(layer "In15.Cu")
		(net "P5E_CPU1_P0_RX_BUF_DP<0>")
	)
	(segment
		(start 48.504094 -407.562812)
		(end 48.366934 -407.425652)
		(width 0.14224)
		(layer "In15.Cu")
		(net "P5E_CPU1_P0_RX_BUF_DP<0>")
	)
	(segment
		(start 48.256698 -406.1587)
		(end 47.672752 -405.574754)
		(width 0.14224)
		(layer "In15.Cu")
		(net "P5E_CPU1_P0_RX_BUF_DP<0>")
	)
	(segment
		(start 56.649112 -418.238178)
		(end 50.12944 -413.881316)
		(width 0.14224)
		(layer "In15.Cu")
		(net "P5E_CPU1_P0_RX_BUF_DP<0>")
	)
	(segment
		(start 48.366934 -410.574744)
		(end 48.366934 -408.126692)
		(width 0.14224)
		(layer "In15.Cu")
		(net "P5E_CPU1_P0_RX_BUF_DP<0>")
	)
	(segment
		(start 48.366934 -406.424892)
		(end 48.256698 -406.1587)
		(width 0.14224)
		(layer "In15.Cu")
		(net "P5E_CPU1_P0_RX_BUF_DP<0>")
	)
	(segment
		(start 47.494698 -396.61084)
		(end 47.494698 -396.18412)
		(width 0.14224)
		(layer "In15.Cu")
		(net "P5E_CPU1_P0_RX_BUF_DP<0>")
	)
	(segment
		(start 47.357538 -401.914868)
		(end 47.357538 -401.25904)
		(width 0.14224)
		(layer "In15.Cu")
		(net "P5E_CPU1_P0_RX_BUF_DP<0>")
	)
	(segment
		(start 47.494698 -395.48308)
		(end 47.494698 -395.05636)
		(width 0.14224)
		(layer "In15.Cu")
		(net "P5E_CPU1_P0_RX_BUF_DP<0>")
	)
	(segment
		(start 47.67707 -392.989562)
		(end 47.816516 -393.129008)
		(width 0.14224)
		(layer "In15.Cu")
		(net "P5E_CPU1_P0_RX_BUF_DP<0>")
	)
	(segment
		(start 47.357538 -399.00352)
		(end 47.494698 -398.86636)
		(width 0.14224)
		(layer "In15.Cu")
		(net "P5E_CPU1_P0_RX_BUF_DP<0>")
	)
	(segment
		(start 47.672752 -405.574754)
		(end 47.164244 -405.574754)
		(width 0.14224)
		(layer "In15.Cu")
		(net "P5E_CPU1_P0_RX_BUF_DP<0>")
	)
	(segment
		(start 57.97804 -437.3372)
		(end 57.490106 -436.849266)
		(width 0.14224)
		(layer "In15.Cu")
		(net "P5E_CPU1_P0_RX_BUF_DP<0>")
	)
	(segment
		(start 58.64987 -436.889906)
		(end 58.64987 -437.19115)
		(width 0.14224)
		(layer "In15.Cu")
		(net "P5E_CPU1_P0_RX_BUF_DP<0>")
	)
	(segment
		(start 47.357538 -395.62024)
		(end 47.494698 -395.48308)
		(width 0.14224)
		(layer "In15.Cu")
		(net "P5E_CPU1_P0_RX_BUF_DP<0>")
	)
	(segment
		(start 58.50382 -437.3372)
		(end 57.97804 -437.3372)
		(width 0.14224)
		(layer "In15.Cu")
		(net "P5E_CPU1_P0_RX_BUF_DP<0>")
	)
	(segment
		(start 47.315628 -402.646896)
		(end 47.21606 -402.480526)
		(width 0.14224)
		(layer "In15.Cu")
		(net "P5E_CPU1_P0_RX_BUF_DP<0>")
	)
	(segment
		(start 47.211996 -403.06117)
		(end 47.315628 -402.646896)
		(width 0.14224)
		(layer "In15.Cu")
		(net "P5E_CPU1_P0_RX_BUF_DP<0>")
	)
	(arc
		(start 57.490106 -419.811454)
		(mid 57.266661 -418.919485)
		(end 56.649112 -418.238178)
		(width 0.14224)
		(layer "In15.Cu")
		(net "P5E_CPU1_P0_RX_BUF_DP<0>")
	)
	(segment
		(start 58.218578 -390.761982)
		(end 58.218578 -391.578338)
		(width 0.1016)
		(layer "F.Cu")
		(net "P5E_CPU1_P0_RX_BUF_DN<9>")
	)
	(segment
		(start 58.218578 -391.578338)
		(end 58.147458 -391.649458)
		(width 0.1016)
		(layer "F.Cu")
		(net "P5E_CPU1_P0_RX_BUF_DN<9>")
	)
	(segment
		(start 58.147458 -392.634216)
		(end 58.274458 -392.761216)
		(width 0.1016)
		(layer "F.Cu")
		(net "P5E_CPU1_P0_RX_BUF_DN<9>")
	)
	(segment
		(start 58.21807 -390.761474)
		(end 58.218578 -390.761982)
		(width 0.1016)
		(layer "F.Cu")
		(net "P5E_CPU1_P0_RX_BUF_DN<9>")
	)
	(segment
		(start 58.47588 -392.761216)
		(end 58.616596 -392.6205)
		(width 0.1016)
		(layer "F.Cu")
		(net "P5E_CPU1_P0_RX_BUF_DN<9>")
	)
	(segment
		(start 58.147458 -391.649458)
		(end 58.147458 -392.634216)
		(width 0.1016)
		(layer "F.Cu")
		(net "P5E_CPU1_P0_RX_BUF_DN<9>")
	)
	(segment
		(start 58.274458 -392.761216)
		(end 58.47588 -392.761216)
		(width 0.1016)
		(layer "F.Cu")
		(net "P5E_CPU1_P0_RX_BUF_DN<9>")
	)
	(segment
		(start 58.616596 -392.6205)
		(end 58.616596 -392.429238)
		(width 0.1016)
		(layer "F.Cu")
		(net "P5E_CPU1_P0_RX_BUF_DN<9>")
	)
	(segment
		(start 59.470798 -397.993108)
		(end 59.470544 -397.993108)
		(width 0.14224)
		(layer "In15.Cu")
		(net "P5E_CPU1_P0_RX_BUF_DN<9>")
	)
	(segment
		(start 75.491594 -406.088596)
		(end 75.309476 -405.906478)
		(width 0.14224)
		(layer "In15.Cu")
		(net "P5E_CPU1_P0_RX_BUF_DN<9>")
	)
	(segment
		(start 77.650086 -439.0898)
		(end 77.650086 -438.76976)
		(width 0.14224)
		(layer "In15.Cu")
		(net "P5E_CPU1_P0_RX_BUF_DN<9>")
	)
	(segment
		(start 58.616596 -392.580622)
		(end 58.616596 -392.429238)
		(width 0.14224)
		(layer "In15.Cu")
		(net "P5E_CPU1_P0_RX_BUF_DN<9>")
	)
	(segment
		(start 58.467752 -392.729466)
		(end 58.616596 -392.580622)
		(width 0.14224)
		(layer "In15.Cu")
		(net "P5E_CPU1_P0_RX_BUF_DN<9>")
	)
	(segment
		(start 77.104748 -411.808422)
		(end 76.955396 -411.584648)
		(width 0.14224)
		(layer "In15.Cu")
		(net "P5E_CPU1_P0_RX_BUF_DN<9>")
	)
	(segment
		(start 76.12634 -411.24124)
		(end 76.12634 -411.241494)
		(width 0.14224)
		(layer "In15.Cu")
		(net "P5E_CPU1_P0_RX_BUF_DN<9>")
	)
	(segment
		(start 77.650086 -438.76976)
		(end 77.503528 -438.623202)
		(width 0.14224)
		(layer "In15.Cu")
		(net "P5E_CPU1_P0_RX_BUF_DN<9>")
	)
	(segment
		(start 75.189334 -405.856694)
		(end 74.677016 -405.856694)
		(width 0.14224)
		(layer "In15.Cu")
		(net "P5E_CPU1_P0_RX_BUF_DN<9>")
	)
	(segment
		(start 75.309476 -405.906478)
		(end 75.189334 -405.856694)
		(width 0.14224)
		(layer "In15.Cu")
		(net "P5E_CPU1_P0_RX_BUF_DN<9>")
	)
	(segment
		(start 77.503528 -438.623202)
		(end 76.991718 -438.623202)
		(width 0.14224)
		(layer "In15.Cu")
		(net "P5E_CPU1_P0_RX_BUF_DN<9>")
	)
	(segment
		(start 76.955396 -411.584648)
		(end 76.12634 -411.24124)
		(width 0.14224)
		(layer "In15.Cu")
		(net "P5E_CPU1_P0_RX_BUF_DN<9>")
	)
	(segment
		(start 58.167778 -392.729466)
		(end 58.467752 -392.729466)
		(width 0.14224)
		(layer "In15.Cu")
		(net "P5E_CPU1_P0_RX_BUF_DN<9>")
	)
	(segment
		(start 75.777598 -410.928566)
		(end 75.654154 -410.630878)
		(width 0.14224)
		(layer "In15.Cu")
		(net "P5E_CPU1_P0_RX_BUF_DN<9>")
	)
	(segment
		(start 60.307982 -398.830292)
		(end 59.470798 -397.993108)
		(width 0.14224)
		(layer "In15.Cu")
		(net "P5E_CPU1_P0_RX_BUF_DN<9>")
	)
	(segment
		(start 74.677016 -405.856694)
		(end 74.50201 -405.78405)
		(width 0.14224)
		(layer "In15.Cu")
		(net "P5E_CPU1_P0_RX_BUF_DN<9>")
	)
	(segment
		(start 57.875678 -393.021566)
		(end 58.167778 -392.729466)
		(width 0.14224)
		(layer "In15.Cu")
		(net "P5E_CPU1_P0_RX_BUF_DN<9>")
	)
	(segment
		(start 57.875678 -396.228316)
		(end 57.875678 -393.021566)
		(width 0.14224)
		(layer "In15.Cu")
		(net "P5E_CPU1_P0_RX_BUF_DN<9>")
	)
	(segment
		(start 73.94956 -403.263862)
		(end 73.486772 -403.072092)
		(width 0.14224)
		(layer "In15.Cu")
		(net "P5E_CPU1_P0_RX_BUF_DN<9>")
	)
	(segment
		(start 74.122534 -405.240998)
		(end 74.122534 -403.52218)
		(width 0.14224)
		(layer "In15.Cu")
		(net "P5E_CPU1_P0_RX_BUF_DN<9>")
	)
	(segment
		(start 76.991718 -438.623202)
		(end 76.69403 -438.325514)
		(width 0.14224)
		(layer "In15.Cu")
		(net "P5E_CPU1_P0_RX_BUF_DN<9>")
	)
	(segment
		(start 74.50201 -405.78405)
		(end 74.238104 -405.520144)
		(width 0.14224)
		(layer "In15.Cu")
		(net "P5E_CPU1_P0_RX_BUF_DN<9>")
	)
	(segment
		(start 76.12634 -411.241494)
		(end 76.100178 -411.230572)
		(width 0.14224)
		(layer "In15.Cu")
		(net "P5E_CPU1_P0_RX_BUF_DN<9>")
	)
	(segment
		(start 75.654154 -406.481026)
		(end 75.491594 -406.088596)
		(width 0.14224)
		(layer "In15.Cu")
		(net "P5E_CPU1_P0_RX_BUF_DN<9>")
	)
	(segment
		(start 76.741528 -416.724084)
		(end 77.185774 -413.169354)
		(width 0.14224)
		(layer "In15.Cu")
		(net "P5E_CPU1_P0_RX_BUF_DN<9>")
	)
	(segment
		(start 76.100178 -411.230572)
		(end 76.03744 -411.188408)
		(width 0.14224)
		(layer "In15.Cu")
		(net "P5E_CPU1_P0_RX_BUF_DN<9>")
	)
	(segment
		(start 76.69403 -438.325514)
		(end 76.69403 -417.71951)
		(width 0.14224)
		(layer "In15.Cu")
		(net "P5E_CPU1_P0_RX_BUF_DN<9>")
	)
	(segment
		(start 74.122534 -403.52218)
		(end 73.94956 -403.263862)
		(width 0.14224)
		(layer "In15.Cu")
		(net "P5E_CPU1_P0_RX_BUF_DN<9>")
	)
	(segment
		(start 74.238104 -405.520144)
		(end 74.122534 -405.240998)
		(width 0.14224)
		(layer "In15.Cu")
		(net "P5E_CPU1_P0_RX_BUF_DN<9>")
	)
	(segment
		(start 75.654154 -410.630878)
		(end 75.654154 -406.481026)
		(width 0.14224)
		(layer "In15.Cu")
		(net "P5E_CPU1_P0_RX_BUF_DN<9>")
	)
	(segment
		(start 73.486772 -403.072092)
		(end 61.13018 -399.323306)
		(width 0.14224)
		(layer "In15.Cu")
		(net "P5E_CPU1_P0_RX_BUF_DN<9>")
	)
	(segment
		(start 76.69403 -417.71951)
		(end 76.741528 -416.724084)
		(width 0.14224)
		(layer "In15.Cu")
		(net "P5E_CPU1_P0_RX_BUF_DN<9>")
	)
	(segment
		(start 77.185774 -412.003494)
		(end 77.104748 -411.808422)
		(width 0.14224)
		(layer "In15.Cu")
		(net "P5E_CPU1_P0_RX_BUF_DN<9>")
	)
	(segment
		(start 59.470544 -397.993108)
		(end 57.995566 -396.517876)
		(width 0.14224)
		(layer "In15.Cu")
		(net "P5E_CPU1_P0_RX_BUF_DN<9>")
	)
	(segment
		(start 77.185774 -413.169354)
		(end 77.185774 -412.003494)
		(width 0.14224)
		(layer "In15.Cu")
		(net "P5E_CPU1_P0_RX_BUF_DN<9>")
	)
	(segment
		(start 76.03744 -411.188408)
		(end 75.777598 -410.928566)
		(width 0.14224)
		(layer "In15.Cu")
		(net "P5E_CPU1_P0_RX_BUF_DN<9>")
	)
	(arc
		(start 61.13018 -399.323306)
		(mid 60.688696 -399.127477)
		(end 60.307982 -398.830292)
		(width 0.14224)
		(layer "In15.Cu")
		(net "P5E_CPU1_P0_RX_BUF_DN<9>")
	)
	(arc
		(start 57.995566 -396.517876)
		(mid 57.906851 -396.385011)
		(end 57.875678 -396.228316)
		(width 0.14224)
		(layer "In15.Cu")
		(net "P5E_CPU1_P0_RX_BUF_DN<9>")
	)
	(segment
		(start 56.929782 -391.666984)
		(end 57.018428 -391.578338)
		(width 0.1016)
		(layer "F.Cu")
		(net "P5E_CPU1_P0_RX_BUF_DN<8>")
	)
	(segment
		(start 57.4167 -392.620246)
		(end 57.27573 -392.761216)
		(width 0.1016)
		(layer "F.Cu")
		(net "P5E_CPU1_P0_RX_BUF_DN<8>")
	)
	(segment
		(start 57.27573 -392.761216)
		(end 57.056782 -392.761216)
		(width 0.1016)
		(layer "F.Cu")
		(net "P5E_CPU1_P0_RX_BUF_DN<8>")
	)
	(segment
		(start 57.4167 -392.429238)
		(end 57.4167 -392.620246)
		(width 0.1016)
		(layer "F.Cu")
		(net "P5E_CPU1_P0_RX_BUF_DN<8>")
	)
	(segment
		(start 56.929782 -392.634216)
		(end 56.929782 -391.666984)
		(width 0.1016)
		(layer "F.Cu")
		(net "P5E_CPU1_P0_RX_BUF_DN<8>")
	)
	(segment
		(start 57.018428 -390.761982)
		(end 57.01792 -390.761474)
		(width 0.1016)
		(layer "F.Cu")
		(net "P5E_CPU1_P0_RX_BUF_DN<8>")
	)
	(segment
		(start 57.018428 -391.578338)
		(end 57.018428 -390.761982)
		(width 0.1016)
		(layer "F.Cu")
		(net "P5E_CPU1_P0_RX_BUF_DN<8>")
	)
	(segment
		(start 57.056782 -392.761216)
		(end 56.929782 -392.634216)
		(width 0.1016)
		(layer "F.Cu")
		(net "P5E_CPU1_P0_RX_BUF_DN<8>")
	)
	(segment
		(start 71.613776 -405.856694)
		(end 71.43877 -405.78405)
		(width 0.14224)
		(layer "In15.Cu")
		(net "P5E_CPU1_P0_RX_BUF_DN<8>")
	)
	(segment
		(start 71.059294 -405.241252)
		(end 71.059294 -403.51583)
		(width 0.14224)
		(layer "In15.Cu")
		(net "P5E_CPU1_P0_RX_BUF_DN<8>")
	)
	(segment
		(start 75.65009 -437.769762)
		(end 75.499468 -437.61914)
		(width 0.14224)
		(layer "In15.Cu")
		(net "P5E_CPU1_P0_RX_BUF_DN<8>")
	)
	(segment
		(start 72.194928 -405.885142)
		(end 72.126348 -405.856694)
		(width 0.14224)
		(layer "In15.Cu")
		(net "P5E_CPU1_P0_RX_BUF_DN<8>")
	)
	(segment
		(start 72.449436 -406.13965)
		(end 72.194928 -405.885142)
		(width 0.14224)
		(layer "In15.Cu")
		(net "P5E_CPU1_P0_RX_BUF_DN<8>")
	)
	(segment
		(start 71.059294 -403.51583)
		(end 70.78853 -403.245066)
		(width 0.14224)
		(layer "In15.Cu")
		(net "P5E_CPU1_P0_RX_BUF_DN<8>")
	)
	(segment
		(start 56.980328 -392.707622)
		(end 57.2897 -392.707622)
		(width 0.14224)
		(layer "In15.Cu")
		(net "P5E_CPU1_P0_RX_BUF_DN<8>")
	)
	(segment
		(start 56.675782 -393.012168)
		(end 56.980328 -392.707622)
		(width 0.14224)
		(layer "In15.Cu")
		(net "P5E_CPU1_P0_RX_BUF_DN<8>")
	)
	(segment
		(start 59.068208 -399.23593)
		(end 56.79567 -396.963392)
		(width 0.14224)
		(layer "In15.Cu")
		(net "P5E_CPU1_P0_RX_BUF_DN<8>")
	)
	(segment
		(start 74.27214 -414.764728)
		(end 74.122534 -413.2453)
		(width 0.14224)
		(layer "In15.Cu")
		(net "P5E_CPU1_P0_RX_BUF_DN<8>")
	)
	(segment
		(start 59.855354 -399.92808)
		(end 59.619134 -399.786602)
		(width 0.14224)
		(layer "In15.Cu")
		(net "P5E_CPU1_P0_RX_BUF_DN<8>")
	)
	(segment
		(start 74.982832 -437.61914)
		(end 74.27214 -436.908448)
		(width 0.14224)
		(layer "In15.Cu")
		(net "P5E_CPU1_P0_RX_BUF_DN<8>")
	)
	(segment
		(start 72.728836 -410.963618)
		(end 72.590914 -410.630878)
		(width 0.14224)
		(layer "In15.Cu")
		(net "P5E_CPU1_P0_RX_BUF_DN<8>")
	)
	(segment
		(start 72.911716 -411.146498)
		(end 72.728836 -410.963618)
		(width 0.14224)
		(layer "In15.Cu")
		(net "P5E_CPU1_P0_RX_BUF_DN<8>")
	)
	(segment
		(start 56.675782 -396.673832)
		(end 56.675782 -393.012168)
		(width 0.14224)
		(layer "In15.Cu")
		(net "P5E_CPU1_P0_RX_BUF_DN<8>")
	)
	(segment
		(start 71.174864 -405.520144)
		(end 71.059294 -405.241252)
		(width 0.14224)
		(layer "In15.Cu")
		(net "P5E_CPU1_P0_RX_BUF_DN<8>")
	)
	(segment
		(start 73.036938 -411.230318)
		(end 72.911716 -411.146498)
		(width 0.14224)
		(layer "In15.Cu")
		(net "P5E_CPU1_P0_RX_BUF_DN<8>")
	)
	(segment
		(start 75.499468 -437.61914)
		(end 74.982832 -437.61914)
		(width 0.14224)
		(layer "In15.Cu")
		(net "P5E_CPU1_P0_RX_BUF_DN<8>")
	)
	(segment
		(start 74.122534 -412.003748)
		(end 74.019664 -411.755082)
		(width 0.14224)
		(layer "In15.Cu")
		(net "P5E_CPU1_P0_RX_BUF_DN<8>")
	)
	(segment
		(start 70.78853 -403.245066)
		(end 59.855354 -399.92808)
		(width 0.14224)
		(layer "In15.Cu")
		(net "P5E_CPU1_P0_RX_BUF_DN<8>")
	)
	(segment
		(start 72.590914 -410.630878)
		(end 72.590914 -406.481026)
		(width 0.14224)
		(layer "In15.Cu")
		(net "P5E_CPU1_P0_RX_BUF_DN<8>")
	)
	(segment
		(start 57.2897 -392.707622)
		(end 57.4167 -392.580622)
		(width 0.14224)
		(layer "In15.Cu")
		(net "P5E_CPU1_P0_RX_BUF_DN<8>")
	)
	(segment
		(start 75.65009 -438.089802)
		(end 75.65009 -437.769762)
		(width 0.14224)
		(layer "In15.Cu")
		(net "P5E_CPU1_P0_RX_BUF_DN<8>")
	)
	(segment
		(start 59.619134 -399.786602)
		(end 59.068462 -399.23593)
		(width 0.14224)
		(layer "In15.Cu")
		(net "P5E_CPU1_P0_RX_BUF_DN<8>")
	)
	(segment
		(start 72.126348 -405.856694)
		(end 71.613776 -405.856694)
		(width 0.14224)
		(layer "In15.Cu")
		(net "P5E_CPU1_P0_RX_BUF_DN<8>")
	)
	(segment
		(start 74.27214 -436.908448)
		(end 74.27214 -414.764728)
		(width 0.14224)
		(layer "In15.Cu")
		(net "P5E_CPU1_P0_RX_BUF_DN<8>")
	)
	(segment
		(start 59.068462 -399.23593)
		(end 59.068208 -399.23593)
		(width 0.14224)
		(layer "In15.Cu")
		(net "P5E_CPU1_P0_RX_BUF_DN<8>")
	)
	(segment
		(start 57.4167 -392.580622)
		(end 57.4167 -392.429238)
		(width 0.14224)
		(layer "In15.Cu")
		(net "P5E_CPU1_P0_RX_BUF_DN<8>")
	)
	(segment
		(start 74.019664 -411.755082)
		(end 73.818496 -411.553914)
		(width 0.14224)
		(layer "In15.Cu")
		(net "P5E_CPU1_P0_RX_BUF_DN<8>")
	)
	(segment
		(start 71.43877 -405.78405)
		(end 71.174864 -405.520144)
		(width 0.14224)
		(layer "In15.Cu")
		(net "P5E_CPU1_P0_RX_BUF_DN<8>")
	)
	(segment
		(start 74.122534 -413.2453)
		(end 74.122534 -412.003748)
		(width 0.14224)
		(layer "In15.Cu")
		(net "P5E_CPU1_P0_RX_BUF_DN<8>")
	)
	(segment
		(start 73.818496 -411.553914)
		(end 73.036938 -411.230318)
		(width 0.14224)
		(layer "In15.Cu")
		(net "P5E_CPU1_P0_RX_BUF_DN<8>")
	)
	(segment
		(start 72.590914 -406.481026)
		(end 72.449436 -406.13965)
		(width 0.14224)
		(layer "In15.Cu")
		(net "P5E_CPU1_P0_RX_BUF_DN<8>")
	)
	(arc
		(start 56.79567 -396.963392)
		(mid 56.706955 -396.830527)
		(end 56.675782 -396.673832)
		(width 0.14224)
		(layer "In15.Cu")
		(net "P5E_CPU1_P0_RX_BUF_DN<8>")
	)
	(segment
		(start 55.729886 -391.666984)
		(end 55.729886 -392.634216)
		(width 0.1016)
		(layer "F.Cu")
		(net "P5E_CPU1_P0_RX_BUF_DN<7>")
	)
	(segment
		(start 55.856886 -392.761216)
		(end 56.075834 -392.761216)
		(width 0.1016)
		(layer "F.Cu")
		(net "P5E_CPU1_P0_RX_BUF_DN<7>")
	)
	(segment
		(start 55.818532 -390.761982)
		(end 55.818532 -391.578338)
		(width 0.1016)
		(layer "F.Cu")
		(net "P5E_CPU1_P0_RX_BUF_DN<7>")
	)
	(segment
		(start 55.729886 -392.634216)
		(end 55.856886 -392.761216)
		(width 0.1016)
		(layer "F.Cu")
		(net "P5E_CPU1_P0_RX_BUF_DN<7>")
	)
	(segment
		(start 55.818532 -391.578338)
		(end 55.729886 -391.666984)
		(width 0.1016)
		(layer "F.Cu")
		(net "P5E_CPU1_P0_RX_BUF_DN<7>")
	)
	(segment
		(start 55.818024 -390.761474)
		(end 55.818532 -390.761982)
		(width 0.1016)
		(layer "F.Cu")
		(net "P5E_CPU1_P0_RX_BUF_DN<7>")
	)
	(segment
		(start 56.075834 -392.761216)
		(end 56.21655 -392.6205)
		(width 0.1016)
		(layer "F.Cu")
		(net "P5E_CPU1_P0_RX_BUF_DN<7>")
	)
	(segment
		(start 56.21655 -392.6205)
		(end 56.21655 -392.429238)
		(width 0.1016)
		(layer "F.Cu")
		(net "P5E_CPU1_P0_RX_BUF_DN<7>")
	)
	(segment
		(start 69.063108 -405.856694)
		(end 68.709286 -405.856694)
		(width 0.14224)
		(layer "In15.Cu")
		(net "P5E_CPU1_P0_RX_BUF_DN<7>")
	)
	(segment
		(start 67.851782 -403.45614)
		(end 67.45097 -403.290278)
		(width 0.14224)
		(layer "In15.Cu")
		(net "P5E_CPU1_P0_RX_BUF_DN<7>")
	)
	(segment
		(start 56.08955 -392.707622)
		(end 56.21655 -392.580622)
		(width 0.14224)
		(layer "In15.Cu")
		(net "P5E_CPU1_P0_RX_BUF_DN<7>")
	)
	(segment
		(start 67.45097 -403.290278)
		(end 66.841878 -403.290278)
		(width 0.14224)
		(layer "In15.Cu")
		(net "P5E_CPU1_P0_RX_BUF_DN<7>")
	)
	(segment
		(start 71.996554 -438.619392)
		(end 71.699628 -438.322466)
		(width 0.14224)
		(layer "In15.Cu")
		(net "P5E_CPU1_P0_RX_BUF_DN<7>")
	)
	(segment
		(start 71.059294 -413.239458)
		(end 71.059294 -412.003748)
		(width 0.14224)
		(layer "In15.Cu")
		(net "P5E_CPU1_P0_RX_BUF_DN<7>")
	)
	(segment
		(start 55.475632 -393.012168)
		(end 55.780178 -392.707622)
		(width 0.14224)
		(layer "In15.Cu")
		(net "P5E_CPU1_P0_RX_BUF_DN<7>")
	)
	(segment
		(start 65.748154 -402.83765)
		(end 64.495172 -402.319236)
		(width 0.14224)
		(layer "In15.Cu")
		(net "P5E_CPU1_P0_RX_BUF_DN<7>")
	)
	(segment
		(start 69.527674 -406.481026)
		(end 69.386196 -406.13965)
		(width 0.14224)
		(layer "In15.Cu")
		(net "P5E_CPU1_P0_RX_BUF_DN<7>")
	)
	(segment
		(start 69.665596 -410.963618)
		(end 69.527674 -410.630878)
		(width 0.14224)
		(layer "In15.Cu")
		(net "P5E_CPU1_P0_RX_BUF_DN<7>")
	)
	(segment
		(start 69.386196 -406.13965)
		(end 69.131688 -405.885142)
		(width 0.14224)
		(layer "In15.Cu")
		(net "P5E_CPU1_P0_RX_BUF_DN<7>")
	)
	(segment
		(start 69.848476 -411.146498)
		(end 69.665596 -410.963618)
		(width 0.14224)
		(layer "In15.Cu")
		(net "P5E_CPU1_P0_RX_BUF_DN<7>")
	)
	(segment
		(start 55.780178 -392.707622)
		(end 56.08955 -392.707622)
		(width 0.14224)
		(layer "In15.Cu")
		(net "P5E_CPU1_P0_RX_BUF_DN<7>")
	)
	(segment
		(start 58.64352 -400.37131)
		(end 55.59552 -397.32331)
		(width 0.14224)
		(layer "In15.Cu")
		(net "P5E_CPU1_P0_RX_BUF_DN<7>")
	)
	(segment
		(start 67.996054 -403.671786)
		(end 67.851782 -403.45614)
		(width 0.14224)
		(layer "In15.Cu")
		(net "P5E_CPU1_P0_RX_BUF_DN<7>")
	)
	(segment
		(start 71.699628 -417.962842)
		(end 71.178674 -414.4518)
		(width 0.14224)
		(layer "In15.Cu")
		(net "P5E_CPU1_P0_RX_BUF_DN<7>")
	)
	(segment
		(start 55.475632 -397.03375)
		(end 55.475632 -393.012168)
		(width 0.14224)
		(layer "In15.Cu")
		(net "P5E_CPU1_P0_RX_BUF_DN<7>")
	)
	(segment
		(start 70.928738 -411.689042)
		(end 70.821042 -411.581092)
		(width 0.14224)
		(layer "In15.Cu")
		(net "P5E_CPU1_P0_RX_BUF_DN<7>")
	)
	(segment
		(start 66.841878 -403.290278)
		(end 65.7479 -402.83765)
		(width 0.14224)
		(layer "In15.Cu")
		(net "P5E_CPU1_P0_RX_BUF_DN<7>")
	)
	(segment
		(start 67.996054 -405.143462)
		(end 67.996054 -403.671786)
		(width 0.14224)
		(layer "In15.Cu")
		(net "P5E_CPU1_P0_RX_BUF_DN<7>")
	)
	(segment
		(start 69.527674 -410.630878)
		(end 69.527674 -406.481026)
		(width 0.14224)
		(layer "In15.Cu")
		(net "P5E_CPU1_P0_RX_BUF_DN<7>")
	)
	(segment
		(start 69.973698 -411.230318)
		(end 69.848476 -411.146498)
		(width 0.14224)
		(layer "In15.Cu")
		(net "P5E_CPU1_P0_RX_BUF_DN<7>")
	)
	(segment
		(start 64.495172 -402.319236)
		(end 59.225942 -400.72056)
		(width 0.14224)
		(layer "In15.Cu")
		(net "P5E_CPU1_P0_RX_BUF_DN<7>")
	)
	(segment
		(start 69.131688 -405.885142)
		(end 69.063108 -405.856694)
		(width 0.14224)
		(layer "In15.Cu")
		(net "P5E_CPU1_P0_RX_BUF_DN<7>")
	)
	(segment
		(start 70.821042 -411.581092)
		(end 69.973698 -411.230318)
		(width 0.14224)
		(layer "In15.Cu")
		(net "P5E_CPU1_P0_RX_BUF_DN<7>")
	)
	(segment
		(start 65.7479 -402.83765)
		(end 65.748154 -402.83765)
		(width 0.14224)
		(layer "In15.Cu")
		(net "P5E_CPU1_P0_RX_BUF_DN<7>")
	)
	(segment
		(start 72.499474 -438.619392)
		(end 71.996554 -438.619392)
		(width 0.14224)
		(layer "In15.Cu")
		(net "P5E_CPU1_P0_RX_BUF_DN<7>")
	)
	(segment
		(start 56.21655 -392.580622)
		(end 56.21655 -392.429238)
		(width 0.14224)
		(layer "In15.Cu")
		(net "P5E_CPU1_P0_RX_BUF_DN<7>")
	)
	(segment
		(start 71.178674 -414.4518)
		(end 71.059294 -413.239458)
		(width 0.14224)
		(layer "In15.Cu")
		(net "P5E_CPU1_P0_RX_BUF_DN<7>")
	)
	(segment
		(start 71.699628 -438.322466)
		(end 71.699628 -417.962842)
		(width 0.14224)
		(layer "In15.Cu")
		(net "P5E_CPU1_P0_RX_BUF_DN<7>")
	)
	(segment
		(start 71.059294 -412.003748)
		(end 70.928738 -411.689042)
		(width 0.14224)
		(layer "In15.Cu")
		(net "P5E_CPU1_P0_RX_BUF_DN<7>")
	)
	(segment
		(start 72.649842 -439.0898)
		(end 72.649842 -438.76976)
		(width 0.14224)
		(layer "In15.Cu")
		(net "P5E_CPU1_P0_RX_BUF_DN<7>")
	)
	(segment
		(start 72.649842 -438.76976)
		(end 72.499474 -438.619392)
		(width 0.14224)
		(layer "In15.Cu")
		(net "P5E_CPU1_P0_RX_BUF_DN<7>")
	)
	(arc
		(start 59.225942 -400.72056)
		(mid 58.913218 -400.581816)
		(end 58.64352 -400.37131)
		(width 0.14224)
		(layer "In15.Cu")
		(net "P5E_CPU1_P0_RX_BUF_DN<7>")
	)
	(arc
		(start 68.709286 -405.856694)
		(mid 68.204955 -405.647793)
		(end 67.996054 -405.143462)
		(width 0.14224)
		(layer "In15.Cu")
		(net "P5E_CPU1_P0_RX_BUF_DN<7>")
	)
	(arc
		(start 55.59552 -397.32331)
		(mid 55.506805 -397.190445)
		(end 55.475632 -397.03375)
		(width 0.14224)
		(layer "In15.Cu")
		(net "P5E_CPU1_P0_RX_BUF_DN<7>")
	)
	(segment
		(start 54.618636 -390.761982)
		(end 54.618636 -391.365486)
		(width 0.1016)
		(layer "F.Cu")
		(net "P5E_CPU1_P0_RX_BUF_DN<6>")
	)
	(segment
		(start 55.016654 -392.6205)
		(end 55.016654 -392.429238)
		(width 0.1016)
		(layer "F.Cu")
		(net "P5E_CPU1_P0_RX_BUF_DN<6>")
	)
	(segment
		(start 54.618382 -391.36574)
		(end 54.618382 -391.578338)
		(width 0.1016)
		(layer "F.Cu")
		(net "P5E_CPU1_P0_RX_BUF_DN<6>")
	)
	(segment
		(start 54.618128 -390.761474)
		(end 54.618636 -390.761982)
		(width 0.1016)
		(layer "F.Cu")
		(net "P5E_CPU1_P0_RX_BUF_DN<6>")
	)
	(segment
		(start 54.618636 -391.365486)
		(end 54.618382 -391.36574)
		(width 0.1016)
		(layer "F.Cu")
		(net "P5E_CPU1_P0_RX_BUF_DN<6>")
	)
	(segment
		(start 54.618382 -391.578338)
		(end 54.538626 -391.658094)
		(width 0.1016)
		(layer "F.Cu")
		(net "P5E_CPU1_P0_RX_BUF_DN<6>")
	)
	(segment
		(start 54.538626 -391.658094)
		(end 54.538626 -392.634216)
		(width 0.1016)
		(layer "F.Cu")
		(net "P5E_CPU1_P0_RX_BUF_DN<6>")
	)
	(segment
		(start 54.875938 -392.761216)
		(end 55.016654 -392.6205)
		(width 0.1016)
		(layer "F.Cu")
		(net "P5E_CPU1_P0_RX_BUF_DN<6>")
	)
	(segment
		(start 54.665626 -392.761216)
		(end 54.875938 -392.761216)
		(width 0.1016)
		(layer "F.Cu")
		(net "P5E_CPU1_P0_RX_BUF_DN<6>")
	)
	(segment
		(start 54.538626 -392.634216)
		(end 54.665626 -392.761216)
		(width 0.1016)
		(layer "F.Cu")
		(net "P5E_CPU1_P0_RX_BUF_DN<6>")
	)
	(segment
		(start 54.889654 -392.707622)
		(end 55.016654 -392.580622)
		(width 0.14224)
		(layer "In15.Cu")
		(net "P5E_CPU1_P0_RX_BUF_DN<6>")
	)
	(segment
		(start 66.322956 -406.13965)
		(end 66.068448 -405.885142)
		(width 0.14224)
		(layer "In15.Cu")
		(net "P5E_CPU1_P0_RX_BUF_DN<6>")
	)
	(segment
		(start 70.649846 -438.089802)
		(end 70.649846 -437.769762)
		(width 0.14224)
		(layer "In15.Cu")
		(net "P5E_CPU1_P0_RX_BUF_DN<6>")
	)
	(segment
		(start 69.993764 -437.623204)
		(end 69.701664 -437.331104)
		(width 0.14224)
		(layer "In15.Cu")
		(net "P5E_CPU1_P0_RX_BUF_DN<6>")
	)
	(segment
		(start 57.545986 -400.86534)
		(end 57.545732 -400.86534)
		(width 0.14224)
		(layer "In15.Cu")
		(net "P5E_CPU1_P0_RX_BUF_DN<6>")
	)
	(segment
		(start 55.016654 -392.580622)
		(end 55.016654 -392.429238)
		(width 0.14224)
		(layer "In15.Cu")
		(net "P5E_CPU1_P0_RX_BUF_DN<6>")
	)
	(segment
		(start 54.580282 -392.707622)
		(end 54.889654 -392.707622)
		(width 0.14224)
		(layer "In15.Cu")
		(net "P5E_CPU1_P0_RX_BUF_DN<6>")
	)
	(segment
		(start 66.464434 -406.481026)
		(end 66.322956 -406.13965)
		(width 0.14224)
		(layer "In15.Cu")
		(net "P5E_CPU1_P0_RX_BUF_DN<6>")
	)
	(segment
		(start 67.667632 -411.543754)
		(end 66.910458 -411.230318)
		(width 0.14224)
		(layer "In15.Cu")
		(net "P5E_CPU1_P0_RX_BUF_DN<6>")
	)
	(segment
		(start 54.275736 -397.266922)
		(end 54.275736 -393.012168)
		(width 0.14224)
		(layer "In15.Cu")
		(net "P5E_CPU1_P0_RX_BUF_DN<6>")
	)
	(segment
		(start 64.327278 -403.272244)
		(end 58.215276 -401.418044)
		(width 0.14224)
		(layer "In15.Cu")
		(net "P5E_CPU1_P0_RX_BUF_DN<6>")
	)
	(segment
		(start 57.92343 -401.242784)
		(end 57.545986 -400.86534)
		(width 0.14224)
		(layer "In15.Cu")
		(net "P5E_CPU1_P0_RX_BUF_DN<6>")
	)
	(segment
		(start 64.932814 -405.240998)
		(end 64.932814 -403.87651)
		(width 0.14224)
		(layer "In15.Cu")
		(net "P5E_CPU1_P0_RX_BUF_DN<6>")
	)
	(segment
		(start 66.068448 -405.885142)
		(end 65.999868 -405.856694)
		(width 0.14224)
		(layer "In15.Cu")
		(net "P5E_CPU1_P0_RX_BUF_DN<6>")
	)
	(segment
		(start 65.037716 -405.494236)
		(end 64.932814 -405.240998)
		(width 0.14224)
		(layer "In15.Cu")
		(net "P5E_CPU1_P0_RX_BUF_DN<6>")
	)
	(segment
		(start 70.503288 -437.623204)
		(end 69.993764 -437.623204)
		(width 0.14224)
		(layer "In15.Cu")
		(net "P5E_CPU1_P0_RX_BUF_DN<6>")
	)
	(segment
		(start 65.999868 -405.856694)
		(end 65.48755 -405.856694)
		(width 0.14224)
		(layer "In15.Cu")
		(net "P5E_CPU1_P0_RX_BUF_DN<6>")
	)
	(segment
		(start 54.275736 -393.012168)
		(end 54.580282 -392.707622)
		(width 0.14224)
		(layer "In15.Cu")
		(net "P5E_CPU1_P0_RX_BUF_DN<6>")
	)
	(segment
		(start 65.338452 -405.795226)
		(end 65.037716 -405.494236)
		(width 0.14224)
		(layer "In15.Cu")
		(net "P5E_CPU1_P0_RX_BUF_DN<6>")
	)
	(segment
		(start 64.932814 -403.87651)
		(end 64.787272 -403.596094)
		(width 0.14224)
		(layer "In15.Cu")
		(net "P5E_CPU1_P0_RX_BUF_DN<6>")
	)
	(segment
		(start 67.996054 -412.004002)
		(end 67.902836 -411.778958)
		(width 0.14224)
		(layer "In15.Cu")
		(net "P5E_CPU1_P0_RX_BUF_DN<6>")
	)
	(segment
		(start 69.701664 -417.590224)
		(end 67.996054 -413.471614)
		(width 0.14224)
		(layer "In15.Cu")
		(net "P5E_CPU1_P0_RX_BUF_DN<6>")
	)
	(segment
		(start 67.902836 -411.778958)
		(end 67.667632 -411.543754)
		(width 0.14224)
		(layer "In15.Cu")
		(net "P5E_CPU1_P0_RX_BUF_DN<6>")
	)
	(segment
		(start 66.464434 -410.630878)
		(end 66.464434 -406.481026)
		(width 0.14224)
		(layer "In15.Cu")
		(net "P5E_CPU1_P0_RX_BUF_DN<6>")
	)
	(segment
		(start 66.602356 -410.963618)
		(end 66.464434 -410.630878)
		(width 0.14224)
		(layer "In15.Cu")
		(net "P5E_CPU1_P0_RX_BUF_DN<6>")
	)
	(segment
		(start 70.649846 -437.769762)
		(end 70.503288 -437.623204)
		(width 0.14224)
		(layer "In15.Cu")
		(net "P5E_CPU1_P0_RX_BUF_DN<6>")
	)
	(segment
		(start 67.996054 -413.471614)
		(end 67.996054 -412.004002)
		(width 0.14224)
		(layer "In15.Cu")
		(net "P5E_CPU1_P0_RX_BUF_DN<6>")
	)
	(segment
		(start 66.785236 -411.146498)
		(end 66.602356 -410.963618)
		(width 0.14224)
		(layer "In15.Cu")
		(net "P5E_CPU1_P0_RX_BUF_DN<6>")
	)
	(segment
		(start 64.787272 -403.596094)
		(end 64.327278 -403.272244)
		(width 0.14224)
		(layer "In15.Cu")
		(net "P5E_CPU1_P0_RX_BUF_DN<6>")
	)
	(segment
		(start 65.48755 -405.856694)
		(end 65.338452 -405.795226)
		(width 0.14224)
		(layer "In15.Cu")
		(net "P5E_CPU1_P0_RX_BUF_DN<6>")
	)
	(segment
		(start 69.701664 -437.331104)
		(end 69.701664 -417.590224)
		(width 0.14224)
		(layer "In15.Cu")
		(net "P5E_CPU1_P0_RX_BUF_DN<6>")
	)
	(segment
		(start 66.910458 -411.230318)
		(end 66.785236 -411.146498)
		(width 0.14224)
		(layer "In15.Cu")
		(net "P5E_CPU1_P0_RX_BUF_DN<6>")
	)
	(segment
		(start 57.545732 -400.86534)
		(end 54.507892 -397.827246)
		(width 0.14224)
		(layer "In15.Cu")
		(net "P5E_CPU1_P0_RX_BUF_DN<6>")
	)
	(arc
		(start 54.507892 -397.827246)
		(mid 54.336064 -397.570181)
		(end 54.275736 -397.266922)
		(width 0.14224)
		(layer "In15.Cu")
		(net "P5E_CPU1_P0_RX_BUF_DN<6>")
	)
	(arc
		(start 58.215276 -401.418044)
		(mid 58.058527 -401.348432)
		(end 57.92343 -401.242784)
		(width 0.14224)
		(layer "In15.Cu")
		(net "P5E_CPU1_P0_RX_BUF_DN<6>")
	)
	(segment
		(start 53.418486 -390.761982)
		(end 53.418486 -391.578338)
		(width 0.1016)
		(layer "F.Cu")
		(net "P5E_CPU1_P0_RX_BUF_DN<5>")
	)
	(segment
		(start 53.418486 -391.578338)
		(end 53.32984 -391.666984)
		(width 0.1016)
		(layer "F.Cu")
		(net "P5E_CPU1_P0_RX_BUF_DN<5>")
	)
	(segment
		(start 53.816504 -392.6205)
		(end 53.816504 -392.429238)
		(width 0.1016)
		(layer "F.Cu")
		(net "P5E_CPU1_P0_RX_BUF_DN<5>")
	)
	(segment
		(start 53.32984 -392.634216)
		(end 53.45684 -392.761216)
		(width 0.1016)
		(layer "F.Cu")
		(net "P5E_CPU1_P0_RX_BUF_DN<5>")
	)
	(segment
		(start 53.32984 -391.666984)
		(end 53.32984 -392.634216)
		(width 0.1016)
		(layer "F.Cu")
		(net "P5E_CPU1_P0_RX_BUF_DN<5>")
	)
	(segment
		(start 53.45684 -392.761216)
		(end 53.675788 -392.761216)
		(width 0.1016)
		(layer "F.Cu")
		(net "P5E_CPU1_P0_RX_BUF_DN<5>")
	)
	(segment
		(start 53.417978 -390.761474)
		(end 53.418486 -390.761982)
		(width 0.1016)
		(layer "F.Cu")
		(net "P5E_CPU1_P0_RX_BUF_DN<5>")
	)
	(segment
		(start 53.675788 -392.761216)
		(end 53.816504 -392.6205)
		(width 0.1016)
		(layer "F.Cu")
		(net "P5E_CPU1_P0_RX_BUF_DN<5>")
	)
	(segment
		(start 61.34735 -403.366478)
		(end 57.475374 -402.192744)
		(width 0.14224)
		(layer "In15.Cu")
		(net "P5E_CPU1_P0_RX_BUF_DN<5>")
	)
	(segment
		(start 53.689504 -392.707622)
		(end 53.816504 -392.580622)
		(width 0.14224)
		(layer "In15.Cu")
		(net "P5E_CPU1_P0_RX_BUF_DN<5>")
	)
	(segment
		(start 61.869574 -403.754844)
		(end 61.786008 -403.630638)
		(width 0.14224)
		(layer "In15.Cu")
		(net "P5E_CPU1_P0_RX_BUF_DN<5>")
	)
	(segment
		(start 66.30035 -415.12617)
		(end 65.365884 -413.987488)
		(width 0.14224)
		(layer "In15.Cu")
		(net "P5E_CPU1_P0_RX_BUF_DN<5>")
	)
	(segment
		(start 68.64985 -438.76976)
		(end 68.503292 -438.623202)
		(width 0.14224)
		(layer "In15.Cu")
		(net "P5E_CPU1_P0_RX_BUF_DN<5>")
	)
	(segment
		(start 65.365884 -413.987488)
		(end 64.932814 -413.33928)
		(width 0.14224)
		(layer "In15.Cu")
		(net "P5E_CPU1_P0_RX_BUF_DN<5>")
	)
	(segment
		(start 62.24905 -405.78405)
		(end 61.927232 -405.462232)
		(width 0.14224)
		(layer "In15.Cu")
		(net "P5E_CPU1_P0_RX_BUF_DN<5>")
	)
	(segment
		(start 67.700906 -417.598606)
		(end 66.30035 -415.12617)
		(width 0.14224)
		(layer "In15.Cu")
		(net "P5E_CPU1_P0_RX_BUF_DN<5>")
	)
	(segment
		(start 64.932814 -412.004002)
		(end 64.846708 -411.79623)
		(width 0.14224)
		(layer "In15.Cu")
		(net "P5E_CPU1_P0_RX_BUF_DN<5>")
	)
	(segment
		(start 63.005208 -405.885142)
		(end 62.936628 -405.856694)
		(width 0.14224)
		(layer "In15.Cu")
		(net "P5E_CPU1_P0_RX_BUF_DN<5>")
	)
	(segment
		(start 63.539116 -410.963618)
		(end 63.401194 -410.630878)
		(width 0.14224)
		(layer "In15.Cu")
		(net "P5E_CPU1_P0_RX_BUF_DN<5>")
	)
	(segment
		(start 63.259716 -406.13965)
		(end 63.005208 -405.885142)
		(width 0.14224)
		(layer "In15.Cu")
		(net "P5E_CPU1_P0_RX_BUF_DN<5>")
	)
	(segment
		(start 63.721996 -411.146498)
		(end 63.539116 -410.963618)
		(width 0.14224)
		(layer "In15.Cu")
		(net "P5E_CPU1_P0_RX_BUF_DN<5>")
	)
	(segment
		(start 61.927232 -405.462232)
		(end 61.869574 -405.32304)
		(width 0.14224)
		(layer "In15.Cu")
		(net "P5E_CPU1_P0_RX_BUF_DN<5>")
	)
	(segment
		(start 64.846708 -411.79623)
		(end 64.58712 -411.536642)
		(width 0.14224)
		(layer "In15.Cu")
		(net "P5E_CPU1_P0_RX_BUF_DN<5>")
	)
	(segment
		(start 64.58712 -411.536642)
		(end 63.847218 -411.230318)
		(width 0.14224)
		(layer "In15.Cu")
		(net "P5E_CPU1_P0_RX_BUF_DN<5>")
	)
	(segment
		(start 61.869574 -405.32304)
		(end 61.869574 -403.754844)
		(width 0.14224)
		(layer "In15.Cu")
		(net "P5E_CPU1_P0_RX_BUF_DN<5>")
	)
	(segment
		(start 53.380132 -392.707622)
		(end 53.689504 -392.707622)
		(width 0.14224)
		(layer "In15.Cu")
		(net "P5E_CPU1_P0_RX_BUF_DN<5>")
	)
	(segment
		(start 62.424056 -405.856694)
		(end 62.24905 -405.78405)
		(width 0.14224)
		(layer "In15.Cu")
		(net "P5E_CPU1_P0_RX_BUF_DN<5>")
	)
	(segment
		(start 56.73598 -401.749514)
		(end 53.195474 -398.209008)
		(width 0.14224)
		(layer "In15.Cu")
		(net "P5E_CPU1_P0_RX_BUF_DN<5>")
	)
	(segment
		(start 68.503292 -438.623202)
		(end 68.058284 -438.623202)
		(width 0.14224)
		(layer "In15.Cu")
		(net "P5E_CPU1_P0_RX_BUF_DN<5>")
	)
	(segment
		(start 68.058284 -438.623202)
		(end 67.700906 -438.265824)
		(width 0.14224)
		(layer "In15.Cu")
		(net "P5E_CPU1_P0_RX_BUF_DN<5>")
	)
	(segment
		(start 64.932814 -413.33928)
		(end 64.932814 -412.004002)
		(width 0.14224)
		(layer "In15.Cu")
		(net "P5E_CPU1_P0_RX_BUF_DN<5>")
	)
	(segment
		(start 62.936628 -405.856694)
		(end 62.424056 -405.856694)
		(width 0.14224)
		(layer "In15.Cu")
		(net "P5E_CPU1_P0_RX_BUF_DN<5>")
	)
	(segment
		(start 53.816504 -392.580622)
		(end 53.816504 -392.429238)
		(width 0.14224)
		(layer "In15.Cu")
		(net "P5E_CPU1_P0_RX_BUF_DN<5>")
	)
	(segment
		(start 63.847218 -411.230318)
		(end 63.721996 -411.146498)
		(width 0.14224)
		(layer "In15.Cu")
		(net "P5E_CPU1_P0_RX_BUF_DN<5>")
	)
	(segment
		(start 67.700906 -438.265824)
		(end 67.700906 -417.598606)
		(width 0.14224)
		(layer "In15.Cu")
		(net "P5E_CPU1_P0_RX_BUF_DN<5>")
	)
	(segment
		(start 53.075586 -397.919448)
		(end 53.075586 -393.012168)
		(width 0.14224)
		(layer "In15.Cu")
		(net "P5E_CPU1_P0_RX_BUF_DN<5>")
	)
	(segment
		(start 63.401194 -410.630878)
		(end 63.401194 -406.481026)
		(width 0.14224)
		(layer "In15.Cu")
		(net "P5E_CPU1_P0_RX_BUF_DN<5>")
	)
	(segment
		(start 61.786008 -403.630638)
		(end 61.34735 -403.366478)
		(width 0.14224)
		(layer "In15.Cu")
		(net "P5E_CPU1_P0_RX_BUF_DN<5>")
	)
	(segment
		(start 63.401194 -406.481026)
		(end 63.259716 -406.13965)
		(width 0.14224)
		(layer "In15.Cu")
		(net "P5E_CPU1_P0_RX_BUF_DN<5>")
	)
	(segment
		(start 53.075586 -393.012168)
		(end 53.380132 -392.707622)
		(width 0.14224)
		(layer "In15.Cu")
		(net "P5E_CPU1_P0_RX_BUF_DN<5>")
	)
	(segment
		(start 68.64985 -439.0898)
		(end 68.64985 -438.76976)
		(width 0.14224)
		(layer "In15.Cu")
		(net "P5E_CPU1_P0_RX_BUF_DN<5>")
	)
	(arc
		(start 53.195474 -398.209008)
		(mid 53.106759 -398.076143)
		(end 53.075586 -397.919448)
		(width 0.14224)
		(layer "In15.Cu")
		(net "P5E_CPU1_P0_RX_BUF_DN<5>")
	)
	(arc
		(start 57.475374 -402.192744)
		(mid 57.078336 -402.016742)
		(end 56.73598 -401.749514)
		(width 0.14224)
		(layer "In15.Cu")
		(net "P5E_CPU1_P0_RX_BUF_DN<5>")
	)
	(segment
		(start 52.129944 -391.666984)
		(end 52.129944 -392.634216)
		(width 0.1016)
		(layer "F.Cu")
		(net "P5E_CPU1_P0_RX_BUF_DN<4>")
	)
	(segment
		(start 52.21859 -390.761982)
		(end 52.21859 -391.578338)
		(width 0.1016)
		(layer "F.Cu")
		(net "P5E_CPU1_P0_RX_BUF_DN<4>")
	)
	(segment
		(start 52.129944 -392.634216)
		(end 52.256944 -392.761216)
		(width 0.1016)
		(layer "F.Cu")
		(net "P5E_CPU1_P0_RX_BUF_DN<4>")
	)
	(segment
		(start 52.218082 -390.761474)
		(end 52.21859 -390.761982)
		(width 0.1016)
		(layer "F.Cu")
		(net "P5E_CPU1_P0_RX_BUF_DN<4>")
	)
	(segment
		(start 52.616608 -392.6205)
		(end 52.616608 -392.429238)
		(width 0.1016)
		(layer "F.Cu")
		(net "P5E_CPU1_P0_RX_BUF_DN<4>")
	)
	(segment
		(start 52.475892 -392.761216)
		(end 52.616608 -392.6205)
		(width 0.1016)
		(layer "F.Cu")
		(net "P5E_CPU1_P0_RX_BUF_DN<4>")
	)
	(segment
		(start 52.21859 -391.578338)
		(end 52.129944 -391.666984)
		(width 0.1016)
		(layer "F.Cu")
		(net "P5E_CPU1_P0_RX_BUF_DN<4>")
	)
	(segment
		(start 52.256944 -392.761216)
		(end 52.475892 -392.761216)
		(width 0.1016)
		(layer "F.Cu")
		(net "P5E_CPU1_P0_RX_BUF_DN<4>")
	)
	(segment
		(start 66.649854 -437.769762)
		(end 66.503296 -437.623204)
		(width 0.14224)
		(layer "In15.Cu")
		(net "P5E_CPU1_P0_RX_BUF_DN<4>")
	)
	(segment
		(start 56.308244 -402.951696)
		(end 52.00777 -398.651222)
		(width 0.14224)
		(layer "In15.Cu")
		(net "P5E_CPU1_P0_RX_BUF_DN<4>")
	)
	(segment
		(start 52.489608 -392.707622)
		(end 52.616608 -392.580622)
		(width 0.14224)
		(layer "In15.Cu")
		(net "P5E_CPU1_P0_RX_BUF_DN<4>")
	)
	(segment
		(start 65.47739 -416.961574)
		(end 65.173606 -416.591496)
		(width 0.14224)
		(layer "In15.Cu")
		(net "P5E_CPU1_P0_RX_BUF_DN<4>")
	)
	(segment
		(start 61.562742 -411.552898)
		(end 60.783724 -411.230318)
		(width 0.14224)
		(layer "In15.Cu")
		(net "P5E_CPU1_P0_RX_BUF_DN<4>")
	)
	(segment
		(start 58.689494 -403.712934)
		(end 58.479436 -403.502876)
		(width 0.14224)
		(layer "In15.Cu")
		(net "P5E_CPU1_P0_RX_BUF_DN<4>")
	)
	(segment
		(start 60.196476 -406.13965)
		(end 59.968892 -405.912066)
		(width 0.14224)
		(layer "In15.Cu")
		(net "P5E_CPU1_P0_RX_BUF_DN<4>")
	)
	(segment
		(start 52.616608 -392.580622)
		(end 52.616608 -392.429238)
		(width 0.14224)
		(layer "In15.Cu")
		(net "P5E_CPU1_P0_RX_BUF_DN<4>")
	)
	(segment
		(start 65.70472 -437.331104)
		(end 65.70472 -417.509452)
		(width 0.14224)
		(layer "In15.Cu")
		(net "P5E_CPU1_P0_RX_BUF_DN<4>")
	)
	(segment
		(start 62.01283 -414.06445)
		(end 61.869574 -413.71774)
		(width 0.14224)
		(layer "In15.Cu")
		(net "P5E_CPU1_P0_RX_BUF_DN<4>")
	)
	(segment
		(start 66.649854 -438.089802)
		(end 66.649854 -437.769762)
		(width 0.14224)
		(layer "In15.Cu")
		(net "P5E_CPU1_P0_RX_BUF_DN<4>")
	)
	(segment
		(start 66.503296 -437.623204)
		(end 65.99682 -437.623204)
		(width 0.14224)
		(layer "In15.Cu")
		(net "P5E_CPU1_P0_RX_BUF_DN<4>")
	)
	(segment
		(start 59.968892 -405.912066)
		(end 59.835288 -405.856694)
		(width 0.14224)
		(layer "In15.Cu")
		(net "P5E_CPU1_P0_RX_BUF_DN<4>")
	)
	(segment
		(start 60.682124 -411.162246)
		(end 60.470542 -410.950664)
		(width 0.14224)
		(layer "In15.Cu")
		(net "P5E_CPU1_P0_RX_BUF_DN<4>")
	)
	(segment
		(start 65.173606 -416.591496)
		(end 62.284864 -414.33623)
		(width 0.14224)
		(layer "In15.Cu")
		(net "P5E_CPU1_P0_RX_BUF_DN<4>")
	)
	(segment
		(start 58.806334 -405.240998)
		(end 58.806334 -403.994874)
		(width 0.14224)
		(layer "In15.Cu")
		(net "P5E_CPU1_P0_RX_BUF_DN<4>")
	)
	(segment
		(start 51.87569 -398.332198)
		(end 51.87569 -393.012168)
		(width 0.14224)
		(layer "In15.Cu")
		(net "P5E_CPU1_P0_RX_BUF_DN<4>")
	)
	(segment
		(start 58.921904 -405.520144)
		(end 58.806334 -405.240998)
		(width 0.14224)
		(layer "In15.Cu")
		(net "P5E_CPU1_P0_RX_BUF_DN<4>")
	)
	(segment
		(start 60.337954 -406.481026)
		(end 60.196476 -406.13965)
		(width 0.14224)
		(layer "In15.Cu")
		(net "P5E_CPU1_P0_RX_BUF_DN<4>")
	)
	(segment
		(start 60.783724 -411.230318)
		(end 60.682124 -411.162246)
		(width 0.14224)
		(layer "In15.Cu")
		(net "P5E_CPU1_P0_RX_BUF_DN<4>")
	)
	(segment
		(start 59.360816 -405.856694)
		(end 59.18581 -405.78405)
		(width 0.14224)
		(layer "In15.Cu")
		(net "P5E_CPU1_P0_RX_BUF_DN<4>")
	)
	(segment
		(start 59.835288 -405.856694)
		(end 59.360816 -405.856694)
		(width 0.14224)
		(layer "In15.Cu")
		(net "P5E_CPU1_P0_RX_BUF_DN<4>")
	)
	(segment
		(start 61.721492 -411.711648)
		(end 61.562742 -411.552898)
		(width 0.14224)
		(layer "In15.Cu")
		(net "P5E_CPU1_P0_RX_BUF_DN<4>")
	)
	(segment
		(start 59.18581 -405.78405)
		(end 58.921904 -405.520144)
		(width 0.14224)
		(layer "In15.Cu")
		(net "P5E_CPU1_P0_RX_BUF_DN<4>")
	)
	(segment
		(start 62.284864 -414.33623)
		(end 62.01283 -414.06445)
		(width 0.14224)
		(layer "In15.Cu")
		(net "P5E_CPU1_P0_RX_BUF_DN<4>")
	)
	(segment
		(start 52.180236 -392.707622)
		(end 52.489608 -392.707622)
		(width 0.14224)
		(layer "In15.Cu")
		(net "P5E_CPU1_P0_RX_BUF_DN<4>")
	)
	(segment
		(start 51.87569 -393.012168)
		(end 52.180236 -392.707622)
		(width 0.14224)
		(layer "In15.Cu")
		(net "P5E_CPU1_P0_RX_BUF_DN<4>")
	)
	(segment
		(start 65.99682 -437.623204)
		(end 65.70472 -437.331104)
		(width 0.14224)
		(layer "In15.Cu")
		(net "P5E_CPU1_P0_RX_BUF_DN<4>")
	)
	(segment
		(start 60.337954 -410.630878)
		(end 60.337954 -406.481026)
		(width 0.14224)
		(layer "In15.Cu")
		(net "P5E_CPU1_P0_RX_BUF_DN<4>")
	)
	(segment
		(start 61.869574 -413.71774)
		(end 61.869574 -412.07055)
		(width 0.14224)
		(layer "In15.Cu")
		(net "P5E_CPU1_P0_RX_BUF_DN<4>")
	)
	(segment
		(start 65.70472 -417.509452)
		(end 65.47739 -416.961574)
		(width 0.14224)
		(layer "In15.Cu")
		(net "P5E_CPU1_P0_RX_BUF_DN<4>")
	)
	(segment
		(start 61.869574 -412.07055)
		(end 61.721492 -411.711648)
		(width 0.14224)
		(layer "In15.Cu")
		(net "P5E_CPU1_P0_RX_BUF_DN<4>")
	)
	(segment
		(start 58.25363 -403.409404)
		(end 56.51754 -403.06371)
		(width 0.14224)
		(layer "In15.Cu")
		(net "P5E_CPU1_P0_RX_BUF_DN<4>")
	)
	(segment
		(start 60.470542 -410.950664)
		(end 60.337954 -410.630878)
		(width 0.14224)
		(layer "In15.Cu")
		(net "P5E_CPU1_P0_RX_BUF_DN<4>")
	)
	(segment
		(start 58.479436 -403.502876)
		(end 58.25363 -403.409404)
		(width 0.14224)
		(layer "In15.Cu")
		(net "P5E_CPU1_P0_RX_BUF_DN<4>")
	)
	(arc
		(start 56.51754 -403.06371)
		(mid 56.404583 -403.023226)
		(end 56.308244 -402.951696)
		(width 0.14224)
		(layer "In15.Cu")
		(net "P5E_CPU1_P0_RX_BUF_DN<4>")
	)
	(arc
		(start 58.806334 -403.994874)
		(mid 58.775964 -403.842282)
		(end 58.689494 -403.712934)
		(width 0.14224)
		(layer "In15.Cu")
		(net "P5E_CPU1_P0_RX_BUF_DN<4>")
	)
	(arc
		(start 52.00777 -398.651222)
		(mid 51.910023 -398.504838)
		(end 51.87569 -398.332198)
		(width 0.14224)
		(layer "In15.Cu")
		(net "P5E_CPU1_P0_RX_BUF_DN<4>")
	)
	(segment
		(start 50.943002 -391.653776)
		(end 50.943002 -392.634216)
		(width 0.1016)
		(layer "F.Cu")
		(net "P5E_CPU1_P0_RX_BUF_DN<3>")
	)
	(segment
		(start 51.017932 -390.761474)
		(end 51.01844 -390.761982)
		(width 0.1016)
		(layer "F.Cu")
		(net "P5E_CPU1_P0_RX_BUF_DN<3>")
	)
	(segment
		(start 50.943002 -392.634216)
		(end 51.070002 -392.761216)
		(width 0.1016)
		(layer "F.Cu")
		(net "P5E_CPU1_P0_RX_BUF_DN<3>")
	)
	(segment
		(start 51.01844 -391.578338)
		(end 50.943002 -391.653776)
		(width 0.1016)
		(layer "F.Cu")
		(net "P5E_CPU1_P0_RX_BUF_DN<3>")
	)
	(segment
		(start 51.01844 -390.761982)
		(end 51.01844 -391.578338)
		(width 0.1016)
		(layer "F.Cu")
		(net "P5E_CPU1_P0_RX_BUF_DN<3>")
	)
	(segment
		(start 51.070002 -392.761216)
		(end 51.275742 -392.761216)
		(width 0.1016)
		(layer "F.Cu")
		(net "P5E_CPU1_P0_RX_BUF_DN<3>")
	)
	(segment
		(start 51.275742 -392.761216)
		(end 51.416458 -392.6205)
		(width 0.1016)
		(layer "F.Cu")
		(net "P5E_CPU1_P0_RX_BUF_DN<3>")
	)
	(segment
		(start 51.416458 -392.6205)
		(end 51.416458 -392.429238)
		(width 0.1016)
		(layer "F.Cu")
		(net "P5E_CPU1_P0_RX_BUF_DN<3>")
	)
	(segment
		(start 57.274714 -410.630878)
		(end 57.274714 -406.48128)
		(width 0.14224)
		(layer "In15.Cu")
		(net "P5E_CPU1_P0_RX_BUF_DN<3>")
	)
	(segment
		(start 59.2328 -413.958278)
		(end 58.806334 -413.531812)
		(width 0.14224)
		(layer "In15.Cu")
		(net "P5E_CPU1_P0_RX_BUF_DN<3>")
	)
	(segment
		(start 51.416458 -392.580622)
		(end 51.416458 -392.429238)
		(width 0.14224)
		(layer "In15.Cu")
		(net "P5E_CPU1_P0_RX_BUF_DN<3>")
	)
	(segment
		(start 61.254386 -415.254186)
		(end 60.527692 -414.80613)
		(width 0.14224)
		(layer "In15.Cu")
		(net "P5E_CPU1_P0_RX_BUF_DN<3>")
	)
	(segment
		(start 58.701432 -411.751018)
		(end 58.505852 -411.555438)
		(width 0.14224)
		(layer "In15.Cu")
		(net "P5E_CPU1_P0_RX_BUF_DN<3>")
	)
	(segment
		(start 57.178448 -406.249378)
		(end 56.785764 -405.856694)
		(width 0.14224)
		(layer "In15.Cu")
		(net "P5E_CPU1_P0_RX_BUF_DN<3>")
	)
	(segment
		(start 55.646828 -403.819868)
		(end 50.795428 -398.968468)
		(width 0.14224)
		(layer "In15.Cu")
		(net "P5E_CPU1_P0_RX_BUF_DN<3>")
	)
	(segment
		(start 64.649858 -438.76976)
		(end 64.5033 -438.623202)
		(width 0.14224)
		(layer "In15.Cu")
		(net "P5E_CPU1_P0_RX_BUF_DN<3>")
	)
	(segment
		(start 57.412636 -410.963618)
		(end 57.274714 -410.630878)
		(width 0.14224)
		(layer "In15.Cu")
		(net "P5E_CPU1_P0_RX_BUF_DN<3>")
	)
	(segment
		(start 58.806334 -412.004002)
		(end 58.701432 -411.751018)
		(width 0.14224)
		(layer "In15.Cu")
		(net "P5E_CPU1_P0_RX_BUF_DN<3>")
	)
	(segment
		(start 57.595516 -411.146498)
		(end 57.412636 -410.963618)
		(width 0.14224)
		(layer "In15.Cu")
		(net "P5E_CPU1_P0_RX_BUF_DN<3>")
	)
	(segment
		(start 63.689992 -417.320222)
		(end 62.841124 -416.49269)
		(width 0.14224)
		(layer "In15.Cu")
		(net "P5E_CPU1_P0_RX_BUF_DN<3>")
	)
	(segment
		(start 62.841124 -416.49269)
		(end 61.254386 -415.254186)
		(width 0.14224)
		(layer "In15.Cu")
		(net "P5E_CPU1_P0_RX_BUF_DN<3>")
	)
	(segment
		(start 58.806334 -413.531812)
		(end 58.806334 -412.004002)
		(width 0.14224)
		(layer "In15.Cu")
		(net "P5E_CPU1_P0_RX_BUF_DN<3>")
	)
	(segment
		(start 57.720738 -411.230318)
		(end 57.595516 -411.146498)
		(width 0.14224)
		(layer "In15.Cu")
		(net "P5E_CPU1_P0_RX_BUF_DN<3>")
	)
	(segment
		(start 56.12257 -405.78405)
		(end 55.858664 -405.520144)
		(width 0.14224)
		(layer "In15.Cu")
		(net "P5E_CPU1_P0_RX_BUF_DN<3>")
	)
	(segment
		(start 50.67554 -393.012168)
		(end 50.980086 -392.707622)
		(width 0.14224)
		(layer "In15.Cu")
		(net "P5E_CPU1_P0_RX_BUF_DN<3>")
	)
	(segment
		(start 57.274714 -406.48128)
		(end 57.178448 -406.249378)
		(width 0.14224)
		(layer "In15.Cu")
		(net "P5E_CPU1_P0_RX_BUF_DN<3>")
	)
	(segment
		(start 56.785764 -405.856694)
		(end 56.297576 -405.856694)
		(width 0.14224)
		(layer "In15.Cu")
		(net "P5E_CPU1_P0_RX_BUF_DN<3>")
	)
	(segment
		(start 60.527692 -414.80613)
		(end 60.527692 -414.806384)
		(width 0.14224)
		(layer "In15.Cu")
		(net "P5E_CPU1_P0_RX_BUF_DN<3>")
	)
	(segment
		(start 55.858664 -405.520144)
		(end 55.743094 -405.241252)
		(width 0.14224)
		(layer "In15.Cu")
		(net "P5E_CPU1_P0_RX_BUF_DN<3>")
	)
	(segment
		(start 55.743094 -405.241252)
		(end 55.743094 -404.052024)
		(width 0.14224)
		(layer "In15.Cu")
		(net "P5E_CPU1_P0_RX_BUF_DN<3>")
	)
	(segment
		(start 50.67554 -398.678908)
		(end 50.67554 -393.012168)
		(width 0.14224)
		(layer "In15.Cu")
		(net "P5E_CPU1_P0_RX_BUF_DN<3>")
	)
	(segment
		(start 63.689992 -438.321704)
		(end 63.689992 -417.320222)
		(width 0.14224)
		(layer "In15.Cu")
		(net "P5E_CPU1_P0_RX_BUF_DN<3>")
	)
	(segment
		(start 59.801252 -414.358582)
		(end 59.2328 -413.958278)
		(width 0.14224)
		(layer "In15.Cu")
		(net "P5E_CPU1_P0_RX_BUF_DN<3>")
	)
	(segment
		(start 50.980086 -392.707622)
		(end 51.289458 -392.707622)
		(width 0.14224)
		(layer "In15.Cu")
		(net "P5E_CPU1_P0_RX_BUF_DN<3>")
	)
	(segment
		(start 64.5033 -438.623202)
		(end 63.99149 -438.623202)
		(width 0.14224)
		(layer "In15.Cu")
		(net "P5E_CPU1_P0_RX_BUF_DN<3>")
	)
	(segment
		(start 60.527692 -414.806384)
		(end 59.801252 -414.358582)
		(width 0.14224)
		(layer "In15.Cu")
		(net "P5E_CPU1_P0_RX_BUF_DN<3>")
	)
	(segment
		(start 58.505852 -411.555438)
		(end 57.720738 -411.230318)
		(width 0.14224)
		(layer "In15.Cu")
		(net "P5E_CPU1_P0_RX_BUF_DN<3>")
	)
	(segment
		(start 51.289458 -392.707622)
		(end 51.416458 -392.580622)
		(width 0.14224)
		(layer "In15.Cu")
		(net "P5E_CPU1_P0_RX_BUF_DN<3>")
	)
	(segment
		(start 64.649858 -439.0898)
		(end 64.649858 -438.76976)
		(width 0.14224)
		(layer "In15.Cu")
		(net "P5E_CPU1_P0_RX_BUF_DN<3>")
	)
	(segment
		(start 63.99149 -438.623202)
		(end 63.689992 -438.321704)
		(width 0.14224)
		(layer "In15.Cu")
		(net "P5E_CPU1_P0_RX_BUF_DN<3>")
	)
	(segment
		(start 56.297576 -405.856694)
		(end 56.12257 -405.78405)
		(width 0.14224)
		(layer "In15.Cu")
		(net "P5E_CPU1_P0_RX_BUF_DN<3>")
	)
	(arc
		(start 50.795428 -398.968468)
		(mid 50.706713 -398.835603)
		(end 50.67554 -398.678908)
		(width 0.14224)
		(layer "In15.Cu")
		(net "P5E_CPU1_P0_RX_BUF_DN<3>")
	)
	(arc
		(start 55.743094 -404.052024)
		(mid 55.718079 -403.926357)
		(end 55.646828 -403.819868)
		(width 0.14224)
		(layer "In15.Cu")
		(net "P5E_CPU1_P0_RX_BUF_DN<3>")
	)
	(segment
		(start 49.729898 -392.634216)
		(end 49.856898 -392.761216)
		(width 0.1016)
		(layer "F.Cu")
		(net "P5E_CPU1_P0_RX_BUF_DN<2>")
	)
	(segment
		(start 49.729898 -391.666984)
		(end 49.729898 -392.634216)
		(width 0.1016)
		(layer "F.Cu")
		(net "P5E_CPU1_P0_RX_BUF_DN<2>")
	)
	(segment
		(start 49.818544 -390.761982)
		(end 49.818544 -391.578338)
		(width 0.1016)
		(layer "F.Cu")
		(net "P5E_CPU1_P0_RX_BUF_DN<2>")
	)
	(segment
		(start 49.818036 -390.761474)
		(end 49.818544 -390.761982)
		(width 0.1016)
		(layer "F.Cu")
		(net "P5E_CPU1_P0_RX_BUF_DN<2>")
	)
	(segment
		(start 49.818544 -391.578338)
		(end 49.729898 -391.666984)
		(width 0.1016)
		(layer "F.Cu")
		(net "P5E_CPU1_P0_RX_BUF_DN<2>")
	)
	(segment
		(start 49.856898 -392.761216)
		(end 50.075846 -392.761216)
		(width 0.1016)
		(layer "F.Cu")
		(net "P5E_CPU1_P0_RX_BUF_DN<2>")
	)
	(segment
		(start 50.216562 -392.6205)
		(end 50.216562 -392.429238)
		(width 0.1016)
		(layer "F.Cu")
		(net "P5E_CPU1_P0_RX_BUF_DN<2>")
	)
	(segment
		(start 50.075846 -392.761216)
		(end 50.216562 -392.6205)
		(width 0.1016)
		(layer "F.Cu")
		(net "P5E_CPU1_P0_RX_BUF_DN<2>")
	)
	(segment
		(start 54.069996 -406.13965)
		(end 53.815488 -405.885142)
		(width 0.14224)
		(layer "In15.Cu")
		(net "P5E_CPU1_P0_RX_BUF_DN<2>")
	)
	(segment
		(start 56.332374 -414.198308)
		(end 56.002174 -414.000442)
		(width 0.14224)
		(layer "In15.Cu")
		(net "P5E_CPU1_P0_RX_BUF_DN<2>")
	)
	(segment
		(start 52.795424 -405.520144)
		(end 52.679854 -405.241252)
		(width 0.14224)
		(layer "In15.Cu")
		(net "P5E_CPU1_P0_RX_BUF_DN<2>")
	)
	(segment
		(start 61.386466 -416.67303)
		(end 58.802016 -414.9471)
		(width 0.14224)
		(layer "In15.Cu")
		(net "P5E_CPU1_P0_RX_BUF_DN<2>")
	)
	(segment
		(start 50.089562 -392.707622)
		(end 50.216562 -392.580622)
		(width 0.14224)
		(layer "In15.Cu")
		(net "P5E_CPU1_P0_RX_BUF_DN<2>")
	)
	(segment
		(start 61.714634 -417.164012)
		(end 61.386466 -416.67303)
		(width 0.14224)
		(layer "In15.Cu")
		(net "P5E_CPU1_P0_RX_BUF_DN<2>")
	)
	(segment
		(start 54.349396 -410.963618)
		(end 54.211474 -410.630878)
		(width 0.14224)
		(layer "In15.Cu")
		(net "P5E_CPU1_P0_RX_BUF_DN<2>")
	)
	(segment
		(start 52.563014 -403.450552)
		(end 49.608232 -399.850102)
		(width 0.14224)
		(layer "In15.Cu")
		(net "P5E_CPU1_P0_RX_BUF_DN<2>")
	)
	(segment
		(start 53.05933 -405.78405)
		(end 52.795424 -405.520144)
		(width 0.14224)
		(layer "In15.Cu")
		(net "P5E_CPU1_P0_RX_BUF_DN<2>")
	)
	(segment
		(start 58.802016 -414.9471)
		(end 56.332374 -414.198308)
		(width 0.14224)
		(layer "In15.Cu")
		(net "P5E_CPU1_P0_RX_BUF_DN<2>")
	)
	(segment
		(start 62.006734 -437.623204)
		(end 61.714634 -437.331104)
		(width 0.14224)
		(layer "In15.Cu")
		(net "P5E_CPU1_P0_RX_BUF_DN<2>")
	)
	(segment
		(start 49.475644 -393.012168)
		(end 49.78019 -392.707622)
		(width 0.14224)
		(layer "In15.Cu")
		(net "P5E_CPU1_P0_RX_BUF_DN<2>")
	)
	(segment
		(start 54.211474 -406.481026)
		(end 54.069996 -406.13965)
		(width 0.14224)
		(layer "In15.Cu")
		(net "P5E_CPU1_P0_RX_BUF_DN<2>")
	)
	(segment
		(start 56.002174 -414.000442)
		(end 55.845202 -413.84347)
		(width 0.14224)
		(layer "In15.Cu")
		(net "P5E_CPU1_P0_RX_BUF_DN<2>")
	)
	(segment
		(start 62.649862 -438.089802)
		(end 62.649862 -437.769762)
		(width 0.14224)
		(layer "In15.Cu")
		(net "P5E_CPU1_P0_RX_BUF_DN<2>")
	)
	(segment
		(start 54.532276 -411.146498)
		(end 54.349396 -410.963618)
		(width 0.14224)
		(layer "In15.Cu")
		(net "P5E_CPU1_P0_RX_BUF_DN<2>")
	)
	(segment
		(start 49.78019 -392.707622)
		(end 50.089562 -392.707622)
		(width 0.14224)
		(layer "In15.Cu")
		(net "P5E_CPU1_P0_RX_BUF_DN<2>")
	)
	(segment
		(start 54.211474 -410.630878)
		(end 54.211474 -406.481026)
		(width 0.14224)
		(layer "In15.Cu")
		(net "P5E_CPU1_P0_RX_BUF_DN<2>")
	)
	(segment
		(start 53.746908 -405.856694)
		(end 53.234336 -405.856694)
		(width 0.14224)
		(layer "In15.Cu")
		(net "P5E_CPU1_P0_RX_BUF_DN<2>")
	)
	(segment
		(start 55.743094 -412.004002)
		(end 55.65775 -411.798008)
		(width 0.14224)
		(layer "In15.Cu")
		(net "P5E_CPU1_P0_RX_BUF_DN<2>")
	)
	(segment
		(start 49.475644 -399.478754)
		(end 49.475644 -393.012168)
		(width 0.14224)
		(layer "In15.Cu")
		(net "P5E_CPU1_P0_RX_BUF_DN<2>")
	)
	(segment
		(start 50.216562 -392.580622)
		(end 50.216562 -392.429238)
		(width 0.14224)
		(layer "In15.Cu")
		(net "P5E_CPU1_P0_RX_BUF_DN<2>")
	)
	(segment
		(start 52.679854 -405.241252)
		(end 52.679854 -403.77745)
		(width 0.14224)
		(layer "In15.Cu")
		(net "P5E_CPU1_P0_RX_BUF_DN<2>")
	)
	(segment
		(start 54.657498 -411.230318)
		(end 54.532276 -411.146498)
		(width 0.14224)
		(layer "In15.Cu")
		(net "P5E_CPU1_P0_RX_BUF_DN<2>")
	)
	(segment
		(start 62.649862 -437.769762)
		(end 62.503304 -437.623204)
		(width 0.14224)
		(layer "In15.Cu")
		(net "P5E_CPU1_P0_RX_BUF_DN<2>")
	)
	(segment
		(start 55.395622 -411.53588)
		(end 54.657498 -411.230318)
		(width 0.14224)
		(layer "In15.Cu")
		(net "P5E_CPU1_P0_RX_BUF_DN<2>")
	)
	(segment
		(start 61.714634 -437.331104)
		(end 61.714634 -417.164012)
		(width 0.14224)
		(layer "In15.Cu")
		(net "P5E_CPU1_P0_RX_BUF_DN<2>")
	)
	(segment
		(start 53.815488 -405.885142)
		(end 53.746908 -405.856694)
		(width 0.14224)
		(layer "In15.Cu")
		(net "P5E_CPU1_P0_RX_BUF_DN<2>")
	)
	(segment
		(start 62.503304 -437.623204)
		(end 62.006734 -437.623204)
		(width 0.14224)
		(layer "In15.Cu")
		(net "P5E_CPU1_P0_RX_BUF_DN<2>")
	)
	(segment
		(start 55.743094 -413.596836)
		(end 55.743094 -412.004002)
		(width 0.14224)
		(layer "In15.Cu")
		(net "P5E_CPU1_P0_RX_BUF_DN<2>")
	)
	(segment
		(start 55.845202 -413.84347)
		(end 55.743094 -413.596836)
		(width 0.14224)
		(layer "In15.Cu")
		(net "P5E_CPU1_P0_RX_BUF_DN<2>")
	)
	(segment
		(start 55.65775 -411.798008)
		(end 55.395622 -411.53588)
		(width 0.14224)
		(layer "In15.Cu")
		(net "P5E_CPU1_P0_RX_BUF_DN<2>")
	)
	(segment
		(start 53.234336 -405.856694)
		(end 53.05933 -405.78405)
		(width 0.14224)
		(layer "In15.Cu")
		(net "P5E_CPU1_P0_RX_BUF_DN<2>")
	)
	(arc
		(start 52.679854 -403.77745)
		(mid 52.649825 -403.603846)
		(end 52.563014 -403.450552)
		(width 0.14224)
		(layer "In15.Cu")
		(net "P5E_CPU1_P0_RX_BUF_DN<2>")
	)
	(arc
		(start 49.608232 -399.850102)
		(mid 49.509712 -399.675935)
		(end 49.475644 -399.478754)
		(width 0.14224)
		(layer "In15.Cu")
		(net "P5E_CPU1_P0_RX_BUF_DN<2>")
	)
	(segment
		(start 48.618394 -390.761982)
		(end 48.618394 -391.578338)
		(width 0.1016)
		(layer "F.Cu")
		(net "P5E_CPU1_P0_RX_BUF_DN<1>")
	)
	(segment
		(start 48.618394 -391.578338)
		(end 48.529748 -391.666984)
		(width 0.1016)
		(layer "F.Cu")
		(net "P5E_CPU1_P0_RX_BUF_DN<1>")
	)
	(segment
		(start 48.529748 -391.666984)
		(end 48.529748 -392.634216)
		(width 0.1016)
		(layer "F.Cu")
		(net "P5E_CPU1_P0_RX_BUF_DN<1>")
	)
	(segment
		(start 48.656748 -392.761216)
		(end 48.875696 -392.761216)
		(width 0.1016)
		(layer "F.Cu")
		(net "P5E_CPU1_P0_RX_BUF_DN<1>")
	)
	(segment
		(start 48.617886 -390.761474)
		(end 48.618394 -390.761982)
		(width 0.1016)
		(layer "F.Cu")
		(net "P5E_CPU1_P0_RX_BUF_DN<1>")
	)
	(segment
		(start 49.016412 -392.6205)
		(end 49.016412 -392.429238)
		(width 0.1016)
		(layer "F.Cu")
		(net "P5E_CPU1_P0_RX_BUF_DN<1>")
	)
	(segment
		(start 48.875696 -392.761216)
		(end 49.016412 -392.6205)
		(width 0.1016)
		(layer "F.Cu")
		(net "P5E_CPU1_P0_RX_BUF_DN<1>")
	)
	(segment
		(start 48.529748 -392.634216)
		(end 48.656748 -392.761216)
		(width 0.1016)
		(layer "F.Cu")
		(net "P5E_CPU1_P0_RX_BUF_DN<1>")
	)
	(segment
		(start 52.508404 -411.627828)
		(end 52.493164 -411.612334)
		(width 0.14224)
		(layer "In15.Cu")
		(net "P5E_CPU1_P0_RX_BUF_DN<1>")
	)
	(segment
		(start 48.58004 -392.707622)
		(end 48.889412 -392.707622)
		(width 0.14224)
		(layer "In15.Cu")
		(net "P5E_CPU1_P0_RX_BUF_DN<1>")
	)
	(segment
		(start 53.043074 -413.976058)
		(end 53.043074 -413.975804)
		(width 0.14224)
		(layer "In15.Cu")
		(net "P5E_CPU1_P0_RX_BUF_DN<1>")
	)
	(segment
		(start 53.043074 -413.975804)
		(end 52.85613 -413.850836)
		(width 0.14224)
		(layer "In15.Cu")
		(net "P5E_CPU1_P0_RX_BUF_DN<1>")
	)
	(segment
		(start 49.732184 -405.520144)
		(end 49.616614 -405.241252)
		(width 0.14224)
		(layer "In15.Cu")
		(net "P5E_CPU1_P0_RX_BUF_DN<1>")
	)
	(segment
		(start 59.687968 -417.511738)
		(end 59.129676 -416.895788)
		(width 0.14224)
		(layer "In15.Cu")
		(net "P5E_CPU1_P0_RX_BUF_DN<1>")
	)
	(segment
		(start 51.63312 -411.256226)
		(end 51.469036 -411.146498)
		(width 0.14224)
		(layer "In15.Cu")
		(net "P5E_CPU1_P0_RX_BUF_DN<1>")
	)
	(segment
		(start 50.60061 -405.856694)
		(end 50.171096 -405.856694)
		(width 0.14224)
		(layer "In15.Cu")
		(net "P5E_CPU1_P0_RX_BUF_DN<1>")
	)
	(segment
		(start 52.679854 -412.042356)
		(end 52.508404 -411.627828)
		(width 0.14224)
		(layer "In15.Cu")
		(net "P5E_CPU1_P0_RX_BUF_DN<1>")
	)
	(segment
		(start 59.129676 -416.895788)
		(end 57.643776 -415.903156)
		(width 0.14224)
		(layer "In15.Cu")
		(net "P5E_CPU1_P0_RX_BUF_DN<1>")
	)
	(segment
		(start 59.687968 -438.324498)
		(end 59.687968 -417.511738)
		(width 0.14224)
		(layer "In15.Cu")
		(net "P5E_CPU1_P0_RX_BUF_DN<1>")
	)
	(segment
		(start 51.148234 -406.481026)
		(end 51.006756 -406.13965)
		(width 0.14224)
		(layer "In15.Cu")
		(net "P5E_CPU1_P0_RX_BUF_DN<1>")
	)
	(segment
		(start 48.275494 -400.312128)
		(end 48.275494 -393.012168)
		(width 0.14224)
		(layer "In15.Cu")
		(net "P5E_CPU1_P0_RX_BUF_DN<1>")
	)
	(segment
		(start 51.469036 -411.146498)
		(end 51.290728 -410.96819)
		(width 0.14224)
		(layer "In15.Cu")
		(net "P5E_CPU1_P0_RX_BUF_DN<1>")
	)
	(segment
		(start 60.649866 -438.76976)
		(end 60.499244 -438.619138)
		(width 0.14224)
		(layer "In15.Cu")
		(net "P5E_CPU1_P0_RX_BUF_DN<1>")
	)
	(segment
		(start 48.889412 -392.707622)
		(end 49.016412 -392.580622)
		(width 0.14224)
		(layer "In15.Cu")
		(net "P5E_CPU1_P0_RX_BUF_DN<1>")
	)
	(segment
		(start 50.810922 -405.943816)
		(end 50.60061 -405.856694)
		(width 0.14224)
		(layer "In15.Cu")
		(net "P5E_CPU1_P0_RX_BUF_DN<1>")
	)
	(segment
		(start 60.649866 -439.0898)
		(end 60.649866 -438.76976)
		(width 0.14224)
		(layer "In15.Cu")
		(net "P5E_CPU1_P0_RX_BUF_DN<1>")
	)
	(segment
		(start 50.171096 -405.856694)
		(end 49.99609 -405.78405)
		(width 0.14224)
		(layer "In15.Cu")
		(net "P5E_CPU1_P0_RX_BUF_DN<1>")
	)
	(segment
		(start 59.982608 -438.619138)
		(end 59.687968 -438.324498)
		(width 0.14224)
		(layer "In15.Cu")
		(net "P5E_CPU1_P0_RX_BUF_DN<1>")
	)
	(segment
		(start 51.148234 -410.624274)
		(end 51.148234 -406.481026)
		(width 0.14224)
		(layer "In15.Cu")
		(net "P5E_CPU1_P0_RX_BUF_DN<1>")
	)
	(segment
		(start 52.493164 -411.612334)
		(end 51.63312 -411.256226)
		(width 0.14224)
		(layer "In15.Cu")
		(net "P5E_CPU1_P0_RX_BUF_DN<1>")
	)
	(segment
		(start 49.616614 -405.241252)
		(end 49.616614 -403.631908)
		(width 0.14224)
		(layer "In15.Cu")
		(net "P5E_CPU1_P0_RX_BUF_DN<1>")
	)
	(segment
		(start 48.275494 -393.012168)
		(end 48.58004 -392.707622)
		(width 0.14224)
		(layer "In15.Cu")
		(net "P5E_CPU1_P0_RX_BUF_DN<1>")
	)
	(segment
		(start 52.679854 -413.424878)
		(end 52.679854 -412.042356)
		(width 0.14224)
		(layer "In15.Cu")
		(net "P5E_CPU1_P0_RX_BUF_DN<1>")
	)
	(segment
		(start 49.616614 -403.631908)
		(end 48.460152 -400.839686)
		(width 0.14224)
		(layer "In15.Cu")
		(net "P5E_CPU1_P0_RX_BUF_DN<1>")
	)
	(segment
		(start 51.006756 -406.13965)
		(end 50.810922 -405.943816)
		(width 0.14224)
		(layer "In15.Cu")
		(net "P5E_CPU1_P0_RX_BUF_DN<1>")
	)
	(segment
		(start 48.459898 -400.839686)
		(end 48.306482 -400.468846)
		(width 0.14224)
		(layer "In15.Cu")
		(net "P5E_CPU1_P0_RX_BUF_DN<1>")
	)
	(segment
		(start 53.194204 -414.076896)
		(end 53.043074 -413.976058)
		(width 0.14224)
		(layer "In15.Cu")
		(net "P5E_CPU1_P0_RX_BUF_DN<1>")
	)
	(segment
		(start 49.016412 -392.580622)
		(end 49.016412 -392.429238)
		(width 0.14224)
		(layer "In15.Cu")
		(net "P5E_CPU1_P0_RX_BUF_DN<1>")
	)
	(segment
		(start 57.643776 -415.903156)
		(end 53.333396 -414.118552)
		(width 0.14224)
		(layer "In15.Cu")
		(net "P5E_CPU1_P0_RX_BUF_DN<1>")
	)
	(segment
		(start 48.460152 -400.839686)
		(end 48.459898 -400.839686)
		(width 0.14224)
		(layer "In15.Cu")
		(net "P5E_CPU1_P0_RX_BUF_DN<1>")
	)
	(segment
		(start 60.499244 -438.619138)
		(end 59.982608 -438.619138)
		(width 0.14224)
		(layer "In15.Cu")
		(net "P5E_CPU1_P0_RX_BUF_DN<1>")
	)
	(segment
		(start 49.99609 -405.78405)
		(end 49.732184 -405.520144)
		(width 0.14224)
		(layer "In15.Cu")
		(net "P5E_CPU1_P0_RX_BUF_DN<1>")
	)
	(segment
		(start 52.85613 -413.850836)
		(end 52.679854 -413.424878)
		(width 0.14224)
		(layer "In15.Cu")
		(net "P5E_CPU1_P0_RX_BUF_DN<1>")
	)
	(segment
		(start 51.290728 -410.96819)
		(end 51.148234 -410.624274)
		(width 0.14224)
		(layer "In15.Cu")
		(net "P5E_CPU1_P0_RX_BUF_DN<1>")
	)
	(segment
		(start 53.333396 -414.118552)
		(end 53.194204 -414.076896)
		(width 0.14224)
		(layer "In15.Cu")
		(net "P5E_CPU1_P0_RX_BUF_DN<1>")
	)
	(arc
		(start 48.306482 -400.468846)
		(mid 48.283279 -400.392012)
		(end 48.275494 -400.312128)
		(width 0.14224)
		(layer "In15.Cu")
		(net "P5E_CPU1_P0_RX_BUF_DN<1>")
	)
	(segment
		(start 65.418462 -391.578338)
		(end 65.418462 -390.761982)
		(width 0.1016)
		(layer "F.Cu")
		(net "P5E_CPU1_P0_RX_BUF_DN<15>")
	)
	(segment
		(start 65.456816 -392.761216)
		(end 65.329816 -392.634216)
		(width 0.1016)
		(layer "F.Cu")
		(net "P5E_CPU1_P0_RX_BUF_DN<15>")
	)
	(segment
		(start 65.329816 -392.634216)
		(end 65.329816 -391.666984)
		(width 0.1016)
		(layer "F.Cu")
		(net "P5E_CPU1_P0_RX_BUF_DN<15>")
	)
	(segment
		(start 65.418462 -390.761982)
		(end 65.417954 -390.761474)
		(width 0.1016)
		(layer "F.Cu")
		(net "P5E_CPU1_P0_RX_BUF_DN<15>")
	)
	(segment
		(start 65.65519 -392.761216)
		(end 65.456816 -392.761216)
		(width 0.1016)
		(layer "F.Cu")
		(net "P5E_CPU1_P0_RX_BUF_DN<15>")
	)
	(segment
		(start 65.329816 -391.666984)
		(end 65.418462 -391.578338)
		(width 0.1016)
		(layer "F.Cu")
		(net "P5E_CPU1_P0_RX_BUF_DN<15>")
	)
	(segment
		(start 65.81648 -392.429238)
		(end 65.81648 -392.599926)
		(width 0.1016)
		(layer "F.Cu")
		(net "P5E_CPU1_P0_RX_BUF_DN<15>")
	)
	(segment
		(start 65.81648 -392.599926)
		(end 65.65519 -392.761216)
		(width 0.1016)
		(layer "F.Cu")
		(net "P5E_CPU1_P0_RX_BUF_DN<15>")
	)
	(segment
		(start 65.075562 -393.012168)
		(end 65.380108 -392.707622)
		(width 0.14224)
		(layer "In15.Cu")
		(net "P5E_CPU1_P0_RX_BUF_DN<15>")
	)
	(segment
		(start 94.033594 -410.630878)
		(end 94.033594 -406.481026)
		(width 0.14224)
		(layer "In15.Cu")
		(net "P5E_CPU1_P0_RX_BUF_DN<15>")
	)
	(segment
		(start 89.650062 -439.0898)
		(end 89.650062 -438.76976)
		(width 0.14224)
		(layer "In15.Cu")
		(net "P5E_CPU1_P0_RX_BUF_DN<15>")
	)
	(segment
		(start 92.617544 -405.520144)
		(end 92.501974 -405.241252)
		(width 0.14224)
		(layer "In15.Cu")
		(net "P5E_CPU1_P0_RX_BUF_DN<15>")
	)
	(segment
		(start 65.68948 -392.707622)
		(end 65.81648 -392.580622)
		(width 0.14224)
		(layer "In15.Cu")
		(net "P5E_CPU1_P0_RX_BUF_DN<15>")
	)
	(segment
		(start 67.977258 -395.223238)
		(end 65.57645 -394.624306)
		(width 0.14224)
		(layer "In15.Cu")
		(net "P5E_CPU1_P0_RX_BUF_DN<15>")
	)
	(segment
		(start 92.116656 -402.995384)
		(end 91.909392 -402.78812)
		(width 0.14224)
		(layer "In15.Cu")
		(net "P5E_CPU1_P0_RX_BUF_DN<15>")
	)
	(segment
		(start 92.88145 -405.78405)
		(end 92.617544 -405.520144)
		(width 0.14224)
		(layer "In15.Cu")
		(net "P5E_CPU1_P0_RX_BUF_DN<15>")
	)
	(segment
		(start 88.991694 -438.623202)
		(end 88.694514 -438.326022)
		(width 0.14224)
		(layer "In15.Cu")
		(net "P5E_CPU1_P0_RX_BUF_DN<15>")
	)
	(segment
		(start 94.479618 -411.230318)
		(end 94.354396 -411.146498)
		(width 0.14224)
		(layer "In15.Cu")
		(net "P5E_CPU1_P0_RX_BUF_DN<15>")
	)
	(segment
		(start 93.637608 -405.885142)
		(end 93.569028 -405.856694)
		(width 0.14224)
		(layer "In15.Cu")
		(net "P5E_CPU1_P0_RX_BUF_DN<15>")
	)
	(segment
		(start 89.053162 -423.386758)
		(end 95.474028 -413.777176)
		(width 0.14224)
		(layer "In15.Cu")
		(net "P5E_CPU1_P0_RX_BUF_DN<15>")
	)
	(segment
		(start 94.033594 -406.481026)
		(end 93.892116 -406.13965)
		(width 0.14224)
		(layer "In15.Cu")
		(net "P5E_CPU1_P0_RX_BUF_DN<15>")
	)
	(segment
		(start 95.108522 -411.490668)
		(end 94.479618 -411.230318)
		(width 0.14224)
		(layer "In15.Cu")
		(net "P5E_CPU1_P0_RX_BUF_DN<15>")
	)
	(segment
		(start 89.650062 -438.76976)
		(end 89.503504 -438.623202)
		(width 0.14224)
		(layer "In15.Cu")
		(net "P5E_CPU1_P0_RX_BUF_DN<15>")
	)
	(segment
		(start 94.354396 -411.146498)
		(end 94.171516 -410.963618)
		(width 0.14224)
		(layer "In15.Cu")
		(net "P5E_CPU1_P0_RX_BUF_DN<15>")
	)
	(segment
		(start 94.171516 -410.963618)
		(end 94.033594 -410.630878)
		(width 0.14224)
		(layer "In15.Cu")
		(net "P5E_CPU1_P0_RX_BUF_DN<15>")
	)
	(segment
		(start 91.854528 -402.743162)
		(end 84.268564 -397.674084)
		(width 0.14224)
		(layer "In15.Cu")
		(net "P5E_CPU1_P0_RX_BUF_DN<15>")
	)
	(segment
		(start 65.380108 -392.707622)
		(end 65.68948 -392.707622)
		(width 0.14224)
		(layer "In15.Cu")
		(net "P5E_CPU1_P0_RX_BUF_DN<15>")
	)
	(segment
		(start 93.569028 -405.856694)
		(end 93.056456 -405.856694)
		(width 0.14224)
		(layer "In15.Cu")
		(net "P5E_CPU1_P0_RX_BUF_DN<15>")
	)
	(segment
		(start 95.525336 -411.907482)
		(end 95.108522 -411.490668)
		(width 0.14224)
		(layer "In15.Cu")
		(net "P5E_CPU1_P0_RX_BUF_DN<15>")
	)
	(segment
		(start 93.056456 -405.856694)
		(end 92.88145 -405.78405)
		(width 0.14224)
		(layer "In15.Cu")
		(net "P5E_CPU1_P0_RX_BUF_DN<15>")
	)
	(segment
		(start 95.474028 -413.777176)
		(end 95.565214 -413.476694)
		(width 0.14224)
		(layer "In15.Cu")
		(net "P5E_CPU1_P0_RX_BUF_DN<15>")
	)
	(segment
		(start 65.81648 -392.580622)
		(end 65.81648 -392.429238)
		(width 0.14224)
		(layer "In15.Cu")
		(net "P5E_CPU1_P0_RX_BUF_DN<15>")
	)
	(segment
		(start 88.694514 -438.326022)
		(end 88.694514 -424.56989)
		(width 0.14224)
		(layer "In15.Cu")
		(net "P5E_CPU1_P0_RX_BUF_DN<15>")
	)
	(segment
		(start 84.152486 -397.626078)
		(end 76.30922 -396.065502)
		(width 0.14224)
		(layer "In15.Cu")
		(net "P5E_CPU1_P0_RX_BUF_DN<15>")
	)
	(segment
		(start 95.565214 -412.003748)
		(end 95.525336 -411.907482)
		(width 0.14224)
		(layer "In15.Cu")
		(net "P5E_CPU1_P0_RX_BUF_DN<15>")
	)
	(segment
		(start 95.565214 -413.476694)
		(end 95.565214 -412.003748)
		(width 0.14224)
		(layer "In15.Cu")
		(net "P5E_CPU1_P0_RX_BUF_DN<15>")
	)
	(segment
		(start 76.183744 -396.04696)
		(end 68.101718 -395.244828)
		(width 0.14224)
		(layer "In15.Cu")
		(net "P5E_CPU1_P0_RX_BUF_DN<15>")
	)
	(segment
		(start 92.501974 -405.241252)
		(end 92.501974 -403.861524)
		(width 0.14224)
		(layer "In15.Cu")
		(net "P5E_CPU1_P0_RX_BUF_DN<15>")
	)
	(segment
		(start 65.075562 -393.84859)
		(end 65.075562 -393.012168)
		(width 0.14224)
		(layer "In15.Cu")
		(net "P5E_CPU1_P0_RX_BUF_DN<15>")
	)
	(segment
		(start 93.892116 -406.13965)
		(end 93.637608 -405.885142)
		(width 0.14224)
		(layer "In15.Cu")
		(net "P5E_CPU1_P0_RX_BUF_DN<15>")
	)
	(segment
		(start 92.501974 -403.861524)
		(end 92.186506 -403.100286)
		(width 0.14224)
		(layer "In15.Cu")
		(net "P5E_CPU1_P0_RX_BUF_DN<15>")
	)
	(segment
		(start 89.503504 -438.623202)
		(end 88.991694 -438.623202)
		(width 0.14224)
		(layer "In15.Cu")
		(net "P5E_CPU1_P0_RX_BUF_DN<15>")
	)
	(arc
		(start 92.186506 -403.100286)
		(mid 92.15676 -403.044387)
		(end 92.116656 -402.995384)
		(width 0.14224)
		(layer "In15.Cu")
		(net "P5E_CPU1_P0_RX_BUF_DN<15>")
	)
	(arc
		(start 65.333118 -394.484606)
		(mid 65.142218 -394.191756)
		(end 65.075562 -393.84859)
		(width 0.14224)
		(layer "In15.Cu")
		(net "P5E_CPU1_P0_RX_BUF_DN<15>")
	)
	(arc
		(start 68.101718 -395.244828)
		(mid 68.039096 -395.236292)
		(end 67.977258 -395.223238)
		(width 0.14224)
		(layer "In15.Cu")
		(net "P5E_CPU1_P0_RX_BUF_DN<15>")
	)
	(arc
		(start 76.30922 -396.065502)
		(mid 76.246708 -396.0547)
		(end 76.183744 -396.04696)
		(width 0.14224)
		(layer "In15.Cu")
		(net "P5E_CPU1_P0_RX_BUF_DN<15>")
	)
	(arc
		(start 65.57645 -394.624306)
		(mid 65.445028 -394.571445)
		(end 65.333118 -394.484606)
		(width 0.14224)
		(layer "In15.Cu")
		(net "P5E_CPU1_P0_RX_BUF_DN<15>")
	)
	(arc
		(start 91.909392 -402.78812)
		(mid 91.883062 -402.764297)
		(end 91.854528 -402.743162)
		(width 0.14224)
		(layer "In15.Cu")
		(net "P5E_CPU1_P0_RX_BUF_DN<15>")
	)
	(arc
		(start 84.268564 -397.674084)
		(mid 84.212882 -397.644386)
		(end 84.152486 -397.626078)
		(width 0.14224)
		(layer "In15.Cu")
		(net "P5E_CPU1_P0_RX_BUF_DN<15>")
	)
	(arc
		(start 88.694514 -424.56989)
		(mid 88.786079 -423.951723)
		(end 89.053162 -423.386758)
		(width 0.14224)
		(layer "In15.Cu")
		(net "P5E_CPU1_P0_RX_BUF_DN<15>")
	)
	(segment
		(start 64.218566 -390.761982)
		(end 64.218058 -390.761474)
		(width 0.1016)
		(layer "F.Cu")
		(net "P5E_CPU1_P0_RX_BUF_DN<14>")
	)
	(segment
		(start 64.449198 -392.761216)
		(end 64.25692 -392.761216)
		(width 0.1016)
		(layer "F.Cu")
		(net "P5E_CPU1_P0_RX_BUF_DN<14>")
	)
	(segment
		(start 64.12992 -392.634216)
		(end 64.12992 -391.666984)
		(width 0.1016)
		(layer "F.Cu")
		(net "P5E_CPU1_P0_RX_BUF_DN<14>")
	)
	(segment
		(start 64.616584 -392.429238)
		(end 64.616584 -392.59383)
		(width 0.1016)
		(layer "F.Cu")
		(net "P5E_CPU1_P0_RX_BUF_DN<14>")
	)
	(segment
		(start 64.25692 -392.761216)
		(end 64.12992 -392.634216)
		(width 0.1016)
		(layer "F.Cu")
		(net "P5E_CPU1_P0_RX_BUF_DN<14>")
	)
	(segment
		(start 64.12992 -391.666984)
		(end 64.218566 -391.578338)
		(width 0.1016)
		(layer "F.Cu")
		(net "P5E_CPU1_P0_RX_BUF_DN<14>")
	)
	(segment
		(start 64.616584 -392.59383)
		(end 64.449198 -392.761216)
		(width 0.1016)
		(layer "F.Cu")
		(net "P5E_CPU1_P0_RX_BUF_DN<14>")
	)
	(segment
		(start 64.218566 -391.578338)
		(end 64.218566 -390.761982)
		(width 0.1016)
		(layer "F.Cu")
		(net "P5E_CPU1_P0_RX_BUF_DN<14>")
	)
	(segment
		(start 87.650066 -437.769762)
		(end 87.503508 -437.623204)
		(width 0.14224)
		(layer "In15.Cu")
		(net "P5E_CPU1_P0_RX_BUF_DN<14>")
	)
	(segment
		(start 89.011506 -403.210776)
		(end 88.483186 -402.64588)
		(width 0.14224)
		(layer "In15.Cu")
		(net "P5E_CPU1_P0_RX_BUF_DN<14>")
	)
	(segment
		(start 86.694518 -437.326024)
		(end 86.694518 -424.54957)
		(width 0.14224)
		(layer "In15.Cu")
		(net "P5E_CPU1_P0_RX_BUF_DN<14>")
	)
	(segment
		(start 68.54698 -396.432024)
		(end 67.922902 -396.308072)
		(width 0.14224)
		(layer "In15.Cu")
		(net "P5E_CPU1_P0_RX_BUF_DN<14>")
	)
	(segment
		(start 89.993216 -405.856694)
		(end 89.81821 -405.78405)
		(width 0.14224)
		(layer "In15.Cu")
		(net "P5E_CPU1_P0_RX_BUF_DN<14>")
	)
	(segment
		(start 91.108276 -410.963618)
		(end 90.970354 -410.630878)
		(width 0.14224)
		(layer "In15.Cu")
		(net "P5E_CPU1_P0_RX_BUF_DN<14>")
	)
	(segment
		(start 90.574368 -405.885142)
		(end 90.505788 -405.856694)
		(width 0.14224)
		(layer "In15.Cu")
		(net "P5E_CPU1_P0_RX_BUF_DN<14>")
	)
	(segment
		(start 87.650066 -438.089802)
		(end 87.650066 -437.769762)
		(width 0.14224)
		(layer "In15.Cu")
		(net "P5E_CPU1_P0_RX_BUF_DN<14>")
	)
	(segment
		(start 87.126826 -422.909238)
		(end 92.501974 -413.42056)
		(width 0.14224)
		(layer "In15.Cu")
		(net "P5E_CPU1_P0_RX_BUF_DN<14>")
	)
	(segment
		(start 90.970354 -410.630878)
		(end 90.970354 -406.481026)
		(width 0.14224)
		(layer "In15.Cu")
		(net "P5E_CPU1_P0_RX_BUF_DN<14>")
	)
	(segment
		(start 92.29852 -411.59557)
		(end 91.416378 -411.230318)
		(width 0.14224)
		(layer "In15.Cu")
		(net "P5E_CPU1_P0_RX_BUF_DN<14>")
	)
	(segment
		(start 83.217258 -399.284952)
		(end 80.638396 -398.19834)
		(width 0.14224)
		(layer "In15.Cu")
		(net "P5E_CPU1_P0_RX_BUF_DN<14>")
	)
	(segment
		(start 86.991698 -437.623204)
		(end 86.694518 -437.326024)
		(width 0.14224)
		(layer "In15.Cu")
		(net "P5E_CPU1_P0_RX_BUF_DN<14>")
	)
	(segment
		(start 88.38946 -402.561044)
		(end 86.98738 -401.48002)
		(width 0.14224)
		(layer "In15.Cu")
		(net "P5E_CPU1_P0_RX_BUF_DN<14>")
	)
	(segment
		(start 69.050408 -396.487904)
		(end 68.672202 -396.450566)
		(width 0.14224)
		(layer "In15.Cu")
		(net "P5E_CPU1_P0_RX_BUF_DN<14>")
	)
	(segment
		(start 64.489584 -392.707622)
		(end 64.616584 -392.580622)
		(width 0.14224)
		(layer "In15.Cu")
		(net "P5E_CPU1_P0_RX_BUF_DN<14>")
	)
	(segment
		(start 92.501974 -413.42056)
		(end 92.501974 -412.036768)
		(width 0.14224)
		(layer "In15.Cu")
		(net "P5E_CPU1_P0_RX_BUF_DN<14>")
	)
	(segment
		(start 64.180212 -392.707622)
		(end 64.489584 -392.707622)
		(width 0.14224)
		(layer "In15.Cu")
		(net "P5E_CPU1_P0_RX_BUF_DN<14>")
	)
	(segment
		(start 90.505788 -405.856694)
		(end 89.993216 -405.856694)
		(width 0.14224)
		(layer "In15.Cu")
		(net "P5E_CPU1_P0_RX_BUF_DN<14>")
	)
	(segment
		(start 91.416378 -411.230318)
		(end 91.291156 -411.146498)
		(width 0.14224)
		(layer "In15.Cu")
		(net "P5E_CPU1_P0_RX_BUF_DN<14>")
	)
	(segment
		(start 89.81821 -405.78405)
		(end 89.554304 -405.520144)
		(width 0.14224)
		(layer "In15.Cu")
		(net "P5E_CPU1_P0_RX_BUF_DN<14>")
	)
	(segment
		(start 67.773042 -396.270734)
		(end 64.51854 -395.283182)
		(width 0.14224)
		(layer "In15.Cu")
		(net "P5E_CPU1_P0_RX_BUF_DN<14>")
	)
	(segment
		(start 90.828876 -406.13965)
		(end 90.574368 -405.885142)
		(width 0.14224)
		(layer "In15.Cu")
		(net "P5E_CPU1_P0_RX_BUF_DN<14>")
	)
	(segment
		(start 64.616584 -392.580622)
		(end 64.616584 -392.429238)
		(width 0.14224)
		(layer "In15.Cu")
		(net "P5E_CPU1_P0_RX_BUF_DN<14>")
	)
	(segment
		(start 87.503508 -437.623204)
		(end 86.991698 -437.623204)
		(width 0.14224)
		(layer "In15.Cu")
		(net "P5E_CPU1_P0_RX_BUF_DN<14>")
	)
	(segment
		(start 89.360502 -403.733)
		(end 89.011506 -403.210776)
		(width 0.14224)
		(layer "In15.Cu")
		(net "P5E_CPU1_P0_RX_BUF_DN<14>")
	)
	(segment
		(start 86.912704 -401.429728)
		(end 83.330542 -399.341594)
		(width 0.14224)
		(layer "In15.Cu")
		(net "P5E_CPU1_P0_RX_BUF_DN<14>")
	)
	(segment
		(start 63.875666 -393.012168)
		(end 64.180212 -392.707622)
		(width 0.14224)
		(layer "In15.Cu")
		(net "P5E_CPU1_P0_RX_BUF_DN<14>")
	)
	(segment
		(start 90.970354 -406.481026)
		(end 90.828876 -406.13965)
		(width 0.14224)
		(layer "In15.Cu")
		(net "P5E_CPU1_P0_RX_BUF_DN<14>")
	)
	(segment
		(start 89.438734 -405.241252)
		(end 89.438734 -403.921722)
		(width 0.14224)
		(layer "In15.Cu")
		(net "P5E_CPU1_P0_RX_BUF_DN<14>")
	)
	(segment
		(start 92.501974 -412.036768)
		(end 92.33408 -411.63113)
		(width 0.14224)
		(layer "In15.Cu")
		(net "P5E_CPU1_P0_RX_BUF_DN<14>")
	)
	(segment
		(start 89.438734 -403.921722)
		(end 89.360502 -403.733)
		(width 0.14224)
		(layer "In15.Cu")
		(net "P5E_CPU1_P0_RX_BUF_DN<14>")
	)
	(segment
		(start 80.51673 -398.164304)
		(end 70.102984 -396.617952)
		(width 0.14224)
		(layer "In15.Cu")
		(net "P5E_CPU1_P0_RX_BUF_DN<14>")
	)
	(segment
		(start 63.875666 -394.386562)
		(end 63.875666 -393.012168)
		(width 0.14224)
		(layer "In15.Cu")
		(net "P5E_CPU1_P0_RX_BUF_DN<14>")
	)
	(segment
		(start 91.291156 -411.146498)
		(end 91.108276 -410.963618)
		(width 0.14224)
		(layer "In15.Cu")
		(net "P5E_CPU1_P0_RX_BUF_DN<14>")
	)
	(segment
		(start 89.554304 -405.520144)
		(end 89.438734 -405.241252)
		(width 0.14224)
		(layer "In15.Cu")
		(net "P5E_CPU1_P0_RX_BUF_DN<14>")
	)
	(segment
		(start 92.33408 -411.63113)
		(end 92.29852 -411.59557)
		(width 0.14224)
		(layer "In15.Cu")
		(net "P5E_CPU1_P0_RX_BUF_DN<14>")
	)
	(arc
		(start 80.638396 -398.19834)
		(mid 80.578636 -398.177482)
		(end 80.51673 -398.164304)
		(width 0.14224)
		(layer "In15.Cu")
		(net "P5E_CPU1_P0_RX_BUF_DN<14>")
	)
	(arc
		(start 64.51854 -395.283182)
		(mid 64.108514 -395.021628)
		(end 63.893954 -394.58519)
		(width 0.14224)
		(layer "In15.Cu")
		(net "P5E_CPU1_P0_RX_BUF_DN<14>")
	)
	(arc
		(start 70.102984 -396.617952)
		(mid 69.577493 -396.546476)
		(end 69.050408 -396.487904)
		(width 0.14224)
		(layer "In15.Cu")
		(net "P5E_CPU1_P0_RX_BUF_DN<14>")
	)
	(arc
		(start 86.98738 -401.48002)
		(mid 86.950852 -401.453671)
		(end 86.912704 -401.429728)
		(width 0.14224)
		(layer "In15.Cu")
		(net "P5E_CPU1_P0_RX_BUF_DN<14>")
	)
	(arc
		(start 68.672202 -396.450566)
		(mid 68.609363 -396.442831)
		(end 68.54698 -396.432024)
		(width 0.14224)
		(layer "In15.Cu")
		(net "P5E_CPU1_P0_RX_BUF_DN<14>")
	)
	(arc
		(start 63.893954 -394.58519)
		(mid 63.880228 -394.486298)
		(end 63.875666 -394.386562)
		(width 0.14224)
		(layer "In15.Cu")
		(net "P5E_CPU1_P0_RX_BUF_DN<14>")
	)
	(arc
		(start 83.330542 -399.341594)
		(mid 83.274813 -399.311447)
		(end 83.217258 -399.284952)
		(width 0.14224)
		(layer "In15.Cu")
		(net "P5E_CPU1_P0_RX_BUF_DN<14>")
	)
	(arc
		(start 67.922902 -396.308072)
		(mid 67.847511 -396.291252)
		(end 67.773042 -396.270734)
		(width 0.14224)
		(layer "In15.Cu")
		(net "P5E_CPU1_P0_RX_BUF_DN<14>")
	)
	(arc
		(start 88.483186 -402.64588)
		(mid 88.438034 -402.601573)
		(end 88.38946 -402.561044)
		(width 0.14224)
		(layer "In15.Cu")
		(net "P5E_CPU1_P0_RX_BUF_DN<14>")
	)
	(arc
		(start 86.694518 -424.54957)
		(mid 86.804409 -423.701398)
		(end 87.126826 -422.909238)
		(width 0.14224)
		(layer "In15.Cu")
		(net "P5E_CPU1_P0_RX_BUF_DN<14>")
	)
	(segment
		(start 63.018416 -390.761982)
		(end 63.018416 -391.578338)
		(width 0.1016)
		(layer "F.Cu")
		(net "P5E_CPU1_P0_RX_BUF_DN<13>")
	)
	(segment
		(start 62.938406 -392.634216)
		(end 63.065406 -392.761216)
		(width 0.1016)
		(layer "F.Cu")
		(net "P5E_CPU1_P0_RX_BUF_DN<13>")
	)
	(segment
		(start 63.018416 -391.578338)
		(end 62.938406 -391.658348)
		(width 0.1016)
		(layer "F.Cu")
		(net "P5E_CPU1_P0_RX_BUF_DN<13>")
	)
	(segment
		(start 63.017908 -390.761474)
		(end 63.018416 -390.761982)
		(width 0.1016)
		(layer "F.Cu")
		(net "P5E_CPU1_P0_RX_BUF_DN<13>")
	)
	(segment
		(start 62.938406 -391.658348)
		(end 62.938406 -392.634216)
		(width 0.1016)
		(layer "F.Cu")
		(net "P5E_CPU1_P0_RX_BUF_DN<13>")
	)
	(segment
		(start 63.275718 -392.761216)
		(end 63.416434 -392.6205)
		(width 0.1016)
		(layer "F.Cu")
		(net "P5E_CPU1_P0_RX_BUF_DN<13>")
	)
	(segment
		(start 63.065406 -392.761216)
		(end 63.275718 -392.761216)
		(width 0.1016)
		(layer "F.Cu")
		(net "P5E_CPU1_P0_RX_BUF_DN<13>")
	)
	(segment
		(start 63.416434 -392.6205)
		(end 63.416434 -392.429238)
		(width 0.1016)
		(layer "F.Cu")
		(net "P5E_CPU1_P0_RX_BUF_DN<13>")
	)
	(segment
		(start 88.045036 -410.963618)
		(end 87.907114 -410.630878)
		(width 0.14224)
		(layer "In15.Cu")
		(net "P5E_CPU1_P0_RX_BUF_DN<13>")
	)
	(segment
		(start 65.687194 -396.664942)
		(end 65.367154 -396.538704)
		(width 0.14224)
		(layer "In15.Cu")
		(net "P5E_CPU1_P0_RX_BUF_DN<13>")
	)
	(segment
		(start 85.503512 -438.623202)
		(end 84.996528 -438.623202)
		(width 0.14224)
		(layer "In15.Cu")
		(net "P5E_CPU1_P0_RX_BUF_DN<13>")
	)
	(segment
		(start 78.448662 -399.078704)
		(end 70.147434 -397.847058)
		(width 0.14224)
		(layer "In15.Cu")
		(net "P5E_CPU1_P0_RX_BUF_DN<13>")
	)
	(segment
		(start 79.914496 -399.484342)
		(end 78.448662 -399.078704)
		(width 0.14224)
		(layer "In15.Cu")
		(net "P5E_CPU1_P0_RX_BUF_DN<13>")
	)
	(segment
		(start 86.24316 -419.238684)
		(end 89.438734 -413.26054)
		(width 0.14224)
		(layer "In15.Cu")
		(net "P5E_CPU1_P0_RX_BUF_DN<13>")
	)
	(segment
		(start 88.227916 -411.146498)
		(end 88.045036 -410.963618)
		(width 0.14224)
		(layer "In15.Cu")
		(net "P5E_CPU1_P0_RX_BUF_DN<13>")
	)
	(segment
		(start 66.293238 -396.959836)
		(end 65.687194 -396.664942)
		(width 0.14224)
		(layer "In15.Cu")
		(net "P5E_CPU1_P0_RX_BUF_DN<13>")
	)
	(segment
		(start 89.438734 -412.003748)
		(end 89.294208 -411.654498)
		(width 0.14224)
		(layer "In15.Cu")
		(net "P5E_CPU1_P0_RX_BUF_DN<13>")
	)
	(segment
		(start 88.353138 -411.230318)
		(end 88.227916 -411.146498)
		(width 0.14224)
		(layer "In15.Cu")
		(net "P5E_CPU1_P0_RX_BUF_DN<13>")
	)
	(segment
		(start 63.566802 -395.929104)
		(end 62.94374 -395.305788)
		(width 0.14224)
		(layer "In15.Cu")
		(net "P5E_CPU1_P0_RX_BUF_DN<13>")
	)
	(segment
		(start 84.694522 -438.321196)
		(end 84.694522 -423.888916)
		(width 0.14224)
		(layer "In15.Cu")
		(net "P5E_CPU1_P0_RX_BUF_DN<13>")
	)
	(segment
		(start 85.405976 -421.26027)
		(end 86.24316 -419.238684)
		(width 0.14224)
		(layer "In15.Cu")
		(net "P5E_CPU1_P0_RX_BUF_DN<13>")
	)
	(segment
		(start 86.32317 -403.463506)
		(end 85.765132 -402.905468)
		(width 0.14224)
		(layer "In15.Cu")
		(net "P5E_CPU1_P0_RX_BUF_DN<13>")
	)
	(segment
		(start 84.996528 -438.623202)
		(end 84.694522 -438.321196)
		(width 0.14224)
		(layer "In15.Cu")
		(net "P5E_CPU1_P0_RX_BUF_DN<13>")
	)
	(segment
		(start 86.491064 -405.520144)
		(end 86.375494 -405.240998)
		(width 0.14224)
		(layer "In15.Cu")
		(net "P5E_CPU1_P0_RX_BUF_DN<13>")
	)
	(segment
		(start 86.929976 -405.856694)
		(end 86.75497 -405.78405)
		(width 0.14224)
		(layer "In15.Cu")
		(net "P5E_CPU1_P0_RX_BUF_DN<13>")
	)
	(segment
		(start 85.765132 -402.905468)
		(end 82.24139 -400.55038)
		(width 0.14224)
		(layer "In15.Cu")
		(net "P5E_CPU1_P0_RX_BUF_DN<13>")
	)
	(segment
		(start 70.147434 -397.847058)
		(end 66.293238 -396.959836)
		(width 0.14224)
		(layer "In15.Cu")
		(net "P5E_CPU1_P0_RX_BUF_DN<13>")
	)
	(segment
		(start 87.765636 -406.13965)
		(end 87.511128 -405.885142)
		(width 0.14224)
		(layer "In15.Cu")
		(net "P5E_CPU1_P0_RX_BUF_DN<13>")
	)
	(segment
		(start 89.438734 -413.26054)
		(end 89.438734 -412.003748)
		(width 0.14224)
		(layer "In15.Cu")
		(net "P5E_CPU1_P0_RX_BUF_DN<13>")
	)
	(segment
		(start 86.375494 -405.240998)
		(end 86.375494 -403.589744)
		(width 0.14224)
		(layer "In15.Cu")
		(net "P5E_CPU1_P0_RX_BUF_DN<13>")
	)
	(segment
		(start 89.294208 -411.654498)
		(end 89.23528 -411.59557)
		(width 0.14224)
		(layer "In15.Cu")
		(net "P5E_CPU1_P0_RX_BUF_DN<13>")
	)
	(segment
		(start 63.416434 -392.580622)
		(end 63.416434 -392.429238)
		(width 0.14224)
		(layer "In15.Cu")
		(net "P5E_CPU1_P0_RX_BUF_DN<13>")
	)
	(segment
		(start 62.675516 -393.012168)
		(end 62.980062 -392.707622)
		(width 0.14224)
		(layer "In15.Cu")
		(net "P5E_CPU1_P0_RX_BUF_DN<13>")
	)
	(segment
		(start 87.511128 -405.885142)
		(end 87.442548 -405.856694)
		(width 0.14224)
		(layer "In15.Cu")
		(net "P5E_CPU1_P0_RX_BUF_DN<13>")
	)
	(segment
		(start 85.405722 -421.260524)
		(end 85.405976 -421.26027)
		(width 0.14224)
		(layer "In15.Cu")
		(net "P5E_CPU1_P0_RX_BUF_DN<13>")
	)
	(segment
		(start 89.23528 -411.59557)
		(end 88.353138 -411.230318)
		(width 0.14224)
		(layer "In15.Cu")
		(net "P5E_CPU1_P0_RX_BUF_DN<13>")
	)
	(segment
		(start 65.367154 -396.538704)
		(end 63.76162 -396.046198)
		(width 0.14224)
		(layer "In15.Cu")
		(net "P5E_CPU1_P0_RX_BUF_DN<13>")
	)
	(segment
		(start 87.442548 -405.856694)
		(end 86.929976 -405.856694)
		(width 0.14224)
		(layer "In15.Cu")
		(net "P5E_CPU1_P0_RX_BUF_DN<13>")
	)
	(segment
		(start 63.289434 -392.707622)
		(end 63.416434 -392.580622)
		(width 0.14224)
		(layer "In15.Cu")
		(net "P5E_CPU1_P0_RX_BUF_DN<13>")
	)
	(segment
		(start 86.75497 -405.78405)
		(end 86.491064 -405.520144)
		(width 0.14224)
		(layer "In15.Cu")
		(net "P5E_CPU1_P0_RX_BUF_DN<13>")
	)
	(segment
		(start 62.675516 -394.658342)
		(end 62.675516 -393.012168)
		(width 0.14224)
		(layer "In15.Cu")
		(net "P5E_CPU1_P0_RX_BUF_DN<13>")
	)
	(segment
		(start 85.04301 -422.135808)
		(end 85.405722 -421.260524)
		(width 0.14224)
		(layer "In15.Cu")
		(net "P5E_CPU1_P0_RX_BUF_DN<13>")
	)
	(segment
		(start 85.65007 -438.76976)
		(end 85.503512 -438.623202)
		(width 0.14224)
		(layer "In15.Cu")
		(net "P5E_CPU1_P0_RX_BUF_DN<13>")
	)
	(segment
		(start 62.980062 -392.707622)
		(end 63.289434 -392.707622)
		(width 0.14224)
		(layer "In15.Cu")
		(net "P5E_CPU1_P0_RX_BUF_DN<13>")
	)
	(segment
		(start 87.907114 -406.481026)
		(end 87.765636 -406.13965)
		(width 0.14224)
		(layer "In15.Cu")
		(net "P5E_CPU1_P0_RX_BUF_DN<13>")
	)
	(segment
		(start 63.76162 -396.046198)
		(end 63.566802 -395.929104)
		(width 0.14224)
		(layer "In15.Cu")
		(net "P5E_CPU1_P0_RX_BUF_DN<13>")
	)
	(segment
		(start 87.907114 -410.630878)
		(end 87.907114 -406.481026)
		(width 0.14224)
		(layer "In15.Cu")
		(net "P5E_CPU1_P0_RX_BUF_DN<13>")
	)
	(segment
		(start 82.24139 -400.55038)
		(end 79.914496 -399.484342)
		(width 0.14224)
		(layer "In15.Cu")
		(net "P5E_CPU1_P0_RX_BUF_DN<13>")
	)
	(segment
		(start 85.65007 -439.0898)
		(end 85.65007 -438.76976)
		(width 0.14224)
		(layer "In15.Cu")
		(net "P5E_CPU1_P0_RX_BUF_DN<13>")
	)
	(arc
		(start 84.694522 -423.888916)
		(mid 84.782412 -422.995196)
		(end 85.04301 -422.135808)
		(width 0.14224)
		(layer "In15.Cu")
		(net "P5E_CPU1_P0_RX_BUF_DN<13>")
	)
	(arc
		(start 62.94374 -395.305788)
		(mid 62.745203 -395.008751)
		(end 62.675516 -394.658342)
		(width 0.14224)
		(layer "In15.Cu")
		(net "P5E_CPU1_P0_RX_BUF_DN<13>")
	)
	(arc
		(start 86.375494 -403.589744)
		(mid 86.361902 -403.521411)
		(end 86.32317 -403.463506)
		(width 0.14224)
		(layer "In15.Cu")
		(net "P5E_CPU1_P0_RX_BUF_DN<13>")
	)
	(segment
		(start 61.81852 -390.761982)
		(end 61.818012 -390.761474)
		(width 0.1016)
		(layer "F.Cu")
		(net "P5E_CPU1_P0_RX_BUF_DN<12>")
	)
	(segment
		(start 62.216538 -392.429238)
		(end 62.216538 -392.595862)
		(width 0.1016)
		(layer "F.Cu")
		(net "P5E_CPU1_P0_RX_BUF_DN<12>")
	)
	(segment
		(start 61.729874 -392.634216)
		(end 61.729874 -391.666984)
		(width 0.1016)
		(layer "F.Cu")
		(net "P5E_CPU1_P0_RX_BUF_DN<12>")
	)
	(segment
		(start 61.81852 -391.578338)
		(end 61.81852 -390.761982)
		(width 0.1016)
		(layer "F.Cu")
		(net "P5E_CPU1_P0_RX_BUF_DN<12>")
	)
	(segment
		(start 61.729874 -391.666984)
		(end 61.81852 -391.578338)
		(width 0.1016)
		(layer "F.Cu")
		(net "P5E_CPU1_P0_RX_BUF_DN<12>")
	)
	(segment
		(start 62.216538 -392.595862)
		(end 62.051184 -392.761216)
		(width 0.1016)
		(layer "F.Cu")
		(net "P5E_CPU1_P0_RX_BUF_DN<12>")
	)
	(segment
		(start 61.856874 -392.761216)
		(end 61.729874 -392.634216)
		(width 0.1016)
		(layer "F.Cu")
		(net "P5E_CPU1_P0_RX_BUF_DN<12>")
	)
	(segment
		(start 62.051184 -392.761216)
		(end 61.856874 -392.761216)
		(width 0.1016)
		(layer "F.Cu")
		(net "P5E_CPU1_P0_RX_BUF_DN<12>")
	)
	(segment
		(start 83.11134 -403.314916)
		(end 82.772758 -402.976334)
		(width 0.14224)
		(layer "In15.Cu")
		(net "P5E_CPU1_P0_RX_BUF_DN<12>")
	)
	(segment
		(start 84.702396 -406.13965)
		(end 84.447888 -405.885142)
		(width 0.14224)
		(layer "In15.Cu")
		(net "P5E_CPU1_P0_RX_BUF_DN<12>")
	)
	(segment
		(start 83.866736 -405.856694)
		(end 83.69173 -405.78405)
		(width 0.14224)
		(layer "In15.Cu")
		(net "P5E_CPU1_P0_RX_BUF_DN<12>")
	)
	(segment
		(start 63.29299 -397.042386)
		(end 62.896496 -396.801086)
		(width 0.14224)
		(layer "In15.Cu")
		(net "P5E_CPU1_P0_RX_BUF_DN<12>")
	)
	(segment
		(start 83.650074 -437.769762)
		(end 83.503516 -437.623204)
		(width 0.14224)
		(layer "In15.Cu")
		(net "P5E_CPU1_P0_RX_BUF_DN<12>")
	)
	(segment
		(start 61.47562 -393.012168)
		(end 61.780166 -392.707622)
		(width 0.14224)
		(layer "In15.Cu")
		(net "P5E_CPU1_P0_RX_BUF_DN<12>")
	)
	(segment
		(start 62.089538 -392.707622)
		(end 62.216538 -392.580622)
		(width 0.14224)
		(layer "In15.Cu")
		(net "P5E_CPU1_P0_RX_BUF_DN<12>")
	)
	(segment
		(start 84.843874 -410.630878)
		(end 84.843874 -406.481026)
		(width 0.14224)
		(layer "In15.Cu")
		(net "P5E_CPU1_P0_RX_BUF_DN<12>")
	)
	(segment
		(start 82.717894 -402.931376)
		(end 79.939134 -401.074382)
		(width 0.14224)
		(layer "In15.Cu")
		(net "P5E_CPU1_P0_RX_BUF_DN<12>")
	)
	(segment
		(start 82.694526 -437.326024)
		(end 82.694526 -423.117772)
		(width 0.14224)
		(layer "In15.Cu")
		(net "P5E_CPU1_P0_RX_BUF_DN<12>")
	)
	(segment
		(start 83.07832 -421.188642)
		(end 86.375494 -413.22879)
		(width 0.14224)
		(layer "In15.Cu")
		(net "P5E_CPU1_P0_RX_BUF_DN<12>")
	)
	(segment
		(start 83.503516 -437.623204)
		(end 82.991706 -437.623204)
		(width 0.14224)
		(layer "In15.Cu")
		(net "P5E_CPU1_P0_RX_BUF_DN<12>")
	)
	(segment
		(start 84.379308 -405.856694)
		(end 83.866736 -405.856694)
		(width 0.14224)
		(layer "In15.Cu")
		(net "P5E_CPU1_P0_RX_BUF_DN<12>")
	)
	(segment
		(start 86.375494 -412.004002)
		(end 86.230968 -411.654498)
		(width 0.14224)
		(layer "In15.Cu")
		(net "P5E_CPU1_P0_RX_BUF_DN<12>")
	)
	(segment
		(start 83.427316 -405.51989)
		(end 83.312254 -405.239474)
		(width 0.14224)
		(layer "In15.Cu")
		(net "P5E_CPU1_P0_RX_BUF_DN<12>")
	)
	(segment
		(start 86.230968 -411.654498)
		(end 86.17204 -411.59557)
		(width 0.14224)
		(layer "In15.Cu")
		(net "P5E_CPU1_P0_RX_BUF_DN<12>")
	)
	(segment
		(start 82.991706 -437.623204)
		(end 82.694526 -437.326024)
		(width 0.14224)
		(layer "In15.Cu")
		(net "P5E_CPU1_P0_RX_BUF_DN<12>")
	)
	(segment
		(start 62.896496 -396.801086)
		(end 62.352936 -396.257526)
		(width 0.14224)
		(layer "In15.Cu")
		(net "P5E_CPU1_P0_RX_BUF_DN<12>")
	)
	(segment
		(start 61.780166 -392.707622)
		(end 62.089538 -392.707622)
		(width 0.14224)
		(layer "In15.Cu")
		(net "P5E_CPU1_P0_RX_BUF_DN<12>")
	)
	(segment
		(start 67.6148 -398.353788)
		(end 63.29299 -397.042386)
		(width 0.14224)
		(layer "In15.Cu")
		(net "P5E_CPU1_P0_RX_BUF_DN<12>")
	)
	(segment
		(start 78.6638 -400.55927)
		(end 67.76466 -398.391126)
		(width 0.14224)
		(layer "In15.Cu")
		(net "P5E_CPU1_P0_RX_BUF_DN<12>")
	)
	(segment
		(start 86.17204 -411.59557)
		(end 85.289898 -411.230318)
		(width 0.14224)
		(layer "In15.Cu")
		(net "P5E_CPU1_P0_RX_BUF_DN<12>")
	)
	(segment
		(start 83.312254 -405.239474)
		(end 83.312254 -403.799802)
		(width 0.14224)
		(layer "In15.Cu")
		(net "P5E_CPU1_P0_RX_BUF_DN<12>")
	)
	(segment
		(start 84.447888 -405.885142)
		(end 84.379308 -405.856694)
		(width 0.14224)
		(layer "In15.Cu")
		(net "P5E_CPU1_P0_RX_BUF_DN<12>")
	)
	(segment
		(start 83.650074 -438.089802)
		(end 83.650074 -437.769762)
		(width 0.14224)
		(layer "In15.Cu")
		(net "P5E_CPU1_P0_RX_BUF_DN<12>")
	)
	(segment
		(start 83.69173 -405.78405)
		(end 83.427316 -405.51989)
		(width 0.14224)
		(layer "In15.Cu")
		(net "P5E_CPU1_P0_RX_BUF_DN<12>")
	)
	(segment
		(start 61.47562 -395.315694)
		(end 61.47562 -393.012168)
		(width 0.14224)
		(layer "In15.Cu")
		(net "P5E_CPU1_P0_RX_BUF_DN<12>")
	)
	(segment
		(start 62.352936 -396.257526)
		(end 62.352936 -396.25778)
		(width 0.14224)
		(layer "In15.Cu")
		(net "P5E_CPU1_P0_RX_BUF_DN<12>")
	)
	(segment
		(start 62.216538 -392.580622)
		(end 62.216538 -392.429238)
		(width 0.14224)
		(layer "In15.Cu")
		(net "P5E_CPU1_P0_RX_BUF_DN<12>")
	)
	(segment
		(start 84.843874 -406.481026)
		(end 84.702396 -406.13965)
		(width 0.14224)
		(layer "In15.Cu")
		(net "P5E_CPU1_P0_RX_BUF_DN<12>")
	)
	(segment
		(start 62.352936 -396.25778)
		(end 61.522102 -395.426946)
		(width 0.14224)
		(layer "In15.Cu")
		(net "P5E_CPU1_P0_RX_BUF_DN<12>")
	)
	(segment
		(start 61.522102 -395.426946)
		(end 61.47562 -395.315694)
		(width 0.14224)
		(layer "In15.Cu")
		(net "P5E_CPU1_P0_RX_BUF_DN<12>")
	)
	(segment
		(start 79.827628 -401.014692)
		(end 78.901036 -400.631152)
		(width 0.14224)
		(layer "In15.Cu")
		(net "P5E_CPU1_P0_RX_BUF_DN<12>")
	)
	(segment
		(start 85.289898 -411.230318)
		(end 84.952586 -410.893006)
		(width 0.14224)
		(layer "In15.Cu")
		(net "P5E_CPU1_P0_RX_BUF_DN<12>")
	)
	(segment
		(start 84.952586 -410.893006)
		(end 84.843874 -410.630878)
		(width 0.14224)
		(layer "In15.Cu")
		(net "P5E_CPU1_P0_RX_BUF_DN<12>")
	)
	(segment
		(start 86.375494 -413.22879)
		(end 86.375494 -412.004002)
		(width 0.14224)
		(layer "In15.Cu")
		(net "P5E_CPU1_P0_RX_BUF_DN<12>")
	)
	(arc
		(start 83.312254 -403.799802)
		(mid 83.260036 -403.537372)
		(end 83.11134 -403.314916)
		(width 0.14224)
		(layer "In15.Cu")
		(net "P5E_CPU1_P0_RX_BUF_DN<12>")
	)
	(arc
		(start 67.76466 -398.391126)
		(mid 67.689272 -398.374294)
		(end 67.6148 -398.353788)
		(width 0.14224)
		(layer "In15.Cu")
		(net "P5E_CPU1_P0_RX_BUF_DN<12>")
	)
	(arc
		(start 78.901036 -400.631152)
		(mid 78.784175 -400.589413)
		(end 78.6638 -400.55927)
		(width 0.14224)
		(layer "In15.Cu")
		(net "P5E_CPU1_P0_RX_BUF_DN<12>")
	)
	(arc
		(start 79.939134 -401.074382)
		(mid 79.884851 -401.041791)
		(end 79.827628 -401.014692)
		(width 0.14224)
		(layer "In15.Cu")
		(net "P5E_CPU1_P0_RX_BUF_DN<12>")
	)
	(arc
		(start 82.694526 -423.117772)
		(mid 82.791423 -422.134306)
		(end 83.07832 -421.188642)
		(width 0.14224)
		(layer "In15.Cu")
		(net "P5E_CPU1_P0_RX_BUF_DN<12>")
	)
	(arc
		(start 82.772758 -402.976334)
		(mid 82.746428 -402.952511)
		(end 82.717894 -402.931376)
		(width 0.14224)
		(layer "In15.Cu")
		(net "P5E_CPU1_P0_RX_BUF_DN<12>")
	)
	(segment
		(start 60.875672 -392.761216)
		(end 60.656724 -392.761216)
		(width 0.1016)
		(layer "F.Cu")
		(net "P5E_CPU1_P0_RX_BUF_DN<11>")
	)
	(segment
		(start 61.016642 -392.429238)
		(end 61.016642 -392.620246)
		(width 0.1016)
		(layer "F.Cu")
		(net "P5E_CPU1_P0_RX_BUF_DN<11>")
	)
	(segment
		(start 61.016642 -392.620246)
		(end 60.875672 -392.761216)
		(width 0.1016)
		(layer "F.Cu")
		(net "P5E_CPU1_P0_RX_BUF_DN<11>")
	)
	(segment
		(start 60.529724 -391.666984)
		(end 60.61837 -391.578338)
		(width 0.1016)
		(layer "F.Cu")
		(net "P5E_CPU1_P0_RX_BUF_DN<11>")
	)
	(segment
		(start 60.529724 -392.634216)
		(end 60.529724 -391.666984)
		(width 0.1016)
		(layer "F.Cu")
		(net "P5E_CPU1_P0_RX_BUF_DN<11>")
	)
	(segment
		(start 60.61837 -391.578338)
		(end 60.61837 -390.761728)
		(width 0.1016)
		(layer "F.Cu")
		(net "P5E_CPU1_P0_RX_BUF_DN<11>")
	)
	(segment
		(start 60.656724 -392.761216)
		(end 60.529724 -392.634216)
		(width 0.1016)
		(layer "F.Cu")
		(net "P5E_CPU1_P0_RX_BUF_DN<11>")
	)
	(segment
		(start 60.61837 -390.761728)
		(end 60.618116 -390.761474)
		(width 0.1016)
		(layer "F.Cu")
		(net "P5E_CPU1_P0_RX_BUF_DN<11>")
	)
	(segment
		(start 81.918556 -410.963618)
		(end 81.780634 -410.630878)
		(width 0.14224)
		(layer "In15.Cu")
		(net "P5E_CPU1_P0_RX_BUF_DN<11>")
	)
	(segment
		(start 83.312254 -412.004002)
		(end 83.167474 -411.654498)
		(width 0.14224)
		(layer "In15.Cu")
		(net "P5E_CPU1_P0_RX_BUF_DN<11>")
	)
	(segment
		(start 82.101436 -411.146498)
		(end 81.918556 -410.963618)
		(width 0.14224)
		(layer "In15.Cu")
		(net "P5E_CPU1_P0_RX_BUF_DN<11>")
	)
	(segment
		(start 81.384648 -405.885142)
		(end 81.316068 -405.856694)
		(width 0.14224)
		(layer "In15.Cu")
		(net "P5E_CPU1_P0_RX_BUF_DN<11>")
	)
	(segment
		(start 82.226658 -411.230318)
		(end 82.101436 -411.146498)
		(width 0.14224)
		(layer "In15.Cu")
		(net "P5E_CPU1_P0_RX_BUF_DN<11>")
	)
	(segment
		(start 81.650078 -439.0898)
		(end 81.650078 -438.76976)
		(width 0.14224)
		(layer "In15.Cu")
		(net "P5E_CPU1_P0_RX_BUF_DN<11>")
	)
	(segment
		(start 62.023244 -397.459708)
		(end 60.40501 -395.995906)
		(width 0.14224)
		(layer "In15.Cu")
		(net "P5E_CPU1_P0_RX_BUF_DN<11>")
	)
	(segment
		(start 81.650078 -438.76976)
		(end 81.50352 -438.623202)
		(width 0.14224)
		(layer "In15.Cu")
		(net "P5E_CPU1_P0_RX_BUF_DN<11>")
	)
	(segment
		(start 60.275724 -393.012168)
		(end 60.58027 -392.707622)
		(width 0.14224)
		(layer "In15.Cu")
		(net "P5E_CPU1_P0_RX_BUF_DN<11>")
	)
	(segment
		(start 74.526902 -400.896836)
		(end 67.806316 -399.386806)
		(width 0.14224)
		(layer "In15.Cu")
		(net "P5E_CPU1_P0_RX_BUF_DN<11>")
	)
	(segment
		(start 81.780634 -406.481026)
		(end 81.639156 -406.13965)
		(width 0.14224)
		(layer "In15.Cu")
		(net "P5E_CPU1_P0_RX_BUF_DN<11>")
	)
	(segment
		(start 83.167474 -411.654498)
		(end 83.167728 -411.654498)
		(width 0.14224)
		(layer "In15.Cu")
		(net "P5E_CPU1_P0_RX_BUF_DN<11>")
	)
	(segment
		(start 79.790544 -403.077426)
		(end 74.526902 -400.896836)
		(width 0.14224)
		(layer "In15.Cu")
		(net "P5E_CPU1_P0_RX_BUF_DN<11>")
	)
	(segment
		(start 80.99171 -438.623202)
		(end 80.69453 -438.326022)
		(width 0.14224)
		(layer "In15.Cu")
		(net "P5E_CPU1_P0_RX_BUF_DN<11>")
	)
	(segment
		(start 81.639156 -406.13965)
		(end 81.384648 -405.885142)
		(width 0.14224)
		(layer "In15.Cu")
		(net "P5E_CPU1_P0_RX_BUF_DN<11>")
	)
	(segment
		(start 80.249014 -403.535896)
		(end 79.790544 -403.077426)
		(width 0.14224)
		(layer "In15.Cu")
		(net "P5E_CPU1_P0_RX_BUF_DN<11>")
	)
	(segment
		(start 61.016642 -392.580622)
		(end 61.016642 -392.429238)
		(width 0.14224)
		(layer "In15.Cu")
		(net "P5E_CPU1_P0_RX_BUF_DN<11>")
	)
	(segment
		(start 81.316068 -405.856694)
		(end 80.803496 -405.856694)
		(width 0.14224)
		(layer "In15.Cu")
		(net "P5E_CPU1_P0_RX_BUF_DN<11>")
	)
	(segment
		(start 80.62849 -405.78405)
		(end 80.449674 -405.605234)
		(width 0.14224)
		(layer "In15.Cu")
		(net "P5E_CPU1_P0_RX_BUF_DN<11>")
	)
	(segment
		(start 81.50352 -438.623202)
		(end 80.99171 -438.623202)
		(width 0.14224)
		(layer "In15.Cu")
		(net "P5E_CPU1_P0_RX_BUF_DN<11>")
	)
	(segment
		(start 60.889642 -392.707622)
		(end 61.016642 -392.580622)
		(width 0.14224)
		(layer "In15.Cu")
		(net "P5E_CPU1_P0_RX_BUF_DN<11>")
	)
	(segment
		(start 81.006188 -421.235632)
		(end 81.337912 -420.142924)
		(width 0.14224)
		(layer "In15.Cu")
		(net "P5E_CPU1_P0_RX_BUF_DN<11>")
	)
	(segment
		(start 80.69453 -438.326022)
		(end 80.69453 -424.389804)
		(width 0.14224)
		(layer "In15.Cu")
		(net "P5E_CPU1_P0_RX_BUF_DN<11>")
	)
	(segment
		(start 81.337912 -420.142924)
		(end 83.312254 -413.634936)
		(width 0.14224)
		(layer "In15.Cu")
		(net "P5E_CPU1_P0_RX_BUF_DN<11>")
	)
	(segment
		(start 80.249014 -405.120856)
		(end 80.249014 -403.535896)
		(width 0.14224)
		(layer "In15.Cu")
		(net "P5E_CPU1_P0_RX_BUF_DN<11>")
	)
	(segment
		(start 67.555364 -399.320766)
		(end 62.720982 -397.853662)
		(width 0.14224)
		(layer "In15.Cu")
		(net "P5E_CPU1_P0_RX_BUF_DN<11>")
	)
	(segment
		(start 60.40501 -395.995906)
		(end 60.275724 -395.682978)
		(width 0.14224)
		(layer "In15.Cu")
		(net "P5E_CPU1_P0_RX_BUF_DN<11>")
	)
	(segment
		(start 81.780634 -410.630878)
		(end 81.780634 -406.481026)
		(width 0.14224)
		(layer "In15.Cu")
		(net "P5E_CPU1_P0_RX_BUF_DN<11>")
	)
	(segment
		(start 60.58027 -392.707622)
		(end 60.889642 -392.707622)
		(width 0.14224)
		(layer "In15.Cu")
		(net "P5E_CPU1_P0_RX_BUF_DN<11>")
	)
	(segment
		(start 83.312254 -413.634936)
		(end 83.312254 -412.004002)
		(width 0.14224)
		(layer "In15.Cu")
		(net "P5E_CPU1_P0_RX_BUF_DN<11>")
	)
	(segment
		(start 83.167728 -411.654498)
		(end 83.1088 -411.59557)
		(width 0.14224)
		(layer "In15.Cu")
		(net "P5E_CPU1_P0_RX_BUF_DN<11>")
	)
	(segment
		(start 80.803496 -405.856694)
		(end 80.62849 -405.78405)
		(width 0.14224)
		(layer "In15.Cu")
		(net "P5E_CPU1_P0_RX_BUF_DN<11>")
	)
	(segment
		(start 83.1088 -411.59557)
		(end 82.226658 -411.230318)
		(width 0.14224)
		(layer "In15.Cu")
		(net "P5E_CPU1_P0_RX_BUF_DN<11>")
	)
	(segment
		(start 60.275724 -395.682978)
		(end 60.275724 -393.012168)
		(width 0.14224)
		(layer "In15.Cu")
		(net "P5E_CPU1_P0_RX_BUF_DN<11>")
	)
	(arc
		(start 67.806316 -399.386806)
		(mid 67.680235 -399.356084)
		(end 67.555364 -399.320766)
		(width 0.14224)
		(layer "In15.Cu")
		(net "P5E_CPU1_P0_RX_BUF_DN<11>")
	)
	(arc
		(start 80.69453 -424.389804)
		(mid 80.772548 -422.80503)
		(end 81.006188 -421.235632)
		(width 0.14224)
		(layer "In15.Cu")
		(net "P5E_CPU1_P0_RX_BUF_DN<11>")
	)
	(arc
		(start 62.720982 -397.853662)
		(mid 62.422711 -397.733834)
		(end 62.149736 -397.564102)
		(width 0.14224)
		(layer "In15.Cu")
		(net "P5E_CPU1_P0_RX_BUF_DN<11>")
	)
	(arc
		(start 62.149736 -397.564102)
		(mid 62.08527 -397.513383)
		(end 62.023244 -397.459708)
		(width 0.14224)
		(layer "In15.Cu")
		(net "P5E_CPU1_P0_RX_BUF_DN<11>")
	)
	(arc
		(start 80.449674 -405.605234)
		(mid 80.301182 -405.382999)
		(end 80.249014 -405.120856)
		(width 0.14224)
		(layer "In15.Cu")
		(net "P5E_CPU1_P0_RX_BUF_DN<11>")
	)
	(segment
		(start 59.329828 -392.634216)
		(end 59.329828 -391.666984)
		(width 0.1016)
		(layer "F.Cu")
		(net "P5E_CPU1_P0_RX_BUF_DN<10>")
	)
	(segment
		(start 59.816746 -392.429238)
		(end 59.816746 -392.620246)
		(width 0.1016)
		(layer "F.Cu")
		(net "P5E_CPU1_P0_RX_BUF_DN<10>")
	)
	(segment
		(start 59.816746 -392.620246)
		(end 59.675776 -392.761216)
		(width 0.1016)
		(layer "F.Cu")
		(net "P5E_CPU1_P0_RX_BUF_DN<10>")
	)
	(segment
		(start 59.675776 -392.761216)
		(end 59.456828 -392.761216)
		(width 0.1016)
		(layer "F.Cu")
		(net "P5E_CPU1_P0_RX_BUF_DN<10>")
	)
	(segment
		(start 59.417966 -391.578846)
		(end 59.417966 -390.761474)
		(width 0.1016)
		(layer "F.Cu")
		(net "P5E_CPU1_P0_RX_BUF_DN<10>")
	)
	(segment
		(start 59.329828 -391.666984)
		(end 59.417966 -391.578846)
		(width 0.1016)
		(layer "F.Cu")
		(net "P5E_CPU1_P0_RX_BUF_DN<10>")
	)
	(segment
		(start 59.456828 -392.761216)
		(end 59.329828 -392.634216)
		(width 0.1016)
		(layer "F.Cu")
		(net "P5E_CPU1_P0_RX_BUF_DN<10>")
	)
	(segment
		(start 59.689746 -392.707622)
		(end 59.816746 -392.580622)
		(width 0.14224)
		(layer "In15.Cu")
		(net "P5E_CPU1_P0_RX_BUF_DN<10>")
	)
	(segment
		(start 77.054964 -403.306788)
		(end 76.667106 -403.074378)
		(width 0.14224)
		(layer "In15.Cu")
		(net "P5E_CPU1_P0_RX_BUF_DN<10>")
	)
	(segment
		(start 77.185774 -405.240998)
		(end 77.185774 -403.55647)
		(width 0.14224)
		(layer "In15.Cu")
		(net "P5E_CPU1_P0_RX_BUF_DN<10>")
	)
	(segment
		(start 78.99654 -437.623204)
		(end 78.689454 -437.316118)
		(width 0.14224)
		(layer "In15.Cu")
		(net "P5E_CPU1_P0_RX_BUF_DN<10>")
	)
	(segment
		(start 78.689454 -437.316118)
		(end 78.689454 -424.944286)
		(width 0.14224)
		(layer "In15.Cu")
		(net "P5E_CPU1_P0_RX_BUF_DN<10>")
	)
	(segment
		(start 77.301344 -405.520144)
		(end 77.185774 -405.240998)
		(width 0.14224)
		(layer "In15.Cu")
		(net "P5E_CPU1_P0_RX_BUF_DN<10>")
	)
	(segment
		(start 78.717394 -410.630878)
		(end 78.717394 -406.481026)
		(width 0.14224)
		(layer "In15.Cu")
		(net "P5E_CPU1_P0_RX_BUF_DN<10>")
	)
	(segment
		(start 78.717394 -406.481026)
		(end 78.575916 -406.13965)
		(width 0.14224)
		(layer "In15.Cu")
		(net "P5E_CPU1_P0_RX_BUF_DN<10>")
	)
	(segment
		(start 80.042766 -415.056066)
		(end 80.249014 -413.664908)
		(width 0.14224)
		(layer "In15.Cu")
		(net "P5E_CPU1_P0_RX_BUF_DN<10>")
	)
	(segment
		(start 79.650082 -437.769762)
		(end 79.503524 -437.623204)
		(width 0.14224)
		(layer "In15.Cu")
		(net "P5E_CPU1_P0_RX_BUF_DN<10>")
	)
	(segment
		(start 79.018638 -411.12694)
		(end 78.855316 -410.963618)
		(width 0.14224)
		(layer "In15.Cu")
		(net "P5E_CPU1_P0_RX_BUF_DN<10>")
	)
	(segment
		(start 59.075828 -395.780006)
		(end 59.075828 -393.012168)
		(width 0.14224)
		(layer "In15.Cu")
		(net "P5E_CPU1_P0_RX_BUF_DN<10>")
	)
	(segment
		(start 61.108082 -398.054576)
		(end 59.247278 -396.193772)
		(width 0.14224)
		(layer "In15.Cu")
		(net "P5E_CPU1_P0_RX_BUF_DN<10>")
	)
	(segment
		(start 59.075828 -393.012168)
		(end 59.380374 -392.707622)
		(width 0.14224)
		(layer "In15.Cu")
		(net "P5E_CPU1_P0_RX_BUF_DN<10>")
	)
	(segment
		(start 78.575916 -406.13965)
		(end 78.321408 -405.885142)
		(width 0.14224)
		(layer "In15.Cu")
		(net "P5E_CPU1_P0_RX_BUF_DN<10>")
	)
	(segment
		(start 77.185774 -403.55647)
		(end 77.107034 -403.366986)
		(width 0.14224)
		(layer "In15.Cu")
		(net "P5E_CPU1_P0_RX_BUF_DN<10>")
	)
	(segment
		(start 79.650082 -438.089802)
		(end 79.650082 -437.769762)
		(width 0.14224)
		(layer "In15.Cu")
		(net "P5E_CPU1_P0_RX_BUF_DN<10>")
	)
	(segment
		(start 80.005428 -415.307526)
		(end 80.042766 -415.056066)
		(width 0.14224)
		(layer "In15.Cu")
		(net "P5E_CPU1_P0_RX_BUF_DN<10>")
	)
	(segment
		(start 59.380374 -392.707622)
		(end 59.689746 -392.707622)
		(width 0.14224)
		(layer "In15.Cu")
		(net "P5E_CPU1_P0_RX_BUF_DN<10>")
	)
	(segment
		(start 80.005174 -415.307526)
		(end 80.005428 -415.307526)
		(width 0.14224)
		(layer "In15.Cu")
		(net "P5E_CPU1_P0_RX_BUF_DN<10>")
	)
	(segment
		(start 78.252828 -405.856694)
		(end 77.740256 -405.856694)
		(width 0.14224)
		(layer "In15.Cu")
		(net "P5E_CPU1_P0_RX_BUF_DN<10>")
	)
	(segment
		(start 78.801468 -423.424858)
		(end 80.005174 -415.307526)
		(width 0.14224)
		(layer "In15.Cu")
		(net "P5E_CPU1_P0_RX_BUF_DN<10>")
	)
	(segment
		(start 78.321408 -405.885142)
		(end 78.252828 -405.856694)
		(width 0.14224)
		(layer "In15.Cu")
		(net "P5E_CPU1_P0_RX_BUF_DN<10>")
	)
	(segment
		(start 77.740256 -405.856694)
		(end 77.56525 -405.78405)
		(width 0.14224)
		(layer "In15.Cu")
		(net "P5E_CPU1_P0_RX_BUF_DN<10>")
	)
	(segment
		(start 80.249014 -413.664908)
		(end 80.249014 -412.122874)
		(width 0.14224)
		(layer "In15.Cu")
		(net "P5E_CPU1_P0_RX_BUF_DN<10>")
	)
	(segment
		(start 77.56525 -405.78405)
		(end 77.301344 -405.520144)
		(width 0.14224)
		(layer "In15.Cu")
		(net "P5E_CPU1_P0_RX_BUF_DN<10>")
	)
	(segment
		(start 76.667106 -403.074378)
		(end 76.571856 -403.03196)
		(width 0.14224)
		(layer "In15.Cu")
		(net "P5E_CPU1_P0_RX_BUF_DN<10>")
	)
	(segment
		(start 59.816746 -392.580622)
		(end 59.816746 -392.429238)
		(width 0.14224)
		(layer "In15.Cu")
		(net "P5E_CPU1_P0_RX_BUF_DN<10>")
	)
	(segment
		(start 78.689454 -424.944286)
		(end 78.801468 -423.424858)
		(width 0.14224)
		(layer "In15.Cu")
		(net "P5E_CPU1_P0_RX_BUF_DN<10>")
	)
	(segment
		(start 79.960216 -411.560264)
		(end 79.18958 -411.24124)
		(width 0.14224)
		(layer "In15.Cu")
		(net "P5E_CPU1_P0_RX_BUF_DN<10>")
	)
	(segment
		(start 76.571856 -403.03196)
		(end 62.071504 -398.634204)
		(width 0.14224)
		(layer "In15.Cu")
		(net "P5E_CPU1_P0_RX_BUF_DN<10>")
	)
	(segment
		(start 78.855316 -410.963618)
		(end 78.717394 -410.630878)
		(width 0.14224)
		(layer "In15.Cu")
		(net "P5E_CPU1_P0_RX_BUF_DN<10>")
	)
	(segment
		(start 79.503524 -437.623204)
		(end 78.99654 -437.623204)
		(width 0.14224)
		(layer "In15.Cu")
		(net "P5E_CPU1_P0_RX_BUF_DN<10>")
	)
	(segment
		(start 61.411866 -398.291558)
		(end 61.108082 -398.054576)
		(width 0.14224)
		(layer "In15.Cu")
		(net "P5E_CPU1_P0_RX_BUF_DN<10>")
	)
	(arc
		(start 62.071504 -398.634204)
		(mid 61.725887 -398.493299)
		(end 61.411866 -398.291558)
		(width 0.14224)
		(layer "In15.Cu")
		(net "P5E_CPU1_P0_RX_BUF_DN<10>")
	)
	(arc
		(start 80.249014 -412.122874)
		(mid 80.222598 -411.939862)
		(end 80.145382 -411.771846)
		(width 0.14224)
		(layer "In15.Cu")
		(net "P5E_CPU1_P0_RX_BUF_DN<10>")
	)
	(arc
		(start 59.247278 -396.193772)
		(mid 59.120379 -396.003949)
		(end 59.075828 -395.780006)
		(width 0.14224)
		(layer "In15.Cu")
		(net "P5E_CPU1_P0_RX_BUF_DN<10>")
	)
	(arc
		(start 80.058514 -411.640274)
		(mid 80.015272 -411.593005)
		(end 79.960216 -411.560264)
		(width 0.14224)
		(layer "In15.Cu")
		(net "P5E_CPU1_P0_RX_BUF_DN<10>")
	)
	(arc
		(start 77.107034 -403.366986)
		(mid 77.085853 -403.332683)
		(end 77.054964 -403.306788)
		(width 0.14224)
		(layer "In15.Cu")
		(net "P5E_CPU1_P0_RX_BUF_DN<10>")
	)
	(arc
		(start 80.145382 -411.771846)
		(mid 80.102271 -411.705846)
		(end 80.058514 -411.640274)
		(width 0.14224)
		(layer "In15.Cu")
		(net "P5E_CPU1_P0_RX_BUF_DN<10>")
	)
	(arc
		(start 79.18958 -411.24124)
		(mid 79.098473 -411.192518)
		(end 79.018638 -411.12694)
		(width 0.14224)
		(layer "In15.Cu")
		(net "P5E_CPU1_P0_RX_BUF_DN<10>")
	)
	(segment
		(start 47.3075 -392.611864)
		(end 47.456852 -392.761216)
		(width 0.1016)
		(layer "F.Cu")
		(net "P5E_CPU1_P0_RX_BUF_DN<0>")
	)
	(segment
		(start 47.6758 -392.761216)
		(end 47.816516 -392.6205)
		(width 0.1016)
		(layer "F.Cu")
		(net "P5E_CPU1_P0_RX_BUF_DN<0>")
	)
	(segment
		(start 47.3075 -391.689336)
		(end 47.3075 -392.611864)
		(width 0.1016)
		(layer "F.Cu")
		(net "P5E_CPU1_P0_RX_BUF_DN<0>")
	)
	(segment
		(start 47.418498 -390.761982)
		(end 47.418498 -391.578338)
		(width 0.1016)
		(layer "F.Cu")
		(net "P5E_CPU1_P0_RX_BUF_DN<0>")
	)
	(segment
		(start 47.816516 -392.6205)
		(end 47.816516 -392.429238)
		(width 0.1016)
		(layer "F.Cu")
		(net "P5E_CPU1_P0_RX_BUF_DN<0>")
	)
	(segment
		(start 47.418498 -391.578338)
		(end 47.3075 -391.689336)
		(width 0.1016)
		(layer "F.Cu")
		(net "P5E_CPU1_P0_RX_BUF_DN<0>")
	)
	(segment
		(start 47.41799 -390.761474)
		(end 47.418498 -390.761982)
		(width 0.1016)
		(layer "F.Cu")
		(net "P5E_CPU1_P0_RX_BUF_DN<0>")
	)
	(segment
		(start 47.456852 -392.761216)
		(end 47.6758 -392.761216)
		(width 0.1016)
		(layer "F.Cu")
		(net "P5E_CPU1_P0_RX_BUF_DN<0>")
	)
	(segment
		(start 49.616614 -412.004256)
		(end 49.483518 -411.682438)
		(width 0.14224)
		(layer "In15.Cu")
		(net "P5E_CPU1_P0_RX_BUF_DN<0>")
	)
	(segment
		(start 56.492394 -418.47262)
		(end 49.901602 -414.06826)
		(width 0.14224)
		(layer "In15.Cu")
		(net "P5E_CPU1_P0_RX_BUF_DN<0>")
	)
	(segment
		(start 48.084994 -410.630878)
		(end 48.084994 -406.481026)
		(width 0.14224)
		(layer "In15.Cu")
		(net "P5E_CPU1_P0_RX_BUF_DN<0>")
	)
	(segment
		(start 47.689516 -392.707622)
		(end 47.816516 -392.580622)
		(width 0.14224)
		(layer "In15.Cu")
		(net "P5E_CPU1_P0_RX_BUF_DN<0>")
	)
	(segment
		(start 47.555912 -405.856694)
		(end 47.107856 -405.856694)
		(width 0.14224)
		(layer "In15.Cu")
		(net "P5E_CPU1_P0_RX_BUF_DN<0>")
	)
	(segment
		(start 46.668944 -405.520144)
		(end 46.474888 -405.052022)
		(width 0.14224)
		(layer "In15.Cu")
		(net "P5E_CPU1_P0_RX_BUF_DN<0>")
	)
	(segment
		(start 48.017684 -406.318466)
		(end 47.555912 -405.856694)
		(width 0.14224)
		(layer "In15.Cu")
		(net "P5E_CPU1_P0_RX_BUF_DN<0>")
	)
	(segment
		(start 46.93285 -405.78405)
		(end 46.668944 -405.520144)
		(width 0.14224)
		(layer "In15.Cu")
		(net "P5E_CPU1_P0_RX_BUF_DN<0>")
	)
	(segment
		(start 46.590458 -403.816058)
		(end 47.075598 -401.88007)
		(width 0.14224)
		(layer "In15.Cu")
		(net "P5E_CPU1_P0_RX_BUF_DN<0>")
	)
	(segment
		(start 47.107856 -405.856694)
		(end 46.93285 -405.78405)
		(width 0.14224)
		(layer "In15.Cu")
		(net "P5E_CPU1_P0_RX_BUF_DN<0>")
	)
	(segment
		(start 48.531272 -411.230572)
		(end 48.40605 -411.146752)
		(width 0.14224)
		(layer "In15.Cu")
		(net "P5E_CPU1_P0_RX_BUF_DN<0>")
	)
	(segment
		(start 46.474888 -405.052022)
		(end 46.474888 -404.396702)
		(width 0.14224)
		(layer "In15.Cu")
		(net "P5E_CPU1_P0_RX_BUF_DN<0>")
	)
	(segment
		(start 57.8612 -437.61914)
		(end 57.208166 -436.966106)
		(width 0.14224)
		(layer "In15.Cu")
		(net "P5E_CPU1_P0_RX_BUF_DN<0>")
	)
	(segment
		(start 46.474888 -404.396702)
		(end 46.590458 -403.816058)
		(width 0.14224)
		(layer "In15.Cu")
		(net "P5E_CPU1_P0_RX_BUF_DN<0>")
	)
	(segment
		(start 48.084994 -406.481026)
		(end 48.017684 -406.318466)
		(width 0.14224)
		(layer "In15.Cu")
		(net "P5E_CPU1_P0_RX_BUF_DN<0>")
	)
	(segment
		(start 49.257458 -411.531054)
		(end 48.531272 -411.230572)
		(width 0.14224)
		(layer "In15.Cu")
		(net "P5E_CPU1_P0_RX_BUF_DN<0>")
	)
	(segment
		(start 58.64987 -437.769762)
		(end 58.499248 -437.61914)
		(width 0.14224)
		(layer "In15.Cu")
		(net "P5E_CPU1_P0_RX_BUF_DN<0>")
	)
	(segment
		(start 47.075598 -393.012168)
		(end 47.380144 -392.707622)
		(width 0.14224)
		(layer "In15.Cu")
		(net "P5E_CPU1_P0_RX_BUF_DN<0>")
	)
	(segment
		(start 49.616614 -413.37992)
		(end 49.616614 -412.004256)
		(width 0.14224)
		(layer "In15.Cu")
		(net "P5E_CPU1_P0_RX_BUF_DN<0>")
	)
	(segment
		(start 49.483518 -411.682438)
		(end 49.257458 -411.531054)
		(width 0.14224)
		(layer "In15.Cu")
		(net "P5E_CPU1_P0_RX_BUF_DN<0>")
	)
	(segment
		(start 58.64987 -438.089802)
		(end 58.64987 -437.769762)
		(width 0.14224)
		(layer "In15.Cu")
		(net "P5E_CPU1_P0_RX_BUF_DN<0>")
	)
	(segment
		(start 48.222916 -410.963618)
		(end 48.084994 -410.630878)
		(width 0.14224)
		(layer "In15.Cu")
		(net "P5E_CPU1_P0_RX_BUF_DN<0>")
	)
	(segment
		(start 58.499248 -437.61914)
		(end 57.8612 -437.61914)
		(width 0.14224)
		(layer "In15.Cu")
		(net "P5E_CPU1_P0_RX_BUF_DN<0>")
	)
	(segment
		(start 48.40605 -411.146752)
		(end 48.222916 -410.963618)
		(width 0.14224)
		(layer "In15.Cu")
		(net "P5E_CPU1_P0_RX_BUF_DN<0>")
	)
	(segment
		(start 47.816516 -392.580622)
		(end 47.816516 -392.429238)
		(width 0.14224)
		(layer "In15.Cu")
		(net "P5E_CPU1_P0_RX_BUF_DN<0>")
	)
	(segment
		(start 47.075598 -401.88007)
		(end 47.075598 -393.012168)
		(width 0.14224)
		(layer "In15.Cu")
		(net "P5E_CPU1_P0_RX_BUF_DN<0>")
	)
	(segment
		(start 47.380144 -392.707622)
		(end 47.689516 -392.707622)
		(width 0.14224)
		(layer "In15.Cu")
		(net "P5E_CPU1_P0_RX_BUF_DN<0>")
	)
	(segment
		(start 57.208166 -436.966106)
		(end 57.208166 -419.811454)
		(width 0.14224)
		(layer "In15.Cu")
		(net "P5E_CPU1_P0_RX_BUF_DN<0>")
	)
	(segment
		(start 49.901602 -414.06826)
		(end 49.616614 -413.37992)
		(width 0.14224)
		(layer "In15.Cu")
		(net "P5E_CPU1_P0_RX_BUF_DN<0>")
	)
	(arc
		(start 57.208166 -419.811454)
		(mid 57.017998 -419.052365)
		(end 56.492394 -418.47262)
		(width 0.14224)
		(layer "In15.Cu")
		(net "P5E_CPU1_P0_RX_BUF_DN<0>")
	)
	(segment
		(start 381.570484 -397.849344)
		(end 382.091184 -397.849344)
		(width 0.127)
		(layer "F.Cu")
		(net "P5E_CPU0_P3_TX_BUF_DP<9>")
	)
	(segment
		(start 400.587972 -416.336734)
		(end 400.587972 -415.65703)
		(width 0.12954)
		(layer "B.Cu")
		(net "P5E_CPU0_P3_TX_BUF_DP<9>")
	)
	(segment
		(start 400.883882 -416.632644)
		(end 400.587972 -416.336734)
		(width 0.12954)
		(layer "B.Cu")
		(net "P5E_CPU0_P3_TX_BUF_DP<9>")
	)
	(segment
		(start 400.587972 -415.65703)
		(end 400.858482 -415.38652)
		(width 0.12954)
		(layer "B.Cu")
		(net "P5E_CPU0_P3_TX_BUF_DP<9>")
	)
	(segment
		(start 398.429988 -410.849064)
		(end 398.824196 -411.012386)
		(width 0.14224)
		(layer "In6.Cu")
		(net "P5E_CPU0_P3_TX_BUF_DP<9>")
	)
	(segment
		(start 399.471896 -411.280864)
		(end 400.089878 -411.536896)
		(width 0.14224)
		(layer "In6.Cu")
		(net "P5E_CPU0_P3_TX_BUF_DP<9>")
	)
	(segment
		(start 397.961104 -410.506418)
		(end 398.355566 -410.66974)
		(width 0.14224)
		(layer "In6.Cu")
		(net "P5E_CPU0_P3_TX_BUF_DP<9>")
	)
	(segment
		(start 398.429988 -410.849318)
		(end 398.429988 -410.849064)
		(width 0.14224)
		(layer "In6.Cu")
		(net "P5E_CPU0_P3_TX_BUF_DP<9>")
	)
	(segment
		(start 397.387826 -410.417518)
		(end 397.782034 -410.580586)
		(width 0.14224)
		(layer "In6.Cu")
		(net "P5E_CPU0_P3_TX_BUF_DP<9>")
	)
	(segment
		(start 398.429734 -410.849318)
		(end 398.429734 -410.849064)
		(width 0.14224)
		(layer "In6.Cu")
		(net "P5E_CPU0_P3_TX_BUF_DP<9>")
	)
	(segment
		(start 399.003266 -410.937964)
		(end 399.397728 -411.10154)
		(width 0.14224)
		(layer "In6.Cu")
		(net "P5E_CPU0_P3_TX_BUF_DP<9>")
	)
	(segment
		(start 381.79629 -397.734536)
		(end 381.706882 -397.823944)
		(width 0.14224)
		(layer "In6.Cu")
		(net "P5E_CPU0_P3_TX_BUF_DP<9>")
	)
	(segment
		(start 382.627632 -404.377144)
		(end 384.6068 -406.356312)
		(width 0.14224)
		(layer "In6.Cu")
		(net "P5E_CPU0_P3_TX_BUF_DP<9>")
	)
	(segment
		(start 398.824196 -411.012386)
		(end 399.003266 -410.937964)
		(width 0.14224)
		(layer "In6.Cu")
		(net "P5E_CPU0_P3_TX_BUF_DP<9>")
	)
	(segment
		(start 398.355566 -410.66974)
		(end 398.429734 -410.849318)
		(width 0.14224)
		(layer "In6.Cu")
		(net "P5E_CPU0_P3_TX_BUF_DP<9>")
	)
	(segment
		(start 382.345692 -399.835878)
		(end 382.411732 -400.033744)
		(width 0.14224)
		(layer "In6.Cu")
		(net "P5E_CPU0_P3_TX_BUF_DP<9>")
	)
	(segment
		(start 387.059932 -407.243788)
		(end 390.011412 -407.983436)
		(width 0.14224)
		(layer "In6.Cu")
		(net "P5E_CPU0_P3_TX_BUF_DP<9>")
	)
	(segment
		(start 396.740126 -410.14904)
		(end 396.919196 -410.074872)
		(width 0.14224)
		(layer "In6.Cu")
		(net "P5E_CPU0_P3_TX_BUF_DP<9>")
	)
	(segment
		(start 390.011412 -407.983436)
		(end 395.616176 -409.683458)
		(width 0.14224)
		(layer "In6.Cu")
		(net "P5E_CPU0_P3_TX_BUF_DP<9>")
	)
	(segment
		(start 382.091184 -397.849344)
		(end 381.976376 -397.734536)
		(width 0.14224)
		(layer "In6.Cu")
		(net "P5E_CPU0_P3_TX_BUF_DP<9>")
	)
	(segment
		(start 382.06553 -398.570704)
		(end 382.06553 -398.887442)
		(width 0.14224)
		(layer "In6.Cu")
		(net "P5E_CPU0_P3_TX_BUF_DP<9>")
	)
	(segment
		(start 398.429734 -410.849064)
		(end 398.429988 -410.849318)
		(width 0.14224)
		(layer "In6.Cu")
		(net "P5E_CPU0_P3_TX_BUF_DP<9>")
	)
	(segment
		(start 385.797806 -406.992836)
		(end 387.059932 -407.243788)
		(width 0.14224)
		(layer "In6.Cu")
		(net "P5E_CPU0_P3_TX_BUF_DP<9>")
	)
	(segment
		(start 400.089878 -411.536896)
		(end 400.20113 -411.648148)
		(width 0.14224)
		(layer "In6.Cu")
		(net "P5E_CPU0_P3_TX_BUF_DP<9>")
	)
	(segment
		(start 382.073912 -398.94383)
		(end 382.345692 -399.835878)
		(width 0.14224)
		(layer "In6.Cu")
		(net "P5E_CPU0_P3_TX_BUF_DP<9>")
	)
	(segment
		(start 381.819658 -398.140936)
		(end 381.935736 -398.257014)
		(width 0.14224)
		(layer "In6.Cu")
		(net "P5E_CPU0_P3_TX_BUF_DP<9>")
	)
	(segment
		(start 396.919196 -410.074872)
		(end 397.313658 -410.238194)
		(width 0.14224)
		(layer "In6.Cu")
		(net "P5E_CPU0_P3_TX_BUF_DP<9>")
	)
	(segment
		(start 381.706882 -397.823944)
		(end 381.706882 -397.868902)
		(width 0.14224)
		(layer "In6.Cu")
		(net "P5E_CPU0_P3_TX_BUF_DP<9>")
	)
	(segment
		(start 400.567652 -412.53283)
		(end 400.567652 -415.09569)
		(width 0.14224)
		(layer "In6.Cu")
		(net "P5E_CPU0_P3_TX_BUF_DP<9>")
	)
	(segment
		(start 397.313658 -410.238194)
		(end 397.387826 -410.417518)
		(width 0.14224)
		(layer "In6.Cu")
		(net "P5E_CPU0_P3_TX_BUF_DP<9>")
	)
	(segment
		(start 399.397728 -411.10154)
		(end 399.471896 -411.280864)
		(width 0.14224)
		(layer "In6.Cu")
		(net "P5E_CPU0_P3_TX_BUF_DP<9>")
	)
	(segment
		(start 382.468628 -400.386042)
		(end 382.468628 -404.06447)
		(width 0.14224)
		(layer "In6.Cu")
		(net "P5E_CPU0_P3_TX_BUF_DP<9>")
	)
	(segment
		(start 381.976376 -397.734536)
		(end 381.79629 -397.734536)
		(width 0.14224)
		(layer "In6.Cu")
		(net "P5E_CPU0_P3_TX_BUF_DP<9>")
	)
	(segment
		(start 395.616176 -409.683458)
		(end 396.740126 -410.14904)
		(width 0.14224)
		(layer "In6.Cu")
		(net "P5E_CPU0_P3_TX_BUF_DP<9>")
	)
	(segment
		(start 397.782034 -410.580586)
		(end 397.961104 -410.506418)
		(width 0.14224)
		(layer "In6.Cu")
		(net "P5E_CPU0_P3_TX_BUF_DP<9>")
	)
	(segment
		(start 400.567652 -415.09569)
		(end 400.858482 -415.38652)
		(width 0.14224)
		(layer "In6.Cu")
		(net "P5E_CPU0_P3_TX_BUF_DP<9>")
	)
	(arc
		(start 384.6068 -406.356312)
		(mid 385.155082 -406.762936)
		(end 385.797806 -406.992836)
		(width 0.14224)
		(layer "In6.Cu")
		(net "P5E_CPU0_P3_TX_BUF_DP<9>")
	)
	(arc
		(start 400.20113 -411.648148)
		(mid 400.472394 -412.054029)
		(end 400.567652 -412.53283)
		(width 0.14224)
		(layer "In6.Cu")
		(net "P5E_CPU0_P3_TX_BUF_DP<9>")
	)
	(arc
		(start 382.411732 -400.033744)
		(mid 382.454304 -400.207612)
		(end 382.468628 -400.386042)
		(width 0.14224)
		(layer "In6.Cu")
		(net "P5E_CPU0_P3_TX_BUF_DP<9>")
	)
	(arc
		(start 382.06553 -398.887442)
		(mid 382.067643 -398.915944)
		(end 382.073912 -398.94383)
		(width 0.14224)
		(layer "In6.Cu")
		(net "P5E_CPU0_P3_TX_BUF_DP<9>")
	)
	(arc
		(start 381.935736 -398.257014)
		(mid 382.031872 -398.400937)
		(end 382.06553 -398.570704)
		(width 0.14224)
		(layer "In6.Cu")
		(net "P5E_CPU0_P3_TX_BUF_DP<9>")
	)
	(arc
		(start 381.706882 -397.868902)
		(mid 381.736189 -398.016148)
		(end 381.819658 -398.140936)
		(width 0.14224)
		(layer "In6.Cu")
		(net "P5E_CPU0_P3_TX_BUF_DP<9>")
	)
	(arc
		(start 382.468628 -404.06447)
		(mid 382.481338 -404.155739)
		(end 382.518666 -404.239984)
		(width 0.14224)
		(layer "In6.Cu")
		(net "P5E_CPU0_P3_TX_BUF_DP<9>")
	)
	(arc
		(start 382.518666 -404.239984)
		(mid 382.569176 -404.311721)
		(end 382.627632 -404.377144)
		(width 0.14224)
		(layer "In6.Cu")
		(net "P5E_CPU0_P3_TX_BUF_DP<9>")
	)
	(segment
		(start 380.370588 -397.849344)
		(end 380.891288 -397.849344)
		(width 0.127)
		(layer "F.Cu")
		(net "P5E_CPU0_P3_TX_BUF_DP<8>")
	)
	(segment
		(start 397.52651 -416.338512)
		(end 397.820642 -416.632644)
		(width 0.12954)
		(layer "B.Cu")
		(net "P5E_CPU0_P3_TX_BUF_DP<8>")
	)
	(segment
		(start 397.52651 -415.655252)
		(end 397.52651 -416.338512)
		(width 0.12954)
		(layer "B.Cu")
		(net "P5E_CPU0_P3_TX_BUF_DP<8>")
	)
	(segment
		(start 397.795242 -415.38652)
		(end 397.52651 -415.655252)
		(width 0.12954)
		(layer "B.Cu")
		(net "P5E_CPU0_P3_TX_BUF_DP<8>")
	)
	(segment
		(start 389.681466 -408.866848)
		(end 392.74877 -409.79725)
		(width 0.14224)
		(layer "In6.Cu")
		(net "P5E_CPU0_P3_TX_BUF_DP<8>")
	)
	(segment
		(start 381.385318 -404.461472)
		(end 384.021584 -407.097738)
		(width 0.14224)
		(layer "In6.Cu")
		(net "P5E_CPU0_P3_TX_BUF_DP<8>")
	)
	(segment
		(start 380.891288 -397.849344)
		(end 380.77648 -397.734536)
		(width 0.14224)
		(layer "In6.Cu")
		(net "P5E_CPU0_P3_TX_BUF_DP<8>")
	)
	(segment
		(start 396.355824 -411.142942)
		(end 396.430246 -411.322266)
		(width 0.14224)
		(layer "In6.Cu")
		(net "P5E_CPU0_P3_TX_BUF_DP<8>")
	)
	(segment
		(start 395.961362 -410.97962)
		(end 396.355824 -411.142942)
		(width 0.14224)
		(layer "In6.Cu")
		(net "P5E_CPU0_P3_TX_BUF_DP<8>")
	)
	(segment
		(start 380.621794 -398.142968)
		(end 380.724664 -398.245838)
		(width 0.14224)
		(layer "In6.Cu")
		(net "P5E_CPU0_P3_TX_BUF_DP<8>")
	)
	(segment
		(start 380.873 -398.848072)
		(end 381.221488 -399.998438)
		(width 0.14224)
		(layer "In6.Cu")
		(net "P5E_CPU0_P3_TX_BUF_DP<8>")
	)
	(segment
		(start 394.54201 -410.391356)
		(end 394.616178 -410.570934)
		(width 0.14224)
		(layer "In6.Cu")
		(net "P5E_CPU0_P3_TX_BUF_DP<8>")
	)
	(segment
		(start 392.74877 -409.79725)
		(end 393.968224 -410.302456)
		(width 0.14224)
		(layer "In6.Cu")
		(net "P5E_CPU0_P3_TX_BUF_DP<8>")
	)
	(segment
		(start 380.77648 -397.734536)
		(end 380.583186 -397.734536)
		(width 0.14224)
		(layer "In6.Cu")
		(net "P5E_CPU0_P3_TX_BUF_DP<8>")
	)
	(segment
		(start 385.49453 -407.885138)
		(end 386.80263 -408.145234)
		(width 0.14224)
		(layer "In6.Cu")
		(net "P5E_CPU0_P3_TX_BUF_DP<8>")
	)
	(segment
		(start 381.221488 -402.90242)
		(end 381.358648 -403.03958)
		(width 0.14224)
		(layer "In6.Cu")
		(net "P5E_CPU0_P3_TX_BUF_DP<8>")
	)
	(segment
		(start 380.583186 -397.734536)
		(end 380.506986 -397.810736)
		(width 0.14224)
		(layer "In6.Cu")
		(net "P5E_CPU0_P3_TX_BUF_DP<8>")
	)
	(segment
		(start 393.968224 -410.302456)
		(end 394.147548 -410.228034)
		(width 0.14224)
		(layer "In6.Cu")
		(net "P5E_CPU0_P3_TX_BUF_DP<8>")
	)
	(segment
		(start 380.506986 -397.810736)
		(end 380.506986 -397.866108)
		(width 0.14224)
		(layer "In6.Cu")
		(net "P5E_CPU0_P3_TX_BUF_DP<8>")
	)
	(segment
		(start 396.917164 -411.523942)
		(end 397.203422 -411.8102)
		(width 0.14224)
		(layer "In6.Cu")
		(net "P5E_CPU0_P3_TX_BUF_DP<8>")
	)
	(segment
		(start 386.80263 -408.145234)
		(end 389.681466 -408.866848)
		(width 0.14224)
		(layer "In6.Cu")
		(net "P5E_CPU0_P3_TX_BUF_DP<8>")
	)
	(segment
		(start 381.221488 -399.998438)
		(end 381.221488 -402.90242)
		(width 0.14224)
		(layer "In6.Cu")
		(net "P5E_CPU0_P3_TX_BUF_DP<8>")
	)
	(segment
		(start 381.358648 -403.03958)
		(end 381.358648 -403.4663)
		(width 0.14224)
		(layer "In6.Cu")
		(net "P5E_CPU0_P3_TX_BUF_DP<8>")
	)
	(segment
		(start 396.430246 -411.322266)
		(end 396.917164 -411.523942)
		(width 0.14224)
		(layer "In6.Cu")
		(net "P5E_CPU0_P3_TX_BUF_DP<8>")
	)
	(segment
		(start 381.358648 -403.4663)
		(end 381.221488 -403.60346)
		(width 0.14224)
		(layer "In6.Cu")
		(net "P5E_CPU0_P3_TX_BUF_DP<8>")
	)
	(segment
		(start 381.221488 -403.60346)
		(end 381.221488 -404.065994)
		(width 0.14224)
		(layer "In6.Cu")
		(net "P5E_CPU0_P3_TX_BUF_DP<8>")
	)
	(segment
		(start 395.782292 -411.053788)
		(end 395.961362 -410.97962)
		(width 0.14224)
		(layer "In6.Cu")
		(net "P5E_CPU0_P3_TX_BUF_DP<8>")
	)
	(segment
		(start 394.616178 -410.570934)
		(end 395.782292 -411.053788)
		(width 0.14224)
		(layer "In6.Cu")
		(net "P5E_CPU0_P3_TX_BUF_DP<8>")
	)
	(segment
		(start 394.147548 -410.228034)
		(end 394.54201 -410.391356)
		(width 0.14224)
		(layer "In6.Cu")
		(net "P5E_CPU0_P3_TX_BUF_DP<8>")
	)
	(segment
		(start 397.504412 -415.09569)
		(end 397.795242 -415.38652)
		(width 0.14224)
		(layer "In6.Cu")
		(net "P5E_CPU0_P3_TX_BUF_DP<8>")
	)
	(segment
		(start 397.504412 -412.53664)
		(end 397.504412 -415.09569)
		(width 0.14224)
		(layer "In6.Cu")
		(net "P5E_CPU0_P3_TX_BUF_DP<8>")
	)
	(segment
		(start 380.854458 -398.559528)
		(end 380.854458 -398.723358)
		(width 0.14224)
		(layer "In6.Cu")
		(net "P5E_CPU0_P3_TX_BUF_DP<8>")
	)
	(arc
		(start 380.724664 -398.245838)
		(mid 380.8208 -398.389761)
		(end 380.854458 -398.559528)
		(width 0.14224)
		(layer "In6.Cu")
		(net "P5E_CPU0_P3_TX_BUF_DP<8>")
	)
	(arc
		(start 397.203422 -411.8102)
		(mid 397.426175 -412.143479)
		(end 397.504412 -412.53664)
		(width 0.14224)
		(layer "In6.Cu")
		(net "P5E_CPU0_P3_TX_BUF_DP<8>")
	)
	(arc
		(start 380.506986 -397.866108)
		(mid 380.53683 -398.015964)
		(end 380.621794 -398.142968)
		(width 0.14224)
		(layer "In6.Cu")
		(net "P5E_CPU0_P3_TX_BUF_DP<8>")
	)
	(arc
		(start 384.021584 -407.097738)
		(mid 384.699671 -407.600648)
		(end 385.49453 -407.885138)
		(width 0.14224)
		(layer "In6.Cu")
		(net "P5E_CPU0_P3_TX_BUF_DP<8>")
	)
	(arc
		(start 381.221488 -404.065994)
		(mid 381.264048 -404.280046)
		(end 381.385318 -404.461472)
		(width 0.14224)
		(layer "In6.Cu")
		(net "P5E_CPU0_P3_TX_BUF_DP<8>")
	)
	(arc
		(start 380.854458 -398.723358)
		(mid 380.859139 -398.786397)
		(end 380.873 -398.848072)
		(width 0.14224)
		(layer "In6.Cu")
		(net "P5E_CPU0_P3_TX_BUF_DP<8>")
	)
	(segment
		(start 379.170438 -397.849344)
		(end 379.691138 -397.849344)
		(width 0.127)
		(layer "F.Cu")
		(net "P5E_CPU0_P3_TX_BUF_DP<7>")
	)
	(segment
		(start 394.461492 -416.336734)
		(end 394.461492 -415.65703)
		(width 0.12954)
		(layer "B.Cu")
		(net "P5E_CPU0_P3_TX_BUF_DP<7>")
	)
	(segment
		(start 394.757402 -416.632644)
		(end 394.461492 -416.336734)
		(width 0.12954)
		(layer "B.Cu")
		(net "P5E_CPU0_P3_TX_BUF_DP<7>")
	)
	(segment
		(start 394.461492 -415.65703)
		(end 394.732002 -415.38652)
		(width 0.12954)
		(layer "B.Cu")
		(net "P5E_CPU0_P3_TX_BUF_DP<7>")
	)
	(segment
		(start 379.57633 -397.734536)
		(end 379.409706 -397.734536)
		(width 0.14224)
		(layer "In6.Cu")
		(net "P5E_CPU0_P3_TX_BUF_DP<7>")
	)
	(segment
		(start 391.803382 -410.494734)
		(end 392.197844 -410.658056)
		(width 0.14224)
		(layer "In6.Cu")
		(net "P5E_CPU0_P3_TX_BUF_DP<7>")
	)
	(segment
		(start 380.156974 -404.55723)
		(end 383.398268 -407.798524)
		(width 0.14224)
		(layer "In6.Cu")
		(net "P5E_CPU0_P3_TX_BUF_DP<7>")
	)
	(segment
		(start 379.666246 -398.839944)
		(end 380.02337 -400.017742)
		(width 0.14224)
		(layer "In6.Cu")
		(net "P5E_CPU0_P3_TX_BUF_DP<7>")
	)
	(segment
		(start 386.29209 -408.994864)
		(end 389.43661 -409.782772)
		(width 0.14224)
		(layer "In6.Cu")
		(net "P5E_CPU0_P3_TX_BUF_DP<7>")
	)
	(segment
		(start 392.666474 -411.000448)
		(end 392.845544 -410.92628)
		(width 0.14224)
		(layer "In6.Cu")
		(net "P5E_CPU0_P3_TX_BUF_DP<7>")
	)
	(segment
		(start 379.313948 -397.830294)
		(end 379.313948 -397.943324)
		(width 0.14224)
		(layer "In6.Cu")
		(net "P5E_CPU0_P3_TX_BUF_DP<7>")
	)
	(segment
		(start 391.624312 -410.568902)
		(end 391.803382 -410.494734)
		(width 0.14224)
		(layer "In6.Cu")
		(net "P5E_CPU0_P3_TX_BUF_DP<7>")
	)
	(segment
		(start 393.240006 -411.089602)
		(end 393.314174 -411.26918)
		(width 0.14224)
		(layer "In6.Cu")
		(net "P5E_CPU0_P3_TX_BUF_DP<7>")
	)
	(segment
		(start 392.845544 -410.92628)
		(end 393.240006 -411.089602)
		(width 0.14224)
		(layer "In6.Cu")
		(net "P5E_CPU0_P3_TX_BUF_DP<7>")
	)
	(segment
		(start 393.734544 -411.44317)
		(end 394.127736 -411.836362)
		(width 0.14224)
		(layer "In6.Cu")
		(net "P5E_CPU0_P3_TX_BUF_DP<7>")
	)
	(segment
		(start 394.441172 -415.09569)
		(end 394.732002 -415.38652)
		(width 0.14224)
		(layer "In6.Cu")
		(net "P5E_CPU0_P3_TX_BUF_DP<7>")
	)
	(segment
		(start 385.247642 -408.787092)
		(end 386.29209 -408.994864)
		(width 0.14224)
		(layer "In6.Cu")
		(net "P5E_CPU0_P3_TX_BUF_DP<7>")
	)
	(segment
		(start 379.357636 -398.048734)
		(end 379.51791 -398.209008)
		(width 0.14224)
		(layer "In6.Cu")
		(net "P5E_CPU0_P3_TX_BUF_DP<7>")
	)
	(segment
		(start 379.691138 -397.849344)
		(end 379.57633 -397.734536)
		(width 0.14224)
		(layer "In6.Cu")
		(net "P5E_CPU0_P3_TX_BUF_DP<7>")
	)
	(segment
		(start 389.43661 -409.782772)
		(end 390.519412 -410.111194)
		(width 0.14224)
		(layer "In6.Cu")
		(net "P5E_CPU0_P3_TX_BUF_DP<7>")
	)
	(segment
		(start 379.647704 -398.522698)
		(end 379.647704 -398.714976)
		(width 0.14224)
		(layer "In6.Cu")
		(net "P5E_CPU0_P3_TX_BUF_DP<7>")
	)
	(segment
		(start 380.05385 -400.22399)
		(end 380.05385 -402.886418)
		(width 0.14224)
		(layer "In6.Cu")
		(net "P5E_CPU0_P3_TX_BUF_DP<7>")
	)
	(segment
		(start 392.272266 -410.83738)
		(end 392.666474 -411.000448)
		(width 0.14224)
		(layer "In6.Cu")
		(net "P5E_CPU0_P3_TX_BUF_DP<7>")
	)
	(segment
		(start 380.19101 -403.023578)
		(end 380.19101 -403.450298)
		(width 0.14224)
		(layer "In6.Cu")
		(net "P5E_CPU0_P3_TX_BUF_DP<7>")
	)
	(segment
		(start 392.197844 -410.658056)
		(end 392.272266 -410.83738)
		(width 0.14224)
		(layer "In6.Cu")
		(net "P5E_CPU0_P3_TX_BUF_DP<7>")
	)
	(segment
		(start 380.05385 -402.886418)
		(end 380.19101 -403.023578)
		(width 0.14224)
		(layer "In6.Cu")
		(net "P5E_CPU0_P3_TX_BUF_DP<7>")
	)
	(segment
		(start 393.314174 -411.26918)
		(end 393.734544 -411.44317)
		(width 0.14224)
		(layer "In6.Cu")
		(net "P5E_CPU0_P3_TX_BUF_DP<7>")
	)
	(segment
		(start 380.19101 -403.450298)
		(end 380.05385 -403.587458)
		(width 0.14224)
		(layer "In6.Cu")
		(net "P5E_CPU0_P3_TX_BUF_DP<7>")
	)
	(segment
		(start 380.05385 -403.587458)
		(end 380.05385 -404.308564)
		(width 0.14224)
		(layer "In6.Cu")
		(net "P5E_CPU0_P3_TX_BUF_DP<7>")
	)
	(segment
		(start 390.519412 -410.111194)
		(end 391.624312 -410.568902)
		(width 0.14224)
		(layer "In6.Cu")
		(net "P5E_CPU0_P3_TX_BUF_DP<7>")
	)
	(segment
		(start 394.441172 -412.593028)
		(end 394.441172 -415.09569)
		(width 0.14224)
		(layer "In6.Cu")
		(net "P5E_CPU0_P3_TX_BUF_DP<7>")
	)
	(segment
		(start 379.409706 -397.734536)
		(end 379.313948 -397.830294)
		(width 0.14224)
		(layer "In6.Cu")
		(net "P5E_CPU0_P3_TX_BUF_DP<7>")
	)
	(arc
		(start 383.398268 -407.798524)
		(mid 384.249641 -408.429959)
		(end 385.247642 -408.787092)
		(width 0.14224)
		(layer "In6.Cu")
		(net "P5E_CPU0_P3_TX_BUF_DP<7>")
	)
	(arc
		(start 379.647704 -398.714976)
		(mid 379.652358 -398.778146)
		(end 379.666246 -398.839944)
		(width 0.14224)
		(layer "In6.Cu")
		(net "P5E_CPU0_P3_TX_BUF_DP<7>")
	)
	(arc
		(start 379.313948 -397.943324)
		(mid 379.325282 -398.000396)
		(end 379.357636 -398.048734)
		(width 0.14224)
		(layer "In6.Cu")
		(net "P5E_CPU0_P3_TX_BUF_DP<7>")
	)
	(arc
		(start 379.51791 -398.209008)
		(mid 379.614046 -398.352931)
		(end 379.647704 -398.522698)
		(width 0.14224)
		(layer "In6.Cu")
		(net "P5E_CPU0_P3_TX_BUF_DP<7>")
	)
	(arc
		(start 380.05385 -404.308564)
		(mid 380.080659 -404.44316)
		(end 380.156974 -404.55723)
		(width 0.14224)
		(layer "In6.Cu")
		(net "P5E_CPU0_P3_TX_BUF_DP<7>")
	)
	(arc
		(start 380.02337 -400.017742)
		(mid 380.046187 -400.119745)
		(end 380.05385 -400.22399)
		(width 0.14224)
		(layer "In6.Cu")
		(net "P5E_CPU0_P3_TX_BUF_DP<7>")
	)
	(arc
		(start 394.127736 -411.836362)
		(mid 394.359702 -412.183523)
		(end 394.441172 -412.593028)
		(width 0.14224)
		(layer "In6.Cu")
		(net "P5E_CPU0_P3_TX_BUF_DP<7>")
	)
	(segment
		(start 377.970542 -397.849344)
		(end 378.491242 -397.849344)
		(width 0.127)
		(layer "F.Cu")
		(net "P5E_CPU0_P3_TX_BUF_DP<6>")
	)
	(segment
		(start 391.398252 -416.336734)
		(end 391.398252 -415.65703)
		(width 0.12954)
		(layer "B.Cu")
		(net "P5E_CPU0_P3_TX_BUF_DP<6>")
	)
	(segment
		(start 391.398252 -415.65703)
		(end 391.668762 -415.38652)
		(width 0.12954)
		(layer "B.Cu")
		(net "P5E_CPU0_P3_TX_BUF_DP<6>")
	)
	(segment
		(start 391.694162 -416.632644)
		(end 391.398252 -416.336734)
		(width 0.12954)
		(layer "B.Cu")
		(net "P5E_CPU0_P3_TX_BUF_DP<6>")
	)
	(segment
		(start 378.46762 -398.572736)
		(end 378.46762 -398.74825)
		(width 0.14224)
		(layer "In6.Cu")
		(net "P5E_CPU0_P3_TX_BUF_DP<6>")
	)
	(segment
		(start 378.242322 -398.163796)
		(end 378.337826 -398.2593)
		(width 0.14224)
		(layer "In6.Cu")
		(net "P5E_CPU0_P3_TX_BUF_DP<6>")
	)
	(segment
		(start 389.619744 -410.980636)
		(end 389.799068 -410.906468)
		(width 0.14224)
		(layer "In6.Cu")
		(net "P5E_CPU0_P3_TX_BUF_DP<6>")
	)
	(segment
		(start 378.8537 -403.613874)
		(end 378.8537 -404.275798)
		(width 0.14224)
		(layer "In6.Cu")
		(net "P5E_CPU0_P3_TX_BUF_DP<6>")
	)
	(segment
		(start 378.8537 -402.912834)
		(end 378.99086 -403.049994)
		(width 0.14224)
		(layer "In6.Cu")
		(net "P5E_CPU0_P3_TX_BUF_DP<6>")
	)
	(segment
		(start 391.377932 -412.677864)
		(end 391.377932 -413.616648)
		(width 0.14224)
		(layer "In6.Cu")
		(net "P5E_CPU0_P3_TX_BUF_DP<6>")
	)
	(segment
		(start 388.484618 -410.509974)
		(end 389.619744 -410.980382)
		(width 0.14224)
		(layer "In6.Cu")
		(net "P5E_CPU0_P3_TX_BUF_DP<6>")
	)
	(segment
		(start 391.377932 -415.09569)
		(end 391.668762 -415.38652)
		(width 0.14224)
		(layer "In6.Cu")
		(net "P5E_CPU0_P3_TX_BUF_DP<6>")
	)
	(segment
		(start 389.799068 -410.906468)
		(end 390.19353 -411.06979)
		(width 0.14224)
		(layer "In6.Cu")
		(net "P5E_CPU0_P3_TX_BUF_DP<6>")
	)
	(segment
		(start 390.267698 -411.24886)
		(end 390.69391 -411.425644)
		(width 0.14224)
		(layer "In6.Cu")
		(net "P5E_CPU0_P3_TX_BUF_DP<6>")
	)
	(segment
		(start 378.486162 -398.872964)
		(end 378.822966 -399.984976)
		(width 0.14224)
		(layer "In6.Cu")
		(net "P5E_CPU0_P3_TX_BUF_DP<6>")
	)
	(segment
		(start 379.068076 -404.793196)
		(end 382.847088 -408.572208)
		(width 0.14224)
		(layer "In6.Cu")
		(net "P5E_CPU0_P3_TX_BUF_DP<6>")
	)
	(segment
		(start 386.139944 -409.922472)
		(end 388.484618 -410.509974)
		(width 0.14224)
		(layer "In6.Cu")
		(net "P5E_CPU0_P3_TX_BUF_DP<6>")
	)
	(segment
		(start 391.377932 -413.616648)
		(end 391.515092 -413.753808)
		(width 0.14224)
		(layer "In6.Cu")
		(net "P5E_CPU0_P3_TX_BUF_DP<6>")
	)
	(segment
		(start 390.267698 -411.249114)
		(end 390.267698 -411.24886)
		(width 0.14224)
		(layer "In6.Cu")
		(net "P5E_CPU0_P3_TX_BUF_DP<6>")
	)
	(segment
		(start 378.376434 -397.734536)
		(end 378.196348 -397.734536)
		(width 0.14224)
		(layer "In6.Cu")
		(net "P5E_CPU0_P3_TX_BUF_DP<6>")
	)
	(segment
		(start 378.196348 -397.734536)
		(end 378.10694 -397.823944)
		(width 0.14224)
		(layer "In6.Cu")
		(net "P5E_CPU0_P3_TX_BUF_DP<6>")
	)
	(segment
		(start 378.99086 -403.049994)
		(end 378.99086 -403.476714)
		(width 0.14224)
		(layer "In6.Cu")
		(net "P5E_CPU0_P3_TX_BUF_DP<6>")
	)
	(segment
		(start 384.919728 -409.679902)
		(end 386.139944 -409.922472)
		(width 0.14224)
		(layer "In6.Cu")
		(net "P5E_CPU0_P3_TX_BUF_DP<6>")
	)
	(segment
		(start 390.69391 -411.425644)
		(end 390.976104 -411.707838)
		(width 0.14224)
		(layer "In6.Cu")
		(net "P5E_CPU0_P3_TX_BUF_DP<6>")
	)
	(segment
		(start 390.19353 -411.06979)
		(end 390.267698 -411.249114)
		(width 0.14224)
		(layer "In6.Cu")
		(net "P5E_CPU0_P3_TX_BUF_DP<6>")
	)
	(segment
		(start 391.515092 -413.753808)
		(end 391.515092 -414.180528)
		(width 0.14224)
		(layer "In6.Cu")
		(net "P5E_CPU0_P3_TX_BUF_DP<6>")
	)
	(segment
		(start 378.99086 -403.476714)
		(end 378.8537 -403.613874)
		(width 0.14224)
		(layer "In6.Cu")
		(net "P5E_CPU0_P3_TX_BUF_DP<6>")
	)
	(segment
		(start 378.10694 -397.823944)
		(end 378.10694 -397.837152)
		(width 0.14224)
		(layer "In6.Cu")
		(net "P5E_CPU0_P3_TX_BUF_DP<6>")
	)
	(segment
		(start 389.619744 -410.980382)
		(end 389.619744 -410.980636)
		(width 0.14224)
		(layer "In6.Cu")
		(net "P5E_CPU0_P3_TX_BUF_DP<6>")
	)
	(segment
		(start 391.515092 -414.180528)
		(end 391.377932 -414.317688)
		(width 0.14224)
		(layer "In6.Cu")
		(net "P5E_CPU0_P3_TX_BUF_DP<6>")
	)
	(segment
		(start 391.377932 -414.317688)
		(end 391.377932 -415.09569)
		(width 0.14224)
		(layer "In6.Cu")
		(net "P5E_CPU0_P3_TX_BUF_DP<6>")
	)
	(segment
		(start 378.8537 -400.191478)
		(end 378.8537 -402.912834)
		(width 0.14224)
		(layer "In6.Cu")
		(net "P5E_CPU0_P3_TX_BUF_DP<6>")
	)
	(segment
		(start 378.491242 -397.849344)
		(end 378.376434 -397.734536)
		(width 0.14224)
		(layer "In6.Cu")
		(net "P5E_CPU0_P3_TX_BUF_DP<6>")
	)
	(arc
		(start 378.10694 -397.837152)
		(mid 378.142125 -398.013947)
		(end 378.242322 -398.163796)
		(width 0.14224)
		(layer "In6.Cu")
		(net "P5E_CPU0_P3_TX_BUF_DP<6>")
	)
	(arc
		(start 382.847088 -408.572208)
		(mid 383.801235 -409.279815)
		(end 384.919728 -409.679902)
		(width 0.14224)
		(layer "In6.Cu")
		(net "P5E_CPU0_P3_TX_BUF_DP<6>")
	)
	(arc
		(start 378.46762 -398.74825)
		(mid 378.472303 -398.811288)
		(end 378.486162 -398.872964)
		(width 0.14224)
		(layer "In6.Cu")
		(net "P5E_CPU0_P3_TX_BUF_DP<6>")
	)
	(arc
		(start 378.337826 -398.2593)
		(mid 378.433914 -398.403106)
		(end 378.46762 -398.572736)
		(width 0.14224)
		(layer "In6.Cu")
		(net "P5E_CPU0_P3_TX_BUF_DP<6>")
	)
	(arc
		(start 378.8537 -404.275798)
		(mid 378.909418 -404.555822)
		(end 379.068076 -404.793196)
		(width 0.14224)
		(layer "In6.Cu")
		(net "P5E_CPU0_P3_TX_BUF_DP<6>")
	)
	(arc
		(start 378.822966 -399.984976)
		(mid 378.845955 -400.087093)
		(end 378.8537 -400.191478)
		(width 0.14224)
		(layer "In6.Cu")
		(net "P5E_CPU0_P3_TX_BUF_DP<6>")
	)
	(arc
		(start 390.976104 -411.707838)
		(mid 391.273478 -412.15289)
		(end 391.377932 -412.677864)
		(width 0.14224)
		(layer "In6.Cu")
		(net "P5E_CPU0_P3_TX_BUF_DP<6>")
	)
	(segment
		(start 376.770646 -397.849344)
		(end 377.291346 -397.849344)
		(width 0.127)
		(layer "F.Cu")
		(net "P5E_CPU0_P3_TX_BUF_DP<5>")
	)
	(segment
		(start 388.335012 -416.336734)
		(end 388.335012 -415.65703)
		(width 0.12954)
		(layer "B.Cu")
		(net "P5E_CPU0_P3_TX_BUF_DP<5>")
	)
	(segment
		(start 388.335012 -415.65703)
		(end 388.605522 -415.38652)
		(width 0.12954)
		(layer "B.Cu")
		(net "P5E_CPU0_P3_TX_BUF_DP<5>")
	)
	(segment
		(start 388.630922 -416.632644)
		(end 388.335012 -416.336734)
		(width 0.12954)
		(layer "B.Cu")
		(net "P5E_CPU0_P3_TX_BUF_DP<5>")
	)
	(segment
		(start 388.451852 -414.312862)
		(end 388.314692 -414.450022)
		(width 0.14224)
		(layer "In6.Cu")
		(net "P5E_CPU0_P3_TX_BUF_DP<5>")
	)
	(segment
		(start 388.314692 -412.495492)
		(end 388.314692 -413.748982)
		(width 0.14224)
		(layer "In6.Cu")
		(net "P5E_CPU0_P3_TX_BUF_DP<5>")
	)
	(segment
		(start 386.574284 -411.131766)
		(end 386.749544 -411.048708)
		(width 0.14224)
		(layer "In6.Cu")
		(net "P5E_CPU0_P3_TX_BUF_DP<5>")
	)
	(segment
		(start 387.900164 -411.678882)
		(end 388.030466 -411.809184)
		(width 0.14224)
		(layer "In6.Cu")
		(net "P5E_CPU0_P3_TX_BUF_DP<5>")
	)
	(segment
		(start 376.996452 -397.734536)
		(end 376.907044 -397.823944)
		(width 0.14224)
		(layer "In6.Cu")
		(net "P5E_CPU0_P3_TX_BUF_DP<5>")
	)
	(segment
		(start 387.234684 -411.36824)
		(end 387.636258 -411.51175)
		(width 0.14224)
		(layer "In6.Cu")
		(net "P5E_CPU0_P3_TX_BUF_DP<5>")
	)
	(segment
		(start 384.467354 -410.544264)
		(end 385.512564 -410.752036)
		(width 0.14224)
		(layer "In6.Cu")
		(net "P5E_CPU0_P3_TX_BUF_DP<5>")
	)
	(segment
		(start 386.749544 -411.048708)
		(end 387.151626 -411.192472)
		(width 0.14224)
		(layer "In6.Cu")
		(net "P5E_CPU0_P3_TX_BUF_DP<5>")
	)
	(segment
		(start 377.176538 -397.734536)
		(end 376.996452 -397.734536)
		(width 0.14224)
		(layer "In6.Cu")
		(net "P5E_CPU0_P3_TX_BUF_DP<5>")
	)
	(segment
		(start 377.004326 -398.125442)
		(end 377.147836 -398.268698)
		(width 0.14224)
		(layer "In6.Cu")
		(net "P5E_CPU0_P3_TX_BUF_DP<5>")
	)
	(segment
		(start 388.314692 -415.09569)
		(end 388.605522 -415.38652)
		(width 0.14224)
		(layer "In6.Cu")
		(net "P5E_CPU0_P3_TX_BUF_DP<5>")
	)
	(segment
		(start 377.849892 -404.894542)
		(end 382.388364 -409.433014)
		(width 0.14224)
		(layer "In6.Cu")
		(net "P5E_CPU0_P3_TX_BUF_DP<5>")
	)
	(segment
		(start 377.290838 -398.907254)
		(end 377.62307 -400.003264)
		(width 0.14224)
		(layer "In6.Cu")
		(net "P5E_CPU0_P3_TX_BUF_DP<5>")
	)
	(segment
		(start 387.636258 -411.51175)
		(end 387.900164 -411.678882)
		(width 0.14224)
		(layer "In6.Cu")
		(net "P5E_CPU0_P3_TX_BUF_DP<5>")
	)
	(segment
		(start 385.512564 -410.752036)
		(end 386.574284 -411.131766)
		(width 0.14224)
		(layer "In6.Cu")
		(net "P5E_CPU0_P3_TX_BUF_DP<5>")
	)
	(segment
		(start 377.272296 -398.568926)
		(end 377.272296 -398.78254)
		(width 0.14224)
		(layer "In6.Cu")
		(net "P5E_CPU0_P3_TX_BUF_DP<5>")
	)
	(segment
		(start 388.451852 -413.886142)
		(end 388.451852 -414.312862)
		(width 0.14224)
		(layer "In6.Cu")
		(net "P5E_CPU0_P3_TX_BUF_DP<5>")
	)
	(segment
		(start 377.790964 -403.751034)
		(end 377.653804 -403.888194)
		(width 0.14224)
		(layer "In6.Cu")
		(net "P5E_CPU0_P3_TX_BUF_DP<5>")
	)
	(segment
		(start 388.314692 -414.450022)
		(end 388.314692 -415.09569)
		(width 0.14224)
		(layer "In6.Cu")
		(net "P5E_CPU0_P3_TX_BUF_DP<5>")
	)
	(segment
		(start 377.653804 -403.888194)
		(end 377.653804 -404.42134)
		(width 0.14224)
		(layer "In6.Cu")
		(net "P5E_CPU0_P3_TX_BUF_DP<5>")
	)
	(segment
		(start 377.790964 -403.324314)
		(end 377.790964 -403.751034)
		(width 0.14224)
		(layer "In6.Cu")
		(net "P5E_CPU0_P3_TX_BUF_DP<5>")
	)
	(segment
		(start 376.907044 -397.823944)
		(end 376.907044 -397.890746)
		(width 0.14224)
		(layer "In6.Cu")
		(net "P5E_CPU0_P3_TX_BUF_DP<5>")
	)
	(segment
		(start 387.151626 -411.192472)
		(end 387.234684 -411.36824)
		(width 0.14224)
		(layer "In6.Cu")
		(net "P5E_CPU0_P3_TX_BUF_DP<5>")
	)
	(segment
		(start 377.291346 -397.849344)
		(end 377.176538 -397.734536)
		(width 0.14224)
		(layer "In6.Cu")
		(net "P5E_CPU0_P3_TX_BUF_DP<5>")
	)
	(segment
		(start 377.653804 -400.209766)
		(end 377.653804 -403.187154)
		(width 0.14224)
		(layer "In6.Cu")
		(net "P5E_CPU0_P3_TX_BUF_DP<5>")
	)
	(segment
		(start 388.314692 -413.748982)
		(end 388.451852 -413.886142)
		(width 0.14224)
		(layer "In6.Cu")
		(net "P5E_CPU0_P3_TX_BUF_DP<5>")
	)
	(segment
		(start 377.653804 -403.187154)
		(end 377.790964 -403.324314)
		(width 0.14224)
		(layer "In6.Cu")
		(net "P5E_CPU0_P3_TX_BUF_DP<5>")
	)
	(arc
		(start 376.907044 -397.890746)
		(mid 376.932329 -398.017774)
		(end 377.004326 -398.125442)
		(width 0.14224)
		(layer "In6.Cu")
		(net "P5E_CPU0_P3_TX_BUF_DP<5>")
	)
	(arc
		(start 377.62307 -400.003264)
		(mid 377.646068 -400.105381)
		(end 377.653804 -400.209766)
		(width 0.14224)
		(layer "In6.Cu")
		(net "P5E_CPU0_P3_TX_BUF_DP<5>")
	)
	(arc
		(start 377.653804 -404.42134)
		(mid 377.704766 -404.677452)
		(end 377.849892 -404.894542)
		(width 0.14224)
		(layer "In6.Cu")
		(net "P5E_CPU0_P3_TX_BUF_DP<5>")
	)
	(arc
		(start 382.388364 -409.433014)
		(mid 383.345427 -410.142861)
		(end 384.467354 -410.544264)
		(width 0.14224)
		(layer "In6.Cu")
		(net "P5E_CPU0_P3_TX_BUF_DP<5>")
	)
	(arc
		(start 377.272296 -398.78254)
		(mid 377.276979 -398.845578)
		(end 377.290838 -398.907254)
		(width 0.14224)
		(layer "In6.Cu")
		(net "P5E_CPU0_P3_TX_BUF_DP<5>")
	)
	(arc
		(start 377.147836 -398.268698)
		(mid 377.239929 -398.40643)
		(end 377.272296 -398.568926)
		(width 0.14224)
		(layer "In6.Cu")
		(net "P5E_CPU0_P3_TX_BUF_DP<5>")
	)
	(arc
		(start 388.030466 -411.809184)
		(mid 388.240809 -412.124079)
		(end 388.314692 -412.495492)
		(width 0.14224)
		(layer "In6.Cu")
		(net "P5E_CPU0_P3_TX_BUF_DP<5>")
	)
	(segment
		(start 375.570496 -397.849344)
		(end 376.091196 -397.849344)
		(width 0.127)
		(layer "F.Cu")
		(net "P5E_CPU0_P3_TX_BUF_DP<4>")
	)
	(segment
		(start 385.271772 -416.336734)
		(end 385.271772 -415.65703)
		(width 0.12954)
		(layer "B.Cu")
		(net "P5E_CPU0_P3_TX_BUF_DP<4>")
	)
	(segment
		(start 385.567682 -416.632644)
		(end 385.271772 -416.336734)
		(width 0.12954)
		(layer "B.Cu")
		(net "P5E_CPU0_P3_TX_BUF_DP<4>")
	)
	(segment
		(start 385.271772 -415.65703)
		(end 385.542282 -415.38652)
		(width 0.12954)
		(layer "B.Cu")
		(net "P5E_CPU0_P3_TX_BUF_DP<4>")
	)
	(segment
		(start 376.091196 -397.849344)
		(end 375.976388 -397.734536)
		(width 0.14224)
		(layer "In6.Cu")
		(net "P5E_CPU0_P3_TX_BUF_DP<4>")
	)
	(segment
		(start 378.290074 -406.699212)
		(end 378.59208 -407.001218)
		(width 0.14224)
		(layer "In6.Cu")
		(net "P5E_CPU0_P3_TX_BUF_DP<4>")
	)
	(segment
		(start 378.59208 -407.19502)
		(end 382.090676 -410.693616)
		(width 0.14224)
		(layer "In6.Cu")
		(net "P5E_CPU0_P3_TX_BUF_DP<4>")
	)
	(segment
		(start 375.976388 -397.734536)
		(end 375.796302 -397.734536)
		(width 0.14224)
		(layer "In6.Cu")
		(net "P5E_CPU0_P3_TX_BUF_DP<4>")
	)
	(segment
		(start 383.274316 -411.331156)
		(end 384.35153 -411.491176)
		(width 0.14224)
		(layer "In6.Cu")
		(net "P5E_CPU0_P3_TX_BUF_DP<4>")
	)
	(segment
		(start 385.251452 -415.09569)
		(end 385.542282 -415.38652)
		(width 0.14224)
		(layer "In6.Cu")
		(net "P5E_CPU0_P3_TX_BUF_DP<4>")
	)
	(segment
		(start 382.090676 -410.693616)
		(end 382.853946 -411.203648)
		(width 0.14224)
		(layer "In6.Cu")
		(net "P5E_CPU0_P3_TX_BUF_DP<4>")
	)
	(segment
		(start 385.251452 -412.567628)
		(end 385.251452 -413.76219)
		(width 0.14224)
		(layer "In6.Cu")
		(net "P5E_CPU0_P3_TX_BUF_DP<4>")
	)
	(segment
		(start 376.453654 -400.178016)
		(end 376.453654 -402.921978)
		(width 0.14224)
		(layer "In6.Cu")
		(net "P5E_CPU0_P3_TX_BUF_DP<4>")
	)
	(segment
		(start 376.067574 -398.55775)
		(end 376.067574 -398.73555)
		(width 0.14224)
		(layer "In6.Cu")
		(net "P5E_CPU0_P3_TX_BUF_DP<4>")
	)
	(segment
		(start 376.453654 -403.623018)
		(end 376.453654 -404.78456)
		(width 0.14224)
		(layer "In6.Cu")
		(net "P5E_CPU0_P3_TX_BUF_DP<4>")
	)
	(segment
		(start 376.590814 -403.059138)
		(end 376.590814 -403.485858)
		(width 0.14224)
		(layer "In6.Cu")
		(net "P5E_CPU0_P3_TX_BUF_DP<4>")
	)
	(segment
		(start 385.388612 -413.89935)
		(end 385.388612 -414.32607)
		(width 0.14224)
		(layer "In6.Cu")
		(net "P5E_CPU0_P3_TX_BUF_DP<4>")
	)
	(segment
		(start 375.796302 -397.734536)
		(end 375.706894 -397.823944)
		(width 0.14224)
		(layer "In6.Cu")
		(net "P5E_CPU0_P3_TX_BUF_DP<4>")
	)
	(segment
		(start 378.59208 -407.001218)
		(end 378.59208 -407.19502)
		(width 0.14224)
		(layer "In6.Cu")
		(net "P5E_CPU0_P3_TX_BUF_DP<4>")
	)
	(segment
		(start 376.453654 -402.921978)
		(end 376.590814 -403.059138)
		(width 0.14224)
		(layer "In6.Cu")
		(net "P5E_CPU0_P3_TX_BUF_DP<4>")
	)
	(segment
		(start 385.388612 -414.32607)
		(end 385.251452 -414.46323)
		(width 0.14224)
		(layer "In6.Cu")
		(net "P5E_CPU0_P3_TX_BUF_DP<4>")
	)
	(segment
		(start 382.853946 -411.203648)
		(end 383.274316 -411.331156)
		(width 0.14224)
		(layer "In6.Cu")
		(net "P5E_CPU0_P3_TX_BUF_DP<4>")
	)
	(segment
		(start 385.251452 -413.76219)
		(end 385.388612 -413.89935)
		(width 0.14224)
		(layer "In6.Cu")
		(net "P5E_CPU0_P3_TX_BUF_DP<4>")
	)
	(segment
		(start 376.590814 -403.485858)
		(end 376.453654 -403.623018)
		(width 0.14224)
		(layer "In6.Cu")
		(net "P5E_CPU0_P3_TX_BUF_DP<4>")
	)
	(segment
		(start 375.706894 -397.823944)
		(end 375.706894 -397.883888)
		(width 0.14224)
		(layer "In6.Cu")
		(net "P5E_CPU0_P3_TX_BUF_DP<4>")
	)
	(segment
		(start 384.852926 -411.74416)
		(end 384.95097 -411.842204)
		(width 0.14224)
		(layer "In6.Cu")
		(net "P5E_CPU0_P3_TX_BUF_DP<4>")
	)
	(segment
		(start 375.809002 -398.130268)
		(end 375.947686 -398.268698)
		(width 0.14224)
		(layer "In6.Cu")
		(net "P5E_CPU0_P3_TX_BUF_DP<4>")
	)
	(segment
		(start 378.096272 -406.699212)
		(end 378.290074 -406.699212)
		(width 0.14224)
		(layer "In6.Cu")
		(net "P5E_CPU0_P3_TX_BUF_DP<4>")
	)
	(segment
		(start 376.646186 -405.249126)
		(end 378.096272 -406.699212)
		(width 0.14224)
		(layer "In6.Cu")
		(net "P5E_CPU0_P3_TX_BUF_DP<4>")
	)
	(segment
		(start 385.251452 -414.46323)
		(end 385.251452 -415.09569)
		(width 0.14224)
		(layer "In6.Cu")
		(net "P5E_CPU0_P3_TX_BUF_DP<4>")
	)
	(segment
		(start 376.086116 -398.860518)
		(end 376.423174 -399.971514)
		(width 0.14224)
		(layer "In6.Cu")
		(net "P5E_CPU0_P3_TX_BUF_DP<4>")
	)
	(arc
		(start 376.067574 -398.73555)
		(mid 376.072241 -398.798716)
		(end 376.086116 -398.860518)
		(width 0.14224)
		(layer "In6.Cu")
		(net "P5E_CPU0_P3_TX_BUF_DP<4>")
	)
	(arc
		(start 375.947686 -398.268698)
		(mid 376.036382 -398.401301)
		(end 376.067574 -398.55775)
		(width 0.14224)
		(layer "In6.Cu")
		(net "P5E_CPU0_P3_TX_BUF_DP<4>")
	)
	(arc
		(start 384.35153 -411.491176)
		(mid 384.622565 -411.577364)
		(end 384.852926 -411.74416)
		(width 0.14224)
		(layer "In6.Cu")
		(net "P5E_CPU0_P3_TX_BUF_DP<4>")
	)
	(arc
		(start 376.453654 -404.78456)
		(mid 376.503688 -405.036006)
		(end 376.646186 -405.249126)
		(width 0.14224)
		(layer "In6.Cu")
		(net "P5E_CPU0_P3_TX_BUF_DP<4>")
	)
	(arc
		(start 375.706894 -397.883888)
		(mid 375.733436 -398.017234)
		(end 375.809002 -398.130268)
		(width 0.14224)
		(layer "In6.Cu")
		(net "P5E_CPU0_P3_TX_BUF_DP<4>")
	)
	(arc
		(start 384.95097 -411.842204)
		(mid 385.173358 -412.175031)
		(end 385.251452 -412.567628)
		(width 0.14224)
		(layer "In6.Cu")
		(net "P5E_CPU0_P3_TX_BUF_DP<4>")
	)
	(arc
		(start 376.423174 -399.971514)
		(mid 376.446018 -400.073642)
		(end 376.453654 -400.178016)
		(width 0.14224)
		(layer "In6.Cu")
		(net "P5E_CPU0_P3_TX_BUF_DP<4>")
	)
	(segment
		(start 374.3706 -397.849344)
		(end 374.8913 -397.849344)
		(width 0.127)
		(layer "F.Cu")
		(net "P5E_CPU0_P3_TX_BUF_DP<3>")
	)
	(segment
		(start 382.208532 -416.336734)
		(end 382.208532 -415.65703)
		(width 0.12954)
		(layer "B.Cu")
		(net "P5E_CPU0_P3_TX_BUF_DP<3>")
	)
	(segment
		(start 382.504442 -416.632644)
		(end 382.208532 -416.336734)
		(width 0.12954)
		(layer "B.Cu")
		(net "P5E_CPU0_P3_TX_BUF_DP<3>")
	)
	(segment
		(start 382.208532 -415.65703)
		(end 382.479042 -415.38652)
		(width 0.12954)
		(layer "B.Cu")
		(net "P5E_CPU0_P3_TX_BUF_DP<3>")
	)
	(segment
		(start 375.253758 -403.384512)
		(end 375.253758 -403.811232)
		(width 0.14224)
		(layer "In6.Cu")
		(net "P5E_CPU0_P3_TX_BUF_DP<3>")
	)
	(segment
		(start 375.253758 -403.811232)
		(end 375.390918 -403.948392)
		(width 0.14224)
		(layer "In6.Cu")
		(net "P5E_CPU0_P3_TX_BUF_DP<3>")
	)
	(segment
		(start 382.188212 -412.637732)
		(end 382.188212 -413.404558)
		(width 0.14224)
		(layer "In6.Cu")
		(net "P5E_CPU0_P3_TX_BUF_DP<3>")
	)
	(segment
		(start 375.253758 -400.394424)
		(end 375.253758 -402.683472)
		(width 0.14224)
		(layer "In6.Cu")
		(net "P5E_CPU0_P3_TX_BUF_DP<3>")
	)
	(segment
		(start 374.506998 -397.823944)
		(end 374.506998 -397.918686)
		(width 0.14224)
		(layer "In6.Cu")
		(net "P5E_CPU0_P3_TX_BUF_DP<3>")
	)
	(segment
		(start 374.8913 -397.849344)
		(end 374.776492 -397.734536)
		(width 0.14224)
		(layer "In6.Cu")
		(net "P5E_CPU0_P3_TX_BUF_DP<3>")
	)
	(segment
		(start 382.188212 -414.105598)
		(end 382.188212 -415.09569)
		(width 0.14224)
		(layer "In6.Cu")
		(net "P5E_CPU0_P3_TX_BUF_DP<3>")
	)
	(segment
		(start 375.390918 -403.247352)
		(end 375.253758 -403.384512)
		(width 0.14224)
		(layer "In6.Cu")
		(net "P5E_CPU0_P3_TX_BUF_DP<3>")
	)
	(segment
		(start 375.390918 -404.375112)
		(end 375.253758 -404.512272)
		(width 0.14224)
		(layer "In6.Cu")
		(net "P5E_CPU0_P3_TX_BUF_DP<3>")
	)
	(segment
		(start 382.325372 -413.541718)
		(end 382.325372 -413.968438)
		(width 0.14224)
		(layer "In6.Cu")
		(net "P5E_CPU0_P3_TX_BUF_DP<3>")
	)
	(segment
		(start 374.596406 -397.734536)
		(end 374.506998 -397.823944)
		(width 0.14224)
		(layer "In6.Cu")
		(net "P5E_CPU0_P3_TX_BUF_DP<3>")
	)
	(segment
		(start 374.776492 -397.734536)
		(end 374.596406 -397.734536)
		(width 0.14224)
		(layer "In6.Cu")
		(net "P5E_CPU0_P3_TX_BUF_DP<3>")
	)
	(segment
		(start 375.390918 -403.948392)
		(end 375.390918 -404.375112)
		(width 0.14224)
		(layer "In6.Cu")
		(net "P5E_CPU0_P3_TX_BUF_DP<3>")
	)
	(segment
		(start 375.253758 -402.683472)
		(end 375.390918 -402.820632)
		(width 0.14224)
		(layer "In6.Cu")
		(net "P5E_CPU0_P3_TX_BUF_DP<3>")
	)
	(segment
		(start 374.88622 -398.884902)
		(end 375.166382 -399.809462)
		(width 0.14224)
		(layer "In6.Cu")
		(net "P5E_CPU0_P3_TX_BUF_DP<3>")
	)
	(segment
		(start 375.390918 -402.820632)
		(end 375.390918 -403.247352)
		(width 0.14224)
		(layer "In6.Cu")
		(net "P5E_CPU0_P3_TX_BUF_DP<3>")
	)
	(segment
		(start 374.867678 -398.558512)
		(end 374.867678 -398.760188)
		(width 0.14224)
		(layer "In6.Cu")
		(net "P5E_CPU0_P3_TX_BUF_DP<3>")
	)
	(segment
		(start 375.202958 -399.972784)
		(end 375.241312 -400.225768)
		(width 0.14224)
		(layer "In6.Cu")
		(net "P5E_CPU0_P3_TX_BUF_DP<3>")
	)
	(segment
		(start 382.325372 -413.968438)
		(end 382.188212 -414.105598)
		(width 0.14224)
		(layer "In6.Cu")
		(net "P5E_CPU0_P3_TX_BUF_DP<3>")
	)
	(segment
		(start 382.188212 -413.404558)
		(end 382.325372 -413.541718)
		(width 0.14224)
		(layer "In6.Cu")
		(net "P5E_CPU0_P3_TX_BUF_DP<3>")
	)
	(segment
		(start 375.253758 -404.512272)
		(end 375.253758 -405.065992)
		(width 0.14224)
		(layer "In6.Cu")
		(net "P5E_CPU0_P3_TX_BUF_DP<3>")
	)
	(segment
		(start 374.584468 -398.10563)
		(end 374.74779 -398.268952)
		(width 0.14224)
		(layer "In6.Cu")
		(net "P5E_CPU0_P3_TX_BUF_DP<3>")
	)
	(segment
		(start 382.188212 -415.09569)
		(end 382.479042 -415.38652)
		(width 0.14224)
		(layer "In6.Cu")
		(net "P5E_CPU0_P3_TX_BUF_DP<3>")
	)
	(segment
		(start 375.391426 -405.398478)
		(end 381.87503 -411.882082)
		(width 0.14224)
		(layer "In6.Cu")
		(net "P5E_CPU0_P3_TX_BUF_DP<3>")
	)
	(arc
		(start 374.867678 -398.760188)
		(mid 374.872361 -398.823226)
		(end 374.88622 -398.884902)
		(width 0.14224)
		(layer "In6.Cu")
		(net "P5E_CPU0_P3_TX_BUF_DP<3>")
	)
	(arc
		(start 374.74779 -398.268952)
		(mid 374.836505 -398.401817)
		(end 374.867678 -398.558512)
		(width 0.14224)
		(layer "In6.Cu")
		(net "P5E_CPU0_P3_TX_BUF_DP<3>")
	)
	(arc
		(start 375.166382 -399.809462)
		(mid 375.187625 -399.890461)
		(end 375.202958 -399.972784)
		(width 0.14224)
		(layer "In6.Cu")
		(net "P5E_CPU0_P3_TX_BUF_DP<3>")
	)
	(arc
		(start 375.241312 -400.225768)
		(mid 375.2507 -400.309862)
		(end 375.253758 -400.394424)
		(width 0.14224)
		(layer "In6.Cu")
		(net "P5E_CPU0_P3_TX_BUF_DP<3>")
	)
	(arc
		(start 374.506998 -397.918686)
		(mid 374.527125 -398.019873)
		(end 374.584468 -398.10563)
		(width 0.14224)
		(layer "In6.Cu")
		(net "P5E_CPU0_P3_TX_BUF_DP<3>")
	)
	(arc
		(start 375.253758 -405.065992)
		(mid 375.289531 -405.245926)
		(end 375.391426 -405.398478)
		(width 0.14224)
		(layer "In6.Cu")
		(net "P5E_CPU0_P3_TX_BUF_DP<3>")
	)
	(arc
		(start 381.87503 -411.882082)
		(mid 382.106714 -412.228776)
		(end 382.188212 -412.637732)
		(width 0.14224)
		(layer "In6.Cu")
		(net "P5E_CPU0_P3_TX_BUF_DP<3>")
	)
	(segment
		(start 373.17045 -397.849344)
		(end 373.69115 -397.849344)
		(width 0.127)
		(layer "F.Cu")
		(net "P5E_CPU0_P3_TX_BUF_DP<2>")
	)
	(segment
		(start 379.145292 -416.336734)
		(end 379.145292 -415.65703)
		(width 0.12954)
		(layer "B.Cu")
		(net "P5E_CPU0_P3_TX_BUF_DP<2>")
	)
	(segment
		(start 379.145292 -415.65703)
		(end 379.415802 -415.38652)
		(width 0.12954)
		(layer "B.Cu")
		(net "P5E_CPU0_P3_TX_BUF_DP<2>")
	)
	(segment
		(start 379.441202 -416.632644)
		(end 379.145292 -416.336734)
		(width 0.12954)
		(layer "B.Cu")
		(net "P5E_CPU0_P3_TX_BUF_DP<2>")
	)
	(segment
		(start 374.191022 -404.401528)
		(end 374.053862 -404.538688)
		(width 0.14224)
		(layer "In6.Cu")
		(net "P5E_CPU0_P3_TX_BUF_DP<2>")
	)
	(segment
		(start 377.622562 -409.742132)
		(end 377.815602 -409.761182)
		(width 0.14224)
		(layer "In6.Cu")
		(net "P5E_CPU0_P3_TX_BUF_DP<2>")
	)
	(segment
		(start 373.400066 -398.121632)
		(end 373.548148 -398.269714)
		(width 0.14224)
		(layer "In6.Cu")
		(net "P5E_CPU0_P3_TX_BUF_DP<2>")
	)
	(segment
		(start 373.306848 -397.848582)
		(end 373.306848 -397.896588)
		(width 0.14224)
		(layer "In6.Cu")
		(net "P5E_CPU0_P3_TX_BUF_DP<2>")
	)
	(segment
		(start 374.191022 -403.273768)
		(end 374.053862 -403.410928)
		(width 0.14224)
		(layer "In6.Cu")
		(net "P5E_CPU0_P3_TX_BUF_DP<2>")
	)
	(segment
		(start 373.69496 -398.624298)
		(end 373.69496 -398.859502)
		(width 0.14224)
		(layer "In6.Cu")
		(net "P5E_CPU0_P3_TX_BUF_DP<2>")
	)
	(segment
		(start 379.124972 -415.09569)
		(end 379.415802 -415.38652)
		(width 0.14224)
		(layer "In6.Cu")
		(net "P5E_CPU0_P3_TX_BUF_DP<2>")
	)
	(segment
		(start 374.191022 -402.847048)
		(end 374.191022 -403.273768)
		(width 0.14224)
		(layer "In6.Cu")
		(net "P5E_CPU0_P3_TX_BUF_DP<2>")
	)
	(segment
		(start 373.69115 -397.849344)
		(end 373.576342 -397.734536)
		(width 0.14224)
		(layer "In6.Cu")
		(net "P5E_CPU0_P3_TX_BUF_DP<2>")
	)
	(segment
		(start 377.815602 -409.761182)
		(end 378.086366 -410.091382)
		(width 0.14224)
		(layer "In6.Cu")
		(net "P5E_CPU0_P3_TX_BUF_DP<2>")
	)
	(segment
		(start 374.25376 -405.637238)
		(end 377.622308 -409.742132)
		(width 0.14224)
		(layer "In6.Cu")
		(net "P5E_CPU0_P3_TX_BUF_DP<2>")
	)
	(segment
		(start 374.053862 -404.538688)
		(end 374.053862 -405.079454)
		(width 0.14224)
		(layer "In6.Cu")
		(net "P5E_CPU0_P3_TX_BUF_DP<2>")
	)
	(segment
		(start 373.713502 -398.984216)
		(end 374.023128 -400.003772)
		(width 0.14224)
		(layer "In6.Cu")
		(net "P5E_CPU0_P3_TX_BUF_DP<2>")
	)
	(segment
		(start 374.053862 -400.210274)
		(end 374.053862 -402.709888)
		(width 0.14224)
		(layer "In6.Cu")
		(net "P5E_CPU0_P3_TX_BUF_DP<2>")
	)
	(segment
		(start 374.191022 -403.974808)
		(end 374.191022 -404.401528)
		(width 0.14224)
		(layer "In6.Cu")
		(net "P5E_CPU0_P3_TX_BUF_DP<2>")
	)
	(segment
		(start 374.053862 -403.837648)
		(end 374.191022 -403.974808)
		(width 0.14224)
		(layer "In6.Cu")
		(net "P5E_CPU0_P3_TX_BUF_DP<2>")
	)
	(segment
		(start 374.053862 -402.709888)
		(end 374.191022 -402.847048)
		(width 0.14224)
		(layer "In6.Cu")
		(net "P5E_CPU0_P3_TX_BUF_DP<2>")
	)
	(segment
		(start 378.06757 -410.284422)
		(end 378.712476 -411.070298)
		(width 0.14224)
		(layer "In6.Cu")
		(net "P5E_CPU0_P3_TX_BUF_DP<2>")
	)
	(segment
		(start 377.622308 -409.742132)
		(end 377.622562 -409.742132)
		(width 0.14224)
		(layer "In6.Cu")
		(net "P5E_CPU0_P3_TX_BUF_DP<2>")
	)
	(segment
		(start 373.576342 -397.734536)
		(end 373.420894 -397.734536)
		(width 0.14224)
		(layer "In6.Cu")
		(net "P5E_CPU0_P3_TX_BUF_DP<2>")
	)
	(segment
		(start 379.124972 -412.223204)
		(end 379.124972 -415.09569)
		(width 0.14224)
		(layer "In6.Cu")
		(net "P5E_CPU0_P3_TX_BUF_DP<2>")
	)
	(segment
		(start 373.420894 -397.734536)
		(end 373.306848 -397.848582)
		(width 0.14224)
		(layer "In6.Cu")
		(net "P5E_CPU0_P3_TX_BUF_DP<2>")
	)
	(segment
		(start 378.086366 -410.091382)
		(end 378.06757 -410.284422)
		(width 0.14224)
		(layer "In6.Cu")
		(net "P5E_CPU0_P3_TX_BUF_DP<2>")
	)
	(segment
		(start 374.053862 -403.410928)
		(end 374.053862 -403.837648)
		(width 0.14224)
		(layer "In6.Cu")
		(net "P5E_CPU0_P3_TX_BUF_DP<2>")
	)
	(arc
		(start 374.023128 -400.003772)
		(mid 374.046114 -400.105889)
		(end 374.053862 -400.210274)
		(width 0.14224)
		(layer "In6.Cu")
		(net "P5E_CPU0_P3_TX_BUF_DP<2>")
	)
	(arc
		(start 373.306848 -397.896588)
		(mid 373.331074 -398.018382)
		(end 373.400066 -398.121632)
		(width 0.14224)
		(layer "In6.Cu")
		(net "P5E_CPU0_P3_TX_BUF_DP<2>")
	)
	(arc
		(start 373.548148 -398.269714)
		(mid 373.656797 -398.432413)
		(end 373.69496 -398.624298)
		(width 0.14224)
		(layer "In6.Cu")
		(net "P5E_CPU0_P3_TX_BUF_DP<2>")
	)
	(arc
		(start 374.053862 -405.079454)
		(mid 374.105439 -405.375677)
		(end 374.25376 -405.637238)
		(width 0.14224)
		(layer "In6.Cu")
		(net "P5E_CPU0_P3_TX_BUF_DP<2>")
	)
	(arc
		(start 378.712476 -411.070298)
		(mid 379.018749 -411.610964)
		(end 379.124972 -412.223204)
		(width 0.14224)
		(layer "In6.Cu")
		(net "P5E_CPU0_P3_TX_BUF_DP<2>")
	)
	(arc
		(start 373.69496 -398.859502)
		(mid 373.699615 -398.922546)
		(end 373.713502 -398.984216)
		(width 0.14224)
		(layer "In6.Cu")
		(net "P5E_CPU0_P3_TX_BUF_DP<2>")
	)
	(segment
		(start 371.970554 -397.849344)
		(end 372.491254 -397.849344)
		(width 0.127)
		(layer "F.Cu")
		(net "P5E_CPU0_P3_TX_BUF_DP<1>")
	)
	(segment
		(start 376.082052 -416.336734)
		(end 376.082052 -415.65703)
		(width 0.12954)
		(layer "B.Cu")
		(net "P5E_CPU0_P3_TX_BUF_DP<1>")
	)
	(segment
		(start 376.377962 -416.632644)
		(end 376.082052 -416.336734)
		(width 0.12954)
		(layer "B.Cu")
		(net "P5E_CPU0_P3_TX_BUF_DP<1>")
	)
	(segment
		(start 376.082052 -415.65703)
		(end 376.352562 -415.38652)
		(width 0.12954)
		(layer "B.Cu")
		(net "P5E_CPU0_P3_TX_BUF_DP<1>")
	)
	(segment
		(start 374.053608 -407.72969)
		(end 374.236488 -407.794968)
		(width 0.14224)
		(layer "In6.Cu")
		(net "P5E_CPU0_P3_TX_BUF_DP<1>")
	)
	(segment
		(start 372.19636 -397.734536)
		(end 372.106952 -397.823944)
		(width 0.14224)
		(layer "In6.Cu")
		(net "P5E_CPU0_P3_TX_BUF_DP<1>")
	)
	(segment
		(start 374.779794 -408.94381)
		(end 374.96242 -409.32989)
		(width 0.14224)
		(layer "In6.Cu")
		(net "P5E_CPU0_P3_TX_BUF_DP<1>")
	)
	(segment
		(start 374.41886 -408.181048)
		(end 374.353582 -408.363674)
		(width 0.14224)
		(layer "In6.Cu")
		(net "P5E_CPU0_P3_TX_BUF_DP<1>")
	)
	(segment
		(start 374.236488 -407.794968)
		(end 374.41886 -408.181048)
		(width 0.14224)
		(layer "In6.Cu")
		(net "P5E_CPU0_P3_TX_BUF_DP<1>")
	)
	(segment
		(start 373.754142 -406.775412)
		(end 373.936514 -407.161238)
		(width 0.14224)
		(layer "In6.Cu")
		(net "P5E_CPU0_P3_TX_BUF_DP<1>")
	)
	(segment
		(start 372.376446 -397.734536)
		(end 372.19636 -397.734536)
		(width 0.14224)
		(layer "In6.Cu")
		(net "P5E_CPU0_P3_TX_BUF_DP<1>")
	)
	(segment
		(start 374.596914 -408.878532)
		(end 374.779794 -408.94381)
		(width 0.14224)
		(layer "In6.Cu")
		(net "P5E_CPU0_P3_TX_BUF_DP<1>")
	)
	(segment
		(start 373.571262 -406.710134)
		(end 373.754142 -406.775412)
		(width 0.14224)
		(layer "In6.Cu")
		(net "P5E_CPU0_P3_TX_BUF_DP<1>")
	)
	(segment
		(start 374.896888 -409.512516)
		(end 376.061732 -411.975808)
		(width 0.14224)
		(layer "In6.Cu")
		(net "P5E_CPU0_P3_TX_BUF_DP<1>")
	)
	(segment
		(start 376.061732 -411.975808)
		(end 376.061732 -415.09569)
		(width 0.14224)
		(layer "In6.Cu")
		(net "P5E_CPU0_P3_TX_BUF_DP<1>")
	)
	(segment
		(start 372.853712 -400.035776)
		(end 372.853712 -405.192484)
		(width 0.14224)
		(layer "In6.Cu")
		(net "P5E_CPU0_P3_TX_BUF_DP<1>")
	)
	(segment
		(start 373.871236 -407.344118)
		(end 374.053608 -407.72969)
		(width 0.14224)
		(layer "In6.Cu")
		(net "P5E_CPU0_P3_TX_BUF_DP<1>")
	)
	(segment
		(start 374.96242 -409.32989)
		(end 374.896888 -409.512516)
		(width 0.14224)
		(layer "In6.Cu")
		(net "P5E_CPU0_P3_TX_BUF_DP<1>")
	)
	(segment
		(start 372.853712 -405.192484)
		(end 373.571262 -406.710134)
		(width 0.14224)
		(layer "In6.Cu")
		(net "P5E_CPU0_P3_TX_BUF_DP<1>")
	)
	(segment
		(start 372.190518 -398.111726)
		(end 372.347744 -398.268698)
		(width 0.14224)
		(layer "In6.Cu")
		(net "P5E_CPU0_P3_TX_BUF_DP<1>")
	)
	(segment
		(start 373.936514 -407.161238)
		(end 373.871236 -407.344118)
		(width 0.14224)
		(layer "In6.Cu")
		(net "P5E_CPU0_P3_TX_BUF_DP<1>")
	)
	(segment
		(start 372.106952 -397.823944)
		(end 372.106952 -397.91005)
		(width 0.14224)
		(layer "In6.Cu")
		(net "P5E_CPU0_P3_TX_BUF_DP<1>")
	)
	(segment
		(start 372.511828 -399.212308)
		(end 372.853712 -400.035776)
		(width 0.14224)
		(layer "In6.Cu")
		(net "P5E_CPU0_P3_TX_BUF_DP<1>")
	)
	(segment
		(start 376.061732 -415.09569)
		(end 376.352562 -415.38652)
		(width 0.14224)
		(layer "In6.Cu")
		(net "P5E_CPU0_P3_TX_BUF_DP<1>")
	)
	(segment
		(start 372.467632 -398.55775)
		(end 372.467632 -398.91335)
		(width 0.14224)
		(layer "In6.Cu")
		(net "P5E_CPU0_P3_TX_BUF_DP<1>")
	)
	(segment
		(start 372.491254 -397.849344)
		(end 372.376446 -397.734536)
		(width 0.14224)
		(layer "In6.Cu")
		(net "P5E_CPU0_P3_TX_BUF_DP<1>")
	)
	(segment
		(start 374.353582 -408.363674)
		(end 374.596914 -408.878532)
		(width 0.14224)
		(layer "In6.Cu")
		(net "P5E_CPU0_P3_TX_BUF_DP<1>")
	)
	(arc
		(start 372.347744 -398.268698)
		(mid 372.43644 -398.401301)
		(end 372.467632 -398.55775)
		(width 0.14224)
		(layer "In6.Cu")
		(net "P5E_CPU0_P3_TX_BUF_DP<1>")
	)
	(arc
		(start 372.467632 -398.91335)
		(mid 372.478702 -399.06446)
		(end 372.511828 -399.212308)
		(width 0.14224)
		(layer "In6.Cu")
		(net "P5E_CPU0_P3_TX_BUF_DP<1>")
	)
	(arc
		(start 372.106952 -397.91005)
		(mid 372.128665 -398.019207)
		(end 372.190518 -398.111726)
		(width 0.14224)
		(layer "In6.Cu")
		(net "P5E_CPU0_P3_TX_BUF_DP<1>")
	)
	(segment
		(start 388.770622 -397.849344)
		(end 389.291322 -397.849344)
		(width 0.127)
		(layer "F.Cu")
		(net "P5E_CPU0_P3_TX_BUF_DP<15>")
	)
	(segment
		(start 419.263322 -416.632644)
		(end 418.967412 -416.336734)
		(width 0.12954)
		(layer "B.Cu")
		(net "P5E_CPU0_P3_TX_BUF_DP<15>")
	)
	(segment
		(start 418.967412 -415.65703)
		(end 419.237922 -415.38652)
		(width 0.12954)
		(layer "B.Cu")
		(net "P5E_CPU0_P3_TX_BUF_DP<15>")
	)
	(segment
		(start 418.967412 -416.336734)
		(end 418.967412 -415.65703)
		(width 0.12954)
		(layer "B.Cu")
		(net "P5E_CPU0_P3_TX_BUF_DP<15>")
	)
	(segment
		(start 389.176514 -397.734536)
		(end 388.996428 -397.734536)
		(width 0.14224)
		(layer "In6.Cu")
		(net "P5E_CPU0_P3_TX_BUF_DP<15>")
	)
	(segment
		(start 396.422118 -403.591522)
		(end 402.083016 -405.158194)
		(width 0.14224)
		(layer "In6.Cu")
		(net "P5E_CPU0_P3_TX_BUF_DP<15>")
	)
	(segment
		(start 390.16051 -401.280376)
		(end 390.337294 -401.45716)
		(width 0.14224)
		(layer "In6.Cu")
		(net "P5E_CPU0_P3_TX_BUF_DP<15>")
	)
	(segment
		(start 405.49449 -406.102312)
		(end 407.05913 -406.535382)
		(width 0.14224)
		(layer "In6.Cu")
		(net "P5E_CPU0_P3_TX_BUF_DP<15>")
	)
	(segment
		(start 402.75891 -405.345392)
		(end 402.759164 -405.345392)
		(width 0.14224)
		(layer "In6.Cu")
		(net "P5E_CPU0_P3_TX_BUF_DP<15>")
	)
	(segment
		(start 395.915134 -403.30882)
		(end 396.326614 -403.422612)
		(width 0.14224)
		(layer "In6.Cu")
		(net "P5E_CPU0_P3_TX_BUF_DP<15>")
	)
	(segment
		(start 396.326614 -403.422612)
		(end 396.422118 -403.591522)
		(width 0.14224)
		(layer "In6.Cu")
		(net "P5E_CPU0_P3_TX_BUF_DP<15>")
	)
	(segment
		(start 389.818626 -400.083528)
		(end 389.818626 -400.416014)
		(width 0.14224)
		(layer "In6.Cu")
		(net "P5E_CPU0_P3_TX_BUF_DP<15>")
	)
	(segment
		(start 418.975286 -415.123884)
		(end 419.237922 -415.38652)
		(width 0.14224)
		(layer "In6.Cu")
		(net "P5E_CPU0_P3_TX_BUF_DP<15>")
	)
	(segment
		(start 388.996174 -398.117314)
		(end 389.12419 -398.245076)
		(width 0.14224)
		(layer "In6.Cu")
		(net "P5E_CPU0_P3_TX_BUF_DP<15>")
	)
	(segment
		(start 418.975286 -413.097472)
		(end 418.975286 -415.123884)
		(width 0.14224)
		(layer "In6.Cu")
		(net "P5E_CPU0_P3_TX_BUF_DP<15>")
	)
	(segment
		(start 395.746224 -403.404324)
		(end 395.915134 -403.30882)
		(width 0.14224)
		(layer "In6.Cu")
		(net "P5E_CPU0_P3_TX_BUF_DP<15>")
	)
	(segment
		(start 402.759164 -405.345392)
		(end 404.818596 -405.915368)
		(width 0.14224)
		(layer "In6.Cu")
		(net "P5E_CPU0_P3_TX_BUF_DP<15>")
	)
	(segment
		(start 404.818596 -405.915368)
		(end 404.987252 -405.81961)
		(width 0.14224)
		(layer "In6.Cu")
		(net "P5E_CPU0_P3_TX_BUF_DP<15>")
	)
	(segment
		(start 388.996428 -397.734536)
		(end 388.90702 -397.823944)
		(width 0.14224)
		(layer "In6.Cu")
		(net "P5E_CPU0_P3_TX_BUF_DP<15>")
	)
	(segment
		(start 391.807954 -402.31441)
		(end 395.746224 -403.404324)
		(width 0.14224)
		(layer "In6.Cu")
		(net "P5E_CPU0_P3_TX_BUF_DP<15>")
	)
	(segment
		(start 389.64235 -399.395696)
		(end 389.787892 -399.877026)
		(width 0.14224)
		(layer "In6.Cu")
		(net "P5E_CPU0_P3_TX_BUF_DP<15>")
	)
	(segment
		(start 402.083016 -405.158194)
		(end 402.251672 -405.062436)
		(width 0.14224)
		(layer "In6.Cu")
		(net "P5E_CPU0_P3_TX_BUF_DP<15>")
	)
	(segment
		(start 402.251672 -405.062436)
		(end 402.663406 -405.176228)
		(width 0.14224)
		(layer "In6.Cu")
		(net "P5E_CPU0_P3_TX_BUF_DP<15>")
	)
	(segment
		(start 404.987252 -405.81961)
		(end 405.398732 -405.933402)
		(width 0.14224)
		(layer "In6.Cu")
		(net "P5E_CPU0_P3_TX_BUF_DP<15>")
	)
	(segment
		(start 407.05913 -406.535382)
		(end 417.60394 -410.90342)
		(width 0.14224)
		(layer "In6.Cu")
		(net "P5E_CPU0_P3_TX_BUF_DP<15>")
	)
	(segment
		(start 388.90702 -397.823944)
		(end 388.90702 -397.902176)
		(width 0.14224)
		(layer "In6.Cu")
		(net "P5E_CPU0_P3_TX_BUF_DP<15>")
	)
	(segment
		(start 389.843264 -400.539204)
		(end 390.132824 -401.238974)
		(width 0.14224)
		(layer "In6.Cu")
		(net "P5E_CPU0_P3_TX_BUF_DP<15>")
	)
	(segment
		(start 405.49449 -406.102566)
		(end 405.49449 -406.102312)
		(width 0.14224)
		(layer "In6.Cu")
		(net "P5E_CPU0_P3_TX_BUF_DP<15>")
	)
	(segment
		(start 405.398732 -405.933402)
		(end 405.49449 -406.102566)
		(width 0.14224)
		(layer "In6.Cu")
		(net "P5E_CPU0_P3_TX_BUF_DP<15>")
	)
	(segment
		(start 389.291322 -397.849344)
		(end 389.176514 -397.734536)
		(width 0.14224)
		(layer "In6.Cu")
		(net "P5E_CPU0_P3_TX_BUF_DP<15>")
	)
	(segment
		(start 402.663406 -405.176228)
		(end 402.75891 -405.345392)
		(width 0.14224)
		(layer "In6.Cu")
		(net "P5E_CPU0_P3_TX_BUF_DP<15>")
	)
	(segment
		(start 389.255508 -398.441418)
		(end 389.59028 -399.250662)
		(width 0.14224)
		(layer "In6.Cu")
		(net "P5E_CPU0_P3_TX_BUF_DP<15>")
	)
	(segment
		(start 418.465 -411.610048)
		(end 418.572696 -411.771338)
		(width 0.14224)
		(layer "In6.Cu")
		(net "P5E_CPU0_P3_TX_BUF_DP<15>")
	)
	(arc
		(start 418.572696 -411.771338)
		(mid 418.872374 -412.404533)
		(end 418.975286 -413.097472)
		(width 0.14224)
		(layer "In6.Cu")
		(net "P5E_CPU0_P3_TX_BUF_DP<15>")
	)
	(arc
		(start 389.207756 -398.34947)
		(mid 389.233604 -398.39442)
		(end 389.255508 -398.441418)
		(width 0.14224)
		(layer "In6.Cu")
		(net "P5E_CPU0_P3_TX_BUF_DP<15>")
	)
	(arc
		(start 389.787892 -399.877026)
		(mid 389.810865 -399.979145)
		(end 389.818626 -400.083528)
		(width 0.14224)
		(layer "In6.Cu")
		(net "P5E_CPU0_P3_TX_BUF_DP<15>")
	)
	(arc
		(start 389.818626 -400.416014)
		(mid 389.824899 -400.478817)
		(end 389.843264 -400.539204)
		(width 0.14224)
		(layer "In6.Cu")
		(net "P5E_CPU0_P3_TX_BUF_DP<15>")
	)
	(arc
		(start 389.12419 -398.245076)
		(mid 389.168874 -398.294951)
		(end 389.207756 -398.34947)
		(width 0.14224)
		(layer "In6.Cu")
		(net "P5E_CPU0_P3_TX_BUF_DP<15>")
	)
	(arc
		(start 417.60394 -410.90342)
		(mid 418.086831 -411.192922)
		(end 418.465 -411.610048)
		(width 0.14224)
		(layer "In6.Cu")
		(net "P5E_CPU0_P3_TX_BUF_DP<15>")
	)
	(arc
		(start 390.132824 -401.238974)
		(mid 390.144615 -401.261049)
		(end 390.16051 -401.280376)
		(width 0.14224)
		(layer "In6.Cu")
		(net "P5E_CPU0_P3_TX_BUF_DP<15>")
	)
	(arc
		(start 388.90702 -397.902176)
		(mid 388.930198 -398.018609)
		(end 388.996174 -398.117314)
		(width 0.14224)
		(layer "In6.Cu")
		(net "P5E_CPU0_P3_TX_BUF_DP<15>")
	)
	(arc
		(start 389.59028 -399.250662)
		(mid 389.618092 -399.322541)
		(end 389.64235 -399.395696)
		(width 0.14224)
		(layer "In6.Cu")
		(net "P5E_CPU0_P3_TX_BUF_DP<15>")
	)
	(arc
		(start 390.337294 -401.45716)
		(mid 391.017087 -401.981063)
		(end 391.807954 -402.31441)
		(width 0.14224)
		(layer "In6.Cu")
		(net "P5E_CPU0_P3_TX_BUF_DP<15>")
	)
	(segment
		(start 387.570472 -397.849344)
		(end 388.091172 -397.849344)
		(width 0.127)
		(layer "F.Cu")
		(net "P5E_CPU0_P3_TX_BUF_DP<14>")
	)
	(segment
		(start 415.904172 -415.65703)
		(end 416.174682 -415.38652)
		(width 0.12954)
		(layer "B.Cu")
		(net "P5E_CPU0_P3_TX_BUF_DP<14>")
	)
	(segment
		(start 416.200082 -416.632644)
		(end 415.904172 -416.336734)
		(width 0.12954)
		(layer "B.Cu")
		(net "P5E_CPU0_P3_TX_BUF_DP<14>")
	)
	(segment
		(start 415.904172 -416.336734)
		(end 415.904172 -415.65703)
		(width 0.12954)
		(layer "B.Cu")
		(net "P5E_CPU0_P3_TX_BUF_DP<14>")
	)
	(segment
		(start 410.892498 -409.588716)
		(end 411.071822 -409.514548)
		(width 0.14224)
		(layer "In6.Cu")
		(net "P5E_CPU0_P3_TX_BUF_DP<14>")
	)
	(segment
		(start 415.883852 -415.09569)
		(end 416.174682 -415.38652)
		(width 0.14224)
		(layer "In6.Cu")
		(net "P5E_CPU0_P3_TX_BUF_DP<14>")
	)
	(segment
		(start 409.858464 -409.160472)
		(end 410.892498 -409.588716)
		(width 0.14224)
		(layer "In6.Cu")
		(net "P5E_CPU0_P3_TX_BUF_DP<14>")
	)
	(segment
		(start 409.38958 -408.817572)
		(end 409.784296 -408.980894)
		(width 0.14224)
		(layer "In6.Cu")
		(net "P5E_CPU0_P3_TX_BUF_DP<14>")
	)
	(segment
		(start 388.453884 -400.360134)
		(end 388.453884 -402.442934)
		(width 0.14224)
		(layer "In6.Cu")
		(net "P5E_CPU0_P3_TX_BUF_DP<14>")
	)
	(segment
		(start 411.466284 -409.67787)
		(end 411.540452 -409.857194)
		(width 0.14224)
		(layer "In6.Cu")
		(net "P5E_CPU0_P3_TX_BUF_DP<14>")
	)
	(segment
		(start 411.540452 -409.857194)
		(end 415.086292 -411.325822)
		(width 0.14224)
		(layer "In6.Cu")
		(net "P5E_CPU0_P3_TX_BUF_DP<14>")
	)
	(segment
		(start 388.093712 -398.610582)
		(end 388.115556 -398.75079)
		(width 0.14224)
		(layer "In6.Cu")
		(net "P5E_CPU0_P3_TX_BUF_DP<14>")
	)
	(segment
		(start 409.784296 -408.980894)
		(end 409.858464 -409.160472)
		(width 0.14224)
		(layer "In6.Cu")
		(net "P5E_CPU0_P3_TX_BUF_DP<14>")
	)
	(segment
		(start 387.782308 -397.734536)
		(end 387.698996 -397.817848)
		(width 0.14224)
		(layer "In6.Cu")
		(net "P5E_CPU0_P3_TX_BUF_DP<14>")
	)
	(segment
		(start 415.883852 -412.519622)
		(end 415.883852 -415.09569)
		(width 0.14224)
		(layer "In6.Cu")
		(net "P5E_CPU0_P3_TX_BUF_DP<14>")
	)
	(segment
		(start 411.071822 -409.514548)
		(end 411.466284 -409.67787)
		(width 0.14224)
		(layer "In6.Cu")
		(net "P5E_CPU0_P3_TX_BUF_DP<14>")
	)
	(segment
		(start 403.435058 -406.704038)
		(end 403.843744 -406.827736)
		(width 0.14224)
		(layer "In6.Cu")
		(net "P5E_CPU0_P3_TX_BUF_DP<14>")
	)
	(segment
		(start 388.501128 -402.55698)
		(end 388.69366 -402.749512)
		(width 0.14224)
		(layer "In6.Cu")
		(net "P5E_CPU0_P3_TX_BUF_DP<14>")
	)
	(segment
		(start 406.57145 -407.798778)
		(end 409.21051 -408.891994)
		(width 0.14224)
		(layer "In6.Cu")
		(net "P5E_CPU0_P3_TX_BUF_DP<14>")
	)
	(segment
		(start 388.802626 -402.811234)
		(end 396.42161 -404.720044)
		(width 0.14224)
		(layer "In6.Cu")
		(net "P5E_CPU0_P3_TX_BUF_DP<14>")
	)
	(segment
		(start 409.21051 -408.891994)
		(end 409.38958 -408.817572)
		(width 0.14224)
		(layer "In6.Cu")
		(net "P5E_CPU0_P3_TX_BUF_DP<14>")
	)
	(segment
		(start 387.698996 -397.817848)
		(end 387.698996 -397.856456)
		(width 0.14224)
		(layer "In6.Cu")
		(net "P5E_CPU0_P3_TX_BUF_DP<14>")
	)
	(segment
		(start 387.976364 -397.734536)
		(end 387.782308 -397.734536)
		(width 0.14224)
		(layer "In6.Cu")
		(net "P5E_CPU0_P3_TX_BUF_DP<14>")
	)
	(segment
		(start 388.139432 -398.87525)
		(end 388.433056 -400.17192)
		(width 0.14224)
		(layer "In6.Cu")
		(net "P5E_CPU0_P3_TX_BUF_DP<14>")
	)
	(segment
		(start 403.935184 -406.999186)
		(end 406.57145 -407.798778)
		(width 0.14224)
		(layer "In6.Cu")
		(net "P5E_CPU0_P3_TX_BUF_DP<14>")
	)
	(segment
		(start 387.81482 -398.13611)
		(end 387.891782 -398.213072)
		(width 0.14224)
		(layer "In6.Cu")
		(net "P5E_CPU0_P3_TX_BUF_DP<14>")
	)
	(segment
		(start 403.263862 -406.795478)
		(end 403.435058 -406.704038)
		(width 0.14224)
		(layer "In6.Cu")
		(net "P5E_CPU0_P3_TX_BUF_DP<14>")
	)
	(segment
		(start 388.091172 -397.849344)
		(end 387.976364 -397.734536)
		(width 0.14224)
		(layer "In6.Cu")
		(net "P5E_CPU0_P3_TX_BUF_DP<14>")
	)
	(segment
		(start 396.42161 -404.720044)
		(end 403.263862 -406.795478)
		(width 0.14224)
		(layer "In6.Cu")
		(net "P5E_CPU0_P3_TX_BUF_DP<14>")
	)
	(segment
		(start 403.843744 -406.827736)
		(end 403.935184 -406.999186)
		(width 0.14224)
		(layer "In6.Cu")
		(net "P5E_CPU0_P3_TX_BUF_DP<14>")
	)
	(arc
		(start 387.891782 -398.213072)
		(mid 388.024355 -398.395772)
		(end 388.093712 -398.610582)
		(width 0.14224)
		(layer "In6.Cu")
		(net "P5E_CPU0_P3_TX_BUF_DP<14>")
	)
	(arc
		(start 388.433056 -400.17192)
		(mid 388.448736 -400.265445)
		(end 388.453884 -400.360134)
		(width 0.14224)
		(layer "In6.Cu")
		(net "P5E_CPU0_P3_TX_BUF_DP<14>")
	)
	(arc
		(start 388.115556 -398.75079)
		(mid 388.126447 -398.813221)
		(end 388.139432 -398.87525)
		(width 0.14224)
		(layer "In6.Cu")
		(net "P5E_CPU0_P3_TX_BUF_DP<14>")
	)
	(arc
		(start 388.453884 -402.442934)
		(mid 388.466161 -402.504657)
		(end 388.501128 -402.55698)
		(width 0.14224)
		(layer "In6.Cu")
		(net "P5E_CPU0_P3_TX_BUF_DP<14>")
	)
	(arc
		(start 415.086292 -411.325822)
		(mid 415.666066 -411.801789)
		(end 415.883852 -412.519622)
		(width 0.14224)
		(layer "In6.Cu")
		(net "P5E_CPU0_P3_TX_BUF_DP<14>")
	)
	(arc
		(start 387.698996 -397.856456)
		(mid 387.7291 -398.007799)
		(end 387.81482 -398.13611)
		(width 0.14224)
		(layer "In6.Cu")
		(net "P5E_CPU0_P3_TX_BUF_DP<14>")
	)
	(arc
		(start 388.69366 -402.749512)
		(mid 388.743952 -402.787768)
		(end 388.802626 -402.811234)
		(width 0.14224)
		(layer "In6.Cu")
		(net "P5E_CPU0_P3_TX_BUF_DP<14>")
	)
	(segment
		(start 386.370576 -397.849344)
		(end 386.891276 -397.849344)
		(width 0.127)
		(layer "F.Cu")
		(net "P5E_CPU0_P3_TX_BUF_DP<13>")
	)
	(segment
		(start 413.136842 -416.632644)
		(end 412.840932 -416.336734)
		(width 0.12954)
		(layer "B.Cu")
		(net "P5E_CPU0_P3_TX_BUF_DP<13>")
	)
	(segment
		(start 412.840932 -416.336734)
		(end 412.840932 -415.65703)
		(width 0.12954)
		(layer "B.Cu")
		(net "P5E_CPU0_P3_TX_BUF_DP<13>")
	)
	(segment
		(start 412.840932 -415.65703)
		(end 413.111442 -415.38652)
		(width 0.12954)
		(layer "B.Cu")
		(net "P5E_CPU0_P3_TX_BUF_DP<13>")
	)
	(segment
		(start 386.594604 -398.11579)
		(end 386.747766 -398.268952)
		(width 0.14224)
		(layer "In6.Cu")
		(net "P5E_CPU0_P3_TX_BUF_DP<13>")
	)
	(segment
		(start 405.707342 -408.878532)
		(end 405.882602 -408.795728)
		(width 0.14224)
		(layer "In6.Cu")
		(net "P5E_CPU0_P3_TX_BUF_DP<13>")
	)
	(segment
		(start 401.228052 -407.276046)
		(end 401.629626 -407.419556)
		(width 0.14224)
		(layer "In6.Cu")
		(net "P5E_CPU0_P3_TX_BUF_DP<13>")
	)
	(segment
		(start 402.290026 -407.65603)
		(end 405.707342 -408.878532)
		(width 0.14224)
		(layer "In6.Cu")
		(net "P5E_CPU0_P3_TX_BUF_DP<13>")
	)
	(segment
		(start 386.892038 -398.97685)
		(end 387.253734 -400.169634)
		(width 0.14224)
		(layer "In6.Cu")
		(net "P5E_CPU0_P3_TX_BUF_DP<13>")
	)
	(segment
		(start 388.29488 -403.647402)
		(end 393.87272 -405.044656)
		(width 0.14224)
		(layer "In6.Cu")
		(net "P5E_CPU0_P3_TX_BUF_DP<13>")
	)
	(segment
		(start 387.253734 -400.169634)
		(end 387.253734 -402.756878)
		(width 0.14224)
		(layer "In6.Cu")
		(net "P5E_CPU0_P3_TX_BUF_DP<13>")
	)
	(segment
		(start 386.596382 -397.734536)
		(end 386.506974 -397.823944)
		(width 0.14224)
		(layer "In6.Cu")
		(net "P5E_CPU0_P3_TX_BUF_DP<13>")
	)
	(segment
		(start 411.044644 -410.789882)
		(end 411.118812 -410.969206)
		(width 0.14224)
		(layer "In6.Cu")
		(net "P5E_CPU0_P3_TX_BUF_DP<13>")
	)
	(segment
		(start 406.284684 -408.939492)
		(end 406.367742 -409.115006)
		(width 0.14224)
		(layer "In6.Cu")
		(net "P5E_CPU0_P3_TX_BUF_DP<13>")
	)
	(segment
		(start 387.308852 -402.889974)
		(end 387.76783 -403.348952)
		(width 0.14224)
		(layer "In6.Cu")
		(net "P5E_CPU0_P3_TX_BUF_DP<13>")
	)
	(segment
		(start 402.206968 -407.480516)
		(end 402.290026 -407.65603)
		(width 0.14224)
		(layer "In6.Cu")
		(net "P5E_CPU0_P3_TX_BUF_DP<13>")
	)
	(segment
		(start 401.629626 -407.419556)
		(end 401.80514 -407.336752)
		(width 0.14224)
		(layer "In6.Cu")
		(net "P5E_CPU0_P3_TX_BUF_DP<13>")
	)
	(segment
		(start 410.650182 -410.62656)
		(end 411.044644 -410.789882)
		(width 0.14224)
		(layer "In6.Cu")
		(net "P5E_CPU0_P3_TX_BUF_DP<13>")
	)
	(segment
		(start 386.776468 -397.734536)
		(end 386.596382 -397.734536)
		(width 0.14224)
		(layer "In6.Cu")
		(net "P5E_CPU0_P3_TX_BUF_DP<13>")
	)
	(segment
		(start 408.383994 -409.836366)
		(end 410.470858 -410.700728)
		(width 0.14224)
		(layer "In6.Cu")
		(net "P5E_CPU0_P3_TX_BUF_DP<13>")
	)
	(segment
		(start 386.867654 -398.558512)
		(end 386.867654 -398.812766)
		(width 0.14224)
		(layer "In6.Cu")
		(net "P5E_CPU0_P3_TX_BUF_DP<13>")
	)
	(segment
		(start 412.820612 -415.09569)
		(end 413.111442 -415.38652)
		(width 0.14224)
		(layer "In6.Cu")
		(net "P5E_CPU0_P3_TX_BUF_DP<13>")
	)
	(segment
		(start 412.820612 -412.420308)
		(end 412.820612 -415.09569)
		(width 0.14224)
		(layer "In6.Cu")
		(net "P5E_CPU0_P3_TX_BUF_DP<13>")
	)
	(segment
		(start 386.506974 -397.823944)
		(end 386.506974 -397.904462)
		(width 0.14224)
		(layer "In6.Cu")
		(net "P5E_CPU0_P3_TX_BUF_DP<13>")
	)
	(segment
		(start 405.882602 -408.795728)
		(end 406.284684 -408.939492)
		(width 0.14224)
		(layer "In6.Cu")
		(net "P5E_CPU0_P3_TX_BUF_DP<13>")
	)
	(segment
		(start 411.118812 -410.969206)
		(end 412.131002 -411.388306)
		(width 0.14224)
		(layer "In6.Cu")
		(net "P5E_CPU0_P3_TX_BUF_DP<13>")
	)
	(segment
		(start 410.470858 -410.700728)
		(end 410.650182 -410.62656)
		(width 0.14224)
		(layer "In6.Cu")
		(net "P5E_CPU0_P3_TX_BUF_DP<13>")
	)
	(segment
		(start 406.367742 -409.115006)
		(end 408.383994 -409.836366)
		(width 0.14224)
		(layer "In6.Cu")
		(net "P5E_CPU0_P3_TX_BUF_DP<13>")
	)
	(segment
		(start 401.80514 -407.336752)
		(end 402.206968 -407.480516)
		(width 0.14224)
		(layer "In6.Cu")
		(net "P5E_CPU0_P3_TX_BUF_DP<13>")
	)
	(segment
		(start 386.891276 -397.849344)
		(end 386.776468 -397.734536)
		(width 0.14224)
		(layer "In6.Cu")
		(net "P5E_CPU0_P3_TX_BUF_DP<13>")
	)
	(segment
		(start 393.87272 -405.044656)
		(end 401.228052 -407.276046)
		(width 0.14224)
		(layer "In6.Cu")
		(net "P5E_CPU0_P3_TX_BUF_DP<13>")
	)
	(arc
		(start 387.253734 -402.756878)
		(mid 387.268061 -402.828904)
		(end 387.308852 -402.889974)
		(width 0.14224)
		(layer "In6.Cu")
		(net "P5E_CPU0_P3_TX_BUF_DP<13>")
	)
	(arc
		(start 412.131002 -411.388306)
		(mid 412.632305 -411.799721)
		(end 412.820612 -412.420308)
		(width 0.14224)
		(layer "In6.Cu")
		(net "P5E_CPU0_P3_TX_BUF_DP<13>")
	)
	(arc
		(start 387.76783 -403.348952)
		(mid 388.011104 -403.533927)
		(end 388.29488 -403.647402)
		(width 0.14224)
		(layer "In6.Cu")
		(net "P5E_CPU0_P3_TX_BUF_DP<13>")
	)
	(arc
		(start 386.867654 -398.812766)
		(mid 386.87379 -398.895707)
		(end 386.892038 -398.97685)
		(width 0.14224)
		(layer "In6.Cu")
		(net "P5E_CPU0_P3_TX_BUF_DP<13>")
	)
	(arc
		(start 386.747766 -398.268952)
		(mid 386.836481 -398.401817)
		(end 386.867654 -398.558512)
		(width 0.14224)
		(layer "In6.Cu")
		(net "P5E_CPU0_P3_TX_BUF_DP<13>")
	)
	(arc
		(start 386.506974 -397.904462)
		(mid 386.529746 -398.018854)
		(end 386.594604 -398.11579)
		(width 0.14224)
		(layer "In6.Cu")
		(net "P5E_CPU0_P3_TX_BUF_DP<13>")
	)
	(segment
		(start 385.170426 -397.849344)
		(end 385.691126 -397.849344)
		(width 0.127)
		(layer "F.Cu")
		(net "P5E_CPU0_P3_TX_BUF_DP<12>")
	)
	(segment
		(start 410.073602 -416.632644)
		(end 409.777692 -416.336734)
		(width 0.12954)
		(layer "B.Cu")
		(net "P5E_CPU0_P3_TX_BUF_DP<12>")
	)
	(segment
		(start 409.777692 -416.336734)
		(end 409.777692 -415.65703)
		(width 0.12954)
		(layer "B.Cu")
		(net "P5E_CPU0_P3_TX_BUF_DP<12>")
	)
	(segment
		(start 409.777692 -415.65703)
		(end 410.048202 -415.38652)
		(width 0.12954)
		(layer "B.Cu")
		(net "P5E_CPU0_P3_TX_BUF_DP<12>")
	)
	(segment
		(start 386.851144 -404.029164)
		(end 387.044946 -404.222966)
		(width 0.14224)
		(layer "In6.Cu")
		(net "P5E_CPU0_P3_TX_BUF_DP<12>")
	)
	(segment
		(start 409.757372 -412.014924)
		(end 409.757372 -415.09569)
		(width 0.14224)
		(layer "In6.Cu")
		(net "P5E_CPU0_P3_TX_BUF_DP<12>")
	)
	(segment
		(start 406.39238 -410.214572)
		(end 406.458166 -410.374338)
		(width 0.14224)
		(layer "In6.Cu")
		(net "P5E_CPU0_P3_TX_BUF_DP<12>")
	)
	(segment
		(start 385.773676 -399.299684)
		(end 386.053584 -399.975832)
		(width 0.14224)
		(layer "In6.Cu")
		(net "P5E_CPU0_P3_TX_BUF_DP<12>")
	)
	(segment
		(start 386.355082 -403.533102)
		(end 386.549138 -403.533102)
		(width 0.14224)
		(layer "In6.Cu")
		(net "P5E_CPU0_P3_TX_BUF_DP<12>")
	)
	(segment
		(start 407.412952 -410.631894)
		(end 407.481786 -410.79801)
		(width 0.14224)
		(layer "In6.Cu")
		(net "P5E_CPU0_P3_TX_BUF_DP<12>")
	)
	(segment
		(start 405.997664 -410.051504)
		(end 406.39238 -410.214572)
		(width 0.14224)
		(layer "In6.Cu")
		(net "P5E_CPU0_P3_TX_BUF_DP<12>")
	)
	(segment
		(start 386.851144 -403.835108)
		(end 386.851144 -404.029164)
		(width 0.14224)
		(layer "In6.Cu")
		(net "P5E_CPU0_P3_TX_BUF_DP<12>")
	)
	(segment
		(start 385.691126 -397.849344)
		(end 385.576318 -397.734536)
		(width 0.14224)
		(layer "In6.Cu")
		(net "P5E_CPU0_P3_TX_BUF_DP<12>")
	)
	(segment
		(start 402.322538 -408.661108)
		(end 405.838406 -410.11729)
		(width 0.14224)
		(layer "In6.Cu")
		(net "P5E_CPU0_P3_TX_BUF_DP<12>")
	)
	(segment
		(start 406.852374 -410.537406)
		(end 407.01849 -410.468826)
		(width 0.14224)
		(layer "In6.Cu")
		(net "P5E_CPU0_P3_TX_BUF_DP<12>")
	)
	(segment
		(start 409.757372 -415.09569)
		(end 410.048202 -415.38652)
		(width 0.14224)
		(layer "In6.Cu")
		(net "P5E_CPU0_P3_TX_BUF_DP<12>")
	)
	(segment
		(start 406.458166 -410.374338)
		(end 406.852374 -410.537406)
		(width 0.14224)
		(layer "In6.Cu")
		(net "P5E_CPU0_P3_TX_BUF_DP<12>")
	)
	(segment
		(start 387.411214 -404.430484)
		(end 392.964416 -405.82215)
		(width 0.14224)
		(layer "In6.Cu")
		(net "P5E_CPU0_P3_TX_BUF_DP<12>")
	)
	(segment
		(start 407.01849 -410.468826)
		(end 407.412952 -410.631894)
		(width 0.14224)
		(layer "In6.Cu")
		(net "P5E_CPU0_P3_TX_BUF_DP<12>")
	)
	(segment
		(start 405.838406 -410.11729)
		(end 405.997664 -410.051504)
		(width 0.14224)
		(layer "In6.Cu")
		(net "P5E_CPU0_P3_TX_BUF_DP<12>")
	)
	(segment
		(start 408.060398 -411.03804)
		(end 408.219656 -410.972)
		(width 0.14224)
		(layer "In6.Cu")
		(net "P5E_CPU0_P3_TX_BUF_DP<12>")
	)
	(segment
		(start 408.219656 -410.972)
		(end 408.614118 -411.135322)
		(width 0.14224)
		(layer "In6.Cu")
		(net "P5E_CPU0_P3_TX_BUF_DP<12>")
	)
	(segment
		(start 385.673092 -399.020538)
		(end 385.773676 -399.299684)
		(width 0.14224)
		(layer "In6.Cu")
		(net "P5E_CPU0_P3_TX_BUF_DP<12>")
	)
	(segment
		(start 385.383786 -398.105122)
		(end 385.547616 -398.268952)
		(width 0.14224)
		(layer "In6.Cu")
		(net "P5E_CPU0_P3_TX_BUF_DP<12>")
	)
	(segment
		(start 408.614118 -411.135322)
		(end 408.680158 -411.295088)
		(width 0.14224)
		(layer "In6.Cu")
		(net "P5E_CPU0_P3_TX_BUF_DP<12>")
	)
	(segment
		(start 385.576318 -397.734536)
		(end 385.41325 -397.734536)
		(width 0.14224)
		(layer "In6.Cu")
		(net "P5E_CPU0_P3_TX_BUF_DP<12>")
	)
	(segment
		(start 386.150104 -403.328124)
		(end 386.355082 -403.533102)
		(width 0.14224)
		(layer "In6.Cu")
		(net "P5E_CPU0_P3_TX_BUF_DP<12>")
	)
	(segment
		(start 385.667504 -398.558512)
		(end 385.667504 -398.983708)
		(width 0.14224)
		(layer "In6.Cu")
		(net "P5E_CPU0_P3_TX_BUF_DP<12>")
	)
	(segment
		(start 385.307078 -397.840708)
		(end 385.307078 -397.92021)
		(width 0.14224)
		(layer "In6.Cu")
		(net "P5E_CPU0_P3_TX_BUF_DP<12>")
	)
	(segment
		(start 386.053584 -399.975832)
		(end 386.053584 -403.095206)
		(width 0.14224)
		(layer "In6.Cu")
		(net "P5E_CPU0_P3_TX_BUF_DP<12>")
	)
	(segment
		(start 408.680158 -411.295088)
		(end 409.50515 -411.636718)
		(width 0.14224)
		(layer "In6.Cu")
		(net "P5E_CPU0_P3_TX_BUF_DP<12>")
	)
	(segment
		(start 392.964416 -405.82215)
		(end 402.322538 -408.661108)
		(width 0.14224)
		(layer "In6.Cu")
		(net "P5E_CPU0_P3_TX_BUF_DP<12>")
	)
	(segment
		(start 386.549138 -403.533102)
		(end 386.851144 -403.835108)
		(width 0.14224)
		(layer "In6.Cu")
		(net "P5E_CPU0_P3_TX_BUF_DP<12>")
	)
	(segment
		(start 385.41325 -397.734536)
		(end 385.307078 -397.840708)
		(width 0.14224)
		(layer "In6.Cu")
		(net "P5E_CPU0_P3_TX_BUF_DP<12>")
	)
	(segment
		(start 407.481786 -410.79801)
		(end 407.48204 -410.798518)
		(width 0.14224)
		(layer "In6.Cu")
		(net "P5E_CPU0_P3_TX_BUF_DP<12>")
	)
	(segment
		(start 407.48204 -410.798518)
		(end 408.060398 -411.03804)
		(width 0.14224)
		(layer "In6.Cu")
		(net "P5E_CPU0_P3_TX_BUF_DP<12>")
	)
	(arc
		(start 409.50515 -411.636718)
		(mid 409.68853 -411.787611)
		(end 409.757372 -412.014924)
		(width 0.14224)
		(layer "In6.Cu")
		(net "P5E_CPU0_P3_TX_BUF_DP<12>")
	)
	(arc
		(start 385.547616 -398.268952)
		(mid 385.636331 -398.401817)
		(end 385.667504 -398.558512)
		(width 0.14224)
		(layer "In6.Cu")
		(net "P5E_CPU0_P3_TX_BUF_DP<12>")
	)
	(arc
		(start 385.307078 -397.92021)
		(mid 385.327023 -398.020299)
		(end 385.383786 -398.105122)
		(width 0.14224)
		(layer "In6.Cu")
		(net "P5E_CPU0_P3_TX_BUF_DP<12>")
	)
	(arc
		(start 385.667504 -398.983708)
		(mid 385.668949 -399.002327)
		(end 385.673092 -399.020538)
		(width 0.14224)
		(layer "In6.Cu")
		(net "P5E_CPU0_P3_TX_BUF_DP<12>")
	)
	(arc
		(start 386.053584 -403.095206)
		(mid 386.078676 -403.221262)
		(end 386.150104 -403.328124)
		(width 0.14224)
		(layer "In6.Cu")
		(net "P5E_CPU0_P3_TX_BUF_DP<12>")
	)
	(arc
		(start 387.044946 -404.222966)
		(mid 387.213993 -404.351586)
		(end 387.411214 -404.430484)
		(width 0.14224)
		(layer "In6.Cu")
		(net "P5E_CPU0_P3_TX_BUF_DP<12>")
	)
	(segment
		(start 383.97053 -397.849344)
		(end 384.49123 -397.849344)
		(width 0.127)
		(layer "F.Cu")
		(net "P5E_CPU0_P3_TX_BUF_DP<11>")
	)
	(segment
		(start 406.714452 -416.336734)
		(end 406.714452 -415.65703)
		(width 0.12954)
		(layer "B.Cu")
		(net "P5E_CPU0_P3_TX_BUF_DP<11>")
	)
	(segment
		(start 406.714452 -415.65703)
		(end 406.984962 -415.38652)
		(width 0.12954)
		(layer "B.Cu")
		(net "P5E_CPU0_P3_TX_BUF_DP<11>")
	)
	(segment
		(start 407.010362 -416.632644)
		(end 406.714452 -416.336734)
		(width 0.12954)
		(layer "B.Cu")
		(net "P5E_CPU0_P3_TX_BUF_DP<11>")
	)
	(segment
		(start 404.315168 -410.558234)
		(end 404.389336 -410.737812)
		(width 0.14224)
		(layer "In6.Cu")
		(net "P5E_CPU0_P3_TX_BUF_DP<11>")
	)
	(segment
		(start 385.182872 -404.137622)
		(end 385.376928 -404.137622)
		(width 0.14224)
		(layer "In6.Cu")
		(net "P5E_CPU0_P3_TX_BUF_DP<11>")
	)
	(segment
		(start 384.5179 -398.99717)
		(end 384.853688 -400.10461)
		(width 0.14224)
		(layer "In6.Cu")
		(net "P5E_CPU0_P3_TX_BUF_DP<11>")
	)
	(segment
		(start 406.694132 -412.62427)
		(end 406.694132 -413.377888)
		(width 0.14224)
		(layer "In6.Cu")
		(net "P5E_CPU0_P3_TX_BUF_DP<11>")
	)
	(segment
		(start 384.179572 -398.100804)
		(end 384.34772 -398.268952)
		(width 0.14224)
		(layer "In6.Cu")
		(net "P5E_CPU0_P3_TX_BUF_DP<11>")
	)
	(segment
		(start 406.694132 -415.09569)
		(end 406.984962 -415.38652)
		(width 0.14224)
		(layer "In6.Cu")
		(net "P5E_CPU0_P3_TX_BUF_DP<11>")
	)
	(segment
		(start 384.106928 -397.823944)
		(end 384.106928 -397.925544)
		(width 0.14224)
		(layer "In6.Cu")
		(net "P5E_CPU0_P3_TX_BUF_DP<11>")
	)
	(segment
		(start 384.467608 -398.558512)
		(end 384.467608 -398.657064)
		(width 0.14224)
		(layer "In6.Cu")
		(net "P5E_CPU0_P3_TX_BUF_DP<11>")
	)
	(segment
		(start 404.389336 -410.737812)
		(end 405.952706 -411.387036)
		(width 0.14224)
		(layer "In6.Cu")
		(net "P5E_CPU0_P3_TX_BUF_DP<11>")
	)
	(segment
		(start 406.694132 -414.078928)
		(end 406.694132 -415.09569)
		(width 0.14224)
		(layer "In6.Cu")
		(net "P5E_CPU0_P3_TX_BUF_DP<11>")
	)
	(segment
		(start 406.831292 -413.515048)
		(end 406.831292 -413.941768)
		(width 0.14224)
		(layer "In6.Cu")
		(net "P5E_CPU0_P3_TX_BUF_DP<11>")
	)
	(segment
		(start 385.678934 -404.439628)
		(end 385.678934 -404.633684)
		(width 0.14224)
		(layer "In6.Cu")
		(net "P5E_CPU0_P3_TX_BUF_DP<11>")
	)
	(segment
		(start 385.006596 -403.961346)
		(end 385.182872 -404.137622)
		(width 0.14224)
		(layer "In6.Cu")
		(net "P5E_CPU0_P3_TX_BUF_DP<11>")
	)
	(segment
		(start 385.678934 -404.633684)
		(end 386.0419 -404.99665)
		(width 0.14224)
		(layer "In6.Cu")
		(net "P5E_CPU0_P3_TX_BUF_DP<11>")
	)
	(segment
		(start 406.831292 -413.941768)
		(end 406.694132 -414.078928)
		(width 0.14224)
		(layer "In6.Cu")
		(net "P5E_CPU0_P3_TX_BUF_DP<11>")
	)
	(segment
		(start 406.694132 -413.377888)
		(end 406.831292 -413.515048)
		(width 0.14224)
		(layer "In6.Cu")
		(net "P5E_CPU0_P3_TX_BUF_DP<11>")
	)
	(segment
		(start 384.853688 -400.10461)
		(end 384.853688 -403.592538)
		(width 0.14224)
		(layer "In6.Cu")
		(net "P5E_CPU0_P3_TX_BUF_DP<11>")
	)
	(segment
		(start 403.92096 -410.394658)
		(end 404.315168 -410.558234)
		(width 0.14224)
		(layer "In6.Cu")
		(net "P5E_CPU0_P3_TX_BUF_DP<11>")
	)
	(segment
		(start 384.196336 -397.734536)
		(end 384.106928 -397.823944)
		(width 0.14224)
		(layer "In6.Cu")
		(net "P5E_CPU0_P3_TX_BUF_DP<11>")
	)
	(segment
		(start 385.376928 -404.137622)
		(end 385.678934 -404.439628)
		(width 0.14224)
		(layer "In6.Cu")
		(net "P5E_CPU0_P3_TX_BUF_DP<11>")
	)
	(segment
		(start 391.185654 -406.35047)
		(end 400.980656 -409.322016)
		(width 0.14224)
		(layer "In6.Cu")
		(net "P5E_CPU0_P3_TX_BUF_DP<11>")
	)
	(segment
		(start 386.250942 -405.115014)
		(end 391.185654 -406.35047)
		(width 0.14224)
		(layer "In6.Cu")
		(net "P5E_CPU0_P3_TX_BUF_DP<11>")
	)
	(segment
		(start 384.49123 -397.849344)
		(end 384.376422 -397.734536)
		(width 0.14224)
		(layer "In6.Cu")
		(net "P5E_CPU0_P3_TX_BUF_DP<11>")
	)
	(segment
		(start 384.376422 -397.734536)
		(end 384.196336 -397.734536)
		(width 0.14224)
		(layer "In6.Cu")
		(net "P5E_CPU0_P3_TX_BUF_DP<11>")
	)
	(segment
		(start 406.195784 -411.55112)
		(end 406.283922 -411.633924)
		(width 0.14224)
		(layer "In6.Cu")
		(net "P5E_CPU0_P3_TX_BUF_DP<11>")
	)
	(segment
		(start 403.741636 -410.468572)
		(end 403.92096 -410.394658)
		(width 0.14224)
		(layer "In6.Cu")
		(net "P5E_CPU0_P3_TX_BUF_DP<11>")
	)
	(segment
		(start 400.980656 -409.322016)
		(end 403.741636 -410.468572)
		(width 0.14224)
		(layer "In6.Cu")
		(net "P5E_CPU0_P3_TX_BUF_DP<11>")
	)
	(arc
		(start 384.106928 -397.925544)
		(mid 384.125814 -398.020399)
		(end 384.179572 -398.100804)
		(width 0.14224)
		(layer "In6.Cu")
		(net "P5E_CPU0_P3_TX_BUF_DP<11>")
	)
	(arc
		(start 406.283922 -411.633924)
		(mid 406.587525 -412.088299)
		(end 406.694132 -412.62427)
		(width 0.14224)
		(layer "In6.Cu")
		(net "P5E_CPU0_P3_TX_BUF_DP<11>")
	)
	(arc
		(start 386.0419 -404.99665)
		(mid 386.138376 -405.070041)
		(end 386.250942 -405.115014)
		(width 0.14224)
		(layer "In6.Cu")
		(net "P5E_CPU0_P3_TX_BUF_DP<11>")
	)
	(arc
		(start 384.853688 -403.592538)
		(mid 384.893431 -403.792162)
		(end 385.006596 -403.961346)
		(width 0.14224)
		(layer "In6.Cu")
		(net "P5E_CPU0_P3_TX_BUF_DP<11>")
	)
	(arc
		(start 384.34772 -398.268952)
		(mid 384.436435 -398.401817)
		(end 384.467608 -398.558512)
		(width 0.14224)
		(layer "In6.Cu")
		(net "P5E_CPU0_P3_TX_BUF_DP<11>")
	)
	(arc
		(start 405.952706 -411.387036)
		(mid 406.08084 -411.459308)
		(end 406.195784 -411.55112)
		(width 0.14224)
		(layer "In6.Cu")
		(net "P5E_CPU0_P3_TX_BUF_DP<11>")
	)
	(arc
		(start 384.467608 -398.657064)
		(mid 384.480204 -398.828974)
		(end 384.5179 -398.99717)
		(width 0.14224)
		(layer "In6.Cu")
		(net "P5E_CPU0_P3_TX_BUF_DP<11>")
	)
	(segment
		(start 382.770634 -397.849344)
		(end 383.291334 -397.849344)
		(width 0.127)
		(layer "F.Cu")
		(net "P5E_CPU0_P3_TX_BUF_DP<10>")
	)
	(segment
		(start 403.651212 -416.336734)
		(end 403.651212 -415.65703)
		(width 0.12954)
		(layer "B.Cu")
		(net "P5E_CPU0_P3_TX_BUF_DP<10>")
	)
	(segment
		(start 403.651212 -415.65703)
		(end 403.921722 -415.38652)
		(width 0.12954)
		(layer "B.Cu")
		(net "P5E_CPU0_P3_TX_BUF_DP<10>")
	)
	(segment
		(start 403.947122 -416.632644)
		(end 403.651212 -416.336734)
		(width 0.12954)
		(layer "B.Cu")
		(net "P5E_CPU0_P3_TX_BUF_DP<10>")
	)
	(segment
		(start 401.065746 -410.533342)
		(end 401.46478 -410.685742)
		(width 0.14224)
		(layer "In6.Cu")
		(net "P5E_CPU0_P3_TX_BUF_DP<10>")
	)
	(segment
		(start 385.809744 -405.967692)
		(end 390.349232 -407.104596)
		(width 0.14224)
		(layer "In6.Cu")
		(net "P5E_CPU0_P3_TX_BUF_DP<10>")
	)
	(segment
		(start 385.447286 -405.785828)
		(end 385.753864 -405.946356)
		(width 0.14224)
		(layer "In6.Cu")
		(net "P5E_CPU0_P3_TX_BUF_DP<10>")
	)
	(segment
		(start 402.119338 -410.93644)
		(end 402.518118 -411.08884)
		(width 0.14224)
		(layer "In6.Cu")
		(net "P5E_CPU0_P3_TX_BUF_DP<10>")
	)
	(segment
		(start 399.835116 -410.209746)
		(end 400.012154 -410.130752)
		(width 0.14224)
		(layer "In6.Cu")
		(net "P5E_CPU0_P3_TX_BUF_DP<10>")
	)
	(segment
		(start 400.888708 -410.61259)
		(end 401.065746 -410.533342)
		(width 0.14224)
		(layer "In6.Cu")
		(net "P5E_CPU0_P3_TX_BUF_DP<10>")
	)
	(segment
		(start 382.97612 -397.734536)
		(end 382.907032 -397.803624)
		(width 0.14224)
		(layer "In6.Cu")
		(net "P5E_CPU0_P3_TX_BUF_DP<10>")
	)
	(segment
		(start 400.490182 -410.460444)
		(end 400.888708 -410.61259)
		(width 0.14224)
		(layer "In6.Cu")
		(net "P5E_CPU0_P3_TX_BUF_DP<10>")
	)
	(segment
		(start 382.907032 -397.803624)
		(end 382.907032 -397.923766)
		(width 0.14224)
		(layer "In6.Cu")
		(net "P5E_CPU0_P3_TX_BUF_DP<10>")
	)
	(segment
		(start 390.39419 -407.117042)
		(end 397.506444 -409.274518)
		(width 0.14224)
		(layer "In6.Cu")
		(net "P5E_CPU0_P3_TX_BUF_DP<10>")
	)
	(segment
		(start 390.349232 -407.104596)
		(end 390.39419 -407.117042)
		(width 0.14224)
		(layer "In6.Cu")
		(net "P5E_CPU0_P3_TX_BUF_DP<10>")
	)
	(segment
		(start 383.267712 -398.558258)
		(end 383.267712 -398.72158)
		(width 0.14224)
		(layer "In6.Cu")
		(net "P5E_CPU0_P3_TX_BUF_DP<10>")
	)
	(segment
		(start 383.291334 -397.849344)
		(end 383.176526 -397.734536)
		(width 0.14224)
		(layer "In6.Cu")
		(net "P5E_CPU0_P3_TX_BUF_DP<10>")
	)
	(segment
		(start 383.286254 -398.846294)
		(end 383.591308 -399.854674)
		(width 0.14224)
		(layer "In6.Cu")
		(net "P5E_CPU0_P3_TX_BUF_DP<10>")
	)
	(segment
		(start 403.630892 -412.236158)
		(end 403.630892 -415.09569)
		(width 0.14224)
		(layer "In6.Cu")
		(net "P5E_CPU0_P3_TX_BUF_DP<10>")
	)
	(segment
		(start 401.46478 -410.685742)
		(end 401.543774 -410.863288)
		(width 0.14224)
		(layer "In6.Cu")
		(net "P5E_CPU0_P3_TX_BUF_DP<10>")
	)
	(segment
		(start 402.996146 -411.418532)
		(end 403.180296 -411.484318)
		(width 0.14224)
		(layer "In6.Cu")
		(net "P5E_CPU0_P3_TX_BUF_DP<10>")
	)
	(segment
		(start 402.518118 -411.08884)
		(end 402.597366 -411.266132)
		(width 0.14224)
		(layer "In6.Cu")
		(net "P5E_CPU0_P3_TX_BUF_DP<10>")
	)
	(segment
		(start 383.615692 -400.019012)
		(end 383.615692 -403.572218)
		(width 0.14224)
		(layer "In6.Cu")
		(net "P5E_CPU0_P3_TX_BUF_DP<10>")
	)
	(segment
		(start 401.543774 -410.863288)
		(end 401.9423 -411.015434)
		(width 0.14224)
		(layer "In6.Cu")
		(net "P5E_CPU0_P3_TX_BUF_DP<10>")
	)
	(segment
		(start 397.62557 -409.31719)
		(end 399.068798 -409.915614)
		(width 0.14224)
		(layer "In6.Cu")
		(net "P5E_CPU0_P3_TX_BUF_DP<10>")
	)
	(segment
		(start 403.630892 -415.09569)
		(end 403.921722 -415.38652)
		(width 0.14224)
		(layer "In6.Cu")
		(net "P5E_CPU0_P3_TX_BUF_DP<10>")
	)
	(segment
		(start 401.9423 -411.015434)
		(end 402.119338 -410.93644)
		(width 0.14224)
		(layer "In6.Cu")
		(net "P5E_CPU0_P3_TX_BUF_DP<10>")
	)
	(segment
		(start 382.980946 -398.102074)
		(end 383.147824 -398.268698)
		(width 0.14224)
		(layer "In6.Cu")
		(net "P5E_CPU0_P3_TX_BUF_DP<10>")
	)
	(segment
		(start 383.908808 -404.279862)
		(end 385.325112 -405.696166)
		(width 0.14224)
		(layer "In6.Cu")
		(net "P5E_CPU0_P3_TX_BUF_DP<10>")
	)
	(segment
		(start 399.141188 -409.94457)
		(end 399.835116 -410.209746)
		(width 0.14224)
		(layer "In6.Cu")
		(net "P5E_CPU0_P3_TX_BUF_DP<10>")
	)
	(segment
		(start 400.411188 -410.282898)
		(end 400.490182 -410.460444)
		(width 0.14224)
		(layer "In6.Cu")
		(net "P5E_CPU0_P3_TX_BUF_DP<10>")
	)
	(segment
		(start 400.012154 -410.130752)
		(end 400.411188 -410.282898)
		(width 0.14224)
		(layer "In6.Cu")
		(net "P5E_CPU0_P3_TX_BUF_DP<10>")
	)
	(segment
		(start 402.597366 -411.266132)
		(end 402.996146 -411.418532)
		(width 0.14224)
		(layer "In6.Cu")
		(net "P5E_CPU0_P3_TX_BUF_DP<10>")
	)
	(segment
		(start 383.176526 -397.734536)
		(end 382.97612 -397.734536)
		(width 0.14224)
		(layer "In6.Cu")
		(net "P5E_CPU0_P3_TX_BUF_DP<10>")
	)
	(arc
		(start 383.147824 -398.268698)
		(mid 383.236617 -398.401536)
		(end 383.267712 -398.558258)
		(width 0.14224)
		(layer "In6.Cu")
		(net "P5E_CPU0_P3_TX_BUF_DP<10>")
	)
	(arc
		(start 385.325112 -405.696166)
		(mid 385.382797 -405.745632)
		(end 385.447286 -405.785828)
		(width 0.14224)
		(layer "In6.Cu")
		(net "P5E_CPU0_P3_TX_BUF_DP<10>")
	)
	(arc
		(start 403.46757 -411.713426)
		(mid 403.583945 -411.963946)
		(end 403.630892 -412.236158)
		(width 0.14224)
		(layer "In6.Cu")
		(net "P5E_CPU0_P3_TX_BUF_DP<10>")
	)
	(arc
		(start 383.267712 -398.72158)
		(mid 383.272387 -398.784621)
		(end 383.286254 -398.846294)
		(width 0.14224)
		(layer "In6.Cu")
		(net "P5E_CPU0_P3_TX_BUF_DP<10>")
	)
	(arc
		(start 382.907032 -397.923766)
		(mid 382.926246 -398.020273)
		(end 382.980946 -398.102074)
		(width 0.14224)
		(layer "In6.Cu")
		(net "P5E_CPU0_P3_TX_BUF_DP<10>")
	)
	(arc
		(start 383.591308 -399.854674)
		(mid 383.609552 -399.935945)
		(end 383.615692 -400.019012)
		(width 0.14224)
		(layer "In6.Cu")
		(net "P5E_CPU0_P3_TX_BUF_DP<10>")
	)
	(arc
		(start 385.753864 -405.946356)
		(mid 385.781174 -405.958672)
		(end 385.809744 -405.967692)
		(width 0.14224)
		(layer "In6.Cu")
		(net "P5E_CPU0_P3_TX_BUF_DP<10>")
	)
	(arc
		(start 383.615692 -403.572218)
		(mid 383.69187 -403.955192)
		(end 383.908808 -404.279862)
		(width 0.14224)
		(layer "In6.Cu")
		(net "P5E_CPU0_P3_TX_BUF_DP<10>")
	)
	(arc
		(start 403.180296 -411.484318)
		(mid 403.342975 -411.574992)
		(end 403.46757 -411.713426)
		(width 0.14224)
		(layer "In6.Cu")
		(net "P5E_CPU0_P3_TX_BUF_DP<10>")
	)
	(arc
		(start 399.068798 -409.915614)
		(mid 399.104892 -409.930345)
		(end 399.141188 -409.94457)
		(width 0.14224)
		(layer "In6.Cu")
		(net "P5E_CPU0_P3_TX_BUF_DP<10>")
	)
	(arc
		(start 397.506444 -409.274518)
		(mid 397.56653 -409.294393)
		(end 397.62557 -409.31719)
		(width 0.14224)
		(layer "In6.Cu")
		(net "P5E_CPU0_P3_TX_BUF_DP<10>")
	)
	(segment
		(start 370.770658 -397.849344)
		(end 371.291358 -397.849344)
		(width 0.127)
		(layer "F.Cu")
		(net "P5E_CPU0_P3_TX_BUF_DP<0>")
	)
	(segment
		(start 373.018812 -415.65703)
		(end 373.289322 -415.38652)
		(width 0.12954)
		(layer "B.Cu")
		(net "P5E_CPU0_P3_TX_BUF_DP<0>")
	)
	(segment
		(start 373.018812 -416.336734)
		(end 373.018812 -415.65703)
		(width 0.12954)
		(layer "B.Cu")
		(net "P5E_CPU0_P3_TX_BUF_DP<0>")
	)
	(segment
		(start 373.314722 -416.632644)
		(end 373.018812 -416.336734)
		(width 0.12954)
		(layer "B.Cu")
		(net "P5E_CPU0_P3_TX_BUF_DP<0>")
	)
	(segment
		(start 372.653814 -409.548076)
		(end 372.545864 -409.709366)
		(width 0.14224)
		(layer "In6.Cu")
		(net "P5E_CPU0_P3_TX_BUF_DP<0>")
	)
	(segment
		(start 372.545864 -409.709366)
		(end 372.628668 -410.127704)
		(width 0.14224)
		(layer "In6.Cu")
		(net "P5E_CPU0_P3_TX_BUF_DP<0>")
	)
	(segment
		(start 372.628668 -410.127704)
		(end 372.789958 -410.235654)
		(width 0.14224)
		(layer "In6.Cu")
		(net "P5E_CPU0_P3_TX_BUF_DP<0>")
	)
	(segment
		(start 370.975382 -398.096232)
		(end 371.147594 -398.268444)
		(width 0.14224)
		(layer "In6.Cu")
		(net "P5E_CPU0_P3_TX_BUF_DP<0>")
	)
	(segment
		(start 372.765066 -410.815536)
		(end 372.998492 -411.994604)
		(width 0.14224)
		(layer "In6.Cu")
		(net "P5E_CPU0_P3_TX_BUF_DP<0>")
	)
	(segment
		(start 371.653816 -405.206962)
		(end 372.190518 -407.914856)
		(width 0.14224)
		(layer "In6.Cu")
		(net "P5E_CPU0_P3_TX_BUF_DP<0>")
	)
	(segment
		(start 372.998492 -415.09569)
		(end 373.289322 -415.38652)
		(width 0.14224)
		(layer "In6.Cu")
		(net "P5E_CPU0_P3_TX_BUF_DP<0>")
	)
	(segment
		(start 372.873016 -410.6545)
		(end 372.765066 -410.815536)
		(width 0.14224)
		(layer "In6.Cu")
		(net "P5E_CPU0_P3_TX_BUF_DP<0>")
	)
	(segment
		(start 372.190518 -407.914856)
		(end 372.190264 -407.914856)
		(width 0.14224)
		(layer "In6.Cu")
		(net "P5E_CPU0_P3_TX_BUF_DP<0>")
	)
	(segment
		(start 372.434612 -408.441652)
		(end 372.326662 -408.602942)
		(width 0.14224)
		(layer "In6.Cu")
		(net "P5E_CPU0_P3_TX_BUF_DP<0>")
	)
	(segment
		(start 371.17655 -397.734536)
		(end 370.996464 -397.734536)
		(width 0.14224)
		(layer "In6.Cu")
		(net "P5E_CPU0_P3_TX_BUF_DP<0>")
	)
	(segment
		(start 372.789958 -410.235654)
		(end 372.873016 -410.6545)
		(width 0.14224)
		(layer "In6.Cu")
		(net "P5E_CPU0_P3_TX_BUF_DP<0>")
	)
	(segment
		(start 371.653816 -400.185382)
		(end 371.653816 -405.206962)
		(width 0.14224)
		(layer "In6.Cu")
		(net "P5E_CPU0_P3_TX_BUF_DP<0>")
	)
	(segment
		(start 372.570756 -409.12923)
		(end 372.653814 -409.548076)
		(width 0.14224)
		(layer "In6.Cu")
		(net "P5E_CPU0_P3_TX_BUF_DP<0>")
	)
	(segment
		(start 372.326662 -408.602942)
		(end 372.409466 -409.02128)
		(width 0.14224)
		(layer "In6.Cu")
		(net "P5E_CPU0_P3_TX_BUF_DP<0>")
	)
	(segment
		(start 370.996464 -397.734536)
		(end 370.907056 -397.823944)
		(width 0.14224)
		(layer "In6.Cu")
		(net "P5E_CPU0_P3_TX_BUF_DP<0>")
	)
	(segment
		(start 371.286278 -398.867884)
		(end 371.623336 -399.97888)
		(width 0.14224)
		(layer "In6.Cu")
		(net "P5E_CPU0_P3_TX_BUF_DP<0>")
	)
	(segment
		(start 371.291358 -397.849344)
		(end 371.17655 -397.734536)
		(width 0.14224)
		(layer "In6.Cu")
		(net "P5E_CPU0_P3_TX_BUF_DP<0>")
	)
	(segment
		(start 371.267736 -398.55775)
		(end 371.267736 -398.742916)
		(width 0.14224)
		(layer "In6.Cu")
		(net "P5E_CPU0_P3_TX_BUF_DP<0>")
	)
	(segment
		(start 372.998492 -411.994604)
		(end 372.998492 -415.09569)
		(width 0.14224)
		(layer "In6.Cu")
		(net "P5E_CPU0_P3_TX_BUF_DP<0>")
	)
	(segment
		(start 372.409466 -409.02128)
		(end 372.570756 -409.12923)
		(width 0.14224)
		(layer "In6.Cu")
		(net "P5E_CPU0_P3_TX_BUF_DP<0>")
	)
	(segment
		(start 372.351554 -408.022806)
		(end 372.434612 -408.441652)
		(width 0.14224)
		(layer "In6.Cu")
		(net "P5E_CPU0_P3_TX_BUF_DP<0>")
	)
	(segment
		(start 370.907056 -397.823944)
		(end 370.907056 -397.931894)
		(width 0.14224)
		(layer "In6.Cu")
		(net "P5E_CPU0_P3_TX_BUF_DP<0>")
	)
	(segment
		(start 372.190264 -407.914856)
		(end 372.351554 -408.022806)
		(width 0.14224)
		(layer "In6.Cu")
		(net "P5E_CPU0_P3_TX_BUF_DP<0>")
	)
	(arc
		(start 371.147594 -398.268444)
		(mid 371.236475 -398.401135)
		(end 371.267736 -398.55775)
		(width 0.14224)
		(layer "In6.Cu")
		(net "P5E_CPU0_P3_TX_BUF_DP<0>")
	)
	(arc
		(start 371.623336 -399.97888)
		(mid 371.64618 -400.081008)
		(end 371.653816 -400.185382)
		(width 0.14224)
		(layer "In6.Cu")
		(net "P5E_CPU0_P3_TX_BUF_DP<0>")
	)
	(arc
		(start 370.907056 -397.931894)
		(mid 370.924865 -398.020863)
		(end 370.975382 -398.096232)
		(width 0.14224)
		(layer "In6.Cu")
		(net "P5E_CPU0_P3_TX_BUF_DP<0>")
	)
	(arc
		(start 371.267736 -398.742916)
		(mid 371.272403 -398.806082)
		(end 371.286278 -398.867884)
		(width 0.14224)
		(layer "In6.Cu")
		(net "P5E_CPU0_P3_TX_BUF_DP<0>")
	)
	(segment
		(start 381.170434 -397.156432)
		(end 381.691134 -397.156432)
		(width 0.127)
		(layer "F.Cu")
		(net "P5E_CPU0_P3_TX_BUF_DN<9>")
	)
	(segment
		(start 399.969482 -416.632644)
		(end 400.265392 -416.336734)
		(width 0.12954)
		(layer "B.Cu")
		(net "P5E_CPU0_P3_TX_BUF_DN<9>")
	)
	(segment
		(start 400.265392 -416.336734)
		(end 400.265392 -415.65703)
		(width 0.12954)
		(layer "B.Cu")
		(net "P5E_CPU0_P3_TX_BUF_DN<9>")
	)
	(segment
		(start 400.265392 -415.65703)
		(end 399.994882 -415.38652)
		(width 0.12954)
		(layer "B.Cu")
		(net "P5E_CPU0_P3_TX_BUF_DN<9>")
	)
	(segment
		(start 382.186688 -400.386296)
		(end 382.186688 -404.06447)
		(width 0.14224)
		(layer "In6.Cu")
		(net "P5E_CPU0_P3_TX_BUF_DN<9>")
	)
	(segment
		(start 399.363946 -411.541214)
		(end 399.3642 -411.541468)
		(width 0.14224)
		(layer "In6.Cu")
		(net "P5E_CPU0_P3_TX_BUF_DN<9>")
	)
	(segment
		(start 386.997956 -407.519124)
		(end 389.936228 -408.25547)
		(width 0.14224)
		(layer "In6.Cu")
		(net "P5E_CPU0_P3_TX_BUF_DN<9>")
	)
	(segment
		(start 385.742688 -407.269442)
		(end 386.997956 -407.519124)
		(width 0.14224)
		(layer "In6.Cu")
		(net "P5E_CPU0_P3_TX_BUF_DN<9>")
	)
	(segment
		(start 399.930112 -411.77591)
		(end 400.00174 -411.847538)
		(width 0.14224)
		(layer "In6.Cu")
		(net "P5E_CPU0_P3_TX_BUF_DN<9>")
	)
	(segment
		(start 395.520926 -409.949396)
		(end 399.363946 -411.541214)
		(width 0.14224)
		(layer "In6.Cu")
		(net "P5E_CPU0_P3_TX_BUF_DN<9>")
	)
	(segment
		(start 381.743458 -397.388588)
		(end 381.424942 -397.707104)
		(width 0.14224)
		(layer "In6.Cu")
		(net "P5E_CPU0_P3_TX_BUF_DN<9>")
	)
	(segment
		(start 381.424942 -397.707104)
		(end 381.424942 -397.868902)
		(width 0.14224)
		(layer "In6.Cu")
		(net "P5E_CPU0_P3_TX_BUF_DN<9>")
	)
	(segment
		(start 381.78359 -398.57045)
		(end 381.78359 -398.887696)
		(width 0.14224)
		(layer "In6.Cu")
		(net "P5E_CPU0_P3_TX_BUF_DN<9>")
	)
	(segment
		(start 381.743458 -397.208756)
		(end 381.743458 -397.388588)
		(width 0.14224)
		(layer "In6.Cu")
		(net "P5E_CPU0_P3_TX_BUF_DN<9>")
	)
	(segment
		(start 400.285712 -415.09569)
		(end 399.994882 -415.38652)
		(width 0.14224)
		(layer "In6.Cu")
		(net "P5E_CPU0_P3_TX_BUF_DN<9>")
	)
	(segment
		(start 381.691134 -397.156432)
		(end 381.743458 -397.208756)
		(width 0.14224)
		(layer "In6.Cu")
		(net "P5E_CPU0_P3_TX_BUF_DN<9>")
	)
	(segment
		(start 381.620268 -398.340326)
		(end 381.736346 -398.456404)
		(width 0.14224)
		(layer "In6.Cu")
		(net "P5E_CPU0_P3_TX_BUF_DN<9>")
	)
	(segment
		(start 400.285712 -412.53283)
		(end 400.285712 -415.09569)
		(width 0.14224)
		(layer "In6.Cu")
		(net "P5E_CPU0_P3_TX_BUF_DN<9>")
	)
	(segment
		(start 389.936228 -408.25547)
		(end 395.520926 -409.949396)
		(width 0.14224)
		(layer "In6.Cu")
		(net "P5E_CPU0_P3_TX_BUF_DN<9>")
	)
	(segment
		(start 382.07696 -399.921476)
		(end 382.144016 -400.122898)
		(width 0.14224)
		(layer "In6.Cu")
		(net "P5E_CPU0_P3_TX_BUF_DN<9>")
	)
	(segment
		(start 399.3642 -411.541468)
		(end 399.930112 -411.77591)
		(width 0.14224)
		(layer "In6.Cu")
		(net "P5E_CPU0_P3_TX_BUF_DN<9>")
	)
	(segment
		(start 382.428496 -404.576788)
		(end 384.40741 -406.555702)
		(width 0.14224)
		(layer "In6.Cu")
		(net "P5E_CPU0_P3_TX_BUF_DN<9>")
	)
	(segment
		(start 381.804164 -399.025872)
		(end 382.07696 -399.921476)
		(width 0.14224)
		(layer "In6.Cu")
		(net "P5E_CPU0_P3_TX_BUF_DN<9>")
	)
	(arc
		(start 400.00174 -411.847538)
		(mid 400.211933 -412.161924)
		(end 400.285712 -412.53283)
		(width 0.14224)
		(layer "In6.Cu")
		(net "P5E_CPU0_P3_TX_BUF_DN<9>")
	)
	(arc
		(start 381.78359 -398.887696)
		(mid 381.788752 -398.957549)
		(end 381.804164 -399.025872)
		(width 0.14224)
		(layer "In6.Cu")
		(net "P5E_CPU0_P3_TX_BUF_DN<9>")
	)
	(arc
		(start 381.424942 -397.868902)
		(mid 381.47571 -398.124042)
		(end 381.620268 -398.340326)
		(width 0.14224)
		(layer "In6.Cu")
		(net "P5E_CPU0_P3_TX_BUF_DN<9>")
	)
	(arc
		(start 382.144016 -400.122898)
		(mid 382.175909 -400.252887)
		(end 382.186688 -400.386296)
		(width 0.14224)
		(layer "In6.Cu")
		(net "P5E_CPU0_P3_TX_BUF_DN<9>")
	)
	(arc
		(start 382.186688 -404.06447)
		(mid 382.210224 -404.233116)
		(end 382.279144 -404.388828)
		(width 0.14224)
		(layer "In6.Cu")
		(net "P5E_CPU0_P3_TX_BUF_DN<9>")
	)
	(arc
		(start 384.40741 -406.555702)
		(mid 385.022116 -407.011598)
		(end 385.742688 -407.269442)
		(width 0.14224)
		(layer "In6.Cu")
		(net "P5E_CPU0_P3_TX_BUF_DN<9>")
	)
	(arc
		(start 382.279144 -404.388828)
		(mid 382.348403 -404.487111)
		(end 382.428496 -404.576788)
		(width 0.14224)
		(layer "In6.Cu")
		(net "P5E_CPU0_P3_TX_BUF_DN<9>")
	)
	(arc
		(start 381.736346 -398.456404)
		(mid 381.771308 -398.508729)
		(end 381.78359 -398.57045)
		(width 0.14224)
		(layer "In6.Cu")
		(net "P5E_CPU0_P3_TX_BUF_DN<9>")
	)
	(segment
		(start 379.970538 -397.156432)
		(end 380.491238 -397.156432)
		(width 0.127)
		(layer "F.Cu")
		(net "P5E_CPU0_P3_TX_BUF_DN<8>")
	)
	(segment
		(start 397.20393 -416.334956)
		(end 396.906242 -416.632644)
		(width 0.12954)
		(layer "B.Cu")
		(net "P5E_CPU0_P3_TX_BUF_DN<8>")
	)
	(segment
		(start 397.20393 -415.658808)
		(end 397.20393 -416.334956)
		(width 0.12954)
		(layer "B.Cu")
		(net "P5E_CPU0_P3_TX_BUF_DN<8>")
	)
	(segment
		(start 396.931642 -415.38652)
		(end 397.20393 -415.658808)
		(width 0.12954)
		(layer "B.Cu")
		(net "P5E_CPU0_P3_TX_BUF_DN<8>")
	)
	(segment
		(start 396.757398 -411.762956)
		(end 397.004032 -412.00959)
		(width 0.14224)
		(layer "In6.Cu")
		(net "P5E_CPU0_P3_TX_BUF_DN<8>")
	)
	(segment
		(start 396.322296 -411.58287)
		(end 396.32255 -411.58287)
		(width 0.14224)
		(layer "In6.Cu")
		(net "P5E_CPU0_P3_TX_BUF_DN<8>")
	)
	(segment
		(start 396.32255 -411.58287)
		(end 396.757398 -411.762956)
		(width 0.14224)
		(layer "In6.Cu")
		(net "P5E_CPU0_P3_TX_BUF_DN<8>")
	)
	(segment
		(start 397.222472 -415.09569)
		(end 396.931642 -415.38652)
		(width 0.14224)
		(layer "In6.Cu")
		(net "P5E_CPU0_P3_TX_BUF_DN<8>")
	)
	(segment
		(start 397.222472 -412.53664)
		(end 397.222472 -415.09569)
		(width 0.14224)
		(layer "In6.Cu")
		(net "P5E_CPU0_P3_TX_BUF_DN<8>")
	)
	(segment
		(start 380.536958 -397.381984)
		(end 380.225046 -397.693896)
		(width 0.14224)
		(layer "In6.Cu")
		(net "P5E_CPU0_P3_TX_BUF_DN<8>")
	)
	(segment
		(start 389.606028 -409.138882)
		(end 392.65352 -410.063188)
		(width 0.14224)
		(layer "In6.Cu")
		(net "P5E_CPU0_P3_TX_BUF_DN<8>")
	)
	(segment
		(start 380.572518 -398.559274)
		(end 380.572518 -398.723612)
		(width 0.14224)
		(layer "In6.Cu")
		(net "P5E_CPU0_P3_TX_BUF_DN<8>")
	)
	(segment
		(start 381.185928 -404.660862)
		(end 383.822194 -407.297128)
		(width 0.14224)
		(layer "In6.Cu")
		(net "P5E_CPU0_P3_TX_BUF_DN<8>")
	)
	(segment
		(start 380.491238 -397.156432)
		(end 380.536958 -397.202152)
		(width 0.14224)
		(layer "In6.Cu")
		(net "P5E_CPU0_P3_TX_BUF_DN<8>")
	)
	(segment
		(start 385.439412 -408.161744)
		(end 386.740654 -408.42057)
		(width 0.14224)
		(layer "In6.Cu")
		(net "P5E_CPU0_P3_TX_BUF_DN<8>")
	)
	(segment
		(start 386.740654 -408.42057)
		(end 389.606028 -409.138882)
		(width 0.14224)
		(layer "In6.Cu")
		(net "P5E_CPU0_P3_TX_BUF_DN<8>")
	)
	(segment
		(start 392.65352 -410.063188)
		(end 396.322296 -411.58287)
		(width 0.14224)
		(layer "In6.Cu")
		(net "P5E_CPU0_P3_TX_BUF_DN<8>")
	)
	(segment
		(start 380.602998 -398.92986)
		(end 380.939548 -400.040348)
		(width 0.14224)
		(layer "In6.Cu")
		(net "P5E_CPU0_P3_TX_BUF_DN<8>")
	)
	(segment
		(start 380.422404 -398.342358)
		(end 380.525274 -398.445228)
		(width 0.14224)
		(layer "In6.Cu")
		(net "P5E_CPU0_P3_TX_BUF_DN<8>")
	)
	(segment
		(start 380.225046 -397.693896)
		(end 380.225046 -397.866108)
		(width 0.14224)
		(layer "In6.Cu")
		(net "P5E_CPU0_P3_TX_BUF_DN<8>")
	)
	(segment
		(start 380.939548 -400.040348)
		(end 380.939548 -404.066248)
		(width 0.14224)
		(layer "In6.Cu")
		(net "P5E_CPU0_P3_TX_BUF_DN<8>")
	)
	(segment
		(start 380.536958 -397.202152)
		(end 380.536958 -397.381984)
		(width 0.14224)
		(layer "In6.Cu")
		(net "P5E_CPU0_P3_TX_BUF_DN<8>")
	)
	(arc
		(start 380.572518 -398.723612)
		(mid 380.580188 -398.827853)
		(end 380.602998 -398.92986)
		(width 0.14224)
		(layer "In6.Cu")
		(net "P5E_CPU0_P3_TX_BUF_DN<8>")
	)
	(arc
		(start 383.822194 -407.297128)
		(mid 384.566684 -407.849367)
		(end 385.439412 -408.161744)
		(width 0.14224)
		(layer "In6.Cu")
		(net "P5E_CPU0_P3_TX_BUF_DN<8>")
	)
	(arc
		(start 380.225046 -397.866108)
		(mid 380.276336 -398.123872)
		(end 380.422404 -398.342358)
		(width 0.14224)
		(layer "In6.Cu")
		(net "P5E_CPU0_P3_TX_BUF_DN<8>")
	)
	(arc
		(start 380.939548 -404.066248)
		(mid 381.003618 -404.388057)
		(end 381.185928 -404.660862)
		(width 0.14224)
		(layer "In6.Cu")
		(net "P5E_CPU0_P3_TX_BUF_DN<8>")
	)
	(arc
		(start 380.525274 -398.445228)
		(mid 380.560236 -398.497553)
		(end 380.572518 -398.559274)
		(width 0.14224)
		(layer "In6.Cu")
		(net "P5E_CPU0_P3_TX_BUF_DN<8>")
	)
	(arc
		(start 397.004032 -412.00959)
		(mid 397.165713 -412.251374)
		(end 397.222472 -412.53664)
		(width 0.14224)
		(layer "In6.Cu")
		(net "P5E_CPU0_P3_TX_BUF_DN<8>")
	)
	(segment
		(start 378.770642 -397.156432)
		(end 379.291342 -397.156432)
		(width 0.127)
		(layer "F.Cu")
		(net "P5E_CPU0_P3_TX_BUF_DN<7>")
	)
	(segment
		(start 394.138912 -415.65703)
		(end 393.868402 -415.38652)
		(width 0.12954)
		(layer "B.Cu")
		(net "P5E_CPU0_P3_TX_BUF_DN<7>")
	)
	(segment
		(start 394.138912 -416.336734)
		(end 394.138912 -415.65703)
		(width 0.12954)
		(layer "B.Cu")
		(net "P5E_CPU0_P3_TX_BUF_DN<7>")
	)
	(segment
		(start 393.843002 -416.632644)
		(end 394.138912 -416.336734)
		(width 0.12954)
		(layer "B.Cu")
		(net "P5E_CPU0_P3_TX_BUF_DN<7>")
	)
	(segment
		(start 379.957584 -404.75662)
		(end 383.198878 -407.997914)
		(width 0.14224)
		(layer "In6.Cu")
		(net "P5E_CPU0_P3_TX_BUF_DN<7>")
	)
	(segment
		(start 390.424162 -410.377132)
		(end 393.206478 -411.529784)
		(width 0.14224)
		(layer "In6.Cu")
		(net "P5E_CPU0_P3_TX_BUF_DN<7>")
	)
	(segment
		(start 379.291342 -397.156432)
		(end 379.343666 -397.208756)
		(width 0.14224)
		(layer "In6.Cu")
		(net "P5E_CPU0_P3_TX_BUF_DN<7>")
	)
	(segment
		(start 379.343666 -397.208756)
		(end 379.343666 -397.401796)
		(width 0.14224)
		(layer "In6.Cu")
		(net "P5E_CPU0_P3_TX_BUF_DN<7>")
	)
	(segment
		(start 379.158246 -398.248124)
		(end 379.31852 -398.408398)
		(width 0.14224)
		(layer "In6.Cu")
		(net "P5E_CPU0_P3_TX_BUF_DN<7>")
	)
	(segment
		(start 379.343666 -397.401796)
		(end 379.032008 -397.713454)
		(width 0.14224)
		(layer "In6.Cu")
		(net "P5E_CPU0_P3_TX_BUF_DN<7>")
	)
	(segment
		(start 394.159232 -412.593028)
		(end 394.159232 -415.09569)
		(width 0.14224)
		(layer "In6.Cu")
		(net "P5E_CPU0_P3_TX_BUF_DN<7>")
	)
	(segment
		(start 386.230114 -409.2702)
		(end 389.361172 -410.054806)
		(width 0.14224)
		(layer "In6.Cu")
		(net "P5E_CPU0_P3_TX_BUF_DN<7>")
	)
	(segment
		(start 379.365764 -398.522444)
		(end 379.365764 -398.71523)
		(width 0.14224)
		(layer "In6.Cu")
		(net "P5E_CPU0_P3_TX_BUF_DN<7>")
	)
	(segment
		(start 393.206478 -411.529784)
		(end 393.574778 -411.682184)
		(width 0.14224)
		(layer "In6.Cu")
		(net "P5E_CPU0_P3_TX_BUF_DN<7>")
	)
	(segment
		(start 379.77191 -400.224244)
		(end 379.77191 -404.308564)
		(width 0.14224)
		(layer "In6.Cu")
		(net "P5E_CPU0_P3_TX_BUF_DN<7>")
	)
	(segment
		(start 393.574778 -411.682184)
		(end 393.928346 -412.035752)
		(width 0.14224)
		(layer "In6.Cu")
		(net "P5E_CPU0_P3_TX_BUF_DN<7>")
	)
	(segment
		(start 379.396244 -398.921732)
		(end 379.753368 -400.09953)
		(width 0.14224)
		(layer "In6.Cu")
		(net "P5E_CPU0_P3_TX_BUF_DN<7>")
	)
	(segment
		(start 389.361172 -410.054806)
		(end 390.424162 -410.377132)
		(width 0.14224)
		(layer "In6.Cu")
		(net "P5E_CPU0_P3_TX_BUF_DN<7>")
	)
	(segment
		(start 394.159232 -415.09569)
		(end 393.868402 -415.38652)
		(width 0.14224)
		(layer "In6.Cu")
		(net "P5E_CPU0_P3_TX_BUF_DN<7>")
	)
	(segment
		(start 379.032008 -397.713454)
		(end 379.032008 -397.943578)
		(width 0.14224)
		(layer "In6.Cu")
		(net "P5E_CPU0_P3_TX_BUF_DN<7>")
	)
	(segment
		(start 385.192524 -409.063698)
		(end 386.230114 -409.2702)
		(width 0.14224)
		(layer "In6.Cu")
		(net "P5E_CPU0_P3_TX_BUF_DN<7>")
	)
	(arc
		(start 379.77191 -404.308564)
		(mid 379.820165 -404.551068)
		(end 379.957584 -404.75662)
		(width 0.14224)
		(layer "In6.Cu")
		(net "P5E_CPU0_P3_TX_BUF_DN<7>")
	)
	(arc
		(start 379.31852 -398.408398)
		(mid 379.353482 -398.460723)
		(end 379.365764 -398.522444)
		(width 0.14224)
		(layer "In6.Cu")
		(net "P5E_CPU0_P3_TX_BUF_DN<7>")
	)
	(arc
		(start 379.365764 -398.71523)
		(mid 379.373381 -398.819607)
		(end 379.396244 -398.921732)
		(width 0.14224)
		(layer "In6.Cu")
		(net "P5E_CPU0_P3_TX_BUF_DN<7>")
	)
	(arc
		(start 383.198878 -407.997914)
		(mid 384.116675 -408.67862)
		(end 385.192524 -409.063698)
		(width 0.14224)
		(layer "In6.Cu")
		(net "P5E_CPU0_P3_TX_BUF_DN<7>")
	)
	(arc
		(start 393.928346 -412.035752)
		(mid 394.09924 -412.291418)
		(end 394.159232 -412.593028)
		(width 0.14224)
		(layer "In6.Cu")
		(net "P5E_CPU0_P3_TX_BUF_DN<7>")
	)
	(arc
		(start 379.753368 -400.09953)
		(mid 379.767243 -400.161203)
		(end 379.77191 -400.224244)
		(width 0.14224)
		(layer "In6.Cu")
		(net "P5E_CPU0_P3_TX_BUF_DN<7>")
	)
	(arc
		(start 379.032008 -397.943578)
		(mid 379.064852 -398.108407)
		(end 379.158246 -398.248124)
		(width 0.14224)
		(layer "In6.Cu")
		(net "P5E_CPU0_P3_TX_BUF_DN<7>")
	)
	(segment
		(start 377.570492 -397.156432)
		(end 378.091192 -397.156432)
		(width 0.127)
		(layer "F.Cu")
		(net "P5E_CPU0_P3_TX_BUF_DN<6>")
	)
	(segment
		(start 391.075672 -415.65703)
		(end 390.805162 -415.38652)
		(width 0.12954)
		(layer "B.Cu")
		(net "P5E_CPU0_P3_TX_BUF_DN<6>")
	)
	(segment
		(start 390.779762 -416.632644)
		(end 391.075672 -416.336734)
		(width 0.12954)
		(layer "B.Cu")
		(net "P5E_CPU0_P3_TX_BUF_DN<6>")
	)
	(segment
		(start 391.075672 -416.336734)
		(end 391.075672 -415.65703)
		(width 0.12954)
		(layer "B.Cu")
		(net "P5E_CPU0_P3_TX_BUF_DN<6>")
	)
	(segment
		(start 378.042932 -398.363186)
		(end 378.138436 -398.45869)
		(width 0.14224)
		(layer "In6.Cu")
		(net "P5E_CPU0_P3_TX_BUF_DN<6>")
	)
	(segment
		(start 378.18568 -398.572736)
		(end 378.18568 -398.748504)
		(width 0.14224)
		(layer "In6.Cu")
		(net "P5E_CPU0_P3_TX_BUF_DN<6>")
	)
	(segment
		(start 378.21616 -398.954752)
		(end 378.553218 -400.067018)
		(width 0.14224)
		(layer "In6.Cu")
		(net "P5E_CPU0_P3_TX_BUF_DN<6>")
	)
	(segment
		(start 390.534144 -411.664658)
		(end 390.776714 -411.907228)
		(width 0.14224)
		(layer "In6.Cu")
		(net "P5E_CPU0_P3_TX_BUF_DN<6>")
	)
	(segment
		(start 378.091192 -397.156432)
		(end 378.143516 -397.208756)
		(width 0.14224)
		(layer "In6.Cu")
		(net "P5E_CPU0_P3_TX_BUF_DN<6>")
	)
	(segment
		(start 386.077968 -410.197808)
		(end 388.394956 -410.778452)
		(width 0.14224)
		(layer "In6.Cu")
		(net "P5E_CPU0_P3_TX_BUF_DN<6>")
	)
	(segment
		(start 391.095992 -415.09569)
		(end 390.805162 -415.38652)
		(width 0.14224)
		(layer "In6.Cu")
		(net "P5E_CPU0_P3_TX_BUF_DN<6>")
	)
	(segment
		(start 378.868686 -404.992586)
		(end 382.647698 -408.771598)
		(width 0.14224)
		(layer "In6.Cu")
		(net "P5E_CPU0_P3_TX_BUF_DN<6>")
	)
	(segment
		(start 384.86461 -409.956508)
		(end 386.077968 -410.197808)
		(width 0.14224)
		(layer "In6.Cu")
		(net "P5E_CPU0_P3_TX_BUF_DN<6>")
	)
	(segment
		(start 378.57176 -400.191732)
		(end 378.57176 -404.275798)
		(width 0.14224)
		(layer "In6.Cu")
		(net "P5E_CPU0_P3_TX_BUF_DN<6>")
	)
	(segment
		(start 390.159748 -411.509718)
		(end 390.160002 -411.509464)
		(width 0.14224)
		(layer "In6.Cu")
		(net "P5E_CPU0_P3_TX_BUF_DN<6>")
	)
	(segment
		(start 391.095992 -412.677864)
		(end 391.095992 -415.09569)
		(width 0.14224)
		(layer "In6.Cu")
		(net "P5E_CPU0_P3_TX_BUF_DN<6>")
	)
	(segment
		(start 388.394956 -410.778452)
		(end 390.159748 -411.509718)
		(width 0.14224)
		(layer "In6.Cu")
		(net "P5E_CPU0_P3_TX_BUF_DN<6>")
	)
	(segment
		(start 377.825 -397.707104)
		(end 377.825 -397.837152)
		(width 0.14224)
		(layer "In6.Cu")
		(net "P5E_CPU0_P3_TX_BUF_DN<6>")
	)
	(segment
		(start 378.143516 -397.388588)
		(end 377.825 -397.707104)
		(width 0.14224)
		(layer "In6.Cu")
		(net "P5E_CPU0_P3_TX_BUF_DN<6>")
	)
	(segment
		(start 378.143516 -397.208756)
		(end 378.143516 -397.388588)
		(width 0.14224)
		(layer "In6.Cu")
		(net "P5E_CPU0_P3_TX_BUF_DN<6>")
	)
	(segment
		(start 390.160002 -411.509464)
		(end 390.534144 -411.664658)
		(width 0.14224)
		(layer "In6.Cu")
		(net "P5E_CPU0_P3_TX_BUF_DN<6>")
	)
	(arc
		(start 378.57176 -404.275798)
		(mid 378.648924 -404.66373)
		(end 378.868686 -404.992586)
		(width 0.14224)
		(layer "In6.Cu")
		(net "P5E_CPU0_P3_TX_BUF_DN<6>")
	)
	(arc
		(start 382.647698 -408.771598)
		(mid 383.668268 -409.528477)
		(end 384.86461 -409.956508)
		(width 0.14224)
		(layer "In6.Cu")
		(net "P5E_CPU0_P3_TX_BUF_DN<6>")
	)
	(arc
		(start 378.18568 -398.748504)
		(mid 378.193316 -398.852753)
		(end 378.21616 -398.954752)
		(width 0.14224)
		(layer "In6.Cu")
		(net "P5E_CPU0_P3_TX_BUF_DN<6>")
	)
	(arc
		(start 378.138436 -398.45869)
		(mid 378.173398 -398.511015)
		(end 378.18568 -398.572736)
		(width 0.14224)
		(layer "In6.Cu")
		(net "P5E_CPU0_P3_TX_BUF_DN<6>")
	)
	(arc
		(start 390.776714 -411.907228)
		(mid 391.013016 -412.260785)
		(end 391.095992 -412.677864)
		(width 0.14224)
		(layer "In6.Cu")
		(net "P5E_CPU0_P3_TX_BUF_DN<6>")
	)
	(arc
		(start 377.825 -397.837152)
		(mid 377.881646 -398.121841)
		(end 378.042932 -398.363186)
		(width 0.14224)
		(layer "In6.Cu")
		(net "P5E_CPU0_P3_TX_BUF_DN<6>")
	)
	(arc
		(start 378.553218 -400.067018)
		(mid 378.567093 -400.128691)
		(end 378.57176 -400.191732)
		(width 0.14224)
		(layer "In6.Cu")
		(net "P5E_CPU0_P3_TX_BUF_DN<6>")
	)
	(segment
		(start 376.370596 -397.156432)
		(end 376.891296 -397.156432)
		(width 0.127)
		(layer "F.Cu")
		(net "P5E_CPU0_P3_TX_BUF_DN<5>")
	)
	(segment
		(start 387.716522 -416.632644)
		(end 388.012432 -416.336734)
		(width 0.12954)
		(layer "B.Cu")
		(net "P5E_CPU0_P3_TX_BUF_DN<5>")
	)
	(segment
		(start 388.012432 -415.65703)
		(end 387.741922 -415.38652)
		(width 0.12954)
		(layer "B.Cu")
		(net "P5E_CPU0_P3_TX_BUF_DN<5>")
	)
	(segment
		(start 388.012432 -416.336734)
		(end 388.012432 -415.65703)
		(width 0.12954)
		(layer "B.Cu")
		(net "P5E_CPU0_P3_TX_BUF_DN<5>")
	)
	(segment
		(start 377.371864 -400.21002)
		(end 377.371864 -404.42134)
		(width 0.14224)
		(layer "In6.Cu")
		(net "P5E_CPU0_P3_TX_BUF_DN<5>")
	)
	(segment
		(start 377.020836 -398.989042)
		(end 377.353322 -400.085306)
		(width 0.14224)
		(layer "In6.Cu")
		(net "P5E_CPU0_P3_TX_BUF_DN<5>")
	)
	(segment
		(start 388.032752 -415.09569)
		(end 387.741922 -415.38652)
		(width 0.14224)
		(layer "In6.Cu")
		(net "P5E_CPU0_P3_TX_BUF_DN<5>")
	)
	(segment
		(start 376.94362 -397.208756)
		(end 376.94362 -397.388588)
		(width 0.14224)
		(layer "In6.Cu")
		(net "P5E_CPU0_P3_TX_BUF_DN<5>")
	)
	(segment
		(start 387.722872 -411.90037)
		(end 387.831076 -412.008574)
		(width 0.14224)
		(layer "In6.Cu")
		(net "P5E_CPU0_P3_TX_BUF_DN<5>")
	)
	(segment
		(start 376.94362 -397.388588)
		(end 376.625104 -397.707104)
		(width 0.14224)
		(layer "In6.Cu")
		(net "P5E_CPU0_P3_TX_BUF_DN<5>")
	)
	(segment
		(start 387.511798 -411.766766)
		(end 387.722872 -411.90037)
		(width 0.14224)
		(layer "In6.Cu")
		(net "P5E_CPU0_P3_TX_BUF_DN<5>")
	)
	(segment
		(start 388.032752 -412.495492)
		(end 388.032752 -415.09569)
		(width 0.14224)
		(layer "In6.Cu")
		(net "P5E_CPU0_P3_TX_BUF_DN<5>")
	)
	(segment
		(start 376.804936 -398.324832)
		(end 376.948446 -398.468342)
		(width 0.14224)
		(layer "In6.Cu")
		(net "P5E_CPU0_P3_TX_BUF_DN<5>")
	)
	(segment
		(start 376.891296 -397.156432)
		(end 376.94362 -397.208756)
		(width 0.14224)
		(layer "In6.Cu")
		(net "P5E_CPU0_P3_TX_BUF_DN<5>")
	)
	(segment
		(start 376.625104 -397.707104)
		(end 376.625104 -397.890746)
		(width 0.14224)
		(layer "In6.Cu")
		(net "P5E_CPU0_P3_TX_BUF_DN<5>")
	)
	(segment
		(start 377.650502 -405.093932)
		(end 382.188974 -409.632404)
		(width 0.14224)
		(layer "In6.Cu")
		(net "P5E_CPU0_P3_TX_BUF_DN<5>")
	)
	(segment
		(start 385.437126 -411.024578)
		(end 387.139942 -411.633924)
		(width 0.14224)
		(layer "In6.Cu")
		(net "P5E_CPU0_P3_TX_BUF_DN<5>")
	)
	(segment
		(start 384.41249 -410.82087)
		(end 385.437126 -411.024578)
		(width 0.14224)
		(layer "In6.Cu")
		(net "P5E_CPU0_P3_TX_BUF_DN<5>")
	)
	(segment
		(start 376.990356 -398.56918)
		(end 376.990356 -398.782794)
		(width 0.14224)
		(layer "In6.Cu")
		(net "P5E_CPU0_P3_TX_BUF_DN<5>")
	)
	(segment
		(start 387.139942 -411.633924)
		(end 387.511798 -411.766766)
		(width 0.14224)
		(layer "In6.Cu")
		(net "P5E_CPU0_P3_TX_BUF_DN<5>")
	)
	(arc
		(start 376.625104 -397.890746)
		(mid 376.671836 -398.125682)
		(end 376.804936 -398.324832)
		(width 0.14224)
		(layer "In6.Cu")
		(net "P5E_CPU0_P3_TX_BUF_DN<5>")
	)
	(arc
		(start 376.990356 -398.782794)
		(mid 376.997992 -398.887043)
		(end 377.020836 -398.989042)
		(width 0.14224)
		(layer "In6.Cu")
		(net "P5E_CPU0_P3_TX_BUF_DN<5>")
	)
	(arc
		(start 377.353322 -400.085306)
		(mid 377.367205 -400.146978)
		(end 377.371864 -400.21002)
		(width 0.14224)
		(layer "In6.Cu")
		(net "P5E_CPU0_P3_TX_BUF_DN<5>")
	)
	(arc
		(start 382.188974 -409.632404)
		(mid 383.21257 -410.391582)
		(end 384.41249 -410.82087)
		(width 0.14224)
		(layer "In6.Cu")
		(net "P5E_CPU0_P3_TX_BUF_DN<5>")
	)
	(arc
		(start 387.831076 -412.008574)
		(mid 387.980347 -412.231974)
		(end 388.032752 -412.495492)
		(width 0.14224)
		(layer "In6.Cu")
		(net "P5E_CPU0_P3_TX_BUF_DN<5>")
	)
	(arc
		(start 377.371864 -404.42134)
		(mid 377.444287 -404.785346)
		(end 377.650502 -405.093932)
		(width 0.14224)
		(layer "In6.Cu")
		(net "P5E_CPU0_P3_TX_BUF_DN<5>")
	)
	(arc
		(start 376.948446 -398.468342)
		(mid 376.979413 -398.514593)
		(end 376.990356 -398.56918)
		(width 0.14224)
		(layer "In6.Cu")
		(net "P5E_CPU0_P3_TX_BUF_DN<5>")
	)
	(segment
		(start 375.170446 -397.156432)
		(end 375.691146 -397.156432)
		(width 0.127)
		(layer "F.Cu")
		(net "P5E_CPU0_P3_TX_BUF_DN<4>")
	)
	(segment
		(start 384.949192 -415.65703)
		(end 384.678682 -415.38652)
		(width 0.12954)
		(layer "B.Cu")
		(net "P5E_CPU0_P3_TX_BUF_DN<4>")
	)
	(segment
		(start 384.653282 -416.632644)
		(end 384.949192 -416.336734)
		(width 0.12954)
		(layer "B.Cu")
		(net "P5E_CPU0_P3_TX_BUF_DN<4>")
	)
	(segment
		(start 384.949192 -416.336734)
		(end 384.949192 -415.65703)
		(width 0.12954)
		(layer "B.Cu")
		(net "P5E_CPU0_P3_TX_BUF_DN<4>")
	)
	(segment
		(start 376.446796 -405.448516)
		(end 381.910844 -410.912564)
		(width 0.14224)
		(layer "In6.Cu")
		(net "P5E_CPU0_P3_TX_BUF_DN<4>")
	)
	(segment
		(start 384.969512 -415.09569)
		(end 384.678682 -415.38652)
		(width 0.14224)
		(layer "In6.Cu")
		(net "P5E_CPU0_P3_TX_BUF_DN<4>")
	)
	(segment
		(start 381.910844 -410.912564)
		(end 382.732026 -411.461458)
		(width 0.14224)
		(layer "In6.Cu")
		(net "P5E_CPU0_P3_TX_BUF_DN<4>")
	)
	(segment
		(start 375.74347 -397.388588)
		(end 375.424954 -397.707104)
		(width 0.14224)
		(layer "In6.Cu")
		(net "P5E_CPU0_P3_TX_BUF_DN<4>")
	)
	(segment
		(start 384.653536 -411.94355)
		(end 384.75158 -412.041594)
		(width 0.14224)
		(layer "In6.Cu")
		(net "P5E_CPU0_P3_TX_BUF_DN<4>")
	)
	(segment
		(start 375.74347 -397.208756)
		(end 375.74347 -397.388588)
		(width 0.14224)
		(layer "In6.Cu")
		(net "P5E_CPU0_P3_TX_BUF_DN<4>")
	)
	(segment
		(start 382.732026 -411.461458)
		(end 383.21234 -411.607)
		(width 0.14224)
		(layer "In6.Cu")
		(net "P5E_CPU0_P3_TX_BUF_DN<4>")
	)
	(segment
		(start 376.171714 -400.17827)
		(end 376.171714 -404.78456)
		(width 0.14224)
		(layer "In6.Cu")
		(net "P5E_CPU0_P3_TX_BUF_DN<4>")
	)
	(segment
		(start 375.609612 -398.329658)
		(end 375.748296 -398.468342)
		(width 0.14224)
		(layer "In6.Cu")
		(net "P5E_CPU0_P3_TX_BUF_DN<4>")
	)
	(segment
		(start 375.691146 -397.156432)
		(end 375.74347 -397.208756)
		(width 0.14224)
		(layer "In6.Cu")
		(net "P5E_CPU0_P3_TX_BUF_DN<4>")
	)
	(segment
		(start 384.969512 -412.567628)
		(end 384.969512 -415.09569)
		(width 0.14224)
		(layer "In6.Cu")
		(net "P5E_CPU0_P3_TX_BUF_DN<4>")
	)
	(segment
		(start 375.424954 -397.707104)
		(end 375.424954 -397.883888)
		(width 0.14224)
		(layer "In6.Cu")
		(net "P5E_CPU0_P3_TX_BUF_DN<4>")
	)
	(segment
		(start 383.21234 -411.607)
		(end 384.309874 -411.770322)
		(width 0.14224)
		(layer "In6.Cu")
		(net "P5E_CPU0_P3_TX_BUF_DN<4>")
	)
	(segment
		(start 375.785634 -398.558004)
		(end 375.785634 -398.735296)
		(width 0.14224)
		(layer "In6.Cu")
		(net "P5E_CPU0_P3_TX_BUF_DN<4>")
	)
	(segment
		(start 375.816114 -398.942306)
		(end 376.153172 -400.053556)
		(width 0.14224)
		(layer "In6.Cu")
		(net "P5E_CPU0_P3_TX_BUF_DN<4>")
	)
	(arc
		(start 375.785634 -398.735296)
		(mid 375.793216 -398.839929)
		(end 375.816114 -398.942306)
		(width 0.14224)
		(layer "In6.Cu")
		(net "P5E_CPU0_P3_TX_BUF_DN<4>")
	)
	(arc
		(start 376.153172 -400.053556)
		(mid 376.167055 -400.115228)
		(end 376.171714 -400.17827)
		(width 0.14224)
		(layer "In6.Cu")
		(net "P5E_CPU0_P3_TX_BUF_DN<4>")
	)
	(arc
		(start 376.171714 -404.78456)
		(mid 376.243209 -405.1439)
		(end 376.446796 -405.448516)
		(width 0.14224)
		(layer "In6.Cu")
		(net "P5E_CPU0_P3_TX_BUF_DN<4>")
	)
	(arc
		(start 384.309874 -411.770322)
		(mid 384.495603 -411.829346)
		(end 384.653536 -411.94355)
		(width 0.14224)
		(layer "In6.Cu")
		(net "P5E_CPU0_P3_TX_BUF_DN<4>")
	)
	(arc
		(start 375.424954 -397.883888)
		(mid 375.472942 -398.125142)
		(end 375.609612 -398.329658)
		(width 0.14224)
		(layer "In6.Cu")
		(net "P5E_CPU0_P3_TX_BUF_DN<4>")
	)
	(arc
		(start 384.75158 -412.041594)
		(mid 384.912896 -412.282926)
		(end 384.969512 -412.567628)
		(width 0.14224)
		(layer "In6.Cu")
		(net "P5E_CPU0_P3_TX_BUF_DN<4>")
	)
	(arc
		(start 375.748296 -398.468342)
		(mid 375.775866 -398.509464)
		(end 375.785634 -398.558004)
		(width 0.14224)
		(layer "In6.Cu")
		(net "P5E_CPU0_P3_TX_BUF_DN<4>")
	)
	(segment
		(start 373.97055 -397.156432)
		(end 374.49125 -397.156432)
		(width 0.127)
		(layer "F.Cu")
		(net "P5E_CPU0_P3_TX_BUF_DN<3>")
	)
	(segment
		(start 381.885952 -415.65703)
		(end 381.615442 -415.38652)
		(width 0.12954)
		(layer "B.Cu")
		(net "P5E_CPU0_P3_TX_BUF_DN<3>")
	)
	(segment
		(start 381.885952 -416.336734)
		(end 381.885952 -415.65703)
		(width 0.12954)
		(layer "B.Cu")
		(net "P5E_CPU0_P3_TX_BUF_DN<3>")
	)
	(segment
		(start 381.590042 -416.632644)
		(end 381.885952 -416.336734)
		(width 0.12954)
		(layer "B.Cu")
		(net "P5E_CPU0_P3_TX_BUF_DN<3>")
	)
	(segment
		(start 374.924066 -400.014694)
		(end 374.96242 -400.267932)
		(width 0.14224)
		(layer "In6.Cu")
		(net "P5E_CPU0_P3_TX_BUF_DN<3>")
	)
	(segment
		(start 374.543574 -397.208756)
		(end 374.543574 -397.388588)
		(width 0.14224)
		(layer "In6.Cu")
		(net "P5E_CPU0_P3_TX_BUF_DN<3>")
	)
	(segment
		(start 381.906272 -415.09569)
		(end 381.615442 -415.38652)
		(width 0.14224)
		(layer "In6.Cu")
		(net "P5E_CPU0_P3_TX_BUF_DN<3>")
	)
	(segment
		(start 374.585738 -398.558512)
		(end 374.585738 -398.760442)
		(width 0.14224)
		(layer "In6.Cu")
		(net "P5E_CPU0_P3_TX_BUF_DN<3>")
	)
	(segment
		(start 374.225058 -397.707104)
		(end 374.225058 -397.918686)
		(width 0.14224)
		(layer "In6.Cu")
		(net "P5E_CPU0_P3_TX_BUF_DN<3>")
	)
	(segment
		(start 374.385078 -398.30502)
		(end 374.5484 -398.468342)
		(width 0.14224)
		(layer "In6.Cu")
		(net "P5E_CPU0_P3_TX_BUF_DN<3>")
	)
	(segment
		(start 374.616218 -398.966436)
		(end 374.89638 -399.89125)
		(width 0.14224)
		(layer "In6.Cu")
		(net "P5E_CPU0_P3_TX_BUF_DN<3>")
	)
	(segment
		(start 374.543574 -397.388588)
		(end 374.225058 -397.707104)
		(width 0.14224)
		(layer "In6.Cu")
		(net "P5E_CPU0_P3_TX_BUF_DN<3>")
	)
	(segment
		(start 374.971818 -400.39417)
		(end 374.971818 -405.065992)
		(width 0.14224)
		(layer "In6.Cu")
		(net "P5E_CPU0_P3_TX_BUF_DN<3>")
	)
	(segment
		(start 381.906272 -412.637986)
		(end 381.906272 -415.09569)
		(width 0.14224)
		(layer "In6.Cu")
		(net "P5E_CPU0_P3_TX_BUF_DN<3>")
	)
	(segment
		(start 374.49125 -397.156432)
		(end 374.543574 -397.208756)
		(width 0.14224)
		(layer "In6.Cu")
		(net "P5E_CPU0_P3_TX_BUF_DN<3>")
	)
	(segment
		(start 375.192036 -405.597868)
		(end 381.67564 -412.081472)
		(width 0.14224)
		(layer "In6.Cu")
		(net "P5E_CPU0_P3_TX_BUF_DN<3>")
	)
	(arc
		(start 374.89638 -399.89125)
		(mid 374.912449 -399.952473)
		(end 374.924066 -400.014694)
		(width 0.14224)
		(layer "In6.Cu")
		(net "P5E_CPU0_P3_TX_BUF_DN<3>")
	)
	(arc
		(start 381.67564 -412.081472)
		(mid 381.84633 -412.336788)
		(end 381.906272 -412.637986)
		(width 0.14224)
		(layer "In6.Cu")
		(net "P5E_CPU0_P3_TX_BUF_DN<3>")
	)
	(arc
		(start 374.585738 -398.760442)
		(mid 374.593393 -398.864562)
		(end 374.616218 -398.966436)
		(width 0.14224)
		(layer "In6.Cu")
		(net "P5E_CPU0_P3_TX_BUF_DN<3>")
	)
	(arc
		(start 374.225058 -397.918686)
		(mid 374.266647 -398.127767)
		(end 374.385078 -398.30502)
		(width 0.14224)
		(layer "In6.Cu")
		(net "P5E_CPU0_P3_TX_BUF_DN<3>")
	)
	(arc
		(start 374.971818 -405.065992)
		(mid 375.029053 -405.35382)
		(end 375.192036 -405.597868)
		(width 0.14224)
		(layer "In6.Cu")
		(net "P5E_CPU0_P3_TX_BUF_DN<3>")
	)
	(arc
		(start 374.96242 -400.267932)
		(mid 374.969498 -400.330874)
		(end 374.971818 -400.39417)
		(width 0.14224)
		(layer "In6.Cu")
		(net "P5E_CPU0_P3_TX_BUF_DN<3>")
	)
	(arc
		(start 374.5484 -398.468342)
		(mid 374.576043 -398.509712)
		(end 374.585738 -398.558512)
		(width 0.14224)
		(layer "In6.Cu")
		(net "P5E_CPU0_P3_TX_BUF_DN<3>")
	)
	(segment
		(start 372.770654 -397.156432)
		(end 373.291354 -397.156432)
		(width 0.127)
		(layer "F.Cu")
		(net "P5E_CPU0_P3_TX_BUF_DN<2>")
	)
	(segment
		(start 378.822712 -416.336734)
		(end 378.822712 -415.65703)
		(width 0.12954)
		(layer "B.Cu")
		(net "P5E_CPU0_P3_TX_BUF_DN<2>")
	)
	(segment
		(start 378.526802 -416.632644)
		(end 378.822712 -416.336734)
		(width 0.12954)
		(layer "B.Cu")
		(net "P5E_CPU0_P3_TX_BUF_DN<2>")
	)
	(segment
		(start 378.822712 -415.65703)
		(end 378.552202 -415.38652)
		(width 0.12954)
		(layer "B.Cu")
		(net "P5E_CPU0_P3_TX_BUF_DN<2>")
	)
	(segment
		(start 373.343678 -397.412972)
		(end 373.024908 -397.731742)
		(width 0.14224)
		(layer "In6.Cu")
		(net "P5E_CPU0_P3_TX_BUF_DN<2>")
	)
	(segment
		(start 373.4435 -399.066258)
		(end 373.75338 -400.085814)
		(width 0.14224)
		(layer "In6.Cu")
		(net "P5E_CPU0_P3_TX_BUF_DN<2>")
	)
	(segment
		(start 373.200676 -398.321022)
		(end 373.348758 -398.469104)
		(width 0.14224)
		(layer "In6.Cu")
		(net "P5E_CPU0_P3_TX_BUF_DN<2>")
	)
	(segment
		(start 377.849638 -410.463492)
		(end 378.49429 -411.249368)
		(width 0.14224)
		(layer "In6.Cu")
		(net "P5E_CPU0_P3_TX_BUF_DN<2>")
	)
	(segment
		(start 378.843032 -415.09569)
		(end 378.552202 -415.38652)
		(width 0.14224)
		(layer "In6.Cu")
		(net "P5E_CPU0_P3_TX_BUF_DN<2>")
	)
	(segment
		(start 377.849384 -410.463492)
		(end 377.849638 -410.463492)
		(width 0.14224)
		(layer "In6.Cu")
		(net "P5E_CPU0_P3_TX_BUF_DN<2>")
	)
	(segment
		(start 373.343678 -397.208756)
		(end 373.343678 -397.412972)
		(width 0.14224)
		(layer "In6.Cu")
		(net "P5E_CPU0_P3_TX_BUF_DN<2>")
	)
	(segment
		(start 373.291354 -397.156432)
		(end 373.343678 -397.208756)
		(width 0.14224)
		(layer "In6.Cu")
		(net "P5E_CPU0_P3_TX_BUF_DN<2>")
	)
	(segment
		(start 374.035574 -405.816308)
		(end 377.849384 -410.463492)
		(width 0.14224)
		(layer "In6.Cu")
		(net "P5E_CPU0_P3_TX_BUF_DN<2>")
	)
	(segment
		(start 373.41302 -398.624298)
		(end 373.41302 -398.859756)
		(width 0.14224)
		(layer "In6.Cu")
		(net "P5E_CPU0_P3_TX_BUF_DN<2>")
	)
	(segment
		(start 373.771922 -400.210528)
		(end 373.771922 -405.079454)
		(width 0.14224)
		(layer "In6.Cu")
		(net "P5E_CPU0_P3_TX_BUF_DN<2>")
	)
	(segment
		(start 378.843032 -412.223204)
		(end 378.843032 -415.09569)
		(width 0.14224)
		(layer "In6.Cu")
		(net "P5E_CPU0_P3_TX_BUF_DN<2>")
	)
	(segment
		(start 373.024908 -397.731742)
		(end 373.024908 -397.896588)
		(width 0.14224)
		(layer "In6.Cu")
		(net "P5E_CPU0_P3_TX_BUF_DN<2>")
	)
	(arc
		(start 373.75338 -400.085814)
		(mid 373.767251 -400.147487)
		(end 373.771922 -400.210528)
		(width 0.14224)
		(layer "In6.Cu")
		(net "P5E_CPU0_P3_TX_BUF_DN<2>")
	)
	(arc
		(start 373.771922 -405.079454)
		(mid 373.839818 -405.470757)
		(end 374.035574 -405.816308)
		(width 0.14224)
		(layer "In6.Cu")
		(net "P5E_CPU0_P3_TX_BUF_DN<2>")
	)
	(arc
		(start 373.41302 -398.859756)
		(mid 373.420643 -398.964132)
		(end 373.4435 -399.066258)
		(width 0.14224)
		(layer "In6.Cu")
		(net "P5E_CPU0_P3_TX_BUF_DN<2>")
	)
	(arc
		(start 373.024908 -397.896588)
		(mid 373.070581 -398.12629)
		(end 373.200676 -398.321022)
		(width 0.14224)
		(layer "In6.Cu")
		(net "P5E_CPU0_P3_TX_BUF_DN<2>")
	)
	(arc
		(start 373.348758 -398.469104)
		(mid 373.396335 -398.540308)
		(end 373.41302 -398.624298)
		(width 0.14224)
		(layer "In6.Cu")
		(net "P5E_CPU0_P3_TX_BUF_DN<2>")
	)
	(arc
		(start 378.49429 -411.249368)
		(mid 378.753141 -411.706034)
		(end 378.843032 -412.223204)
		(width 0.14224)
		(layer "In6.Cu")
		(net "P5E_CPU0_P3_TX_BUF_DN<2>")
	)
	(segment
		(start 371.570504 -397.156432)
		(end 372.091204 -397.156432)
		(width 0.127)
		(layer "F.Cu")
		(net "P5E_CPU0_P3_TX_BUF_DN<1>")
	)
	(segment
		(start 375.759472 -415.65703)
		(end 375.488962 -415.38652)
		(width 0.12954)
		(layer "B.Cu")
		(net "P5E_CPU0_P3_TX_BUF_DN<1>")
	)
	(segment
		(start 375.463562 -416.632644)
		(end 375.759472 -416.336734)
		(width 0.12954)
		(layer "B.Cu")
		(net "P5E_CPU0_P3_TX_BUF_DN<1>")
	)
	(segment
		(start 375.759472 -416.336734)
		(end 375.759472 -415.65703)
		(width 0.12954)
		(layer "B.Cu")
		(net "P5E_CPU0_P3_TX_BUF_DN<1>")
	)
	(segment
		(start 371.825012 -397.707104)
		(end 371.825012 -397.91005)
		(width 0.14224)
		(layer "In6.Cu")
		(net "P5E_CPU0_P3_TX_BUF_DN<1>")
	)
	(segment
		(start 371.991128 -398.311116)
		(end 372.148354 -398.468342)
		(width 0.14224)
		(layer "In6.Cu")
		(net "P5E_CPU0_P3_TX_BUF_DN<1>")
	)
	(segment
		(start 372.571772 -405.255984)
		(end 373.316246 -406.83053)
		(width 0.14224)
		(layer "In6.Cu")
		(net "P5E_CPU0_P3_TX_BUF_DN<1>")
	)
	(segment
		(start 372.185692 -398.558004)
		(end 372.185692 -398.91335)
		(width 0.14224)
		(layer "In6.Cu")
		(net "P5E_CPU0_P3_TX_BUF_DN<1>")
	)
	(segment
		(start 372.143528 -397.208756)
		(end 372.143528 -397.388588)
		(width 0.14224)
		(layer "In6.Cu")
		(net "P5E_CPU0_P3_TX_BUF_DN<1>")
	)
	(segment
		(start 372.143528 -397.388588)
		(end 371.825012 -397.707104)
		(width 0.14224)
		(layer "In6.Cu")
		(net "P5E_CPU0_P3_TX_BUF_DN<1>")
	)
	(segment
		(start 372.246398 -399.30832)
		(end 372.571772 -400.092164)
		(width 0.14224)
		(layer "In6.Cu")
		(net "P5E_CPU0_P3_TX_BUF_DN<1>")
	)
	(segment
		(start 373.316246 -406.83053)
		(end 373.3165 -406.830784)
		(width 0.14224)
		(layer "In6.Cu")
		(net "P5E_CPU0_P3_TX_BUF_DN<1>")
	)
	(segment
		(start 373.3165 -406.830784)
		(end 375.779792 -412.039308)
		(width 0.14224)
		(layer "In6.Cu")
		(net "P5E_CPU0_P3_TX_BUF_DN<1>")
	)
	(segment
		(start 372.571772 -400.092164)
		(end 372.571772 -405.255984)
		(width 0.14224)
		(layer "In6.Cu")
		(net "P5E_CPU0_P3_TX_BUF_DN<1>")
	)
	(segment
		(start 375.779792 -415.09569)
		(end 375.488962 -415.38652)
		(width 0.14224)
		(layer "In6.Cu")
		(net "P5E_CPU0_P3_TX_BUF_DN<1>")
	)
	(segment
		(start 372.091204 -397.156432)
		(end 372.143528 -397.208756)
		(width 0.14224)
		(layer "In6.Cu")
		(net "P5E_CPU0_P3_TX_BUF_DN<1>")
	)
	(segment
		(start 375.779792 -412.039308)
		(end 375.779792 -415.09569)
		(width 0.14224)
		(layer "In6.Cu")
		(net "P5E_CPU0_P3_TX_BUF_DN<1>")
	)
	(arc
		(start 372.148354 -398.468342)
		(mid 372.175924 -398.509464)
		(end 372.185692 -398.558004)
		(width 0.14224)
		(layer "In6.Cu")
		(net "P5E_CPU0_P3_TX_BUF_DN<1>")
	)
	(arc
		(start 372.185692 -398.91335)
		(mid 372.200919 -399.11316)
		(end 372.246398 -399.30832)
		(width 0.14224)
		(layer "In6.Cu")
		(net "P5E_CPU0_P3_TX_BUF_DN<1>")
	)
	(arc
		(start 371.825012 -397.91005)
		(mid 371.868186 -398.127101)
		(end 371.991128 -398.311116)
		(width 0.14224)
		(layer "In6.Cu")
		(net "P5E_CPU0_P3_TX_BUF_DN<1>")
	)
	(segment
		(start 388.370572 -397.156432)
		(end 388.891272 -397.156432)
		(width 0.127)
		(layer "F.Cu")
		(net "P5E_CPU0_P3_TX_BUF_DN<15>")
	)
	(segment
		(start 418.644832 -415.65703)
		(end 418.374322 -415.38652)
		(width 0.12954)
		(layer "B.Cu")
		(net "P5E_CPU0_P3_TX_BUF_DN<15>")
	)
	(segment
		(start 418.644832 -416.336734)
		(end 418.644832 -415.65703)
		(width 0.12954)
		(layer "B.Cu")
		(net "P5E_CPU0_P3_TX_BUF_DN<15>")
	)
	(segment
		(start 418.348922 -416.632644)
		(end 418.644832 -416.336734)
		(width 0.12954)
		(layer "B.Cu")
		(net "P5E_CPU0_P3_TX_BUF_DN<15>")
	)
	(segment
		(start 395.783562 -403.7076)
		(end 406.967182 -406.80259)
		(width 0.14224)
		(layer "In6.Cu")
		(net "P5E_CPU0_P3_TX_BUF_DN<15>")
	)
	(segment
		(start 391.73277 -402.58619)
		(end 395.783562 -403.707346)
		(width 0.14224)
		(layer "In6.Cu")
		(net "P5E_CPU0_P3_TX_BUF_DN<15>")
	)
	(segment
		(start 389.96112 -401.479766)
		(end 390.137904 -401.65655)
		(width 0.14224)
		(layer "In6.Cu")
		(net "P5E_CPU0_P3_TX_BUF_DN<15>")
	)
	(segment
		(start 388.943596 -397.388588)
		(end 388.62508 -397.707104)
		(width 0.14224)
		(layer "In6.Cu")
		(net "P5E_CPU0_P3_TX_BUF_DN<15>")
	)
	(segment
		(start 389.372348 -399.477738)
		(end 389.518144 -399.959068)
		(width 0.14224)
		(layer "In6.Cu")
		(net "P5E_CPU0_P3_TX_BUF_DN<15>")
	)
	(segment
		(start 388.943596 -397.208756)
		(end 388.943596 -397.388588)
		(width 0.14224)
		(layer "In6.Cu")
		(net "P5E_CPU0_P3_TX_BUF_DN<15>")
	)
	(segment
		(start 418.693346 -413.097726)
		(end 418.693346 -415.067496)
		(width 0.14224)
		(layer "In6.Cu")
		(net "P5E_CPU0_P3_TX_BUF_DN<15>")
	)
	(segment
		(start 406.967182 -406.80259)
		(end 417.49599 -411.164024)
		(width 0.14224)
		(layer "In6.Cu")
		(net "P5E_CPU0_P3_TX_BUF_DN<15>")
	)
	(segment
		(start 388.62508 -397.707104)
		(end 388.62508 -397.902176)
		(width 0.14224)
		(layer "In6.Cu")
		(net "P5E_CPU0_P3_TX_BUF_DN<15>")
	)
	(segment
		(start 388.994904 -398.549368)
		(end 389.329676 -399.358612)
		(width 0.14224)
		(layer "In6.Cu")
		(net "P5E_CPU0_P3_TX_BUF_DN<15>")
	)
	(segment
		(start 389.536686 -400.083782)
		(end 389.536686 -400.416268)
		(width 0.14224)
		(layer "In6.Cu")
		(net "P5E_CPU0_P3_TX_BUF_DN<15>")
	)
	(segment
		(start 388.891272 -397.156432)
		(end 388.943596 -397.208756)
		(width 0.14224)
		(layer "In6.Cu")
		(net "P5E_CPU0_P3_TX_BUF_DN<15>")
	)
	(segment
		(start 418.230558 -411.766766)
		(end 418.338254 -411.928056)
		(width 0.14224)
		(layer "In6.Cu")
		(net "P5E_CPU0_P3_TX_BUF_DN<15>")
	)
	(segment
		(start 418.693346 -415.067496)
		(end 418.374322 -415.38652)
		(width 0.14224)
		(layer "In6.Cu")
		(net "P5E_CPU0_P3_TX_BUF_DN<15>")
	)
	(segment
		(start 395.783562 -403.707346)
		(end 395.783562 -403.7076)
		(width 0.14224)
		(layer "In6.Cu")
		(net "P5E_CPU0_P3_TX_BUF_DN<15>")
	)
	(segment
		(start 388.796784 -398.316704)
		(end 388.9248 -398.44472)
		(width 0.14224)
		(layer "In6.Cu")
		(net "P5E_CPU0_P3_TX_BUF_DN<15>")
	)
	(segment
		(start 389.58266 -400.647154)
		(end 389.87222 -401.346924)
		(width 0.14224)
		(layer "In6.Cu")
		(net "P5E_CPU0_P3_TX_BUF_DN<15>")
	)
	(arc
		(start 388.9248 -398.44472)
		(mid 388.948688 -398.471298)
		(end 388.969504 -398.500346)
		(width 0.14224)
		(layer "In6.Cu")
		(net "P5E_CPU0_P3_TX_BUF_DN<15>")
	)
	(arc
		(start 388.62508 -397.902176)
		(mid 388.669704 -398.126517)
		(end 388.796784 -398.316704)
		(width 0.14224)
		(layer "In6.Cu")
		(net "P5E_CPU0_P3_TX_BUF_DN<15>")
	)
	(arc
		(start 388.969504 -398.500346)
		(mid 388.983259 -398.524311)
		(end 388.994904 -398.549368)
		(width 0.14224)
		(layer "In6.Cu")
		(net "P5E_CPU0_P3_TX_BUF_DN<15>")
	)
	(arc
		(start 389.518144 -399.959068)
		(mid 389.532002 -400.020743)
		(end 389.536686 -400.083782)
		(width 0.14224)
		(layer "In6.Cu")
		(net "P5E_CPU0_P3_TX_BUF_DN<15>")
	)
	(arc
		(start 389.329676 -399.358612)
		(mid 389.352474 -399.417651)
		(end 389.372348 -399.477738)
		(width 0.14224)
		(layer "In6.Cu")
		(net "P5E_CPU0_P3_TX_BUF_DN<15>")
	)
	(arc
		(start 389.87222 -401.346924)
		(mid 389.91013 -401.417721)
		(end 389.96112 -401.479766)
		(width 0.14224)
		(layer "In6.Cu")
		(net "P5E_CPU0_P3_TX_BUF_DN<15>")
	)
	(arc
		(start 418.338254 -411.928056)
		(mid 418.60263 -412.486532)
		(end 418.693346 -413.097726)
		(width 0.14224)
		(layer "In6.Cu")
		(net "P5E_CPU0_P3_TX_BUF_DN<15>")
	)
	(arc
		(start 417.49599 -411.164024)
		(mid 417.907981 -411.410918)
		(end 418.230558 -411.766766)
		(width 0.14224)
		(layer "In6.Cu")
		(net "P5E_CPU0_P3_TX_BUF_DN<15>")
	)
	(arc
		(start 389.536686 -400.416268)
		(mid 389.548307 -400.533976)
		(end 389.58266 -400.647154)
		(width 0.14224)
		(layer "In6.Cu")
		(net "P5E_CPU0_P3_TX_BUF_DN<15>")
	)
	(arc
		(start 390.137904 -401.65655)
		(mid 390.875111 -402.224693)
		(end 391.73277 -402.58619)
		(width 0.14224)
		(layer "In6.Cu")
		(net "P5E_CPU0_P3_TX_BUF_DN<15>")
	)
	(segment
		(start 387.170676 -397.156432)
		(end 387.691376 -397.156432)
		(width 0.127)
		(layer "F.Cu")
		(net "P5E_CPU0_P3_TX_BUF_DN<14>")
	)
	(segment
		(start 415.581592 -415.65703)
		(end 415.311082 -415.38652)
		(width 0.12954)
		(layer "B.Cu")
		(net "P5E_CPU0_P3_TX_BUF_DN<14>")
	)
	(segment
		(start 415.581592 -416.336734)
		(end 415.581592 -415.65703)
		(width 0.12954)
		(layer "B.Cu")
		(net "P5E_CPU0_P3_TX_BUF_DN<14>")
	)
	(segment
		(start 415.285682 -416.632644)
		(end 415.581592 -416.336734)
		(width 0.12954)
		(layer "B.Cu")
		(net "P5E_CPU0_P3_TX_BUF_DN<14>")
	)
	(segment
		(start 387.61543 -398.3355)
		(end 387.692392 -398.412462)
		(width 0.14224)
		(layer "In6.Cu")
		(net "P5E_CPU0_P3_TX_BUF_DN<14>")
	)
	(segment
		(start 388.301738 -402.75637)
		(end 388.49427 -402.948902)
		(width 0.14224)
		(layer "In6.Cu")
		(net "P5E_CPU0_P3_TX_BUF_DN<14>")
	)
	(segment
		(start 387.736588 -397.201644)
		(end 387.736588 -397.381476)
		(width 0.14224)
		(layer "In6.Cu")
		(net "P5E_CPU0_P3_TX_BUF_DN<14>")
	)
	(segment
		(start 387.691376 -397.156432)
		(end 387.736588 -397.201644)
		(width 0.14224)
		(layer "In6.Cu")
		(net "P5E_CPU0_P3_TX_BUF_DN<14>")
	)
	(segment
		(start 387.736588 -397.381476)
		(end 387.417056 -397.701008)
		(width 0.14224)
		(layer "In6.Cu")
		(net "P5E_CPU0_P3_TX_BUF_DN<14>")
	)
	(segment
		(start 406.4762 -408.064716)
		(end 411.432502 -410.117798)
		(width 0.14224)
		(layer "In6.Cu")
		(net "P5E_CPU0_P3_TX_BUF_DN<14>")
	)
	(segment
		(start 388.171944 -400.35988)
		(end 388.171944 -402.442934)
		(width 0.14224)
		(layer "In6.Cu")
		(net "P5E_CPU0_P3_TX_BUF_DN<14>")
	)
	(segment
		(start 387.86435 -398.93748)
		(end 388.157974 -400.23415)
		(width 0.14224)
		(layer "In6.Cu")
		(net "P5E_CPU0_P3_TX_BUF_DN<14>")
	)
	(segment
		(start 415.601912 -412.519622)
		(end 415.601912 -415.09569)
		(width 0.14224)
		(layer "In6.Cu")
		(net "P5E_CPU0_P3_TX_BUF_DN<14>")
	)
	(segment
		(start 396.346426 -404.992078)
		(end 406.4762 -408.064716)
		(width 0.14224)
		(layer "In6.Cu")
		(net "P5E_CPU0_P3_TX_BUF_DN<14>")
	)
	(segment
		(start 388.734046 -403.084792)
		(end 396.346426 -404.992078)
		(width 0.14224)
		(layer "In6.Cu")
		(net "P5E_CPU0_P3_TX_BUF_DN<14>")
	)
	(segment
		(start 387.815074 -398.654016)
		(end 387.836918 -398.794478)
		(width 0.14224)
		(layer "In6.Cu")
		(net "P5E_CPU0_P3_TX_BUF_DN<14>")
	)
	(segment
		(start 387.417056 -397.701008)
		(end 387.417056 -397.856456)
		(width 0.14224)
		(layer "In6.Cu")
		(net "P5E_CPU0_P3_TX_BUF_DN<14>")
	)
	(segment
		(start 411.432502 -410.117798)
		(end 411.432756 -410.117798)
		(width 0.14224)
		(layer "In6.Cu")
		(net "P5E_CPU0_P3_TX_BUF_DN<14>")
	)
	(segment
		(start 415.601912 -415.09569)
		(end 415.311082 -415.38652)
		(width 0.14224)
		(layer "In6.Cu")
		(net "P5E_CPU0_P3_TX_BUF_DN<14>")
	)
	(segment
		(start 411.432756 -410.117798)
		(end 414.978342 -411.586426)
		(width 0.14224)
		(layer "In6.Cu")
		(net "P5E_CPU0_P3_TX_BUF_DN<14>")
	)
	(arc
		(start 387.692392 -398.412462)
		(mid 387.772952 -398.523481)
		(end 387.815074 -398.654016)
		(width 0.14224)
		(layer "In6.Cu")
		(net "P5E_CPU0_P3_TX_BUF_DN<14>")
	)
	(arc
		(start 414.978342 -411.586426)
		(mid 415.431634 -411.958457)
		(end 415.601912 -412.519622)
		(width 0.14224)
		(layer "In6.Cu")
		(net "P5E_CPU0_P3_TX_BUF_DN<14>")
	)
	(arc
		(start 387.417056 -397.856456)
		(mid 387.468606 -398.115707)
		(end 387.61543 -398.3355)
		(width 0.14224)
		(layer "In6.Cu")
		(net "P5E_CPU0_P3_TX_BUF_DN<14>")
	)
	(arc
		(start 388.157974 -400.23415)
		(mid 388.16846 -400.296626)
		(end 388.171944 -400.35988)
		(width 0.14224)
		(layer "In6.Cu")
		(net "P5E_CPU0_P3_TX_BUF_DN<14>")
	)
	(arc
		(start 387.836918 -398.794478)
		(mid 387.849427 -398.866211)
		(end 387.86435 -398.93748)
		(width 0.14224)
		(layer "In6.Cu")
		(net "P5E_CPU0_P3_TX_BUF_DN<14>")
	)
	(arc
		(start 388.171944 -402.442934)
		(mid 388.205683 -402.612551)
		(end 388.301738 -402.75637)
		(width 0.14224)
		(layer "In6.Cu")
		(net "P5E_CPU0_P3_TX_BUF_DN<14>")
	)
	(arc
		(start 388.49427 -402.948902)
		(mid 388.604924 -403.03314)
		(end 388.734046 -403.084792)
		(width 0.14224)
		(layer "In6.Cu")
		(net "P5E_CPU0_P3_TX_BUF_DN<14>")
	)
	(segment
		(start 385.970526 -397.156432)
		(end 386.491226 -397.156432)
		(width 0.127)
		(layer "F.Cu")
		(net "P5E_CPU0_P3_TX_BUF_DN<13>")
	)
	(segment
		(start 412.222442 -416.632644)
		(end 412.518352 -416.336734)
		(width 0.12954)
		(layer "B.Cu")
		(net "P5E_CPU0_P3_TX_BUF_DN<13>")
	)
	(segment
		(start 412.518352 -415.65703)
		(end 412.247842 -415.38652)
		(width 0.12954)
		(layer "B.Cu")
		(net "P5E_CPU0_P3_TX_BUF_DN<13>")
	)
	(segment
		(start 412.518352 -416.336734)
		(end 412.518352 -415.65703)
		(width 0.12954)
		(layer "B.Cu")
		(net "P5E_CPU0_P3_TX_BUF_DN<13>")
	)
	(segment
		(start 386.491226 -397.156432)
		(end 386.54355 -397.208756)
		(width 0.14224)
		(layer "In6.Cu")
		(net "P5E_CPU0_P3_TX_BUF_DN<13>")
	)
	(segment
		(start 402.194776 -407.922222)
		(end 408.282394 -410.09951)
		(width 0.14224)
		(layer "In6.Cu")
		(net "P5E_CPU0_P3_TX_BUF_DN<13>")
	)
	(segment
		(start 412.538672 -412.420308)
		(end 412.538672 -415.09569)
		(width 0.14224)
		(layer "In6.Cu")
		(net "P5E_CPU0_P3_TX_BUF_DN<13>")
	)
	(segment
		(start 386.225034 -397.707104)
		(end 386.225034 -397.904462)
		(width 0.14224)
		(layer "In6.Cu")
		(net "P5E_CPU0_P3_TX_BUF_DN<13>")
	)
	(segment
		(start 386.54355 -397.208756)
		(end 386.54355 -397.388588)
		(width 0.14224)
		(layer "In6.Cu")
		(net "P5E_CPU0_P3_TX_BUF_DN<13>")
	)
	(segment
		(start 386.395214 -398.31518)
		(end 386.548376 -398.468342)
		(width 0.14224)
		(layer "In6.Cu")
		(net "P5E_CPU0_P3_TX_BUF_DN<13>")
	)
	(segment
		(start 393.797536 -405.31669)
		(end 401.139406 -407.544016)
		(width 0.14224)
		(layer "In6.Cu")
		(net "P5E_CPU0_P3_TX_BUF_DN<13>")
	)
	(segment
		(start 386.54355 -397.388588)
		(end 386.225034 -397.707104)
		(width 0.14224)
		(layer "In6.Cu")
		(net "P5E_CPU0_P3_TX_BUF_DN<13>")
	)
	(segment
		(start 386.585714 -398.558512)
		(end 386.585714 -398.812512)
		(width 0.14224)
		(layer "In6.Cu")
		(net "P5E_CPU0_P3_TX_BUF_DN<13>")
	)
	(segment
		(start 386.971794 -400.211544)
		(end 386.971794 -402.756878)
		(width 0.14224)
		(layer "In6.Cu")
		(net "P5E_CPU0_P3_TX_BUF_DN<13>")
	)
	(segment
		(start 411.010862 -411.22981)
		(end 411.011116 -411.22981)
		(width 0.14224)
		(layer "In6.Cu")
		(net "P5E_CPU0_P3_TX_BUF_DN<13>")
	)
	(segment
		(start 387.109462 -403.089364)
		(end 387.56844 -403.548342)
		(width 0.14224)
		(layer "In6.Cu")
		(net "P5E_CPU0_P3_TX_BUF_DN<13>")
	)
	(segment
		(start 411.011116 -411.22981)
		(end 412.023052 -411.64891)
		(width 0.14224)
		(layer "In6.Cu")
		(net "P5E_CPU0_P3_TX_BUF_DN<13>")
	)
	(segment
		(start 386.622036 -399.058638)
		(end 386.971794 -400.211544)
		(width 0.14224)
		(layer "In6.Cu")
		(net "P5E_CPU0_P3_TX_BUF_DN<13>")
	)
	(segment
		(start 401.139406 -407.544016)
		(end 402.19503 -407.921714)
		(width 0.14224)
		(layer "In6.Cu")
		(net "P5E_CPU0_P3_TX_BUF_DN<13>")
	)
	(segment
		(start 408.282394 -410.09951)
		(end 411.010862 -411.22981)
		(width 0.14224)
		(layer "In6.Cu")
		(net "P5E_CPU0_P3_TX_BUF_DN<13>")
	)
	(segment
		(start 388.2263 -403.92096)
		(end 393.797536 -405.31669)
		(width 0.14224)
		(layer "In6.Cu")
		(net "P5E_CPU0_P3_TX_BUF_DN<13>")
	)
	(segment
		(start 412.538672 -415.09569)
		(end 412.247842 -415.38652)
		(width 0.14224)
		(layer "In6.Cu")
		(net "P5E_CPU0_P3_TX_BUF_DN<13>")
	)
	(segment
		(start 402.19503 -407.921714)
		(end 402.194776 -407.922222)
		(width 0.14224)
		(layer "In6.Cu")
		(net "P5E_CPU0_P3_TX_BUF_DN<13>")
	)
	(arc
		(start 387.56844 -403.548342)
		(mid 387.872056 -403.77935)
		(end 388.2263 -403.92096)
		(width 0.14224)
		(layer "In6.Cu")
		(net "P5E_CPU0_P3_TX_BUF_DN<13>")
	)
	(arc
		(start 386.585714 -398.812512)
		(mid 386.594762 -398.936921)
		(end 386.622036 -399.058638)
		(width 0.14224)
		(layer "In6.Cu")
		(net "P5E_CPU0_P3_TX_BUF_DN<13>")
	)
	(arc
		(start 386.548376 -398.468342)
		(mid 386.576019 -398.509712)
		(end 386.585714 -398.558512)
		(width 0.14224)
		(layer "In6.Cu")
		(net "P5E_CPU0_P3_TX_BUF_DN<13>")
	)
	(arc
		(start 386.971794 -402.756878)
		(mid 387.007567 -402.936812)
		(end 387.109462 -403.089364)
		(width 0.14224)
		(layer "In6.Cu")
		(net "P5E_CPU0_P3_TX_BUF_DN<13>")
	)
	(arc
		(start 386.225034 -397.904462)
		(mid 386.269267 -398.126748)
		(end 386.395214 -398.31518)
		(width 0.14224)
		(layer "In6.Cu")
		(net "P5E_CPU0_P3_TX_BUF_DN<13>")
	)
	(arc
		(start 412.023052 -411.64891)
		(mid 412.397873 -411.95639)
		(end 412.538672 -412.420308)
		(width 0.14224)
		(layer "In6.Cu")
		(net "P5E_CPU0_P3_TX_BUF_DN<13>")
	)
	(segment
		(start 384.77063 -397.156432)
		(end 385.29133 -397.156432)
		(width 0.127)
		(layer "F.Cu")
		(net "P5E_CPU0_P3_TX_BUF_DN<12>")
	)
	(segment
		(start 409.455112 -415.65703)
		(end 409.184602 -415.38652)
		(width 0.12954)
		(layer "B.Cu")
		(net "P5E_CPU0_P3_TX_BUF_DN<12>")
	)
	(segment
		(start 409.455112 -416.336734)
		(end 409.455112 -415.65703)
		(width 0.12954)
		(layer "B.Cu")
		(net "P5E_CPU0_P3_TX_BUF_DN<12>")
	)
	(segment
		(start 409.159202 -416.632644)
		(end 409.455112 -416.336734)
		(width 0.12954)
		(layer "B.Cu")
		(net "P5E_CPU0_P3_TX_BUF_DN<12>")
	)
	(segment
		(start 385.510532 -399.401538)
		(end 385.771644 -400.031966)
		(width 0.14224)
		(layer "In6.Cu")
		(net "P5E_CPU0_P3_TX_BUF_DN<12>")
	)
	(segment
		(start 409.475432 -412.014924)
		(end 409.475432 -415.09569)
		(width 0.14224)
		(layer "In6.Cu")
		(net "P5E_CPU0_P3_TX_BUF_DN<12>")
	)
	(segment
		(start 387.342634 -404.704042)
		(end 392.889232 -406.094184)
		(width 0.14224)
		(layer "In6.Cu")
		(net "P5E_CPU0_P3_TX_BUF_DN<12>")
	)
	(segment
		(start 409.475432 -415.09569)
		(end 409.184602 -415.38652)
		(width 0.14224)
		(layer "In6.Cu")
		(net "P5E_CPU0_P3_TX_BUF_DN<12>")
	)
	(segment
		(start 385.771644 -400.031966)
		(end 385.771644 -403.095206)
		(width 0.14224)
		(layer "In6.Cu")
		(net "P5E_CPU0_P3_TX_BUF_DN<12>")
	)
	(segment
		(start 385.950714 -403.527514)
		(end 386.845556 -404.422356)
		(width 0.14224)
		(layer "In6.Cu")
		(net "P5E_CPU0_P3_TX_BUF_DN<12>")
	)
	(segment
		(start 402.227288 -408.927046)
		(end 409.396946 -411.897322)
		(width 0.14224)
		(layer "In6.Cu")
		(net "P5E_CPU0_P3_TX_BUF_DN<12>")
	)
	(segment
		(start 385.343654 -397.208756)
		(end 385.343654 -397.405352)
		(width 0.14224)
		(layer "In6.Cu")
		(net "P5E_CPU0_P3_TX_BUF_DN<12>")
	)
	(segment
		(start 385.025138 -397.723868)
		(end 385.025138 -397.92021)
		(width 0.14224)
		(layer "In6.Cu")
		(net "P5E_CPU0_P3_TX_BUF_DN<12>")
	)
	(segment
		(start 385.385564 -398.558512)
		(end 385.385564 -398.984216)
		(width 0.14224)
		(layer "In6.Cu")
		(net "P5E_CPU0_P3_TX_BUF_DN<12>")
	)
	(segment
		(start 392.889232 -406.094184)
		(end 402.227288 -408.927046)
		(width 0.14224)
		(layer "In6.Cu")
		(net "P5E_CPU0_P3_TX_BUF_DN<12>")
	)
	(segment
		(start 385.406138 -399.11147)
		(end 385.510532 -399.401538)
		(width 0.14224)
		(layer "In6.Cu")
		(net "P5E_CPU0_P3_TX_BUF_DN<12>")
	)
	(segment
		(start 385.343654 -397.405352)
		(end 385.025138 -397.723868)
		(width 0.14224)
		(layer "In6.Cu")
		(net "P5E_CPU0_P3_TX_BUF_DN<12>")
	)
	(segment
		(start 385.29133 -397.156432)
		(end 385.343654 -397.208756)
		(width 0.14224)
		(layer "In6.Cu")
		(net "P5E_CPU0_P3_TX_BUF_DN<12>")
	)
	(segment
		(start 385.184396 -398.304512)
		(end 385.348226 -398.468342)
		(width 0.14224)
		(layer "In6.Cu")
		(net "P5E_CPU0_P3_TX_BUF_DN<12>")
	)
	(arc
		(start 409.396946 -411.897322)
		(mid 409.454049 -411.944214)
		(end 409.475432 -412.014924)
		(width 0.14224)
		(layer "In6.Cu")
		(net "P5E_CPU0_P3_TX_BUF_DN<12>")
	)
	(arc
		(start 385.348226 -398.468342)
		(mid 385.375869 -398.509712)
		(end 385.385564 -398.558512)
		(width 0.14224)
		(layer "In6.Cu")
		(net "P5E_CPU0_P3_TX_BUF_DN<12>")
	)
	(arc
		(start 385.385564 -398.984216)
		(mid 385.390792 -399.048662)
		(end 385.406138 -399.11147)
		(width 0.14224)
		(layer "In6.Cu")
		(net "P5E_CPU0_P3_TX_BUF_DN<12>")
	)
	(arc
		(start 385.771644 -403.095206)
		(mid 385.818182 -403.32917)
		(end 385.950714 -403.527514)
		(width 0.14224)
		(layer "In6.Cu")
		(net "P5E_CPU0_P3_TX_BUF_DN<12>")
	)
	(arc
		(start 385.025138 -397.92021)
		(mid 385.066529 -398.128207)
		(end 385.184396 -398.304512)
		(width 0.14224)
		(layer "In6.Cu")
		(net "P5E_CPU0_P3_TX_BUF_DN<12>")
	)
	(arc
		(start 386.845556 -404.422356)
		(mid 387.074961 -404.59697)
		(end 387.342634 -404.704042)
		(width 0.14224)
		(layer "In6.Cu")
		(net "P5E_CPU0_P3_TX_BUF_DN<12>")
	)
	(segment
		(start 383.57048 -397.156432)
		(end 384.09118 -397.156432)
		(width 0.127)
		(layer "F.Cu")
		(net "P5E_CPU0_P3_TX_BUF_DN<11>")
	)
	(segment
		(start 406.095962 -416.632644)
		(end 406.391872 -416.336734)
		(width 0.12954)
		(layer "B.Cu")
		(net "P5E_CPU0_P3_TX_BUF_DN<11>")
	)
	(segment
		(start 406.391872 -415.65703)
		(end 406.121362 -415.38652)
		(width 0.12954)
		(layer "B.Cu")
		(net "P5E_CPU0_P3_TX_BUF_DN<11>")
	)
	(segment
		(start 406.391872 -416.336734)
		(end 406.391872 -415.65703)
		(width 0.12954)
		(layer "B.Cu")
		(net "P5E_CPU0_P3_TX_BUF_DN<11>")
	)
	(segment
		(start 384.185668 -398.558512)
		(end 384.185668 -398.657064)
		(width 0.14224)
		(layer "In6.Cu")
		(net "P5E_CPU0_P3_TX_BUF_DN<11>")
	)
	(segment
		(start 400.885406 -409.587954)
		(end 405.838914 -411.6451)
		(width 0.14224)
		(layer "In6.Cu")
		(net "P5E_CPU0_P3_TX_BUF_DN<11>")
	)
	(segment
		(start 406.412192 -412.62427)
		(end 406.412192 -415.09569)
		(width 0.14224)
		(layer "In6.Cu")
		(net "P5E_CPU0_P3_TX_BUF_DN<11>")
	)
	(segment
		(start 384.143504 -397.388588)
		(end 383.824988 -397.707104)
		(width 0.14224)
		(layer "In6.Cu")
		(net "P5E_CPU0_P3_TX_BUF_DN<11>")
	)
	(segment
		(start 383.824988 -397.707104)
		(end 383.824988 -397.925544)
		(width 0.14224)
		(layer "In6.Cu")
		(net "P5E_CPU0_P3_TX_BUF_DN<11>")
	)
	(segment
		(start 384.571748 -400.14652)
		(end 384.571748 -403.592538)
		(width 0.14224)
		(layer "In6.Cu")
		(net "P5E_CPU0_P3_TX_BUF_DN<11>")
	)
	(segment
		(start 406.00249 -411.75686)
		(end 406.087326 -411.836362)
		(width 0.14224)
		(layer "In6.Cu")
		(net "P5E_CPU0_P3_TX_BUF_DN<11>")
	)
	(segment
		(start 386.182362 -405.388572)
		(end 391.11047 -406.622504)
		(width 0.14224)
		(layer "In6.Cu")
		(net "P5E_CPU0_P3_TX_BUF_DN<11>")
	)
	(segment
		(start 384.807206 -404.160736)
		(end 385.84251 -405.19604)
		(width 0.14224)
		(layer "In6.Cu")
		(net "P5E_CPU0_P3_TX_BUF_DN<11>")
	)
	(segment
		(start 391.11047 -406.622504)
		(end 400.885406 -409.587954)
		(width 0.14224)
		(layer "In6.Cu")
		(net "P5E_CPU0_P3_TX_BUF_DN<11>")
	)
	(segment
		(start 384.247898 -399.078958)
		(end 384.571748 -400.14652)
		(width 0.14224)
		(layer "In6.Cu")
		(net "P5E_CPU0_P3_TX_BUF_DN<11>")
	)
	(segment
		(start 406.412192 -415.09569)
		(end 406.121362 -415.38652)
		(width 0.14224)
		(layer "In6.Cu")
		(net "P5E_CPU0_P3_TX_BUF_DN<11>")
	)
	(segment
		(start 383.980182 -398.300194)
		(end 384.14833 -398.468342)
		(width 0.14224)
		(layer "In6.Cu")
		(net "P5E_CPU0_P3_TX_BUF_DN<11>")
	)
	(segment
		(start 384.09118 -397.156432)
		(end 384.143504 -397.208756)
		(width 0.14224)
		(layer "In6.Cu")
		(net "P5E_CPU0_P3_TX_BUF_DN<11>")
	)
	(segment
		(start 384.143504 -397.208756)
		(end 384.143504 -397.388588)
		(width 0.14224)
		(layer "In6.Cu")
		(net "P5E_CPU0_P3_TX_BUF_DN<11>")
	)
	(arc
		(start 405.838914 -411.6451)
		(mid 405.925093 -411.694555)
		(end 406.00249 -411.75686)
		(width 0.14224)
		(layer "In6.Cu")
		(net "P5E_CPU0_P3_TX_BUF_DN<11>")
	)
	(arc
		(start 384.185668 -398.657064)
		(mid 384.201235 -398.870304)
		(end 384.247898 -399.078958)
		(width 0.14224)
		(layer "In6.Cu")
		(net "P5E_CPU0_P3_TX_BUF_DN<11>")
	)
	(arc
		(start 384.571748 -403.592538)
		(mid 384.632938 -403.90007)
		(end 384.807206 -404.160736)
		(width 0.14224)
		(layer "In6.Cu")
		(net "P5E_CPU0_P3_TX_BUF_DN<11>")
	)
	(arc
		(start 406.087326 -411.836362)
		(mid 406.327722 -412.198168)
		(end 406.412192 -412.62427)
		(width 0.14224)
		(layer "In6.Cu")
		(net "P5E_CPU0_P3_TX_BUF_DN<11>")
	)
	(arc
		(start 384.14833 -398.468342)
		(mid 384.175973 -398.509712)
		(end 384.185668 -398.558512)
		(width 0.14224)
		(layer "In6.Cu")
		(net "P5E_CPU0_P3_TX_BUF_DN<11>")
	)
	(arc
		(start 383.824988 -397.925544)
		(mid 383.86532 -398.128307)
		(end 383.980182 -398.300194)
		(width 0.14224)
		(layer "In6.Cu")
		(net "P5E_CPU0_P3_TX_BUF_DN<11>")
	)
	(arc
		(start 385.84251 -405.19604)
		(mid 385.999365 -405.315375)
		(end 386.182362 -405.388572)
		(width 0.14224)
		(layer "In6.Cu")
		(net "P5E_CPU0_P3_TX_BUF_DN<11>")
	)
	(segment
		(start 382.370584 -397.156432)
		(end 382.891284 -397.156432)
		(width 0.127)
		(layer "F.Cu")
		(net "P5E_CPU0_P3_TX_BUF_DN<10>")
	)
	(segment
		(start 403.032722 -416.632644)
		(end 403.328632 -416.336734)
		(width 0.12954)
		(layer "B.Cu")
		(net "P5E_CPU0_P3_TX_BUF_DN<10>")
	)
	(segment
		(start 403.328632 -415.65703)
		(end 403.058122 -415.38652)
		(width 0.12954)
		(layer "B.Cu")
		(net "P5E_CPU0_P3_TX_BUF_DN<10>")
	)
	(segment
		(start 403.328632 -416.336734)
		(end 403.328632 -415.65703)
		(width 0.12954)
		(layer "B.Cu")
		(net "P5E_CPU0_P3_TX_BUF_DN<10>")
	)
	(segment
		(start 403.348952 -412.242254)
		(end 403.348952 -415.09569)
		(width 0.14224)
		(layer "In6.Cu")
		(net "P5E_CPU0_P3_TX_BUF_DN<10>")
	)
	(segment
		(start 382.933448 -397.378428)
		(end 382.625092 -397.686784)
		(width 0.14224)
		(layer "In6.Cu")
		(net "P5E_CPU0_P3_TX_BUF_DN<10>")
	)
	(segment
		(start 383.709418 -404.479252)
		(end 385.125722 -405.895556)
		(width 0.14224)
		(layer "In6.Cu")
		(net "P5E_CPU0_P3_TX_BUF_DN<10>")
	)
	(segment
		(start 397.517366 -409.577794)
		(end 398.960848 -410.176218)
		(width 0.14224)
		(layer "In6.Cu")
		(net "P5E_CPU0_P3_TX_BUF_DN<10>")
	)
	(segment
		(start 402.898356 -411.6832)
		(end 403.0853 -411.750002)
		(width 0.14224)
		(layer "In6.Cu")
		(net "P5E_CPU0_P3_TX_BUF_DN<10>")
	)
	(segment
		(start 382.985772 -398.558258)
		(end 382.985772 -398.721834)
		(width 0.14224)
		(layer "In6.Cu")
		(net "P5E_CPU0_P3_TX_BUF_DN<10>")
	)
	(segment
		(start 382.891284 -397.156432)
		(end 382.933448 -397.198596)
		(width 0.14224)
		(layer "In6.Cu")
		(net "P5E_CPU0_P3_TX_BUF_DN<10>")
	)
	(segment
		(start 382.933448 -397.198596)
		(end 382.933448 -397.378428)
		(width 0.14224)
		(layer "In6.Cu")
		(net "P5E_CPU0_P3_TX_BUF_DN<10>")
	)
	(segment
		(start 385.741164 -406.24125)
		(end 390.232646 -407.366216)
		(width 0.14224)
		(layer "In6.Cu")
		(net "P5E_CPU0_P3_TX_BUF_DN<10>")
	)
	(segment
		(start 399.040604 -410.207968)
		(end 402.898356 -411.6832)
		(width 0.14224)
		(layer "In6.Cu")
		(net "P5E_CPU0_P3_TX_BUF_DN<10>")
	)
	(segment
		(start 403.348952 -415.09569)
		(end 403.058122 -415.38652)
		(width 0.14224)
		(layer "In6.Cu")
		(net "P5E_CPU0_P3_TX_BUF_DN<10>")
	)
	(segment
		(start 383.333752 -400.019266)
		(end 383.333752 -403.572218)
		(width 0.14224)
		(layer "In6.Cu")
		(net "P5E_CPU0_P3_TX_BUF_DN<10>")
	)
	(segment
		(start 382.625092 -397.686784)
		(end 382.625092 -397.923766)
		(width 0.14224)
		(layer "In6.Cu")
		(net "P5E_CPU0_P3_TX_BUF_DN<10>")
	)
	(segment
		(start 383.016252 -398.928082)
		(end 383.321306 -399.936462)
		(width 0.14224)
		(layer "In6.Cu")
		(net "P5E_CPU0_P3_TX_BUF_DN<10>")
	)
	(segment
		(start 385.316476 -406.035764)
		(end 385.623054 -406.196292)
		(width 0.14224)
		(layer "In6.Cu")
		(net "P5E_CPU0_P3_TX_BUF_DN<10>")
	)
	(segment
		(start 382.781556 -398.301464)
		(end 382.948434 -398.468342)
		(width 0.14224)
		(layer "In6.Cu")
		(net "P5E_CPU0_P3_TX_BUF_DN<10>")
	)
	(segment
		(start 390.35482 -407.399998)
		(end 397.424402 -409.544266)
		(width 0.14224)
		(layer "In6.Cu")
		(net "P5E_CPU0_P3_TX_BUF_DN<10>")
	)
	(arc
		(start 390.232646 -407.366216)
		(mid 390.293941 -407.382355)
		(end 390.35482 -407.399998)
		(width 0.14224)
		(layer "In6.Cu")
		(net "P5E_CPU0_P3_TX_BUF_DN<10>")
	)
	(arc
		(start 398.960848 -410.176218)
		(mid 399.000615 -410.192372)
		(end 399.040604 -410.207968)
		(width 0.14224)
		(layer "In6.Cu")
		(net "P5E_CPU0_P3_TX_BUF_DN<10>")
	)
	(arc
		(start 403.229826 -411.865064)
		(mid 403.314102 -412.045851)
		(end 403.348952 -412.242254)
		(width 0.14224)
		(layer "In6.Cu")
		(net "P5E_CPU0_P3_TX_BUF_DN<10>")
	)
	(arc
		(start 385.125722 -405.895556)
		(mid 385.215764 -405.97292)
		(end 385.316476 -406.035764)
		(width 0.14224)
		(layer "In6.Cu")
		(net "P5E_CPU0_P3_TX_BUF_DN<10>")
	)
	(arc
		(start 382.985772 -398.721834)
		(mid 382.993437 -398.826077)
		(end 383.016252 -398.928082)
		(width 0.14224)
		(layer "In6.Cu")
		(net "P5E_CPU0_P3_TX_BUF_DN<10>")
	)
	(arc
		(start 382.625092 -397.923766)
		(mid 382.665753 -398.128181)
		(end 382.781556 -398.301464)
		(width 0.14224)
		(layer "In6.Cu")
		(net "P5E_CPU0_P3_TX_BUF_DN<10>")
	)
	(arc
		(start 385.623054 -406.196292)
		(mid 385.680777 -406.222271)
		(end 385.741164 -406.24125)
		(width 0.14224)
		(layer "In6.Cu")
		(net "P5E_CPU0_P3_TX_BUF_DN<10>")
	)
	(arc
		(start 383.333752 -403.572218)
		(mid 383.431377 -404.0631)
		(end 383.709418 -404.479252)
		(width 0.14224)
		(layer "In6.Cu")
		(net "P5E_CPU0_P3_TX_BUF_DN<10>")
	)
	(arc
		(start 383.321306 -399.936462)
		(mid 383.330572 -399.977406)
		(end 383.333752 -400.019266)
		(width 0.14224)
		(layer "In6.Cu")
		(net "P5E_CPU0_P3_TX_BUF_DN<10>")
	)
	(arc
		(start 403.0853 -411.750002)
		(mid 403.167105 -411.795538)
		(end 403.229826 -411.865064)
		(width 0.14224)
		(layer "In6.Cu")
		(net "P5E_CPU0_P3_TX_BUF_DN<10>")
	)
	(arc
		(start 397.424402 -409.544266)
		(mid 397.471297 -409.559884)
		(end 397.517366 -409.577794)
		(width 0.14224)
		(layer "In6.Cu")
		(net "P5E_CPU0_P3_TX_BUF_DN<10>")
	)
	(arc
		(start 382.948434 -398.468342)
		(mid 382.976053 -398.509582)
		(end 382.985772 -398.558258)
		(width 0.14224)
		(layer "In6.Cu")
		(net "P5E_CPU0_P3_TX_BUF_DN<10>")
	)
	(segment
		(start 370.370608 -397.156432)
		(end 370.891308 -397.156432)
		(width 0.127)
		(layer "F.Cu")
		(net "P5E_CPU0_P3_TX_BUF_DN<0>")
	)
	(segment
		(start 372.696232 -416.336734)
		(end 372.696232 -415.65703)
		(width 0.12954)
		(layer "B.Cu")
		(net "P5E_CPU0_P3_TX_BUF_DN<0>")
	)
	(segment
		(start 372.400322 -416.632644)
		(end 372.696232 -416.336734)
		(width 0.12954)
		(layer "B.Cu")
		(net "P5E_CPU0_P3_TX_BUF_DN<0>")
	)
	(segment
		(start 372.696232 -415.65703)
		(end 372.425722 -415.38652)
		(width 0.12954)
		(layer "B.Cu")
		(net "P5E_CPU0_P3_TX_BUF_DN<0>")
	)
	(segment
		(start 371.371876 -405.234648)
		(end 372.716552 -412.02229)
		(width 0.14224)
		(layer "In6.Cu")
		(net "P5E_CPU0_P3_TX_BUF_DN<0>")
	)
	(segment
		(start 370.625116 -397.707104)
		(end 370.625116 -397.932148)
		(width 0.14224)
		(layer "In6.Cu")
		(net "P5E_CPU0_P3_TX_BUF_DN<0>")
	)
	(segment
		(start 370.943632 -397.388588)
		(end 370.625116 -397.707104)
		(width 0.14224)
		(layer "In6.Cu")
		(net "P5E_CPU0_P3_TX_BUF_DN<0>")
	)
	(segment
		(start 370.943632 -397.208756)
		(end 370.943632 -397.388588)
		(width 0.14224)
		(layer "In6.Cu")
		(net "P5E_CPU0_P3_TX_BUF_DN<0>")
	)
	(segment
		(start 370.985796 -398.558004)
		(end 370.985796 -398.742662)
		(width 0.14224)
		(layer "In6.Cu")
		(net "P5E_CPU0_P3_TX_BUF_DN<0>")
	)
	(segment
		(start 372.716552 -412.02229)
		(end 372.716552 -415.09569)
		(width 0.14224)
		(layer "In6.Cu")
		(net "P5E_CPU0_P3_TX_BUF_DN<0>")
	)
	(segment
		(start 371.016276 -398.949672)
		(end 371.353334 -400.060922)
		(width 0.14224)
		(layer "In6.Cu")
		(net "P5E_CPU0_P3_TX_BUF_DN<0>")
	)
	(segment
		(start 371.371876 -400.185636)
		(end 371.371876 -405.234648)
		(width 0.14224)
		(layer "In6.Cu")
		(net "P5E_CPU0_P3_TX_BUF_DN<0>")
	)
	(segment
		(start 370.775992 -398.295876)
		(end 370.948458 -398.468088)
		(width 0.14224)
		(layer "In6.Cu")
		(net "P5E_CPU0_P3_TX_BUF_DN<0>")
	)
	(segment
		(start 370.891308 -397.156432)
		(end 370.943632 -397.208756)
		(width 0.14224)
		(layer "In6.Cu")
		(net "P5E_CPU0_P3_TX_BUF_DN<0>")
	)
	(segment
		(start 372.716552 -415.09569)
		(end 372.425722 -415.38652)
		(width 0.14224)
		(layer "In6.Cu")
		(net "P5E_CPU0_P3_TX_BUF_DN<0>")
	)
	(arc
		(start 371.353334 -400.060922)
		(mid 371.367217 -400.122594)
		(end 371.371876 -400.185636)
		(width 0.14224)
		(layer "In6.Cu")
		(net "P5E_CPU0_P3_TX_BUF_DN<0>")
	)
	(arc
		(start 370.625116 -397.932148)
		(mid 370.664386 -398.12901)
		(end 370.775992 -398.295876)
		(width 0.14224)
		(layer "In6.Cu")
		(net "P5E_CPU0_P3_TX_BUF_DN<0>")
	)
	(arc
		(start 370.948458 -398.468088)
		(mid 370.976077 -398.509328)
		(end 370.985796 -398.558004)
		(width 0.14224)
		(layer "In6.Cu")
		(net "P5E_CPU0_P3_TX_BUF_DN<0>")
	)
	(arc
		(start 370.985796 -398.742662)
		(mid 370.993378 -398.847295)
		(end 371.016276 -398.949672)
		(width 0.14224)
		(layer "In6.Cu")
		(net "P5E_CPU0_P3_TX_BUF_DN<0>")
	)
	(segment
		(start 400.587972 -418.141658)
		(end 400.858482 -418.412168)
		(width 0.12954)
		(layer "B.Cu")
		(net "P5E_CPU0_P3_TX_BUF_C_DP<9>")
	)
	(segment
		(start 400.883882 -417.166044)
		(end 400.587972 -417.461954)
		(width 0.12954)
		(layer "B.Cu")
		(net "P5E_CPU0_P3_TX_BUF_C_DP<9>")
	)
	(segment
		(start 400.587972 -417.461954)
		(end 400.587972 -418.141658)
		(width 0.12954)
		(layer "B.Cu")
		(net "P5E_CPU0_P3_TX_BUF_C_DP<9>")
	)
	(segment
		(start 400.083782 -425.124118)
		(end 400.083782 -427.19498)
		(width 0.14224)
		(layer "In6.Cu")
		(net "P5E_CPU0_P3_TX_BUF_C_DP<9>")
	)
	(segment
		(start 400.164554 -424.300396)
		(end 400.083782 -425.124118)
		(width 0.14224)
		(layer "In6.Cu")
		(net "P5E_CPU0_P3_TX_BUF_C_DP<9>")
	)
	(segment
		(start 400.18589 -427.44136)
		(end 400.217386 -427.472856)
		(width 0.14224)
		(layer "In6.Cu")
		(net "P5E_CPU0_P3_TX_BUF_C_DP<9>")
	)
	(segment
		(start 400.567652 -419.690042)
		(end 400.704812 -419.827202)
		(width 0.14224)
		(layer "In6.Cu")
		(net "P5E_CPU0_P3_TX_BUF_C_DP<9>")
	)
	(segment
		(start 400.343878 -422.479978)
		(end 400.467068 -422.629838)
		(width 0.14224)
		(layer "In6.Cu")
		(net "P5E_CPU0_P3_TX_BUF_C_DP<9>")
	)
	(segment
		(start 400.40052 -427.548802)
		(end 400.607784 -427.548802)
		(width 0.14224)
		(layer "In6.Cu")
		(net "P5E_CPU0_P3_TX_BUF_C_DP<9>")
	)
	(segment
		(start 400.567652 -418.702998)
		(end 400.567652 -419.690042)
		(width 0.14224)
		(layer "In6.Cu")
		(net "P5E_CPU0_P3_TX_BUF_C_DP<9>")
	)
	(segment
		(start 400.567652 -421.147494)
		(end 400.38401 -422.070784)
		(width 0.14224)
		(layer "In6.Cu")
		(net "P5E_CPU0_P3_TX_BUF_C_DP<9>")
	)
	(segment
		(start 400.858482 -418.412168)
		(end 400.567652 -418.702998)
		(width 0.14224)
		(layer "In6.Cu")
		(net "P5E_CPU0_P3_TX_BUF_C_DP<9>")
	)
	(segment
		(start 400.750024 -427.406562)
		(end 400.750024 -427.089824)
		(width 0.14224)
		(layer "In6.Cu")
		(net "P5E_CPU0_P3_TX_BUF_C_DP<9>")
	)
	(segment
		(start 400.467068 -422.629838)
		(end 400.425412 -423.05478)
		(width 0.14224)
		(layer "In6.Cu")
		(net "P5E_CPU0_P3_TX_BUF_C_DP<9>")
	)
	(segment
		(start 400.38401 -422.070784)
		(end 400.343878 -422.479978)
		(width 0.14224)
		(layer "In6.Cu")
		(net "P5E_CPU0_P3_TX_BUF_C_DP<9>")
	)
	(segment
		(start 400.704812 -419.827202)
		(end 400.704812 -420.253922)
		(width 0.14224)
		(layer "In6.Cu")
		(net "P5E_CPU0_P3_TX_BUF_C_DP<9>")
	)
	(segment
		(start 400.425412 -423.05478)
		(end 400.275298 -423.17797)
		(width 0.14224)
		(layer "In6.Cu")
		(net "P5E_CPU0_P3_TX_BUF_C_DP<9>")
	)
	(segment
		(start 400.275298 -423.17797)
		(end 400.233642 -423.602404)
		(width 0.14224)
		(layer "In6.Cu")
		(net "P5E_CPU0_P3_TX_BUF_C_DP<9>")
	)
	(segment
		(start 400.233642 -423.602404)
		(end 400.356578 -423.752264)
		(width 0.14224)
		(layer "In6.Cu")
		(net "P5E_CPU0_P3_TX_BUF_C_DP<9>")
	)
	(segment
		(start 400.607784 -427.548802)
		(end 400.750024 -427.406562)
		(width 0.14224)
		(layer "In6.Cu")
		(net "P5E_CPU0_P3_TX_BUF_C_DP<9>")
	)
	(segment
		(start 400.567652 -420.391082)
		(end 400.567652 -421.147494)
		(width 0.14224)
		(layer "In6.Cu")
		(net "P5E_CPU0_P3_TX_BUF_C_DP<9>")
	)
	(segment
		(start 400.356578 -423.752264)
		(end 400.314922 -424.177206)
		(width 0.14224)
		(layer "In6.Cu")
		(net "P5E_CPU0_P3_TX_BUF_C_DP<9>")
	)
	(segment
		(start 400.704812 -420.253922)
		(end 400.567652 -420.391082)
		(width 0.14224)
		(layer "In6.Cu")
		(net "P5E_CPU0_P3_TX_BUF_C_DP<9>")
	)
	(segment
		(start 400.314922 -424.177206)
		(end 400.164554 -424.300396)
		(width 0.14224)
		(layer "In6.Cu")
		(net "P5E_CPU0_P3_TX_BUF_C_DP<9>")
	)
	(arc
		(start 400.083782 -427.19498)
		(mid 400.110324 -427.328326)
		(end 400.18589 -427.44136)
		(width 0.14224)
		(layer "In6.Cu")
		(net "P5E_CPU0_P3_TX_BUF_C_DP<9>")
	)
	(arc
		(start 400.217386 -427.472856)
		(mid 400.301394 -427.529052)
		(end 400.40052 -427.548802)
		(width 0.14224)
		(layer "In6.Cu")
		(net "P5E_CPU0_P3_TX_BUF_C_DP<9>")
	)
	(segment
		(start 397.509492 -417.477194)
		(end 397.509492 -418.126418)
		(width 0.12954)
		(layer "B.Cu")
		(net "P5E_CPU0_P3_TX_BUF_C_DP<8>")
	)
	(segment
		(start 397.820642 -417.166044)
		(end 397.509492 -417.477194)
		(width 0.12954)
		(layer "B.Cu")
		(net "P5E_CPU0_P3_TX_BUF_C_DP<8>")
	)
	(segment
		(start 397.509492 -418.126418)
		(end 397.795242 -418.412168)
		(width 0.12954)
		(layer "B.Cu")
		(net "P5E_CPU0_P3_TX_BUF_C_DP<8>")
	)
	(segment
		(start 397.504412 -418.702998)
		(end 397.504412 -421.210486)
		(width 0.14224)
		(layer "In6.Cu")
		(net "P5E_CPU0_P3_TX_BUF_C_DP<8>")
	)
	(segment
		(start 397.641572 -421.774366)
		(end 397.504412 -421.911526)
		(width 0.14224)
		(layer "In6.Cu")
		(net "P5E_CPU0_P3_TX_BUF_C_DP<8>")
	)
	(segment
		(start 397.641572 -421.347646)
		(end 397.641572 -421.774366)
		(width 0.14224)
		(layer "In6.Cu")
		(net "P5E_CPU0_P3_TX_BUF_C_DP<8>")
	)
	(segment
		(start 398.750028 -426.406564)
		(end 398.750028 -426.089826)
		(width 0.14224)
		(layer "In6.Cu")
		(net "P5E_CPU0_P3_TX_BUF_C_DP<8>")
	)
	(segment
		(start 397.641572 -422.902126)
		(end 397.504412 -423.039286)
		(width 0.14224)
		(layer "In6.Cu")
		(net "P5E_CPU0_P3_TX_BUF_C_DP<8>")
	)
	(segment
		(start 397.504412 -423.466006)
		(end 397.641572 -423.603166)
		(width 0.14224)
		(layer "In6.Cu")
		(net "P5E_CPU0_P3_TX_BUF_C_DP<8>")
	)
	(segment
		(start 397.641572 -425.157646)
		(end 397.504412 -425.294806)
		(width 0.14224)
		(layer "In6.Cu")
		(net "P5E_CPU0_P3_TX_BUF_C_DP<8>")
	)
	(segment
		(start 398.324578 -426.548804)
		(end 398.607788 -426.548804)
		(width 0.14224)
		(layer "In6.Cu")
		(net "P5E_CPU0_P3_TX_BUF_C_DP<8>")
	)
	(segment
		(start 397.504412 -422.338246)
		(end 397.641572 -422.475406)
		(width 0.14224)
		(layer "In6.Cu")
		(net "P5E_CPU0_P3_TX_BUF_C_DP<8>")
	)
	(segment
		(start 397.641572 -424.029886)
		(end 397.504412 -424.167046)
		(width 0.14224)
		(layer "In6.Cu")
		(net "P5E_CPU0_P3_TX_BUF_C_DP<8>")
	)
	(segment
		(start 397.504412 -425.294806)
		(end 397.504412 -425.588938)
		(width 0.14224)
		(layer "In6.Cu")
		(net "P5E_CPU0_P3_TX_BUF_C_DP<8>")
	)
	(segment
		(start 397.504412 -421.911526)
		(end 397.504412 -422.338246)
		(width 0.14224)
		(layer "In6.Cu")
		(net "P5E_CPU0_P3_TX_BUF_C_DP<8>")
	)
	(segment
		(start 397.770096 -426.230288)
		(end 397.921734 -426.381926)
		(width 0.14224)
		(layer "In6.Cu")
		(net "P5E_CPU0_P3_TX_BUF_C_DP<8>")
	)
	(segment
		(start 397.504412 -421.210486)
		(end 397.641572 -421.347646)
		(width 0.14224)
		(layer "In6.Cu")
		(net "P5E_CPU0_P3_TX_BUF_C_DP<8>")
	)
	(segment
		(start 397.504412 -423.039286)
		(end 397.504412 -423.466006)
		(width 0.14224)
		(layer "In6.Cu")
		(net "P5E_CPU0_P3_TX_BUF_C_DP<8>")
	)
	(segment
		(start 397.641572 -424.730926)
		(end 397.641572 -425.157646)
		(width 0.14224)
		(layer "In6.Cu")
		(net "P5E_CPU0_P3_TX_BUF_C_DP<8>")
	)
	(segment
		(start 397.641572 -422.475406)
		(end 397.641572 -422.902126)
		(width 0.14224)
		(layer "In6.Cu")
		(net "P5E_CPU0_P3_TX_BUF_C_DP<8>")
	)
	(segment
		(start 397.504412 -424.593766)
		(end 397.641572 -424.730926)
		(width 0.14224)
		(layer "In6.Cu")
		(net "P5E_CPU0_P3_TX_BUF_C_DP<8>")
	)
	(segment
		(start 397.641572 -423.603166)
		(end 397.641572 -424.029886)
		(width 0.14224)
		(layer "In6.Cu")
		(net "P5E_CPU0_P3_TX_BUF_C_DP<8>")
	)
	(segment
		(start 397.504412 -424.167046)
		(end 397.504412 -424.593766)
		(width 0.14224)
		(layer "In6.Cu")
		(net "P5E_CPU0_P3_TX_BUF_C_DP<8>")
	)
	(segment
		(start 398.607788 -426.548804)
		(end 398.750028 -426.406564)
		(width 0.14224)
		(layer "In6.Cu")
		(net "P5E_CPU0_P3_TX_BUF_C_DP<8>")
	)
	(segment
		(start 397.795242 -418.412168)
		(end 397.504412 -418.702998)
		(width 0.14224)
		(layer "In6.Cu")
		(net "P5E_CPU0_P3_TX_BUF_C_DP<8>")
	)
	(arc
		(start 397.504412 -425.588938)
		(mid 397.573456 -425.936045)
		(end 397.770096 -426.230288)
		(width 0.14224)
		(layer "In6.Cu")
		(net "P5E_CPU0_P3_TX_BUF_C_DP<8>")
	)
	(arc
		(start 397.921734 -426.381926)
		(mid 398.10656 -426.505423)
		(end 398.324578 -426.548804)
		(width 0.14224)
		(layer "In6.Cu")
		(net "P5E_CPU0_P3_TX_BUF_C_DP<8>")
	)
	(segment
		(start 394.461492 -418.141658)
		(end 394.732002 -418.412168)
		(width 0.12954)
		(layer "B.Cu")
		(net "P5E_CPU0_P3_TX_BUF_C_DP<7>")
	)
	(segment
		(start 394.757402 -417.166044)
		(end 394.461492 -417.461954)
		(width 0.12954)
		(layer "B.Cu")
		(net "P5E_CPU0_P3_TX_BUF_C_DP<7>")
	)
	(segment
		(start 394.461492 -417.461954)
		(end 394.461492 -418.141658)
		(width 0.12954)
		(layer "B.Cu")
		(net "P5E_CPU0_P3_TX_BUF_C_DP<7>")
	)
	(segment
		(start 394.769086 -422.266618)
		(end 394.66139 -422.427908)
		(width 0.14224)
		(layer "In6.Cu")
		(net "P5E_CPU0_P3_TX_BUF_C_DP<7>")
	)
	(segment
		(start 394.441172 -420.42969)
		(end 394.441172 -421.321738)
		(width 0.14224)
		(layer "In6.Cu")
		(net "P5E_CPU0_P3_TX_BUF_C_DP<7>")
	)
	(segment
		(start 395.448536 -427.548802)
		(end 395.60754 -427.548802)
		(width 0.14224)
		(layer "In6.Cu")
		(net "P5E_CPU0_P3_TX_BUF_C_DP<7>")
	)
	(segment
		(start 395.74978 -427.406562)
		(end 395.74978 -427.089824)
		(width 0.14224)
		(layer "In6.Cu")
		(net "P5E_CPU0_P3_TX_BUF_C_DP<7>")
	)
	(segment
		(start 394.441172 -418.702998)
		(end 394.441172 -419.72865)
		(width 0.14224)
		(layer "In6.Cu")
		(net "P5E_CPU0_P3_TX_BUF_C_DP<7>")
	)
	(segment
		(start 395.60754 -427.548802)
		(end 395.74978 -427.406562)
		(width 0.14224)
		(layer "In6.Cu")
		(net "P5E_CPU0_P3_TX_BUF_C_DP<7>")
	)
	(segment
		(start 395.179804 -427.42739)
		(end 395.197076 -427.444662)
		(width 0.14224)
		(layer "In6.Cu")
		(net "P5E_CPU0_P3_TX_BUF_C_DP<7>")
	)
	(segment
		(start 394.578332 -419.86581)
		(end 394.578332 -420.29253)
		(width 0.14224)
		(layer "In6.Cu")
		(net "P5E_CPU0_P3_TX_BUF_C_DP<7>")
	)
	(segment
		(start 394.441172 -419.72865)
		(end 394.578332 -419.86581)
		(width 0.14224)
		(layer "In6.Cu")
		(net "P5E_CPU0_P3_TX_BUF_C_DP<7>")
	)
	(segment
		(start 395.092174 -424.594782)
		(end 395.092174 -427.215808)
		(width 0.14224)
		(layer "In6.Cu")
		(net "P5E_CPU0_P3_TX_BUF_C_DP<7>")
	)
	(segment
		(start 394.578332 -420.29253)
		(end 394.441172 -420.42969)
		(width 0.14224)
		(layer "In6.Cu")
		(net "P5E_CPU0_P3_TX_BUF_C_DP<7>")
	)
	(segment
		(start 394.905992 -422.954196)
		(end 394.989304 -423.372788)
		(width 0.14224)
		(layer "In6.Cu")
		(net "P5E_CPU0_P3_TX_BUF_C_DP<7>")
	)
	(segment
		(start 394.685774 -421.848026)
		(end 394.769086 -422.266618)
		(width 0.14224)
		(layer "In6.Cu")
		(net "P5E_CPU0_P3_TX_BUF_C_DP<7>")
	)
	(segment
		(start 394.989304 -423.372788)
		(end 394.881354 -423.534078)
		(width 0.14224)
		(layer "In6.Cu")
		(net "P5E_CPU0_P3_TX_BUF_C_DP<7>")
	)
	(segment
		(start 394.881354 -423.534078)
		(end 395.092174 -424.594782)
		(width 0.14224)
		(layer "In6.Cu")
		(net "P5E_CPU0_P3_TX_BUF_C_DP<7>")
	)
	(segment
		(start 394.66139 -422.427908)
		(end 394.744448 -422.846246)
		(width 0.14224)
		(layer "In6.Cu")
		(net "P5E_CPU0_P3_TX_BUF_C_DP<7>")
	)
	(segment
		(start 394.732002 -418.412168)
		(end 394.441172 -418.702998)
		(width 0.14224)
		(layer "In6.Cu")
		(net "P5E_CPU0_P3_TX_BUF_C_DP<7>")
	)
	(segment
		(start 394.744448 -422.846246)
		(end 394.905992 -422.954196)
		(width 0.14224)
		(layer "In6.Cu")
		(net "P5E_CPU0_P3_TX_BUF_C_DP<7>")
	)
	(segment
		(start 394.441172 -421.321738)
		(end 394.52423 -421.740076)
		(width 0.14224)
		(layer "In6.Cu")
		(net "P5E_CPU0_P3_TX_BUF_C_DP<7>")
	)
	(segment
		(start 394.52423 -421.740076)
		(end 394.685774 -421.848026)
		(width 0.14224)
		(layer "In6.Cu")
		(net "P5E_CPU0_P3_TX_BUF_C_DP<7>")
	)
	(arc
		(start 395.197076 -427.444662)
		(mid 395.312447 -427.52175)
		(end 395.448536 -427.548802)
		(width 0.14224)
		(layer "In6.Cu")
		(net "P5E_CPU0_P3_TX_BUF_C_DP<7>")
	)
	(arc
		(start 395.092174 -427.215808)
		(mid 395.11495 -427.330311)
		(end 395.179804 -427.42739)
		(width 0.14224)
		(layer "In6.Cu")
		(net "P5E_CPU0_P3_TX_BUF_C_DP<7>")
	)
	(segment
		(start 391.398252 -417.461954)
		(end 391.398252 -418.141658)
		(width 0.12954)
		(layer "B.Cu")
		(net "P5E_CPU0_P3_TX_BUF_C_DP<6>")
	)
	(segment
		(start 391.694162 -417.166044)
		(end 391.398252 -417.461954)
		(width 0.12954)
		(layer "B.Cu")
		(net "P5E_CPU0_P3_TX_BUF_C_DP<6>")
	)
	(segment
		(start 391.398252 -418.141658)
		(end 391.668762 -418.412168)
		(width 0.12954)
		(layer "B.Cu")
		(net "P5E_CPU0_P3_TX_BUF_C_DP<6>")
	)
	(segment
		(start 392.746992 -424.324526)
		(end 392.672824 -424.50385)
		(width 0.14224)
		(layer "In6.Cu")
		(net "P5E_CPU0_P3_TX_BUF_C_DP<6>")
	)
	(segment
		(start 391.377932 -419.61562)
		(end 391.515092 -419.75278)
		(width 0.14224)
		(layer "In6.Cu")
		(net "P5E_CPU0_P3_TX_BUF_C_DP<6>")
	)
	(segment
		(start 392.241024 -423.461688)
		(end 392.241278 -423.461434)
		(width 0.14224)
		(layer "In6.Cu")
		(net "P5E_CPU0_P3_TX_BUF_C_DP<6>")
	)
	(segment
		(start 391.541 -421.771572)
		(end 391.720578 -421.84574)
		(width 0.14224)
		(layer "In6.Cu")
		(net "P5E_CPU0_P3_TX_BUF_C_DP<6>")
	)
	(segment
		(start 393.588494 -426.567854)
		(end 393.749784 -426.406564)
		(width 0.14224)
		(layer "In6.Cu")
		(net "P5E_CPU0_P3_TX_BUF_C_DP<6>")
	)
	(segment
		(start 391.515092 -420.1795)
		(end 391.377932 -420.31666)
		(width 0.14224)
		(layer "In6.Cu")
		(net "P5E_CPU0_P3_TX_BUF_C_DP<6>")
	)
	(segment
		(start 393.172442 -426.459396)
		(end 393.199112 -426.48505)
		(width 0.14224)
		(layer "In6.Cu")
		(net "P5E_CPU0_P3_TX_BUF_C_DP<6>")
	)
	(segment
		(start 391.720578 -421.84574)
		(end 391.8839 -422.240202)
		(width 0.14224)
		(layer "In6.Cu")
		(net "P5E_CPU0_P3_TX_BUF_C_DP<6>")
	)
	(segment
		(start 392.404092 -423.855896)
		(end 392.58367 -423.930064)
		(width 0.14224)
		(layer "In6.Cu")
		(net "P5E_CPU0_P3_TX_BUF_C_DP<6>")
	)
	(segment
		(start 391.377932 -421.377364)
		(end 391.541 -421.771572)
		(width 0.14224)
		(layer "In6.Cu")
		(net "P5E_CPU0_P3_TX_BUF_C_DP<6>")
	)
	(segment
		(start 391.809478 -422.419526)
		(end 391.809732 -422.419526)
		(width 0.14224)
		(layer "In6.Cu")
		(net "P5E_CPU0_P3_TX_BUF_C_DP<6>")
	)
	(segment
		(start 391.809732 -422.419526)
		(end 391.973054 -422.812972)
		(width 0.14224)
		(layer "In6.Cu")
		(net "P5E_CPU0_P3_TX_BUF_C_DP<6>")
	)
	(segment
		(start 391.668762 -418.412168)
		(end 391.377932 -418.702998)
		(width 0.14224)
		(layer "In6.Cu")
		(net "P5E_CPU0_P3_TX_BUF_C_DP<6>")
	)
	(segment
		(start 393.401804 -426.566838)
		(end 393.58824 -426.567854)
		(width 0.14224)
		(layer "In6.Cu")
		(net "P5E_CPU0_P3_TX_BUF_C_DP<6>")
	)
	(segment
		(start 392.672824 -424.50385)
		(end 392.785854 -424.776392)
		(width 0.14224)
		(layer "In6.Cu")
		(net "P5E_CPU0_P3_TX_BUF_C_DP<6>")
	)
	(segment
		(start 391.377932 -420.31666)
		(end 391.377932 -421.377364)
		(width 0.14224)
		(layer "In6.Cu")
		(net "P5E_CPU0_P3_TX_BUF_C_DP<6>")
	)
	(segment
		(start 391.8839 -422.240202)
		(end 391.809478 -422.419526)
		(width 0.14224)
		(layer "In6.Cu")
		(net "P5E_CPU0_P3_TX_BUF_C_DP<6>")
	)
	(segment
		(start 392.152124 -422.887902)
		(end 392.315446 -423.282364)
		(width 0.14224)
		(layer "In6.Cu")
		(net "P5E_CPU0_P3_TX_BUF_C_DP<6>")
	)
	(segment
		(start 391.377932 -418.702998)
		(end 391.377932 -419.61562)
		(width 0.14224)
		(layer "In6.Cu")
		(net "P5E_CPU0_P3_TX_BUF_C_DP<6>")
	)
	(segment
		(start 392.58367 -423.930064)
		(end 392.746992 -424.324526)
		(width 0.14224)
		(layer "In6.Cu")
		(net "P5E_CPU0_P3_TX_BUF_C_DP<6>")
	)
	(segment
		(start 392.315446 -423.282364)
		(end 392.241024 -423.461688)
		(width 0.14224)
		(layer "In6.Cu")
		(net "P5E_CPU0_P3_TX_BUF_C_DP<6>")
	)
	(segment
		(start 392.4046 -423.855134)
		(end 392.404092 -423.855896)
		(width 0.14224)
		(layer "In6.Cu")
		(net "P5E_CPU0_P3_TX_BUF_C_DP<6>")
	)
	(segment
		(start 392.241278 -423.461434)
		(end 392.4046 -423.855134)
		(width 0.14224)
		(layer "In6.Cu")
		(net "P5E_CPU0_P3_TX_BUF_C_DP<6>")
	)
	(segment
		(start 391.972546 -422.813734)
		(end 392.152124 -422.887902)
		(width 0.14224)
		(layer "In6.Cu")
		(net "P5E_CPU0_P3_TX_BUF_C_DP<6>")
	)
	(segment
		(start 391.515092 -419.75278)
		(end 391.515092 -420.1795)
		(width 0.14224)
		(layer "In6.Cu")
		(net "P5E_CPU0_P3_TX_BUF_C_DP<6>")
	)
	(segment
		(start 393.58824 -426.567854)
		(end 393.588494 -426.567854)
		(width 0.14224)
		(layer "In6.Cu")
		(net "P5E_CPU0_P3_TX_BUF_C_DP<6>")
	)
	(segment
		(start 393.749784 -426.406564)
		(end 393.749784 -426.089826)
		(width 0.14224)
		(layer "In6.Cu")
		(net "P5E_CPU0_P3_TX_BUF_C_DP<6>")
	)
	(segment
		(start 391.973054 -422.812972)
		(end 391.972546 -422.813734)
		(width 0.14224)
		(layer "In6.Cu")
		(net "P5E_CPU0_P3_TX_BUF_C_DP<6>")
	)
	(segment
		(start 392.936984 -425.537884)
		(end 392.936984 -425.887388)
		(width 0.14224)
		(layer "In6.Cu")
		(net "P5E_CPU0_P3_TX_BUF_C_DP<6>")
	)
	(arc
		(start 392.785854 -424.776392)
		(mid 392.898944 -425.149693)
		(end 392.936984 -425.537884)
		(width 0.14224)
		(layer "In6.Cu")
		(net "P5E_CPU0_P3_TX_BUF_C_DP<6>")
	)
	(arc
		(start 393.199112 -426.48505)
		(mid 393.292645 -426.545284)
		(end 393.401804 -426.566838)
		(width 0.14224)
		(layer "In6.Cu")
		(net "P5E_CPU0_P3_TX_BUF_C_DP<6>")
	)
	(arc
		(start 392.936984 -425.887388)
		(mid 392.998203 -426.196651)
		(end 393.172442 -426.459396)
		(width 0.14224)
		(layer "In6.Cu")
		(net "P5E_CPU0_P3_TX_BUF_C_DP<6>")
	)
	(segment
		(start 388.335012 -418.141658)
		(end 388.605522 -418.412168)
		(width 0.12954)
		(layer "B.Cu")
		(net "P5E_CPU0_P3_TX_BUF_C_DP<5>")
	)
	(segment
		(start 388.335012 -417.461954)
		(end 388.335012 -418.141658)
		(width 0.12954)
		(layer "B.Cu")
		(net "P5E_CPU0_P3_TX_BUF_C_DP<5>")
	)
	(segment
		(start 388.630922 -417.166044)
		(end 388.335012 -417.461954)
		(width 0.12954)
		(layer "B.Cu")
		(net "P5E_CPU0_P3_TX_BUF_C_DP<5>")
	)
	(segment
		(start 389.32739 -422.8846)
		(end 389.52043 -422.90365)
		(width 0.14224)
		(layer "In6.Cu")
		(net "P5E_CPU0_P3_TX_BUF_C_DP<5>")
	)
	(segment
		(start 391.089134 -425.48175)
		(end 391.089134 -427.22927)
		(width 0.14224)
		(layer "In6.Cu")
		(net "P5E_CPU0_P3_TX_BUF_C_DP<5>")
	)
	(segment
		(start 390.506966 -424.105832)
		(end 390.487916 -424.298364)
		(width 0.14224)
		(layer "In6.Cu")
		(net "P5E_CPU0_P3_TX_BUF_C_DP<5>")
	)
	(segment
		(start 390.042908 -423.756582)
		(end 390.235948 -423.775632)
		(width 0.14224)
		(layer "In6.Cu")
		(net "P5E_CPU0_P3_TX_BUF_C_DP<5>")
	)
	(segment
		(start 388.314692 -420.279068)
		(end 388.314692 -421.123364)
		(width 0.14224)
		(layer "In6.Cu")
		(net "P5E_CPU0_P3_TX_BUF_C_DP<5>")
	)
	(segment
		(start 388.314692 -418.702998)
		(end 388.314692 -419.578028)
		(width 0.14224)
		(layer "In6.Cu")
		(net "P5E_CPU0_P3_TX_BUF_C_DP<5>")
	)
	(segment
		(start 389.791448 -423.23385)
		(end 389.772398 -423.42689)
		(width 0.14224)
		(layer "In6.Cu")
		(net "P5E_CPU0_P3_TX_BUF_C_DP<5>")
	)
	(segment
		(start 391.607548 -427.548802)
		(end 391.749788 -427.406562)
		(width 0.14224)
		(layer "In6.Cu")
		(net "P5E_CPU0_P3_TX_BUF_C_DP<5>")
	)
	(segment
		(start 388.451852 -419.715188)
		(end 388.451852 -420.141908)
		(width 0.14224)
		(layer "In6.Cu")
		(net "P5E_CPU0_P3_TX_BUF_C_DP<5>")
	)
	(segment
		(start 391.749788 -427.406562)
		(end 391.749788 -427.089824)
		(width 0.14224)
		(layer "In6.Cu")
		(net "P5E_CPU0_P3_TX_BUF_C_DP<5>")
	)
	(segment
		(start 388.314692 -419.578028)
		(end 388.451852 -419.715188)
		(width 0.14224)
		(layer "In6.Cu")
		(net "P5E_CPU0_P3_TX_BUF_C_DP<5>")
	)
	(segment
		(start 388.605522 -418.412168)
		(end 388.314692 -418.702998)
		(width 0.14224)
		(layer "In6.Cu")
		(net "P5E_CPU0_P3_TX_BUF_C_DP<5>")
	)
	(segment
		(start 389.52043 -422.90365)
		(end 389.791448 -423.23385)
		(width 0.14224)
		(layer "In6.Cu")
		(net "P5E_CPU0_P3_TX_BUF_C_DP<5>")
	)
	(segment
		(start 390.487916 -424.298364)
		(end 390.803892 -424.683428)
		(width 0.14224)
		(layer "In6.Cu")
		(net "P5E_CPU0_P3_TX_BUF_C_DP<5>")
	)
	(segment
		(start 390.235948 -423.775632)
		(end 390.506966 -424.105832)
		(width 0.14224)
		(layer "In6.Cu")
		(net "P5E_CPU0_P3_TX_BUF_C_DP<5>")
	)
	(segment
		(start 389.772398 -423.42689)
		(end 390.042908 -423.756582)
		(width 0.14224)
		(layer "In6.Cu")
		(net "P5E_CPU0_P3_TX_BUF_C_DP<5>")
	)
	(segment
		(start 388.451852 -420.141908)
		(end 388.314692 -420.279068)
		(width 0.14224)
		(layer "In6.Cu")
		(net "P5E_CPU0_P3_TX_BUF_C_DP<5>")
	)
	(segment
		(start 391.140442 -427.352968)
		(end 391.29843 -427.510956)
		(width 0.14224)
		(layer "In6.Cu")
		(net "P5E_CPU0_P3_TX_BUF_C_DP<5>")
	)
	(segment
		(start 388.648956 -422.05783)
		(end 389.32739 -422.8846)
		(width 0.14224)
		(layer "In6.Cu")
		(net "P5E_CPU0_P3_TX_BUF_C_DP<5>")
	)
	(segment
		(start 391.389616 -427.548802)
		(end 391.607548 -427.548802)
		(width 0.14224)
		(layer "In6.Cu")
		(net "P5E_CPU0_P3_TX_BUF_C_DP<5>")
	)
	(arc
		(start 390.803892 -424.683428)
		(mid 391.015729 -425.057853)
		(end 391.089134 -425.48175)
		(width 0.14224)
		(layer "In6.Cu")
		(net "P5E_CPU0_P3_TX_BUF_C_DP<5>")
	)
	(arc
		(start 391.29843 -427.510956)
		(mid 391.340252 -427.538964)
		(end 391.389616 -427.548802)
		(width 0.14224)
		(layer "In6.Cu")
		(net "P5E_CPU0_P3_TX_BUF_C_DP<5>")
	)
	(arc
		(start 388.314692 -421.123364)
		(mid 388.400779 -421.619585)
		(end 388.648956 -422.05783)
		(width 0.14224)
		(layer "In6.Cu")
		(net "P5E_CPU0_P3_TX_BUF_C_DP<5>")
	)
	(arc
		(start 391.089134 -427.22927)
		(mid 391.102471 -427.296228)
		(end 391.140442 -427.352968)
		(width 0.14224)
		(layer "In6.Cu")
		(net "P5E_CPU0_P3_TX_BUF_C_DP<5>")
	)
	(segment
		(start 385.271772 -417.461954)
		(end 385.271772 -418.141658)
		(width 0.12954)
		(layer "B.Cu")
		(net "P5E_CPU0_P3_TX_BUF_C_DP<4>")
	)
	(segment
		(start 385.271772 -418.141658)
		(end 385.542282 -418.412168)
		(width 0.12954)
		(layer "B.Cu")
		(net "P5E_CPU0_P3_TX_BUF_C_DP<4>")
	)
	(segment
		(start 385.567682 -417.166044)
		(end 385.271772 -417.461954)
		(width 0.12954)
		(layer "B.Cu")
		(net "P5E_CPU0_P3_TX_BUF_C_DP<4>")
	)
	(segment
		(start 387.419342 -423.18559)
		(end 387.44779 -423.377614)
		(width 0.14224)
		(layer "In6.Cu")
		(net "P5E_CPU0_P3_TX_BUF_C_DP<4>")
	)
	(segment
		(start 385.542282 -418.412168)
		(end 385.251452 -418.702998)
		(width 0.14224)
		(layer "In6.Cu")
		(net "P5E_CPU0_P3_TX_BUF_C_DP<4>")
	)
	(segment
		(start 388.32536 -423.857674)
		(end 388.353808 -424.049444)
		(width 0.14224)
		(layer "In6.Cu")
		(net "P5E_CPU0_P3_TX_BUF_C_DP<4>")
	)
	(segment
		(start 386.513324 -422.513506)
		(end 386.541772 -422.70553)
		(width 0.14224)
		(layer "In6.Cu")
		(net "P5E_CPU0_P3_TX_BUF_C_DP<4>")
	)
	(segment
		(start 388.883398 -424.66768)
		(end 388.883398 -425.801282)
		(width 0.14224)
		(layer "In6.Cu")
		(net "P5E_CPU0_P3_TX_BUF_C_DP<4>")
	)
	(segment
		(start 385.251452 -418.702998)
		(end 385.251452 -419.552882)
		(width 0.14224)
		(layer "In6.Cu")
		(net "P5E_CPU0_P3_TX_BUF_C_DP<4>")
	)
	(segment
		(start 389.749792 -426.442632)
		(end 389.749792 -426.089826)
		(width 0.14224)
		(layer "In6.Cu")
		(net "P5E_CPU0_P3_TX_BUF_C_DP<4>")
	)
	(segment
		(start 385.251452 -420.253922)
		(end 385.251452 -421.226234)
		(width 0.14224)
		(layer "In6.Cu")
		(net "P5E_CPU0_P3_TX_BUF_C_DP<4>")
	)
	(segment
		(start 387.44779 -423.377614)
		(end 387.790436 -423.631614)
		(width 0.14224)
		(layer "In6.Cu")
		(net "P5E_CPU0_P3_TX_BUF_C_DP<4>")
	)
	(segment
		(start 389.622538 -426.569886)
		(end 389.749792 -426.442632)
		(width 0.14224)
		(layer "In6.Cu")
		(net "P5E_CPU0_P3_TX_BUF_C_DP<4>")
	)
	(segment
		(start 389.506206 -426.569886)
		(end 389.622538 -426.569886)
		(width 0.14224)
		(layer "In6.Cu")
		(net "P5E_CPU0_P3_TX_BUF_C_DP<4>")
	)
	(segment
		(start 385.978654 -422.287446)
		(end 386.170424 -422.258998)
		(width 0.14224)
		(layer "In6.Cu")
		(net "P5E_CPU0_P3_TX_BUF_C_DP<4>")
	)
	(segment
		(start 386.884418 -422.95953)
		(end 387.076188 -422.931082)
		(width 0.14224)
		(layer "In6.Cu")
		(net "P5E_CPU0_P3_TX_BUF_C_DP<4>")
	)
	(segment
		(start 385.388612 -420.116762)
		(end 385.251452 -420.253922)
		(width 0.14224)
		(layer "In6.Cu")
		(net "P5E_CPU0_P3_TX_BUF_C_DP<4>")
	)
	(segment
		(start 387.790436 -423.631614)
		(end 387.982206 -423.603166)
		(width 0.14224)
		(layer "In6.Cu")
		(net "P5E_CPU0_P3_TX_BUF_C_DP<4>")
	)
	(segment
		(start 387.982206 -423.603166)
		(end 388.32536 -423.857674)
		(width 0.14224)
		(layer "In6.Cu")
		(net "P5E_CPU0_P3_TX_BUF_C_DP<4>")
	)
	(segment
		(start 388.70255 -424.308016)
		(end 388.883398 -424.66768)
		(width 0.14224)
		(layer "In6.Cu")
		(net "P5E_CPU0_P3_TX_BUF_C_DP<4>")
	)
	(segment
		(start 386.541772 -422.70553)
		(end 386.884418 -422.95953)
		(width 0.14224)
		(layer "In6.Cu")
		(net "P5E_CPU0_P3_TX_BUF_C_DP<4>")
	)
	(segment
		(start 386.170424 -422.258998)
		(end 386.513324 -422.513506)
		(width 0.14224)
		(layer "In6.Cu")
		(net "P5E_CPU0_P3_TX_BUF_C_DP<4>")
	)
	(segment
		(start 385.251452 -419.552882)
		(end 385.388612 -419.690042)
		(width 0.14224)
		(layer "In6.Cu")
		(net "P5E_CPU0_P3_TX_BUF_C_DP<4>")
	)
	(segment
		(start 388.353808 -424.049444)
		(end 388.70255 -424.308016)
		(width 0.14224)
		(layer "In6.Cu")
		(net "P5E_CPU0_P3_TX_BUF_C_DP<4>")
	)
	(segment
		(start 389.077454 -426.269658)
		(end 389.28675 -426.478954)
		(width 0.14224)
		(layer "In6.Cu")
		(net "P5E_CPU0_P3_TX_BUF_C_DP<4>")
	)
	(segment
		(start 385.636008 -422.033446)
		(end 385.978654 -422.287446)
		(width 0.14224)
		(layer "In6.Cu")
		(net "P5E_CPU0_P3_TX_BUF_C_DP<4>")
	)
	(segment
		(start 385.388612 -419.690042)
		(end 385.388612 -420.116762)
		(width 0.14224)
		(layer "In6.Cu")
		(net "P5E_CPU0_P3_TX_BUF_C_DP<4>")
	)
	(segment
		(start 387.076188 -422.931082)
		(end 387.419342 -423.18559)
		(width 0.14224)
		(layer "In6.Cu")
		(net "P5E_CPU0_P3_TX_BUF_C_DP<4>")
	)
	(segment
		(start 385.55041 -421.947848)
		(end 385.636008 -422.033446)
		(width 0.14224)
		(layer "In6.Cu")
		(net "P5E_CPU0_P3_TX_BUF_C_DP<4>")
	)
	(arc
		(start 388.883398 -425.801282)
		(mid 388.933838 -426.05477)
		(end 389.077454 -426.269658)
		(width 0.14224)
		(layer "In6.Cu")
		(net "P5E_CPU0_P3_TX_BUF_C_DP<4>")
	)
	(arc
		(start 385.251452 -421.226234)
		(mid 385.329153 -421.616776)
		(end 385.55041 -421.947848)
		(width 0.14224)
		(layer "In6.Cu")
		(net "P5E_CPU0_P3_TX_BUF_C_DP<4>")
	)
	(arc
		(start 389.28675 -426.478954)
		(mid 389.387409 -426.546339)
		(end 389.506206 -426.569886)
		(width 0.14224)
		(layer "In6.Cu")
		(net "P5E_CPU0_P3_TX_BUF_C_DP<4>")
	)
	(segment
		(start 382.208532 -417.461954)
		(end 382.208532 -418.141658)
		(width 0.12954)
		(layer "B.Cu")
		(net "P5E_CPU0_P3_TX_BUF_C_DP<3>")
	)
	(segment
		(start 382.504442 -417.166044)
		(end 382.208532 -417.461954)
		(width 0.12954)
		(layer "B.Cu")
		(net "P5E_CPU0_P3_TX_BUF_C_DP<3>")
	)
	(segment
		(start 382.208532 -418.141658)
		(end 382.479042 -418.412168)
		(width 0.12954)
		(layer "B.Cu")
		(net "P5E_CPU0_P3_TX_BUF_C_DP<3>")
	)
	(segment
		(start 382.418844 -421.716454)
		(end 382.659128 -421.956738)
		(width 0.14224)
		(layer "In6.Cu")
		(net "P5E_CPU0_P3_TX_BUF_C_DP<3>")
	)
	(segment
		(start 382.188212 -419.587426)
		(end 382.325372 -419.724586)
		(width 0.14224)
		(layer "In6.Cu")
		(net "P5E_CPU0_P3_TX_BUF_C_DP<3>")
	)
	(segment
		(start 385.56184 -423.460926)
		(end 385.599686 -423.651172)
		(width 0.14224)
		(layer "In6.Cu")
		(net "P5E_CPU0_P3_TX_BUF_C_DP<3>")
	)
	(segment
		(start 382.659128 -421.956738)
		(end 383.72415 -422.397936)
		(width 0.14224)
		(layer "In6.Cu")
		(net "P5E_CPU0_P3_TX_BUF_C_DP<3>")
	)
	(segment
		(start 387.074156 -424.992546)
		(end 387.074156 -427.256702)
		(width 0.14224)
		(layer "In6.Cu")
		(net "P5E_CPU0_P3_TX_BUF_C_DP<3>")
	)
	(segment
		(start 385.016502 -423.261536)
		(end 385.206748 -423.22369)
		(width 0.14224)
		(layer "In6.Cu")
		(net "P5E_CPU0_P3_TX_BUF_C_DP<3>")
	)
	(segment
		(start 387.471158 -427.548802)
		(end 387.607556 -427.548802)
		(width 0.14224)
		(layer "In6.Cu")
		(net "P5E_CPU0_P3_TX_BUF_C_DP<3>")
	)
	(segment
		(start 382.479042 -418.412168)
		(end 382.188212 -418.702998)
		(width 0.14224)
		(layer "In6.Cu")
		(net "P5E_CPU0_P3_TX_BUF_C_DP<3>")
	)
	(segment
		(start 384.661918 -423.024554)
		(end 385.016502 -423.261536)
		(width 0.14224)
		(layer "In6.Cu")
		(net "P5E_CPU0_P3_TX_BUF_C_DP<3>")
	)
	(segment
		(start 387.607556 -427.548802)
		(end 387.749796 -427.406562)
		(width 0.14224)
		(layer "In6.Cu")
		(net "P5E_CPU0_P3_TX_BUF_C_DP<3>")
	)
	(segment
		(start 384.624072 -422.834308)
		(end 384.661918 -423.024554)
		(width 0.14224)
		(layer "In6.Cu")
		(net "P5E_CPU0_P3_TX_BUF_C_DP<3>")
	)
	(segment
		(start 387.120384 -427.368208)
		(end 387.180582 -427.428406)
		(width 0.14224)
		(layer "In6.Cu")
		(net "P5E_CPU0_P3_TX_BUF_C_DP<3>")
	)
	(segment
		(start 382.325372 -420.151306)
		(end 382.188212 -420.288466)
		(width 0.14224)
		(layer "In6.Cu")
		(net "P5E_CPU0_P3_TX_BUF_C_DP<3>")
	)
	(segment
		(start 384.26898 -422.597072)
		(end 384.624072 -422.834308)
		(width 0.14224)
		(layer "In6.Cu")
		(net "P5E_CPU0_P3_TX_BUF_C_DP<3>")
	)
	(segment
		(start 387.749796 -427.406562)
		(end 387.749796 -427.089824)
		(width 0.14224)
		(layer "In6.Cu")
		(net "P5E_CPU0_P3_TX_BUF_C_DP<3>")
	)
	(segment
		(start 385.599686 -423.651172)
		(end 386.7785 -424.43908)
		(width 0.14224)
		(layer "In6.Cu")
		(net "P5E_CPU0_P3_TX_BUF_C_DP<3>")
	)
	(segment
		(start 385.206748 -423.22369)
		(end 385.56184 -423.460926)
		(width 0.14224)
		(layer "In6.Cu")
		(net "P5E_CPU0_P3_TX_BUF_C_DP<3>")
	)
	(segment
		(start 382.325372 -419.724586)
		(end 382.325372 -420.151306)
		(width 0.14224)
		(layer "In6.Cu")
		(net "P5E_CPU0_P3_TX_BUF_C_DP<3>")
	)
	(segment
		(start 382.188212 -418.702998)
		(end 382.188212 -419.587426)
		(width 0.14224)
		(layer "In6.Cu")
		(net "P5E_CPU0_P3_TX_BUF_C_DP<3>")
	)
	(segment
		(start 384.078734 -422.634918)
		(end 384.26898 -422.597072)
		(width 0.14224)
		(layer "In6.Cu")
		(net "P5E_CPU0_P3_TX_BUF_C_DP<3>")
	)
	(segment
		(start 383.72415 -422.397936)
		(end 384.078734 -422.634918)
		(width 0.14224)
		(layer "In6.Cu")
		(net "P5E_CPU0_P3_TX_BUF_C_DP<3>")
	)
	(segment
		(start 382.188212 -420.288466)
		(end 382.188212 -421.15994)
		(width 0.14224)
		(layer "In6.Cu")
		(net "P5E_CPU0_P3_TX_BUF_C_DP<3>")
	)
	(arc
		(start 382.188212 -421.15994)
		(mid 382.248213 -421.461114)
		(end 382.418844 -421.716454)
		(width 0.14224)
		(layer "In6.Cu")
		(net "P5E_CPU0_P3_TX_BUF_C_DP<3>")
	)
	(arc
		(start 387.074156 -427.256702)
		(mid 387.086178 -427.31705)
		(end 387.120384 -427.368208)
		(width 0.14224)
		(layer "In6.Cu")
		(net "P5E_CPU0_P3_TX_BUF_C_DP<3>")
	)
	(arc
		(start 387.180582 -427.428406)
		(mid 387.313899 -427.517486)
		(end 387.471158 -427.548802)
		(width 0.14224)
		(layer "In6.Cu")
		(net "P5E_CPU0_P3_TX_BUF_C_DP<3>")
	)
	(arc
		(start 386.7785 -424.43908)
		(mid 386.995572 -424.678816)
		(end 387.074156 -424.992546)
		(width 0.14224)
		(layer "In6.Cu")
		(net "P5E_CPU0_P3_TX_BUF_C_DP<3>")
	)
	(segment
		(start 379.145292 -417.461954)
		(end 379.145292 -418.141658)
		(width 0.12954)
		(layer "B.Cu")
		(net "P5E_CPU0_P3_TX_BUF_C_DP<2>")
	)
	(segment
		(start 379.145292 -418.141658)
		(end 379.415802 -418.412168)
		(width 0.12954)
		(layer "B.Cu")
		(net "P5E_CPU0_P3_TX_BUF_C_DP<2>")
	)
	(segment
		(start 379.441202 -417.166044)
		(end 379.145292 -417.461954)
		(width 0.12954)
		(layer "B.Cu")
		(net "P5E_CPU0_P3_TX_BUF_C_DP<2>")
	)
	(segment
		(start 381.16637 -422.461182)
		(end 381.560832 -422.624504)
		(width 0.14224)
		(layer "In6.Cu")
		(net "P5E_CPU0_P3_TX_BUF_C_DP<2>")
	)
	(segment
		(start 379.124972 -420.178738)
		(end 379.124972 -421.30726)
		(width 0.14224)
		(layer "In6.Cu")
		(net "P5E_CPU0_P3_TX_BUF_C_DP<2>")
	)
	(segment
		(start 383.900172 -423.74185)
		(end 384.13309 -423.83837)
		(width 0.14224)
		(layer "In6.Cu")
		(net "P5E_CPU0_P3_TX_BUF_C_DP<2>")
	)
	(segment
		(start 379.262132 -420.041578)
		(end 379.124972 -420.178738)
		(width 0.14224)
		(layer "In6.Cu")
		(net "P5E_CPU0_P3_TX_BUF_C_DP<2>")
	)
	(segment
		(start 379.311662 -421.75811)
		(end 379.454156 -421.900604)
		(width 0.14224)
		(layer "In6.Cu")
		(net "P5E_CPU0_P3_TX_BUF_C_DP<2>")
	)
	(segment
		(start 382.208532 -422.892728)
		(end 382.602994 -423.05605)
		(width 0.14224)
		(layer "In6.Cu")
		(net "P5E_CPU0_P3_TX_BUF_C_DP<2>")
	)
	(segment
		(start 384.13309 -423.83837)
		(end 384.454654 -424.159934)
		(width 0.14224)
		(layer "In6.Cu")
		(net "P5E_CPU0_P3_TX_BUF_C_DP<2>")
	)
	(segment
		(start 383.900172 -423.741342)
		(end 383.900172 -423.74185)
		(width 0.14224)
		(layer "In6.Cu")
		(net "P5E_CPU0_P3_TX_BUF_C_DP<2>")
	)
	(segment
		(start 383.071624 -423.398442)
		(end 383.250694 -423.324274)
		(width 0.14224)
		(layer "In6.Cu")
		(net "P5E_CPU0_P3_TX_BUF_C_DP<2>")
	)
	(segment
		(start 383.645156 -423.487596)
		(end 383.719578 -423.66692)
		(width 0.14224)
		(layer "In6.Cu")
		(net "P5E_CPU0_P3_TX_BUF_C_DP<2>")
	)
	(segment
		(start 380.124208 -422.029636)
		(end 380.518924 -422.192704)
		(width 0.14224)
		(layer "In6.Cu")
		(net "P5E_CPU0_P3_TX_BUF_C_DP<2>")
	)
	(segment
		(start 380.593092 -422.372282)
		(end 380.9873 -422.53535)
		(width 0.14224)
		(layer "In6.Cu")
		(net "P5E_CPU0_P3_TX_BUF_C_DP<2>")
	)
	(segment
		(start 385.60756 -426.548804)
		(end 385.7498 -426.406564)
		(width 0.14224)
		(layer "In6.Cu")
		(net "P5E_CPU0_P3_TX_BUF_C_DP<2>")
	)
	(segment
		(start 383.719578 -423.66692)
		(end 383.900172 -423.741342)
		(width 0.14224)
		(layer "In6.Cu")
		(net "P5E_CPU0_P3_TX_BUF_C_DP<2>")
	)
	(segment
		(start 383.250694 -423.324274)
		(end 383.645156 -423.487596)
		(width 0.14224)
		(layer "In6.Cu")
		(net "P5E_CPU0_P3_TX_BUF_C_DP<2>")
	)
	(segment
		(start 382.677416 -423.235374)
		(end 383.071624 -423.398442)
		(width 0.14224)
		(layer "In6.Cu")
		(net "P5E_CPU0_P3_TX_BUF_C_DP<2>")
	)
	(segment
		(start 382.029462 -422.966896)
		(end 382.208532 -422.892728)
		(width 0.14224)
		(layer "In6.Cu")
		(net "P5E_CPU0_P3_TX_BUF_C_DP<2>")
	)
	(segment
		(start 379.124972 -418.702998)
		(end 379.124972 -419.477698)
		(width 0.14224)
		(layer "In6.Cu")
		(net "P5E_CPU0_P3_TX_BUF_C_DP<2>")
	)
	(segment
		(start 379.415802 -418.412168)
		(end 379.124972 -418.702998)
		(width 0.14224)
		(layer "In6.Cu")
		(net "P5E_CPU0_P3_TX_BUF_C_DP<2>")
	)
	(segment
		(start 379.945138 -422.103804)
		(end 380.124208 -422.029636)
		(width 0.14224)
		(layer "In6.Cu")
		(net "P5E_CPU0_P3_TX_BUF_C_DP<2>")
	)
	(segment
		(start 379.454156 -421.900604)
		(end 379.945138 -422.103804)
		(width 0.14224)
		(layer "In6.Cu")
		(net "P5E_CPU0_P3_TX_BUF_C_DP<2>")
	)
	(segment
		(start 385.502658 -426.548804)
		(end 385.60756 -426.548804)
		(width 0.14224)
		(layer "In6.Cu")
		(net "P5E_CPU0_P3_TX_BUF_C_DP<2>")
	)
	(segment
		(start 380.518924 -422.192704)
		(end 380.593092 -422.372282)
		(width 0.14224)
		(layer "In6.Cu")
		(net "P5E_CPU0_P3_TX_BUF_C_DP<2>")
	)
	(segment
		(start 384.840734 -425.09186)
		(end 384.840734 -425.586398)
		(width 0.14224)
		(layer "In6.Cu")
		(net "P5E_CPU0_P3_TX_BUF_C_DP<2>")
	)
	(segment
		(start 385.7498 -426.406564)
		(end 385.7498 -426.089826)
		(width 0.14224)
		(layer "In6.Cu")
		(net "P5E_CPU0_P3_TX_BUF_C_DP<2>")
	)
	(segment
		(start 381.560832 -422.624504)
		(end 381.635254 -422.803828)
		(width 0.14224)
		(layer "In6.Cu")
		(net "P5E_CPU0_P3_TX_BUF_C_DP<2>")
	)
	(segment
		(start 379.262132 -419.614858)
		(end 379.262132 -420.041578)
		(width 0.14224)
		(layer "In6.Cu")
		(net "P5E_CPU0_P3_TX_BUF_C_DP<2>")
	)
	(segment
		(start 381.635254 -422.803828)
		(end 382.029462 -422.966896)
		(width 0.14224)
		(layer "In6.Cu")
		(net "P5E_CPU0_P3_TX_BUF_C_DP<2>")
	)
	(segment
		(start 379.124972 -419.477698)
		(end 379.262132 -419.614858)
		(width 0.14224)
		(layer "In6.Cu")
		(net "P5E_CPU0_P3_TX_BUF_C_DP<2>")
	)
	(segment
		(start 382.602994 -423.05605)
		(end 382.677416 -423.235374)
		(width 0.14224)
		(layer "In6.Cu")
		(net "P5E_CPU0_P3_TX_BUF_C_DP<2>")
	)
	(segment
		(start 380.9873 -422.53535)
		(end 381.16637 -422.461182)
		(width 0.14224)
		(layer "In6.Cu")
		(net "P5E_CPU0_P3_TX_BUF_C_DP<2>")
	)
	(arc
		(start 379.124972 -421.30726)
		(mid 379.173487 -421.55125)
		(end 379.311662 -421.75811)
		(width 0.14224)
		(layer "In6.Cu")
		(net "P5E_CPU0_P3_TX_BUF_C_DP<2>")
	)
	(arc
		(start 385.18465 -426.416978)
		(mid 385.330539 -426.514521)
		(end 385.502658 -426.548804)
		(width 0.14224)
		(layer "In6.Cu")
		(net "P5E_CPU0_P3_TX_BUF_C_DP<2>")
	)
	(arc
		(start 384.840734 -425.586398)
		(mid 384.930107 -426.035887)
		(end 385.18465 -426.416978)
		(width 0.14224)
		(layer "In6.Cu")
		(net "P5E_CPU0_P3_TX_BUF_C_DP<2>")
	)
	(arc
		(start 384.454654 -424.159934)
		(mid 384.740402 -424.587491)
		(end 384.840734 -425.09186)
		(width 0.14224)
		(layer "In6.Cu")
		(net "P5E_CPU0_P3_TX_BUF_C_DP<2>")
	)
	(segment
		(start 376.377962 -417.166044)
		(end 376.082052 -417.461954)
		(width 0.12954)
		(layer "B.Cu")
		(net "P5E_CPU0_P3_TX_BUF_C_DP<1>")
	)
	(segment
		(start 376.082052 -417.461954)
		(end 376.082052 -418.141658)
		(width 0.12954)
		(layer "B.Cu")
		(net "P5E_CPU0_P3_TX_BUF_C_DP<1>")
	)
	(segment
		(start 376.082052 -418.141658)
		(end 376.352562 -418.412168)
		(width 0.12954)
		(layer "B.Cu")
		(net "P5E_CPU0_P3_TX_BUF_C_DP<1>")
	)
	(segment
		(start 377.208034 -422.268142)
		(end 377.37034 -422.191434)
		(width 0.14224)
		(layer "In6.Cu")
		(net "P5E_CPU0_P3_TX_BUF_C_DP<1>")
	)
	(segment
		(start 383.478024 -427.548802)
		(end 383.62255 -427.548802)
		(width 0.14224)
		(layer "In6.Cu")
		(net "P5E_CPU0_P3_TX_BUF_C_DP<1>")
	)
	(segment
		(start 376.061732 -420.72433)
		(end 376.061732 -421.516302)
		(width 0.14224)
		(layer "In6.Cu")
		(net "P5E_CPU0_P3_TX_BUF_C_DP<1>")
	)
	(segment
		(start 377.37034 -422.191434)
		(end 377.772422 -422.335198)
		(width 0.14224)
		(layer "In6.Cu")
		(net "P5E_CPU0_P3_TX_BUF_C_DP<1>")
	)
	(segment
		(start 376.188732 -420.17061)
		(end 376.188732 -420.59733)
		(width 0.14224)
		(layer "In6.Cu")
		(net "P5E_CPU0_P3_TX_BUF_C_DP<1>")
	)
	(segment
		(start 376.061732 -418.702998)
		(end 376.061732 -420.04361)
		(width 0.14224)
		(layer "In6.Cu")
		(net "P5E_CPU0_P3_TX_BUF_C_DP<1>")
	)
	(segment
		(start 378.413518 -422.56456)
		(end 378.815346 -422.70807)
		(width 0.14224)
		(layer "In6.Cu")
		(net "P5E_CPU0_P3_TX_BUF_C_DP<1>")
	)
	(segment
		(start 377.772422 -422.335198)
		(end 377.849384 -422.497758)
		(width 0.14224)
		(layer "In6.Cu")
		(net "P5E_CPU0_P3_TX_BUF_C_DP<1>")
	)
	(segment
		(start 376.551952 -422.0337)
		(end 377.208034 -422.268142)
		(width 0.14224)
		(layer "In6.Cu")
		(net "P5E_CPU0_P3_TX_BUF_C_DP<1>")
	)
	(segment
		(start 383.749804 -427.421548)
		(end 383.749804 -427.089824)
		(width 0.14224)
		(layer "In6.Cu")
		(net "P5E_CPU0_P3_TX_BUF_C_DP<1>")
	)
	(segment
		(start 376.352562 -418.412168)
		(end 376.061732 -418.702998)
		(width 0.14224)
		(layer "In6.Cu")
		(net "P5E_CPU0_P3_TX_BUF_C_DP<1>")
	)
	(segment
		(start 377.849384 -422.497758)
		(end 378.250958 -422.641268)
		(width 0.14224)
		(layer "In6.Cu")
		(net "P5E_CPU0_P3_TX_BUF_C_DP<1>")
	)
	(segment
		(start 376.1105 -421.633904)
		(end 376.43816 -421.961564)
		(width 0.14224)
		(layer "In6.Cu")
		(net "P5E_CPU0_P3_TX_BUF_C_DP<1>")
	)
	(segment
		(start 378.892308 -422.870884)
		(end 382.067816 -424.006264)
		(width 0.14224)
		(layer "In6.Cu")
		(net "P5E_CPU0_P3_TX_BUF_C_DP<1>")
	)
	(segment
		(start 376.188732 -420.59733)
		(end 376.061732 -420.72433)
		(width 0.14224)
		(layer "In6.Cu")
		(net "P5E_CPU0_P3_TX_BUF_C_DP<1>")
	)
	(segment
		(start 383.62255 -427.548802)
		(end 383.749804 -427.421548)
		(width 0.14224)
		(layer "In6.Cu")
		(net "P5E_CPU0_P3_TX_BUF_C_DP<1>")
	)
	(segment
		(start 378.250958 -422.641268)
		(end 378.413518 -422.56456)
		(width 0.14224)
		(layer "In6.Cu")
		(net "P5E_CPU0_P3_TX_BUF_C_DP<1>")
	)
	(segment
		(start 382.652016 -424.358562)
		(end 382.702562 -424.409108)
		(width 0.14224)
		(layer "In6.Cu")
		(net "P5E_CPU0_P3_TX_BUF_C_DP<1>")
	)
	(segment
		(start 383.086864 -425.336716)
		(end 383.086864 -427.157642)
		(width 0.14224)
		(layer "In6.Cu")
		(net "P5E_CPU0_P3_TX_BUF_C_DP<1>")
	)
	(segment
		(start 376.061732 -420.04361)
		(end 376.188732 -420.17061)
		(width 0.14224)
		(layer "In6.Cu")
		(net "P5E_CPU0_P3_TX_BUF_C_DP<1>")
	)
	(segment
		(start 378.815346 -422.70807)
		(end 378.892308 -422.870884)
		(width 0.14224)
		(layer "In6.Cu")
		(net "P5E_CPU0_P3_TX_BUF_C_DP<1>")
	)
	(arc
		(start 376.061732 -421.516302)
		(mid 376.074411 -421.579955)
		(end 376.1105 -421.633904)
		(width 0.14224)
		(layer "In6.Cu")
		(net "P5E_CPU0_P3_TX_BUF_C_DP<1>")
	)
	(arc
		(start 382.067816 -424.006264)
		(mid 382.381436 -424.146728)
		(end 382.652016 -424.358562)
		(width 0.14224)
		(layer "In6.Cu")
		(net "P5E_CPU0_P3_TX_BUF_C_DP<1>")
	)
	(arc
		(start 382.702562 -424.409108)
		(mid 382.986986 -424.834684)
		(end 383.086864 -425.336716)
		(width 0.14224)
		(layer "In6.Cu")
		(net "P5E_CPU0_P3_TX_BUF_C_DP<1>")
	)
	(arc
		(start 376.43816 -421.961564)
		(mid 376.491055 -422.003944)
		(end 376.551952 -422.0337)
		(width 0.14224)
		(layer "In6.Cu")
		(net "P5E_CPU0_P3_TX_BUF_C_DP<1>")
	)
	(arc
		(start 383.086864 -427.157642)
		(mid 383.201432 -427.434234)
		(end 383.478024 -427.548802)
		(width 0.14224)
		(layer "In6.Cu")
		(net "P5E_CPU0_P3_TX_BUF_C_DP<1>")
	)
	(segment
		(start 419.263322 -417.166044)
		(end 418.967412 -417.461954)
		(width 0.12954)
		(layer "B.Cu")
		(net "P5E_CPU0_P3_TX_BUF_C_DP<15>")
	)
	(segment
		(start 418.967412 -417.461954)
		(end 418.967412 -418.141658)
		(width 0.12954)
		(layer "B.Cu")
		(net "P5E_CPU0_P3_TX_BUF_C_DP<15>")
	)
	(segment
		(start 418.967412 -418.141658)
		(end 419.237922 -418.412168)
		(width 0.12954)
		(layer "B.Cu")
		(net "P5E_CPU0_P3_TX_BUF_C_DP<15>")
	)
	(segment
		(start 419.084252 -419.615874)
		(end 418.947092 -419.478714)
		(width 0.14224)
		(layer "In6.Cu")
		(net "P5E_CPU0_P3_TX_BUF_C_DP<15>")
	)
	(segment
		(start 412.60776 -427.548802)
		(end 412.44139 -427.548802)
		(width 0.14224)
		(layer "In6.Cu")
		(net "P5E_CPU0_P3_TX_BUF_C_DP<15>")
	)
	(segment
		(start 413.31896 -423.936668)
		(end 413.48025 -424.044364)
		(width 0.14224)
		(layer "In6.Cu")
		(net "P5E_CPU0_P3_TX_BUF_C_DP<15>")
	)
	(segment
		(start 414.006792 -423.799762)
		(end 414.42513 -423.716704)
		(width 0.14224)
		(layer "In6.Cu")
		(net "P5E_CPU0_P3_TX_BUF_C_DP<15>")
	)
	(segment
		(start 418.947092 -419.478714)
		(end 418.947092 -418.702998)
		(width 0.14224)
		(layer "In6.Cu")
		(net "P5E_CPU0_P3_TX_BUF_C_DP<15>")
	)
	(segment
		(start 412.171134 -424.391074)
		(end 412.171642 -424.390566)
		(width 0.14224)
		(layer "In6.Cu")
		(net "P5E_CPU0_P3_TX_BUF_C_DP<15>")
	)
	(segment
		(start 415.88563 -423.408602)
		(end 418.133276 -422.477692)
		(width 0.14224)
		(layer "In6.Cu")
		(net "P5E_CPU0_P3_TX_BUF_C_DP<15>")
	)
	(segment
		(start 412.171134 -427.436788)
		(end 412.12516 -427.390814)
		(width 0.14224)
		(layer "In6.Cu")
		(net "P5E_CPU0_P3_TX_BUF_C_DP<15>")
	)
	(segment
		(start 418.947092 -421.544496)
		(end 418.947092 -420.179754)
		(width 0.14224)
		(layer "In6.Cu")
		(net "P5E_CPU0_P3_TX_BUF_C_DP<15>")
	)
	(segment
		(start 418.947092 -420.179754)
		(end 419.084252 -420.042594)
		(width 0.14224)
		(layer "In6.Cu")
		(net "P5E_CPU0_P3_TX_BUF_C_DP<15>")
	)
	(segment
		(start 413.48025 -424.044364)
		(end 413.898842 -423.961306)
		(width 0.14224)
		(layer "In6.Cu")
		(net "P5E_CPU0_P3_TX_BUF_C_DP<15>")
	)
	(segment
		(start 413.898842 -423.961306)
		(end 414.006792 -423.799762)
		(width 0.14224)
		(layer "In6.Cu")
		(net "P5E_CPU0_P3_TX_BUF_C_DP<15>")
	)
	(segment
		(start 419.084252 -420.042594)
		(end 419.084252 -419.615874)
		(width 0.14224)
		(layer "In6.Cu")
		(net "P5E_CPU0_P3_TX_BUF_C_DP<15>")
	)
	(segment
		(start 415.005266 -423.741342)
		(end 415.112962 -423.580052)
		(width 0.14224)
		(layer "In6.Cu")
		(net "P5E_CPU0_P3_TX_BUF_C_DP<15>")
	)
	(segment
		(start 412.073852 -427.267116)
		(end 412.073852 -424.62577)
		(width 0.14224)
		(layer "In6.Cu")
		(net "P5E_CPU0_P3_TX_BUF_C_DP<15>")
	)
	(segment
		(start 412.75 -427.089824)
		(end 412.75 -427.406562)
		(width 0.14224)
		(layer "In6.Cu")
		(net "P5E_CPU0_P3_TX_BUF_C_DP<15>")
	)
	(segment
		(start 414.58642 -423.824654)
		(end 415.005266 -423.741342)
		(width 0.14224)
		(layer "In6.Cu")
		(net "P5E_CPU0_P3_TX_BUF_C_DP<15>")
	)
	(segment
		(start 418.329364 -422.34612)
		(end 418.817298 -421.858186)
		(width 0.14224)
		(layer "In6.Cu")
		(net "P5E_CPU0_P3_TX_BUF_C_DP<15>")
	)
	(segment
		(start 414.42513 -423.716704)
		(end 414.58642 -423.824654)
		(width 0.14224)
		(layer "In6.Cu")
		(net "P5E_CPU0_P3_TX_BUF_C_DP<15>")
	)
	(segment
		(start 412.75 -427.406562)
		(end 412.60776 -427.548802)
		(width 0.14224)
		(layer "In6.Cu")
		(net "P5E_CPU0_P3_TX_BUF_C_DP<15>")
	)
	(segment
		(start 418.947092 -418.702998)
		(end 419.237922 -418.412168)
		(width 0.14224)
		(layer "In6.Cu")
		(net "P5E_CPU0_P3_TX_BUF_C_DP<15>")
	)
	(segment
		(start 412.84525 -424.030648)
		(end 413.31896 -423.936668)
		(width 0.14224)
		(layer "In6.Cu")
		(net "P5E_CPU0_P3_TX_BUF_C_DP<15>")
	)
	(segment
		(start 415.112962 -423.580052)
		(end 415.71291 -423.460926)
		(width 0.14224)
		(layer "In6.Cu")
		(net "P5E_CPU0_P3_TX_BUF_C_DP<15>")
	)
	(arc
		(start 415.71291 -423.460926)
		(mid 415.800552 -423.438995)
		(end 415.88563 -423.408602)
		(width 0.14224)
		(layer "In6.Cu")
		(net "P5E_CPU0_P3_TX_BUF_C_DP<15>")
	)
	(arc
		(start 418.133276 -422.477692)
		(mid 418.23779 -422.421553)
		(end 418.329364 -422.34612)
		(width 0.14224)
		(layer "In6.Cu")
		(net "P5E_CPU0_P3_TX_BUF_C_DP<15>")
	)
	(arc
		(start 412.171642 -424.390566)
		(mid 412.481722 -424.160584)
		(end 412.84525 -424.030648)
		(width 0.14224)
		(layer "In6.Cu")
		(net "P5E_CPU0_P3_TX_BUF_C_DP<15>")
	)
	(arc
		(start 412.073852 -424.62577)
		(mid 412.099137 -424.498742)
		(end 412.171134 -424.391074)
		(width 0.14224)
		(layer "In6.Cu")
		(net "P5E_CPU0_P3_TX_BUF_C_DP<15>")
	)
	(arc
		(start 412.12516 -427.390814)
		(mid 412.087185 -427.334075)
		(end 412.073852 -427.267116)
		(width 0.14224)
		(layer "In6.Cu")
		(net "P5E_CPU0_P3_TX_BUF_C_DP<15>")
	)
	(arc
		(start 412.44139 -427.548802)
		(mid 412.295116 -427.519688)
		(end 412.171134 -427.436788)
		(width 0.14224)
		(layer "In6.Cu")
		(net "P5E_CPU0_P3_TX_BUF_C_DP<15>")
	)
	(arc
		(start 418.817298 -421.858186)
		(mid 418.913434 -421.714263)
		(end 418.947092 -421.544496)
		(width 0.14224)
		(layer "In6.Cu")
		(net "P5E_CPU0_P3_TX_BUF_C_DP<15>")
	)
	(segment
		(start 415.904172 -417.461954)
		(end 415.904172 -418.141658)
		(width 0.12954)
		(layer "B.Cu")
		(net "P5E_CPU0_P3_TX_BUF_C_DP<14>")
	)
	(segment
		(start 416.200082 -417.166044)
		(end 415.904172 -417.461954)
		(width 0.12954)
		(layer "B.Cu")
		(net "P5E_CPU0_P3_TX_BUF_C_DP<14>")
	)
	(segment
		(start 415.904172 -418.141658)
		(end 416.174682 -418.412168)
		(width 0.12954)
		(layer "B.Cu")
		(net "P5E_CPU0_P3_TX_BUF_C_DP<14>")
	)
	(segment
		(start 410.328364 -426.583856)
		(end 410.59354 -426.583856)
		(width 0.14224)
		(layer "In6.Cu")
		(net "P5E_CPU0_P3_TX_BUF_C_DP<14>")
	)
	(segment
		(start 415.883852 -421.677592)
		(end 415.259266 -422.301416)
		(width 0.14224)
		(layer "In6.Cu")
		(net "P5E_CPU0_P3_TX_BUF_C_DP<14>")
	)
	(segment
		(start 410.003244 -424.608498)
		(end 410.003244 -426.09008)
		(width 0.14224)
		(layer "In6.Cu")
		(net "P5E_CPU0_P3_TX_BUF_C_DP<14>")
	)
	(segment
		(start 410.59354 -426.583856)
		(end 410.750004 -426.427392)
		(width 0.14224)
		(layer "In6.Cu")
		(net "P5E_CPU0_P3_TX_BUF_C_DP<14>")
	)
	(segment
		(start 416.023044 -420.28618)
		(end 416.023044 -420.57066)
		(width 0.14224)
		(layer "In6.Cu")
		(net "P5E_CPU0_P3_TX_BUF_C_DP<14>")
	)
	(segment
		(start 415.259266 -422.301416)
		(end 414.701736 -422.470326)
		(width 0.14224)
		(layer "In6.Cu")
		(net "P5E_CPU0_P3_TX_BUF_C_DP<14>")
	)
	(segment
		(start 411.225746 -423.525442)
		(end 410.817568 -423.64914)
		(width 0.14224)
		(layer "In6.Cu")
		(net "P5E_CPU0_P3_TX_BUF_C_DP<14>")
	)
	(segment
		(start 416.023044 -419.723316)
		(end 415.883852 -419.862508)
		(width 0.14224)
		(layer "In6.Cu")
		(net "P5E_CPU0_P3_TX_BUF_C_DP<14>")
	)
	(segment
		(start 414.030668 -422.674288)
		(end 411.87751 -423.327576)
		(width 0.14224)
		(layer "In6.Cu")
		(net "P5E_CPU0_P3_TX_BUF_C_DP<14>")
	)
	(segment
		(start 414.701736 -422.470326)
		(end 414.610296 -422.641776)
		(width 0.14224)
		(layer "In6.Cu")
		(net "P5E_CPU0_P3_TX_BUF_C_DP<14>")
	)
	(segment
		(start 415.883852 -418.702998)
		(end 415.883852 -419.299644)
		(width 0.14224)
		(layer "In6.Cu")
		(net "P5E_CPU0_P3_TX_BUF_C_DP<14>")
	)
	(segment
		(start 411.87751 -423.327576)
		(end 411.792674 -423.486072)
		(width 0.14224)
		(layer "In6.Cu")
		(net "P5E_CPU0_P3_TX_BUF_C_DP<14>")
	)
	(segment
		(start 410.750004 -426.427392)
		(end 410.750004 -426.089826)
		(width 0.14224)
		(layer "In6.Cu")
		(net "P5E_CPU0_P3_TX_BUF_C_DP<14>")
	)
	(segment
		(start 414.20161 -422.765728)
		(end 414.030668 -422.674288)
		(width 0.14224)
		(layer "In6.Cu")
		(net "P5E_CPU0_P3_TX_BUF_C_DP<14>")
	)
	(segment
		(start 411.792674 -423.486072)
		(end 411.384242 -423.610024)
		(width 0.14224)
		(layer "In6.Cu")
		(net "P5E_CPU0_P3_TX_BUF_C_DP<14>")
	)
	(segment
		(start 415.883852 -419.299644)
		(end 416.023044 -419.438836)
		(width 0.14224)
		(layer "In6.Cu")
		(net "P5E_CPU0_P3_TX_BUF_C_DP<14>")
	)
	(segment
		(start 411.384242 -423.610024)
		(end 411.225746 -423.525442)
		(width 0.14224)
		(layer "In6.Cu")
		(net "P5E_CPU0_P3_TX_BUF_C_DP<14>")
	)
	(segment
		(start 410.817568 -423.64914)
		(end 410.10586 -424.360848)
		(width 0.14224)
		(layer "In6.Cu")
		(net "P5E_CPU0_P3_TX_BUF_C_DP<14>")
	)
	(segment
		(start 415.883852 -420.709852)
		(end 415.883852 -421.677592)
		(width 0.14224)
		(layer "In6.Cu")
		(net "P5E_CPU0_P3_TX_BUF_C_DP<14>")
	)
	(segment
		(start 416.174682 -418.412168)
		(end 415.883852 -418.702998)
		(width 0.14224)
		(layer "In6.Cu")
		(net "P5E_CPU0_P3_TX_BUF_C_DP<14>")
	)
	(segment
		(start 416.023044 -420.57066)
		(end 415.883852 -420.709852)
		(width 0.14224)
		(layer "In6.Cu")
		(net "P5E_CPU0_P3_TX_BUF_C_DP<14>")
	)
	(segment
		(start 414.610296 -422.641776)
		(end 414.20161 -422.765728)
		(width 0.14224)
		(layer "In6.Cu")
		(net "P5E_CPU0_P3_TX_BUF_C_DP<14>")
	)
	(segment
		(start 416.023044 -419.438836)
		(end 416.023044 -419.723316)
		(width 0.14224)
		(layer "In6.Cu")
		(net "P5E_CPU0_P3_TX_BUF_C_DP<14>")
	)
	(segment
		(start 410.173932 -426.501814)
		(end 410.20492 -426.532802)
		(width 0.14224)
		(layer "In6.Cu")
		(net "P5E_CPU0_P3_TX_BUF_C_DP<14>")
	)
	(segment
		(start 415.883852 -419.862508)
		(end 415.883852 -420.146988)
		(width 0.14224)
		(layer "In6.Cu")
		(net "P5E_CPU0_P3_TX_BUF_C_DP<14>")
	)
	(segment
		(start 415.883852 -420.146988)
		(end 416.023044 -420.28618)
		(width 0.14224)
		(layer "In6.Cu")
		(net "P5E_CPU0_P3_TX_BUF_C_DP<14>")
	)
	(arc
		(start 410.20492 -426.532802)
		(mid 410.261557 -426.570645)
		(end 410.328364 -426.583856)
		(width 0.14224)
		(layer "In6.Cu")
		(net "P5E_CPU0_P3_TX_BUF_C_DP<14>")
	)
	(arc
		(start 410.10586 -424.360848)
		(mid 410.02994 -424.474471)
		(end 410.003244 -424.608498)
		(width 0.14224)
		(layer "In6.Cu")
		(net "P5E_CPU0_P3_TX_BUF_C_DP<14>")
	)
	(arc
		(start 410.003244 -426.09008)
		(mid 410.047608 -426.312935)
		(end 410.173932 -426.501814)
		(width 0.14224)
		(layer "In6.Cu")
		(net "P5E_CPU0_P3_TX_BUF_C_DP<14>")
	)
	(segment
		(start 412.840932 -417.461954)
		(end 412.840932 -418.141658)
		(width 0.12954)
		(layer "B.Cu")
		(net "P5E_CPU0_P3_TX_BUF_C_DP<13>")
	)
	(segment
		(start 413.136842 -417.166044)
		(end 412.840932 -417.461954)
		(width 0.12954)
		(layer "B.Cu")
		(net "P5E_CPU0_P3_TX_BUF_C_DP<13>")
	)
	(segment
		(start 412.840932 -418.141658)
		(end 413.111442 -418.412168)
		(width 0.12954)
		(layer "B.Cu")
		(net "P5E_CPU0_P3_TX_BUF_C_DP<13>")
	)
	(segment
		(start 412.485332 -421.917876)
		(end 412.2801 -422.123362)
		(width 0.14224)
		(layer "In6.Cu")
		(net "P5E_CPU0_P3_TX_BUF_C_DP<13>")
	)
	(segment
		(start 409.4607 -423.34688)
		(end 409.44165 -423.53992)
		(width 0.14224)
		(layer "In6.Cu")
		(net "P5E_CPU0_P3_TX_BUF_C_DP<13>")
	)
	(segment
		(start 412.021274 -422.282874)
		(end 411.990794 -422.293034)
		(width 0.14224)
		(layer "In6.Cu")
		(net "P5E_CPU0_P3_TX_BUF_C_DP<13>")
	)
	(segment
		(start 408.607768 -427.548802)
		(end 408.750008 -427.406562)
		(width 0.14224)
		(layer "In6.Cu")
		(net "P5E_CPU0_P3_TX_BUF_C_DP<13>")
	)
	(segment
		(start 409.44165 -423.53992)
		(end 409.111704 -423.810938)
		(width 0.14224)
		(layer "In6.Cu")
		(net "P5E_CPU0_P3_TX_BUF_C_DP<13>")
	)
	(segment
		(start 408.446986 -427.548802)
		(end 408.607768 -427.548802)
		(width 0.14224)
		(layer "In6.Cu")
		(net "P5E_CPU0_P3_TX_BUF_C_DP<13>")
	)
	(segment
		(start 413.111442 -418.412168)
		(end 412.820612 -418.702998)
		(width 0.14224)
		(layer "In6.Cu")
		(net "P5E_CPU0_P3_TX_BUF_C_DP<13>")
	)
	(segment
		(start 412.957772 -419.632638)
		(end 412.957772 -420.059358)
		(width 0.14224)
		(layer "In6.Cu")
		(net "P5E_CPU0_P3_TX_BUF_C_DP<13>")
	)
	(segment
		(start 408.089354 -424.871896)
		(end 408.089354 -427.245526)
		(width 0.14224)
		(layer "In6.Cu")
		(net "P5E_CPU0_P3_TX_BUF_C_DP<13>")
	)
	(segment
		(start 412.820612 -418.702998)
		(end 412.820612 -419.495478)
		(width 0.14224)
		(layer "In6.Cu")
		(net "P5E_CPU0_P3_TX_BUF_C_DP<13>")
	)
	(segment
		(start 412.820612 -420.196518)
		(end 412.820612 -421.108378)
		(width 0.14224)
		(layer "In6.Cu")
		(net "P5E_CPU0_P3_TX_BUF_C_DP<13>")
	)
	(segment
		(start 408.089608 -424.87215)
		(end 408.089354 -424.871896)
		(width 0.14224)
		(layer "In6.Cu")
		(net "P5E_CPU0_P3_TX_BUF_C_DP<13>")
	)
	(segment
		(start 410.66212 -422.360852)
		(end 410.332428 -422.631362)
		(width 0.14224)
		(layer "In6.Cu")
		(net "P5E_CPU0_P3_TX_BUF_C_DP<13>")
	)
	(segment
		(start 409.111704 -423.810938)
		(end 408.918664 -423.791888)
		(width 0.14224)
		(layer "In6.Cu")
		(net "P5E_CPU0_P3_TX_BUF_C_DP<13>")
	)
	(segment
		(start 408.918664 -423.791888)
		(end 408.398472 -424.218862)
		(width 0.14224)
		(layer "In6.Cu")
		(net "P5E_CPU0_P3_TX_BUF_C_DP<13>")
	)
	(segment
		(start 409.983432 -423.09542)
		(end 409.790392 -423.07637)
		(width 0.14224)
		(layer "In6.Cu")
		(net "P5E_CPU0_P3_TX_BUF_C_DP<13>")
	)
	(segment
		(start 412.957772 -420.059358)
		(end 412.820612 -420.196518)
		(width 0.14224)
		(layer "In6.Cu")
		(net "P5E_CPU0_P3_TX_BUF_C_DP<13>")
	)
	(segment
		(start 408.750008 -427.406562)
		(end 408.750008 -427.089824)
		(width 0.14224)
		(layer "In6.Cu")
		(net "P5E_CPU0_P3_TX_BUF_C_DP<13>")
	)
	(segment
		(start 410.332428 -422.631362)
		(end 410.313378 -422.824402)
		(width 0.14224)
		(layer "In6.Cu")
		(net "P5E_CPU0_P3_TX_BUF_C_DP<13>")
	)
	(segment
		(start 408.161998 -427.420786)
		(end 408.179016 -427.437804)
		(width 0.14224)
		(layer "In6.Cu")
		(net "P5E_CPU0_P3_TX_BUF_C_DP<13>")
	)
	(segment
		(start 409.790392 -423.07637)
		(end 409.4607 -423.34688)
		(width 0.14224)
		(layer "In6.Cu")
		(net "P5E_CPU0_P3_TX_BUF_C_DP<13>")
	)
	(segment
		(start 412.820612 -419.495478)
		(end 412.957772 -419.632638)
		(width 0.14224)
		(layer "In6.Cu")
		(net "P5E_CPU0_P3_TX_BUF_C_DP<13>")
	)
	(segment
		(start 410.313378 -422.824402)
		(end 409.983432 -423.09542)
		(width 0.14224)
		(layer "In6.Cu")
		(net "P5E_CPU0_P3_TX_BUF_C_DP<13>")
	)
	(segment
		(start 411.777688 -422.326562)
		(end 410.757624 -422.326562)
		(width 0.14224)
		(layer "In6.Cu")
		(net "P5E_CPU0_P3_TX_BUF_C_DP<13>")
	)
	(arc
		(start 411.990794 -422.293034)
		(mid 411.885576 -422.318295)
		(end 411.777688 -422.326562)
		(width 0.14224)
		(layer "In6.Cu")
		(net "P5E_CPU0_P3_TX_BUF_C_DP<13>")
	)
	(arc
		(start 408.089354 -427.245526)
		(mid 408.10824 -427.340381)
		(end 408.161998 -427.420786)
		(width 0.14224)
		(layer "In6.Cu")
		(net "P5E_CPU0_P3_TX_BUF_C_DP<13>")
	)
	(arc
		(start 408.398472 -424.218862)
		(mid 408.170711 -424.510838)
		(end 408.089608 -424.87215)
		(width 0.14224)
		(layer "In6.Cu")
		(net "P5E_CPU0_P3_TX_BUF_C_DP<13>")
	)
	(arc
		(start 410.757624 -422.326562)
		(mid 410.706911 -422.335447)
		(end 410.66212 -422.360852)
		(width 0.14224)
		(layer "In6.Cu")
		(net "P5E_CPU0_P3_TX_BUF_C_DP<13>")
	)
	(arc
		(start 412.2801 -422.123362)
		(mid 412.160073 -422.218353)
		(end 412.021274 -422.282874)
		(width 0.14224)
		(layer "In6.Cu")
		(net "P5E_CPU0_P3_TX_BUF_C_DP<13>")
	)
	(arc
		(start 408.179016 -427.437804)
		(mid 408.301962 -427.519954)
		(end 408.446986 -427.548802)
		(width 0.14224)
		(layer "In6.Cu")
		(net "P5E_CPU0_P3_TX_BUF_C_DP<13>")
	)
	(arc
		(start 412.820612 -421.108378)
		(mid 412.733471 -421.546466)
		(end 412.485332 -421.917876)
		(width 0.14224)
		(layer "In6.Cu")
		(net "P5E_CPU0_P3_TX_BUF_C_DP<13>")
	)
	(segment
		(start 409.759912 -417.479734)
		(end 409.759912 -418.123878)
		(width 0.12954)
		(layer "B.Cu")
		(net "P5E_CPU0_P3_TX_BUF_C_DP<12>")
	)
	(segment
		(start 410.073602 -417.166044)
		(end 409.759912 -417.479734)
		(width 0.12954)
		(layer "B.Cu")
		(net "P5E_CPU0_P3_TX_BUF_C_DP<12>")
	)
	(segment
		(start 409.759912 -418.123878)
		(end 410.048202 -418.412168)
		(width 0.12954)
		(layer "B.Cu")
		(net "P5E_CPU0_P3_TX_BUF_C_DP<12>")
	)
	(segment
		(start 408.98826 -422.472612)
		(end 408.648408 -422.731184)
		(width 0.14224)
		(layer "In6.Cu")
		(net "P5E_CPU0_P3_TX_BUF_C_DP<12>")
	)
	(segment
		(start 409.757372 -418.702998)
		(end 409.757372 -419.80104)
		(width 0.14224)
		(layer "In6.Cu")
		(net "P5E_CPU0_P3_TX_BUF_C_DP<12>")
	)
	(segment
		(start 409.757372 -420.50208)
		(end 409.757372 -421.448992)
		(width 0.14224)
		(layer "In6.Cu")
		(net "P5E_CPU0_P3_TX_BUF_C_DP<12>")
	)
	(segment
		(start 406.750012 -426.421804)
		(end 406.750012 -426.089826)
		(width 0.14224)
		(layer "In6.Cu")
		(net "P5E_CPU0_P3_TX_BUF_C_DP<12>")
	)
	(segment
		(start 408.116786 -422.96334)
		(end 408.090624 -423.155618)
		(width 0.14224)
		(layer "In6.Cu")
		(net "P5E_CPU0_P3_TX_BUF_C_DP<12>")
	)
	(segment
		(start 408.45613 -422.705022)
		(end 408.116786 -422.96334)
		(width 0.14224)
		(layer "In6.Cu")
		(net "P5E_CPU0_P3_TX_BUF_C_DP<12>")
	)
	(segment
		(start 410.048202 -418.412168)
		(end 409.757372 -418.702998)
		(width 0.14224)
		(layer "In6.Cu")
		(net "P5E_CPU0_P3_TX_BUF_C_DP<12>")
	)
	(segment
		(start 406.661112 -424.071034)
		(end 406.260554 -424.375834)
		(width 0.14224)
		(layer "In6.Cu")
		(net "P5E_CPU0_P3_TX_BUF_C_DP<12>")
	)
	(segment
		(start 407.558494 -423.388028)
		(end 407.21915 -423.646346)
		(width 0.14224)
		(layer "In6.Cu")
		(net "P5E_CPU0_P3_TX_BUF_C_DP<12>")
	)
	(segment
		(start 406.059386 -424.781218)
		(end 406.059386 -426.217334)
		(width 0.14224)
		(layer "In6.Cu")
		(net "P5E_CPU0_P3_TX_BUF_C_DP<12>")
	)
	(segment
		(start 407.750772 -423.41419)
		(end 407.558494 -423.388028)
		(width 0.14224)
		(layer "In6.Cu")
		(net "P5E_CPU0_P3_TX_BUF_C_DP<12>")
	)
	(segment
		(start 406.15108 -426.438568)
		(end 406.157938 -426.445426)
		(width 0.14224)
		(layer "In6.Cu")
		(net "P5E_CPU0_P3_TX_BUF_C_DP<12>")
	)
	(segment
		(start 409.757372 -419.80104)
		(end 409.894532 -419.9382)
		(width 0.14224)
		(layer "In6.Cu")
		(net "P5E_CPU0_P3_TX_BUF_C_DP<12>")
	)
	(segment
		(start 406.623012 -426.548804)
		(end 406.750012 -426.421804)
		(width 0.14224)
		(layer "In6.Cu")
		(net "P5E_CPU0_P3_TX_BUF_C_DP<12>")
	)
	(segment
		(start 409.637484 -421.738298)
		(end 409.353766 -422.022016)
		(width 0.14224)
		(layer "In6.Cu")
		(net "P5E_CPU0_P3_TX_BUF_C_DP<12>")
	)
	(segment
		(start 409.353766 -422.022016)
		(end 409.014422 -422.280334)
		(width 0.14224)
		(layer "In6.Cu")
		(net "P5E_CPU0_P3_TX_BUF_C_DP<12>")
	)
	(segment
		(start 409.014422 -422.280334)
		(end 408.98826 -422.472612)
		(width 0.14224)
		(layer "In6.Cu")
		(net "P5E_CPU0_P3_TX_BUF_C_DP<12>")
	)
	(segment
		(start 406.853136 -424.097196)
		(end 406.661112 -424.071034)
		(width 0.14224)
		(layer "In6.Cu")
		(net "P5E_CPU0_P3_TX_BUF_C_DP<12>")
	)
	(segment
		(start 407.21915 -423.646346)
		(end 407.192988 -423.838624)
		(width 0.14224)
		(layer "In6.Cu")
		(net "P5E_CPU0_P3_TX_BUF_C_DP<12>")
	)
	(segment
		(start 406.432512 -426.548804)
		(end 406.623012 -426.548804)
		(width 0.14224)
		(layer "In6.Cu")
		(net "P5E_CPU0_P3_TX_BUF_C_DP<12>")
	)
	(segment
		(start 408.648408 -422.731184)
		(end 408.45613 -422.705022)
		(width 0.14224)
		(layer "In6.Cu")
		(net "P5E_CPU0_P3_TX_BUF_C_DP<12>")
	)
	(segment
		(start 408.090624 -423.155618)
		(end 407.750772 -423.41419)
		(width 0.14224)
		(layer "In6.Cu")
		(net "P5E_CPU0_P3_TX_BUF_C_DP<12>")
	)
	(segment
		(start 409.894532 -420.36492)
		(end 409.757372 -420.50208)
		(width 0.14224)
		(layer "In6.Cu")
		(net "P5E_CPU0_P3_TX_BUF_C_DP<12>")
	)
	(segment
		(start 409.894532 -419.9382)
		(end 409.894532 -420.36492)
		(width 0.14224)
		(layer "In6.Cu")
		(net "P5E_CPU0_P3_TX_BUF_C_DP<12>")
	)
	(segment
		(start 407.192988 -423.838624)
		(end 406.853136 -424.097196)
		(width 0.14224)
		(layer "In6.Cu")
		(net "P5E_CPU0_P3_TX_BUF_C_DP<12>")
	)
	(arc
		(start 409.757372 -421.448992)
		(mid 409.726209 -421.60557)
		(end 409.637484 -421.738298)
		(width 0.14224)
		(layer "In6.Cu")
		(net "P5E_CPU0_P3_TX_BUF_C_DP<12>")
	)
	(arc
		(start 406.059386 -426.217334)
		(mid 406.083221 -426.337072)
		(end 406.15108 -426.438568)
		(width 0.14224)
		(layer "In6.Cu")
		(net "P5E_CPU0_P3_TX_BUF_C_DP<12>")
	)
	(arc
		(start 406.263348 -426.51553)
		(mid 406.346315 -426.540376)
		(end 406.432512 -426.548804)
		(width 0.14224)
		(layer "In6.Cu")
		(net "P5E_CPU0_P3_TX_BUF_C_DP<12>")
	)
	(arc
		(start 406.157938 -426.445426)
		(mid 406.207129 -426.485766)
		(end 406.263348 -426.51553)
		(width 0.14224)
		(layer "In6.Cu")
		(net "P5E_CPU0_P3_TX_BUF_C_DP<12>")
	)
	(arc
		(start 406.260554 -424.375834)
		(mid 406.112489 -424.554965)
		(end 406.059386 -424.781218)
		(width 0.14224)
		(layer "In6.Cu")
		(net "P5E_CPU0_P3_TX_BUF_C_DP<12>")
	)
	(segment
		(start 407.010362 -417.166044)
		(end 406.714452 -417.461954)
		(width 0.12954)
		(layer "B.Cu")
		(net "P5E_CPU0_P3_TX_BUF_C_DP<11>")
	)
	(segment
		(start 406.714452 -417.461954)
		(end 406.714452 -418.141658)
		(width 0.12954)
		(layer "B.Cu")
		(net "P5E_CPU0_P3_TX_BUF_C_DP<11>")
	)
	(segment
		(start 406.714452 -418.141658)
		(end 406.984962 -418.412168)
		(width 0.12954)
		(layer "B.Cu")
		(net "P5E_CPU0_P3_TX_BUF_C_DP<11>")
	)
	(segment
		(start 406.984962 -418.412168)
		(end 406.694132 -418.702998)
		(width 0.14224)
		(layer "In6.Cu")
		(net "P5E_CPU0_P3_TX_BUF_C_DP<11>")
	)
	(segment
		(start 404.750016 -427.406562)
		(end 404.750016 -427.089824)
		(width 0.14224)
		(layer "In6.Cu")
		(net "P5E_CPU0_P3_TX_BUF_C_DP<11>")
	)
	(segment
		(start 404.348442 -427.548802)
		(end 404.607776 -427.548802)
		(width 0.14224)
		(layer "In6.Cu")
		(net "P5E_CPU0_P3_TX_BUF_C_DP<11>")
	)
	(segment
		(start 404.607776 -427.548802)
		(end 404.750016 -427.406562)
		(width 0.14224)
		(layer "In6.Cu")
		(net "P5E_CPU0_P3_TX_BUF_C_DP<11>")
	)
	(segment
		(start 405.266144 -423.058336)
		(end 404.964646 -423.359834)
		(width 0.14224)
		(layer "In6.Cu")
		(net "P5E_CPU0_P3_TX_BUF_C_DP<11>")
	)
	(segment
		(start 404.66264 -423.855642)
		(end 404.468838 -423.855642)
		(width 0.14224)
		(layer "In6.Cu")
		(net "P5E_CPU0_P3_TX_BUF_C_DP<11>")
	)
	(segment
		(start 404.18385 -427.479968)
		(end 404.184866 -427.480984)
		(width 0.14224)
		(layer "In6.Cu")
		(net "P5E_CPU0_P3_TX_BUF_C_DP<11>")
	)
	(segment
		(start 406.831292 -419.703504)
		(end 406.831292 -420.130224)
		(width 0.14224)
		(layer "In6.Cu")
		(net "P5E_CPU0_P3_TX_BUF_C_DP<11>")
	)
	(segment
		(start 406.831292 -420.130224)
		(end 406.694132 -420.267384)
		(width 0.14224)
		(layer "In6.Cu")
		(net "P5E_CPU0_P3_TX_BUF_C_DP<11>")
	)
	(segment
		(start 404.094696 -424.38574)
		(end 404.094696 -427.26483)
		(width 0.14224)
		(layer "In6.Cu")
		(net "P5E_CPU0_P3_TX_BUF_C_DP<11>")
	)
	(segment
		(start 406.694132 -418.702998)
		(end 406.694132 -419.566344)
		(width 0.14224)
		(layer "In6.Cu")
		(net "P5E_CPU0_P3_TX_BUF_C_DP<11>")
	)
	(segment
		(start 405.762206 -422.562274)
		(end 405.762206 -422.75633)
		(width 0.14224)
		(layer "In6.Cu")
		(net "P5E_CPU0_P3_TX_BUF_C_DP<11>")
	)
	(segment
		(start 404.964646 -423.553636)
		(end 404.66264 -423.855642)
		(width 0.14224)
		(layer "In6.Cu")
		(net "P5E_CPU0_P3_TX_BUF_C_DP<11>")
	)
	(segment
		(start 405.762206 -422.75633)
		(end 405.4602 -423.058336)
		(width 0.14224)
		(layer "In6.Cu")
		(net "P5E_CPU0_P3_TX_BUF_C_DP<11>")
	)
	(segment
		(start 404.468838 -423.855642)
		(end 404.204932 -424.119548)
		(width 0.14224)
		(layer "In6.Cu")
		(net "P5E_CPU0_P3_TX_BUF_C_DP<11>")
	)
	(segment
		(start 406.435306 -421.889174)
		(end 405.762206 -422.562274)
		(width 0.14224)
		(layer "In6.Cu")
		(net "P5E_CPU0_P3_TX_BUF_C_DP<11>")
	)
	(segment
		(start 405.4602 -423.058336)
		(end 405.266144 -423.058336)
		(width 0.14224)
		(layer "In6.Cu")
		(net "P5E_CPU0_P3_TX_BUF_C_DP<11>")
	)
	(segment
		(start 404.964646 -423.359834)
		(end 404.964646 -423.553636)
		(width 0.14224)
		(layer "In6.Cu")
		(net "P5E_CPU0_P3_TX_BUF_C_DP<11>")
	)
	(segment
		(start 406.694132 -419.566344)
		(end 406.831292 -419.703504)
		(width 0.14224)
		(layer "In6.Cu")
		(net "P5E_CPU0_P3_TX_BUF_C_DP<11>")
	)
	(segment
		(start 406.694132 -420.267384)
		(end 406.694132 -421.264334)
		(width 0.14224)
		(layer "In6.Cu")
		(net "P5E_CPU0_P3_TX_BUF_C_DP<11>")
	)
	(arc
		(start 404.094696 -427.26483)
		(mid 404.117874 -427.381263)
		(end 404.18385 -427.479968)
		(width 0.14224)
		(layer "In6.Cu")
		(net "P5E_CPU0_P3_TX_BUF_C_DP<11>")
	)
	(arc
		(start 404.184866 -427.480984)
		(mid 404.259901 -427.531184)
		(end 404.348442 -427.548802)
		(width 0.14224)
		(layer "In6.Cu")
		(net "P5E_CPU0_P3_TX_BUF_C_DP<11>")
	)
	(arc
		(start 406.694132 -421.264334)
		(mid 406.626867 -421.602498)
		(end 406.435306 -421.889174)
		(width 0.14224)
		(layer "In6.Cu")
		(net "P5E_CPU0_P3_TX_BUF_C_DP<11>")
	)
	(arc
		(start 404.204932 -424.119548)
		(mid 404.123327 -424.241678)
		(end 404.094696 -424.38574)
		(width 0.14224)
		(layer "In6.Cu")
		(net "P5E_CPU0_P3_TX_BUF_C_DP<11>")
	)
	(segment
		(start 403.947122 -417.166044)
		(end 403.651212 -417.461954)
		(width 0.12954)
		(layer "B.Cu")
		(net "P5E_CPU0_P3_TX_BUF_C_DP<10>")
	)
	(segment
		(start 403.651212 -418.141658)
		(end 403.921722 -418.412168)
		(width 0.12954)
		(layer "B.Cu")
		(net "P5E_CPU0_P3_TX_BUF_C_DP<10>")
	)
	(segment
		(start 403.651212 -417.461954)
		(end 403.651212 -418.141658)
		(width 0.12954)
		(layer "B.Cu")
		(net "P5E_CPU0_P3_TX_BUF_C_DP<10>")
	)
	(segment
		(start 403.031452 -422.859708)
		(end 402.84908 -423.245788)
		(width 0.14224)
		(layer "In6.Cu")
		(net "P5E_CPU0_P3_TX_BUF_C_DP<10>")
	)
	(segment
		(start 402.966174 -422.677082)
		(end 403.031452 -422.859708)
		(width 0.14224)
		(layer "In6.Cu")
		(net "P5E_CPU0_P3_TX_BUF_C_DP<10>")
	)
	(segment
		(start 402.366988 -424.265344)
		(end 402.184108 -424.330622)
		(width 0.14224)
		(layer "In6.Cu")
		(net "P5E_CPU0_P3_TX_BUF_C_DP<10>")
	)
	(segment
		(start 403.148546 -422.29151)
		(end 402.966174 -422.677082)
		(width 0.14224)
		(layer "In6.Cu")
		(net "P5E_CPU0_P3_TX_BUF_C_DP<10>")
	)
	(segment
		(start 403.630892 -419.502082)
		(end 403.768052 -419.639242)
		(width 0.14224)
		(layer "In6.Cu")
		(net "P5E_CPU0_P3_TX_BUF_C_DP<10>")
	)
	(segment
		(start 403.630892 -421.271954)
		(end 403.44852 -421.657526)
		(width 0.14224)
		(layer "In6.Cu")
		(net "P5E_CPU0_P3_TX_BUF_C_DP<10>")
	)
	(segment
		(start 403.768052 -419.639242)
		(end 403.768052 -420.065962)
		(width 0.14224)
		(layer "In6.Cu")
		(net "P5E_CPU0_P3_TX_BUF_C_DP<10>")
	)
	(segment
		(start 402.590762 -426.565822)
		(end 402.75002 -426.406564)
		(width 0.14224)
		(layer "In6.Cu")
		(net "P5E_CPU0_P3_TX_BUF_C_DP<10>")
	)
	(segment
		(start 403.921722 -418.412168)
		(end 403.630892 -418.702998)
		(width 0.14224)
		(layer "In6.Cu")
		(net "P5E_CPU0_P3_TX_BUF_C_DP<10>")
	)
	(segment
		(start 402.666454 -423.311066)
		(end 402.484082 -423.696638)
		(width 0.14224)
		(layer "In6.Cu")
		(net "P5E_CPU0_P3_TX_BUF_C_DP<10>")
	)
	(segment
		(start 403.513798 -421.840152)
		(end 403.331426 -422.226232)
		(width 0.14224)
		(layer "In6.Cu")
		(net "P5E_CPU0_P3_TX_BUF_C_DP<10>")
	)
	(segment
		(start 403.331426 -422.226232)
		(end 403.148546 -422.29151)
		(width 0.14224)
		(layer "In6.Cu")
		(net "P5E_CPU0_P3_TX_BUF_C_DP<10>")
	)
	(segment
		(start 402.406104 -426.565822)
		(end 402.590762 -426.565822)
		(width 0.14224)
		(layer "In6.Cu")
		(net "P5E_CPU0_P3_TX_BUF_C_DP<10>")
	)
	(segment
		(start 402.54936 -423.879264)
		(end 402.366988 -424.265344)
		(width 0.14224)
		(layer "In6.Cu")
		(net "P5E_CPU0_P3_TX_BUF_C_DP<10>")
	)
	(segment
		(start 402.14804 -426.457618)
		(end 402.150072 -426.45965)
		(width 0.14224)
		(layer "In6.Cu")
		(net "P5E_CPU0_P3_TX_BUF_C_DP<10>")
	)
	(segment
		(start 402.484082 -423.696638)
		(end 402.54936 -423.879264)
		(width 0.14224)
		(layer "In6.Cu")
		(net "P5E_CPU0_P3_TX_BUF_C_DP<10>")
	)
	(segment
		(start 403.630892 -418.702998)
		(end 403.630892 -419.502082)
		(width 0.14224)
		(layer "In6.Cu")
		(net "P5E_CPU0_P3_TX_BUF_C_DP<10>")
	)
	(segment
		(start 402.84908 -423.245788)
		(end 402.666454 -423.311066)
		(width 0.14224)
		(layer "In6.Cu")
		(net "P5E_CPU0_P3_TX_BUF_C_DP<10>")
	)
	(segment
		(start 401.998942 -426.097954)
		(end 401.999196 -426.0977)
		(width 0.14224)
		(layer "In6.Cu")
		(net "P5E_CPU0_P3_TX_BUF_C_DP<10>")
	)
	(segment
		(start 401.998942 -424.722036)
		(end 401.998942 -426.097954)
		(width 0.14224)
		(layer "In6.Cu")
		(net "P5E_CPU0_P3_TX_BUF_C_DP<10>")
	)
	(segment
		(start 403.630892 -420.203122)
		(end 403.630892 -421.271954)
		(width 0.14224)
		(layer "In6.Cu")
		(net "P5E_CPU0_P3_TX_BUF_C_DP<10>")
	)
	(segment
		(start 402.184108 -424.330622)
		(end 401.998942 -424.722036)
		(width 0.14224)
		(layer "In6.Cu")
		(net "P5E_CPU0_P3_TX_BUF_C_DP<10>")
	)
	(segment
		(start 403.44852 -421.657526)
		(end 403.513798 -421.840152)
		(width 0.14224)
		(layer "In6.Cu")
		(net "P5E_CPU0_P3_TX_BUF_C_DP<10>")
	)
	(segment
		(start 402.75002 -426.406564)
		(end 402.75002 -426.089826)
		(width 0.14224)
		(layer "In6.Cu")
		(net "P5E_CPU0_P3_TX_BUF_C_DP<10>")
	)
	(segment
		(start 403.768052 -420.065962)
		(end 403.630892 -420.203122)
		(width 0.14224)
		(layer "In6.Cu")
		(net "P5E_CPU0_P3_TX_BUF_C_DP<10>")
	)
	(arc
		(start 402.150072 -426.45965)
		(mid 402.26754 -426.538169)
		(end 402.406104 -426.565822)
		(width 0.14224)
		(layer "In6.Cu")
		(net "P5E_CPU0_P3_TX_BUF_C_DP<10>")
	)
	(arc
		(start 401.999196 -426.0977)
		(mid 402.03784 -426.292449)
		(end 402.14804 -426.457618)
		(width 0.14224)
		(layer "In6.Cu")
		(net "P5E_CPU0_P3_TX_BUF_C_DP<10>")
	)
	(segment
		(start 373.018812 -417.461954)
		(end 373.018812 -418.141658)
		(width 0.12954)
		(layer "B.Cu")
		(net "P5E_CPU0_P3_TX_BUF_C_DP<0>")
	)
	(segment
		(start 373.018812 -418.141658)
		(end 373.289322 -418.412168)
		(width 0.12954)
		(layer "B.Cu")
		(net "P5E_CPU0_P3_TX_BUF_C_DP<0>")
	)
	(segment
		(start 373.314722 -417.166044)
		(end 373.018812 -417.461954)
		(width 0.12954)
		(layer "B.Cu")
		(net "P5E_CPU0_P3_TX_BUF_C_DP<0>")
	)
	(segment
		(start 379.404372 -425.794424)
		(end 380.873508 -426.579538)
		(width 0.1143)
		(layer "In6.Cu")
		(net "P5E_CPU0_P3_TX_BUF_C_DP<0>")
	)
	(segment
		(start 374.661938 -423.176192)
		(end 374.964452 -423.33799)
		(width 0.1143)
		(layer "In6.Cu")
		(net "P5E_CPU0_P3_TX_BUF_C_DP<0>")
	)
	(segment
		(start 378.08027 -425.08678)
		(end 378.179838 -425.056554)
		(width 0.1143)
		(layer "In6.Cu")
		(net "P5E_CPU0_P3_TX_BUF_C_DP<0>")
	)
	(segment
		(start 377.37034 -424.623992)
		(end 377.400566 -424.72356)
		(width 0.1143)
		(layer "In6.Cu")
		(net "P5E_CPU0_P3_TX_BUF_C_DP<0>")
	)
	(segment
		(start 373.057928 -421.5003)
		(end 373.661178 -422.628822)
		(width 0.1143)
		(layer "In6.Cu")
		(net "P5E_CPU0_P3_TX_BUF_C_DP<0>")
	)
	(segment
		(start 375.699274 -423.730928)
		(end 375.7295 -423.830496)
		(width 0.1143)
		(layer "In6.Cu")
		(net "P5E_CPU0_P3_TX_BUF_C_DP<0>")
	)
	(segment
		(start 376.464322 -424.22318)
		(end 376.968004 -424.49242)
		(width 0.1143)
		(layer "In6.Cu")
		(net "P5E_CPU0_P3_TX_BUF_C_DP<0>")
	)
	(segment
		(start 377.067572 -424.46194)
		(end 377.37034 -424.623992)
		(width 0.1143)
		(layer "In6.Cu")
		(net "P5E_CPU0_P3_TX_BUF_C_DP<0>")
	)
	(segment
		(start 373.86895 -422.83634)
		(end 374.561862 -423.206418)
		(width 0.1143)
		(layer "In6.Cu")
		(net "P5E_CPU0_P3_TX_BUF_C_DP<0>")
	)
	(segment
		(start 372.952772 -418.748718)
		(end 372.952772 -421.080692)
		(width 0.1143)
		(layer "In6.Cu")
		(net "P5E_CPU0_P3_TX_BUF_C_DP<0>")
	)
	(segment
		(start 374.562116 -423.206418)
		(end 374.661938 -423.176192)
		(width 0.1143)
		(layer "In6.Cu")
		(net "P5E_CPU0_P3_TX_BUF_C_DP<0>")
	)
	(segment
		(start 378.179838 -425.056554)
		(end 378.482606 -425.218352)
		(width 0.1143)
		(layer "In6.Cu")
		(net "P5E_CPU0_P3_TX_BUF_C_DP<0>")
	)
	(segment
		(start 372.952772 -421.080692)
		(end 372.953026 -421.080438)
		(width 0.1143)
		(layer "In6.Cu")
		(net "P5E_CPU0_P3_TX_BUF_C_DP<0>")
	)
	(segment
		(start 376.968004 -424.49242)
		(end 377.067572 -424.46194)
		(width 0.1143)
		(layer "In6.Cu")
		(net "P5E_CPU0_P3_TX_BUF_C_DP<0>")
	)
	(segment
		(start 375.39676 -423.56913)
		(end 375.699274 -423.730928)
		(width 0.1143)
		(layer "In6.Cu")
		(net "P5E_CPU0_P3_TX_BUF_C_DP<0>")
	)
	(segment
		(start 375.7295 -423.830496)
		(end 376.03176 -423.99204)
		(width 0.1143)
		(layer "In6.Cu")
		(net "P5E_CPU0_P3_TX_BUF_C_DP<0>")
	)
	(segment
		(start 378.97181 -425.56303)
		(end 379.071378 -425.532804)
		(width 0.1143)
		(layer "In6.Cu")
		(net "P5E_CPU0_P3_TX_BUF_C_DP<0>")
	)
	(segment
		(start 380.933452 -426.594524)
		(end 381.622808 -426.594524)
		(width 0.1143)
		(layer "In6.Cu")
		(net "P5E_CPU0_P3_TX_BUF_C_DP<0>")
	)
	(segment
		(start 379.071378 -425.532804)
		(end 379.374146 -425.694856)
		(width 0.1143)
		(layer "In6.Cu")
		(net "P5E_CPU0_P3_TX_BUF_C_DP<0>")
	)
	(segment
		(start 378.482606 -425.218352)
		(end 378.512832 -425.31792)
		(width 0.1143)
		(layer "In6.Cu")
		(net "P5E_CPU0_P3_TX_BUF_C_DP<0>")
	)
	(segment
		(start 377.400566 -424.72356)
		(end 378.08027 -425.08678)
		(width 0.1143)
		(layer "In6.Cu")
		(net "P5E_CPU0_P3_TX_BUF_C_DP<0>")
	)
	(segment
		(start 375.296938 -423.599356)
		(end 375.39676 -423.56913)
		(width 0.1143)
		(layer "In6.Cu")
		(net "P5E_CPU0_P3_TX_BUF_C_DP<0>")
	)
	(segment
		(start 374.994678 -423.437812)
		(end 375.296938 -423.599356)
		(width 0.1143)
		(layer "In6.Cu")
		(net "P5E_CPU0_P3_TX_BUF_C_DP<0>")
	)
	(segment
		(start 376.03176 -423.99204)
		(end 376.131582 -423.961814)
		(width 0.1143)
		(layer "In6.Cu")
		(net "P5E_CPU0_P3_TX_BUF_C_DP<0>")
	)
	(segment
		(start 378.512832 -425.31792)
		(end 378.97181 -425.56303)
		(width 0.1143)
		(layer "In6.Cu")
		(net "P5E_CPU0_P3_TX_BUF_C_DP<0>")
	)
	(segment
		(start 376.131582 -423.961814)
		(end 376.434096 -424.123612)
		(width 0.1143)
		(layer "In6.Cu")
		(net "P5E_CPU0_P3_TX_BUF_C_DP<0>")
	)
	(segment
		(start 376.434096 -424.123612)
		(end 376.464322 -424.22318)
		(width 0.1143)
		(layer "In6.Cu")
		(net "P5E_CPU0_P3_TX_BUF_C_DP<0>")
	)
	(segment
		(start 374.964452 -423.33799)
		(end 374.994678 -423.437812)
		(width 0.1143)
		(layer "In6.Cu")
		(net "P5E_CPU0_P3_TX_BUF_C_DP<0>")
	)
	(segment
		(start 381.622808 -426.594524)
		(end 381.749808 -426.467524)
		(width 0.1143)
		(layer "In6.Cu")
		(net "P5E_CPU0_P3_TX_BUF_C_DP<0>")
	)
	(segment
		(start 374.561862 -423.206418)
		(end 374.562116 -423.206418)
		(width 0.1143)
		(layer "In6.Cu")
		(net "P5E_CPU0_P3_TX_BUF_C_DP<0>")
	)
	(segment
		(start 373.289322 -418.412168)
		(end 372.952772 -418.748718)
		(width 0.1143)
		(layer "In6.Cu")
		(net "P5E_CPU0_P3_TX_BUF_C_DP<0>")
	)
	(segment
		(start 381.749808 -426.467524)
		(end 381.749808 -426.089826)
		(width 0.1143)
		(layer "In6.Cu")
		(net "P5E_CPU0_P3_TX_BUF_C_DP<0>")
	)
	(segment
		(start 379.374146 -425.694856)
		(end 379.404372 -425.794424)
		(width 0.1143)
		(layer "In6.Cu")
		(net "P5E_CPU0_P3_TX_BUF_C_DP<0>")
	)
	(arc
		(start 380.873508 -426.579538)
		(mid 380.902559 -426.59071)
		(end 380.933452 -426.594524)
		(width 0.1143)
		(layer "In6.Cu")
		(net "P5E_CPU0_P3_TX_BUF_C_DP<0>")
	)
	(arc
		(start 372.953026 -421.080438)
		(mid 372.979547 -421.29685)
		(end 373.057928 -421.5003)
		(width 0.1143)
		(layer "In6.Cu")
		(net "P5E_CPU0_P3_TX_BUF_C_DP<0>")
	)
	(arc
		(start 373.661178 -422.628822)
		(mid 373.749719 -422.747936)
		(end 373.86895 -422.83634)
		(width 0.1143)
		(layer "In6.Cu")
		(net "P5E_CPU0_P3_TX_BUF_C_DP<0>")
	)
	(segment
		(start 400.265392 -417.461954)
		(end 400.265392 -418.141658)
		(width 0.12954)
		(layer "B.Cu")
		(net "P5E_CPU0_P3_TX_BUF_C_DN<9>")
	)
	(segment
		(start 399.969482 -417.166044)
		(end 400.265392 -417.461954)
		(width 0.12954)
		(layer "B.Cu")
		(net "P5E_CPU0_P3_TX_BUF_C_DN<9>")
	)
	(segment
		(start 400.265392 -418.141658)
		(end 399.994882 -418.412168)
		(width 0.12954)
		(layer "B.Cu")
		(net "P5E_CPU0_P3_TX_BUF_C_DN<9>")
	)
	(segment
		(start 400.285712 -421.119554)
		(end 400.10461 -422.029382)
		(width 0.14224)
		(layer "In6.Cu")
		(net "P5E_CPU0_P3_TX_BUF_C_DN<9>")
	)
	(segment
		(start 400.607784 -427.830742)
		(end 400.750024 -427.972982)
		(width 0.14224)
		(layer "In6.Cu")
		(net "P5E_CPU0_P3_TX_BUF_C_DN<9>")
	)
	(segment
		(start 400.40052 -427.830742)
		(end 400.607784 -427.830742)
		(width 0.14224)
		(layer "In6.Cu")
		(net "P5E_CPU0_P3_TX_BUF_C_DN<9>")
	)
	(segment
		(start 400.285712 -418.702998)
		(end 400.285712 -421.119554)
		(width 0.14224)
		(layer "In6.Cu")
		(net "P5E_CPU0_P3_TX_BUF_C_DN<9>")
	)
	(segment
		(start 399.801842 -425.110148)
		(end 399.801842 -427.19498)
		(width 0.14224)
		(layer "In6.Cu")
		(net "P5E_CPU0_P3_TX_BUF_C_DN<9>")
	)
	(segment
		(start 399.9865 -427.64075)
		(end 400.017996 -427.672246)
		(width 0.14224)
		(layer "In6.Cu")
		(net "P5E_CPU0_P3_TX_BUF_C_DN<9>")
	)
	(segment
		(start 400.750024 -427.972982)
		(end 400.750024 -428.28972)
		(width 0.14224)
		(layer "In6.Cu")
		(net "P5E_CPU0_P3_TX_BUF_C_DN<9>")
	)
	(segment
		(start 399.994882 -418.412168)
		(end 400.285712 -418.702998)
		(width 0.14224)
		(layer "In6.Cu")
		(net "P5E_CPU0_P3_TX_BUF_C_DN<9>")
	)
	(segment
		(start 400.10461 -422.029382)
		(end 399.801842 -425.110148)
		(width 0.14224)
		(layer "In6.Cu")
		(net "P5E_CPU0_P3_TX_BUF_C_DN<9>")
	)
	(arc
		(start 400.017996 -427.672246)
		(mid 400.193485 -427.789567)
		(end 400.40052 -427.830742)
		(width 0.14224)
		(layer "In6.Cu")
		(net "P5E_CPU0_P3_TX_BUF_C_DN<9>")
	)
	(arc
		(start 399.801842 -427.19498)
		(mid 399.84983 -427.436234)
		(end 399.9865 -427.64075)
		(width 0.14224)
		(layer "In6.Cu")
		(net "P5E_CPU0_P3_TX_BUF_C_DN<9>")
	)
	(segment
		(start 396.906242 -417.166044)
		(end 397.186912 -417.446714)
		(width 0.12954)
		(layer "B.Cu")
		(net "P5E_CPU0_P3_TX_BUF_C_DN<8>")
	)
	(segment
		(start 397.186912 -418.156898)
		(end 396.931642 -418.412168)
		(width 0.12954)
		(layer "B.Cu")
		(net "P5E_CPU0_P3_TX_BUF_C_DN<8>")
	)
	(segment
		(start 397.186912 -417.446714)
		(end 397.186912 -418.156898)
		(width 0.12954)
		(layer "B.Cu")
		(net "P5E_CPU0_P3_TX_BUF_C_DN<8>")
	)
	(segment
		(start 398.324578 -426.830744)
		(end 398.607788 -426.830744)
		(width 0.14224)
		(layer "In6.Cu")
		(net "P5E_CPU0_P3_TX_BUF_C_DN<8>")
	)
	(segment
		(start 398.607788 -426.830744)
		(end 398.750028 -426.972984)
		(width 0.14224)
		(layer "In6.Cu")
		(net "P5E_CPU0_P3_TX_BUF_C_DN<8>")
	)
	(segment
		(start 397.570706 -426.429678)
		(end 397.722344 -426.581316)
		(width 0.14224)
		(layer "In6.Cu")
		(net "P5E_CPU0_P3_TX_BUF_C_DN<8>")
	)
	(segment
		(start 398.750028 -426.972984)
		(end 398.750028 -427.289976)
		(width 0.14224)
		(layer "In6.Cu")
		(net "P5E_CPU0_P3_TX_BUF_C_DN<8>")
	)
	(segment
		(start 396.931642 -418.412168)
		(end 397.222472 -418.702998)
		(width 0.14224)
		(layer "In6.Cu")
		(net "P5E_CPU0_P3_TX_BUF_C_DN<8>")
	)
	(segment
		(start 397.222472 -418.702998)
		(end 397.222472 -425.588938)
		(width 0.14224)
		(layer "In6.Cu")
		(net "P5E_CPU0_P3_TX_BUF_C_DN<8>")
	)
	(arc
		(start 397.222472 -425.588938)
		(mid 397.312977 -426.043939)
		(end 397.570706 -426.429678)
		(width 0.14224)
		(layer "In6.Cu")
		(net "P5E_CPU0_P3_TX_BUF_C_DN<8>")
	)
	(arc
		(start 397.722344 -426.581316)
		(mid 397.998651 -426.765939)
		(end 398.324578 -426.830744)
		(width 0.14224)
		(layer "In6.Cu")
		(net "P5E_CPU0_P3_TX_BUF_C_DN<8>")
	)
	(segment
		(start 394.138912 -418.141658)
		(end 393.868402 -418.412168)
		(width 0.12954)
		(layer "B.Cu")
		(net "P5E_CPU0_P3_TX_BUF_C_DN<7>")
	)
	(segment
		(start 393.843002 -417.166044)
		(end 394.138912 -417.461954)
		(width 0.12954)
		(layer "B.Cu")
		(net "P5E_CPU0_P3_TX_BUF_C_DN<7>")
	)
	(segment
		(start 394.138912 -417.461954)
		(end 394.138912 -418.141658)
		(width 0.12954)
		(layer "B.Cu")
		(net "P5E_CPU0_P3_TX_BUF_C_DN<7>")
	)
	(segment
		(start 394.707364 -424.105832)
		(end 394.810234 -424.622722)
		(width 0.14224)
		(layer "In6.Cu")
		(net "P5E_CPU0_P3_TX_BUF_C_DN<7>")
	)
	(segment
		(start 394.70711 -424.105832)
		(end 394.707364 -424.105832)
		(width 0.14224)
		(layer "In6.Cu")
		(net "P5E_CPU0_P3_TX_BUF_C_DN<7>")
	)
	(segment
		(start 395.60754 -427.830742)
		(end 395.74978 -427.972982)
		(width 0.14224)
		(layer "In6.Cu")
		(net "P5E_CPU0_P3_TX_BUF_C_DN<7>")
	)
	(segment
		(start 395.448536 -427.830742)
		(end 395.60754 -427.830742)
		(width 0.14224)
		(layer "In6.Cu")
		(net "P5E_CPU0_P3_TX_BUF_C_DN<7>")
	)
	(segment
		(start 394.980414 -427.62678)
		(end 394.997686 -427.644052)
		(width 0.14224)
		(layer "In6.Cu")
		(net "P5E_CPU0_P3_TX_BUF_C_DN<7>")
	)
	(segment
		(start 393.868402 -418.412168)
		(end 394.159232 -418.702998)
		(width 0.14224)
		(layer "In6.Cu")
		(net "P5E_CPU0_P3_TX_BUF_C_DN<7>")
	)
	(segment
		(start 395.74978 -427.972982)
		(end 395.74978 -428.28972)
		(width 0.14224)
		(layer "In6.Cu")
		(net "P5E_CPU0_P3_TX_BUF_C_DN<7>")
	)
	(segment
		(start 394.159232 -418.702998)
		(end 394.159232 -421.349678)
		(width 0.14224)
		(layer "In6.Cu")
		(net "P5E_CPU0_P3_TX_BUF_C_DN<7>")
	)
	(segment
		(start 394.810234 -424.622722)
		(end 394.810234 -427.215808)
		(width 0.14224)
		(layer "In6.Cu")
		(net "P5E_CPU0_P3_TX_BUF_C_DN<7>")
	)
	(segment
		(start 394.159232 -421.349678)
		(end 394.70711 -424.105832)
		(width 0.14224)
		(layer "In6.Cu")
		(net "P5E_CPU0_P3_TX_BUF_C_DN<7>")
	)
	(arc
		(start 394.997686 -427.644052)
		(mid 395.204552 -427.782212)
		(end 395.448536 -427.830742)
		(width 0.14224)
		(layer "In6.Cu")
		(net "P5E_CPU0_P3_TX_BUF_C_DN<7>")
	)
	(arc
		(start 394.810234 -427.215808)
		(mid 394.854457 -427.438219)
		(end 394.980414 -427.62678)
		(width 0.14224)
		(layer "In6.Cu")
		(net "P5E_CPU0_P3_TX_BUF_C_DN<7>")
	)
	(segment
		(start 390.779762 -417.166044)
		(end 391.075672 -417.461954)
		(width 0.12954)
		(layer "B.Cu")
		(net "P5E_CPU0_P3_TX_BUF_C_DN<6>")
	)
	(segment
		(start 391.075672 -418.141658)
		(end 390.805162 -418.412168)
		(width 0.12954)
		(layer "B.Cu")
		(net "P5E_CPU0_P3_TX_BUF_C_DN<6>")
	)
	(segment
		(start 391.075672 -417.461954)
		(end 391.075672 -418.141658)
		(width 0.12954)
		(layer "B.Cu")
		(net "P5E_CPU0_P3_TX_BUF_C_DN<6>")
	)
	(segment
		(start 391.095992 -421.433498)
		(end 392.52525 -424.884342)
		(width 0.14224)
		(layer "In6.Cu")
		(net "P5E_CPU0_P3_TX_BUF_C_DN<6>")
	)
	(segment
		(start 393.61872 -426.849794)
		(end 393.749784 -426.980858)
		(width 0.14224)
		(layer "In6.Cu")
		(net "P5E_CPU0_P3_TX_BUF_C_DN<6>")
	)
	(segment
		(start 393.587224 -426.849794)
		(end 393.61872 -426.849794)
		(width 0.14224)
		(layer "In6.Cu")
		(net "P5E_CPU0_P3_TX_BUF_C_DN<6>")
	)
	(segment
		(start 391.095992 -418.702998)
		(end 391.095992 -421.433498)
		(width 0.14224)
		(layer "In6.Cu")
		(net "P5E_CPU0_P3_TX_BUF_C_DN<6>")
	)
	(segment
		(start 393.400534 -426.848778)
		(end 393.587224 -426.849794)
		(width 0.14224)
		(layer "In6.Cu")
		(net "P5E_CPU0_P3_TX_BUF_C_DN<6>")
	)
	(segment
		(start 392.655044 -425.53763)
		(end 392.655044 -425.887642)
		(width 0.14224)
		(layer "In6.Cu")
		(net "P5E_CPU0_P3_TX_BUF_C_DN<6>")
	)
	(segment
		(start 393.749784 -426.980858)
		(end 393.749784 -427.289976)
		(width 0.14224)
		(layer "In6.Cu")
		(net "P5E_CPU0_P3_TX_BUF_C_DN<6>")
	)
	(segment
		(start 392.974322 -426.660056)
		(end 393.004548 -426.689266)
		(width 0.14224)
		(layer "In6.Cu")
		(net "P5E_CPU0_P3_TX_BUF_C_DN<6>")
	)
	(segment
		(start 390.805162 -418.412168)
		(end 391.095992 -418.702998)
		(width 0.14224)
		(layer "In6.Cu")
		(net "P5E_CPU0_P3_TX_BUF_C_DN<6>")
	)
	(arc
		(start 392.52525 -424.884342)
		(mid 392.62231 -425.204596)
		(end 392.655044 -425.53763)
		(width 0.14224)
		(layer "In6.Cu")
		(net "P5E_CPU0_P3_TX_BUF_C_DN<6>")
	)
	(arc
		(start 392.655044 -425.887642)
		(mid 392.738115 -426.305492)
		(end 392.974322 -426.660056)
		(width 0.14224)
		(layer "In6.Cu")
		(net "P5E_CPU0_P3_TX_BUF_C_DN<6>")
	)
	(arc
		(start 393.004548 -426.689266)
		(mid 393.187275 -426.806926)
		(end 393.400534 -426.848778)
		(width 0.14224)
		(layer "In6.Cu")
		(net "P5E_CPU0_P3_TX_BUF_C_DN<6>")
	)
	(segment
		(start 387.716522 -417.166044)
		(end 388.012432 -417.461954)
		(width 0.12954)
		(layer "B.Cu")
		(net "P5E_CPU0_P3_TX_BUF_C_DN<5>")
	)
	(segment
		(start 388.012432 -418.141658)
		(end 387.741922 -418.412168)
		(width 0.12954)
		(layer "B.Cu")
		(net "P5E_CPU0_P3_TX_BUF_C_DN<5>")
	)
	(segment
		(start 388.012432 -417.461954)
		(end 388.012432 -418.141658)
		(width 0.12954)
		(layer "B.Cu")
		(net "P5E_CPU0_P3_TX_BUF_C_DN<5>")
	)
	(segment
		(start 391.607548 -427.830742)
		(end 391.749788 -427.972982)
		(width 0.14224)
		(layer "In6.Cu")
		(net "P5E_CPU0_P3_TX_BUF_C_DN<5>")
	)
	(segment
		(start 390.807194 -425.48175)
		(end 390.807194 -427.22927)
		(width 0.14224)
		(layer "In6.Cu")
		(net "P5E_CPU0_P3_TX_BUF_C_DN<5>")
	)
	(segment
		(start 391.749788 -427.972982)
		(end 391.749788 -428.28972)
		(width 0.14224)
		(layer "In6.Cu")
		(net "P5E_CPU0_P3_TX_BUF_C_DN<5>")
	)
	(segment
		(start 388.032752 -418.702998)
		(end 388.032752 -421.123364)
		(width 0.14224)
		(layer "In6.Cu")
		(net "P5E_CPU0_P3_TX_BUF_C_DN<5>")
	)
	(segment
		(start 388.43077 -422.2369)
		(end 390.585706 -424.862498)
		(width 0.14224)
		(layer "In6.Cu")
		(net "P5E_CPU0_P3_TX_BUF_C_DN<5>")
	)
	(segment
		(start 391.389616 -427.830742)
		(end 391.607548 -427.830742)
		(width 0.14224)
		(layer "In6.Cu")
		(net "P5E_CPU0_P3_TX_BUF_C_DN<5>")
	)
	(segment
		(start 390.941052 -427.552358)
		(end 391.09904 -427.710346)
		(width 0.14224)
		(layer "In6.Cu")
		(net "P5E_CPU0_P3_TX_BUF_C_DN<5>")
	)
	(segment
		(start 387.741922 -418.412168)
		(end 388.032752 -418.702998)
		(width 0.14224)
		(layer "In6.Cu")
		(net "P5E_CPU0_P3_TX_BUF_C_DN<5>")
	)
	(arc
		(start 390.807194 -427.22927)
		(mid 390.841977 -427.404136)
		(end 390.941052 -427.552358)
		(width 0.14224)
		(layer "In6.Cu")
		(net "P5E_CPU0_P3_TX_BUF_C_DN<5>")
	)
	(arc
		(start 390.585706 -424.862498)
		(mid 390.750163 -425.152913)
		(end 390.807194 -425.48175)
		(width 0.14224)
		(layer "In6.Cu")
		(net "P5E_CPU0_P3_TX_BUF_C_DN<5>")
	)
	(arc
		(start 388.032752 -421.123364)
		(mid 388.135157 -421.714665)
		(end 388.43077 -422.2369)
		(width 0.14224)
		(layer "In6.Cu")
		(net "P5E_CPU0_P3_TX_BUF_C_DN<5>")
	)
	(arc
		(start 391.09904 -427.710346)
		(mid 391.232357 -427.799426)
		(end 391.389616 -427.830742)
		(width 0.14224)
		(layer "In6.Cu")
		(net "P5E_CPU0_P3_TX_BUF_C_DN<5>")
	)
	(segment
		(start 384.949192 -417.461954)
		(end 384.949192 -418.141658)
		(width 0.12954)
		(layer "B.Cu")
		(net "P5E_CPU0_P3_TX_BUF_C_DN<4>")
	)
	(segment
		(start 384.653282 -417.166044)
		(end 384.949192 -417.461954)
		(width 0.12954)
		(layer "B.Cu")
		(net "P5E_CPU0_P3_TX_BUF_C_DN<4>")
	)
	(segment
		(start 384.949192 -418.141658)
		(end 384.678682 -418.412168)
		(width 0.12954)
		(layer "B.Cu")
		(net "P5E_CPU0_P3_TX_BUF_C_DN<4>")
	)
	(segment
		(start 388.601458 -424.734736)
		(end 388.601458 -425.801282)
		(width 0.14224)
		(layer "In6.Cu")
		(net "P5E_CPU0_P3_TX_BUF_C_DN<4>")
	)
	(segment
		(start 384.678682 -418.412168)
		(end 384.969512 -418.702998)
		(width 0.14224)
		(layer "In6.Cu")
		(net "P5E_CPU0_P3_TX_BUF_C_DN<4>")
	)
	(segment
		(start 388.480554 -424.494706)
		(end 388.601458 -424.734736)
		(width 0.14224)
		(layer "In6.Cu")
		(net "P5E_CPU0_P3_TX_BUF_C_DN<4>")
	)
	(segment
		(start 384.969512 -418.702998)
		(end 384.969512 -421.226234)
		(width 0.14224)
		(layer "In6.Cu")
		(net "P5E_CPU0_P3_TX_BUF_C_DN<4>")
	)
	(segment
		(start 388.878064 -426.469048)
		(end 389.08736 -426.678344)
		(width 0.14224)
		(layer "In6.Cu")
		(net "P5E_CPU0_P3_TX_BUF_C_DN<4>")
	)
	(segment
		(start 385.45135 -422.247568)
		(end 385.810506 -422.51376)
		(width 0.14224)
		(layer "In6.Cu")
		(net "P5E_CPU0_P3_TX_BUF_C_DN<4>")
	)
	(segment
		(start 389.588248 -426.851826)
		(end 389.749792 -427.01337)
		(width 0.14224)
		(layer "In6.Cu")
		(net "P5E_CPU0_P3_TX_BUF_C_DN<4>")
	)
	(segment
		(start 385.35102 -422.147238)
		(end 385.45135 -422.247568)
		(width 0.14224)
		(layer "In6.Cu")
		(net "P5E_CPU0_P3_TX_BUF_C_DN<4>")
	)
	(segment
		(start 389.749792 -427.01337)
		(end 389.749792 -427.289976)
		(width 0.14224)
		(layer "In6.Cu")
		(net "P5E_CPU0_P3_TX_BUF_C_DN<4>")
	)
	(segment
		(start 385.810506 -422.514014)
		(end 388.18566 -424.276012)
		(width 0.14224)
		(layer "In6.Cu")
		(net "P5E_CPU0_P3_TX_BUF_C_DN<4>")
	)
	(segment
		(start 389.50646 -426.851826)
		(end 389.588248 -426.851826)
		(width 0.14224)
		(layer "In6.Cu")
		(net "P5E_CPU0_P3_TX_BUF_C_DN<4>")
	)
	(segment
		(start 388.18566 -424.275758)
		(end 388.480554 -424.494706)
		(width 0.14224)
		(layer "In6.Cu")
		(net "P5E_CPU0_P3_TX_BUF_C_DN<4>")
	)
	(segment
		(start 385.810506 -422.51376)
		(end 385.810506 -422.514014)
		(width 0.14224)
		(layer "In6.Cu")
		(net "P5E_CPU0_P3_TX_BUF_C_DN<4>")
	)
	(segment
		(start 388.18566 -424.276012)
		(end 388.18566 -424.275758)
		(width 0.14224)
		(layer "In6.Cu")
		(net "P5E_CPU0_P3_TX_BUF_C_DN<4>")
	)
	(arc
		(start 388.601458 -425.801282)
		(mid 388.673344 -426.162678)
		(end 388.878064 -426.469048)
		(width 0.14224)
		(layer "In6.Cu")
		(net "P5E_CPU0_P3_TX_BUF_C_DN<4>")
	)
	(arc
		(start 389.08736 -426.678344)
		(mid 389.279632 -426.80682)
		(end 389.50646 -426.851826)
		(width 0.14224)
		(layer "In6.Cu")
		(net "P5E_CPU0_P3_TX_BUF_C_DN<4>")
	)
	(arc
		(start 384.969512 -421.226234)
		(mid 385.06866 -421.724684)
		(end 385.35102 -422.147238)
		(width 0.14224)
		(layer "In6.Cu")
		(net "P5E_CPU0_P3_TX_BUF_C_DN<4>")
	)
	(segment
		(start 381.590042 -417.166044)
		(end 381.885952 -417.461954)
		(width 0.12954)
		(layer "B.Cu")
		(net "P5E_CPU0_P3_TX_BUF_C_DN<3>")
	)
	(segment
		(start 381.885952 -417.461954)
		(end 381.885952 -418.141658)
		(width 0.12954)
		(layer "B.Cu")
		(net "P5E_CPU0_P3_TX_BUF_C_DN<3>")
	)
	(segment
		(start 381.885952 -418.141658)
		(end 381.615442 -418.412168)
		(width 0.12954)
		(layer "B.Cu")
		(net "P5E_CPU0_P3_TX_BUF_C_DN<3>")
	)
	(segment
		(start 386.792216 -424.992546)
		(end 386.792216 -427.256702)
		(width 0.14224)
		(layer "In6.Cu")
		(net "P5E_CPU0_P3_TX_BUF_C_DN<3>")
	)
	(segment
		(start 387.749796 -427.972982)
		(end 387.749796 -428.28972)
		(width 0.14224)
		(layer "In6.Cu")
		(net "P5E_CPU0_P3_TX_BUF_C_DN<3>")
	)
	(segment
		(start 387.607556 -427.830742)
		(end 387.749796 -427.972982)
		(width 0.14224)
		(layer "In6.Cu")
		(net "P5E_CPU0_P3_TX_BUF_C_DN<3>")
	)
	(segment
		(start 382.219454 -421.915844)
		(end 382.499362 -422.195752)
		(width 0.14224)
		(layer "In6.Cu")
		(net "P5E_CPU0_P3_TX_BUF_C_DN<3>")
	)
	(segment
		(start 386.920994 -427.567598)
		(end 386.981192 -427.627796)
		(width 0.14224)
		(layer "In6.Cu")
		(net "P5E_CPU0_P3_TX_BUF_C_DN<3>")
	)
	(segment
		(start 383.590546 -422.647872)
		(end 386.621782 -424.673522)
		(width 0.14224)
		(layer "In6.Cu")
		(net "P5E_CPU0_P3_TX_BUF_C_DN<3>")
	)
	(segment
		(start 381.615442 -418.412168)
		(end 381.906272 -418.702998)
		(width 0.14224)
		(layer "In6.Cu")
		(net "P5E_CPU0_P3_TX_BUF_C_DN<3>")
	)
	(segment
		(start 381.906272 -418.702998)
		(end 381.906272 -421.160194)
		(width 0.14224)
		(layer "In6.Cu")
		(net "P5E_CPU0_P3_TX_BUF_C_DN<3>")
	)
	(segment
		(start 382.499362 -422.195752)
		(end 383.590546 -422.647872)
		(width 0.14224)
		(layer "In6.Cu")
		(net "P5E_CPU0_P3_TX_BUF_C_DN<3>")
	)
	(segment
		(start 387.471158 -427.830742)
		(end 387.607556 -427.830742)
		(width 0.14224)
		(layer "In6.Cu")
		(net "P5E_CPU0_P3_TX_BUF_C_DN<3>")
	)
	(arc
		(start 381.906272 -421.160194)
		(mid 381.9877 -421.569179)
		(end 382.219454 -421.915844)
		(width 0.14224)
		(layer "In6.Cu")
		(net "P5E_CPU0_P3_TX_BUF_C_DN<3>")
	)
	(arc
		(start 386.792216 -427.256702)
		(mid 386.825684 -427.424958)
		(end 386.920994 -427.567598)
		(width 0.14224)
		(layer "In6.Cu")
		(net "P5E_CPU0_P3_TX_BUF_C_DN<3>")
	)
	(arc
		(start 386.621782 -424.673522)
		(mid 386.746937 -424.811698)
		(end 386.792216 -424.992546)
		(width 0.14224)
		(layer "In6.Cu")
		(net "P5E_CPU0_P3_TX_BUF_C_DN<3>")
	)
	(arc
		(start 386.981192 -427.627796)
		(mid 387.20599 -427.778001)
		(end 387.471158 -427.830742)
		(width 0.14224)
		(layer "In6.Cu")
		(net "P5E_CPU0_P3_TX_BUF_C_DN<3>")
	)
	(segment
		(start 378.526802 -417.166044)
		(end 378.822712 -417.461954)
		(width 0.12954)
		(layer "B.Cu")
		(net "P5E_CPU0_P3_TX_BUF_C_DN<2>")
	)
	(segment
		(start 378.822712 -418.141658)
		(end 378.552202 -418.412168)
		(width 0.12954)
		(layer "B.Cu")
		(net "P5E_CPU0_P3_TX_BUF_C_DN<2>")
	)
	(segment
		(start 378.822712 -417.461954)
		(end 378.822712 -418.141658)
		(width 0.12954)
		(layer "B.Cu")
		(net "P5E_CPU0_P3_TX_BUF_C_DN<2>")
	)
	(segment
		(start 383.791968 -424.0022)
		(end 383.792476 -424.002454)
		(width 0.14224)
		(layer "In6.Cu")
		(net "P5E_CPU0_P3_TX_BUF_C_DN<2>")
	)
	(segment
		(start 385.7498 -426.972984)
		(end 385.7498 -427.289976)
		(width 0.14224)
		(layer "In6.Cu")
		(net "P5E_CPU0_P3_TX_BUF_C_DN<2>")
	)
	(segment
		(start 385.60756 -426.830744)
		(end 385.7498 -426.972984)
		(width 0.14224)
		(layer "In6.Cu")
		(net "P5E_CPU0_P3_TX_BUF_C_DN<2>")
	)
	(segment
		(start 379.958854 -422.4147)
		(end 383.791968 -424.0022)
		(width 0.14224)
		(layer "In6.Cu")
		(net "P5E_CPU0_P3_TX_BUF_C_DN<2>")
	)
	(segment
		(start 379.29439 -422.139618)
		(end 379.958854 -422.4147)
		(width 0.14224)
		(layer "In6.Cu")
		(net "P5E_CPU0_P3_TX_BUF_C_DN<2>")
	)
	(segment
		(start 383.973324 -424.077384)
		(end 384.255264 -424.359324)
		(width 0.14224)
		(layer "In6.Cu")
		(net "P5E_CPU0_P3_TX_BUF_C_DN<2>")
	)
	(segment
		(start 378.552202 -418.412168)
		(end 378.843032 -418.702998)
		(width 0.14224)
		(layer "In6.Cu")
		(net "P5E_CPU0_P3_TX_BUF_C_DN<2>")
	)
	(segment
		(start 379.112272 -421.9575)
		(end 379.29439 -422.139618)
		(width 0.14224)
		(layer "In6.Cu")
		(net "P5E_CPU0_P3_TX_BUF_C_DN<2>")
	)
	(segment
		(start 385.502658 -426.830744)
		(end 385.60756 -426.830744)
		(width 0.14224)
		(layer "In6.Cu")
		(net "P5E_CPU0_P3_TX_BUF_C_DN<2>")
	)
	(segment
		(start 378.843032 -418.702998)
		(end 378.843032 -421.30726)
		(width 0.14224)
		(layer "In6.Cu")
		(net "P5E_CPU0_P3_TX_BUF_C_DN<2>")
	)
	(segment
		(start 384.558794 -425.09186)
		(end 384.558794 -425.586398)
		(width 0.14224)
		(layer "In6.Cu")
		(net "P5E_CPU0_P3_TX_BUF_C_DN<2>")
	)
	(segment
		(start 383.792476 -424.002454)
		(end 383.973324 -424.077384)
		(width 0.14224)
		(layer "In6.Cu")
		(net "P5E_CPU0_P3_TX_BUF_C_DN<2>")
	)
	(arc
		(start 384.255264 -424.359324)
		(mid 384.479886 -424.6954)
		(end 384.558794 -425.09186)
		(width 0.14224)
		(layer "In6.Cu")
		(net "P5E_CPU0_P3_TX_BUF_C_DN<2>")
	)
	(arc
		(start 378.843032 -421.30726)
		(mid 378.913008 -421.659144)
		(end 379.112272 -421.9575)
		(width 0.14224)
		(layer "In6.Cu")
		(net "P5E_CPU0_P3_TX_BUF_C_DN<2>")
	)
	(arc
		(start 384.98526 -426.616368)
		(mid 385.22263 -426.775037)
		(end 385.502658 -426.830744)
		(width 0.14224)
		(layer "In6.Cu")
		(net "P5E_CPU0_P3_TX_BUF_C_DN<2>")
	)
	(arc
		(start 384.558794 -425.586398)
		(mid 384.669629 -426.14378)
		(end 384.98526 -426.616368)
		(width 0.14224)
		(layer "In6.Cu")
		(net "P5E_CPU0_P3_TX_BUF_C_DN<2>")
	)
	(segment
		(start 375.463562 -417.166044)
		(end 375.759472 -417.461954)
		(width 0.12954)
		(layer "B.Cu")
		(net "P5E_CPU0_P3_TX_BUF_C_DN<1>")
	)
	(segment
		(start 375.759472 -417.461954)
		(end 375.759472 -418.141658)
		(width 0.12954)
		(layer "B.Cu")
		(net "P5E_CPU0_P3_TX_BUF_C_DN<1>")
	)
	(segment
		(start 375.759472 -418.141658)
		(end 375.488962 -418.412168)
		(width 0.12954)
		(layer "B.Cu")
		(net "P5E_CPU0_P3_TX_BUF_C_DN<1>")
	)
	(segment
		(start 377.113292 -422.533826)
		(end 377.113038 -422.53408)
		(width 0.14224)
		(layer "In6.Cu")
		(net "P5E_CPU0_P3_TX_BUF_C_DN<1>")
	)
	(segment
		(start 382.804924 -425.336716)
		(end 382.804924 -427.157642)
		(width 0.14224)
		(layer "In6.Cu")
		(net "P5E_CPU0_P3_TX_BUF_C_DN<1>")
	)
	(segment
		(start 383.612898 -427.830742)
		(end 383.749804 -427.967648)
		(width 0.14224)
		(layer "In6.Cu")
		(net "P5E_CPU0_P3_TX_BUF_C_DN<1>")
	)
	(segment
		(start 382.452626 -424.557952)
		(end 382.503172 -424.608498)
		(width 0.14224)
		(layer "In6.Cu")
		(net "P5E_CPU0_P3_TX_BUF_C_DN<1>")
	)
	(segment
		(start 383.749804 -427.967648)
		(end 383.749804 -428.28972)
		(width 0.14224)
		(layer "In6.Cu")
		(net "P5E_CPU0_P3_TX_BUF_C_DN<1>")
	)
	(segment
		(start 375.488962 -418.412168)
		(end 375.779792 -418.702998)
		(width 0.14224)
		(layer "In6.Cu")
		(net "P5E_CPU0_P3_TX_BUF_C_DN<1>")
	)
	(segment
		(start 375.91111 -421.833294)
		(end 376.23877 -422.160954)
		(width 0.14224)
		(layer "In6.Cu")
		(net "P5E_CPU0_P3_TX_BUF_C_DN<1>")
	)
	(segment
		(start 383.478024 -427.830742)
		(end 383.612898 -427.830742)
		(width 0.14224)
		(layer "In6.Cu")
		(net "P5E_CPU0_P3_TX_BUF_C_DN<1>")
	)
	(segment
		(start 377.113038 -422.53408)
		(end 381.978916 -424.274234)
		(width 0.14224)
		(layer "In6.Cu")
		(net "P5E_CPU0_P3_TX_BUF_C_DN<1>")
	)
	(segment
		(start 375.779792 -418.702998)
		(end 375.779792 -421.516302)
		(width 0.14224)
		(layer "In6.Cu")
		(net "P5E_CPU0_P3_TX_BUF_C_DN<1>")
	)
	(segment
		(start 376.456956 -422.299384)
		(end 377.113292 -422.533826)
		(width 0.14224)
		(layer "In6.Cu")
		(net "P5E_CPU0_P3_TX_BUF_C_DN<1>")
	)
	(arc
		(start 382.503172 -424.608498)
		(mid 382.726524 -424.942579)
		(end 382.804924 -425.336716)
		(width 0.14224)
		(layer "In6.Cu")
		(net "P5E_CPU0_P3_TX_BUF_C_DN<1>")
	)
	(arc
		(start 381.978916 -424.274234)
		(mid 382.233292 -424.386839)
		(end 382.452626 -424.557952)
		(width 0.14224)
		(layer "In6.Cu")
		(net "P5E_CPU0_P3_TX_BUF_C_DN<1>")
	)
	(arc
		(start 376.23877 -422.160954)
		(mid 376.340188 -422.242264)
		(end 376.456956 -422.299384)
		(width 0.14224)
		(layer "In6.Cu")
		(net "P5E_CPU0_P3_TX_BUF_C_DN<1>")
	)
	(arc
		(start 375.779792 -421.516302)
		(mid 375.813918 -421.687863)
		(end 375.91111 -421.833294)
		(width 0.14224)
		(layer "In6.Cu")
		(net "P5E_CPU0_P3_TX_BUF_C_DN<1>")
	)
	(arc
		(start 382.804924 -427.157642)
		(mid 383.00207 -427.633596)
		(end 383.478024 -427.830742)
		(width 0.14224)
		(layer "In6.Cu")
		(net "P5E_CPU0_P3_TX_BUF_C_DN<1>")
	)
	(segment
		(start 418.348922 -417.166044)
		(end 418.644832 -417.461954)
		(width 0.12954)
		(layer "B.Cu")
		(net "P5E_CPU0_P3_TX_BUF_C_DN<15>")
	)
	(segment
		(start 418.644832 -418.141658)
		(end 418.374322 -418.412168)
		(width 0.12954)
		(layer "B.Cu")
		(net "P5E_CPU0_P3_TX_BUF_C_DN<15>")
	)
	(segment
		(start 418.644832 -417.461954)
		(end 418.644832 -418.141658)
		(width 0.12954)
		(layer "B.Cu")
		(net "P5E_CPU0_P3_TX_BUF_C_DN<15>")
	)
	(segment
		(start 412.790386 -423.754042)
		(end 415.656776 -423.184574)
		(width 0.14224)
		(layer "In6.Cu")
		(net "P5E_CPU0_P3_TX_BUF_C_DN<15>")
	)
	(segment
		(start 418.665152 -418.702998)
		(end 418.374322 -418.412168)
		(width 0.14224)
		(layer "In6.Cu")
		(net "P5E_CPU0_P3_TX_BUF_C_DN<15>")
	)
	(segment
		(start 412.60776 -427.830742)
		(end 412.44139 -427.830742)
		(width 0.14224)
		(layer "In6.Cu")
		(net "P5E_CPU0_P3_TX_BUF_C_DN<15>")
	)
	(segment
		(start 411.971744 -424.191684)
		(end 411.972252 -424.191176)
		(width 0.14224)
		(layer "In6.Cu")
		(net "P5E_CPU0_P3_TX_BUF_C_DN<15>")
	)
	(segment
		(start 418.665152 -421.54475)
		(end 418.665152 -418.702998)
		(width 0.14224)
		(layer "In6.Cu")
		(net "P5E_CPU0_P3_TX_BUF_C_DN<15>")
	)
	(segment
		(start 415.777934 -423.147998)
		(end 418.025072 -422.217088)
		(width 0.14224)
		(layer "In6.Cu")
		(net "P5E_CPU0_P3_TX_BUF_C_DN<15>")
	)
	(segment
		(start 411.791912 -427.267116)
		(end 411.791912 -424.62577)
		(width 0.14224)
		(layer "In6.Cu")
		(net "P5E_CPU0_P3_TX_BUF_C_DN<15>")
	)
	(segment
		(start 418.12972 -422.146984)
		(end 418.617908 -421.658796)
		(width 0.14224)
		(layer "In6.Cu")
		(net "P5E_CPU0_P3_TX_BUF_C_DN<15>")
	)
	(segment
		(start 412.75 -428.28972)
		(end 412.75 -427.972982)
		(width 0.14224)
		(layer "In6.Cu")
		(net "P5E_CPU0_P3_TX_BUF_C_DN<15>")
	)
	(segment
		(start 411.971744 -427.636178)
		(end 411.92577 -427.590204)
		(width 0.14224)
		(layer "In6.Cu")
		(net "P5E_CPU0_P3_TX_BUF_C_DN<15>")
	)
	(segment
		(start 412.75 -427.972982)
		(end 412.60776 -427.830742)
		(width 0.14224)
		(layer "In6.Cu")
		(net "P5E_CPU0_P3_TX_BUF_C_DN<15>")
	)
	(arc
		(start 411.972252 -424.191176)
		(mid 412.348865 -423.911864)
		(end 412.790386 -423.754042)
		(width 0.14224)
		(layer "In6.Cu")
		(net "P5E_CPU0_P3_TX_BUF_C_DN<15>")
	)
	(arc
		(start 411.791912 -424.62577)
		(mid 411.838644 -424.390834)
		(end 411.971744 -424.191684)
		(width 0.14224)
		(layer "In6.Cu")
		(net "P5E_CPU0_P3_TX_BUF_C_DN<15>")
	)
	(arc
		(start 412.44139 -427.830742)
		(mid 412.187208 -427.780182)
		(end 411.971744 -427.636178)
		(width 0.14224)
		(layer "In6.Cu")
		(net "P5E_CPU0_P3_TX_BUF_C_DN<15>")
	)
	(arc
		(start 418.025072 -422.217088)
		(mid 418.080845 -422.187186)
		(end 418.12972 -422.146984)
		(width 0.14224)
		(layer "In6.Cu")
		(net "P5E_CPU0_P3_TX_BUF_C_DN<15>")
	)
	(arc
		(start 418.617908 -421.658796)
		(mid 418.65287 -421.606471)
		(end 418.665152 -421.54475)
		(width 0.14224)
		(layer "In6.Cu")
		(net "P5E_CPU0_P3_TX_BUF_C_DN<15>")
	)
	(arc
		(start 411.92577 -427.590204)
		(mid 411.826723 -427.44197)
		(end 411.791912 -427.267116)
		(width 0.14224)
		(layer "In6.Cu")
		(net "P5E_CPU0_P3_TX_BUF_C_DN<15>")
	)
	(arc
		(start 415.656776 -423.184574)
		(mid 415.718258 -423.169277)
		(end 415.777934 -423.147998)
		(width 0.14224)
		(layer "In6.Cu")
		(net "P5E_CPU0_P3_TX_BUF_C_DN<15>")
	)
	(segment
		(start 415.581592 -418.141658)
		(end 415.311082 -418.412168)
		(width 0.12954)
		(layer "B.Cu")
		(net "P5E_CPU0_P3_TX_BUF_C_DN<14>")
	)
	(segment
		(start 415.285682 -417.166044)
		(end 415.581592 -417.461954)
		(width 0.12954)
		(layer "B.Cu")
		(net "P5E_CPU0_P3_TX_BUF_C_DN<14>")
	)
	(segment
		(start 415.581592 -417.461954)
		(end 415.581592 -418.141658)
		(width 0.12954)
		(layer "B.Cu")
		(net "P5E_CPU0_P3_TX_BUF_C_DN<14>")
	)
	(segment
		(start 410.668216 -423.399712)
		(end 409.90647 -424.161458)
		(width 0.14224)
		(layer "In6.Cu")
		(net "P5E_CPU0_P3_TX_BUF_C_DN<14>")
	)
	(segment
		(start 415.311082 -418.412168)
		(end 415.601912 -418.702998)
		(width 0.14224)
		(layer "In6.Cu")
		(net "P5E_CPU0_P3_TX_BUF_C_DN<14>")
	)
	(segment
		(start 414.507934 -422.23436)
		(end 414.50768 -422.234614)
		(width 0.14224)
		(layer "In6.Cu")
		(net "P5E_CPU0_P3_TX_BUF_C_DN<14>")
	)
	(segment
		(start 410.623004 -426.865796)
		(end 410.750004 -426.992796)
		(width 0.14224)
		(layer "In6.Cu")
		(net "P5E_CPU0_P3_TX_BUF_C_DN<14>")
	)
	(segment
		(start 410.750004 -426.992796)
		(end 410.750004 -427.289976)
		(width 0.14224)
		(layer "In6.Cu")
		(net "P5E_CPU0_P3_TX_BUF_C_DN<14>")
	)
	(segment
		(start 409.721304 -424.608498)
		(end 409.721304 -426.09008)
		(width 0.14224)
		(layer "In6.Cu")
		(net "P5E_CPU0_P3_TX_BUF_C_DN<14>")
	)
	(segment
		(start 415.601912 -421.560498)
		(end 415.109914 -422.051988)
		(width 0.14224)
		(layer "In6.Cu")
		(net "P5E_CPU0_P3_TX_BUF_C_DN<14>")
	)
	(segment
		(start 413.948626 -422.404286)
		(end 413.948626 -422.40454)
		(width 0.14224)
		(layer "In6.Cu")
		(net "P5E_CPU0_P3_TX_BUF_C_DN<14>")
	)
	(segment
		(start 415.601912 -418.702998)
		(end 415.601912 -421.560498)
		(width 0.14224)
		(layer "In6.Cu")
		(net "P5E_CPU0_P3_TX_BUF_C_DN<14>")
	)
	(segment
		(start 410.328618 -426.865796)
		(end 410.623004 -426.865796)
		(width 0.14224)
		(layer "In6.Cu")
		(net "P5E_CPU0_P3_TX_BUF_C_DN<14>")
	)
	(segment
		(start 413.948626 -422.40454)
		(end 410.668216 -423.399712)
		(width 0.14224)
		(layer "In6.Cu")
		(net "P5E_CPU0_P3_TX_BUF_C_DN<14>")
	)
	(segment
		(start 409.974542 -426.701204)
		(end 410.00553 -426.732192)
		(width 0.14224)
		(layer "In6.Cu")
		(net "P5E_CPU0_P3_TX_BUF_C_DN<14>")
	)
	(segment
		(start 415.109914 -422.051988)
		(end 414.507934 -422.23436)
		(width 0.14224)
		(layer "In6.Cu")
		(net "P5E_CPU0_P3_TX_BUF_C_DN<14>")
	)
	(segment
		(start 414.50768 -422.234614)
		(end 413.948626 -422.404286)
		(width 0.14224)
		(layer "In6.Cu")
		(net "P5E_CPU0_P3_TX_BUF_C_DN<14>")
	)
	(arc
		(start 409.721304 -426.09008)
		(mid 409.787115 -426.420843)
		(end 409.974542 -426.701204)
		(width 0.14224)
		(layer "In6.Cu")
		(net "P5E_CPU0_P3_TX_BUF_C_DN<14>")
	)
	(arc
		(start 410.00553 -426.732192)
		(mid 410.153765 -426.83121)
		(end 410.328618 -426.865796)
		(width 0.14224)
		(layer "In6.Cu")
		(net "P5E_CPU0_P3_TX_BUF_C_DN<14>")
	)
	(arc
		(start 409.90647 -424.161458)
		(mid 409.769424 -424.366562)
		(end 409.721304 -424.608498)
		(width 0.14224)
		(layer "In6.Cu")
		(net "P5E_CPU0_P3_TX_BUF_C_DN<14>")
	)
	(segment
		(start 412.518352 -417.461954)
		(end 412.518352 -418.141658)
		(width 0.12954)
		(layer "B.Cu")
		(net "P5E_CPU0_P3_TX_BUF_C_DN<13>")
	)
	(segment
		(start 412.222442 -417.166044)
		(end 412.518352 -417.461954)
		(width 0.12954)
		(layer "B.Cu")
		(net "P5E_CPU0_P3_TX_BUF_C_DN<13>")
	)
	(segment
		(start 412.518352 -418.141658)
		(end 412.247842 -418.412168)
		(width 0.12954)
		(layer "B.Cu")
		(net "P5E_CPU0_P3_TX_BUF_C_DN<13>")
	)
	(segment
		(start 407.807414 -424.87215)
		(end 407.807414 -427.245526)
		(width 0.14224)
		(layer "In6.Cu")
		(net "P5E_CPU0_P3_TX_BUF_C_DN<13>")
	)
	(segment
		(start 412.247842 -418.412168)
		(end 412.538672 -418.702998)
		(width 0.14224)
		(layer "In6.Cu")
		(net "P5E_CPU0_P3_TX_BUF_C_DN<13>")
	)
	(segment
		(start 408.446986 -427.830742)
		(end 408.607768 -427.830742)
		(width 0.14224)
		(layer "In6.Cu")
		(net "P5E_CPU0_P3_TX_BUF_C_DN<13>")
	)
	(segment
		(start 407.962608 -427.620176)
		(end 407.979626 -427.637194)
		(width 0.14224)
		(layer "In6.Cu")
		(net "P5E_CPU0_P3_TX_BUF_C_DN<13>")
	)
	(segment
		(start 408.750008 -427.972982)
		(end 408.750008 -428.28972)
		(width 0.14224)
		(layer "In6.Cu")
		(net "P5E_CPU0_P3_TX_BUF_C_DN<13>")
	)
	(segment
		(start 408.607768 -427.830742)
		(end 408.750008 -427.972982)
		(width 0.14224)
		(layer "In6.Cu")
		(net "P5E_CPU0_P3_TX_BUF_C_DN<13>")
	)
	(segment
		(start 410.48305 -422.14292)
		(end 408.219402 -424.000676)
		(width 0.14224)
		(layer "In6.Cu")
		(net "P5E_CPU0_P3_TX_BUF_C_DN<13>")
	)
	(segment
		(start 410.483304 -422.142666)
		(end 410.48305 -422.14292)
		(width 0.14224)
		(layer "In6.Cu")
		(net "P5E_CPU0_P3_TX_BUF_C_DN<13>")
	)
	(segment
		(start 411.933136 -422.014904)
		(end 411.90291 -422.02481)
		(width 0.14224)
		(layer "In6.Cu")
		(net "P5E_CPU0_P3_TX_BUF_C_DN<13>")
	)
	(segment
		(start 412.538672 -418.702998)
		(end 412.538672 -421.108378)
		(width 0.14224)
		(layer "In6.Cu")
		(net "P5E_CPU0_P3_TX_BUF_C_DN<13>")
	)
	(segment
		(start 411.777942 -422.044622)
		(end 410.757624 -422.044622)
		(width 0.14224)
		(layer "In6.Cu")
		(net "P5E_CPU0_P3_TX_BUF_C_DN<13>")
	)
	(segment
		(start 412.285942 -421.718486)
		(end 412.080456 -421.923972)
		(width 0.14224)
		(layer "In6.Cu")
		(net "P5E_CPU0_P3_TX_BUF_C_DN<13>")
	)
	(arc
		(start 408.219402 -424.000676)
		(mid 407.915571 -424.390157)
		(end 407.807414 -424.87215)
		(width 0.14224)
		(layer "In6.Cu")
		(net "P5E_CPU0_P3_TX_BUF_C_DN<13>")
	)
	(arc
		(start 412.538672 -421.108378)
		(mid 412.472992 -421.438572)
		(end 412.285942 -421.718486)
		(width 0.14224)
		(layer "In6.Cu")
		(net "P5E_CPU0_P3_TX_BUF_C_DN<13>")
	)
	(arc
		(start 411.90291 -422.02481)
		(mid 411.841213 -422.039668)
		(end 411.777942 -422.044622)
		(width 0.14224)
		(layer "In6.Cu")
		(net "P5E_CPU0_P3_TX_BUF_C_DN<13>")
	)
	(arc
		(start 410.757624 -422.044622)
		(mid 410.611966 -422.069868)
		(end 410.483304 -422.142666)
		(width 0.14224)
		(layer "In6.Cu")
		(net "P5E_CPU0_P3_TX_BUF_C_DN<13>")
	)
	(arc
		(start 407.979626 -427.637194)
		(mid 408.194067 -427.780416)
		(end 408.446986 -427.830742)
		(width 0.14224)
		(layer "In6.Cu")
		(net "P5E_CPU0_P3_TX_BUF_C_DN<13>")
	)
	(arc
		(start 412.080456 -421.923972)
		(mid 412.012135 -421.978085)
		(end 411.933136 -422.014904)
		(width 0.14224)
		(layer "In6.Cu")
		(net "P5E_CPU0_P3_TX_BUF_C_DN<13>")
	)
	(arc
		(start 407.807414 -427.245526)
		(mid 407.847746 -427.448289)
		(end 407.962608 -427.620176)
		(width 0.14224)
		(layer "In6.Cu")
		(net "P5E_CPU0_P3_TX_BUF_C_DN<13>")
	)
	(segment
		(start 409.159202 -417.166044)
		(end 409.437332 -417.444174)
		(width 0.12954)
		(layer "B.Cu")
		(net "P5E_CPU0_P3_TX_BUF_C_DN<12>")
	)
	(segment
		(start 409.437332 -417.444174)
		(end 409.437332 -418.159438)
		(width 0.12954)
		(layer "B.Cu")
		(net "P5E_CPU0_P3_TX_BUF_C_DN<12>")
	)
	(segment
		(start 409.437332 -418.159438)
		(end 409.184602 -418.412168)
		(width 0.12954)
		(layer "B.Cu")
		(net "P5E_CPU0_P3_TX_BUF_C_DN<12>")
	)
	(segment
		(start 409.438094 -421.538908)
		(end 409.167838 -421.809164)
		(width 0.14224)
		(layer "In6.Cu")
		(net "P5E_CPU0_P3_TX_BUF_C_DN<12>")
	)
	(segment
		(start 409.475432 -418.702998)
		(end 409.475432 -421.448992)
		(width 0.14224)
		(layer "In6.Cu")
		(net "P5E_CPU0_P3_TX_BUF_C_DN<12>")
	)
	(segment
		(start 406.750012 -426.985176)
		(end 406.750012 -427.289976)
		(width 0.14224)
		(layer "In6.Cu")
		(net "P5E_CPU0_P3_TX_BUF_C_DN<12>")
	)
	(segment
		(start 406.156668 -426.776642)
		(end 406.156922 -426.776642)
		(width 0.14224)
		(layer "In6.Cu")
		(net "P5E_CPU0_P3_TX_BUF_C_DN<12>")
	)
	(segment
		(start 405.95169 -426.637958)
		(end 405.958548 -426.644816)
		(width 0.14224)
		(layer "In6.Cu")
		(net "P5E_CPU0_P3_TX_BUF_C_DN<12>")
	)
	(segment
		(start 409.167838 -421.809164)
		(end 406.089612 -424.151298)
		(width 0.14224)
		(layer "In6.Cu")
		(net "P5E_CPU0_P3_TX_BUF_C_DN<12>")
	)
	(segment
		(start 406.432766 -426.830744)
		(end 406.59558 -426.830744)
		(width 0.14224)
		(layer "In6.Cu")
		(net "P5E_CPU0_P3_TX_BUF_C_DN<12>")
	)
	(segment
		(start 405.777446 -424.781218)
		(end 405.777446 -426.217334)
		(width 0.14224)
		(layer "In6.Cu")
		(net "P5E_CPU0_P3_TX_BUF_C_DN<12>")
	)
	(segment
		(start 409.184602 -418.412168)
		(end 409.475432 -418.702998)
		(width 0.14224)
		(layer "In6.Cu")
		(net "P5E_CPU0_P3_TX_BUF_C_DN<12>")
	)
	(segment
		(start 406.59558 -426.830744)
		(end 406.750012 -426.985176)
		(width 0.14224)
		(layer "In6.Cu")
		(net "P5E_CPU0_P3_TX_BUF_C_DN<12>")
	)
	(arc
		(start 405.777446 -426.217334)
		(mid 405.822728 -426.44498)
		(end 405.95169 -426.637958)
		(width 0.14224)
		(layer "In6.Cu")
		(net "P5E_CPU0_P3_TX_BUF_C_DN<12>")
	)
	(arc
		(start 406.156922 -426.776642)
		(mid 406.292214 -426.817105)
		(end 406.432766 -426.830744)
		(width 0.14224)
		(layer "In6.Cu")
		(net "P5E_CPU0_P3_TX_BUF_C_DN<12>")
	)
	(arc
		(start 409.475432 -421.448992)
		(mid 409.46573 -421.497676)
		(end 409.438094 -421.538908)
		(width 0.14224)
		(layer "In6.Cu")
		(net "P5E_CPU0_P3_TX_BUF_C_DN<12>")
	)
	(arc
		(start 405.958548 -426.644816)
		(mid 406.051036 -426.720602)
		(end 406.156668 -426.776642)
		(width 0.14224)
		(layer "In6.Cu")
		(net "P5E_CPU0_P3_TX_BUF_C_DN<12>")
	)
	(arc
		(start 406.089612 -424.151298)
		(mid 405.859789 -424.429711)
		(end 405.777446 -424.781218)
		(width 0.14224)
		(layer "In6.Cu")
		(net "P5E_CPU0_P3_TX_BUF_C_DN<12>")
	)
	(segment
		(start 406.391872 -417.461954)
		(end 406.391872 -418.141658)
		(width 0.12954)
		(layer "B.Cu")
		(net "P5E_CPU0_P3_TX_BUF_C_DN<11>")
	)
	(segment
		(start 406.095962 -417.166044)
		(end 406.391872 -417.461954)
		(width 0.12954)
		(layer "B.Cu")
		(net "P5E_CPU0_P3_TX_BUF_C_DN<11>")
	)
	(segment
		(start 406.391872 -418.141658)
		(end 406.121362 -418.412168)
		(width 0.12954)
		(layer "B.Cu")
		(net "P5E_CPU0_P3_TX_BUF_C_DN<11>")
	)
	(segment
		(start 404.750016 -427.972982)
		(end 404.750016 -428.28972)
		(width 0.14224)
		(layer "In6.Cu")
		(net "P5E_CPU0_P3_TX_BUF_C_DN<11>")
	)
	(segment
		(start 403.812756 -424.38574)
		(end 403.812756 -427.26483)
		(width 0.14224)
		(layer "In6.Cu")
		(net "P5E_CPU0_P3_TX_BUF_C_DN<11>")
	)
	(segment
		(start 406.121362 -418.412168)
		(end 406.412192 -418.702998)
		(width 0.14224)
		(layer "In6.Cu")
		(net "P5E_CPU0_P3_TX_BUF_C_DN<11>")
	)
	(segment
		(start 404.348442 -427.830742)
		(end 404.607776 -427.830742)
		(width 0.14224)
		(layer "In6.Cu")
		(net "P5E_CPU0_P3_TX_BUF_C_DN<11>")
	)
	(segment
		(start 406.412192 -418.702998)
		(end 406.412192 -421.264334)
		(width 0.14224)
		(layer "In6.Cu")
		(net "P5E_CPU0_P3_TX_BUF_C_DN<11>")
	)
	(segment
		(start 406.235916 -421.689784)
		(end 404.005542 -423.920158)
		(width 0.14224)
		(layer "In6.Cu")
		(net "P5E_CPU0_P3_TX_BUF_C_DN<11>")
	)
	(segment
		(start 404.607776 -427.830742)
		(end 404.750016 -427.972982)
		(width 0.14224)
		(layer "In6.Cu")
		(net "P5E_CPU0_P3_TX_BUF_C_DN<11>")
	)
	(segment
		(start 403.98446 -427.679358)
		(end 403.985476 -427.680374)
		(width 0.14224)
		(layer "In6.Cu")
		(net "P5E_CPU0_P3_TX_BUF_C_DN<11>")
	)
	(arc
		(start 406.412192 -421.264334)
		(mid 406.366373 -421.49459)
		(end 406.235916 -421.689784)
		(width 0.14224)
		(layer "In6.Cu")
		(net "P5E_CPU0_P3_TX_BUF_C_DN<11>")
	)
	(arc
		(start 404.005542 -423.920158)
		(mid 403.862865 -424.133783)
		(end 403.812756 -424.38574)
		(width 0.14224)
		(layer "In6.Cu")
		(net "P5E_CPU0_P3_TX_BUF_C_DN<11>")
	)
	(arc
		(start 403.985476 -427.680374)
		(mid 404.152006 -427.791646)
		(end 404.348442 -427.830742)
		(width 0.14224)
		(layer "In6.Cu")
		(net "P5E_CPU0_P3_TX_BUF_C_DN<11>")
	)
	(arc
		(start 403.812756 -427.26483)
		(mid 403.85738 -427.489171)
		(end 403.98446 -427.679358)
		(width 0.14224)
		(layer "In6.Cu")
		(net "P5E_CPU0_P3_TX_BUF_C_DN<11>")
	)
	(segment
		(start 403.328632 -417.461954)
		(end 403.328632 -418.141658)
		(width 0.12954)
		(layer "B.Cu")
		(net "P5E_CPU0_P3_TX_BUF_C_DN<10>")
	)
	(segment
		(start 403.032722 -417.166044)
		(end 403.328632 -417.461954)
		(width 0.12954)
		(layer "B.Cu")
		(net "P5E_CPU0_P3_TX_BUF_C_DN<10>")
	)
	(segment
		(start 403.328632 -418.141658)
		(end 403.058122 -418.412168)
		(width 0.12954)
		(layer "B.Cu")
		(net "P5E_CPU0_P3_TX_BUF_C_DN<10>")
	)
	(segment
		(start 403.348952 -418.702998)
		(end 403.348952 -421.208454)
		(width 0.14224)
		(layer "In6.Cu")
		(net "P5E_CPU0_P3_TX_BUF_C_DN<10>")
	)
	(segment
		(start 401.94865 -426.657008)
		(end 401.950682 -426.65904)
		(width 0.14224)
		(layer "In6.Cu")
		(net "P5E_CPU0_P3_TX_BUF_C_DN<10>")
	)
	(segment
		(start 401.717002 -424.658536)
		(end 401.717002 -426.0977)
		(width 0.14224)
		(layer "In6.Cu")
		(net "P5E_CPU0_P3_TX_BUF_C_DN<10>")
	)
	(segment
		(start 402.75002 -426.98289)
		(end 402.75002 -427.289976)
		(width 0.14224)
		(layer "In6.Cu")
		(net "P5E_CPU0_P3_TX_BUF_C_DN<10>")
	)
	(segment
		(start 402.614892 -426.847762)
		(end 402.75002 -426.98289)
		(width 0.14224)
		(layer "In6.Cu")
		(net "P5E_CPU0_P3_TX_BUF_C_DN<10>")
	)
	(segment
		(start 403.348952 -421.208454)
		(end 401.717002 -424.658536)
		(width 0.14224)
		(layer "In6.Cu")
		(net "P5E_CPU0_P3_TX_BUF_C_DN<10>")
	)
	(segment
		(start 402.406358 -426.847762)
		(end 402.614892 -426.847762)
		(width 0.14224)
		(layer "In6.Cu")
		(net "P5E_CPU0_P3_TX_BUF_C_DN<10>")
	)
	(segment
		(start 403.058122 -418.412168)
		(end 403.348952 -418.702998)
		(width 0.14224)
		(layer "In6.Cu")
		(net "P5E_CPU0_P3_TX_BUF_C_DN<10>")
	)
	(arc
		(start 401.950682 -426.65904)
		(mid 402.159748 -426.798733)
		(end 402.406358 -426.847762)
		(width 0.14224)
		(layer "In6.Cu")
		(net "P5E_CPU0_P3_TX_BUF_C_DN<10>")
	)
	(arc
		(start 401.717002 -426.0977)
		(mid 401.777225 -426.400372)
		(end 401.94865 -426.657008)
		(width 0.14224)
		(layer "In6.Cu")
		(net "P5E_CPU0_P3_TX_BUF_C_DN<10>")
	)
	(segment
		(start 372.400322 -417.166044)
		(end 372.696232 -417.461954)
		(width 0.12954)
		(layer "B.Cu")
		(net "P5E_CPU0_P3_TX_BUF_C_DN<0>")
	)
	(segment
		(start 372.696232 -417.461954)
		(end 372.696232 -418.141658)
		(width 0.12954)
		(layer "B.Cu")
		(net "P5E_CPU0_P3_TX_BUF_C_DN<0>")
	)
	(segment
		(start 372.696232 -418.141658)
		(end 372.425722 -418.412168)
		(width 0.12954)
		(layer "B.Cu")
		(net "P5E_CPU0_P3_TX_BUF_C_DN<0>")
	)
	(segment
		(start 372.762272 -418.748718)
		(end 372.762272 -421.080438)
		(width 0.1143)
		(layer "In6.Cu")
		(net "P5E_CPU0_P3_TX_BUF_C_DN<0>")
	)
	(segment
		(start 379.314456 -425.962572)
		(end 379.31471 -425.962572)
		(width 0.1143)
		(layer "In6.Cu")
		(net "P5E_CPU0_P3_TX_BUF_C_DN<0>")
	)
	(segment
		(start 381.622808 -426.785024)
		(end 381.749808 -426.912024)
		(width 0.1143)
		(layer "In6.Cu")
		(net "P5E_CPU0_P3_TX_BUF_C_DN<0>")
	)
	(segment
		(start 380.933452 -426.785024)
		(end 381.622808 -426.785024)
		(width 0.1143)
		(layer "In6.Cu")
		(net "P5E_CPU0_P3_TX_BUF_C_DN<0>")
	)
	(segment
		(start 379.31471 -425.962572)
		(end 380.783846 -426.747686)
		(width 0.1143)
		(layer "In6.Cu")
		(net "P5E_CPU0_P3_TX_BUF_C_DN<0>")
	)
	(segment
		(start 372.88978 -421.590216)
		(end 373.49303 -422.718484)
		(width 0.1143)
		(layer "In6.Cu")
		(net "P5E_CPU0_P3_TX_BUF_C_DN<0>")
	)
	(segment
		(start 373.779288 -423.004488)
		(end 379.314456 -425.962572)
		(width 0.1143)
		(layer "In6.Cu")
		(net "P5E_CPU0_P3_TX_BUF_C_DN<0>")
	)
	(segment
		(start 372.425722 -418.412168)
		(end 372.762272 -418.748718)
		(width 0.1143)
		(layer "In6.Cu")
		(net "P5E_CPU0_P3_TX_BUF_C_DN<0>")
	)
	(segment
		(start 381.749808 -426.912024)
		(end 381.749808 -427.289976)
		(width 0.1143)
		(layer "In6.Cu")
		(net "P5E_CPU0_P3_TX_BUF_C_DN<0>")
	)
	(arc
		(start 373.49303 -422.718484)
		(mid 373.614973 -422.882681)
		(end 373.779288 -423.004488)
		(width 0.1143)
		(layer "In6.Cu")
		(net "P5E_CPU0_P3_TX_BUF_C_DN<0>")
	)
	(arc
		(start 380.783846 -426.747686)
		(mid 380.856349 -426.775582)
		(end 380.933452 -426.785024)
		(width 0.1143)
		(layer "In6.Cu")
		(net "P5E_CPU0_P3_TX_BUF_C_DN<0>")
	)
	(arc
		(start 372.762272 -421.080438)
		(mid 372.794572 -421.343194)
		(end 372.88978 -421.590216)
		(width 0.1143)
		(layer "In6.Cu")
		(net "P5E_CPU0_P3_TX_BUF_C_DN<0>")
	)
	(segment
		(start 381.031496 -399.941796)
		(end 381.031496 -401.105878)
		(width 0.1016)
		(layer "F.Cu")
		(net "P5E_CPU0_P3_RX_BUF_DP<9>")
	)
	(segment
		(start 381.716534 -401.4978)
		(end 381.716534 -401.674838)
		(width 0.1016)
		(layer "F.Cu")
		(net "P5E_CPU0_P3_RX_BUF_DP<9>")
	)
	(segment
		(start 381.031496 -401.105878)
		(end 381.284734 -401.359116)
		(width 0.1016)
		(layer "F.Cu")
		(net "P5E_CPU0_P3_RX_BUF_DP<9>")
	)
	(segment
		(start 381.57785 -401.359116)
		(end 381.716534 -401.4978)
		(width 0.1016)
		(layer "F.Cu")
		(net "P5E_CPU0_P3_RX_BUF_DP<9>")
	)
	(segment
		(start 381.284734 -401.359116)
		(end 381.57785 -401.359116)
		(width 0.1016)
		(layer "F.Cu")
		(net "P5E_CPU0_P3_RX_BUF_DP<9>")
	)
	(segment
		(start 381.018034 -399.663158)
		(end 381.102616 -399.74774)
		(width 0.1016)
		(layer "F.Cu")
		(net "P5E_CPU0_P3_RX_BUF_DP<9>")
	)
	(segment
		(start 381.102616 -399.870676)
		(end 381.031496 -399.941796)
		(width 0.1016)
		(layer "F.Cu")
		(net "P5E_CPU0_P3_RX_BUF_DP<9>")
	)
	(segment
		(start 381.102616 -399.74774)
		(end 381.102616 -399.870676)
		(width 0.1016)
		(layer "F.Cu")
		(net "P5E_CPU0_P3_RX_BUF_DP<9>")
	)
	(segment
		(start 399.173192 -417.47186)
		(end 399.173192 -417.04514)
		(width 0.14224)
		(layer "In13.Cu")
		(net "P5E_CPU0_P3_RX_BUF_DP<9>")
	)
	(segment
		(start 393.509246 -410.50337)
		(end 391.989056 -410.041852)
		(width 0.14224)
		(layer "In13.Cu")
		(net "P5E_CPU0_P3_RX_BUF_DP<9>")
	)
	(segment
		(start 399.210022 -419.104064)
		(end 399.036032 -418.684964)
		(width 0.14224)
		(layer "In13.Cu")
		(net "P5E_CPU0_P3_RX_BUF_DP<9>")
	)
	(segment
		(start 400.522186 -421.929306)
		(end 400.567652 -421.468296)
		(width 0.14224)
		(layer "In13.Cu")
		(net "P5E_CPU0_P3_RX_BUF_DP<9>")
	)
	(segment
		(start 399.036032 -418.684964)
		(end 399.036032 -417.60902)
		(width 0.14224)
		(layer "In13.Cu")
		(net "P5E_CPU0_P3_RX_BUF_DP<9>")
	)
	(segment
		(start 396.265908 -411.226)
		(end 395.804136 -411.085792)
		(width 0.14224)
		(layer "In13.Cu")
		(net "P5E_CPU0_P3_RX_BUF_DP<9>")
	)
	(segment
		(start 394.588492 -410.83103)
		(end 394.180314 -410.707078)
		(width 0.14224)
		(layer "In13.Cu")
		(net "P5E_CPU0_P3_RX_BUF_DP<9>")
	)
	(segment
		(start 383.650236 -407.055828)
		(end 383.650236 -406.861772)
		(width 0.14224)
		(layer "In13.Cu")
		(net "P5E_CPU0_P3_RX_BUF_DP<9>")
	)
	(segment
		(start 396.746984 -411.48635)
		(end 396.338806 -411.362398)
		(width 0.14224)
		(layer "In13.Cu")
		(net "P5E_CPU0_P3_RX_BUF_DP<9>")
	)
	(segment
		(start 399.036032 -416.48126)
		(end 399.173192 -416.3441)
		(width 0.14224)
		(layer "In13.Cu")
		(net "P5E_CPU0_P3_RX_BUF_DP<9>")
	)
	(segment
		(start 399.036032 -416.90798)
		(end 399.036032 -416.48126)
		(width 0.14224)
		(layer "In13.Cu")
		(net "P5E_CPU0_P3_RX_BUF_DP<9>")
	)
	(segment
		(start 398.56918 -414.049464)
		(end 398.345406 -413.956754)
		(width 0.14224)
		(layer "In13.Cu")
		(net "P5E_CPU0_P3_RX_BUF_DP<9>")
	)
	(segment
		(start 381.257556 -404.236428)
		(end 381.394716 -404.099268)
		(width 0.14224)
		(layer "In13.Cu")
		(net "P5E_CPU0_P3_RX_BUF_DP<9>")
	)
	(segment
		(start 391.2997 -409.567126)
		(end 384.094736 -407.36901)
		(width 0.14224)
		(layer "In13.Cu")
		(net "P5E_CPU0_P3_RX_BUF_DP<9>")
	)
	(segment
		(start 383.825242 -407.230834)
		(end 383.650236 -407.055828)
		(width 0.14224)
		(layer "In13.Cu")
		(net "P5E_CPU0_P3_RX_BUF_DP<9>")
	)
	(segment
		(start 400.510502 -422.92651)
		(end 400.57324 -422.504108)
		(width 0.14224)
		(layer "In13.Cu")
		(net "P5E_CPU0_P3_RX_BUF_DP<9>")
	)
	(segment
		(start 400.185382 -434.74894)
		(end 400.058382 -434.62194)
		(width 0.14224)
		(layer "In13.Cu")
		(net "P5E_CPU0_P3_RX_BUF_DP<9>")
	)
	(segment
		(start 381.394716 -403.672548)
		(end 381.257556 -403.535388)
		(width 0.14224)
		(layer "In13.Cu")
		(net "P5E_CPU0_P3_RX_BUF_DP<9>")
	)
	(segment
		(start 381.394716 -404.099268)
		(end 381.394716 -403.672548)
		(width 0.14224)
		(layer "In13.Cu")
		(net "P5E_CPU0_P3_RX_BUF_DP<9>")
	)
	(segment
		(start 382.55067 -405.762206)
		(end 382.356614 -405.762206)
		(width 0.14224)
		(layer "In13.Cu")
		(net "P5E_CPU0_P3_RX_BUF_DP<9>")
	)
	(segment
		(start 382.055116 -405.460708)
		(end 382.055116 -405.266652)
		(width 0.14224)
		(layer "In13.Cu")
		(net "P5E_CPU0_P3_RX_BUF_DP<9>")
	)
	(segment
		(start 382.356614 -405.762206)
		(end 382.055116 -405.460708)
		(width 0.14224)
		(layer "In13.Cu")
		(net "P5E_CPU0_P3_RX_BUF_DP<9>")
	)
	(segment
		(start 381.75311 -404.964646)
		(end 381.559054 -404.964646)
		(width 0.14224)
		(layer "In13.Cu")
		(net "P5E_CPU0_P3_RX_BUF_DP<9>")
	)
	(segment
		(start 400.459702 -422.3512)
		(end 400.522186 -421.929306)
		(width 0.14224)
		(layer "In13.Cu")
		(net "P5E_CPU0_P3_RX_BUF_DP<9>")
	)
	(segment
		(start 381.384556 -401.393406)
		(end 381.589534 -401.393406)
		(width 0.14224)
		(layer "In13.Cu")
		(net "P5E_CPU0_P3_RX_BUF_DP<9>")
	)
	(segment
		(start 400.058382 -424.680126)
		(end 400.14144 -424.261788)
		(width 0.14224)
		(layer "In13.Cu")
		(net "P5E_CPU0_P3_RX_BUF_DP<9>")
	)
	(segment
		(start 381.716534 -401.520406)
		(end 381.716534 -401.674838)
		(width 0.14224)
		(layer "In13.Cu")
		(net "P5E_CPU0_P3_RX_BUF_DP<9>")
	)
	(segment
		(start 395.25956 -411.034992)
		(end 395.187932 -410.90088)
		(width 0.14224)
		(layer "In13.Cu")
		(net "P5E_CPU0_P3_RX_BUF_DP<9>")
	)
	(segment
		(start 399.173192 -416.3441)
		(end 399.173192 -415.91738)
		(width 0.14224)
		(layer "In13.Cu")
		(net "P5E_CPU0_P3_RX_BUF_DP<9>")
	)
	(segment
		(start 381.257556 -404.610316)
		(end 381.257556 -404.236428)
		(width 0.14224)
		(layer "In13.Cu")
		(net "P5E_CPU0_P3_RX_BUF_DP<9>")
	)
	(segment
		(start 395.667738 -411.15869)
		(end 395.25956 -411.034992)
		(width 0.14224)
		(layer "In13.Cu")
		(net "P5E_CPU0_P3_RX_BUF_DP<9>")
	)
	(segment
		(start 384.094736 -407.36901)
		(end 383.825242 -407.230834)
		(width 0.14224)
		(layer "In13.Cu")
		(net "P5E_CPU0_P3_RX_BUF_DP<9>")
	)
	(segment
		(start 382.055116 -405.266652)
		(end 381.75311 -404.964646)
		(width 0.14224)
		(layer "In13.Cu")
		(net "P5E_CPU0_P3_RX_BUF_DP<9>")
	)
	(segment
		(start 394.72235 -410.759656)
		(end 394.588492 -410.83103)
		(width 0.14224)
		(layer "In13.Cu")
		(net "P5E_CPU0_P3_RX_BUF_DP<9>")
	)
	(segment
		(start 381.589534 -401.393406)
		(end 381.716534 -401.520406)
		(width 0.14224)
		(layer "In13.Cu")
		(net "P5E_CPU0_P3_RX_BUF_DP<9>")
	)
	(segment
		(start 394.180314 -410.707078)
		(end 394.116052 -410.586936)
		(width 0.14224)
		(layer "In13.Cu")
		(net "P5E_CPU0_P3_RX_BUF_DP<9>")
	)
	(segment
		(start 399.173192 -415.91738)
		(end 399.036032 -415.78022)
		(width 0.14224)
		(layer "In13.Cu")
		(net "P5E_CPU0_P3_RX_BUF_DP<9>")
	)
	(segment
		(start 400.14144 -424.261788)
		(end 400.299936 -424.15587)
		(width 0.14224)
		(layer "In13.Cu")
		(net "P5E_CPU0_P3_RX_BUF_DP<9>")
	)
	(segment
		(start 383.154174 -406.559766)
		(end 382.852676 -406.258268)
		(width 0.14224)
		(layer "In13.Cu")
		(net "P5E_CPU0_P3_RX_BUF_DP<9>")
	)
	(segment
		(start 381.257556 -403.535388)
		(end 381.257556 -401.520406)
		(width 0.14224)
		(layer "In13.Cu")
		(net "P5E_CPU0_P3_RX_BUF_DP<9>")
	)
	(segment
		(start 398.830546 -414.31083)
		(end 398.56918 -414.049464)
		(width 0.14224)
		(layer "In13.Cu")
		(net "P5E_CPU0_P3_RX_BUF_DP<9>")
	)
	(segment
		(start 400.35734 -423.040048)
		(end 400.510502 -422.92651)
		(width 0.14224)
		(layer "In13.Cu")
		(net "P5E_CPU0_P3_RX_BUF_DP<9>")
	)
	(segment
		(start 398.345406 -413.956754)
		(end 397.872204 -413.956754)
		(width 0.14224)
		(layer "In13.Cu")
		(net "P5E_CPU0_P3_RX_BUF_DP<9>")
	)
	(segment
		(start 394.116052 -410.586936)
		(end 393.629388 -410.439108)
		(width 0.14224)
		(layer "In13.Cu")
		(net "P5E_CPU0_P3_RX_BUF_DP<9>")
	)
	(segment
		(start 397.504412 -413.502856)
		(end 397.504412 -412.337504)
		(width 0.14224)
		(layer "In13.Cu")
		(net "P5E_CPU0_P3_RX_BUF_DP<9>")
	)
	(segment
		(start 393.629388 -410.439108)
		(end 393.509246 -410.50337)
		(width 0.14224)
		(layer "In13.Cu")
		(net "P5E_CPU0_P3_RX_BUF_DP<9>")
	)
	(segment
		(start 400.750024 -434.594254)
		(end 400.595338 -434.74894)
		(width 0.14224)
		(layer "In13.Cu")
		(net "P5E_CPU0_P3_RX_BUF_DP<9>")
	)
	(segment
		(start 400.447764 -420.109396)
		(end 399.960338 -419.62197)
		(width 0.14224)
		(layer "In13.Cu")
		(net "P5E_CPU0_P3_RX_BUF_DP<9>")
	)
	(segment
		(start 383.34823 -406.559766)
		(end 383.154174 -406.559766)
		(width 0.14224)
		(layer "In13.Cu")
		(net "P5E_CPU0_P3_RX_BUF_DP<9>")
	)
	(segment
		(start 400.299936 -424.15587)
		(end 400.383248 -423.737278)
		(width 0.14224)
		(layer "In13.Cu")
		(net "P5E_CPU0_P3_RX_BUF_DP<9>")
	)
	(segment
		(start 382.852676 -406.064212)
		(end 382.55067 -405.762206)
		(width 0.14224)
		(layer "In13.Cu")
		(net "P5E_CPU0_P3_RX_BUF_DP<9>")
	)
	(segment
		(start 400.383248 -423.737278)
		(end 400.277584 -423.578782)
		(width 0.14224)
		(layer "In13.Cu")
		(net "P5E_CPU0_P3_RX_BUF_DP<9>")
	)
	(segment
		(start 400.57324 -422.504108)
		(end 400.459702 -422.3512)
		(width 0.14224)
		(layer "In13.Cu")
		(net "P5E_CPU0_P3_RX_BUF_DP<9>")
	)
	(segment
		(start 400.058382 -434.62194)
		(end 400.058382 -424.680126)
		(width 0.14224)
		(layer "In13.Cu")
		(net "P5E_CPU0_P3_RX_BUF_DP<9>")
	)
	(segment
		(start 399.036032 -417.60902)
		(end 399.173192 -417.47186)
		(width 0.14224)
		(layer "In13.Cu")
		(net "P5E_CPU0_P3_RX_BUF_DP<9>")
	)
	(segment
		(start 382.852676 -406.258268)
		(end 382.852676 -406.064212)
		(width 0.14224)
		(layer "In13.Cu")
		(net "P5E_CPU0_P3_RX_BUF_DP<9>")
	)
	(segment
		(start 400.567652 -421.468296)
		(end 400.567652 -420.398702)
		(width 0.14224)
		(layer "In13.Cu")
		(net "P5E_CPU0_P3_RX_BUF_DP<9>")
	)
	(segment
		(start 400.750024 -434.289962)
		(end 400.750024 -434.594254)
		(width 0.14224)
		(layer "In13.Cu")
		(net "P5E_CPU0_P3_RX_BUF_DP<9>")
	)
	(segment
		(start 400.595338 -434.74894)
		(end 400.185382 -434.74894)
		(width 0.14224)
		(layer "In13.Cu")
		(net "P5E_CPU0_P3_RX_BUF_DP<9>")
	)
	(segment
		(start 397.374618 -412.023814)
		(end 396.972028 -411.62097)
		(width 0.14224)
		(layer "In13.Cu")
		(net "P5E_CPU0_P3_RX_BUF_DP<9>")
	)
	(segment
		(start 383.650236 -406.861772)
		(end 383.34823 -406.559766)
		(width 0.14224)
		(layer "In13.Cu")
		(net "P5E_CPU0_P3_RX_BUF_DP<9>")
	)
	(segment
		(start 399.960338 -419.62197)
		(end 399.56359 -419.457378)
		(width 0.14224)
		(layer "In13.Cu")
		(net "P5E_CPU0_P3_RX_BUF_DP<9>")
	)
	(segment
		(start 391.877804 -409.982162)
		(end 391.507218 -409.678378)
		(width 0.14224)
		(layer "In13.Cu")
		(net "P5E_CPU0_P3_RX_BUF_DP<9>")
	)
	(segment
		(start 395.187932 -410.90088)
		(end 394.72235 -410.759656)
		(width 0.14224)
		(layer "In13.Cu")
		(net "P5E_CPU0_P3_RX_BUF_DP<9>")
	)
	(segment
		(start 397.734282 -413.899604)
		(end 397.622522 -413.787844)
		(width 0.14224)
		(layer "In13.Cu")
		(net "P5E_CPU0_P3_RX_BUF_DP<9>")
	)
	(segment
		(start 399.036032 -414.806892)
		(end 398.830546 -414.31083)
		(width 0.14224)
		(layer "In13.Cu")
		(net "P5E_CPU0_P3_RX_BUF_DP<9>")
	)
	(segment
		(start 399.036032 -415.78022)
		(end 399.036032 -414.806892)
		(width 0.14224)
		(layer "In13.Cu")
		(net "P5E_CPU0_P3_RX_BUF_DP<9>")
	)
	(segment
		(start 381.257556 -401.520406)
		(end 381.384556 -401.393406)
		(width 0.14224)
		(layer "In13.Cu")
		(net "P5E_CPU0_P3_RX_BUF_DP<9>")
	)
	(segment
		(start 381.559054 -404.964646)
		(end 381.294894 -404.700486)
		(width 0.14224)
		(layer "In13.Cu")
		(net "P5E_CPU0_P3_RX_BUF_DP<9>")
	)
	(segment
		(start 395.804136 -411.085792)
		(end 395.667738 -411.15869)
		(width 0.14224)
		(layer "In13.Cu")
		(net "P5E_CPU0_P3_RX_BUF_DP<9>")
	)
	(segment
		(start 400.277584 -423.578782)
		(end 400.35734 -423.040048)
		(width 0.14224)
		(layer "In13.Cu")
		(net "P5E_CPU0_P3_RX_BUF_DP<9>")
	)
	(segment
		(start 396.338806 -411.362398)
		(end 396.265908 -411.226)
		(width 0.14224)
		(layer "In13.Cu")
		(net "P5E_CPU0_P3_RX_BUF_DP<9>")
	)
	(segment
		(start 399.173192 -417.04514)
		(end 399.036032 -416.90798)
		(width 0.14224)
		(layer "In13.Cu")
		(net "P5E_CPU0_P3_RX_BUF_DP<9>")
	)
	(arc
		(start 399.56359 -419.457378)
		(mid 399.35167 -419.315876)
		(end 399.210022 -419.104064)
		(width 0.14224)
		(layer "In13.Cu")
		(net "P5E_CPU0_P3_RX_BUF_DP<9>")
	)
	(arc
		(start 397.622522 -413.787844)
		(mid 397.535102 -413.657105)
		(end 397.504412 -413.502856)
		(width 0.14224)
		(layer "In13.Cu")
		(net "P5E_CPU0_P3_RX_BUF_DP<9>")
	)
	(arc
		(start 396.972028 -411.62097)
		(mid 396.867805 -411.539784)
		(end 396.746984 -411.48635)
		(width 0.14224)
		(layer "In13.Cu")
		(net "P5E_CPU0_P3_RX_BUF_DP<9>")
	)
	(arc
		(start 397.872204 -413.956754)
		(mid 397.797553 -413.941905)
		(end 397.734282 -413.899604)
		(width 0.14224)
		(layer "In13.Cu")
		(net "P5E_CPU0_P3_RX_BUF_DP<9>")
	)
	(arc
		(start 381.294894 -404.700486)
		(mid 381.267251 -404.659116)
		(end 381.257556 -404.610316)
		(width 0.14224)
		(layer "In13.Cu")
		(net "P5E_CPU0_P3_RX_BUF_DP<9>")
	)
	(arc
		(start 397.504412 -412.337504)
		(mid 397.470722 -412.167751)
		(end 397.374618 -412.023814)
		(width 0.14224)
		(layer "In13.Cu")
		(net "P5E_CPU0_P3_RX_BUF_DP<9>")
	)
	(arc
		(start 391.507218 -409.678378)
		(mid 391.408925 -409.612559)
		(end 391.2997 -409.567126)
		(width 0.14224)
		(layer "In13.Cu")
		(net "P5E_CPU0_P3_RX_BUF_DP<9>")
	)
	(arc
		(start 391.989056 -410.041852)
		(mid 391.93051 -410.017453)
		(end 391.877804 -409.982162)
		(width 0.14224)
		(layer "In13.Cu")
		(net "P5E_CPU0_P3_RX_BUF_DP<9>")
	)
	(arc
		(start 400.567652 -420.398702)
		(mid 400.536489 -420.242124)
		(end 400.447764 -420.109396)
		(width 0.14224)
		(layer "In13.Cu")
		(net "P5E_CPU0_P3_RX_BUF_DP<9>")
	)
	(segment
		(start 379.81382 -401.105878)
		(end 380.067058 -401.359116)
		(width 0.1016)
		(layer "F.Cu")
		(net "P5E_CPU0_P3_RX_BUF_DP<8>")
	)
	(segment
		(start 379.81382 -399.959322)
		(end 379.81382 -401.105878)
		(width 0.1016)
		(layer "F.Cu")
		(net "P5E_CPU0_P3_RX_BUF_DP<8>")
	)
	(segment
		(start 379.902466 -399.74774)
		(end 379.902466 -399.870676)
		(width 0.1016)
		(layer "F.Cu")
		(net "P5E_CPU0_P3_RX_BUF_DP<8>")
	)
	(segment
		(start 379.817884 -399.663158)
		(end 379.902466 -399.74774)
		(width 0.1016)
		(layer "F.Cu")
		(net "P5E_CPU0_P3_RX_BUF_DP<8>")
	)
	(segment
		(start 380.3777 -401.359116)
		(end 380.516638 -401.498054)
		(width 0.1016)
		(layer "F.Cu")
		(net "P5E_CPU0_P3_RX_BUF_DP<8>")
	)
	(segment
		(start 379.902466 -399.870676)
		(end 379.81382 -399.959322)
		(width 0.1016)
		(layer "F.Cu")
		(net "P5E_CPU0_P3_RX_BUF_DP<8>")
	)
	(segment
		(start 380.067058 -401.359116)
		(end 380.3777 -401.359116)
		(width 0.1016)
		(layer "F.Cu")
		(net "P5E_CPU0_P3_RX_BUF_DP<8>")
	)
	(segment
		(start 380.516638 -401.498054)
		(end 380.516638 -401.674838)
		(width 0.1016)
		(layer "F.Cu")
		(net "P5E_CPU0_P3_RX_BUF_DP<8>")
	)
	(segment
		(start 391.700512 -410.990034)
		(end 391.485374 -410.910278)
		(width 0.14224)
		(layer "In13.Cu")
		(net "P5E_CPU0_P3_RX_BUF_DP<8>")
	)
	(segment
		(start 380.197106 -401.371562)
		(end 380.377192 -401.371562)
		(width 0.14224)
		(layer "In13.Cu")
		(net "P5E_CPU0_P3_RX_BUF_DP<8>")
	)
	(segment
		(start 380.05766 -402.853144)
		(end 380.05766 -401.511008)
		(width 0.14224)
		(layer "In13.Cu")
		(net "P5E_CPU0_P3_RX_BUF_DP<8>")
	)
	(segment
		(start 396.109952 -416.718496)
		(end 396.109952 -416.291776)
		(width 0.14224)
		(layer "In13.Cu")
		(net "P5E_CPU0_P3_RX_BUF_DP<8>")
	)
	(segment
		(start 380.05766 -404.681944)
		(end 380.19482 -404.544784)
		(width 0.14224)
		(layer "In13.Cu")
		(net "P5E_CPU0_P3_RX_BUF_DP<8>")
	)
	(segment
		(start 380.85522 -405.712168)
		(end 380.553214 -405.410162)
		(width 0.14224)
		(layer "In13.Cu")
		(net "P5E_CPU0_P3_RX_BUF_DP<8>")
	)
	(segment
		(start 397.72463 -423.460418)
		(end 397.832326 -423.299128)
		(width 0.14224)
		(layer "In13.Cu")
		(net "P5E_CPU0_P3_RX_BUF_DP<8>")
	)
	(segment
		(start 394.513816 -413.742378)
		(end 394.441172 -413.567118)
		(width 0.14224)
		(layer "In13.Cu")
		(net "P5E_CPU0_P3_RX_BUF_DP<8>")
	)
	(segment
		(start 382.893824 -407.944574)
		(end 382.45034 -407.50109)
		(width 0.14224)
		(layer "In13.Cu")
		(net "P5E_CPU0_P3_RX_BUF_DP<8>")
	)
	(segment
		(start 397.944594 -424.566588)
		(end 398.052544 -424.405298)
		(width 0.14224)
		(layer "In13.Cu")
		(net "P5E_CPU0_P3_RX_BUF_DP<8>")
	)
	(segment
		(start 396.880588 -419.615112)
		(end 396.468092 -419.44417)
		(width 0.14224)
		(layer "In13.Cu")
		(net "P5E_CPU0_P3_RX_BUF_DP<8>")
	)
	(segment
		(start 381.156972 -406.207722)
		(end 380.85522 -405.906224)
		(width 0.14224)
		(layer "In13.Cu")
		(net "P5E_CPU0_P3_RX_BUF_DP<8>")
	)
	(segment
		(start 380.05766 -403.980904)
		(end 380.05766 -403.554184)
		(width 0.14224)
		(layer "In13.Cu")
		(net "P5E_CPU0_P3_RX_BUF_DP<8>")
	)
	(segment
		(start 397.969232 -423.986706)
		(end 397.807688 -423.878756)
		(width 0.14224)
		(layer "In13.Cu")
		(net "P5E_CPU0_P3_RX_BUF_DP<8>")
	)
	(segment
		(start 381.350774 -406.207722)
		(end 381.156972 -406.207722)
		(width 0.14224)
		(layer "In13.Cu")
		(net "P5E_CPU0_P3_RX_BUF_DP<8>")
	)
	(segment
		(start 382.45034 -407.50109)
		(end 382.45034 -407.307288)
		(width 0.14224)
		(layer "In13.Cu")
		(net "P5E_CPU0_P3_RX_BUF_DP<8>")
	)
	(segment
		(start 380.05766 -403.554184)
		(end 380.19482 -403.417024)
		(width 0.14224)
		(layer "In13.Cu")
		(net "P5E_CPU0_P3_RX_BUF_DP<8>")
	)
	(segment
		(start 398.623028 -433.748942)
		(end 398.210278 -433.748942)
		(width 0.14224)
		(layer "In13.Cu")
		(net "P5E_CPU0_P3_RX_BUF_DP<8>")
	)
	(segment
		(start 396.109952 -417.419536)
		(end 395.972792 -417.282376)
		(width 0.14224)
		(layer "In13.Cu")
		(net "P5E_CPU0_P3_RX_BUF_DP<8>")
	)
	(segment
		(start 393.899644 -411.621224)
		(end 392.34364 -411.128972)
		(width 0.14224)
		(layer "In13.Cu")
		(net "P5E_CPU0_P3_RX_BUF_DP<8>")
	)
	(segment
		(start 390.607042 -410.43225)
		(end 390.288272 -410.259022)
		(width 0.14224)
		(layer "In13.Cu")
		(net "P5E_CPU0_P3_RX_BUF_DP<8>")
	)
	(segment
		(start 397.504412 -421.320214)
		(end 397.504412 -420.408354)
		(width 0.14224)
		(layer "In13.Cu")
		(net "P5E_CPU0_P3_RX_BUF_DP<8>")
	)
	(segment
		(start 398.750028 -433.621942)
		(end 398.623028 -433.748942)
		(width 0.14224)
		(layer "In13.Cu")
		(net "P5E_CPU0_P3_RX_BUF_DP<8>")
	)
	(segment
		(start 395.972792 -414.806892)
		(end 395.788388 -414.361884)
		(width 0.14224)
		(layer "In13.Cu")
		(net "P5E_CPU0_P3_RX_BUF_DP<8>")
	)
	(segment
		(start 383.070354 -408.050238)
		(end 382.893824 -407.944574)
		(width 0.14224)
		(layer "In13.Cu")
		(net "P5E_CPU0_P3_RX_BUF_DP<8>")
	)
	(segment
		(start 380.516638 -401.511008)
		(end 380.516638 -401.674838)
		(width 0.14224)
		(layer "In13.Cu")
		(net "P5E_CPU0_P3_RX_BUF_DP<8>")
	)
	(segment
		(start 390.122664 -410.18968)
		(end 383.070354 -408.050238)
		(width 0.14224)
		(layer "In13.Cu")
		(net "P5E_CPU0_P3_RX_BUF_DP<8>")
	)
	(segment
		(start 396.109952 -416.291776)
		(end 395.972792 -416.154616)
		(width 0.14224)
		(layer "In13.Cu")
		(net "P5E_CPU0_P3_RX_BUF_DP<8>")
	)
	(segment
		(start 394.770102 -413.956754)
		(end 394.698474 -413.927036)
		(width 0.14224)
		(layer "In13.Cu")
		(net "P5E_CPU0_P3_RX_BUF_DP<8>")
	)
	(segment
		(start 380.359158 -405.410162)
		(end 380.094998 -405.146002)
		(width 0.14224)
		(layer "In13.Cu")
		(net "P5E_CPU0_P3_RX_BUF_DP<8>")
	)
	(segment
		(start 395.454632 -414.028128)
		(end 395.28242 -413.956754)
		(width 0.14224)
		(layer "In13.Cu")
		(net "P5E_CPU0_P3_RX_BUF_DP<8>")
	)
	(segment
		(start 398.210278 -433.748942)
		(end 398.083278 -433.621942)
		(width 0.14224)
		(layer "In13.Cu")
		(net "P5E_CPU0_P3_RX_BUF_DP<8>")
	)
	(segment
		(start 397.749014 -422.880282)
		(end 397.58747 -422.772586)
		(width 0.14224)
		(layer "In13.Cu")
		(net "P5E_CPU0_P3_RX_BUF_DP<8>")
	)
	(segment
		(start 380.553214 -405.410162)
		(end 380.359158 -405.410162)
		(width 0.14224)
		(layer "In13.Cu")
		(net "P5E_CPU0_P3_RX_BUF_DP<8>")
	)
	(segment
		(start 390.760204 -410.387292)
		(end 390.607042 -410.43225)
		(width 0.14224)
		(layer "In13.Cu")
		(net "P5E_CPU0_P3_RX_BUF_DP<8>")
	)
	(segment
		(start 394.321284 -412.00324)
		(end 393.997942 -411.679898)
		(width 0.14224)
		(layer "In13.Cu")
		(net "P5E_CPU0_P3_RX_BUF_DP<8>")
	)
	(segment
		(start 395.972792 -416.154616)
		(end 395.972792 -414.806892)
		(width 0.14224)
		(layer "In13.Cu")
		(net "P5E_CPU0_P3_RX_BUF_DP<8>")
	)
	(segment
		(start 397.58747 -422.772586)
		(end 397.504412 -422.354248)
		(width 0.14224)
		(layer "In13.Cu")
		(net "P5E_CPU0_P3_RX_BUF_DP<8>")
	)
	(segment
		(start 395.788388 -414.361884)
		(end 395.454632 -414.028128)
		(width 0.14224)
		(layer "In13.Cu")
		(net "P5E_CPU0_P3_RX_BUF_DP<8>")
	)
	(segment
		(start 397.504412 -422.354248)
		(end 397.504412 -421.998902)
		(width 0.14224)
		(layer "In13.Cu")
		(net "P5E_CPU0_P3_RX_BUF_DP<8>")
	)
	(segment
		(start 396.174976 -419.151054)
		(end 395.972792 -418.663882)
		(width 0.14224)
		(layer "In13.Cu")
		(net "P5E_CPU0_P3_RX_BUF_DP<8>")
	)
	(segment
		(start 396.109952 -417.846256)
		(end 396.109952 -417.419536)
		(width 0.14224)
		(layer "In13.Cu")
		(net "P5E_CPU0_P3_RX_BUF_DP<8>")
	)
	(segment
		(start 380.19482 -402.990304)
		(end 380.05766 -402.853144)
		(width 0.14224)
		(layer "In13.Cu")
		(net "P5E_CPU0_P3_RX_BUF_DP<8>")
	)
	(segment
		(start 393.997942 -411.679898)
		(end 393.899644 -411.621224)
		(width 0.14224)
		(layer "In13.Cu")
		(net "P5E_CPU0_P3_RX_BUF_DP<8>")
	)
	(segment
		(start 395.972792 -416.855656)
		(end 396.109952 -416.718496)
		(width 0.14224)
		(layer "In13.Cu")
		(net "P5E_CPU0_P3_RX_BUF_DP<8>")
	)
	(segment
		(start 381.65278 -406.509728)
		(end 381.350774 -406.207722)
		(width 0.14224)
		(layer "In13.Cu")
		(net "P5E_CPU0_P3_RX_BUF_DP<8>")
	)
	(segment
		(start 394.441172 -413.567118)
		(end 394.441172 -412.292546)
		(width 0.14224)
		(layer "In13.Cu")
		(net "P5E_CPU0_P3_RX_BUF_DP<8>")
	)
	(segment
		(start 380.377192 -401.371562)
		(end 380.516638 -401.511008)
		(width 0.14224)
		(layer "In13.Cu")
		(net "P5E_CPU0_P3_RX_BUF_DP<8>")
	)
	(segment
		(start 397.504412 -421.998902)
		(end 397.630396 -421.872918)
		(width 0.14224)
		(layer "In13.Cu")
		(net "P5E_CPU0_P3_RX_BUF_DP<8>")
	)
	(segment
		(start 398.083278 -433.621942)
		(end 398.083278 -425.264072)
		(width 0.14224)
		(layer "In13.Cu")
		(net "P5E_CPU0_P3_RX_BUF_DP<8>")
	)
	(segment
		(start 395.972792 -417.282376)
		(end 395.972792 -416.855656)
		(width 0.14224)
		(layer "In13.Cu")
		(net "P5E_CPU0_P3_RX_BUF_DP<8>")
	)
	(segment
		(start 380.19482 -404.544784)
		(end 380.19482 -404.118064)
		(width 0.14224)
		(layer "In13.Cu")
		(net "P5E_CPU0_P3_RX_BUF_DP<8>")
	)
	(segment
		(start 395.28242 -413.956754)
		(end 394.770102 -413.956754)
		(width 0.14224)
		(layer "In13.Cu")
		(net "P5E_CPU0_P3_RX_BUF_DP<8>")
	)
	(segment
		(start 397.807688 -423.878756)
		(end 397.72463 -423.460418)
		(width 0.14224)
		(layer "In13.Cu")
		(net "P5E_CPU0_P3_RX_BUF_DP<8>")
	)
	(segment
		(start 392.34364 -411.128972)
		(end 391.700512 -410.990034)
		(width 0.14224)
		(layer "In13.Cu")
		(net "P5E_CPU0_P3_RX_BUF_DP<8>")
	)
	(segment
		(start 380.19482 -404.118064)
		(end 380.05766 -403.980904)
		(width 0.14224)
		(layer "In13.Cu")
		(net "P5E_CPU0_P3_RX_BUF_DP<8>")
	)
	(segment
		(start 397.832326 -423.299128)
		(end 397.749014 -422.880282)
		(width 0.14224)
		(layer "In13.Cu")
		(net "P5E_CPU0_P3_RX_BUF_DP<8>")
	)
	(segment
		(start 391.485374 -410.910278)
		(end 391.2235 -410.767784)
		(width 0.14224)
		(layer "In13.Cu")
		(net "P5E_CPU0_P3_RX_BUF_DP<8>")
	)
	(segment
		(start 381.65278 -406.703784)
		(end 381.65278 -406.509728)
		(width 0.14224)
		(layer "In13.Cu")
		(net "P5E_CPU0_P3_RX_BUF_DP<8>")
	)
	(segment
		(start 398.750028 -433.289964)
		(end 398.750028 -433.621942)
		(width 0.14224)
		(layer "In13.Cu")
		(net "P5E_CPU0_P3_RX_BUF_DP<8>")
	)
	(segment
		(start 397.630396 -421.872918)
		(end 397.630396 -421.446198)
		(width 0.14224)
		(layer "In13.Cu")
		(net "P5E_CPU0_P3_RX_BUF_DP<8>")
	)
	(segment
		(start 380.85522 -405.906224)
		(end 380.85522 -405.712168)
		(width 0.14224)
		(layer "In13.Cu")
		(net "P5E_CPU0_P3_RX_BUF_DP<8>")
	)
	(segment
		(start 397.630396 -421.446198)
		(end 397.504412 -421.320214)
		(width 0.14224)
		(layer "In13.Cu")
		(net "P5E_CPU0_P3_RX_BUF_DP<8>")
	)
	(segment
		(start 391.178288 -410.614622)
		(end 390.760204 -410.387292)
		(width 0.14224)
		(layer "In13.Cu")
		(net "P5E_CPU0_P3_RX_BUF_DP<8>")
	)
	(segment
		(start 391.2235 -410.767784)
		(end 391.178288 -410.614622)
		(width 0.14224)
		(layer "In13.Cu")
		(net "P5E_CPU0_P3_RX_BUF_DP<8>")
	)
	(segment
		(start 382.148334 -407.005282)
		(end 381.954532 -407.005282)
		(width 0.14224)
		(layer "In13.Cu")
		(net "P5E_CPU0_P3_RX_BUF_DP<8>")
	)
	(segment
		(start 397.384524 -420.119048)
		(end 396.880588 -419.615112)
		(width 0.14224)
		(layer "In13.Cu")
		(net "P5E_CPU0_P3_RX_BUF_DP<8>")
	)
	(segment
		(start 398.083278 -425.264072)
		(end 397.944594 -424.566588)
		(width 0.14224)
		(layer "In13.Cu")
		(net "P5E_CPU0_P3_RX_BUF_DP<8>")
	)
	(segment
		(start 381.954532 -407.005282)
		(end 381.65278 -406.703784)
		(width 0.14224)
		(layer "In13.Cu")
		(net "P5E_CPU0_P3_RX_BUF_DP<8>")
	)
	(segment
		(start 382.45034 -407.307288)
		(end 382.148334 -407.005282)
		(width 0.14224)
		(layer "In13.Cu")
		(net "P5E_CPU0_P3_RX_BUF_DP<8>")
	)
	(segment
		(start 395.972792 -418.663882)
		(end 395.972792 -417.983416)
		(width 0.14224)
		(layer "In13.Cu")
		(net "P5E_CPU0_P3_RX_BUF_DP<8>")
	)
	(segment
		(start 394.698474 -413.927036)
		(end 394.513816 -413.742378)
		(width 0.14224)
		(layer "In13.Cu")
		(net "P5E_CPU0_P3_RX_BUF_DP<8>")
	)
	(segment
		(start 380.19482 -403.417024)
		(end 380.19482 -402.990304)
		(width 0.14224)
		(layer "In13.Cu")
		(net "P5E_CPU0_P3_RX_BUF_DP<8>")
	)
	(segment
		(start 398.052544 -424.405298)
		(end 397.969232 -423.986706)
		(width 0.14224)
		(layer "In13.Cu")
		(net "P5E_CPU0_P3_RX_BUF_DP<8>")
	)
	(segment
		(start 395.972792 -417.983416)
		(end 396.109952 -417.846256)
		(width 0.14224)
		(layer "In13.Cu")
		(net "P5E_CPU0_P3_RX_BUF_DP<8>")
	)
	(segment
		(start 390.288272 -410.259022)
		(end 390.122664 -410.18968)
		(width 0.14224)
		(layer "In13.Cu")
		(net "P5E_CPU0_P3_RX_BUF_DP<8>")
	)
	(segment
		(start 380.05766 -405.055832)
		(end 380.05766 -404.681944)
		(width 0.14224)
		(layer "In13.Cu")
		(net "P5E_CPU0_P3_RX_BUF_DP<8>")
	)
	(segment
		(start 380.05766 -401.511008)
		(end 380.197106 -401.371562)
		(width 0.14224)
		(layer "In13.Cu")
		(net "P5E_CPU0_P3_RX_BUF_DP<8>")
	)
	(arc
		(start 380.094998 -405.146002)
		(mid 380.067355 -405.104632)
		(end 380.05766 -405.055832)
		(width 0.14224)
		(layer "In13.Cu")
		(net "P5E_CPU0_P3_RX_BUF_DP<8>")
	)
	(arc
		(start 397.504412 -420.408354)
		(mid 397.473249 -420.251776)
		(end 397.384524 -420.119048)
		(width 0.14224)
		(layer "In13.Cu")
		(net "P5E_CPU0_P3_RX_BUF_DP<8>")
	)
	(arc
		(start 396.468092 -419.44417)
		(mid 396.292401 -419.326745)
		(end 396.174976 -419.151054)
		(width 0.14224)
		(layer "In13.Cu")
		(net "P5E_CPU0_P3_RX_BUF_DP<8>")
	)
	(arc
		(start 394.441172 -412.292546)
		(mid 394.410009 -412.135968)
		(end 394.321284 -412.00324)
		(width 0.14224)
		(layer "In13.Cu")
		(net "P5E_CPU0_P3_RX_BUF_DP<8>")
	)
	(segment
		(start 378.70257 -399.74774)
		(end 378.70257 -399.870676)
		(width 0.1016)
		(layer "F.Cu")
		(net "P5E_CPU0_P3_RX_BUF_DP<7>")
	)
	(segment
		(start 378.613924 -401.105878)
		(end 378.867162 -401.359116)
		(width 0.1016)
		(layer "F.Cu")
		(net "P5E_CPU0_P3_RX_BUF_DP<7>")
	)
	(segment
		(start 378.70257 -399.870676)
		(end 378.613924 -399.959322)
		(width 0.1016)
		(layer "F.Cu")
		(net "P5E_CPU0_P3_RX_BUF_DP<7>")
	)
	(segment
		(start 378.867162 -401.359116)
		(end 379.177804 -401.359116)
		(width 0.1016)
		(layer "F.Cu")
		(net "P5E_CPU0_P3_RX_BUF_DP<7>")
	)
	(segment
		(start 379.316488 -401.4978)
		(end 379.316488 -401.674838)
		(width 0.1016)
		(layer "F.Cu")
		(net "P5E_CPU0_P3_RX_BUF_DP<7>")
	)
	(segment
		(start 378.617988 -399.663158)
		(end 378.70257 -399.74774)
		(width 0.1016)
		(layer "F.Cu")
		(net "P5E_CPU0_P3_RX_BUF_DP<7>")
	)
	(segment
		(start 378.613924 -399.959322)
		(end 378.613924 -401.105878)
		(width 0.1016)
		(layer "F.Cu")
		(net "P5E_CPU0_P3_RX_BUF_DP<7>")
	)
	(segment
		(start 379.177804 -401.359116)
		(end 379.316488 -401.4978)
		(width 0.1016)
		(layer "F.Cu")
		(net "P5E_CPU0_P3_RX_BUF_DP<7>")
	)
	(segment
		(start 391.377932 -412.38424)
		(end 391.308336 -412.154878)
		(width 0.14224)
		(layer "In13.Cu")
		(net "P5E_CPU0_P3_RX_BUF_DP<7>")
	)
	(segment
		(start 387.69036 -410.435298)
		(end 382.407922 -408.832558)
		(width 0.14224)
		(layer "In13.Cu")
		(net "P5E_CPU0_P3_RX_BUF_DP<7>")
	)
	(segment
		(start 380.150624 -406.56764)
		(end 379.956822 -406.56764)
		(width 0.14224)
		(layer "In13.Cu")
		(net "P5E_CPU0_P3_RX_BUF_DP<7>")
	)
	(segment
		(start 395.058392 -425.086018)
		(end 394.925296 -424.415712)
		(width 0.14224)
		(layer "In13.Cu")
		(net "P5E_CPU0_P3_RX_BUF_DP<7>")
	)
	(segment
		(start 379.956822 -406.56764)
		(end 379.65507 -406.266142)
		(width 0.14224)
		(layer "In13.Cu")
		(net "P5E_CPU0_P3_RX_BUF_DP<7>")
	)
	(segment
		(start 393.046712 -416.167062)
		(end 392.909552 -416.029902)
		(width 0.14224)
		(layer "In13.Cu")
		(net "P5E_CPU0_P3_RX_BUF_DP<7>")
	)
	(segment
		(start 381.25019 -407.861262)
		(end 381.25019 -407.667206)
		(width 0.14224)
		(layer "In13.Cu")
		(net "P5E_CPU0_P3_RX_BUF_DP<7>")
	)
	(segment
		(start 392.909552 -418.545772)
		(end 392.909552 -417.858702)
		(width 0.14224)
		(layer "In13.Cu")
		(net "P5E_CPU0_P3_RX_BUF_DP<7>")
	)
	(segment
		(start 378.99467 -403.396704)
		(end 378.99467 -402.969984)
		(width 0.14224)
		(layer "In13.Cu")
		(net "P5E_CPU0_P3_RX_BUF_DP<7>")
	)
	(segment
		(start 378.85751 -404.661624)
		(end 378.99467 -404.524464)
		(width 0.14224)
		(layer "In13.Cu")
		(net "P5E_CPU0_P3_RX_BUF_DP<7>")
	)
	(segment
		(start 389.134858 -410.884624)
		(end 388.955788 -410.959046)
		(width 0.14224)
		(layer "In13.Cu")
		(net "P5E_CPU0_P3_RX_BUF_DP<7>")
	)
	(segment
		(start 380.754382 -407.3652)
		(end 380.45263 -407.063702)
		(width 0.14224)
		(layer "In13.Cu")
		(net "P5E_CPU0_P3_RX_BUF_DP<7>")
	)
	(segment
		(start 395.058392 -434.6067)
		(end 395.058392 -425.086018)
		(width 0.14224)
		(layer "In13.Cu")
		(net "P5E_CPU0_P3_RX_BUF_DP<7>")
	)
	(segment
		(start 378.99467 -404.524464)
		(end 378.99467 -404.097744)
		(width 0.14224)
		(layer "In13.Cu")
		(net "P5E_CPU0_P3_RX_BUF_DP<7>")
	)
	(segment
		(start 392.909552 -414.806892)
		(end 392.725148 -414.361884)
		(width 0.14224)
		(layer "In13.Cu")
		(net "P5E_CPU0_P3_RX_BUF_DP<7>")
	)
	(segment
		(start 394.94968 -423.83583)
		(end 394.788136 -423.72788)
		(width 0.14224)
		(layer "In13.Cu")
		(net "P5E_CPU0_P3_RX_BUF_DP<7>")
	)
	(segment
		(start 389.997696 -411.390338)
		(end 389.603742 -411.227016)
		(width 0.14224)
		(layer "In13.Cu")
		(net "P5E_CPU0_P3_RX_BUF_DP<7>")
	)
	(segment
		(start 394.925296 -424.415712)
		(end 395.032992 -424.254422)
		(width 0.14224)
		(layer "In13.Cu")
		(net "P5E_CPU0_P3_RX_BUF_DP<7>")
	)
	(segment
		(start 380.45263 -407.063702)
		(end 380.45263 -406.869646)
		(width 0.14224)
		(layer "In13.Cu")
		(net "P5E_CPU0_P3_RX_BUF_DP<7>")
	)
	(segment
		(start 379.177042 -401.371562)
		(end 379.316488 -401.511008)
		(width 0.14224)
		(layer "In13.Cu")
		(net "P5E_CPU0_P3_RX_BUF_DP<7>")
	)
	(segment
		(start 394.569188 -422.62679)
		(end 394.441172 -421.983154)
		(width 0.14224)
		(layer "In13.Cu")
		(net "P5E_CPU0_P3_RX_BUF_DP<7>")
	)
	(segment
		(start 394.810742 -423.151046)
		(end 394.727684 -422.732454)
		(width 0.14224)
		(layer "In13.Cu")
		(net "P5E_CPU0_P3_RX_BUF_DP<7>")
	)
	(segment
		(start 389.603742 -411.22727)
		(end 389.529574 -411.047946)
		(width 0.14224)
		(layer "In13.Cu")
		(net "P5E_CPU0_P3_RX_BUF_DP<7>")
	)
	(segment
		(start 380.948184 -407.3652)
		(end 380.754382 -407.3652)
		(width 0.14224)
		(layer "In13.Cu")
		(net "P5E_CPU0_P3_RX_BUF_DP<7>")
	)
	(segment
		(start 378.85751 -405.41575)
		(end 378.85751 -404.661624)
		(width 0.14224)
		(layer "In13.Cu")
		(net "P5E_CPU0_P3_RX_BUF_DP<7>")
	)
	(segment
		(start 395.74978 -434.289962)
		(end 395.74978 -434.62194)
		(width 0.14224)
		(layer "In13.Cu")
		(net "P5E_CPU0_P3_RX_BUF_DP<7>")
	)
	(segment
		(start 388.955788 -410.959046)
		(end 387.69036 -410.435298)
		(width 0.14224)
		(layer "In13.Cu")
		(net "P5E_CPU0_P3_RX_BUF_DP<7>")
	)
	(segment
		(start 392.909552 -417.157662)
		(end 392.909552 -416.730942)
		(width 0.14224)
		(layer "In13.Cu")
		(net "P5E_CPU0_P3_RX_BUF_DP<7>")
	)
	(segment
		(start 393.046712 -417.294822)
		(end 392.909552 -417.157662)
		(width 0.14224)
		(layer "In13.Cu")
		(net "P5E_CPU0_P3_RX_BUF_DP<7>")
	)
	(segment
		(start 395.032992 -424.254422)
		(end 394.94968 -423.83583)
		(width 0.14224)
		(layer "In13.Cu")
		(net "P5E_CPU0_P3_RX_BUF_DP<7>")
	)
	(segment
		(start 394.441172 -421.983154)
		(end 394.441172 -420.433754)
		(width 0.14224)
		(layer "In13.Cu")
		(net "P5E_CPU0_P3_RX_BUF_DP<7>")
	)
	(segment
		(start 394.321284 -420.144448)
		(end 393.858496 -419.68166)
		(width 0.14224)
		(layer "In13.Cu")
		(net "P5E_CPU0_P3_RX_BUF_DP<7>")
	)
	(segment
		(start 395.74978 -434.62194)
		(end 395.62278 -434.74894)
		(width 0.14224)
		(layer "In13.Cu")
		(net "P5E_CPU0_P3_RX_BUF_DP<7>")
	)
	(segment
		(start 393.113006 -419.06825)
		(end 392.921744 -418.607494)
		(width 0.14224)
		(layer "In13.Cu")
		(net "P5E_CPU0_P3_RX_BUF_DP<7>")
	)
	(segment
		(start 379.65507 -406.266142)
		(end 379.65507 -406.072086)
		(width 0.14224)
		(layer "In13.Cu")
		(net "P5E_CPU0_P3_RX_BUF_DP<7>")
	)
	(segment
		(start 390.646666 -411.524958)
		(end 390.321292 -411.390338)
		(width 0.14224)
		(layer "In13.Cu")
		(net "P5E_CPU0_P3_RX_BUF_DP<7>")
	)
	(segment
		(start 379.159008 -405.77008)
		(end 378.894848 -405.50592)
		(width 0.14224)
		(layer "In13.Cu")
		(net "P5E_CPU0_P3_RX_BUF_DP<7>")
	)
	(segment
		(start 379.353064 -405.77008)
		(end 379.159008 -405.77008)
		(width 0.14224)
		(layer "In13.Cu")
		(net "P5E_CPU0_P3_RX_BUF_DP<7>")
	)
	(segment
		(start 379.316488 -401.511008)
		(end 379.316488 -401.674838)
		(width 0.14224)
		(layer "In13.Cu")
		(net "P5E_CPU0_P3_RX_BUF_DP<7>")
	)
	(segment
		(start 380.45263 -406.869646)
		(end 380.150624 -406.56764)
		(width 0.14224)
		(layer "In13.Cu")
		(net "P5E_CPU0_P3_RX_BUF_DP<7>")
	)
	(segment
		(start 392.21918 -413.956754)
		(end 391.706862 -413.956754)
		(width 0.14224)
		(layer "In13.Cu")
		(net "P5E_CPU0_P3_RX_BUF_DP<7>")
	)
	(segment
		(start 378.85751 -401.511008)
		(end 378.996956 -401.371562)
		(width 0.14224)
		(layer "In13.Cu")
		(net "P5E_CPU0_P3_RX_BUF_DP<7>")
	)
	(segment
		(start 378.99467 -402.969984)
		(end 378.85751 -402.832824)
		(width 0.14224)
		(layer "In13.Cu")
		(net "P5E_CPU0_P3_RX_BUF_DP<7>")
	)
	(segment
		(start 391.178796 -411.961076)
		(end 390.646666 -411.524958)
		(width 0.14224)
		(layer "In13.Cu")
		(net "P5E_CPU0_P3_RX_BUF_DP<7>")
	)
	(segment
		(start 391.635234 -413.927036)
		(end 391.450576 -413.742378)
		(width 0.14224)
		(layer "In13.Cu")
		(net "P5E_CPU0_P3_RX_BUF_DP<7>")
	)
	(segment
		(start 378.85751 -403.533864)
		(end 378.99467 -403.396704)
		(width 0.14224)
		(layer "In13.Cu")
		(net "P5E_CPU0_P3_RX_BUF_DP<7>")
	)
	(segment
		(start 391.377932 -413.567118)
		(end 391.377932 -412.38424)
		(width 0.14224)
		(layer "In13.Cu")
		(net "P5E_CPU0_P3_RX_BUF_DP<7>")
	)
	(segment
		(start 390.321292 -411.390338)
		(end 389.997696 -411.390338)
		(width 0.14224)
		(layer "In13.Cu")
		(net "P5E_CPU0_P3_RX_BUF_DP<7>")
	)
	(segment
		(start 389.603742 -411.227016)
		(end 389.603742 -411.22727)
		(width 0.14224)
		(layer "In13.Cu")
		(net "P5E_CPU0_P3_RX_BUF_DP<7>")
	)
	(segment
		(start 392.725148 -414.361884)
		(end 392.391392 -414.028128)
		(width 0.14224)
		(layer "In13.Cu")
		(net "P5E_CPU0_P3_RX_BUF_DP<7>")
	)
	(segment
		(start 393.6619 -419.550596)
		(end 393.52982 -419.495986)
		(width 0.14224)
		(layer "In13.Cu")
		(net "P5E_CPU0_P3_RX_BUF_DP<7>")
	)
	(segment
		(start 394.727684 -422.732454)
		(end 394.569188 -422.62679)
		(width 0.14224)
		(layer "In13.Cu")
		(net "P5E_CPU0_P3_RX_BUF_DP<7>")
	)
	(segment
		(start 389.529574 -411.047946)
		(end 389.134858 -410.884624)
		(width 0.14224)
		(layer "In13.Cu")
		(net "P5E_CPU0_P3_RX_BUF_DP<7>")
	)
	(segment
		(start 378.85751 -403.960584)
		(end 378.85751 -403.533864)
		(width 0.14224)
		(layer "In13.Cu")
		(net "P5E_CPU0_P3_RX_BUF_DP<7>")
	)
	(segment
		(start 381.25019 -407.667206)
		(end 380.948184 -407.3652)
		(width 0.14224)
		(layer "In13.Cu")
		(net "P5E_CPU0_P3_RX_BUF_DP<7>")
	)
	(segment
		(start 393.046712 -417.721542)
		(end 393.046712 -417.294822)
		(width 0.14224)
		(layer "In13.Cu")
		(net "P5E_CPU0_P3_RX_BUF_DP<7>")
	)
	(segment
		(start 392.391392 -414.028128)
		(end 392.21918 -413.956754)
		(width 0.14224)
		(layer "In13.Cu")
		(net "P5E_CPU0_P3_RX_BUF_DP<7>")
	)
	(segment
		(start 391.450576 -413.742378)
		(end 391.377932 -413.567118)
		(width 0.14224)
		(layer "In13.Cu")
		(net "P5E_CPU0_P3_RX_BUF_DP<7>")
	)
	(segment
		(start 394.705078 -423.309542)
		(end 394.810742 -423.151046)
		(width 0.14224)
		(layer "In13.Cu")
		(net "P5E_CPU0_P3_RX_BUF_DP<7>")
	)
	(segment
		(start 391.706862 -413.956754)
		(end 391.635234 -413.927036)
		(width 0.14224)
		(layer "In13.Cu")
		(net "P5E_CPU0_P3_RX_BUF_DP<7>")
	)
	(segment
		(start 378.996956 -401.371562)
		(end 379.177042 -401.371562)
		(width 0.14224)
		(layer "In13.Cu")
		(net "P5E_CPU0_P3_RX_BUF_DP<7>")
	)
	(segment
		(start 381.942848 -408.55392)
		(end 381.25019 -407.861262)
		(width 0.14224)
		(layer "In13.Cu")
		(net "P5E_CPU0_P3_RX_BUF_DP<7>")
	)
	(segment
		(start 392.909552 -416.029902)
		(end 392.909552 -414.806892)
		(width 0.14224)
		(layer "In13.Cu")
		(net "P5E_CPU0_P3_RX_BUF_DP<7>")
	)
	(segment
		(start 392.909552 -417.858702)
		(end 393.046712 -417.721542)
		(width 0.14224)
		(layer "In13.Cu")
		(net "P5E_CPU0_P3_RX_BUF_DP<7>")
	)
	(segment
		(start 378.85751 -402.832824)
		(end 378.85751 -401.511008)
		(width 0.14224)
		(layer "In13.Cu")
		(net "P5E_CPU0_P3_RX_BUF_DP<7>")
	)
	(segment
		(start 393.046712 -416.593782)
		(end 393.046712 -416.167062)
		(width 0.14224)
		(layer "In13.Cu")
		(net "P5E_CPU0_P3_RX_BUF_DP<7>")
	)
	(segment
		(start 379.65507 -406.072086)
		(end 379.353064 -405.77008)
		(width 0.14224)
		(layer "In13.Cu")
		(net "P5E_CPU0_P3_RX_BUF_DP<7>")
	)
	(segment
		(start 392.909552 -416.730942)
		(end 393.046712 -416.593782)
		(width 0.14224)
		(layer "In13.Cu")
		(net "P5E_CPU0_P3_RX_BUF_DP<7>")
	)
	(segment
		(start 391.308336 -412.154878)
		(end 391.178796 -411.961076)
		(width 0.14224)
		(layer "In13.Cu")
		(net "P5E_CPU0_P3_RX_BUF_DP<7>")
	)
	(segment
		(start 394.788136 -423.72788)
		(end 394.705078 -423.309542)
		(width 0.14224)
		(layer "In13.Cu")
		(net "P5E_CPU0_P3_RX_BUF_DP<7>")
	)
	(segment
		(start 395.200632 -434.74894)
		(end 395.058392 -434.6067)
		(width 0.14224)
		(layer "In13.Cu")
		(net "P5E_CPU0_P3_RX_BUF_DP<7>")
	)
	(segment
		(start 378.99467 -404.097744)
		(end 378.85751 -403.960584)
		(width 0.14224)
		(layer "In13.Cu")
		(net "P5E_CPU0_P3_RX_BUF_DP<7>")
	)
	(segment
		(start 395.62278 -434.74894)
		(end 395.200632 -434.74894)
		(width 0.14224)
		(layer "In13.Cu")
		(net "P5E_CPU0_P3_RX_BUF_DP<7>")
	)
	(arc
		(start 393.172442 -419.18001)
		(mid 393.140058 -419.125548)
		(end 393.113006 -419.06825)
		(width 0.14224)
		(layer "In13.Cu")
		(net "P5E_CPU0_P3_RX_BUF_DP<7>")
	)
	(arc
		(start 392.921744 -418.607494)
		(mid 392.912604 -418.577234)
		(end 392.909552 -418.545772)
		(width 0.14224)
		(layer "In13.Cu")
		(net "P5E_CPU0_P3_RX_BUF_DP<7>")
	)
	(arc
		(start 393.52982 -419.495986)
		(mid 393.472599 -419.468503)
		(end 393.418822 -419.434772)
		(width 0.14224)
		(layer "In13.Cu")
		(net "P5E_CPU0_P3_RX_BUF_DP<7>")
	)
	(arc
		(start 393.858496 -419.68166)
		(mid 393.766665 -419.606431)
		(end 393.6619 -419.550596)
		(width 0.14224)
		(layer "In13.Cu")
		(net "P5E_CPU0_P3_RX_BUF_DP<7>")
	)
	(arc
		(start 378.894848 -405.50592)
		(mid 378.867205 -405.46455)
		(end 378.85751 -405.41575)
		(width 0.14224)
		(layer "In13.Cu")
		(net "P5E_CPU0_P3_RX_BUF_DP<7>")
	)
	(arc
		(start 393.418822 -419.434772)
		(mid 393.283873 -419.318762)
		(end 393.172442 -419.18001)
		(width 0.14224)
		(layer "In13.Cu")
		(net "P5E_CPU0_P3_RX_BUF_DP<7>")
	)
	(arc
		(start 382.407922 -408.832558)
		(mid 382.158202 -408.721917)
		(end 381.942848 -408.55392)
		(width 0.14224)
		(layer "In13.Cu")
		(net "P5E_CPU0_P3_RX_BUF_DP<7>")
	)
	(arc
		(start 394.441172 -420.433754)
		(mid 394.410009 -420.277176)
		(end 394.321284 -420.144448)
		(width 0.14224)
		(layer "In13.Cu")
		(net "P5E_CPU0_P3_RX_BUF_DP<7>")
	)
	(segment
		(start 377.50242 -399.74774)
		(end 377.50242 -399.870676)
		(width 0.1016)
		(layer "F.Cu")
		(net "P5E_CPU0_P3_RX_BUF_DP<6>")
	)
	(segment
		(start 378.116592 -401.498054)
		(end 378.116592 -401.674838)
		(width 0.1016)
		(layer "F.Cu")
		(net "P5E_CPU0_P3_RX_BUF_DP<6>")
	)
	(segment
		(start 377.417838 -399.663158)
		(end 377.50242 -399.74774)
		(width 0.1016)
		(layer "F.Cu")
		(net "P5E_CPU0_P3_RX_BUF_DP<6>")
	)
	(segment
		(start 377.422664 -401.105878)
		(end 377.675902 -401.359116)
		(width 0.1016)
		(layer "F.Cu")
		(net "P5E_CPU0_P3_RX_BUF_DP<6>")
	)
	(segment
		(start 377.675902 -401.359116)
		(end 377.977654 -401.359116)
		(width 0.1016)
		(layer "F.Cu")
		(net "P5E_CPU0_P3_RX_BUF_DP<6>")
	)
	(segment
		(start 377.50242 -399.870676)
		(end 377.422664 -399.950432)
		(width 0.1016)
		(layer "F.Cu")
		(net "P5E_CPU0_P3_RX_BUF_DP<6>")
	)
	(segment
		(start 377.422664 -399.950432)
		(end 377.422664 -401.105878)
		(width 0.1016)
		(layer "F.Cu")
		(net "P5E_CPU0_P3_RX_BUF_DP<6>")
	)
	(segment
		(start 377.977654 -401.359116)
		(end 378.116592 -401.498054)
		(width 0.1016)
		(layer "F.Cu")
		(net "P5E_CPU0_P3_RX_BUF_DP<6>")
	)
	(segment
		(start 378.756672 -406.959308)
		(end 378.950728 -406.959308)
		(width 0.14224)
		(layer "In13.Cu")
		(net "P5E_CPU0_P3_RX_BUF_DP<6>")
	)
	(segment
		(start 392.44524 -423.667682)
		(end 392.624818 -423.731944)
		(width 0.14224)
		(layer "In13.Cu")
		(net "P5E_CPU0_P3_RX_BUF_DP<6>")
	)
	(segment
		(start 389.983472 -417.18992)
		(end 389.983472 -417.61664)
		(width 0.14224)
		(layer "In13.Cu")
		(net "P5E_CPU0_P3_RX_BUF_DP<6>")
	)
	(segment
		(start 388.314692 -413.509968)
		(end 388.427468 -413.78251)
		(width 0.14224)
		(layer "In13.Cu")
		(net "P5E_CPU0_P3_RX_BUF_DP<6>")
	)
	(segment
		(start 378.455174 -406.65781)
		(end 378.756672 -406.959308)
		(width 0.14224)
		(layer "In13.Cu")
		(net "P5E_CPU0_P3_RX_BUF_DP<6>")
	)
	(segment
		(start 378.455174 -406.463754)
		(end 378.455174 -406.65781)
		(width 0.14224)
		(layer "In13.Cu")
		(net "P5E_CPU0_P3_RX_BUF_DP<6>")
	)
	(segment
		(start 377.977146 -401.371562)
		(end 377.79706 -401.371562)
		(width 0.14224)
		(layer "In13.Cu")
		(net "P5E_CPU0_P3_RX_BUF_DP<6>")
	)
	(segment
		(start 379.554232 -407.756868)
		(end 379.748288 -407.756868)
		(width 0.14224)
		(layer "In13.Cu")
		(net "P5E_CPU0_P3_RX_BUF_DP<6>")
	)
	(segment
		(start 392.80719 -424.11777)
		(end 392.742928 -424.297094)
		(width 0.14224)
		(layer "In13.Cu")
		(net "P5E_CPU0_P3_RX_BUF_DP<6>")
	)
	(segment
		(start 389.15594 -413.956754)
		(end 389.328152 -414.028128)
		(width 0.14224)
		(layer "In13.Cu")
		(net "P5E_CPU0_P3_RX_BUF_DP<6>")
	)
	(segment
		(start 389.87095 -418.635942)
		(end 390.042146 -419.0492)
		(width 0.14224)
		(layer "In13.Cu")
		(net "P5E_CPU0_P3_RX_BUF_DP<6>")
	)
	(segment
		(start 392.624818 -423.731944)
		(end 392.80719 -424.11777)
		(width 0.14224)
		(layer "In13.Cu")
		(net "P5E_CPU0_P3_RX_BUF_DP<6>")
	)
	(segment
		(start 388.314692 -412.289498)
		(end 388.314692 -413.509968)
		(width 0.14224)
		(layer "In13.Cu")
		(net "P5E_CPU0_P3_RX_BUF_DP<6>")
	)
	(segment
		(start 378.950728 -406.959308)
		(end 379.252734 -407.261314)
		(width 0.14224)
		(layer "In13.Cu")
		(net "P5E_CPU0_P3_RX_BUF_DP<6>")
	)
	(segment
		(start 389.846312 -414.806892)
		(end 389.846312 -415.925)
		(width 0.14224)
		(layer "In13.Cu")
		(net "P5E_CPU0_P3_RX_BUF_DP<6>")
	)
	(segment
		(start 379.252734 -407.261314)
		(end 379.252734 -407.45537)
		(width 0.14224)
		(layer "In13.Cu")
		(net "P5E_CPU0_P3_RX_BUF_DP<6>")
	)
	(segment
		(start 378.153168 -406.161748)
		(end 378.455174 -406.463754)
		(width 0.14224)
		(layer "In13.Cu")
		(net "P5E_CPU0_P3_RX_BUF_DP<6>")
	)
	(segment
		(start 389.983472 -417.61664)
		(end 389.846312 -417.7538)
		(width 0.14224)
		(layer "In13.Cu")
		(net "P5E_CPU0_P3_RX_BUF_DP<6>")
	)
	(segment
		(start 377.794774 -404.571454)
		(end 377.657614 -404.708614)
		(width 0.14224)
		(layer "In13.Cu")
		(net "P5E_CPU0_P3_RX_BUF_DP<6>")
	)
	(segment
		(start 389.661908 -414.361884)
		(end 389.846312 -414.806892)
		(width 0.14224)
		(layer "In13.Cu")
		(net "P5E_CPU0_P3_RX_BUF_DP<6>")
	)
	(segment
		(start 393.749784 -433.621942)
		(end 393.749784 -433.289964)
		(width 0.14224)
		(layer "In13.Cu")
		(net "P5E_CPU0_P3_RX_BUF_DP<6>")
	)
	(segment
		(start 392.32713 -423.102786)
		(end 392.262868 -423.28211)
		(width 0.14224)
		(layer "In13.Cu")
		(net "P5E_CPU0_P3_RX_BUF_DP<6>")
	)
	(segment
		(start 377.794774 -403.443694)
		(end 377.657614 -403.580854)
		(width 0.14224)
		(layer "In13.Cu")
		(net "P5E_CPU0_P3_RX_BUF_DP<6>")
	)
	(segment
		(start 378.116592 -401.674838)
		(end 378.116592 -401.511008)
		(width 0.14224)
		(layer "In13.Cu")
		(net "P5E_CPU0_P3_RX_BUF_DP<6>")
	)
	(segment
		(start 389.846312 -416.62604)
		(end 389.846312 -417.05276)
		(width 0.14224)
		(layer "In13.Cu")
		(net "P5E_CPU0_P3_RX_BUF_DP<6>")
	)
	(segment
		(start 380.050294 -408.25293)
		(end 380.431802 -408.634438)
		(width 0.14224)
		(layer "In13.Cu")
		(net "P5E_CPU0_P3_RX_BUF_DP<6>")
	)
	(segment
		(start 393.185396 -433.748942)
		(end 393.622784 -433.748942)
		(width 0.14224)
		(layer "In13.Cu")
		(net "P5E_CPU0_P3_RX_BUF_DP<6>")
	)
	(segment
		(start 377.657614 -404.708614)
		(end 377.657614 -405.648922)
		(width 0.14224)
		(layer "In13.Cu")
		(net "P5E_CPU0_P3_RX_BUF_DP<6>")
	)
	(segment
		(start 377.657614 -402.879814)
		(end 377.794774 -403.016974)
		(width 0.14224)
		(layer "In13.Cu")
		(net "P5E_CPU0_P3_RX_BUF_DP<6>")
	)
	(segment
		(start 377.657614 -404.007574)
		(end 377.794774 -404.144734)
		(width 0.14224)
		(layer "In13.Cu")
		(net "P5E_CPU0_P3_RX_BUF_DP<6>")
	)
	(segment
		(start 379.252734 -407.45537)
		(end 379.554232 -407.756868)
		(width 0.14224)
		(layer "In13.Cu")
		(net "P5E_CPU0_P3_RX_BUF_DP<6>")
	)
	(segment
		(start 379.748288 -407.756868)
		(end 380.050294 -408.058874)
		(width 0.14224)
		(layer "In13.Cu")
		(net "P5E_CPU0_P3_RX_BUF_DP<6>")
	)
	(segment
		(start 391.426446 -421.513762)
		(end 391.96518 -422.652698)
		(width 0.14224)
		(layer "In13.Cu")
		(net "P5E_CPU0_P3_RX_BUF_DP<6>")
	)
	(segment
		(start 389.328152 -414.028128)
		(end 389.661908 -414.361884)
		(width 0.14224)
		(layer "In13.Cu")
		(net "P5E_CPU0_P3_RX_BUF_DP<6>")
	)
	(segment
		(start 388.427468 -413.78251)
		(end 388.571994 -413.927036)
		(width 0.14224)
		(layer "In13.Cu")
		(net "P5E_CPU0_P3_RX_BUF_DP<6>")
	)
	(segment
		(start 377.794774 -403.016974)
		(end 377.794774 -403.443694)
		(width 0.14224)
		(layer "In13.Cu")
		(net "P5E_CPU0_P3_RX_BUF_DP<6>")
	)
	(segment
		(start 393.622784 -433.748942)
		(end 393.749784 -433.621942)
		(width 0.14224)
		(layer "In13.Cu")
		(net "P5E_CPU0_P3_RX_BUF_DP<6>")
	)
	(segment
		(start 391.377932 -420.498524)
		(end 391.377932 -421.298624)
		(width 0.14224)
		(layer "In13.Cu")
		(net "P5E_CPU0_P3_RX_BUF_DP<6>")
	)
	(segment
		(start 389.846312 -417.05276)
		(end 389.983472 -417.18992)
		(width 0.14224)
		(layer "In13.Cu")
		(net "P5E_CPU0_P3_RX_BUF_DP<6>")
	)
	(segment
		(start 377.657614 -403.580854)
		(end 377.657614 -404.007574)
		(width 0.14224)
		(layer "In13.Cu")
		(net "P5E_CPU0_P3_RX_BUF_DP<6>")
	)
	(segment
		(start 381.397256 -409.530042)
		(end 387.552692 -411.39745)
		(width 0.14224)
		(layer "In13.Cu")
		(net "P5E_CPU0_P3_RX_BUF_DP<6>")
	)
	(segment
		(start 377.959112 -406.161748)
		(end 378.153168 -406.161748)
		(width 0.14224)
		(layer "In13.Cu")
		(net "P5E_CPU0_P3_RX_BUF_DP<6>")
	)
	(segment
		(start 389.846312 -417.7538)
		(end 389.846312 -418.512498)
		(width 0.14224)
		(layer "In13.Cu")
		(net "P5E_CPU0_P3_RX_BUF_DP<6>")
	)
	(segment
		(start 380.625858 -408.634438)
		(end 380.927864 -408.936444)
		(width 0.14224)
		(layer "In13.Cu")
		(net "P5E_CPU0_P3_RX_BUF_DP<6>")
	)
	(segment
		(start 393.058396 -425.057316)
		(end 393.058396 -433.621942)
		(width 0.14224)
		(layer "In13.Cu")
		(net "P5E_CPU0_P3_RX_BUF_DP<6>")
	)
	(segment
		(start 377.79706 -401.371562)
		(end 377.657614 -401.511008)
		(width 0.14224)
		(layer "In13.Cu")
		(net "P5E_CPU0_P3_RX_BUF_DP<6>")
	)
	(segment
		(start 389.983472 -416.48888)
		(end 389.846312 -416.62604)
		(width 0.14224)
		(layer "In13.Cu")
		(net "P5E_CPU0_P3_RX_BUF_DP<6>")
	)
	(segment
		(start 392.262868 -423.28211)
		(end 392.44524 -423.667682)
		(width 0.14224)
		(layer "In13.Cu")
		(net "P5E_CPU0_P3_RX_BUF_DP<6>")
	)
	(segment
		(start 378.116592 -401.511008)
		(end 377.977146 -401.371562)
		(width 0.14224)
		(layer "In13.Cu")
		(net "P5E_CPU0_P3_RX_BUF_DP<6>")
	)
	(segment
		(start 380.050294 -408.058874)
		(end 380.050294 -408.25293)
		(width 0.14224)
		(layer "In13.Cu")
		(net "P5E_CPU0_P3_RX_BUF_DP<6>")
	)
	(segment
		(start 388.643622 -413.956754)
		(end 389.15594 -413.956754)
		(width 0.14224)
		(layer "In13.Cu")
		(net "P5E_CPU0_P3_RX_BUF_DP<6>")
	)
	(segment
		(start 389.983472 -416.06216)
		(end 389.983472 -416.48888)
		(width 0.14224)
		(layer "In13.Cu")
		(net "P5E_CPU0_P3_RX_BUF_DP<6>")
	)
	(segment
		(start 387.552692 -411.39745)
		(end 388.118096 -411.795722)
		(width 0.14224)
		(layer "In13.Cu")
		(net "P5E_CPU0_P3_RX_BUF_DP<6>")
	)
	(segment
		(start 390.82218 -419.75913)
		(end 391.248138 -420.185088)
		(width 0.14224)
		(layer "In13.Cu")
		(net "P5E_CPU0_P3_RX_BUF_DP<6>")
	)
	(segment
		(start 392.742928 -424.297094)
		(end 393.018518 -424.87977)
		(width 0.14224)
		(layer "In13.Cu")
		(net "P5E_CPU0_P3_RX_BUF_DP<6>")
	)
	(segment
		(start 380.431802 -408.634438)
		(end 380.625858 -408.634438)
		(width 0.14224)
		(layer "In13.Cu")
		(net "P5E_CPU0_P3_RX_BUF_DP<6>")
	)
	(segment
		(start 377.657614 -401.511008)
		(end 377.657614 -402.879814)
		(width 0.14224)
		(layer "In13.Cu")
		(net "P5E_CPU0_P3_RX_BUF_DP<6>")
	)
	(segment
		(start 389.846312 -415.925)
		(end 389.983472 -416.06216)
		(width 0.14224)
		(layer "In13.Cu")
		(net "P5E_CPU0_P3_RX_BUF_DP<6>")
	)
	(segment
		(start 388.571994 -413.927036)
		(end 388.643622 -413.956754)
		(width 0.14224)
		(layer "In13.Cu")
		(net "P5E_CPU0_P3_RX_BUF_DP<6>")
	)
	(segment
		(start 377.80722 -406.009856)
		(end 377.959112 -406.161748)
		(width 0.14224)
		(layer "In13.Cu")
		(net "P5E_CPU0_P3_RX_BUF_DP<6>")
	)
	(segment
		(start 388.118096 -411.795722)
		(end 388.26186 -412.07309)
		(width 0.14224)
		(layer "In13.Cu")
		(net "P5E_CPU0_P3_RX_BUF_DP<6>")
	)
	(segment
		(start 393.058396 -433.621942)
		(end 393.185396 -433.748942)
		(width 0.14224)
		(layer "In13.Cu")
		(net "P5E_CPU0_P3_RX_BUF_DP<6>")
	)
	(segment
		(start 380.927864 -408.936444)
		(end 380.927864 -409.1305)
		(width 0.14224)
		(layer "In13.Cu")
		(net "P5E_CPU0_P3_RX_BUF_DP<6>")
	)
	(segment
		(start 391.96518 -422.652698)
		(end 392.144504 -422.716706)
		(width 0.14224)
		(layer "In13.Cu")
		(net "P5E_CPU0_P3_RX_BUF_DP<6>")
	)
	(segment
		(start 392.144504 -422.716706)
		(end 392.32713 -423.102786)
		(width 0.14224)
		(layer "In13.Cu")
		(net "P5E_CPU0_P3_RX_BUF_DP<6>")
	)
	(segment
		(start 380.927864 -409.1305)
		(end 381.222758 -409.425394)
		(width 0.14224)
		(layer "In13.Cu")
		(net "P5E_CPU0_P3_RX_BUF_DP<6>")
	)
	(segment
		(start 377.794774 -404.144734)
		(end 377.794774 -404.571454)
		(width 0.14224)
		(layer "In13.Cu")
		(net "P5E_CPU0_P3_RX_BUF_DP<6>")
	)
	(arc
		(start 377.657614 -405.648922)
		(mid 377.696492 -405.844283)
		(end 377.80722 -406.009856)
		(width 0.14224)
		(layer "In13.Cu")
		(net "P5E_CPU0_P3_RX_BUF_DP<6>")
	)
	(arc
		(start 391.377932 -421.298624)
		(mid 391.390268 -421.408881)
		(end 391.426446 -421.513762)
		(width 0.14224)
		(layer "In13.Cu")
		(net "P5E_CPU0_P3_RX_BUF_DP<6>")
	)
	(arc
		(start 393.018518 -424.87977)
		(mid 393.048296 -424.966333)
		(end 393.058396 -425.057316)
		(width 0.14224)
		(layer "In13.Cu")
		(net "P5E_CPU0_P3_RX_BUF_DP<6>")
	)
	(arc
		(start 390.442196 -419.482778)
		(mid 390.642994 -419.606097)
		(end 390.82218 -419.75913)
		(width 0.14224)
		(layer "In13.Cu")
		(net "P5E_CPU0_P3_RX_BUF_DP<6>")
	)
	(arc
		(start 381.222758 -409.425394)
		(mid 381.303546 -409.488495)
		(end 381.397256 -409.530042)
		(width 0.14224)
		(layer "In13.Cu")
		(net "P5E_CPU0_P3_RX_BUF_DP<6>")
	)
	(arc
		(start 391.248138 -420.185088)
		(mid 391.344226 -420.328894)
		(end 391.377932 -420.498524)
		(width 0.14224)
		(layer "In13.Cu")
		(net "P5E_CPU0_P3_RX_BUF_DP<6>")
	)
	(arc
		(start 389.846312 -418.512498)
		(mid 389.852566 -418.575429)
		(end 389.87095 -418.635942)
		(width 0.14224)
		(layer "In13.Cu")
		(net "P5E_CPU0_P3_RX_BUF_DP<6>")
	)
	(arc
		(start 388.26186 -412.07309)
		(mid 388.301271 -412.17812)
		(end 388.314692 -412.289498)
		(width 0.14224)
		(layer "In13.Cu")
		(net "P5E_CPU0_P3_RX_BUF_DP<6>")
	)
	(arc
		(start 390.042146 -419.0492)
		(mid 390.203502 -419.301679)
		(end 390.442196 -419.482778)
		(width 0.14224)
		(layer "In13.Cu")
		(net "P5E_CPU0_P3_RX_BUF_DP<6>")
	)
	(segment
		(start 376.213878 -401.105878)
		(end 376.467116 -401.359116)
		(width 0.1016)
		(layer "F.Cu")
		(net "P5E_CPU0_P3_RX_BUF_DP<5>")
	)
	(segment
		(start 376.467116 -401.359116)
		(end 376.777758 -401.359116)
		(width 0.1016)
		(layer "F.Cu")
		(net "P5E_CPU0_P3_RX_BUF_DP<5>")
	)
	(segment
		(start 376.217942 -399.663158)
		(end 376.302524 -399.74774)
		(width 0.1016)
		(layer "F.Cu")
		(net "P5E_CPU0_P3_RX_BUF_DP<5>")
	)
	(segment
		(start 376.302524 -399.870676)
		(end 376.213878 -399.959322)
		(width 0.1016)
		(layer "F.Cu")
		(net "P5E_CPU0_P3_RX_BUF_DP<5>")
	)
	(segment
		(start 376.777758 -401.359116)
		(end 376.916442 -401.4978)
		(width 0.1016)
		(layer "F.Cu")
		(net "P5E_CPU0_P3_RX_BUF_DP<5>")
	)
	(segment
		(start 376.302524 -399.74774)
		(end 376.302524 -399.870676)
		(width 0.1016)
		(layer "F.Cu")
		(net "P5E_CPU0_P3_RX_BUF_DP<5>")
	)
	(segment
		(start 376.213878 -399.959322)
		(end 376.213878 -401.105878)
		(width 0.1016)
		(layer "F.Cu")
		(net "P5E_CPU0_P3_RX_BUF_DP<5>")
	)
	(segment
		(start 376.916442 -401.4978)
		(end 376.916442 -401.674838)
		(width 0.1016)
		(layer "F.Cu")
		(net "P5E_CPU0_P3_RX_BUF_DP<5>")
	)
	(segment
		(start 391.0584 -434.532024)
		(end 391.0584 -425.416726)
		(width 0.14224)
		(layer "In13.Cu")
		(net "P5E_CPU0_P3_RX_BUF_DP<5>")
	)
	(segment
		(start 376.457464 -403.869398)
		(end 376.594624 -403.732238)
		(width 0.14224)
		(layer "In13.Cu")
		(net "P5E_CPU0_P3_RX_BUF_DP<5>")
	)
	(segment
		(start 385.580382 -413.956754)
		(end 385.508754 -413.927036)
		(width 0.14224)
		(layer "In13.Cu")
		(net "P5E_CPU0_P3_RX_BUF_DP<5>")
	)
	(segment
		(start 377.255024 -406.957784)
		(end 376.953018 -406.655778)
		(width 0.14224)
		(layer "In13.Cu")
		(net "P5E_CPU0_P3_RX_BUF_DP<5>")
	)
	(segment
		(start 379.345698 -409.048458)
		(end 379.151642 -409.048458)
		(width 0.14224)
		(layer "In13.Cu")
		(net "P5E_CPU0_P3_RX_BUF_DP<5>")
	)
	(segment
		(start 386.783072 -414.806892)
		(end 386.598668 -414.361884)
		(width 0.14224)
		(layer "In13.Cu")
		(net "P5E_CPU0_P3_RX_BUF_DP<5>")
	)
	(segment
		(start 376.457464 -403.168358)
		(end 376.457464 -401.511008)
		(width 0.14224)
		(layer "In13.Cu")
		(net "P5E_CPU0_P3_RX_BUF_DP<5>")
	)
	(segment
		(start 378.850144 -408.552904)
		(end 378.548138 -408.250898)
		(width 0.14224)
		(layer "In13.Cu")
		(net "P5E_CPU0_P3_RX_BUF_DP<5>")
	)
	(segment
		(start 376.594624 -404.507192)
		(end 376.457464 -404.370032)
		(width 0.14224)
		(layer "In13.Cu")
		(net "P5E_CPU0_P3_RX_BUF_DP<5>")
	)
	(segment
		(start 376.457464 -405.071072)
		(end 376.594624 -404.933912)
		(width 0.14224)
		(layer "In13.Cu")
		(net "P5E_CPU0_P3_RX_BUF_DP<5>")
	)
	(segment
		(start 376.457464 -404.370032)
		(end 376.457464 -403.869398)
		(width 0.14224)
		(layer "In13.Cu")
		(net "P5E_CPU0_P3_RX_BUF_DP<5>")
	)
	(segment
		(start 389.624824 -423.090848)
		(end 389.653272 -422.899078)
		(width 0.14224)
		(layer "In13.Cu")
		(net "P5E_CPU0_P3_RX_BUF_DP<5>")
	)
	(segment
		(start 390.070848 -423.461942)
		(end 389.879078 -423.433494)
		(width 0.14224)
		(layer "In13.Cu")
		(net "P5E_CPU0_P3_RX_BUF_DP<5>")
	)
	(segment
		(start 376.776996 -401.371562)
		(end 376.916442 -401.511008)
		(width 0.14224)
		(layer "In13.Cu")
		(net "P5E_CPU0_P3_RX_BUF_DP<5>")
	)
	(segment
		(start 390.843008 -424.7769)
		(end 390.551162 -424.339258)
		(width 0.14224)
		(layer "In13.Cu")
		(net "P5E_CPU0_P3_RX_BUF_DP<5>")
	)
	(segment
		(start 386.783072 -418.175186)
		(end 386.920232 -418.038026)
		(width 0.14224)
		(layer "In13.Cu")
		(net "P5E_CPU0_P3_RX_BUF_DP<5>")
	)
	(segment
		(start 386.783072 -417.474146)
		(end 386.783072 -417.047426)
		(width 0.14224)
		(layer "In13.Cu")
		(net "P5E_CPU0_P3_RX_BUF_DP<5>")
	)
	(segment
		(start 380.035308 -409.932124)
		(end 379.647704 -409.54452)
		(width 0.14224)
		(layer "In13.Cu")
		(net "P5E_CPU0_P3_RX_BUF_DP<5>")
	)
	(segment
		(start 376.59691 -401.371562)
		(end 376.776996 -401.371562)
		(width 0.14224)
		(layer "In13.Cu")
		(net "P5E_CPU0_P3_RX_BUF_DP<5>")
	)
	(segment
		(start 376.594624 -403.305518)
		(end 376.457464 -403.168358)
		(width 0.14224)
		(layer "In13.Cu")
		(net "P5E_CPU0_P3_RX_BUF_DP<5>")
	)
	(segment
		(start 385.251452 -413.49168)
		(end 385.251452 -412.180532)
		(width 0.14224)
		(layer "In13.Cu")
		(net "P5E_CPU0_P3_RX_BUF_DP<5>")
	)
	(segment
		(start 376.457464 -401.511008)
		(end 376.59691 -401.371562)
		(width 0.14224)
		(layer "In13.Cu")
		(net "P5E_CPU0_P3_RX_BUF_DP<5>")
	)
	(segment
		(start 389.653272 -422.899078)
		(end 389.398764 -422.556178)
		(width 0.14224)
		(layer "In13.Cu")
		(net "P5E_CPU0_P3_RX_BUF_DP<5>")
	)
	(segment
		(start 376.457464 -406.301448)
		(end 376.457464 -405.071072)
		(width 0.14224)
		(layer "In13.Cu")
		(net "P5E_CPU0_P3_RX_BUF_DP<5>")
	)
	(segment
		(start 385.377436 -413.795718)
		(end 385.251452 -413.49168)
		(width 0.14224)
		(layer "In13.Cu")
		(net "P5E_CPU0_P3_RX_BUF_DP<5>")
	)
	(segment
		(start 389.206994 -422.52773)
		(end 388.342632 -421.362632)
		(width 0.14224)
		(layer "In13.Cu")
		(net "P5E_CPU0_P3_RX_BUF_DP<5>")
	)
	(segment
		(start 379.151642 -409.048458)
		(end 378.850144 -408.74696)
		(width 0.14224)
		(layer "In13.Cu")
		(net "P5E_CPU0_P3_RX_BUF_DP<5>")
	)
	(segment
		(start 386.783072 -417.047426)
		(end 386.920232 -416.910266)
		(width 0.14224)
		(layer "In13.Cu")
		(net "P5E_CPU0_P3_RX_BUF_DP<5>")
	)
	(segment
		(start 376.953018 -406.655778)
		(end 376.758962 -406.655778)
		(width 0.14224)
		(layer "In13.Cu")
		(net "P5E_CPU0_P3_RX_BUF_DP<5>")
	)
	(segment
		(start 391.749788 -434.289962)
		(end 391.749788 -434.62194)
		(width 0.14224)
		(layer "In13.Cu")
		(net "P5E_CPU0_P3_RX_BUF_DP<5>")
	)
	(segment
		(start 384.562858 -411.488636)
		(end 380.6571 -410.304742)
		(width 0.14224)
		(layer "In13.Cu")
		(net "P5E_CPU0_P3_RX_BUF_DP<5>")
	)
	(segment
		(start 386.920232 -418.038026)
		(end 386.920232 -417.611306)
		(width 0.14224)
		(layer "In13.Cu")
		(net "P5E_CPU0_P3_RX_BUF_DP<5>")
	)
	(segment
		(start 379.647704 -409.54452)
		(end 379.647704 -409.350464)
		(width 0.14224)
		(layer "In13.Cu")
		(net "P5E_CPU0_P3_RX_BUF_DP<5>")
	)
	(segment
		(start 388.342632 -421.362632)
		(end 388.314692 -421.27805)
		(width 0.14224)
		(layer "In13.Cu")
		(net "P5E_CPU0_P3_RX_BUF_DP<5>")
	)
	(segment
		(start 386.88518 -419.0111)
		(end 386.783072 -418.764974)
		(width 0.14224)
		(layer "In13.Cu")
		(net "P5E_CPU0_P3_RX_BUF_DP<5>")
	)
	(segment
		(start 389.398764 -422.556178)
		(end 389.206994 -422.52773)
		(width 0.14224)
		(layer "In13.Cu")
		(net "P5E_CPU0_P3_RX_BUF_DP<5>")
	)
	(segment
		(start 378.052584 -407.755344)
		(end 377.750578 -407.453338)
		(width 0.14224)
		(layer "In13.Cu")
		(net "P5E_CPU0_P3_RX_BUF_DP<5>")
	)
	(segment
		(start 376.916442 -401.511008)
		(end 376.916442 -401.674838)
		(width 0.14224)
		(layer "In13.Cu")
		(net "P5E_CPU0_P3_RX_BUF_DP<5>")
	)
	(segment
		(start 376.594624 -404.933912)
		(end 376.594624 -404.507192)
		(width 0.14224)
		(layer "In13.Cu")
		(net "P5E_CPU0_P3_RX_BUF_DP<5>")
	)
	(segment
		(start 390.296908 -423.996612)
		(end 390.325356 -423.804842)
		(width 0.14224)
		(layer "In13.Cu")
		(net "P5E_CPU0_P3_RX_BUF_DP<5>")
	)
	(segment
		(start 386.264912 -414.028128)
		(end 386.0927 -413.956754)
		(width 0.14224)
		(layer "In13.Cu")
		(net "P5E_CPU0_P3_RX_BUF_DP<5>")
	)
	(segment
		(start 385.508754 -413.927036)
		(end 385.377436 -413.795718)
		(width 0.14224)
		(layer "In13.Cu")
		(net "P5E_CPU0_P3_RX_BUF_DP<5>")
	)
	(segment
		(start 376.594624 -403.732238)
		(end 376.594624 -403.305518)
		(width 0.14224)
		(layer "In13.Cu")
		(net "P5E_CPU0_P3_RX_BUF_DP<5>")
	)
	(segment
		(start 391.275316 -434.74894)
		(end 391.0584 -434.532024)
		(width 0.14224)
		(layer "In13.Cu")
		(net "P5E_CPU0_P3_RX_BUF_DP<5>")
	)
	(segment
		(start 386.598668 -414.361884)
		(end 386.264912 -414.028128)
		(width 0.14224)
		(layer "In13.Cu")
		(net "P5E_CPU0_P3_RX_BUF_DP<5>")
	)
	(segment
		(start 391.012426 -425.185586)
		(end 390.843008 -424.7769)
		(width 0.14224)
		(layer "In13.Cu")
		(net "P5E_CPU0_P3_RX_BUF_DP<5>")
	)
	(segment
		(start 391.622788 -434.74894)
		(end 391.275316 -434.74894)
		(width 0.14224)
		(layer "In13.Cu")
		(net "P5E_CPU0_P3_RX_BUF_DP<5>")
	)
	(segment
		(start 386.920232 -416.483546)
		(end 386.783072 -416.346386)
		(width 0.14224)
		(layer "In13.Cu")
		(net "P5E_CPU0_P3_RX_BUF_DP<5>")
	)
	(segment
		(start 386.783072 -418.764974)
		(end 386.783072 -418.175186)
		(width 0.14224)
		(layer "In13.Cu")
		(net "P5E_CPU0_P3_RX_BUF_DP<5>")
	)
	(segment
		(start 391.749788 -434.62194)
		(end 391.622788 -434.74894)
		(width 0.14224)
		(layer "In13.Cu")
		(net "P5E_CPU0_P3_RX_BUF_DP<5>")
	)
	(segment
		(start 390.551162 -424.339258)
		(end 390.296908 -423.996612)
		(width 0.14224)
		(layer "In13.Cu")
		(net "P5E_CPU0_P3_RX_BUF_DP<5>")
	)
	(segment
		(start 377.750578 -407.453338)
		(end 377.556522 -407.453338)
		(width 0.14224)
		(layer "In13.Cu")
		(net "P5E_CPU0_P3_RX_BUF_DP<5>")
	)
	(segment
		(start 386.920232 -416.910266)
		(end 386.920232 -416.483546)
		(width 0.14224)
		(layer "In13.Cu")
		(net "P5E_CPU0_P3_RX_BUF_DP<5>")
	)
	(segment
		(start 386.920232 -417.611306)
		(end 386.783072 -417.474146)
		(width 0.14224)
		(layer "In13.Cu")
		(net "P5E_CPU0_P3_RX_BUF_DP<5>")
	)
	(segment
		(start 378.850144 -408.74696)
		(end 378.850144 -408.552904)
		(width 0.14224)
		(layer "In13.Cu")
		(net "P5E_CPU0_P3_RX_BUF_DP<5>")
	)
	(segment
		(start 390.325356 -423.804842)
		(end 390.070848 -423.461942)
		(width 0.14224)
		(layer "In13.Cu")
		(net "P5E_CPU0_P3_RX_BUF_DP<5>")
	)
	(segment
		(start 386.783072 -416.346386)
		(end 386.783072 -414.806892)
		(width 0.14224)
		(layer "In13.Cu")
		(net "P5E_CPU0_P3_RX_BUF_DP<5>")
	)
	(segment
		(start 388.194804 -420.164006)
		(end 387.729222 -419.698424)
		(width 0.14224)
		(layer "In13.Cu")
		(net "P5E_CPU0_P3_RX_BUF_DP<5>")
	)
	(segment
		(start 378.052584 -407.9494)
		(end 378.052584 -407.755344)
		(width 0.14224)
		(layer "In13.Cu")
		(net "P5E_CPU0_P3_RX_BUF_DP<5>")
	)
	(segment
		(start 376.758962 -406.655778)
		(end 376.494802 -406.391618)
		(width 0.14224)
		(layer "In13.Cu")
		(net "P5E_CPU0_P3_RX_BUF_DP<5>")
	)
	(segment
		(start 385.013962 -411.760416)
		(end 384.562858 -411.488636)
		(width 0.14224)
		(layer "In13.Cu")
		(net "P5E_CPU0_P3_RX_BUF_DP<5>")
	)
	(segment
		(start 377.556522 -407.453338)
		(end 377.255024 -407.15184)
		(width 0.14224)
		(layer "In13.Cu")
		(net "P5E_CPU0_P3_RX_BUF_DP<5>")
	)
	(segment
		(start 388.314692 -421.27805)
		(end 388.314692 -420.453312)
		(width 0.14224)
		(layer "In13.Cu")
		(net "P5E_CPU0_P3_RX_BUF_DP<5>")
	)
	(segment
		(start 387.46176 -419.519862)
		(end 387.347206 -419.472618)
		(width 0.14224)
		(layer "In13.Cu")
		(net "P5E_CPU0_P3_RX_BUF_DP<5>")
	)
	(segment
		(start 378.354082 -408.250898)
		(end 378.052584 -407.9494)
		(width 0.14224)
		(layer "In13.Cu")
		(net "P5E_CPU0_P3_RX_BUF_DP<5>")
	)
	(segment
		(start 378.548138 -408.250898)
		(end 378.354082 -408.250898)
		(width 0.14224)
		(layer "In13.Cu")
		(net "P5E_CPU0_P3_RX_BUF_DP<5>")
	)
	(segment
		(start 379.647704 -409.350464)
		(end 379.345698 -409.048458)
		(width 0.14224)
		(layer "In13.Cu")
		(net "P5E_CPU0_P3_RX_BUF_DP<5>")
	)
	(segment
		(start 389.879078 -423.433494)
		(end 389.624824 -423.090848)
		(width 0.14224)
		(layer "In13.Cu")
		(net "P5E_CPU0_P3_RX_BUF_DP<5>")
	)
	(segment
		(start 377.255024 -407.15184)
		(end 377.255024 -406.957784)
		(width 0.14224)
		(layer "In13.Cu")
		(net "P5E_CPU0_P3_RX_BUF_DP<5>")
	)
	(segment
		(start 386.0927 -413.956754)
		(end 385.580382 -413.956754)
		(width 0.14224)
		(layer "In13.Cu")
		(net "P5E_CPU0_P3_RX_BUF_DP<5>")
	)
	(arc
		(start 380.6571 -410.304742)
		(mid 380.323212 -410.156798)
		(end 380.035308 -409.932124)
		(width 0.14224)
		(layer "In13.Cu")
		(net "P5E_CPU0_P3_RX_BUF_DP<5>")
	)
	(arc
		(start 387.729222 -419.698424)
		(mid 387.604312 -419.595931)
		(end 387.46176 -419.519862)
		(width 0.14224)
		(layer "In13.Cu")
		(net "P5E_CPU0_P3_RX_BUF_DP<5>")
	)
	(arc
		(start 391.0584 -425.416726)
		(mid 391.046799 -425.29889)
		(end 391.012426 -425.185586)
		(width 0.14224)
		(layer "In13.Cu")
		(net "P5E_CPU0_P3_RX_BUF_DP<5>")
	)
	(arc
		(start 387.347206 -419.472618)
		(mid 387.070355 -419.287756)
		(end 386.88518 -419.0111)
		(width 0.14224)
		(layer "In13.Cu")
		(net "P5E_CPU0_P3_RX_BUF_DP<5>")
	)
	(arc
		(start 388.314692 -420.453312)
		(mid 388.283529 -420.296734)
		(end 388.194804 -420.164006)
		(width 0.14224)
		(layer "In13.Cu")
		(net "P5E_CPU0_P3_RX_BUF_DP<5>")
	)
	(arc
		(start 385.251452 -412.180532)
		(mid 385.187928 -411.939243)
		(end 385.013962 -411.760416)
		(width 0.14224)
		(layer "In13.Cu")
		(net "P5E_CPU0_P3_RX_BUF_DP<5>")
	)
	(arc
		(start 376.494802 -406.391618)
		(mid 376.467159 -406.350248)
		(end 376.457464 -406.301448)
		(width 0.14224)
		(layer "In13.Cu")
		(net "P5E_CPU0_P3_RX_BUF_DP<5>")
	)
	(segment
		(start 375.102628 -399.870676)
		(end 375.013982 -399.959322)
		(width 0.1016)
		(layer "F.Cu")
		(net "P5E_CPU0_P3_RX_BUF_DP<4>")
	)
	(segment
		(start 375.013982 -401.105878)
		(end 375.26722 -401.359116)
		(width 0.1016)
		(layer "F.Cu")
		(net "P5E_CPU0_P3_RX_BUF_DP<4>")
	)
	(segment
		(start 375.716546 -401.4978)
		(end 375.716546 -401.674838)
		(width 0.1016)
		(layer "F.Cu")
		(net "P5E_CPU0_P3_RX_BUF_DP<4>")
	)
	(segment
		(start 375.013982 -399.959322)
		(end 375.013982 -401.105878)
		(width 0.1016)
		(layer "F.Cu")
		(net "P5E_CPU0_P3_RX_BUF_DP<4>")
	)
	(segment
		(start 375.018046 -399.663158)
		(end 375.102628 -399.74774)
		(width 0.1016)
		(layer "F.Cu")
		(net "P5E_CPU0_P3_RX_BUF_DP<4>")
	)
	(segment
		(start 375.26722 -401.359116)
		(end 375.577862 -401.359116)
		(width 0.1016)
		(layer "F.Cu")
		(net "P5E_CPU0_P3_RX_BUF_DP<4>")
	)
	(segment
		(start 375.102628 -399.74774)
		(end 375.102628 -399.870676)
		(width 0.1016)
		(layer "F.Cu")
		(net "P5E_CPU0_P3_RX_BUF_DP<4>")
	)
	(segment
		(start 375.577862 -401.359116)
		(end 375.716546 -401.4978)
		(width 0.1016)
		(layer "F.Cu")
		(net "P5E_CPU0_P3_RX_BUF_DP<4>")
	)
	(segment
		(start 376.055128 -407.581862)
		(end 376.356626 -407.88336)
		(width 0.14224)
		(layer "In13.Cu")
		(net "P5E_CPU0_P3_RX_BUF_DP<4>")
	)
	(segment
		(start 378.191268 -409.523946)
		(end 378.493274 -409.825952)
		(width 0.14224)
		(layer "In13.Cu")
		(net "P5E_CPU0_P3_RX_BUF_DP<4>")
	)
	(segment
		(start 385.685792 -422.197784)
		(end 386.349748 -422.640252)
		(width 0.14224)
		(layer "In13.Cu")
		(net "P5E_CPU0_P3_RX_BUF_DP<4>")
	)
	(segment
		(start 383.535428 -414.361884)
		(end 383.719832 -414.806892)
		(width 0.14224)
		(layer "In13.Cu")
		(net "P5E_CPU0_P3_RX_BUF_DP<4>")
	)
	(segment
		(start 383.719832 -418.62756)
		(end 383.909062 -419.083998)
		(width 0.14224)
		(layer "In13.Cu")
		(net "P5E_CPU0_P3_RX_BUF_DP<4>")
	)
	(segment
		(start 383.719832 -414.806892)
		(end 383.719832 -416.595814)
		(width 0.14224)
		(layer "In13.Cu")
		(net "P5E_CPU0_P3_RX_BUF_DP<4>")
	)
	(segment
		(start 376.852688 -408.185366)
		(end 376.852688 -408.379422)
		(width 0.14224)
		(layer "In13.Cu")
		(net "P5E_CPU0_P3_RX_BUF_DP<4>")
	)
	(segment
		(start 384.215386 -419.425628)
		(end 384.474212 -419.532816)
		(width 0.14224)
		(layer "In13.Cu")
		(net "P5E_CPU0_P3_RX_BUF_DP<4>")
	)
	(segment
		(start 386.891784 -422.839896)
		(end 386.929376 -423.026586)
		(width 0.14224)
		(layer "In13.Cu")
		(net "P5E_CPU0_P3_RX_BUF_DP<4>")
	)
	(segment
		(start 375.257568 -401.511008)
		(end 375.257568 -402.723604)
		(width 0.14224)
		(layer "In13.Cu")
		(net "P5E_CPU0_P3_RX_BUF_DP<4>")
	)
	(segment
		(start 387.960362 -423.550334)
		(end 387.998208 -423.74058)
		(width 0.14224)
		(layer "In13.Cu")
		(net "P5E_CPU0_P3_RX_BUF_DP<4>")
	)
	(segment
		(start 387.998208 -423.74058)
		(end 388.482586 -424.064176)
		(width 0.14224)
		(layer "In13.Cu")
		(net "P5E_CPU0_P3_RX_BUF_DP<4>")
	)
	(segment
		(start 386.349748 -422.640252)
		(end 386.536438 -422.602914)
		(width 0.14224)
		(layer "In13.Cu")
		(net "P5E_CPU0_P3_RX_BUF_DP<4>")
	)
	(segment
		(start 385.26974 -421.44696)
		(end 385.35229 -421.720264)
		(width 0.14224)
		(layer "In13.Cu")
		(net "P5E_CPU0_P3_RX_BUF_DP<4>")
	)
	(segment
		(start 386.536438 -422.602914)
		(end 386.891784 -422.839896)
		(width 0.14224)
		(layer "In13.Cu")
		(net "P5E_CPU0_P3_RX_BUF_DP<4>")
	)
	(segment
		(start 377.348242 -408.68092)
		(end 377.650248 -408.982926)
		(width 0.14224)
		(layer "In13.Cu")
		(net "P5E_CPU0_P3_RX_BUF_DP<4>")
	)
	(segment
		(start 389.058404 -425.049442)
		(end 389.058404 -433.606702)
		(width 0.14224)
		(layer "In13.Cu")
		(net "P5E_CPU0_P3_RX_BUF_DP<4>")
	)
	(segment
		(start 377.997212 -409.523946)
		(end 378.191268 -409.523946)
		(width 0.14224)
		(layer "In13.Cu")
		(net "P5E_CPU0_P3_RX_BUF_DP<4>")
	)
	(segment
		(start 378.988828 -410.321506)
		(end 379.290834 -410.623512)
		(width 0.14224)
		(layer "In13.Cu")
		(net "P5E_CPU0_P3_RX_BUF_DP<4>")
	)
	(segment
		(start 381.435864 -411.520132)
		(end 381.73914 -411.645862)
		(width 0.14224)
		(layer "In13.Cu")
		(net "P5E_CPU0_P3_RX_BUF_DP<4>")
	)
	(segment
		(start 375.257568 -404.552404)
		(end 375.257568 -404.979124)
		(width 0.14224)
		(layer "In13.Cu")
		(net "P5E_CPU0_P3_RX_BUF_DP<4>")
	)
	(segment
		(start 389.622792 -433.748942)
		(end 389.749792 -433.621942)
		(width 0.14224)
		(layer "In13.Cu")
		(net "P5E_CPU0_P3_RX_BUF_DP<4>")
	)
	(segment
		(start 376.550682 -407.88336)
		(end 376.852688 -408.185366)
		(width 0.14224)
		(layer "In13.Cu")
		(net "P5E_CPU0_P3_RX_BUF_DP<4>")
	)
	(segment
		(start 382.445514 -413.927036)
		(end 382.517142 -413.956754)
		(width 0.14224)
		(layer "In13.Cu")
		(net "P5E_CPU0_P3_RX_BUF_DP<4>")
	)
	(segment
		(start 377.650248 -409.176982)
		(end 377.997212 -409.523946)
		(width 0.14224)
		(layer "In13.Cu")
		(net "P5E_CPU0_P3_RX_BUF_DP<4>")
	)
	(segment
		(start 375.394728 -403.287484)
		(end 375.257568 -403.424644)
		(width 0.14224)
		(layer "In13.Cu")
		(net "P5E_CPU0_P3_RX_BUF_DP<4>")
	)
	(segment
		(start 375.559066 -407.0858)
		(end 375.753122 -407.0858)
		(width 0.14224)
		(layer "In13.Cu")
		(net "P5E_CPU0_P3_RX_BUF_DP<4>")
	)
	(segment
		(start 379.290834 -410.817568)
		(end 379.607572 -411.134306)
		(width 0.14224)
		(layer "In13.Cu")
		(net "P5E_CPU0_P3_RX_BUF_DP<4>")
	)
	(segment
		(start 383.719832 -416.595814)
		(end 383.856992 -416.732974)
		(width 0.14224)
		(layer "In13.Cu")
		(net "P5E_CPU0_P3_RX_BUF_DP<4>")
	)
	(segment
		(start 382.188212 -413.566864)
		(end 382.260856 -413.742378)
		(width 0.14224)
		(layer "In13.Cu")
		(net "P5E_CPU0_P3_RX_BUF_DP<4>")
	)
	(segment
		(start 375.716546 -401.511008)
		(end 375.5771 -401.371562)
		(width 0.14224)
		(layer "In13.Cu")
		(net "P5E_CPU0_P3_RX_BUF_DP<4>")
	)
	(segment
		(start 387.60527 -423.313098)
		(end 387.960362 -423.550334)
		(width 0.14224)
		(layer "In13.Cu")
		(net "P5E_CPU0_P3_RX_BUF_DP<4>")
	)
	(segment
		(start 389.200644 -433.748942)
		(end 389.622792 -433.748942)
		(width 0.14224)
		(layer "In13.Cu")
		(net "P5E_CPU0_P3_RX_BUF_DP<4>")
	)
	(segment
		(start 382.260856 -413.742378)
		(end 382.445514 -413.927036)
		(width 0.14224)
		(layer "In13.Cu")
		(net "P5E_CPU0_P3_RX_BUF_DP<4>")
	)
	(segment
		(start 375.394728 -404.415244)
		(end 375.257568 -404.552404)
		(width 0.14224)
		(layer "In13.Cu")
		(net "P5E_CPU0_P3_RX_BUF_DP<4>")
	)
	(segment
		(start 383.228596 -414.055052)
		(end 383.535428 -414.361884)
		(width 0.14224)
		(layer "In13.Cu")
		(net "P5E_CPU0_P3_RX_BUF_DP<4>")
	)
	(segment
		(start 382.517142 -413.956754)
		(end 382.99136 -413.956754)
		(width 0.14224)
		(layer "In13.Cu")
		(net "P5E_CPU0_P3_RX_BUF_DP<4>")
	)
	(segment
		(start 386.929376 -423.026586)
		(end 387.415024 -423.350944)
		(width 0.14224)
		(layer "In13.Cu")
		(net "P5E_CPU0_P3_RX_BUF_DP<4>")
	)
	(segment
		(start 378.794772 -410.321506)
		(end 378.988828 -410.321506)
		(width 0.14224)
		(layer "In13.Cu")
		(net "P5E_CPU0_P3_RX_BUF_DP<4>")
	)
	(segment
		(start 385.251452 -420.409116)
		(end 385.251452 -421.322246)
		(width 0.14224)
		(layer "In13.Cu")
		(net "P5E_CPU0_P3_RX_BUF_DP<4>")
	)
	(segment
		(start 376.356626 -407.88336)
		(end 376.550682 -407.88336)
		(width 0.14224)
		(layer "In13.Cu")
		(net "P5E_CPU0_P3_RX_BUF_DP<4>")
	)
	(segment
		(start 375.397014 -401.371562)
		(end 375.257568 -401.511008)
		(width 0.14224)
		(layer "In13.Cu")
		(net "P5E_CPU0_P3_RX_BUF_DP<4>")
	)
	(segment
		(start 378.493274 -409.825952)
		(end 378.493274 -410.020008)
		(width 0.14224)
		(layer "In13.Cu")
		(net "P5E_CPU0_P3_RX_BUF_DP<4>")
	)
	(segment
		(start 382.188212 -412.376874)
		(end 382.188212 -413.566864)
		(width 0.14224)
		(layer "In13.Cu")
		(net "P5E_CPU0_P3_RX_BUF_DP<4>")
	)
	(segment
		(start 377.154186 -408.68092)
		(end 377.348242 -408.68092)
		(width 0.14224)
		(layer "In13.Cu")
		(net "P5E_CPU0_P3_RX_BUF_DP<4>")
	)
	(segment
		(start 384.681984 -419.671246)
		(end 385.13131 -420.119556)
		(width 0.14224)
		(layer "In13.Cu")
		(net "P5E_CPU0_P3_RX_BUF_DP<4>")
	)
	(segment
		(start 389.749792 -433.621942)
		(end 389.749792 -433.289964)
		(width 0.14224)
		(layer "In13.Cu")
		(net "P5E_CPU0_P3_RX_BUF_DP<4>")
	)
	(segment
		(start 387.415024 -423.350944)
		(end 387.60527 -423.313098)
		(width 0.14224)
		(layer "In13.Cu")
		(net "P5E_CPU0_P3_RX_BUF_DP<4>")
	)
	(segment
		(start 378.493274 -410.020008)
		(end 378.794772 -410.321506)
		(width 0.14224)
		(layer "In13.Cu")
		(net "P5E_CPU0_P3_RX_BUF_DP<4>")
	)
	(segment
		(start 382.99136 -413.956754)
		(end 383.228596 -414.055052)
		(width 0.14224)
		(layer "In13.Cu")
		(net "P5E_CPU0_P3_RX_BUF_DP<4>")
	)
	(segment
		(start 388.482586 -424.064176)
		(end 388.724394 -424.305984)
		(width 0.14224)
		(layer "In13.Cu")
		(net "P5E_CPU0_P3_RX_BUF_DP<4>")
	)
	(segment
		(start 375.753122 -407.0858)
		(end 376.055128 -407.387806)
		(width 0.14224)
		(layer "In13.Cu")
		(net "P5E_CPU0_P3_RX_BUF_DP<4>")
	)
	(segment
		(start 375.716546 -401.674838)
		(end 375.716546 -401.511008)
		(width 0.14224)
		(layer "In13.Cu")
		(net "P5E_CPU0_P3_RX_BUF_DP<4>")
	)
	(segment
		(start 375.257568 -405.680164)
		(end 375.257568 -406.714198)
		(width 0.14224)
		(layer "In13.Cu")
		(net "P5E_CPU0_P3_RX_BUF_DP<4>")
	)
	(segment
		(start 381.73914 -411.645862)
		(end 381.988822 -411.895544)
		(width 0.14224)
		(layer "In13.Cu")
		(net "P5E_CPU0_P3_RX_BUF_DP<4>")
	)
	(segment
		(start 375.394728 -405.543004)
		(end 375.257568 -405.680164)
		(width 0.14224)
		(layer "In13.Cu")
		(net "P5E_CPU0_P3_RX_BUF_DP<4>")
	)
	(segment
		(start 375.257568 -404.979124)
		(end 375.394728 -405.116284)
		(width 0.14224)
		(layer "In13.Cu")
		(net "P5E_CPU0_P3_RX_BUF_DP<4>")
	)
	(segment
		(start 383.856992 -417.159694)
		(end 383.719832 -417.296854)
		(width 0.14224)
		(layer "In13.Cu")
		(net "P5E_CPU0_P3_RX_BUF_DP<4>")
	)
	(segment
		(start 375.5771 -401.371562)
		(end 375.397014 -401.371562)
		(width 0.14224)
		(layer "In13.Cu")
		(net "P5E_CPU0_P3_RX_BUF_DP<4>")
	)
	(segment
		(start 383.719832 -417.296854)
		(end 383.719832 -418.62756)
		(width 0.14224)
		(layer "In13.Cu")
		(net "P5E_CPU0_P3_RX_BUF_DP<4>")
	)
	(segment
		(start 376.055128 -407.387806)
		(end 376.055128 -407.581862)
		(width 0.14224)
		(layer "In13.Cu")
		(net "P5E_CPU0_P3_RX_BUF_DP<4>")
	)
	(segment
		(start 375.257568 -403.851364)
		(end 375.394728 -403.988524)
		(width 0.14224)
		(layer "In13.Cu")
		(net "P5E_CPU0_P3_RX_BUF_DP<4>")
	)
	(segment
		(start 375.394728 -405.116284)
		(end 375.394728 -405.543004)
		(width 0.14224)
		(layer "In13.Cu")
		(net "P5E_CPU0_P3_RX_BUF_DP<4>")
	)
	(segment
		(start 377.650248 -408.982926)
		(end 377.650248 -409.176982)
		(width 0.14224)
		(layer "In13.Cu")
		(net "P5E_CPU0_P3_RX_BUF_DP<4>")
	)
	(segment
		(start 379.290834 -410.623512)
		(end 379.290834 -410.817568)
		(width 0.14224)
		(layer "In13.Cu")
		(net "P5E_CPU0_P3_RX_BUF_DP<4>")
	)
	(segment
		(start 383.856992 -416.732974)
		(end 383.856992 -417.159694)
		(width 0.14224)
		(layer "In13.Cu")
		(net "P5E_CPU0_P3_RX_BUF_DP<4>")
	)
	(segment
		(start 375.257568 -402.723604)
		(end 375.394728 -402.860764)
		(width 0.14224)
		(layer "In13.Cu")
		(net "P5E_CPU0_P3_RX_BUF_DP<4>")
	)
	(segment
		(start 389.058404 -433.606702)
		(end 389.200644 -433.748942)
		(width 0.14224)
		(layer "In13.Cu")
		(net "P5E_CPU0_P3_RX_BUF_DP<4>")
	)
	(segment
		(start 375.394728 -402.860764)
		(end 375.394728 -403.287484)
		(width 0.14224)
		(layer "In13.Cu")
		(net "P5E_CPU0_P3_RX_BUF_DP<4>")
	)
	(segment
		(start 375.257568 -403.424644)
		(end 375.257568 -403.851364)
		(width 0.14224)
		(layer "In13.Cu")
		(net "P5E_CPU0_P3_RX_BUF_DP<4>")
	)
	(segment
		(start 375.307098 -406.833832)
		(end 375.559066 -407.0858)
		(width 0.14224)
		(layer "In13.Cu")
		(net "P5E_CPU0_P3_RX_BUF_DP<4>")
	)
	(segment
		(start 376.852688 -408.379422)
		(end 377.154186 -408.68092)
		(width 0.14224)
		(layer "In13.Cu")
		(net "P5E_CPU0_P3_RX_BUF_DP<4>")
	)
	(segment
		(start 375.394728 -403.988524)
		(end 375.394728 -404.415244)
		(width 0.14224)
		(layer "In13.Cu")
		(net "P5E_CPU0_P3_RX_BUF_DP<4>")
	)
	(segment
		(start 379.672596 -411.169104)
		(end 381.435864 -411.520132)
		(width 0.14224)
		(layer "In13.Cu")
		(net "P5E_CPU0_P3_RX_BUF_DP<4>")
	)
	(arc
		(start 375.257568 -406.714198)
		(mid 375.270445 -406.778934)
		(end 375.307098 -406.833832)
		(width 0.14224)
		(layer "In13.Cu")
		(net "P5E_CPU0_P3_RX_BUF_DP<4>")
	)
	(arc
		(start 381.988822 -411.895544)
		(mid 382.13638 -412.11638)
		(end 382.188212 -412.376874)
		(width 0.14224)
		(layer "In13.Cu")
		(net "P5E_CPU0_P3_RX_BUF_DP<4>")
	)
	(arc
		(start 383.909062 -419.083998)
		(mid 383.992247 -419.233081)
		(end 384.107436 -419.35908)
		(width 0.14224)
		(layer "In13.Cu")
		(net "P5E_CPU0_P3_RX_BUF_DP<4>")
	)
	(arc
		(start 388.724394 -424.305984)
		(mid 388.91722 -424.559614)
		(end 389.035036 -424.85564)
		(width 0.14224)
		(layer "In13.Cu")
		(net "P5E_CPU0_P3_RX_BUF_DP<4>")
	)
	(arc
		(start 379.607572 -411.134306)
		(mid 379.637508 -411.156516)
		(end 379.672596 -411.169104)
		(width 0.14224)
		(layer "In13.Cu")
		(net "P5E_CPU0_P3_RX_BUF_DP<4>")
	)
	(arc
		(start 385.251452 -421.322246)
		(mid 385.256033 -421.385272)
		(end 385.26974 -421.44696)
		(width 0.14224)
		(layer "In13.Cu")
		(net "P5E_CPU0_P3_RX_BUF_DP<4>")
	)
	(arc
		(start 389.035036 -424.85564)
		(mid 389.052615 -424.95183)
		(end 389.058404 -425.049442)
		(width 0.14224)
		(layer "In13.Cu")
		(net "P5E_CPU0_P3_RX_BUF_DP<4>")
	)
	(arc
		(start 385.13131 -420.119556)
		(mid 385.22024 -420.252364)
		(end 385.251452 -420.409116)
		(width 0.14224)
		(layer "In13.Cu")
		(net "P5E_CPU0_P3_RX_BUF_DP<4>")
	)
	(arc
		(start 384.474212 -419.532816)
		(mid 384.584884 -419.591842)
		(end 384.681984 -419.671246)
		(width 0.14224)
		(layer "In13.Cu")
		(net "P5E_CPU0_P3_RX_BUF_DP<4>")
	)
	(arc
		(start 384.107436 -419.35908)
		(mid 384.158727 -419.396706)
		(end 384.215386 -419.425628)
		(width 0.14224)
		(layer "In13.Cu")
		(net "P5E_CPU0_P3_RX_BUF_DP<4>")
	)
	(arc
		(start 385.35229 -421.720264)
		(mid 385.481049 -421.985553)
		(end 385.685792 -422.197784)
		(width 0.14224)
		(layer "In13.Cu")
		(net "P5E_CPU0_P3_RX_BUF_DP<4>")
	)
	(segment
		(start 374.516396 -401.4978)
		(end 374.516396 -401.674838)
		(width 0.1016)
		(layer "F.Cu")
		(net "P5E_CPU0_P3_RX_BUF_DP<3>")
	)
	(segment
		(start 373.82704 -399.946114)
		(end 373.82704 -401.105878)
		(width 0.1016)
		(layer "F.Cu")
		(net "P5E_CPU0_P3_RX_BUF_DP<3>")
	)
	(segment
		(start 373.902478 -399.74774)
		(end 373.902478 -399.870676)
		(width 0.1016)
		(layer "F.Cu")
		(net "P5E_CPU0_P3_RX_BUF_DP<3>")
	)
	(segment
		(start 373.82704 -401.105878)
		(end 374.080278 -401.359116)
		(width 0.1016)
		(layer "F.Cu")
		(net "P5E_CPU0_P3_RX_BUF_DP<3>")
	)
	(segment
		(start 373.902478 -399.870676)
		(end 373.82704 -399.946114)
		(width 0.1016)
		(layer "F.Cu")
		(net "P5E_CPU0_P3_RX_BUF_DP<3>")
	)
	(segment
		(start 373.817896 -399.663158)
		(end 373.902478 -399.74774)
		(width 0.1016)
		(layer "F.Cu")
		(net "P5E_CPU0_P3_RX_BUF_DP<3>")
	)
	(segment
		(start 374.080278 -401.359116)
		(end 374.377712 -401.359116)
		(width 0.1016)
		(layer "F.Cu")
		(net "P5E_CPU0_P3_RX_BUF_DP<3>")
	)
	(segment
		(start 374.377712 -401.359116)
		(end 374.516396 -401.4978)
		(width 0.1016)
		(layer "F.Cu")
		(net "P5E_CPU0_P3_RX_BUF_DP<3>")
	)
	(segment
		(start 382.188212 -421.24376)
		(end 382.188212 -420.413942)
		(width 0.14224)
		(layer "In13.Cu")
		(net "P5E_CPU0_P3_RX_BUF_DP<3>")
	)
	(segment
		(start 374.057418 -401.511008)
		(end 374.196864 -401.371562)
		(width 0.14224)
		(layer "In13.Cu")
		(net "P5E_CPU0_P3_RX_BUF_DP<3>")
	)
	(segment
		(start 374.516396 -401.511008)
		(end 374.516396 -401.674838)
		(width 0.14224)
		(layer "In13.Cu")
		(net "P5E_CPU0_P3_RX_BUF_DP<3>")
	)
	(segment
		(start 387.058408 -434.532024)
		(end 387.058408 -425.29125)
		(width 0.14224)
		(layer "In13.Cu")
		(net "P5E_CPU0_P3_RX_BUF_DP<3>")
	)
	(segment
		(start 377.247658 -410.109924)
		(end 376.945652 -409.807918)
		(width 0.14224)
		(layer "In13.Cu")
		(net "P5E_CPU0_P3_RX_BUF_DP<3>")
	)
	(segment
		(start 380.656592 -417.909502)
		(end 380.793752 -417.772342)
		(width 0.14224)
		(layer "In13.Cu")
		(net "P5E_CPU0_P3_RX_BUF_DP<3>")
	)
	(segment
		(start 387.012434 -425.06011)
		(end 386.910326 -424.814492)
		(width 0.14224)
		(layer "In13.Cu")
		(net "P5E_CPU0_P3_RX_BUF_DP<3>")
	)
	(segment
		(start 380.656592 -417.208462)
		(end 380.656592 -416.781742)
		(width 0.14224)
		(layer "In13.Cu")
		(net "P5E_CPU0_P3_RX_BUF_DP<3>")
	)
	(segment
		(start 380.793752 -417.772342)
		(end 380.793752 -417.345622)
		(width 0.14224)
		(layer "In13.Cu")
		(net "P5E_CPU0_P3_RX_BUF_DP<3>")
	)
	(segment
		(start 387.622796 -434.74894)
		(end 387.275324 -434.74894)
		(width 0.14224)
		(layer "In13.Cu")
		(net "P5E_CPU0_P3_RX_BUF_DP<3>")
	)
	(segment
		(start 380.72695 -418.91458)
		(end 380.656592 -418.744908)
		(width 0.14224)
		(layer "In13.Cu")
		(net "P5E_CPU0_P3_RX_BUF_DP<3>")
	)
	(segment
		(start 376.450098 -409.50642)
		(end 376.450098 -409.312364)
		(width 0.14224)
		(layer "In13.Cu")
		(net "P5E_CPU0_P3_RX_BUF_DP<3>")
	)
	(segment
		(start 375.954036 -409.010358)
		(end 375.652538 -408.70886)
		(width 0.14224)
		(layer "In13.Cu")
		(net "P5E_CPU0_P3_RX_BUF_DP<3>")
	)
	(segment
		(start 380.656592 -418.744908)
		(end 380.656592 -417.909502)
		(width 0.14224)
		(layer "In13.Cu")
		(net "P5E_CPU0_P3_RX_BUF_DP<3>")
	)
	(segment
		(start 374.057418 -403.455886)
		(end 374.194578 -403.318726)
		(width 0.14224)
		(layer "In13.Cu")
		(net "P5E_CPU0_P3_RX_BUF_DP<3>")
	)
	(segment
		(start 374.552972 -407.415238)
		(end 374.358916 -407.415238)
		(width 0.14224)
		(layer "In13.Cu")
		(net "P5E_CPU0_P3_RX_BUF_DP<3>")
	)
	(segment
		(start 374.057418 -407.060908)
		(end 374.057418 -405.711406)
		(width 0.14224)
		(layer "In13.Cu")
		(net "P5E_CPU0_P3_RX_BUF_DP<3>")
	)
	(segment
		(start 386.910326 -424.814492)
		(end 386.799582 -424.630088)
		(width 0.14224)
		(layer "In13.Cu")
		(net "P5E_CPU0_P3_RX_BUF_DP<3>")
	)
	(segment
		(start 382.068324 -420.124636)
		(end 381.554736 -419.610794)
		(width 0.14224)
		(layer "In13.Cu")
		(net "P5E_CPU0_P3_RX_BUF_DP<3>")
	)
	(segment
		(start 374.057418 -404.583646)
		(end 374.194578 -404.446486)
		(width 0.14224)
		(layer "In13.Cu")
		(net "P5E_CPU0_P3_RX_BUF_DP<3>")
	)
	(segment
		(start 386.799582 -424.630088)
		(end 386.340858 -424.070526)
		(width 0.14224)
		(layer "In13.Cu")
		(net "P5E_CPU0_P3_RX_BUF_DP<3>")
	)
	(segment
		(start 385.040632 -423.300906)
		(end 384.984244 -423.115232)
		(width 0.14224)
		(layer "In13.Cu")
		(net "P5E_CPU0_P3_RX_BUF_DP<3>")
	)
	(segment
		(start 380.793752 -416.644582)
		(end 380.793752 -416.217862)
		(width 0.14224)
		(layer "In13.Cu")
		(net "P5E_CPU0_P3_RX_BUF_DP<3>")
	)
	(segment
		(start 374.057418 -405.711406)
		(end 374.194578 -405.574246)
		(width 0.14224)
		(layer "In13.Cu")
		(net "P5E_CPU0_P3_RX_BUF_DP<3>")
	)
	(segment
		(start 384.984244 -423.115232)
		(end 384.607562 -422.914064)
		(width 0.14224)
		(layer "In13.Cu")
		(net "P5E_CPU0_P3_RX_BUF_DP<3>")
	)
	(segment
		(start 384.607562 -422.914064)
		(end 384.421888 -422.970198)
		(width 0.14224)
		(layer "In13.Cu")
		(net "P5E_CPU0_P3_RX_BUF_DP<3>")
	)
	(segment
		(start 374.057418 -402.754846)
		(end 374.057418 -401.511008)
		(width 0.14224)
		(layer "In13.Cu")
		(net "P5E_CPU0_P3_RX_BUF_DP<3>")
	)
	(segment
		(start 374.194578 -402.892006)
		(end 374.057418 -402.754846)
		(width 0.14224)
		(layer "In13.Cu")
		(net "P5E_CPU0_P3_RX_BUF_DP<3>")
	)
	(segment
		(start 380.793752 -416.217862)
		(end 380.656592 -416.080702)
		(width 0.14224)
		(layer "In13.Cu")
		(net "P5E_CPU0_P3_RX_BUF_DP<3>")
	)
	(segment
		(start 375.652538 -408.514804)
		(end 375.350532 -408.212798)
		(width 0.14224)
		(layer "In13.Cu")
		(net "P5E_CPU0_P3_RX_BUF_DP<3>")
	)
	(segment
		(start 374.194578 -405.574246)
		(end 374.194578 -405.147526)
		(width 0.14224)
		(layer "In13.Cu")
		(net "P5E_CPU0_P3_RX_BUF_DP<3>")
	)
	(segment
		(start 380.656592 -414.806892)
		(end 380.472188 -414.361884)
		(width 0.14224)
		(layer "In13.Cu")
		(net "P5E_CPU0_P3_RX_BUF_DP<3>")
	)
	(segment
		(start 376.148092 -409.010358)
		(end 375.954036 -409.010358)
		(width 0.14224)
		(layer "In13.Cu")
		(net "P5E_CPU0_P3_RX_BUF_DP<3>")
	)
	(segment
		(start 379.382274 -413.927036)
		(end 379.197616 -413.742378)
		(width 0.14224)
		(layer "In13.Cu")
		(net "P5E_CPU0_P3_RX_BUF_DP<3>")
	)
	(segment
		(start 374.37695 -401.371562)
		(end 374.516396 -401.511008)
		(width 0.14224)
		(layer "In13.Cu")
		(net "P5E_CPU0_P3_RX_BUF_DP<3>")
	)
	(segment
		(start 376.450098 -409.312364)
		(end 376.148092 -409.010358)
		(width 0.14224)
		(layer "In13.Cu")
		(net "P5E_CPU0_P3_RX_BUF_DP<3>")
	)
	(segment
		(start 379.96622 -413.956754)
		(end 379.453902 -413.956754)
		(width 0.14224)
		(layer "In13.Cu")
		(net "P5E_CPU0_P3_RX_BUF_DP<3>")
	)
	(segment
		(start 380.656592 -416.781742)
		(end 380.793752 -416.644582)
		(width 0.14224)
		(layer "In13.Cu")
		(net "P5E_CPU0_P3_RX_BUF_DP<3>")
	)
	(segment
		(start 378.946156 -412.002478)
		(end 377.247658 -410.30398)
		(width 0.14224)
		(layer "In13.Cu")
		(net "P5E_CPU0_P3_RX_BUF_DP<3>")
	)
	(segment
		(start 384.421888 -422.970198)
		(end 383.214626 -422.325038)
		(width 0.14224)
		(layer "In13.Cu")
		(net "P5E_CPU0_P3_RX_BUF_DP<3>")
	)
	(segment
		(start 375.156476 -408.212798)
		(end 374.854978 -407.9113)
		(width 0.14224)
		(layer "In13.Cu")
		(net "P5E_CPU0_P3_RX_BUF_DP<3>")
	)
	(segment
		(start 386.340858 -424.070526)
		(end 385.782312 -423.6974)
		(width 0.14224)
		(layer "In13.Cu")
		(net "P5E_CPU0_P3_RX_BUF_DP<3>")
	)
	(segment
		(start 377.247658 -410.30398)
		(end 377.247658 -410.109924)
		(width 0.14224)
		(layer "In13.Cu")
		(net "P5E_CPU0_P3_RX_BUF_DP<3>")
	)
	(segment
		(start 374.854978 -407.717244)
		(end 374.552972 -407.415238)
		(width 0.14224)
		(layer "In13.Cu")
		(net "P5E_CPU0_P3_RX_BUF_DP<3>")
	)
	(segment
		(start 382.62941 -421.934132)
		(end 382.364488 -421.66921)
		(width 0.14224)
		(layer "In13.Cu")
		(net "P5E_CPU0_P3_RX_BUF_DP<3>")
	)
	(segment
		(start 387.749796 -434.62194)
		(end 387.622796 -434.74894)
		(width 0.14224)
		(layer "In13.Cu")
		(net "P5E_CPU0_P3_RX_BUF_DP<3>")
	)
	(segment
		(start 381.554736 -419.610794)
		(end 381.330454 -419.518338)
		(width 0.14224)
		(layer "In13.Cu")
		(net "P5E_CPU0_P3_RX_BUF_DP<3>")
	)
	(segment
		(start 374.194578 -404.446486)
		(end 374.194578 -404.019766)
		(width 0.14224)
		(layer "In13.Cu")
		(net "P5E_CPU0_P3_RX_BUF_DP<3>")
	)
	(segment
		(start 376.751596 -409.807918)
		(end 376.450098 -409.50642)
		(width 0.14224)
		(layer "In13.Cu")
		(net "P5E_CPU0_P3_RX_BUF_DP<3>")
	)
	(segment
		(start 374.194578 -403.318726)
		(end 374.194578 -402.892006)
		(width 0.14224)
		(layer "In13.Cu")
		(net "P5E_CPU0_P3_RX_BUF_DP<3>")
	)
	(segment
		(start 380.138432 -414.028128)
		(end 379.96622 -413.956754)
		(width 0.14224)
		(layer "In13.Cu")
		(net "P5E_CPU0_P3_RX_BUF_DP<3>")
	)
	(segment
		(start 374.057418 -403.882606)
		(end 374.057418 -403.455886)
		(width 0.14224)
		(layer "In13.Cu")
		(net "P5E_CPU0_P3_RX_BUF_DP<3>")
	)
	(segment
		(start 374.854978 -407.9113)
		(end 374.854978 -407.717244)
		(width 0.14224)
		(layer "In13.Cu")
		(net "P5E_CPU0_P3_RX_BUF_DP<3>")
	)
	(segment
		(start 380.656592 -416.080702)
		(end 380.656592 -414.806892)
		(width 0.14224)
		(layer "In13.Cu")
		(net "P5E_CPU0_P3_RX_BUF_DP<3>")
	)
	(segment
		(start 379.124972 -413.567118)
		(end 379.124972 -412.434024)
		(width 0.14224)
		(layer "In13.Cu")
		(net "P5E_CPU0_P3_RX_BUF_DP<3>")
	)
	(segment
		(start 387.749796 -434.289962)
		(end 387.749796 -434.62194)
		(width 0.14224)
		(layer "In13.Cu")
		(net "P5E_CPU0_P3_RX_BUF_DP<3>")
	)
	(segment
		(start 374.057418 -405.010366)
		(end 374.057418 -404.583646)
		(width 0.14224)
		(layer "In13.Cu")
		(net "P5E_CPU0_P3_RX_BUF_DP<3>")
	)
	(segment
		(start 387.275324 -434.74894)
		(end 387.058408 -434.532024)
		(width 0.14224)
		(layer "In13.Cu")
		(net "P5E_CPU0_P3_RX_BUF_DP<3>")
	)
	(segment
		(start 374.194578 -404.019766)
		(end 374.057418 -403.882606)
		(width 0.14224)
		(layer "In13.Cu")
		(net "P5E_CPU0_P3_RX_BUF_DP<3>")
	)
	(segment
		(start 375.652538 -408.70886)
		(end 375.652538 -408.514804)
		(width 0.14224)
		(layer "In13.Cu")
		(net "P5E_CPU0_P3_RX_BUF_DP<3>")
	)
	(segment
		(start 380.472188 -414.361884)
		(end 380.138432 -414.028128)
		(width 0.14224)
		(layer "In13.Cu")
		(net "P5E_CPU0_P3_RX_BUF_DP<3>")
	)
	(segment
		(start 374.358916 -407.415238)
		(end 374.094756 -407.151078)
		(width 0.14224)
		(layer "In13.Cu")
		(net "P5E_CPU0_P3_RX_BUF_DP<3>")
	)
	(segment
		(start 385.782312 -423.6974)
		(end 385.040632 -423.300906)
		(width 0.14224)
		(layer "In13.Cu")
		(net "P5E_CPU0_P3_RX_BUF_DP<3>")
	)
	(segment
		(start 374.196864 -401.371562)
		(end 374.37695 -401.371562)
		(width 0.14224)
		(layer "In13.Cu")
		(net "P5E_CPU0_P3_RX_BUF_DP<3>")
	)
	(segment
		(start 380.793752 -417.345622)
		(end 380.656592 -417.208462)
		(width 0.14224)
		(layer "In13.Cu")
		(net "P5E_CPU0_P3_RX_BUF_DP<3>")
	)
	(segment
		(start 379.453902 -413.956754)
		(end 379.382274 -413.927036)
		(width 0.14224)
		(layer "In13.Cu")
		(net "P5E_CPU0_P3_RX_BUF_DP<3>")
	)
	(segment
		(start 375.350532 -408.212798)
		(end 375.156476 -408.212798)
		(width 0.14224)
		(layer "In13.Cu")
		(net "P5E_CPU0_P3_RX_BUF_DP<3>")
	)
	(segment
		(start 383.214626 -422.325038)
		(end 382.62941 -421.934132)
		(width 0.14224)
		(layer "In13.Cu")
		(net "P5E_CPU0_P3_RX_BUF_DP<3>")
	)
	(segment
		(start 376.945652 -409.807918)
		(end 376.751596 -409.807918)
		(width 0.14224)
		(layer "In13.Cu")
		(net "P5E_CPU0_P3_RX_BUF_DP<3>")
	)
	(segment
		(start 374.194578 -405.147526)
		(end 374.057418 -405.010366)
		(width 0.14224)
		(layer "In13.Cu")
		(net "P5E_CPU0_P3_RX_BUF_DP<3>")
	)
	(segment
		(start 379.197616 -413.742378)
		(end 379.124972 -413.567118)
		(width 0.14224)
		(layer "In13.Cu")
		(net "P5E_CPU0_P3_RX_BUF_DP<3>")
	)
	(arc
		(start 374.094756 -407.151078)
		(mid 374.067113 -407.109708)
		(end 374.057418 -407.060908)
		(width 0.14224)
		(layer "In13.Cu")
		(net "P5E_CPU0_P3_RX_BUF_DP<3>")
	)
	(arc
		(start 387.058408 -425.29125)
		(mid 387.046807 -425.173414)
		(end 387.012434 -425.06011)
		(width 0.14224)
		(layer "In13.Cu")
		(net "P5E_CPU0_P3_RX_BUF_DP<3>")
	)
	(arc
		(start 381.330454 -419.518338)
		(mid 380.968702 -419.27644)
		(end 380.72695 -418.91458)
		(width 0.14224)
		(layer "In13.Cu")
		(net "P5E_CPU0_P3_RX_BUF_DP<3>")
	)
	(arc
		(start 382.364488 -421.66921)
		(mid 382.234007 -421.474026)
		(end 382.188212 -421.24376)
		(width 0.14224)
		(layer "In13.Cu")
		(net "P5E_CPU0_P3_RX_BUF_DP<3>")
	)
	(arc
		(start 382.188212 -420.413942)
		(mid 382.157049 -420.257364)
		(end 382.068324 -420.124636)
		(width 0.14224)
		(layer "In13.Cu")
		(net "P5E_CPU0_P3_RX_BUF_DP<3>")
	)
	(arc
		(start 379.124972 -412.434024)
		(mid 379.078496 -412.200463)
		(end 378.946156 -412.002478)
		(width 0.14224)
		(layer "In13.Cu")
		(net "P5E_CPU0_P3_RX_BUF_DP<3>")
	)
	(segment
		(start 372.613936 -401.105878)
		(end 372.867174 -401.359116)
		(width 0.1016)
		(layer "F.Cu")
		(net "P5E_CPU0_P3_RX_BUF_DP<2>")
	)
	(segment
		(start 372.613936 -399.959322)
		(end 372.613936 -401.105878)
		(width 0.1016)
		(layer "F.Cu")
		(net "P5E_CPU0_P3_RX_BUF_DP<2>")
	)
	(segment
		(start 373.3165 -401.4978)
		(end 373.3165 -401.674838)
		(width 0.1016)
		(layer "F.Cu")
		(net "P5E_CPU0_P3_RX_BUF_DP<2>")
	)
	(segment
		(start 372.618 -399.663158)
		(end 372.702582 -399.74774)
		(width 0.1016)
		(layer "F.Cu")
		(net "P5E_CPU0_P3_RX_BUF_DP<2>")
	)
	(segment
		(start 373.177816 -401.359116)
		(end 373.3165 -401.4978)
		(width 0.1016)
		(layer "F.Cu")
		(net "P5E_CPU0_P3_RX_BUF_DP<2>")
	)
	(segment
		(start 372.867174 -401.359116)
		(end 373.177816 -401.359116)
		(width 0.1016)
		(layer "F.Cu")
		(net "P5E_CPU0_P3_RX_BUF_DP<2>")
	)
	(segment
		(start 372.702582 -399.74774)
		(end 372.702582 -399.870676)
		(width 0.1016)
		(layer "F.Cu")
		(net "P5E_CPU0_P3_RX_BUF_DP<2>")
	)
	(segment
		(start 372.702582 -399.870676)
		(end 372.613936 -399.959322)
		(width 0.1016)
		(layer "F.Cu")
		(net "P5E_CPU0_P3_RX_BUF_DP<2>")
	)
	(segment
		(start 372.996968 -401.371562)
		(end 372.857522 -401.511008)
		(width 0.14224)
		(layer "In13.Cu")
		(net "P5E_CPU0_P3_RX_BUF_DP<2>")
	)
	(segment
		(start 374.33123 -409.549092)
		(end 374.31218 -409.742132)
		(width 0.14224)
		(layer "In13.Cu")
		(net "P5E_CPU0_P3_RX_BUF_DP<2>")
	)
	(segment
		(start 374.841008 -410.386276)
		(end 375.034048 -410.405326)
		(width 0.14224)
		(layer "In13.Cu")
		(net "P5E_CPU0_P3_RX_BUF_DP<2>")
	)
	(segment
		(start 377.593352 -418.729922)
		(end 377.751594 -419.111684)
		(width 0.14224)
		(layer "In13.Cu")
		(net "P5E_CPU0_P3_RX_BUF_DP<2>")
	)
	(segment
		(start 373.151908 -408.328114)
		(end 373.344948 -408.347164)
		(width 0.14224)
		(layer "In13.Cu")
		(net "P5E_CPU0_P3_RX_BUF_DP<2>")
	)
	(segment
		(start 373.596662 -408.87015)
		(end 373.867172 -409.199842)
		(width 0.14224)
		(layer "In13.Cu")
		(net "P5E_CPU0_P3_RX_BUF_DP<2>")
	)
	(segment
		(start 373.344948 -408.347164)
		(end 373.615712 -408.67711)
		(width 0.14224)
		(layer "In13.Cu")
		(net "P5E_CPU0_P3_RX_BUF_DP<2>")
	)
	(segment
		(start 377.730512 -416.703002)
		(end 377.593352 -416.840162)
		(width 0.14224)
		(layer "In13.Cu")
		(net "P5E_CPU0_P3_RX_BUF_DP<2>")
	)
	(segment
		(start 385.7498 -433.621942)
		(end 385.7498 -433.289964)
		(width 0.14224)
		(layer "In13.Cu")
		(net "P5E_CPU0_P3_RX_BUF_DP<2>")
	)
	(segment
		(start 372.994682 -404.19147)
		(end 372.994682 -404.61819)
		(width 0.14224)
		(layer "In13.Cu")
		(net "P5E_CPU0_P3_RX_BUF_DP<2>")
	)
	(segment
		(start 377.593352 -417.967922)
		(end 377.593352 -418.729922)
		(width 0.14224)
		(layer "In13.Cu")
		(net "P5E_CPU0_P3_RX_BUF_DP<2>")
	)
	(segment
		(start 372.857522 -402.92655)
		(end 372.994682 -403.06371)
		(width 0.14224)
		(layer "In13.Cu")
		(net "P5E_CPU0_P3_RX_BUF_DP<2>")
	)
	(segment
		(start 379.124972 -421.161972)
		(end 379.29693 -421.576754)
		(width 0.14224)
		(layer "In13.Cu")
		(net "P5E_CPU0_P3_RX_BUF_DP<2>")
	)
	(segment
		(start 376.319034 -413.927036)
		(end 376.390662 -413.956754)
		(width 0.14224)
		(layer "In13.Cu")
		(net "P5E_CPU0_P3_RX_BUF_DP<2>")
	)
	(segment
		(start 373.615712 -408.67711)
		(end 373.596662 -408.87015)
		(width 0.14224)
		(layer "In13.Cu")
		(net "P5E_CPU0_P3_RX_BUF_DP<2>")
	)
	(segment
		(start 376.061732 -412.15945)
		(end 376.061732 -413.567118)
		(width 0.14224)
		(layer "In13.Cu")
		(net "P5E_CPU0_P3_RX_BUF_DP<2>")
	)
	(segment
		(start 375.286016 -410.928566)
		(end 375.881138 -411.653482)
		(width 0.14224)
		(layer "In13.Cu")
		(net "P5E_CPU0_P3_RX_BUF_DP<2>")
	)
	(segment
		(start 377.593352 -417.266882)
		(end 377.730512 -417.404042)
		(width 0.14224)
		(layer "In13.Cu")
		(net "P5E_CPU0_P3_RX_BUF_DP<2>")
	)
	(segment
		(start 385.058412 -424.840908)
		(end 385.058412 -433.58689)
		(width 0.14224)
		(layer "In13.Cu")
		(net "P5E_CPU0_P3_RX_BUF_DP<2>")
	)
	(segment
		(start 384.333242 -423.985436)
		(end 384.51282 -424.105578)
		(width 0.14224)
		(layer "In13.Cu")
		(net "P5E_CPU0_P3_RX_BUF_DP<2>")
	)
	(segment
		(start 372.994682 -406.44699)
		(end 372.994682 -406.87371)
		(width 0.14224)
		(layer "In13.Cu")
		(net "P5E_CPU0_P3_RX_BUF_DP<2>")
	)
	(segment
		(start 372.857522 -404.05431)
		(end 372.994682 -404.19147)
		(width 0.14224)
		(layer "In13.Cu")
		(net "P5E_CPU0_P3_RX_BUF_DP<2>")
	)
	(segment
		(start 372.994682 -406.87371)
		(end 372.857522 -407.01087)
		(width 0.14224)
		(layer "In13.Cu")
		(net "P5E_CPU0_P3_RX_BUF_DP<2>")
	)
	(segment
		(start 374.31218 -409.742132)
		(end 374.841008 -410.386276)
		(width 0.14224)
		(layer "In13.Cu")
		(net "P5E_CPU0_P3_RX_BUF_DP<2>")
	)
	(segment
		(start 372.994682 -403.49043)
		(end 372.857522 -403.62759)
		(width 0.14224)
		(layer "In13.Cu")
		(net "P5E_CPU0_P3_RX_BUF_DP<2>")
	)
	(segment
		(start 377.593352 -414.806892)
		(end 377.593352 -416.139122)
		(width 0.14224)
		(layer "In13.Cu")
		(net "P5E_CPU0_P3_RX_BUF_DP<2>")
	)
	(segment
		(start 385.6228 -433.748942)
		(end 385.7498 -433.621942)
		(width 0.14224)
		(layer "In13.Cu")
		(net "P5E_CPU0_P3_RX_BUF_DP<2>")
	)
	(segment
		(start 372.857522 -404.75535)
		(end 372.857522 -405.18207)
		(width 0.14224)
		(layer "In13.Cu")
		(net "P5E_CPU0_P3_RX_BUF_DP<2>")
	)
	(segment
		(start 376.134376 -413.742378)
		(end 376.319034 -413.927036)
		(width 0.14224)
		(layer "In13.Cu")
		(net "P5E_CPU0_P3_RX_BUF_DP<2>")
	)
	(segment
		(start 372.926356 -408.053032)
		(end 373.151908 -408.328114)
		(width 0.14224)
		(layer "In13.Cu")
		(net "P5E_CPU0_P3_RX_BUF_DP<2>")
	)
	(segment
		(start 381.65405 -422.717722)
		(end 384.333242 -423.985436)
		(width 0.14224)
		(layer "In13.Cu")
		(net "P5E_CPU0_P3_RX_BUF_DP<2>")
	)
	(segment
		(start 381.154178 -422.423082)
		(end 381.245872 -422.594278)
		(width 0.14224)
		(layer "In13.Cu")
		(net "P5E_CPU0_P3_RX_BUF_DP<2>")
	)
	(segment
		(start 375.305066 -410.735526)
		(end 375.286016 -410.928566)
		(width 0.14224)
		(layer "In13.Cu")
		(net "P5E_CPU0_P3_RX_BUF_DP<2>")
	)
	(segment
		(start 373.867172 -409.199842)
		(end 374.060212 -409.218892)
		(width 0.14224)
		(layer "In13.Cu")
		(net "P5E_CPU0_P3_RX_BUF_DP<2>")
	)
	(segment
		(start 378.49429 -419.612064)
		(end 379.005084 -420.123112)
		(width 0.14224)
		(layer "In13.Cu")
		(net "P5E_CPU0_P3_RX_BUF_DP<2>")
	)
	(segment
		(start 385.220464 -433.748942)
		(end 385.6228 -433.748942)
		(width 0.14224)
		(layer "In13.Cu")
		(net "P5E_CPU0_P3_RX_BUF_DP<2>")
	)
	(segment
		(start 385.058412 -433.58689)
		(end 385.220464 -433.748942)
		(width 0.14224)
		(layer "In13.Cu")
		(net "P5E_CPU0_P3_RX_BUF_DP<2>")
	)
	(segment
		(start 375.034048 -410.405326)
		(end 375.305066 -410.735526)
		(width 0.14224)
		(layer "In13.Cu")
		(net "P5E_CPU0_P3_RX_BUF_DP<2>")
	)
	(segment
		(start 377.730512 -416.276282)
		(end 377.730512 -416.703002)
		(width 0.14224)
		(layer "In13.Cu")
		(net "P5E_CPU0_P3_RX_BUF_DP<2>")
	)
	(segment
		(start 377.730512 -417.404042)
		(end 377.730512 -417.830762)
		(width 0.14224)
		(layer "In13.Cu")
		(net "P5E_CPU0_P3_RX_BUF_DP<2>")
	)
	(segment
		(start 379.443234 -421.795702)
		(end 379.638052 -421.990774)
		(width 0.14224)
		(layer "In13.Cu")
		(net "P5E_CPU0_P3_RX_BUF_DP<2>")
	)
	(segment
		(start 372.994682 -404.61819)
		(end 372.857522 -404.75535)
		(width 0.14224)
		(layer "In13.Cu")
		(net "P5E_CPU0_P3_RX_BUF_DP<2>")
	)
	(segment
		(start 380.031752 -422.22674)
		(end 380.57455 -422.390824)
		(width 0.14224)
		(layer "In13.Cu")
		(net "P5E_CPU0_P3_RX_BUF_DP<2>")
	)
	(segment
		(start 379.124972 -420.412418)
		(end 379.124972 -421.161972)
		(width 0.14224)
		(layer "In13.Cu")
		(net "P5E_CPU0_P3_RX_BUF_DP<2>")
	)
	(segment
		(start 373.3165 -401.511008)
		(end 373.177054 -401.371562)
		(width 0.14224)
		(layer "In13.Cu")
		(net "P5E_CPU0_P3_RX_BUF_DP<2>")
	)
	(segment
		(start 377.075192 -414.028128)
		(end 377.408948 -414.361884)
		(width 0.14224)
		(layer "In13.Cu")
		(net "P5E_CPU0_P3_RX_BUF_DP<2>")
	)
	(segment
		(start 372.857522 -407.01087)
		(end 372.857522 -407.860754)
		(width 0.14224)
		(layer "In13.Cu")
		(net "P5E_CPU0_P3_RX_BUF_DP<2>")
	)
	(segment
		(start 372.857522 -405.18207)
		(end 372.994682 -405.31923)
		(width 0.14224)
		(layer "In13.Cu")
		(net "P5E_CPU0_P3_RX_BUF_DP<2>")
	)
	(segment
		(start 380.745492 -422.299384)
		(end 381.154178 -422.423082)
		(width 0.14224)
		(layer "In13.Cu")
		(net "P5E_CPU0_P3_RX_BUF_DP<2>")
	)
	(segment
		(start 376.90298 -413.956754)
		(end 377.075192 -414.028128)
		(width 0.14224)
		(layer "In13.Cu")
		(net "P5E_CPU0_P3_RX_BUF_DP<2>")
	)
	(segment
		(start 377.593352 -416.139122)
		(end 377.730512 -416.276282)
		(width 0.14224)
		(layer "In13.Cu")
		(net "P5E_CPU0_P3_RX_BUF_DP<2>")
	)
	(segment
		(start 374.060212 -409.218892)
		(end 374.33123 -409.549092)
		(width 0.14224)
		(layer "In13.Cu")
		(net "P5E_CPU0_P3_RX_BUF_DP<2>")
	)
	(segment
		(start 380.57455 -422.390824)
		(end 380.745492 -422.299384)
		(width 0.14224)
		(layer "In13.Cu")
		(net "P5E_CPU0_P3_RX_BUF_DP<2>")
	)
	(segment
		(start 377.593352 -416.840162)
		(end 377.593352 -417.266882)
		(width 0.14224)
		(layer "In13.Cu")
		(net "P5E_CPU0_P3_RX_BUF_DP<2>")
	)
	(segment
		(start 372.994682 -403.06371)
		(end 372.994682 -403.49043)
		(width 0.14224)
		(layer "In13.Cu")
		(net "P5E_CPU0_P3_RX_BUF_DP<2>")
	)
	(segment
		(start 373.3165 -401.674838)
		(end 373.3165 -401.511008)
		(width 0.14224)
		(layer "In13.Cu")
		(net "P5E_CPU0_P3_RX_BUF_DP<2>")
	)
	(segment
		(start 377.408948 -414.361884)
		(end 377.593352 -414.806892)
		(width 0.14224)
		(layer "In13.Cu")
		(net "P5E_CPU0_P3_RX_BUF_DP<2>")
	)
	(segment
		(start 379.638052 -421.990774)
		(end 380.031752 -422.22674)
		(width 0.14224)
		(layer "In13.Cu")
		(net "P5E_CPU0_P3_RX_BUF_DP<2>")
	)
	(segment
		(start 372.857522 -405.88311)
		(end 372.857522 -406.30983)
		(width 0.14224)
		(layer "In13.Cu")
		(net "P5E_CPU0_P3_RX_BUF_DP<2>")
	)
	(segment
		(start 384.51282 -424.105578)
		(end 384.9243 -424.517058)
		(width 0.14224)
		(layer "In13.Cu")
		(net "P5E_CPU0_P3_RX_BUF_DP<2>")
	)
	(segment
		(start 372.857522 -403.62759)
		(end 372.857522 -404.05431)
		(width 0.14224)
		(layer "In13.Cu")
		(net "P5E_CPU0_P3_RX_BUF_DP<2>")
	)
	(segment
		(start 372.857522 -406.30983)
		(end 372.994682 -406.44699)
		(width 0.14224)
		(layer "In13.Cu")
		(net "P5E_CPU0_P3_RX_BUF_DP<2>")
	)
	(segment
		(start 376.061732 -413.567118)
		(end 376.134376 -413.742378)
		(width 0.14224)
		(layer "In13.Cu")
		(net "P5E_CPU0_P3_RX_BUF_DP<2>")
	)
	(segment
		(start 376.390662 -413.956754)
		(end 376.90298 -413.956754)
		(width 0.14224)
		(layer "In13.Cu")
		(net "P5E_CPU0_P3_RX_BUF_DP<2>")
	)
	(segment
		(start 379.29693 -421.576754)
		(end 379.443234 -421.795702)
		(width 0.14224)
		(layer "In13.Cu")
		(net "P5E_CPU0_P3_RX_BUF_DP<2>")
	)
	(segment
		(start 372.857522 -401.511008)
		(end 372.857522 -402.92655)
		(width 0.14224)
		(layer "In13.Cu")
		(net "P5E_CPU0_P3_RX_BUF_DP<2>")
	)
	(segment
		(start 372.994682 -405.74595)
		(end 372.857522 -405.88311)
		(width 0.14224)
		(layer "In13.Cu")
		(net "P5E_CPU0_P3_RX_BUF_DP<2>")
	)
	(segment
		(start 381.245872 -422.594278)
		(end 381.65405 -422.717722)
		(width 0.14224)
		(layer "In13.Cu")
		(net "P5E_CPU0_P3_RX_BUF_DP<2>")
	)
	(segment
		(start 372.994682 -405.31923)
		(end 372.994682 -405.74595)
		(width 0.14224)
		(layer "In13.Cu")
		(net "P5E_CPU0_P3_RX_BUF_DP<2>")
	)
	(segment
		(start 373.177054 -401.371562)
		(end 372.996968 -401.371562)
		(width 0.14224)
		(layer "In13.Cu")
		(net "P5E_CPU0_P3_RX_BUF_DP<2>")
	)
	(segment
		(start 377.730512 -417.830762)
		(end 377.593352 -417.967922)
		(width 0.14224)
		(layer "In13.Cu")
		(net "P5E_CPU0_P3_RX_BUF_DP<2>")
	)
	(segment
		(start 378.08154 -419.441376)
		(end 378.49429 -419.612064)
		(width 0.14224)
		(layer "In13.Cu")
		(net "P5E_CPU0_P3_RX_BUF_DP<2>")
	)
	(arc
		(start 372.857522 -407.860754)
		(mid 372.875246 -407.96287)
		(end 372.926356 -408.053032)
		(width 0.14224)
		(layer "In13.Cu")
		(net "P5E_CPU0_P3_RX_BUF_DP<2>")
	)
	(arc
		(start 377.751594 -419.111684)
		(mid 377.883785 -419.309332)
		(end 378.08154 -419.441376)
		(width 0.14224)
		(layer "In13.Cu")
		(net "P5E_CPU0_P3_RX_BUF_DP<2>")
	)
	(arc
		(start 384.9243 -424.517058)
		(mid 385.02358 -424.665642)
		(end 385.058412 -424.840908)
		(width 0.14224)
		(layer "In13.Cu")
		(net "P5E_CPU0_P3_RX_BUF_DP<2>")
	)
	(arc
		(start 375.881138 -411.653482)
		(mid 376.015371 -411.890791)
		(end 376.061732 -412.15945)
		(width 0.14224)
		(layer "In13.Cu")
		(net "P5E_CPU0_P3_RX_BUF_DP<2>")
	)
	(arc
		(start 379.005084 -420.123112)
		(mid 379.093828 -420.255832)
		(end 379.124972 -420.412418)
		(width 0.14224)
		(layer "In13.Cu")
		(net "P5E_CPU0_P3_RX_BUF_DP<2>")
	)
	(segment
		(start 371.413786 -401.105878)
		(end 371.667024 -401.359116)
		(width 0.1016)
		(layer "F.Cu")
		(net "P5E_CPU0_P3_RX_BUF_DP<1>")
	)
	(segment
		(start 371.667024 -401.359116)
		(end 371.977666 -401.359116)
		(width 0.1016)
		(layer "F.Cu")
		(net "P5E_CPU0_P3_RX_BUF_DP<1>")
	)
	(segment
		(start 372.11635 -401.4978)
		(end 372.11635 -401.674838)
		(width 0.1016)
		(layer "F.Cu")
		(net "P5E_CPU0_P3_RX_BUF_DP<1>")
	)
	(segment
		(start 371.41785 -399.663158)
		(end 371.502432 -399.74774)
		(width 0.1016)
		(layer "F.Cu")
		(net "P5E_CPU0_P3_RX_BUF_DP<1>")
	)
	(segment
		(start 371.977666 -401.359116)
		(end 372.11635 -401.4978)
		(width 0.1016)
		(layer "F.Cu")
		(net "P5E_CPU0_P3_RX_BUF_DP<1>")
	)
	(segment
		(start 371.502432 -399.870676)
		(end 371.413786 -399.959322)
		(width 0.1016)
		(layer "F.Cu")
		(net "P5E_CPU0_P3_RX_BUF_DP<1>")
	)
	(segment
		(start 371.502432 -399.74774)
		(end 371.502432 -399.870676)
		(width 0.1016)
		(layer "F.Cu")
		(net "P5E_CPU0_P3_RX_BUF_DP<1>")
	)
	(segment
		(start 371.413786 -399.959322)
		(end 371.413786 -401.105878)
		(width 0.1016)
		(layer "F.Cu")
		(net "P5E_CPU0_P3_RX_BUF_DP<1>")
	)
	(segment
		(start 373.071136 -413.742378)
		(end 373.255794 -413.927036)
		(width 0.14224)
		(layer "In13.Cu")
		(net "P5E_CPU0_P3_RX_BUF_DP<1>")
	)
	(segment
		(start 372.998492 -412.039562)
		(end 372.998492 -413.567118)
		(width 0.14224)
		(layer "In13.Cu")
		(net "P5E_CPU0_P3_RX_BUF_DP<1>")
	)
	(segment
		(start 378.033534 -422.711372)
		(end 378.457968 -422.84015)
		(width 0.14224)
		(layer "In13.Cu")
		(net "P5E_CPU0_P3_RX_BUF_DP<1>")
	)
	(segment
		(start 371.657372 -404.96363)
		(end 371.794532 -405.10079)
		(width 0.14224)
		(layer "In13.Cu")
		(net "P5E_CPU0_P3_RX_BUF_DP<1>")
	)
	(segment
		(start 372.59514 -410.624782)
		(end 372.520718 -410.804106)
		(width 0.14224)
		(layer "In13.Cu")
		(net "P5E_CPU0_P3_RX_BUF_DP<1>")
	)
	(segment
		(start 383.30124 -434.74894)
		(end 383.595118 -434.74894)
		(width 0.14224)
		(layer "In13.Cu")
		(net "P5E_CPU0_P3_RX_BUF_DP<1>")
	)
	(segment
		(start 372.520718 -410.804106)
		(end 372.967504 -411.882844)
		(width 0.14224)
		(layer "In13.Cu")
		(net "P5E_CPU0_P3_RX_BUF_DP<1>")
	)
	(segment
		(start 374.530112 -417.796218)
		(end 374.530112 -418.619686)
		(width 0.14224)
		(layer "In13.Cu")
		(net "P5E_CPU0_P3_RX_BUF_DP<1>")
	)
	(segment
		(start 374.667272 -416.015424)
		(end 374.667272 -416.442144)
		(width 0.14224)
		(layer "In13.Cu")
		(net "P5E_CPU0_P3_RX_BUF_DP<1>")
	)
	(segment
		(start 371.794532 -406.22855)
		(end 371.794532 -406.65527)
		(width 0.14224)
		(layer "In13.Cu")
		(net "P5E_CPU0_P3_RX_BUF_DP<1>")
	)
	(segment
		(start 378.62891 -422.74871)
		(end 379.037596 -422.872408)
		(width 0.14224)
		(layer "In13.Cu")
		(net "P5E_CPU0_P3_RX_BUF_DP<1>")
	)
	(segment
		(start 383.749804 -434.594254)
		(end 383.749804 -434.289962)
		(width 0.14224)
		(layer "In13.Cu")
		(net "P5E_CPU0_P3_RX_BUF_DP<1>")
	)
	(segment
		(start 371.794532 -403.97303)
		(end 371.794532 -404.39975)
		(width 0.14224)
		(layer "In13.Cu")
		(net "P5E_CPU0_P3_RX_BUF_DP<1>")
	)
	(segment
		(start 371.794532 -404.39975)
		(end 371.657372 -404.53691)
		(width 0.14224)
		(layer "In13.Cu")
		(net "P5E_CPU0_P3_RX_BUF_DP<1>")
	)
	(segment
		(start 371.794532 -405.10079)
		(end 371.794532 -405.52751)
		(width 0.14224)
		(layer "In13.Cu")
		(net "P5E_CPU0_P3_RX_BUF_DP<1>")
	)
	(segment
		(start 371.794532 -405.52751)
		(end 371.657372 -405.66467)
		(width 0.14224)
		(layer "In13.Cu")
		(net "P5E_CPU0_P3_RX_BUF_DP<1>")
	)
	(segment
		(start 371.657372 -407.21915)
		(end 371.794532 -407.35631)
		(width 0.14224)
		(layer "In13.Cu")
		(net "P5E_CPU0_P3_RX_BUF_DP<1>")
	)
	(segment
		(start 376.74804 -422.10355)
		(end 378.033534 -422.711372)
		(width 0.14224)
		(layer "In13.Cu")
		(net "P5E_CPU0_P3_RX_BUF_DP<1>")
	)
	(segment
		(start 371.796818 -401.371562)
		(end 371.657372 -401.511008)
		(width 0.14224)
		(layer "In13.Cu")
		(net "P5E_CPU0_P3_RX_BUF_DP<1>")
	)
	(segment
		(start 376.189748 -421.650414)
		(end 376.62612 -422.017444)
		(width 0.14224)
		(layer "In13.Cu")
		(net "P5E_CPU0_P3_RX_BUF_DP<1>")
	)
	(segment
		(start 372.11635 -401.674838)
		(end 372.11635 -401.511008)
		(width 0.14224)
		(layer "In13.Cu")
		(net "P5E_CPU0_P3_RX_BUF_DP<1>")
	)
	(segment
		(start 383.058416 -434.506116)
		(end 383.30124 -434.74894)
		(width 0.14224)
		(layer "In13.Cu")
		(net "P5E_CPU0_P3_RX_BUF_DP<1>")
	)
	(segment
		(start 376.061732 -420.391336)
		(end 376.061732 -421.37584)
		(width 0.14224)
		(layer "In13.Cu")
		(net "P5E_CPU0_P3_RX_BUF_DP<1>")
	)
	(segment
		(start 383.058416 -424.691048)
		(end 383.058416 -434.506116)
		(width 0.14224)
		(layer "In13.Cu")
		(net "P5E_CPU0_P3_RX_BUF_DP<1>")
	)
	(segment
		(start 372.998492 -413.567118)
		(end 373.071136 -413.742378)
		(width 0.14224)
		(layer "In13.Cu")
		(net "P5E_CPU0_P3_RX_BUF_DP<1>")
	)
	(segment
		(start 375.465848 -419.626542)
		(end 375.941844 -420.101522)
		(width 0.14224)
		(layer "In13.Cu")
		(net "P5E_CPU0_P3_RX_BUF_DP<1>")
	)
	(segment
		(start 374.530112 -415.878264)
		(end 374.667272 -416.015424)
		(width 0.14224)
		(layer "In13.Cu")
		(net "P5E_CPU0_P3_RX_BUF_DP<1>")
	)
	(segment
		(start 374.070626 -414.086802)
		(end 374.345708 -414.361884)
		(width 0.14224)
		(layer "In13.Cu")
		(net "P5E_CPU0_P3_RX_BUF_DP<1>")
	)
	(segment
		(start 373.756682 -413.956754)
		(end 374.070626 -414.086802)
		(width 0.14224)
		(layer "In13.Cu")
		(net "P5E_CPU0_P3_RX_BUF_DP<1>")
	)
	(segment
		(start 371.794532 -402.84527)
		(end 371.794532 -403.27199)
		(width 0.14224)
		(layer "In13.Cu")
		(net "P5E_CPU0_P3_RX_BUF_DP<1>")
	)
	(segment
		(start 372.431818 -410.23032)
		(end 372.59514 -410.624782)
		(width 0.14224)
		(layer "In13.Cu")
		(net "P5E_CPU0_P3_RX_BUF_DP<1>")
	)
	(segment
		(start 371.657372 -401.511008)
		(end 371.657372 -402.70811)
		(width 0.14224)
		(layer "In13.Cu")
		(net "P5E_CPU0_P3_RX_BUF_DP<1>")
	)
	(segment
		(start 371.657372 -405.66467)
		(end 371.657372 -406.09139)
		(width 0.14224)
		(layer "In13.Cu")
		(net "P5E_CPU0_P3_RX_BUF_DP<1>")
	)
	(segment
		(start 373.255794 -413.927036)
		(end 373.327422 -413.956754)
		(width 0.14224)
		(layer "In13.Cu")
		(net "P5E_CPU0_P3_RX_BUF_DP<1>")
	)
	(segment
		(start 379.037596 -422.872408)
		(end 379.129036 -423.043858)
		(width 0.14224)
		(layer "In13.Cu")
		(net "P5E_CPU0_P3_RX_BUF_DP<1>")
	)
	(segment
		(start 371.657372 -406.09139)
		(end 371.794532 -406.22855)
		(width 0.14224)
		(layer "In13.Cu")
		(net "P5E_CPU0_P3_RX_BUF_DP<1>")
	)
	(segment
		(start 376.62612 -422.017444)
		(end 376.74804 -422.10355)
		(width 0.14224)
		(layer "In13.Cu")
		(net "P5E_CPU0_P3_RX_BUF_DP<1>")
	)
	(segment
		(start 371.657372 -403.40915)
		(end 371.657372 -403.83587)
		(width 0.14224)
		(layer "In13.Cu")
		(net "P5E_CPU0_P3_RX_BUF_DP<1>")
	)
	(segment
		(start 371.657372 -404.53691)
		(end 371.657372 -404.96363)
		(width 0.14224)
		(layer "In13.Cu")
		(net "P5E_CPU0_P3_RX_BUF_DP<1>")
	)
	(segment
		(start 371.794532 -403.27199)
		(end 371.657372 -403.40915)
		(width 0.14224)
		(layer "In13.Cu")
		(net "P5E_CPU0_P3_RX_BUF_DP<1>")
	)
	(segment
		(start 371.794532 -407.35631)
		(end 371.794532 -407.78303)
		(width 0.14224)
		(layer "In13.Cu")
		(net "P5E_CPU0_P3_RX_BUF_DP<1>")
	)
	(segment
		(start 371.976904 -401.371562)
		(end 371.796818 -401.371562)
		(width 0.14224)
		(layer "In13.Cu")
		(net "P5E_CPU0_P3_RX_BUF_DP<1>")
	)
	(segment
		(start 371.794532 -406.65527)
		(end 371.657372 -406.79243)
		(width 0.14224)
		(layer "In13.Cu")
		(net "P5E_CPU0_P3_RX_BUF_DP<1>")
	)
	(segment
		(start 374.667272 -417.659058)
		(end 374.530112 -417.796218)
		(width 0.14224)
		(layer "In13.Cu")
		(net "P5E_CPU0_P3_RX_BUF_DP<1>")
	)
	(segment
		(start 383.595118 -434.74894)
		(end 383.749804 -434.594254)
		(width 0.14224)
		(layer "In13.Cu")
		(net "P5E_CPU0_P3_RX_BUF_DP<1>")
	)
	(segment
		(start 374.530112 -417.095178)
		(end 374.667272 -417.232338)
		(width 0.14224)
		(layer "In13.Cu")
		(net "P5E_CPU0_P3_RX_BUF_DP<1>")
	)
	(segment
		(start 374.530112 -416.579304)
		(end 374.530112 -417.095178)
		(width 0.14224)
		(layer "In13.Cu")
		(net "P5E_CPU0_P3_RX_BUF_DP<1>")
	)
	(segment
		(start 372.16334 -409.58262)
		(end 372.089172 -409.761944)
		(width 0.14224)
		(layer "In13.Cu")
		(net "P5E_CPU0_P3_RX_BUF_DP<1>")
	)
	(segment
		(start 373.327422 -413.956754)
		(end 373.756682 -413.956754)
		(width 0.14224)
		(layer "In13.Cu")
		(net "P5E_CPU0_P3_RX_BUF_DP<1>")
	)
	(segment
		(start 372.089172 -409.761944)
		(end 372.25224 -410.156152)
		(width 0.14224)
		(layer "In13.Cu")
		(net "P5E_CPU0_P3_RX_BUF_DP<1>")
	)
	(segment
		(start 374.667272 -417.232338)
		(end 374.667272 -417.659058)
		(width 0.14224)
		(layer "In13.Cu")
		(net "P5E_CPU0_P3_RX_BUF_DP<1>")
	)
	(segment
		(start 371.657372 -402.70811)
		(end 371.794532 -402.84527)
		(width 0.14224)
		(layer "In13.Cu")
		(net "P5E_CPU0_P3_RX_BUF_DP<1>")
	)
	(segment
		(start 372.000018 -409.188158)
		(end 372.16334 -409.58262)
		(width 0.14224)
		(layer "In13.Cu")
		(net "P5E_CPU0_P3_RX_BUF_DP<1>")
	)
	(segment
		(start 375.189496 -419.511988)
		(end 375.465848 -419.626542)
		(width 0.14224)
		(layer "In13.Cu")
		(net "P5E_CPU0_P3_RX_BUF_DP<1>")
	)
	(segment
		(start 371.657372 -406.79243)
		(end 371.657372 -407.21915)
		(width 0.14224)
		(layer "In13.Cu")
		(net "P5E_CPU0_P3_RX_BUF_DP<1>")
	)
	(segment
		(start 372.11635 -401.511008)
		(end 371.976904 -401.371562)
		(width 0.14224)
		(layer "In13.Cu")
		(net "P5E_CPU0_P3_RX_BUF_DP<1>")
	)
	(segment
		(start 371.794532 -407.78303)
		(end 371.657372 -407.92019)
		(width 0.14224)
		(layer "In13.Cu")
		(net "P5E_CPU0_P3_RX_BUF_DP<1>")
	)
	(segment
		(start 371.82044 -409.11399)
		(end 372.000018 -409.188158)
		(width 0.14224)
		(layer "In13.Cu")
		(net "P5E_CPU0_P3_RX_BUF_DP<1>")
	)
	(segment
		(start 371.657372 -403.83587)
		(end 371.794532 -403.97303)
		(width 0.14224)
		(layer "In13.Cu")
		(net "P5E_CPU0_P3_RX_BUF_DP<1>")
	)
	(segment
		(start 374.345708 -414.361884)
		(end 374.530112 -414.806892)
		(width 0.14224)
		(layer "In13.Cu")
		(net "P5E_CPU0_P3_RX_BUF_DP<1>")
	)
	(segment
		(start 372.25224 -410.156152)
		(end 372.431818 -410.23032)
		(width 0.14224)
		(layer "In13.Cu")
		(net "P5E_CPU0_P3_RX_BUF_DP<1>")
	)
	(segment
		(start 378.457968 -422.84015)
		(end 378.62891 -422.74871)
		(width 0.14224)
		(layer "In13.Cu")
		(net "P5E_CPU0_P3_RX_BUF_DP<1>")
	)
	(segment
		(start 379.129036 -423.043858)
		(end 381.66167 -423.812208)
		(width 0.14224)
		(layer "In13.Cu")
		(net "P5E_CPU0_P3_RX_BUF_DP<1>")
	)
	(segment
		(start 374.530112 -418.619686)
		(end 374.69572 -419.018466)
		(width 0.14224)
		(layer "In13.Cu")
		(net "P5E_CPU0_P3_RX_BUF_DP<1>")
	)
	(segment
		(start 374.667272 -416.442144)
		(end 374.530112 -416.579304)
		(width 0.14224)
		(layer "In13.Cu")
		(net "P5E_CPU0_P3_RX_BUF_DP<1>")
	)
	(segment
		(start 371.657372 -407.92019)
		(end 371.657372 -408.694382)
		(width 0.14224)
		(layer "In13.Cu")
		(net "P5E_CPU0_P3_RX_BUF_DP<1>")
	)
	(segment
		(start 381.66167 -423.812208)
		(end 382.779524 -424.274234)
		(width 0.14224)
		(layer "In13.Cu")
		(net "P5E_CPU0_P3_RX_BUF_DP<1>")
	)
	(segment
		(start 374.530112 -414.806892)
		(end 374.530112 -415.878264)
		(width 0.14224)
		(layer "In13.Cu")
		(net "P5E_CPU0_P3_RX_BUF_DP<1>")
	)
	(segment
		(start 371.667024 -408.74315)
		(end 371.82044 -409.11399)
		(width 0.14224)
		(layer "In13.Cu")
		(net "P5E_CPU0_P3_RX_BUF_DP<1>")
	)
	(arc
		(start 376.061732 -421.37584)
		(mid 376.095367 -421.527283)
		(end 376.189748 -421.650414)
		(width 0.14224)
		(layer "In13.Cu")
		(net "P5E_CPU0_P3_RX_BUF_DP<1>")
	)
	(arc
		(start 382.779524 -424.274234)
		(mid 382.982172 -424.440345)
		(end 383.058416 -424.691048)
		(width 0.14224)
		(layer "In13.Cu")
		(net "P5E_CPU0_P3_RX_BUF_DP<1>")
	)
	(arc
		(start 375.006616 -419.410134)
		(mid 375.095124 -419.466325)
		(end 375.189496 -419.511988)
		(width 0.14224)
		(layer "In13.Cu")
		(net "P5E_CPU0_P3_RX_BUF_DP<1>")
	)
	(arc
		(start 372.967504 -411.882844)
		(mid 372.990692 -411.95968)
		(end 372.998492 -412.039562)
		(width 0.14224)
		(layer "In13.Cu")
		(net "P5E_CPU0_P3_RX_BUF_DP<1>")
	)
	(arc
		(start 374.69572 -419.018466)
		(mid 374.823834 -419.235994)
		(end 375.006616 -419.410134)
		(width 0.14224)
		(layer "In13.Cu")
		(net "P5E_CPU0_P3_RX_BUF_DP<1>")
	)
	(arc
		(start 375.941844 -420.101522)
		(mid 376.030607 -420.234505)
		(end 376.061732 -420.391336)
		(width 0.14224)
		(layer "In13.Cu")
		(net "P5E_CPU0_P3_RX_BUF_DP<1>")
	)
	(arc
		(start 371.657372 -408.694382)
		(mid 371.659818 -408.719235)
		(end 371.667024 -408.74315)
		(width 0.14224)
		(layer "In13.Cu")
		(net "P5E_CPU0_P3_RX_BUF_DP<1>")
	)
	(segment
		(start 388.916418 -401.51431)
		(end 388.916418 -401.674838)
		(width 0.1016)
		(layer "F.Cu")
		(net "P5E_CPU0_P3_RX_BUF_DP<15>")
	)
	(segment
		(start 388.467092 -401.359116)
		(end 388.761224 -401.359116)
		(width 0.1016)
		(layer "F.Cu")
		(net "P5E_CPU0_P3_RX_BUF_DP<15>")
	)
	(segment
		(start 388.3025 -399.74774)
		(end 388.3025 -399.870676)
		(width 0.1016)
		(layer "F.Cu")
		(net "P5E_CPU0_P3_RX_BUF_DP<15>")
	)
	(segment
		(start 388.213854 -401.105878)
		(end 388.467092 -401.359116)
		(width 0.1016)
		(layer "F.Cu")
		(net "P5E_CPU0_P3_RX_BUF_DP<15>")
	)
	(segment
		(start 388.3025 -399.870676)
		(end 388.213854 -399.959322)
		(width 0.1016)
		(layer "F.Cu")
		(net "P5E_CPU0_P3_RX_BUF_DP<15>")
	)
	(segment
		(start 388.213854 -399.959322)
		(end 388.213854 -401.105878)
		(width 0.1016)
		(layer "F.Cu")
		(net "P5E_CPU0_P3_RX_BUF_DP<15>")
	)
	(segment
		(start 388.217918 -399.663158)
		(end 388.3025 -399.74774)
		(width 0.1016)
		(layer "F.Cu")
		(net "P5E_CPU0_P3_RX_BUF_DP<15>")
	)
	(segment
		(start 388.761224 -401.359116)
		(end 388.916418 -401.51431)
		(width 0.1016)
		(layer "F.Cu")
		(net "P5E_CPU0_P3_RX_BUF_DP<15>")
	)
	(segment
		(start 417.230052 -422.769538)
		(end 418.022532 -422.44137)
		(width 0.14224)
		(layer "In13.Cu")
		(net "P5E_CPU0_P3_RX_BUF_DP<15>")
	)
	(segment
		(start 415.524696 -411.695646)
		(end 409.400248 -407.603706)
		(width 0.14224)
		(layer "In13.Cu")
		(net "P5E_CPU0_P3_RX_BUF_DP<15>")
	)
	(segment
		(start 416.588702 -423.107612)
		(end 416.680142 -422.936162)
		(width 0.14224)
		(layer "In13.Cu")
		(net "P5E_CPU0_P3_RX_BUF_DP<15>")
	)
	(segment
		(start 417.415472 -415.842704)
		(end 417.415472 -414.806892)
		(width 0.14224)
		(layer "In13.Cu")
		(net "P5E_CPU0_P3_RX_BUF_DP<15>")
	)
	(segment
		(start 413.850582 -423.794682)
		(end 414.021778 -423.886122)
		(width 0.14224)
		(layer "In13.Cu")
		(net "P5E_CPU0_P3_RX_BUF_DP<15>")
	)
	(segment
		(start 416.009074 -423.13987)
		(end 416.18027 -423.23131)
		(width 0.14224)
		(layer "In13.Cu")
		(net "P5E_CPU0_P3_RX_BUF_DP<15>")
	)
	(segment
		(start 398.8816 -404.108158)
		(end 398.457166 -404.066502)
		(width 0.14224)
		(layer "In13.Cu")
		(net "P5E_CPU0_P3_RX_BUF_DP<15>")
	)
	(segment
		(start 388.45744 -401.511008)
		(end 388.596886 -401.371562)
		(width 0.14224)
		(layer "In13.Cu")
		(net "P5E_CPU0_P3_RX_BUF_DP<15>")
	)
	(segment
		(start 415.883598 -412.356554)
		(end 415.883598 -412.356046)
		(width 0.14224)
		(layer "In13.Cu")
		(net "P5E_CPU0_P3_RX_BUF_DP<15>")
	)
	(segment
		(start 417.231068 -414.361884)
		(end 416.897312 -414.028128)
		(width 0.14224)
		(layer "In13.Cu")
		(net "P5E_CPU0_P3_RX_BUF_DP<15>")
	)
	(segment
		(start 417.415472 -414.806892)
		(end 417.231068 -414.361884)
		(width 0.14224)
		(layer "In13.Cu")
		(net "P5E_CPU0_P3_RX_BUF_DP<15>")
	)
	(segment
		(start 418.270436 -419.593268)
		(end 417.83 -419.410642)
		(width 0.14224)
		(layer "In13.Cu")
		(net "P5E_CPU0_P3_RX_BUF_DP<15>")
	)
	(segment
		(start 418.022532 -422.44137)
		(end 418.169852 -422.36263)
		(width 0.14224)
		(layer "In13.Cu")
		(net "P5E_CPU0_P3_RX_BUF_DP<15>")
	)
	(segment
		(start 408.049984 -406.701498)
		(end 403.930104 -404.994872)
		(width 0.14224)
		(layer "In13.Cu")
		(net "P5E_CPU0_P3_RX_BUF_DP<15>")
	)
	(segment
		(start 416.897312 -414.028128)
		(end 416.7251 -413.956754)
		(width 0.14224)
		(layer "In13.Cu")
		(net "P5E_CPU0_P3_RX_BUF_DP<15>")
	)
	(segment
		(start 418.58692 -422.053258)
		(end 418.852096 -421.713406)
		(width 0.14224)
		(layer "In13.Cu")
		(net "P5E_CPU0_P3_RX_BUF_DP<15>")
	)
	(segment
		(start 414.021778 -423.886122)
		(end 414.43021 -423.76217)
		(width 0.14224)
		(layer "In13.Cu")
		(net "P5E_CPU0_P3_RX_BUF_DP<15>")
	)
	(segment
		(start 388.596886 -401.371562)
		(end 388.776972 -401.371562)
		(width 0.14224)
		(layer "In13.Cu")
		(net "P5E_CPU0_P3_RX_BUF_DP<15>")
	)
	(segment
		(start 395.983714 -403.68474)
		(end 395.558772 -403.64283)
		(width 0.14224)
		(layer "In13.Cu")
		(net "P5E_CPU0_P3_RX_BUF_DP<15>")
	)
	(segment
		(start 415.509456 -423.434764)
		(end 415.600896 -423.263568)
		(width 0.14224)
		(layer "In13.Cu")
		(net "P5E_CPU0_P3_RX_BUF_DP<15>")
	)
	(segment
		(start 418.169852 -422.36263)
		(end 418.58692 -422.053258)
		(width 0.14224)
		(layer "In13.Cu")
		(net "P5E_CPU0_P3_RX_BUF_DP<15>")
	)
	(segment
		(start 388.916418 -401.511008)
		(end 388.916418 -401.674838)
		(width 0.14224)
		(layer "In13.Cu")
		(net "P5E_CPU0_P3_RX_BUF_DP<15>")
	)
	(segment
		(start 417.415472 -416.970464)
		(end 417.415472 -416.543744)
		(width 0.14224)
		(layer "In13.Cu")
		(net "P5E_CPU0_P3_RX_BUF_DP<15>")
	)
	(segment
		(start 397.22933 -403.945344)
		(end 397.10614 -403.79523)
		(width 0.14224)
		(layer "In13.Cu")
		(net "P5E_CPU0_P3_RX_BUF_DP<15>")
	)
	(segment
		(start 415.844228 -412.130748)
		(end 415.843974 -412.130748)
		(width 0.14224)
		(layer "In13.Cu")
		(net "P5E_CPU0_P3_RX_BUF_DP<15>")
	)
	(segment
		(start 412.455868 -424.162982)
		(end 412.601918 -424.101768)
		(width 0.14224)
		(layer "In13.Cu")
		(net "P5E_CPU0_P3_RX_BUF_DP<15>")
	)
	(segment
		(start 409.400248 -407.603706)
		(end 409.362402 -407.41346)
		(width 0.14224)
		(layer "In13.Cu")
		(net "P5E_CPU0_P3_RX_BUF_DP<15>")
	)
	(segment
		(start 417.415472 -416.543744)
		(end 417.552632 -416.406584)
		(width 0.14224)
		(layer "In13.Cu")
		(net "P5E_CPU0_P3_RX_BUF_DP<15>")
	)
	(segment
		(start 395.408912 -403.76602)
		(end 391.0584 -403.337776)
		(width 0.14224)
		(layer "In13.Cu")
		(net "P5E_CPU0_P3_RX_BUF_DP<15>")
	)
	(segment
		(start 418.852096 -421.713406)
		(end 418.941504 -421.497506)
		(width 0.14224)
		(layer "In13.Cu")
		(net "P5E_CPU0_P3_RX_BUF_DP<15>")
	)
	(segment
		(start 414.52165 -423.590974)
		(end 414.929828 -423.467276)
		(width 0.14224)
		(layer "In13.Cu")
		(net "P5E_CPU0_P3_RX_BUF_DP<15>")
	)
	(segment
		(start 412.208726 -434.74894)
		(end 412.058358 -434.598572)
		(width 0.14224)
		(layer "In13.Cu")
		(net "P5E_CPU0_P3_RX_BUF_DP<15>")
	)
	(segment
		(start 415.101024 -423.558716)
		(end 415.509456 -423.434764)
		(width 0.14224)
		(layer "In13.Cu")
		(net "P5E_CPU0_P3_RX_BUF_DP<15>")
	)
	(segment
		(start 388.45744 -402.554694)
		(end 388.45744 -401.511008)
		(width 0.14224)
		(layer "In13.Cu")
		(net "P5E_CPU0_P3_RX_BUF_DP<15>")
	)
	(segment
		(start 415.883344 -412.356554)
		(end 415.883598 -412.356554)
		(width 0.14224)
		(layer "In13.Cu")
		(net "P5E_CPU0_P3_RX_BUF_DP<15>")
	)
	(segment
		(start 414.929828 -423.467276)
		(end 415.101024 -423.558716)
		(width 0.14224)
		(layer "In13.Cu")
		(net "P5E_CPU0_P3_RX_BUF_DP<15>")
	)
	(segment
		(start 418.862256 -420.185088)
		(end 418.270436 -419.593268)
		(width 0.14224)
		(layer "In13.Cu")
		(net "P5E_CPU0_P3_RX_BUF_DP<15>")
	)
	(segment
		(start 398.457166 -404.066502)
		(end 398.333976 -403.916388)
		(width 0.14224)
		(layer "In13.Cu")
		(net "P5E_CPU0_P3_RX_BUF_DP<15>")
	)
	(segment
		(start 412.058358 -434.598572)
		(end 412.058358 -424.644312)
		(width 0.14224)
		(layer "In13.Cu")
		(net "P5E_CPU0_P3_RX_BUF_DP<15>")
	)
	(segment
		(start 397.909034 -403.874478)
		(end 397.759174 -403.997414)
		(width 0.14224)
		(layer "In13.Cu")
		(net "P5E_CPU0_P3_RX_BUF_DP<15>")
	)
	(segment
		(start 418.941504 -421.497506)
		(end 418.982144 -421.292782)
		(width 0.14224)
		(layer "In13.Cu")
		(net "P5E_CPU0_P3_RX_BUF_DP<15>")
	)
	(segment
		(start 416.7251 -413.956754)
		(end 416.274758 -413.956754)
		(width 0.14224)
		(layer "In13.Cu")
		(net "P5E_CPU0_P3_RX_BUF_DP<15>")
	)
	(segment
		(start 414.43021 -423.76217)
		(end 414.52165 -423.590974)
		(width 0.14224)
		(layer "In13.Cu")
		(net "P5E_CPU0_P3_RX_BUF_DP<15>")
	)
	(segment
		(start 399.579592 -404.177246)
		(end 399.456656 -404.027132)
		(width 0.14224)
		(layer "In13.Cu")
		(net "P5E_CPU0_P3_RX_BUF_DP<15>")
	)
	(segment
		(start 391.0584 -403.337776)
		(end 388.864348 -402.900896)
		(width 0.14224)
		(layer "In13.Cu")
		(net "P5E_CPU0_P3_RX_BUF_DP<15>")
	)
	(segment
		(start 409.00731 -407.176224)
		(end 408.817064 -407.21407)
		(width 0.14224)
		(layer "In13.Cu")
		(net "P5E_CPU0_P3_RX_BUF_DP<15>")
	)
	(segment
		(start 396.531338 -403.87651)
		(end 396.106904 -403.834854)
		(width 0.14224)
		(layer "In13.Cu")
		(net "P5E_CPU0_P3_RX_BUF_DP<15>")
	)
	(segment
		(start 412.1277 -424.471084)
		(end 412.352998 -424.234102)
		(width 0.14224)
		(layer "In13.Cu")
		(net "P5E_CPU0_P3_RX_BUF_DP<15>")
	)
	(segment
		(start 402.622766 -404.598378)
		(end 401.413726 -404.35784)
		(width 0.14224)
		(layer "In13.Cu")
		(net "P5E_CPU0_P3_RX_BUF_DP<15>")
	)
	(segment
		(start 412.75 -434.62194)
		(end 412.623 -434.74894)
		(width 0.14224)
		(layer "In13.Cu")
		(net "P5E_CPU0_P3_RX_BUF_DP<15>")
	)
	(segment
		(start 417.552632 -415.979864)
		(end 417.415472 -415.842704)
		(width 0.14224)
		(layer "In13.Cu")
		(net "P5E_CPU0_P3_RX_BUF_DP<15>")
	)
	(segment
		(start 418.982144 -421.292782)
		(end 418.982144 -420.474394)
		(width 0.14224)
		(layer "In13.Cu")
		(net "P5E_CPU0_P3_RX_BUF_DP<15>")
	)
	(segment
		(start 417.415472 -417.671504)
		(end 417.552632 -417.534344)
		(width 0.14224)
		(layer "In13.Cu")
		(net "P5E_CPU0_P3_RX_BUF_DP<15>")
	)
	(segment
		(start 416.680142 -422.936162)
		(end 417.230052 -422.769538)
		(width 0.14224)
		(layer "In13.Cu")
		(net "P5E_CPU0_P3_RX_BUF_DP<15>")
	)
	(segment
		(start 396.681198 -403.75332)
		(end 396.531338 -403.87651)
		(width 0.14224)
		(layer "In13.Cu")
		(net "P5E_CPU0_P3_RX_BUF_DP<15>")
	)
	(segment
		(start 417.652454 -419.233096)
		(end 417.415472 -418.662104)
		(width 0.14224)
		(layer "In13.Cu")
		(net "P5E_CPU0_P3_RX_BUF_DP<15>")
	)
	(segment
		(start 412.623 -434.74894)
		(end 412.208726 -434.74894)
		(width 0.14224)
		(layer "In13.Cu")
		(net "P5E_CPU0_P3_RX_BUF_DP<15>")
	)
	(segment
		(start 416.18027 -423.23131)
		(end 416.588702 -423.107612)
		(width 0.14224)
		(layer "In13.Cu")
		(net "P5E_CPU0_P3_RX_BUF_DP<15>")
	)
	(segment
		(start 417.552632 -417.107624)
		(end 417.415472 -416.970464)
		(width 0.14224)
		(layer "In13.Cu")
		(net "P5E_CPU0_P3_RX_BUF_DP<15>")
	)
	(segment
		(start 417.415472 -418.662104)
		(end 417.415472 -417.671504)
		(width 0.14224)
		(layer "In13.Cu")
		(net "P5E_CPU0_P3_RX_BUF_DP<15>")
	)
	(segment
		(start 388.549896 -402.679154)
		(end 388.45744 -402.554694)
		(width 0.14224)
		(layer "In13.Cu")
		(net "P5E_CPU0_P3_RX_BUF_DP<15>")
	)
	(segment
		(start 403.930104 -404.994872)
		(end 402.622766 -404.598378)
		(width 0.14224)
		(layer "In13.Cu")
		(net "P5E_CPU0_P3_RX_BUF_DP<15>")
	)
	(segment
		(start 401.413726 -404.35784)
		(end 399.579592 -404.177246)
		(width 0.14224)
		(layer "In13.Cu")
		(net "P5E_CPU0_P3_RX_BUF_DP<15>")
	)
	(segment
		(start 396.106904 -403.834854)
		(end 395.983714 -403.68474)
		(width 0.14224)
		(layer "In13.Cu")
		(net "P5E_CPU0_P3_RX_BUF_DP<15>")
	)
	(segment
		(start 399.031714 -403.985222)
		(end 398.8816 -404.108158)
		(width 0.14224)
		(layer "In13.Cu")
		(net "P5E_CPU0_P3_RX_BUF_DP<15>")
	)
	(segment
		(start 413.442404 -423.91838)
		(end 413.850582 -423.794682)
		(width 0.14224)
		(layer "In13.Cu")
		(net "P5E_CPU0_P3_RX_BUF_DP<15>")
	)
	(segment
		(start 412.75 -434.289962)
		(end 412.75 -434.62194)
		(width 0.14224)
		(layer "In13.Cu")
		(net "P5E_CPU0_P3_RX_BUF_DP<15>")
	)
	(segment
		(start 417.552632 -417.534344)
		(end 417.552632 -417.107624)
		(width 0.14224)
		(layer "In13.Cu")
		(net "P5E_CPU0_P3_RX_BUF_DP<15>")
	)
	(segment
		(start 397.10614 -403.79523)
		(end 396.681198 -403.75332)
		(width 0.14224)
		(layer "In13.Cu")
		(net "P5E_CPU0_P3_RX_BUF_DP<15>")
	)
	(segment
		(start 417.552632 -416.406584)
		(end 417.552632 -415.979864)
		(width 0.14224)
		(layer "In13.Cu")
		(net "P5E_CPU0_P3_RX_BUF_DP<15>")
	)
	(segment
		(start 397.759174 -403.997414)
		(end 397.22933 -403.945344)
		(width 0.14224)
		(layer "In13.Cu")
		(net "P5E_CPU0_P3_RX_BUF_DP<15>")
	)
	(segment
		(start 395.558772 -403.64283)
		(end 395.408912 -403.76602)
		(width 0.14224)
		(layer "In13.Cu")
		(net "P5E_CPU0_P3_RX_BUF_DP<15>")
	)
	(segment
		(start 408.817064 -407.21407)
		(end 408.049984 -406.701498)
		(width 0.14224)
		(layer "In13.Cu")
		(net "P5E_CPU0_P3_RX_BUF_DP<15>")
	)
	(segment
		(start 409.362402 -407.41346)
		(end 409.00731 -407.176224)
		(width 0.14224)
		(layer "In13.Cu")
		(net "P5E_CPU0_P3_RX_BUF_DP<15>")
	)
	(segment
		(start 388.776972 -401.371562)
		(end 388.916418 -401.511008)
		(width 0.14224)
		(layer "In13.Cu")
		(net "P5E_CPU0_P3_RX_BUF_DP<15>")
	)
	(segment
		(start 415.884868 -413.505904)
		(end 415.883344 -412.356554)
		(width 0.14224)
		(layer "In13.Cu")
		(net "P5E_CPU0_P3_RX_BUF_DP<15>")
	)
	(segment
		(start 416.160712 -413.90951)
		(end 415.955988 -413.704786)
		(width 0.14224)
		(layer "In13.Cu")
		(net "P5E_CPU0_P3_RX_BUF_DP<15>")
	)
	(segment
		(start 398.333976 -403.916388)
		(end 397.909034 -403.874478)
		(width 0.14224)
		(layer "In13.Cu")
		(net "P5E_CPU0_P3_RX_BUF_DP<15>")
	)
	(segment
		(start 415.600896 -423.263568)
		(end 416.009074 -423.13987)
		(width 0.14224)
		(layer "In13.Cu")
		(net "P5E_CPU0_P3_RX_BUF_DP<15>")
	)
	(segment
		(start 399.456656 -404.027132)
		(end 399.031714 -403.985222)
		(width 0.14224)
		(layer "In13.Cu")
		(net "P5E_CPU0_P3_RX_BUF_DP<15>")
	)
	(segment
		(start 412.752032 -424.055794)
		(end 413.442404 -423.91838)
		(width 0.14224)
		(layer "In13.Cu")
		(net "P5E_CPU0_P3_RX_BUF_DP<15>")
	)
	(arc
		(start 415.955988 -413.704786)
		(mid 415.917718 -413.653971)
		(end 415.895028 -413.59455)
		(width 0.14224)
		(layer "In13.Cu")
		(net "P5E_CPU0_P3_RX_BUF_DP<15>")
	)
	(arc
		(start 416.274758 -413.956754)
		(mid 416.213035 -413.944477)
		(end 416.160712 -413.90951)
		(width 0.14224)
		(layer "In13.Cu")
		(net "P5E_CPU0_P3_RX_BUF_DP<15>")
	)
	(arc
		(start 388.864348 -402.900896)
		(mid 388.689298 -402.815305)
		(end 388.549896 -402.679154)
		(width 0.14224)
		(layer "In13.Cu")
		(net "P5E_CPU0_P3_RX_BUF_DP<15>")
	)
	(arc
		(start 415.843974 -412.130748)
		(mid 415.808052 -412.04188)
		(end 415.76498 -411.95625)
		(width 0.14224)
		(layer "In13.Cu")
		(net "P5E_CPU0_P3_RX_BUF_DP<15>")
	)
	(arc
		(start 412.601918 -424.101768)
		(mid 412.675821 -424.075015)
		(end 412.752032 -424.055794)
		(width 0.14224)
		(layer "In13.Cu")
		(net "P5E_CPU0_P3_RX_BUF_DP<15>")
	)
	(arc
		(start 415.895028 -413.59455)
		(mid 415.88745 -413.550514)
		(end 415.884868 -413.505904)
		(width 0.14224)
		(layer "In13.Cu")
		(net "P5E_CPU0_P3_RX_BUF_DP<15>")
	)
	(arc
		(start 417.83 -419.410642)
		(mid 417.723583 -419.339513)
		(end 417.652454 -419.233096)
		(width 0.14224)
		(layer "In13.Cu")
		(net "P5E_CPU0_P3_RX_BUF_DP<15>")
	)
	(arc
		(start 412.352998 -424.234102)
		(mid 412.400759 -424.193224)
		(end 412.455868 -424.162982)
		(width 0.14224)
		(layer "In13.Cu")
		(net "P5E_CPU0_P3_RX_BUF_DP<15>")
	)
	(arc
		(start 418.982144 -420.474394)
		(mid 418.950981 -420.317816)
		(end 418.862256 -420.185088)
		(width 0.14224)
		(layer "In13.Cu")
		(net "P5E_CPU0_P3_RX_BUF_DP<15>")
	)
	(arc
		(start 412.058358 -424.644312)
		(mid 412.076395 -424.551046)
		(end 412.1277 -424.471084)
		(width 0.14224)
		(layer "In13.Cu")
		(net "P5E_CPU0_P3_RX_BUF_DP<15>")
	)
	(arc
		(start 415.76498 -411.95625)
		(mid 415.66035 -411.811649)
		(end 415.524696 -411.695646)
		(width 0.14224)
		(layer "In13.Cu")
		(net "P5E_CPU0_P3_RX_BUF_DP<15>")
	)
	(arc
		(start 415.883598 -412.356046)
		(mid 415.873746 -412.241679)
		(end 415.844228 -412.130748)
		(width 0.14224)
		(layer "In13.Cu")
		(net "P5E_CPU0_P3_RX_BUF_DP<15>")
	)
	(segment
		(start 387.267196 -401.359116)
		(end 387.559804 -401.359116)
		(width 0.1016)
		(layer "F.Cu")
		(net "P5E_CPU0_P3_RX_BUF_DP<14>")
	)
	(segment
		(start 387.013958 -401.105878)
		(end 387.267196 -401.359116)
		(width 0.1016)
		(layer "F.Cu")
		(net "P5E_CPU0_P3_RX_BUF_DP<14>")
	)
	(segment
		(start 387.716522 -401.515834)
		(end 387.716522 -401.674838)
		(width 0.1016)
		(layer "F.Cu")
		(net "P5E_CPU0_P3_RX_BUF_DP<14>")
	)
	(segment
		(start 387.102604 -399.870676)
		(end 387.013958 -399.959322)
		(width 0.1016)
		(layer "F.Cu")
		(net "P5E_CPU0_P3_RX_BUF_DP<14>")
	)
	(segment
		(start 387.013958 -399.959322)
		(end 387.013958 -401.105878)
		(width 0.1016)
		(layer "F.Cu")
		(net "P5E_CPU0_P3_RX_BUF_DP<14>")
	)
	(segment
		(start 387.018022 -399.663158)
		(end 387.102604 -399.74774)
		(width 0.1016)
		(layer "F.Cu")
		(net "P5E_CPU0_P3_RX_BUF_DP<14>")
	)
	(segment
		(start 387.102604 -399.74774)
		(end 387.102604 -399.870676)
		(width 0.1016)
		(layer "F.Cu")
		(net "P5E_CPU0_P3_RX_BUF_DP<14>")
	)
	(segment
		(start 387.559804 -401.359116)
		(end 387.716522 -401.515834)
		(width 0.1016)
		(layer "F.Cu")
		(net "P5E_CPU0_P3_RX_BUF_DP<14>")
	)
	(segment
		(start 413.077914 -413.927036)
		(end 412.893256 -413.742378)
		(width 0.14224)
		(layer "In13.Cu")
		(net "P5E_CPU0_P3_RX_BUF_DP<14>")
	)
	(segment
		(start 412.333186 -411.417008)
		(end 411.73019 -410.772102)
		(width 0.14224)
		(layer "In13.Cu")
		(net "P5E_CPU0_P3_RX_BUF_DP<14>")
	)
	(segment
		(start 396.84071 -405.254968)
		(end 396.72514 -405.099012)
		(width 0.14224)
		(layer "In13.Cu")
		(net "P5E_CPU0_P3_RX_BUF_DP<14>")
	)
	(segment
		(start 396.72514 -405.099012)
		(end 396.302738 -405.036274)
		(width 0.14224)
		(layer "In13.Cu")
		(net "P5E_CPU0_P3_RX_BUF_DP<14>")
	)
	(segment
		(start 414.489392 -417.201096)
		(end 414.352232 -417.063936)
		(width 0.14224)
		(layer "In13.Cu")
		(net "P5E_CPU0_P3_RX_BUF_DP<14>")
	)
	(segment
		(start 400.772122 -405.699976)
		(end 400.61642 -405.815546)
		(width 0.14224)
		(layer "In13.Cu")
		(net "P5E_CPU0_P3_RX_BUF_DP<14>")
	)
	(segment
		(start 395.121384 -404.86076)
		(end 394.698982 -404.798276)
		(width 0.14224)
		(layer "In13.Cu")
		(net "P5E_CPU0_P3_RX_BUF_DP<14>")
	)
	(segment
		(start 412.359602 -423.192448)
		(end 413.199072 -422.912794)
		(width 0.14224)
		(layer "In13.Cu")
		(net "P5E_CPU0_P3_RX_BUF_DP<14>")
	)
	(segment
		(start 398.184116 -405.454358)
		(end 396.84071 -405.254968)
		(width 0.14224)
		(layer "In13.Cu")
		(net "P5E_CPU0_P3_RX_BUF_DP<14>")
	)
	(segment
		(start 415.201862 -419.590982)
		(end 414.853374 -419.446456)
		(width 0.14224)
		(layer "In13.Cu")
		(net "P5E_CPU0_P3_RX_BUF_DP<14>")
	)
	(segment
		(start 402.93036 -406.02027)
		(end 402.508212 -405.957532)
		(width 0.14224)
		(layer "In13.Cu")
		(net "P5E_CPU0_P3_RX_BUF_DP<14>")
	)
	(segment
		(start 408.26055 -408.46375)
		(end 406.272238 -407.304748)
		(width 0.14224)
		(layer "In13.Cu")
		(net "P5E_CPU0_P3_RX_BUF_DP<14>")
	)
	(segment
		(start 410.155644 -424.42638)
		(end 411.448504 -423.618406)
		(width 0.14224)
		(layer "In13.Cu")
		(net "P5E_CPU0_P3_RX_BUF_DP<14>")
	)
	(segment
		(start 414.352232 -414.806892)
		(end 414.167828 -414.361884)
		(width 0.14224)
		(layer "In13.Cu")
		(net "P5E_CPU0_P3_RX_BUF_DP<14>")
	)
	(segment
		(start 394.47724 -404.90394)
		(end 393.202922 -404.714964)
		(width 0.14224)
		(layer "In13.Cu")
		(net "P5E_CPU0_P3_RX_BUF_DP<14>")
	)
	(segment
		(start 395.236954 -405.01697)
		(end 395.121384 -404.86076)
		(width 0.14224)
		(layer "In13.Cu")
		(net "P5E_CPU0_P3_RX_BUF_DP<14>")
	)
	(segment
		(start 414.578038 -419.17112)
		(end 414.352232 -418.627306)
		(width 0.14224)
		(layer "In13.Cu")
		(net "P5E_CPU0_P3_RX_BUF_DP<14>")
	)
	(segment
		(start 393.105132 -404.6982)
		(end 388.54888 -403.792436)
		(width 0.14224)
		(layer "In13.Cu")
		(net "P5E_CPU0_P3_RX_BUF_DP<14>")
	)
	(segment
		(start 414.352232 -416.637216)
		(end 414.489392 -416.500056)
		(width 0.14224)
		(layer "In13.Cu")
		(net "P5E_CPU0_P3_RX_BUF_DP<14>")
	)
	(segment
		(start 402.508212 -405.957532)
		(end 402.352256 -406.073102)
		(width 0.14224)
		(layer "In13.Cu")
		(net "P5E_CPU0_P3_RX_BUF_DP<14>")
	)
	(segment
		(start 414.489392 -416.073336)
		(end 414.352232 -415.936176)
		(width 0.14224)
		(layer "In13.Cu")
		(net "P5E_CPU0_P3_RX_BUF_DP<14>")
	)
	(segment
		(start 400.61642 -405.815546)
		(end 398.87779 -405.557482)
		(width 0.14224)
		(layer "In13.Cu")
		(net "P5E_CPU0_P3_RX_BUF_DP<14>")
	)
	(segment
		(start 412.820612 -413.567118)
		(end 412.820612 -412.247588)
		(width 0.14224)
		(layer "In13.Cu")
		(net "P5E_CPU0_P3_RX_BUF_DP<14>")
	)
	(segment
		(start 387.716522 -401.511008)
		(end 387.716522 -401.674838)
		(width 0.14224)
		(layer "In13.Cu")
		(net "P5E_CPU0_P3_RX_BUF_DP<14>")
	)
	(segment
		(start 415.883852 -421.350186)
		(end 415.883852 -420.44239)
		(width 0.14224)
		(layer "In13.Cu")
		(net "P5E_CPU0_P3_RX_BUF_DP<14>")
	)
	(segment
		(start 413.732726 -422.842182)
		(end 413.796988 -422.713404)
		(width 0.14224)
		(layer "In13.Cu")
		(net "P5E_CPU0_P3_RX_BUF_DP<14>")
	)
	(segment
		(start 394.698982 -404.798276)
		(end 394.596874 -404.873968)
		(width 0.14224)
		(layer "In13.Cu")
		(net "P5E_CPU0_P3_RX_BUF_DP<14>")
	)
	(segment
		(start 398.76222 -405.401526)
		(end 398.340072 -405.338788)
		(width 0.14224)
		(layer "In13.Cu")
		(net "P5E_CPU0_P3_RX_BUF_DP<14>")
	)
	(segment
		(start 412.710376 -411.981396)
		(end 412.333186 -411.417008)
		(width 0.14224)
		(layer "In13.Cu")
		(net "P5E_CPU0_P3_RX_BUF_DP<14>")
	)
	(segment
		(start 414.352232 -417.764976)
		(end 414.489392 -417.627816)
		(width 0.14224)
		(layer "In13.Cu")
		(net "P5E_CPU0_P3_RX_BUF_DP<14>")
	)
	(segment
		(start 414.735264 -422.507918)
		(end 414.799526 -422.37914)
		(width 0.14224)
		(layer "In13.Cu")
		(net "P5E_CPU0_P3_RX_BUF_DP<14>")
	)
	(segment
		(start 387.257544 -402.768308)
		(end 387.257544 -401.511008)
		(width 0.14224)
		(layer "In13.Cu")
		(net "P5E_CPU0_P3_RX_BUF_DP<14>")
	)
	(segment
		(start 408.81681 -408.629104)
		(end 408.448002 -408.41422)
		(width 0.14224)
		(layer "In13.Cu")
		(net "P5E_CPU0_P3_RX_BUF_DP<14>")
	)
	(segment
		(start 412.820612 -412.247588)
		(end 412.710376 -411.981396)
		(width 0.14224)
		(layer "In13.Cu")
		(net "P5E_CPU0_P3_RX_BUF_DP<14>")
	)
	(segment
		(start 403.890226 -406.301448)
		(end 403.04593 -406.176226)
		(width 0.14224)
		(layer "In13.Cu")
		(net "P5E_CPU0_P3_RX_BUF_DP<14>")
	)
	(segment
		(start 410.750004 -433.289964)
		(end 410.750004 -433.621942)
		(width 0.14224)
		(layer "In13.Cu")
		(net "P5E_CPU0_P3_RX_BUF_DP<14>")
	)
	(segment
		(start 398.87779 -405.557482)
		(end 398.76222 -405.401526)
		(width 0.14224)
		(layer "In13.Cu")
		(net "P5E_CPU0_P3_RX_BUF_DP<14>")
	)
	(segment
		(start 396.147036 -405.151844)
		(end 395.236954 -405.01697)
		(width 0.14224)
		(layer "In13.Cu")
		(net "P5E_CPU0_P3_RX_BUF_DP<14>")
	)
	(segment
		(start 414.489392 -417.627816)
		(end 414.489392 -417.201096)
		(width 0.14224)
		(layer "In13.Cu")
		(net "P5E_CPU0_P3_RX_BUF_DP<14>")
	)
	(segment
		(start 410.196538 -433.748942)
		(end 410.058362 -433.610766)
		(width 0.14224)
		(layer "In13.Cu")
		(net "P5E_CPU0_P3_RX_BUF_DP<14>")
	)
	(segment
		(start 414.167828 -414.361884)
		(end 413.834072 -414.028128)
		(width 0.14224)
		(layer "In13.Cu")
		(net "P5E_CPU0_P3_RX_BUF_DP<14>")
	)
	(segment
		(start 410.750004 -433.621942)
		(end 410.623004 -433.748942)
		(width 0.14224)
		(layer "In13.Cu")
		(net "P5E_CPU0_P3_RX_BUF_DP<14>")
	)
	(segment
		(start 401.310094 -405.91867)
		(end 401.194524 -405.76246)
		(width 0.14224)
		(layer "In13.Cu")
		(net "P5E_CPU0_P3_RX_BUF_DP<14>")
	)
	(segment
		(start 410.623004 -433.748942)
		(end 410.196538 -433.748942)
		(width 0.14224)
		(layer "In13.Cu")
		(net "P5E_CPU0_P3_RX_BUF_DP<14>")
	)
	(segment
		(start 387.577076 -401.371562)
		(end 387.716522 -401.511008)
		(width 0.14224)
		(layer "In13.Cu")
		(net "P5E_CPU0_P3_RX_BUF_DP<14>")
	)
	(segment
		(start 414.489392 -416.500056)
		(end 414.489392 -416.073336)
		(width 0.14224)
		(layer "In13.Cu")
		(net "P5E_CPU0_P3_RX_BUF_DP<14>")
	)
	(segment
		(start 408.86634 -408.81681)
		(end 408.81681 -408.629104)
		(width 0.14224)
		(layer "In13.Cu")
		(net "P5E_CPU0_P3_RX_BUF_DP<14>")
	)
	(segment
		(start 388.52348 -403.785832)
		(end 387.959346 -403.614382)
		(width 0.14224)
		(layer "In13.Cu")
		(net "P5E_CPU0_P3_RX_BUF_DP<14>")
	)
	(segment
		(start 412.893256 -413.742378)
		(end 412.820612 -413.567118)
		(width 0.14224)
		(layer "In13.Cu")
		(net "P5E_CPU0_P3_RX_BUF_DP<14>")
	)
	(segment
		(start 387.39699 -401.371562)
		(end 387.577076 -401.371562)
		(width 0.14224)
		(layer "In13.Cu")
		(net "P5E_CPU0_P3_RX_BUF_DP<14>")
	)
	(segment
		(start 414.352232 -415.936176)
		(end 414.352232 -414.806892)
		(width 0.14224)
		(layer "In13.Cu")
		(net "P5E_CPU0_P3_RX_BUF_DP<14>")
	)
	(segment
		(start 388.524242 -403.786086)
		(end 388.52348 -403.785832)
		(width 0.14224)
		(layer "In13.Cu")
		(net "P5E_CPU0_P3_RX_BUF_DP<14>")
	)
	(segment
		(start 413.327596 -422.977056)
		(end 413.732726 -422.842182)
		(width 0.14224)
		(layer "In13.Cu")
		(net "P5E_CPU0_P3_RX_BUF_DP<14>")
	)
	(segment
		(start 403.04593 -406.176226)
		(end 402.93036 -406.02027)
		(width 0.14224)
		(layer "In13.Cu")
		(net "P5E_CPU0_P3_RX_BUF_DP<14>")
	)
	(segment
		(start 387.257544 -401.511008)
		(end 387.39699 -401.371562)
		(width 0.14224)
		(layer "In13.Cu")
		(net "P5E_CPU0_P3_RX_BUF_DP<14>")
	)
	(segment
		(start 405.756618 -406.93848)
		(end 405.363172 -406.772872)
		(width 0.14224)
		(layer "In13.Cu")
		(net "P5E_CPU0_P3_RX_BUF_DP<14>")
	)
	(segment
		(start 405.82977 -407.118566)
		(end 405.756618 -406.93848)
		(width 0.14224)
		(layer "In13.Cu")
		(net "P5E_CPU0_P3_RX_BUF_DP<14>")
	)
	(segment
		(start 408.448002 -408.41422)
		(end 408.26055 -408.46375)
		(width 0.14224)
		(layer "In13.Cu")
		(net "P5E_CPU0_P3_RX_BUF_DP<14>")
	)
	(segment
		(start 410.205682 -409.597098)
		(end 408.86634 -408.81681)
		(width 0.14224)
		(layer "In13.Cu")
		(net "P5E_CPU0_P3_RX_BUF_DP<14>")
	)
	(segment
		(start 415.763964 -420.153084)
		(end 415.201862 -419.590982)
		(width 0.14224)
		(layer "In13.Cu")
		(net "P5E_CPU0_P3_RX_BUF_DP<14>")
	)
	(segment
		(start 413.149542 -413.956754)
		(end 413.077914 -413.927036)
		(width 0.14224)
		(layer "In13.Cu")
		(net "P5E_CPU0_P3_RX_BUF_DP<14>")
	)
	(segment
		(start 402.352256 -406.073102)
		(end 401.310094 -405.91867)
		(width 0.14224)
		(layer "In13.Cu")
		(net "P5E_CPU0_P3_RX_BUF_DP<14>")
	)
	(segment
		(start 414.799526 -422.37914)
		(end 415.25063 -422.228772)
		(width 0.14224)
		(layer "In13.Cu")
		(net "P5E_CPU0_P3_RX_BUF_DP<14>")
	)
	(segment
		(start 410.058362 -433.610766)
		(end 410.058362 -424.601894)
		(width 0.14224)
		(layer "In13.Cu")
		(net "P5E_CPU0_P3_RX_BUF_DP<14>")
	)
	(segment
		(start 414.352232 -418.627306)
		(end 414.352232 -417.764976)
		(width 0.14224)
		(layer "In13.Cu")
		(net "P5E_CPU0_P3_RX_BUF_DP<14>")
	)
	(segment
		(start 401.194524 -405.76246)
		(end 400.772122 -405.699976)
		(width 0.14224)
		(layer "In13.Cu")
		(net "P5E_CPU0_P3_RX_BUF_DP<14>")
	)
	(segment
		(start 411.73019 -410.772102)
		(end 410.205682 -409.597098)
		(width 0.14224)
		(layer "In13.Cu")
		(net "P5E_CPU0_P3_RX_BUF_DP<14>")
	)
	(segment
		(start 405.363172 -406.772872)
		(end 405.183594 -406.846024)
		(width 0.14224)
		(layer "In13.Cu")
		(net "P5E_CPU0_P3_RX_BUF_DP<14>")
	)
	(segment
		(start 396.302738 -405.036274)
		(end 396.147036 -405.151844)
		(width 0.14224)
		(layer "In13.Cu")
		(net "P5E_CPU0_P3_RX_BUF_DP<14>")
	)
	(segment
		(start 398.340072 -405.338788)
		(end 398.184116 -405.454358)
		(width 0.14224)
		(layer "In13.Cu")
		(net "P5E_CPU0_P3_RX_BUF_DP<14>")
	)
	(segment
		(start 413.796988 -422.713404)
		(end 414.20161 -422.57853)
		(width 0.14224)
		(layer "In13.Cu")
		(net "P5E_CPU0_P3_RX_BUF_DP<14>")
	)
	(segment
		(start 414.352232 -417.063936)
		(end 414.352232 -416.637216)
		(width 0.14224)
		(layer "In13.Cu")
		(net "P5E_CPU0_P3_RX_BUF_DP<14>")
	)
	(segment
		(start 406.272238 -407.304748)
		(end 405.82977 -407.118566)
		(width 0.14224)
		(layer "In13.Cu")
		(net "P5E_CPU0_P3_RX_BUF_DP<14>")
	)
	(segment
		(start 414.20161 -422.57853)
		(end 414.330134 -422.642792)
		(width 0.14224)
		(layer "In13.Cu")
		(net "P5E_CPU0_P3_RX_BUF_DP<14>")
	)
	(segment
		(start 413.834072 -414.028128)
		(end 413.66186 -413.956754)
		(width 0.14224)
		(layer "In13.Cu")
		(net "P5E_CPU0_P3_RX_BUF_DP<14>")
	)
	(segment
		(start 405.183594 -406.846024)
		(end 403.890226 -406.301448)
		(width 0.14224)
		(layer "In13.Cu")
		(net "P5E_CPU0_P3_RX_BUF_DP<14>")
	)
	(segment
		(start 413.66186 -413.956754)
		(end 413.149542 -413.956754)
		(width 0.14224)
		(layer "In13.Cu")
		(net "P5E_CPU0_P3_RX_BUF_DP<14>")
	)
	(segment
		(start 413.199072 -422.912794)
		(end 413.327596 -422.977056)
		(width 0.14224)
		(layer "In13.Cu")
		(net "P5E_CPU0_P3_RX_BUF_DP<14>")
	)
	(segment
		(start 414.330134 -422.642792)
		(end 414.735264 -422.507918)
		(width 0.14224)
		(layer "In13.Cu")
		(net "P5E_CPU0_P3_RX_BUF_DP<14>")
	)
	(arc
		(start 415.25063 -422.228772)
		(mid 415.709068 -421.891693)
		(end 415.883852 -421.350186)
		(width 0.14224)
		(layer "In13.Cu")
		(net "P5E_CPU0_P3_RX_BUF_DP<14>")
	)
	(arc
		(start 410.058362 -424.601894)
		(mid 410.084306 -424.501554)
		(end 410.155644 -424.42638)
		(width 0.14224)
		(layer "In13.Cu")
		(net "P5E_CPU0_P3_RX_BUF_DP<14>")
	)
	(arc
		(start 415.883852 -420.44239)
		(mid 415.852689 -420.285812)
		(end 415.763964 -420.153084)
		(width 0.14224)
		(layer "In13.Cu")
		(net "P5E_CPU0_P3_RX_BUF_DP<14>")
	)
	(arc
		(start 414.853374 -419.446456)
		(mid 414.688332 -419.336162)
		(end 414.578038 -419.17112)
		(width 0.14224)
		(layer "In13.Cu")
		(net "P5E_CPU0_P3_RX_BUF_DP<14>")
	)
	(arc
		(start 411.448504 -423.618406)
		(mid 411.579378 -423.540039)
		(end 411.713172 -423.466768)
		(width 0.14224)
		(layer "In13.Cu")
		(net "P5E_CPU0_P3_RX_BUF_DP<14>")
	)
	(arc
		(start 387.491986 -403.33422)
		(mid 387.318498 -403.074577)
		(end 387.257544 -402.768308)
		(width 0.14224)
		(layer "In13.Cu")
		(net "P5E_CPU0_P3_RX_BUF_DP<14>")
	)
	(arc
		(start 393.202922 -404.714964)
		(mid 393.153936 -404.707112)
		(end 393.105132 -404.6982)
		(width 0.14224)
		(layer "In13.Cu")
		(net "P5E_CPU0_P3_RX_BUF_DP<14>")
	)
	(arc
		(start 394.596874 -404.873968)
		(mid 394.540041 -404.900881)
		(end 394.47724 -404.90394)
		(width 0.14224)
		(layer "In13.Cu")
		(net "P5E_CPU0_P3_RX_BUF_DP<14>")
	)
	(arc
		(start 387.959346 -403.614382)
		(mid 387.708407 -403.503097)
		(end 387.491986 -403.33422)
		(width 0.14224)
		(layer "In13.Cu")
		(net "P5E_CPU0_P3_RX_BUF_DP<14>")
	)
	(arc
		(start 411.713172 -423.466768)
		(mid 412.0309 -423.31668)
		(end 412.359602 -423.192448)
		(width 0.14224)
		(layer "In13.Cu")
		(net "P5E_CPU0_P3_RX_BUF_DP<14>")
	)
	(arc
		(start 388.54888 -403.792436)
		(mid 388.536482 -403.789569)
		(end 388.524242 -403.786086)
		(width 0.14224)
		(layer "In13.Cu")
		(net "P5E_CPU0_P3_RX_BUF_DP<14>")
	)
	(segment
		(start 385.822444 -399.950686)
		(end 385.822444 -401.105878)
		(width 0.1016)
		(layer "F.Cu")
		(net "P5E_CPU0_P3_RX_BUF_DP<13>")
	)
	(segment
		(start 385.822444 -401.105878)
		(end 386.075682 -401.359116)
		(width 0.1016)
		(layer "F.Cu")
		(net "P5E_CPU0_P3_RX_BUF_DP<13>")
	)
	(segment
		(start 386.377688 -401.359116)
		(end 386.516372 -401.4978)
		(width 0.1016)
		(layer "F.Cu")
		(net "P5E_CPU0_P3_RX_BUF_DP<13>")
	)
	(segment
		(start 386.516372 -401.4978)
		(end 386.516372 -401.674838)
		(width 0.1016)
		(layer "F.Cu")
		(net "P5E_CPU0_P3_RX_BUF_DP<13>")
	)
	(segment
		(start 385.902454 -399.74774)
		(end 385.902454 -399.870676)
		(width 0.1016)
		(layer "F.Cu")
		(net "P5E_CPU0_P3_RX_BUF_DP<13>")
	)
	(segment
		(start 385.902454 -399.870676)
		(end 385.822444 -399.950686)
		(width 0.1016)
		(layer "F.Cu")
		(net "P5E_CPU0_P3_RX_BUF_DP<13>")
	)
	(segment
		(start 386.075682 -401.359116)
		(end 386.377688 -401.359116)
		(width 0.1016)
		(layer "F.Cu")
		(net "P5E_CPU0_P3_RX_BUF_DP<13>")
	)
	(segment
		(start 385.817872 -399.663158)
		(end 385.902454 -399.74774)
		(width 0.1016)
		(layer "F.Cu")
		(net "P5E_CPU0_P3_RX_BUF_DP<13>")
	)
	(segment
		(start 410.770832 -414.028128)
		(end 410.59862 -413.956754)
		(width 0.14224)
		(layer "In13.Cu")
		(net "P5E_CPU0_P3_RX_BUF_DP<13>")
	)
	(segment
		(start 401.196556 -407.260044)
		(end 400.774154 -407.197306)
		(width 0.14224)
		(layer "In13.Cu")
		(net "P5E_CPU0_P3_RX_BUF_DP<13>")
	)
	(segment
		(start 408.208734 -434.74894)
		(end 408.10561 -434.645816)
		(width 0.14224)
		(layer "In13.Cu")
		(net "P5E_CPU0_P3_RX_BUF_DP<13>")
	)
	(segment
		(start 404.69693 -408.507692)
		(end 404.515066 -408.57551)
		(width 0.14224)
		(layer "In13.Cu")
		(net "P5E_CPU0_P3_RX_BUF_DP<13>")
	)
	(segment
		(start 411.288992 -416.77336)
		(end 411.288992 -416.34664)
		(width 0.14224)
		(layer "In13.Cu")
		(net "P5E_CPU0_P3_RX_BUF_DP<13>")
	)
	(segment
		(start 403.280118 -408.009852)
		(end 402.305266 -407.56332)
		(width 0.14224)
		(layer "In13.Cu")
		(net "P5E_CPU0_P3_RX_BUF_DP<13>")
	)
	(segment
		(start 411.426152 -416.20948)
		(end 411.426152 -415.78276)
		(width 0.14224)
		(layer "In13.Cu")
		(net "P5E_CPU0_P3_RX_BUF_DP<13>")
	)
	(segment
		(start 405.085042 -408.685492)
		(end 404.69693 -408.507692)
		(width 0.14224)
		(layer "In13.Cu")
		(net "P5E_CPU0_P3_RX_BUF_DP<13>")
	)
	(segment
		(start 411.156404 -414.4137)
		(end 410.770832 -414.028128)
		(width 0.14224)
		(layer "In13.Cu")
		(net "P5E_CPU0_P3_RX_BUF_DP<13>")
	)
	(segment
		(start 400.774154 -407.197306)
		(end 400.618452 -407.312876)
		(width 0.14224)
		(layer "In13.Cu")
		(net "P5E_CPU0_P3_RX_BUF_DP<13>")
	)
	(segment
		(start 410.086302 -413.956754)
		(end 410.014674 -413.927036)
		(width 0.14224)
		(layer "In13.Cu")
		(net "P5E_CPU0_P3_RX_BUF_DP<13>")
	)
	(segment
		(start 411.288992 -415.6456)
		(end 411.288992 -414.733486)
		(width 0.14224)
		(layer "In13.Cu")
		(net "P5E_CPU0_P3_RX_BUF_DP<13>")
	)
	(segment
		(start 396.915386 -406.763474)
		(end 395.063218 -406.347676)
		(width 0.14224)
		(layer "In13.Cu")
		(net "P5E_CPU0_P3_RX_BUF_DP<13>")
	)
	(segment
		(start 400.196558 -407.250392)
		(end 400.080988 -407.094436)
		(width 0.14224)
		(layer "In13.Cu")
		(net "P5E_CPU0_P3_RX_BUF_DP<13>")
	)
	(segment
		(start 399.502884 -407.147268)
		(end 398.235424 -406.959308)
		(width 0.14224)
		(layer "In13.Cu")
		(net "P5E_CPU0_P3_RX_BUF_DP<13>")
	)
	(segment
		(start 408.882596 -423.872406)
		(end 409.072842 -423.910506)
		(width 0.14224)
		(layer "In13.Cu")
		(net "P5E_CPU0_P3_RX_BUF_DP<13>")
	)
	(segment
		(start 399.658586 -407.031698)
		(end 399.502884 -407.147268)
		(width 0.14224)
		(layer "In13.Cu")
		(net "P5E_CPU0_P3_RX_BUF_DP<13>")
	)
	(segment
		(start 409.998926 -423.141902)
		(end 412.003494 -422.311576)
		(width 0.14224)
		(layer "In13.Cu")
		(net "P5E_CPU0_P3_RX_BUF_DP<13>")
	)
	(segment
		(start 394.542772 -406.09012)
		(end 394.378942 -406.194006)
		(width 0.14224)
		(layer "In13.Cu")
		(net "P5E_CPU0_P3_RX_BUF_DP<13>")
	)
	(segment
		(start 410.59862 -413.956754)
		(end 410.086302 -413.956754)
		(width 0.14224)
		(layer "In13.Cu")
		(net "P5E_CPU0_P3_RX_BUF_DP<13>")
	)
	(segment
		(start 395.063218 -406.347676)
		(end 394.959332 -406.183592)
		(width 0.14224)
		(layer "In13.Cu")
		(net "P5E_CPU0_P3_RX_BUF_DP<13>")
	)
	(segment
		(start 392.307064 -405.728678)
		(end 389.882634 -405.184356)
		(width 0.14224)
		(layer "In13.Cu")
		(net "P5E_CPU0_P3_RX_BUF_DP<13>")
	)
	(segment
		(start 392.471148 -405.624792)
		(end 392.307064 -405.728678)
		(width 0.14224)
		(layer "In13.Cu")
		(net "P5E_CPU0_P3_RX_BUF_DP<13>")
	)
	(segment
		(start 398.119854 -406.803352)
		(end 397.697452 -406.740614)
		(width 0.14224)
		(layer "In13.Cu")
		(net "P5E_CPU0_P3_RX_BUF_DP<13>")
	)
	(segment
		(start 409.757372 -412.210758)
		(end 409.586176 -411.7975)
		(width 0.14224)
		(layer "In13.Cu")
		(net "P5E_CPU0_P3_RX_BUF_DP<13>")
	)
	(segment
		(start 410.014674 -413.927036)
		(end 409.830016 -413.742378)
		(width 0.14224)
		(layer "In13.Cu")
		(net "P5E_CPU0_P3_RX_BUF_DP<13>")
	)
	(segment
		(start 402.305266 -407.56332)
		(end 401.312126 -407.416)
		(width 0.14224)
		(layer "In13.Cu")
		(net "P5E_CPU0_P3_RX_BUF_DP<13>")
	)
	(segment
		(start 400.080988 -407.094436)
		(end 399.658586 -407.031698)
		(width 0.14224)
		(layer "In13.Cu")
		(net "P5E_CPU0_P3_RX_BUF_DP<13>")
	)
	(segment
		(start 409.072842 -423.910506)
		(end 409.427934 -423.67327)
		(width 0.14224)
		(layer "In13.Cu")
		(net "P5E_CPU0_P3_RX_BUF_DP<13>")
	)
	(segment
		(start 409.441396 -411.65272)
		(end 405.540464 -409.045156)
		(width 0.14224)
		(layer "In13.Cu")
		(net "P5E_CPU0_P3_RX_BUF_DP<13>")
	)
	(segment
		(start 411.468062 -419.105842)
		(end 411.288992 -418.67455)
		(width 0.14224)
		(layer "In13.Cu")
		(net "P5E_CPU0_P3_RX_BUF_DP<13>")
	)
	(segment
		(start 408.750008 -434.289962)
		(end 408.750008 -434.62194)
		(width 0.14224)
		(layer "In13.Cu")
		(net "P5E_CPU0_P3_RX_BUF_DP<13>")
	)
	(segment
		(start 411.426152 -417.33724)
		(end 411.426152 -416.91052)
		(width 0.14224)
		(layer "In13.Cu")
		(net "P5E_CPU0_P3_RX_BUF_DP<13>")
	)
	(segment
		(start 386.19684 -401.371562)
		(end 386.389372 -401.371562)
		(width 0.14224)
		(layer "In13.Cu")
		(net "P5E_CPU0_P3_RX_BUF_DP<13>")
	)
	(segment
		(start 397.697452 -406.740614)
		(end 397.54175 -406.856184)
		(width 0.14224)
		(layer "In13.Cu")
		(net "P5E_CPU0_P3_RX_BUF_DP<13>")
	)
	(segment
		(start 392.99134 -405.882602)
		(end 392.887708 -405.718518)
		(width 0.14224)
		(layer "In13.Cu")
		(net "P5E_CPU0_P3_RX_BUF_DP<13>")
	)
	(segment
		(start 409.830016 -413.742378)
		(end 409.757372 -413.566864)
		(width 0.14224)
		(layer "In13.Cu")
		(net "P5E_CPU0_P3_RX_BUF_DP<13>")
	)
	(segment
		(start 398.235424 -406.959308)
		(end 398.119854 -406.803352)
		(width 0.14224)
		(layer "In13.Cu")
		(net "P5E_CPU0_P3_RX_BUF_DP<13>")
	)
	(segment
		(start 386.516372 -401.498562)
		(end 386.516372 -401.674838)
		(width 0.14224)
		(layer "In13.Cu")
		(net "P5E_CPU0_P3_RX_BUF_DP<13>")
	)
	(segment
		(start 411.288992 -414.733486)
		(end 411.156404 -414.4137)
		(width 0.14224)
		(layer "In13.Cu")
		(net "P5E_CPU0_P3_RX_BUF_DP<13>")
	)
	(segment
		(start 408.750008 -434.62194)
		(end 408.623008 -434.74894)
		(width 0.14224)
		(layer "In13.Cu")
		(net "P5E_CPU0_P3_RX_BUF_DP<13>")
	)
	(segment
		(start 412.003494 -422.311576)
		(end 412.155132 -422.235376)
		(width 0.14224)
		(layer "In13.Cu")
		(net "P5E_CPU0_P3_RX_BUF_DP<13>")
	)
	(segment
		(start 408.058366 -434.53177)
		(end 408.058366 -424.730926)
		(width 0.14224)
		(layer "In13.Cu")
		(net "P5E_CPU0_P3_RX_BUF_DP<13>")
	)
	(segment
		(start 386.057394 -401.511008)
		(end 386.19684 -401.371562)
		(width 0.14224)
		(layer "In13.Cu")
		(net "P5E_CPU0_P3_RX_BUF_DP<13>")
	)
	(segment
		(start 411.288992 -418.67455)
		(end 411.288992 -417.4744)
		(width 0.14224)
		(layer "In13.Cu")
		(net "P5E_CPU0_P3_RX_BUF_DP<13>")
	)
	(segment
		(start 412.700724 -420.185088)
		(end 412.084266 -419.56863)
		(width 0.14224)
		(layer "In13.Cu")
		(net "P5E_CPU0_P3_RX_BUF_DP<13>")
	)
	(segment
		(start 405.152606 -408.86761)
		(end 405.085042 -408.685492)
		(width 0.14224)
		(layer "In13.Cu")
		(net "P5E_CPU0_P3_RX_BUF_DP<13>")
	)
	(segment
		(start 412.820612 -421.154606)
		(end 412.820612 -420.474394)
		(width 0.14224)
		(layer "In13.Cu")
		(net "P5E_CPU0_P3_RX_BUF_DP<13>")
	)
	(segment
		(start 392.887708 -405.718518)
		(end 392.471148 -405.624792)
		(width 0.14224)
		(layer "In13.Cu")
		(net "P5E_CPU0_P3_RX_BUF_DP<13>")
	)
	(segment
		(start 409.586176 -411.7975)
		(end 409.441396 -411.65272)
		(width 0.14224)
		(layer "In13.Cu")
		(net "P5E_CPU0_P3_RX_BUF_DP<13>")
	)
	(segment
		(start 405.540464 -409.045156)
		(end 405.152606 -408.86761)
		(width 0.14224)
		(layer "In13.Cu")
		(net "P5E_CPU0_P3_RX_BUF_DP<13>")
	)
	(segment
		(start 411.426152 -415.78276)
		(end 411.288992 -415.6456)
		(width 0.14224)
		(layer "In13.Cu")
		(net "P5E_CPU0_P3_RX_BUF_DP<13>")
	)
	(segment
		(start 389.774938 -405.155908)
		(end 387.302502 -404.4061)
		(width 0.14224)
		(layer "In13.Cu")
		(net "P5E_CPU0_P3_RX_BUF_DP<13>")
	)
	(segment
		(start 411.288992 -417.4744)
		(end 411.426152 -417.33724)
		(width 0.14224)
		(layer "In13.Cu")
		(net "P5E_CPU0_P3_RX_BUF_DP<13>")
	)
	(segment
		(start 404.515066 -408.57551)
		(end 403.917658 -408.301952)
		(width 0.14224)
		(layer "In13.Cu")
		(net "P5E_CPU0_P3_RX_BUF_DP<13>")
	)
	(segment
		(start 411.288992 -416.34664)
		(end 411.426152 -416.20948)
		(width 0.14224)
		(layer "In13.Cu")
		(net "P5E_CPU0_P3_RX_BUF_DP<13>")
	)
	(segment
		(start 412.084266 -419.56863)
		(end 411.822646 -419.460172)
		(width 0.14224)
		(layer "In13.Cu")
		(net "P5E_CPU0_P3_RX_BUF_DP<13>")
	)
	(segment
		(start 408.623008 -434.74894)
		(end 408.208734 -434.74894)
		(width 0.14224)
		(layer "In13.Cu")
		(net "P5E_CPU0_P3_RX_BUF_DP<13>")
	)
	(segment
		(start 409.427934 -423.67327)
		(end 409.466034 -423.483024)
		(width 0.14224)
		(layer "In13.Cu")
		(net "P5E_CPU0_P3_RX_BUF_DP<13>")
	)
	(segment
		(start 397.54175 -406.856184)
		(end 396.915386 -406.763474)
		(width 0.14224)
		(layer "In13.Cu")
		(net "P5E_CPU0_P3_RX_BUF_DP<13>")
	)
	(segment
		(start 403.850094 -408.119834)
		(end 403.461728 -407.942034)
		(width 0.14224)
		(layer "In13.Cu")
		(net "P5E_CPU0_P3_RX_BUF_DP<13>")
	)
	(segment
		(start 401.312126 -407.416)
		(end 401.196556 -407.260044)
		(width 0.14224)
		(layer "In13.Cu")
		(net "P5E_CPU0_P3_RX_BUF_DP<13>")
	)
	(segment
		(start 411.426152 -416.91052)
		(end 411.288992 -416.77336)
		(width 0.14224)
		(layer "In13.Cu")
		(net "P5E_CPU0_P3_RX_BUF_DP<13>")
	)
	(segment
		(start 386.899404 -404.144734)
		(end 386.243068 -403.488398)
		(width 0.14224)
		(layer "In13.Cu")
		(net "P5E_CPU0_P3_RX_BUF_DP<13>")
	)
	(segment
		(start 403.917658 -408.301952)
		(end 403.850094 -408.119834)
		(width 0.14224)
		(layer "In13.Cu")
		(net "P5E_CPU0_P3_RX_BUF_DP<13>")
	)
	(segment
		(start 386.389372 -401.371562)
		(end 386.516372 -401.498562)
		(width 0.14224)
		(layer "In13.Cu")
		(net "P5E_CPU0_P3_RX_BUF_DP<13>")
	)
	(segment
		(start 409.757372 -413.566864)
		(end 409.757372 -412.210758)
		(width 0.14224)
		(layer "In13.Cu")
		(net "P5E_CPU0_P3_RX_BUF_DP<13>")
	)
	(segment
		(start 409.466034 -423.483024)
		(end 409.88742 -423.201592)
		(width 0.14224)
		(layer "In13.Cu")
		(net "P5E_CPU0_P3_RX_BUF_DP<13>")
	)
	(segment
		(start 394.378942 -406.194006)
		(end 392.99134 -405.882602)
		(width 0.14224)
		(layer "In13.Cu")
		(net "P5E_CPU0_P3_RX_BUF_DP<13>")
	)
	(segment
		(start 403.461728 -407.942034)
		(end 403.280118 -408.009852)
		(width 0.14224)
		(layer "In13.Cu")
		(net "P5E_CPU0_P3_RX_BUF_DP<13>")
	)
	(segment
		(start 394.959332 -406.183592)
		(end 394.542772 -406.09012)
		(width 0.14224)
		(layer "In13.Cu")
		(net "P5E_CPU0_P3_RX_BUF_DP<13>")
	)
	(segment
		(start 386.057394 -403.040342)
		(end 386.057394 -401.511008)
		(width 0.14224)
		(layer "In13.Cu")
		(net "P5E_CPU0_P3_RX_BUF_DP<13>")
	)
	(segment
		(start 408.178508 -424.34256)
		(end 408.882596 -423.872406)
		(width 0.14224)
		(layer "In13.Cu")
		(net "P5E_CPU0_P3_RX_BUF_DP<13>")
	)
	(segment
		(start 400.618452 -407.312876)
		(end 400.196558 -407.250392)
		(width 0.14224)
		(layer "In13.Cu")
		(net "P5E_CPU0_P3_RX_BUF_DP<13>")
	)
	(arc
		(start 411.822646 -419.460172)
		(mid 411.610082 -419.318299)
		(end 411.468062 -419.105842)
		(width 0.14224)
		(layer "In13.Cu")
		(net "P5E_CPU0_P3_RX_BUF_DP<13>")
	)
	(arc
		(start 387.302502 -404.4061)
		(mid 387.245102 -404.385615)
		(end 387.18998 -404.359618)
		(width 0.14224)
		(layer "In13.Cu")
		(net "P5E_CPU0_P3_RX_BUF_DP<13>")
	)
	(arc
		(start 386.243068 -403.488398)
		(mid 386.105657 -403.282842)
		(end 386.057394 -403.040342)
		(width 0.14224)
		(layer "In13.Cu")
		(net "P5E_CPU0_P3_RX_BUF_DP<13>")
	)
	(arc
		(start 408.058366 -424.730926)
		(mid 408.06935 -424.585733)
		(end 408.102308 -424.443906)
		(width 0.14224)
		(layer "In13.Cu")
		(net "P5E_CPU0_P3_RX_BUF_DP<13>")
	)
	(arc
		(start 408.102308 -424.443906)
		(mid 408.131735 -424.386711)
		(end 408.178508 -424.34256)
		(width 0.14224)
		(layer "In13.Cu")
		(net "P5E_CPU0_P3_RX_BUF_DP<13>")
	)
	(arc
		(start 412.155132 -422.235376)
		(mid 412.640818 -421.789172)
		(end 412.820612 -421.154606)
		(width 0.14224)
		(layer "In13.Cu")
		(net "P5E_CPU0_P3_RX_BUF_DP<13>")
	)
	(arc
		(start 412.820612 -420.474394)
		(mid 412.789449 -420.317816)
		(end 412.700724 -420.185088)
		(width 0.14224)
		(layer "In13.Cu")
		(net "P5E_CPU0_P3_RX_BUF_DP<13>")
	)
	(arc
		(start 387.18998 -404.359618)
		(mid 387.036705 -404.262976)
		(end 386.899404 -404.144734)
		(width 0.14224)
		(layer "In13.Cu")
		(net "P5E_CPU0_P3_RX_BUF_DP<13>")
	)
	(arc
		(start 389.882634 -405.184356)
		(mid 389.828526 -405.171118)
		(end 389.774938 -405.155908)
		(width 0.14224)
		(layer "In13.Cu")
		(net "P5E_CPU0_P3_RX_BUF_DP<13>")
	)
	(arc
		(start 409.88742 -423.201592)
		(mid 409.941709 -423.169012)
		(end 409.998926 -423.141902)
		(width 0.14224)
		(layer "In13.Cu")
		(net "P5E_CPU0_P3_RX_BUF_DP<13>")
	)
	(arc
		(start 408.10561 -434.645816)
		(mid 408.070648 -434.593491)
		(end 408.058366 -434.53177)
		(width 0.14224)
		(layer "In13.Cu")
		(net "P5E_CPU0_P3_RX_BUF_DP<13>")
	)
	(segment
		(start 385.316476 -401.501102)
		(end 385.316476 -401.674838)
		(width 0.1016)
		(layer "F.Cu")
		(net "P5E_CPU0_P3_RX_BUF_DP<12>")
	)
	(segment
		(start 385.17449 -401.359116)
		(end 385.316476 -401.501102)
		(width 0.1016)
		(layer "F.Cu")
		(net "P5E_CPU0_P3_RX_BUF_DP<12>")
	)
	(segment
		(start 384.86715 -401.359116)
		(end 385.17449 -401.359116)
		(width 0.1016)
		(layer "F.Cu")
		(net "P5E_CPU0_P3_RX_BUF_DP<12>")
	)
	(segment
		(start 384.617976 -399.663158)
		(end 384.702558 -399.74774)
		(width 0.1016)
		(layer "F.Cu")
		(net "P5E_CPU0_P3_RX_BUF_DP<12>")
	)
	(segment
		(start 384.613912 -401.105878)
		(end 384.86715 -401.359116)
		(width 0.1016)
		(layer "F.Cu")
		(net "P5E_CPU0_P3_RX_BUF_DP<12>")
	)
	(segment
		(start 384.613912 -399.959322)
		(end 384.613912 -401.105878)
		(width 0.1016)
		(layer "F.Cu")
		(net "P5E_CPU0_P3_RX_BUF_DP<12>")
	)
	(segment
		(start 384.702558 -399.74774)
		(end 384.702558 -399.870676)
		(width 0.1016)
		(layer "F.Cu")
		(net "P5E_CPU0_P3_RX_BUF_DP<12>")
	)
	(segment
		(start 384.702558 -399.870676)
		(end 384.613912 -399.959322)
		(width 0.1016)
		(layer "F.Cu")
		(net "P5E_CPU0_P3_RX_BUF_DP<12>")
	)
	(segment
		(start 408.225752 -416.730942)
		(end 408.362912 -416.593782)
		(width 0.14224)
		(layer "In13.Cu")
		(net "P5E_CPU0_P3_RX_BUF_DP<12>")
	)
	(segment
		(start 395.460982 -407.667714)
		(end 395.371574 -407.495248)
		(width 0.14224)
		(layer "In13.Cu")
		(net "P5E_CPU0_P3_RX_BUF_DP<12>")
	)
	(segment
		(start 406.05837 -433.543964)
		(end 406.05837 -424.940984)
		(width 0.14224)
		(layer "In13.Cu")
		(net "P5E_CPU0_P3_RX_BUF_DP<12>")
	)
	(segment
		(start 384.857498 -402.682202)
		(end 384.857498 -401.511008)
		(width 0.14224)
		(layer "In13.Cu")
		(net "P5E_CPU0_P3_RX_BUF_DP<12>")
	)
	(segment
		(start 408.225752 -414.806892)
		(end 408.041348 -414.361884)
		(width 0.14224)
		(layer "In13.Cu")
		(net "P5E_CPU0_P3_RX_BUF_DP<12>")
	)
	(segment
		(start 395.97457 -407.829766)
		(end 395.460982 -407.667714)
		(width 0.14224)
		(layer "In13.Cu")
		(net "P5E_CPU0_P3_RX_BUF_DP<12>")
	)
	(segment
		(start 403.751542 -409.600908)
		(end 403.561296 -409.638754)
		(width 0.14224)
		(layer "In13.Cu")
		(net "P5E_CPU0_P3_RX_BUF_DP<12>")
	)
	(segment
		(start 406.694132 -413.566102)
		(end 406.694132 -412.25724)
		(width 0.14224)
		(layer "In13.Cu")
		(net "P5E_CPU0_P3_RX_BUF_DP<12>")
	)
	(segment
		(start 384.857498 -401.511008)
		(end 384.996944 -401.371562)
		(width 0.14224)
		(layer "In13.Cu")
		(net "P5E_CPU0_P3_RX_BUF_DP<12>")
	)
	(segment
		(start 408.149298 -422.94048)
		(end 409.424378 -422.087802)
		(width 0.14224)
		(layer "In13.Cu")
		(net "P5E_CPU0_P3_RX_BUF_DP<12>")
	)
	(segment
		(start 408.041348 -414.361884)
		(end 407.707592 -414.028128)
		(width 0.14224)
		(layer "In13.Cu")
		(net "P5E_CPU0_P3_RX_BUF_DP<12>")
	)
	(segment
		(start 408.362912 -417.294822)
		(end 408.225752 -417.157662)
		(width 0.14224)
		(layer "In13.Cu")
		(net "P5E_CPU0_P3_RX_BUF_DP<12>")
	)
	(segment
		(start 384.968242 -403.219666)
		(end 384.968242 -402.792946)
		(width 0.14224)
		(layer "In13.Cu")
		(net "P5E_CPU0_P3_RX_BUF_DP<12>")
	)
	(segment
		(start 409.126436 -419.612064)
		(end 408.780234 -419.468808)
		(width 0.14224)
		(layer "In13.Cu")
		(net "P5E_CPU0_P3_RX_BUF_DP<12>")
	)
	(segment
		(start 385.17703 -401.371562)
		(end 385.316476 -401.511008)
		(width 0.14224)
		(layer "In13.Cu")
		(net "P5E_CPU0_P3_RX_BUF_DP<12>")
	)
	(segment
		(start 409.757372 -421.497506)
		(end 409.757372 -420.411402)
		(width 0.14224)
		(layer "In13.Cu")
		(net "P5E_CPU0_P3_RX_BUF_DP<12>")
	)
	(segment
		(start 395.371574 -407.495248)
		(end 394.964412 -407.366724)
		(width 0.14224)
		(layer "In13.Cu")
		(net "P5E_CPU0_P3_RX_BUF_DP<12>")
	)
	(segment
		(start 401.796504 -408.987752)
		(end 401.688808 -408.826462)
		(width 0.14224)
		(layer "In13.Cu")
		(net "P5E_CPU0_P3_RX_BUF_DP<12>")
	)
	(segment
		(start 397.263874 -407.946098)
		(end 396.845282 -407.862786)
		(width 0.14224)
		(layer "In13.Cu")
		(net "P5E_CPU0_P3_RX_BUF_DP<12>")
	)
	(segment
		(start 384.968242 -402.792946)
		(end 384.857498 -402.682202)
		(width 0.14224)
		(layer "In13.Cu")
		(net "P5E_CPU0_P3_RX_BUF_DP<12>")
	)
	(segment
		(start 408.451812 -419.140386)
		(end 408.225752 -418.595048)
		(width 0.14224)
		(layer "In13.Cu")
		(net "P5E_CPU0_P3_RX_BUF_DP<12>")
	)
	(segment
		(start 406.623012 -433.748942)
		(end 406.196546 -433.748942)
		(width 0.14224)
		(layer "In13.Cu")
		(net "P5E_CPU0_P3_RX_BUF_DP<12>")
	)
	(segment
		(start 406.750012 -433.289964)
		(end 406.750012 -433.621942)
		(width 0.14224)
		(layer "In13.Cu")
		(net "P5E_CPU0_P3_RX_BUF_DP<12>")
	)
	(segment
		(start 406.951434 -413.927036)
		(end 406.766776 -413.742378)
		(width 0.14224)
		(layer "In13.Cu")
		(net "P5E_CPU0_P3_RX_BUF_DP<12>")
	)
	(segment
		(start 406.750012 -433.621942)
		(end 406.623012 -433.748942)
		(width 0.14224)
		(layer "In13.Cu")
		(net "P5E_CPU0_P3_RX_BUF_DP<12>")
	)
	(segment
		(start 406.076658 -424.81627)
		(end 406.14092 -424.60164)
		(width 0.14224)
		(layer "In13.Cu")
		(net "P5E_CPU0_P3_RX_BUF_DP<12>")
	)
	(segment
		(start 406.200102 -424.490642)
		(end 406.562306 -424.049698)
		(width 0.14224)
		(layer "In13.Cu")
		(net "P5E_CPU0_P3_RX_BUF_DP<12>")
	)
	(segment
		(start 407.707592 -414.028128)
		(end 407.53538 -413.956754)
		(width 0.14224)
		(layer "In13.Cu")
		(net "P5E_CPU0_P3_RX_BUF_DP<12>")
	)
	(segment
		(start 408.111452 -423.130726)
		(end 408.149298 -422.94048)
		(width 0.14224)
		(layer "In13.Cu")
		(net "P5E_CPU0_P3_RX_BUF_DP<12>")
	)
	(segment
		(start 384.857498 -403.448012)
		(end 384.857498 -403.33041)
		(width 0.14224)
		(layer "In13.Cu")
		(net "P5E_CPU0_P3_RX_BUF_DP<12>")
	)
	(segment
		(start 407.53538 -413.956754)
		(end 407.023062 -413.956754)
		(width 0.14224)
		(layer "In13.Cu")
		(net "P5E_CPU0_P3_RX_BUF_DP<12>")
	)
	(segment
		(start 407.566368 -423.33037)
		(end 407.756614 -423.367962)
		(width 0.14224)
		(layer "In13.Cu")
		(net "P5E_CPU0_P3_RX_BUF_DP<12>")
	)
	(segment
		(start 400.582384 -408.606244)
		(end 400.163792 -408.522932)
		(width 0.14224)
		(layer "In13.Cu")
		(net "P5E_CPU0_P3_RX_BUF_DP<12>")
	)
	(segment
		(start 385.316476 -401.511008)
		(end 385.316476 -401.674838)
		(width 0.14224)
		(layer "In13.Cu")
		(net "P5E_CPU0_P3_RX_BUF_DP<12>")
	)
	(segment
		(start 404.68931 -410.227526)
		(end 404.499064 -410.265372)
		(width 0.14224)
		(layer "In13.Cu")
		(net "P5E_CPU0_P3_RX_BUF_DP<12>")
	)
	(segment
		(start 396.845282 -407.862786)
		(end 396.683992 -407.970736)
		(width 0.14224)
		(layer "In13.Cu")
		(net "P5E_CPU0_P3_RX_BUF_DP<12>")
	)
	(segment
		(start 386.155184 -405.024336)
		(end 384.958336 -403.938486)
		(width 0.14224)
		(layer "In13.Cu")
		(net "P5E_CPU0_P3_RX_BUF_DP<12>")
	)
	(segment
		(start 408.225752 -417.157662)
		(end 408.225752 -416.730942)
		(width 0.14224)
		(layer "In13.Cu")
		(net "P5E_CPU0_P3_RX_BUF_DP<12>")
	)
	(segment
		(start 407.756614 -423.367962)
		(end 408.111452 -423.130726)
		(width 0.14224)
		(layer "In13.Cu")
		(net "P5E_CPU0_P3_RX_BUF_DP<12>")
	)
	(segment
		(start 408.225752 -416.029902)
		(end 408.225752 -414.806892)
		(width 0.14224)
		(layer "In13.Cu")
		(net "P5E_CPU0_P3_RX_BUF_DP<12>")
	)
	(segment
		(start 398.370044 -408.166062)
		(end 397.951452 -408.08275)
		(width 0.14224)
		(layer "In13.Cu")
		(net "P5E_CPU0_P3_RX_BUF_DP<12>")
	)
	(segment
		(start 409.63723 -420.121842)
		(end 409.126436 -419.612064)
		(width 0.14224)
		(layer "In13.Cu")
		(net "P5E_CPU0_P3_RX_BUF_DP<12>")
	)
	(segment
		(start 401.108672 -408.850846)
		(end 400.690334 -408.767788)
		(width 0.14224)
		(layer "In13.Cu")
		(net "P5E_CPU0_P3_RX_BUF_DP<12>")
	)
	(segment
		(start 408.362912 -417.721542)
		(end 408.362912 -417.294822)
		(width 0.14224)
		(layer "In13.Cu")
		(net "P5E_CPU0_P3_RX_BUF_DP<12>")
	)
	(segment
		(start 405.082248 -410.655008)
		(end 405.044402 -410.464762)
		(width 0.14224)
		(layer "In13.Cu")
		(net "P5E_CPU0_P3_RX_BUF_DP<12>")
	)
	(segment
		(start 397.951452 -408.08275)
		(end 397.790162 -408.1907)
		(width 0.14224)
		(layer "In13.Cu")
		(net "P5E_CPU0_P3_RX_BUF_DP<12>")
	)
	(segment
		(start 406.574244 -411.967934)
		(end 405.666956 -411.060646)
		(width 0.14224)
		(layer "In13.Cu")
		(net "P5E_CPU0_P3_RX_BUF_DP<12>")
	)
	(segment
		(start 392.931904 -406.868884)
		(end 392.897106 -406.86355)
		(width 0.14224)
		(layer "In13.Cu")
		(net "P5E_CPU0_P3_RX_BUF_DP<12>")
	)
	(segment
		(start 404.14448 -410.02839)
		(end 404.106634 -409.838144)
		(width 0.14224)
		(layer "In13.Cu")
		(net "P5E_CPU0_P3_RX_BUF_DP<12>")
	)
	(segment
		(start 408.362912 -416.167062)
		(end 408.225752 -416.029902)
		(width 0.14224)
		(layer "In13.Cu")
		(net "P5E_CPU0_P3_RX_BUF_DP<12>")
	)
	(segment
		(start 384.996944 -401.371562)
		(end 385.17703 -401.371562)
		(width 0.14224)
		(layer "In13.Cu")
		(net "P5E_CPU0_P3_RX_BUF_DP<12>")
	)
	(segment
		(start 406.196546 -433.748942)
		(end 406.105614 -433.65801)
		(width 0.14224)
		(layer "In13.Cu")
		(net "P5E_CPU0_P3_RX_BUF_DP<12>")
	)
	(segment
		(start 408.225752 -417.858702)
		(end 408.362912 -417.721542)
		(width 0.14224)
		(layer "In13.Cu")
		(net "P5E_CPU0_P3_RX_BUF_DP<12>")
	)
	(segment
		(start 406.562306 -424.049698)
		(end 406.707594 -423.90441)
		(width 0.14224)
		(layer "In13.Cu")
		(net "P5E_CPU0_P3_RX_BUF_DP<12>")
	)
	(segment
		(start 400.690334 -408.767788)
		(end 400.582384 -408.606244)
		(width 0.14224)
		(layer "In13.Cu")
		(net "P5E_CPU0_P3_RX_BUF_DP<12>")
	)
	(segment
		(start 405.044402 -410.464762)
		(end 404.68931 -410.227526)
		(width 0.14224)
		(layer "In13.Cu")
		(net "P5E_CPU0_P3_RX_BUF_DP<12>")
	)
	(segment
		(start 398.477994 -408.327606)
		(end 398.370044 -408.166062)
		(width 0.14224)
		(layer "In13.Cu")
		(net "P5E_CPU0_P3_RX_BUF_DP<12>")
	)
	(segment
		(start 402.606002 -409.148788)
		(end 401.796504 -408.987752)
		(width 0.14224)
		(layer "In13.Cu")
		(net "P5E_CPU0_P3_RX_BUF_DP<12>")
	)
	(segment
		(start 401.269962 -408.74315)
		(end 401.108672 -408.850846)
		(width 0.14224)
		(layer "In13.Cu")
		(net "P5E_CPU0_P3_RX_BUF_DP<12>")
	)
	(segment
		(start 396.683992 -407.970736)
		(end 395.97457 -407.829766)
		(width 0.14224)
		(layer "In13.Cu")
		(net "P5E_CPU0_P3_RX_BUF_DP<12>")
	)
	(segment
		(start 408.225752 -418.595048)
		(end 408.225752 -417.858702)
		(width 0.14224)
		(layer "In13.Cu")
		(net "P5E_CPU0_P3_RX_BUF_DP<12>")
	)
	(segment
		(start 404.106634 -409.838144)
		(end 403.751542 -409.600908)
		(width 0.14224)
		(layer "In13.Cu")
		(net "P5E_CPU0_P3_RX_BUF_DP<12>")
	)
	(segment
		(start 400.002502 -408.630628)
		(end 398.477994 -408.327606)
		(width 0.14224)
		(layer "In13.Cu")
		(net "P5E_CPU0_P3_RX_BUF_DP<12>")
	)
	(segment
		(start 404.499064 -410.265372)
		(end 404.14448 -410.02839)
		(width 0.14224)
		(layer "In13.Cu")
		(net "P5E_CPU0_P3_RX_BUF_DP<12>")
	)
	(segment
		(start 405.569166 -410.980382)
		(end 405.082248 -410.655008)
		(width 0.14224)
		(layer "In13.Cu")
		(net "P5E_CPU0_P3_RX_BUF_DP<12>")
	)
	(segment
		(start 400.163792 -408.522932)
		(end 400.002502 -408.630628)
		(width 0.14224)
		(layer "In13.Cu")
		(net "P5E_CPU0_P3_RX_BUF_DP<12>")
	)
	(segment
		(start 389.805672 -406.160732)
		(end 386.264404 -405.086312)
		(width 0.14224)
		(layer "In13.Cu")
		(net "P5E_CPU0_P3_RX_BUF_DP<12>")
	)
	(segment
		(start 407.023062 -413.956754)
		(end 406.951434 -413.927036)
		(width 0.14224)
		(layer "In13.Cu")
		(net "P5E_CPU0_P3_RX_BUF_DP<12>")
	)
	(segment
		(start 394.792454 -407.456386)
		(end 392.931904 -406.868884)
		(width 0.14224)
		(layer "In13.Cu")
		(net "P5E_CPU0_P3_RX_BUF_DP<12>")
	)
	(segment
		(start 406.707594 -423.90441)
		(end 407.566368 -423.33037)
		(width 0.14224)
		(layer "In13.Cu")
		(net "P5E_CPU0_P3_RX_BUF_DP<12>")
	)
	(segment
		(start 403.561296 -409.638754)
		(end 403.189948 -409.390596)
		(width 0.14224)
		(layer "In13.Cu")
		(net "P5E_CPU0_P3_RX_BUF_DP<12>")
	)
	(segment
		(start 397.371824 -408.107642)
		(end 397.263874 -407.946098)
		(width 0.14224)
		(layer "In13.Cu")
		(net "P5E_CPU0_P3_RX_BUF_DP<12>")
	)
	(segment
		(start 408.362912 -416.593782)
		(end 408.362912 -416.167062)
		(width 0.14224)
		(layer "In13.Cu")
		(net "P5E_CPU0_P3_RX_BUF_DP<12>")
	)
	(segment
		(start 394.964412 -407.366724)
		(end 394.792454 -407.456386)
		(width 0.14224)
		(layer "In13.Cu")
		(net "P5E_CPU0_P3_RX_BUF_DP<12>")
	)
	(segment
		(start 401.688808 -408.826462)
		(end 401.269962 -408.74315)
		(width 0.14224)
		(layer "In13.Cu")
		(net "P5E_CPU0_P3_RX_BUF_DP<12>")
	)
	(segment
		(start 406.766776 -413.742378)
		(end 406.694132 -413.566102)
		(width 0.14224)
		(layer "In13.Cu")
		(net "P5E_CPU0_P3_RX_BUF_DP<12>")
	)
	(segment
		(start 409.424378 -422.087802)
		(end 409.575508 -421.936672)
		(width 0.14224)
		(layer "In13.Cu")
		(net "P5E_CPU0_P3_RX_BUF_DP<12>")
	)
	(segment
		(start 397.790162 -408.1907)
		(end 397.371824 -408.107642)
		(width 0.14224)
		(layer "In13.Cu")
		(net "P5E_CPU0_P3_RX_BUF_DP<12>")
	)
	(segment
		(start 384.857498 -403.33041)
		(end 384.968242 -403.219666)
		(width 0.14224)
		(layer "In13.Cu")
		(net "P5E_CPU0_P3_RX_BUF_DP<12>")
	)
	(arc
		(start 405.666956 -411.060646)
		(mid 405.620029 -411.018117)
		(end 405.569166 -410.980382)
		(width 0.14224)
		(layer "In13.Cu")
		(net "P5E_CPU0_P3_RX_BUF_DP<12>")
	)
	(arc
		(start 392.897106 -406.86355)
		(mid 391.338896 -406.567092)
		(end 389.805672 -406.160732)
		(width 0.14224)
		(layer "In13.Cu")
		(net "P5E_CPU0_P3_RX_BUF_DP<12>")
	)
	(arc
		(start 409.757372 -420.411402)
		(mid 409.72614 -420.254659)
		(end 409.63723 -420.121842)
		(width 0.14224)
		(layer "In13.Cu")
		(net "P5E_CPU0_P3_RX_BUF_DP<12>")
	)
	(arc
		(start 406.694132 -412.25724)
		(mid 406.662969 -412.100662)
		(end 406.574244 -411.967934)
		(width 0.14224)
		(layer "In13.Cu")
		(net "P5E_CPU0_P3_RX_BUF_DP<12>")
	)
	(arc
		(start 386.264404 -405.086312)
		(mid 386.206355 -405.061385)
		(end 386.155184 -405.024336)
		(width 0.14224)
		(layer "In13.Cu")
		(net "P5E_CPU0_P3_RX_BUF_DP<12>")
	)
	(arc
		(start 406.05837 -424.940984)
		(mid 406.062967 -424.87796)
		(end 406.076658 -424.81627)
		(width 0.14224)
		(layer "In13.Cu")
		(net "P5E_CPU0_P3_RX_BUF_DP<12>")
	)
	(arc
		(start 384.958336 -403.938486)
		(mid 384.918167 -403.888517)
		(end 384.895598 -403.828504)
		(width 0.14224)
		(layer "In13.Cu")
		(net "P5E_CPU0_P3_RX_BUF_DP<12>")
	)
	(arc
		(start 403.189948 -409.390596)
		(mid 402.909889 -409.240916)
		(end 402.606002 -409.148788)
		(width 0.14224)
		(layer "In13.Cu")
		(net "P5E_CPU0_P3_RX_BUF_DP<12>")
	)
	(arc
		(start 384.895598 -403.828504)
		(mid 384.867028 -403.639211)
		(end 384.857498 -403.448012)
		(width 0.14224)
		(layer "In13.Cu")
		(net "P5E_CPU0_P3_RX_BUF_DP<12>")
	)
	(arc
		(start 406.14092 -424.60164)
		(mid 406.165001 -424.543204)
		(end 406.200102 -424.490642)
		(width 0.14224)
		(layer "In13.Cu")
		(net "P5E_CPU0_P3_RX_BUF_DP<12>")
	)
	(arc
		(start 408.780234 -419.468808)
		(mid 408.583392 -419.337228)
		(end 408.451812 -419.140386)
		(width 0.14224)
		(layer "In13.Cu")
		(net "P5E_CPU0_P3_RX_BUF_DP<12>")
	)
	(arc
		(start 406.105614 -433.65801)
		(mid 406.070652 -433.605685)
		(end 406.05837 -433.543964)
		(width 0.14224)
		(layer "In13.Cu")
		(net "P5E_CPU0_P3_RX_BUF_DP<12>")
	)
	(arc
		(start 409.575508 -421.936672)
		(mid 409.710086 -421.735167)
		(end 409.757372 -421.497506)
		(width 0.14224)
		(layer "In13.Cu")
		(net "P5E_CPU0_P3_RX_BUF_DP<12>")
	)
	(segment
		(start 383.413762 -399.959322)
		(end 383.413762 -401.105878)
		(width 0.1016)
		(layer "F.Cu")
		(net "P5E_CPU0_P3_RX_BUF_DP<11>")
	)
	(segment
		(start 383.417826 -399.663158)
		(end 383.502408 -399.74774)
		(width 0.1016)
		(layer "F.Cu")
		(net "P5E_CPU0_P3_RX_BUF_DP<11>")
	)
	(segment
		(start 383.502408 -399.870676)
		(end 383.413762 -399.959322)
		(width 0.1016)
		(layer "F.Cu")
		(net "P5E_CPU0_P3_RX_BUF_DP<11>")
	)
	(segment
		(start 383.667 -401.359116)
		(end 383.977642 -401.359116)
		(width 0.1016)
		(layer "F.Cu")
		(net "P5E_CPU0_P3_RX_BUF_DP<11>")
	)
	(segment
		(start 383.977642 -401.359116)
		(end 384.11658 -401.498054)
		(width 0.1016)
		(layer "F.Cu")
		(net "P5E_CPU0_P3_RX_BUF_DP<11>")
	)
	(segment
		(start 383.502408 -399.74774)
		(end 383.502408 -399.870676)
		(width 0.1016)
		(layer "F.Cu")
		(net "P5E_CPU0_P3_RX_BUF_DP<11>")
	)
	(segment
		(start 383.413762 -401.105878)
		(end 383.667 -401.359116)
		(width 0.1016)
		(layer "F.Cu")
		(net "P5E_CPU0_P3_RX_BUF_DP<11>")
	)
	(segment
		(start 384.11658 -401.498054)
		(end 384.11658 -401.674838)
		(width 0.1016)
		(layer "F.Cu")
		(net "P5E_CPU0_P3_RX_BUF_DP<11>")
	)
	(segment
		(start 404.750016 -434.62194)
		(end 404.623016 -434.74894)
		(width 0.14224)
		(layer "In13.Cu")
		(net "P5E_CPU0_P3_RX_BUF_DP<11>")
	)
	(segment
		(start 403.959822 -413.956754)
		(end 403.888194 -413.927036)
		(width 0.14224)
		(layer "In13.Cu")
		(net "P5E_CPU0_P3_RX_BUF_DP<11>")
	)
	(segment
		(start 383.657602 -402.881084)
		(end 383.657602 -401.511008)
		(width 0.14224)
		(layer "In13.Cu")
		(net "P5E_CPU0_P3_RX_BUF_DP<11>")
	)
	(segment
		(start 383.657602 -403.582124)
		(end 383.794762 -403.444964)
		(width 0.14224)
		(layer "In13.Cu")
		(net "P5E_CPU0_P3_RX_BUF_DP<11>")
	)
	(segment
		(start 405.299672 -417.201096)
		(end 405.162512 -417.063936)
		(width 0.14224)
		(layer "In13.Cu")
		(net "P5E_CPU0_P3_RX_BUF_DP<11>")
	)
	(segment
		(start 397.323818 -409.090368)
		(end 396.907258 -408.996896)
		(width 0.14224)
		(layer "In13.Cu")
		(net "P5E_CPU0_P3_RX_BUF_DP<11>")
	)
	(segment
		(start 405.162512 -416.637216)
		(end 405.299672 -416.500056)
		(width 0.14224)
		(layer "In13.Cu")
		(net "P5E_CPU0_P3_RX_BUF_DP<11>")
	)
	(segment
		(start 402.500338 -411.00121)
		(end 402.14804 -410.759402)
		(width 0.14224)
		(layer "In13.Cu")
		(net "P5E_CPU0_P3_RX_BUF_DP<11>")
	)
	(segment
		(start 405.466296 -423.045382)
		(end 405.466296 -422.851326)
		(width 0.14224)
		(layer "In13.Cu")
		(net "P5E_CPU0_P3_RX_BUF_DP<11>")
	)
	(segment
		(start 405.162512 -415.936176)
		(end 405.162512 -414.806892)
		(width 0.14224)
		(layer "In13.Cu")
		(net "P5E_CPU0_P3_RX_BUF_DP<11>")
	)
	(segment
		(start 403.630892 -413.566864)
		(end 403.630892 -412.405576)
		(width 0.14224)
		(layer "In13.Cu")
		(net "P5E_CPU0_P3_RX_BUF_DP<11>")
	)
	(segment
		(start 396.907258 -408.996896)
		(end 396.743428 -409.100782)
		(width 0.14224)
		(layer "In13.Cu")
		(net "P5E_CPU0_P3_RX_BUF_DP<11>")
	)
	(segment
		(start 405.299672 -416.500056)
		(end 405.299672 -416.073336)
		(width 0.14224)
		(layer "In13.Cu")
		(net "P5E_CPU0_P3_RX_BUF_DP<11>")
	)
	(segment
		(start 406.019254 -419.59403)
		(end 405.641556 -419.437312)
		(width 0.14224)
		(layer "In13.Cu")
		(net "P5E_CPU0_P3_RX_BUF_DP<11>")
	)
	(segment
		(start 383.797048 -401.371562)
		(end 383.977134 -401.371562)
		(width 0.14224)
		(layer "In13.Cu")
		(net "P5E_CPU0_P3_RX_BUF_DP<11>")
	)
	(segment
		(start 396.743428 -409.100782)
		(end 396.327122 -409.00731)
		(width 0.14224)
		(layer "In13.Cu")
		(net "P5E_CPU0_P3_RX_BUF_DP<11>")
	)
	(segment
		(start 405.767794 -422.549828)
		(end 405.96185 -422.549828)
		(width 0.14224)
		(layer "In13.Cu")
		(net "P5E_CPU0_P3_RX_BUF_DP<11>")
	)
	(segment
		(start 394.884656 -408.67838)
		(end 385.767326 -405.911812)
		(width 0.14224)
		(layer "In13.Cu")
		(net "P5E_CPU0_P3_RX_BUF_DP<11>")
	)
	(segment
		(start 398.00784 -409.244038)
		(end 397.84401 -409.347924)
		(width 0.14224)
		(layer "In13.Cu")
		(net "P5E_CPU0_P3_RX_BUF_DP<11>")
	)
	(segment
		(start 385.312412 -405.632666)
		(end 383.816606 -404.2791)
		(width 0.14224)
		(layer "In13.Cu")
		(net "P5E_CPU0_P3_RX_BUF_DP<11>")
	)
	(segment
		(start 403.023578 -411.526736)
		(end 402.535644 -411.19171)
		(width 0.14224)
		(layer "In13.Cu")
		(net "P5E_CPU0_P3_RX_BUF_DP<11>")
	)
	(segment
		(start 399.108422 -409.491434)
		(end 398.944592 -409.59532)
		(width 0.14224)
		(layer "In13.Cu")
		(net "P5E_CPU0_P3_RX_BUF_DP<11>")
	)
	(segment
		(start 403.438868 -411.942026)
		(end 403.023578 -411.526736)
		(width 0.14224)
		(layer "In13.Cu")
		(net "P5E_CPU0_P3_RX_BUF_DP<11>")
	)
	(segment
		(start 404.623016 -434.74894)
		(end 404.208742 -434.74894)
		(width 0.14224)
		(layer "In13.Cu")
		(net "P5E_CPU0_P3_RX_BUF_DP<11>")
	)
	(segment
		(start 406.57399 -420.147496)
		(end 406.019254 -419.59403)
		(width 0.14224)
		(layer "In13.Cu")
		(net "P5E_CPU0_P3_RX_BUF_DP<11>")
	)
	(segment
		(start 403.703536 -413.742378)
		(end 403.630892 -413.566864)
		(width 0.14224)
		(layer "In13.Cu")
		(net "P5E_CPU0_P3_RX_BUF_DP<11>")
	)
	(segment
		(start 402.535644 -411.19171)
		(end 402.500338 -411.00121)
		(width 0.14224)
		(layer "In13.Cu")
		(net "P5E_CPU0_P3_RX_BUF_DP<11>")
	)
	(segment
		(start 383.794762 -403.018244)
		(end 383.657602 -402.881084)
		(width 0.14224)
		(layer "In13.Cu")
		(net "P5E_CPU0_P3_RX_BUF_DP<11>")
	)
	(segment
		(start 383.657602 -403.920706)
		(end 383.657602 -403.582124)
		(width 0.14224)
		(layer "In13.Cu")
		(net "P5E_CPU0_P3_RX_BUF_DP<11>")
	)
	(segment
		(start 396.327122 -409.00731)
		(end 396.223236 -408.842972)
		(width 0.14224)
		(layer "In13.Cu")
		(net "P5E_CPU0_P3_RX_BUF_DP<11>")
	)
	(segment
		(start 396.223236 -408.842972)
		(end 395.806676 -408.7495)
		(width 0.14224)
		(layer "In13.Cu")
		(net "P5E_CPU0_P3_RX_BUF_DP<11>")
	)
	(segment
		(start 397.84401 -409.347924)
		(end 397.427704 -409.254452)
		(width 0.14224)
		(layer "In13.Cu")
		(net "P5E_CPU0_P3_RX_BUF_DP<11>")
	)
	(segment
		(start 404.750016 -434.289962)
		(end 404.750016 -434.62194)
		(width 0.14224)
		(layer "In13.Cu")
		(net "P5E_CPU0_P3_RX_BUF_DP<11>")
	)
	(segment
		(start 398.528286 -409.501848)
		(end 398.4244 -409.33751)
		(width 0.14224)
		(layer "In13.Cu")
		(net "P5E_CPU0_P3_RX_BUF_DP<11>")
	)
	(segment
		(start 404.178008 -424.377612)
		(end 404.65756 -423.660062)
		(width 0.14224)
		(layer "In13.Cu")
		(net "P5E_CPU0_P3_RX_BUF_DP<11>")
	)
	(segment
		(start 384.11658 -401.511008)
		(end 384.11658 -401.674838)
		(width 0.14224)
		(layer "In13.Cu")
		(net "P5E_CPU0_P3_RX_BUF_DP<11>")
	)
	(segment
		(start 405.162512 -417.063936)
		(end 405.162512 -416.637216)
		(width 0.14224)
		(layer "In13.Cu")
		(net "P5E_CPU0_P3_RX_BUF_DP<11>")
	)
	(segment
		(start 406.263856 -422.247822)
		(end 406.263856 -422.053766)
		(width 0.14224)
		(layer "In13.Cu")
		(net "P5E_CPU0_P3_RX_BUF_DP<11>")
	)
	(segment
		(start 383.977134 -401.371562)
		(end 384.11658 -401.511008)
		(width 0.14224)
		(layer "In13.Cu")
		(net "P5E_CPU0_P3_RX_BUF_DP<11>")
	)
	(segment
		(start 404.058374 -434.598572)
		(end 404.058374 -424.77182)
		(width 0.14224)
		(layer "In13.Cu")
		(net "P5E_CPU0_P3_RX_BUF_DP<11>")
	)
	(segment
		(start 404.978108 -414.361884)
		(end 404.644352 -414.028128)
		(width 0.14224)
		(layer "In13.Cu")
		(net "P5E_CPU0_P3_RX_BUF_DP<11>")
	)
	(segment
		(start 399.629376 -409.749752)
		(end 399.628868 -409.74899)
		(width 0.14224)
		(layer "In13.Cu")
		(net "P5E_CPU0_P3_RX_BUF_DP<11>")
	)
	(segment
		(start 405.162512 -417.764976)
		(end 405.299672 -417.627816)
		(width 0.14224)
		(layer "In13.Cu")
		(net "P5E_CPU0_P3_RX_BUF_DP<11>")
	)
	(segment
		(start 398.944592 -409.59532)
		(end 398.528286 -409.501848)
		(width 0.14224)
		(layer "In13.Cu")
		(net "P5E_CPU0_P3_RX_BUF_DP<11>")
	)
	(segment
		(start 405.37003 -419.165786)
		(end 405.162512 -418.665914)
		(width 0.14224)
		(layer "In13.Cu")
		(net "P5E_CPU0_P3_RX_BUF_DP<11>")
	)
	(segment
		(start 404.970234 -423.347388)
		(end 405.16429 -423.347388)
		(width 0.14224)
		(layer "In13.Cu")
		(net "P5E_CPU0_P3_RX_BUF_DP<11>")
	)
	(segment
		(start 383.794762 -403.444964)
		(end 383.794762 -403.018244)
		(width 0.14224)
		(layer "In13.Cu")
		(net "P5E_CPU0_P3_RX_BUF_DP<11>")
	)
	(segment
		(start 405.299672 -416.073336)
		(end 405.162512 -415.936176)
		(width 0.14224)
		(layer "In13.Cu")
		(net "P5E_CPU0_P3_RX_BUF_DP<11>")
	)
	(segment
		(start 399.524982 -409.584906)
		(end 399.108422 -409.491434)
		(width 0.14224)
		(layer "In13.Cu")
		(net "P5E_CPU0_P3_RX_BUF_DP<11>")
	)
	(segment
		(start 404.65756 -423.660062)
		(end 404.970234 -423.347388)
		(width 0.14224)
		(layer "In13.Cu")
		(net "P5E_CPU0_P3_RX_BUF_DP<11>")
	)
	(segment
		(start 400.281394 -409.89631)
		(end 399.629376 -409.749752)
		(width 0.14224)
		(layer "In13.Cu")
		(net "P5E_CPU0_P3_RX_BUF_DP<11>")
	)
	(segment
		(start 405.16429 -423.347388)
		(end 405.466296 -423.045382)
		(width 0.14224)
		(layer "In13.Cu")
		(net "P5E_CPU0_P3_RX_BUF_DP<11>")
	)
	(segment
		(start 383.657602 -401.511008)
		(end 383.797048 -401.371562)
		(width 0.14224)
		(layer "In13.Cu")
		(net "P5E_CPU0_P3_RX_BUF_DP<11>")
	)
	(segment
		(start 405.162512 -418.665914)
		(end 405.162512 -417.764976)
		(width 0.14224)
		(layer "In13.Cu")
		(net "P5E_CPU0_P3_RX_BUF_DP<11>")
	)
	(segment
		(start 405.299672 -417.627816)
		(end 405.299672 -417.201096)
		(width 0.14224)
		(layer "In13.Cu")
		(net "P5E_CPU0_P3_RX_BUF_DP<11>")
	)
	(segment
		(start 401.95754 -410.794708)
		(end 401.289774 -410.336492)
		(width 0.14224)
		(layer "In13.Cu")
		(net "P5E_CPU0_P3_RX_BUF_DP<11>")
	)
	(segment
		(start 397.427704 -409.254452)
		(end 397.323818 -409.090368)
		(width 0.14224)
		(layer "In13.Cu")
		(net "P5E_CPU0_P3_RX_BUF_DP<11>")
	)
	(segment
		(start 401.289774 -410.336492)
		(end 400.281394 -409.89631)
		(width 0.14224)
		(layer "In13.Cu")
		(net "P5E_CPU0_P3_RX_BUF_DP<11>")
	)
	(segment
		(start 404.644352 -414.028128)
		(end 404.47214 -413.956754)
		(width 0.14224)
		(layer "In13.Cu")
		(net "P5E_CPU0_P3_RX_BUF_DP<11>")
	)
	(segment
		(start 404.208742 -434.74894)
		(end 404.058374 -434.598572)
		(width 0.14224)
		(layer "In13.Cu")
		(net "P5E_CPU0_P3_RX_BUF_DP<11>")
	)
	(segment
		(start 405.96185 -422.549828)
		(end 406.263856 -422.247822)
		(width 0.14224)
		(layer "In13.Cu")
		(net "P5E_CPU0_P3_RX_BUF_DP<11>")
	)
	(segment
		(start 405.466296 -422.851326)
		(end 405.767794 -422.549828)
		(width 0.14224)
		(layer "In13.Cu")
		(net "P5E_CPU0_P3_RX_BUF_DP<11>")
	)
	(segment
		(start 398.4244 -409.33751)
		(end 398.00784 -409.244038)
		(width 0.14224)
		(layer "In13.Cu")
		(net "P5E_CPU0_P3_RX_BUF_DP<11>")
	)
	(segment
		(start 395.806676 -408.7495)
		(end 395.642846 -408.853386)
		(width 0.14224)
		(layer "In13.Cu")
		(net "P5E_CPU0_P3_RX_BUF_DP<11>")
	)
	(segment
		(start 399.628868 -409.74899)
		(end 399.524982 -409.584906)
		(width 0.14224)
		(layer "In13.Cu")
		(net "P5E_CPU0_P3_RX_BUF_DP<11>")
	)
	(segment
		(start 402.14804 -410.759402)
		(end 401.95754 -410.794708)
		(width 0.14224)
		(layer "In13.Cu")
		(net "P5E_CPU0_P3_RX_BUF_DP<11>")
	)
	(segment
		(start 395.642846 -408.853386)
		(end 395.007084 -408.710638)
		(width 0.14224)
		(layer "In13.Cu")
		(net "P5E_CPU0_P3_RX_BUF_DP<11>")
	)
	(segment
		(start 406.263856 -422.053766)
		(end 406.694132 -421.62349)
		(width 0.14224)
		(layer "In13.Cu")
		(net "P5E_CPU0_P3_RX_BUF_DP<11>")
	)
	(segment
		(start 406.694132 -421.62349)
		(end 406.694132 -420.437056)
		(width 0.14224)
		(layer "In13.Cu")
		(net "P5E_CPU0_P3_RX_BUF_DP<11>")
	)
	(segment
		(start 403.888194 -413.927036)
		(end 403.703536 -413.742378)
		(width 0.14224)
		(layer "In13.Cu")
		(net "P5E_CPU0_P3_RX_BUF_DP<11>")
	)
	(segment
		(start 405.162512 -414.806892)
		(end 404.978108 -414.361884)
		(width 0.14224)
		(layer "In13.Cu")
		(net "P5E_CPU0_P3_RX_BUF_DP<11>")
	)
	(segment
		(start 404.47214 -413.956754)
		(end 403.959822 -413.956754)
		(width 0.14224)
		(layer "In13.Cu")
		(net "P5E_CPU0_P3_RX_BUF_DP<11>")
	)
	(arc
		(start 385.767326 -405.911812)
		(mid 385.707491 -405.890762)
		(end 385.649724 -405.864568)
		(width 0.14224)
		(layer "In13.Cu")
		(net "P5E_CPU0_P3_RX_BUF_DP<11>")
	)
	(arc
		(start 406.694132 -420.437056)
		(mid 406.6629 -420.280313)
		(end 406.57399 -420.147496)
		(width 0.14224)
		(layer "In13.Cu")
		(net "P5E_CPU0_P3_RX_BUF_DP<11>")
	)
	(arc
		(start 385.649724 -405.864568)
		(mid 385.473293 -405.759926)
		(end 385.312412 -405.632666)
		(width 0.14224)
		(layer "In13.Cu")
		(net "P5E_CPU0_P3_RX_BUF_DP<11>")
	)
	(arc
		(start 405.641556 -419.437312)
		(mid 405.478809 -419.328533)
		(end 405.37003 -419.165786)
		(width 0.14224)
		(layer "In13.Cu")
		(net "P5E_CPU0_P3_RX_BUF_DP<11>")
	)
	(arc
		(start 383.816606 -404.2791)
		(mid 383.699126 -404.11675)
		(end 383.657602 -403.920706)
		(width 0.14224)
		(layer "In13.Cu")
		(net "P5E_CPU0_P3_RX_BUF_DP<11>")
	)
	(arc
		(start 403.630892 -412.405576)
		(mid 403.580989 -412.154699)
		(end 403.438868 -411.942026)
		(width 0.14224)
		(layer "In13.Cu")
		(net "P5E_CPU0_P3_RX_BUF_DP<11>")
	)
	(arc
		(start 395.007084 -408.710638)
		(mid 394.945573 -408.695635)
		(end 394.884656 -408.67838)
		(width 0.14224)
		(layer "In13.Cu")
		(net "P5E_CPU0_P3_RX_BUF_DP<11>")
	)
	(arc
		(start 404.058374 -424.77182)
		(mid 404.088936 -424.565836)
		(end 404.178008 -424.377612)
		(width 0.14224)
		(layer "In13.Cu")
		(net "P5E_CPU0_P3_RX_BUF_DP<11>")
	)
	(segment
		(start 382.916684 -401.498054)
		(end 382.777746 -401.359116)
		(width 0.1016)
		(layer "F.Cu")
		(net "P5E_CPU0_P3_RX_BUF_DP<10>")
	)
	(segment
		(start 382.467104 -401.359116)
		(end 382.213866 -401.105878)
		(width 0.1016)
		(layer "F.Cu")
		(net "P5E_CPU0_P3_RX_BUF_DP<10>")
	)
	(segment
		(start 382.213866 -401.105878)
		(end 382.213866 -399.959322)
		(width 0.1016)
		(layer "F.Cu")
		(net "P5E_CPU0_P3_RX_BUF_DP<10>")
	)
	(segment
		(start 382.302004 -399.747232)
		(end 382.21793 -399.663158)
		(width 0.1016)
		(layer "F.Cu")
		(net "P5E_CPU0_P3_RX_BUF_DP<10>")
	)
	(segment
		(start 382.916684 -401.674838)
		(end 382.916684 -401.498054)
		(width 0.1016)
		(layer "F.Cu")
		(net "P5E_CPU0_P3_RX_BUF_DP<10>")
	)
	(segment
		(start 382.777746 -401.359116)
		(end 382.467104 -401.359116)
		(width 0.1016)
		(layer "F.Cu")
		(net "P5E_CPU0_P3_RX_BUF_DP<10>")
	)
	(segment
		(start 382.213866 -399.959322)
		(end 382.302004 -399.871184)
		(width 0.1016)
		(layer "F.Cu")
		(net "P5E_CPU0_P3_RX_BUF_DP<10>")
	)
	(segment
		(start 382.302004 -399.871184)
		(end 382.302004 -399.747232)
		(width 0.1016)
		(layer "F.Cu")
		(net "P5E_CPU0_P3_RX_BUF_DP<10>")
	)
	(segment
		(start 394.435838 -409.69565)
		(end 394.344398 -409.524454)
		(width 0.14224)
		(layer "In13.Cu")
		(net "P5E_CPU0_P3_RX_BUF_DP<10>")
	)
	(segment
		(start 401.581112 -414.028128)
		(end 401.4089 -413.956754)
		(width 0.14224)
		(layer "In13.Cu")
		(net "P5E_CPU0_P3_RX_BUF_DP<10>")
	)
	(segment
		(start 397.002508 -410.47416)
		(end 396.59433 -410.350462)
		(width 0.14224)
		(layer "In13.Cu")
		(net "P5E_CPU0_P3_RX_BUF_DP<10>")
	)
	(segment
		(start 392.85672 -409.073096)
		(end 392.685524 -409.164536)
		(width 0.14224)
		(layer "In13.Cu")
		(net "P5E_CPU0_P3_RX_BUF_DP<10>")
	)
	(segment
		(start 402.75002 -433.289964)
		(end 402.75002 -433.621942)
		(width 0.14224)
		(layer "In13.Cu")
		(net "P5E_CPU0_P3_RX_BUF_DP<10>")
	)
	(segment
		(start 402.909532 -419.574726)
		(end 402.751036 -419.509448)
		(width 0.14224)
		(layer "In13.Cu")
		(net "P5E_CPU0_P3_RX_BUF_DP<10>")
	)
	(segment
		(start 395.923262 -410.146754)
		(end 395.515084 -410.023056)
		(width 0.14224)
		(layer "In13.Cu")
		(net "P5E_CPU0_P3_RX_BUF_DP<10>")
	)
	(segment
		(start 384.472942 -406.275794)
		(end 382.527302 -404.330154)
		(width 0.14224)
		(layer "In13.Cu")
		(net "P5E_CPU0_P3_RX_BUF_DP<10>")
	)
	(segment
		(start 393.265152 -409.197048)
		(end 392.85672 -409.073096)
		(width 0.14224)
		(layer "In13.Cu")
		(net "P5E_CPU0_P3_RX_BUF_DP<10>")
	)
	(segment
		(start 402.099272 -417.082224)
		(end 402.099272 -416.655504)
		(width 0.14224)
		(layer "In13.Cu")
		(net "P5E_CPU0_P3_RX_BUF_DP<10>")
	)
	(segment
		(start 399.53184 -411.24124)
		(end 397.673576 -410.677868)
		(width 0.14224)
		(layer "In13.Cu")
		(net "P5E_CPU0_P3_RX_BUF_DP<10>")
	)
	(segment
		(start 402.377656 -424.020996)
		(end 402.567902 -423.98315)
		(width 0.14224)
		(layer "In13.Cu")
		(net "P5E_CPU0_P3_RX_BUF_DP<10>")
	)
	(segment
		(start 382.916684 -401.511008)
		(end 382.916684 -401.674838)
		(width 0.14224)
		(layer "In13.Cu")
		(net "P5E_CPU0_P3_RX_BUF_DP<10>")
	)
	(segment
		(start 401.914868 -414.361884)
		(end 401.581112 -414.028128)
		(width 0.14224)
		(layer "In13.Cu")
		(net "P5E_CPU0_P3_RX_BUF_DP<10>")
	)
	(segment
		(start 400.501612 -412.235142)
		(end 400.166078 -411.718252)
		(width 0.14224)
		(layer "In13.Cu")
		(net "P5E_CPU0_P3_RX_BUF_DP<10>")
	)
	(segment
		(start 403.630892 -422.14546)
		(end 403.630892 -420.465504)
		(width 0.14224)
		(layer "In13.Cu")
		(net "P5E_CPU0_P3_RX_BUF_DP<10>")
	)
	(segment
		(start 395.423644 -409.85186)
		(end 395.015212 -409.727908)
		(width 0.14224)
		(layer "In13.Cu")
		(net "P5E_CPU0_P3_RX_BUF_DP<10>")
	)
	(segment
		(start 402.62302 -433.748942)
		(end 402.223478 -433.748942)
		(width 0.14224)
		(layer "In13.Cu")
		(net "P5E_CPU0_P3_RX_BUF_DP<10>")
	)
	(segment
		(start 393.935966 -409.400502)
		(end 393.76477 -409.491942)
		(width 0.14224)
		(layer "In13.Cu")
		(net "P5E_CPU0_P3_RX_BUF_DP<10>")
	)
	(segment
		(start 392.685524 -409.164536)
		(end 392.277346 -409.040838)
		(width 0.14224)
		(layer "In13.Cu")
		(net "P5E_CPU0_P3_RX_BUF_DP<10>")
	)
	(segment
		(start 397.582136 -410.506672)
		(end 397.173704 -410.38272)
		(width 0.14224)
		(layer "In13.Cu")
		(net "P5E_CPU0_P3_RX_BUF_DP<10>")
	)
	(segment
		(start 403.004274 -423.083228)
		(end 403.19452 -423.045382)
		(width 0.14224)
		(layer "In13.Cu")
		(net "P5E_CPU0_P3_RX_BUF_DP<10>")
	)
	(segment
		(start 403.19452 -423.045382)
		(end 403.431756 -422.69029)
		(width 0.14224)
		(layer "In13.Cu")
		(net "P5E_CPU0_P3_RX_BUF_DP<10>")
	)
	(segment
		(start 397.673576 -410.677868)
		(end 397.582136 -410.506672)
		(width 0.14224)
		(layer "In13.Cu")
		(net "P5E_CPU0_P3_RX_BUF_DP<10>")
	)
	(segment
		(start 402.567902 -423.98315)
		(end 402.805138 -423.628058)
		(width 0.14224)
		(layer "In13.Cu")
		(net "P5E_CPU0_P3_RX_BUF_DP<10>")
	)
	(segment
		(start 382.597152 -401.371562)
		(end 382.777238 -401.371562)
		(width 0.14224)
		(layer "In13.Cu")
		(net "P5E_CPU0_P3_RX_BUF_DP<10>")
	)
	(segment
		(start 395.515084 -410.023056)
		(end 395.423644 -409.85186)
		(width 0.14224)
		(layer "In13.Cu")
		(net "P5E_CPU0_P3_RX_BUF_DP<10>")
	)
	(segment
		(start 395.015212 -409.727908)
		(end 394.844016 -409.819348)
		(width 0.14224)
		(layer "In13.Cu")
		(net "P5E_CPU0_P3_RX_BUF_DP<10>")
	)
	(segment
		(start 382.457706 -401.511008)
		(end 382.597152 -401.371562)
		(width 0.14224)
		(layer "In13.Cu")
		(net "P5E_CPU0_P3_RX_BUF_DP<10>")
	)
	(segment
		(start 392.277346 -409.040838)
		(end 391.959338 -408.77998)
		(width 0.14224)
		(layer "In13.Cu")
		(net "P5E_CPU0_P3_RX_BUF_DP<10>")
	)
	(segment
		(start 384.685286 -406.451308)
		(end 384.567684 -406.35936)
		(width 0.14224)
		(layer "In13.Cu")
		(net "P5E_CPU0_P3_RX_BUF_DP<10>")
	)
	(segment
		(start 401.4089 -413.956754)
		(end 400.896582 -413.956754)
		(width 0.14224)
		(layer "In13.Cu")
		(net "P5E_CPU0_P3_RX_BUF_DP<10>")
	)
	(segment
		(start 403.39391 -422.500044)
		(end 403.630892 -422.14546)
		(width 0.14224)
		(layer "In13.Cu")
		(net "P5E_CPU0_P3_RX_BUF_DP<10>")
	)
	(segment
		(start 402.099272 -417.783264)
		(end 402.236432 -417.646104)
		(width 0.14224)
		(layer "In13.Cu")
		(net "P5E_CPU0_P3_RX_BUF_DP<10>")
	)
	(segment
		(start 402.236432 -416.518344)
		(end 402.236432 -416.091624)
		(width 0.14224)
		(layer "In13.Cu")
		(net "P5E_CPU0_P3_RX_BUF_DP<10>")
	)
	(segment
		(start 382.594866 -403.583902)
		(end 382.594866 -403.157182)
		(width 0.14224)
		(layer "In13.Cu")
		(net "P5E_CPU0_P3_RX_BUF_DP<10>")
	)
	(segment
		(start 382.457706 -404.162006)
		(end 382.457706 -403.721062)
		(width 0.14224)
		(layer "In13.Cu")
		(net "P5E_CPU0_P3_RX_BUF_DP<10>")
	)
	(segment
		(start 382.457706 -403.721062)
		(end 382.594866 -403.583902)
		(width 0.14224)
		(layer "In13.Cu")
		(net "P5E_CPU0_P3_RX_BUF_DP<10>")
	)
	(segment
		(start 402.099272 -416.655504)
		(end 402.236432 -416.518344)
		(width 0.14224)
		(layer "In13.Cu")
		(net "P5E_CPU0_P3_RX_BUF_DP<10>")
	)
	(segment
		(start 400.640296 -413.742378)
		(end 400.567652 -413.566864)
		(width 0.14224)
		(layer "In13.Cu")
		(net "P5E_CPU0_P3_RX_BUF_DP<10>")
	)
	(segment
		(start 382.457706 -403.020022)
		(end 382.457706 -401.511008)
		(width 0.14224)
		(layer "In13.Cu")
		(net "P5E_CPU0_P3_RX_BUF_DP<10>")
	)
	(segment
		(start 402.207476 -418.96538)
		(end 402.099272 -418.704522)
		(width 0.14224)
		(layer "In13.Cu")
		(net "P5E_CPU0_P3_RX_BUF_DP<10>")
	)
	(segment
		(start 402.767292 -423.437812)
		(end 403.004274 -423.083228)
		(width 0.14224)
		(layer "In13.Cu")
		(net "P5E_CPU0_P3_RX_BUF_DP<10>")
	)
	(segment
		(start 402.099272 -414.806892)
		(end 401.914868 -414.361884)
		(width 0.14224)
		(layer "In13.Cu")
		(net "P5E_CPU0_P3_RX_BUF_DP<10>")
	)
	(segment
		(start 396.094458 -410.055314)
		(end 395.923262 -410.146754)
		(width 0.14224)
		(layer "In13.Cu")
		(net "P5E_CPU0_P3_RX_BUF_DP<10>")
	)
	(segment
		(start 382.777238 -401.371562)
		(end 382.916684 -401.511008)
		(width 0.14224)
		(layer "In13.Cu")
		(net "P5E_CPU0_P3_RX_BUF_DP<10>")
	)
	(segment
		(start 382.594866 -403.157182)
		(end 382.457706 -403.020022)
		(width 0.14224)
		(layer "In13.Cu")
		(net "P5E_CPU0_P3_RX_BUF_DP<10>")
	)
	(segment
		(start 400.824954 -413.927036)
		(end 400.640296 -413.742378)
		(width 0.14224)
		(layer "In13.Cu")
		(net "P5E_CPU0_P3_RX_BUF_DP<10>")
	)
	(segment
		(start 396.50289 -410.179266)
		(end 396.094458 -410.055314)
		(width 0.14224)
		(layer "In13.Cu")
		(net "P5E_CPU0_P3_RX_BUF_DP<10>")
	)
	(segment
		(start 403.511004 -420.176198)
		(end 402.909532 -419.574726)
		(width 0.14224)
		(layer "In13.Cu")
		(net "P5E_CPU0_P3_RX_BUF_DP<10>")
	)
	(segment
		(start 393.356592 -409.368244)
		(end 393.265152 -409.197048)
		(width 0.14224)
		(layer "In13.Cu")
		(net "P5E_CPU0_P3_RX_BUF_DP<10>")
	)
	(segment
		(start 402.236432 -417.646104)
		(end 402.236432 -417.219384)
		(width 0.14224)
		(layer "In13.Cu")
		(net "P5E_CPU0_P3_RX_BUF_DP<10>")
	)
	(segment
		(start 393.76477 -409.491942)
		(end 393.356592 -409.368244)
		(width 0.14224)
		(layer "In13.Cu")
		(net "P5E_CPU0_P3_RX_BUF_DP<10>")
	)
	(segment
		(start 402.058378 -424.49877)
		(end 402.377656 -424.020996)
		(width 0.14224)
		(layer "In13.Cu")
		(net "P5E_CPU0_P3_RX_BUF_DP<10>")
	)
	(segment
		(start 402.75002 -433.621942)
		(end 402.62302 -433.748942)
		(width 0.14224)
		(layer "In13.Cu")
		(net "P5E_CPU0_P3_RX_BUF_DP<10>")
	)
	(segment
		(start 396.59433 -410.350462)
		(end 396.50289 -410.179266)
		(width 0.14224)
		(layer "In13.Cu")
		(net "P5E_CPU0_P3_RX_BUF_DP<10>")
	)
	(segment
		(start 397.173704 -410.38272)
		(end 397.002508 -410.47416)
		(width 0.14224)
		(layer "In13.Cu")
		(net "P5E_CPU0_P3_RX_BUF_DP<10>")
	)
	(segment
		(start 402.223478 -433.748942)
		(end 402.058378 -433.583842)
		(width 0.14224)
		(layer "In13.Cu")
		(net "P5E_CPU0_P3_RX_BUF_DP<10>")
	)
	(segment
		(start 402.805138 -423.628058)
		(end 402.767292 -423.437812)
		(width 0.14224)
		(layer "In13.Cu")
		(net "P5E_CPU0_P3_RX_BUF_DP<10>")
	)
	(segment
		(start 402.236432 -417.219384)
		(end 402.099272 -417.082224)
		(width 0.14224)
		(layer "In13.Cu")
		(net "P5E_CPU0_P3_RX_BUF_DP<10>")
	)
	(segment
		(start 402.058378 -433.583842)
		(end 402.058378 -424.49877)
		(width 0.14224)
		(layer "In13.Cu")
		(net "P5E_CPU0_P3_RX_BUF_DP<10>")
	)
	(segment
		(start 400.567652 -413.566864)
		(end 400.567652 -412.4579)
		(width 0.14224)
		(layer "In13.Cu")
		(net "P5E_CPU0_P3_RX_BUF_DP<10>")
	)
	(segment
		(start 402.236432 -416.091624)
		(end 402.099272 -415.954464)
		(width 0.14224)
		(layer "In13.Cu")
		(net "P5E_CPU0_P3_RX_BUF_DP<10>")
	)
	(segment
		(start 403.431756 -422.69029)
		(end 403.39391 -422.500044)
		(width 0.14224)
		(layer "In13.Cu")
		(net "P5E_CPU0_P3_RX_BUF_DP<10>")
	)
	(segment
		(start 400.896582 -413.956754)
		(end 400.824954 -413.927036)
		(width 0.14224)
		(layer "In13.Cu")
		(net "P5E_CPU0_P3_RX_BUF_DP<10>")
	)
	(segment
		(start 394.344398 -409.524454)
		(end 393.935966 -409.400502)
		(width 0.14224)
		(layer "In13.Cu")
		(net "P5E_CPU0_P3_RX_BUF_DP<10>")
	)
	(segment
		(start 402.099272 -415.954464)
		(end 402.099272 -414.806892)
		(width 0.14224)
		(layer "In13.Cu")
		(net "P5E_CPU0_P3_RX_BUF_DP<10>")
	)
	(segment
		(start 402.099272 -418.704522)
		(end 402.099272 -417.783264)
		(width 0.14224)
		(layer "In13.Cu")
		(net "P5E_CPU0_P3_RX_BUF_DP<10>")
	)
	(segment
		(start 391.959338 -408.77998)
		(end 385.2545 -406.746456)
		(width 0.14224)
		(layer "In13.Cu")
		(net "P5E_CPU0_P3_RX_BUF_DP<10>")
	)
	(segment
		(start 394.844016 -409.819348)
		(end 394.435838 -409.69565)
		(width 0.14224)
		(layer "In13.Cu")
		(net "P5E_CPU0_P3_RX_BUF_DP<10>")
	)
	(arc
		(start 382.527302 -404.330154)
		(mid 382.475808 -404.252993)
		(end 382.457706 -404.162006)
		(width 0.14224)
		(layer "In13.Cu")
		(net "P5E_CPU0_P3_RX_BUF_DP<10>")
	)
	(arc
		(start 400.567652 -412.4579)
		(mid 400.550793 -412.34173)
		(end 400.501612 -412.235142)
		(width 0.14224)
		(layer "In13.Cu")
		(net "P5E_CPU0_P3_RX_BUF_DP<10>")
	)
	(arc
		(start 385.2545 -406.746456)
		(mid 384.956255 -406.625186)
		(end 384.685286 -406.451308)
		(width 0.14224)
		(layer "In13.Cu")
		(net "P5E_CPU0_P3_RX_BUF_DP<10>")
	)
	(arc
		(start 400.166078 -411.718252)
		(mid 399.891155 -411.42365)
		(end 399.53184 -411.24124)
		(width 0.14224)
		(layer "In13.Cu")
		(net "P5E_CPU0_P3_RX_BUF_DP<10>")
	)
	(arc
		(start 403.630892 -420.465504)
		(mid 403.599729 -420.308926)
		(end 403.511004 -420.176198)
		(width 0.14224)
		(layer "In13.Cu")
		(net "P5E_CPU0_P3_RX_BUF_DP<10>")
	)
	(arc
		(start 384.567684 -406.35936)
		(mid 384.519027 -406.319034)
		(end 384.472942 -406.275794)
		(width 0.14224)
		(layer "In13.Cu")
		(net "P5E_CPU0_P3_RX_BUF_DP<10>")
	)
	(arc
		(start 402.751036 -419.509448)
		(mid 402.425181 -419.29145)
		(end 402.207476 -418.96538)
		(width 0.14224)
		(layer "In13.Cu")
		(net "P5E_CPU0_P3_RX_BUF_DP<10>")
	)
	(segment
		(start 370.467128 -401.359116)
		(end 370.77777 -401.359116)
		(width 0.1016)
		(layer "F.Cu")
		(net "P5E_CPU0_P3_RX_BUF_DP<0>")
	)
	(segment
		(start 370.217954 -399.663158)
		(end 370.302536 -399.74774)
		(width 0.1016)
		(layer "F.Cu")
		(net "P5E_CPU0_P3_RX_BUF_DP<0>")
	)
	(segment
		(start 370.191538 -401.083526)
		(end 370.467128 -401.359116)
		(width 0.1016)
		(layer "F.Cu")
		(net "P5E_CPU0_P3_RX_BUF_DP<0>")
	)
	(segment
		(start 370.302536 -399.870676)
		(end 370.191538 -399.981674)
		(width 0.1016)
		(layer "F.Cu")
		(net "P5E_CPU0_P3_RX_BUF_DP<0>")
	)
	(segment
		(start 370.191538 -399.981674)
		(end 370.191538 -401.083526)
		(width 0.1016)
		(layer "F.Cu")
		(net "P5E_CPU0_P3_RX_BUF_DP<0>")
	)
	(segment
		(start 370.916454 -401.4978)
		(end 370.916454 -401.674838)
		(width 0.1016)
		(layer "F.Cu")
		(net "P5E_CPU0_P3_RX_BUF_DP<0>")
	)
	(segment
		(start 370.77777 -401.359116)
		(end 370.916454 -401.4978)
		(width 0.1016)
		(layer "F.Cu")
		(net "P5E_CPU0_P3_RX_BUF_DP<0>")
	)
	(segment
		(start 370.302536 -399.74774)
		(end 370.302536 -399.870676)
		(width 0.1016)
		(layer "F.Cu")
		(net "P5E_CPU0_P3_RX_BUF_DP<0>")
	)
	(segment
		(start 370.457476 -405.13)
		(end 370.594636 -404.99284)
		(width 0.14224)
		(layer "In13.Cu")
		(net "P5E_CPU0_P3_RX_BUF_DP<0>")
	)
	(segment
		(start 370.007896 -413.742378)
		(end 369.924584 -413.541464)
		(width 0.14224)
		(layer "In13.Cu")
		(net "P5E_CPU0_P3_RX_BUF_DP<0>")
	)
	(segment
		(start 371.466872 -417.636452)
		(end 371.604032 -417.499292)
		(width 0.14224)
		(layer "In13.Cu")
		(net "P5E_CPU0_P3_RX_BUF_DP<0>")
	)
	(segment
		(start 370.594636 -409.07716)
		(end 370.457476 -408.94)
		(width 0.14224)
		(layer "In13.Cu")
		(net "P5E_CPU0_P3_RX_BUF_DP<0>")
	)
	(segment
		(start 380.680722 -424.89628)
		(end 376.516646 -423.17162)
		(width 0.14224)
		(layer "In13.Cu")
		(net "P5E_CPU0_P3_RX_BUF_DP<0>")
	)
	(segment
		(start 374.305068 -422.18737)
		(end 373.910606 -422.023794)
		(width 0.14224)
		(layer "In13.Cu")
		(net "P5E_CPU0_P3_RX_BUF_DP<0>")
	)
	(segment
		(start 370.594636 -407.24836)
		(end 370.594636 -406.82164)
		(width 0.14224)
		(layer "In13.Cu")
		(net "P5E_CPU0_P3_RX_BUF_DP<0>")
	)
	(segment
		(start 369.965732 -412.260034)
		(end 370.14531 -411.542738)
		(width 0.14224)
		(layer "In13.Cu")
		(net "P5E_CPU0_P3_RX_BUF_DP<0>")
	)
	(segment
		(start 371.604032 -417.499292)
		(end 371.604032 -417.072572)
		(width 0.14224)
		(layer "In13.Cu")
		(net "P5E_CPU0_P3_RX_BUF_DP<0>")
	)
	(segment
		(start 371.356636 -414.5407)
		(end 370.77269 -413.956754)
		(width 0.14224)
		(layer "In13.Cu")
		(net "P5E_CPU0_P3_RX_BUF_DP<0>")
	)
	(segment
		(start 371.604032 -417.072572)
		(end 371.466872 -416.935412)
		(width 0.14224)
		(layer "In13.Cu")
		(net "P5E_CPU0_P3_RX_BUF_DP<0>")
	)
	(segment
		(start 370.594636 -409.50388)
		(end 370.594636 -409.07716)
		(width 0.14224)
		(layer "In13.Cu")
		(net "P5E_CPU0_P3_RX_BUF_DP<0>")
	)
	(segment
		(start 370.457476 -408.94)
		(end 370.457476 -408.51328)
		(width 0.14224)
		(layer "In13.Cu")
		(net "P5E_CPU0_P3_RX_BUF_DP<0>")
	)
	(segment
		(start 369.924584 -413.541464)
		(end 369.924584 -412.466536)
		(width 0.14224)
		(layer "In13.Cu")
		(net "P5E_CPU0_P3_RX_BUF_DP<0>")
	)
	(segment
		(start 373.910606 -422.023794)
		(end 373.734584 -422.096692)
		(width 0.14224)
		(layer "In13.Cu")
		(net "P5E_CPU0_P3_RX_BUF_DP<0>")
	)
	(segment
		(start 370.594636 -407.9494)
		(end 370.457476 -407.81224)
		(width 0.14224)
		(layer "In13.Cu")
		(net "P5E_CPU0_P3_RX_BUF_DP<0>")
	)
	(segment
		(start 371.466872 -415.807652)
		(end 371.466872 -414.806892)
		(width 0.14224)
		(layer "In13.Cu")
		(net "P5E_CPU0_P3_RX_BUF_DP<0>")
	)
	(segment
		(start 370.594636 -403.86508)
		(end 370.594636 -403.43836)
		(width 0.14224)
		(layer "In13.Cu")
		(net "P5E_CPU0_P3_RX_BUF_DP<0>")
	)
	(segment
		(start 370.457476 -403.3012)
		(end 370.457476 -401.511008)
		(width 0.14224)
		(layer "In13.Cu")
		(net "P5E_CPU0_P3_RX_BUF_DP<0>")
	)
	(segment
		(start 381.311912 -433.748942)
		(end 381.09271 -433.52974)
		(width 0.14224)
		(layer "In13.Cu")
		(net "P5E_CPU0_P3_RX_BUF_DP<0>")
	)
	(segment
		(start 371.466872 -416.508692)
		(end 371.604032 -416.371532)
		(width 0.14224)
		(layer "In13.Cu")
		(net "P5E_CPU0_P3_RX_BUF_DP<0>")
	)
	(segment
		(start 370.457476 -409.64104)
		(end 370.594636 -409.50388)
		(width 0.14224)
		(layer "In13.Cu")
		(net "P5E_CPU0_P3_RX_BUF_DP<0>")
	)
	(segment
		(start 371.604032 -415.944812)
		(end 371.466872 -415.807652)
		(width 0.14224)
		(layer "In13.Cu")
		(net "P5E_CPU0_P3_RX_BUF_DP<0>")
	)
	(segment
		(start 370.457476 -407.38552)
		(end 370.594636 -407.24836)
		(width 0.14224)
		(layer "In13.Cu")
		(net "P5E_CPU0_P3_RX_BUF_DP<0>")
	)
	(segment
		(start 381.622808 -433.748942)
		(end 381.311912 -433.748942)
		(width 0.14224)
		(layer "In13.Cu")
		(net "P5E_CPU0_P3_RX_BUF_DP<0>")
	)
	(segment
		(start 375.868692 -422.902888)
		(end 375.474484 -422.73982)
		(width 0.14224)
		(layer "In13.Cu")
		(net "P5E_CPU0_P3_RX_BUF_DP<0>")
	)
	(segment
		(start 376.516646 -423.17162)
		(end 376.442224 -422.992042)
		(width 0.14224)
		(layer "In13.Cu")
		(net "P5E_CPU0_P3_RX_BUF_DP<0>")
	)
	(segment
		(start 373.337074 -421.931846)
		(end 373.097298 -421.734996)
		(width 0.14224)
		(layer "In13.Cu")
		(net "P5E_CPU0_P3_RX_BUF_DP<0>")
	)
	(segment
		(start 374.377966 -422.363392)
		(end 374.305068 -422.18737)
		(width 0.14224)
		(layer "In13.Cu")
		(net "P5E_CPU0_P3_RX_BUF_DP<0>")
	)
	(segment
		(start 370.14531 -411.542738)
		(end 370.311934 -411.44317)
		(width 0.14224)
		(layer "In13.Cu")
		(net "P5E_CPU0_P3_RX_BUF_DP<0>")
	)
	(segment
		(start 370.457476 -408.51328)
		(end 370.594636 -408.37612)
		(width 0.14224)
		(layer "In13.Cu")
		(net "P5E_CPU0_P3_RX_BUF_DP<0>")
	)
	(segment
		(start 371.466872 -416.935412)
		(end 371.466872 -416.508692)
		(width 0.14224)
		(layer "In13.Cu")
		(net "P5E_CPU0_P3_RX_BUF_DP<0>")
	)
	(segment
		(start 370.457476 -404.00224)
		(end 370.594636 -403.86508)
		(width 0.14224)
		(layer "In13.Cu")
		(net "P5E_CPU0_P3_RX_BUF_DP<0>")
	)
	(segment
		(start 370.916454 -401.511008)
		(end 370.916454 -401.674838)
		(width 0.14224)
		(layer "In13.Cu")
		(net "P5E_CPU0_P3_RX_BUF_DP<0>")
	)
	(segment
		(start 370.777008 -401.371562)
		(end 370.916454 -401.511008)
		(width 0.14224)
		(layer "In13.Cu")
		(net "P5E_CPU0_P3_RX_BUF_DP<0>")
	)
	(segment
		(start 376.442224 -422.992042)
		(end 376.047762 -422.82872)
		(width 0.14224)
		(layer "In13.Cu")
		(net "P5E_CPU0_P3_RX_BUF_DP<0>")
	)
	(segment
		(start 372.998492 -421.520874)
		(end 372.998492 -420.49573)
		(width 0.14224)
		(layer "In13.Cu")
		(net "P5E_CPU0_P3_RX_BUF_DP<0>")
	)
	(segment
		(start 370.594636 -405.69388)
		(end 370.457476 -405.55672)
		(width 0.14224)
		(layer "In13.Cu")
		(net "P5E_CPU0_P3_RX_BUF_DP<0>")
	)
	(segment
		(start 371.466872 -418.606732)
		(end 371.466872 -417.636452)
		(width 0.14224)
		(layer "In13.Cu")
		(net "P5E_CPU0_P3_RX_BUF_DP<0>")
	)
	(segment
		(start 372.81866 -420.060882)
		(end 372.373144 -419.61435)
		(width 0.14224)
		(layer "In13.Cu")
		(net "P5E_CPU0_P3_RX_BUF_DP<0>")
	)
	(segment
		(start 369.924584 -412.466536)
		(end 369.965732 -412.260034)
		(width 0.14224)
		(layer "In13.Cu")
		(net "P5E_CPU0_P3_RX_BUF_DP<0>")
	)
	(segment
		(start 370.457476 -405.55672)
		(end 370.457476 -405.13)
		(width 0.14224)
		(layer "In13.Cu")
		(net "P5E_CPU0_P3_RX_BUF_DP<0>")
	)
	(segment
		(start 370.457476 -406.68448)
		(end 370.457476 -406.25776)
		(width 0.14224)
		(layer "In13.Cu")
		(net "P5E_CPU0_P3_RX_BUF_DP<0>")
	)
	(segment
		(start 371.656102 -419.062916)
		(end 371.466872 -418.606732)
		(width 0.14224)
		(layer "In13.Cu")
		(net "P5E_CPU0_P3_RX_BUF_DP<0>")
	)
	(segment
		(start 370.457476 -404.42896)
		(end 370.457476 -404.00224)
		(width 0.14224)
		(layer "In13.Cu")
		(net "P5E_CPU0_P3_RX_BUF_DP<0>")
	)
	(segment
		(start 371.466872 -414.806892)
		(end 371.356636 -414.5407)
		(width 0.14224)
		(layer "In13.Cu")
		(net "P5E_CPU0_P3_RX_BUF_DP<0>")
	)
	(segment
		(start 373.097298 -421.734996)
		(end 373.03583 -421.643302)
		(width 0.14224)
		(layer "In13.Cu")
		(net "P5E_CPU0_P3_RX_BUF_DP<0>")
	)
	(segment
		(start 381.749808 -433.289964)
		(end 381.749808 -433.621942)
		(width 0.14224)
		(layer "In13.Cu")
		(net "P5E_CPU0_P3_RX_BUF_DP<0>")
	)
	(segment
		(start 370.415566 -411.028896)
		(end 370.315998 -410.862526)
		(width 0.14224)
		(layer "In13.Cu")
		(net "P5E_CPU0_P3_RX_BUF_DP<0>")
	)
	(segment
		(start 370.457476 -401.511008)
		(end 370.596922 -401.371562)
		(width 0.14224)
		(layer "In13.Cu")
		(net "P5E_CPU0_P3_RX_BUF_DP<0>")
	)
	(segment
		(start 370.594636 -403.43836)
		(end 370.457476 -403.3012)
		(width 0.14224)
		(layer "In13.Cu")
		(net "P5E_CPU0_P3_RX_BUF_DP<0>")
	)
	(segment
		(start 370.594636 -406.82164)
		(end 370.457476 -406.68448)
		(width 0.14224)
		(layer "In13.Cu")
		(net "P5E_CPU0_P3_RX_BUF_DP<0>")
	)
	(segment
		(start 370.594636 -406.1206)
		(end 370.594636 -405.69388)
		(width 0.14224)
		(layer "In13.Cu")
		(net "P5E_CPU0_P3_RX_BUF_DP<0>")
	)
	(segment
		(start 373.734584 -422.096692)
		(end 373.337074 -421.931846)
		(width 0.14224)
		(layer "In13.Cu")
		(net "P5E_CPU0_P3_RX_BUF_DP<0>")
	)
	(segment
		(start 381.009652 -425.23918)
		(end 380.903988 -425.080176)
		(width 0.14224)
		(layer "In13.Cu")
		(net "P5E_CPU0_P3_RX_BUF_DP<0>")
	)
	(segment
		(start 370.311934 -411.44317)
		(end 370.415566 -411.028896)
		(width 0.14224)
		(layer "In13.Cu")
		(net "P5E_CPU0_P3_RX_BUF_DP<0>")
	)
	(segment
		(start 381.09271 -433.52974)
		(end 381.09271 -425.51477)
		(width 0.14224)
		(layer "In13.Cu")
		(net "P5E_CPU0_P3_RX_BUF_DP<0>")
	)
	(segment
		(start 375.474484 -422.73982)
		(end 374.77192 -422.526714)
		(width 0.14224)
		(layer "In13.Cu")
		(net "P5E_CPU0_P3_RX_BUF_DP<0>")
	)
	(segment
		(start 370.594636 -404.99284)
		(end 370.594636 -404.56612)
		(width 0.14224)
		(layer "In13.Cu")
		(net "P5E_CPU0_P3_RX_BUF_DP<0>")
	)
	(segment
		(start 370.315998 -410.862526)
		(end 370.457476 -410.296868)
		(width 0.14224)
		(layer "In13.Cu")
		(net "P5E_CPU0_P3_RX_BUF_DP<0>")
	)
	(segment
		(start 370.457476 -407.81224)
		(end 370.457476 -407.38552)
		(width 0.14224)
		(layer "In13.Cu")
		(net "P5E_CPU0_P3_RX_BUF_DP<0>")
	)
	(segment
		(start 370.596922 -401.371562)
		(end 370.777008 -401.371562)
		(width 0.14224)
		(layer "In13.Cu")
		(net "P5E_CPU0_P3_RX_BUF_DP<0>")
	)
	(segment
		(start 370.264182 -413.956754)
		(end 370.192554 -413.927036)
		(width 0.14224)
		(layer "In13.Cu")
		(net "P5E_CPU0_P3_RX_BUF_DP<0>")
	)
	(segment
		(start 370.457476 -406.25776)
		(end 370.594636 -406.1206)
		(width 0.14224)
		(layer "In13.Cu")
		(net "P5E_CPU0_P3_RX_BUF_DP<0>")
	)
	(segment
		(start 376.047762 -422.82872)
		(end 375.868692 -422.902888)
		(width 0.14224)
		(layer "In13.Cu")
		(net "P5E_CPU0_P3_RX_BUF_DP<0>")
	)
	(segment
		(start 372.373144 -419.61435)
		(end 372.09095 -419.497764)
		(width 0.14224)
		(layer "In13.Cu")
		(net "P5E_CPU0_P3_RX_BUF_DP<0>")
	)
	(segment
		(start 370.192554 -413.927036)
		(end 370.007896 -413.742378)
		(width 0.14224)
		(layer "In13.Cu")
		(net "P5E_CPU0_P3_RX_BUF_DP<0>")
	)
	(segment
		(start 370.594636 -404.56612)
		(end 370.457476 -404.42896)
		(width 0.14224)
		(layer "In13.Cu")
		(net "P5E_CPU0_P3_RX_BUF_DP<0>")
	)
	(segment
		(start 370.457476 -410.296868)
		(end 370.457476 -409.64104)
		(width 0.14224)
		(layer "In13.Cu")
		(net "P5E_CPU0_P3_RX_BUF_DP<0>")
	)
	(segment
		(start 374.77192 -422.526714)
		(end 374.377966 -422.363392)
		(width 0.14224)
		(layer "In13.Cu")
		(net "P5E_CPU0_P3_RX_BUF_DP<0>")
	)
	(segment
		(start 381.749808 -433.621942)
		(end 381.622808 -433.748942)
		(width 0.14224)
		(layer "In13.Cu")
		(net "P5E_CPU0_P3_RX_BUF_DP<0>")
	)
	(segment
		(start 370.77269 -413.956754)
		(end 370.264182 -413.956754)
		(width 0.14224)
		(layer "In13.Cu")
		(net "P5E_CPU0_P3_RX_BUF_DP<0>")
	)
	(segment
		(start 370.594636 -408.37612)
		(end 370.594636 -407.9494)
		(width 0.14224)
		(layer "In13.Cu")
		(net "P5E_CPU0_P3_RX_BUF_DP<0>")
	)
	(segment
		(start 371.604032 -416.371532)
		(end 371.604032 -415.944812)
		(width 0.14224)
		(layer "In13.Cu")
		(net "P5E_CPU0_P3_RX_BUF_DP<0>")
	)
	(arc
		(start 373.03583 -421.643302)
		(mid 373.00807 -421.584861)
		(end 372.998492 -421.520874)
		(width 0.14224)
		(layer "In13.Cu")
		(net "P5E_CPU0_P3_RX_BUF_DP<0>")
	)
	(arc
		(start 372.998492 -420.49573)
		(mid 372.951762 -420.260445)
		(end 372.81866 -420.060882)
		(width 0.14224)
		(layer "In13.Cu")
		(net "P5E_CPU0_P3_RX_BUF_DP<0>")
	)
	(arc
		(start 372.09095 -419.497764)
		(mid 371.830325 -419.323541)
		(end 371.656102 -419.062916)
		(width 0.14224)
		(layer "In13.Cu")
		(net "P5E_CPU0_P3_RX_BUF_DP<0>")
	)
	(arc
		(start 381.09271 -425.51477)
		(mid 381.071528 -425.370843)
		(end 381.009652 -425.23918)
		(width 0.14224)
		(layer "In13.Cu")
		(net "P5E_CPU0_P3_RX_BUF_DP<0>")
	)
	(arc
		(start 380.903988 -425.080176)
		(mid 380.80608 -424.971556)
		(end 380.680722 -424.89628)
		(width 0.14224)
		(layer "In13.Cu")
		(net "P5E_CPU0_P3_RX_BUF_DP<0>")
	)
	(segment
		(start 381.575818 -401.143216)
		(end 381.716534 -401.0025)
		(width 0.1016)
		(layer "F.Cu")
		(net "P5E_CPU0_P3_RX_BUF_DN<9>")
	)
	(segment
		(start 381.247396 -401.016216)
		(end 381.374396 -401.143216)
		(width 0.1016)
		(layer "F.Cu")
		(net "P5E_CPU0_P3_RX_BUF_DN<9>")
	)
	(segment
		(start 381.247396 -400.031458)
		(end 381.247396 -401.016216)
		(width 0.1016)
		(layer "F.Cu")
		(net "P5E_CPU0_P3_RX_BUF_DN<9>")
	)
	(segment
		(start 381.318008 -399.143474)
		(end 381.318516 -399.143982)
		(width 0.1016)
		(layer "F.Cu")
		(net "P5E_CPU0_P3_RX_BUF_DN<9>")
	)
	(segment
		(start 381.318516 -399.960338)
		(end 381.247396 -400.031458)
		(width 0.1016)
		(layer "F.Cu")
		(net "P5E_CPU0_P3_RX_BUF_DN<9>")
	)
	(segment
		(start 381.374396 -401.143216)
		(end 381.575818 -401.143216)
		(width 0.1016)
		(layer "F.Cu")
		(net "P5E_CPU0_P3_RX_BUF_DN<9>")
	)
	(segment
		(start 381.318516 -399.143982)
		(end 381.318516 -399.960338)
		(width 0.1016)
		(layer "F.Cu")
		(net "P5E_CPU0_P3_RX_BUF_DN<9>")
	)
	(segment
		(start 381.716534 -401.0025)
		(end 381.716534 -400.811238)
		(width 0.1016)
		(layer "F.Cu")
		(net "P5E_CPU0_P3_RX_BUF_DN<9>")
	)
	(segment
		(start 382.570736 -406.375108)
		(end 382.570482 -406.375108)
		(width 0.14224)
		(layer "In13.Cu")
		(net "P5E_CPU0_P3_RX_BUF_DN<9>")
	)
	(segment
		(start 398.591532 -414.470596)
		(end 398.409414 -414.288478)
		(width 0.14224)
		(layer "In13.Cu")
		(net "P5E_CPU0_P3_RX_BUF_DN<9>")
	)
	(segment
		(start 400.242278 -421.894762)
		(end 400.285712 -421.454326)
		(width 0.14224)
		(layer "In13.Cu")
		(net "P5E_CPU0_P3_RX_BUF_DN<9>")
	)
	(segment
		(start 400.068542 -435.03088)
		(end 399.776442 -434.73878)
		(width 0.14224)
		(layer "In13.Cu")
		(net "P5E_CPU0_P3_RX_BUF_DN<9>")
	)
	(segment
		(start 380.975616 -404.610316)
		(end 380.975616 -401.403566)
		(width 0.14224)
		(layer "In13.Cu")
		(net "P5E_CPU0_P3_RX_BUF_DN<9>")
	)
	(segment
		(start 381.716534 -400.962622)
		(end 381.716534 -400.811238)
		(width 0.14224)
		(layer "In13.Cu")
		(net "P5E_CPU0_P3_RX_BUF_DN<9>")
	)
	(segment
		(start 399.776442 -424.652186)
		(end 399.999962 -423.526966)
		(width 0.14224)
		(layer "In13.Cu")
		(net "P5E_CPU0_P3_RX_BUF_DN<9>")
	)
	(segment
		(start 397.534892 -414.098994)
		(end 397.423132 -413.987234)
		(width 0.14224)
		(layer "In13.Cu")
		(net "P5E_CPU0_P3_RX_BUF_DN<9>")
	)
	(segment
		(start 400.58467 -435.03088)
		(end 400.068542 -435.03088)
		(width 0.14224)
		(layer "In13.Cu")
		(net "P5E_CPU0_P3_RX_BUF_DN<9>")
	)
	(segment
		(start 398.289272 -414.238694)
		(end 397.872204 -414.238694)
		(width 0.14224)
		(layer "In13.Cu")
		(net "P5E_CPU0_P3_RX_BUF_DN<9>")
	)
	(segment
		(start 400.750024 -435.196234)
		(end 400.58467 -435.03088)
		(width 0.14224)
		(layer "In13.Cu")
		(net "P5E_CPU0_P3_RX_BUF_DN<9>")
	)
	(segment
		(start 399.800572 -419.860984)
		(end 399.455386 -419.717982)
		(width 0.14224)
		(layer "In13.Cu")
		(net "P5E_CPU0_P3_RX_BUF_DN<9>")
	)
	(segment
		(start 391.217404 -409.836874)
		(end 383.98831 -407.631646)
		(width 0.14224)
		(layer "In13.Cu")
		(net "P5E_CPU0_P3_RX_BUF_DN<9>")
	)
	(segment
		(start 382.570482 -406.375108)
		(end 381.095504 -404.899876)
		(width 0.14224)
		(layer "In13.Cu")
		(net "P5E_CPU0_P3_RX_BUF_DN<9>")
	)
	(segment
		(start 383.98831 -407.631646)
		(end 383.657094 -407.461466)
		(width 0.14224)
		(layer "In13.Cu")
		(net "P5E_CPU0_P3_RX_BUF_DN<9>")
	)
	(segment
		(start 398.754092 -418.741098)
		(end 398.754092 -414.863026)
		(width 0.14224)
		(layer "In13.Cu")
		(net "P5E_CPU0_P3_RX_BUF_DN<9>")
	)
	(segment
		(start 391.907522 -410.312108)
		(end 391.907522 -410.311854)
		(width 0.14224)
		(layer "In13.Cu")
		(net "P5E_CPU0_P3_RX_BUF_DN<9>")
	)
	(segment
		(start 381.56769 -401.111466)
		(end 381.716534 -400.962622)
		(width 0.14224)
		(layer "In13.Cu")
		(net "P5E_CPU0_P3_RX_BUF_DN<9>")
	)
	(segment
		(start 398.409414 -414.288478)
		(end 398.289272 -414.238694)
		(width 0.14224)
		(layer "In13.Cu")
		(net "P5E_CPU0_P3_RX_BUF_DN<9>")
	)
	(segment
		(start 400.750024 -435.489858)
		(end 400.750024 -435.196234)
		(width 0.14224)
		(layer "In13.Cu")
		(net "P5E_CPU0_P3_RX_BUF_DN<9>")
	)
	(segment
		(start 399.776442 -434.73878)
		(end 399.776442 -424.652186)
		(width 0.14224)
		(layer "In13.Cu")
		(net "P5E_CPU0_P3_RX_BUF_DN<9>")
	)
	(segment
		(start 399.999962 -423.526966)
		(end 400.242278 -421.894762)
		(width 0.14224)
		(layer "In13.Cu")
		(net "P5E_CPU0_P3_RX_BUF_DN<9>")
	)
	(segment
		(start 391.698734 -410.200348)
		(end 391.328148 -409.89631)
		(width 0.14224)
		(layer "In13.Cu")
		(net "P5E_CPU0_P3_RX_BUF_DN<9>")
	)
	(segment
		(start 397.175228 -412.223204)
		(end 396.772638 -411.820614)
		(width 0.14224)
		(layer "In13.Cu")
		(net "P5E_CPU0_P3_RX_BUF_DN<9>")
	)
	(segment
		(start 400.248374 -420.308786)
		(end 399.800572 -419.860984)
		(width 0.14224)
		(layer "In13.Cu")
		(net "P5E_CPU0_P3_RX_BUF_DN<9>")
	)
	(segment
		(start 383.657094 -407.461466)
		(end 382.570736 -406.375108)
		(width 0.14224)
		(layer "In13.Cu")
		(net "P5E_CPU0_P3_RX_BUF_DN<9>")
	)
	(segment
		(start 398.949418 -419.212268)
		(end 398.754092 -418.741098)
		(width 0.14224)
		(layer "In13.Cu")
		(net "P5E_CPU0_P3_RX_BUF_DN<9>")
	)
	(segment
		(start 381.267716 -401.111466)
		(end 381.56769 -401.111466)
		(width 0.14224)
		(layer "In13.Cu")
		(net "P5E_CPU0_P3_RX_BUF_DN<9>")
	)
	(segment
		(start 398.754092 -414.863026)
		(end 398.591532 -414.470596)
		(width 0.14224)
		(layer "In13.Cu")
		(net "P5E_CPU0_P3_RX_BUF_DN<9>")
	)
	(segment
		(start 400.285712 -421.454326)
		(end 400.285712 -420.398702)
		(width 0.14224)
		(layer "In13.Cu")
		(net "P5E_CPU0_P3_RX_BUF_DN<9>")
	)
	(segment
		(start 396.665196 -411.756352)
		(end 391.907522 -410.312108)
		(width 0.14224)
		(layer "In13.Cu")
		(net "P5E_CPU0_P3_RX_BUF_DN<9>")
	)
	(segment
		(start 397.222472 -413.502856)
		(end 397.222472 -412.33725)
		(width 0.14224)
		(layer "In13.Cu")
		(net "P5E_CPU0_P3_RX_BUF_DN<9>")
	)
	(segment
		(start 380.975616 -401.403566)
		(end 381.267716 -401.111466)
		(width 0.14224)
		(layer "In13.Cu")
		(net "P5E_CPU0_P3_RX_BUF_DN<9>")
	)
	(arc
		(start 397.222472 -412.33725)
		(mid 397.210195 -412.275527)
		(end 397.175228 -412.223204)
		(width 0.14224)
		(layer "In13.Cu")
		(net "P5E_CPU0_P3_RX_BUF_DN<9>")
	)
	(arc
		(start 391.907522 -410.311854)
		(mid 391.797647 -410.266368)
		(end 391.698734 -410.200348)
		(width 0.14224)
		(layer "In13.Cu")
		(net "P5E_CPU0_P3_RX_BUF_DN<9>")
	)
	(arc
		(start 397.423132 -413.987234)
		(mid 397.27464 -413.764999)
		(end 397.222472 -413.502856)
		(width 0.14224)
		(layer "In13.Cu")
		(net "P5E_CPU0_P3_RX_BUF_DN<9>")
	)
	(arc
		(start 400.285712 -420.398702)
		(mid 400.27601 -420.350018)
		(end 400.248374 -420.308786)
		(width 0.14224)
		(layer "In13.Cu")
		(net "P5E_CPU0_P3_RX_BUF_DN<9>")
	)
	(arc
		(start 391.328148 -409.89631)
		(mid 391.275704 -409.861134)
		(end 391.217404 -409.836874)
		(width 0.14224)
		(layer "In13.Cu")
		(net "P5E_CPU0_P3_RX_BUF_DN<9>")
	)
	(arc
		(start 399.455386 -419.717982)
		(mid 399.152143 -419.515404)
		(end 398.949418 -419.212268)
		(width 0.14224)
		(layer "In13.Cu")
		(net "P5E_CPU0_P3_RX_BUF_DN<9>")
	)
	(arc
		(start 396.772638 -411.820614)
		(mid 396.722871 -411.781875)
		(end 396.665196 -411.756352)
		(width 0.14224)
		(layer "In13.Cu")
		(net "P5E_CPU0_P3_RX_BUF_DN<9>")
	)
	(arc
		(start 381.095504 -404.899876)
		(mid 381.006789 -404.767011)
		(end 380.975616 -404.610316)
		(width 0.14224)
		(layer "In13.Cu")
		(net "P5E_CPU0_P3_RX_BUF_DN<9>")
	)
	(arc
		(start 397.872204 -414.238694)
		(mid 397.689659 -414.202384)
		(end 397.534892 -414.098994)
		(width 0.14224)
		(layer "In13.Cu")
		(net "P5E_CPU0_P3_RX_BUF_DN<9>")
	)
	(segment
		(start 380.02972 -400.048984)
		(end 380.118366 -399.960338)
		(width 0.1016)
		(layer "F.Cu")
		(net "P5E_CPU0_P3_RX_BUF_DN<8>")
	)
	(segment
		(start 380.516638 -401.002246)
		(end 380.375668 -401.143216)
		(width 0.1016)
		(layer "F.Cu")
		(net "P5E_CPU0_P3_RX_BUF_DN<8>")
	)
	(segment
		(start 380.375668 -401.143216)
		(end 380.15672 -401.143216)
		(width 0.1016)
		(layer "F.Cu")
		(net "P5E_CPU0_P3_RX_BUF_DN<8>")
	)
	(segment
		(start 380.15672 -401.143216)
		(end 380.02972 -401.016216)
		(width 0.1016)
		(layer "F.Cu")
		(net "P5E_CPU0_P3_RX_BUF_DN<8>")
	)
	(segment
		(start 380.118366 -399.960338)
		(end 380.118366 -399.143982)
		(width 0.1016)
		(layer "F.Cu")
		(net "P5E_CPU0_P3_RX_BUF_DN<8>")
	)
	(segment
		(start 380.516638 -400.811238)
		(end 380.516638 -401.002246)
		(width 0.1016)
		(layer "F.Cu")
		(net "P5E_CPU0_P3_RX_BUF_DN<8>")
	)
	(segment
		(start 380.118366 -399.143982)
		(end 380.117858 -399.143474)
		(width 0.1016)
		(layer "F.Cu")
		(net "P5E_CPU0_P3_RX_BUF_DN<8>")
	)
	(segment
		(start 380.02972 -401.016216)
		(end 380.02972 -400.048984)
		(width 0.1016)
		(layer "F.Cu")
		(net "P5E_CPU0_P3_RX_BUF_DN<8>")
	)
	(segment
		(start 395.294866 -414.267142)
		(end 395.226286 -414.238694)
		(width 0.14224)
		(layer "In13.Cu")
		(net "P5E_CPU0_P3_RX_BUF_DN<8>")
	)
	(segment
		(start 392.270996 -411.402022)
		(end 391.621264 -411.26156)
		(width 0.14224)
		(layer "In13.Cu")
		(net "P5E_CPU0_P3_RX_BUF_DN<8>")
	)
	(segment
		(start 395.914372 -419.259258)
		(end 395.690852 -418.72027)
		(width 0.14224)
		(layer "In13.Cu")
		(net "P5E_CPU0_P3_RX_BUF_DN<8>")
	)
	(segment
		(start 390.02716 -410.455364)
		(end 382.955292 -408.31008)
		(width 0.14224)
		(layer "In13.Cu")
		(net "P5E_CPU0_P3_RX_BUF_DN<8>")
	)
	(segment
		(start 398.750028 -434.157882)
		(end 398.623028 -434.030882)
		(width 0.14224)
		(layer "In13.Cu")
		(net "P5E_CPU0_P3_RX_BUF_DN<8>")
	)
	(segment
		(start 394.159232 -413.623252)
		(end 394.159232 -412.292546)
		(width 0.14224)
		(layer "In13.Cu")
		(net "P5E_CPU0_P3_RX_BUF_DN<8>")
	)
	(segment
		(start 398.623028 -434.030882)
		(end 398.093438 -434.030882)
		(width 0.14224)
		(layer "In13.Cu")
		(net "P5E_CPU0_P3_RX_BUF_DN<8>")
	)
	(segment
		(start 391.621264 -411.26156)
		(end 391.36828 -411.16758)
		(width 0.14224)
		(layer "In13.Cu")
		(net "P5E_CPU0_P3_RX_BUF_DN<8>")
	)
	(segment
		(start 382.168146 -407.61793)
		(end 379.895608 -405.345392)
		(width 0.14224)
		(layer "In13.Cu")
		(net "P5E_CPU0_P3_RX_BUF_DN<8>")
	)
	(segment
		(start 397.185134 -420.318438)
		(end 396.720822 -419.854126)
		(width 0.14224)
		(layer "In13.Cu")
		(net "P5E_CPU0_P3_RX_BUF_DN<8>")
	)
	(segment
		(start 395.690852 -418.72027)
		(end 395.690852 -414.863026)
		(width 0.14224)
		(layer "In13.Cu")
		(net "P5E_CPU0_P3_RX_BUF_DN<8>")
	)
	(segment
		(start 379.77572 -401.394168)
		(end 380.080266 -401.089622)
		(width 0.14224)
		(layer "In13.Cu")
		(net "P5E_CPU0_P3_RX_BUF_DN<8>")
	)
	(segment
		(start 390.166098 -410.51353)
		(end 390.02716 -410.455364)
		(width 0.14224)
		(layer "In13.Cu")
		(net "P5E_CPU0_P3_RX_BUF_DN<8>")
	)
	(segment
		(start 397.801338 -425.293282)
		(end 397.222472 -422.383458)
		(width 0.14224)
		(layer "In13.Cu")
		(net "P5E_CPU0_P3_RX_BUF_DN<8>")
	)
	(segment
		(start 394.121894 -412.20263)
		(end 393.823444 -411.90418)
		(width 0.14224)
		(layer "In13.Cu")
		(net "P5E_CPU0_P3_RX_BUF_DN<8>")
	)
	(segment
		(start 380.080266 -401.089622)
		(end 380.389638 -401.089622)
		(width 0.14224)
		(layer "In13.Cu")
		(net "P5E_CPU0_P3_RX_BUF_DN<8>")
	)
	(segment
		(start 394.274802 -413.902144)
		(end 394.159232 -413.623252)
		(width 0.14224)
		(layer "In13.Cu")
		(net "P5E_CPU0_P3_RX_BUF_DN<8>")
	)
	(segment
		(start 398.750028 -434.48986)
		(end 398.750028 -434.157882)
		(width 0.14224)
		(layer "In13.Cu")
		(net "P5E_CPU0_P3_RX_BUF_DN<8>")
	)
	(segment
		(start 395.226286 -414.238694)
		(end 394.713714 -414.238694)
		(width 0.14224)
		(layer "In13.Cu")
		(net "P5E_CPU0_P3_RX_BUF_DN<8>")
	)
	(segment
		(start 395.690852 -414.863026)
		(end 395.549374 -414.52165)
		(width 0.14224)
		(layer "In13.Cu")
		(net "P5E_CPU0_P3_RX_BUF_DN<8>")
	)
	(segment
		(start 394.538708 -414.16605)
		(end 394.274802 -413.902144)
		(width 0.14224)
		(layer "In13.Cu")
		(net "P5E_CPU0_P3_RX_BUF_DN<8>")
	)
	(segment
		(start 380.516638 -400.962622)
		(end 380.516638 -400.811238)
		(width 0.14224)
		(layer "In13.Cu")
		(net "P5E_CPU0_P3_RX_BUF_DN<8>")
	)
	(segment
		(start 382.1684 -407.61793)
		(end 382.168146 -407.61793)
		(width 0.14224)
		(layer "In13.Cu")
		(net "P5E_CPU0_P3_RX_BUF_DN<8>")
	)
	(segment
		(start 393.78382 -411.880558)
		(end 392.270996 -411.402022)
		(width 0.14224)
		(layer "In13.Cu")
		(net "P5E_CPU0_P3_RX_BUF_DN<8>")
	)
	(segment
		(start 382.719072 -408.168602)
		(end 382.1684 -407.61793)
		(width 0.14224)
		(layer "In13.Cu")
		(net "P5E_CPU0_P3_RX_BUF_DN<8>")
	)
	(segment
		(start 382.955292 -408.31008)
		(end 382.719072 -408.168602)
		(width 0.14224)
		(layer "In13.Cu")
		(net "P5E_CPU0_P3_RX_BUF_DN<8>")
	)
	(segment
		(start 393.823444 -411.90418)
		(end 393.78382 -411.880558)
		(width 0.14224)
		(layer "In13.Cu")
		(net "P5E_CPU0_P3_RX_BUF_DN<8>")
	)
	(segment
		(start 380.389638 -401.089622)
		(end 380.516638 -400.962622)
		(width 0.14224)
		(layer "In13.Cu")
		(net "P5E_CPU0_P3_RX_BUF_DN<8>")
	)
	(segment
		(start 398.093438 -434.030882)
		(end 397.801338 -433.738782)
		(width 0.14224)
		(layer "In13.Cu")
		(net "P5E_CPU0_P3_RX_BUF_DN<8>")
	)
	(segment
		(start 391.36828 -411.16758)
		(end 390.166098 -410.51353)
		(width 0.14224)
		(layer "In13.Cu")
		(net "P5E_CPU0_P3_RX_BUF_DN<8>")
	)
	(segment
		(start 396.720822 -419.854126)
		(end 396.359888 -419.704774)
		(width 0.14224)
		(layer "In13.Cu")
		(net "P5E_CPU0_P3_RX_BUF_DN<8>")
	)
	(segment
		(start 394.713714 -414.238694)
		(end 394.538708 -414.16605)
		(width 0.14224)
		(layer "In13.Cu")
		(net "P5E_CPU0_P3_RX_BUF_DN<8>")
	)
	(segment
		(start 397.801338 -433.738782)
		(end 397.801338 -425.293282)
		(width 0.14224)
		(layer "In13.Cu")
		(net "P5E_CPU0_P3_RX_BUF_DN<8>")
	)
	(segment
		(start 397.222472 -422.383458)
		(end 397.222472 -420.408354)
		(width 0.14224)
		(layer "In13.Cu")
		(net "P5E_CPU0_P3_RX_BUF_DN<8>")
	)
	(segment
		(start 395.549374 -414.52165)
		(end 395.294866 -414.267142)
		(width 0.14224)
		(layer "In13.Cu")
		(net "P5E_CPU0_P3_RX_BUF_DN<8>")
	)
	(segment
		(start 379.77572 -405.055832)
		(end 379.77572 -401.394168)
		(width 0.14224)
		(layer "In13.Cu")
		(net "P5E_CPU0_P3_RX_BUF_DN<8>")
	)
	(arc
		(start 396.359888 -419.704774)
		(mid 396.092854 -419.526292)
		(end 395.914372 -419.259258)
		(width 0.14224)
		(layer "In13.Cu")
		(net "P5E_CPU0_P3_RX_BUF_DN<8>")
	)
	(arc
		(start 394.159232 -412.292546)
		(mid 394.14953 -412.243862)
		(end 394.121894 -412.20263)
		(width 0.14224)
		(layer "In13.Cu")
		(net "P5E_CPU0_P3_RX_BUF_DN<8>")
	)
	(arc
		(start 397.222472 -420.408354)
		(mid 397.21277 -420.35967)
		(end 397.185134 -420.318438)
		(width 0.14224)
		(layer "In13.Cu")
		(net "P5E_CPU0_P3_RX_BUF_DN<8>")
	)
	(arc
		(start 379.895608 -405.345392)
		(mid 379.806893 -405.212527)
		(end 379.77572 -405.055832)
		(width 0.14224)
		(layer "In13.Cu")
		(net "P5E_CPU0_P3_RX_BUF_DN<8>")
	)
	(segment
		(start 378.917962 -399.143474)
		(end 378.91847 -399.143982)
		(width 0.1016)
		(layer "F.Cu")
		(net "P5E_CPU0_P3_RX_BUF_DN<7>")
	)
	(segment
		(start 378.91847 -399.143982)
		(end 378.91847 -399.960338)
		(width 0.1016)
		(layer "F.Cu")
		(net "P5E_CPU0_P3_RX_BUF_DN<7>")
	)
	(segment
		(start 378.956824 -401.143216)
		(end 379.175772 -401.143216)
		(width 0.1016)
		(layer "F.Cu")
		(net "P5E_CPU0_P3_RX_BUF_DN<7>")
	)
	(segment
		(start 378.829824 -400.048984)
		(end 378.829824 -401.016216)
		(width 0.1016)
		(layer "F.Cu")
		(net "P5E_CPU0_P3_RX_BUF_DN<7>")
	)
	(segment
		(start 379.316488 -401.0025)
		(end 379.316488 -400.811238)
		(width 0.1016)
		(layer "F.Cu")
		(net "P5E_CPU0_P3_RX_BUF_DN<7>")
	)
	(segment
		(start 378.91847 -399.960338)
		(end 378.829824 -400.048984)
		(width 0.1016)
		(layer "F.Cu")
		(net "P5E_CPU0_P3_RX_BUF_DN<7>")
	)
	(segment
		(start 378.829824 -401.016216)
		(end 378.956824 -401.143216)
		(width 0.1016)
		(layer "F.Cu")
		(net "P5E_CPU0_P3_RX_BUF_DN<7>")
	)
	(segment
		(start 379.175772 -401.143216)
		(end 379.316488 -401.0025)
		(width 0.1016)
		(layer "F.Cu")
		(net "P5E_CPU0_P3_RX_BUF_DN<7>")
	)
	(segment
		(start 381.743458 -408.75331)
		(end 378.695458 -405.70531)
		(width 0.14224)
		(layer "In13.Cu")
		(net "P5E_CPU0_P3_RX_BUF_DN<7>")
	)
	(segment
		(start 388.848092 -411.21965)
		(end 387.59511 -410.701236)
		(width 0.14224)
		(layer "In13.Cu")
		(net "P5E_CPU0_P3_RX_BUF_DN<7>")
	)
	(segment
		(start 395.74978 -435.489858)
		(end 395.74978 -435.15788)
		(width 0.14224)
		(layer "In13.Cu")
		(net "P5E_CPU0_P3_RX_BUF_DN<7>")
	)
	(segment
		(start 391.050526 -412.277052)
		(end 390.967468 -412.152846)
		(width 0.14224)
		(layer "In13.Cu")
		(net "P5E_CPU0_P3_RX_BUF_DN<7>")
	)
	(segment
		(start 391.650474 -414.238694)
		(end 391.475468 -414.16605)
		(width 0.14224)
		(layer "In13.Cu")
		(net "P5E_CPU0_P3_RX_BUF_DN<7>")
	)
	(segment
		(start 392.486134 -414.52165)
		(end 392.231626 -414.267142)
		(width 0.14224)
		(layer "In13.Cu")
		(net "P5E_CPU0_P3_RX_BUF_DN<7>")
	)
	(segment
		(start 392.163046 -414.238694)
		(end 391.650474 -414.238694)
		(width 0.14224)
		(layer "In13.Cu")
		(net "P5E_CPU0_P3_RX_BUF_DN<7>")
	)
	(segment
		(start 392.627612 -414.863026)
		(end 392.486134 -414.52165)
		(width 0.14224)
		(layer "In13.Cu")
		(net "P5E_CPU0_P3_RX_BUF_DN<7>")
	)
	(segment
		(start 390.500108 -411.76956)
		(end 390.265158 -411.672278)
		(width 0.14224)
		(layer "In13.Cu")
		(net "P5E_CPU0_P3_RX_BUF_DN<7>")
	)
	(segment
		(start 394.121894 -420.343838)
		(end 393.659106 -419.88105)
		(width 0.14224)
		(layer "In13.Cu")
		(net "P5E_CPU0_P3_RX_BUF_DN<7>")
	)
	(segment
		(start 395.083792 -435.03088)
		(end 394.776452 -434.72354)
		(width 0.14224)
		(layer "In13.Cu")
		(net "P5E_CPU0_P3_RX_BUF_DN<7>")
	)
	(segment
		(start 395.62278 -435.03088)
		(end 395.083792 -435.03088)
		(width 0.14224)
		(layer "In13.Cu")
		(net "P5E_CPU0_P3_RX_BUF_DN<7>")
	)
	(segment
		(start 391.095992 -412.426404)
		(end 391.050526 -412.277052)
		(width 0.14224)
		(layer "In13.Cu")
		(net "P5E_CPU0_P3_RX_BUF_DN<7>")
	)
	(segment
		(start 392.852402 -419.176454)
		(end 392.66114 -418.715444)
		(width 0.14224)
		(layer "In13.Cu")
		(net "P5E_CPU0_P3_RX_BUF_DN<7>")
	)
	(segment
		(start 390.265158 -411.672278)
		(end 389.941562 -411.672278)
		(width 0.14224)
		(layer "In13.Cu")
		(net "P5E_CPU0_P3_RX_BUF_DN<7>")
	)
	(segment
		(start 394.776452 -425.115228)
		(end 394.159232 -422.011094)
		(width 0.14224)
		(layer "In13.Cu")
		(net "P5E_CPU0_P3_RX_BUF_DN<7>")
	)
	(segment
		(start 395.74978 -435.15788)
		(end 395.62278 -435.03088)
		(width 0.14224)
		(layer "In13.Cu")
		(net "P5E_CPU0_P3_RX_BUF_DN<7>")
	)
	(segment
		(start 378.57557 -401.394168)
		(end 378.880116 -401.089622)
		(width 0.14224)
		(layer "In13.Cu")
		(net "P5E_CPU0_P3_RX_BUF_DN<7>")
	)
	(segment
		(start 388.847838 -411.21965)
		(end 388.848092 -411.21965)
		(width 0.14224)
		(layer "In13.Cu")
		(net "P5E_CPU0_P3_RX_BUF_DN<7>")
	)
	(segment
		(start 391.211562 -413.902144)
		(end 391.095992 -413.623252)
		(width 0.14224)
		(layer "In13.Cu")
		(net "P5E_CPU0_P3_RX_BUF_DN<7>")
	)
	(segment
		(start 387.59511 -410.701236)
		(end 382.32588 -409.10256)
		(width 0.14224)
		(layer "In13.Cu")
		(net "P5E_CPU0_P3_RX_BUF_DN<7>")
	)
	(segment
		(start 389.941562 -411.672278)
		(end 388.847838 -411.21965)
		(width 0.14224)
		(layer "In13.Cu")
		(net "P5E_CPU0_P3_RX_BUF_DN<7>")
	)
	(segment
		(start 391.475468 -414.16605)
		(end 391.211562 -413.902144)
		(width 0.14224)
		(layer "In13.Cu")
		(net "P5E_CPU0_P3_RX_BUF_DN<7>")
	)
	(segment
		(start 391.095992 -413.623252)
		(end 391.095992 -412.426404)
		(width 0.14224)
		(layer "In13.Cu")
		(net "P5E_CPU0_P3_RX_BUF_DN<7>")
	)
	(segment
		(start 378.880116 -401.089622)
		(end 379.189488 -401.089622)
		(width 0.14224)
		(layer "In13.Cu")
		(net "P5E_CPU0_P3_RX_BUF_DN<7>")
	)
	(segment
		(start 379.189488 -401.089622)
		(end 379.316488 -400.962622)
		(width 0.14224)
		(layer "In13.Cu")
		(net "P5E_CPU0_P3_RX_BUF_DN<7>")
	)
	(segment
		(start 393.554204 -419.8112)
		(end 393.422124 -419.75659)
		(width 0.14224)
		(layer "In13.Cu")
		(net "P5E_CPU0_P3_RX_BUF_DN<7>")
	)
	(segment
		(start 378.57557 -405.41575)
		(end 378.57557 -401.394168)
		(width 0.14224)
		(layer "In13.Cu")
		(net "P5E_CPU0_P3_RX_BUF_DN<7>")
	)
	(segment
		(start 394.159232 -422.011094)
		(end 394.159232 -420.433754)
		(width 0.14224)
		(layer "In13.Cu")
		(net "P5E_CPU0_P3_RX_BUF_DN<7>")
	)
	(segment
		(start 379.316488 -400.962622)
		(end 379.316488 -400.811238)
		(width 0.14224)
		(layer "In13.Cu")
		(net "P5E_CPU0_P3_RX_BUF_DN<7>")
	)
	(segment
		(start 392.627612 -418.545518)
		(end 392.627612 -414.863026)
		(width 0.14224)
		(layer "In13.Cu")
		(net "P5E_CPU0_P3_RX_BUF_DN<7>")
	)
	(segment
		(start 392.231626 -414.267142)
		(end 392.163046 -414.238694)
		(width 0.14224)
		(layer "In13.Cu")
		(net "P5E_CPU0_P3_RX_BUF_DN<7>")
	)
	(segment
		(start 394.776452 -434.72354)
		(end 394.776452 -425.115228)
		(width 0.14224)
		(layer "In13.Cu")
		(net "P5E_CPU0_P3_RX_BUF_DN<7>")
	)
	(segment
		(start 390.967468 -412.152846)
		(end 390.500108 -411.76956)
		(width 0.14224)
		(layer "In13.Cu")
		(net "P5E_CPU0_P3_RX_BUF_DN<7>")
	)
	(arc
		(start 393.2555 -419.664642)
		(mid 393.081193 -419.514862)
		(end 392.937238 -419.335712)
		(width 0.14224)
		(layer "In13.Cu")
		(net "P5E_CPU0_P3_RX_BUF_DN<7>")
	)
	(arc
		(start 394.159232 -420.433754)
		(mid 394.14953 -420.38507)
		(end 394.121894 -420.343838)
		(width 0.14224)
		(layer "In13.Cu")
		(net "P5E_CPU0_P3_RX_BUF_DN<7>")
	)
	(arc
		(start 392.937238 -419.335712)
		(mid 392.891016 -419.25811)
		(end 392.852402 -419.176454)
		(width 0.14224)
		(layer "In13.Cu")
		(net "P5E_CPU0_P3_RX_BUF_DN<7>")
	)
	(arc
		(start 392.66114 -418.715444)
		(mid 392.63597 -418.632138)
		(end 392.627612 -418.545518)
		(width 0.14224)
		(layer "In13.Cu")
		(net "P5E_CPU0_P3_RX_BUF_DN<7>")
	)
	(arc
		(start 393.422124 -419.75659)
		(mid 393.336208 -419.715332)
		(end 393.2555 -419.664642)
		(width 0.14224)
		(layer "In13.Cu")
		(net "P5E_CPU0_P3_RX_BUF_DN<7>")
	)
	(arc
		(start 378.695458 -405.70531)
		(mid 378.606743 -405.572445)
		(end 378.57557 -405.41575)
		(width 0.14224)
		(layer "In13.Cu")
		(net "P5E_CPU0_P3_RX_BUF_DN<7>")
	)
	(arc
		(start 393.659106 -419.88105)
		(mid 393.610101 -419.840953)
		(end 393.554204 -419.8112)
		(width 0.14224)
		(layer "In13.Cu")
		(net "P5E_CPU0_P3_RX_BUF_DN<7>")
	)
	(arc
		(start 382.32588 -409.10256)
		(mid 382.013156 -408.963816)
		(end 381.743458 -408.75331)
		(width 0.14224)
		(layer "In13.Cu")
		(net "P5E_CPU0_P3_RX_BUF_DN<7>")
	)
	(segment
		(start 377.975876 -401.143216)
		(end 378.116592 -401.0025)
		(width 0.1016)
		(layer "F.Cu")
		(net "P5E_CPU0_P3_RX_BUF_DN<6>")
	)
	(segment
		(start 377.765564 -401.143216)
		(end 377.975876 -401.143216)
		(width 0.1016)
		(layer "F.Cu")
		(net "P5E_CPU0_P3_RX_BUF_DN<6>")
	)
	(segment
		(start 377.718574 -399.143982)
		(end 377.718574 -399.747486)
		(width 0.1016)
		(layer "F.Cu")
		(net "P5E_CPU0_P3_RX_BUF_DN<6>")
	)
	(segment
		(start 377.718574 -399.747486)
		(end 377.71832 -399.74774)
		(width 0.1016)
		(layer "F.Cu")
		(net "P5E_CPU0_P3_RX_BUF_DN<6>")
	)
	(segment
		(start 377.638564 -400.040094)
		(end 377.638564 -401.016216)
		(width 0.1016)
		(layer "F.Cu")
		(net "P5E_CPU0_P3_RX_BUF_DN<6>")
	)
	(segment
		(start 377.638564 -401.016216)
		(end 377.765564 -401.143216)
		(width 0.1016)
		(layer "F.Cu")
		(net "P5E_CPU0_P3_RX_BUF_DN<6>")
	)
	(segment
		(start 378.116592 -401.0025)
		(end 378.116592 -400.811238)
		(width 0.1016)
		(layer "F.Cu")
		(net "P5E_CPU0_P3_RX_BUF_DN<6>")
	)
	(segment
		(start 377.71832 -399.74774)
		(end 377.71832 -399.960338)
		(width 0.1016)
		(layer "F.Cu")
		(net "P5E_CPU0_P3_RX_BUF_DN<6>")
	)
	(segment
		(start 377.71832 -399.960338)
		(end 377.638564 -400.040094)
		(width 0.1016)
		(layer "F.Cu")
		(net "P5E_CPU0_P3_RX_BUF_DN<6>")
	)
	(segment
		(start 377.718066 -399.143474)
		(end 377.718574 -399.143982)
		(width 0.1016)
		(layer "F.Cu")
		(net "P5E_CPU0_P3_RX_BUF_DN<6>")
	)
	(segment
		(start 380.645924 -409.24734)
		(end 381.023368 -409.624784)
		(width 0.14224)
		(layer "In13.Cu")
		(net "P5E_CPU0_P3_RX_BUF_DN<6>")
	)
	(segment
		(start 389.564372 -414.863026)
		(end 389.564372 -418.512752)
		(width 0.14224)
		(layer "In13.Cu")
		(net "P5E_CPU0_P3_RX_BUF_DN<6>")
	)
	(segment
		(start 388.032752 -412.289752)
		(end 388.032752 -413.566102)
		(width 0.14224)
		(layer "In13.Cu")
		(net "P5E_CPU0_P3_RX_BUF_DN<6>")
	)
	(segment
		(start 377.60783 -406.209246)
		(end 380.64567 -409.24734)
		(width 0.14224)
		(layer "In13.Cu")
		(net "P5E_CPU0_P3_RX_BUF_DN<6>")
	)
	(segment
		(start 388.1882 -413.942276)
		(end 388.412228 -414.16605)
		(width 0.14224)
		(layer "In13.Cu")
		(net "P5E_CPU0_P3_RX_BUF_DN<6>")
	)
	(segment
		(start 391.095992 -420.498524)
		(end 391.095992 -421.298878)
		(width 0.14224)
		(layer "In13.Cu")
		(net "P5E_CPU0_P3_RX_BUF_DN<6>")
	)
	(segment
		(start 392.776456 -433.738782)
		(end 393.068556 -434.030882)
		(width 0.14224)
		(layer "In13.Cu")
		(net "P5E_CPU0_P3_RX_BUF_DN<6>")
	)
	(segment
		(start 391.17143 -421.634412)
		(end 392.763502 -425.00042)
		(width 0.14224)
		(layer "In13.Cu")
		(net "P5E_CPU0_P3_RX_BUF_DN<6>")
	)
	(segment
		(start 377.989592 -401.089622)
		(end 377.68022 -401.089622)
		(width 0.14224)
		(layer "In13.Cu")
		(net "P5E_CPU0_P3_RX_BUF_DN<6>")
	)
	(segment
		(start 389.168386 -414.267142)
		(end 389.422894 -414.52165)
		(width 0.14224)
		(layer "In13.Cu")
		(net "P5E_CPU0_P3_RX_BUF_DN<6>")
	)
	(segment
		(start 389.610346 -418.743892)
		(end 389.781034 -419.156896)
		(width 0.14224)
		(layer "In13.Cu")
		(net "P5E_CPU0_P3_RX_BUF_DN<6>")
	)
	(segment
		(start 381.315214 -409.800044)
		(end 387.427216 -411.654244)
		(width 0.14224)
		(layer "In13.Cu")
		(net "P5E_CPU0_P3_RX_BUF_DN<6>")
	)
	(segment
		(start 387.427216 -411.654244)
		(end 387.899148 -411.98673)
		(width 0.14224)
		(layer "In13.Cu")
		(net "P5E_CPU0_P3_RX_BUF_DN<6>")
	)
	(segment
		(start 389.099806 -414.238694)
		(end 389.168386 -414.267142)
		(width 0.14224)
		(layer "In13.Cu")
		(net "P5E_CPU0_P3_RX_BUF_DN<6>")
	)
	(segment
		(start 393.068556 -434.030882)
		(end 393.622784 -434.030882)
		(width 0.14224)
		(layer "In13.Cu")
		(net "P5E_CPU0_P3_RX_BUF_DN<6>")
	)
	(segment
		(start 392.776456 -425.05757)
		(end 392.776456 -433.738782)
		(width 0.14224)
		(layer "In13.Cu")
		(net "P5E_CPU0_P3_RX_BUF_DN<6>")
	)
	(segment
		(start 387.899148 -411.98673)
		(end 388.011416 -412.203138)
		(width 0.14224)
		(layer "In13.Cu")
		(net "P5E_CPU0_P3_RX_BUF_DN<6>")
	)
	(segment
		(start 388.587234 -414.238694)
		(end 389.099806 -414.238694)
		(width 0.14224)
		(layer "In13.Cu")
		(net "P5E_CPU0_P3_RX_BUF_DN<6>")
	)
	(segment
		(start 389.422894 -414.52165)
		(end 389.564372 -414.863026)
		(width 0.14224)
		(layer "In13.Cu")
		(net "P5E_CPU0_P3_RX_BUF_DN<6>")
	)
	(segment
		(start 380.64567 -409.24734)
		(end 380.645924 -409.24734)
		(width 0.14224)
		(layer "In13.Cu")
		(net "P5E_CPU0_P3_RX_BUF_DN<6>")
	)
	(segment
		(start 393.622784 -434.030882)
		(end 393.749784 -434.157882)
		(width 0.14224)
		(layer "In13.Cu")
		(net "P5E_CPU0_P3_RX_BUF_DN<6>")
	)
	(segment
		(start 389.781034 -419.156896)
		(end 389.781542 -419.156896)
		(width 0.14224)
		(layer "In13.Cu")
		(net "P5E_CPU0_P3_RX_BUF_DN<6>")
	)
	(segment
		(start 377.375674 -401.394168)
		(end 377.375674 -405.648922)
		(width 0.14224)
		(layer "In13.Cu")
		(net "P5E_CPU0_P3_RX_BUF_DN<6>")
	)
	(segment
		(start 388.412228 -414.16605)
		(end 388.587234 -414.238694)
		(width 0.14224)
		(layer "In13.Cu")
		(net "P5E_CPU0_P3_RX_BUF_DN<6>")
	)
	(segment
		(start 378.116592 -400.962622)
		(end 377.989592 -401.089622)
		(width 0.14224)
		(layer "In13.Cu")
		(net "P5E_CPU0_P3_RX_BUF_DN<6>")
	)
	(segment
		(start 378.116592 -400.811238)
		(end 378.116592 -400.962622)
		(width 0.14224)
		(layer "In13.Cu")
		(net "P5E_CPU0_P3_RX_BUF_DN<6>")
	)
	(segment
		(start 393.749784 -434.157882)
		(end 393.749784 -434.48986)
		(width 0.14224)
		(layer "In13.Cu")
		(net "P5E_CPU0_P3_RX_BUF_DN<6>")
	)
	(segment
		(start 388.032752 -413.566102)
		(end 388.1882 -413.942276)
		(width 0.14224)
		(layer "In13.Cu")
		(net "P5E_CPU0_P3_RX_BUF_DN<6>")
	)
	(segment
		(start 377.68022 -401.089622)
		(end 377.375674 -401.394168)
		(width 0.14224)
		(layer "In13.Cu")
		(net "P5E_CPU0_P3_RX_BUF_DN<6>")
	)
	(segment
		(start 390.62279 -419.95852)
		(end 391.048748 -420.384478)
		(width 0.14224)
		(layer "In13.Cu")
		(net "P5E_CPU0_P3_RX_BUF_DN<6>")
	)
	(arc
		(start 381.023368 -409.624784)
		(mid 381.158503 -409.730369)
		(end 381.315214 -409.800044)
		(width 0.14224)
		(layer "In13.Cu")
		(net "P5E_CPU0_P3_RX_BUF_DN<6>")
	)
	(arc
		(start 389.781542 -419.156896)
		(mid 389.996208 -419.492728)
		(end 390.313672 -419.73373)
		(width 0.14224)
		(layer "In13.Cu")
		(net "P5E_CPU0_P3_RX_BUF_DN<6>")
	)
	(arc
		(start 389.564372 -418.512752)
		(mid 389.575968 -418.63059)
		(end 389.610346 -418.743892)
		(width 0.14224)
		(layer "In13.Cu")
		(net "P5E_CPU0_P3_RX_BUF_DN<6>")
	)
	(arc
		(start 377.375674 -405.648922)
		(mid 377.436013 -405.952177)
		(end 377.60783 -406.209246)
		(width 0.14224)
		(layer "In13.Cu")
		(net "P5E_CPU0_P3_RX_BUF_DN<6>")
	)
	(arc
		(start 391.048748 -420.384478)
		(mid 391.08371 -420.436803)
		(end 391.095992 -420.498524)
		(width 0.14224)
		(layer "In13.Cu")
		(net "P5E_CPU0_P3_RX_BUF_DN<6>")
	)
	(arc
		(start 392.763502 -425.00042)
		(mid 392.773172 -425.028273)
		(end 392.776456 -425.05757)
		(width 0.14224)
		(layer "In13.Cu")
		(net "P5E_CPU0_P3_RX_BUF_DN<6>")
	)
	(arc
		(start 388.011416 -412.203138)
		(mid 388.027272 -412.245164)
		(end 388.032752 -412.289752)
		(width 0.14224)
		(layer "In13.Cu")
		(net "P5E_CPU0_P3_RX_BUF_DN<6>")
	)
	(arc
		(start 390.313672 -419.73373)
		(mid 390.477009 -419.834052)
		(end 390.62279 -419.95852)
		(width 0.14224)
		(layer "In13.Cu")
		(net "P5E_CPU0_P3_RX_BUF_DN<6>")
	)
	(arc
		(start 391.095992 -421.298878)
		(mid 391.115098 -421.470833)
		(end 391.17143 -421.634412)
		(width 0.14224)
		(layer "In13.Cu")
		(net "P5E_CPU0_P3_RX_BUF_DN<6>")
	)
	(segment
		(start 376.429778 -401.016216)
		(end 376.556778 -401.143216)
		(width 0.1016)
		(layer "F.Cu")
		(net "P5E_CPU0_P3_RX_BUF_DN<5>")
	)
	(segment
		(start 376.916442 -401.0025)
		(end 376.916442 -400.811238)
		(width 0.1016)
		(layer "F.Cu")
		(net "P5E_CPU0_P3_RX_BUF_DN<5>")
	)
	(segment
		(start 376.556778 -401.143216)
		(end 376.775726 -401.143216)
		(width 0.1016)
		(layer "F.Cu")
		(net "P5E_CPU0_P3_RX_BUF_DN<5>")
	)
	(segment
		(start 376.517916 -399.143474)
		(end 376.518424 -399.143982)
		(width 0.1016)
		(layer "F.Cu")
		(net "P5E_CPU0_P3_RX_BUF_DN<5>")
	)
	(segment
		(start 376.775726 -401.143216)
		(end 376.916442 -401.0025)
		(width 0.1016)
		(layer "F.Cu")
		(net "P5E_CPU0_P3_RX_BUF_DN<5>")
	)
	(segment
		(start 376.518424 -399.143982)
		(end 376.518424 -399.960338)
		(width 0.1016)
		(layer "F.Cu")
		(net "P5E_CPU0_P3_RX_BUF_DN<5>")
	)
	(segment
		(start 376.429778 -400.048984)
		(end 376.429778 -401.016216)
		(width 0.1016)
		(layer "F.Cu")
		(net "P5E_CPU0_P3_RX_BUF_DN<5>")
	)
	(segment
		(start 376.518424 -399.960338)
		(end 376.429778 -400.048984)
		(width 0.1016)
		(layer "F.Cu")
		(net "P5E_CPU0_P3_RX_BUF_DN<5>")
	)
	(segment
		(start 376.175524 -401.394168)
		(end 376.48007 -401.089622)
		(width 0.14224)
		(layer "In13.Cu")
		(net "P5E_CPU0_P3_RX_BUF_DN<5>")
	)
	(segment
		(start 385.348988 -414.16605)
		(end 385.138422 -413.955484)
		(width 0.14224)
		(layer "In13.Cu")
		(net "P5E_CPU0_P3_RX_BUF_DN<5>")
	)
	(segment
		(start 390.320276 -424.501818)
		(end 388.08914 -421.494712)
		(width 0.14224)
		(layer "In13.Cu")
		(net "P5E_CPU0_P3_RX_BUF_DN<5>")
	)
	(segment
		(start 388.08914 -421.494712)
		(end 388.060692 -421.40886)
		(width 0.14224)
		(layer "In13.Cu")
		(net "P5E_CPU0_P3_RX_BUF_DN<5>")
	)
	(segment
		(start 386.501132 -418.821362)
		(end 386.501132 -414.863026)
		(width 0.14224)
		(layer "In13.Cu")
		(net "P5E_CPU0_P3_RX_BUF_DN<5>")
	)
	(segment
		(start 391.749788 -435.489858)
		(end 391.749788 -435.15788)
		(width 0.14224)
		(layer "In13.Cu")
		(net "P5E_CPU0_P3_RX_BUF_DN<5>")
	)
	(segment
		(start 379.835918 -410.131514)
		(end 376.295412 -406.591008)
		(width 0.14224)
		(layer "In13.Cu")
		(net "P5E_CPU0_P3_RX_BUF_DN<5>")
	)
	(segment
		(start 386.036566 -414.238694)
		(end 385.523994 -414.238694)
		(width 0.14224)
		(layer "In13.Cu")
		(net "P5E_CPU0_P3_RX_BUF_DN<5>")
	)
	(segment
		(start 390.751822 -425.29379)
		(end 390.592818 -424.910504)
		(width 0.14224)
		(layer "In13.Cu")
		(net "P5E_CPU0_P3_RX_BUF_DN<5>")
	)
	(segment
		(start 386.105146 -414.267142)
		(end 386.036566 -414.238694)
		(width 0.14224)
		(layer "In13.Cu")
		(net "P5E_CPU0_P3_RX_BUF_DN<5>")
	)
	(segment
		(start 390.592818 -424.910504)
		(end 390.320276 -424.501818)
		(width 0.14224)
		(layer "In13.Cu")
		(net "P5E_CPU0_P3_RX_BUF_DN<5>")
	)
	(segment
		(start 386.501132 -414.863026)
		(end 386.359654 -414.52165)
		(width 0.14224)
		(layer "In13.Cu")
		(net "P5E_CPU0_P3_RX_BUF_DN<5>")
	)
	(segment
		(start 376.916442 -400.962622)
		(end 376.916442 -400.811238)
		(width 0.14224)
		(layer "In13.Cu")
		(net "P5E_CPU0_P3_RX_BUF_DN<5>")
	)
	(segment
		(start 385.523994 -414.238694)
		(end 385.348988 -414.16605)
		(width 0.14224)
		(layer "In13.Cu")
		(net "P5E_CPU0_P3_RX_BUF_DN<5>")
	)
	(segment
		(start 391.622788 -435.03088)
		(end 391.158476 -435.03088)
		(width 0.14224)
		(layer "In13.Cu")
		(net "P5E_CPU0_P3_RX_BUF_DN<5>")
	)
	(segment
		(start 387.354064 -419.780466)
		(end 387.23951 -419.733222)
		(width 0.14224)
		(layer "In13.Cu")
		(net "P5E_CPU0_P3_RX_BUF_DN<5>")
	)
	(segment
		(start 388.032752 -421.323516)
		(end 388.032752 -420.453312)
		(width 0.14224)
		(layer "In13.Cu")
		(net "P5E_CPU0_P3_RX_BUF_DN<5>")
	)
	(segment
		(start 385.138422 -413.955484)
		(end 384.969512 -413.547814)
		(width 0.14224)
		(layer "In13.Cu")
		(net "P5E_CPU0_P3_RX_BUF_DN<5>")
	)
	(segment
		(start 386.359654 -414.52165)
		(end 386.105146 -414.267142)
		(width 0.14224)
		(layer "In13.Cu")
		(net "P5E_CPU0_P3_RX_BUF_DN<5>")
	)
	(segment
		(start 388.060692 -421.408352)
		(end 388.032752 -421.323516)
		(width 0.14224)
		(layer "In13.Cu")
		(net "P5E_CPU0_P3_RX_BUF_DN<5>")
	)
	(segment
		(start 391.749788 -435.15788)
		(end 391.622788 -435.03088)
		(width 0.14224)
		(layer "In13.Cu")
		(net "P5E_CPU0_P3_RX_BUF_DN<5>")
	)
	(segment
		(start 384.969512 -413.547814)
		(end 384.969512 -412.180786)
		(width 0.14224)
		(layer "In13.Cu")
		(net "P5E_CPU0_P3_RX_BUF_DN<5>")
	)
	(segment
		(start 388.060692 -421.40886)
		(end 388.060692 -421.408352)
		(width 0.14224)
		(layer "In13.Cu")
		(net "P5E_CPU0_P3_RX_BUF_DN<5>")
	)
	(segment
		(start 387.995414 -420.363396)
		(end 387.529832 -419.897814)
		(width 0.14224)
		(layer "In13.Cu")
		(net "P5E_CPU0_P3_RX_BUF_DN<5>")
	)
	(segment
		(start 386.624576 -419.119304)
		(end 386.501132 -418.821362)
		(width 0.14224)
		(layer "In13.Cu")
		(net "P5E_CPU0_P3_RX_BUF_DN<5>")
	)
	(segment
		(start 376.789442 -401.089622)
		(end 376.916442 -400.962622)
		(width 0.14224)
		(layer "In13.Cu")
		(net "P5E_CPU0_P3_RX_BUF_DN<5>")
	)
	(segment
		(start 376.48007 -401.089622)
		(end 376.789442 -401.089622)
		(width 0.14224)
		(layer "In13.Cu")
		(net "P5E_CPU0_P3_RX_BUF_DN<5>")
	)
	(segment
		(start 376.175524 -406.301448)
		(end 376.175524 -401.394168)
		(width 0.14224)
		(layer "In13.Cu")
		(net "P5E_CPU0_P3_RX_BUF_DN<5>")
	)
	(segment
		(start 390.77646 -434.648864)
		(end 390.77646 -425.41698)
		(width 0.14224)
		(layer "In13.Cu")
		(net "P5E_CPU0_P3_RX_BUF_DN<5>")
	)
	(segment
		(start 391.158476 -435.03088)
		(end 390.77646 -434.648864)
		(width 0.14224)
		(layer "In13.Cu")
		(net "P5E_CPU0_P3_RX_BUF_DN<5>")
	)
	(segment
		(start 384.86842 -412.00197)
		(end 384.447288 -411.748478)
		(width 0.14224)
		(layer "In13.Cu")
		(net "P5E_CPU0_P3_RX_BUF_DN<5>")
	)
	(segment
		(start 384.447288 -411.748478)
		(end 380.575312 -410.574744)
		(width 0.14224)
		(layer "In13.Cu")
		(net "P5E_CPU0_P3_RX_BUF_DN<5>")
	)
	(arc
		(start 387.23951 -419.733222)
		(mid 386.871014 -419.48739)
		(end 386.624576 -419.119304)
		(width 0.14224)
		(layer "In13.Cu")
		(net "P5E_CPU0_P3_RX_BUF_DN<5>")
	)
	(arc
		(start 387.529832 -419.897814)
		(mid 387.447748 -419.830453)
		(end 387.354064 -419.780466)
		(width 0.14224)
		(layer "In13.Cu")
		(net "P5E_CPU0_P3_RX_BUF_DN<5>")
	)
	(arc
		(start 388.032752 -420.453312)
		(mid 388.02305 -420.404628)
		(end 387.995414 -420.363396)
		(width 0.14224)
		(layer "In13.Cu")
		(net "P5E_CPU0_P3_RX_BUF_DN<5>")
	)
	(arc
		(start 376.295412 -406.591008)
		(mid 376.206697 -406.458143)
		(end 376.175524 -406.301448)
		(width 0.14224)
		(layer "In13.Cu")
		(net "P5E_CPU0_P3_RX_BUF_DN<5>")
	)
	(arc
		(start 390.77646 -425.41698)
		(mid 390.770225 -425.354166)
		(end 390.751822 -425.29379)
		(width 0.14224)
		(layer "In13.Cu")
		(net "P5E_CPU0_P3_RX_BUF_DN<5>")
	)
	(arc
		(start 384.969512 -412.180786)
		(mid 384.942497 -412.078068)
		(end 384.86842 -412.00197)
		(width 0.14224)
		(layer "In13.Cu")
		(net "P5E_CPU0_P3_RX_BUF_DN<5>")
	)
	(arc
		(start 380.575312 -410.574744)
		(mid 380.178274 -410.398742)
		(end 379.835918 -410.131514)
		(width 0.14224)
		(layer "In13.Cu")
		(net "P5E_CPU0_P3_RX_BUF_DN<5>")
	)
	(segment
		(start 375.229882 -400.048984)
		(end 375.229882 -401.016216)
		(width 0.1016)
		(layer "F.Cu")
		(net "P5E_CPU0_P3_RX_BUF_DN<4>")
	)
	(segment
		(start 375.31802 -399.143474)
		(end 375.318528 -399.143982)
		(width 0.1016)
		(layer "F.Cu")
		(net "P5E_CPU0_P3_RX_BUF_DN<4>")
	)
	(segment
		(start 375.716546 -401.0025)
		(end 375.716546 -400.811238)
		(width 0.1016)
		(layer "F.Cu")
		(net "P5E_CPU0_P3_RX_BUF_DN<4>")
	)
	(segment
		(start 375.229882 -401.016216)
		(end 375.356882 -401.143216)
		(width 0.1016)
		(layer "F.Cu")
		(net "P5E_CPU0_P3_RX_BUF_DN<4>")
	)
	(segment
		(start 375.318528 -399.960338)
		(end 375.229882 -400.048984)
		(width 0.1016)
		(layer "F.Cu")
		(net "P5E_CPU0_P3_RX_BUF_DN<4>")
	)
	(segment
		(start 375.356882 -401.143216)
		(end 375.57583 -401.143216)
		(width 0.1016)
		(layer "F.Cu")
		(net "P5E_CPU0_P3_RX_BUF_DN<4>")
	)
	(segment
		(start 375.57583 -401.143216)
		(end 375.716546 -401.0025)
		(width 0.1016)
		(layer "F.Cu")
		(net "P5E_CPU0_P3_RX_BUF_DN<4>")
	)
	(segment
		(start 375.318528 -399.143982)
		(end 375.318528 -399.960338)
		(width 0.1016)
		(layer "F.Cu")
		(net "P5E_CPU0_P3_RX_BUF_DN<4>")
	)
	(segment
		(start 383.437892 -418.683694)
		(end 383.648458 -419.192202)
		(width 0.14224)
		(layer "In13.Cu")
		(net "P5E_CPU0_P3_RX_BUF_DN<4>")
	)
	(segment
		(start 382.460754 -414.238694)
		(end 382.935226 -414.238694)
		(width 0.14224)
		(layer "In13.Cu")
		(net "P5E_CPU0_P3_RX_BUF_DN<4>")
	)
	(segment
		(start 385.522978 -422.428162)
		(end 388.302754 -424.283124)
		(width 0.14224)
		(layer "In13.Cu")
		(net "P5E_CPU0_P3_RX_BUF_DN<4>")
	)
	(segment
		(start 389.749792 -434.157882)
		(end 389.749792 -434.48986)
		(width 0.14224)
		(layer "In13.Cu")
		(net "P5E_CPU0_P3_RX_BUF_DN<4>")
	)
	(segment
		(start 384.10769 -419.686232)
		(end 384.366516 -419.79342)
		(width 0.14224)
		(layer "In13.Cu")
		(net "P5E_CPU0_P3_RX_BUF_DN<4>")
	)
	(segment
		(start 375.589546 -401.089622)
		(end 375.280174 -401.089622)
		(width 0.14224)
		(layer "In13.Cu")
		(net "P5E_CPU0_P3_RX_BUF_DN<4>")
	)
	(segment
		(start 382.285748 -414.16605)
		(end 382.460754 -414.238694)
		(width 0.14224)
		(layer "In13.Cu")
		(net "P5E_CPU0_P3_RX_BUF_DN<4>")
	)
	(segment
		(start 381.353568 -411.791404)
		(end 381.579374 -411.884876)
		(width 0.14224)
		(layer "In13.Cu")
		(net "P5E_CPU0_P3_RX_BUF_DN<4>")
	)
	(segment
		(start 389.622792 -434.030882)
		(end 389.749792 -434.157882)
		(width 0.14224)
		(layer "In13.Cu")
		(net "P5E_CPU0_P3_RX_BUF_DN<4>")
	)
	(segment
		(start 384.999738 -421.52824)
		(end 385.082288 -421.801798)
		(width 0.14224)
		(layer "In13.Cu")
		(net "P5E_CPU0_P3_RX_BUF_DN<4>")
	)
	(segment
		(start 379.617478 -411.44571)
		(end 381.353568 -411.791404)
		(width 0.14224)
		(layer "In13.Cu")
		(net "P5E_CPU0_P3_RX_BUF_DN<4>")
	)
	(segment
		(start 384.482848 -419.87089)
		(end 384.932174 -420.3192)
		(width 0.14224)
		(layer "In13.Cu")
		(net "P5E_CPU0_P3_RX_BUF_DN<4>")
	)
	(segment
		(start 381.579374 -411.884876)
		(end 381.789432 -412.094934)
		(width 0.14224)
		(layer "In13.Cu")
		(net "P5E_CPU0_P3_RX_BUF_DN<4>")
	)
	(segment
		(start 388.776464 -433.723542)
		(end 389.083804 -434.030882)
		(width 0.14224)
		(layer "In13.Cu")
		(net "P5E_CPU0_P3_RX_BUF_DN<4>")
	)
	(segment
		(start 389.083804 -434.030882)
		(end 389.622792 -434.030882)
		(width 0.14224)
		(layer "In13.Cu")
		(net "P5E_CPU0_P3_RX_BUF_DN<4>")
	)
	(segment
		(start 383.296414 -414.52165)
		(end 383.437892 -414.863026)
		(width 0.14224)
		(layer "In13.Cu")
		(net "P5E_CPU0_P3_RX_BUF_DN<4>")
	)
	(segment
		(start 375.716546 -400.962622)
		(end 375.589546 -401.089622)
		(width 0.14224)
		(layer "In13.Cu")
		(net "P5E_CPU0_P3_RX_BUF_DN<4>")
	)
	(segment
		(start 381.906272 -412.376874)
		(end 381.906272 -413.622998)
		(width 0.14224)
		(layer "In13.Cu")
		(net "P5E_CPU0_P3_RX_BUF_DN<4>")
	)
	(segment
		(start 388.776464 -425.049442)
		(end 388.776464 -433.723542)
		(width 0.14224)
		(layer "In13.Cu")
		(net "P5E_CPU0_P3_RX_BUF_DN<4>")
	)
	(segment
		(start 374.975628 -401.394168)
		(end 374.975628 -406.714198)
		(width 0.14224)
		(layer "In13.Cu")
		(net "P5E_CPU0_P3_RX_BUF_DN<4>")
	)
	(segment
		(start 382.021842 -413.902144)
		(end 382.285748 -414.16605)
		(width 0.14224)
		(layer "In13.Cu")
		(net "P5E_CPU0_P3_RX_BUF_DN<4>")
	)
	(segment
		(start 375.280174 -401.089622)
		(end 374.975628 -401.394168)
		(width 0.14224)
		(layer "In13.Cu")
		(net "P5E_CPU0_P3_RX_BUF_DN<4>")
	)
	(segment
		(start 383.06883 -414.294066)
		(end 383.296414 -414.52165)
		(width 0.14224)
		(layer "In13.Cu")
		(net "P5E_CPU0_P3_RX_BUF_DN<4>")
	)
	(segment
		(start 388.302754 -424.283124)
		(end 388.525004 -424.505374)
		(width 0.14224)
		(layer "In13.Cu")
		(net "P5E_CPU0_P3_RX_BUF_DN<4>")
	)
	(segment
		(start 383.437892 -414.863026)
		(end 383.437892 -418.683694)
		(width 0.14224)
		(layer "In13.Cu")
		(net "P5E_CPU0_P3_RX_BUF_DN<4>")
	)
	(segment
		(start 382.935226 -414.238694)
		(end 383.06883 -414.294066)
		(width 0.14224)
		(layer "In13.Cu")
		(net "P5E_CPU0_P3_RX_BUF_DN<4>")
	)
	(segment
		(start 384.969512 -420.409116)
		(end 384.969512 -421.321992)
		(width 0.14224)
		(layer "In13.Cu")
		(net "P5E_CPU0_P3_RX_BUF_DN<4>")
	)
	(segment
		(start 375.716546 -400.811238)
		(end 375.716546 -400.962622)
		(width 0.14224)
		(layer "In13.Cu")
		(net "P5E_CPU0_P3_RX_BUF_DN<4>")
	)
	(segment
		(start 381.906272 -413.622998)
		(end 382.021842 -413.902144)
		(width 0.14224)
		(layer "In13.Cu")
		(net "P5E_CPU0_P3_RX_BUF_DN<4>")
	)
	(segment
		(start 375.107708 -407.033222)
		(end 379.408182 -411.333696)
		(width 0.14224)
		(layer "In13.Cu")
		(net "P5E_CPU0_P3_RX_BUF_DN<4>")
	)
	(arc
		(start 381.789432 -412.094934)
		(mid 381.875918 -412.224275)
		(end 381.906272 -412.376874)
		(width 0.14224)
		(layer "In13.Cu")
		(net "P5E_CPU0_P3_RX_BUF_DN<4>")
	)
	(arc
		(start 388.761224 -424.923458)
		(mid 388.772671 -424.985986)
		(end 388.776464 -425.049442)
		(width 0.14224)
		(layer "In13.Cu")
		(net "P5E_CPU0_P3_RX_BUF_DN<4>")
	)
	(arc
		(start 374.975628 -406.714198)
		(mid 375.009951 -406.886842)
		(end 375.107708 -407.033222)
		(width 0.14224)
		(layer "In13.Cu")
		(net "P5E_CPU0_P3_RX_BUF_DN<4>")
	)
	(arc
		(start 384.366516 -419.79342)
		(mid 384.428484 -419.826446)
		(end 384.482848 -419.87089)
		(width 0.14224)
		(layer "In13.Cu")
		(net "P5E_CPU0_P3_RX_BUF_DN<4>")
	)
	(arc
		(start 383.922778 -419.572186)
		(mid 384.010633 -419.636667)
		(end 384.10769 -419.686232)
		(width 0.14224)
		(layer "In13.Cu")
		(net "P5E_CPU0_P3_RX_BUF_DN<4>")
	)
	(arc
		(start 384.969512 -421.321992)
		(mid 384.977046 -421.426228)
		(end 384.999738 -421.52824)
		(width 0.14224)
		(layer "In13.Cu")
		(net "P5E_CPU0_P3_RX_BUF_DN<4>")
	)
	(arc
		(start 385.082288 -421.801798)
		(mid 385.252207 -422.150457)
		(end 385.522978 -422.428162)
		(width 0.14224)
		(layer "In13.Cu")
		(net "P5E_CPU0_P3_RX_BUF_DN<4>")
	)
	(arc
		(start 379.408182 -411.333696)
		(mid 379.504525 -411.405219)
		(end 379.617478 -411.44571)
		(width 0.14224)
		(layer "In13.Cu")
		(net "P5E_CPU0_P3_RX_BUF_DN<4>")
	)
	(arc
		(start 388.525004 -424.505374)
		(mid 388.671651 -424.698294)
		(end 388.761224 -424.923458)
		(width 0.14224)
		(layer "In13.Cu")
		(net "P5E_CPU0_P3_RX_BUF_DN<4>")
	)
	(arc
		(start 383.648458 -419.192202)
		(mid 383.763501 -419.398165)
		(end 383.922778 -419.572186)
		(width 0.14224)
		(layer "In13.Cu")
		(net "P5E_CPU0_P3_RX_BUF_DN<4>")
	)
	(arc
		(start 384.932174 -420.3192)
		(mid 384.959793 -420.36044)
		(end 384.969512 -420.409116)
		(width 0.14224)
		(layer "In13.Cu")
		(net "P5E_CPU0_P3_RX_BUF_DN<4>")
	)
	(segment
		(start 374.118378 -399.143982)
		(end 374.118378 -399.960338)
		(width 0.1016)
		(layer "F.Cu")
		(net "P5E_CPU0_P3_RX_BUF_DN<3>")
	)
	(segment
		(start 374.11787 -399.143474)
		(end 374.118378 -399.143982)
		(width 0.1016)
		(layer "F.Cu")
		(net "P5E_CPU0_P3_RX_BUF_DN<3>")
	)
	(segment
		(start 374.04294 -400.035776)
		(end 374.04294 -401.016216)
		(width 0.1016)
		(layer "F.Cu")
		(net "P5E_CPU0_P3_RX_BUF_DN<3>")
	)
	(segment
		(start 374.118378 -399.960338)
		(end 374.04294 -400.035776)
		(width 0.1016)
		(layer "F.Cu")
		(net "P5E_CPU0_P3_RX_BUF_DN<3>")
	)
	(segment
		(start 374.16994 -401.143216)
		(end 374.37568 -401.143216)
		(width 0.1016)
		(layer "F.Cu")
		(net "P5E_CPU0_P3_RX_BUF_DN<3>")
	)
	(segment
		(start 374.04294 -401.016216)
		(end 374.16994 -401.143216)
		(width 0.1016)
		(layer "F.Cu")
		(net "P5E_CPU0_P3_RX_BUF_DN<3>")
	)
	(segment
		(start 374.516396 -401.0025)
		(end 374.516396 -400.811238)
		(width 0.1016)
		(layer "F.Cu")
		(net "P5E_CPU0_P3_RX_BUF_DN<3>")
	)
	(segment
		(start 374.37568 -401.143216)
		(end 374.516396 -401.0025)
		(width 0.1016)
		(layer "F.Cu")
		(net "P5E_CPU0_P3_RX_BUF_DN<3>")
	)
	(segment
		(start 387.158484 -435.03088)
		(end 386.776468 -434.648864)
		(width 0.14224)
		(layer "In13.Cu")
		(net "P5E_CPU0_P3_RX_BUF_DN<3>")
	)
	(segment
		(start 378.843032 -413.623252)
		(end 378.843032 -412.434024)
		(width 0.14224)
		(layer "In13.Cu")
		(net "P5E_CPU0_P3_RX_BUF_DN<3>")
	)
	(segment
		(start 382.449578 -422.15308)
		(end 382.165098 -421.8686)
		(width 0.14224)
		(layer "In13.Cu")
		(net "P5E_CPU0_P3_RX_BUF_DN<3>")
	)
	(segment
		(start 385.637024 -423.939716)
		(end 383.069338 -422.567354)
		(width 0.14224)
		(layer "In13.Cu")
		(net "P5E_CPU0_P3_RX_BUF_DN<3>")
	)
	(segment
		(start 378.958602 -413.902144)
		(end 378.843032 -413.623252)
		(width 0.14224)
		(layer "In13.Cu")
		(net "P5E_CPU0_P3_RX_BUF_DN<3>")
	)
	(segment
		(start 379.910086 -414.238694)
		(end 379.397514 -414.238694)
		(width 0.14224)
		(layer "In13.Cu")
		(net "P5E_CPU0_P3_RX_BUF_DN<3>")
	)
	(segment
		(start 380.374652 -414.863026)
		(end 380.233174 -414.52165)
		(width 0.14224)
		(layer "In13.Cu")
		(net "P5E_CPU0_P3_RX_BUF_DN<3>")
	)
	(segment
		(start 381.868934 -420.324026)
		(end 381.395224 -419.850062)
		(width 0.14224)
		(layer "In13.Cu")
		(net "P5E_CPU0_P3_RX_BUF_DN<3>")
	)
	(segment
		(start 381.906272 -421.24376)
		(end 381.906272 -420.413942)
		(width 0.14224)
		(layer "In13.Cu")
		(net "P5E_CPU0_P3_RX_BUF_DN<3>")
	)
	(segment
		(start 373.775478 -407.060908)
		(end 373.775478 -401.394168)
		(width 0.14224)
		(layer "In13.Cu")
		(net "P5E_CPU0_P3_RX_BUF_DN<3>")
	)
	(segment
		(start 387.622796 -435.03088)
		(end 387.158484 -435.03088)
		(width 0.14224)
		(layer "In13.Cu")
		(net "P5E_CPU0_P3_RX_BUF_DN<3>")
	)
	(segment
		(start 386.75183 -425.168314)
		(end 386.65785 -424.941746)
		(width 0.14224)
		(layer "In13.Cu")
		(net "P5E_CPU0_P3_RX_BUF_DN<3>")
	)
	(segment
		(start 380.374652 -418.801296)
		(end 380.374652 -414.863026)
		(width 0.14224)
		(layer "In13.Cu")
		(net "P5E_CPU0_P3_RX_BUF_DN<3>")
	)
	(segment
		(start 374.389396 -401.089622)
		(end 374.516396 -400.962622)
		(width 0.14224)
		(layer "In13.Cu")
		(net "P5E_CPU0_P3_RX_BUF_DN<3>")
	)
	(segment
		(start 381.395224 -419.850062)
		(end 381.222758 -419.778942)
		(width 0.14224)
		(layer "In13.Cu")
		(net "P5E_CPU0_P3_RX_BUF_DN<3>")
	)
	(segment
		(start 386.149342 -424.281854)
		(end 385.637024 -423.939716)
		(width 0.14224)
		(layer "In13.Cu")
		(net "P5E_CPU0_P3_RX_BUF_DN<3>")
	)
	(segment
		(start 379.397514 -414.238694)
		(end 379.222508 -414.16605)
		(width 0.14224)
		(layer "In13.Cu")
		(net "P5E_CPU0_P3_RX_BUF_DN<3>")
	)
	(segment
		(start 380.466346 -419.02253)
		(end 380.374652 -418.801296)
		(width 0.14224)
		(layer "In13.Cu")
		(net "P5E_CPU0_P3_RX_BUF_DN<3>")
	)
	(segment
		(start 374.516396 -400.962622)
		(end 374.516396 -400.811238)
		(width 0.14224)
		(layer "In13.Cu")
		(net "P5E_CPU0_P3_RX_BUF_DN<3>")
	)
	(segment
		(start 387.749796 -435.489858)
		(end 387.749796 -435.15788)
		(width 0.14224)
		(layer "In13.Cu")
		(net "P5E_CPU0_P3_RX_BUF_DN<3>")
	)
	(segment
		(start 374.080024 -401.089622)
		(end 374.389396 -401.089622)
		(width 0.14224)
		(layer "In13.Cu")
		(net "P5E_CPU0_P3_RX_BUF_DN<3>")
	)
	(segment
		(start 386.65785 -424.941746)
		(end 386.568442 -424.792902)
		(width 0.14224)
		(layer "In13.Cu")
		(net "P5E_CPU0_P3_RX_BUF_DN<3>")
	)
	(segment
		(start 380.233174 -414.52165)
		(end 379.978666 -414.267142)
		(width 0.14224)
		(layer "In13.Cu")
		(net "P5E_CPU0_P3_RX_BUF_DN<3>")
	)
	(segment
		(start 373.775478 -401.394168)
		(end 374.080024 -401.089622)
		(width 0.14224)
		(layer "In13.Cu")
		(net "P5E_CPU0_P3_RX_BUF_DN<3>")
	)
	(segment
		(start 383.069338 -422.567354)
		(end 382.449578 -422.15308)
		(width 0.14224)
		(layer "In13.Cu")
		(net "P5E_CPU0_P3_RX_BUF_DN<3>")
	)
	(segment
		(start 386.776468 -434.648864)
		(end 386.776468 -425.291504)
		(width 0.14224)
		(layer "In13.Cu")
		(net "P5E_CPU0_P3_RX_BUF_DN<3>")
	)
	(segment
		(start 379.978666 -414.267142)
		(end 379.910086 -414.238694)
		(width 0.14224)
		(layer "In13.Cu")
		(net "P5E_CPU0_P3_RX_BUF_DN<3>")
	)
	(segment
		(start 379.222508 -414.16605)
		(end 378.958602 -413.902144)
		(width 0.14224)
		(layer "In13.Cu")
		(net "P5E_CPU0_P3_RX_BUF_DN<3>")
	)
	(segment
		(start 378.746766 -412.201868)
		(end 373.895366 -407.350468)
		(width 0.14224)
		(layer "In13.Cu")
		(net "P5E_CPU0_P3_RX_BUF_DN<3>")
	)
	(segment
		(start 386.568442 -424.792902)
		(end 386.149342 -424.281854)
		(width 0.14224)
		(layer "In13.Cu")
		(net "P5E_CPU0_P3_RX_BUF_DN<3>")
	)
	(segment
		(start 387.749796 -435.15788)
		(end 387.622796 -435.03088)
		(width 0.14224)
		(layer "In13.Cu")
		(net "P5E_CPU0_P3_RX_BUF_DN<3>")
	)
	(arc
		(start 386.776468 -425.291504)
		(mid 386.770233 -425.22869)
		(end 386.75183 -425.168314)
		(width 0.14224)
		(layer "In13.Cu")
		(net "P5E_CPU0_P3_RX_BUF_DN<3>")
	)
	(arc
		(start 378.843032 -412.434024)
		(mid 378.818017 -412.308357)
		(end 378.746766 -412.201868)
		(width 0.14224)
		(layer "In13.Cu")
		(net "P5E_CPU0_P3_RX_BUF_DN<3>")
	)
	(arc
		(start 381.906272 -420.413942)
		(mid 381.89657 -420.365258)
		(end 381.868934 -420.324026)
		(width 0.14224)
		(layer "In13.Cu")
		(net "P5E_CPU0_P3_RX_BUF_DN<3>")
	)
	(arc
		(start 381.222758 -419.778942)
		(mid 380.769327 -419.475961)
		(end 380.466346 -419.02253)
		(width 0.14224)
		(layer "In13.Cu")
		(net "P5E_CPU0_P3_RX_BUF_DN<3>")
	)
	(arc
		(start 373.895366 -407.350468)
		(mid 373.806651 -407.217603)
		(end 373.775478 -407.060908)
		(width 0.14224)
		(layer "In13.Cu")
		(net "P5E_CPU0_P3_RX_BUF_DN<3>")
	)
	(arc
		(start 382.165098 -421.8686)
		(mid 381.973545 -421.581921)
		(end 381.906272 -421.24376)
		(width 0.14224)
		(layer "In13.Cu")
		(net "P5E_CPU0_P3_RX_BUF_DN<3>")
	)
	(segment
		(start 372.829836 -400.048984)
		(end 372.829836 -401.016216)
		(width 0.1016)
		(layer "F.Cu")
		(net "P5E_CPU0_P3_RX_BUF_DN<2>")
	)
	(segment
		(start 372.917974 -399.143474)
		(end 372.918482 -399.143982)
		(width 0.1016)
		(layer "F.Cu")
		(net "P5E_CPU0_P3_RX_BUF_DN<2>")
	)
	(segment
		(start 372.956836 -401.143216)
		(end 373.175784 -401.143216)
		(width 0.1016)
		(layer "F.Cu")
		(net "P5E_CPU0_P3_RX_BUF_DN<2>")
	)
	(segment
		(start 372.829836 -401.016216)
		(end 372.956836 -401.143216)
		(width 0.1016)
		(layer "F.Cu")
		(net "P5E_CPU0_P3_RX_BUF_DN<2>")
	)
	(segment
		(start 373.3165 -401.0025)
		(end 373.3165 -400.811238)
		(width 0.1016)
		(layer "F.Cu")
		(net "P5E_CPU0_P3_RX_BUF_DN<2>")
	)
	(segment
		(start 372.918482 -399.143982)
		(end 372.918482 -399.960338)
		(width 0.1016)
		(layer "F.Cu")
		(net "P5E_CPU0_P3_RX_BUF_DN<2>")
	)
	(segment
		(start 373.175784 -401.143216)
		(end 373.3165 -401.0025)
		(width 0.1016)
		(layer "F.Cu")
		(net "P5E_CPU0_P3_RX_BUF_DN<2>")
	)
	(segment
		(start 372.918482 -399.960338)
		(end 372.829836 -400.048984)
		(width 0.1016)
		(layer "F.Cu")
		(net "P5E_CPU0_P3_RX_BUF_DN<2>")
	)
	(segment
		(start 379.224032 -421.975534)
		(end 379.4633 -422.214802)
		(width 0.14224)
		(layer "In13.Cu")
		(net "P5E_CPU0_P3_RX_BUF_DN<2>")
	)
	(segment
		(start 384.332988 -424.324526)
		(end 384.72491 -424.716448)
		(width 0.14224)
		(layer "In13.Cu")
		(net "P5E_CPU0_P3_RX_BUF_DN<2>")
	)
	(segment
		(start 376.159268 -414.16605)
		(end 376.334274 -414.238694)
		(width 0.14224)
		(layer "In13.Cu")
		(net "P5E_CPU0_P3_RX_BUF_DN<2>")
	)
	(segment
		(start 385.7498 -434.157882)
		(end 385.7498 -434.48986)
		(width 0.14224)
		(layer "In13.Cu")
		(net "P5E_CPU0_P3_RX_BUF_DN<2>")
	)
	(segment
		(start 379.91669 -422.486582)
		(end 381.55245 -422.981628)
		(width 0.14224)
		(layer "In13.Cu")
		(net "P5E_CPU0_P3_RX_BUF_DN<2>")
	)
	(segment
		(start 372.880128 -401.089622)
		(end 372.575582 -401.394168)
		(width 0.14224)
		(layer "In13.Cu")
		(net "P5E_CPU0_P3_RX_BUF_DN<2>")
	)
	(segment
		(start 377.169934 -414.52165)
		(end 377.311412 -414.863026)
		(width 0.14224)
		(layer "In13.Cu")
		(net "P5E_CPU0_P3_RX_BUF_DN<2>")
	)
	(segment
		(start 375.779792 -412.15945)
		(end 375.779792 -413.623252)
		(width 0.14224)
		(layer "In13.Cu")
		(net "P5E_CPU0_P3_RX_BUF_DN<2>")
	)
	(segment
		(start 384.193796 -424.231562)
		(end 384.332988 -424.324526)
		(width 0.14224)
		(layer "In13.Cu")
		(net "P5E_CPU0_P3_RX_BUF_DN<2>")
	)
	(segment
		(start 377.311412 -414.863026)
		(end 377.311412 -418.786056)
		(width 0.14224)
		(layer "In13.Cu")
		(net "P5E_CPU0_P3_RX_BUF_DN<2>")
	)
	(segment
		(start 377.311412 -418.786056)
		(end 377.49099 -419.219634)
		(width 0.14224)
		(layer "In13.Cu")
		(net "P5E_CPU0_P3_RX_BUF_DN<2>")
	)
	(segment
		(start 385.6228 -434.030882)
		(end 385.7498 -434.157882)
		(width 0.14224)
		(layer "In13.Cu")
		(net "P5E_CPU0_P3_RX_BUF_DN<2>")
	)
	(segment
		(start 381.55245 -422.981628)
		(end 384.193796 -424.231562)
		(width 0.14224)
		(layer "In13.Cu")
		(net "P5E_CPU0_P3_RX_BUF_DN<2>")
	)
	(segment
		(start 376.915426 -414.267142)
		(end 377.169934 -414.52165)
		(width 0.14224)
		(layer "In13.Cu")
		(net "P5E_CPU0_P3_RX_BUF_DN<2>")
	)
	(segment
		(start 373.3165 -400.962622)
		(end 373.1895 -401.089622)
		(width 0.14224)
		(layer "In13.Cu")
		(net "P5E_CPU0_P3_RX_BUF_DN<2>")
	)
	(segment
		(start 375.895362 -413.902144)
		(end 376.159268 -414.16605)
		(width 0.14224)
		(layer "In13.Cu")
		(net "P5E_CPU0_P3_RX_BUF_DN<2>")
	)
	(segment
		(start 372.70817 -408.232102)
		(end 375.662952 -411.832552)
		(width 0.14224)
		(layer "In13.Cu")
		(net "P5E_CPU0_P3_RX_BUF_DN<2>")
	)
	(segment
		(start 378.334524 -419.851332)
		(end 378.805694 -420.322502)
		(width 0.14224)
		(layer "In13.Cu")
		(net "P5E_CPU0_P3_RX_BUF_DN<2>")
	)
	(segment
		(start 379.4633 -422.214802)
		(end 379.91669 -422.486582)
		(width 0.14224)
		(layer "In13.Cu")
		(net "P5E_CPU0_P3_RX_BUF_DN<2>")
	)
	(segment
		(start 384.776472 -433.70373)
		(end 385.103624 -434.030882)
		(width 0.14224)
		(layer "In13.Cu")
		(net "P5E_CPU0_P3_RX_BUF_DN<2>")
	)
	(segment
		(start 376.846846 -414.238694)
		(end 376.915426 -414.267142)
		(width 0.14224)
		(layer "In13.Cu")
		(net "P5E_CPU0_P3_RX_BUF_DN<2>")
	)
	(segment
		(start 384.776472 -424.840908)
		(end 384.776472 -433.70373)
		(width 0.14224)
		(layer "In13.Cu")
		(net "P5E_CPU0_P3_RX_BUF_DN<2>")
	)
	(segment
		(start 378.843032 -420.412418)
		(end 378.843032 -421.218106)
		(width 0.14224)
		(layer "In13.Cu")
		(net "P5E_CPU0_P3_RX_BUF_DN<2>")
	)
	(segment
		(start 373.3165 -400.811238)
		(end 373.3165 -400.962622)
		(width 0.14224)
		(layer "In13.Cu")
		(net "P5E_CPU0_P3_RX_BUF_DN<2>")
	)
	(segment
		(start 372.575582 -401.394168)
		(end 372.575582 -407.860754)
		(width 0.14224)
		(layer "In13.Cu")
		(net "P5E_CPU0_P3_RX_BUF_DN<2>")
	)
	(segment
		(start 385.103624 -434.030882)
		(end 385.6228 -434.030882)
		(width 0.14224)
		(layer "In13.Cu")
		(net "P5E_CPU0_P3_RX_BUF_DN<2>")
	)
	(segment
		(start 375.779792 -413.623252)
		(end 375.895362 -413.902144)
		(width 0.14224)
		(layer "In13.Cu")
		(net "P5E_CPU0_P3_RX_BUF_DN<2>")
	)
	(segment
		(start 379.046994 -421.710358)
		(end 379.224032 -421.975534)
		(width 0.14224)
		(layer "In13.Cu")
		(net "P5E_CPU0_P3_RX_BUF_DN<2>")
	)
	(segment
		(start 378.843032 -421.218106)
		(end 379.046994 -421.710358)
		(width 0.14224)
		(layer "In13.Cu")
		(net "P5E_CPU0_P3_RX_BUF_DN<2>")
	)
	(segment
		(start 373.1895 -401.089622)
		(end 372.880128 -401.089622)
		(width 0.14224)
		(layer "In13.Cu")
		(net "P5E_CPU0_P3_RX_BUF_DN<2>")
	)
	(segment
		(start 377.97359 -419.70198)
		(end 378.334524 -419.851332)
		(width 0.14224)
		(layer "In13.Cu")
		(net "P5E_CPU0_P3_RX_BUF_DN<2>")
	)
	(segment
		(start 376.334274 -414.238694)
		(end 376.846846 -414.238694)
		(width 0.14224)
		(layer "In13.Cu")
		(net "P5E_CPU0_P3_RX_BUF_DN<2>")
	)
	(arc
		(start 375.662952 -411.832552)
		(mid 375.749687 -411.985873)
		(end 375.779792 -412.15945)
		(width 0.14224)
		(layer "In13.Cu")
		(net "P5E_CPU0_P3_RX_BUF_DN<2>")
	)
	(arc
		(start 378.805694 -420.322502)
		(mid 378.833313 -420.363742)
		(end 378.843032 -420.412418)
		(width 0.14224)
		(layer "In13.Cu")
		(net "P5E_CPU0_P3_RX_BUF_DN<2>")
	)
	(arc
		(start 384.72491 -424.716448)
		(mid 384.763065 -424.773551)
		(end 384.776472 -424.840908)
		(width 0.14224)
		(layer "In13.Cu")
		(net "P5E_CPU0_P3_RX_BUF_DN<2>")
	)
	(arc
		(start 372.575582 -407.860754)
		(mid 372.609637 -408.05794)
		(end 372.70817 -408.232102)
		(width 0.14224)
		(layer "In13.Cu")
		(net "P5E_CPU0_P3_RX_BUF_DN<2>")
	)
	(arc
		(start 377.49099 -419.219634)
		(mid 377.684326 -419.50879)
		(end 377.97359 -419.70198)
		(width 0.14224)
		(layer "In13.Cu")
		(net "P5E_CPU0_P3_RX_BUF_DN<2>")
	)
	(segment
		(start 371.629686 -401.016216)
		(end 371.756686 -401.143216)
		(width 0.1016)
		(layer "F.Cu")
		(net "P5E_CPU0_P3_RX_BUF_DN<1>")
	)
	(segment
		(start 371.756686 -401.143216)
		(end 371.975634 -401.143216)
		(width 0.1016)
		(layer "F.Cu")
		(net "P5E_CPU0_P3_RX_BUF_DN<1>")
	)
	(segment
		(start 371.629686 -400.048984)
		(end 371.629686 -401.016216)
		(width 0.1016)
		(layer "F.Cu")
		(net "P5E_CPU0_P3_RX_BUF_DN<1>")
	)
	(segment
		(start 371.975634 -401.143216)
		(end 372.11635 -401.0025)
		(width 0.1016)
		(layer "F.Cu")
		(net "P5E_CPU0_P3_RX_BUF_DN<1>")
	)
	(segment
		(start 371.718332 -399.960338)
		(end 371.629686 -400.048984)
		(width 0.1016)
		(layer "F.Cu")
		(net "P5E_CPU0_P3_RX_BUF_DN<1>")
	)
	(segment
		(start 371.718332 -399.143982)
		(end 371.718332 -399.960338)
		(width 0.1016)
		(layer "F.Cu")
		(net "P5E_CPU0_P3_RX_BUF_DN<1>")
	)
	(segment
		(start 372.11635 -401.0025)
		(end 372.11635 -400.811238)
		(width 0.1016)
		(layer "F.Cu")
		(net "P5E_CPU0_P3_RX_BUF_DN<1>")
	)
	(segment
		(start 371.717824 -399.143474)
		(end 371.718332 -399.143982)
		(width 0.1016)
		(layer "F.Cu")
		(net "P5E_CPU0_P3_RX_BUF_DN<1>")
	)
	(segment
		(start 375.306082 -419.86581)
		(end 375.742454 -420.301166)
		(width 0.14224)
		(layer "In13.Cu")
		(net "P5E_CPU0_P3_RX_BUF_DN<1>")
	)
	(segment
		(start 374.106694 -414.52165)
		(end 374.248172 -414.863026)
		(width 0.14224)
		(layer "In13.Cu")
		(net "P5E_CPU0_P3_RX_BUF_DN<1>")
	)
	(segment
		(start 373.91086 -414.325816)
		(end 374.106694 -414.52165)
		(width 0.14224)
		(layer "In13.Cu")
		(net "P5E_CPU0_P3_RX_BUF_DN<1>")
	)
	(segment
		(start 383.749804 -435.196234)
		(end 383.749804 -435.489858)
		(width 0.14224)
		(layer "In13.Cu")
		(net "P5E_CPU0_P3_RX_BUF_DN<1>")
	)
	(segment
		(start 377.93168 -422.975278)
		(end 381.566674 -424.078146)
		(width 0.14224)
		(layer "In13.Cu")
		(net "P5E_CPU0_P3_RX_BUF_DN<1>")
	)
	(segment
		(start 372.11635 -400.962622)
		(end 371.98935 -401.089622)
		(width 0.14224)
		(layer "In13.Cu")
		(net "P5E_CPU0_P3_RX_BUF_DN<1>")
	)
	(segment
		(start 372.832122 -413.902144)
		(end 373.096028 -414.16605)
		(width 0.14224)
		(layer "In13.Cu")
		(net "P5E_CPU0_P3_RX_BUF_DN<1>")
	)
	(segment
		(start 376.605546 -422.348152)
		(end 377.93168 -422.975278)
		(width 0.14224)
		(layer "In13.Cu")
		(net "P5E_CPU0_P3_RX_BUF_DN<1>")
	)
	(segment
		(start 374.248172 -418.676074)
		(end 374.435116 -419.12667)
		(width 0.14224)
		(layer "In13.Cu")
		(net "P5E_CPU0_P3_RX_BUF_DN<1>")
	)
	(segment
		(start 373.271034 -414.238694)
		(end 373.700548 -414.238694)
		(width 0.14224)
		(layer "In13.Cu")
		(net "P5E_CPU0_P3_RX_BUF_DN<1>")
	)
	(segment
		(start 376.453654 -422.241218)
		(end 376.605546 -422.348152)
		(width 0.14224)
		(layer "In13.Cu")
		(net "P5E_CPU0_P3_RX_BUF_DN<1>")
	)
	(segment
		(start 371.559836 -409.221686)
		(end 371.56009 -409.221686)
		(width 0.14224)
		(layer "In13.Cu")
		(net "P5E_CPU0_P3_RX_BUF_DN<1>")
	)
	(segment
		(start 373.096028 -414.16605)
		(end 373.271034 -414.238694)
		(width 0.14224)
		(layer "In13.Cu")
		(net "P5E_CPU0_P3_RX_BUF_DN<1>")
	)
	(segment
		(start 375.081292 -419.772592)
		(end 375.306082 -419.86581)
		(width 0.14224)
		(layer "In13.Cu")
		(net "P5E_CPU0_P3_RX_BUF_DN<1>")
	)
	(segment
		(start 372.716552 -412.039308)
		(end 372.716552 -413.623252)
		(width 0.14224)
		(layer "In13.Cu")
		(net "P5E_CPU0_P3_RX_BUF_DN<1>")
	)
	(segment
		(start 382.776476 -434.622956)
		(end 383.1844 -435.03088)
		(width 0.14224)
		(layer "In13.Cu")
		(net "P5E_CPU0_P3_RX_BUF_DN<1>")
	)
	(segment
		(start 373.700548 -414.238694)
		(end 373.91086 -414.325816)
		(width 0.14224)
		(layer "In13.Cu")
		(net "P5E_CPU0_P3_RX_BUF_DN<1>")
	)
	(segment
		(start 371.375432 -401.394168)
		(end 371.375432 -408.694128)
		(width 0.14224)
		(layer "In13.Cu")
		(net "P5E_CPU0_P3_RX_BUF_DN<1>")
	)
	(segment
		(start 375.779792 -420.391336)
		(end 375.779792 -421.37584)
		(width 0.14224)
		(layer "In13.Cu")
		(net "P5E_CPU0_P3_RX_BUF_DN<1>")
	)
	(segment
		(start 381.566674 -424.078146)
		(end 382.671828 -424.534838)
		(width 0.14224)
		(layer "In13.Cu")
		(net "P5E_CPU0_P3_RX_BUF_DN<1>")
	)
	(segment
		(start 371.40642 -408.850846)
		(end 371.559836 -409.221686)
		(width 0.14224)
		(layer "In13.Cu")
		(net "P5E_CPU0_P3_RX_BUF_DN<1>")
	)
	(segment
		(start 382.776476 -424.691302)
		(end 382.776476 -434.622956)
		(width 0.14224)
		(layer "In13.Cu")
		(net "P5E_CPU0_P3_RX_BUF_DN<1>")
	)
	(segment
		(start 376.008138 -421.866314)
		(end 376.453654 -422.241218)
		(width 0.14224)
		(layer "In13.Cu")
		(net "P5E_CPU0_P3_RX_BUF_DN<1>")
	)
	(segment
		(start 383.58445 -435.03088)
		(end 383.749804 -435.196234)
		(width 0.14224)
		(layer "In13.Cu")
		(net "P5E_CPU0_P3_RX_BUF_DN<1>")
	)
	(segment
		(start 383.1844 -435.03088)
		(end 383.58445 -435.03088)
		(width 0.14224)
		(layer "In13.Cu")
		(net "P5E_CPU0_P3_RX_BUF_DN<1>")
	)
	(segment
		(start 371.98935 -401.089622)
		(end 371.679978 -401.089622)
		(width 0.14224)
		(layer "In13.Cu")
		(net "P5E_CPU0_P3_RX_BUF_DN<1>")
	)
	(segment
		(start 372.11635 -400.811238)
		(end 372.11635 -400.962622)
		(width 0.14224)
		(layer "In13.Cu")
		(net "P5E_CPU0_P3_RX_BUF_DN<1>")
	)
	(segment
		(start 372.716552 -413.623252)
		(end 372.832122 -413.902144)
		(width 0.14224)
		(layer "In13.Cu")
		(net "P5E_CPU0_P3_RX_BUF_DN<1>")
	)
	(segment
		(start 371.56009 -409.221686)
		(end 372.7069 -411.99054)
		(width 0.14224)
		(layer "In13.Cu")
		(net "P5E_CPU0_P3_RX_BUF_DN<1>")
	)
	(segment
		(start 374.248172 -414.863026)
		(end 374.248172 -418.676074)
		(width 0.14224)
		(layer "In13.Cu")
		(net "P5E_CPU0_P3_RX_BUF_DN<1>")
	)
	(segment
		(start 371.679978 -401.089622)
		(end 371.375432 -401.394168)
		(width 0.14224)
		(layer "In13.Cu")
		(net "P5E_CPU0_P3_RX_BUF_DN<1>")
	)
	(arc
		(start 375.742454 -420.301166)
		(mid 375.770097 -420.342536)
		(end 375.779792 -420.391336)
		(width 0.14224)
		(layer "In13.Cu")
		(net "P5E_CPU0_P3_RX_BUF_DN<1>")
	)
	(arc
		(start 382.671828 -424.534838)
		(mid 382.747849 -424.597206)
		(end 382.776476 -424.691302)
		(width 0.14224)
		(layer "In13.Cu")
		(net "P5E_CPU0_P3_RX_BUF_DN<1>")
	)
	(arc
		(start 371.375432 -408.694128)
		(mid 371.3832 -408.774016)
		(end 371.40642 -408.850846)
		(width 0.14224)
		(layer "In13.Cu")
		(net "P5E_CPU0_P3_RX_BUF_DN<1>")
	)
	(arc
		(start 372.7069 -411.99054)
		(mid 372.714145 -412.014447)
		(end 372.716552 -412.039308)
		(width 0.14224)
		(layer "In13.Cu")
		(net "P5E_CPU0_P3_RX_BUF_DN<1>")
	)
	(arc
		(start 375.779792 -421.37584)
		(mid 375.839682 -421.646345)
		(end 376.008138 -421.866314)
		(width 0.14224)
		(layer "In13.Cu")
		(net "P5E_CPU0_P3_RX_BUF_DN<1>")
	)
	(arc
		(start 374.435116 -419.12667)
		(mid 374.694041 -419.513813)
		(end 375.081292 -419.772592)
		(width 0.14224)
		(layer "In13.Cu")
		(net "P5E_CPU0_P3_RX_BUF_DN<1>")
	)
	(segment
		(start 388.755128 -401.143216)
		(end 388.556754 -401.143216)
		(width 0.1016)
		(layer "F.Cu")
		(net "P5E_CPU0_P3_RX_BUF_DN<15>")
	)
	(segment
		(start 388.556754 -401.143216)
		(end 388.429754 -401.016216)
		(width 0.1016)
		(layer "F.Cu")
		(net "P5E_CPU0_P3_RX_BUF_DN<15>")
	)
	(segment
		(start 388.5184 -399.143982)
		(end 388.517892 -399.143474)
		(width 0.1016)
		(layer "F.Cu")
		(net "P5E_CPU0_P3_RX_BUF_DN<15>")
	)
	(segment
		(start 388.429754 -401.016216)
		(end 388.429754 -400.048984)
		(width 0.1016)
		(layer "F.Cu")
		(net "P5E_CPU0_P3_RX_BUF_DN<15>")
	)
	(segment
		(start 388.5184 -399.960338)
		(end 388.5184 -399.143982)
		(width 0.1016)
		(layer "F.Cu")
		(net "P5E_CPU0_P3_RX_BUF_DN<15>")
	)
	(segment
		(start 388.916418 -400.811238)
		(end 388.916418 -400.981926)
		(width 0.1016)
		(layer "F.Cu")
		(net "P5E_CPU0_P3_RX_BUF_DN<15>")
	)
	(segment
		(start 388.429754 -400.048984)
		(end 388.5184 -399.960338)
		(width 0.1016)
		(layer "F.Cu")
		(net "P5E_CPU0_P3_RX_BUF_DN<15>")
	)
	(segment
		(start 388.916418 -400.981926)
		(end 388.755128 -401.143216)
		(width 0.1016)
		(layer "F.Cu")
		(net "P5E_CPU0_P3_RX_BUF_DN<15>")
	)
	(segment
		(start 407.91638 -406.951434)
		(end 403.834854 -405.26081)
		(width 0.14224)
		(layer "In13.Cu")
		(net "P5E_CPU0_P3_RX_BUF_DN<15>")
	)
	(segment
		(start 418.606224 -421.57015)
		(end 418.670232 -421.41521)
		(width 0.14224)
		(layer "In13.Cu")
		(net "P5E_CPU0_P3_RX_BUF_DN<15>")
	)
	(segment
		(start 415.961322 -414.1089)
		(end 415.756598 -413.904176)
		(width 0.14224)
		(layer "In13.Cu")
		(net "P5E_CPU0_P3_RX_BUF_DN<15>")
	)
	(segment
		(start 388.1755 -402.648166)
		(end 388.1755 -401.394168)
		(width 0.14224)
		(layer "In13.Cu")
		(net "P5E_CPU0_P3_RX_BUF_DN<15>")
	)
	(segment
		(start 395.381226 -404.047198)
		(end 395.38148 -404.04669)
		(width 0.14224)
		(layer "In13.Cu")
		(net "P5E_CPU0_P3_RX_BUF_DN<15>")
	)
	(segment
		(start 417.134802 -422.5036)
		(end 417.901882 -422.1861)
		(width 0.14224)
		(layer "In13.Cu")
		(net "P5E_CPU0_P3_RX_BUF_DN<15>")
	)
	(segment
		(start 403.834854 -405.26081)
		(end 402.554186 -404.872444)
		(width 0.14224)
		(layer "In13.Cu")
		(net "P5E_CPU0_P3_RX_BUF_DN<15>")
	)
	(segment
		(start 416.992054 -414.52165)
		(end 416.737546 -414.267142)
		(width 0.14224)
		(layer "In13.Cu")
		(net "P5E_CPU0_P3_RX_BUF_DN<15>")
	)
	(segment
		(start 388.916418 -400.962622)
		(end 388.916418 -400.811238)
		(width 0.14224)
		(layer "In13.Cu")
		(net "P5E_CPU0_P3_RX_BUF_DN<15>")
	)
	(segment
		(start 418.388038 -421.84955)
		(end 418.606224 -421.57015)
		(width 0.14224)
		(layer "In13.Cu")
		(net "P5E_CPU0_P3_RX_BUF_DN<15>")
	)
	(segment
		(start 413.373824 -423.644314)
		(end 417.134802 -422.5036)
		(width 0.14224)
		(layer "In13.Cu")
		(net "P5E_CPU0_P3_RX_BUF_DN<15>")
	)
	(segment
		(start 411.776418 -434.715412)
		(end 411.776418 -424.644058)
		(width 0.14224)
		(layer "In13.Cu")
		(net "P5E_CPU0_P3_RX_BUF_DN<15>")
	)
	(segment
		(start 418.662866 -420.384478)
		(end 418.11067 -419.832282)
		(width 0.14224)
		(layer "In13.Cu")
		(net "P5E_CPU0_P3_RX_BUF_DN<15>")
	)
	(segment
		(start 391.016998 -403.617176)
		(end 388.796784 -403.175216)
		(width 0.14224)
		(layer "In13.Cu")
		(net "P5E_CPU0_P3_RX_BUF_DN<15>")
	)
	(segment
		(start 417.133532 -414.863026)
		(end 416.992054 -414.52165)
		(width 0.14224)
		(layer "In13.Cu")
		(net "P5E_CPU0_P3_RX_BUF_DN<15>")
	)
	(segment
		(start 415.602928 -413.506158)
		(end 415.60115 -412.336996)
		(width 0.14224)
		(layer "In13.Cu")
		(net "P5E_CPU0_P3_RX_BUF_DN<15>")
	)
	(segment
		(start 388.1755 -401.394168)
		(end 388.480046 -401.089622)
		(width 0.14224)
		(layer "In13.Cu")
		(net "P5E_CPU0_P3_RX_BUF_DN<15>")
	)
	(segment
		(start 412.696914 -423.779188)
		(end 413.373824 -423.644314)
		(width 0.14224)
		(layer "In13.Cu")
		(net "P5E_CPU0_P3_RX_BUF_DN<15>")
	)
	(segment
		(start 388.323328 -402.847302)
		(end 388.1755 -402.648166)
		(width 0.14224)
		(layer "In13.Cu")
		(net "P5E_CPU0_P3_RX_BUF_DN<15>")
	)
	(segment
		(start 416.737546 -414.267142)
		(end 416.668966 -414.238694)
		(width 0.14224)
		(layer "In13.Cu")
		(net "P5E_CPU0_P3_RX_BUF_DN<15>")
	)
	(segment
		(start 388.789418 -401.089622)
		(end 388.916418 -400.962622)
		(width 0.14224)
		(layer "In13.Cu")
		(net "P5E_CPU0_P3_RX_BUF_DN<15>")
	)
	(segment
		(start 412.346394 -423.902886)
		(end 412.492952 -423.841672)
		(width 0.14224)
		(layer "In13.Cu")
		(net "P5E_CPU0_P3_RX_BUF_DN<15>")
	)
	(segment
		(start 412.623 -435.03088)
		(end 412.091886 -435.03088)
		(width 0.14224)
		(layer "In13.Cu")
		(net "P5E_CPU0_P3_RX_BUF_DN<15>")
	)
	(segment
		(start 412.75 -435.489858)
		(end 412.75 -435.15788)
		(width 0.14224)
		(layer "In13.Cu")
		(net "P5E_CPU0_P3_RX_BUF_DN<15>")
	)
	(segment
		(start 412.091886 -435.03088)
		(end 411.776418 -434.715412)
		(width 0.14224)
		(layer "In13.Cu")
		(net "P5E_CPU0_P3_RX_BUF_DN<15>")
	)
	(segment
		(start 401.372324 -404.63724)
		(end 395.381226 -404.047198)
		(width 0.14224)
		(layer "In13.Cu")
		(net "P5E_CPU0_P3_RX_BUF_DN<15>")
	)
	(segment
		(start 411.922976 -424.276774)
		(end 412.148528 -424.039538)
		(width 0.14224)
		(layer "In13.Cu")
		(net "P5E_CPU0_P3_RX_BUF_DN<15>")
	)
	(segment
		(start 416.668966 -414.238694)
		(end 416.274758 -414.238694)
		(width 0.14224)
		(layer "In13.Cu")
		(net "P5E_CPU0_P3_RX_BUF_DN<15>")
	)
	(segment
		(start 417.133532 -418.718492)
		(end 417.133532 -414.863026)
		(width 0.14224)
		(layer "In13.Cu")
		(net "P5E_CPU0_P3_RX_BUF_DN<15>")
	)
	(segment
		(start 415.367978 -411.930088)
		(end 407.91638 -406.951434)
		(width 0.14224)
		(layer "In13.Cu")
		(net "P5E_CPU0_P3_RX_BUF_DN<15>")
	)
	(segment
		(start 388.480046 -401.089622)
		(end 388.789418 -401.089622)
		(width 0.14224)
		(layer "In13.Cu")
		(net "P5E_CPU0_P3_RX_BUF_DN<15>")
	)
	(segment
		(start 418.670232 -421.41521)
		(end 418.700204 -421.264842)
		(width 0.14224)
		(layer "In13.Cu")
		(net "P5E_CPU0_P3_RX_BUF_DN<15>")
	)
	(segment
		(start 418.018468 -422.123616)
		(end 418.388038 -421.84955)
		(width 0.14224)
		(layer "In13.Cu")
		(net "P5E_CPU0_P3_RX_BUF_DN<15>")
	)
	(segment
		(start 412.75 -435.15788)
		(end 412.623 -435.03088)
		(width 0.14224)
		(layer "In13.Cu")
		(net "P5E_CPU0_P3_RX_BUF_DN<15>")
	)
	(segment
		(start 402.554186 -404.872444)
		(end 401.372324 -404.63724)
		(width 0.14224)
		(layer "In13.Cu")
		(net "P5E_CPU0_P3_RX_BUF_DN<15>")
	)
	(segment
		(start 417.901882 -422.1861)
		(end 418.018468 -422.123616)
		(width 0.14224)
		(layer "In13.Cu")
		(net "P5E_CPU0_P3_RX_BUF_DN<15>")
	)
	(segment
		(start 418.700204 -421.264842)
		(end 418.700204 -420.474394)
		(width 0.14224)
		(layer "In13.Cu")
		(net "P5E_CPU0_P3_RX_BUF_DN<15>")
	)
	(segment
		(start 418.11067 -419.832282)
		(end 417.721796 -419.671246)
		(width 0.14224)
		(layer "In13.Cu")
		(net "P5E_CPU0_P3_RX_BUF_DN<15>")
	)
	(segment
		(start 417.39185 -419.341046)
		(end 417.133532 -418.718492)
		(width 0.14224)
		(layer "In13.Cu")
		(net "P5E_CPU0_P3_RX_BUF_DN<15>")
	)
	(segment
		(start 395.38148 -404.04669)
		(end 391.016998 -403.617176)
		(width 0.14224)
		(layer "In13.Cu")
		(net "P5E_CPU0_P3_RX_BUF_DN<15>")
	)
	(segment
		(start 415.583878 -412.240984)
		(end 415.57829 -412.225744)
		(width 0.14224)
		(layer "In13.Cu")
		(net "P5E_CPU0_P3_RX_BUF_DN<15>")
	)
	(arc
		(start 417.721796 -419.671246)
		(mid 417.524021 -419.538928)
		(end 417.39185 -419.341046)
		(width 0.14224)
		(layer "In13.Cu")
		(net "P5E_CPU0_P3_RX_BUF_DN<15>")
	)
	(arc
		(start 412.148528 -424.039538)
		(mid 412.240408 -423.960999)
		(end 412.346394 -423.902886)
		(width 0.14224)
		(layer "In13.Cu")
		(net "P5E_CPU0_P3_RX_BUF_DN<15>")
	)
	(arc
		(start 388.796784 -403.175216)
		(mid 388.532985 -403.050348)
		(end 388.323328 -402.847302)
		(width 0.14224)
		(layer "In13.Cu")
		(net "P5E_CPU0_P3_RX_BUF_DN<15>")
	)
	(arc
		(start 415.60115 -412.336996)
		(mid 415.595632 -412.288429)
		(end 415.583878 -412.240984)
		(width 0.14224)
		(layer "In13.Cu")
		(net "P5E_CPU0_P3_RX_BUF_DN<15>")
	)
	(arc
		(start 416.274758 -414.238694)
		(mid 416.105141 -414.204955)
		(end 415.961322 -414.1089)
		(width 0.14224)
		(layer "In13.Cu")
		(net "P5E_CPU0_P3_RX_BUF_DN<15>")
	)
	(arc
		(start 418.700204 -420.474394)
		(mid 418.690502 -420.42571)
		(end 418.662866 -420.384478)
		(width 0.14224)
		(layer "In13.Cu")
		(net "P5E_CPU0_P3_RX_BUF_DN<15>")
	)
	(arc
		(start 415.756598 -413.904176)
		(mid 415.671045 -413.790591)
		(end 415.6202 -413.657796)
		(width 0.14224)
		(layer "In13.Cu")
		(net "P5E_CPU0_P3_RX_BUF_DN<15>")
	)
	(arc
		(start 411.776418 -424.644058)
		(mid 411.814401 -424.446328)
		(end 411.922976 -424.276774)
		(width 0.14224)
		(layer "In13.Cu")
		(net "P5E_CPU0_P3_RX_BUF_DN<15>")
	)
	(arc
		(start 412.492952 -423.841672)
		(mid 412.593363 -423.805306)
		(end 412.696914 -423.779188)
		(width 0.14224)
		(layer "In13.Cu")
		(net "P5E_CPU0_P3_RX_BUF_DN<15>")
	)
	(arc
		(start 415.6202 -413.657796)
		(mid 415.607283 -413.582464)
		(end 415.602928 -413.506158)
		(width 0.14224)
		(layer "In13.Cu")
		(net "P5E_CPU0_P3_RX_BUF_DN<15>")
	)
	(arc
		(start 415.57829 -412.225744)
		(mid 415.551016 -412.158355)
		(end 415.518346 -412.09341)
		(width 0.14224)
		(layer "In13.Cu")
		(net "P5E_CPU0_P3_RX_BUF_DN<15>")
	)
	(arc
		(start 415.518346 -412.09341)
		(mid 415.452892 -412.002791)
		(end 415.367978 -411.930088)
		(width 0.14224)
		(layer "In13.Cu")
		(net "P5E_CPU0_P3_RX_BUF_DN<15>")
	)
	(segment
		(start 387.356858 -401.143216)
		(end 387.229858 -401.016216)
		(width 0.1016)
		(layer "F.Cu")
		(net "P5E_CPU0_P3_RX_BUF_DN<14>")
	)
	(segment
		(start 387.229858 -401.016216)
		(end 387.229858 -400.048984)
		(width 0.1016)
		(layer "F.Cu")
		(net "P5E_CPU0_P3_RX_BUF_DN<14>")
	)
	(segment
		(start 387.318504 -399.143982)
		(end 387.317996 -399.143474)
		(width 0.1016)
		(layer "F.Cu")
		(net "P5E_CPU0_P3_RX_BUF_DN<14>")
	)
	(segment
		(start 387.716522 -400.811238)
		(end 387.716522 -400.97583)
		(width 0.1016)
		(layer "F.Cu")
		(net "P5E_CPU0_P3_RX_BUF_DN<14>")
	)
	(segment
		(start 387.716522 -400.97583)
		(end 387.549136 -401.143216)
		(width 0.1016)
		(layer "F.Cu")
		(net "P5E_CPU0_P3_RX_BUF_DN<14>")
	)
	(segment
		(start 387.318504 -399.960338)
		(end 387.318504 -399.143982)
		(width 0.1016)
		(layer "F.Cu")
		(net "P5E_CPU0_P3_RX_BUF_DN<14>")
	)
	(segment
		(start 387.549136 -401.143216)
		(end 387.356858 -401.143216)
		(width 0.1016)
		(layer "F.Cu")
		(net "P5E_CPU0_P3_RX_BUF_DN<14>")
	)
	(segment
		(start 387.229858 -400.048984)
		(end 387.318504 -399.960338)
		(width 0.1016)
		(layer "F.Cu")
		(net "P5E_CPU0_P3_RX_BUF_DN<14>")
	)
	(segment
		(start 403.814026 -406.575514)
		(end 395.13764 -405.269446)
		(width 0.14224)
		(layer "In13.Cu")
		(net "P5E_CPU0_P3_RX_BUF_DN<14>")
	)
	(segment
		(start 386.975604 -402.768308)
		(end 386.975604 -401.394168)
		(width 0.14224)
		(layer "In13.Cu")
		(net "P5E_CPU0_P3_RX_BUF_DN<14>")
	)
	(segment
		(start 412.46044 -412.115)
		(end 412.111444 -411.592776)
		(width 0.14224)
		(layer "In13.Cu")
		(net "P5E_CPU0_P3_RX_BUF_DN<14>")
	)
	(segment
		(start 388.441438 -404.055834)
		(end 387.877304 -403.88413)
		(width 0.14224)
		(layer "In13.Cu")
		(net "P5E_CPU0_P3_RX_BUF_DN<14>")
	)
	(segment
		(start 414.070292 -414.863026)
		(end 413.928814 -414.52165)
		(width 0.14224)
		(layer "In13.Cu")
		(net "P5E_CPU0_P3_RX_BUF_DN<14>")
	)
	(segment
		(start 395.13764 -405.269446)
		(end 394.952982 -405.185626)
		(width 0.14224)
		(layer "In13.Cu")
		(net "P5E_CPU0_P3_RX_BUF_DN<14>")
	)
	(segment
		(start 413.928814 -414.52165)
		(end 413.674306 -414.267142)
		(width 0.14224)
		(layer "In13.Cu")
		(net "P5E_CPU0_P3_RX_BUF_DN<14>")
	)
	(segment
		(start 414.317434 -419.279324)
		(end 414.070292 -418.683694)
		(width 0.14224)
		(layer "In13.Cu")
		(net "P5E_CPU0_P3_RX_BUF_DN<14>")
	)
	(segment
		(start 412.538672 -413.623252)
		(end 412.538672 -412.303722)
		(width 0.14224)
		(layer "In13.Cu")
		(net "P5E_CPU0_P3_RX_BUF_DN<14>")
	)
	(segment
		(start 411.53969 -410.981652)
		(end 410.047948 -409.83154)
		(width 0.14224)
		(layer "In13.Cu")
		(net "P5E_CPU0_P3_RX_BUF_DN<14>")
	)
	(segment
		(start 414.070292 -418.683694)
		(end 414.070292 -414.863026)
		(width 0.14224)
		(layer "In13.Cu")
		(net "P5E_CPU0_P3_RX_BUF_DN<14>")
	)
	(segment
		(start 406.146 -407.557732)
		(end 403.814026 -406.575514)
		(width 0.14224)
		(layer "In13.Cu")
		(net "P5E_CPU0_P3_RX_BUF_DN<14>")
	)
	(segment
		(start 387.716522 -400.962622)
		(end 387.716522 -400.811238)
		(width 0.14224)
		(layer "In13.Cu")
		(net "P5E_CPU0_P3_RX_BUF_DN<14>")
	)
	(segment
		(start 387.28015 -401.089622)
		(end 387.589522 -401.089622)
		(width 0.14224)
		(layer "In13.Cu")
		(net "P5E_CPU0_P3_RX_BUF_DN<14>")
	)
	(segment
		(start 413.674306 -414.267142)
		(end 413.605726 -414.238694)
		(width 0.14224)
		(layer "In13.Cu")
		(net "P5E_CPU0_P3_RX_BUF_DN<14>")
	)
	(segment
		(start 393.050014 -404.974806)
		(end 388.493254 -404.069042)
		(width 0.14224)
		(layer "In13.Cu")
		(net "P5E_CPU0_P3_RX_BUF_DN<14>")
	)
	(segment
		(start 408.623008 -409.001722)
		(end 408.118564 -408.70759)
		(width 0.14224)
		(layer "In13.Cu")
		(net "P5E_CPU0_P3_RX_BUF_DN<14>")
	)
	(segment
		(start 410.750004 -434.157882)
		(end 410.623004 -434.030882)
		(width 0.14224)
		(layer "In13.Cu")
		(net "P5E_CPU0_P3_RX_BUF_DN<14>")
	)
	(segment
		(start 410.750004 -434.48986)
		(end 410.750004 -434.157882)
		(width 0.14224)
		(layer "In13.Cu")
		(net "P5E_CPU0_P3_RX_BUF_DN<14>")
	)
	(segment
		(start 412.538672 -412.303722)
		(end 412.46044 -412.115)
		(width 0.14224)
		(layer "In13.Cu")
		(net "P5E_CPU0_P3_RX_BUF_DN<14>")
	)
	(segment
		(start 408.118564 -408.70759)
		(end 408.118564 -408.707336)
		(width 0.14224)
		(layer "In13.Cu")
		(net "P5E_CPU0_P3_RX_BUF_DN<14>")
	)
	(segment
		(start 409.776422 -433.727606)
		(end 409.776422 -424.601894)
		(width 0.14224)
		(layer "In13.Cu")
		(net "P5E_CPU0_P3_RX_BUF_DN<14>")
	)
	(segment
		(start 386.975604 -401.394168)
		(end 387.28015 -401.089622)
		(width 0.14224)
		(layer "In13.Cu")
		(net "P5E_CPU0_P3_RX_BUF_DN<14>")
	)
	(segment
		(start 415.042096 -419.829996)
		(end 414.74517 -419.70706)
		(width 0.14224)
		(layer "In13.Cu")
		(net "P5E_CPU0_P3_RX_BUF_DN<14>")
	)
	(segment
		(start 394.435838 -405.183086)
		(end 393.16152 -404.993856)
		(width 0.14224)
		(layer "In13.Cu")
		(net "P5E_CPU0_P3_RX_BUF_DN<14>")
	)
	(segment
		(start 410.623004 -434.030882)
		(end 410.079698 -434.030882)
		(width 0.14224)
		(layer "In13.Cu")
		(net "P5E_CPU0_P3_RX_BUF_DN<14>")
	)
	(segment
		(start 393.050776 -404.97506)
		(end 393.050014 -404.974806)
		(width 0.14224)
		(layer "In13.Cu")
		(net "P5E_CPU0_P3_RX_BUF_DN<14>")
	)
	(segment
		(start 412.654242 -413.902144)
		(end 412.538672 -413.623252)
		(width 0.14224)
		(layer "In13.Cu")
		(net "P5E_CPU0_P3_RX_BUF_DN<14>")
	)
	(segment
		(start 408.623262 -409.001722)
		(end 408.623008 -409.001722)
		(width 0.14224)
		(layer "In13.Cu")
		(net "P5E_CPU0_P3_RX_BUF_DN<14>")
	)
	(segment
		(start 410.079698 -434.030882)
		(end 409.776422 -433.727606)
		(width 0.14224)
		(layer "In13.Cu")
		(net "P5E_CPU0_P3_RX_BUF_DN<14>")
	)
	(segment
		(start 413.093154 -414.238694)
		(end 412.918148 -414.16605)
		(width 0.14224)
		(layer "In13.Cu")
		(net "P5E_CPU0_P3_RX_BUF_DN<14>")
	)
	(segment
		(start 410.047948 -409.83154)
		(end 408.623262 -409.001722)
		(width 0.14224)
		(layer "In13.Cu")
		(net "P5E_CPU0_P3_RX_BUF_DN<14>")
	)
	(segment
		(start 408.118564 -408.707336)
		(end 406.146 -407.557732)
		(width 0.14224)
		(layer "In13.Cu")
		(net "P5E_CPU0_P3_RX_BUF_DN<14>")
	)
	(segment
		(start 412.111444 -411.592776)
		(end 411.53969 -410.981652)
		(width 0.14224)
		(layer "In13.Cu")
		(net "P5E_CPU0_P3_RX_BUF_DN<14>")
	)
	(segment
		(start 412.918148 -414.16605)
		(end 412.654242 -413.902144)
		(width 0.14224)
		(layer "In13.Cu")
		(net "P5E_CPU0_P3_RX_BUF_DN<14>")
	)
	(segment
		(start 387.589522 -401.089622)
		(end 387.716522 -400.962622)
		(width 0.14224)
		(layer "In13.Cu")
		(net "P5E_CPU0_P3_RX_BUF_DN<14>")
	)
	(segment
		(start 415.601912 -421.350186)
		(end 415.601912 -420.44239)
		(width 0.14224)
		(layer "In13.Cu")
		(net "P5E_CPU0_P3_RX_BUF_DN<14>")
	)
	(segment
		(start 412.270448 -422.924732)
		(end 415.161222 -421.961056)
		(width 0.14224)
		(layer "In13.Cu")
		(net "P5E_CPU0_P3_RX_BUF_DN<14>")
	)
	(segment
		(start 415.564574 -420.352474)
		(end 415.042096 -419.829996)
		(width 0.14224)
		(layer "In13.Cu")
		(net "P5E_CPU0_P3_RX_BUF_DN<14>")
	)
	(segment
		(start 413.605726 -414.238694)
		(end 413.093154 -414.238694)
		(width 0.14224)
		(layer "In13.Cu")
		(net "P5E_CPU0_P3_RX_BUF_DN<14>")
	)
	(segment
		(start 410.006038 -424.187112)
		(end 411.298898 -423.379392)
		(width 0.14224)
		(layer "In13.Cu")
		(net "P5E_CPU0_P3_RX_BUF_DN<14>")
	)
	(arc
		(start 414.74517 -419.70706)
		(mid 414.488785 -419.535709)
		(end 414.317434 -419.279324)
		(width 0.14224)
		(layer "In13.Cu")
		(net "P5E_CPU0_P3_RX_BUF_DN<14>")
	)
	(arc
		(start 415.161222 -421.961056)
		(mid 415.480145 -421.726745)
		(end 415.601912 -421.350186)
		(width 0.14224)
		(layer "In13.Cu")
		(net "P5E_CPU0_P3_RX_BUF_DN<14>")
	)
	(arc
		(start 394.635228 -405.167084)
		(mid 394.536449 -405.186464)
		(end 394.435838 -405.183086)
		(width 0.14224)
		(layer "In13.Cu")
		(net "P5E_CPU0_P3_RX_BUF_DN<14>")
	)
	(arc
		(start 387.292596 -403.53361)
		(mid 387.057983 -403.182486)
		(end 386.975604 -402.768308)
		(width 0.14224)
		(layer "In13.Cu")
		(net "P5E_CPU0_P3_RX_BUF_DN<14>")
	)
	(arc
		(start 415.601912 -420.44239)
		(mid 415.59221 -420.393706)
		(end 415.564574 -420.352474)
		(width 0.14224)
		(layer "In13.Cu")
		(net "P5E_CPU0_P3_RX_BUF_DN<14>")
	)
	(arc
		(start 387.877304 -403.88413)
		(mid 387.563352 -403.744898)
		(end 387.292596 -403.53361)
		(width 0.14224)
		(layer "In13.Cu")
		(net "P5E_CPU0_P3_RX_BUF_DN<14>")
	)
	(arc
		(start 409.776422 -424.601894)
		(mid 409.837602 -424.364818)
		(end 410.006038 -424.187112)
		(width 0.14224)
		(layer "In13.Cu")
		(net "P5E_CPU0_P3_RX_BUF_DN<14>")
	)
	(arc
		(start 411.298898 -423.379392)
		(mid 411.439193 -423.295381)
		(end 411.582616 -423.216832)
		(width 0.14224)
		(layer "In13.Cu")
		(net "P5E_CPU0_P3_RX_BUF_DN<14>")
	)
	(arc
		(start 411.582616 -423.216832)
		(mid 411.920685 -423.057013)
		(end 412.270448 -422.924732)
		(width 0.14224)
		(layer "In13.Cu")
		(net "P5E_CPU0_P3_RX_BUF_DN<14>")
	)
	(arc
		(start 394.952982 -405.185626)
		(mid 394.795832 -405.146851)
		(end 394.635228 -405.167084)
		(width 0.14224)
		(layer "In13.Cu")
		(net "P5E_CPU0_P3_RX_BUF_DN<14>")
	)
	(arc
		(start 393.16152 -404.993856)
		(mid 393.106046 -404.985061)
		(end 393.050776 -404.97506)
		(width 0.14224)
		(layer "In13.Cu")
		(net "P5E_CPU0_P3_RX_BUF_DN<14>")
	)
	(arc
		(start 388.493254 -404.069042)
		(mid 388.467182 -404.063082)
		(end 388.441438 -404.055834)
		(width 0.14224)
		(layer "In13.Cu")
		(net "P5E_CPU0_P3_RX_BUF_DN<14>")
	)
	(segment
		(start 386.038344 -400.040348)
		(end 386.038344 -401.016216)
		(width 0.1016)
		(layer "F.Cu")
		(net "P5E_CPU0_P3_RX_BUF_DN<13>")
	)
	(segment
		(start 386.375656 -401.143216)
		(end 386.516372 -401.0025)
		(width 0.1016)
		(layer "F.Cu")
		(net "P5E_CPU0_P3_RX_BUF_DN<13>")
	)
	(segment
		(start 386.516372 -401.0025)
		(end 386.516372 -400.811238)
		(width 0.1016)
		(layer "F.Cu")
		(net "P5E_CPU0_P3_RX_BUF_DN<13>")
	)
	(segment
		(start 386.038344 -401.016216)
		(end 386.165344 -401.143216)
		(width 0.1016)
		(layer "F.Cu")
		(net "P5E_CPU0_P3_RX_BUF_DN<13>")
	)
	(segment
		(start 386.117846 -399.143474)
		(end 386.118354 -399.143982)
		(width 0.1016)
		(layer "F.Cu")
		(net "P5E_CPU0_P3_RX_BUF_DN<13>")
	)
	(segment
		(start 386.118354 -399.143982)
		(end 386.118354 -399.960338)
		(width 0.1016)
		(layer "F.Cu")
		(net "P5E_CPU0_P3_RX_BUF_DN<13>")
	)
	(segment
		(start 386.165344 -401.143216)
		(end 386.375656 -401.143216)
		(width 0.1016)
		(layer "F.Cu")
		(net "P5E_CPU0_P3_RX_BUF_DN<13>")
	)
	(segment
		(start 386.118354 -399.960338)
		(end 386.038344 -400.040348)
		(width 0.1016)
		(layer "F.Cu")
		(net "P5E_CPU0_P3_RX_BUF_DN<13>")
	)
	(segment
		(start 409.260802 -411.87116)
		(end 407.992326 -411.023562)
		(width 0.14224)
		(layer "In13.Cu")
		(net "P5E_CPU0_P3_RX_BUF_DN<13>")
	)
	(segment
		(start 411.007052 -418.730938)
		(end 411.007052 -414.78962)
		(width 0.14224)
		(layer "In13.Cu")
		(net "P5E_CPU0_P3_RX_BUF_DN<13>")
	)
	(segment
		(start 386.516372 -400.962622)
		(end 386.516372 -400.811238)
		(width 0.14224)
		(layer "In13.Cu")
		(net "P5E_CPU0_P3_RX_BUF_DN<13>")
	)
	(segment
		(start 405.402542 -409.292298)
		(end 402.22424 -407.83637)
		(width 0.14224)
		(layer "In13.Cu")
		(net "P5E_CPU0_P3_RX_BUF_DN<13>")
	)
	(segment
		(start 412.538672 -421.154352)
		(end 412.538672 -420.474394)
		(width 0.14224)
		(layer "In13.Cu")
		(net "P5E_CPU0_P3_RX_BUF_DN<13>")
	)
	(segment
		(start 410.611066 -414.267142)
		(end 410.542486 -414.238694)
		(width 0.14224)
		(layer "In13.Cu")
		(net "P5E_CPU0_P3_RX_BUF_DN<13>")
	)
	(segment
		(start 396.863824 -407.041096)
		(end 392.245342 -406.004014)
		(width 0.14224)
		(layer "In13.Cu")
		(net "P5E_CPU0_P3_RX_BUF_DN<13>")
	)
	(segment
		(start 399.461482 -407.426668)
		(end 399.461482 -407.42616)
		(width 0.14224)
		(layer "In13.Cu")
		(net "P5E_CPU0_P3_RX_BUF_DN<13>")
	)
	(segment
		(start 410.91739 -414.573466)
		(end 410.611066 -414.267142)
		(width 0.14224)
		(layer "In13.Cu")
		(net "P5E_CPU0_P3_RX_BUF_DN<13>")
	)
	(segment
		(start 411.885892 -422.055036)
		(end 412.028386 -421.983408)
		(width 0.14224)
		(layer "In13.Cu")
		(net "P5E_CPU0_P3_RX_BUF_DN<13>")
	)
	(segment
		(start 409.261564 -411.871922)
		(end 409.260802 -411.87116)
		(width 0.14224)
		(layer "In13.Cu")
		(net "P5E_CPU0_P3_RX_BUF_DN<13>")
	)
	(segment
		(start 411.207458 -419.214046)
		(end 411.207712 -419.214046)
		(width 0.14224)
		(layer "In13.Cu")
		(net "P5E_CPU0_P3_RX_BUF_DN<13>")
	)
	(segment
		(start 386.700014 -404.344124)
		(end 386.043678 -403.687788)
		(width 0.14224)
		(layer "In13.Cu")
		(net "P5E_CPU0_P3_RX_BUF_DN<13>")
	)
	(segment
		(start 411.207712 -419.214046)
		(end 411.007052 -418.730938)
		(width 0.14224)
		(layer "In13.Cu")
		(net "P5E_CPU0_P3_RX_BUF_DN<13>")
	)
	(segment
		(start 407.992326 -411.023562)
		(end 405.402542 -409.292298)
		(width 0.14224)
		(layer "In13.Cu")
		(net "P5E_CPU0_P3_RX_BUF_DN<13>")
	)
	(segment
		(start 408.750008 -435.15788)
		(end 408.623008 -435.03088)
		(width 0.14224)
		(layer "In13.Cu")
		(net "P5E_CPU0_P3_RX_BUF_DN<13>")
	)
	(segment
		(start 408.750008 -435.489858)
		(end 408.750008 -435.15788)
		(width 0.14224)
		(layer "In13.Cu")
		(net "P5E_CPU0_P3_RX_BUF_DN<13>")
	)
	(segment
		(start 412.501334 -420.384478)
		(end 411.9245 -419.807644)
		(width 0.14224)
		(layer "In13.Cu")
		(net "P5E_CPU0_P3_RX_BUF_DN<13>")
	)
	(segment
		(start 409.890722 -422.881298)
		(end 411.885892 -422.055036)
		(width 0.14224)
		(layer "In13.Cu")
		(net "P5E_CPU0_P3_RX_BUF_DN<13>")
	)
	(segment
		(start 411.9245 -419.807644)
		(end 411.714696 -419.720776)
		(width 0.14224)
		(layer "In13.Cu")
		(net "P5E_CPU0_P3_RX_BUF_DN<13>")
	)
	(segment
		(start 408.623008 -435.03088)
		(end 408.158696 -435.03088)
		(width 0.14224)
		(layer "In13.Cu")
		(net "P5E_CPU0_P3_RX_BUF_DN<13>")
	)
	(segment
		(start 411.007052 -414.78962)
		(end 410.91739 -414.573466)
		(width 0.14224)
		(layer "In13.Cu")
		(net "P5E_CPU0_P3_RX_BUF_DN<13>")
	)
	(segment
		(start 389.692896 -405.42591)
		(end 387.220714 -404.676102)
		(width 0.14224)
		(layer "In13.Cu")
		(net "P5E_CPU0_P3_RX_BUF_DN<13>")
	)
	(segment
		(start 409.347162 -411.957266)
		(end 409.261564 -411.871922)
		(width 0.14224)
		(layer "In13.Cu")
		(net "P5E_CPU0_P3_RX_BUF_DN<13>")
	)
	(segment
		(start 399.461482 -407.42616)
		(end 396.863824 -407.041096)
		(width 0.14224)
		(layer "In13.Cu")
		(net "P5E_CPU0_P3_RX_BUF_DN<13>")
	)
	(segment
		(start 385.775454 -401.394168)
		(end 386.08 -401.089622)
		(width 0.14224)
		(layer "In13.Cu")
		(net "P5E_CPU0_P3_RX_BUF_DN<13>")
	)
	(segment
		(start 407.776426 -434.531516)
		(end 407.776426 -424.73118)
		(width 0.14224)
		(layer "In13.Cu")
		(net "P5E_CPU0_P3_RX_BUF_DN<13>")
	)
	(segment
		(start 410.029914 -414.238694)
		(end 409.854908 -414.16605)
		(width 0.14224)
		(layer "In13.Cu")
		(net "P5E_CPU0_P3_RX_BUF_DN<13>")
	)
	(segment
		(start 409.591002 -413.902144)
		(end 409.475432 -413.622998)
		(width 0.14224)
		(layer "In13.Cu")
		(net "P5E_CPU0_P3_RX_BUF_DN<13>")
	)
	(segment
		(start 409.475432 -412.266892)
		(end 409.347162 -411.957266)
		(width 0.14224)
		(layer "In13.Cu")
		(net "P5E_CPU0_P3_RX_BUF_DN<13>")
	)
	(segment
		(start 408.022044 -424.107864)
		(end 409.730702 -422.96715)
		(width 0.14224)
		(layer "In13.Cu")
		(net "P5E_CPU0_P3_RX_BUF_DN<13>")
	)
	(segment
		(start 392.245342 -406.004014)
		(end 392.245088 -406.00376)
		(width 0.14224)
		(layer "In13.Cu")
		(net "P5E_CPU0_P3_RX_BUF_DN<13>")
	)
	(segment
		(start 386.08 -401.089622)
		(end 386.389372 -401.089622)
		(width 0.14224)
		(layer "In13.Cu")
		(net "P5E_CPU0_P3_RX_BUF_DN<13>")
	)
	(segment
		(start 386.389372 -401.089622)
		(end 386.516372 -400.962622)
		(width 0.14224)
		(layer "In13.Cu")
		(net "P5E_CPU0_P3_RX_BUF_DN<13>")
	)
	(segment
		(start 408.04465 -434.983636)
		(end 407.90622 -434.845206)
		(width 0.14224)
		(layer "In13.Cu")
		(net "P5E_CPU0_P3_RX_BUF_DN<13>")
	)
	(segment
		(start 410.542486 -414.238694)
		(end 410.029914 -414.238694)
		(width 0.14224)
		(layer "In13.Cu")
		(net "P5E_CPU0_P3_RX_BUF_DN<13>")
	)
	(segment
		(start 409.475432 -413.622998)
		(end 409.475432 -412.266892)
		(width 0.14224)
		(layer "In13.Cu")
		(net "P5E_CPU0_P3_RX_BUF_DN<13>")
	)
	(segment
		(start 402.22424 -407.83637)
		(end 399.461482 -407.426668)
		(width 0.14224)
		(layer "In13.Cu")
		(net "P5E_CPU0_P3_RX_BUF_DN<13>")
	)
	(segment
		(start 385.775454 -403.040342)
		(end 385.775454 -401.394168)
		(width 0.14224)
		(layer "In13.Cu")
		(net "P5E_CPU0_P3_RX_BUF_DN<13>")
	)
	(segment
		(start 392.245088 -406.00376)
		(end 389.820658 -405.459692)
		(width 0.14224)
		(layer "In13.Cu")
		(net "P5E_CPU0_P3_RX_BUF_DN<13>")
	)
	(segment
		(start 409.854908 -414.16605)
		(end 409.591002 -413.902144)
		(width 0.14224)
		(layer "In13.Cu")
		(net "P5E_CPU0_P3_RX_BUF_DN<13>")
	)
	(arc
		(start 387.220714 -404.676102)
		(mid 387.137412 -404.64643)
		(end 387.057392 -404.608792)
		(width 0.14224)
		(layer "In13.Cu")
		(net "P5E_CPU0_P3_RX_BUF_DN<13>")
	)
	(arc
		(start 389.820658 -405.459692)
		(mid 389.756465 -405.443979)
		(end 389.692896 -405.42591)
		(width 0.14224)
		(layer "In13.Cu")
		(net "P5E_CPU0_P3_RX_BUF_DN<13>")
	)
	(arc
		(start 412.028386 -421.983408)
		(mid 412.400779 -421.641071)
		(end 412.538672 -421.154352)
		(width 0.14224)
		(layer "In13.Cu")
		(net "P5E_CPU0_P3_RX_BUF_DN<13>")
	)
	(arc
		(start 407.776426 -424.73118)
		(mid 407.790655 -424.543076)
		(end 407.833322 -424.359324)
		(width 0.14224)
		(layer "In13.Cu")
		(net "P5E_CPU0_P3_RX_BUF_DN<13>")
	)
	(arc
		(start 412.538672 -420.474394)
		(mid 412.52897 -420.42571)
		(end 412.501334 -420.384478)
		(width 0.14224)
		(layer "In13.Cu")
		(net "P5E_CPU0_P3_RX_BUF_DN<13>")
	)
	(arc
		(start 387.057392 -404.608792)
		(mid 386.86888 -404.489724)
		(end 386.700014 -404.344124)
		(width 0.14224)
		(layer "In13.Cu")
		(net "P5E_CPU0_P3_RX_BUF_DN<13>")
	)
	(arc
		(start 407.90622 -434.845206)
		(mid 407.810084 -434.701283)
		(end 407.776426 -434.531516)
		(width 0.14224)
		(layer "In13.Cu")
		(net "P5E_CPU0_P3_RX_BUF_DN<13>")
	)
	(arc
		(start 409.730702 -422.96715)
		(mid 409.808607 -422.9203)
		(end 409.890722 -422.881298)
		(width 0.14224)
		(layer "In13.Cu")
		(net "P5E_CPU0_P3_RX_BUF_DN<13>")
	)
	(arc
		(start 386.043678 -403.687788)
		(mid 385.845141 -403.390751)
		(end 385.775454 -403.040342)
		(width 0.14224)
		(layer "In13.Cu")
		(net "P5E_CPU0_P3_RX_BUF_DN<13>")
	)
	(arc
		(start 408.158696 -435.03088)
		(mid 408.096973 -435.018603)
		(end 408.04465 -434.983636)
		(width 0.14224)
		(layer "In13.Cu")
		(net "P5E_CPU0_P3_RX_BUF_DN<13>")
	)
	(arc
		(start 411.714696 -419.720776)
		(mid 411.410706 -419.517841)
		(end 411.207458 -419.214046)
		(width 0.14224)
		(layer "In13.Cu")
		(net "P5E_CPU0_P3_RX_BUF_DN<13>")
	)
	(arc
		(start 407.833322 -424.359324)
		(mid 407.906143 -424.217423)
		(end 408.022044 -424.107864)
		(width 0.14224)
		(layer "In13.Cu")
		(net "P5E_CPU0_P3_RX_BUF_DN<13>")
	)
	(segment
		(start 384.918458 -399.960338)
		(end 384.918458 -399.143982)
		(width 0.1016)
		(layer "F.Cu")
		(net "P5E_CPU0_P3_RX_BUF_DN<12>")
	)
	(segment
		(start 384.918458 -399.143982)
		(end 384.91795 -399.143474)
		(width 0.1016)
		(layer "F.Cu")
		(net "P5E_CPU0_P3_RX_BUF_DN<12>")
	)
	(segment
		(start 385.316476 -400.977862)
		(end 385.151122 -401.143216)
		(width 0.1016)
		(layer "F.Cu")
		(net "P5E_CPU0_P3_RX_BUF_DN<12>")
	)
	(segment
		(start 384.829812 -400.048984)
		(end 384.918458 -399.960338)
		(width 0.1016)
		(layer "F.Cu")
		(net "P5E_CPU0_P3_RX_BUF_DN<12>")
	)
	(segment
		(start 384.829812 -401.016216)
		(end 384.829812 -400.048984)
		(width 0.1016)
		(layer "F.Cu")
		(net "P5E_CPU0_P3_RX_BUF_DN<12>")
	)
	(segment
		(start 385.151122 -401.143216)
		(end 384.956812 -401.143216)
		(width 0.1016)
		(layer "F.Cu")
		(net "P5E_CPU0_P3_RX_BUF_DN<12>")
	)
	(segment
		(start 385.316476 -400.811238)
		(end 385.316476 -400.977862)
		(width 0.1016)
		(layer "F.Cu")
		(net "P5E_CPU0_P3_RX_BUF_DN<12>")
	)
	(segment
		(start 384.956812 -401.143216)
		(end 384.829812 -401.016216)
		(width 0.1016)
		(layer "F.Cu")
		(net "P5E_CPU0_P3_RX_BUF_DN<12>")
	)
	(segment
		(start 406.623012 -434.030882)
		(end 406.079706 -434.030882)
		(width 0.14224)
		(layer "In13.Cu")
		(net "P5E_CPU0_P3_RX_BUF_DN<12>")
	)
	(segment
		(start 409.475432 -421.497506)
		(end 409.475432 -420.411402)
		(width 0.14224)
		(layer "In13.Cu")
		(net "P5E_CPU0_P3_RX_BUF_DN<12>")
	)
	(segment
		(start 406.791922 -414.166304)
		(end 406.527508 -413.90189)
		(width 0.14224)
		(layer "In13.Cu")
		(net "P5E_CPU0_P3_RX_BUF_DN<12>")
	)
	(segment
		(start 407.547826 -414.267142)
		(end 407.479246 -414.238694)
		(width 0.14224)
		(layer "In13.Cu")
		(net "P5E_CPU0_P3_RX_BUF_DN<12>")
	)
	(segment
		(start 396.628874 -408.247596)
		(end 396.628874 -408.247342)
		(width 0.14224)
		(layer "In13.Cu")
		(net "P5E_CPU0_P3_RX_BUF_DN<12>")
	)
	(segment
		(start 392.867642 -407.144474)
		(end 392.85418 -407.142442)
		(width 0.14224)
		(layer "In13.Cu")
		(net "P5E_CPU0_P3_RX_BUF_DN<12>")
	)
	(segment
		(start 385.189476 -401.089622)
		(end 385.316476 -400.962622)
		(width 0.14224)
		(layer "In13.Cu")
		(net "P5E_CPU0_P3_RX_BUF_DN<12>")
	)
	(segment
		(start 406.079706 -434.030882)
		(end 405.906224 -433.8574)
		(width 0.14224)
		(layer "In13.Cu")
		(net "P5E_CPU0_P3_RX_BUF_DN<12>")
	)
	(segment
		(start 405.77643 -433.54371)
		(end 405.77643 -424.94073)
		(width 0.14224)
		(layer "In13.Cu")
		(net "P5E_CPU0_P3_RX_BUF_DN<12>")
	)
	(segment
		(start 406.527762 -423.685462)
		(end 409.244546 -421.868854)
		(width 0.14224)
		(layer "In13.Cu")
		(net "P5E_CPU0_P3_RX_BUF_DN<12>")
	)
	(segment
		(start 384.575558 -403.447758)
		(end 384.575558 -401.394168)
		(width 0.14224)
		(layer "In13.Cu")
		(net "P5E_CPU0_P3_RX_BUF_DN<12>")
	)
	(segment
		(start 406.527508 -413.90189)
		(end 406.412192 -413.621982)
		(width 0.14224)
		(layer "In13.Cu")
		(net "P5E_CPU0_P3_RX_BUF_DN<12>")
	)
	(segment
		(start 384.880104 -401.089622)
		(end 385.189476 -401.089622)
		(width 0.14224)
		(layer "In13.Cu")
		(net "P5E_CPU0_P3_RX_BUF_DN<12>")
	)
	(segment
		(start 406.750012 -434.48986)
		(end 406.750012 -434.157882)
		(width 0.14224)
		(layer "In13.Cu")
		(net "P5E_CPU0_P3_RX_BUF_DN<12>")
	)
	(segment
		(start 407.802334 -414.52165)
		(end 407.547826 -414.267142)
		(width 0.14224)
		(layer "In13.Cu")
		(net "P5E_CPU0_P3_RX_BUF_DN<12>")
	)
	(segment
		(start 385.9657 -405.233124)
		(end 384.768852 -404.147528)
		(width 0.14224)
		(layer "In13.Cu")
		(net "P5E_CPU0_P3_RX_BUF_DN<12>")
	)
	(segment
		(start 385.316476 -400.962622)
		(end 385.316476 -400.811238)
		(width 0.14224)
		(layer "In13.Cu")
		(net "P5E_CPU0_P3_RX_BUF_DN<12>")
	)
	(segment
		(start 406.750012 -434.157882)
		(end 406.623012 -434.030882)
		(width 0.14224)
		(layer "In13.Cu")
		(net "P5E_CPU0_P3_RX_BUF_DN<12>")
	)
	(segment
		(start 408.96667 -419.851332)
		(end 408.672284 -419.729412)
		(width 0.14224)
		(layer "In13.Cu")
		(net "P5E_CPU0_P3_RX_BUF_DN<12>")
	)
	(segment
		(start 405.98217 -424.311572)
		(end 406.353264 -423.85996)
		(width 0.14224)
		(layer "In13.Cu")
		(net "P5E_CPU0_P3_RX_BUF_DN<12>")
	)
	(segment
		(start 402.551138 -409.425394)
		(end 398.308322 -408.581606)
		(width 0.14224)
		(layer "In13.Cu")
		(net "P5E_CPU0_P3_RX_BUF_DN<12>")
	)
	(segment
		(start 406.412192 -413.621982)
		(end 406.412192 -412.25724)
		(width 0.14224)
		(layer "In13.Cu")
		(net "P5E_CPU0_P3_RX_BUF_DN<12>")
	)
	(segment
		(start 405.806402 -424.735244)
		(end 405.870664 -424.520614)
		(width 0.14224)
		(layer "In13.Cu")
		(net "P5E_CPU0_P3_RX_BUF_DN<12>")
	)
	(segment
		(start 406.966674 -414.238694)
		(end 406.791922 -414.166304)
		(width 0.14224)
		(layer "In13.Cu")
		(net "P5E_CPU0_P3_RX_BUF_DN<12>")
	)
	(segment
		(start 384.575558 -401.394168)
		(end 384.880104 -401.089622)
		(width 0.14224)
		(layer "In13.Cu")
		(net "P5E_CPU0_P3_RX_BUF_DN<12>")
	)
	(segment
		(start 396.628874 -408.247342)
		(end 395.904466 -408.103324)
		(width 0.14224)
		(layer "In13.Cu")
		(net "P5E_CPU0_P3_RX_BUF_DN<12>")
	)
	(segment
		(start 406.374854 -412.167324)
		(end 405.467566 -411.260036)
		(width 0.14224)
		(layer "In13.Cu")
		(net "P5E_CPU0_P3_RX_BUF_DN<12>")
	)
	(segment
		(start 407.479246 -414.238694)
		(end 406.966674 -414.238694)
		(width 0.14224)
		(layer "In13.Cu")
		(net "P5E_CPU0_P3_RX_BUF_DN<12>")
	)
	(segment
		(start 405.412448 -411.214824)
		(end 403.03323 -409.625038)
		(width 0.14224)
		(layer "In13.Cu")
		(net "P5E_CPU0_P3_RX_BUF_DN<12>")
	)
	(segment
		(start 398.308322 -408.581606)
		(end 398.308322 -408.58186)
		(width 0.14224)
		(layer "In13.Cu")
		(net "P5E_CPU0_P3_RX_BUF_DN<12>")
	)
	(segment
		(start 409.244546 -421.868854)
		(end 409.376118 -421.737282)
		(width 0.14224)
		(layer "In13.Cu")
		(net "P5E_CPU0_P3_RX_BUF_DN<12>")
	)
	(segment
		(start 389.72363 -406.430734)
		(end 386.182362 -405.35606)
		(width 0.14224)
		(layer "In13.Cu")
		(net "P5E_CPU0_P3_RX_BUF_DN<12>")
	)
	(segment
		(start 398.308322 -408.58186)
		(end 396.628874 -408.247596)
		(width 0.14224)
		(layer "In13.Cu")
		(net "P5E_CPU0_P3_RX_BUF_DN<12>")
	)
	(segment
		(start 407.943812 -418.651182)
		(end 407.943812 -414.863026)
		(width 0.14224)
		(layer "In13.Cu")
		(net "P5E_CPU0_P3_RX_BUF_DN<12>")
	)
	(segment
		(start 409.438094 -420.321486)
		(end 408.96667 -419.851332)
		(width 0.14224)
		(layer "In13.Cu")
		(net "P5E_CPU0_P3_RX_BUF_DN<12>")
	)
	(segment
		(start 395.904466 -408.103324)
		(end 392.867642 -407.144474)
		(width 0.14224)
		(layer "In13.Cu")
		(net "P5E_CPU0_P3_RX_BUF_DN<12>")
	)
	(segment
		(start 407.943812 -414.863026)
		(end 407.802334 -414.52165)
		(width 0.14224)
		(layer "In13.Cu")
		(net "P5E_CPU0_P3_RX_BUF_DN<12>")
	)
	(segment
		(start 406.353264 -423.85996)
		(end 406.527762 -423.685462)
		(width 0.14224)
		(layer "In13.Cu")
		(net "P5E_CPU0_P3_RX_BUF_DN<12>")
	)
	(segment
		(start 408.191208 -419.248336)
		(end 407.943812 -418.651182)
		(width 0.14224)
		(layer "In13.Cu")
		(net "P5E_CPU0_P3_RX_BUF_DN<12>")
	)
	(arc
		(start 392.85418 -407.142442)
		(mid 391.276256 -406.842227)
		(end 389.72363 -406.430734)
		(width 0.14224)
		(layer "In13.Cu")
		(net "P5E_CPU0_P3_RX_BUF_DN<12>")
	)
	(arc
		(start 405.467566 -411.260036)
		(mid 405.44112 -411.236073)
		(end 405.412448 -411.214824)
		(width 0.14224)
		(layer "In13.Cu")
		(net "P5E_CPU0_P3_RX_BUF_DN<12>")
	)
	(arc
		(start 386.182362 -405.35606)
		(mid 386.067213 -405.306608)
		(end 385.9657 -405.233124)
		(width 0.14224)
		(layer "In13.Cu")
		(net "P5E_CPU0_P3_RX_BUF_DN<12>")
	)
	(arc
		(start 408.672284 -419.729412)
		(mid 408.383934 -419.536686)
		(end 408.191208 -419.248336)
		(width 0.14224)
		(layer "In13.Cu")
		(net "P5E_CPU0_P3_RX_BUF_DN<12>")
	)
	(arc
		(start 384.768852 -404.147528)
		(mid 384.673019 -404.028052)
		(end 384.619246 -403.884638)
		(width 0.14224)
		(layer "In13.Cu")
		(net "P5E_CPU0_P3_RX_BUF_DN<12>")
	)
	(arc
		(start 403.03323 -409.625038)
		(mid 402.802017 -409.501468)
		(end 402.551138 -409.425394)
		(width 0.14224)
		(layer "In13.Cu")
		(net "P5E_CPU0_P3_RX_BUF_DN<12>")
	)
	(arc
		(start 406.412192 -412.25724)
		(mid 406.40249 -412.208556)
		(end 406.374854 -412.167324)
		(width 0.14224)
		(layer "In13.Cu")
		(net "P5E_CPU0_P3_RX_BUF_DN<12>")
	)
	(arc
		(start 405.77643 -424.94073)
		(mid 405.783919 -424.836893)
		(end 405.806402 -424.735244)
		(width 0.14224)
		(layer "In13.Cu")
		(net "P5E_CPU0_P3_RX_BUF_DN<12>")
	)
	(arc
		(start 405.870664 -424.520614)
		(mid 405.916015 -424.410543)
		(end 405.98217 -424.311572)
		(width 0.14224)
		(layer "In13.Cu")
		(net "P5E_CPU0_P3_RX_BUF_DN<12>")
	)
	(arc
		(start 409.376118 -421.737282)
		(mid 409.449624 -421.627272)
		(end 409.475432 -421.497506)
		(width 0.14224)
		(layer "In13.Cu")
		(net "P5E_CPU0_P3_RX_BUF_DN<12>")
	)
	(arc
		(start 409.475432 -420.411402)
		(mid 409.46573 -420.362718)
		(end 409.438094 -420.321486)
		(width 0.14224)
		(layer "In13.Cu")
		(net "P5E_CPU0_P3_RX_BUF_DN<12>")
	)
	(arc
		(start 384.619246 -403.884638)
		(mid 384.586484 -403.66729)
		(end 384.575558 -403.447758)
		(width 0.14224)
		(layer "In13.Cu")
		(net "P5E_CPU0_P3_RX_BUF_DN<12>")
	)
	(arc
		(start 405.906224 -433.8574)
		(mid 405.810088 -433.713477)
		(end 405.77643 -433.54371)
		(width 0.14224)
		(layer "In13.Cu")
		(net "P5E_CPU0_P3_RX_BUF_DN<12>")
	)
	(segment
		(start 383.629662 -400.048984)
		(end 383.718308 -399.960338)
		(width 0.1016)
		(layer "F.Cu")
		(net "P5E_CPU0_P3_RX_BUF_DN<11>")
	)
	(segment
		(start 384.11658 -400.811238)
		(end 384.11658 -401.002246)
		(width 0.1016)
		(layer "F.Cu")
		(net "P5E_CPU0_P3_RX_BUF_DN<11>")
	)
	(segment
		(start 384.11658 -401.002246)
		(end 383.97561 -401.143216)
		(width 0.1016)
		(layer "F.Cu")
		(net "P5E_CPU0_P3_RX_BUF_DN<11>")
	)
	(segment
		(start 383.718308 -399.960338)
		(end 383.718308 -399.143728)
		(width 0.1016)
		(layer "F.Cu")
		(net "P5E_CPU0_P3_RX_BUF_DN<11>")
	)
	(segment
		(start 383.756662 -401.143216)
		(end 383.629662 -401.016216)
		(width 0.1016)
		(layer "F.Cu")
		(net "P5E_CPU0_P3_RX_BUF_DN<11>")
	)
	(segment
		(start 383.718308 -399.143728)
		(end 383.718054 -399.143474)
		(width 0.1016)
		(layer "F.Cu")
		(net "P5E_CPU0_P3_RX_BUF_DN<11>")
	)
	(segment
		(start 383.629662 -401.016216)
		(end 383.629662 -400.048984)
		(width 0.1016)
		(layer "F.Cu")
		(net "P5E_CPU0_P3_RX_BUF_DN<11>")
	)
	(segment
		(start 383.97561 -401.143216)
		(end 383.756662 -401.143216)
		(width 0.1016)
		(layer "F.Cu")
		(net "P5E_CPU0_P3_RX_BUF_DN<11>")
	)
	(segment
		(start 394.802614 -408.948382)
		(end 385.685284 -406.181814)
		(width 0.14224)
		(layer "In13.Cu")
		(net "P5E_CPU0_P3_RX_BUF_DN<11>")
	)
	(segment
		(start 404.416006 -414.238694)
		(end 403.903434 -414.238694)
		(width 0.14224)
		(layer "In13.Cu")
		(net "P5E_CPU0_P3_RX_BUF_DN<11>")
	)
	(segment
		(start 404.880572 -414.863026)
		(end 404.739094 -414.52165)
		(width 0.14224)
		(layer "In13.Cu")
		(net "P5E_CPU0_P3_RX_BUF_DN<11>")
	)
	(segment
		(start 395.58087 -409.128468)
		(end 394.945362 -408.985974)
		(width 0.14224)
		(layer "In13.Cu")
		(net "P5E_CPU0_P3_RX_BUF_DN<11>")
	)
	(segment
		(start 403.903434 -414.238694)
		(end 403.728428 -414.16605)
		(width 0.14224)
		(layer "In13.Cu")
		(net "P5E_CPU0_P3_RX_BUF_DN<11>")
	)
	(segment
		(start 400.193256 -410.16555)
		(end 395.58087 -409.129484)
		(width 0.14224)
		(layer "In13.Cu")
		(net "P5E_CPU0_P3_RX_BUF_DN<11>")
	)
	(segment
		(start 404.739094 -414.52165)
		(end 404.484586 -414.267142)
		(width 0.14224)
		(layer "In13.Cu")
		(net "P5E_CPU0_P3_RX_BUF_DN<11>")
	)
	(segment
		(start 406.412192 -421.50665)
		(end 406.412192 -420.437056)
		(width 0.14224)
		(layer "In13.Cu")
		(net "P5E_CPU0_P3_RX_BUF_DN<11>")
	)
	(segment
		(start 405.109426 -419.27399)
		(end 404.880572 -418.722302)
		(width 0.14224)
		(layer "In13.Cu")
		(net "P5E_CPU0_P3_RX_BUF_DN<11>")
	)
	(segment
		(start 403.464522 -413.902144)
		(end 403.348952 -413.622998)
		(width 0.14224)
		(layer "In13.Cu")
		(net "P5E_CPU0_P3_RX_BUF_DN<11>")
	)
	(segment
		(start 401.15236 -410.584142)
		(end 400.193256 -410.16555)
		(width 0.14224)
		(layer "In13.Cu")
		(net "P5E_CPU0_P3_RX_BUF_DN<11>")
	)
	(segment
		(start 403.239478 -412.141416)
		(end 402.842476 -411.744414)
		(width 0.14224)
		(layer "In13.Cu")
		(net "P5E_CPU0_P3_RX_BUF_DN<11>")
	)
	(segment
		(start 395.58087 -409.129484)
		(end 395.58087 -409.128468)
		(width 0.14224)
		(layer "In13.Cu")
		(net "P5E_CPU0_P3_RX_BUF_DN<11>")
	)
	(segment
		(start 403.943566 -424.220894)
		(end 404.438612 -423.48023)
		(width 0.14224)
		(layer "In13.Cu")
		(net "P5E_CPU0_P3_RX_BUF_DN<11>")
	)
	(segment
		(start 385.123182 -405.841708)
		(end 383.627376 -404.488142)
		(width 0.14224)
		(layer "In13.Cu")
		(net "P5E_CPU0_P3_RX_BUF_DN<11>")
	)
	(segment
		(start 403.776434 -434.715412)
		(end 403.776434 -424.77182)
		(width 0.14224)
		(layer "In13.Cu")
		(net "P5E_CPU0_P3_RX_BUF_DN<11>")
	)
	(segment
		(start 403.348952 -413.622998)
		(end 403.348952 -412.405576)
		(width 0.14224)
		(layer "In13.Cu")
		(net "P5E_CPU0_P3_RX_BUF_DN<11>")
	)
	(segment
		(start 406.374854 -420.34714)
		(end 405.859488 -419.833298)
		(width 0.14224)
		(layer "In13.Cu")
		(net "P5E_CPU0_P3_RX_BUF_DN<11>")
	)
	(segment
		(start 404.438612 -423.48023)
		(end 406.412192 -421.50665)
		(width 0.14224)
		(layer "In13.Cu")
		(net "P5E_CPU0_P3_RX_BUF_DN<11>")
	)
	(segment
		(start 384.11658 -400.962622)
		(end 384.11658 -400.811238)
		(width 0.14224)
		(layer "In13.Cu")
		(net "P5E_CPU0_P3_RX_BUF_DN<11>")
	)
	(segment
		(start 404.750016 -435.489858)
		(end 404.750016 -435.15788)
		(width 0.14224)
		(layer "In13.Cu")
		(net "P5E_CPU0_P3_RX_BUF_DN<11>")
	)
	(segment
		(start 383.375662 -403.920706)
		(end 383.375662 -401.394168)
		(width 0.14224)
		(layer "In13.Cu")
		(net "P5E_CPU0_P3_RX_BUF_DN<11>")
	)
	(segment
		(start 404.880572 -418.722302)
		(end 404.880572 -414.863026)
		(width 0.14224)
		(layer "In13.Cu")
		(net "P5E_CPU0_P3_RX_BUF_DN<11>")
	)
	(segment
		(start 383.98958 -401.089622)
		(end 384.11658 -400.962622)
		(width 0.14224)
		(layer "In13.Cu")
		(net "P5E_CPU0_P3_RX_BUF_DN<11>")
	)
	(segment
		(start 383.375662 -401.394168)
		(end 383.680208 -401.089622)
		(width 0.14224)
		(layer "In13.Cu")
		(net "P5E_CPU0_P3_RX_BUF_DN<11>")
	)
	(segment
		(start 405.859488 -419.833298)
		(end 405.533352 -419.697916)
		(width 0.14224)
		(layer "In13.Cu")
		(net "P5E_CPU0_P3_RX_BUF_DN<11>")
	)
	(segment
		(start 404.091902 -435.03088)
		(end 403.776434 -434.715412)
		(width 0.14224)
		(layer "In13.Cu")
		(net "P5E_CPU0_P3_RX_BUF_DN<11>")
	)
	(segment
		(start 404.750016 -435.15788)
		(end 404.623016 -435.03088)
		(width 0.14224)
		(layer "In13.Cu")
		(net "P5E_CPU0_P3_RX_BUF_DN<11>")
	)
	(segment
		(start 404.484586 -414.267142)
		(end 404.416006 -414.238694)
		(width 0.14224)
		(layer "In13.Cu")
		(net "P5E_CPU0_P3_RX_BUF_DN<11>")
	)
	(segment
		(start 402.842476 -411.744414)
		(end 401.15236 -410.584142)
		(width 0.14224)
		(layer "In13.Cu")
		(net "P5E_CPU0_P3_RX_BUF_DN<11>")
	)
	(segment
		(start 403.728428 -414.16605)
		(end 403.464522 -413.902144)
		(width 0.14224)
		(layer "In13.Cu")
		(net "P5E_CPU0_P3_RX_BUF_DN<11>")
	)
	(segment
		(start 383.680208 -401.089622)
		(end 383.98958 -401.089622)
		(width 0.14224)
		(layer "In13.Cu")
		(net "P5E_CPU0_P3_RX_BUF_DN<11>")
	)
	(segment
		(start 404.623016 -435.03088)
		(end 404.091902 -435.03088)
		(width 0.14224)
		(layer "In13.Cu")
		(net "P5E_CPU0_P3_RX_BUF_DN<11>")
	)
	(arc
		(start 394.945362 -408.985974)
		(mid 394.873642 -408.968491)
		(end 394.802614 -408.948382)
		(width 0.14224)
		(layer "In13.Cu")
		(net "P5E_CPU0_P3_RX_BUF_DN<11>")
	)
	(arc
		(start 383.627376 -404.488142)
		(mid 383.441442 -404.231078)
		(end 383.375662 -403.920706)
		(width 0.14224)
		(layer "In13.Cu")
		(net "P5E_CPU0_P3_RX_BUF_DN<11>")
	)
	(arc
		(start 405.533352 -419.697916)
		(mid 405.279282 -419.52806)
		(end 405.109426 -419.27399)
		(width 0.14224)
		(layer "In13.Cu")
		(net "P5E_CPU0_P3_RX_BUF_DN<11>")
	)
	(arc
		(start 403.348952 -412.405576)
		(mid 403.320496 -412.262607)
		(end 403.239478 -412.141416)
		(width 0.14224)
		(layer "In13.Cu")
		(net "P5E_CPU0_P3_RX_BUF_DN<11>")
	)
	(arc
		(start 385.522216 -406.116282)
		(mid 385.313503 -405.99236)
		(end 385.123182 -405.841708)
		(width 0.14224)
		(layer "In13.Cu")
		(net "P5E_CPU0_P3_RX_BUF_DN<11>")
	)
	(arc
		(start 385.685284 -406.181814)
		(mid 385.602325 -406.152594)
		(end 385.522216 -406.116282)
		(width 0.14224)
		(layer "In13.Cu")
		(net "P5E_CPU0_P3_RX_BUF_DN<11>")
	)
	(arc
		(start 406.412192 -420.437056)
		(mid 406.40249 -420.388372)
		(end 406.374854 -420.34714)
		(width 0.14224)
		(layer "In13.Cu")
		(net "P5E_CPU0_P3_RX_BUF_DN<11>")
	)
	(arc
		(start 403.776434 -424.77182)
		(mid 403.819135 -424.48396)
		(end 403.943566 -424.220894)
		(width 0.14224)
		(layer "In13.Cu")
		(net "P5E_CPU0_P3_RX_BUF_DN<11>")
	)
	(segment
		(start 382.556766 -401.143216)
		(end 382.429766 -401.016216)
		(width 0.1016)
		(layer "F.Cu")
		(net "P5E_CPU0_P3_RX_BUF_DN<10>")
	)
	(segment
		(start 382.429766 -401.016216)
		(end 382.429766 -400.048984)
		(width 0.1016)
		(layer "F.Cu")
		(net "P5E_CPU0_P3_RX_BUF_DN<10>")
	)
	(segment
		(start 382.916684 -401.002246)
		(end 382.775714 -401.143216)
		(width 0.1016)
		(layer "F.Cu")
		(net "P5E_CPU0_P3_RX_BUF_DN<10>")
	)
	(segment
		(start 382.429766 -400.048984)
		(end 382.517904 -399.960846)
		(width 0.1016)
		(layer "F.Cu")
		(net "P5E_CPU0_P3_RX_BUF_DN<10>")
	)
	(segment
		(start 382.517904 -399.960846)
		(end 382.517904 -399.143474)
		(width 0.1016)
		(layer "F.Cu")
		(net "P5E_CPU0_P3_RX_BUF_DN<10>")
	)
	(segment
		(start 382.916684 -400.811238)
		(end 382.916684 -401.002246)
		(width 0.1016)
		(layer "F.Cu")
		(net "P5E_CPU0_P3_RX_BUF_DN<10>")
	)
	(segment
		(start 382.775714 -401.143216)
		(end 382.556766 -401.143216)
		(width 0.1016)
		(layer "F.Cu")
		(net "P5E_CPU0_P3_RX_BUF_DN<10>")
	)
	(segment
		(start 402.75002 -434.157882)
		(end 402.62302 -434.030882)
		(width 0.14224)
		(layer "In13.Cu")
		(net "P5E_CPU0_P3_RX_BUF_DN<10>")
	)
	(segment
		(start 392.142218 -409.295092)
		(end 391.823702 -409.033726)
		(width 0.14224)
		(layer "In13.Cu")
		(net "P5E_CPU0_P3_RX_BUF_DN<10>")
	)
	(segment
		(start 382.175766 -404.162006)
		(end 382.175766 -401.394168)
		(width 0.14224)
		(layer "In13.Cu")
		(net "P5E_CPU0_P3_RX_BUF_DN<10>")
	)
	(segment
		(start 401.421346 -414.267142)
		(end 401.352766 -414.238694)
		(width 0.14224)
		(layer "In13.Cu")
		(net "P5E_CPU0_P3_RX_BUF_DN<10>")
	)
	(segment
		(start 401.817332 -418.760656)
		(end 401.817332 -414.863026)
		(width 0.14224)
		(layer "In13.Cu")
		(net "P5E_CPU0_P3_RX_BUF_DN<10>")
	)
	(segment
		(start 401.352766 -414.238694)
		(end 400.840194 -414.238694)
		(width 0.14224)
		(layer "In13.Cu")
		(net "P5E_CPU0_P3_RX_BUF_DN<10>")
	)
	(segment
		(start 382.175766 -401.394168)
		(end 382.480312 -401.089622)
		(width 0.14224)
		(layer "In13.Cu")
		(net "P5E_CPU0_P3_RX_BUF_DN<10>")
	)
	(segment
		(start 402.75002 -419.813994)
		(end 402.64334 -419.770052)
		(width 0.14224)
		(layer "In13.Cu")
		(net "P5E_CPU0_P3_RX_BUF_DN<10>")
	)
	(segment
		(start 401.817332 -414.863026)
		(end 401.675854 -414.52165)
		(width 0.14224)
		(layer "In13.Cu")
		(net "P5E_CPU0_P3_RX_BUF_DN<10>")
	)
	(segment
		(start 397.479774 -410.914088)
		(end 397.47952 -410.913834)
		(width 0.14224)
		(layer "In13.Cu")
		(net "P5E_CPU0_P3_RX_BUF_DN<10>")
	)
	(segment
		(start 400.285712 -413.622998)
		(end 400.285712 -412.4579)
		(width 0.14224)
		(layer "In13.Cu")
		(net "P5E_CPU0_P3_RX_BUF_DN<10>")
	)
	(segment
		(start 401.776438 -424.413172)
		(end 403.348952 -422.059862)
		(width 0.14224)
		(layer "In13.Cu")
		(net "P5E_CPU0_P3_RX_BUF_DN<10>")
	)
	(segment
		(start 382.916684 -400.962622)
		(end 382.916684 -400.811238)
		(width 0.14224)
		(layer "In13.Cu")
		(net "P5E_CPU0_P3_RX_BUF_DN<10>")
	)
	(segment
		(start 382.789684 -401.089622)
		(end 382.916684 -400.962622)
		(width 0.14224)
		(layer "In13.Cu")
		(net "P5E_CPU0_P3_RX_BUF_DN<10>")
	)
	(segment
		(start 400.265138 -412.388812)
		(end 399.92935 -411.871922)
		(width 0.14224)
		(layer "In13.Cu")
		(net "P5E_CPU0_P3_RX_BUF_DN<10>")
	)
	(segment
		(start 391.823702 -409.033726)
		(end 385.172458 -407.016458)
		(width 0.14224)
		(layer "In13.Cu")
		(net "P5E_CPU0_P3_RX_BUF_DN<10>")
	)
	(segment
		(start 382.480312 -401.089622)
		(end 382.789684 -401.089622)
		(width 0.14224)
		(layer "In13.Cu")
		(net "P5E_CPU0_P3_RX_BUF_DN<10>")
	)
	(segment
		(start 384.273552 -406.475438)
		(end 382.327912 -404.529544)
		(width 0.14224)
		(layer "In13.Cu")
		(net "P5E_CPU0_P3_RX_BUF_DN<10>")
	)
	(segment
		(start 402.62302 -434.030882)
		(end 402.106638 -434.030882)
		(width 0.14224)
		(layer "In13.Cu")
		(net "P5E_CPU0_P3_RX_BUF_DN<10>")
	)
	(segment
		(start 400.840194 -414.238694)
		(end 400.665188 -414.16605)
		(width 0.14224)
		(layer "In13.Cu")
		(net "P5E_CPU0_P3_RX_BUF_DN<10>")
	)
	(segment
		(start 402.106638 -434.030882)
		(end 401.776438 -433.700682)
		(width 0.14224)
		(layer "In13.Cu")
		(net "P5E_CPU0_P3_RX_BUF_DN<10>")
	)
	(segment
		(start 403.348952 -422.059862)
		(end 403.348952 -420.465504)
		(width 0.14224)
		(layer "In13.Cu")
		(net "P5E_CPU0_P3_RX_BUF_DN<10>")
	)
	(segment
		(start 401.675854 -414.52165)
		(end 401.421346 -414.267142)
		(width 0.14224)
		(layer "In13.Cu")
		(net "P5E_CPU0_P3_RX_BUF_DN<10>")
	)
	(segment
		(start 397.47952 -410.913834)
		(end 392.142218 -409.295092)
		(width 0.14224)
		(layer "In13.Cu")
		(net "P5E_CPU0_P3_RX_BUF_DN<10>")
	)
	(segment
		(start 403.311614 -420.375588)
		(end 402.75002 -419.813994)
		(width 0.14224)
		(layer "In13.Cu")
		(net "P5E_CPU0_P3_RX_BUF_DN<10>")
	)
	(segment
		(start 384.511804 -406.673558)
		(end 384.394202 -406.58161)
		(width 0.14224)
		(layer "In13.Cu")
		(net "P5E_CPU0_P3_RX_BUF_DN<10>")
	)
	(segment
		(start 400.401282 -413.902144)
		(end 400.285712 -413.622998)
		(width 0.14224)
		(layer "In13.Cu")
		(net "P5E_CPU0_P3_RX_BUF_DN<10>")
	)
	(segment
		(start 401.776438 -433.700682)
		(end 401.776438 -424.413172)
		(width 0.14224)
		(layer "In13.Cu")
		(net "P5E_CPU0_P3_RX_BUF_DN<10>")
	)
	(segment
		(start 399.450052 -411.511242)
		(end 397.479774 -410.914088)
		(width 0.14224)
		(layer "In13.Cu")
		(net "P5E_CPU0_P3_RX_BUF_DN<10>")
	)
	(segment
		(start 402.75002 -434.48986)
		(end 402.75002 -434.157882)
		(width 0.14224)
		(layer "In13.Cu")
		(net "P5E_CPU0_P3_RX_BUF_DN<10>")
	)
	(segment
		(start 401.946872 -419.07333)
		(end 401.817332 -418.760656)
		(width 0.14224)
		(layer "In13.Cu")
		(net "P5E_CPU0_P3_RX_BUF_DN<10>")
	)
	(segment
		(start 400.665188 -414.16605)
		(end 400.401282 -413.902144)
		(width 0.14224)
		(layer "In13.Cu")
		(net "P5E_CPU0_P3_RX_BUF_DN<10>")
	)
	(arc
		(start 385.172458 -407.016458)
		(mid 384.82628 -406.875545)
		(end 384.511804 -406.673558)
		(width 0.14224)
		(layer "In13.Cu")
		(net "P5E_CPU0_P3_RX_BUF_DN<10>")
	)
	(arc
		(start 382.327912 -404.529544)
		(mid 382.215292 -404.360902)
		(end 382.175766 -404.162006)
		(width 0.14224)
		(layer "In13.Cu")
		(net "P5E_CPU0_P3_RX_BUF_DN<10>")
	)
	(arc
		(start 399.92935 -411.871922)
		(mid 399.721632 -411.64914)
		(end 399.450052 -411.511242)
		(width 0.14224)
		(layer "In13.Cu")
		(net "P5E_CPU0_P3_RX_BUF_DN<10>")
	)
	(arc
		(start 384.394202 -406.58161)
		(mid 384.332253 -406.53037)
		(end 384.273552 -406.475438)
		(width 0.14224)
		(layer "In13.Cu")
		(net "P5E_CPU0_P3_RX_BUF_DN<10>")
	)
	(arc
		(start 403.348952 -420.465504)
		(mid 403.33925 -420.41682)
		(end 403.311614 -420.375588)
		(width 0.14224)
		(layer "In13.Cu")
		(net "P5E_CPU0_P3_RX_BUF_DN<10>")
	)
	(arc
		(start 400.285712 -412.4579)
		(mid 400.28041 -412.421876)
		(end 400.265138 -412.388812)
		(width 0.14224)
		(layer "In13.Cu")
		(net "P5E_CPU0_P3_RX_BUF_DN<10>")
	)
	(arc
		(start 402.64334 -419.770052)
		(mid 402.225757 -419.491001)
		(end 401.946872 -419.07333)
		(width 0.14224)
		(layer "In13.Cu")
		(net "P5E_CPU0_P3_RX_BUF_DN<10>")
	)
	(segment
		(start 370.407438 -400.071336)
		(end 370.407438 -400.993864)
		(width 0.1016)
		(layer "F.Cu")
		(net "P5E_CPU0_P3_RX_BUF_DN<0>")
	)
	(segment
		(start 370.407438 -400.993864)
		(end 370.55679 -401.143216)
		(width 0.1016)
		(layer "F.Cu")
		(net "P5E_CPU0_P3_RX_BUF_DN<0>")
	)
	(segment
		(start 370.55679 -401.143216)
		(end 370.775738 -401.143216)
		(width 0.1016)
		(layer "F.Cu")
		(net "P5E_CPU0_P3_RX_BUF_DN<0>")
	)
	(segment
		(start 370.916454 -401.0025)
		(end 370.916454 -400.811238)
		(width 0.1016)
		(layer "F.Cu")
		(net "P5E_CPU0_P3_RX_BUF_DN<0>")
	)
	(segment
		(start 370.518436 -399.143982)
		(end 370.518436 -399.960338)
		(width 0.1016)
		(layer "F.Cu")
		(net "P5E_CPU0_P3_RX_BUF_DN<0>")
	)
	(segment
		(start 370.775738 -401.143216)
		(end 370.916454 -401.0025)
		(width 0.1016)
		(layer "F.Cu")
		(net "P5E_CPU0_P3_RX_BUF_DN<0>")
	)
	(segment
		(start 370.518436 -399.960338)
		(end 370.407438 -400.071336)
		(width 0.1016)
		(layer "F.Cu")
		(net "P5E_CPU0_P3_RX_BUF_DN<0>")
	)
	(segment
		(start 370.517928 -399.143474)
		(end 370.518436 -399.143982)
		(width 0.1016)
		(layer "F.Cu")
		(net "P5E_CPU0_P3_RX_BUF_DN<0>")
	)
	(segment
		(start 380.81077 -433.64658)
		(end 380.81077 -425.51477)
		(width 0.14224)
		(layer "In13.Cu")
		(net "P5E_CPU0_P3_RX_BUF_DN<0>")
	)
	(segment
		(start 370.032788 -414.16605)
		(end 369.768882 -413.902144)
		(width 0.14224)
		(layer "In13.Cu")
		(net "P5E_CPU0_P3_RX_BUF_DN<0>")
	)
	(segment
		(start 370.916454 -400.962622)
		(end 370.916454 -400.811238)
		(width 0.14224)
		(layer "In13.Cu")
		(net "P5E_CPU0_P3_RX_BUF_DN<0>")
	)
	(segment
		(start 381.749808 -434.157882)
		(end 381.622808 -434.030882)
		(width 0.14224)
		(layer "In13.Cu")
		(net "P5E_CPU0_P3_RX_BUF_DN<0>")
	)
	(segment
		(start 369.642644 -413.597852)
		(end 369.642644 -412.438596)
		(width 0.14224)
		(layer "In13.Cu")
		(net "P5E_CPU0_P3_RX_BUF_DN<0>")
	)
	(segment
		(start 381.622808 -434.030882)
		(end 381.195072 -434.030882)
		(width 0.14224)
		(layer "In13.Cu")
		(net "P5E_CPU0_P3_RX_BUF_DN<0>")
	)
	(segment
		(start 370.175536 -410.26207)
		(end 370.175536 -401.394168)
		(width 0.14224)
		(layer "In13.Cu")
		(net "P5E_CPU0_P3_RX_BUF_DN<0>")
	)
	(segment
		(start 373.190262 -422.176448)
		(end 372.88597 -421.926512)
		(width 0.14224)
		(layer "In13.Cu")
		(net "P5E_CPU0_P3_RX_BUF_DN<0>")
	)
	(segment
		(start 370.207794 -414.238694)
		(end 370.032788 -414.16605)
		(width 0.14224)
		(layer "In13.Cu")
		(net "P5E_CPU0_P3_RX_BUF_DN<0>")
	)
	(segment
		(start 370.65585 -414.238694)
		(end 370.207794 -414.238694)
		(width 0.14224)
		(layer "In13.Cu")
		(net "P5E_CPU0_P3_RX_BUF_DN<0>")
	)
	(segment
		(start 372.88597 -421.926512)
		(end 372.801642 -421.800528)
		(width 0.14224)
		(layer "In13.Cu")
		(net "P5E_CPU0_P3_RX_BUF_DN<0>")
	)
	(segment
		(start 374.67667 -422.792652)
		(end 373.190262 -422.176448)
		(width 0.14224)
		(layer "In13.Cu")
		(net "P5E_CPU0_P3_RX_BUF_DN<0>")
	)
	(segment
		(start 372.213124 -419.853618)
		(end 371.983 -419.758368)
		(width 0.14224)
		(layer "In13.Cu")
		(net "P5E_CPU0_P3_RX_BUF_DN<0>")
	)
	(segment
		(start 381.749808 -434.48986)
		(end 381.749808 -434.157882)
		(width 0.14224)
		(layer "In13.Cu")
		(net "P5E_CPU0_P3_RX_BUF_DN<0>")
	)
	(segment
		(start 369.690396 -412.198058)
		(end 370.175536 -410.26207)
		(width 0.14224)
		(layer "In13.Cu")
		(net "P5E_CPU0_P3_RX_BUF_DN<0>")
	)
	(segment
		(start 381.195072 -434.030882)
		(end 380.81077 -433.64658)
		(width 0.14224)
		(layer "In13.Cu")
		(net "P5E_CPU0_P3_RX_BUF_DN<0>")
	)
	(segment
		(start 375.379234 -423.005758)
		(end 374.67667 -422.792652)
		(width 0.14224)
		(layer "In13.Cu")
		(net "P5E_CPU0_P3_RX_BUF_DN<0>")
	)
	(segment
		(start 370.175536 -401.394168)
		(end 370.480082 -401.089622)
		(width 0.14224)
		(layer "In13.Cu")
		(net "P5E_CPU0_P3_RX_BUF_DN<0>")
	)
	(segment
		(start 369.768882 -413.902144)
		(end 369.642644 -413.597852)
		(width 0.14224)
		(layer "In13.Cu")
		(net "P5E_CPU0_P3_RX_BUF_DN<0>")
	)
	(segment
		(start 369.642644 -412.438596)
		(end 369.690396 -412.198058)
		(width 0.14224)
		(layer "In13.Cu")
		(net "P5E_CPU0_P3_RX_BUF_DN<0>")
	)
	(segment
		(start 372.619016 -420.260018)
		(end 372.213124 -419.853618)
		(width 0.14224)
		(layer "In13.Cu")
		(net "P5E_CPU0_P3_RX_BUF_DN<0>")
	)
	(segment
		(start 380.774702 -425.395136)
		(end 380.669038 -425.236132)
		(width 0.14224)
		(layer "In13.Cu")
		(net "P5E_CPU0_P3_RX_BUF_DN<0>")
	)
	(segment
		(start 371.395498 -419.170866)
		(end 371.184932 -418.662866)
		(width 0.14224)
		(layer "In13.Cu")
		(net "P5E_CPU0_P3_RX_BUF_DN<0>")
	)
	(segment
		(start 370.789454 -401.089622)
		(end 370.916454 -400.962622)
		(width 0.14224)
		(layer "In13.Cu")
		(net "P5E_CPU0_P3_RX_BUF_DN<0>")
	)
	(segment
		(start 371.184932 -414.863026)
		(end 371.117622 -414.700466)
		(width 0.14224)
		(layer "In13.Cu")
		(net "P5E_CPU0_P3_RX_BUF_DN<0>")
	)
	(segment
		(start 371.184932 -418.662866)
		(end 371.184932 -414.863026)
		(width 0.14224)
		(layer "In13.Cu")
		(net "P5E_CPU0_P3_RX_BUF_DN<0>")
	)
	(segment
		(start 380.572772 -425.156884)
		(end 375.379234 -423.005758)
		(width 0.14224)
		(layer "In13.Cu")
		(net "P5E_CPU0_P3_RX_BUF_DN<0>")
	)
	(segment
		(start 370.480082 -401.089622)
		(end 370.789454 -401.089622)
		(width 0.14224)
		(layer "In13.Cu")
		(net "P5E_CPU0_P3_RX_BUF_DN<0>")
	)
	(segment
		(start 371.117622 -414.700466)
		(end 370.65585 -414.238694)
		(width 0.14224)
		(layer "In13.Cu")
		(net "P5E_CPU0_P3_RX_BUF_DN<0>")
	)
	(segment
		(start 372.716552 -421.521128)
		(end 372.716552 -420.49573)
		(width 0.14224)
		(layer "In13.Cu")
		(net "P5E_CPU0_P3_RX_BUF_DN<0>")
	)
	(arc
		(start 380.81077 -425.51477)
		(mid 380.801604 -425.452276)
		(end 380.774702 -425.395136)
		(width 0.14224)
		(layer "In13.Cu")
		(net "P5E_CPU0_P3_RX_BUF_DN<0>")
	)
	(arc
		(start 372.716552 -420.49573)
		(mid 372.6912 -420.368187)
		(end 372.619016 -420.260018)
		(width 0.14224)
		(layer "In13.Cu")
		(net "P5E_CPU0_P3_RX_BUF_DN<0>")
	)
	(arc
		(start 380.669038 -425.236132)
		(mid 380.626793 -425.189362)
		(end 380.572772 -425.156884)
		(width 0.14224)
		(layer "In13.Cu")
		(net "P5E_CPU0_P3_RX_BUF_DN<0>")
	)
	(arc
		(start 372.801642 -421.800528)
		(mid 372.73834 -421.66715)
		(end 372.716552 -421.521128)
		(width 0.14224)
		(layer "In13.Cu")
		(net "P5E_CPU0_P3_RX_BUF_DN<0>")
	)
	(arc
		(start 371.983 -419.758368)
		(mid 371.630866 -419.523)
		(end 371.395498 -419.170866)
		(width 0.14224)
		(layer "In13.Cu")
		(net "P5E_CPU0_P3_RX_BUF_DN<0>")
	)
	(segment
		(start 414.098232 -397.849344)
		(end 414.618932 -397.849344)
		(width 0.127)
		(layer "F.Cu")
		(net "P5E_CPU0_P2_TX_BUF_DP<9>")
	)
	(segment
		(start 399.056352 -416.336734)
		(end 399.056352 -413.11703)
		(width 0.12954)
		(layer "F.Cu")
		(net "P5E_CPU0_P2_TX_BUF_DP<9>")
	)
	(segment
		(start 399.352262 -416.632644)
		(end 399.056352 -416.336734)
		(width 0.12954)
		(layer "F.Cu")
		(net "P5E_CPU0_P2_TX_BUF_DP<9>")
	)
	(segment
		(start 399.056352 -413.11703)
		(end 399.326862 -412.84652)
		(width 0.12954)
		(layer "F.Cu")
		(net "P5E_CPU0_P2_TX_BUF_DP<9>")
	)
	(segment
		(start 414.319974 -399.523204)
		(end 413.870902 -399.972276)
		(width 0.14224)
		(layer "In4.Cu")
		(net "P5E_CPU0_P2_TX_BUF_DP<9>")
	)
	(segment
		(start 401.75688 -410.920946)
		(end 401.447254 -411.03169)
		(width 0.14224)
		(layer "In4.Cu")
		(net "P5E_CPU0_P2_TX_BUF_DP<9>")
	)
	(segment
		(start 399.264378 -411.81274)
		(end 399.170652 -411.906212)
		(width 0.14224)
		(layer "In4.Cu")
		(net "P5E_CPU0_P2_TX_BUF_DP<9>")
	)
	(segment
		(start 414.504124 -397.734536)
		(end 414.324038 -397.734536)
		(width 0.14224)
		(layer "In4.Cu")
		(net "P5E_CPU0_P2_TX_BUF_DP<9>")
	)
	(segment
		(start 414.21939 -397.839184)
		(end 414.21939 -397.897858)
		(width 0.14224)
		(layer "In4.Cu")
		(net "P5E_CPU0_P2_TX_BUF_DP<9>")
	)
	(segment
		(start 414.324038 -397.734536)
		(end 414.21939 -397.839184)
		(width 0.14224)
		(layer "In4.Cu")
		(net "P5E_CPU0_P2_TX_BUF_DP<9>")
	)
	(segment
		(start 399.725134 -411.647894)
		(end 399.264378 -411.81274)
		(width 0.14224)
		(layer "In4.Cu")
		(net "P5E_CPU0_P2_TX_BUF_DP<9>")
	)
	(segment
		(start 414.618932 -397.849344)
		(end 414.504124 -397.734536)
		(width 0.14224)
		(layer "In4.Cu")
		(net "P5E_CPU0_P2_TX_BUF_DP<9>")
	)
	(segment
		(start 413.960818 -402.833586)
		(end 413.960818 -403.260306)
		(width 0.14224)
		(layer "In4.Cu")
		(net "P5E_CPU0_P2_TX_BUF_DP<9>")
	)
	(segment
		(start 400.38528 -411.411674)
		(end 400.302476 -411.587188)
		(width 0.14224)
		(layer "In4.Cu")
		(net "P5E_CPU0_P2_TX_BUF_DP<9>")
	)
	(segment
		(start 414.59531 -398.504918)
		(end 414.59531 -398.858486)
		(width 0.14224)
		(layer "In4.Cu")
		(net "P5E_CPU0_P2_TX_BUF_DP<9>")
	)
	(segment
		(start 400.302476 -411.587188)
		(end 399.900394 -411.730952)
		(width 0.14224)
		(layer "In4.Cu")
		(net "P5E_CPU0_P2_TX_BUF_DP<9>")
	)
	(segment
		(start 401.447254 -411.03169)
		(end 401.364196 -411.207204)
		(width 0.14224)
		(layer "In4.Cu")
		(net "P5E_CPU0_P2_TX_BUF_DP<9>")
	)
	(segment
		(start 413.823658 -403.397466)
		(end 413.823658 -403.654768)
		(width 0.14224)
		(layer "In4.Cu")
		(net "P5E_CPU0_P2_TX_BUF_DP<9>")
	)
	(segment
		(start 399.036032 -412.231078)
		(end 399.036032 -412.55569)
		(width 0.14224)
		(layer "In4.Cu")
		(net "P5E_CPU0_P2_TX_BUF_DP<9>")
	)
	(segment
		(start 413.823658 -402.696426)
		(end 413.960818 -402.833586)
		(width 0.14224)
		(layer "In4.Cu")
		(net "P5E_CPU0_P2_TX_BUF_DP<9>")
	)
	(segment
		(start 400.962368 -411.350968)
		(end 400.786854 -411.268164)
		(width 0.14224)
		(layer "In4.Cu")
		(net "P5E_CPU0_P2_TX_BUF_DP<9>")
	)
	(segment
		(start 399.900394 -411.730952)
		(end 399.725134 -411.647894)
		(width 0.14224)
		(layer "In4.Cu")
		(net "P5E_CPU0_P2_TX_BUF_DP<9>")
	)
	(segment
		(start 408.52725 -408.516328)
		(end 405.055578 -409.954476)
		(width 0.14224)
		(layer "In4.Cu")
		(net "P5E_CPU0_P2_TX_BUF_DP<9>")
	)
	(segment
		(start 401.364196 -411.207204)
		(end 400.962368 -411.350968)
		(width 0.14224)
		(layer "In4.Cu")
		(net "P5E_CPU0_P2_TX_BUF_DP<9>")
	)
	(segment
		(start 414.29813 -398.08785)
		(end 414.510474 -398.300194)
		(width 0.14224)
		(layer "In4.Cu")
		(net "P5E_CPU0_P2_TX_BUF_DP<9>")
	)
	(segment
		(start 405.055578 -409.954476)
		(end 401.75688 -410.920946)
		(width 0.14224)
		(layer "In4.Cu")
		(net "P5E_CPU0_P2_TX_BUF_DP<9>")
	)
	(segment
		(start 413.823658 -400.086322)
		(end 413.823658 -402.696426)
		(width 0.14224)
		(layer "In4.Cu")
		(net "P5E_CPU0_P2_TX_BUF_DP<9>")
	)
	(segment
		(start 413.70377 -403.944074)
		(end 410.347922 -407.299922)
		(width 0.14224)
		(layer "In4.Cu")
		(net "P5E_CPU0_P2_TX_BUF_DP<9>")
	)
	(segment
		(start 413.960818 -403.260306)
		(end 413.823658 -403.397466)
		(width 0.14224)
		(layer "In4.Cu")
		(net "P5E_CPU0_P2_TX_BUF_DP<9>")
	)
	(segment
		(start 400.786854 -411.268164)
		(end 400.38528 -411.411674)
		(width 0.14224)
		(layer "In4.Cu")
		(net "P5E_CPU0_P2_TX_BUF_DP<9>")
	)
	(segment
		(start 399.036032 -412.55569)
		(end 399.326862 -412.84652)
		(width 0.14224)
		(layer "In4.Cu")
		(net "P5E_CPU0_P2_TX_BUF_DP<9>")
	)
	(arc
		(start 414.21939 -397.897858)
		(mid 414.239876 -398.000669)
		(end 414.29813 -398.08785)
		(width 0.14224)
		(layer "In4.Cu")
		(net "P5E_CPU0_P2_TX_BUF_DP<9>")
	)
	(arc
		(start 414.59531 -398.858486)
		(mid 414.523753 -399.218229)
		(end 414.319974 -399.523204)
		(width 0.14224)
		(layer "In4.Cu")
		(net "P5E_CPU0_P2_TX_BUF_DP<9>")
	)
	(arc
		(start 399.170652 -411.906212)
		(mid 399.071006 -412.055248)
		(end 399.036032 -412.231078)
		(width 0.14224)
		(layer "In4.Cu")
		(net "P5E_CPU0_P2_TX_BUF_DP<9>")
	)
	(arc
		(start 414.510474 -398.300194)
		(mid 414.573235 -398.394122)
		(end 414.59531 -398.504918)
		(width 0.14224)
		(layer "In4.Cu")
		(net "P5E_CPU0_P2_TX_BUF_DP<9>")
	)
	(arc
		(start 413.823658 -403.654768)
		(mid 413.792495 -403.811346)
		(end 413.70377 -403.944074)
		(width 0.14224)
		(layer "In4.Cu")
		(net "P5E_CPU0_P2_TX_BUF_DP<9>")
	)
	(arc
		(start 410.347922 -407.299922)
		(mid 409.497482 -407.997772)
		(end 408.52725 -408.516328)
		(width 0.14224)
		(layer "In4.Cu")
		(net "P5E_CPU0_P2_TX_BUF_DP<9>")
	)
	(arc
		(start 413.870902 -399.972276)
		(mid 413.83594 -400.024601)
		(end 413.823658 -400.086322)
		(width 0.14224)
		(layer "In4.Cu")
		(net "P5E_CPU0_P2_TX_BUF_DP<9>")
	)
	(segment
		(start 412.898336 -397.849344)
		(end 413.419036 -397.849344)
		(width 0.127)
		(layer "F.Cu")
		(net "P5E_CPU0_P2_TX_BUF_DP<8>")
	)
	(segment
		(start 395.993112 -416.336734)
		(end 395.993112 -413.11703)
		(width 0.12954)
		(layer "F.Cu")
		(net "P5E_CPU0_P2_TX_BUF_DP<8>")
	)
	(segment
		(start 396.289022 -416.632644)
		(end 395.993112 -416.336734)
		(width 0.12954)
		(layer "F.Cu")
		(net "P5E_CPU0_P2_TX_BUF_DP<8>")
	)
	(segment
		(start 395.993112 -413.11703)
		(end 396.263622 -412.84652)
		(width 0.12954)
		(layer "F.Cu")
		(net "P5E_CPU0_P2_TX_BUF_DP<8>")
	)
	(segment
		(start 413.084518 -399.548604)
		(end 412.611824 -400.021552)
		(width 0.14224)
		(layer "In4.Cu")
		(net "P5E_CPU0_P2_TX_BUF_DP<8>")
	)
	(segment
		(start 395.972792 -412.154878)
		(end 395.972792 -412.55569)
		(width 0.14224)
		(layer "In4.Cu")
		(net "P5E_CPU0_P2_TX_BUF_DP<8>")
	)
	(segment
		(start 402.723604 -409.657042)
		(end 401.96643 -409.807918)
		(width 0.14224)
		(layer "In4.Cu")
		(net "P5E_CPU0_P2_TX_BUF_DP<8>")
	)
	(segment
		(start 398.137126 -411.047692)
		(end 398.058894 -411.225492)
		(width 0.14224)
		(layer "In4.Cu")
		(net "P5E_CPU0_P2_TX_BUF_DP<8>")
	)
	(segment
		(start 412.092648 -404.075392)
		(end 409.231338 -406.936702)
		(width 0.14224)
		(layer "In4.Cu")
		(net "P5E_CPU0_P2_TX_BUF_DP<8>")
	)
	(segment
		(start 412.557976 -400.1516)
		(end 412.557976 -402.952204)
		(width 0.14224)
		(layer "In4.Cu")
		(net "P5E_CPU0_P2_TX_BUF_DP<8>")
	)
	(segment
		(start 399.188178 -410.638752)
		(end 399.109946 -410.816552)
		(width 0.14224)
		(layer "In4.Cu")
		(net "P5E_CPU0_P2_TX_BUF_DP<8>")
	)
	(segment
		(start 413.124142 -397.734536)
		(end 413.034734 -397.823944)
		(width 0.14224)
		(layer "In4.Cu")
		(net "P5E_CPU0_P2_TX_BUF_DP<8>")
	)
	(segment
		(start 413.142684 -398.13611)
		(end 413.275526 -398.268952)
		(width 0.14224)
		(layer "In4.Cu")
		(net "P5E_CPU0_P2_TX_BUF_DP<8>")
	)
	(segment
		(start 408.144726 -407.662634)
		(end 404.986236 -408.97048)
		(width 0.14224)
		(layer "In4.Cu")
		(net "P5E_CPU0_P2_TX_BUF_DP<8>")
	)
	(segment
		(start 401.96643 -409.807918)
		(end 399.585688 -410.484066)
		(width 0.14224)
		(layer "In4.Cu")
		(net "P5E_CPU0_P2_TX_BUF_DP<8>")
	)
	(segment
		(start 398.058894 -411.225492)
		(end 397.66113 -411.380178)
		(width 0.14224)
		(layer "In4.Cu")
		(net "P5E_CPU0_P2_TX_BUF_DP<8>")
	)
	(segment
		(start 396.621508 -411.766766)
		(end 396.46606 -411.697932)
		(width 0.14224)
		(layer "In4.Cu")
		(net "P5E_CPU0_P2_TX_BUF_DP<8>")
	)
	(segment
		(start 395.972792 -412.55569)
		(end 396.263622 -412.84652)
		(width 0.14224)
		(layer "In4.Cu")
		(net "P5E_CPU0_P2_TX_BUF_DP<8>")
	)
	(segment
		(start 413.304228 -397.734536)
		(end 413.124142 -397.734536)
		(width 0.14224)
		(layer "In4.Cu")
		(net "P5E_CPU0_P2_TX_BUF_DP<8>")
	)
	(segment
		(start 399.585688 -410.484066)
		(end 399.188178 -410.638752)
		(width 0.14224)
		(layer "In4.Cu")
		(net "P5E_CPU0_P2_TX_BUF_DP<8>")
	)
	(segment
		(start 399.109946 -410.816552)
		(end 398.712182 -410.971238)
		(width 0.14224)
		(layer "In4.Cu")
		(net "P5E_CPU0_P2_TX_BUF_DP<8>")
	)
	(segment
		(start 404.986236 -408.97048)
		(end 402.723604 -409.657042)
		(width 0.14224)
		(layer "In4.Cu")
		(net "P5E_CPU0_P2_TX_BUF_DP<8>")
	)
	(segment
		(start 413.034734 -397.823944)
		(end 413.034734 -397.87576)
		(width 0.14224)
		(layer "In4.Cu")
		(net "P5E_CPU0_P2_TX_BUF_DP<8>")
	)
	(segment
		(start 397.019526 -411.611826)
		(end 396.621508 -411.766766)
		(width 0.14224)
		(layer "In4.Cu")
		(net "P5E_CPU0_P2_TX_BUF_DP<8>")
	)
	(segment
		(start 413.395414 -398.558512)
		(end 413.395414 -398.79778)
		(width 0.14224)
		(layer "In4.Cu")
		(net "P5E_CPU0_P2_TX_BUF_DP<8>")
	)
	(segment
		(start 397.087344 -411.456124)
		(end 397.019526 -411.611826)
		(width 0.14224)
		(layer "In4.Cu")
		(net "P5E_CPU0_P2_TX_BUF_DP<8>")
	)
	(segment
		(start 413.419036 -397.849344)
		(end 413.304228 -397.734536)
		(width 0.14224)
		(layer "In4.Cu")
		(net "P5E_CPU0_P2_TX_BUF_DP<8>")
	)
	(segment
		(start 397.66113 -411.380178)
		(end 397.483584 -411.301946)
		(width 0.14224)
		(layer "In4.Cu")
		(net "P5E_CPU0_P2_TX_BUF_DP<8>")
	)
	(segment
		(start 397.483584 -411.301946)
		(end 397.087344 -411.456124)
		(width 0.14224)
		(layer "In4.Cu")
		(net "P5E_CPU0_P2_TX_BUF_DP<8>")
	)
	(segment
		(start 396.46606 -411.697932)
		(end 396.202154 -411.800548)
		(width 0.14224)
		(layer "In4.Cu")
		(net "P5E_CPU0_P2_TX_BUF_DP<8>")
	)
	(segment
		(start 396.202154 -411.800548)
		(end 396.061184 -411.941518)
		(width 0.14224)
		(layer "In4.Cu")
		(net "P5E_CPU0_P2_TX_BUF_DP<8>")
	)
	(segment
		(start 398.534636 -410.893006)
		(end 398.137126 -411.047692)
		(width 0.14224)
		(layer "In4.Cu")
		(net "P5E_CPU0_P2_TX_BUF_DP<8>")
	)
	(segment
		(start 398.712182 -410.971238)
		(end 398.534636 -410.893006)
		(width 0.14224)
		(layer "In4.Cu")
		(net "P5E_CPU0_P2_TX_BUF_DP<8>")
	)
	(arc
		(start 412.611824 -400.021552)
		(mid 412.571956 -400.081219)
		(end 412.557976 -400.1516)
		(width 0.14224)
		(layer "In4.Cu")
		(net "P5E_CPU0_P2_TX_BUF_DP<8>")
	)
	(arc
		(start 413.034734 -397.87576)
		(mid 413.062784 -398.016688)
		(end 413.142684 -398.13611)
		(width 0.14224)
		(layer "In4.Cu")
		(net "P5E_CPU0_P2_TX_BUF_DP<8>")
	)
	(arc
		(start 412.557976 -402.952204)
		(mid 412.437042 -403.560089)
		(end 412.092648 -404.075392)
		(width 0.14224)
		(layer "In4.Cu")
		(net "P5E_CPU0_P2_TX_BUF_DP<8>")
	)
	(arc
		(start 413.275526 -398.268952)
		(mid 413.364241 -398.401817)
		(end 413.395414 -398.558512)
		(width 0.14224)
		(layer "In4.Cu")
		(net "P5E_CPU0_P2_TX_BUF_DP<8>")
	)
	(arc
		(start 396.061184 -411.941518)
		(mid 395.995776 -412.039408)
		(end 395.972792 -412.154878)
		(width 0.14224)
		(layer "In4.Cu")
		(net "P5E_CPU0_P2_TX_BUF_DP<8>")
	)
	(arc
		(start 413.395414 -398.79778)
		(mid 413.31461 -399.204097)
		(end 413.084518 -399.548604)
		(width 0.14224)
		(layer "In4.Cu")
		(net "P5E_CPU0_P2_TX_BUF_DP<8>")
	)
	(arc
		(start 409.231338 -406.936702)
		(mid 408.723797 -407.353205)
		(end 408.144726 -407.662634)
		(width 0.14224)
		(layer "In4.Cu")
		(net "P5E_CPU0_P2_TX_BUF_DP<8>")
	)
	(segment
		(start 411.698186 -397.849344)
		(end 412.218886 -397.849344)
		(width 0.127)
		(layer "F.Cu")
		(net "P5E_CPU0_P2_TX_BUF_DP<7>")
	)
	(segment
		(start 392.929872 -416.336734)
		(end 392.929872 -413.11703)
		(width 0.12954)
		(layer "F.Cu")
		(net "P5E_CPU0_P2_TX_BUF_DP<7>")
	)
	(segment
		(start 392.929872 -413.11703)
		(end 393.200382 -412.84652)
		(width 0.12954)
		(layer "F.Cu")
		(net "P5E_CPU0_P2_TX_BUF_DP<7>")
	)
	(segment
		(start 393.225782 -416.632644)
		(end 392.929872 -416.336734)
		(width 0.12954)
		(layer "F.Cu")
		(net "P5E_CPU0_P2_TX_BUF_DP<7>")
	)
	(segment
		(start 401.497292 -408.929078)
		(end 396.849346 -410.339032)
		(width 0.14224)
		(layer "In4.Cu")
		(net "P5E_CPU0_P2_TX_BUF_DP<7>")
	)
	(segment
		(start 394.171678 -411.328362)
		(end 394.097256 -411.507686)
		(width 0.14224)
		(layer "In4.Cu")
		(net "P5E_CPU0_P2_TX_BUF_DP<7>")
	)
	(segment
		(start 396.757906 -410.510228)
		(end 396.349474 -410.63418)
		(width 0.14224)
		(layer "In4.Cu")
		(net "P5E_CPU0_P2_TX_BUF_DP<7>")
	)
	(segment
		(start 393.129516 -411.759908)
		(end 393.055602 -411.833822)
		(width 0.14224)
		(layer "In4.Cu")
		(net "P5E_CPU0_P2_TX_BUF_DP<7>")
	)
	(segment
		(start 411.997906 -399.400776)
		(end 411.516322 -399.88236)
		(width 0.14224)
		(layer "In4.Cu")
		(net "P5E_CPU0_P2_TX_BUF_DP<7>")
	)
	(segment
		(start 411.092904 -403.700996)
		(end 408.468322 -406.325578)
		(width 0.14224)
		(layer "In4.Cu")
		(net "P5E_CPU0_P2_TX_BUF_DP<7>")
	)
	(segment
		(start 396.178278 -410.54274)
		(end 395.7701 -410.666438)
		(width 0.14224)
		(layer "In4.Cu")
		(net "P5E_CPU0_P2_TX_BUF_DP<7>")
	)
	(segment
		(start 392.909552 -412.18612)
		(end 392.909552 -412.55569)
		(width 0.14224)
		(layer "In4.Cu")
		(net "P5E_CPU0_P2_TX_BUF_DP<7>")
	)
	(segment
		(start 395.139418 -411.07614)
		(end 394.744956 -411.239462)
		(width 0.14224)
		(layer "In4.Cu")
		(net "P5E_CPU0_P2_TX_BUF_DP<7>")
	)
	(segment
		(start 411.417262 -400.121628)
		(end 411.417262 -402.917914)
		(width 0.14224)
		(layer "In4.Cu")
		(net "P5E_CPU0_P2_TX_BUF_DP<7>")
	)
	(segment
		(start 404.867364 -408.009852)
		(end 402.48586 -408.732228)
		(width 0.14224)
		(layer "In4.Cu")
		(net "P5E_CPU0_P2_TX_BUF_DP<7>")
	)
	(segment
		(start 393.523724 -411.59684)
		(end 393.129516 -411.759908)
		(width 0.14224)
		(layer "In4.Cu")
		(net "P5E_CPU0_P2_TX_BUF_DP<7>")
	)
	(segment
		(start 411.926278 -398.1196)
		(end 412.07563 -398.268698)
		(width 0.14224)
		(layer "In4.Cu")
		(net "P5E_CPU0_P2_TX_BUF_DP<7>")
	)
	(segment
		(start 394.565886 -411.165294)
		(end 394.171678 -411.328362)
		(width 0.14224)
		(layer "In4.Cu")
		(net "P5E_CPU0_P2_TX_BUF_DP<7>")
	)
	(segment
		(start 412.218886 -397.849344)
		(end 412.104078 -397.734536)
		(width 0.14224)
		(layer "In4.Cu")
		(net "P5E_CPU0_P2_TX_BUF_DP<7>")
	)
	(segment
		(start 392.909552 -412.55569)
		(end 393.200382 -412.84652)
		(width 0.14224)
		(layer "In4.Cu")
		(net "P5E_CPU0_P2_TX_BUF_DP<7>")
	)
	(segment
		(start 411.84195 -397.816832)
		(end 411.84195 -397.916146)
		(width 0.14224)
		(layer "In4.Cu")
		(net "P5E_CPU0_P2_TX_BUF_DP<7>")
	)
	(segment
		(start 393.702794 -411.671008)
		(end 393.523724 -411.59684)
		(width 0.14224)
		(layer "In4.Cu")
		(net "P5E_CPU0_P2_TX_BUF_DP<7>")
	)
	(segment
		(start 396.849346 -410.339032)
		(end 396.757906 -410.510228)
		(width 0.14224)
		(layer "In4.Cu")
		(net "P5E_CPU0_P2_TX_BUF_DP<7>")
	)
	(segment
		(start 395.7701 -410.666438)
		(end 395.21384 -410.896816)
		(width 0.14224)
		(layer "In4.Cu")
		(net "P5E_CPU0_P2_TX_BUF_DP<7>")
	)
	(segment
		(start 407.70937 -406.832816)
		(end 404.867364 -408.009852)
		(width 0.14224)
		(layer "In4.Cu")
		(net "P5E_CPU0_P2_TX_BUF_DP<7>")
	)
	(segment
		(start 412.195518 -398.558258)
		(end 412.195518 -398.923764)
		(width 0.14224)
		(layer "In4.Cu")
		(net "P5E_CPU0_P2_TX_BUF_DP<7>")
	)
	(segment
		(start 394.744956 -411.239462)
		(end 394.565886 -411.165294)
		(width 0.14224)
		(layer "In4.Cu")
		(net "P5E_CPU0_P2_TX_BUF_DP<7>")
	)
	(segment
		(start 402.48586 -408.732228)
		(end 401.497292 -408.929078)
		(width 0.14224)
		(layer "In4.Cu")
		(net "P5E_CPU0_P2_TX_BUF_DP<7>")
	)
	(segment
		(start 396.349474 -410.63418)
		(end 396.178278 -410.54274)
		(width 0.14224)
		(layer "In4.Cu")
		(net "P5E_CPU0_P2_TX_BUF_DP<7>")
	)
	(segment
		(start 411.924246 -397.734536)
		(end 411.84195 -397.816832)
		(width 0.14224)
		(layer "In4.Cu")
		(net "P5E_CPU0_P2_TX_BUF_DP<7>")
	)
	(segment
		(start 395.21384 -410.896816)
		(end 395.139418 -411.07614)
		(width 0.14224)
		(layer "In4.Cu")
		(net "P5E_CPU0_P2_TX_BUF_DP<7>")
	)
	(segment
		(start 394.097256 -411.507686)
		(end 393.702794 -411.671008)
		(width 0.14224)
		(layer "In4.Cu")
		(net "P5E_CPU0_P2_TX_BUF_DP<7>")
	)
	(segment
		(start 412.104078 -397.734536)
		(end 411.924246 -397.734536)
		(width 0.14224)
		(layer "In4.Cu")
		(net "P5E_CPU0_P2_TX_BUF_DP<7>")
	)
	(arc
		(start 393.055602 -411.833822)
		(mid 392.947493 -411.995429)
		(end 392.909552 -412.18612)
		(width 0.14224)
		(layer "In4.Cu")
		(net "P5E_CPU0_P2_TX_BUF_DP<7>")
	)
	(arc
		(start 411.84195 -397.916146)
		(mid 411.863871 -398.026261)
		(end 411.926278 -398.1196)
		(width 0.14224)
		(layer "In4.Cu")
		(net "P5E_CPU0_P2_TX_BUF_DP<7>")
	)
	(arc
		(start 412.07563 -398.268698)
		(mid 412.164423 -398.401536)
		(end 412.195518 -398.558258)
		(width 0.14224)
		(layer "In4.Cu")
		(net "P5E_CPU0_P2_TX_BUF_DP<7>")
	)
	(arc
		(start 412.195518 -398.923764)
		(mid 412.144165 -399.181931)
		(end 411.997906 -399.400776)
		(width 0.14224)
		(layer "In4.Cu")
		(net "P5E_CPU0_P2_TX_BUF_DP<7>")
	)
	(arc
		(start 411.516322 -399.88236)
		(mid 411.443025 -399.992151)
		(end 411.417262 -400.121628)
		(width 0.14224)
		(layer "In4.Cu")
		(net "P5E_CPU0_P2_TX_BUF_DP<7>")
	)
	(arc
		(start 411.417262 -402.917914)
		(mid 411.332963 -403.341713)
		(end 411.092904 -403.700996)
		(width 0.14224)
		(layer "In4.Cu")
		(net "P5E_CPU0_P2_TX_BUF_DP<7>")
	)
	(arc
		(start 408.468322 -406.325578)
		(mid 408.113834 -406.616589)
		(end 407.70937 -406.832816)
		(width 0.14224)
		(layer "In4.Cu")
		(net "P5E_CPU0_P2_TX_BUF_DP<7>")
	)
	(segment
		(start 410.49829 -397.849344)
		(end 411.01899 -397.849344)
		(width 0.127)
		(layer "F.Cu")
		(net "P5E_CPU0_P2_TX_BUF_DP<6>")
	)
	(segment
		(start 390.162542 -416.632644)
		(end 389.866632 -416.336734)
		(width 0.12954)
		(layer "F.Cu")
		(net "P5E_CPU0_P2_TX_BUF_DP<6>")
	)
	(segment
		(start 389.866632 -416.336734)
		(end 389.866632 -413.11703)
		(width 0.12954)
		(layer "F.Cu")
		(net "P5E_CPU0_P2_TX_BUF_DP<6>")
	)
	(segment
		(start 389.866632 -413.11703)
		(end 390.137142 -412.84652)
		(width 0.12954)
		(layer "F.Cu")
		(net "P5E_CPU0_P2_TX_BUF_DP<6>")
	)
	(segment
		(start 392.21664 -410.818076)
		(end 392.142218 -410.9974)
		(width 0.14224)
		(layer "In4.Cu")
		(net "P5E_CPU0_P2_TX_BUF_DP<6>")
	)
	(segment
		(start 407.317956 -405.985472)
		(end 404.683214 -407.076656)
		(width 0.14224)
		(layer "In4.Cu")
		(net "P5E_CPU0_P2_TX_BUF_DP<6>")
	)
	(segment
		(start 410.689298 -399.524474)
		(end 410.258514 -399.955258)
		(width 0.14224)
		(layer "In4.Cu")
		(net "P5E_CPU0_P2_TX_BUF_DP<6>")
	)
	(segment
		(start 393.64158 -410.48051)
		(end 393.233148 -410.604462)
		(width 0.14224)
		(layer "In4.Cu")
		(net "P5E_CPU0_P2_TX_BUF_DP<6>")
	)
	(segment
		(start 393.233148 -410.604462)
		(end 393.061952 -410.513022)
		(width 0.14224)
		(layer "In4.Cu")
		(net "P5E_CPU0_P2_TX_BUF_DP<6>")
	)
	(segment
		(start 391.174478 -411.249622)
		(end 391.10031 -411.4292)
		(width 0.14224)
		(layer "In4.Cu")
		(net "P5E_CPU0_P2_TX_BUF_DP<6>")
	)
	(segment
		(start 392.142218 -410.9974)
		(end 391.747756 -411.160722)
		(width 0.14224)
		(layer "In4.Cu")
		(net "P5E_CPU0_P2_TX_BUF_DP<6>")
	)
	(segment
		(start 391.747756 -411.160722)
		(end 391.568686 -411.086554)
		(width 0.14224)
		(layer "In4.Cu")
		(net "P5E_CPU0_P2_TX_BUF_DP<6>")
	)
	(segment
		(start 390.705594 -411.592268)
		(end 390.526524 -411.5181)
		(width 0.14224)
		(layer "In4.Cu")
		(net "P5E_CPU0_P2_TX_BUF_DP<6>")
	)
	(segment
		(start 402.083016 -407.776426)
		(end 393.73302 -410.309314)
		(width 0.14224)
		(layer "In4.Cu")
		(net "P5E_CPU0_P2_TX_BUF_DP<6>")
	)
	(segment
		(start 392.216894 -410.817822)
		(end 392.21664 -410.818076)
		(width 0.14224)
		(layer "In4.Cu")
		(net "P5E_CPU0_P2_TX_BUF_DP<6>")
	)
	(segment
		(start 402.936456 -407.6065)
		(end 402.083016 -407.776426)
		(width 0.14224)
		(layer "In4.Cu")
		(net "P5E_CPU0_P2_TX_BUF_DP<6>")
	)
	(segment
		(start 393.73302 -410.309314)
		(end 393.64158 -410.48051)
		(width 0.14224)
		(layer "In4.Cu")
		(net "P5E_CPU0_P2_TX_BUF_DP<6>")
	)
	(segment
		(start 390.038844 -411.72003)
		(end 389.93191 -411.826964)
		(width 0.14224)
		(layer "In4.Cu")
		(net "P5E_CPU0_P2_TX_BUF_DP<6>")
	)
	(segment
		(start 389.846312 -412.033466)
		(end 389.846312 -412.55569)
		(width 0.14224)
		(layer "In4.Cu")
		(net "P5E_CPU0_P2_TX_BUF_DP<6>")
	)
	(segment
		(start 392.653774 -410.63672)
		(end 392.216894 -410.817822)
		(width 0.14224)
		(layer "In4.Cu")
		(net "P5E_CPU0_P2_TX_BUF_DP<6>")
	)
	(segment
		(start 391.568686 -411.086554)
		(end 391.174478 -411.249622)
		(width 0.14224)
		(layer "In4.Cu")
		(net "P5E_CPU0_P2_TX_BUF_DP<6>")
	)
	(segment
		(start 410.995368 -398.558512)
		(end 410.995368 -398.785588)
		(width 0.14224)
		(layer "In4.Cu")
		(net "P5E_CPU0_P2_TX_BUF_DP<6>")
	)
	(segment
		(start 409.878276 -403.552406)
		(end 407.701496 -405.729186)
		(width 0.14224)
		(layer "In4.Cu")
		(net "P5E_CPU0_P2_TX_BUF_DP<6>")
	)
	(segment
		(start 389.846312 -412.55569)
		(end 390.137142 -412.84652)
		(width 0.14224)
		(layer "In4.Cu")
		(net "P5E_CPU0_P2_TX_BUF_DP<6>")
	)
	(segment
		(start 410.904182 -397.734536)
		(end 410.724096 -397.734536)
		(width 0.14224)
		(layer "In4.Cu")
		(net "P5E_CPU0_P2_TX_BUF_DP<6>")
	)
	(segment
		(start 410.192982 -400.1135)
		(end 410.192982 -402.792692)
		(width 0.14224)
		(layer "In4.Cu")
		(net "P5E_CPU0_P2_TX_BUF_DP<6>")
	)
	(segment
		(start 391.10031 -411.4292)
		(end 390.705594 -411.592268)
		(width 0.14224)
		(layer "In4.Cu")
		(net "P5E_CPU0_P2_TX_BUF_DP<6>")
	)
	(segment
		(start 410.634688 -397.823944)
		(end 410.634688 -397.907256)
		(width 0.14224)
		(layer "In4.Cu")
		(net "P5E_CPU0_P2_TX_BUF_DP<6>")
	)
	(segment
		(start 404.683214 -407.076656)
		(end 402.936456 -407.6065)
		(width 0.14224)
		(layer "In4.Cu")
		(net "P5E_CPU0_P2_TX_BUF_DP<6>")
	)
	(segment
		(start 390.526524 -411.5181)
		(end 390.038844 -411.72003)
		(width 0.14224)
		(layer "In4.Cu")
		(net "P5E_CPU0_P2_TX_BUF_DP<6>")
	)
	(segment
		(start 393.061952 -410.513022)
		(end 392.653774 -410.63672)
		(width 0.14224)
		(layer "In4.Cu")
		(net "P5E_CPU0_P2_TX_BUF_DP<6>")
	)
	(segment
		(start 411.01899 -397.849344)
		(end 410.904182 -397.734536)
		(width 0.14224)
		(layer "In4.Cu")
		(net "P5E_CPU0_P2_TX_BUF_DP<6>")
	)
	(segment
		(start 410.720286 -398.113758)
		(end 410.87548 -398.268952)
		(width 0.14224)
		(layer "In4.Cu")
		(net "P5E_CPU0_P2_TX_BUF_DP<6>")
	)
	(segment
		(start 410.724096 -397.734536)
		(end 410.634688 -397.823944)
		(width 0.14224)
		(layer "In4.Cu")
		(net "P5E_CPU0_P2_TX_BUF_DP<6>")
	)
	(arc
		(start 410.258514 -399.955258)
		(mid 410.210003 -400.02786)
		(end 410.192982 -400.1135)
		(width 0.14224)
		(layer "In4.Cu")
		(net "P5E_CPU0_P2_TX_BUF_DP<6>")
	)
	(arc
		(start 410.634688 -397.907256)
		(mid 410.656938 -398.019024)
		(end 410.720286 -398.113758)
		(width 0.14224)
		(layer "In4.Cu")
		(net "P5E_CPU0_P2_TX_BUF_DP<6>")
	)
	(arc
		(start 410.995368 -398.785588)
		(mid 410.915825 -399.185475)
		(end 410.689298 -399.524474)
		(width 0.14224)
		(layer "In4.Cu")
		(net "P5E_CPU0_P2_TX_BUF_DP<6>")
	)
	(arc
		(start 389.93191 -411.826964)
		(mid 389.86855 -411.921694)
		(end 389.846312 -412.033466)
		(width 0.14224)
		(layer "In4.Cu")
		(net "P5E_CPU0_P2_TX_BUF_DP<6>")
	)
	(arc
		(start 407.701496 -405.729186)
		(mid 407.522344 -405.876211)
		(end 407.317956 -405.985472)
		(width 0.14224)
		(layer "In4.Cu")
		(net "P5E_CPU0_P2_TX_BUF_DP<6>")
	)
	(arc
		(start 410.87548 -398.268952)
		(mid 410.964195 -398.401817)
		(end 410.995368 -398.558512)
		(width 0.14224)
		(layer "In4.Cu")
		(net "P5E_CPU0_P2_TX_BUF_DP<6>")
	)
	(arc
		(start 410.192982 -402.792692)
		(mid 410.111197 -403.203855)
		(end 409.878276 -403.552406)
		(width 0.14224)
		(layer "In4.Cu")
		(net "P5E_CPU0_P2_TX_BUF_DP<6>")
	)
	(segment
		(start 409.298394 -397.849344)
		(end 409.819094 -397.849344)
		(width 0.127)
		(layer "F.Cu")
		(net "P5E_CPU0_P2_TX_BUF_DP<5>")
	)
	(segment
		(start 386.803392 -413.11703)
		(end 387.073902 -412.84652)
		(width 0.12954)
		(layer "F.Cu")
		(net "P5E_CPU0_P2_TX_BUF_DP<5>")
	)
	(segment
		(start 386.803392 -416.336734)
		(end 386.803392 -413.11703)
		(width 0.12954)
		(layer "F.Cu")
		(net "P5E_CPU0_P2_TX_BUF_DP<5>")
	)
	(segment
		(start 387.099302 -416.632644)
		(end 386.803392 -416.336734)
		(width 0.12954)
		(layer "F.Cu")
		(net "P5E_CPU0_P2_TX_BUF_DP<5>")
	)
	(segment
		(start 404.43658 -406.169368)
		(end 402.952712 -406.61971)
		(width 0.14224)
		(layer "In4.Cu")
		(net "P5E_CPU0_P2_TX_BUF_DP<5>")
	)
	(segment
		(start 388.04723 -411.38348)
		(end 387.972808 -411.562804)
		(width 0.14224)
		(layer "In4.Cu")
		(net "P5E_CPU0_P2_TX_BUF_DP<5>")
	)
	(segment
		(start 387.399276 -411.651958)
		(end 387.005068 -411.815026)
		(width 0.14224)
		(layer "In4.Cu")
		(net "P5E_CPU0_P2_TX_BUF_DP<5>")
	)
	(segment
		(start 388.620508 -411.294326)
		(end 388.441438 -411.220158)
		(width 0.14224)
		(layer "In4.Cu")
		(net "P5E_CPU0_P2_TX_BUF_DP<5>")
	)
	(segment
		(start 387.972808 -411.562804)
		(end 387.578346 -411.726126)
		(width 0.14224)
		(layer "In4.Cu")
		(net "P5E_CPU0_P2_TX_BUF_DP<5>")
	)
	(segment
		(start 390.971278 -410.172408)
		(end 390.131554 -410.520134)
		(width 0.14224)
		(layer "In4.Cu")
		(net "P5E_CPU0_P2_TX_BUF_DP<5>")
	)
	(segment
		(start 386.783072 -412.17977)
		(end 386.783072 -412.55569)
		(width 0.14224)
		(layer "In4.Cu")
		(net "P5E_CPU0_P2_TX_BUF_DP<5>")
	)
	(segment
		(start 408.763978 -403.296882)
		(end 406.990042 -405.070818)
		(width 0.14224)
		(layer "In4.Cu")
		(net "P5E_CPU0_P2_TX_BUF_DP<5>")
	)
	(segment
		(start 408.996642 -400.104864)
		(end 408.996642 -402.735288)
		(width 0.14224)
		(layer "In4.Cu")
		(net "P5E_CPU0_P2_TX_BUF_DP<5>")
	)
	(segment
		(start 387.578346 -411.726126)
		(end 387.399276 -411.651958)
		(width 0.14224)
		(layer "In4.Cu")
		(net "P5E_CPU0_P2_TX_BUF_DP<5>")
	)
	(segment
		(start 390.131554 -410.520134)
		(end 390.057132 -410.699458)
		(width 0.14224)
		(layer "In4.Cu")
		(net "P5E_CPU0_P2_TX_BUF_DP<5>")
	)
	(segment
		(start 387.005068 -411.815026)
		(end 386.884164 -411.93593)
		(width 0.14224)
		(layer "In4.Cu")
		(net "P5E_CPU0_P2_TX_BUF_DP<5>")
	)
	(segment
		(start 406.82926 -405.17826)
		(end 404.43658 -406.169368)
		(width 0.14224)
		(layer "In4.Cu")
		(net "P5E_CPU0_P2_TX_BUF_DP<5>")
	)
	(segment
		(start 409.620466 -399.347182)
		(end 409.091384 -399.876264)
		(width 0.14224)
		(layer "In4.Cu")
		(net "P5E_CPU0_P2_TX_BUF_DP<5>")
	)
	(segment
		(start 389.01497 -411.131004)
		(end 388.620508 -411.294326)
		(width 0.14224)
		(layer "In4.Cu")
		(net "P5E_CPU0_P2_TX_BUF_DP<5>")
	)
	(segment
		(start 389.089392 -410.95168)
		(end 389.01497 -411.131004)
		(width 0.14224)
		(layer "In4.Cu")
		(net "P5E_CPU0_P2_TX_BUF_DP<5>")
	)
	(segment
		(start 409.704286 -397.734536)
		(end 409.540964 -397.734536)
		(width 0.14224)
		(layer "In4.Cu")
		(net "P5E_CPU0_P2_TX_BUF_DP<5>")
	)
	(segment
		(start 388.441438 -411.220158)
		(end 388.04723 -411.38348)
		(width 0.14224)
		(layer "In4.Cu")
		(net "P5E_CPU0_P2_TX_BUF_DP<5>")
	)
	(segment
		(start 409.434792 -397.840708)
		(end 409.434792 -397.875506)
		(width 0.14224)
		(layer "In4.Cu")
		(net "P5E_CPU0_P2_TX_BUF_DP<5>")
	)
	(segment
		(start 389.4836 -410.788612)
		(end 389.089392 -410.95168)
		(width 0.14224)
		(layer "In4.Cu")
		(net "P5E_CPU0_P2_TX_BUF_DP<5>")
	)
	(segment
		(start 390.057132 -410.699458)
		(end 389.66267 -410.86278)
		(width 0.14224)
		(layer "In4.Cu")
		(net "P5E_CPU0_P2_TX_BUF_DP<5>")
	)
	(segment
		(start 386.783072 -412.55569)
		(end 387.073902 -412.84652)
		(width 0.14224)
		(layer "In4.Cu")
		(net "P5E_CPU0_P2_TX_BUF_DP<5>")
	)
	(segment
		(start 409.819094 -397.849344)
		(end 409.704286 -397.734536)
		(width 0.14224)
		(layer "In4.Cu")
		(net "P5E_CPU0_P2_TX_BUF_DP<5>")
	)
	(segment
		(start 402.952712 -406.61971)
		(end 402.169122 -406.775412)
		(width 0.14224)
		(layer "In4.Cu")
		(net "P5E_CPU0_P2_TX_BUF_DP<5>")
	)
	(segment
		(start 409.540964 -397.734536)
		(end 409.434792 -397.840708)
		(width 0.14224)
		(layer "In4.Cu")
		(net "P5E_CPU0_P2_TX_BUF_DP<5>")
	)
	(segment
		(start 389.66267 -410.86278)
		(end 389.4836 -410.788612)
		(width 0.14224)
		(layer "In4.Cu")
		(net "P5E_CPU0_P2_TX_BUF_DP<5>")
	)
	(segment
		(start 409.795472 -398.745202)
		(end 409.795472 -398.92478)
		(width 0.14224)
		(layer "In4.Cu")
		(net "P5E_CPU0_P2_TX_BUF_DP<5>")
	)
	(segment
		(start 402.169122 -406.775412)
		(end 390.971278 -410.172408)
		(width 0.14224)
		(layer "In4.Cu")
		(net "P5E_CPU0_P2_TX_BUF_DP<5>")
	)
	(arc
		(start 409.091384 -399.876264)
		(mid 409.02125 -399.981132)
		(end 408.996642 -400.104864)
		(width 0.14224)
		(layer "In4.Cu")
		(net "P5E_CPU0_P2_TX_BUF_DP<5>")
	)
	(arc
		(start 406.990042 -405.070818)
		(mid 406.914956 -405.132482)
		(end 406.82926 -405.17826)
		(width 0.14224)
		(layer "In4.Cu")
		(net "P5E_CPU0_P2_TX_BUF_DP<5>")
	)
	(arc
		(start 409.795472 -398.92478)
		(mid 409.749982 -399.153384)
		(end 409.620466 -399.347182)
		(width 0.14224)
		(layer "In4.Cu")
		(net "P5E_CPU0_P2_TX_BUF_DP<5>")
	)
	(arc
		(start 409.434792 -397.875506)
		(mid 409.462968 -398.016686)
		(end 409.542996 -398.136364)
		(width 0.14224)
		(layer "In4.Cu")
		(net "P5E_CPU0_P2_TX_BUF_DP<5>")
	)
	(arc
		(start 386.884164 -411.93593)
		(mid 386.809358 -412.04779)
		(end 386.783072 -412.17977)
		(width 0.14224)
		(layer "In4.Cu")
		(net "P5E_CPU0_P2_TX_BUF_DP<5>")
	)
	(arc
		(start 408.996642 -402.735288)
		(mid 408.936168 -403.039223)
		(end 408.763978 -403.296882)
		(width 0.14224)
		(layer "In4.Cu")
		(net "P5E_CPU0_P2_TX_BUF_DP<5>")
	)
	(arc
		(start 409.542996 -398.136364)
		(mid 409.729702 -398.4157)
		(end 409.795472 -398.745202)
		(width 0.14224)
		(layer "In4.Cu")
		(net "P5E_CPU0_P2_TX_BUF_DP<5>")
	)
	(segment
		(start 384.036062 -416.632644)
		(end 383.740152 -416.336734)
		(width 0.12954)
		(layer "F.Cu")
		(net "P5E_CPU0_P2_TX_BUF_DP<4>")
	)
	(segment
		(start 383.740152 -413.11703)
		(end 384.010662 -412.84652)
		(width 0.12954)
		(layer "F.Cu")
		(net "P5E_CPU0_P2_TX_BUF_DP<4>")
	)
	(segment
		(start 383.740152 -416.336734)
		(end 383.740152 -413.11703)
		(width 0.12954)
		(layer "F.Cu")
		(net "P5E_CPU0_P2_TX_BUF_DP<4>")
	)
	(segment
		(start 408.098244 -397.849344)
		(end 408.618944 -397.849344)
		(width 0.127)
		(layer "F.Cu")
		(net "P5E_CPU0_P2_TX_BUF_DP<4>")
	)
	(segment
		(start 386.071364 -410.891482)
		(end 385.996942 -411.070806)
		(width 0.14224)
		(layer "In4.Cu")
		(net "P5E_CPU0_P2_TX_BUF_DP<4>")
	)
	(segment
		(start 384.95478 -411.502352)
		(end 384.560318 -411.665674)
		(width 0.14224)
		(layer "In4.Cu")
		(net "P5E_CPU0_P2_TX_BUF_DP<4>")
	)
	(segment
		(start 408.234642 -397.823944)
		(end 408.234642 -397.97355)
		(width 0.14224)
		(layer "In4.Cu")
		(net "P5E_CPU0_P2_TX_BUF_DP<4>")
	)
	(segment
		(start 406.004268 -404.510748)
		(end 404.37435 -405.18588)
		(width 0.14224)
		(layer "In4.Cu")
		(net "P5E_CPU0_P2_TX_BUF_DP<4>")
	)
	(segment
		(start 385.029202 -411.323028)
		(end 384.95478 -411.502352)
		(width 0.14224)
		(layer "In4.Cu")
		(net "P5E_CPU0_P2_TX_BUF_DP<4>")
	)
	(segment
		(start 383.719832 -412.219902)
		(end 383.719832 -412.55569)
		(width 0.14224)
		(layer "In4.Cu")
		(net "P5E_CPU0_P2_TX_BUF_DP<4>")
	)
	(segment
		(start 386.465572 -410.728414)
		(end 386.071364 -410.891482)
		(width 0.14224)
		(layer "In4.Cu")
		(net "P5E_CPU0_P2_TX_BUF_DP<4>")
	)
	(segment
		(start 408.595322 -398.558258)
		(end 408.595322 -398.84604)
		(width 0.14224)
		(layer "In4.Cu")
		(net "P5E_CPU0_P2_TX_BUF_DP<4>")
	)
	(segment
		(start 387.947408 -410.114496)
		(end 387.113526 -410.459936)
		(width 0.14224)
		(layer "In4.Cu")
		(net "P5E_CPU0_P2_TX_BUF_DP<4>")
	)
	(segment
		(start 385.42341 -411.15996)
		(end 385.029202 -411.323028)
		(width 0.14224)
		(layer "In4.Cu")
		(net "P5E_CPU0_P2_TX_BUF_DP<4>")
	)
	(segment
		(start 383.719832 -412.55569)
		(end 384.010662 -412.84652)
		(width 0.14224)
		(layer "In4.Cu")
		(net "P5E_CPU0_P2_TX_BUF_DP<4>")
	)
	(segment
		(start 387.113526 -410.459936)
		(end 387.039104 -410.63926)
		(width 0.14224)
		(layer "In4.Cu")
		(net "P5E_CPU0_P2_TX_BUF_DP<4>")
	)
	(segment
		(start 384.560318 -411.665674)
		(end 384.381248 -411.591506)
		(width 0.14224)
		(layer "In4.Cu")
		(net "P5E_CPU0_P2_TX_BUF_DP<4>")
	)
	(segment
		(start 408.32405 -397.734536)
		(end 408.234642 -397.823944)
		(width 0.14224)
		(layer "In4.Cu")
		(net "P5E_CPU0_P2_TX_BUF_DP<4>")
	)
	(segment
		(start 402.636736 -405.713184)
		(end 402.116798 -405.816562)
		(width 0.14224)
		(layer "In4.Cu")
		(net "P5E_CPU0_P2_TX_BUF_DP<4>")
	)
	(segment
		(start 383.98704 -411.754574)
		(end 383.86004 -411.881574)
		(width 0.14224)
		(layer "In4.Cu")
		(net "P5E_CPU0_P2_TX_BUF_DP<4>")
	)
	(segment
		(start 408.27198 -398.063466)
		(end 408.474164 -398.26565)
		(width 0.14224)
		(layer "In4.Cu")
		(net "P5E_CPU0_P2_TX_BUF_DP<4>")
	)
	(segment
		(start 387.039104 -410.63926)
		(end 386.644642 -410.802582)
		(width 0.14224)
		(layer "In4.Cu")
		(net "P5E_CPU0_P2_TX_BUF_DP<4>")
	)
	(segment
		(start 384.381248 -411.591506)
		(end 383.98704 -411.754574)
		(width 0.14224)
		(layer "In4.Cu")
		(net "P5E_CPU0_P2_TX_BUF_DP<4>")
	)
	(segment
		(start 402.116798 -405.816562)
		(end 387.947408 -410.114496)
		(width 0.14224)
		(layer "In4.Cu")
		(net "P5E_CPU0_P2_TX_BUF_DP<4>")
	)
	(segment
		(start 407.654252 -403.025102)
		(end 406.499568 -404.179786)
		(width 0.14224)
		(layer "In4.Cu")
		(net "P5E_CPU0_P2_TX_BUF_DP<4>")
	)
	(segment
		(start 408.618944 -397.849344)
		(end 408.504136 -397.734536)
		(width 0.14224)
		(layer "In4.Cu")
		(net "P5E_CPU0_P2_TX_BUF_DP<4>")
	)
	(segment
		(start 407.817574 -399.960592)
		(end 407.817574 -402.630894)
		(width 0.14224)
		(layer "In4.Cu")
		(net "P5E_CPU0_P2_TX_BUF_DP<4>")
	)
	(segment
		(start 385.996942 -411.070806)
		(end 385.60248 -411.234128)
		(width 0.14224)
		(layer "In4.Cu")
		(net "P5E_CPU0_P2_TX_BUF_DP<4>")
	)
	(segment
		(start 404.37435 -405.18588)
		(end 402.636736 -405.713184)
		(width 0.14224)
		(layer "In4.Cu")
		(net "P5E_CPU0_P2_TX_BUF_DP<4>")
	)
	(segment
		(start 385.60248 -411.234128)
		(end 385.42341 -411.15996)
		(width 0.14224)
		(layer "In4.Cu")
		(net "P5E_CPU0_P2_TX_BUF_DP<4>")
	)
	(segment
		(start 408.504136 -397.734536)
		(end 408.32405 -397.734536)
		(width 0.14224)
		(layer "In4.Cu")
		(net "P5E_CPU0_P2_TX_BUF_DP<4>")
	)
	(segment
		(start 386.644642 -410.802582)
		(end 386.465572 -410.728414)
		(width 0.14224)
		(layer "In4.Cu")
		(net "P5E_CPU0_P2_TX_BUF_DP<4>")
	)
	(segment
		(start 408.413458 -399.285206)
		(end 407.873708 -399.824956)
		(width 0.14224)
		(layer "In4.Cu")
		(net "P5E_CPU0_P2_TX_BUF_DP<4>")
	)
	(arc
		(start 407.817574 -402.630894)
		(mid 407.775135 -402.844251)
		(end 407.654252 -403.025102)
		(width 0.14224)
		(layer "In4.Cu")
		(net "P5E_CPU0_P2_TX_BUF_DP<4>")
	)
	(arc
		(start 406.499568 -404.179786)
		(mid 406.268213 -404.369652)
		(end 406.004268 -404.510748)
		(width 0.14224)
		(layer "In4.Cu")
		(net "P5E_CPU0_P2_TX_BUF_DP<4>")
	)
	(arc
		(start 408.474164 -398.26565)
		(mid 408.563813 -398.399914)
		(end 408.595322 -398.558258)
		(width 0.14224)
		(layer "In4.Cu")
		(net "P5E_CPU0_P2_TX_BUF_DP<4>")
	)
	(arc
		(start 383.86004 -411.881574)
		(mid 383.756267 -412.036786)
		(end 383.719832 -412.219902)
		(width 0.14224)
		(layer "In4.Cu")
		(net "P5E_CPU0_P2_TX_BUF_DP<4>")
	)
	(arc
		(start 407.873708 -399.824956)
		(mid 407.832181 -399.887201)
		(end 407.817574 -399.960592)
		(width 0.14224)
		(layer "In4.Cu")
		(net "P5E_CPU0_P2_TX_BUF_DP<4>")
	)
	(arc
		(start 408.234642 -397.97355)
		(mid 408.244344 -398.022234)
		(end 408.27198 -398.063466)
		(width 0.14224)
		(layer "In4.Cu")
		(net "P5E_CPU0_P2_TX_BUF_DP<4>")
	)
	(arc
		(start 408.595322 -398.84604)
		(mid 408.548064 -399.083712)
		(end 408.413458 -399.285206)
		(width 0.14224)
		(layer "In4.Cu")
		(net "P5E_CPU0_P2_TX_BUF_DP<4>")
	)
	(segment
		(start 380.676912 -413.11703)
		(end 380.947422 -412.84652)
		(width 0.12954)
		(layer "F.Cu")
		(net "P5E_CPU0_P2_TX_BUF_DP<3>")
	)
	(segment
		(start 380.972822 -416.632644)
		(end 380.676912 -416.336734)
		(width 0.12954)
		(layer "F.Cu")
		(net "P5E_CPU0_P2_TX_BUF_DP<3>")
	)
	(segment
		(start 380.676912 -416.336734)
		(end 380.676912 -413.11703)
		(width 0.12954)
		(layer "F.Cu")
		(net "P5E_CPU0_P2_TX_BUF_DP<3>")
	)
	(segment
		(start 406.898348 -397.849344)
		(end 407.419048 -397.849344)
		(width 0.127)
		(layer "F.Cu")
		(net "P5E_CPU0_P2_TX_BUF_DP<3>")
	)
	(segment
		(start 406.501346 -402.84019)
		(end 405.880824 -403.460712)
		(width 0.14224)
		(layer "In4.Cu")
		(net "P5E_CPU0_P2_TX_BUF_DP<3>")
	)
	(segment
		(start 407.395426 -398.55775)
		(end 407.395426 -398.717516)
		(width 0.14224)
		(layer "In4.Cu")
		(net "P5E_CPU0_P2_TX_BUF_DP<3>")
	)
	(segment
		(start 384.578352 -410.161994)
		(end 384.363214 -410.251148)
		(width 0.14224)
		(layer "In4.Cu")
		(net "P5E_CPU0_P2_TX_BUF_DP<3>")
	)
	(segment
		(start 407.034746 -397.823944)
		(end 407.034746 -397.919956)
		(width 0.14224)
		(layer "In4.Cu")
		(net "P5E_CPU0_P2_TX_BUF_DP<3>")
	)
	(segment
		(start 382.204722 -411.294072)
		(end 381.81026 -411.457394)
		(width 0.14224)
		(layer "In4.Cu")
		(net "P5E_CPU0_P2_TX_BUF_DP<3>")
	)
	(segment
		(start 382.27889 -411.114494)
		(end 382.204722 -411.294072)
		(width 0.14224)
		(layer "In4.Cu")
		(net "P5E_CPU0_P2_TX_BUF_DP<3>")
	)
	(segment
		(start 383.71526 -410.519626)
		(end 383.321052 -410.682694)
		(width 0.14224)
		(layer "In4.Cu")
		(net "P5E_CPU0_P2_TX_BUF_DP<3>")
	)
	(segment
		(start 380.656592 -412.55569)
		(end 380.947422 -412.84652)
		(width 0.14224)
		(layer "In4.Cu")
		(net "P5E_CPU0_P2_TX_BUF_DP<3>")
	)
	(segment
		(start 407.419048 -397.849344)
		(end 407.30424 -397.734536)
		(width 0.14224)
		(layer "In4.Cu")
		(net "P5E_CPU0_P2_TX_BUF_DP<3>")
	)
	(segment
		(start 407.30424 -397.734536)
		(end 407.124154 -397.734536)
		(width 0.14224)
		(layer "In4.Cu")
		(net "P5E_CPU0_P2_TX_BUF_DP<3>")
	)
	(segment
		(start 407.111454 -398.104868)
		(end 407.275538 -398.268698)
		(width 0.14224)
		(layer "In4.Cu")
		(net "P5E_CPU0_P2_TX_BUF_DP<3>")
	)
	(segment
		(start 381.630936 -411.382972)
		(end 381.09017 -411.607)
		(width 0.14224)
		(layer "In4.Cu")
		(net "P5E_CPU0_P2_TX_BUF_DP<3>")
	)
	(segment
		(start 402.251926 -404.80107)
		(end 384.578352 -410.161994)
		(width 0.14224)
		(layer "In4.Cu")
		(net "P5E_CPU0_P2_TX_BUF_DP<3>")
	)
	(segment
		(start 382.852422 -411.025594)
		(end 382.673098 -410.951426)
		(width 0.14224)
		(layer "In4.Cu")
		(net "P5E_CPU0_P2_TX_BUF_DP<3>")
	)
	(segment
		(start 384.363214 -410.251148)
		(end 384.289046 -410.430726)
		(width 0.14224)
		(layer "In4.Cu")
		(net "P5E_CPU0_P2_TX_BUF_DP<3>")
	)
	(segment
		(start 407.200862 -399.187162)
		(end 406.712166 -399.675858)
		(width 0.14224)
		(layer "In4.Cu")
		(net "P5E_CPU0_P2_TX_BUF_DP<3>")
	)
	(segment
		(start 383.321052 -410.682694)
		(end 383.246884 -410.862272)
		(width 0.14224)
		(layer "In4.Cu")
		(net "P5E_CPU0_P2_TX_BUF_DP<3>")
	)
	(segment
		(start 382.673098 -410.951426)
		(end 382.27889 -411.114494)
		(width 0.14224)
		(layer "In4.Cu")
		(net "P5E_CPU0_P2_TX_BUF_DP<3>")
	)
	(segment
		(start 383.246884 -410.862272)
		(end 382.852422 -411.025594)
		(width 0.14224)
		(layer "In4.Cu")
		(net "P5E_CPU0_P2_TX_BUF_DP<3>")
	)
	(segment
		(start 381.048768 -411.634686)
		(end 380.774194 -411.90926)
		(width 0.14224)
		(layer "In4.Cu")
		(net "P5E_CPU0_P2_TX_BUF_DP<3>")
	)
	(segment
		(start 407.124154 -397.734536)
		(end 407.034746 -397.823944)
		(width 0.14224)
		(layer "In4.Cu")
		(net "P5E_CPU0_P2_TX_BUF_DP<3>")
	)
	(segment
		(start 383.894584 -410.594048)
		(end 383.71526 -410.519626)
		(width 0.14224)
		(layer "In4.Cu")
		(net "P5E_CPU0_P2_TX_BUF_DP<3>")
	)
	(segment
		(start 402.742654 -404.70328)
		(end 402.251926 -404.80107)
		(width 0.14224)
		(layer "In4.Cu")
		(net "P5E_CPU0_P2_TX_BUF_DP<3>")
	)
	(segment
		(start 405.521668 -403.700742)
		(end 404.084282 -404.296372)
		(width 0.14224)
		(layer "In4.Cu")
		(net "P5E_CPU0_P2_TX_BUF_DP<3>")
	)
	(segment
		(start 380.656592 -412.192978)
		(end 380.656592 -412.55569)
		(width 0.14224)
		(layer "In4.Cu")
		(net "P5E_CPU0_P2_TX_BUF_DP<3>")
	)
	(segment
		(start 381.81026 -411.457394)
		(end 381.630936 -411.382972)
		(width 0.14224)
		(layer "In4.Cu")
		(net "P5E_CPU0_P2_TX_BUF_DP<3>")
	)
	(segment
		(start 406.621234 -399.895314)
		(end 406.621234 -402.550884)
		(width 0.14224)
		(layer "In4.Cu")
		(net "P5E_CPU0_P2_TX_BUF_DP<3>")
	)
	(segment
		(start 404.084282 -404.296372)
		(end 402.742654 -404.70328)
		(width 0.14224)
		(layer "In4.Cu")
		(net "P5E_CPU0_P2_TX_BUF_DP<3>")
	)
	(segment
		(start 384.289046 -410.430726)
		(end 383.894584 -410.594048)
		(width 0.14224)
		(layer "In4.Cu")
		(net "P5E_CPU0_P2_TX_BUF_DP<3>")
	)
	(arc
		(start 406.621234 -402.550884)
		(mid 406.590071 -402.707462)
		(end 406.501346 -402.84019)
		(width 0.14224)
		(layer "In4.Cu")
		(net "P5E_CPU0_P2_TX_BUF_DP<3>")
	)
	(arc
		(start 381.09017 -411.607)
		(mid 381.068095 -411.618791)
		(end 381.048768 -411.634686)
		(width 0.14224)
		(layer "In4.Cu")
		(net "P5E_CPU0_P2_TX_BUF_DP<3>")
	)
	(arc
		(start 407.034746 -397.919956)
		(mid 407.054691 -398.020045)
		(end 407.111454 -398.104868)
		(width 0.14224)
		(layer "In4.Cu")
		(net "P5E_CPU0_P2_TX_BUF_DP<3>")
	)
	(arc
		(start 407.395426 -398.717516)
		(mid 407.344866 -398.971698)
		(end 407.200862 -399.187162)
		(width 0.14224)
		(layer "In4.Cu")
		(net "P5E_CPU0_P2_TX_BUF_DP<3>")
	)
	(arc
		(start 406.712166 -399.675858)
		(mid 406.644889 -399.776545)
		(end 406.621234 -399.895314)
		(width 0.14224)
		(layer "In4.Cu")
		(net "P5E_CPU0_P2_TX_BUF_DP<3>")
	)
	(arc
		(start 380.774194 -411.90926)
		(mid 380.687163 -412.039417)
		(end 380.656592 -412.192978)
		(width 0.14224)
		(layer "In4.Cu")
		(net "P5E_CPU0_P2_TX_BUF_DP<3>")
	)
	(arc
		(start 407.275538 -398.268698)
		(mid 407.364234 -398.401301)
		(end 407.395426 -398.55775)
		(width 0.14224)
		(layer "In4.Cu")
		(net "P5E_CPU0_P2_TX_BUF_DP<3>")
	)
	(arc
		(start 405.880824 -403.460712)
		(mid 405.713059 -403.598401)
		(end 405.521668 -403.700742)
		(width 0.14224)
		(layer "In4.Cu")
		(net "P5E_CPU0_P2_TX_BUF_DP<3>")
	)
	(segment
		(start 377.909582 -416.632644)
		(end 377.613672 -416.336734)
		(width 0.12954)
		(layer "F.Cu")
		(net "P5E_CPU0_P2_TX_BUF_DP<2>")
	)
	(segment
		(start 377.613672 -416.336734)
		(end 377.613672 -413.11703)
		(width 0.12954)
		(layer "F.Cu")
		(net "P5E_CPU0_P2_TX_BUF_DP<2>")
	)
	(segment
		(start 405.698198 -397.849344)
		(end 406.218898 -397.849344)
		(width 0.127)
		(layer "F.Cu")
		(net "P5E_CPU0_P2_TX_BUF_DP<2>")
	)
	(segment
		(start 377.613672 -413.11703)
		(end 377.884182 -412.84652)
		(width 0.12954)
		(layer "F.Cu")
		(net "P5E_CPU0_P2_TX_BUF_DP<2>")
	)
	(segment
		(start 379.392942 -411.113224)
		(end 378.998734 -411.276292)
		(width 0.14224)
		(layer "In4.Cu")
		(net "P5E_CPU0_P2_TX_BUF_DP<2>")
	)
	(segment
		(start 379.966474 -411.02407)
		(end 379.572012 -411.187392)
		(width 0.14224)
		(layer "In4.Cu")
		(net "P5E_CPU0_P2_TX_BUF_DP<2>")
	)
	(segment
		(start 405.883618 -398.0688)
		(end 405.982932 -398.168368)
		(width 0.14224)
		(layer "In4.Cu")
		(net "P5E_CPU0_P2_TX_BUF_DP<2>")
	)
	(segment
		(start 377.915424 -411.73527)
		(end 377.745244 -411.90545)
		(width 0.14224)
		(layer "In4.Cu")
		(net "P5E_CPU0_P2_TX_BUF_DP<2>")
	)
	(segment
		(start 405.425656 -400.151346)
		(end 405.425656 -402.274786)
		(width 0.14224)
		(layer "In4.Cu")
		(net "P5E_CPU0_P2_TX_BUF_DP<2>")
	)
	(segment
		(start 405.903684 -399.171668)
		(end 405.780494 -399.294858)
		(width 0.14224)
		(layer "In4.Cu")
		(net "P5E_CPU0_P2_TX_BUF_DP<2>")
	)
	(segment
		(start 378.35078 -411.54477)
		(end 377.956572 -411.707838)
		(width 0.14224)
		(layer "In4.Cu")
		(net "P5E_CPU0_P2_TX_BUF_DP<2>")
	)
	(segment
		(start 406.103074 -397.73352)
		(end 405.953214 -397.73352)
		(width 0.14224)
		(layer "In4.Cu")
		(net "P5E_CPU0_P2_TX_BUF_DP<2>")
	)
	(segment
		(start 402.929598 -403.636988)
		(end 402.775674 -403.667722)
		(width 0.14224)
		(layer "In4.Cu")
		(net "P5E_CPU0_P2_TX_BUF_DP<2>")
	)
	(segment
		(start 381.083058 -410.4132)
		(end 381.008636 -410.592524)
		(width 0.14224)
		(layer "In4.Cu")
		(net "P5E_CPU0_P2_TX_BUF_DP<2>")
	)
	(segment
		(start 378.52985 -411.618938)
		(end 378.35078 -411.54477)
		(width 0.14224)
		(layer "In4.Cu")
		(net "P5E_CPU0_P2_TX_BUF_DP<2>")
	)
	(segment
		(start 405.953214 -397.73352)
		(end 405.883872 -397.802862)
		(width 0.14224)
		(layer "In4.Cu")
		(net "P5E_CPU0_P2_TX_BUF_DP<2>")
	)
	(segment
		(start 382.573784 -409.795726)
		(end 381.083058 -410.4132)
		(width 0.14224)
		(layer "In4.Cu")
		(net "P5E_CPU0_P2_TX_BUF_DP<2>")
	)
	(segment
		(start 377.593352 -412.272226)
		(end 377.593352 -412.55569)
		(width 0.14224)
		(layer "In4.Cu")
		(net "P5E_CPU0_P2_TX_BUF_DP<2>")
	)
	(segment
		(start 404.072344 -403.290278)
		(end 402.929598 -403.636988)
		(width 0.14224)
		(layer "In4.Cu")
		(net "P5E_CPU0_P2_TX_BUF_DP<2>")
	)
	(segment
		(start 380.040896 -410.844746)
		(end 379.966474 -411.02407)
		(width 0.14224)
		(layer "In4.Cu")
		(net "P5E_CPU0_P2_TX_BUF_DP<2>")
	)
	(segment
		(start 377.593352 -412.55569)
		(end 377.884182 -412.84652)
		(width 0.14224)
		(layer "In4.Cu")
		(net "P5E_CPU0_P2_TX_BUF_DP<2>")
	)
	(segment
		(start 402.775674 -403.667722)
		(end 382.573784 -409.795726)
		(width 0.14224)
		(layer "In4.Cu")
		(net "P5E_CPU0_P2_TX_BUF_DP<2>")
	)
	(segment
		(start 378.998734 -411.276292)
		(end 378.924312 -411.455616)
		(width 0.14224)
		(layer "In4.Cu")
		(net "P5E_CPU0_P2_TX_BUF_DP<2>")
	)
	(segment
		(start 406.218898 -397.849344)
		(end 406.103074 -397.73352)
		(width 0.14224)
		(layer "In4.Cu")
		(net "P5E_CPU0_P2_TX_BUF_DP<2>")
	)
	(segment
		(start 380.435104 -410.681678)
		(end 380.040896 -410.844746)
		(width 0.14224)
		(layer "In4.Cu")
		(net "P5E_CPU0_P2_TX_BUF_DP<2>")
	)
	(segment
		(start 379.572012 -411.187392)
		(end 379.392942 -411.113224)
		(width 0.14224)
		(layer "In4.Cu")
		(net "P5E_CPU0_P2_TX_BUF_DP<2>")
	)
	(segment
		(start 405.004524 -402.90496)
		(end 404.072344 -403.290278)
		(width 0.14224)
		(layer "In4.Cu")
		(net "P5E_CPU0_P2_TX_BUF_DP<2>")
	)
	(segment
		(start 380.614174 -410.755846)
		(end 380.435104 -410.681678)
		(width 0.14224)
		(layer "In4.Cu")
		(net "P5E_CPU0_P2_TX_BUF_DP<2>")
	)
	(segment
		(start 378.924312 -411.455616)
		(end 378.52985 -411.618938)
		(width 0.14224)
		(layer "In4.Cu")
		(net "P5E_CPU0_P2_TX_BUF_DP<2>")
	)
	(segment
		(start 381.008636 -410.592524)
		(end 380.614174 -410.755846)
		(width 0.14224)
		(layer "In4.Cu")
		(net "P5E_CPU0_P2_TX_BUF_DP<2>")
	)
	(segment
		(start 406.108408 -398.47139)
		(end 406.108408 -398.676876)
		(width 0.14224)
		(layer "In4.Cu")
		(net "P5E_CPU0_P2_TX_BUF_DP<2>")
	)
	(arc
		(start 405.883872 -397.802862)
		(mid 405.828593 -397.935778)
		(end 405.883618 -398.0688)
		(width 0.14224)
		(layer "In4.Cu")
		(net "P5E_CPU0_P2_TX_BUF_DP<2>")
	)
	(arc
		(start 377.956572 -411.707838)
		(mid 377.934662 -411.719548)
		(end 377.915424 -411.73527)
		(width 0.14224)
		(layer "In4.Cu")
		(net "P5E_CPU0_P2_TX_BUF_DP<2>")
	)
	(arc
		(start 406.108408 -398.676876)
		(mid 406.055297 -398.944648)
		(end 405.903684 -399.171668)
		(width 0.14224)
		(layer "In4.Cu")
		(net "P5E_CPU0_P2_TX_BUF_DP<2>")
	)
	(arc
		(start 405.425656 -402.274786)
		(mid 405.310827 -402.653873)
		(end 405.004524 -402.90496)
		(width 0.14224)
		(layer "In4.Cu")
		(net "P5E_CPU0_P2_TX_BUF_DP<2>")
	)
	(arc
		(start 405.780494 -399.294858)
		(mid 405.517873 -399.687804)
		(end 405.425656 -400.151346)
		(width 0.14224)
		(layer "In4.Cu")
		(net "P5E_CPU0_P2_TX_BUF_DP<2>")
	)
	(arc
		(start 377.745244 -411.90545)
		(mid 377.632804 -412.073728)
		(end 377.593352 -412.272226)
		(width 0.14224)
		(layer "In4.Cu")
		(net "P5E_CPU0_P2_TX_BUF_DP<2>")
	)
	(arc
		(start 405.982932 -398.168368)
		(mid 406.075774 -398.30741)
		(end 406.108408 -398.47139)
		(width 0.14224)
		(layer "In4.Cu")
		(net "P5E_CPU0_P2_TX_BUF_DP<2>")
	)
	(segment
		(start 374.550432 -416.336734)
		(end 374.550432 -413.11703)
		(width 0.12954)
		(layer "F.Cu")
		(net "P5E_CPU0_P2_TX_BUF_DP<1>")
	)
	(segment
		(start 374.550432 -413.11703)
		(end 374.820942 -412.84652)
		(width 0.12954)
		(layer "F.Cu")
		(net "P5E_CPU0_P2_TX_BUF_DP<1>")
	)
	(segment
		(start 374.846342 -416.632644)
		(end 374.550432 -416.336734)
		(width 0.12954)
		(layer "F.Cu")
		(net "P5E_CPU0_P2_TX_BUF_DP<1>")
	)
	(segment
		(start 404.498302 -397.849344)
		(end 405.019002 -397.849344)
		(width 0.127)
		(layer "F.Cu")
		(net "P5E_CPU0_P2_TX_BUF_DP<1>")
	)
	(segment
		(start 377.22556 -410.650182)
		(end 376.83567 -410.822902)
		(width 0.14224)
		(layer "In4.Cu")
		(net "P5E_CPU0_P2_TX_BUF_DP<1>")
	)
	(segment
		(start 404.6347 -397.823944)
		(end 404.6347 -397.95323)
		(width 0.14224)
		(layer "In4.Cu")
		(net "P5E_CPU0_P2_TX_BUF_DP<1>")
	)
	(segment
		(start 402.94814 -400.31797)
		(end 402.94814 -401.156424)
		(width 0.14224)
		(layer "In4.Cu")
		(net "P5E_CPU0_P2_TX_BUF_DP<1>")
	)
	(segment
		(start 404.85949 -398.934686)
		(end 404.286212 -399.508472)
		(width 0.14224)
		(layer "In4.Cu")
		(net "P5E_CPU0_P2_TX_BUF_DP<1>")
	)
	(segment
		(start 403.859238 -399.667984)
		(end 403.442424 -399.667984)
		(width 0.14224)
		(layer "In4.Cu")
		(net "P5E_CPU0_P2_TX_BUF_DP<1>")
	)
	(segment
		(start 400.567144 -403.362668)
		(end 378.700538 -409.996386)
		(width 0.14224)
		(layer "In4.Cu")
		(net "P5E_CPU0_P2_TX_BUF_DP<1>")
	)
	(segment
		(start 376.19432 -411.107382)
		(end 375.80443 -411.280102)
		(width 0.14224)
		(layer "In4.Cu")
		(net "P5E_CPU0_P2_TX_BUF_DP<1>")
	)
	(segment
		(start 404.724108 -397.734536)
		(end 404.6347 -397.823944)
		(width 0.14224)
		(layer "In4.Cu")
		(net "P5E_CPU0_P2_TX_BUF_DP<1>")
	)
	(segment
		(start 402.374862 -402.125942)
		(end 401.51177 -402.600414)
		(width 0.14224)
		(layer "In4.Cu")
		(net "P5E_CPU0_P2_TX_BUF_DP<1>")
	)
	(segment
		(start 376.375422 -411.177232)
		(end 376.19432 -411.107382)
		(width 0.14224)
		(layer "In4.Cu")
		(net "P5E_CPU0_P2_TX_BUF_DP<1>")
	)
	(segment
		(start 401.51177 -402.600414)
		(end 401.022312 -403.089872)
		(width 0.14224)
		(layer "In4.Cu")
		(net "P5E_CPU0_P2_TX_BUF_DP<1>")
	)
	(segment
		(start 375.734834 -411.461458)
		(end 375.344436 -411.634432)
		(width 0.14224)
		(layer "In4.Cu")
		(net "P5E_CPU0_P2_TX_BUF_DP<1>")
	)
	(segment
		(start 404.681944 -398.067276)
		(end 404.858982 -398.244314)
		(width 0.14224)
		(layer "In4.Cu")
		(net "P5E_CPU0_P2_TX_BUF_DP<1>")
	)
	(segment
		(start 375.163334 -411.564582)
		(end 375.16308 -411.564582)
		(width 0.14224)
		(layer "In4.Cu")
		(net "P5E_CPU0_P2_TX_BUF_DP<1>")
	)
	(segment
		(start 376.76582 -411.004258)
		(end 376.375422 -411.177232)
		(width 0.14224)
		(layer "In4.Cu")
		(net "P5E_CPU0_P2_TX_BUF_DP<1>")
	)
	(segment
		(start 403.286722 -399.7325)
		(end 403.122892 -399.89633)
		(width 0.14224)
		(layer "In4.Cu")
		(net "P5E_CPU0_P2_TX_BUF_DP<1>")
	)
	(segment
		(start 377.86691 -410.365702)
		(end 377.79706 -410.547058)
		(width 0.14224)
		(layer "In4.Cu")
		(net "P5E_CPU0_P2_TX_BUF_DP<1>")
	)
	(segment
		(start 378.700538 -409.996386)
		(end 377.86691 -410.365702)
		(width 0.14224)
		(layer "In4.Cu")
		(net "P5E_CPU0_P2_TX_BUF_DP<1>")
	)
	(segment
		(start 374.530112 -412.55569)
		(end 374.820942 -412.84652)
		(width 0.14224)
		(layer "In4.Cu")
		(net "P5E_CPU0_P2_TX_BUF_DP<1>")
	)
	(segment
		(start 405.019002 -397.849344)
		(end 404.904194 -397.734536)
		(width 0.14224)
		(layer "In4.Cu")
		(net "P5E_CPU0_P2_TX_BUF_DP<1>")
	)
	(segment
		(start 375.80443 -411.280102)
		(end 375.734834 -411.461458)
		(width 0.14224)
		(layer "In4.Cu")
		(net "P5E_CPU0_P2_TX_BUF_DP<1>")
	)
	(segment
		(start 377.79706 -410.547058)
		(end 377.406662 -410.720032)
		(width 0.14224)
		(layer "In4.Cu")
		(net "P5E_CPU0_P2_TX_BUF_DP<1>")
	)
	(segment
		(start 376.83567 -410.822902)
		(end 376.76582 -411.004258)
		(width 0.14224)
		(layer "In4.Cu")
		(net "P5E_CPU0_P2_TX_BUF_DP<1>")
	)
	(segment
		(start 374.530112 -411.927548)
		(end 374.530112 -412.55569)
		(width 0.14224)
		(layer "In4.Cu")
		(net "P5E_CPU0_P2_TX_BUF_DP<1>")
	)
	(segment
		(start 375.344436 -411.634432)
		(end 375.163334 -411.564582)
		(width 0.14224)
		(layer "In4.Cu")
		(net "P5E_CPU0_P2_TX_BUF_DP<1>")
	)
	(segment
		(start 377.406662 -410.720032)
		(end 377.22556 -410.650182)
		(width 0.14224)
		(layer "In4.Cu")
		(net "P5E_CPU0_P2_TX_BUF_DP<1>")
	)
	(segment
		(start 404.904194 -397.734536)
		(end 404.724108 -397.734536)
		(width 0.14224)
		(layer "In4.Cu")
		(net "P5E_CPU0_P2_TX_BUF_DP<1>")
	)
	(segment
		(start 375.16308 -411.564582)
		(end 374.605804 -411.81147)
		(width 0.14224)
		(layer "In4.Cu")
		(net "P5E_CPU0_P2_TX_BUF_DP<1>")
	)
	(arc
		(start 403.442424 -399.667984)
		(mid 403.35815 -399.684747)
		(end 403.286722 -399.7325)
		(width 0.14224)
		(layer "In4.Cu")
		(net "P5E_CPU0_P2_TX_BUF_DP<1>")
	)
	(arc
		(start 402.94814 -401.156424)
		(mid 402.794095 -401.719583)
		(end 402.374862 -402.125942)
		(width 0.14224)
		(layer "In4.Cu")
		(net "P5E_CPU0_P2_TX_BUF_DP<1>")
	)
	(arc
		(start 404.858982 -398.244314)
		(mid 405.002366 -398.589395)
		(end 404.85949 -398.934686)
		(width 0.14224)
		(layer "In4.Cu")
		(net "P5E_CPU0_P2_TX_BUF_DP<1>")
	)
	(arc
		(start 404.286212 -399.508472)
		(mid 404.17477 -399.593389)
		(end 404.044658 -399.645378)
		(width 0.14224)
		(layer "In4.Cu")
		(net "P5E_CPU0_P2_TX_BUF_DP<1>")
	)
	(arc
		(start 404.044658 -399.645378)
		(mid 403.952638 -399.662344)
		(end 403.859238 -399.667984)
		(width 0.14224)
		(layer "In4.Cu")
		(net "P5E_CPU0_P2_TX_BUF_DP<1>")
	)
	(arc
		(start 403.122892 -399.89633)
		(mid 402.993579 -400.089766)
		(end 402.94814 -400.31797)
		(width 0.14224)
		(layer "In4.Cu")
		(net "P5E_CPU0_P2_TX_BUF_DP<1>")
	)
	(arc
		(start 404.6347 -397.95323)
		(mid 404.646977 -398.014953)
		(end 404.681944 -398.067276)
		(width 0.14224)
		(layer "In4.Cu")
		(net "P5E_CPU0_P2_TX_BUF_DP<1>")
	)
	(arc
		(start 374.605804 -411.81147)
		(mid 374.550663 -411.858243)
		(end 374.530112 -411.927548)
		(width 0.14224)
		(layer "In4.Cu")
		(net "P5E_CPU0_P2_TX_BUF_DP<1>")
	)
	(arc
		(start 401.022312 -403.089872)
		(mid 400.811555 -403.254349)
		(end 400.567144 -403.362668)
		(width 0.14224)
		(layer "In4.Cu")
		(net "P5E_CPU0_P2_TX_BUF_DP<1>")
	)
	(segment
		(start 421.29837 -397.849344)
		(end 421.81907 -397.849344)
		(width 0.127)
		(layer "F.Cu")
		(net "P5E_CPU0_P2_TX_BUF_DP<15>")
	)
	(segment
		(start 417.435792 -413.11703)
		(end 417.706302 -412.84652)
		(width 0.12954)
		(layer "F.Cu")
		(net "P5E_CPU0_P2_TX_BUF_DP<15>")
	)
	(segment
		(start 417.435792 -416.336734)
		(end 417.435792 -413.11703)
		(width 0.12954)
		(layer "F.Cu")
		(net "P5E_CPU0_P2_TX_BUF_DP<15>")
	)
	(segment
		(start 417.731702 -416.632644)
		(end 417.435792 -416.336734)
		(width 0.12954)
		(layer "F.Cu")
		(net "P5E_CPU0_P2_TX_BUF_DP<15>")
	)
	(segment
		(start 421.81907 -397.849344)
		(end 421.704262 -397.734536)
		(width 0.14224)
		(layer "In4.Cu")
		(net "P5E_CPU0_P2_TX_BUF_DP<15>")
	)
	(segment
		(start 417.415472 -412.55569)
		(end 417.706302 -412.84652)
		(width 0.14224)
		(layer "In4.Cu")
		(net "P5E_CPU0_P2_TX_BUF_DP<15>")
	)
	(segment
		(start 420.849806 -404.768812)
		(end 420.708328 -405.334216)
		(width 0.14224)
		(layer "In4.Cu")
		(net "P5E_CPU0_P2_TX_BUF_DP<15>")
	)
	(segment
		(start 420.085774 -406.948894)
		(end 419.555168 -407.941526)
		(width 0.14224)
		(layer "In4.Cu")
		(net "P5E_CPU0_P2_TX_BUF_DP<15>")
	)
	(segment
		(start 421.0304 -400.102578)
		(end 421.0304 -403.305518)
		(width 0.14224)
		(layer "In4.Cu")
		(net "P5E_CPU0_P2_TX_BUF_DP<15>")
	)
	(segment
		(start 419.555168 -407.941526)
		(end 419.611556 -408.126946)
		(width 0.14224)
		(layer "In4.Cu")
		(net "P5E_CPU0_P2_TX_BUF_DP<15>")
	)
	(segment
		(start 419.22446 -408.559762)
		(end 418.975032 -409.026614)
		(width 0.14224)
		(layer "In4.Cu")
		(net "P5E_CPU0_P2_TX_BUF_DP<15>")
	)
	(segment
		(start 419.611556 -408.126946)
		(end 419.410388 -408.503628)
		(width 0.14224)
		(layer "In4.Cu")
		(net "P5E_CPU0_P2_TX_BUF_DP<15>")
	)
	(segment
		(start 418.443156 -410.021278)
		(end 418.499544 -410.206952)
		(width 0.14224)
		(layer "In4.Cu")
		(net "P5E_CPU0_P2_TX_BUF_DP<15>")
	)
	(segment
		(start 421.472106 -398.064482)
		(end 421.674798 -398.267174)
		(width 0.14224)
		(layer "In4.Cu")
		(net "P5E_CPU0_P2_TX_BUF_DP<15>")
	)
	(segment
		(start 421.704262 -397.734536)
		(end 421.524176 -397.734536)
		(width 0.14224)
		(layer "In4.Cu")
		(net "P5E_CPU0_P2_TX_BUF_DP<15>")
	)
	(segment
		(start 421.581072 -399.485104)
		(end 421.077644 -399.988532)
		(width 0.14224)
		(layer "In4.Cu")
		(net "P5E_CPU0_P2_TX_BUF_DP<15>")
	)
	(segment
		(start 421.524176 -397.734536)
		(end 421.434768 -397.823944)
		(width 0.14224)
		(layer "In4.Cu")
		(net "P5E_CPU0_P2_TX_BUF_DP<15>")
	)
	(segment
		(start 418.829998 -409.588716)
		(end 418.64407 -409.645104)
		(width 0.14224)
		(layer "In4.Cu")
		(net "P5E_CPU0_P2_TX_BUF_DP<15>")
	)
	(segment
		(start 418.298376 -410.583634)
		(end 418.112448 -410.639768)
		(width 0.14224)
		(layer "In4.Cu")
		(net "P5E_CPU0_P2_TX_BUF_DP<15>")
	)
	(segment
		(start 417.415472 -412.313374)
		(end 417.415472 -412.55569)
		(width 0.14224)
		(layer "In4.Cu")
		(net "P5E_CPU0_P2_TX_BUF_DP<15>")
	)
	(segment
		(start 421.795448 -398.558512)
		(end 421.795448 -398.966944)
		(width 0.14224)
		(layer "In4.Cu")
		(net "P5E_CPU0_P2_TX_BUF_DP<15>")
	)
	(segment
		(start 418.499544 -410.206952)
		(end 418.298376 -410.583634)
		(width 0.14224)
		(layer "In4.Cu")
		(net "P5E_CPU0_P2_TX_BUF_DP<15>")
	)
	(segment
		(start 418.975032 -409.026614)
		(end 419.031166 -409.212288)
		(width 0.14224)
		(layer "In4.Cu")
		(net "P5E_CPU0_P2_TX_BUF_DP<15>")
	)
	(segment
		(start 419.031166 -409.212288)
		(end 418.829998 -409.588716)
		(width 0.14224)
		(layer "In4.Cu")
		(net "P5E_CPU0_P2_TX_BUF_DP<15>")
	)
	(segment
		(start 421.434768 -397.823944)
		(end 421.434768 -397.974566)
		(width 0.14224)
		(layer "In4.Cu")
		(net "P5E_CPU0_P2_TX_BUF_DP<15>")
	)
	(segment
		(start 419.410388 -408.503628)
		(end 419.22446 -408.559762)
		(width 0.14224)
		(layer "In4.Cu")
		(net "P5E_CPU0_P2_TX_BUF_DP<15>")
	)
	(segment
		(start 418.64407 -409.645104)
		(end 418.443156 -410.021278)
		(width 0.14224)
		(layer "In4.Cu")
		(net "P5E_CPU0_P2_TX_BUF_DP<15>")
	)
	(segment
		(start 418.112448 -410.639768)
		(end 417.589716 -411.618176)
		(width 0.14224)
		(layer "In4.Cu")
		(net "P5E_CPU0_P2_TX_BUF_DP<15>")
	)
	(arc
		(start 421.077644 -399.988532)
		(mid 421.042682 -400.040857)
		(end 421.0304 -400.102578)
		(width 0.14224)
		(layer "In4.Cu")
		(net "P5E_CPU0_P2_TX_BUF_DP<15>")
	)
	(arc
		(start 417.589716 -411.618176)
		(mid 417.459726 -411.955031)
		(end 417.415472 -412.313374)
		(width 0.14224)
		(layer "In4.Cu")
		(net "P5E_CPU0_P2_TX_BUF_DP<15>")
	)
	(arc
		(start 421.434768 -397.974566)
		(mid 421.44447 -398.02325)
		(end 421.472106 -398.064482)
		(width 0.14224)
		(layer "In4.Cu")
		(net "P5E_CPU0_P2_TX_BUF_DP<15>")
	)
	(arc
		(start 421.0304 -403.305518)
		(mid 420.985047 -404.042711)
		(end 420.849806 -404.768812)
		(width 0.14224)
		(layer "In4.Cu")
		(net "P5E_CPU0_P2_TX_BUF_DP<15>")
	)
	(arc
		(start 421.674798 -398.267174)
		(mid 421.764111 -398.400841)
		(end 421.795448 -398.558512)
		(width 0.14224)
		(layer "In4.Cu")
		(net "P5E_CPU0_P2_TX_BUF_DP<15>")
	)
	(arc
		(start 421.795448 -398.966944)
		(mid 421.739853 -399.247381)
		(end 421.581072 -399.485104)
		(width 0.14224)
		(layer "In4.Cu")
		(net "P5E_CPU0_P2_TX_BUF_DP<15>")
	)
	(arc
		(start 420.708328 -405.334216)
		(mid 420.446671 -406.160686)
		(end 420.085774 -406.948894)
		(width 0.14224)
		(layer "In4.Cu")
		(net "P5E_CPU0_P2_TX_BUF_DP<15>")
	)
	(segment
		(start 414.668462 -416.632644)
		(end 414.372552 -416.336734)
		(width 0.12954)
		(layer "F.Cu")
		(net "P5E_CPU0_P2_TX_BUF_DP<14>")
	)
	(segment
		(start 420.09822 -397.849344)
		(end 420.61892 -397.849344)
		(width 0.127)
		(layer "F.Cu")
		(net "P5E_CPU0_P2_TX_BUF_DP<14>")
	)
	(segment
		(start 414.372552 -413.11703)
		(end 414.643062 -412.84652)
		(width 0.12954)
		(layer "F.Cu")
		(net "P5E_CPU0_P2_TX_BUF_DP<14>")
	)
	(segment
		(start 414.372552 -416.336734)
		(end 414.372552 -413.11703)
		(width 0.12954)
		(layer "F.Cu")
		(net "P5E_CPU0_P2_TX_BUF_DP<14>")
	)
	(segment
		(start 420.27221 -398.055338)
		(end 420.450264 -398.233138)
		(width 0.14224)
		(layer "In4.Cu")
		(net "P5E_CPU0_P2_TX_BUF_DP<14>")
	)
	(segment
		(start 418.417502 -406.609296)
		(end 418.224462 -406.628346)
		(width 0.14224)
		(layer "In4.Cu")
		(net "P5E_CPU0_P2_TX_BUF_DP<14>")
	)
	(segment
		(start 418.66947 -406.08631)
		(end 418.688266 -406.27935)
		(width 0.14224)
		(layer "In4.Cu")
		(net "P5E_CPU0_P2_TX_BUF_DP<14>")
	)
	(segment
		(start 420.504112 -397.734536)
		(end 420.32428 -397.734536)
		(width 0.14224)
		(layer "In4.Cu")
		(net "P5E_CPU0_P2_TX_BUF_DP<14>")
	)
	(segment
		(start 417.31819 -407.948892)
		(end 417.12515 -407.967942)
		(width 0.14224)
		(layer "In4.Cu")
		(net "P5E_CPU0_P2_TX_BUF_DP<14>")
	)
	(segment
		(start 415.502344 -409.945078)
		(end 414.43656 -411.539944)
		(width 0.14224)
		(layer "In4.Cu")
		(net "P5E_CPU0_P2_TX_BUF_DP<14>")
	)
	(segment
		(start 416.211766 -409.29687)
		(end 416.018726 -409.31592)
		(width 0.14224)
		(layer "In4.Cu")
		(net "P5E_CPU0_P2_TX_BUF_DP<14>")
	)
	(segment
		(start 419.83025 -400.19351)
		(end 419.83025 -403.81809)
		(width 0.14224)
		(layer "In4.Cu")
		(net "P5E_CPU0_P2_TX_BUF_DP<14>")
	)
	(segment
		(start 420.234872 -397.823944)
		(end 420.234872 -397.965422)
		(width 0.14224)
		(layer "In4.Cu")
		(net "P5E_CPU0_P2_TX_BUF_DP<14>")
	)
	(segment
		(start 420.387272 -399.458688)
		(end 419.956234 -399.889472)
		(width 0.14224)
		(layer "In4.Cu")
		(net "P5E_CPU0_P2_TX_BUF_DP<14>")
	)
	(segment
		(start 417.589208 -407.618692)
		(end 417.31819 -407.948892)
		(width 0.14224)
		(layer "In4.Cu")
		(net "P5E_CPU0_P2_TX_BUF_DP<14>")
	)
	(segment
		(start 420.61892 -397.849344)
		(end 420.504112 -397.734536)
		(width 0.14224)
		(layer "In4.Cu")
		(net "P5E_CPU0_P2_TX_BUF_DP<14>")
	)
	(segment
		(start 416.463734 -408.773884)
		(end 416.48253 -408.966924)
		(width 0.14224)
		(layer "In4.Cu")
		(net "P5E_CPU0_P2_TX_BUF_DP<14>")
	)
	(segment
		(start 414.352232 -412.55569)
		(end 414.643062 -412.84652)
		(width 0.14224)
		(layer "In4.Cu")
		(net "P5E_CPU0_P2_TX_BUF_DP<14>")
	)
	(segment
		(start 419.288722 -405.331422)
		(end 418.66947 -406.08631)
		(width 0.14224)
		(layer "In4.Cu")
		(net "P5E_CPU0_P2_TX_BUF_DP<14>")
	)
	(segment
		(start 420.32428 -397.734536)
		(end 420.234872 -397.823944)
		(width 0.14224)
		(layer "In4.Cu")
		(net "P5E_CPU0_P2_TX_BUF_DP<14>")
	)
	(segment
		(start 417.12515 -407.967942)
		(end 416.463734 -408.773884)
		(width 0.14224)
		(layer "In4.Cu")
		(net "P5E_CPU0_P2_TX_BUF_DP<14>")
	)
	(segment
		(start 414.352232 -411.818074)
		(end 414.352232 -412.55569)
		(width 0.14224)
		(layer "In4.Cu")
		(net "P5E_CPU0_P2_TX_BUF_DP<14>")
	)
	(segment
		(start 418.224462 -406.628346)
		(end 417.570158 -407.425652)
		(width 0.14224)
		(layer "In4.Cu")
		(net "P5E_CPU0_P2_TX_BUF_DP<14>")
	)
	(segment
		(start 420.624508 -398.653508)
		(end 420.624508 -398.886426)
		(width 0.14224)
		(layer "In4.Cu")
		(net "P5E_CPU0_P2_TX_BUF_DP<14>")
	)
	(segment
		(start 416.48253 -408.966924)
		(end 416.211766 -409.29687)
		(width 0.14224)
		(layer "In4.Cu")
		(net "P5E_CPU0_P2_TX_BUF_DP<14>")
	)
	(segment
		(start 416.018726 -409.31592)
		(end 415.502344 -409.945078)
		(width 0.14224)
		(layer "In4.Cu")
		(net "P5E_CPU0_P2_TX_BUF_DP<14>")
	)
	(segment
		(start 417.570158 -407.425652)
		(end 417.589208 -407.618692)
		(width 0.14224)
		(layer "In4.Cu")
		(net "P5E_CPU0_P2_TX_BUF_DP<14>")
	)
	(segment
		(start 418.688266 -406.27935)
		(end 418.417502 -406.609296)
		(width 0.14224)
		(layer "In4.Cu")
		(net "P5E_CPU0_P2_TX_BUF_DP<14>")
	)
	(arc
		(start 419.83025 -403.81809)
		(mid 419.690752 -404.621729)
		(end 419.288722 -405.331422)
		(width 0.14224)
		(layer "In4.Cu")
		(net "P5E_CPU0_P2_TX_BUF_DP<14>")
	)
	(arc
		(start 420.450264 -398.233138)
		(mid 420.579188 -398.425991)
		(end 420.624508 -398.653508)
		(width 0.14224)
		(layer "In4.Cu")
		(net "P5E_CPU0_P2_TX_BUF_DP<14>")
	)
	(arc
		(start 420.624508 -398.886426)
		(mid 420.562859 -399.196179)
		(end 420.387272 -399.458688)
		(width 0.14224)
		(layer "In4.Cu")
		(net "P5E_CPU0_P2_TX_BUF_DP<14>")
	)
	(arc
		(start 419.956234 -399.889472)
		(mid 419.862973 -400.028952)
		(end 419.83025 -400.19351)
		(width 0.14224)
		(layer "In4.Cu")
		(net "P5E_CPU0_P2_TX_BUF_DP<14>")
	)
	(arc
		(start 414.43656 -411.539944)
		(mid 414.373785 -411.672759)
		(end 414.352232 -411.818074)
		(width 0.14224)
		(layer "In4.Cu")
		(net "P5E_CPU0_P2_TX_BUF_DP<14>")
	)
	(arc
		(start 420.234872 -397.965422)
		(mid 420.244574 -398.014106)
		(end 420.27221 -398.055338)
		(width 0.14224)
		(layer "In4.Cu")
		(net "P5E_CPU0_P2_TX_BUF_DP<14>")
	)
	(segment
		(start 411.309312 -416.336734)
		(end 411.309312 -413.11703)
		(width 0.12954)
		(layer "F.Cu")
		(net "P5E_CPU0_P2_TX_BUF_DP<13>")
	)
	(segment
		(start 418.898324 -397.849344)
		(end 419.419024 -397.849344)
		(width 0.127)
		(layer "F.Cu")
		(net "P5E_CPU0_P2_TX_BUF_DP<13>")
	)
	(segment
		(start 411.309312 -413.11703)
		(end 411.579822 -412.84652)
		(width 0.12954)
		(layer "F.Cu")
		(net "P5E_CPU0_P2_TX_BUF_DP<13>")
	)
	(segment
		(start 411.605222 -416.632644)
		(end 411.309312 -416.336734)
		(width 0.12954)
		(layer "F.Cu")
		(net "P5E_CPU0_P2_TX_BUF_DP<13>")
	)
	(segment
		(start 418.630354 -400.08937)
		(end 418.630354 -404.030942)
		(width 0.14224)
		(layer "In4.Cu")
		(net "P5E_CPU0_P2_TX_BUF_DP<13>")
	)
	(segment
		(start 414.140904 -408.98318)
		(end 414.140904 -409.177236)
		(width 0.14224)
		(layer "In4.Cu")
		(net "P5E_CPU0_P2_TX_BUF_DP<13>")
	)
	(segment
		(start 412.333948 -410.790136)
		(end 411.528006 -411.596078)
		(width 0.14224)
		(layer "In4.Cu")
		(net "P5E_CPU0_P2_TX_BUF_DP<13>")
	)
	(segment
		(start 413.838898 -409.479242)
		(end 413.644842 -409.479242)
		(width 0.14224)
		(layer "In4.Cu")
		(net "P5E_CPU0_P2_TX_BUF_DP<13>")
	)
	(segment
		(start 411.288992 -412.172912)
		(end 411.288992 -412.55569)
		(width 0.14224)
		(layer "In4.Cu")
		(net "P5E_CPU0_P2_TX_BUF_DP<13>")
	)
	(segment
		(start 418.303202 -404.820882)
		(end 415.25317 -407.870914)
		(width 0.14224)
		(layer "In4.Cu")
		(net "P5E_CPU0_P2_TX_BUF_DP<13>")
	)
	(segment
		(start 412.829756 -410.48813)
		(end 412.52775 -410.790136)
		(width 0.14224)
		(layer "In4.Cu")
		(net "P5E_CPU0_P2_TX_BUF_DP<13>")
	)
	(segment
		(start 411.288992 -412.55569)
		(end 411.579822 -412.84652)
		(width 0.14224)
		(layer "In4.Cu")
		(net "P5E_CPU0_P2_TX_BUF_DP<13>")
	)
	(segment
		(start 415.25317 -407.870914)
		(end 415.25317 -408.064716)
		(width 0.14224)
		(layer "In4.Cu")
		(net "P5E_CPU0_P2_TX_BUF_DP<13>")
	)
	(segment
		(start 419.419024 -397.849344)
		(end 419.304216 -397.734536)
		(width 0.14224)
		(layer "In4.Cu")
		(net "P5E_CPU0_P2_TX_BUF_DP<13>")
	)
	(segment
		(start 414.757362 -408.366722)
		(end 414.140904 -408.98318)
		(width 0.14224)
		(layer "In4.Cu")
		(net "P5E_CPU0_P2_TX_BUF_DP<13>")
	)
	(segment
		(start 413.644842 -409.479242)
		(end 412.829756 -410.294328)
		(width 0.14224)
		(layer "In4.Cu")
		(net "P5E_CPU0_P2_TX_BUF_DP<13>")
	)
	(segment
		(start 412.829756 -410.294328)
		(end 412.829756 -410.48813)
		(width 0.14224)
		(layer "In4.Cu")
		(net "P5E_CPU0_P2_TX_BUF_DP<13>")
	)
	(segment
		(start 414.951164 -408.366722)
		(end 414.757362 -408.366722)
		(width 0.14224)
		(layer "In4.Cu")
		(net "P5E_CPU0_P2_TX_BUF_DP<13>")
	)
	(segment
		(start 419.304216 -397.734536)
		(end 419.12413 -397.734536)
		(width 0.14224)
		(layer "In4.Cu")
		(net "P5E_CPU0_P2_TX_BUF_DP<13>")
	)
	(segment
		(start 412.52775 -410.790136)
		(end 412.333948 -410.790136)
		(width 0.14224)
		(layer "In4.Cu")
		(net "P5E_CPU0_P2_TX_BUF_DP<13>")
	)
	(segment
		(start 414.140904 -409.177236)
		(end 413.838898 -409.479242)
		(width 0.14224)
		(layer "In4.Cu")
		(net "P5E_CPU0_P2_TX_BUF_DP<13>")
	)
	(segment
		(start 419.12413 -397.734536)
		(end 419.034722 -397.823944)
		(width 0.14224)
		(layer "In4.Cu")
		(net "P5E_CPU0_P2_TX_BUF_DP<13>")
	)
	(segment
		(start 419.202616 -399.44675)
		(end 418.680138 -399.969228)
		(width 0.14224)
		(layer "In4.Cu")
		(net "P5E_CPU0_P2_TX_BUF_DP<13>")
	)
	(segment
		(start 419.395402 -398.764506)
		(end 419.395402 -398.946624)
		(width 0.14224)
		(layer "In4.Cu")
		(net "P5E_CPU0_P2_TX_BUF_DP<13>")
	)
	(segment
		(start 415.25317 -408.064716)
		(end 414.951164 -408.366722)
		(width 0.14224)
		(layer "In4.Cu")
		(net "P5E_CPU0_P2_TX_BUF_DP<13>")
	)
	(segment
		(start 419.034722 -397.823944)
		(end 419.034722 -397.886936)
		(width 0.14224)
		(layer "In4.Cu")
		(net "P5E_CPU0_P2_TX_BUF_DP<13>")
	)
	(arc
		(start 419.332918 -399.25371)
		(mid 419.276976 -399.356445)
		(end 419.202616 -399.44675)
		(width 0.14224)
		(layer "In4.Cu")
		(net "P5E_CPU0_P2_TX_BUF_DP<13>")
	)
	(arc
		(start 418.680138 -399.969228)
		(mid 418.643307 -400.02435)
		(end 418.630354 -400.08937)
		(width 0.14224)
		(layer "In4.Cu")
		(net "P5E_CPU0_P2_TX_BUF_DP<13>")
	)
	(arc
		(start 419.133528 -398.12722)
		(mid 419.327479 -398.419977)
		(end 419.395402 -398.764506)
		(width 0.14224)
		(layer "In4.Cu")
		(net "P5E_CPU0_P2_TX_BUF_DP<13>")
	)
	(arc
		(start 419.034722 -397.886936)
		(mid 419.060384 -398.016842)
		(end 419.133528 -398.12722)
		(width 0.14224)
		(layer "In4.Cu")
		(net "P5E_CPU0_P2_TX_BUF_DP<13>")
	)
	(arc
		(start 418.630354 -404.030942)
		(mid 418.545335 -404.458449)
		(end 418.303202 -404.820882)
		(width 0.14224)
		(layer "In4.Cu")
		(net "P5E_CPU0_P2_TX_BUF_DP<13>")
	)
	(arc
		(start 419.395402 -398.946624)
		(mid 419.379732 -399.103337)
		(end 419.332918 -399.25371)
		(width 0.14224)
		(layer "In4.Cu")
		(net "P5E_CPU0_P2_TX_BUF_DP<13>")
	)
	(arc
		(start 411.528006 -411.596078)
		(mid 411.351116 -411.860717)
		(end 411.288992 -412.172912)
		(width 0.14224)
		(layer "In4.Cu")
		(net "P5E_CPU0_P2_TX_BUF_DP<13>")
	)
	(segment
		(start 408.246072 -413.11703)
		(end 408.516582 -412.84652)
		(width 0.12954)
		(layer "F.Cu")
		(net "P5E_CPU0_P2_TX_BUF_DP<12>")
	)
	(segment
		(start 408.541982 -416.632644)
		(end 408.246072 -416.336734)
		(width 0.12954)
		(layer "F.Cu")
		(net "P5E_CPU0_P2_TX_BUF_DP<12>")
	)
	(segment
		(start 408.246072 -416.336734)
		(end 408.246072 -413.11703)
		(width 0.12954)
		(layer "F.Cu")
		(net "P5E_CPU0_P2_TX_BUF_DP<12>")
	)
	(segment
		(start 417.698174 -397.849344)
		(end 418.218874 -397.849344)
		(width 0.127)
		(layer "F.Cu")
		(net "P5E_CPU0_P2_TX_BUF_DP<12>")
	)
	(segment
		(start 409.555442 -411.29712)
		(end 409.947364 -411.128972)
		(width 0.14224)
		(layer "In4.Cu")
		(net "P5E_CPU0_P2_TX_BUF_DP<12>")
	)
	(segment
		(start 417.834826 -397.903954)
		(end 417.834826 -397.823944)
		(width 0.14224)
		(layer "In4.Cu")
		(net "P5E_CPU0_P2_TX_BUF_DP<12>")
	)
	(segment
		(start 417.477448 -399.951702)
		(end 417.96462 -399.46453)
		(width 0.14224)
		(layer "In4.Cu")
		(net "P5E_CPU0_P2_TX_BUF_DP<12>")
	)
	(segment
		(start 418.183314 -398.936718)
		(end 418.183314 -398.535652)
		(width 0.14224)
		(layer "In4.Cu")
		(net "P5E_CPU0_P2_TX_BUF_DP<12>")
	)
	(segment
		(start 408.225752 -412.55569)
		(end 408.225752 -412.127192)
		(width 0.14224)
		(layer "In4.Cu")
		(net "P5E_CPU0_P2_TX_BUF_DP<12>")
	)
	(segment
		(start 409.947364 -411.128972)
		(end 410.12745 -411.200854)
		(width 0.14224)
		(layer "In4.Cu")
		(net "P5E_CPU0_P2_TX_BUF_DP<12>")
	)
	(segment
		(start 410.591762 -410.852112)
		(end 410.952188 -410.697426)
		(width 0.14224)
		(layer "In4.Cu")
		(net "P5E_CPU0_P2_TX_BUF_DP<12>")
	)
	(segment
		(start 417.924234 -397.734536)
		(end 418.104066 -397.734536)
		(width 0.14224)
		(layer "In4.Cu")
		(net "P5E_CPU0_P2_TX_BUF_DP<12>")
	)
	(segment
		(start 417.567364 -403.054566)
		(end 417.430204 -402.917406)
		(width 0.14224)
		(layer "In4.Cu")
		(net "P5E_CPU0_P2_TX_BUF_DP<12>")
	)
	(segment
		(start 408.290776 -411.970474)
		(end 408.519122 -411.742128)
		(width 0.14224)
		(layer "In4.Cu")
		(net "P5E_CPU0_P2_TX_BUF_DP<12>")
	)
	(segment
		(start 411.255464 -410.49194)
		(end 417.237672 -404.509732)
		(width 0.14224)
		(layer "In4.Cu")
		(net "P5E_CPU0_P2_TX_BUF_DP<12>")
	)
	(segment
		(start 418.063172 -398.246092)
		(end 417.915598 -398.098772)
		(width 0.14224)
		(layer "In4.Cu")
		(net "P5E_CPU0_P2_TX_BUF_DP<12>")
	)
	(segment
		(start 408.516582 -412.84652)
		(end 408.225752 -412.55569)
		(width 0.14224)
		(layer "In4.Cu")
		(net "P5E_CPU0_P2_TX_BUF_DP<12>")
	)
	(segment
		(start 409.48356 -411.47746)
		(end 409.555442 -411.29712)
		(width 0.14224)
		(layer "In4.Cu")
		(net "P5E_CPU0_P2_TX_BUF_DP<12>")
	)
	(segment
		(start 409.09113 -411.645862)
		(end 409.48356 -411.47746)
		(width 0.14224)
		(layer "In4.Cu")
		(net "P5E_CPU0_P2_TX_BUF_DP<12>")
	)
	(segment
		(start 410.12745 -411.200854)
		(end 410.51988 -411.032452)
		(width 0.14224)
		(layer "In4.Cu")
		(net "P5E_CPU0_P2_TX_BUF_DP<12>")
	)
	(segment
		(start 408.519122 -411.742128)
		(end 408.911044 -411.57398)
		(width 0.14224)
		(layer "In4.Cu")
		(net "P5E_CPU0_P2_TX_BUF_DP<12>")
	)
	(segment
		(start 408.911044 -411.57398)
		(end 409.09113 -411.645862)
		(width 0.14224)
		(layer "In4.Cu")
		(net "P5E_CPU0_P2_TX_BUF_DP<12>")
	)
	(segment
		(start 417.430204 -402.917406)
		(end 417.430204 -400.065748)
		(width 0.14224)
		(layer "In4.Cu")
		(net "P5E_CPU0_P2_TX_BUF_DP<12>")
	)
	(segment
		(start 417.430204 -404.045166)
		(end 417.430204 -403.618446)
		(width 0.14224)
		(layer "In4.Cu")
		(net "P5E_CPU0_P2_TX_BUF_DP<12>")
	)
	(segment
		(start 417.834826 -397.823944)
		(end 417.924234 -397.734536)
		(width 0.14224)
		(layer "In4.Cu")
		(net "P5E_CPU0_P2_TX_BUF_DP<12>")
	)
	(segment
		(start 410.51988 -411.032452)
		(end 410.591762 -410.852112)
		(width 0.14224)
		(layer "In4.Cu")
		(net "P5E_CPU0_P2_TX_BUF_DP<12>")
	)
	(segment
		(start 417.430204 -403.618446)
		(end 417.567364 -403.481286)
		(width 0.14224)
		(layer "In4.Cu")
		(net "P5E_CPU0_P2_TX_BUF_DP<12>")
	)
	(segment
		(start 417.567364 -403.481286)
		(end 417.567364 -403.054566)
		(width 0.14224)
		(layer "In4.Cu")
		(net "P5E_CPU0_P2_TX_BUF_DP<12>")
	)
	(segment
		(start 418.104066 -397.734536)
		(end 418.218874 -397.849344)
		(width 0.14224)
		(layer "In4.Cu")
		(net "P5E_CPU0_P2_TX_BUF_DP<12>")
	)
	(arc
		(start 417.96462 -399.46453)
		(mid 418.126481 -399.222382)
		(end 418.183314 -398.936718)
		(width 0.14224)
		(layer "In4.Cu")
		(net "P5E_CPU0_P2_TX_BUF_DP<12>")
	)
	(arc
		(start 408.225752 -412.127192)
		(mid 408.242646 -412.042349)
		(end 408.290776 -411.970474)
		(width 0.14224)
		(layer "In4.Cu")
		(net "P5E_CPU0_P2_TX_BUF_DP<12>")
	)
	(arc
		(start 417.237672 -404.509732)
		(mid 417.380144 -404.296602)
		(end 417.430204 -404.045166)
		(width 0.14224)
		(layer "In4.Cu")
		(net "P5E_CPU0_P2_TX_BUF_DP<12>")
	)
	(arc
		(start 418.183314 -398.535652)
		(mid 418.152082 -398.378909)
		(end 418.063172 -398.246092)
		(width 0.14224)
		(layer "In4.Cu")
		(net "P5E_CPU0_P2_TX_BUF_DP<12>")
	)
	(arc
		(start 417.915598 -398.098772)
		(mid 417.85582 -398.009403)
		(end 417.834826 -397.903954)
		(width 0.14224)
		(layer "In4.Cu")
		(net "P5E_CPU0_P2_TX_BUF_DP<12>")
	)
	(arc
		(start 417.430204 -400.065748)
		(mid 417.442481 -400.004025)
		(end 417.477448 -399.951702)
		(width 0.14224)
		(layer "In4.Cu")
		(net "P5E_CPU0_P2_TX_BUF_DP<12>")
	)
	(arc
		(start 410.952188 -410.697426)
		(mid 411.113601 -410.609113)
		(end 411.255464 -410.49194)
		(width 0.14224)
		(layer "In4.Cu")
		(net "P5E_CPU0_P2_TX_BUF_DP<12>")
	)
	(segment
		(start 405.182832 -413.11703)
		(end 405.453342 -412.84652)
		(width 0.12954)
		(layer "F.Cu")
		(net "P5E_CPU0_P2_TX_BUF_DP<11>")
	)
	(segment
		(start 405.182832 -416.336734)
		(end 405.182832 -413.11703)
		(width 0.12954)
		(layer "F.Cu")
		(net "P5E_CPU0_P2_TX_BUF_DP<11>")
	)
	(segment
		(start 416.498278 -397.849344)
		(end 417.018978 -397.849344)
		(width 0.127)
		(layer "F.Cu")
		(net "P5E_CPU0_P2_TX_BUF_DP<11>")
	)
	(segment
		(start 405.478742 -416.632644)
		(end 405.182832 -416.336734)
		(width 0.12954)
		(layer "F.Cu")
		(net "P5E_CPU0_P2_TX_BUF_DP<11>")
	)
	(segment
		(start 405.162512 -412.233872)
		(end 405.162512 -412.55569)
		(width 0.14224)
		(layer "In4.Cu")
		(net "P5E_CPU0_P2_TX_BUF_DP<11>")
	)
	(segment
		(start 416.995356 -398.558512)
		(end 416.995356 -398.812004)
		(width 0.14224)
		(layer "In4.Cu")
		(net "P5E_CPU0_P2_TX_BUF_DP<11>")
	)
	(segment
		(start 405.162512 -412.55569)
		(end 405.453342 -412.84652)
		(width 0.14224)
		(layer "In4.Cu")
		(net "P5E_CPU0_P2_TX_BUF_DP<11>")
	)
	(segment
		(start 408.698192 -410.614114)
		(end 408.303476 -410.777436)
		(width 0.14224)
		(layer "In4.Cu")
		(net "P5E_CPU0_P2_TX_BUF_DP<11>")
	)
	(segment
		(start 406.376378 -411.575758)
		(end 405.981916 -411.73908)
		(width 0.14224)
		(layer "In4.Cu")
		(net "P5E_CPU0_P2_TX_BUF_DP<11>")
	)
	(segment
		(start 407.492962 -410.964634)
		(end 407.41854 -411.143958)
		(width 0.14224)
		(layer "In4.Cu")
		(net "P5E_CPU0_P2_TX_BUF_DP<11>")
	)
	(segment
		(start 409.484068 -410.14015)
		(end 408.77236 -410.43479)
		(width 0.14224)
		(layer "In4.Cu")
		(net "P5E_CPU0_P2_TX_BUF_DP<11>")
	)
	(segment
		(start 405.802846 -411.664658)
		(end 405.378412 -411.840426)
		(width 0.14224)
		(layer "In4.Cu")
		(net "P5E_CPU0_P2_TX_BUF_DP<11>")
	)
	(segment
		(start 417.018978 -397.849344)
		(end 416.90417 -397.734536)
		(width 0.14224)
		(layer "In4.Cu")
		(net "P5E_CPU0_P2_TX_BUF_DP<11>")
	)
	(segment
		(start 416.706558 -398.100042)
		(end 416.875468 -398.268952)
		(width 0.14224)
		(layer "In4.Cu")
		(net "P5E_CPU0_P2_TX_BUF_DP<11>")
	)
	(segment
		(start 407.024078 -411.30728)
		(end 406.845008 -411.233112)
		(width 0.14224)
		(layer "In4.Cu")
		(net "P5E_CPU0_P2_TX_BUF_DP<11>")
	)
	(segment
		(start 406.845008 -411.233112)
		(end 406.4508 -411.39618)
		(width 0.14224)
		(layer "In4.Cu")
		(net "P5E_CPU0_P2_TX_BUF_DP<11>")
	)
	(segment
		(start 405.378412 -411.840426)
		(end 405.288242 -411.930596)
		(width 0.14224)
		(layer "In4.Cu")
		(net "P5E_CPU0_P2_TX_BUF_DP<11>")
	)
	(segment
		(start 416.90417 -397.734536)
		(end 416.724084 -397.734536)
		(width 0.14224)
		(layer "In4.Cu")
		(net "P5E_CPU0_P2_TX_BUF_DP<11>")
	)
	(segment
		(start 408.124406 -410.703268)
		(end 407.492962 -410.964634)
		(width 0.14224)
		(layer "In4.Cu")
		(net "P5E_CPU0_P2_TX_BUF_DP<11>")
	)
	(segment
		(start 408.303476 -410.777436)
		(end 408.124406 -410.703268)
		(width 0.14224)
		(layer "In4.Cu")
		(net "P5E_CPU0_P2_TX_BUF_DP<11>")
	)
	(segment
		(start 416.724084 -397.734536)
		(end 416.634676 -397.823944)
		(width 0.14224)
		(layer "In4.Cu")
		(net "P5E_CPU0_P2_TX_BUF_DP<11>")
	)
	(segment
		(start 416.230308 -400.049238)
		(end 416.230308 -403.578822)
		(width 0.14224)
		(layer "In4.Cu")
		(net "P5E_CPU0_P2_TX_BUF_DP<11>")
	)
	(segment
		(start 405.981916 -411.73908)
		(end 405.802846 -411.664658)
		(width 0.14224)
		(layer "In4.Cu")
		(net "P5E_CPU0_P2_TX_BUF_DP<11>")
	)
	(segment
		(start 416.634676 -397.823944)
		(end 416.634676 -397.926814)
		(width 0.14224)
		(layer "In4.Cu")
		(net "P5E_CPU0_P2_TX_BUF_DP<11>")
	)
	(segment
		(start 415.843466 -404.512526)
		(end 411.68955 -408.666442)
		(width 0.14224)
		(layer "In4.Cu")
		(net "P5E_CPU0_P2_TX_BUF_DP<11>")
	)
	(segment
		(start 416.70859 -399.504154)
		(end 416.277552 -399.935192)
		(width 0.14224)
		(layer "In4.Cu")
		(net "P5E_CPU0_P2_TX_BUF_DP<11>")
	)
	(segment
		(start 406.4508 -411.39618)
		(end 406.376378 -411.575758)
		(width 0.14224)
		(layer "In4.Cu")
		(net "P5E_CPU0_P2_TX_BUF_DP<11>")
	)
	(segment
		(start 408.77236 -410.43479)
		(end 408.698192 -410.614114)
		(width 0.14224)
		(layer "In4.Cu")
		(net "P5E_CPU0_P2_TX_BUF_DP<11>")
	)
	(segment
		(start 407.41854 -411.143958)
		(end 407.024078 -411.30728)
		(width 0.14224)
		(layer "In4.Cu")
		(net "P5E_CPU0_P2_TX_BUF_DP<11>")
	)
	(arc
		(start 416.634676 -397.926814)
		(mid 416.653364 -398.020585)
		(end 416.706558 -398.100042)
		(width 0.14224)
		(layer "In4.Cu")
		(net "P5E_CPU0_P2_TX_BUF_DP<11>")
	)
	(arc
		(start 416.277552 -399.935192)
		(mid 416.24259 -399.987517)
		(end 416.230308 -400.049238)
		(width 0.14224)
		(layer "In4.Cu")
		(net "P5E_CPU0_P2_TX_BUF_DP<11>")
	)
	(arc
		(start 416.875468 -398.268952)
		(mid 416.964183 -398.401817)
		(end 416.995356 -398.558512)
		(width 0.14224)
		(layer "In4.Cu")
		(net "P5E_CPU0_P2_TX_BUF_DP<11>")
	)
	(arc
		(start 411.68955 -408.666442)
		(mid 410.659381 -409.511899)
		(end 409.484068 -410.14015)
		(width 0.14224)
		(layer "In4.Cu")
		(net "P5E_CPU0_P2_TX_BUF_DP<11>")
	)
	(arc
		(start 405.288242 -411.930596)
		(mid 405.195215 -412.069726)
		(end 405.162512 -412.233872)
		(width 0.14224)
		(layer "In4.Cu")
		(net "P5E_CPU0_P2_TX_BUF_DP<11>")
	)
	(arc
		(start 416.995356 -398.812004)
		(mid 416.920825 -399.186605)
		(end 416.70859 -399.504154)
		(width 0.14224)
		(layer "In4.Cu")
		(net "P5E_CPU0_P2_TX_BUF_DP<11>")
	)
	(arc
		(start 416.230308 -403.578822)
		(mid 416.129772 -404.084159)
		(end 415.843466 -404.512526)
		(width 0.14224)
		(layer "In4.Cu")
		(net "P5E_CPU0_P2_TX_BUF_DP<11>")
	)
	(segment
		(start 402.119592 -416.336734)
		(end 402.119592 -413.11703)
		(width 0.12954)
		(layer "F.Cu")
		(net "P5E_CPU0_P2_TX_BUF_DP<10>")
	)
	(segment
		(start 415.298382 -397.849344)
		(end 415.819082 -397.849344)
		(width 0.127)
		(layer "F.Cu")
		(net "P5E_CPU0_P2_TX_BUF_DP<10>")
	)
	(segment
		(start 402.415502 -416.632644)
		(end 402.119592 -416.336734)
		(width 0.12954)
		(layer "F.Cu")
		(net "P5E_CPU0_P2_TX_BUF_DP<10>")
	)
	(segment
		(start 402.119592 -413.11703)
		(end 402.390102 -412.84652)
		(width 0.12954)
		(layer "F.Cu")
		(net "P5E_CPU0_P2_TX_BUF_DP<10>")
	)
	(segment
		(start 415.79546 -398.802606)
		(end 415.79546 -398.558258)
		(width 0.14224)
		(layer "In4.Cu")
		(net "P5E_CPU0_P2_TX_BUF_DP<10>")
	)
	(segment
		(start 415.704274 -397.734536)
		(end 415.819082 -397.849344)
		(width 0.14224)
		(layer "In4.Cu")
		(net "P5E_CPU0_P2_TX_BUF_DP<10>")
	)
	(segment
		(start 402.422614 -411.732984)
		(end 402.830792 -411.609286)
		(width 0.14224)
		(layer "In4.Cu")
		(net "P5E_CPU0_P2_TX_BUF_DP<10>")
	)
	(segment
		(start 414.964372 -402.717)
		(end 414.964372 -400.116802)
		(width 0.14224)
		(layer "In4.Cu")
		(net "P5E_CPU0_P2_TX_BUF_DP<10>")
	)
	(segment
		(start 414.964372 -403.84476)
		(end 414.964372 -403.41804)
		(width 0.14224)
		(layer "In4.Cu")
		(net "P5E_CPU0_P2_TX_BUF_DP<10>")
	)
	(segment
		(start 415.43478 -397.97355)
		(end 415.43478 -397.823944)
		(width 0.14224)
		(layer "In4.Cu")
		(net "P5E_CPU0_P2_TX_BUF_DP<10>")
	)
	(segment
		(start 415.101532 -402.85416)
		(end 414.964372 -402.717)
		(width 0.14224)
		(layer "In4.Cu")
		(net "P5E_CPU0_P2_TX_BUF_DP<10>")
	)
	(segment
		(start 411.019498 -407.959052)
		(end 414.844484 -404.134066)
		(width 0.14224)
		(layer "In4.Cu")
		(net "P5E_CPU0_P2_TX_BUF_DP<10>")
	)
	(segment
		(start 405.33066 -410.851096)
		(end 408.910536 -409.368244)
		(width 0.14224)
		(layer "In4.Cu")
		(net "P5E_CPU0_P2_TX_BUF_DP<10>")
	)
	(segment
		(start 402.830792 -411.609286)
		(end 403.001988 -411.700726)
		(width 0.14224)
		(layer "In4.Cu")
		(net "P5E_CPU0_P2_TX_BUF_DP<10>")
	)
	(segment
		(start 415.674302 -398.26565)
		(end 415.472118 -398.063466)
		(width 0.14224)
		(layer "In4.Cu")
		(net "P5E_CPU0_P2_TX_BUF_DP<10>")
	)
	(segment
		(start 402.099272 -412.55569)
		(end 402.099272 -412.1658)
		(width 0.14224)
		(layer "In4.Cu")
		(net "P5E_CPU0_P2_TX_BUF_DP<10>")
	)
	(segment
		(start 415.011616 -400.002756)
		(end 415.501074 -399.513298)
		(width 0.14224)
		(layer "In4.Cu")
		(net "P5E_CPU0_P2_TX_BUF_DP<10>")
	)
	(segment
		(start 403.50186 -411.405578)
		(end 403.910038 -411.28188)
		(width 0.14224)
		(layer "In4.Cu")
		(net "P5E_CPU0_P2_TX_BUF_DP<10>")
	)
	(segment
		(start 403.910038 -411.28188)
		(end 404.081234 -411.37332)
		(width 0.14224)
		(layer "In4.Cu")
		(net "P5E_CPU0_P2_TX_BUF_DP<10>")
	)
	(segment
		(start 402.176742 -411.978856)
		(end 402.422614 -411.732984)
		(width 0.14224)
		(layer "In4.Cu")
		(net "P5E_CPU0_P2_TX_BUF_DP<10>")
	)
	(segment
		(start 403.001988 -411.700726)
		(end 403.41042 -411.576774)
		(width 0.14224)
		(layer "In4.Cu")
		(net "P5E_CPU0_P2_TX_BUF_DP<10>")
	)
	(segment
		(start 415.43478 -397.823944)
		(end 415.524188 -397.734536)
		(width 0.14224)
		(layer "In4.Cu")
		(net "P5E_CPU0_P2_TX_BUF_DP<10>")
	)
	(segment
		(start 415.101532 -403.28088)
		(end 415.101532 -402.85416)
		(width 0.14224)
		(layer "In4.Cu")
		(net "P5E_CPU0_P2_TX_BUF_DP<10>")
	)
	(segment
		(start 402.390102 -412.84652)
		(end 402.099272 -412.55569)
		(width 0.14224)
		(layer "In4.Cu")
		(net "P5E_CPU0_P2_TX_BUF_DP<10>")
	)
	(segment
		(start 404.581106 -411.078172)
		(end 405.33066 -410.851096)
		(width 0.14224)
		(layer "In4.Cu")
		(net "P5E_CPU0_P2_TX_BUF_DP<10>")
	)
	(segment
		(start 403.41042 -411.576774)
		(end 403.50186 -411.405578)
		(width 0.14224)
		(layer "In4.Cu")
		(net "P5E_CPU0_P2_TX_BUF_DP<10>")
	)
	(segment
		(start 404.081234 -411.37332)
		(end 404.489666 -411.249622)
		(width 0.14224)
		(layer "In4.Cu")
		(net "P5E_CPU0_P2_TX_BUF_DP<10>")
	)
	(segment
		(start 415.524188 -397.734536)
		(end 415.704274 -397.734536)
		(width 0.14224)
		(layer "In4.Cu")
		(net "P5E_CPU0_P2_TX_BUF_DP<10>")
	)
	(segment
		(start 404.489666 -411.249622)
		(end 404.581106 -411.078172)
		(width 0.14224)
		(layer "In4.Cu")
		(net "P5E_CPU0_P2_TX_BUF_DP<10>")
	)
	(segment
		(start 414.964372 -403.41804)
		(end 415.101532 -403.28088)
		(width 0.14224)
		(layer "In4.Cu")
		(net "P5E_CPU0_P2_TX_BUF_DP<10>")
	)
	(arc
		(start 408.910536 -409.368244)
		(mid 410.034423 -408.767517)
		(end 411.019498 -407.959052)
		(width 0.14224)
		(layer "In4.Cu")
		(net "P5E_CPU0_P2_TX_BUF_DP<10>")
	)
	(arc
		(start 402.099272 -412.1658)
		(mid 402.119399 -412.064613)
		(end 402.176742 -411.978856)
		(width 0.14224)
		(layer "In4.Cu")
		(net "P5E_CPU0_P2_TX_BUF_DP<10>")
	)
	(arc
		(start 414.844484 -404.134066)
		(mid 414.933228 -404.001346)
		(end 414.964372 -403.84476)
		(width 0.14224)
		(layer "In4.Cu")
		(net "P5E_CPU0_P2_TX_BUF_DP<10>")
	)
	(arc
		(start 415.472118 -398.063466)
		(mid 415.444499 -398.022226)
		(end 415.43478 -397.97355)
		(width 0.14224)
		(layer "In4.Cu")
		(net "P5E_CPU0_P2_TX_BUF_DP<10>")
	)
	(arc
		(start 415.501074 -399.513298)
		(mid 415.718946 -399.18723)
		(end 415.79546 -398.802606)
		(width 0.14224)
		(layer "In4.Cu")
		(net "P5E_CPU0_P2_TX_BUF_DP<10>")
	)
	(arc
		(start 415.79546 -398.558258)
		(mid 415.763979 -398.399902)
		(end 415.674302 -398.26565)
		(width 0.14224)
		(layer "In4.Cu")
		(net "P5E_CPU0_P2_TX_BUF_DP<10>")
	)
	(arc
		(start 414.964372 -400.116802)
		(mid 414.976649 -400.055079)
		(end 415.011616 -400.002756)
		(width 0.14224)
		(layer "In4.Cu")
		(net "P5E_CPU0_P2_TX_BUF_DP<10>")
	)
	(segment
		(start 371.385592 -414.073848)
		(end 371.385592 -413.789876)
		(width 0.12954)
		(layer "F.Cu")
		(net "P5E_CPU0_P2_TX_BUF_DP<0>")
	)
	(segment
		(start 371.487192 -413.11703)
		(end 371.757702 -412.84652)
		(width 0.12954)
		(layer "F.Cu")
		(net "P5E_CPU0_P2_TX_BUF_DP<0>")
	)
	(segment
		(start 403.298406 -397.849344)
		(end 403.819106 -397.849344)
		(width 0.127)
		(layer "F.Cu")
		(net "P5E_CPU0_P2_TX_BUF_DP<0>")
	)
	(segment
		(start 371.487192 -413.544512)
		(end 371.487192 -413.11703)
		(width 0.12954)
		(layer "F.Cu")
		(net "P5E_CPU0_P2_TX_BUF_DP<0>")
	)
	(segment
		(start 371.385592 -413.789876)
		(end 371.487192 -413.544512)
		(width 0.12954)
		(layer "F.Cu")
		(net "P5E_CPU0_P2_TX_BUF_DP<0>")
	)
	(segment
		(start 371.681502 -414.369758)
		(end 371.385592 -414.073848)
		(width 0.12954)
		(layer "F.Cu")
		(net "P5E_CPU0_P2_TX_BUF_DP<0>")
	)
	(segment
		(start 375.146316 -410.100018)
		(end 374.647968 -410.320744)
		(width 0.14224)
		(layer "In4.Cu")
		(net "P5E_CPU0_P2_TX_BUF_DP<0>")
	)
	(segment
		(start 371.466872 -411.813756)
		(end 371.466872 -412.55569)
		(width 0.14224)
		(layer "In4.Cu")
		(net "P5E_CPU0_P2_TX_BUF_DP<0>")
	)
	(segment
		(start 403.819106 -397.849344)
		(end 403.696424 -397.726662)
		(width 0.14224)
		(layer "In4.Cu")
		(net "P5E_CPU0_P2_TX_BUF_DP<0>")
	)
	(segment
		(start 403.696424 -397.726662)
		(end 403.518624 -397.726662)
		(width 0.14224)
		(layer "In4.Cu")
		(net "P5E_CPU0_P2_TX_BUF_DP<0>")
	)
	(segment
		(start 402.673058 -398.215358)
		(end 402.47824 -398.410176)
		(width 0.14224)
		(layer "In4.Cu")
		(net "P5E_CPU0_P2_TX_BUF_DP<0>")
	)
	(segment
		(start 399.91284 -402.586698)
		(end 375.146316 -410.100018)
		(width 0.14224)
		(layer "In4.Cu")
		(net "P5E_CPU0_P2_TX_BUF_DP<0>")
	)
	(segment
		(start 372.515892 -411.416246)
		(end 372.125494 -411.58922)
		(width 0.14224)
		(layer "In4.Cu")
		(net "P5E_CPU0_P2_TX_BUF_DP<0>")
	)
	(segment
		(start 371.466872 -412.55569)
		(end 371.757702 -412.84652)
		(width 0.14224)
		(layer "In4.Cu")
		(net "P5E_CPU0_P2_TX_BUF_DP<0>")
	)
	(segment
		(start 402.265642 -398.728438)
		(end 401.526248 -400.514058)
		(width 0.14224)
		(layer "In4.Cu")
		(net "P5E_CPU0_P2_TX_BUF_DP<0>")
	)
	(segment
		(start 374.006618 -410.605224)
		(end 373.616728 -410.777944)
		(width 0.14224)
		(layer "In4.Cu")
		(net "P5E_CPU0_P2_TX_BUF_DP<0>")
	)
	(segment
		(start 372.125494 -411.58922)
		(end 371.944392 -411.51937)
		(width 0.14224)
		(layer "In4.Cu")
		(net "P5E_CPU0_P2_TX_BUF_DP<0>")
	)
	(segment
		(start 373.546878 -410.9593)
		(end 373.15648 -411.132274)
		(width 0.14224)
		(layer "In4.Cu")
		(net "P5E_CPU0_P2_TX_BUF_DP<0>")
	)
	(segment
		(start 403.518624 -397.726662)
		(end 403.32533 -397.919956)
		(width 0.14224)
		(layer "In4.Cu")
		(net "P5E_CPU0_P2_TX_BUF_DP<0>")
	)
	(segment
		(start 374.647968 -410.320744)
		(end 374.578118 -410.5021)
		(width 0.14224)
		(layer "In4.Cu")
		(net "P5E_CPU0_P2_TX_BUF_DP<0>")
	)
	(segment
		(start 371.944392 -411.51937)
		(end 371.54231 -411.697678)
		(width 0.14224)
		(layer "In4.Cu")
		(net "P5E_CPU0_P2_TX_BUF_DP<0>")
	)
	(segment
		(start 373.616728 -410.777944)
		(end 373.546878 -410.9593)
		(width 0.14224)
		(layer "In4.Cu")
		(net "P5E_CPU0_P2_TX_BUF_DP<0>")
	)
	(segment
		(start 374.578118 -410.5021)
		(end 374.18772 -410.675074)
		(width 0.14224)
		(layer "In4.Cu")
		(net "P5E_CPU0_P2_TX_BUF_DP<0>")
	)
	(segment
		(start 372.975378 -411.062424)
		(end 372.585488 -411.235144)
		(width 0.14224)
		(layer "In4.Cu")
		(net "P5E_CPU0_P2_TX_BUF_DP<0>")
	)
	(segment
		(start 373.15648 -411.132274)
		(end 372.975378 -411.062424)
		(width 0.14224)
		(layer "In4.Cu")
		(net "P5E_CPU0_P2_TX_BUF_DP<0>")
	)
	(segment
		(start 401.50669 -400.608546)
		(end 401.50669 -401.002754)
		(width 0.14224)
		(layer "In4.Cu")
		(net "P5E_CPU0_P2_TX_BUF_DP<0>")
	)
	(segment
		(start 401.340066 -401.404582)
		(end 400.524472 -402.220176)
		(width 0.14224)
		(layer "In4.Cu")
		(net "P5E_CPU0_P2_TX_BUF_DP<0>")
	)
	(segment
		(start 374.18772 -410.675074)
		(end 374.006618 -410.605224)
		(width 0.14224)
		(layer "In4.Cu")
		(net "P5E_CPU0_P2_TX_BUF_DP<0>")
	)
	(segment
		(start 372.585488 -411.235144)
		(end 372.515892 -411.416246)
		(width 0.14224)
		(layer "In4.Cu")
		(net "P5E_CPU0_P2_TX_BUF_DP<0>")
	)
	(arc
		(start 400.524472 -402.220176)
		(mid 400.241254 -402.441143)
		(end 399.91284 -402.586698)
		(width 0.14224)
		(layer "In4.Cu")
		(net "P5E_CPU0_P2_TX_BUF_DP<0>")
	)
	(arc
		(start 401.50669 -401.002754)
		(mid 401.463351 -401.220252)
		(end 401.340066 -401.404582)
		(width 0.14224)
		(layer "In4.Cu")
		(net "P5E_CPU0_P2_TX_BUF_DP<0>")
	)
	(arc
		(start 371.54231 -411.697678)
		(mid 371.487482 -411.744574)
		(end 371.466872 -411.813756)
		(width 0.14224)
		(layer "In4.Cu")
		(net "P5E_CPU0_P2_TX_BUF_DP<0>")
	)
	(arc
		(start 401.526248 -400.514058)
		(mid 401.512053 -400.560386)
		(end 401.50669 -400.608546)
		(width 0.14224)
		(layer "In4.Cu")
		(net "P5E_CPU0_P2_TX_BUF_DP<0>")
	)
	(arc
		(start 403.32533 -397.919956)
		(mid 403.175808 -398.023362)
		(end 402.999448 -398.06753)
		(width 0.14224)
		(layer "In4.Cu")
		(net "P5E_CPU0_P2_TX_BUF_DP<0>")
	)
	(arc
		(start 402.47824 -398.410176)
		(mid 402.356245 -398.558825)
		(end 402.265642 -398.728438)
		(width 0.14224)
		(layer "In4.Cu")
		(net "P5E_CPU0_P2_TX_BUF_DP<0>")
	)
	(arc
		(start 402.999448 -398.06753)
		(mid 402.822767 -398.111679)
		(end 402.673058 -398.215358)
		(width 0.14224)
		(layer "In4.Cu")
		(net "P5E_CPU0_P2_TX_BUF_DP<0>")
	)
	(segment
		(start 413.698182 -397.156432)
		(end 414.218882 -397.156432)
		(width 0.127)
		(layer "F.Cu")
		(net "P5E_CPU0_P2_TX_BUF_DN<9>")
	)
	(segment
		(start 398.733772 -416.336734)
		(end 398.733772 -413.11703)
		(width 0.12954)
		(layer "F.Cu")
		(net "P5E_CPU0_P2_TX_BUF_DN<9>")
	)
	(segment
		(start 398.437862 -416.632644)
		(end 398.733772 -416.336734)
		(width 0.12954)
		(layer "F.Cu")
		(net "P5E_CPU0_P2_TX_BUF_DN<9>")
	)
	(segment
		(start 398.733772 -413.11703)
		(end 398.463262 -412.84652)
		(width 0.12954)
		(layer "F.Cu")
		(net "P5E_CPU0_P2_TX_BUF_DN<9>")
	)
	(segment
		(start 414.271206 -397.208756)
		(end 414.271206 -397.388588)
		(width 0.14224)
		(layer "In4.Cu")
		(net "P5E_CPU0_P2_TX_BUF_DN<9>")
	)
	(segment
		(start 413.93745 -397.722344)
		(end 413.93745 -397.897858)
		(width 0.14224)
		(layer "In4.Cu")
		(net "P5E_CPU0_P2_TX_BUF_DN<9>")
	)
	(segment
		(start 413.541718 -400.086576)
		(end 413.541718 -403.654768)
		(width 0.14224)
		(layer "In4.Cu")
		(net "P5E_CPU0_P2_TX_BUF_DN<9>")
	)
	(segment
		(start 404.961598 -409.68803)
		(end 401.669758 -410.652468)
		(width 0.14224)
		(layer "In4.Cu")
		(net "P5E_CPU0_P2_TX_BUF_DN<9>")
	)
	(segment
		(start 413.50438 -403.744684)
		(end 410.148532 -407.100532)
		(width 0.14224)
		(layer "In4.Cu")
		(net "P5E_CPU0_P2_TX_BUF_DN<9>")
	)
	(segment
		(start 414.271206 -397.388588)
		(end 413.93745 -397.722344)
		(width 0.14224)
		(layer "In4.Cu")
		(net "P5E_CPU0_P2_TX_BUF_DN<9>")
	)
	(segment
		(start 414.120584 -399.323814)
		(end 413.671512 -399.772886)
		(width 0.14224)
		(layer "In4.Cu")
		(net "P5E_CPU0_P2_TX_BUF_DN<9>")
	)
	(segment
		(start 399.109692 -411.568392)
		(end 398.971262 -411.706822)
		(width 0.14224)
		(layer "In4.Cu")
		(net "P5E_CPU0_P2_TX_BUF_DN<9>")
	)
	(segment
		(start 408.4193 -408.255724)
		(end 404.961598 -409.68803)
		(width 0.14224)
		(layer "In4.Cu")
		(net "P5E_CPU0_P2_TX_BUF_DN<9>")
	)
	(segment
		(start 414.218882 -397.156432)
		(end 414.271206 -397.208756)
		(width 0.14224)
		(layer "In4.Cu")
		(net "P5E_CPU0_P2_TX_BUF_DN<9>")
	)
	(segment
		(start 401.669758 -410.652468)
		(end 399.109692 -411.568392)
		(width 0.14224)
		(layer "In4.Cu")
		(net "P5E_CPU0_P2_TX_BUF_DN<9>")
	)
	(segment
		(start 398.754092 -412.55569)
		(end 398.463262 -412.84652)
		(width 0.14224)
		(layer "In4.Cu")
		(net "P5E_CPU0_P2_TX_BUF_DN<9>")
	)
	(segment
		(start 414.09874 -398.28724)
		(end 414.311084 -398.499584)
		(width 0.14224)
		(layer "In4.Cu")
		(net "P5E_CPU0_P2_TX_BUF_DN<9>")
	)
	(segment
		(start 414.31337 -398.504918)
		(end 414.31337 -398.858486)
		(width 0.14224)
		(layer "In4.Cu")
		(net "P5E_CPU0_P2_TX_BUF_DN<9>")
	)
	(segment
		(start 398.754092 -412.231078)
		(end 398.754092 -412.55569)
		(width 0.14224)
		(layer "In4.Cu")
		(net "P5E_CPU0_P2_TX_BUF_DN<9>")
	)
	(arc
		(start 410.148532 -407.100532)
		(mid 409.340802 -407.763281)
		(end 408.4193 -408.255724)
		(width 0.14224)
		(layer "In4.Cu")
		(net "P5E_CPU0_P2_TX_BUF_DN<9>")
	)
	(arc
		(start 413.671512 -399.772886)
		(mid 413.575376 -399.916809)
		(end 413.541718 -400.086576)
		(width 0.14224)
		(layer "In4.Cu")
		(net "P5E_CPU0_P2_TX_BUF_DN<9>")
	)
	(arc
		(start 413.93745 -397.897858)
		(mid 413.979314 -398.108616)
		(end 414.09874 -398.28724)
		(width 0.14224)
		(layer "In4.Cu")
		(net "P5E_CPU0_P2_TX_BUF_DN<9>")
	)
	(arc
		(start 398.971262 -411.706822)
		(mid 398.810545 -411.947353)
		(end 398.754092 -412.231078)
		(width 0.14224)
		(layer "In4.Cu")
		(net "P5E_CPU0_P2_TX_BUF_DN<9>")
	)
	(arc
		(start 414.31337 -398.858486)
		(mid 414.263259 -399.110321)
		(end 414.120584 -399.323814)
		(width 0.14224)
		(layer "In4.Cu")
		(net "P5E_CPU0_P2_TX_BUF_DN<9>")
	)
	(arc
		(start 414.311084 -398.499584)
		(mid 414.312774 -398.502016)
		(end 414.31337 -398.504918)
		(width 0.14224)
		(layer "In4.Cu")
		(net "P5E_CPU0_P2_TX_BUF_DN<9>")
	)
	(arc
		(start 413.541718 -403.654768)
		(mid 413.532016 -403.703452)
		(end 413.50438 -403.744684)
		(width 0.14224)
		(layer "In4.Cu")
		(net "P5E_CPU0_P2_TX_BUF_DN<9>")
	)
	(segment
		(start 395.670532 -416.336734)
		(end 395.670532 -413.11703)
		(width 0.12954)
		(layer "F.Cu")
		(net "P5E_CPU0_P2_TX_BUF_DN<8>")
	)
	(segment
		(start 412.498286 -397.156432)
		(end 413.018986 -397.156432)
		(width 0.127)
		(layer "F.Cu")
		(net "P5E_CPU0_P2_TX_BUF_DN<8>")
	)
	(segment
		(start 395.670532 -413.11703)
		(end 395.400022 -412.84652)
		(width 0.12954)
		(layer "F.Cu")
		(net "P5E_CPU0_P2_TX_BUF_DN<8>")
	)
	(segment
		(start 395.374622 -416.632644)
		(end 395.670532 -416.336734)
		(width 0.12954)
		(layer "F.Cu")
		(net "P5E_CPU0_P2_TX_BUF_DN<8>")
	)
	(segment
		(start 401.900136 -409.533598)
		(end 399.495772 -410.21635)
		(width 0.14224)
		(layer "In4.Cu")
		(net "P5E_CPU0_P2_TX_BUF_DN<8>")
	)
	(segment
		(start 412.943294 -398.3355)
		(end 413.076136 -398.468342)
		(width 0.14224)
		(layer "In4.Cu")
		(net "P5E_CPU0_P2_TX_BUF_DN<8>")
	)
	(segment
		(start 399.495772 -410.21635)
		(end 396.044674 -411.559248)
		(width 0.14224)
		(layer "In4.Cu")
		(net "P5E_CPU0_P2_TX_BUF_DN<8>")
	)
	(segment
		(start 395.690852 -412.55569)
		(end 395.400022 -412.84652)
		(width 0.14224)
		(layer "In4.Cu")
		(net "P5E_CPU0_P2_TX_BUF_DN<8>")
	)
	(segment
		(start 412.752794 -397.707104)
		(end 412.752794 -397.87576)
		(width 0.14224)
		(layer "In4.Cu")
		(net "P5E_CPU0_P2_TX_BUF_DN<8>")
	)
	(segment
		(start 408.036776 -407.40203)
		(end 404.890986 -408.704542)
		(width 0.14224)
		(layer "In4.Cu")
		(net "P5E_CPU0_P2_TX_BUF_DN<8>")
	)
	(segment
		(start 413.018986 -397.156432)
		(end 413.07131 -397.208756)
		(width 0.14224)
		(layer "In4.Cu")
		(net "P5E_CPU0_P2_TX_BUF_DN<8>")
	)
	(segment
		(start 413.113474 -398.558512)
		(end 413.113474 -398.79778)
		(width 0.14224)
		(layer "In4.Cu")
		(net "P5E_CPU0_P2_TX_BUF_DN<8>")
	)
	(segment
		(start 404.890986 -408.704542)
		(end 402.655024 -409.382976)
		(width 0.14224)
		(layer "In4.Cu")
		(net "P5E_CPU0_P2_TX_BUF_DN<8>")
	)
	(segment
		(start 412.276036 -400.1516)
		(end 412.276036 -402.952204)
		(width 0.14224)
		(layer "In4.Cu")
		(net "P5E_CPU0_P2_TX_BUF_DN<8>")
	)
	(segment
		(start 412.885128 -399.349214)
		(end 412.412434 -399.822162)
		(width 0.14224)
		(layer "In4.Cu")
		(net "P5E_CPU0_P2_TX_BUF_DN<8>")
	)
	(segment
		(start 413.07131 -397.388588)
		(end 412.752794 -397.707104)
		(width 0.14224)
		(layer "In4.Cu")
		(net "P5E_CPU0_P2_TX_BUF_DN<8>")
	)
	(segment
		(start 396.044674 -411.559248)
		(end 395.861794 -411.742128)
		(width 0.14224)
		(layer "In4.Cu")
		(net "P5E_CPU0_P2_TX_BUF_DN<8>")
	)
	(segment
		(start 402.655024 -409.382976)
		(end 401.900136 -409.533598)
		(width 0.14224)
		(layer "In4.Cu")
		(net "P5E_CPU0_P2_TX_BUF_DN<8>")
	)
	(segment
		(start 413.07131 -397.208756)
		(end 413.07131 -397.388588)
		(width 0.14224)
		(layer "In4.Cu")
		(net "P5E_CPU0_P2_TX_BUF_DN<8>")
	)
	(segment
		(start 395.690852 -412.154878)
		(end 395.690852 -412.55569)
		(width 0.14224)
		(layer "In4.Cu")
		(net "P5E_CPU0_P2_TX_BUF_DN<8>")
	)
	(segment
		(start 411.893258 -403.876002)
		(end 409.031948 -406.737312)
		(width 0.14224)
		(layer "In4.Cu")
		(net "P5E_CPU0_P2_TX_BUF_DN<8>")
	)
	(arc
		(start 409.031948 -406.737312)
		(mid 408.567102 -407.118686)
		(end 408.036776 -407.40203)
		(width 0.14224)
		(layer "In4.Cu")
		(net "P5E_CPU0_P2_TX_BUF_DN<8>")
	)
	(arc
		(start 412.752794 -397.87576)
		(mid 412.802306 -398.124582)
		(end 412.943294 -398.3355)
		(width 0.14224)
		(layer "In4.Cu")
		(net "P5E_CPU0_P2_TX_BUF_DN<8>")
	)
	(arc
		(start 413.113474 -398.79778)
		(mid 413.054132 -399.096203)
		(end 412.885128 -399.349214)
		(width 0.14224)
		(layer "In4.Cu")
		(net "P5E_CPU0_P2_TX_BUF_DN<8>")
	)
	(arc
		(start 412.412434 -399.822162)
		(mid 412.311494 -399.973324)
		(end 412.276036 -400.1516)
		(width 0.14224)
		(layer "In4.Cu")
		(net "P5E_CPU0_P2_TX_BUF_DN<8>")
	)
	(arc
		(start 413.076136 -398.468342)
		(mid 413.103779 -398.509712)
		(end 413.113474 -398.558512)
		(width 0.14224)
		(layer "In4.Cu")
		(net "P5E_CPU0_P2_TX_BUF_DN<8>")
	)
	(arc
		(start 412.276036 -402.952204)
		(mid 412.176549 -403.452181)
		(end 411.893258 -403.876002)
		(width 0.14224)
		(layer "In4.Cu")
		(net "P5E_CPU0_P2_TX_BUF_DN<8>")
	)
	(arc
		(start 395.861794 -411.742128)
		(mid 395.73526 -411.931499)
		(end 395.690852 -412.154878)
		(width 0.14224)
		(layer "In4.Cu")
		(net "P5E_CPU0_P2_TX_BUF_DN<8>")
	)
	(segment
		(start 392.607292 -416.336734)
		(end 392.607292 -413.11703)
		(width 0.12954)
		(layer "F.Cu")
		(net "P5E_CPU0_P2_TX_BUF_DN<7>")
	)
	(segment
		(start 392.607292 -413.11703)
		(end 392.336782 -412.84652)
		(width 0.12954)
		(layer "F.Cu")
		(net "P5E_CPU0_P2_TX_BUF_DN<7>")
	)
	(segment
		(start 411.29839 -397.156432)
		(end 411.81909 -397.156432)
		(width 0.127)
		(layer "F.Cu")
		(net "P5E_CPU0_P2_TX_BUF_DN<7>")
	)
	(segment
		(start 392.311382 -416.632644)
		(end 392.607292 -416.336734)
		(width 0.12954)
		(layer "F.Cu")
		(net "P5E_CPU0_P2_TX_BUF_DN<7>")
	)
	(segment
		(start 411.726888 -398.31899)
		(end 411.87624 -398.468342)
		(width 0.14224)
		(layer "In4.Cu")
		(net "P5E_CPU0_P2_TX_BUF_DN<7>")
	)
	(segment
		(start 402.41728 -408.458162)
		(end 401.428712 -408.655012)
		(width 0.14224)
		(layer "In4.Cu")
		(net "P5E_CPU0_P2_TX_BUF_DN<7>")
	)
	(segment
		(start 411.798516 -399.201386)
		(end 411.316932 -399.68297)
		(width 0.14224)
		(layer "In4.Cu")
		(net "P5E_CPU0_P2_TX_BUF_DN<7>")
	)
	(segment
		(start 392.627612 -412.55569)
		(end 392.336782 -412.84652)
		(width 0.14224)
		(layer "In4.Cu")
		(net "P5E_CPU0_P2_TX_BUF_DN<7>")
	)
	(segment
		(start 404.772114 -407.743914)
		(end 402.41728 -408.458162)
		(width 0.14224)
		(layer "In4.Cu")
		(net "P5E_CPU0_P2_TX_BUF_DN<7>")
	)
	(segment
		(start 410.893514 -403.501606)
		(end 408.268932 -406.126188)
		(width 0.14224)
		(layer "In4.Cu")
		(net "P5E_CPU0_P2_TX_BUF_DN<7>")
	)
	(segment
		(start 392.96975 -411.520894)
		(end 392.856212 -411.634432)
		(width 0.14224)
		(layer "In4.Cu")
		(net "P5E_CPU0_P2_TX_BUF_DN<7>")
	)
	(segment
		(start 411.871414 -397.388588)
		(end 411.56001 -397.699992)
		(width 0.14224)
		(layer "In4.Cu")
		(net "P5E_CPU0_P2_TX_BUF_DN<7>")
	)
	(segment
		(start 392.627612 -412.18612)
		(end 392.627612 -412.55569)
		(width 0.14224)
		(layer "In4.Cu")
		(net "P5E_CPU0_P2_TX_BUF_DN<7>")
	)
	(segment
		(start 401.428712 -408.655012)
		(end 395.67485 -410.4005)
		(width 0.14224)
		(layer "In4.Cu")
		(net "P5E_CPU0_P2_TX_BUF_DN<7>")
	)
	(segment
		(start 407.60142 -406.572212)
		(end 404.772114 -407.743914)
		(width 0.14224)
		(layer "In4.Cu")
		(net "P5E_CPU0_P2_TX_BUF_DN<7>")
	)
	(segment
		(start 411.135322 -400.121628)
		(end 411.135322 -402.917914)
		(width 0.14224)
		(layer "In4.Cu")
		(net "P5E_CPU0_P2_TX_BUF_DN<7>")
	)
	(segment
		(start 395.67485 -410.4005)
		(end 392.96975 -411.520894)
		(width 0.14224)
		(layer "In4.Cu")
		(net "P5E_CPU0_P2_TX_BUF_DN<7>")
	)
	(segment
		(start 411.56001 -397.699992)
		(end 411.56001 -397.916146)
		(width 0.14224)
		(layer "In4.Cu")
		(net "P5E_CPU0_P2_TX_BUF_DN<7>")
	)
	(segment
		(start 411.871414 -397.208756)
		(end 411.871414 -397.388588)
		(width 0.14224)
		(layer "In4.Cu")
		(net "P5E_CPU0_P2_TX_BUF_DN<7>")
	)
	(segment
		(start 411.81909 -397.156432)
		(end 411.871414 -397.208756)
		(width 0.14224)
		(layer "In4.Cu")
		(net "P5E_CPU0_P2_TX_BUF_DN<7>")
	)
	(segment
		(start 411.913578 -398.558004)
		(end 411.913578 -398.923764)
		(width 0.14224)
		(layer "In4.Cu")
		(net "P5E_CPU0_P2_TX_BUF_DN<7>")
	)
	(arc
		(start 411.316932 -399.68297)
		(mid 411.182509 -399.884242)
		(end 411.135322 -400.121628)
		(width 0.14224)
		(layer "In4.Cu")
		(net "P5E_CPU0_P2_TX_BUF_DN<7>")
	)
	(arc
		(start 392.856212 -411.634432)
		(mid 392.687031 -411.887534)
		(end 392.627612 -412.18612)
		(width 0.14224)
		(layer "In4.Cu")
		(net "P5E_CPU0_P2_TX_BUF_DN<7>")
	)
	(arc
		(start 411.913578 -398.923764)
		(mid 411.883672 -399.074023)
		(end 411.798516 -399.201386)
		(width 0.14224)
		(layer "In4.Cu")
		(net "P5E_CPU0_P2_TX_BUF_DN<7>")
	)
	(arc
		(start 411.135322 -402.917914)
		(mid 411.072485 -403.233819)
		(end 410.893514 -403.501606)
		(width 0.14224)
		(layer "In4.Cu")
		(net "P5E_CPU0_P2_TX_BUF_DN<7>")
	)
	(arc
		(start 411.56001 -397.916146)
		(mid 411.603378 -398.134169)
		(end 411.726888 -398.31899)
		(width 0.14224)
		(layer "In4.Cu")
		(net "P5E_CPU0_P2_TX_BUF_DN<7>")
	)
	(arc
		(start 411.87624 -398.468342)
		(mid 411.90381 -398.509464)
		(end 411.913578 -398.558004)
		(width 0.14224)
		(layer "In4.Cu")
		(net "P5E_CPU0_P2_TX_BUF_DN<7>")
	)
	(arc
		(start 408.268932 -406.126188)
		(mid 407.95714 -406.38207)
		(end 407.60142 -406.572212)
		(width 0.14224)
		(layer "In4.Cu")
		(net "P5E_CPU0_P2_TX_BUF_DN<7>")
	)
	(segment
		(start 389.248142 -416.632644)
		(end 389.544052 -416.336734)
		(width 0.12954)
		(layer "F.Cu")
		(net "P5E_CPU0_P2_TX_BUF_DN<6>")
	)
	(segment
		(start 410.09824 -397.156432)
		(end 410.61894 -397.156432)
		(width 0.127)
		(layer "F.Cu")
		(net "P5E_CPU0_P2_TX_BUF_DN<6>")
	)
	(segment
		(start 389.544052 -413.11703)
		(end 389.273542 -412.84652)
		(width 0.12954)
		(layer "F.Cu")
		(net "P5E_CPU0_P2_TX_BUF_DN<6>")
	)
	(segment
		(start 389.544052 -416.336734)
		(end 389.544052 -413.11703)
		(width 0.12954)
		(layer "F.Cu")
		(net "P5E_CPU0_P2_TX_BUF_DN<6>")
	)
	(segment
		(start 402.014436 -407.50236)
		(end 392.558524 -410.370782)
		(width 0.14224)
		(layer "In4.Cu")
		(net "P5E_CPU0_P2_TX_BUF_DN<6>")
	)
	(segment
		(start 409.678886 -403.353016)
		(end 407.502106 -405.529796)
		(width 0.14224)
		(layer "In4.Cu")
		(net "P5E_CPU0_P2_TX_BUF_DN<6>")
	)
	(segment
		(start 389.879078 -411.481016)
		(end 389.73252 -411.627574)
		(width 0.14224)
		(layer "In4.Cu")
		(net "P5E_CPU0_P2_TX_BUF_DN<6>")
	)
	(segment
		(start 410.489908 -399.325084)
		(end 410.059124 -399.755868)
		(width 0.14224)
		(layer "In4.Cu")
		(net "P5E_CPU0_P2_TX_BUF_DN<6>")
	)
	(segment
		(start 410.61894 -397.156432)
		(end 410.671264 -397.208756)
		(width 0.14224)
		(layer "In4.Cu")
		(net "P5E_CPU0_P2_TX_BUF_DN<6>")
	)
	(segment
		(start 410.671264 -397.388588)
		(end 410.352748 -397.707104)
		(width 0.14224)
		(layer "In4.Cu")
		(net "P5E_CPU0_P2_TX_BUF_DN<6>")
	)
	(segment
		(start 407.210006 -405.724868)
		(end 404.587964 -406.810718)
		(width 0.14224)
		(layer "In4.Cu")
		(net "P5E_CPU0_P2_TX_BUF_DN<6>")
	)
	(segment
		(start 410.520896 -398.313148)
		(end 410.67609 -398.468342)
		(width 0.14224)
		(layer "In4.Cu")
		(net "P5E_CPU0_P2_TX_BUF_DN<6>")
	)
	(segment
		(start 392.558524 -410.370782)
		(end 389.879078 -411.481016)
		(width 0.14224)
		(layer "In4.Cu")
		(net "P5E_CPU0_P2_TX_BUF_DN<6>")
	)
	(segment
		(start 389.564372 -412.033466)
		(end 389.564372 -412.55569)
		(width 0.14224)
		(layer "In4.Cu")
		(net "P5E_CPU0_P2_TX_BUF_DN<6>")
	)
	(segment
		(start 410.713428 -398.558512)
		(end 410.713428 -398.785588)
		(width 0.14224)
		(layer "In4.Cu")
		(net "P5E_CPU0_P2_TX_BUF_DN<6>")
	)
	(segment
		(start 404.587964 -406.810718)
		(end 402.867876 -407.332434)
		(width 0.14224)
		(layer "In4.Cu")
		(net "P5E_CPU0_P2_TX_BUF_DN<6>")
	)
	(segment
		(start 389.564372 -412.55569)
		(end 389.273542 -412.84652)
		(width 0.14224)
		(layer "In4.Cu")
		(net "P5E_CPU0_P2_TX_BUF_DN<6>")
	)
	(segment
		(start 402.867876 -407.332434)
		(end 402.014436 -407.50236)
		(width 0.14224)
		(layer "In4.Cu")
		(net "P5E_CPU0_P2_TX_BUF_DN<6>")
	)
	(segment
		(start 410.352748 -397.707104)
		(end 410.352748 -397.907256)
		(width 0.14224)
		(layer "In4.Cu")
		(net "P5E_CPU0_P2_TX_BUF_DN<6>")
	)
	(segment
		(start 410.671264 -397.208756)
		(end 410.671264 -397.388588)
		(width 0.14224)
		(layer "In4.Cu")
		(net "P5E_CPU0_P2_TX_BUF_DN<6>")
	)
	(segment
		(start 409.911042 -400.1135)
		(end 409.911042 -402.792692)
		(width 0.14224)
		(layer "In4.Cu")
		(net "P5E_CPU0_P2_TX_BUF_DN<6>")
	)
	(arc
		(start 410.67609 -398.468342)
		(mid 410.703733 -398.509712)
		(end 410.713428 -398.558512)
		(width 0.14224)
		(layer "In4.Cu")
		(net "P5E_CPU0_P2_TX_BUF_DN<6>")
	)
	(arc
		(start 409.911042 -402.792692)
		(mid 409.850703 -403.095947)
		(end 409.678886 -403.353016)
		(width 0.14224)
		(layer "In4.Cu")
		(net "P5E_CPU0_P2_TX_BUF_DN<6>")
	)
	(arc
		(start 389.73252 -411.627574)
		(mid 389.608089 -411.813799)
		(end 389.564372 -412.033466)
		(width 0.14224)
		(layer "In4.Cu")
		(net "P5E_CPU0_P2_TX_BUF_DN<6>")
	)
	(arc
		(start 410.059124 -399.755868)
		(mid 409.949541 -399.919965)
		(end 409.911042 -400.1135)
		(width 0.14224)
		(layer "In4.Cu")
		(net "P5E_CPU0_P2_TX_BUF_DN<6>")
	)
	(arc
		(start 407.502106 -405.529796)
		(mid 407.365664 -405.64172)
		(end 407.210006 -405.724868)
		(width 0.14224)
		(layer "In4.Cu")
		(net "P5E_CPU0_P2_TX_BUF_DN<6>")
	)
	(arc
		(start 410.713428 -398.785588)
		(mid 410.655332 -399.077567)
		(end 410.489908 -399.325084)
		(width 0.14224)
		(layer "In4.Cu")
		(net "P5E_CPU0_P2_TX_BUF_DN<6>")
	)
	(arc
		(start 410.352748 -397.907256)
		(mid 410.396444 -398.126932)
		(end 410.520896 -398.313148)
		(width 0.14224)
		(layer "In4.Cu")
		(net "P5E_CPU0_P2_TX_BUF_DN<6>")
	)
	(segment
		(start 408.898344 -397.156432)
		(end 409.419044 -397.156432)
		(width 0.127)
		(layer "F.Cu")
		(net "P5E_CPU0_P2_TX_BUF_DN<5>")
	)
	(segment
		(start 386.480812 -416.336734)
		(end 386.480812 -413.11703)
		(width 0.12954)
		(layer "F.Cu")
		(net "P5E_CPU0_P2_TX_BUF_DN<5>")
	)
	(segment
		(start 386.480812 -413.11703)
		(end 386.210302 -412.84652)
		(width 0.12954)
		(layer "F.Cu")
		(net "P5E_CPU0_P2_TX_BUF_DN<5>")
	)
	(segment
		(start 386.184902 -416.632644)
		(end 386.480812 -416.336734)
		(width 0.12954)
		(layer "F.Cu")
		(net "P5E_CPU0_P2_TX_BUF_DN<5>")
	)
	(segment
		(start 386.501132 -412.55569)
		(end 386.210302 -412.84652)
		(width 0.14224)
		(layer "In4.Cu")
		(net "P5E_CPU0_P2_TX_BUF_DN<5>")
	)
	(segment
		(start 390.876028 -409.90647)
		(end 386.845302 -411.576012)
		(width 0.14224)
		(layer "In4.Cu")
		(net "P5E_CPU0_P2_TX_BUF_DN<5>")
	)
	(segment
		(start 386.845302 -411.576012)
		(end 386.684774 -411.73654)
		(width 0.14224)
		(layer "In4.Cu")
		(net "P5E_CPU0_P2_TX_BUF_DN<5>")
	)
	(segment
		(start 406.72131 -404.917656)
		(end 404.34133 -405.90343)
		(width 0.14224)
		(layer "In4.Cu")
		(net "P5E_CPU0_P2_TX_BUF_DN<5>")
	)
	(segment
		(start 409.46959 -397.206978)
		(end 409.46959 -397.40713)
		(width 0.14224)
		(layer "In4.Cu")
		(net "P5E_CPU0_P2_TX_BUF_DN<5>")
	)
	(segment
		(start 408.714702 -400.104864)
		(end 408.714702 -402.735288)
		(width 0.14224)
		(layer "In4.Cu")
		(net "P5E_CPU0_P2_TX_BUF_DN<5>")
	)
	(segment
		(start 409.513532 -398.745456)
		(end 409.513532 -398.92478)
		(width 0.14224)
		(layer "In4.Cu")
		(net "P5E_CPU0_P2_TX_BUF_DN<5>")
	)
	(segment
		(start 409.421076 -399.147792)
		(end 408.891994 -399.676874)
		(width 0.14224)
		(layer "In4.Cu")
		(net "P5E_CPU0_P2_TX_BUF_DN<5>")
	)
	(segment
		(start 402.100542 -406.501346)
		(end 390.876028 -409.90647)
		(width 0.14224)
		(layer "In4.Cu")
		(net "P5E_CPU0_P2_TX_BUF_DN<5>")
	)
	(segment
		(start 404.34133 -405.90343)
		(end 402.884132 -406.345644)
		(width 0.14224)
		(layer "In4.Cu")
		(net "P5E_CPU0_P2_TX_BUF_DN<5>")
	)
	(segment
		(start 408.564588 -403.097492)
		(end 406.790652 -404.871428)
		(width 0.14224)
		(layer "In4.Cu")
		(net "P5E_CPU0_P2_TX_BUF_DN<5>")
	)
	(segment
		(start 409.152852 -397.723868)
		(end 409.152852 -397.87576)
		(width 0.14224)
		(layer "In4.Cu")
		(net "P5E_CPU0_P2_TX_BUF_DN<5>")
	)
	(segment
		(start 386.501132 -412.17977)
		(end 386.501132 -412.55569)
		(width 0.14224)
		(layer "In4.Cu")
		(net "P5E_CPU0_P2_TX_BUF_DN<5>")
	)
	(segment
		(start 409.419044 -397.156432)
		(end 409.46959 -397.206978)
		(width 0.14224)
		(layer "In4.Cu")
		(net "P5E_CPU0_P2_TX_BUF_DN<5>")
	)
	(segment
		(start 409.46959 -397.40713)
		(end 409.152852 -397.723868)
		(width 0.14224)
		(layer "In4.Cu")
		(net "P5E_CPU0_P2_TX_BUF_DN<5>")
	)
	(segment
		(start 402.884132 -406.345644)
		(end 402.100542 -406.501346)
		(width 0.14224)
		(layer "In4.Cu")
		(net "P5E_CPU0_P2_TX_BUF_DN<5>")
	)
	(arc
		(start 386.684774 -411.73654)
		(mid 386.548842 -411.939881)
		(end 386.501132 -412.17977)
		(width 0.14224)
		(layer "In4.Cu")
		(net "P5E_CPU0_P2_TX_BUF_DN<5>")
	)
	(arc
		(start 408.891994 -399.676874)
		(mid 408.760788 -399.873237)
		(end 408.714702 -400.104864)
		(width 0.14224)
		(layer "In4.Cu")
		(net "P5E_CPU0_P2_TX_BUF_DN<5>")
	)
	(arc
		(start 408.714702 -402.735288)
		(mid 408.675689 -402.931329)
		(end 408.564588 -403.097492)
		(width 0.14224)
		(layer "In4.Cu")
		(net "P5E_CPU0_P2_TX_BUF_DN<5>")
	)
	(arc
		(start 409.343606 -398.335754)
		(mid 409.469318 -398.523711)
		(end 409.513532 -398.745456)
		(width 0.14224)
		(layer "In4.Cu")
		(net "P5E_CPU0_P2_TX_BUF_DN<5>")
	)
	(arc
		(start 409.152852 -397.87576)
		(mid 409.202455 -398.124751)
		(end 409.343606 -398.335754)
		(width 0.14224)
		(layer "In4.Cu")
		(net "P5E_CPU0_P2_TX_BUF_DN<5>")
	)
	(arc
		(start 406.790652 -404.871428)
		(mid 406.758261 -404.897964)
		(end 406.72131 -404.917656)
		(width 0.14224)
		(layer "In4.Cu")
		(net "P5E_CPU0_P2_TX_BUF_DN<5>")
	)
	(arc
		(start 409.513532 -398.92478)
		(mid 409.489503 -399.04549)
		(end 409.421076 -399.147792)
		(width 0.14224)
		(layer "In4.Cu")
		(net "P5E_CPU0_P2_TX_BUF_DN<5>")
	)
	(segment
		(start 407.698194 -397.156432)
		(end 408.218894 -397.156432)
		(width 0.127)
		(layer "F.Cu")
		(net "P5E_CPU0_P2_TX_BUF_DN<4>")
	)
	(segment
		(start 383.417572 -416.336734)
		(end 383.417572 -413.11703)
		(width 0.12954)
		(layer "F.Cu")
		(net "P5E_CPU0_P2_TX_BUF_DN<4>")
	)
	(segment
		(start 383.417572 -413.11703)
		(end 383.147062 -412.84652)
		(width 0.12954)
		(layer "F.Cu")
		(net "P5E_CPU0_P2_TX_BUF_DN<4>")
	)
	(segment
		(start 383.121662 -416.632644)
		(end 383.417572 -416.336734)
		(width 0.12954)
		(layer "F.Cu")
		(net "P5E_CPU0_P2_TX_BUF_DN<4>")
	)
	(segment
		(start 407.535634 -399.960592)
		(end 407.535634 -402.630894)
		(width 0.14224)
		(layer "In4.Cu")
		(net "P5E_CPU0_P2_TX_BUF_DN<4>")
	)
	(segment
		(start 408.07259 -398.262856)
		(end 408.274774 -398.46504)
		(width 0.14224)
		(layer "In4.Cu")
		(net "P5E_CPU0_P2_TX_BUF_DN<4>")
	)
	(segment
		(start 407.952702 -397.707104)
		(end 407.952702 -397.97355)
		(width 0.14224)
		(layer "In4.Cu")
		(net "P5E_CPU0_P2_TX_BUF_DN<4>")
	)
	(segment
		(start 383.827274 -411.51556)
		(end 383.66065 -411.682184)
		(width 0.14224)
		(layer "In4.Cu")
		(net "P5E_CPU0_P2_TX_BUF_DN<4>")
	)
	(segment
		(start 408.214068 -399.085816)
		(end 407.674318 -399.625566)
		(width 0.14224)
		(layer "In4.Cu")
		(net "P5E_CPU0_P2_TX_BUF_DN<4>")
	)
	(segment
		(start 408.313382 -398.558258)
		(end 408.313382 -398.84604)
		(width 0.14224)
		(layer "In4.Cu")
		(net "P5E_CPU0_P2_TX_BUF_DN<4>")
	)
	(segment
		(start 407.454862 -402.825712)
		(end 406.300178 -403.980396)
		(width 0.14224)
		(layer "In4.Cu")
		(net "P5E_CPU0_P2_TX_BUF_DN<4>")
	)
	(segment
		(start 405.896318 -404.250144)
		(end 404.2791 -404.919942)
		(width 0.14224)
		(layer "In4.Cu")
		(net "P5E_CPU0_P2_TX_BUF_DN<4>")
	)
	(segment
		(start 402.568156 -405.439118)
		(end 402.048218 -405.542496)
		(width 0.14224)
		(layer "In4.Cu")
		(net "P5E_CPU0_P2_TX_BUF_DN<4>")
	)
	(segment
		(start 408.271218 -397.208756)
		(end 408.271218 -397.388588)
		(width 0.14224)
		(layer "In4.Cu")
		(net "P5E_CPU0_P2_TX_BUF_DN<4>")
	)
	(segment
		(start 387.852158 -409.848558)
		(end 383.827274 -411.51556)
		(width 0.14224)
		(layer "In4.Cu")
		(net "P5E_CPU0_P2_TX_BUF_DN<4>")
	)
	(segment
		(start 404.2791 -404.919942)
		(end 402.568156 -405.439118)
		(width 0.14224)
		(layer "In4.Cu")
		(net "P5E_CPU0_P2_TX_BUF_DN<4>")
	)
	(segment
		(start 408.271218 -397.388588)
		(end 407.952702 -397.707104)
		(width 0.14224)
		(layer "In4.Cu")
		(net "P5E_CPU0_P2_TX_BUF_DN<4>")
	)
	(segment
		(start 383.437892 -412.219902)
		(end 383.437892 -412.55569)
		(width 0.14224)
		(layer "In4.Cu")
		(net "P5E_CPU0_P2_TX_BUF_DN<4>")
	)
	(segment
		(start 383.437892 -412.55569)
		(end 383.147062 -412.84652)
		(width 0.14224)
		(layer "In4.Cu")
		(net "P5E_CPU0_P2_TX_BUF_DN<4>")
	)
	(segment
		(start 402.048218 -405.542496)
		(end 387.852158 -409.848558)
		(width 0.14224)
		(layer "In4.Cu")
		(net "P5E_CPU0_P2_TX_BUF_DN<4>")
	)
	(segment
		(start 408.218894 -397.156432)
		(end 408.271218 -397.208756)
		(width 0.14224)
		(layer "In4.Cu")
		(net "P5E_CPU0_P2_TX_BUF_DN<4>")
	)
	(arc
		(start 383.66065 -411.682184)
		(mid 383.495806 -411.928891)
		(end 383.437892 -412.219902)
		(width 0.14224)
		(layer "In4.Cu")
		(net "P5E_CPU0_P2_TX_BUF_DN<4>")
	)
	(arc
		(start 408.274774 -398.46504)
		(mid 408.303351 -398.507809)
		(end 408.313382 -398.558258)
		(width 0.14224)
		(layer "In4.Cu")
		(net "P5E_CPU0_P2_TX_BUF_DN<4>")
	)
	(arc
		(start 406.300178 -403.980396)
		(mid 406.111519 -404.135133)
		(end 405.896318 -404.250144)
		(width 0.14224)
		(layer "In4.Cu")
		(net "P5E_CPU0_P2_TX_BUF_DN<4>")
	)
	(arc
		(start 407.674318 -399.625566)
		(mid 407.571665 -399.779291)
		(end 407.535634 -399.960592)
		(width 0.14224)
		(layer "In4.Cu")
		(net "P5E_CPU0_P2_TX_BUF_DN<4>")
	)
	(arc
		(start 408.313382 -398.84604)
		(mid 408.28757 -398.975804)
		(end 408.214068 -399.085816)
		(width 0.14224)
		(layer "In4.Cu")
		(net "P5E_CPU0_P2_TX_BUF_DN<4>")
	)
	(arc
		(start 407.535634 -402.630894)
		(mid 407.514641 -402.736343)
		(end 407.454862 -402.825712)
		(width 0.14224)
		(layer "In4.Cu")
		(net "P5E_CPU0_P2_TX_BUF_DN<4>")
	)
	(arc
		(start 407.952702 -397.97355)
		(mid 407.983865 -398.130128)
		(end 408.07259 -398.262856)
		(width 0.14224)
		(layer "In4.Cu")
		(net "P5E_CPU0_P2_TX_BUF_DN<4>")
	)
	(segment
		(start 406.498298 -397.156432)
		(end 407.018998 -397.156432)
		(width 0.127)
		(layer "F.Cu")
		(net "P5E_CPU0_P2_TX_BUF_DN<3>")
	)
	(segment
		(start 380.354332 -416.336734)
		(end 380.354332 -413.11703)
		(width 0.12954)
		(layer "F.Cu")
		(net "P5E_CPU0_P2_TX_BUF_DN<3>")
	)
	(segment
		(start 380.354332 -413.11703)
		(end 380.083822 -412.84652)
		(width 0.12954)
		(layer "F.Cu")
		(net "P5E_CPU0_P2_TX_BUF_DN<3>")
	)
	(segment
		(start 380.058422 -416.632644)
		(end 380.354332 -416.336734)
		(width 0.12954)
		(layer "F.Cu")
		(net "P5E_CPU0_P2_TX_BUF_DN<3>")
	)
	(segment
		(start 406.912064 -398.304258)
		(end 407.076148 -398.468342)
		(width 0.14224)
		(layer "In4.Cu")
		(net "P5E_CPU0_P2_TX_BUF_DN<3>")
	)
	(segment
		(start 407.071322 -397.208756)
		(end 407.071322 -397.388588)
		(width 0.14224)
		(layer "In4.Cu")
		(net "P5E_CPU0_P2_TX_BUF_DN<3>")
	)
	(segment
		(start 384.483102 -409.896056)
		(end 380.98222 -411.346396)
		(width 0.14224)
		(layer "In4.Cu")
		(net "P5E_CPU0_P2_TX_BUF_DN<3>")
	)
	(segment
		(start 407.113486 -398.558004)
		(end 407.113486 -398.717516)
		(width 0.14224)
		(layer "In4.Cu")
		(net "P5E_CPU0_P2_TX_BUF_DN<3>")
	)
	(segment
		(start 380.374652 -412.55569)
		(end 380.083822 -412.84652)
		(width 0.14224)
		(layer "In4.Cu")
		(net "P5E_CPU0_P2_TX_BUF_DN<3>")
	)
	(segment
		(start 402.674074 -404.429214)
		(end 402.183346 -404.527004)
		(width 0.14224)
		(layer "In4.Cu")
		(net "P5E_CPU0_P2_TX_BUF_DN<3>")
	)
	(segment
		(start 407.018998 -397.156432)
		(end 407.071322 -397.208756)
		(width 0.14224)
		(layer "In4.Cu")
		(net "P5E_CPU0_P2_TX_BUF_DN<3>")
	)
	(segment
		(start 407.001472 -398.987772)
		(end 406.512776 -399.476468)
		(width 0.14224)
		(layer "In4.Cu")
		(net "P5E_CPU0_P2_TX_BUF_DN<3>")
	)
	(segment
		(start 406.339294 -399.895314)
		(end 406.339294 -402.550884)
		(width 0.14224)
		(layer "In4.Cu")
		(net "P5E_CPU0_P2_TX_BUF_DN<3>")
	)
	(segment
		(start 403.989032 -404.030434)
		(end 402.674074 -404.429214)
		(width 0.14224)
		(layer "In4.Cu")
		(net "P5E_CPU0_P2_TX_BUF_DN<3>")
	)
	(segment
		(start 405.413718 -403.440138)
		(end 403.989032 -404.030434)
		(width 0.14224)
		(layer "In4.Cu")
		(net "P5E_CPU0_P2_TX_BUF_DN<3>")
	)
	(segment
		(start 406.301956 -402.6408)
		(end 405.681434 -403.261322)
		(width 0.14224)
		(layer "In4.Cu")
		(net "P5E_CPU0_P2_TX_BUF_DN<3>")
	)
	(segment
		(start 407.071322 -397.388588)
		(end 406.752806 -397.707104)
		(width 0.14224)
		(layer "In4.Cu")
		(net "P5E_CPU0_P2_TX_BUF_DN<3>")
	)
	(segment
		(start 406.752806 -397.707104)
		(end 406.752806 -397.919956)
		(width 0.14224)
		(layer "In4.Cu")
		(net "P5E_CPU0_P2_TX_BUF_DN<3>")
	)
	(segment
		(start 380.849378 -411.435296)
		(end 380.574804 -411.70987)
		(width 0.14224)
		(layer "In4.Cu")
		(net "P5E_CPU0_P2_TX_BUF_DN<3>")
	)
	(segment
		(start 402.183346 -404.527004)
		(end 384.483102 -409.896056)
		(width 0.14224)
		(layer "In4.Cu")
		(net "P5E_CPU0_P2_TX_BUF_DN<3>")
	)
	(segment
		(start 380.374652 -412.192978)
		(end 380.374652 -412.55569)
		(width 0.14224)
		(layer "In4.Cu")
		(net "P5E_CPU0_P2_TX_BUF_DN<3>")
	)
	(arc
		(start 406.512776 -399.476468)
		(mid 406.384373 -399.668636)
		(end 406.339294 -399.895314)
		(width 0.14224)
		(layer "In4.Cu")
		(net "P5E_CPU0_P2_TX_BUF_DN<3>")
	)
	(arc
		(start 406.339294 -402.550884)
		(mid 406.329592 -402.599568)
		(end 406.301956 -402.6408)
		(width 0.14224)
		(layer "In4.Cu")
		(net "P5E_CPU0_P2_TX_BUF_DN<3>")
	)
	(arc
		(start 380.574804 -411.70987)
		(mid 380.426647 -411.931508)
		(end 380.374652 -412.192978)
		(width 0.14224)
		(layer "In4.Cu")
		(net "P5E_CPU0_P2_TX_BUF_DN<3>")
	)
	(arc
		(start 407.076148 -398.468342)
		(mid 407.103718 -398.509464)
		(end 407.113486 -398.558004)
		(width 0.14224)
		(layer "In4.Cu")
		(net "P5E_CPU0_P2_TX_BUF_DN<3>")
	)
	(arc
		(start 407.113486 -398.717516)
		(mid 407.084372 -398.86379)
		(end 407.001472 -398.987772)
		(width 0.14224)
		(layer "In4.Cu")
		(net "P5E_CPU0_P2_TX_BUF_DN<3>")
	)
	(arc
		(start 406.752806 -397.919956)
		(mid 406.794197 -398.127953)
		(end 406.912064 -398.304258)
		(width 0.14224)
		(layer "In4.Cu")
		(net "P5E_CPU0_P2_TX_BUF_DN<3>")
	)
	(arc
		(start 405.681434 -403.261322)
		(mid 405.55638 -403.36391)
		(end 405.413718 -403.440138)
		(width 0.14224)
		(layer "In4.Cu")
		(net "P5E_CPU0_P2_TX_BUF_DN<3>")
	)
	(arc
		(start 380.98222 -411.346396)
		(mid 380.911408 -411.384288)
		(end 380.849378 -411.435296)
		(width 0.14224)
		(layer "In4.Cu")
		(net "P5E_CPU0_P2_TX_BUF_DN<3>")
	)
	(segment
		(start 376.995182 -416.632644)
		(end 377.291092 -416.336734)
		(width 0.12954)
		(layer "F.Cu")
		(net "P5E_CPU0_P2_TX_BUF_DN<2>")
	)
	(segment
		(start 377.291092 -413.11703)
		(end 377.020582 -412.84652)
		(width 0.12954)
		(layer "F.Cu")
		(net "P5E_CPU0_P2_TX_BUF_DN<2>")
	)
	(segment
		(start 377.291092 -416.336734)
		(end 377.291092 -413.11703)
		(width 0.12954)
		(layer "F.Cu")
		(net "P5E_CPU0_P2_TX_BUF_DN<2>")
	)
	(segment
		(start 405.298402 -397.156432)
		(end 405.819102 -397.156432)
		(width 0.127)
		(layer "F.Cu")
		(net "P5E_CPU0_P2_TX_BUF_DN<2>")
	)
	(segment
		(start 377.311412 -412.272226)
		(end 377.311412 -412.55569)
		(width 0.14224)
		(layer "In4.Cu")
		(net "P5E_CPU0_P2_TX_BUF_DN<2>")
	)
	(segment
		(start 405.823166 -397.464788)
		(end 405.684736 -397.603218)
		(width 0.14224)
		(layer "In4.Cu")
		(net "P5E_CPU0_P2_TX_BUF_DN<2>")
	)
	(segment
		(start 405.819102 -397.156432)
		(end 405.87041 -397.20774)
		(width 0.14224)
		(layer "In4.Cu")
		(net "P5E_CPU0_P2_TX_BUF_DN<2>")
	)
	(segment
		(start 377.716034 -411.53588)
		(end 377.545854 -411.70606)
		(width 0.14224)
		(layer "In4.Cu")
		(net "P5E_CPU0_P2_TX_BUF_DN<2>")
	)
	(segment
		(start 403.977348 -403.02434)
		(end 402.860764 -403.362922)
		(width 0.14224)
		(layer "In4.Cu")
		(net "P5E_CPU0_P2_TX_BUF_DN<2>")
	)
	(segment
		(start 382.478534 -409.529788)
		(end 377.848876 -411.447234)
		(width 0.14224)
		(layer "In4.Cu")
		(net "P5E_CPU0_P2_TX_BUF_DN<2>")
	)
	(segment
		(start 404.896828 -402.644356)
		(end 403.977348 -403.02434)
		(width 0.14224)
		(layer "In4.Cu")
		(net "P5E_CPU0_P2_TX_BUF_DN<2>")
	)
	(segment
		(start 405.826468 -398.47139)
		(end 405.826468 -398.67713)
		(width 0.14224)
		(layer "In4.Cu")
		(net "P5E_CPU0_P2_TX_BUF_DN<2>")
	)
	(segment
		(start 405.143716 -400.151092)
		(end 405.143716 -402.27504)
		(width 0.14224)
		(layer "In4.Cu")
		(net "P5E_CPU0_P2_TX_BUF_DN<2>")
	)
	(segment
		(start 405.87041 -397.20774)
		(end 405.87041 -397.350742)
		(width 0.14224)
		(layer "In4.Cu")
		(net "P5E_CPU0_P2_TX_BUF_DN<2>")
	)
	(segment
		(start 402.860764 -403.362922)
		(end 402.70684 -403.393656)
		(width 0.14224)
		(layer "In4.Cu")
		(net "P5E_CPU0_P2_TX_BUF_DN<2>")
	)
	(segment
		(start 402.70684 -403.393656)
		(end 382.478534 -409.529788)
		(width 0.14224)
		(layer "In4.Cu")
		(net "P5E_CPU0_P2_TX_BUF_DN<2>")
	)
	(segment
		(start 405.684228 -398.26819)
		(end 405.783542 -398.367758)
		(width 0.14224)
		(layer "In4.Cu")
		(net "P5E_CPU0_P2_TX_BUF_DN<2>")
	)
	(segment
		(start 377.311412 -412.55569)
		(end 377.020582 -412.84652)
		(width 0.14224)
		(layer "In4.Cu")
		(net "P5E_CPU0_P2_TX_BUF_DN<2>")
	)
	(segment
		(start 405.704294 -398.972278)
		(end 405.581104 -399.095468)
		(width 0.14224)
		(layer "In4.Cu")
		(net "P5E_CPU0_P2_TX_BUF_DN<2>")
	)
	(segment
		(start 405.826468 -398.67713)
		(end 405.826214 -398.67713)
		(width 0.14224)
		(layer "In4.Cu")
		(net "P5E_CPU0_P2_TX_BUF_DN<2>")
	)
	(arc
		(start 405.684736 -397.603218)
		(mid 405.546613 -397.935599)
		(end 405.684228 -398.26819)
		(width 0.14224)
		(layer "In4.Cu")
		(net "P5E_CPU0_P2_TX_BUF_DN<2>")
	)
	(arc
		(start 405.143716 -402.27504)
		(mid 405.076298 -402.497137)
		(end 404.896828 -402.644356)
		(width 0.14224)
		(layer "In4.Cu")
		(net "P5E_CPU0_P2_TX_BUF_DN<2>")
	)
	(arc
		(start 405.581104 -399.095468)
		(mid 405.257406 -399.579777)
		(end 405.143716 -400.151092)
		(width 0.14224)
		(layer "In4.Cu")
		(net "P5E_CPU0_P2_TX_BUF_DN<2>")
	)
	(arc
		(start 405.87041 -397.350742)
		(mid 405.858133 -397.412465)
		(end 405.823166 -397.464788)
		(width 0.14224)
		(layer "In4.Cu")
		(net "P5E_CPU0_P2_TX_BUF_DN<2>")
	)
	(arc
		(start 377.545854 -411.70606)
		(mid 377.372342 -411.965833)
		(end 377.311412 -412.272226)
		(width 0.14224)
		(layer "In4.Cu")
		(net "P5E_CPU0_P2_TX_BUF_DN<2>")
	)
	(arc
		(start 405.826214 -398.67713)
		(mid 405.794633 -398.836842)
		(end 405.704294 -398.972278)
		(width 0.14224)
		(layer "In4.Cu")
		(net "P5E_CPU0_P2_TX_BUF_DN<2>")
	)
	(arc
		(start 405.783542 -398.367758)
		(mid 405.815312 -398.415305)
		(end 405.826468 -398.47139)
		(width 0.14224)
		(layer "In4.Cu")
		(net "P5E_CPU0_P2_TX_BUF_DN<2>")
	)
	(arc
		(start 377.848876 -411.447234)
		(mid 377.778098 -411.485026)
		(end 377.716034 -411.53588)
		(width 0.14224)
		(layer "In4.Cu")
		(net "P5E_CPU0_P2_TX_BUF_DN<2>")
	)
	(segment
		(start 373.931942 -416.632644)
		(end 374.227852 -416.336734)
		(width 0.12954)
		(layer "F.Cu")
		(net "P5E_CPU0_P2_TX_BUF_DN<1>")
	)
	(segment
		(start 374.227852 -416.336734)
		(end 374.227852 -413.11703)
		(width 0.12954)
		(layer "F.Cu")
		(net "P5E_CPU0_P2_TX_BUF_DN<1>")
	)
	(segment
		(start 374.227852 -413.11703)
		(end 373.957342 -412.84652)
		(width 0.12954)
		(layer "F.Cu")
		(net "P5E_CPU0_P2_TX_BUF_DN<1>")
	)
	(segment
		(start 404.098252 -397.156432)
		(end 404.618952 -397.156432)
		(width 0.127)
		(layer "F.Cu")
		(net "P5E_CPU0_P2_TX_BUF_DN<1>")
	)
	(segment
		(start 404.482554 -398.266666)
		(end 404.659846 -398.443958)
		(width 0.14224)
		(layer "In4.Cu")
		(net "P5E_CPU0_P2_TX_BUF_DN<1>")
	)
	(segment
		(start 402.238972 -401.8788)
		(end 401.340828 -402.372576)
		(width 0.14224)
		(layer "In4.Cu")
		(net "P5E_CPU0_P2_TX_BUF_DN<1>")
	)
	(segment
		(start 400.485356 -403.092666)
		(end 378.601986 -409.731464)
		(width 0.14224)
		(layer "In4.Cu")
		(net "P5E_CPU0_P2_TX_BUF_DN<1>")
	)
	(segment
		(start 374.248172 -411.927548)
		(end 374.248172 -412.55569)
		(width 0.14224)
		(layer "In4.Cu")
		(net "P5E_CPU0_P2_TX_BUF_DN<1>")
	)
	(segment
		(start 374.248172 -412.55569)
		(end 373.957342 -412.84652)
		(width 0.14224)
		(layer "In4.Cu")
		(net "P5E_CPU0_P2_TX_BUF_DN<1>")
	)
	(segment
		(start 404.671276 -397.388588)
		(end 404.35276 -397.707104)
		(width 0.14224)
		(layer "In4.Cu")
		(net "P5E_CPU0_P2_TX_BUF_DN<1>")
	)
	(segment
		(start 404.671276 -397.208756)
		(end 404.671276 -397.388588)
		(width 0.14224)
		(layer "In4.Cu")
		(net "P5E_CPU0_P2_TX_BUF_DN<1>")
	)
	(segment
		(start 404.6601 -398.735296)
		(end 404.086568 -399.309336)
		(width 0.14224)
		(layer "In4.Cu")
		(net "P5E_CPU0_P2_TX_BUF_DN<1>")
	)
	(segment
		(start 403.087332 -399.53311)
		(end 402.923502 -399.69694)
		(width 0.14224)
		(layer "In4.Cu")
		(net "P5E_CPU0_P2_TX_BUF_DN<1>")
	)
	(segment
		(start 402.6662 -400.31797)
		(end 402.6662 -401.156424)
		(width 0.14224)
		(layer "In4.Cu")
		(net "P5E_CPU0_P2_TX_BUF_DN<1>")
	)
	(segment
		(start 404.618952 -397.156432)
		(end 404.671276 -397.208756)
		(width 0.14224)
		(layer "In4.Cu")
		(net "P5E_CPU0_P2_TX_BUF_DN<1>")
	)
	(segment
		(start 401.340828 -402.372576)
		(end 400.822922 -402.890482)
		(width 0.14224)
		(layer "In4.Cu")
		(net "P5E_CPU0_P2_TX_BUF_DN<1>")
	)
	(segment
		(start 378.601986 -409.731464)
		(end 374.491504 -411.55366)
		(width 0.14224)
		(layer "In4.Cu")
		(net "P5E_CPU0_P2_TX_BUF_DN<1>")
	)
	(segment
		(start 404.35276 -397.707104)
		(end 404.35276 -397.95323)
		(width 0.14224)
		(layer "In4.Cu")
		(net "P5E_CPU0_P2_TX_BUF_DN<1>")
	)
	(segment
		(start 403.859238 -399.386044)
		(end 403.442424 -399.386044)
		(width 0.14224)
		(layer "In4.Cu")
		(net "P5E_CPU0_P2_TX_BUF_DN<1>")
	)
	(arc
		(start 403.442424 -399.386044)
		(mid 403.250256 -399.424269)
		(end 403.087332 -399.53311)
		(width 0.14224)
		(layer "In4.Cu")
		(net "P5E_CPU0_P2_TX_BUF_DN<1>")
	)
	(arc
		(start 403.976332 -399.37182)
		(mid 403.918217 -399.382492)
		(end 403.859238 -399.386044)
		(width 0.14224)
		(layer "In4.Cu")
		(net "P5E_CPU0_P2_TX_BUF_DN<1>")
	)
	(arc
		(start 404.659846 -398.443958)
		(mid 404.720311 -398.589574)
		(end 404.6601 -398.735296)
		(width 0.14224)
		(layer "In4.Cu")
		(net "P5E_CPU0_P2_TX_BUF_DN<1>")
	)
	(arc
		(start 402.6662 -401.156424)
		(mid 402.551391 -401.576039)
		(end 402.238972 -401.8788)
		(width 0.14224)
		(layer "In4.Cu")
		(net "P5E_CPU0_P2_TX_BUF_DN<1>")
	)
	(arc
		(start 404.086568 -399.309336)
		(mid 404.035709 -399.348083)
		(end 403.976332 -399.37182)
		(width 0.14224)
		(layer "In4.Cu")
		(net "P5E_CPU0_P2_TX_BUF_DN<1>")
	)
	(arc
		(start 402.923502 -399.69694)
		(mid 402.733063 -399.981857)
		(end 402.6662 -400.31797)
		(width 0.14224)
		(layer "In4.Cu")
		(net "P5E_CPU0_P2_TX_BUF_DN<1>")
	)
	(arc
		(start 374.491504 -411.55366)
		(mid 374.314374 -411.704504)
		(end 374.248172 -411.927548)
		(width 0.14224)
		(layer "In4.Cu")
		(net "P5E_CPU0_P2_TX_BUF_DN<1>")
	)
	(arc
		(start 400.822922 -402.890482)
		(mid 400.6666 -403.012378)
		(end 400.485356 -403.092666)
		(width 0.14224)
		(layer "In4.Cu")
		(net "P5E_CPU0_P2_TX_BUF_DN<1>")
	)
	(arc
		(start 404.35276 -397.95323)
		(mid 404.386499 -398.122847)
		(end 404.482554 -398.266666)
		(width 0.14224)
		(layer "In4.Cu")
		(net "P5E_CPU0_P2_TX_BUF_DN<1>")
	)
	(segment
		(start 417.113212 -413.11703)
		(end 416.842702 -412.84652)
		(width 0.12954)
		(layer "F.Cu")
		(net "P5E_CPU0_P2_TX_BUF_DN<15>")
	)
	(segment
		(start 420.89832 -397.156432)
		(end 421.41902 -397.156432)
		(width 0.127)
		(layer "F.Cu")
		(net "P5E_CPU0_P2_TX_BUF_DN<15>")
	)
	(segment
		(start 416.817302 -416.632644)
		(end 417.113212 -416.336734)
		(width 0.12954)
		(layer "F.Cu")
		(net "P5E_CPU0_P2_TX_BUF_DN<15>")
	)
	(segment
		(start 417.113212 -416.336734)
		(end 417.113212 -413.11703)
		(width 0.12954)
		(layer "F.Cu")
		(net "P5E_CPU0_P2_TX_BUF_DN<15>")
	)
	(segment
		(start 417.133532 -412.55569)
		(end 416.842702 -412.84652)
		(width 0.14224)
		(layer "In4.Cu")
		(net "P5E_CPU0_P2_TX_BUF_DN<15>")
	)
	(segment
		(start 421.152828 -397.707104)
		(end 421.152828 -397.974566)
		(width 0.14224)
		(layer "In4.Cu")
		(net "P5E_CPU0_P2_TX_BUF_DN<15>")
	)
	(segment
		(start 421.41902 -397.156432)
		(end 421.471344 -397.208756)
		(width 0.14224)
		(layer "In4.Cu")
		(net "P5E_CPU0_P2_TX_BUF_DN<15>")
	)
	(segment
		(start 421.513508 -398.558512)
		(end 421.513508 -398.967198)
		(width 0.14224)
		(layer "In4.Cu")
		(net "P5E_CPU0_P2_TX_BUF_DN<15>")
	)
	(segment
		(start 417.133532 -412.31312)
		(end 417.133532 -412.55569)
		(width 0.14224)
		(layer "In4.Cu")
		(net "P5E_CPU0_P2_TX_BUF_DN<15>")
	)
	(segment
		(start 421.471344 -397.208756)
		(end 421.471344 -397.388588)
		(width 0.14224)
		(layer "In4.Cu")
		(net "P5E_CPU0_P2_TX_BUF_DN<15>")
	)
	(segment
		(start 420.74846 -400.102832)
		(end 420.74846 -403.305264)
		(width 0.14224)
		(layer "In4.Cu")
		(net "P5E_CPU0_P2_TX_BUF_DN<15>")
	)
	(segment
		(start 421.381682 -399.285714)
		(end 420.878254 -399.789142)
		(width 0.14224)
		(layer "In4.Cu")
		(net "P5E_CPU0_P2_TX_BUF_DN<15>")
	)
	(segment
		(start 420.576248 -404.700232)
		(end 420.43477 -405.265636)
		(width 0.14224)
		(layer "In4.Cu")
		(net "P5E_CPU0_P2_TX_BUF_DN<15>")
	)
	(segment
		(start 421.471344 -397.388588)
		(end 421.152828 -397.707104)
		(width 0.14224)
		(layer "In4.Cu")
		(net "P5E_CPU0_P2_TX_BUF_DN<15>")
	)
	(segment
		(start 421.272716 -398.263872)
		(end 421.475408 -398.466564)
		(width 0.14224)
		(layer "In4.Cu")
		(net "P5E_CPU0_P2_TX_BUF_DN<15>")
	)
	(segment
		(start 419.836854 -406.815798)
		(end 417.340796 -411.48508)
		(width 0.14224)
		(layer "In4.Cu")
		(net "P5E_CPU0_P2_TX_BUF_DN<15>")
	)
	(arc
		(start 421.513508 -398.967198)
		(mid 421.479228 -399.139536)
		(end 421.381682 -399.285714)
		(width 0.14224)
		(layer "In4.Cu")
		(net "P5E_CPU0_P2_TX_BUF_DN<15>")
	)
	(arc
		(start 421.475408 -398.466564)
		(mid 421.503596 -398.50875)
		(end 421.513508 -398.558512)
		(width 0.14224)
		(layer "In4.Cu")
		(net "P5E_CPU0_P2_TX_BUF_DN<15>")
	)
	(arc
		(start 417.340796 -411.48508)
		(mid 417.186149 -411.886327)
		(end 417.133532 -412.31312)
		(width 0.14224)
		(layer "In4.Cu")
		(net "P5E_CPU0_P2_TX_BUF_DN<15>")
	)
	(arc
		(start 420.74846 -403.305264)
		(mid 420.705216 -404.00804)
		(end 420.576248 -404.700232)
		(width 0.14224)
		(layer "In4.Cu")
		(net "P5E_CPU0_P2_TX_BUF_DN<15>")
	)
	(arc
		(start 421.152828 -397.974566)
		(mid 421.183991 -398.131144)
		(end 421.272716 -398.263872)
		(width 0.14224)
		(layer "In4.Cu")
		(net "P5E_CPU0_P2_TX_BUF_DN<15>")
	)
	(arc
		(start 420.43477 -405.265636)
		(mid 420.183445 -406.05909)
		(end 419.836854 -406.815798)
		(width 0.14224)
		(layer "In4.Cu")
		(net "P5E_CPU0_P2_TX_BUF_DN<15>")
	)
	(arc
		(start 420.878254 -399.789142)
		(mid 420.782118 -399.933065)
		(end 420.74846 -400.102832)
		(width 0.14224)
		(layer "In4.Cu")
		(net "P5E_CPU0_P2_TX_BUF_DN<15>")
	)
	(segment
		(start 414.049972 -413.11703)
		(end 413.779462 -412.84652)
		(width 0.12954)
		(layer "F.Cu")
		(net "P5E_CPU0_P2_TX_BUF_DN<14>")
	)
	(segment
		(start 419.698424 -397.156432)
		(end 420.219124 -397.156432)
		(width 0.127)
		(layer "F.Cu")
		(net "P5E_CPU0_P2_TX_BUF_DN<14>")
	)
	(segment
		(start 414.049972 -416.336734)
		(end 414.049972 -413.11703)
		(width 0.12954)
		(layer "F.Cu")
		(net "P5E_CPU0_P2_TX_BUF_DN<14>")
	)
	(segment
		(start 413.754062 -416.632644)
		(end 414.049972 -416.336734)
		(width 0.12954)
		(layer "F.Cu")
		(net "P5E_CPU0_P2_TX_BUF_DN<14>")
	)
	(segment
		(start 414.070292 -412.55569)
		(end 413.779462 -412.84652)
		(width 0.14224)
		(layer "In4.Cu")
		(net "P5E_CPU0_P2_TX_BUF_DN<14>")
	)
	(segment
		(start 420.342568 -398.653762)
		(end 420.342568 -398.886172)
		(width 0.14224)
		(layer "In4.Cu")
		(net "P5E_CPU0_P2_TX_BUF_DN<14>")
	)
	(segment
		(start 415.275522 -409.77693)
		(end 414.202118 -411.383226)
		(width 0.14224)
		(layer "In4.Cu")
		(net "P5E_CPU0_P2_TX_BUF_DN<14>")
	)
	(segment
		(start 420.219124 -397.156432)
		(end 420.271448 -397.208756)
		(width 0.14224)
		(layer "In4.Cu")
		(net "P5E_CPU0_P2_TX_BUF_DN<14>")
	)
	(segment
		(start 414.070292 -411.818074)
		(end 414.070292 -412.55569)
		(width 0.14224)
		(layer "In4.Cu")
		(net "P5E_CPU0_P2_TX_BUF_DN<14>")
	)
	(segment
		(start 420.187882 -399.259298)
		(end 419.756844 -399.690082)
		(width 0.14224)
		(layer "In4.Cu")
		(net "P5E_CPU0_P2_TX_BUF_DN<14>")
	)
	(segment
		(start 419.070536 -405.152352)
		(end 415.275522 -409.77693)
		(width 0.14224)
		(layer "In4.Cu")
		(net "P5E_CPU0_P2_TX_BUF_DN<14>")
	)
	(segment
		(start 419.952932 -397.707104)
		(end 419.952932 -397.965422)
		(width 0.14224)
		(layer "In4.Cu")
		(net "P5E_CPU0_P2_TX_BUF_DN<14>")
	)
	(segment
		(start 419.54831 -400.19351)
		(end 419.54831 -403.817836)
		(width 0.14224)
		(layer "In4.Cu")
		(net "P5E_CPU0_P2_TX_BUF_DN<14>")
	)
	(segment
		(start 420.271448 -397.388588)
		(end 419.952932 -397.707104)
		(width 0.14224)
		(layer "In4.Cu")
		(net "P5E_CPU0_P2_TX_BUF_DN<14>")
	)
	(segment
		(start 420.07282 -398.254728)
		(end 420.250874 -398.432782)
		(width 0.14224)
		(layer "In4.Cu")
		(net "P5E_CPU0_P2_TX_BUF_DN<14>")
	)
	(segment
		(start 420.271448 -397.208756)
		(end 420.271448 -397.388588)
		(width 0.14224)
		(layer "In4.Cu")
		(net "P5E_CPU0_P2_TX_BUF_DN<14>")
	)
	(arc
		(start 419.54831 -403.817836)
		(mid 419.425173 -404.52653)
		(end 419.070536 -405.152352)
		(width 0.14224)
		(layer "In4.Cu")
		(net "P5E_CPU0_P2_TX_BUF_DN<14>")
	)
	(arc
		(start 420.250874 -398.432782)
		(mid 420.318672 -398.534154)
		(end 420.342568 -398.653762)
		(width 0.14224)
		(layer "In4.Cu")
		(net "P5E_CPU0_P2_TX_BUF_DN<14>")
	)
	(arc
		(start 420.342568 -398.886172)
		(mid 420.302429 -399.088168)
		(end 420.187882 -399.259298)
		(width 0.14224)
		(layer "In4.Cu")
		(net "P5E_CPU0_P2_TX_BUF_DN<14>")
	)
	(arc
		(start 414.202118 -411.383226)
		(mid 414.103968 -411.590878)
		(end 414.070292 -411.818074)
		(width 0.14224)
		(layer "In4.Cu")
		(net "P5E_CPU0_P2_TX_BUF_DN<14>")
	)
	(arc
		(start 419.952932 -397.965422)
		(mid 419.984095 -398.122)
		(end 420.07282 -398.254728)
		(width 0.14224)
		(layer "In4.Cu")
		(net "P5E_CPU0_P2_TX_BUF_DN<14>")
	)
	(arc
		(start 419.756844 -399.690082)
		(mid 419.602512 -399.921057)
		(end 419.54831 -400.19351)
		(width 0.14224)
		(layer "In4.Cu")
		(net "P5E_CPU0_P2_TX_BUF_DN<14>")
	)
	(segment
		(start 410.986732 -416.336734)
		(end 410.986732 -413.11703)
		(width 0.12954)
		(layer "F.Cu")
		(net "P5E_CPU0_P2_TX_BUF_DN<13>")
	)
	(segment
		(start 410.690822 -416.632644)
		(end 410.986732 -416.336734)
		(width 0.12954)
		(layer "F.Cu")
		(net "P5E_CPU0_P2_TX_BUF_DN<13>")
	)
	(segment
		(start 410.986732 -413.11703)
		(end 410.716222 -412.84652)
		(width 0.12954)
		(layer "F.Cu")
		(net "P5E_CPU0_P2_TX_BUF_DN<13>")
	)
	(segment
		(start 418.498274 -397.156432)
		(end 419.018974 -397.156432)
		(width 0.127)
		(layer "F.Cu")
		(net "P5E_CPU0_P2_TX_BUF_DN<13>")
	)
	(segment
		(start 419.071298 -397.388588)
		(end 418.752782 -397.707104)
		(width 0.14224)
		(layer "In4.Cu")
		(net "P5E_CPU0_P2_TX_BUF_DN<13>")
	)
	(segment
		(start 411.007052 -412.172912)
		(end 411.007052 -412.55569)
		(width 0.14224)
		(layer "In4.Cu")
		(net "P5E_CPU0_P2_TX_BUF_DN<13>")
	)
	(segment
		(start 411.007052 -412.55569)
		(end 410.716222 -412.84652)
		(width 0.14224)
		(layer "In4.Cu")
		(net "P5E_CPU0_P2_TX_BUF_DN<13>")
	)
	(segment
		(start 419.002464 -399.247868)
		(end 418.480748 -399.769838)
		(width 0.14224)
		(layer "In4.Cu")
		(net "P5E_CPU0_P2_TX_BUF_DN<13>")
	)
	(segment
		(start 418.752782 -397.707104)
		(end 418.752782 -397.886936)
		(width 0.14224)
		(layer "In4.Cu")
		(net "P5E_CPU0_P2_TX_BUF_DN<13>")
	)
	(segment
		(start 419.018974 -397.156432)
		(end 419.071298 -397.208756)
		(width 0.14224)
		(layer "In4.Cu")
		(net "P5E_CPU0_P2_TX_BUF_DN<13>")
	)
	(segment
		(start 419.071298 -397.208756)
		(end 419.071298 -397.388588)
		(width 0.14224)
		(layer "In4.Cu")
		(net "P5E_CPU0_P2_TX_BUF_DN<13>")
	)
	(segment
		(start 418.103812 -404.621492)
		(end 411.328616 -411.396688)
		(width 0.14224)
		(layer "In4.Cu")
		(net "P5E_CPU0_P2_TX_BUF_DN<13>")
	)
	(segment
		(start 418.348414 -400.08937)
		(end 418.348414 -404.030942)
		(width 0.14224)
		(layer "In4.Cu")
		(net "P5E_CPU0_P2_TX_BUF_DN<13>")
	)
	(segment
		(start 419.113462 -398.764252)
		(end 419.113462 -398.946878)
		(width 0.14224)
		(layer "In4.Cu")
		(net "P5E_CPU0_P2_TX_BUF_DN<13>")
	)
	(arc
		(start 411.328616 -411.396688)
		(mid 411.090601 -411.752808)
		(end 411.007052 -412.172912)
		(width 0.14224)
		(layer "In4.Cu")
		(net "P5E_CPU0_P2_TX_BUF_DN<13>")
	)
	(arc
		(start 419.073584 -399.142966)
		(mid 419.043064 -399.198835)
		(end 419.002464 -399.247868)
		(width 0.14224)
		(layer "In4.Cu")
		(net "P5E_CPU0_P2_TX_BUF_DN<13>")
	)
	(arc
		(start 418.348414 -404.030942)
		(mid 418.284842 -404.350541)
		(end 418.103812 -404.621492)
		(width 0.14224)
		(layer "In4.Cu")
		(net "P5E_CPU0_P2_TX_BUF_DN<13>")
	)
	(arc
		(start 418.933122 -398.325594)
		(mid 419.066637 -398.527106)
		(end 419.113462 -398.764252)
		(width 0.14224)
		(layer "In4.Cu")
		(net "P5E_CPU0_P2_TX_BUF_DN<13>")
	)
	(arc
		(start 418.752782 -397.886936)
		(mid 418.799632 -398.124072)
		(end 418.933122 -398.325594)
		(width 0.14224)
		(layer "In4.Cu")
		(net "P5E_CPU0_P2_TX_BUF_DN<13>")
	)
	(arc
		(start 418.480748 -399.769838)
		(mid 418.382791 -399.916441)
		(end 418.348414 -400.08937)
		(width 0.14224)
		(layer "In4.Cu")
		(net "P5E_CPU0_P2_TX_BUF_DN<13>")
	)
	(arc
		(start 419.113462 -398.946878)
		(mid 419.103438 -399.046938)
		(end 419.073584 -399.142966)
		(width 0.14224)
		(layer "In4.Cu")
		(net "P5E_CPU0_P2_TX_BUF_DN<13>")
	)
	(segment
		(start 407.923492 -416.336734)
		(end 407.923492 -413.11703)
		(width 0.12954)
		(layer "F.Cu")
		(net "P5E_CPU0_P2_TX_BUF_DN<12>")
	)
	(segment
		(start 407.627582 -416.632644)
		(end 407.923492 -416.336734)
		(width 0.12954)
		(layer "F.Cu")
		(net "P5E_CPU0_P2_TX_BUF_DN<12>")
	)
	(segment
		(start 407.923492 -413.11703)
		(end 407.652982 -412.84652)
		(width 0.12954)
		(layer "F.Cu")
		(net "P5E_CPU0_P2_TX_BUF_DN<12>")
	)
	(segment
		(start 417.298378 -397.156432)
		(end 417.819078 -397.156432)
		(width 0.127)
		(layer "F.Cu")
		(net "P5E_CPU0_P2_TX_BUF_DN<12>")
	)
	(segment
		(start 417.871402 -397.388588)
		(end 417.871402 -397.208756)
		(width 0.14224)
		(layer "In4.Cu")
		(net "P5E_CPU0_P2_TX_BUF_DN<12>")
	)
	(segment
		(start 407.943812 -412.55569)
		(end 407.943812 -412.127192)
		(width 0.14224)
		(layer "In4.Cu")
		(net "P5E_CPU0_P2_TX_BUF_DN<12>")
	)
	(segment
		(start 410.373068 -410.639006)
		(end 410.840936 -410.438346)
		(width 0.14224)
		(layer "In4.Cu")
		(net "P5E_CPU0_P2_TX_BUF_DN<12>")
	)
	(segment
		(start 410.372814 -410.63926)
		(end 410.373068 -410.639006)
		(width 0.14224)
		(layer "In4.Cu")
		(net "P5E_CPU0_P2_TX_BUF_DN<12>")
	)
	(segment
		(start 417.552886 -397.903954)
		(end 417.552886 -397.707104)
		(width 0.14224)
		(layer "In4.Cu")
		(net "P5E_CPU0_P2_TX_BUF_DN<12>")
	)
	(segment
		(start 408.091386 -411.771084)
		(end 408.358086 -411.504384)
		(width 0.14224)
		(layer "In4.Cu")
		(net "P5E_CPU0_P2_TX_BUF_DN<12>")
	)
	(segment
		(start 417.871402 -397.208756)
		(end 417.819078 -397.156432)
		(width 0.14224)
		(layer "In4.Cu")
		(net "P5E_CPU0_P2_TX_BUF_DN<12>")
	)
	(segment
		(start 417.864036 -398.445736)
		(end 417.716462 -398.298416)
		(width 0.14224)
		(layer "In4.Cu")
		(net "P5E_CPU0_P2_TX_BUF_DN<12>")
	)
	(segment
		(start 408.358086 -411.504384)
		(end 410.372814 -410.63926)
		(width 0.14224)
		(layer "In4.Cu")
		(net "P5E_CPU0_P2_TX_BUF_DN<12>")
	)
	(segment
		(start 411.056074 -410.29255)
		(end 417.038282 -404.310342)
		(width 0.14224)
		(layer "In4.Cu")
		(net "P5E_CPU0_P2_TX_BUF_DN<12>")
	)
	(segment
		(start 407.652982 -412.84652)
		(end 407.943812 -412.55569)
		(width 0.14224)
		(layer "In4.Cu")
		(net "P5E_CPU0_P2_TX_BUF_DN<12>")
	)
	(segment
		(start 417.901374 -398.936718)
		(end 417.901374 -398.535652)
		(width 0.14224)
		(layer "In4.Cu")
		(net "P5E_CPU0_P2_TX_BUF_DN<12>")
	)
	(segment
		(start 417.552886 -397.707104)
		(end 417.871402 -397.388588)
		(width 0.14224)
		(layer "In4.Cu")
		(net "P5E_CPU0_P2_TX_BUF_DN<12>")
	)
	(segment
		(start 417.148264 -404.045166)
		(end 417.148264 -400.066002)
		(width 0.14224)
		(layer "In4.Cu")
		(net "P5E_CPU0_P2_TX_BUF_DN<12>")
	)
	(segment
		(start 417.278058 -399.752312)
		(end 417.76523 -399.26514)
		(width 0.14224)
		(layer "In4.Cu")
		(net "P5E_CPU0_P2_TX_BUF_DN<12>")
	)
	(arc
		(start 417.148264 -400.066002)
		(mid 417.181954 -399.896249)
		(end 417.278058 -399.752312)
		(width 0.14224)
		(layer "In4.Cu")
		(net "P5E_CPU0_P2_TX_BUF_DN<12>")
	)
	(arc
		(start 417.76523 -399.26514)
		(mid 417.865966 -399.114473)
		(end 417.901374 -398.936718)
		(width 0.14224)
		(layer "In4.Cu")
		(net "P5E_CPU0_P2_TX_BUF_DN<12>")
	)
	(arc
		(start 410.840936 -410.438346)
		(mid 410.955445 -410.37569)
		(end 411.056074 -410.29255)
		(width 0.14224)
		(layer "In4.Cu")
		(net "P5E_CPU0_P2_TX_BUF_DN<12>")
	)
	(arc
		(start 407.943812 -412.127192)
		(mid 407.982168 -411.934455)
		(end 408.091386 -411.771084)
		(width 0.14224)
		(layer "In4.Cu")
		(net "P5E_CPU0_P2_TX_BUF_DN<12>")
	)
	(arc
		(start 417.716462 -398.298416)
		(mid 417.595427 -398.117464)
		(end 417.552886 -397.903954)
		(width 0.14224)
		(layer "In4.Cu")
		(net "P5E_CPU0_P2_TX_BUF_DN<12>")
	)
	(arc
		(start 417.038282 -404.310342)
		(mid 417.119683 -404.188707)
		(end 417.148264 -404.045166)
		(width 0.14224)
		(layer "In4.Cu")
		(net "P5E_CPU0_P2_TX_BUF_DN<12>")
	)
	(arc
		(start 417.901374 -398.535652)
		(mid 417.891672 -398.486968)
		(end 417.864036 -398.445736)
		(width 0.14224)
		(layer "In4.Cu")
		(net "P5E_CPU0_P2_TX_BUF_DN<12>")
	)
	(segment
		(start 404.860252 -413.11703)
		(end 404.589742 -412.84652)
		(width 0.12954)
		(layer "F.Cu")
		(net "P5E_CPU0_P2_TX_BUF_DN<11>")
	)
	(segment
		(start 404.564342 -416.632644)
		(end 404.860252 -416.336734)
		(width 0.12954)
		(layer "F.Cu")
		(net "P5E_CPU0_P2_TX_BUF_DN<11>")
	)
	(segment
		(start 416.098228 -397.156432)
		(end 416.618928 -397.156432)
		(width 0.127)
		(layer "F.Cu")
		(net "P5E_CPU0_P2_TX_BUF_DN<11>")
	)
	(segment
		(start 404.860252 -416.336734)
		(end 404.860252 -413.11703)
		(width 0.12954)
		(layer "F.Cu")
		(net "P5E_CPU0_P2_TX_BUF_DN<11>")
	)
	(segment
		(start 415.644076 -404.313136)
		(end 411.49016 -408.467052)
		(width 0.14224)
		(layer "In4.Cu")
		(net "P5E_CPU0_P2_TX_BUF_DN<11>")
	)
	(segment
		(start 416.352736 -397.707104)
		(end 416.352736 -397.926814)
		(width 0.14224)
		(layer "In4.Cu")
		(net "P5E_CPU0_P2_TX_BUF_DN<11>")
	)
	(segment
		(start 416.5092 -399.304764)
		(end 416.078162 -399.735802)
		(width 0.14224)
		(layer "In4.Cu")
		(net "P5E_CPU0_P2_TX_BUF_DN<11>")
	)
	(segment
		(start 416.507168 -398.299432)
		(end 416.676078 -398.468342)
		(width 0.14224)
		(layer "In4.Cu")
		(net "P5E_CPU0_P2_TX_BUF_DN<11>")
	)
	(segment
		(start 416.671252 -397.388588)
		(end 416.352736 -397.707104)
		(width 0.14224)
		(layer "In4.Cu")
		(net "P5E_CPU0_P2_TX_BUF_DN<11>")
	)
	(segment
		(start 416.671252 -397.208756)
		(end 416.671252 -397.388588)
		(width 0.14224)
		(layer "In4.Cu")
		(net "P5E_CPU0_P2_TX_BUF_DN<11>")
	)
	(segment
		(start 416.713416 -398.558512)
		(end 416.713416 -398.812004)
		(width 0.14224)
		(layer "In4.Cu")
		(net "P5E_CPU0_P2_TX_BUF_DN<11>")
	)
	(segment
		(start 404.880572 -412.55569)
		(end 404.589742 -412.84652)
		(width 0.14224)
		(layer "In4.Cu")
		(net "P5E_CPU0_P2_TX_BUF_DN<11>")
	)
	(segment
		(start 416.618928 -397.156432)
		(end 416.671252 -397.208756)
		(width 0.14224)
		(layer "In4.Cu")
		(net "P5E_CPU0_P2_TX_BUF_DN<11>")
	)
	(segment
		(start 409.376118 -409.879546)
		(end 405.218646 -411.601412)
		(width 0.14224)
		(layer "In4.Cu")
		(net "P5E_CPU0_P2_TX_BUF_DN<11>")
	)
	(segment
		(start 404.880572 -412.233872)
		(end 404.880572 -412.55569)
		(width 0.14224)
		(layer "In4.Cu")
		(net "P5E_CPU0_P2_TX_BUF_DN<11>")
	)
	(segment
		(start 405.218646 -411.601412)
		(end 405.088852 -411.731206)
		(width 0.14224)
		(layer "In4.Cu")
		(net "P5E_CPU0_P2_TX_BUF_DN<11>")
	)
	(segment
		(start 415.948368 -400.049492)
		(end 415.948368 -403.578822)
		(width 0.14224)
		(layer "In4.Cu")
		(net "P5E_CPU0_P2_TX_BUF_DN<11>")
	)
	(arc
		(start 415.948368 -403.578822)
		(mid 415.869279 -403.976251)
		(end 415.644076 -404.313136)
		(width 0.14224)
		(layer "In4.Cu")
		(net "P5E_CPU0_P2_TX_BUF_DN<11>")
	)
	(arc
		(start 416.352736 -397.926814)
		(mid 416.39287 -398.128493)
		(end 416.507168 -398.299432)
		(width 0.14224)
		(layer "In4.Cu")
		(net "P5E_CPU0_P2_TX_BUF_DN<11>")
	)
	(arc
		(start 416.713416 -398.812004)
		(mid 416.660347 -399.078711)
		(end 416.5092 -399.304764)
		(width 0.14224)
		(layer "In4.Cu")
		(net "P5E_CPU0_P2_TX_BUF_DN<11>")
	)
	(arc
		(start 416.078162 -399.735802)
		(mid 415.982026 -399.879725)
		(end 415.948368 -400.049492)
		(width 0.14224)
		(layer "In4.Cu")
		(net "P5E_CPU0_P2_TX_BUF_DN<11>")
	)
	(arc
		(start 411.49016 -408.467052)
		(mid 410.50272 -409.277442)
		(end 409.376118 -409.879546)
		(width 0.14224)
		(layer "In4.Cu")
		(net "P5E_CPU0_P2_TX_BUF_DN<11>")
	)
	(arc
		(start 416.676078 -398.468342)
		(mid 416.703721 -398.509712)
		(end 416.713416 -398.558512)
		(width 0.14224)
		(layer "In4.Cu")
		(net "P5E_CPU0_P2_TX_BUF_DN<11>")
	)
	(arc
		(start 405.088852 -411.731206)
		(mid 404.9347 -411.961817)
		(end 404.880572 -412.233872)
		(width 0.14224)
		(layer "In4.Cu")
		(net "P5E_CPU0_P2_TX_BUF_DN<11>")
	)
	(segment
		(start 414.898332 -397.156432)
		(end 415.419032 -397.156432)
		(width 0.127)
		(layer "F.Cu")
		(net "P5E_CPU0_P2_TX_BUF_DN<10>")
	)
	(segment
		(start 401.797012 -413.11703)
		(end 401.526502 -412.84652)
		(width 0.12954)
		(layer "F.Cu")
		(net "P5E_CPU0_P2_TX_BUF_DN<10>")
	)
	(segment
		(start 401.797012 -416.336734)
		(end 401.797012 -413.11703)
		(width 0.12954)
		(layer "F.Cu")
		(net "P5E_CPU0_P2_TX_BUF_DN<10>")
	)
	(segment
		(start 401.501102 -416.632644)
		(end 401.797012 -416.336734)
		(width 0.12954)
		(layer "F.Cu")
		(net "P5E_CPU0_P2_TX_BUF_DN<10>")
	)
	(segment
		(start 415.419032 -397.156432)
		(end 415.471356 -397.208756)
		(width 0.14224)
		(layer "In4.Cu")
		(net "P5E_CPU0_P2_TX_BUF_DN<10>")
	)
	(segment
		(start 401.817332 -412.1658)
		(end 401.817332 -412.55569)
		(width 0.14224)
		(layer "In4.Cu")
		(net "P5E_CPU0_P2_TX_BUF_DN<10>")
	)
	(segment
		(start 415.471356 -397.388588)
		(end 415.15284 -397.707104)
		(width 0.14224)
		(layer "In4.Cu")
		(net "P5E_CPU0_P2_TX_BUF_DN<10>")
	)
	(segment
		(start 415.301684 -399.313908)
		(end 414.812226 -399.803366)
		(width 0.14224)
		(layer "In4.Cu")
		(net "P5E_CPU0_P2_TX_BUF_DN<10>")
	)
	(segment
		(start 415.51352 -398.558258)
		(end 415.51352 -398.802606)
		(width 0.14224)
		(layer "In4.Cu")
		(net "P5E_CPU0_P2_TX_BUF_DN<10>")
	)
	(segment
		(start 415.15284 -397.707104)
		(end 415.15284 -397.97355)
		(width 0.14224)
		(layer "In4.Cu")
		(net "P5E_CPU0_P2_TX_BUF_DN<10>")
	)
	(segment
		(start 415.471356 -397.208756)
		(end 415.471356 -397.388588)
		(width 0.14224)
		(layer "In4.Cu")
		(net "P5E_CPU0_P2_TX_BUF_DN<10>")
	)
	(segment
		(start 401.817332 -412.55569)
		(end 401.526502 -412.84652)
		(width 0.14224)
		(layer "In4.Cu")
		(net "P5E_CPU0_P2_TX_BUF_DN<10>")
	)
	(segment
		(start 408.802586 -409.10764)
		(end 405.23541 -410.585158)
		(width 0.14224)
		(layer "In4.Cu")
		(net "P5E_CPU0_P2_TX_BUF_DN<10>")
	)
	(segment
		(start 405.23541 -410.585158)
		(end 402.273262 -411.483556)
		(width 0.14224)
		(layer "In4.Cu")
		(net "P5E_CPU0_P2_TX_BUF_DN<10>")
	)
	(segment
		(start 414.682432 -400.117056)
		(end 414.682432 -403.84476)
		(width 0.14224)
		(layer "In4.Cu")
		(net "P5E_CPU0_P2_TX_BUF_DN<10>")
	)
	(segment
		(start 414.645094 -403.934676)
		(end 410.820108 -407.759662)
		(width 0.14224)
		(layer "In4.Cu")
		(net "P5E_CPU0_P2_TX_BUF_DN<10>")
	)
	(segment
		(start 415.272728 -398.262856)
		(end 415.474912 -398.46504)
		(width 0.14224)
		(layer "In4.Cu")
		(net "P5E_CPU0_P2_TX_BUF_DN<10>")
	)
	(segment
		(start 402.273262 -411.483556)
		(end 401.977352 -411.779466)
		(width 0.14224)
		(layer "In4.Cu")
		(net "P5E_CPU0_P2_TX_BUF_DN<10>")
	)
	(arc
		(start 414.812226 -399.803366)
		(mid 414.71609 -399.947289)
		(end 414.682432 -400.117056)
		(width 0.14224)
		(layer "In4.Cu")
		(net "P5E_CPU0_P2_TX_BUF_DN<10>")
	)
	(arc
		(start 415.15284 -397.97355)
		(mid 415.184003 -398.130128)
		(end 415.272728 -398.262856)
		(width 0.14224)
		(layer "In4.Cu")
		(net "P5E_CPU0_P2_TX_BUF_DN<10>")
	)
	(arc
		(start 415.51352 -398.802606)
		(mid 415.458459 -399.079325)
		(end 415.301684 -399.313908)
		(width 0.14224)
		(layer "In4.Cu")
		(net "P5E_CPU0_P2_TX_BUF_DN<10>")
	)
	(arc
		(start 401.977352 -411.779466)
		(mid 401.858916 -411.956718)
		(end 401.817332 -412.1658)
		(width 0.14224)
		(layer "In4.Cu")
		(net "P5E_CPU0_P2_TX_BUF_DN<10>")
	)
	(arc
		(start 410.820108 -407.759662)
		(mid 409.877728 -408.533003)
		(end 408.802586 -409.10764)
		(width 0.14224)
		(layer "In4.Cu")
		(net "P5E_CPU0_P2_TX_BUF_DN<10>")
	)
	(arc
		(start 414.682432 -403.84476)
		(mid 414.67273 -403.893444)
		(end 414.645094 -403.934676)
		(width 0.14224)
		(layer "In4.Cu")
		(net "P5E_CPU0_P2_TX_BUF_DN<10>")
	)
	(arc
		(start 415.474912 -398.46504)
		(mid 415.503489 -398.507809)
		(end 415.51352 -398.558258)
		(width 0.14224)
		(layer "In4.Cu")
		(net "P5E_CPU0_P2_TX_BUF_DN<10>")
	)
	(segment
		(start 371.063012 -414.073848)
		(end 371.063012 -413.725614)
		(width 0.12954)
		(layer "F.Cu")
		(net "P5E_CPU0_P2_TX_BUF_DN<0>")
	)
	(segment
		(start 370.767102 -414.369758)
		(end 371.063012 -414.073848)
		(width 0.12954)
		(layer "F.Cu")
		(net "P5E_CPU0_P2_TX_BUF_DN<0>")
	)
	(segment
		(start 371.164612 -413.11703)
		(end 370.894102 -412.84652)
		(width 0.12954)
		(layer "F.Cu")
		(net "P5E_CPU0_P2_TX_BUF_DN<0>")
	)
	(segment
		(start 402.898356 -397.156432)
		(end 403.419056 -397.156432)
		(width 0.127)
		(layer "F.Cu")
		(net "P5E_CPU0_P2_TX_BUF_DN<0>")
	)
	(segment
		(start 371.164612 -413.48025)
		(end 371.164612 -413.11703)
		(width 0.12954)
		(layer "F.Cu")
		(net "P5E_CPU0_P2_TX_BUF_DN<0>")
	)
	(segment
		(start 371.063012 -413.725614)
		(end 371.164612 -413.48025)
		(width 0.12954)
		(layer "F.Cu")
		(net "P5E_CPU0_P2_TX_BUF_DN<0>")
	)
	(segment
		(start 403.419056 -397.156432)
		(end 403.464522 -397.201898)
		(width 0.14224)
		(layer "In4.Cu")
		(net "P5E_CPU0_P2_TX_BUF_DN<0>")
	)
	(segment
		(start 401.22475 -400.606514)
		(end 401.22475 -401.0025)
		(width 0.14224)
		(layer "In4.Cu")
		(net "P5E_CPU0_P2_TX_BUF_DN<0>")
	)
	(segment
		(start 375.047764 -409.835096)
		(end 371.42801 -411.439868)
		(width 0.14224)
		(layer "In4.Cu")
		(net "P5E_CPU0_P2_TX_BUF_DN<0>")
	)
	(segment
		(start 402.005038 -398.620488)
		(end 401.265644 -400.406362)
		(width 0.14224)
		(layer "In4.Cu")
		(net "P5E_CPU0_P2_TX_BUF_DN<0>")
	)
	(segment
		(start 371.184932 -412.55569)
		(end 370.894102 -412.84652)
		(width 0.14224)
		(layer "In4.Cu")
		(net "P5E_CPU0_P2_TX_BUF_DN<0>")
	)
	(segment
		(start 399.831052 -402.316696)
		(end 375.047764 -409.835096)
		(width 0.14224)
		(layer "In4.Cu")
		(net "P5E_CPU0_P2_TX_BUF_DN<0>")
	)
	(segment
		(start 403.464522 -397.201898)
		(end 403.464522 -397.381984)
		(width 0.14224)
		(layer "In4.Cu")
		(net "P5E_CPU0_P2_TX_BUF_DN<0>")
	)
	(segment
		(start 401.140676 -401.205192)
		(end 400.325082 -402.020786)
		(width 0.14224)
		(layer "In4.Cu")
		(net "P5E_CPU0_P2_TX_BUF_DN<0>")
	)
	(segment
		(start 371.184932 -411.81401)
		(end 371.184932 -412.55569)
		(width 0.14224)
		(layer "In4.Cu")
		(net "P5E_CPU0_P2_TX_BUF_DN<0>")
	)
	(segment
		(start 403.464522 -397.381984)
		(end 403.12594 -397.720566)
		(width 0.14224)
		(layer "In4.Cu")
		(net "P5E_CPU0_P2_TX_BUF_DN<0>")
	)
	(segment
		(start 402.473668 -398.015968)
		(end 402.27885 -398.210786)
		(width 0.14224)
		(layer "In4.Cu")
		(net "P5E_CPU0_P2_TX_BUF_DN<0>")
	)
	(arc
		(start 403.12594 -397.720566)
		(mid 403.059505 -397.766484)
		(end 402.98116 -397.786098)
		(width 0.14224)
		(layer "In4.Cu")
		(net "P5E_CPU0_P2_TX_BUF_DN<0>")
	)
	(arc
		(start 402.27885 -398.210786)
		(mid 402.121789 -398.402164)
		(end 402.005038 -398.620488)
		(width 0.14224)
		(layer "In4.Cu")
		(net "P5E_CPU0_P2_TX_BUF_DN<0>")
	)
	(arc
		(start 401.265644 -400.406362)
		(mid 401.235667 -400.504491)
		(end 401.22475 -400.606514)
		(width 0.14224)
		(layer "In4.Cu")
		(net "P5E_CPU0_P2_TX_BUF_DN<0>")
	)
	(arc
		(start 401.22475 -401.0025)
		(mid 401.202838 -401.112187)
		(end 401.140676 -401.205192)
		(width 0.14224)
		(layer "In4.Cu")
		(net "P5E_CPU0_P2_TX_BUF_DN<0>")
	)
	(arc
		(start 402.98116 -397.786098)
		(mid 402.706461 -397.854777)
		(end 402.473668 -398.015968)
		(width 0.14224)
		(layer "In4.Cu")
		(net "P5E_CPU0_P2_TX_BUF_DN<0>")
	)
	(arc
		(start 371.42801 -411.439868)
		(mid 371.251019 -411.590901)
		(end 371.184932 -411.81401)
		(width 0.14224)
		(layer "In4.Cu")
		(net "P5E_CPU0_P2_TX_BUF_DN<0>")
	)
	(arc
		(start 400.325082 -402.020786)
		(mid 400.096318 -402.199217)
		(end 399.831052 -402.316696)
		(width 0.14224)
		(layer "In4.Cu")
		(net "P5E_CPU0_P2_TX_BUF_DN<0>")
	)
	(segment
		(start 399.056352 -417.461954)
		(end 399.056352 -420.681658)
		(width 0.12954)
		(layer "F.Cu")
		(net "P5E_CPU0_P2_TX_BUF_C_DP<9>")
	)
	(segment
		(start 399.056352 -420.681658)
		(end 399.326862 -420.952168)
		(width 0.12954)
		(layer "F.Cu")
		(net "P5E_CPU0_P2_TX_BUF_C_DP<9>")
	)
	(segment
		(start 399.352262 -417.166044)
		(end 399.056352 -417.461954)
		(width 0.12954)
		(layer "F.Cu")
		(net "P5E_CPU0_P2_TX_BUF_C_DP<9>")
	)
	(segment
		(start 399.69059 -424.021758)
		(end 400.086068 -425.32681)
		(width 0.14224)
		(layer "In11.Cu")
		(net "P5E_CPU0_P2_TX_BUF_C_DP<9>")
	)
	(segment
		(start 399.330926 -422.362376)
		(end 399.454878 -422.771062)
		(width 0.14224)
		(layer "In11.Cu")
		(net "P5E_CPU0_P2_TX_BUF_C_DP<9>")
	)
	(segment
		(start 399.15973 -422.270936)
		(end 399.330926 -422.362376)
		(width 0.14224)
		(layer "In11.Cu")
		(net "P5E_CPU0_P2_TX_BUF_C_DP<9>")
	)
	(segment
		(start 400.750024 -431.006758)
		(end 400.750024 -430.689766)
		(width 0.14224)
		(layer "In11.Cu")
		(net "P5E_CPU0_P2_TX_BUF_C_DP<9>")
	)
	(segment
		(start 400.177 -431.052732)
		(end 400.235928 -431.11166)
		(width 0.14224)
		(layer "In11.Cu")
		(net "P5E_CPU0_P2_TX_BUF_C_DP<9>")
	)
	(segment
		(start 399.484596 -423.349166)
		(end 399.658078 -423.441876)
		(width 0.14224)
		(layer "In11.Cu")
		(net "P5E_CPU0_P2_TX_BUF_C_DP<9>")
	)
	(segment
		(start 399.78203 -423.850562)
		(end 399.69059 -424.021758)
		(width 0.14224)
		(layer "In11.Cu")
		(net "P5E_CPU0_P2_TX_BUF_C_DP<9>")
	)
	(segment
		(start 399.454878 -422.771062)
		(end 399.361914 -422.944544)
		(width 0.14224)
		(layer "In11.Cu")
		(net "P5E_CPU0_P2_TX_BUF_C_DP<9>")
	)
	(segment
		(start 399.036032 -421.862758)
		(end 399.15973 -422.270936)
		(width 0.14224)
		(layer "In11.Cu")
		(net "P5E_CPU0_P2_TX_BUF_C_DP<9>")
	)
	(segment
		(start 399.361914 -422.944544)
		(end 399.484596 -423.349166)
		(width 0.14224)
		(layer "In11.Cu")
		(net "P5E_CPU0_P2_TX_BUF_C_DP<9>")
	)
	(segment
		(start 399.326862 -420.952168)
		(end 399.036032 -421.242998)
		(width 0.14224)
		(layer "In11.Cu")
		(net "P5E_CPU0_P2_TX_BUF_C_DP<9>")
	)
	(segment
		(start 400.086068 -425.32681)
		(end 400.086068 -430.833276)
		(width 0.14224)
		(layer "In11.Cu")
		(net "P5E_CPU0_P2_TX_BUF_C_DP<9>")
	)
	(segment
		(start 400.607784 -431.148998)
		(end 400.750024 -431.006758)
		(width 0.14224)
		(layer "In11.Cu")
		(net "P5E_CPU0_P2_TX_BUF_C_DP<9>")
	)
	(segment
		(start 399.036032 -421.242998)
		(end 399.036032 -421.862758)
		(width 0.14224)
		(layer "In11.Cu")
		(net "P5E_CPU0_P2_TX_BUF_C_DP<9>")
	)
	(segment
		(start 399.658078 -423.441876)
		(end 399.78203 -423.850562)
		(width 0.14224)
		(layer "In11.Cu")
		(net "P5E_CPU0_P2_TX_BUF_C_DP<9>")
	)
	(segment
		(start 400.325844 -431.148998)
		(end 400.607784 -431.148998)
		(width 0.14224)
		(layer "In11.Cu")
		(net "P5E_CPU0_P2_TX_BUF_C_DP<9>")
	)
	(arc
		(start 400.235928 -431.11166)
		(mid 400.277168 -431.139279)
		(end 400.325844 -431.148998)
		(width 0.14224)
		(layer "In11.Cu")
		(net "P5E_CPU0_P2_TX_BUF_C_DP<9>")
	)
	(arc
		(start 400.086068 -430.833276)
		(mid 400.109695 -430.952056)
		(end 400.177 -431.052732)
		(width 0.14224)
		(layer "In11.Cu")
		(net "P5E_CPU0_P2_TX_BUF_C_DP<9>")
	)
	(segment
		(start 395.993112 -417.461954)
		(end 395.993112 -420.681658)
		(width 0.12954)
		(layer "F.Cu")
		(net "P5E_CPU0_P2_TX_BUF_C_DP<8>")
	)
	(segment
		(start 395.993112 -420.681658)
		(end 396.263622 -420.952168)
		(width 0.12954)
		(layer "F.Cu")
		(net "P5E_CPU0_P2_TX_BUF_C_DP<8>")
	)
	(segment
		(start 396.289022 -417.166044)
		(end 395.993112 -417.461954)
		(width 0.12954)
		(layer "F.Cu")
		(net "P5E_CPU0_P2_TX_BUF_C_DP<8>")
	)
	(segment
		(start 397.773906 -425.647104)
		(end 397.699484 -425.826428)
		(width 0.14224)
		(layer "In11.Cu")
		(net "P5E_CPU0_P2_TX_BUF_C_DP<8>")
	)
	(segment
		(start 397.925798 -426.372528)
		(end 397.925798 -429.60036)
		(width 0.14224)
		(layer "In11.Cu")
		(net "P5E_CPU0_P2_TX_BUF_C_DP<8>")
	)
	(segment
		(start 397.342106 -424.604942)
		(end 397.267938 -424.784266)
		(width 0.14224)
		(layer "In11.Cu")
		(net "P5E_CPU0_P2_TX_BUF_C_DP<8>")
	)
	(segment
		(start 396.263622 -420.952168)
		(end 395.972792 -421.242998)
		(width 0.14224)
		(layer "In11.Cu")
		(net "P5E_CPU0_P2_TX_BUF_C_DP<8>")
	)
	(segment
		(start 397.267938 -424.784266)
		(end 397.431006 -425.178474)
		(width 0.14224)
		(layer "In11.Cu")
		(net "P5E_CPU0_P2_TX_BUF_C_DP<8>")
	)
	(segment
		(start 396.315438 -422.126156)
		(end 396.47876 -422.520618)
		(width 0.14224)
		(layer "In11.Cu")
		(net "P5E_CPU0_P2_TX_BUF_C_DP<8>")
	)
	(segment
		(start 396.136876 -422.052242)
		(end 396.315438 -422.126156)
		(width 0.14224)
		(layer "In11.Cu")
		(net "P5E_CPU0_P2_TX_BUF_C_DP<8>")
	)
	(segment
		(start 397.001492 -424.137328)
		(end 397.178784 -424.21048)
		(width 0.14224)
		(layer "In11.Cu")
		(net "P5E_CPU0_P2_TX_BUF_C_DP<8>")
	)
	(segment
		(start 398.750028 -430.00676)
		(end 398.750028 -429.689768)
		(width 0.14224)
		(layer "In11.Cu")
		(net "P5E_CPU0_P2_TX_BUF_C_DP<8>")
	)
	(segment
		(start 398.607788 -430.149)
		(end 398.750028 -430.00676)
		(width 0.14224)
		(layer "In11.Cu")
		(net "P5E_CPU0_P2_TX_BUF_C_DP<8>")
	)
	(segment
		(start 395.972792 -421.655494)
		(end 396.136876 -422.052242)
		(width 0.14224)
		(layer "In11.Cu")
		(net "P5E_CPU0_P2_TX_BUF_C_DP<8>")
	)
	(segment
		(start 395.972792 -421.242998)
		(end 395.972792 -421.655494)
		(width 0.14224)
		(layer "In11.Cu")
		(net "P5E_CPU0_P2_TX_BUF_C_DP<8>")
	)
	(segment
		(start 398.458944 -430.149)
		(end 398.607788 -430.149)
		(width 0.14224)
		(layer "In11.Cu")
		(net "P5E_CPU0_P2_TX_BUF_C_DP<8>")
	)
	(segment
		(start 397.699484 -425.826428)
		(end 397.925798 -426.372528)
		(width 0.14224)
		(layer "In11.Cu")
		(net "P5E_CPU0_P2_TX_BUF_C_DP<8>")
	)
	(segment
		(start 396.747238 -423.168318)
		(end 396.91056 -423.56278)
		(width 0.14224)
		(layer "In11.Cu")
		(net "P5E_CPU0_P2_TX_BUF_C_DP<8>")
	)
	(segment
		(start 397.178784 -424.21048)
		(end 397.342106 -424.604942)
		(width 0.14224)
		(layer "In11.Cu")
		(net "P5E_CPU0_P2_TX_BUF_C_DP<8>")
	)
	(segment
		(start 396.404592 -422.699942)
		(end 396.56766 -423.09415)
		(width 0.14224)
		(layer "In11.Cu")
		(net "P5E_CPU0_P2_TX_BUF_C_DP<8>")
	)
	(segment
		(start 396.837154 -423.739818)
		(end 397.001492 -424.137328)
		(width 0.14224)
		(layer "In11.Cu")
		(net "P5E_CPU0_P2_TX_BUF_C_DP<8>")
	)
	(segment
		(start 396.56766 -423.09415)
		(end 396.747238 -423.168318)
		(width 0.14224)
		(layer "In11.Cu")
		(net "P5E_CPU0_P2_TX_BUF_C_DP<8>")
	)
	(segment
		(start 397.610584 -425.252642)
		(end 397.773906 -425.647104)
		(width 0.14224)
		(layer "In11.Cu")
		(net "P5E_CPU0_P2_TX_BUF_C_DP<8>")
	)
	(segment
		(start 397.431006 -425.178474)
		(end 397.610584 -425.252642)
		(width 0.14224)
		(layer "In11.Cu")
		(net "P5E_CPU0_P2_TX_BUF_C_DP<8>")
	)
	(segment
		(start 396.91056 -423.56278)
		(end 396.837154 -423.739818)
		(width 0.14224)
		(layer "In11.Cu")
		(net "P5E_CPU0_P2_TX_BUF_C_DP<8>")
	)
	(segment
		(start 396.47876 -422.520618)
		(end 396.404592 -422.699942)
		(width 0.14224)
		(layer "In11.Cu")
		(net "P5E_CPU0_P2_TX_BUF_C_DP<8>")
	)
	(segment
		(start 398.068038 -429.943768)
		(end 398.141952 -430.017682)
		(width 0.14224)
		(layer "In11.Cu")
		(net "P5E_CPU0_P2_TX_BUF_C_DP<8>")
	)
	(arc
		(start 398.141952 -430.017682)
		(mid 398.287389 -430.11486)
		(end 398.458944 -430.149)
		(width 0.14224)
		(layer "In11.Cu")
		(net "P5E_CPU0_P2_TX_BUF_C_DP<8>")
	)
	(arc
		(start 397.925798 -429.60036)
		(mid 397.962766 -429.786209)
		(end 398.068038 -429.943768)
		(width 0.14224)
		(layer "In11.Cu")
		(net "P5E_CPU0_P2_TX_BUF_C_DP<8>")
	)
	(segment
		(start 393.225782 -417.166044)
		(end 392.929872 -417.461954)
		(width 0.12954)
		(layer "F.Cu")
		(net "P5E_CPU0_P2_TX_BUF_C_DP<7>")
	)
	(segment
		(start 392.929872 -420.681658)
		(end 393.200382 -420.952168)
		(width 0.12954)
		(layer "F.Cu")
		(net "P5E_CPU0_P2_TX_BUF_C_DP<7>")
	)
	(segment
		(start 392.929872 -417.461954)
		(end 392.929872 -420.681658)
		(width 0.12954)
		(layer "F.Cu")
		(net "P5E_CPU0_P2_TX_BUF_C_DP<7>")
	)
	(segment
		(start 395.069314 -424.987466)
		(end 394.394182 -423.977562)
		(width 0.14224)
		(layer "In11.Cu")
		(net "P5E_CPU0_P2_TX_BUF_C_DP<7>")
	)
	(segment
		(start 394.394182 -423.977562)
		(end 394.394182 -423.977054)
		(width 0.14224)
		(layer "In11.Cu")
		(net "P5E_CPU0_P2_TX_BUF_C_DP<7>")
	)
	(segment
		(start 395.60754 -431.148998)
		(end 395.273022 -431.148998)
		(width 0.14224)
		(layer "In11.Cu")
		(net "P5E_CPU0_P2_TX_BUF_C_DP<7>")
	)
	(segment
		(start 394.1572 -423.62247)
		(end 394.194284 -423.435526)
		(width 0.14224)
		(layer "In11.Cu")
		(net "P5E_CPU0_P2_TX_BUF_C_DP<7>")
	)
	(segment
		(start 394.194284 -423.435526)
		(end 393.957048 -423.080688)
		(width 0.14224)
		(layer "In11.Cu")
		(net "P5E_CPU0_P2_TX_BUF_C_DP<7>")
	)
	(segment
		(start 393.770358 -423.04335)
		(end 393.533376 -422.688766)
		(width 0.14224)
		(layer "In11.Cu")
		(net "P5E_CPU0_P2_TX_BUF_C_DP<7>")
	)
	(segment
		(start 395.069314 -430.94529)
		(end 395.069314 -424.987466)
		(width 0.14224)
		(layer "In11.Cu")
		(net "P5E_CPU0_P2_TX_BUF_C_DP<7>")
	)
	(segment
		(start 393.146534 -422.109646)
		(end 392.909552 -421.755062)
		(width 0.14224)
		(layer "In11.Cu")
		(net "P5E_CPU0_P2_TX_BUF_C_DP<7>")
	)
	(segment
		(start 394.394182 -423.977054)
		(end 394.1572 -423.62247)
		(width 0.14224)
		(layer "In11.Cu")
		(net "P5E_CPU0_P2_TX_BUF_C_DP<7>")
	)
	(segment
		(start 395.74978 -430.689766)
		(end 395.74978 -431.006758)
		(width 0.14224)
		(layer "In11.Cu")
		(net "P5E_CPU0_P2_TX_BUF_C_DP<7>")
	)
	(segment
		(start 395.273022 -431.148998)
		(end 395.069314 -430.94529)
		(width 0.14224)
		(layer "In11.Cu")
		(net "P5E_CPU0_P2_TX_BUF_C_DP<7>")
	)
	(segment
		(start 393.333224 -422.146984)
		(end 393.146534 -422.109646)
		(width 0.14224)
		(layer "In11.Cu")
		(net "P5E_CPU0_P2_TX_BUF_C_DP<7>")
	)
	(segment
		(start 393.57046 -422.501822)
		(end 393.333224 -422.146984)
		(width 0.14224)
		(layer "In11.Cu")
		(net "P5E_CPU0_P2_TX_BUF_C_DP<7>")
	)
	(segment
		(start 393.533376 -422.688766)
		(end 393.57046 -422.501822)
		(width 0.14224)
		(layer "In11.Cu")
		(net "P5E_CPU0_P2_TX_BUF_C_DP<7>")
	)
	(segment
		(start 392.909552 -421.755062)
		(end 392.909552 -421.242998)
		(width 0.14224)
		(layer "In11.Cu")
		(net "P5E_CPU0_P2_TX_BUF_C_DP<7>")
	)
	(segment
		(start 392.909552 -421.242998)
		(end 393.200382 -420.952168)
		(width 0.14224)
		(layer "In11.Cu")
		(net "P5E_CPU0_P2_TX_BUF_C_DP<7>")
	)
	(segment
		(start 395.74978 -431.006758)
		(end 395.60754 -431.148998)
		(width 0.14224)
		(layer "In11.Cu")
		(net "P5E_CPU0_P2_TX_BUF_C_DP<7>")
	)
	(segment
		(start 393.957048 -423.080688)
		(end 393.770358 -423.04335)
		(width 0.14224)
		(layer "In11.Cu")
		(net "P5E_CPU0_P2_TX_BUF_C_DP<7>")
	)
	(segment
		(start 390.162542 -417.166044)
		(end 389.866632 -417.461954)
		(width 0.12954)
		(layer "F.Cu")
		(net "P5E_CPU0_P2_TX_BUF_C_DP<6>")
	)
	(segment
		(start 389.866632 -420.681658)
		(end 390.137142 -420.952168)
		(width 0.12954)
		(layer "F.Cu")
		(net "P5E_CPU0_P2_TX_BUF_C_DP<6>")
	)
	(segment
		(start 389.866632 -417.461954)
		(end 389.866632 -420.681658)
		(width 0.12954)
		(layer "F.Cu")
		(net "P5E_CPU0_P2_TX_BUF_C_DP<6>")
	)
	(segment
		(start 392.254486 -423.411142)
		(end 392.609578 -423.648378)
		(width 0.14224)
		(layer "In11.Cu")
		(net "P5E_CPU0_P2_TX_BUF_C_DP<6>")
	)
	(segment
		(start 392.067796 -423.448226)
		(end 392.254486 -423.411142)
		(width 0.14224)
		(layer "In11.Cu")
		(net "P5E_CPU0_P2_TX_BUF_C_DP<6>")
	)
	(segment
		(start 393.47902 -430.16297)
		(end 393.59332 -430.16297)
		(width 0.14224)
		(layer "In11.Cu")
		(net "P5E_CPU0_P2_TX_BUF_C_DP<6>")
	)
	(segment
		(start 389.86206 -421.97401)
		(end 390.200896 -422.200578)
		(width 0.14224)
		(layer "In11.Cu")
		(net "P5E_CPU0_P2_TX_BUF_C_DP<6>")
	)
	(segment
		(start 393.080748 -424.28922)
		(end 393.080748 -429.787558)
		(width 0.14224)
		(layer "In11.Cu")
		(net "P5E_CPU0_P2_TX_BUF_C_DP<6>")
	)
	(segment
		(start 391.134346 -422.824402)
		(end 391.321036 -422.787318)
		(width 0.14224)
		(layer "In11.Cu")
		(net "P5E_CPU0_P2_TX_BUF_C_DP<6>")
	)
	(segment
		(start 389.846312 -421.945054)
		(end 389.86206 -421.97401)
		(width 0.14224)
		(layer "In11.Cu")
		(net "P5E_CPU0_P2_TX_BUF_C_DP<6>")
	)
	(segment
		(start 393.167108 -429.996092)
		(end 393.23137 -430.060354)
		(width 0.14224)
		(layer "In11.Cu")
		(net "P5E_CPU0_P2_TX_BUF_C_DP<6>")
	)
	(segment
		(start 390.779762 -422.58742)
		(end 391.134346 -422.824402)
		(width 0.14224)
		(layer "In11.Cu")
		(net "P5E_CPU0_P2_TX_BUF_C_DP<6>")
	)
	(segment
		(start 389.846312 -421.242998)
		(end 389.846312 -421.945054)
		(width 0.14224)
		(layer "In11.Cu")
		(net "P5E_CPU0_P2_TX_BUF_C_DP<6>")
	)
	(segment
		(start 391.321036 -422.787318)
		(end 391.676128 -423.024554)
		(width 0.14224)
		(layer "In11.Cu")
		(net "P5E_CPU0_P2_TX_BUF_C_DP<6>")
	)
	(segment
		(start 392.609578 -423.648378)
		(end 392.646662 -423.835068)
		(width 0.14224)
		(layer "In11.Cu")
		(net "P5E_CPU0_P2_TX_BUF_C_DP<6>")
	)
	(segment
		(start 391.713212 -423.211244)
		(end 392.067796 -423.448226)
		(width 0.14224)
		(layer "In11.Cu")
		(net "P5E_CPU0_P2_TX_BUF_C_DP<6>")
	)
	(segment
		(start 393.749784 -430.006506)
		(end 393.749784 -429.689768)
		(width 0.14224)
		(layer "In11.Cu")
		(net "P5E_CPU0_P2_TX_BUF_C_DP<6>")
	)
	(segment
		(start 391.676128 -423.024554)
		(end 391.713212 -423.211244)
		(width 0.14224)
		(layer "In11.Cu")
		(net "P5E_CPU0_P2_TX_BUF_C_DP<6>")
	)
	(segment
		(start 392.646662 -423.835068)
		(end 392.94435 -424.03395)
		(width 0.14224)
		(layer "In11.Cu")
		(net "P5E_CPU0_P2_TX_BUF_C_DP<6>")
	)
	(segment
		(start 390.137142 -420.952168)
		(end 389.846312 -421.242998)
		(width 0.14224)
		(layer "In11.Cu")
		(net "P5E_CPU0_P2_TX_BUF_C_DP<6>")
	)
	(segment
		(start 390.387586 -422.163494)
		(end 390.742678 -422.40073)
		(width 0.14224)
		(layer "In11.Cu")
		(net "P5E_CPU0_P2_TX_BUF_C_DP<6>")
	)
	(segment
		(start 392.94435 -424.03395)
		(end 393.080748 -424.28922)
		(width 0.14224)
		(layer "In11.Cu")
		(net "P5E_CPU0_P2_TX_BUF_C_DP<6>")
	)
	(segment
		(start 390.200896 -422.200578)
		(end 390.387586 -422.163494)
		(width 0.14224)
		(layer "In11.Cu")
		(net "P5E_CPU0_P2_TX_BUF_C_DP<6>")
	)
	(segment
		(start 393.59332 -430.16297)
		(end 393.749784 -430.006506)
		(width 0.14224)
		(layer "In11.Cu")
		(net "P5E_CPU0_P2_TX_BUF_C_DP<6>")
	)
	(segment
		(start 390.742678 -422.40073)
		(end 390.779762 -422.58742)
		(width 0.14224)
		(layer "In11.Cu")
		(net "P5E_CPU0_P2_TX_BUF_C_DP<6>")
	)
	(arc
		(start 393.080748 -429.787558)
		(mid 393.103195 -429.900409)
		(end 393.167108 -429.996092)
		(width 0.14224)
		(layer "In11.Cu")
		(net "P5E_CPU0_P2_TX_BUF_C_DP<6>")
	)
	(arc
		(start 393.23137 -430.060354)
		(mid 393.344993 -430.136274)
		(end 393.47902 -430.16297)
		(width 0.14224)
		(layer "In11.Cu")
		(net "P5E_CPU0_P2_TX_BUF_C_DP<6>")
	)
	(segment
		(start 386.803392 -420.681658)
		(end 387.073902 -420.952168)
		(width 0.12954)
		(layer "F.Cu")
		(net "P5E_CPU0_P2_TX_BUF_C_DP<5>")
	)
	(segment
		(start 387.099302 -417.166044)
		(end 386.803392 -417.461954)
		(width 0.12954)
		(layer "F.Cu")
		(net "P5E_CPU0_P2_TX_BUF_C_DP<5>")
	)
	(segment
		(start 386.803392 -417.461954)
		(end 386.803392 -420.681658)
		(width 0.12954)
		(layer "F.Cu")
		(net "P5E_CPU0_P2_TX_BUF_C_DP<5>")
	)
	(segment
		(start 388.733538 -422.509696)
		(end 389.035036 -422.811448)
		(width 0.14224)
		(layer "In11.Cu")
		(net "P5E_CPU0_P2_TX_BUF_C_DP<5>")
	)
	(segment
		(start 386.783072 -421.63238)
		(end 387.192774 -422.042082)
		(width 0.14224)
		(layer "In11.Cu")
		(net "P5E_CPU0_P2_TX_BUF_C_DP<5>")
	)
	(segment
		(start 387.073902 -420.952168)
		(end 386.783072 -421.242998)
		(width 0.14224)
		(layer "In11.Cu")
		(net "P5E_CPU0_P2_TX_BUF_C_DP<5>")
	)
	(segment
		(start 391.607548 -431.148998)
		(end 391.749788 -431.006758)
		(width 0.14224)
		(layer "In11.Cu")
		(net "P5E_CPU0_P2_TX_BUF_C_DP<5>")
	)
	(segment
		(start 389.035036 -422.811448)
		(end 389.229092 -422.811448)
		(width 0.14224)
		(layer "In11.Cu")
		(net "P5E_CPU0_P2_TX_BUF_C_DP<5>")
	)
	(segment
		(start 389.530844 -423.113708)
		(end 389.530844 -423.307764)
		(width 0.14224)
		(layer "In11.Cu")
		(net "P5E_CPU0_P2_TX_BUF_C_DP<5>")
	)
	(segment
		(start 390.442704 -424.026584)
		(end 390.442704 -424.22064)
		(width 0.14224)
		(layer "In11.Cu")
		(net "P5E_CPU0_P2_TX_BUF_C_DP<5>")
	)
	(segment
		(start 391.085832 -425.033694)
		(end 391.085832 -430.831244)
		(width 0.14224)
		(layer "In11.Cu")
		(net "P5E_CPU0_P2_TX_BUF_C_DP<5>")
	)
	(segment
		(start 391.371074 -431.148998)
		(end 391.607548 -431.148998)
		(width 0.14224)
		(layer "In11.Cu")
		(net "P5E_CPU0_P2_TX_BUF_C_DP<5>")
	)
	(segment
		(start 391.178288 -431.054256)
		(end 391.203688 -431.079656)
		(width 0.14224)
		(layer "In11.Cu")
		(net "P5E_CPU0_P2_TX_BUF_C_DP<5>")
	)
	(segment
		(start 391.749788 -431.006758)
		(end 391.749788 -430.689766)
		(width 0.14224)
		(layer "In11.Cu")
		(net "P5E_CPU0_P2_TX_BUF_C_DP<5>")
	)
	(segment
		(start 387.192774 -422.042082)
		(end 388.733538 -422.509696)
		(width 0.14224)
		(layer "In11.Cu")
		(net "P5E_CPU0_P2_TX_BUF_C_DP<5>")
	)
	(segment
		(start 389.946896 -423.724324)
		(end 390.140952 -423.724324)
		(width 0.14224)
		(layer "In11.Cu")
		(net "P5E_CPU0_P2_TX_BUF_C_DP<5>")
	)
	(segment
		(start 386.783072 -421.242998)
		(end 386.783072 -421.63238)
		(width 0.14224)
		(layer "In11.Cu")
		(net "P5E_CPU0_P2_TX_BUF_C_DP<5>")
	)
	(segment
		(start 389.229092 -422.811448)
		(end 389.530844 -423.113708)
		(width 0.14224)
		(layer "In11.Cu")
		(net "P5E_CPU0_P2_TX_BUF_C_DP<5>")
	)
	(segment
		(start 390.442704 -424.22064)
		(end 390.966198 -424.744642)
		(width 0.14224)
		(layer "In11.Cu")
		(net "P5E_CPU0_P2_TX_BUF_C_DP<5>")
	)
	(segment
		(start 389.530844 -423.307764)
		(end 389.946896 -423.724324)
		(width 0.14224)
		(layer "In11.Cu")
		(net "P5E_CPU0_P2_TX_BUF_C_DP<5>")
	)
	(segment
		(start 390.140952 -423.724324)
		(end 390.442704 -424.026584)
		(width 0.14224)
		(layer "In11.Cu")
		(net "P5E_CPU0_P2_TX_BUF_C_DP<5>")
	)
	(arc
		(start 391.203688 -431.079656)
		(mid 391.280485 -431.13097)
		(end 391.371074 -431.148998)
		(width 0.14224)
		(layer "In11.Cu")
		(net "P5E_CPU0_P2_TX_BUF_C_DP<5>")
	)
	(arc
		(start 390.966198 -424.744642)
		(mid 391.054757 -424.877274)
		(end 391.085832 -425.033694)
		(width 0.14224)
		(layer "In11.Cu")
		(net "P5E_CPU0_P2_TX_BUF_C_DP<5>")
	)
	(arc
		(start 391.085832 -430.831244)
		(mid 391.109861 -430.951954)
		(end 391.178288 -431.054256)
		(width 0.14224)
		(layer "In11.Cu")
		(net "P5E_CPU0_P2_TX_BUF_C_DP<5>")
	)
	(segment
		(start 383.740152 -420.681658)
		(end 384.010662 -420.952168)
		(width 0.12954)
		(layer "F.Cu")
		(net "P5E_CPU0_P2_TX_BUF_C_DP<4>")
	)
	(segment
		(start 383.740152 -417.461954)
		(end 383.740152 -420.681658)
		(width 0.12954)
		(layer "F.Cu")
		(net "P5E_CPU0_P2_TX_BUF_C_DP<4>")
	)
	(segment
		(start 384.036062 -417.166044)
		(end 383.740152 -417.461954)
		(width 0.12954)
		(layer "F.Cu")
		(net "P5E_CPU0_P2_TX_BUF_C_DP<4>")
	)
	(segment
		(start 387.56336 -423.762424)
		(end 387.793992 -423.762424)
		(width 0.14224)
		(layer "In11.Cu")
		(net "P5E_CPU0_P2_TX_BUF_C_DP<4>")
	)
	(segment
		(start 387.07695 -423.220642)
		(end 387.07695 -423.414698)
		(width 0.14224)
		(layer "In11.Cu")
		(net "P5E_CPU0_P2_TX_BUF_C_DP<4>")
	)
	(segment
		(start 386.320284 -422.489122)
		(end 386.320284 -422.658032)
		(width 0.14224)
		(layer "In11.Cu")
		(net "P5E_CPU0_P2_TX_BUF_C_DP<4>")
	)
	(segment
		(start 386.774944 -422.918636)
		(end 387.07695 -423.220642)
		(width 0.14224)
		(layer "In11.Cu")
		(net "P5E_CPU0_P2_TX_BUF_C_DP<4>")
	)
	(segment
		(start 386.320284 -422.658032)
		(end 386.580888 -422.918636)
		(width 0.14224)
		(layer "In11.Cu")
		(net "P5E_CPU0_P2_TX_BUF_C_DP<4>")
	)
	(segment
		(start 384.010662 -420.952168)
		(end 383.72542 -421.23741)
		(width 0.14224)
		(layer "In11.Cu")
		(net "P5E_CPU0_P2_TX_BUF_C_DP<4>")
	)
	(segment
		(start 385.238498 -421.964358)
		(end 385.62661 -421.964358)
		(width 0.14224)
		(layer "In11.Cu")
		(net "P5E_CPU0_P2_TX_BUF_C_DP<4>")
	)
	(segment
		(start 385.62661 -421.964358)
		(end 385.849622 -422.18737)
		(width 0.14224)
		(layer "In11.Cu")
		(net "P5E_CPU0_P2_TX_BUF_C_DP<4>")
	)
	(segment
		(start 385.849622 -422.18737)
		(end 386.018532 -422.18737)
		(width 0.14224)
		(layer "In11.Cu")
		(net "P5E_CPU0_P2_TX_BUF_C_DP<4>")
	)
	(segment
		(start 387.07695 -423.414698)
		(end 387.326632 -423.66438)
		(width 0.14224)
		(layer "In11.Cu")
		(net "P5E_CPU0_P2_TX_BUF_C_DP<4>")
	)
	(segment
		(start 386.018532 -422.18737)
		(end 386.320284 -422.489122)
		(width 0.14224)
		(layer "In11.Cu")
		(net "P5E_CPU0_P2_TX_BUF_C_DP<4>")
	)
	(segment
		(start 383.72542 -421.68064)
		(end 383.827528 -421.782748)
		(width 0.14224)
		(layer "In11.Cu")
		(net "P5E_CPU0_P2_TX_BUF_C_DP<4>")
	)
	(segment
		(start 385.101338 -421.827198)
		(end 385.238498 -421.964358)
		(width 0.14224)
		(layer "In11.Cu")
		(net "P5E_CPU0_P2_TX_BUF_C_DP<4>")
	)
	(segment
		(start 389.414512 -430.177956)
		(end 389.622538 -430.177956)
		(width 0.14224)
		(layer "In11.Cu")
		(net "P5E_CPU0_P2_TX_BUF_C_DP<4>")
	)
	(segment
		(start 389.749792 -430.050702)
		(end 389.749792 -429.689768)
		(width 0.14224)
		(layer "In11.Cu")
		(net "P5E_CPU0_P2_TX_BUF_C_DP<4>")
	)
	(segment
		(start 389.076184 -425.07027)
		(end 389.076184 -429.839628)
		(width 0.14224)
		(layer "In11.Cu")
		(net "P5E_CPU0_P2_TX_BUF_C_DP<4>")
	)
	(segment
		(start 383.827528 -421.782748)
		(end 384.099308 -421.964358)
		(width 0.14224)
		(layer "In11.Cu")
		(net "P5E_CPU0_P2_TX_BUF_C_DP<4>")
	)
	(segment
		(start 389.622538 -430.177956)
		(end 389.749792 -430.050702)
		(width 0.14224)
		(layer "In11.Cu")
		(net "P5E_CPU0_P2_TX_BUF_C_DP<4>")
	)
	(segment
		(start 386.580888 -422.918636)
		(end 386.774944 -422.918636)
		(width 0.14224)
		(layer "In11.Cu")
		(net "P5E_CPU0_P2_TX_BUF_C_DP<4>")
	)
	(segment
		(start 384.674618 -421.827198)
		(end 385.101338 -421.827198)
		(width 0.14224)
		(layer "In11.Cu")
		(net "P5E_CPU0_P2_TX_BUF_C_DP<4>")
	)
	(segment
		(start 383.72542 -421.23741)
		(end 383.72542 -421.68064)
		(width 0.14224)
		(layer "In11.Cu")
		(net "P5E_CPU0_P2_TX_BUF_C_DP<4>")
	)
	(segment
		(start 384.537458 -421.964358)
		(end 384.674618 -421.827198)
		(width 0.14224)
		(layer "In11.Cu")
		(net "P5E_CPU0_P2_TX_BUF_C_DP<4>")
	)
	(segment
		(start 384.099308 -421.964358)
		(end 384.537458 -421.964358)
		(width 0.14224)
		(layer "In11.Cu")
		(net "P5E_CPU0_P2_TX_BUF_C_DP<4>")
	)
	(segment
		(start 388.255764 -423.953686)
		(end 388.866888 -424.56481)
		(width 0.14224)
		(layer "In11.Cu")
		(net "P5E_CPU0_P2_TX_BUF_C_DP<4>")
	)
	(arc
		(start 387.326632 -423.66438)
		(mid 387.435244 -423.736952)
		(end 387.56336 -423.762424)
		(width 0.14224)
		(layer "In11.Cu")
		(net "P5E_CPU0_P2_TX_BUF_C_DP<4>")
	)
	(arc
		(start 389.076184 -429.839628)
		(mid 389.175278 -430.078862)
		(end 389.414512 -430.177956)
		(width 0.14224)
		(layer "In11.Cu")
		(net "P5E_CPU0_P2_TX_BUF_C_DP<4>")
	)
	(arc
		(start 387.793992 -423.762424)
		(mid 388.043897 -423.812133)
		(end 388.255764 -423.953686)
		(width 0.14224)
		(layer "In11.Cu")
		(net "P5E_CPU0_P2_TX_BUF_C_DP<4>")
	)
	(arc
		(start 388.866888 -424.56481)
		(mid 389.02179 -424.796731)
		(end 389.076184 -425.07027)
		(width 0.14224)
		(layer "In11.Cu")
		(net "P5E_CPU0_P2_TX_BUF_C_DP<4>")
	)
	(segment
		(start 380.676912 -420.681658)
		(end 380.947422 -420.952168)
		(width 0.12954)
		(layer "F.Cu")
		(net "P5E_CPU0_P2_TX_BUF_C_DP<3>")
	)
	(segment
		(start 380.972822 -417.166044)
		(end 380.676912 -417.461954)
		(width 0.12954)
		(layer "F.Cu")
		(net "P5E_CPU0_P2_TX_BUF_C_DP<3>")
	)
	(segment
		(start 380.676912 -417.461954)
		(end 380.676912 -420.681658)
		(width 0.12954)
		(layer "F.Cu")
		(net "P5E_CPU0_P2_TX_BUF_C_DP<3>")
	)
	(segment
		(start 387.607556 -431.148998)
		(end 387.749796 -431.006758)
		(width 0.14224)
		(layer "In11.Cu")
		(net "P5E_CPU0_P2_TX_BUF_C_DP<3>")
	)
	(segment
		(start 380.947422 -420.952168)
		(end 380.656592 -421.242998)
		(width 0.14224)
		(layer "In11.Cu")
		(net "P5E_CPU0_P2_TX_BUF_C_DP<3>")
	)
	(segment
		(start 381.529082 -421.901112)
		(end 381.955802 -421.901112)
		(width 0.14224)
		(layer "In11.Cu")
		(net "P5E_CPU0_P2_TX_BUF_C_DP<3>")
	)
	(segment
		(start 387.749796 -431.006758)
		(end 387.749796 -430.689766)
		(width 0.14224)
		(layer "In11.Cu")
		(net "P5E_CPU0_P2_TX_BUF_C_DP<3>")
	)
	(segment
		(start 386.371846 -424.031156)
		(end 386.673344 -424.332654)
		(width 0.14224)
		(layer "In11.Cu")
		(net "P5E_CPU0_P2_TX_BUF_C_DP<3>")
	)
	(segment
		(start 387.273038 -431.148998)
		(end 387.607556 -431.148998)
		(width 0.14224)
		(layer "In11.Cu")
		(net "P5E_CPU0_P2_TX_BUF_C_DP<3>")
	)
	(segment
		(start 384.013456 -422.897808)
		(end 384.9116 -422.897808)
		(width 0.14224)
		(layer "In11.Cu")
		(net "P5E_CPU0_P2_TX_BUF_C_DP<3>")
	)
	(segment
		(start 386.673344 -424.332654)
		(end 386.673344 -424.490134)
		(width 0.14224)
		(layer "In11.Cu")
		(net "P5E_CPU0_P2_TX_BUF_C_DP<3>")
	)
	(segment
		(start 380.656592 -421.242998)
		(end 380.656592 -421.745664)
		(width 0.14224)
		(layer "In11.Cu")
		(net "P5E_CPU0_P2_TX_BUF_C_DP<3>")
	)
	(segment
		(start 380.656592 -421.745664)
		(end 380.9492 -422.038272)
		(width 0.14224)
		(layer "In11.Cu")
		(net "P5E_CPU0_P2_TX_BUF_C_DP<3>")
	)
	(segment
		(start 380.9492 -422.038272)
		(end 381.391922 -422.038272)
		(width 0.14224)
		(layer "In11.Cu")
		(net "P5E_CPU0_P2_TX_BUF_C_DP<3>")
	)
	(segment
		(start 387.08584 -430.9618)
		(end 387.273038 -431.148998)
		(width 0.14224)
		(layer "In11.Cu")
		(net "P5E_CPU0_P2_TX_BUF_C_DP<3>")
	)
	(segment
		(start 382.092962 -422.038272)
		(end 382.519682 -422.038272)
		(width 0.14224)
		(layer "In11.Cu")
		(net "P5E_CPU0_P2_TX_BUF_C_DP<3>")
	)
	(segment
		(start 385.88188 -423.69867)
		(end 386.214366 -424.031156)
		(width 0.14224)
		(layer "In11.Cu")
		(net "P5E_CPU0_P2_TX_BUF_C_DP<3>")
	)
	(segment
		(start 386.214366 -424.031156)
		(end 386.371846 -424.031156)
		(width 0.14224)
		(layer "In11.Cu")
		(net "P5E_CPU0_P2_TX_BUF_C_DP<3>")
	)
	(segment
		(start 381.391922 -422.038272)
		(end 381.529082 -421.901112)
		(width 0.14224)
		(layer "In11.Cu")
		(net "P5E_CPU0_P2_TX_BUF_C_DP<3>")
	)
	(segment
		(start 387.08584 -425.177712)
		(end 387.08584 -430.9618)
		(width 0.14224)
		(layer "In11.Cu")
		(net "P5E_CPU0_P2_TX_BUF_C_DP<3>")
	)
	(segment
		(start 385.200906 -423.017696)
		(end 385.42341 -423.2402)
		(width 0.14224)
		(layer "In11.Cu")
		(net "P5E_CPU0_P2_TX_BUF_C_DP<3>")
	)
	(segment
		(start 386.673344 -424.490134)
		(end 386.891276 -424.708066)
		(width 0.14224)
		(layer "In11.Cu")
		(net "P5E_CPU0_P2_TX_BUF_C_DP<3>")
	)
	(segment
		(start 385.88188 -423.541698)
		(end 385.88188 -423.69867)
		(width 0.14224)
		(layer "In11.Cu")
		(net "P5E_CPU0_P2_TX_BUF_C_DP<3>")
	)
	(segment
		(start 381.955802 -421.901112)
		(end 382.092962 -422.038272)
		(width 0.14224)
		(layer "In11.Cu")
		(net "P5E_CPU0_P2_TX_BUF_C_DP<3>")
	)
	(segment
		(start 382.519682 -422.038272)
		(end 383.630424 -422.781476)
		(width 0.14224)
		(layer "In11.Cu")
		(net "P5E_CPU0_P2_TX_BUF_C_DP<3>")
	)
	(segment
		(start 385.42341 -423.2402)
		(end 385.580382 -423.2402)
		(width 0.14224)
		(layer "In11.Cu")
		(net "P5E_CPU0_P2_TX_BUF_C_DP<3>")
	)
	(segment
		(start 385.580382 -423.2402)
		(end 385.88188 -423.541698)
		(width 0.14224)
		(layer "In11.Cu")
		(net "P5E_CPU0_P2_TX_BUF_C_DP<3>")
	)
	(arc
		(start 386.891276 -424.708066)
		(mid 387.035252 -424.923541)
		(end 387.08584 -425.177712)
		(width 0.14224)
		(layer "In11.Cu")
		(net "P5E_CPU0_P2_TX_BUF_C_DP<3>")
	)
	(arc
		(start 384.9116 -422.897808)
		(mid 385.068178 -422.928971)
		(end 385.200906 -423.017696)
		(width 0.14224)
		(layer "In11.Cu")
		(net "P5E_CPU0_P2_TX_BUF_C_DP<3>")
	)
	(arc
		(start 383.630424 -422.781476)
		(mid 383.813304 -422.868071)
		(end 384.013456 -422.897808)
		(width 0.14224)
		(layer "In11.Cu")
		(net "P5E_CPU0_P2_TX_BUF_C_DP<3>")
	)
	(segment
		(start 377.613672 -420.681658)
		(end 377.884182 -420.952168)
		(width 0.12954)
		(layer "F.Cu")
		(net "P5E_CPU0_P2_TX_BUF_C_DP<2>")
	)
	(segment
		(start 377.909582 -417.166044)
		(end 377.613672 -417.461954)
		(width 0.12954)
		(layer "F.Cu")
		(net "P5E_CPU0_P2_TX_BUF_C_DP<2>")
	)
	(segment
		(start 377.613672 -417.461954)
		(end 377.613672 -420.681658)
		(width 0.12954)
		(layer "F.Cu")
		(net "P5E_CPU0_P2_TX_BUF_C_DP<2>")
	)
	(segment
		(start 378.395738 -422.845484)
		(end 378.822458 -422.845484)
		(width 0.14224)
		(layer "In11.Cu")
		(net "P5E_CPU0_P2_TX_BUF_C_DP<2>")
	)
	(segment
		(start 382.59385 -423.209974)
		(end 383.39395 -423.745152)
		(width 0.14224)
		(layer "In11.Cu")
		(net "P5E_CPU0_P2_TX_BUF_C_DP<2>")
	)
	(segment
		(start 377.720606 -422.982644)
		(end 378.258578 -422.982644)
		(width 0.14224)
		(layer "In11.Cu")
		(net "P5E_CPU0_P2_TX_BUF_C_DP<2>")
	)
	(segment
		(start 378.959618 -422.982644)
		(end 379.386338 -422.982644)
		(width 0.14224)
		(layer "In11.Cu")
		(net "P5E_CPU0_P2_TX_BUF_C_DP<2>")
	)
	(segment
		(start 378.822458 -422.845484)
		(end 378.959618 -422.982644)
		(width 0.14224)
		(layer "In11.Cu")
		(net "P5E_CPU0_P2_TX_BUF_C_DP<2>")
	)
	(segment
		(start 379.386338 -422.982644)
		(end 379.523498 -422.845484)
		(width 0.14224)
		(layer "In11.Cu")
		(net "P5E_CPU0_P2_TX_BUF_C_DP<2>")
	)
	(segment
		(start 385.080764 -425.74083)
		(end 385.080764 -429.753268)
		(width 0.14224)
		(layer "In11.Cu")
		(net "P5E_CPU0_P2_TX_BUF_C_DP<2>")
	)
	(segment
		(start 385.384802 -430.153826)
		(end 385.60248 -430.153826)
		(width 0.14224)
		(layer "In11.Cu")
		(net "P5E_CPU0_P2_TX_BUF_C_DP<2>")
	)
	(segment
		(start 377.593352 -421.72763)
		(end 377.730512 -421.86479)
		(width 0.14224)
		(layer "In11.Cu")
		(net "P5E_CPU0_P2_TX_BUF_C_DP<2>")
	)
	(segment
		(start 377.593352 -421.242998)
		(end 377.593352 -421.72763)
		(width 0.14224)
		(layer "In11.Cu")
		(net "P5E_CPU0_P2_TX_BUF_C_DP<2>")
	)
	(segment
		(start 379.523498 -422.845484)
		(end 379.950218 -422.845484)
		(width 0.14224)
		(layer "In11.Cu")
		(net "P5E_CPU0_P2_TX_BUF_C_DP<2>")
	)
	(segment
		(start 383.66192 -423.826432)
		(end 383.865374 -423.826432)
		(width 0.14224)
		(layer "In11.Cu")
		(net "P5E_CPU0_P2_TX_BUF_C_DP<2>")
	)
	(segment
		(start 377.884182 -420.952168)
		(end 377.593352 -421.242998)
		(width 0.14224)
		(layer "In11.Cu")
		(net "P5E_CPU0_P2_TX_BUF_C_DP<2>")
	)
	(segment
		(start 377.593352 -422.42867)
		(end 377.593352 -422.85539)
		(width 0.14224)
		(layer "In11.Cu")
		(net "P5E_CPU0_P2_TX_BUF_C_DP<2>")
	)
	(segment
		(start 377.593352 -422.85539)
		(end 377.720606 -422.982644)
		(width 0.14224)
		(layer "In11.Cu")
		(net "P5E_CPU0_P2_TX_BUF_C_DP<2>")
	)
	(segment
		(start 378.258578 -422.982644)
		(end 378.395738 -422.845484)
		(width 0.14224)
		(layer "In11.Cu")
		(net "P5E_CPU0_P2_TX_BUF_C_DP<2>")
	)
	(segment
		(start 377.730512 -422.29151)
		(end 377.593352 -422.42867)
		(width 0.14224)
		(layer "In11.Cu")
		(net "P5E_CPU0_P2_TX_BUF_C_DP<2>")
	)
	(segment
		(start 377.730512 -421.86479)
		(end 377.730512 -422.29151)
		(width 0.14224)
		(layer "In11.Cu")
		(net "P5E_CPU0_P2_TX_BUF_C_DP<2>")
	)
	(segment
		(start 382.044448 -422.982644)
		(end 382.59385 -423.209974)
		(width 0.14224)
		(layer "In11.Cu")
		(net "P5E_CPU0_P2_TX_BUF_C_DP<2>")
	)
	(segment
		(start 385.60248 -430.153826)
		(end 385.7498 -430.006506)
		(width 0.14224)
		(layer "In11.Cu")
		(net "P5E_CPU0_P2_TX_BUF_C_DP<2>")
	)
	(segment
		(start 380.087378 -422.982644)
		(end 382.044448 -422.982644)
		(width 0.14224)
		(layer "In11.Cu")
		(net "P5E_CPU0_P2_TX_BUF_C_DP<2>")
	)
	(segment
		(start 385.7498 -430.006506)
		(end 385.7498 -429.689768)
		(width 0.14224)
		(layer "In11.Cu")
		(net "P5E_CPU0_P2_TX_BUF_C_DP<2>")
	)
	(segment
		(start 384.339846 -424.023028)
		(end 384.389884 -424.073066)
		(width 0.14224)
		(layer "In11.Cu")
		(net "P5E_CPU0_P2_TX_BUF_C_DP<2>")
	)
	(segment
		(start 379.950218 -422.845484)
		(end 380.087378 -422.982644)
		(width 0.14224)
		(layer "In11.Cu")
		(net "P5E_CPU0_P2_TX_BUF_C_DP<2>")
	)
	(arc
		(start 383.39395 -423.745152)
		(mid 383.521894 -423.805731)
		(end 383.66192 -423.826432)
		(width 0.14224)
		(layer "In11.Cu")
		(net "P5E_CPU0_P2_TX_BUF_C_DP<2>")
	)
	(arc
		(start 385.218178 -430.084738)
		(mid 385.294612 -430.135843)
		(end 385.384802 -430.153826)
		(width 0.14224)
		(layer "In11.Cu")
		(net "P5E_CPU0_P2_TX_BUF_C_DP<2>")
	)
	(arc
		(start 383.865374 -423.826432)
		(mid 384.122166 -423.877529)
		(end 384.339846 -424.023028)
		(width 0.14224)
		(layer "In11.Cu")
		(net "P5E_CPU0_P2_TX_BUF_C_DP<2>")
	)
	(arc
		(start 385.080764 -429.753268)
		(mid 385.116486 -429.932674)
		(end 385.218178 -430.084738)
		(width 0.14224)
		(layer "In11.Cu")
		(net "P5E_CPU0_P2_TX_BUF_C_DP<2>")
	)
	(arc
		(start 384.389884 -424.073066)
		(mid 384.901212 -424.838228)
		(end 385.080764 -425.74083)
		(width 0.14224)
		(layer "In11.Cu")
		(net "P5E_CPU0_P2_TX_BUF_C_DP<2>")
	)
	(segment
		(start 374.846342 -417.166044)
		(end 374.550432 -417.461954)
		(width 0.12954)
		(layer "F.Cu")
		(net "P5E_CPU0_P2_TX_BUF_C_DP<1>")
	)
	(segment
		(start 374.550432 -420.681658)
		(end 374.820942 -420.952168)
		(width 0.12954)
		(layer "F.Cu")
		(net "P5E_CPU0_P2_TX_BUF_C_DP<1>")
	)
	(segment
		(start 374.550432 -417.461954)
		(end 374.550432 -420.681658)
		(width 0.12954)
		(layer "F.Cu")
		(net "P5E_CPU0_P2_TX_BUF_C_DP<1>")
	)
	(segment
		(start 383.123186 -430.999138)
		(end 383.165096 -431.041048)
		(width 0.14224)
		(layer "In11.Cu")
		(net "P5E_CPU0_P2_TX_BUF_C_DP<1>")
	)
	(segment
		(start 383.607564 -431.148998)
		(end 383.749804 -431.006758)
		(width 0.14224)
		(layer "In11.Cu")
		(net "P5E_CPU0_P2_TX_BUF_C_DP<1>")
	)
	(segment
		(start 383.085848 -425.559982)
		(end 383.085848 -430.909222)
		(width 0.14224)
		(layer "In11.Cu")
		(net "P5E_CPU0_P2_TX_BUF_C_DP<1>")
	)
	(segment
		(start 375.483374 -422.524682)
		(end 375.483374 -422.718484)
		(width 0.14224)
		(layer "In11.Cu")
		(net "P5E_CPU0_P2_TX_BUF_C_DP<1>")
	)
	(segment
		(start 376.774202 -423.956734)
		(end 381.952754 -423.956734)
		(width 0.14224)
		(layer "In11.Cu")
		(net "P5E_CPU0_P2_TX_BUF_C_DP<1>")
	)
	(segment
		(start 375.181368 -422.222676)
		(end 375.483374 -422.524682)
		(width 0.14224)
		(layer "In11.Cu")
		(net "P5E_CPU0_P2_TX_BUF_C_DP<1>")
	)
	(segment
		(start 376.365262 -423.40657)
		(end 376.365262 -423.600372)
		(width 0.14224)
		(layer "In11.Cu")
		(net "P5E_CPU0_P2_TX_BUF_C_DP<1>")
	)
	(segment
		(start 382.171448 -424.046904)
		(end 382.198372 -424.05808)
		(width 0.14224)
		(layer "In11.Cu")
		(net "P5E_CPU0_P2_TX_BUF_C_DP<1>")
	)
	(segment
		(start 376.063256 -423.104564)
		(end 376.365262 -423.40657)
		(width 0.14224)
		(layer "In11.Cu")
		(net "P5E_CPU0_P2_TX_BUF_C_DP<1>")
	)
	(segment
		(start 382.198372 -424.05808)
		(end 382.333754 -424.149266)
		(width 0.14224)
		(layer "In11.Cu")
		(net "P5E_CPU0_P2_TX_BUF_C_DP<1>")
	)
	(segment
		(start 376.365262 -423.600372)
		(end 376.684286 -423.919396)
		(width 0.14224)
		(layer "In11.Cu")
		(net "P5E_CPU0_P2_TX_BUF_C_DP<1>")
	)
	(segment
		(start 383.425446 -431.148998)
		(end 383.607564 -431.148998)
		(width 0.14224)
		(layer "In11.Cu")
		(net "P5E_CPU0_P2_TX_BUF_C_DP<1>")
	)
	(segment
		(start 374.820942 -420.952168)
		(end 374.530112 -421.242998)
		(width 0.14224)
		(layer "In11.Cu")
		(net "P5E_CPU0_P2_TX_BUF_C_DP<1>")
	)
	(segment
		(start 374.987566 -422.222676)
		(end 375.181368 -422.222676)
		(width 0.14224)
		(layer "In11.Cu")
		(net "P5E_CPU0_P2_TX_BUF_C_DP<1>")
	)
	(segment
		(start 375.869454 -423.104564)
		(end 376.063256 -423.104564)
		(width 0.14224)
		(layer "In11.Cu")
		(net "P5E_CPU0_P2_TX_BUF_C_DP<1>")
	)
	(segment
		(start 382.171448 -424.047158)
		(end 382.171448 -424.046904)
		(width 0.14224)
		(layer "In11.Cu")
		(net "P5E_CPU0_P2_TX_BUF_C_DP<1>")
	)
	(segment
		(start 381.952754 -423.956734)
		(end 382.171448 -424.047158)
		(width 0.14224)
		(layer "In11.Cu")
		(net "P5E_CPU0_P2_TX_BUF_C_DP<1>")
	)
	(segment
		(start 375.483374 -422.718484)
		(end 375.869454 -423.104564)
		(width 0.14224)
		(layer "In11.Cu")
		(net "P5E_CPU0_P2_TX_BUF_C_DP<1>")
	)
	(segment
		(start 374.530112 -421.242998)
		(end 374.530112 -421.651176)
		(width 0.14224)
		(layer "In11.Cu")
		(net "P5E_CPU0_P2_TX_BUF_C_DP<1>")
	)
	(segment
		(start 374.610884 -421.845994)
		(end 374.987566 -422.222676)
		(width 0.14224)
		(layer "In11.Cu")
		(net "P5E_CPU0_P2_TX_BUF_C_DP<1>")
	)
	(segment
		(start 383.749804 -431.006758)
		(end 383.749804 -430.689766)
		(width 0.14224)
		(layer "In11.Cu")
		(net "P5E_CPU0_P2_TX_BUF_C_DP<1>")
	)
	(arc
		(start 383.165096 -431.041048)
		(mid 383.284531 -431.120915)
		(end 383.425446 -431.148998)
		(width 0.14224)
		(layer "In11.Cu")
		(net "P5E_CPU0_P2_TX_BUF_C_DP<1>")
	)
	(arc
		(start 382.333754 -424.149266)
		(mid 382.88611 -424.760634)
		(end 383.085848 -425.559982)
		(width 0.14224)
		(layer "In11.Cu")
		(net "P5E_CPU0_P2_TX_BUF_C_DP<1>")
	)
	(arc
		(start 376.684286 -423.919396)
		(mid 376.725526 -423.947015)
		(end 376.774202 -423.956734)
		(width 0.14224)
		(layer "In11.Cu")
		(net "P5E_CPU0_P2_TX_BUF_C_DP<1>")
	)
	(arc
		(start 383.085848 -430.909222)
		(mid 383.09555 -430.957906)
		(end 383.123186 -430.999138)
		(width 0.14224)
		(layer "In11.Cu")
		(net "P5E_CPU0_P2_TX_BUF_C_DP<1>")
	)
	(arc
		(start 374.530112 -421.651176)
		(mid 374.551105 -421.756625)
		(end 374.610884 -421.845994)
		(width 0.14224)
		(layer "In11.Cu")
		(net "P5E_CPU0_P2_TX_BUF_C_DP<1>")
	)
	(segment
		(start 417.435792 -417.461954)
		(end 417.435792 -420.681658)
		(width 0.12954)
		(layer "F.Cu")
		(net "P5E_CPU0_P2_TX_BUF_C_DP<15>")
	)
	(segment
		(start 417.731702 -417.166044)
		(end 417.435792 -417.461954)
		(width 0.12954)
		(layer "F.Cu")
		(net "P5E_CPU0_P2_TX_BUF_C_DP<15>")
	)
	(segment
		(start 417.435792 -420.681658)
		(end 417.706302 -420.952168)
		(width 0.12954)
		(layer "F.Cu")
		(net "P5E_CPU0_P2_TX_BUF_C_DP<15>")
	)
	(segment
		(start 414.755076 -423.44467)
		(end 414.579562 -423.361866)
		(width 0.14224)
		(layer "In11.Cu")
		(net "P5E_CPU0_P2_TX_BUF_C_DP<15>")
	)
	(segment
		(start 417.431982 -421.226488)
		(end 417.431982 -421.738806)
		(width 0.14224)
		(layer "In11.Cu")
		(net "P5E_CPU0_P2_TX_BUF_C_DP<15>")
	)
	(segment
		(start 417.282884 -422.098724)
		(end 416.913568 -422.46804)
		(width 0.14224)
		(layer "In11.Cu")
		(net "P5E_CPU0_P2_TX_BUF_C_DP<15>")
	)
	(segment
		(start 412.32582 -431.148998)
		(end 412.60776 -431.148998)
		(width 0.14224)
		(layer "In11.Cu")
		(net "P5E_CPU0_P2_TX_BUF_C_DP<15>")
	)
	(segment
		(start 412.60776 -431.148998)
		(end 412.75 -431.006758)
		(width 0.14224)
		(layer "In11.Cu")
		(net "P5E_CPU0_P2_TX_BUF_C_DP<15>")
	)
	(segment
		(start 414.579562 -423.361866)
		(end 412.472886 -424.115738)
		(width 0.14224)
		(layer "In11.Cu")
		(net "P5E_CPU0_P2_TX_BUF_C_DP<15>")
	)
	(segment
		(start 417.706302 -420.952168)
		(end 417.431982 -421.226488)
		(width 0.14224)
		(layer "In11.Cu")
		(net "P5E_CPU0_P2_TX_BUF_C_DP<15>")
	)
	(segment
		(start 415.641536 -422.981628)
		(end 415.239962 -423.125392)
		(width 0.14224)
		(layer "In11.Cu")
		(net "P5E_CPU0_P2_TX_BUF_C_DP<15>")
	)
	(segment
		(start 415.239962 -423.125392)
		(end 415.156904 -423.300906)
		(width 0.14224)
		(layer "In11.Cu")
		(net "P5E_CPU0_P2_TX_BUF_C_DP<15>")
	)
	(segment
		(start 412.75 -431.006758)
		(end 412.75 -430.689766)
		(width 0.14224)
		(layer "In11.Cu")
		(net "P5E_CPU0_P2_TX_BUF_C_DP<15>")
	)
	(segment
		(start 415.81705 -423.064432)
		(end 415.641536 -422.981628)
		(width 0.14224)
		(layer "In11.Cu")
		(net "P5E_CPU0_P2_TX_BUF_C_DP<15>")
	)
	(segment
		(start 416.301936 -422.745154)
		(end 416.218878 -422.920668)
		(width 0.14224)
		(layer "In11.Cu")
		(net "P5E_CPU0_P2_TX_BUF_C_DP<15>")
	)
	(segment
		(start 412.086298 -424.846496)
		(end 412.086044 -424.846242)
		(width 0.14224)
		(layer "In11.Cu")
		(net "P5E_CPU0_P2_TX_BUF_C_DP<15>")
	)
	(segment
		(start 415.156904 -423.300906)
		(end 414.755076 -423.44467)
		(width 0.14224)
		(layer "In11.Cu")
		(net "P5E_CPU0_P2_TX_BUF_C_DP<15>")
	)
	(segment
		(start 412.086044 -424.846242)
		(end 412.086044 -430.875694)
		(width 0.14224)
		(layer "In11.Cu")
		(net "P5E_CPU0_P2_TX_BUF_C_DP<15>")
	)
	(segment
		(start 416.218878 -422.920668)
		(end 415.81705 -423.064432)
		(width 0.14224)
		(layer "In11.Cu")
		(net "P5E_CPU0_P2_TX_BUF_C_DP<15>")
	)
	(segment
		(start 416.70351 -422.60139)
		(end 416.301936 -422.745154)
		(width 0.14224)
		(layer "In11.Cu")
		(net "P5E_CPU0_P2_TX_BUF_C_DP<15>")
	)
	(segment
		(start 412.147004 -431.02276)
		(end 412.235904 -431.11166)
		(width 0.14224)
		(layer "In11.Cu")
		(net "P5E_CPU0_P2_TX_BUF_C_DP<15>")
	)
	(arc
		(start 412.472886 -424.115738)
		(mid 412.368468 -424.170942)
		(end 412.28391 -424.253406)
		(width 0.14224)
		(layer "In11.Cu")
		(net "P5E_CPU0_P2_TX_BUF_C_DP<15>")
	)
	(arc
		(start 412.279592 -424.258994)
		(mid 412.135766 -424.53722)
		(end 412.086298 -424.846496)
		(width 0.14224)
		(layer "In11.Cu")
		(net "P5E_CPU0_P2_TX_BUF_C_DP<15>")
	)
	(arc
		(start 417.431982 -421.738806)
		(mid 417.393235 -421.933598)
		(end 417.282884 -422.098724)
		(width 0.14224)
		(layer "In11.Cu")
		(net "P5E_CPU0_P2_TX_BUF_C_DP<15>")
	)
	(arc
		(start 412.086044 -430.875694)
		(mid 412.101894 -430.955288)
		(end 412.147004 -431.02276)
		(width 0.14224)
		(layer "In11.Cu")
		(net "P5E_CPU0_P2_TX_BUF_C_DP<15>")
	)
	(arc
		(start 412.235904 -431.11166)
		(mid 412.277144 -431.139279)
		(end 412.32582 -431.148998)
		(width 0.14224)
		(layer "In11.Cu")
		(net "P5E_CPU0_P2_TX_BUF_C_DP<15>")
	)
	(arc
		(start 416.913568 -422.46804)
		(mid 416.873905 -422.50415)
		(end 416.831018 -422.536366)
		(width 0.14224)
		(layer "In11.Cu")
		(net "P5E_CPU0_P2_TX_BUF_C_DP<15>")
	)
	(arc
		(start 416.831018 -422.536366)
		(mid 416.769315 -422.5729)
		(end 416.70351 -422.60139)
		(width 0.14224)
		(layer "In11.Cu")
		(net "P5E_CPU0_P2_TX_BUF_C_DP<15>")
	)
	(arc
		(start 412.28391 -424.253406)
		(mid 412.281746 -424.256196)
		(end 412.279592 -424.258994)
		(width 0.14224)
		(layer "In11.Cu")
		(net "P5E_CPU0_P2_TX_BUF_C_DP<15>")
	)
	(segment
		(start 414.372552 -417.461954)
		(end 414.372552 -420.681658)
		(width 0.12954)
		(layer "F.Cu")
		(net "P5E_CPU0_P2_TX_BUF_C_DP<14>")
	)
	(segment
		(start 414.668462 -417.166044)
		(end 414.372552 -417.461954)
		(width 0.12954)
		(layer "F.Cu")
		(net "P5E_CPU0_P2_TX_BUF_C_DP<14>")
	)
	(segment
		(start 414.372552 -420.681658)
		(end 414.643062 -420.952168)
		(width 0.12954)
		(layer "F.Cu")
		(net "P5E_CPU0_P2_TX_BUF_C_DP<14>")
	)
	(segment
		(start 411.985206 -423.045128)
		(end 411.327854 -423.317162)
		(width 0.14224)
		(layer "In11.Cu")
		(net "P5E_CPU0_P2_TX_BUF_C_DP<14>")
	)
	(segment
		(start 412.558992 -422.956228)
		(end 412.16453 -423.119296)
		(width 0.14224)
		(layer "In11.Cu")
		(net "P5E_CPU0_P2_TX_BUF_C_DP<14>")
	)
	(segment
		(start 413.027368 -422.613582)
		(end 412.63316 -422.77665)
		(width 0.14224)
		(layer "In11.Cu")
		(net "P5E_CPU0_P2_TX_BUF_C_DP<14>")
	)
	(segment
		(start 411.026356 -423.61866)
		(end 411.026356 -423.812716)
		(width 0.14224)
		(layer "In11.Cu")
		(net "P5E_CPU0_P2_TX_BUF_C_DP<14>")
	)
	(segment
		(start 414.352232 -421.899334)
		(end 414.06953 -422.182036)
		(width 0.14224)
		(layer "In11.Cu")
		(net "P5E_CPU0_P2_TX_BUF_C_DP<14>")
	)
	(segment
		(start 411.327854 -423.317162)
		(end 411.026356 -423.61866)
		(width 0.14224)
		(layer "In11.Cu")
		(net "P5E_CPU0_P2_TX_BUF_C_DP<14>")
	)
	(segment
		(start 412.63316 -422.77665)
		(end 412.558992 -422.956228)
		(width 0.14224)
		(layer "In11.Cu")
		(net "P5E_CPU0_P2_TX_BUF_C_DP<14>")
	)
	(segment
		(start 410.080968 -424.734736)
		(end 410.080968 -429.795686)
		(width 0.14224)
		(layer "In11.Cu")
		(net "P5E_CPU0_P2_TX_BUF_C_DP<14>")
	)
	(segment
		(start 411.026356 -423.812716)
		(end 410.72435 -424.114722)
		(width 0.14224)
		(layer "In11.Cu")
		(net "P5E_CPU0_P2_TX_BUF_C_DP<14>")
	)
	(segment
		(start 410.530294 -424.114722)
		(end 410.201872 -424.443144)
		(width 0.14224)
		(layer "In11.Cu")
		(net "P5E_CPU0_P2_TX_BUF_C_DP<14>")
	)
	(segment
		(start 412.16453 -423.119296)
		(end 411.985206 -423.045128)
		(width 0.14224)
		(layer "In11.Cu")
		(net "P5E_CPU0_P2_TX_BUF_C_DP<14>")
	)
	(segment
		(start 414.643062 -420.952168)
		(end 414.352232 -421.242998)
		(width 0.14224)
		(layer "In11.Cu")
		(net "P5E_CPU0_P2_TX_BUF_C_DP<14>")
	)
	(segment
		(start 414.352232 -421.242998)
		(end 414.352232 -421.899334)
		(width 0.14224)
		(layer "In11.Cu")
		(net "P5E_CPU0_P2_TX_BUF_C_DP<14>")
	)
	(segment
		(start 413.206692 -422.68775)
		(end 413.027368 -422.613582)
		(width 0.14224)
		(layer "In11.Cu")
		(net "P5E_CPU0_P2_TX_BUF_C_DP<14>")
	)
	(segment
		(start 413.601154 -422.524682)
		(end 413.206692 -422.68775)
		(width 0.14224)
		(layer "In11.Cu")
		(net "P5E_CPU0_P2_TX_BUF_C_DP<14>")
	)
	(segment
		(start 414.06953 -422.182036)
		(end 413.675322 -422.345104)
		(width 0.14224)
		(layer "In11.Cu")
		(net "P5E_CPU0_P2_TX_BUF_C_DP<14>")
	)
	(segment
		(start 410.72435 -424.114722)
		(end 410.530294 -424.114722)
		(width 0.14224)
		(layer "In11.Cu")
		(net "P5E_CPU0_P2_TX_BUF_C_DP<14>")
	)
	(segment
		(start 410.442156 -430.148746)
		(end 410.607764 -430.148746)
		(width 0.14224)
		(layer "In11.Cu")
		(net "P5E_CPU0_P2_TX_BUF_C_DP<14>")
	)
	(segment
		(start 413.675322 -422.345104)
		(end 413.601154 -422.524682)
		(width 0.14224)
		(layer "In11.Cu")
		(net "P5E_CPU0_P2_TX_BUF_C_DP<14>")
	)
	(segment
		(start 410.607764 -430.148746)
		(end 410.750004 -430.006506)
		(width 0.14224)
		(layer "In11.Cu")
		(net "P5E_CPU0_P2_TX_BUF_C_DP<14>")
	)
	(segment
		(start 410.750004 -430.006506)
		(end 410.750004 -429.689768)
		(width 0.14224)
		(layer "In11.Cu")
		(net "P5E_CPU0_P2_TX_BUF_C_DP<14>")
	)
	(segment
		(start 410.16174 -429.990504)
		(end 410.233622 -430.062386)
		(width 0.14224)
		(layer "In11.Cu")
		(net "P5E_CPU0_P2_TX_BUF_C_DP<14>")
	)
	(arc
		(start 410.080968 -429.795686)
		(mid 410.101961 -429.901135)
		(end 410.16174 -429.990504)
		(width 0.14224)
		(layer "In11.Cu")
		(net "P5E_CPU0_P2_TX_BUF_C_DP<14>")
	)
	(arc
		(start 410.201872 -424.443144)
		(mid 410.112373 -424.576899)
		(end 410.080968 -424.734736)
		(width 0.14224)
		(layer "In11.Cu")
		(net "P5E_CPU0_P2_TX_BUF_C_DP<14>")
	)
	(arc
		(start 410.233622 -430.062386)
		(mid 410.329298 -430.126315)
		(end 410.442156 -430.148746)
		(width 0.14224)
		(layer "In11.Cu")
		(net "P5E_CPU0_P2_TX_BUF_C_DP<14>")
	)
	(segment
		(start 411.605222 -417.166044)
		(end 411.309312 -417.461954)
		(width 0.12954)
		(layer "F.Cu")
		(net "P5E_CPU0_P2_TX_BUF_C_DP<13>")
	)
	(segment
		(start 411.309312 -417.461954)
		(end 411.309312 -420.681658)
		(width 0.12954)
		(layer "F.Cu")
		(net "P5E_CPU0_P2_TX_BUF_C_DP<13>")
	)
	(segment
		(start 411.309312 -420.681658)
		(end 411.579822 -420.952168)
		(width 0.12954)
		(layer "F.Cu")
		(net "P5E_CPU0_P2_TX_BUF_C_DP<13>")
	)
	(segment
		(start 408.579828 -423.799508)
		(end 408.218386 -424.041062)
		(width 0.14224)
		(layer "In11.Cu")
		(net "P5E_CPU0_P2_TX_BUF_C_DP<13>")
	)
	(segment
		(start 408.347672 -431.164746)
		(end 408.59202 -431.164746)
		(width 0.14224)
		(layer "In11.Cu")
		(net "P5E_CPU0_P2_TX_BUF_C_DP<13>")
	)
	(segment
		(start 409.162758 -423.409872)
		(end 409.124912 -423.600118)
		(width 0.14224)
		(layer "In11.Cu")
		(net "P5E_CPU0_P2_TX_BUF_C_DP<13>")
	)
	(segment
		(start 408.750008 -431.006758)
		(end 408.750008 -430.689766)
		(width 0.14224)
		(layer "In11.Cu")
		(net "P5E_CPU0_P2_TX_BUF_C_DP<13>")
	)
	(segment
		(start 409.707588 -423.210736)
		(end 409.517342 -423.17289)
		(width 0.14224)
		(layer "In11.Cu")
		(net "P5E_CPU0_P2_TX_BUF_C_DP<13>")
	)
	(segment
		(start 411.133544 -422.093136)
		(end 410.100526 -422.783254)
		(width 0.14224)
		(layer "In11.Cu")
		(net "P5E_CPU0_P2_TX_BUF_C_DP<13>")
	)
	(segment
		(start 411.579822 -420.952168)
		(end 411.288992 -421.242998)
		(width 0.14224)
		(layer "In11.Cu")
		(net "P5E_CPU0_P2_TX_BUF_C_DP<13>")
	)
	(segment
		(start 409.517342 -423.17289)
		(end 409.162758 -423.409872)
		(width 0.14224)
		(layer "In11.Cu")
		(net "P5E_CPU0_P2_TX_BUF_C_DP<13>")
	)
	(segment
		(start 411.288992 -421.242998)
		(end 411.288992 -421.802306)
		(width 0.14224)
		(layer "In11.Cu")
		(net "P5E_CPU0_P2_TX_BUF_C_DP<13>")
	)
	(segment
		(start 408.086052 -424.288204)
		(end 408.086052 -430.90338)
		(width 0.14224)
		(layer "In11.Cu")
		(net "P5E_CPU0_P2_TX_BUF_C_DP<13>")
	)
	(segment
		(start 409.124912 -423.600118)
		(end 408.770074 -423.837354)
		(width 0.14224)
		(layer "In11.Cu")
		(net "P5E_CPU0_P2_TX_BUF_C_DP<13>")
	)
	(segment
		(start 410.06268 -422.9735)
		(end 409.707588 -423.210736)
		(width 0.14224)
		(layer "In11.Cu")
		(net "P5E_CPU0_P2_TX_BUF_C_DP<13>")
	)
	(segment
		(start 408.59202 -431.164746)
		(end 408.750008 -431.006758)
		(width 0.14224)
		(layer "In11.Cu")
		(net "P5E_CPU0_P2_TX_BUF_C_DP<13>")
	)
	(segment
		(start 411.288992 -421.802306)
		(end 411.133544 -422.093136)
		(width 0.14224)
		(layer "In11.Cu")
		(net "P5E_CPU0_P2_TX_BUF_C_DP<13>")
	)
	(segment
		(start 408.218386 -424.041062)
		(end 408.086052 -424.288204)
		(width 0.14224)
		(layer "In11.Cu")
		(net "P5E_CPU0_P2_TX_BUF_C_DP<13>")
	)
	(segment
		(start 410.100526 -422.783254)
		(end 410.06268 -422.9735)
		(width 0.14224)
		(layer "In11.Cu")
		(net "P5E_CPU0_P2_TX_BUF_C_DP<13>")
	)
	(segment
		(start 408.770074 -423.837354)
		(end 408.579828 -423.799508)
		(width 0.14224)
		(layer "In11.Cu")
		(net "P5E_CPU0_P2_TX_BUF_C_DP<13>")
	)
	(arc
		(start 408.086052 -430.90338)
		(mid 408.162694 -431.088283)
		(end 408.347672 -431.164746)
		(width 0.14224)
		(layer "In11.Cu")
		(net "P5E_CPU0_P2_TX_BUF_C_DP<13>")
	)
	(segment
		(start 408.246072 -417.461954)
		(end 408.541982 -417.166044)
		(width 0.12954)
		(layer "F.Cu")
		(net "P5E_CPU0_P2_TX_BUF_C_DP<12>")
	)
	(segment
		(start 408.246072 -420.681658)
		(end 408.246072 -417.461954)
		(width 0.12954)
		(layer "F.Cu")
		(net "P5E_CPU0_P2_TX_BUF_C_DP<12>")
	)
	(segment
		(start 408.516582 -420.952168)
		(end 408.246072 -420.681658)
		(width 0.12954)
		(layer "F.Cu")
		(net "P5E_CPU0_P2_TX_BUF_C_DP<12>")
	)
	(segment
		(start 407.434542 -423.027348)
		(end 407.163524 -423.357548)
		(width 0.14224)
		(layer "In11.Cu")
		(net "P5E_CPU0_P2_TX_BUF_C_DP<12>")
	)
	(segment
		(start 408.048714 -422.293542)
		(end 407.825702 -422.565068)
		(width 0.14224)
		(layer "In11.Cu")
		(net "P5E_CPU0_P2_TX_BUF_C_DP<12>")
	)
	(segment
		(start 406.750012 -430.006506)
		(end 406.750012 -429.689768)
		(width 0.14224)
		(layer "In11.Cu")
		(net "P5E_CPU0_P2_TX_BUF_C_DP<12>")
	)
	(segment
		(start 406.301702 -424.190668)
		(end 406.077674 -424.463718)
		(width 0.14224)
		(layer "In11.Cu")
		(net "P5E_CPU0_P2_TX_BUF_C_DP<12>")
	)
	(segment
		(start 406.394158 -430.170336)
		(end 406.586182 -430.170336)
		(width 0.14224)
		(layer "In11.Cu")
		(net "P5E_CPU0_P2_TX_BUF_C_DP<12>")
	)
	(segment
		(start 407.163524 -423.357548)
		(end 406.969722 -423.376598)
		(width 0.14224)
		(layer "In11.Cu")
		(net "P5E_CPU0_P2_TX_BUF_C_DP<12>")
	)
	(segment
		(start 407.825702 -422.565068)
		(end 407.618946 -422.585642)
		(width 0.14224)
		(layer "In11.Cu")
		(net "P5E_CPU0_P2_TX_BUF_C_DP<12>")
	)
	(segment
		(start 406.479248 -424.173142)
		(end 406.301702 -424.190668)
		(width 0.14224)
		(layer "In11.Cu")
		(net "P5E_CPU0_P2_TX_BUF_C_DP<12>")
	)
	(segment
		(start 406.077674 -424.463718)
		(end 406.077674 -429.71339)
		(width 0.14224)
		(layer "In11.Cu")
		(net "P5E_CPU0_P2_TX_BUF_C_DP<12>")
	)
	(segment
		(start 408.225752 -421.852852)
		(end 408.028902 -422.092628)
		(width 0.14224)
		(layer "In11.Cu")
		(net "P5E_CPU0_P2_TX_BUF_C_DP<12>")
	)
	(segment
		(start 406.73274 -423.665396)
		(end 406.750266 -423.842942)
		(width 0.14224)
		(layer "In11.Cu")
		(net "P5E_CPU0_P2_TX_BUF_C_DP<12>")
	)
	(segment
		(start 406.586182 -430.170336)
		(end 406.750012 -430.006506)
		(width 0.14224)
		(layer "In11.Cu")
		(net "P5E_CPU0_P2_TX_BUF_C_DP<12>")
	)
	(segment
		(start 406.750266 -423.842942)
		(end 406.479248 -424.173142)
		(width 0.14224)
		(layer "In11.Cu")
		(net "P5E_CPU0_P2_TX_BUF_C_DP<12>")
	)
	(segment
		(start 407.618946 -422.585642)
		(end 407.415492 -422.833546)
		(width 0.14224)
		(layer "In11.Cu")
		(net "P5E_CPU0_P2_TX_BUF_C_DP<12>")
	)
	(segment
		(start 408.028902 -422.092628)
		(end 408.048714 -422.293542)
		(width 0.14224)
		(layer "In11.Cu")
		(net "P5E_CPU0_P2_TX_BUF_C_DP<12>")
	)
	(segment
		(start 406.969722 -423.376598)
		(end 406.73274 -423.665396)
		(width 0.14224)
		(layer "In11.Cu")
		(net "P5E_CPU0_P2_TX_BUF_C_DP<12>")
	)
	(segment
		(start 408.516582 -420.952168)
		(end 408.225752 -421.242998)
		(width 0.14224)
		(layer "In11.Cu")
		(net "P5E_CPU0_P2_TX_BUF_C_DP<12>")
	)
	(segment
		(start 406.214326 -430.043082)
		(end 406.304242 -430.132998)
		(width 0.14224)
		(layer "In11.Cu")
		(net "P5E_CPU0_P2_TX_BUF_C_DP<12>")
	)
	(segment
		(start 408.225752 -421.242998)
		(end 408.225752 -421.852852)
		(width 0.14224)
		(layer "In11.Cu")
		(net "P5E_CPU0_P2_TX_BUF_C_DP<12>")
	)
	(segment
		(start 407.415492 -422.833546)
		(end 407.434542 -423.027348)
		(width 0.14224)
		(layer "In11.Cu")
		(net "P5E_CPU0_P2_TX_BUF_C_DP<12>")
	)
	(arc
		(start 406.304242 -430.132998)
		(mid 406.345482 -430.160617)
		(end 406.394158 -430.170336)
		(width 0.14224)
		(layer "In11.Cu")
		(net "P5E_CPU0_P2_TX_BUF_C_DP<12>")
	)
	(arc
		(start 406.077674 -429.71339)
		(mid 406.083771 -429.788277)
		(end 406.101804 -429.861218)
		(width 0.14224)
		(layer "In11.Cu")
		(net "P5E_CPU0_P2_TX_BUF_C_DP<12>")
	)
	(arc
		(start 406.101804 -429.861218)
		(mid 406.147511 -429.958677)
		(end 406.214326 -430.043082)
		(width 0.14224)
		(layer "In11.Cu")
		(net "P5E_CPU0_P2_TX_BUF_C_DP<12>")
	)
	(segment
		(start 405.182832 -417.461954)
		(end 405.182832 -420.681658)
		(width 0.12954)
		(layer "F.Cu")
		(net "P5E_CPU0_P2_TX_BUF_C_DP<11>")
	)
	(segment
		(start 405.478742 -417.166044)
		(end 405.182832 -417.461954)
		(width 0.12954)
		(layer "F.Cu")
		(net "P5E_CPU0_P2_TX_BUF_C_DP<11>")
	)
	(segment
		(start 405.182832 -420.681658)
		(end 405.453342 -420.952168)
		(width 0.12954)
		(layer "F.Cu")
		(net "P5E_CPU0_P2_TX_BUF_C_DP<11>")
	)
	(segment
		(start 404.91029 -422.6179)
		(end 404.730712 -422.692322)
		(width 0.14224)
		(layer "In11.Cu")
		(net "P5E_CPU0_P2_TX_BUF_C_DP<11>")
	)
	(segment
		(start 404.641812 -423.2656)
		(end 404.47849 -423.660062)
		(width 0.14224)
		(layer "In11.Cu")
		(net "P5E_CPU0_P2_TX_BUF_C_DP<11>")
	)
	(segment
		(start 404.730712 -422.692322)
		(end 404.567644 -423.08653)
		(width 0.14224)
		(layer "In11.Cu")
		(net "P5E_CPU0_P2_TX_BUF_C_DP<11>")
	)
	(segment
		(start 405.162512 -421.242998)
		(end 405.162512 -421.65016)
		(width 0.14224)
		(layer "In11.Cu")
		(net "P5E_CPU0_P2_TX_BUF_C_DP<11>")
	)
	(segment
		(start 404.750016 -431.006758)
		(end 404.750016 -430.689766)
		(width 0.14224)
		(layer "In11.Cu")
		(net "P5E_CPU0_P2_TX_BUF_C_DP<11>")
	)
	(segment
		(start 405.073612 -422.223438)
		(end 404.91029 -422.6179)
		(width 0.14224)
		(layer "In11.Cu")
		(net "P5E_CPU0_P2_TX_BUF_C_DP<11>")
	)
	(segment
		(start 404.567644 -423.08653)
		(end 404.641812 -423.2656)
		(width 0.14224)
		(layer "In11.Cu")
		(net "P5E_CPU0_P2_TX_BUF_C_DP<11>")
	)
	(segment
		(start 404.381462 -431.148998)
		(end 404.607776 -431.148998)
		(width 0.14224)
		(layer "In11.Cu")
		(net "P5E_CPU0_P2_TX_BUF_C_DP<11>")
	)
	(segment
		(start 404.123144 -430.999138)
		(end 404.19655 -431.07229)
		(width 0.14224)
		(layer "In11.Cu")
		(net "P5E_CPU0_P2_TX_BUF_C_DP<11>")
	)
	(segment
		(start 404.999444 -422.044368)
		(end 405.073612 -422.223438)
		(width 0.14224)
		(layer "In11.Cu")
		(net "P5E_CPU0_P2_TX_BUF_C_DP<11>")
	)
	(segment
		(start 404.607776 -431.148998)
		(end 404.750016 -431.006758)
		(width 0.14224)
		(layer "In11.Cu")
		(net "P5E_CPU0_P2_TX_BUF_C_DP<11>")
	)
	(segment
		(start 405.453342 -420.952168)
		(end 405.162512 -421.242998)
		(width 0.14224)
		(layer "In11.Cu")
		(net "P5E_CPU0_P2_TX_BUF_C_DP<11>")
	)
	(segment
		(start 404.299166 -423.734484)
		(end 404.08606 -424.248834)
		(width 0.14224)
		(layer "In11.Cu")
		(net "P5E_CPU0_P2_TX_BUF_C_DP<11>")
	)
	(segment
		(start 404.08606 -430.909476)
		(end 404.086314 -430.909476)
		(width 0.14224)
		(layer "In11.Cu")
		(net "P5E_CPU0_P2_TX_BUF_C_DP<11>")
	)
	(segment
		(start 404.47849 -423.660062)
		(end 404.299166 -423.734484)
		(width 0.14224)
		(layer "In11.Cu")
		(net "P5E_CPU0_P2_TX_BUF_C_DP<11>")
	)
	(segment
		(start 405.162512 -421.65016)
		(end 404.999444 -422.044368)
		(width 0.14224)
		(layer "In11.Cu")
		(net "P5E_CPU0_P2_TX_BUF_C_DP<11>")
	)
	(segment
		(start 404.08606 -424.248834)
		(end 404.08606 -430.909476)
		(width 0.14224)
		(layer "In11.Cu")
		(net "P5E_CPU0_P2_TX_BUF_C_DP<11>")
	)
	(arc
		(start 404.086314 -430.909476)
		(mid 404.09583 -430.957964)
		(end 404.123144 -430.999138)
		(width 0.14224)
		(layer "In11.Cu")
		(net "P5E_CPU0_P2_TX_BUF_C_DP<11>")
	)
	(arc
		(start 404.19655 -431.07229)
		(mid 404.28136 -431.129085)
		(end 404.381462 -431.148998)
		(width 0.14224)
		(layer "In11.Cu")
		(net "P5E_CPU0_P2_TX_BUF_C_DP<11>")
	)
	(segment
		(start 402.415502 -417.166044)
		(end 402.119592 -417.461954)
		(width 0.12954)
		(layer "F.Cu")
		(net "P5E_CPU0_P2_TX_BUF_C_DP<10>")
	)
	(segment
		(start 402.119592 -417.461954)
		(end 402.119592 -420.681658)
		(width 0.12954)
		(layer "F.Cu")
		(net "P5E_CPU0_P2_TX_BUF_C_DP<10>")
	)
	(segment
		(start 402.119592 -420.681658)
		(end 402.390102 -420.952168)
		(width 0.12954)
		(layer "F.Cu")
		(net "P5E_CPU0_P2_TX_BUF_C_DP<10>")
	)
	(segment
		(start 402.080984 -421.261286)
		(end 402.080984 -421.688006)
		(width 0.14224)
		(layer "In11.Cu")
		(net "P5E_CPU0_P2_TX_BUF_C_DP<10>")
	)
	(segment
		(start 402.390102 -420.952168)
		(end 402.080984 -421.261286)
		(width 0.14224)
		(layer "In11.Cu")
		(net "P5E_CPU0_P2_TX_BUF_C_DP<10>")
	)
	(segment
		(start 402.372576 -430.148746)
		(end 402.60778 -430.148746)
		(width 0.14224)
		(layer "In11.Cu")
		(net "P5E_CPU0_P2_TX_BUF_C_DP<10>")
	)
	(segment
		(start 402.080984 -421.688006)
		(end 402.218144 -421.825166)
		(width 0.14224)
		(layer "In11.Cu")
		(net "P5E_CPU0_P2_TX_BUF_C_DP<10>")
	)
	(segment
		(start 402.080984 -423.516806)
		(end 402.080984 -423.943526)
		(width 0.14224)
		(layer "In11.Cu")
		(net "P5E_CPU0_P2_TX_BUF_C_DP<10>")
	)
	(segment
		(start 402.20265 -430.031398)
		(end 402.28266 -430.111408)
		(width 0.14224)
		(layer "In11.Cu")
		(net "P5E_CPU0_P2_TX_BUF_C_DP<10>")
	)
	(segment
		(start 402.218144 -423.379646)
		(end 402.080984 -423.516806)
		(width 0.14224)
		(layer "In11.Cu")
		(net "P5E_CPU0_P2_TX_BUF_C_DP<10>")
	)
	(segment
		(start 402.080984 -423.943526)
		(end 402.218144 -424.080686)
		(width 0.14224)
		(layer "In11.Cu")
		(net "P5E_CPU0_P2_TX_BUF_C_DP<10>")
	)
	(segment
		(start 402.218144 -421.825166)
		(end 402.218144 -422.251886)
		(width 0.14224)
		(layer "In11.Cu")
		(net "P5E_CPU0_P2_TX_BUF_C_DP<10>")
	)
	(segment
		(start 402.218144 -422.952926)
		(end 402.218144 -423.379646)
		(width 0.14224)
		(layer "In11.Cu")
		(net "P5E_CPU0_P2_TX_BUF_C_DP<10>")
	)
	(segment
		(start 402.218144 -424.507406)
		(end 402.080984 -424.644566)
		(width 0.14224)
		(layer "In11.Cu")
		(net "P5E_CPU0_P2_TX_BUF_C_DP<10>")
	)
	(segment
		(start 402.080984 -424.644566)
		(end 402.080984 -429.737774)
		(width 0.14224)
		(layer "In11.Cu")
		(net "P5E_CPU0_P2_TX_BUF_C_DP<10>")
	)
	(segment
		(start 402.218144 -424.080686)
		(end 402.218144 -424.507406)
		(width 0.14224)
		(layer "In11.Cu")
		(net "P5E_CPU0_P2_TX_BUF_C_DP<10>")
	)
	(segment
		(start 402.75002 -430.006506)
		(end 402.75002 -429.689768)
		(width 0.14224)
		(layer "In11.Cu")
		(net "P5E_CPU0_P2_TX_BUF_C_DP<10>")
	)
	(segment
		(start 402.080984 -422.389046)
		(end 402.080984 -422.815766)
		(width 0.14224)
		(layer "In11.Cu")
		(net "P5E_CPU0_P2_TX_BUF_C_DP<10>")
	)
	(segment
		(start 402.60778 -430.148746)
		(end 402.75002 -430.006506)
		(width 0.14224)
		(layer "In11.Cu")
		(net "P5E_CPU0_P2_TX_BUF_C_DP<10>")
	)
	(segment
		(start 402.218144 -422.251886)
		(end 402.080984 -422.389046)
		(width 0.14224)
		(layer "In11.Cu")
		(net "P5E_CPU0_P2_TX_BUF_C_DP<10>")
	)
	(segment
		(start 402.080984 -422.815766)
		(end 402.218144 -422.952926)
		(width 0.14224)
		(layer "In11.Cu")
		(net "P5E_CPU0_P2_TX_BUF_C_DP<10>")
	)
	(arc
		(start 402.080984 -429.737774)
		(mid 402.112611 -429.896684)
		(end 402.20265 -430.031398)
		(width 0.14224)
		(layer "In11.Cu")
		(net "P5E_CPU0_P2_TX_BUF_C_DP<10>")
	)
	(arc
		(start 402.28266 -430.111408)
		(mid 402.3239 -430.139027)
		(end 402.372576 -430.148746)
		(width 0.14224)
		(layer "In11.Cu")
		(net "P5E_CPU0_P2_TX_BUF_C_DP<10>")
	)
	(segment
		(start 371.681502 -414.903158)
		(end 371.385592 -415.199068)
		(width 0.12954)
		(layer "F.Cu")
		(net "P5E_CPU0_P2_TX_BUF_C_DP<0>")
	)
	(segment
		(start 371.385592 -415.199068)
		(end 371.385592 -419.367462)
		(width 0.12954)
		(layer "F.Cu")
		(net "P5E_CPU0_P2_TX_BUF_C_DP<0>")
	)
	(segment
		(start 371.385592 -419.367462)
		(end 371.487192 -419.469062)
		(width 0.12954)
		(layer "F.Cu")
		(net "P5E_CPU0_P2_TX_BUF_C_DP<0>")
	)
	(segment
		(start 371.487192 -420.681658)
		(end 371.757702 -420.952168)
		(width 0.12954)
		(layer "F.Cu")
		(net "P5E_CPU0_P2_TX_BUF_C_DP<0>")
	)
	(segment
		(start 371.487192 -419.469062)
		(end 371.487192 -420.681658)
		(width 0.12954)
		(layer "F.Cu")
		(net "P5E_CPU0_P2_TX_BUF_C_DP<0>")
	)
	(segment
		(start 371.608604 -421.944038)
		(end 371.466872 -421.802306)
		(width 0.14224)
		(layer "In11.Cu")
		(net "P5E_CPU0_P2_TX_BUF_C_DP<0>")
	)
	(segment
		(start 376.558048 -425.67098)
		(end 376.364246 -425.671996)
		(width 0.14224)
		(layer "In11.Cu")
		(net "P5E_CPU0_P2_TX_BUF_C_DP<0>")
	)
	(segment
		(start 371.466872 -421.242998)
		(end 371.757702 -420.952168)
		(width 0.14224)
		(layer "In11.Cu")
		(net "P5E_CPU0_P2_TX_BUF_C_DP<0>")
	)
	(segment
		(start 371.466872 -421.802306)
		(end 371.466872 -421.242998)
		(width 0.14224)
		(layer "In11.Cu")
		(net "P5E_CPU0_P2_TX_BUF_C_DP<0>")
	)
	(segment
		(start 380.896368 -430.149)
		(end 380.488952 -429.74641)
		(width 0.14224)
		(layer "In11.Cu")
		(net "P5E_CPU0_P2_TX_BUF_C_DP<0>")
	)
	(segment
		(start 380.487682 -429.552354)
		(end 380.183898 -429.25238)
		(width 0.14224)
		(layer "In11.Cu")
		(net "P5E_CPU0_P2_TX_BUF_C_DP<0>")
	)
	(segment
		(start 379.685296 -428.759874)
		(end 379.381258 -428.4599)
		(width 0.14224)
		(layer "In11.Cu")
		(net "P5E_CPU0_P2_TX_BUF_C_DP<0>")
	)
	(segment
		(start 373.533416 -422.875964)
		(end 373.069104 -422.549066)
		(width 0.14224)
		(layer "In11.Cu")
		(net "P5E_CPU0_P2_TX_BUF_C_DP<0>")
	)
	(segment
		(start 376.364246 -425.671996)
		(end 373.533416 -422.875964)
		(width 0.14224)
		(layer "In11.Cu")
		(net "P5E_CPU0_P2_TX_BUF_C_DP<0>")
	)
	(segment
		(start 376.863102 -426.16501)
		(end 376.862086 -425.970954)
		(width 0.14224)
		(layer "In11.Cu")
		(net "P5E_CPU0_P2_TX_BUF_C_DP<0>")
	)
	(segment
		(start 379.187456 -428.460916)
		(end 378.883926 -428.161196)
		(width 0.14224)
		(layer "In11.Cu")
		(net "P5E_CPU0_P2_TX_BUF_C_DP<0>")
	)
	(segment
		(start 380.183898 -429.25238)
		(end 379.989842 -429.25365)
		(width 0.14224)
		(layer "In11.Cu")
		(net "P5E_CPU0_P2_TX_BUF_C_DP<0>")
	)
	(segment
		(start 379.381258 -428.4599)
		(end 379.187456 -428.460916)
		(width 0.14224)
		(layer "In11.Cu")
		(net "P5E_CPU0_P2_TX_BUF_C_DP<0>")
	)
	(segment
		(start 379.686312 -428.95393)
		(end 379.685296 -428.759874)
		(width 0.14224)
		(layer "In11.Cu")
		(net "P5E_CPU0_P2_TX_BUF_C_DP<0>")
	)
	(segment
		(start 380.488952 -429.74641)
		(end 380.487682 -429.552354)
		(width 0.14224)
		(layer "In11.Cu")
		(net "P5E_CPU0_P2_TX_BUF_C_DP<0>")
	)
	(segment
		(start 381.749808 -429.689768)
		(end 381.290576 -430.149)
		(width 0.14224)
		(layer "In11.Cu")
		(net "P5E_CPU0_P2_TX_BUF_C_DP<0>")
	)
	(segment
		(start 378.578872 -427.667166)
		(end 378.38507 -427.668182)
		(width 0.14224)
		(layer "In11.Cu")
		(net "P5E_CPU0_P2_TX_BUF_C_DP<0>")
	)
	(segment
		(start 381.290576 -430.149)
		(end 380.896368 -430.149)
		(width 0.14224)
		(layer "In11.Cu")
		(net "P5E_CPU0_P2_TX_BUF_C_DP<0>")
	)
	(segment
		(start 379.989842 -429.25365)
		(end 379.686312 -428.95393)
		(width 0.14224)
		(layer "In11.Cu")
		(net "P5E_CPU0_P2_TX_BUF_C_DP<0>")
	)
	(segment
		(start 378.38507 -427.668182)
		(end 376.863102 -426.16501)
		(width 0.14224)
		(layer "In11.Cu")
		(net "P5E_CPU0_P2_TX_BUF_C_DP<0>")
	)
	(segment
		(start 378.883926 -428.161196)
		(end 378.88291 -427.96714)
		(width 0.14224)
		(layer "In11.Cu")
		(net "P5E_CPU0_P2_TX_BUF_C_DP<0>")
	)
	(segment
		(start 376.862086 -425.970954)
		(end 376.558048 -425.67098)
		(width 0.14224)
		(layer "In11.Cu")
		(net "P5E_CPU0_P2_TX_BUF_C_DP<0>")
	)
	(segment
		(start 378.88291 -427.96714)
		(end 378.578872 -427.667166)
		(width 0.14224)
		(layer "In11.Cu")
		(net "P5E_CPU0_P2_TX_BUF_C_DP<0>")
	)
	(segment
		(start 373.069104 -422.549066)
		(end 371.608604 -421.944038)
		(width 0.14224)
		(layer "In11.Cu")
		(net "P5E_CPU0_P2_TX_BUF_C_DP<0>")
	)
	(segment
		(start 398.437862 -417.166044)
		(end 398.733772 -417.461954)
		(width 0.12954)
		(layer "F.Cu")
		(net "P5E_CPU0_P2_TX_BUF_C_DN<9>")
	)
	(segment
		(start 398.733772 -420.681658)
		(end 398.463262 -420.952168)
		(width 0.12954)
		(layer "F.Cu")
		(net "P5E_CPU0_P2_TX_BUF_C_DN<9>")
	)
	(segment
		(start 398.733772 -417.461954)
		(end 398.733772 -420.681658)
		(width 0.12954)
		(layer "F.Cu")
		(net "P5E_CPU0_P2_TX_BUF_C_DN<9>")
	)
	(segment
		(start 398.463262 -420.952168)
		(end 398.754092 -421.242998)
		(width 0.14224)
		(layer "In11.Cu")
		(net "P5E_CPU0_P2_TX_BUF_C_DN<9>")
	)
	(segment
		(start 399.804128 -425.36872)
		(end 399.804128 -430.833276)
		(width 0.14224)
		(layer "In11.Cu")
		(net "P5E_CPU0_P2_TX_BUF_C_DN<9>")
	)
	(segment
		(start 398.754092 -421.904668)
		(end 399.059146 -422.911524)
		(width 0.14224)
		(layer "In11.Cu")
		(net "P5E_CPU0_P2_TX_BUF_C_DN<9>")
	)
	(segment
		(start 399.057876 -422.914318)
		(end 399.248376 -423.542968)
		(width 0.14224)
		(layer "In11.Cu")
		(net "P5E_CPU0_P2_TX_BUF_C_DN<9>")
	)
	(segment
		(start 400.325844 -431.430938)
		(end 400.607784 -431.430938)
		(width 0.14224)
		(layer "In11.Cu")
		(net "P5E_CPU0_P2_TX_BUF_C_DN<9>")
	)
	(segment
		(start 400.607784 -431.430938)
		(end 400.750024 -431.573178)
		(width 0.14224)
		(layer "In11.Cu")
		(net "P5E_CPU0_P2_TX_BUF_C_DN<9>")
	)
	(segment
		(start 399.25117 -423.544492)
		(end 399.804128 -425.36872)
		(width 0.14224)
		(layer "In11.Cu")
		(net "P5E_CPU0_P2_TX_BUF_C_DN<9>")
	)
	(segment
		(start 399.97761 -431.252122)
		(end 400.036538 -431.31105)
		(width 0.14224)
		(layer "In11.Cu")
		(net "P5E_CPU0_P2_TX_BUF_C_DN<9>")
	)
	(segment
		(start 400.750024 -431.573178)
		(end 400.750024 -431.889916)
		(width 0.14224)
		(layer "In11.Cu")
		(net "P5E_CPU0_P2_TX_BUF_C_DN<9>")
	)
	(segment
		(start 399.059146 -422.911524)
		(end 399.057876 -422.914318)
		(width 0.14224)
		(layer "In11.Cu")
		(net "P5E_CPU0_P2_TX_BUF_C_DN<9>")
	)
	(segment
		(start 398.754092 -421.242998)
		(end 398.754092 -421.904668)
		(width 0.14224)
		(layer "In11.Cu")
		(net "P5E_CPU0_P2_TX_BUF_C_DN<9>")
	)
	(segment
		(start 399.248376 -423.542968)
		(end 399.25117 -423.544492)
		(width 0.14224)
		(layer "In11.Cu")
		(net "P5E_CPU0_P2_TX_BUF_C_DN<9>")
	)
	(arc
		(start 399.804128 -430.833276)
		(mid 399.849216 -431.05995)
		(end 399.97761 -431.252122)
		(width 0.14224)
		(layer "In11.Cu")
		(net "P5E_CPU0_P2_TX_BUF_C_DN<9>")
	)
	(arc
		(start 400.036538 -431.31105)
		(mid 400.169258 -431.399794)
		(end 400.325844 -431.430938)
		(width 0.14224)
		(layer "In11.Cu")
		(net "P5E_CPU0_P2_TX_BUF_C_DN<9>")
	)
	(segment
		(start 395.670532 -417.461954)
		(end 395.670532 -420.681658)
		(width 0.12954)
		(layer "F.Cu")
		(net "P5E_CPU0_P2_TX_BUF_C_DN<8>")
	)
	(segment
		(start 395.374622 -417.166044)
		(end 395.670532 -417.461954)
		(width 0.12954)
		(layer "F.Cu")
		(net "P5E_CPU0_P2_TX_BUF_C_DN<8>")
	)
	(segment
		(start 395.670532 -420.681658)
		(end 395.400022 -420.952168)
		(width 0.12954)
		(layer "F.Cu")
		(net "P5E_CPU0_P2_TX_BUF_C_DN<8>")
	)
	(segment
		(start 395.920976 -422.270174)
		(end 396.57528 -423.849038)
		(width 0.14224)
		(layer "In11.Cu")
		(net "P5E_CPU0_P2_TX_BUF_C_DN<8>")
	)
	(segment
		(start 395.920976 -422.268142)
		(end 395.921992 -422.26865)
		(width 0.14224)
		(layer "In11.Cu")
		(net "P5E_CPU0_P2_TX_BUF_C_DN<8>")
	)
	(segment
		(start 396.577312 -423.8498)
		(end 396.785592 -424.353482)
		(width 0.14224)
		(layer "In11.Cu")
		(net "P5E_CPU0_P2_TX_BUF_C_DN<8>")
	)
	(segment
		(start 398.750028 -430.574196)
		(end 398.750028 -430.889918)
		(width 0.14224)
		(layer "In11.Cu")
		(net "P5E_CPU0_P2_TX_BUF_C_DN<8>")
	)
	(segment
		(start 397.868648 -430.143158)
		(end 397.942562 -430.217072)
		(width 0.14224)
		(layer "In11.Cu")
		(net "P5E_CPU0_P2_TX_BUF_C_DN<8>")
	)
	(segment
		(start 395.400022 -420.952168)
		(end 395.690852 -421.242998)
		(width 0.14224)
		(layer "In11.Cu")
		(net "P5E_CPU0_P2_TX_BUF_C_DN<8>")
	)
	(segment
		(start 398.606772 -430.43094)
		(end 398.750028 -430.574196)
		(width 0.14224)
		(layer "In11.Cu")
		(net "P5E_CPU0_P2_TX_BUF_C_DN<8>")
	)
	(segment
		(start 395.921992 -422.26865)
		(end 395.920976 -422.270174)
		(width 0.14224)
		(layer "In11.Cu")
		(net "P5E_CPU0_P2_TX_BUF_C_DN<8>")
	)
	(segment
		(start 395.690852 -421.242998)
		(end 395.690852 -421.711628)
		(width 0.14224)
		(layer "In11.Cu")
		(net "P5E_CPU0_P2_TX_BUF_C_DN<8>")
	)
	(segment
		(start 398.458944 -430.43094)
		(end 398.606772 -430.43094)
		(width 0.14224)
		(layer "In11.Cu")
		(net "P5E_CPU0_P2_TX_BUF_C_DN<8>")
	)
	(segment
		(start 396.784576 -424.355006)
		(end 397.643858 -426.428916)
		(width 0.14224)
		(layer "In11.Cu")
		(net "P5E_CPU0_P2_TX_BUF_C_DN<8>")
	)
	(segment
		(start 397.643858 -426.428916)
		(end 397.643858 -429.60036)
		(width 0.14224)
		(layer "In11.Cu")
		(net "P5E_CPU0_P2_TX_BUF_C_DN<8>")
	)
	(segment
		(start 396.785592 -424.353482)
		(end 396.784576 -424.355006)
		(width 0.14224)
		(layer "In11.Cu")
		(net "P5E_CPU0_P2_TX_BUF_C_DN<8>")
	)
	(segment
		(start 395.690852 -421.711628)
		(end 395.920976 -422.268142)
		(width 0.14224)
		(layer "In11.Cu")
		(net "P5E_CPU0_P2_TX_BUF_C_DN<8>")
	)
	(segment
		(start 396.57528 -423.849038)
		(end 396.577312 -423.8498)
		(width 0.14224)
		(layer "In11.Cu")
		(net "P5E_CPU0_P2_TX_BUF_C_DN<8>")
	)
	(arc
		(start 397.643858 -429.60036)
		(mid 397.702272 -429.894117)
		(end 397.868648 -430.143158)
		(width 0.14224)
		(layer "In11.Cu")
		(net "P5E_CPU0_P2_TX_BUF_C_DN<8>")
	)
	(arc
		(start 397.942562 -430.217072)
		(mid 398.17948 -430.375376)
		(end 398.458944 -430.43094)
		(width 0.14224)
		(layer "In11.Cu")
		(net "P5E_CPU0_P2_TX_BUF_C_DN<8>")
	)
	(segment
		(start 392.311382 -417.166044)
		(end 392.607292 -417.461954)
		(width 0.12954)
		(layer "F.Cu")
		(net "P5E_CPU0_P2_TX_BUF_C_DN<7>")
	)
	(segment
		(start 392.607292 -417.461954)
		(end 392.607292 -420.681658)
		(width 0.12954)
		(layer "F.Cu")
		(net "P5E_CPU0_P2_TX_BUF_C_DN<7>")
	)
	(segment
		(start 392.607292 -420.681658)
		(end 392.336782 -420.952168)
		(width 0.12954)
		(layer "F.Cu")
		(net "P5E_CPU0_P2_TX_BUF_C_DN<7>")
	)
	(segment
		(start 394.787374 -425.073064)
		(end 394.112242 -424.06316)
		(width 0.14224)
		(layer "In11.Cu")
		(net "P5E_CPU0_P2_TX_BUF_C_DN<7>")
	)
	(segment
		(start 393.922758 -423.778934)
		(end 392.627612 -421.84066)
		(width 0.14224)
		(layer "In11.Cu")
		(net "P5E_CPU0_P2_TX_BUF_C_DN<7>")
	)
	(segment
		(start 394.787374 -431.06213)
		(end 394.787374 -425.073064)
		(width 0.14224)
		(layer "In11.Cu")
		(net "P5E_CPU0_P2_TX_BUF_C_DN<7>")
	)
	(segment
		(start 394.112242 -424.062652)
		(end 393.922758 -423.779188)
		(width 0.14224)
		(layer "In11.Cu")
		(net "P5E_CPU0_P2_TX_BUF_C_DN<7>")
	)
	(segment
		(start 392.627612 -421.84066)
		(end 392.627612 -421.242998)
		(width 0.14224)
		(layer "In11.Cu")
		(net "P5E_CPU0_P2_TX_BUF_C_DN<7>")
	)
	(segment
		(start 393.922758 -423.779188)
		(end 393.922758 -423.778934)
		(width 0.14224)
		(layer "In11.Cu")
		(net "P5E_CPU0_P2_TX_BUF_C_DN<7>")
	)
	(segment
		(start 395.74978 -431.889916)
		(end 395.74978 -431.573178)
		(width 0.14224)
		(layer "In11.Cu")
		(net "P5E_CPU0_P2_TX_BUF_C_DN<7>")
	)
	(segment
		(start 395.156182 -431.430938)
		(end 394.787374 -431.06213)
		(width 0.14224)
		(layer "In11.Cu")
		(net "P5E_CPU0_P2_TX_BUF_C_DN<7>")
	)
	(segment
		(start 392.627612 -421.242998)
		(end 392.336782 -420.952168)
		(width 0.14224)
		(layer "In11.Cu")
		(net "P5E_CPU0_P2_TX_BUF_C_DN<7>")
	)
	(segment
		(start 394.112242 -424.06316)
		(end 394.112242 -424.062652)
		(width 0.14224)
		(layer "In11.Cu")
		(net "P5E_CPU0_P2_TX_BUF_C_DN<7>")
	)
	(segment
		(start 395.74978 -431.573178)
		(end 395.60754 -431.430938)
		(width 0.14224)
		(layer "In11.Cu")
		(net "P5E_CPU0_P2_TX_BUF_C_DN<7>")
	)
	(segment
		(start 395.60754 -431.430938)
		(end 395.156182 -431.430938)
		(width 0.14224)
		(layer "In11.Cu")
		(net "P5E_CPU0_P2_TX_BUF_C_DN<7>")
	)
	(segment
		(start 389.248142 -417.166044)
		(end 389.544052 -417.461954)
		(width 0.12954)
		(layer "F.Cu")
		(net "P5E_CPU0_P2_TX_BUF_C_DN<6>")
	)
	(segment
		(start 389.544052 -417.461954)
		(end 389.544052 -420.681658)
		(width 0.12954)
		(layer "F.Cu")
		(net "P5E_CPU0_P2_TX_BUF_C_DN<6>")
	)
	(segment
		(start 389.544052 -420.681658)
		(end 389.273542 -420.952168)
		(width 0.12954)
		(layer "F.Cu")
		(net "P5E_CPU0_P2_TX_BUF_C_DN<6>")
	)
	(segment
		(start 393.607036 -430.44491)
		(end 393.749784 -430.587658)
		(width 0.14224)
		(layer "In11.Cu")
		(net "P5E_CPU0_P2_TX_BUF_C_DN<6>")
	)
	(segment
		(start 392.728704 -424.229276)
		(end 392.798808 -424.359832)
		(width 0.14224)
		(layer "In11.Cu")
		(net "P5E_CPU0_P2_TX_BUF_C_DN<6>")
	)
	(segment
		(start 393.749784 -430.587658)
		(end 393.749784 -430.889918)
		(width 0.14224)
		(layer "In11.Cu")
		(net "P5E_CPU0_P2_TX_BUF_C_DN<6>")
	)
	(segment
		(start 389.646414 -422.169336)
		(end 392.728704 -424.229276)
		(width 0.14224)
		(layer "In11.Cu")
		(net "P5E_CPU0_P2_TX_BUF_C_DN<6>")
	)
	(segment
		(start 389.564372 -422.01592)
		(end 389.646414 -422.169336)
		(width 0.14224)
		(layer "In11.Cu")
		(net "P5E_CPU0_P2_TX_BUF_C_DN<6>")
	)
	(segment
		(start 389.273542 -420.952168)
		(end 389.564372 -421.242998)
		(width 0.14224)
		(layer "In11.Cu")
		(net "P5E_CPU0_P2_TX_BUF_C_DN<6>")
	)
	(segment
		(start 392.798808 -424.359832)
		(end 392.798808 -429.787558)
		(width 0.14224)
		(layer "In11.Cu")
		(net "P5E_CPU0_P2_TX_BUF_C_DN<6>")
	)
	(segment
		(start 392.967718 -430.195482)
		(end 393.03198 -430.259744)
		(width 0.14224)
		(layer "In11.Cu")
		(net "P5E_CPU0_P2_TX_BUF_C_DN<6>")
	)
	(segment
		(start 393.478766 -430.44491)
		(end 393.607036 -430.44491)
		(width 0.14224)
		(layer "In11.Cu")
		(net "P5E_CPU0_P2_TX_BUF_C_DN<6>")
	)
	(segment
		(start 389.564372 -421.242998)
		(end 389.564372 -422.01592)
		(width 0.14224)
		(layer "In11.Cu")
		(net "P5E_CPU0_P2_TX_BUF_C_DN<6>")
	)
	(arc
		(start 393.03198 -430.259744)
		(mid 393.236966 -430.396741)
		(end 393.478766 -430.44491)
		(width 0.14224)
		(layer "In11.Cu")
		(net "P5E_CPU0_P2_TX_BUF_C_DN<6>")
	)
	(arc
		(start 392.798808 -429.787558)
		(mid 392.842702 -430.008317)
		(end 392.967718 -430.195482)
		(width 0.14224)
		(layer "In11.Cu")
		(net "P5E_CPU0_P2_TX_BUF_C_DN<6>")
	)
	(segment
		(start 386.480812 -417.461954)
		(end 386.480812 -420.681658)
		(width 0.12954)
		(layer "F.Cu")
		(net "P5E_CPU0_P2_TX_BUF_C_DN<5>")
	)
	(segment
		(start 386.184902 -417.166044)
		(end 386.480812 -417.461954)
		(width 0.12954)
		(layer "F.Cu")
		(net "P5E_CPU0_P2_TX_BUF_C_DN<5>")
	)
	(segment
		(start 386.480812 -420.681658)
		(end 386.210302 -420.952168)
		(width 0.12954)
		(layer "F.Cu")
		(net "P5E_CPU0_P2_TX_BUF_C_DN<5>")
	)
	(segment
		(start 390.803892 -425.033694)
		(end 390.803892 -430.831244)
		(width 0.14224)
		(layer "In11.Cu")
		(net "P5E_CPU0_P2_TX_BUF_C_DN<5>")
	)
	(segment
		(start 388.583932 -422.759124)
		(end 388.772654 -422.947846)
		(width 0.14224)
		(layer "In11.Cu")
		(net "P5E_CPU0_P2_TX_BUF_C_DN<5>")
	)
	(segment
		(start 386.210302 -420.952168)
		(end 386.501132 -421.242998)
		(width 0.14224)
		(layer "In11.Cu")
		(net "P5E_CPU0_P2_TX_BUF_C_DN<5>")
	)
	(segment
		(start 386.501132 -421.74922)
		(end 387.043168 -422.29151)
		(width 0.14224)
		(layer "In11.Cu")
		(net "P5E_CPU0_P2_TX_BUF_C_DN<5>")
	)
	(segment
		(start 391.607548 -431.430938)
		(end 391.749788 -431.573178)
		(width 0.14224)
		(layer "In11.Cu")
		(net "P5E_CPU0_P2_TX_BUF_C_DN<5>")
	)
	(segment
		(start 391.749788 -431.573178)
		(end 391.749788 -431.889916)
		(width 0.14224)
		(layer "In11.Cu")
		(net "P5E_CPU0_P2_TX_BUF_C_DN<5>")
	)
	(segment
		(start 388.772654 -422.947846)
		(end 390.766554 -424.944032)
		(width 0.14224)
		(layer "In11.Cu")
		(net "P5E_CPU0_P2_TX_BUF_C_DN<5>")
	)
	(segment
		(start 387.043168 -422.29151)
		(end 388.583932 -422.759124)
		(width 0.14224)
		(layer "In11.Cu")
		(net "P5E_CPU0_P2_TX_BUF_C_DN<5>")
	)
	(segment
		(start 391.371074 -431.430938)
		(end 391.607548 -431.430938)
		(width 0.14224)
		(layer "In11.Cu")
		(net "P5E_CPU0_P2_TX_BUF_C_DN<5>")
	)
	(segment
		(start 390.978898 -431.253646)
		(end 391.004298 -431.279046)
		(width 0.14224)
		(layer "In11.Cu")
		(net "P5E_CPU0_P2_TX_BUF_C_DN<5>")
	)
	(segment
		(start 386.501132 -421.242998)
		(end 386.501132 -421.74922)
		(width 0.14224)
		(layer "In11.Cu")
		(net "P5E_CPU0_P2_TX_BUF_C_DN<5>")
	)
	(arc
		(start 391.004298 -431.279046)
		(mid 391.172576 -431.391486)
		(end 391.371074 -431.430938)
		(width 0.14224)
		(layer "In11.Cu")
		(net "P5E_CPU0_P2_TX_BUF_C_DN<5>")
	)
	(arc
		(start 390.766554 -424.944032)
		(mid 390.794124 -424.985154)
		(end 390.803892 -425.033694)
		(width 0.14224)
		(layer "In11.Cu")
		(net "P5E_CPU0_P2_TX_BUF_C_DN<5>")
	)
	(arc
		(start 390.803892 -430.831244)
		(mid 390.849382 -431.059848)
		(end 390.978898 -431.253646)
		(width 0.14224)
		(layer "In11.Cu")
		(net "P5E_CPU0_P2_TX_BUF_C_DN<5>")
	)
	(segment
		(start 383.417572 -417.461954)
		(end 383.417572 -420.681658)
		(width 0.12954)
		(layer "F.Cu")
		(net "P5E_CPU0_P2_TX_BUF_C_DN<4>")
	)
	(segment
		(start 383.121662 -417.166044)
		(end 383.417572 -417.461954)
		(width 0.12954)
		(layer "F.Cu")
		(net "P5E_CPU0_P2_TX_BUF_C_DN<4>")
	)
	(segment
		(start 383.417572 -420.681658)
		(end 383.147062 -420.952168)
		(width 0.12954)
		(layer "F.Cu")
		(net "P5E_CPU0_P2_TX_BUF_C_DN<4>")
	)
	(segment
		(start 389.622792 -430.459896)
		(end 389.749792 -430.586896)
		(width 0.14224)
		(layer "In11.Cu")
		(net "P5E_CPU0_P2_TX_BUF_C_DN<4>")
	)
	(segment
		(start 384.01371 -422.246298)
		(end 385.50977 -422.246298)
		(width 0.14224)
		(layer "In11.Cu")
		(net "P5E_CPU0_P2_TX_BUF_C_DN<4>")
	)
	(segment
		(start 385.50977 -422.246298)
		(end 387.127242 -423.86377)
		(width 0.14224)
		(layer "In11.Cu")
		(net "P5E_CPU0_P2_TX_BUF_C_DN<4>")
	)
	(segment
		(start 389.414512 -430.459896)
		(end 389.622792 -430.459896)
		(width 0.14224)
		(layer "In11.Cu")
		(net "P5E_CPU0_P2_TX_BUF_C_DN<4>")
	)
	(segment
		(start 387.563614 -424.044364)
		(end 387.793992 -424.044364)
		(width 0.14224)
		(layer "In11.Cu")
		(net "P5E_CPU0_P2_TX_BUF_C_DN<4>")
	)
	(segment
		(start 383.44348 -421.79748)
		(end 383.647696 -422.001696)
		(width 0.14224)
		(layer "In11.Cu")
		(net "P5E_CPU0_P2_TX_BUF_C_DN<4>")
	)
	(segment
		(start 383.44348 -421.248586)
		(end 383.44348 -421.79748)
		(width 0.14224)
		(layer "In11.Cu")
		(net "P5E_CPU0_P2_TX_BUF_C_DN<4>")
	)
	(segment
		(start 383.647696 -422.001696)
		(end 384.01371 -422.246298)
		(width 0.14224)
		(layer "In11.Cu")
		(net "P5E_CPU0_P2_TX_BUF_C_DN<4>")
	)
	(segment
		(start 389.749792 -430.586896)
		(end 389.749792 -430.889918)
		(width 0.14224)
		(layer "In11.Cu")
		(net "P5E_CPU0_P2_TX_BUF_C_DN<4>")
	)
	(segment
		(start 388.056374 -424.153076)
		(end 388.667498 -424.7642)
		(width 0.14224)
		(layer "In11.Cu")
		(net "P5E_CPU0_P2_TX_BUF_C_DN<4>")
	)
	(segment
		(start 383.147062 -420.952168)
		(end 383.44348 -421.248586)
		(width 0.14224)
		(layer "In11.Cu")
		(net "P5E_CPU0_P2_TX_BUF_C_DN<4>")
	)
	(segment
		(start 388.794244 -425.07027)
		(end 388.794244 -429.839628)
		(width 0.14224)
		(layer "In11.Cu")
		(net "P5E_CPU0_P2_TX_BUF_C_DN<4>")
	)
	(arc
		(start 387.793992 -424.044364)
		(mid 387.936004 -424.072612)
		(end 388.056374 -424.153076)
		(width 0.14224)
		(layer "In11.Cu")
		(net "P5E_CPU0_P2_TX_BUF_C_DN<4>")
	)
	(arc
		(start 388.794244 -429.839628)
		(mid 388.975916 -430.278224)
		(end 389.414512 -430.459896)
		(width 0.14224)
		(layer "In11.Cu")
		(net "P5E_CPU0_P2_TX_BUF_C_DN<4>")
	)
	(arc
		(start 388.667498 -424.7642)
		(mid 388.761328 -424.904626)
		(end 388.794244 -425.07027)
		(width 0.14224)
		(layer "In11.Cu")
		(net "P5E_CPU0_P2_TX_BUF_C_DN<4>")
	)
	(arc
		(start 387.127242 -423.86377)
		(mid 387.327452 -423.997516)
		(end 387.563614 -424.044364)
		(width 0.14224)
		(layer "In11.Cu")
		(net "P5E_CPU0_P2_TX_BUF_C_DN<4>")
	)
	(segment
		(start 380.354332 -420.681658)
		(end 380.083822 -420.952168)
		(width 0.12954)
		(layer "F.Cu")
		(net "P5E_CPU0_P2_TX_BUF_C_DN<3>")
	)
	(segment
		(start 380.058422 -417.166044)
		(end 380.354332 -417.461954)
		(width 0.12954)
		(layer "F.Cu")
		(net "P5E_CPU0_P2_TX_BUF_C_DN<3>")
	)
	(segment
		(start 380.354332 -417.461954)
		(end 380.354332 -420.681658)
		(width 0.12954)
		(layer "F.Cu")
		(net "P5E_CPU0_P2_TX_BUF_C_DN<3>")
	)
	(segment
		(start 380.083822 -420.952168)
		(end 380.374652 -421.242998)
		(width 0.14224)
		(layer "In11.Cu")
		(net "P5E_CPU0_P2_TX_BUF_C_DN<3>")
	)
	(segment
		(start 384.013456 -423.179748)
		(end 384.9116 -423.179748)
		(width 0.14224)
		(layer "In11.Cu")
		(net "P5E_CPU0_P2_TX_BUF_C_DN<3>")
	)
	(segment
		(start 387.156198 -431.430938)
		(end 387.607556 -431.430938)
		(width 0.14224)
		(layer "In11.Cu")
		(net "P5E_CPU0_P2_TX_BUF_C_DN<3>")
	)
	(segment
		(start 380.374652 -421.242998)
		(end 380.374652 -421.862504)
		(width 0.14224)
		(layer "In11.Cu")
		(net "P5E_CPU0_P2_TX_BUF_C_DN<3>")
	)
	(segment
		(start 385.001516 -423.217086)
		(end 386.691886 -424.907456)
		(width 0.14224)
		(layer "In11.Cu")
		(net "P5E_CPU0_P2_TX_BUF_C_DN<3>")
	)
	(segment
		(start 382.43383 -422.320212)
		(end 383.473706 -423.015918)
		(width 0.14224)
		(layer "In11.Cu")
		(net "P5E_CPU0_P2_TX_BUF_C_DN<3>")
	)
	(segment
		(start 387.749796 -431.573178)
		(end 387.749796 -431.889916)
		(width 0.14224)
		(layer "In11.Cu")
		(net "P5E_CPU0_P2_TX_BUF_C_DN<3>")
	)
	(segment
		(start 386.8039 -431.07864)
		(end 387.156198 -431.430938)
		(width 0.14224)
		(layer "In11.Cu")
		(net "P5E_CPU0_P2_TX_BUF_C_DN<3>")
	)
	(segment
		(start 380.83236 -422.320212)
		(end 382.43383 -422.320212)
		(width 0.14224)
		(layer "In11.Cu")
		(net "P5E_CPU0_P2_TX_BUF_C_DN<3>")
	)
	(segment
		(start 387.607556 -431.430938)
		(end 387.749796 -431.573178)
		(width 0.14224)
		(layer "In11.Cu")
		(net "P5E_CPU0_P2_TX_BUF_C_DN<3>")
	)
	(segment
		(start 380.374652 -421.862504)
		(end 380.83236 -422.320212)
		(width 0.14224)
		(layer "In11.Cu")
		(net "P5E_CPU0_P2_TX_BUF_C_DN<3>")
	)
	(segment
		(start 386.8039 -425.177712)
		(end 386.8039 -431.07864)
		(width 0.14224)
		(layer "In11.Cu")
		(net "P5E_CPU0_P2_TX_BUF_C_DN<3>")
	)
	(arc
		(start 386.691886 -424.907456)
		(mid 386.77479 -425.031436)
		(end 386.8039 -425.177712)
		(width 0.14224)
		(layer "In11.Cu")
		(net "P5E_CPU0_P2_TX_BUF_C_DN<3>")
	)
	(arc
		(start 383.473706 -423.015918)
		(mid 383.731423 -423.137888)
		(end 384.013456 -423.179748)
		(width 0.14224)
		(layer "In11.Cu")
		(net "P5E_CPU0_P2_TX_BUF_C_DN<3>")
	)
	(arc
		(start 384.9116 -423.179748)
		(mid 384.960284 -423.18945)
		(end 385.001516 -423.217086)
		(width 0.14224)
		(layer "In11.Cu")
		(net "P5E_CPU0_P2_TX_BUF_C_DN<3>")
	)
	(segment
		(start 376.995182 -417.166044)
		(end 377.291092 -417.461954)
		(width 0.12954)
		(layer "F.Cu")
		(net "P5E_CPU0_P2_TX_BUF_C_DN<2>")
	)
	(segment
		(start 377.291092 -417.461954)
		(end 377.291092 -420.681658)
		(width 0.12954)
		(layer "F.Cu")
		(net "P5E_CPU0_P2_TX_BUF_C_DN<2>")
	)
	(segment
		(start 377.291092 -420.681658)
		(end 377.020582 -420.952168)
		(width 0.12954)
		(layer "F.Cu")
		(net "P5E_CPU0_P2_TX_BUF_C_DN<2>")
	)
	(segment
		(start 377.311412 -421.242998)
		(end 377.311412 -422.97223)
		(width 0.14224)
		(layer "In11.Cu")
		(net "P5E_CPU0_P2_TX_BUF_C_DN<2>")
	)
	(segment
		(start 381.988314 -423.264584)
		(end 382.460246 -423.45991)
		(width 0.14224)
		(layer "In11.Cu")
		(net "P5E_CPU0_P2_TX_BUF_C_DN<2>")
	)
	(segment
		(start 377.603766 -423.264584)
		(end 381.988314 -423.264584)
		(width 0.14224)
		(layer "In11.Cu")
		(net "P5E_CPU0_P2_TX_BUF_C_DN<2>")
	)
	(segment
		(start 383.662174 -424.108372)
		(end 383.865374 -424.108372)
		(width 0.14224)
		(layer "In11.Cu")
		(net "P5E_CPU0_P2_TX_BUF_C_DN<2>")
	)
	(segment
		(start 384.798824 -425.74083)
		(end 384.798824 -429.753268)
		(width 0.14224)
		(layer "In11.Cu")
		(net "P5E_CPU0_P2_TX_BUF_C_DN<2>")
	)
	(segment
		(start 384.140456 -424.222418)
		(end 384.190494 -424.272456)
		(width 0.14224)
		(layer "In11.Cu")
		(net "P5E_CPU0_P2_TX_BUF_C_DN<2>")
	)
	(segment
		(start 385.384548 -430.435766)
		(end 385.61264 -430.435766)
		(width 0.14224)
		(layer "In11.Cu")
		(net "P5E_CPU0_P2_TX_BUF_C_DN<2>")
	)
	(segment
		(start 385.61264 -430.435766)
		(end 385.7498 -430.572926)
		(width 0.14224)
		(layer "In11.Cu")
		(net "P5E_CPU0_P2_TX_BUF_C_DN<2>")
	)
	(segment
		(start 382.460246 -423.45991)
		(end 383.237232 -423.979594)
		(width 0.14224)
		(layer "In11.Cu")
		(net "P5E_CPU0_P2_TX_BUF_C_DN<2>")
	)
	(segment
		(start 377.020582 -420.952168)
		(end 377.311412 -421.242998)
		(width 0.14224)
		(layer "In11.Cu")
		(net "P5E_CPU0_P2_TX_BUF_C_DN<2>")
	)
	(segment
		(start 385.7498 -430.572926)
		(end 385.7498 -430.889918)
		(width 0.14224)
		(layer "In11.Cu")
		(net "P5E_CPU0_P2_TX_BUF_C_DN<2>")
	)
	(segment
		(start 377.311412 -422.97223)
		(end 377.603766 -423.264584)
		(width 0.14224)
		(layer "In11.Cu")
		(net "P5E_CPU0_P2_TX_BUF_C_DN<2>")
	)
	(arc
		(start 383.865374 -424.108372)
		(mid 384.014273 -424.138008)
		(end 384.140456 -424.222418)
		(width 0.14224)
		(layer "In11.Cu")
		(net "P5E_CPU0_P2_TX_BUF_C_DN<2>")
	)
	(arc
		(start 385.018788 -430.284128)
		(mid 385.186586 -430.39631)
		(end 385.384548 -430.435766)
		(width 0.14224)
		(layer "In11.Cu")
		(net "P5E_CPU0_P2_TX_BUF_C_DN<2>")
	)
	(arc
		(start 384.190494 -424.272456)
		(mid 384.640697 -424.946137)
		(end 384.798824 -425.74083)
		(width 0.14224)
		(layer "In11.Cu")
		(net "P5E_CPU0_P2_TX_BUF_C_DN<2>")
	)
	(arc
		(start 383.237232 -423.979594)
		(mid 383.440144 -424.075517)
		(end 383.662174 -424.108372)
		(width 0.14224)
		(layer "In11.Cu")
		(net "P5E_CPU0_P2_TX_BUF_C_DN<2>")
	)
	(arc
		(start 384.798824 -429.753268)
		(mid 384.855992 -430.040582)
		(end 385.018788 -430.284128)
		(width 0.14224)
		(layer "In11.Cu")
		(net "P5E_CPU0_P2_TX_BUF_C_DN<2>")
	)
	(segment
		(start 374.227852 -420.681658)
		(end 373.957342 -420.952168)
		(width 0.12954)
		(layer "F.Cu")
		(net "P5E_CPU0_P2_TX_BUF_C_DN<1>")
	)
	(segment
		(start 373.931942 -417.166044)
		(end 374.227852 -417.461954)
		(width 0.12954)
		(layer "F.Cu")
		(net "P5E_CPU0_P2_TX_BUF_C_DN<1>")
	)
	(segment
		(start 374.227852 -417.461954)
		(end 374.227852 -420.681658)
		(width 0.12954)
		(layer "F.Cu")
		(net "P5E_CPU0_P2_TX_BUF_C_DN<1>")
	)
	(segment
		(start 383.607564 -431.430938)
		(end 383.749804 -431.573178)
		(width 0.14224)
		(layer "In11.Cu")
		(net "P5E_CPU0_P2_TX_BUF_C_DN<1>")
	)
	(segment
		(start 382.06426 -424.308016)
		(end 382.176528 -424.383454)
		(width 0.14224)
		(layer "In11.Cu")
		(net "P5E_CPU0_P2_TX_BUF_C_DN<1>")
	)
	(segment
		(start 373.957342 -420.952168)
		(end 374.248172 -421.242998)
		(width 0.14224)
		(layer "In11.Cu")
		(net "P5E_CPU0_P2_TX_BUF_C_DN<1>")
	)
	(segment
		(start 383.425446 -431.430938)
		(end 383.607564 -431.430938)
		(width 0.14224)
		(layer "In11.Cu")
		(net "P5E_CPU0_P2_TX_BUF_C_DN<1>")
	)
	(segment
		(start 383.749804 -431.573178)
		(end 383.749804 -431.889916)
		(width 0.14224)
		(layer "In11.Cu")
		(net "P5E_CPU0_P2_TX_BUF_C_DN<1>")
	)
	(segment
		(start 376.774202 -424.238674)
		(end 381.89662 -424.238674)
		(width 0.14224)
		(layer "In11.Cu")
		(net "P5E_CPU0_P2_TX_BUF_C_DN<1>")
	)
	(segment
		(start 381.89662 -424.238674)
		(end 382.06426 -424.308016)
		(width 0.14224)
		(layer "In11.Cu")
		(net "P5E_CPU0_P2_TX_BUF_C_DN<1>")
	)
	(segment
		(start 382.923796 -431.198528)
		(end 382.965706 -431.240438)
		(width 0.14224)
		(layer "In11.Cu")
		(net "P5E_CPU0_P2_TX_BUF_C_DN<1>")
	)
	(segment
		(start 374.248172 -421.242998)
		(end 374.248172 -421.651176)
		(width 0.14224)
		(layer "In11.Cu")
		(net "P5E_CPU0_P2_TX_BUF_C_DN<1>")
	)
	(segment
		(start 382.803908 -425.559982)
		(end 382.803908 -430.909222)
		(width 0.14224)
		(layer "In11.Cu")
		(net "P5E_CPU0_P2_TX_BUF_C_DN<1>")
	)
	(segment
		(start 374.411494 -422.045384)
		(end 376.484896 -424.118786)
		(width 0.14224)
		(layer "In11.Cu")
		(net "P5E_CPU0_P2_TX_BUF_C_DN<1>")
	)
	(arc
		(start 374.248172 -421.651176)
		(mid 374.290611 -421.864533)
		(end 374.411494 -422.045384)
		(width 0.14224)
		(layer "In11.Cu")
		(net "P5E_CPU0_P2_TX_BUF_C_DN<1>")
	)
	(arc
		(start 382.803908 -430.909222)
		(mid 382.835071 -431.0658)
		(end 382.923796 -431.198528)
		(width 0.14224)
		(layer "In11.Cu")
		(net "P5E_CPU0_P2_TX_BUF_C_DN<1>")
	)
	(arc
		(start 376.484896 -424.118786)
		(mid 376.617616 -424.20753)
		(end 376.774202 -424.238674)
		(width 0.14224)
		(layer "In11.Cu")
		(net "P5E_CPU0_P2_TX_BUF_C_DN<1>")
	)
	(arc
		(start 382.176528 -424.383454)
		(mid 382.637279 -424.893301)
		(end 382.803908 -425.559982)
		(width 0.14224)
		(layer "In11.Cu")
		(net "P5E_CPU0_P2_TX_BUF_C_DN<1>")
	)
	(arc
		(start 382.965706 -431.240438)
		(mid 383.176622 -431.381431)
		(end 383.425446 -431.430938)
		(width 0.14224)
		(layer "In11.Cu")
		(net "P5E_CPU0_P2_TX_BUF_C_DN<1>")
	)
	(segment
		(start 416.817302 -417.166044)
		(end 417.113212 -417.461954)
		(width 0.12954)
		(layer "F.Cu")
		(net "P5E_CPU0_P2_TX_BUF_C_DN<15>")
	)
	(segment
		(start 417.113212 -420.681658)
		(end 416.842702 -420.952168)
		(width 0.12954)
		(layer "F.Cu")
		(net "P5E_CPU0_P2_TX_BUF_C_DN<15>")
	)
	(segment
		(start 417.113212 -417.461954)
		(end 417.113212 -420.681658)
		(width 0.12954)
		(layer "F.Cu")
		(net "P5E_CPU0_P2_TX_BUF_C_DN<15>")
	)
	(segment
		(start 416.60826 -422.335706)
		(end 414.484312 -423.096182)
		(width 0.14224)
		(layer "In11.Cu")
		(net "P5E_CPU0_P2_TX_BUF_C_DN<15>")
	)
	(segment
		(start 412.32582 -431.430938)
		(end 412.60776 -431.430938)
		(width 0.14224)
		(layer "In11.Cu")
		(net "P5E_CPU0_P2_TX_BUF_C_DN<15>")
	)
	(segment
		(start 417.150042 -421.259508)
		(end 417.150042 -421.738552)
		(width 0.14224)
		(layer "In11.Cu")
		(net "P5E_CPU0_P2_TX_BUF_C_DN<15>")
	)
	(segment
		(start 411.804104 -424.846496)
		(end 411.804104 -430.875694)
		(width 0.14224)
		(layer "In11.Cu")
		(net "P5E_CPU0_P2_TX_BUF_C_DN<15>")
	)
	(segment
		(start 412.60776 -431.430938)
		(end 412.75 -431.573178)
		(width 0.14224)
		(layer "In11.Cu")
		(net "P5E_CPU0_P2_TX_BUF_C_DN<15>")
	)
	(segment
		(start 416.714178 -422.26865)
		(end 416.713924 -422.26865)
		(width 0.14224)
		(layer "In11.Cu")
		(net "P5E_CPU0_P2_TX_BUF_C_DN<15>")
	)
	(segment
		(start 416.842702 -420.952168)
		(end 417.150042 -421.259508)
		(width 0.14224)
		(layer "In11.Cu")
		(net "P5E_CPU0_P2_TX_BUF_C_DN<15>")
	)
	(segment
		(start 414.484312 -423.096436)
		(end 412.37789 -423.850054)
		(width 0.14224)
		(layer "In11.Cu")
		(net "P5E_CPU0_P2_TX_BUF_C_DN<15>")
	)
	(segment
		(start 417.083494 -421.899334)
		(end 416.714178 -422.26865)
		(width 0.14224)
		(layer "In11.Cu")
		(net "P5E_CPU0_P2_TX_BUF_C_DN<15>")
	)
	(segment
		(start 414.484312 -423.096182)
		(end 414.484312 -423.096436)
		(width 0.14224)
		(layer "In11.Cu")
		(net "P5E_CPU0_P2_TX_BUF_C_DN<15>")
	)
	(segment
		(start 411.947614 -431.22215)
		(end 412.036514 -431.31105)
		(width 0.14224)
		(layer "In11.Cu")
		(net "P5E_CPU0_P2_TX_BUF_C_DN<15>")
	)
	(segment
		(start 412.75 -431.573178)
		(end 412.75 -431.889916)
		(width 0.14224)
		(layer "In11.Cu")
		(net "P5E_CPU0_P2_TX_BUF_C_DN<15>")
	)
	(arc
		(start 412.37789 -423.850054)
		(mid 412.19738 -423.946523)
		(end 412.05277 -424.091354)
		(width 0.14224)
		(layer "In11.Cu")
		(net "P5E_CPU0_P2_TX_BUF_C_DN<15>")
	)
	(arc
		(start 417.150042 -421.738552)
		(mid 417.132806 -421.825587)
		(end 417.083494 -421.899334)
		(width 0.14224)
		(layer "In11.Cu")
		(net "P5E_CPU0_P2_TX_BUF_C_DN<15>")
	)
	(arc
		(start 416.672268 -422.303194)
		(mid 416.641287 -422.321464)
		(end 416.60826 -422.335706)
		(width 0.14224)
		(layer "In11.Cu")
		(net "P5E_CPU0_P2_TX_BUF_C_DN<15>")
	)
	(arc
		(start 412.05277 -424.091354)
		(mid 411.867808 -424.448958)
		(end 411.804104 -424.846496)
		(width 0.14224)
		(layer "In11.Cu")
		(net "P5E_CPU0_P2_TX_BUF_C_DN<15>")
	)
	(arc
		(start 411.804104 -430.875694)
		(mid 411.8414 -431.063196)
		(end 411.947614 -431.22215)
		(width 0.14224)
		(layer "In11.Cu")
		(net "P5E_CPU0_P2_TX_BUF_C_DN<15>")
	)
	(arc
		(start 416.713924 -422.26865)
		(mid 416.693909 -422.286903)
		(end 416.672268 -422.303194)
		(width 0.14224)
		(layer "In11.Cu")
		(net "P5E_CPU0_P2_TX_BUF_C_DN<15>")
	)
	(arc
		(start 412.036514 -431.31105)
		(mid 412.169234 -431.399794)
		(end 412.32582 -431.430938)
		(width 0.14224)
		(layer "In11.Cu")
		(net "P5E_CPU0_P2_TX_BUF_C_DN<15>")
	)
	(segment
		(start 414.049972 -417.461954)
		(end 414.049972 -420.681658)
		(width 0.12954)
		(layer "F.Cu")
		(net "P5E_CPU0_P2_TX_BUF_C_DN<14>")
	)
	(segment
		(start 414.049972 -420.681658)
		(end 413.779462 -420.952168)
		(width 0.12954)
		(layer "F.Cu")
		(net "P5E_CPU0_P2_TX_BUF_C_DN<14>")
	)
	(segment
		(start 413.754062 -417.166044)
		(end 414.049972 -417.461954)
		(width 0.12954)
		(layer "F.Cu")
		(net "P5E_CPU0_P2_TX_BUF_C_DN<14>")
	)
	(segment
		(start 413.779462 -420.952168)
		(end 414.070292 -421.242998)
		(width 0.14224)
		(layer "In11.Cu")
		(net "P5E_CPU0_P2_TX_BUF_C_DN<14>")
	)
	(segment
		(start 414.070292 -421.242998)
		(end 414.070292 -421.782494)
		(width 0.14224)
		(layer "In11.Cu")
		(net "P5E_CPU0_P2_TX_BUF_C_DN<14>")
	)
	(segment
		(start 410.750004 -430.572926)
		(end 410.750004 -430.889918)
		(width 0.14224)
		(layer "In11.Cu")
		(net "P5E_CPU0_P2_TX_BUF_C_DN<14>")
	)
	(segment
		(start 409.96235 -430.189894)
		(end 410.034232 -430.261776)
		(width 0.14224)
		(layer "In11.Cu")
		(net "P5E_CPU0_P2_TX_BUF_C_DN<14>")
	)
	(segment
		(start 414.070292 -421.782494)
		(end 413.909764 -421.943022)
		(width 0.14224)
		(layer "In11.Cu")
		(net "P5E_CPU0_P2_TX_BUF_C_DN<14>")
	)
	(segment
		(start 413.909764 -421.943022)
		(end 412.33471 -422.59504)
		(width 0.14224)
		(layer "In11.Cu")
		(net "P5E_CPU0_P2_TX_BUF_C_DN<14>")
	)
	(segment
		(start 410.607764 -430.430686)
		(end 410.750004 -430.572926)
		(width 0.14224)
		(layer "In11.Cu")
		(net "P5E_CPU0_P2_TX_BUF_C_DN<14>")
	)
	(segment
		(start 410.442156 -430.430686)
		(end 410.607764 -430.430686)
		(width 0.14224)
		(layer "In11.Cu")
		(net "P5E_CPU0_P2_TX_BUF_C_DN<14>")
	)
	(segment
		(start 409.799028 -424.734736)
		(end 409.799028 -429.795686)
		(width 0.14224)
		(layer "In11.Cu")
		(net "P5E_CPU0_P2_TX_BUF_C_DN<14>")
	)
	(segment
		(start 411.168088 -423.078148)
		(end 410.002482 -424.243754)
		(width 0.14224)
		(layer "In11.Cu")
		(net "P5E_CPU0_P2_TX_BUF_C_DN<14>")
	)
	(segment
		(start 412.33471 -422.59504)
		(end 411.168088 -423.078148)
		(width 0.14224)
		(layer "In11.Cu")
		(net "P5E_CPU0_P2_TX_BUF_C_DN<14>")
	)
	(arc
		(start 409.799028 -429.795686)
		(mid 409.841467 -430.009043)
		(end 409.96235 -430.189894)
		(width 0.14224)
		(layer "In11.Cu")
		(net "P5E_CPU0_P2_TX_BUF_C_DN<14>")
	)
	(arc
		(start 410.034232 -430.261776)
		(mid 410.221403 -430.386777)
		(end 410.442156 -430.430686)
		(width 0.14224)
		(layer "In11.Cu")
		(net "P5E_CPU0_P2_TX_BUF_C_DN<14>")
	)
	(arc
		(start 410.002482 -424.243754)
		(mid 409.851911 -424.469004)
		(end 409.799028 -424.734736)
		(width 0.14224)
		(layer "In11.Cu")
		(net "P5E_CPU0_P2_TX_BUF_C_DN<14>")
	)
	(segment
		(start 410.986732 -420.681658)
		(end 410.716222 -420.952168)
		(width 0.12954)
		(layer "F.Cu")
		(net "P5E_CPU0_P2_TX_BUF_C_DN<13>")
	)
	(segment
		(start 410.690822 -417.166044)
		(end 410.986732 -417.461954)
		(width 0.12954)
		(layer "F.Cu")
		(net "P5E_CPU0_P2_TX_BUF_C_DN<13>")
	)
	(segment
		(start 410.986732 -417.461954)
		(end 410.986732 -420.681658)
		(width 0.12954)
		(layer "F.Cu")
		(net "P5E_CPU0_P2_TX_BUF_C_DN<13>")
	)
	(segment
		(start 408.347926 -431.446686)
		(end 408.623008 -431.446686)
		(width 0.14224)
		(layer "In11.Cu")
		(net "P5E_CPU0_P2_TX_BUF_C_DN<13>")
	)
	(segment
		(start 408.623008 -431.446686)
		(end 408.750008 -431.573686)
		(width 0.14224)
		(layer "In11.Cu")
		(net "P5E_CPU0_P2_TX_BUF_C_DN<13>")
	)
	(segment
		(start 411.007052 -421.73144)
		(end 410.917898 -421.89781)
		(width 0.14224)
		(layer "In11.Cu")
		(net "P5E_CPU0_P2_TX_BUF_C_DN<13>")
	)
	(segment
		(start 411.007052 -421.242998)
		(end 411.007052 -421.73144)
		(width 0.14224)
		(layer "In11.Cu")
		(net "P5E_CPU0_P2_TX_BUF_C_DN<13>")
	)
	(segment
		(start 407.804112 -424.217592)
		(end 407.804112 -430.903634)
		(width 0.14224)
		(layer "In11.Cu")
		(net "P5E_CPU0_P2_TX_BUF_C_DN<13>")
	)
	(segment
		(start 408.750008 -431.573686)
		(end 408.750008 -431.889916)
		(width 0.14224)
		(layer "In11.Cu")
		(net "P5E_CPU0_P2_TX_BUF_C_DN<13>")
	)
	(segment
		(start 410.917898 -421.89781)
		(end 408.00274 -423.845736)
		(width 0.14224)
		(layer "In11.Cu")
		(net "P5E_CPU0_P2_TX_BUF_C_DN<13>")
	)
	(segment
		(start 408.00274 -423.845736)
		(end 407.804112 -424.217592)
		(width 0.14224)
		(layer "In11.Cu")
		(net "P5E_CPU0_P2_TX_BUF_C_DN<13>")
	)
	(segment
		(start 410.716222 -420.952168)
		(end 411.007052 -421.242998)
		(width 0.14224)
		(layer "In11.Cu")
		(net "P5E_CPU0_P2_TX_BUF_C_DN<13>")
	)
	(arc
		(start 407.804112 -430.903634)
		(mid 407.963512 -431.287825)
		(end 408.347926 -431.446686)
		(width 0.14224)
		(layer "In11.Cu")
		(net "P5E_CPU0_P2_TX_BUF_C_DN<13>")
	)
	(segment
		(start 407.923492 -420.681658)
		(end 407.652982 -420.952168)
		(width 0.12954)
		(layer "F.Cu")
		(net "P5E_CPU0_P2_TX_BUF_C_DN<12>")
	)
	(segment
		(start 407.923492 -417.461954)
		(end 407.923492 -420.681658)
		(width 0.12954)
		(layer "F.Cu")
		(net "P5E_CPU0_P2_TX_BUF_C_DN<12>")
	)
	(segment
		(start 407.627582 -417.166044)
		(end 407.923492 -417.461954)
		(width 0.12954)
		(layer "F.Cu")
		(net "P5E_CPU0_P2_TX_BUF_C_DN<12>")
	)
	(segment
		(start 406.014936 -430.242472)
		(end 406.104852 -430.332388)
		(width 0.14224)
		(layer "In11.Cu")
		(net "P5E_CPU0_P2_TX_BUF_C_DN<12>")
	)
	(segment
		(start 405.795734 -424.36288)
		(end 405.795734 -429.71339)
		(width 0.14224)
		(layer "In11.Cu")
		(net "P5E_CPU0_P2_TX_BUF_C_DN<12>")
	)
	(segment
		(start 407.943812 -421.242998)
		(end 407.943812 -421.74414)
		(width 0.14224)
		(layer "In11.Cu")
		(net "P5E_CPU0_P2_TX_BUF_C_DN<12>")
	)
	(segment
		(start 407.652982 -420.952168)
		(end 407.943812 -421.242998)
		(width 0.14224)
		(layer "In11.Cu")
		(net "P5E_CPU0_P2_TX_BUF_C_DN<12>")
	)
	(segment
		(start 407.774394 -421.950642)
		(end 407.774394 -421.951404)
		(width 0.14224)
		(layer "In11.Cu")
		(net "P5E_CPU0_P2_TX_BUF_C_DN<12>")
	)
	(segment
		(start 406.750012 -430.64938)
		(end 406.750012 -430.889918)
		(width 0.14224)
		(layer "In11.Cu")
		(net "P5E_CPU0_P2_TX_BUF_C_DN<12>")
	)
	(segment
		(start 407.943812 -421.74414)
		(end 407.774394 -421.950642)
		(width 0.14224)
		(layer "In11.Cu")
		(net "P5E_CPU0_P2_TX_BUF_C_DN<12>")
	)
	(segment
		(start 406.394158 -430.452276)
		(end 406.552908 -430.452276)
		(width 0.14224)
		(layer "In11.Cu")
		(net "P5E_CPU0_P2_TX_BUF_C_DN<12>")
	)
	(segment
		(start 406.552908 -430.452276)
		(end 406.750012 -430.64938)
		(width 0.14224)
		(layer "In11.Cu")
		(net "P5E_CPU0_P2_TX_BUF_C_DN<12>")
	)
	(segment
		(start 407.774394 -421.951404)
		(end 405.795734 -424.36288)
		(width 0.14224)
		(layer "In11.Cu")
		(net "P5E_CPU0_P2_TX_BUF_C_DN<12>")
	)
	(arc
		(start 405.834342 -429.950626)
		(mid 405.907682 -430.107041)
		(end 406.014936 -430.242472)
		(width 0.14224)
		(layer "In11.Cu")
		(net "P5E_CPU0_P2_TX_BUF_C_DN<12>")
	)
	(arc
		(start 406.104852 -430.332388)
		(mid 406.237572 -430.421132)
		(end 406.394158 -430.452276)
		(width 0.14224)
		(layer "In11.Cu")
		(net "P5E_CPU0_P2_TX_BUF_C_DN<12>")
	)
	(arc
		(start 405.795734 -429.71339)
		(mid 405.805448 -429.833569)
		(end 405.834342 -429.950626)
		(width 0.14224)
		(layer "In11.Cu")
		(net "P5E_CPU0_P2_TX_BUF_C_DN<12>")
	)
	(segment
		(start 404.860252 -420.681658)
		(end 404.589742 -420.952168)
		(width 0.12954)
		(layer "F.Cu")
		(net "P5E_CPU0_P2_TX_BUF_C_DN<11>")
	)
	(segment
		(start 404.564342 -417.166044)
		(end 404.860252 -417.461954)
		(width 0.12954)
		(layer "F.Cu")
		(net "P5E_CPU0_P2_TX_BUF_C_DN<11>")
	)
	(segment
		(start 404.860252 -417.461954)
		(end 404.860252 -420.681658)
		(width 0.12954)
		(layer "F.Cu")
		(net "P5E_CPU0_P2_TX_BUF_C_DN<11>")
	)
	(segment
		(start 404.750016 -431.573178)
		(end 404.750016 -431.889916)
		(width 0.14224)
		(layer "In11.Cu")
		(net "P5E_CPU0_P2_TX_BUF_C_DN<11>")
	)
	(segment
		(start 404.880572 -421.242998)
		(end 404.880572 -421.594026)
		(width 0.14224)
		(layer "In11.Cu")
		(net "P5E_CPU0_P2_TX_BUF_C_DN<11>")
	)
	(segment
		(start 404.381462 -431.430938)
		(end 404.607776 -431.430938)
		(width 0.14224)
		(layer "In11.Cu")
		(net "P5E_CPU0_P2_TX_BUF_C_DN<11>")
	)
	(segment
		(start 404.607776 -431.430938)
		(end 404.750016 -431.573178)
		(width 0.14224)
		(layer "In11.Cu")
		(net "P5E_CPU0_P2_TX_BUF_C_DN<11>")
	)
	(segment
		(start 404.880572 -421.594026)
		(end 403.80412 -424.1927)
		(width 0.14224)
		(layer "In11.Cu")
		(net "P5E_CPU0_P2_TX_BUF_C_DN<11>")
	)
	(segment
		(start 403.80412 -430.909222)
		(end 403.803866 -430.909222)
		(width 0.14224)
		(layer "In11.Cu")
		(net "P5E_CPU0_P2_TX_BUF_C_DN<11>")
	)
	(segment
		(start 403.924008 -431.198782)
		(end 403.99716 -431.27168)
		(width 0.14224)
		(layer "In11.Cu")
		(net "P5E_CPU0_P2_TX_BUF_C_DN<11>")
	)
	(segment
		(start 403.80412 -424.1927)
		(end 403.80412 -430.909222)
		(width 0.14224)
		(layer "In11.Cu")
		(net "P5E_CPU0_P2_TX_BUF_C_DN<11>")
	)
	(segment
		(start 404.589742 -420.952168)
		(end 404.880572 -421.242998)
		(width 0.14224)
		(layer "In11.Cu")
		(net "P5E_CPU0_P2_TX_BUF_C_DN<11>")
	)
	(arc
		(start 403.803866 -430.909222)
		(mid 403.835083 -431.06598)
		(end 403.924008 -431.198782)
		(width 0.14224)
		(layer "In11.Cu")
		(net "P5E_CPU0_P2_TX_BUF_C_DN<11>")
	)
	(arc
		(start 403.99716 -431.27168)
		(mid 404.173465 -431.389546)
		(end 404.381462 -431.430938)
		(width 0.14224)
		(layer "In11.Cu")
		(net "P5E_CPU0_P2_TX_BUF_C_DN<11>")
	)
	(segment
		(start 401.797012 -420.681658)
		(end 401.526502 -420.952168)
		(width 0.12954)
		(layer "F.Cu")
		(net "P5E_CPU0_P2_TX_BUF_C_DN<10>")
	)
	(segment
		(start 401.797012 -417.461954)
		(end 401.797012 -420.681658)
		(width 0.12954)
		(layer "F.Cu")
		(net "P5E_CPU0_P2_TX_BUF_C_DN<10>")
	)
	(segment
		(start 401.501102 -417.166044)
		(end 401.797012 -417.461954)
		(width 0.12954)
		(layer "F.Cu")
		(net "P5E_CPU0_P2_TX_BUF_C_DN<10>")
	)
	(segment
		(start 402.75002 -430.59731)
		(end 402.75002 -430.889918)
		(width 0.14224)
		(layer "In11.Cu")
		(net "P5E_CPU0_P2_TX_BUF_C_DN<10>")
	)
	(segment
		(start 402.00326 -430.230788)
		(end 402.08327 -430.310798)
		(width 0.14224)
		(layer "In11.Cu")
		(net "P5E_CPU0_P2_TX_BUF_C_DN<10>")
	)
	(segment
		(start 401.799044 -421.22471)
		(end 401.799044 -429.737774)
		(width 0.14224)
		(layer "In11.Cu")
		(net "P5E_CPU0_P2_TX_BUF_C_DN<10>")
	)
	(segment
		(start 402.583396 -430.430686)
		(end 402.75002 -430.59731)
		(width 0.14224)
		(layer "In11.Cu")
		(net "P5E_CPU0_P2_TX_BUF_C_DN<10>")
	)
	(segment
		(start 402.372576 -430.430686)
		(end 402.583396 -430.430686)
		(width 0.14224)
		(layer "In11.Cu")
		(net "P5E_CPU0_P2_TX_BUF_C_DN<10>")
	)
	(segment
		(start 401.526502 -420.952168)
		(end 401.799044 -421.22471)
		(width 0.14224)
		(layer "In11.Cu")
		(net "P5E_CPU0_P2_TX_BUF_C_DN<10>")
	)
	(arc
		(start 401.799044 -429.737774)
		(mid 401.852117 -430.004592)
		(end 402.00326 -430.230788)
		(width 0.14224)
		(layer "In11.Cu")
		(net "P5E_CPU0_P2_TX_BUF_C_DN<10>")
	)
	(arc
		(start 402.08327 -430.310798)
		(mid 402.21599 -430.399542)
		(end 402.372576 -430.430686)
		(width 0.14224)
		(layer "In11.Cu")
		(net "P5E_CPU0_P2_TX_BUF_C_DN<10>")
	)
	(segment
		(start 370.767102 -414.903158)
		(end 371.063012 -415.199068)
		(width 0.12954)
		(layer "F.Cu")
		(net "P5E_CPU0_P2_TX_BUF_C_DN<0>")
	)
	(segment
		(start 371.063012 -419.50132)
		(end 371.164612 -419.60292)
		(width 0.12954)
		(layer "F.Cu")
		(net "P5E_CPU0_P2_TX_BUF_C_DN<0>")
	)
	(segment
		(start 371.164612 -420.681658)
		(end 370.894102 -420.952168)
		(width 0.12954)
		(layer "F.Cu")
		(net "P5E_CPU0_P2_TX_BUF_C_DN<0>")
	)
	(segment
		(start 371.063012 -415.199068)
		(end 371.063012 -419.50132)
		(width 0.12954)
		(layer "F.Cu")
		(net "P5E_CPU0_P2_TX_BUF_C_DN<0>")
	)
	(segment
		(start 371.164612 -419.60292)
		(end 371.164612 -420.681658)
		(width 0.12954)
		(layer "F.Cu")
		(net "P5E_CPU0_P2_TX_BUF_C_DN<0>")
	)
	(segment
		(start 372.932198 -422.797732)
		(end 371.448838 -422.183052)
		(width 0.14224)
		(layer "In11.Cu")
		(net "P5E_CPU0_P2_TX_BUF_C_DN<0>")
	)
	(segment
		(start 371.184932 -421.919146)
		(end 371.184932 -421.242998)
		(width 0.14224)
		(layer "In11.Cu")
		(net "P5E_CPU0_P2_TX_BUF_C_DN<0>")
	)
	(segment
		(start 371.448838 -422.183052)
		(end 371.184932 -421.919146)
		(width 0.14224)
		(layer "In11.Cu")
		(net "P5E_CPU0_P2_TX_BUF_C_DN<0>")
	)
	(segment
		(start 371.184932 -421.242998)
		(end 370.894102 -420.952168)
		(width 0.14224)
		(layer "In11.Cu")
		(net "P5E_CPU0_P2_TX_BUF_C_DN<0>")
	)
	(segment
		(start 373.35206 -423.093134)
		(end 372.932198 -422.797732)
		(width 0.14224)
		(layer "In11.Cu")
		(net "P5E_CPU0_P2_TX_BUF_C_DN<0>")
	)
	(segment
		(start 381.29083 -430.43094)
		(end 380.780544 -430.43094)
		(width 0.14224)
		(layer "In11.Cu")
		(net "P5E_CPU0_P2_TX_BUF_C_DN<0>")
	)
	(segment
		(start 380.780544 -430.43094)
		(end 373.35206 -423.093134)
		(width 0.14224)
		(layer "In11.Cu")
		(net "P5E_CPU0_P2_TX_BUF_C_DN<0>")
	)
	(segment
		(start 381.749808 -430.889918)
		(end 381.29083 -430.43094)
		(width 0.14224)
		(layer "In11.Cu")
		(net "P5E_CPU0_P2_TX_BUF_C_DN<0>")
	)
	(segment
		(start 414.105598 -401.359116)
		(end 414.244282 -401.4978)
		(width 0.1016)
		(layer "F.Cu")
		(net "P5E_CPU0_P2_RX_BUF_DP<9>")
	)
	(segment
		(start 414.244282 -401.4978)
		(end 414.244282 -401.674838)
		(width 0.1016)
		(layer "F.Cu")
		(net "P5E_CPU0_P2_RX_BUF_DP<9>")
	)
	(segment
		(start 413.630364 -399.74774)
		(end 413.630364 -399.870676)
		(width 0.1016)
		(layer "F.Cu")
		(net "P5E_CPU0_P2_RX_BUF_DP<9>")
	)
	(segment
		(start 413.559244 -401.105878)
		(end 413.812482 -401.359116)
		(width 0.1016)
		(layer "F.Cu")
		(net "P5E_CPU0_P2_RX_BUF_DP<9>")
	)
	(segment
		(start 413.545782 -399.663158)
		(end 413.630364 -399.74774)
		(width 0.1016)
		(layer "F.Cu")
		(net "P5E_CPU0_P2_RX_BUF_DP<9>")
	)
	(segment
		(start 413.630364 -399.870676)
		(end 413.559244 -399.941796)
		(width 0.1016)
		(layer "F.Cu")
		(net "P5E_CPU0_P2_RX_BUF_DP<9>")
	)
	(segment
		(start 413.559244 -399.941796)
		(end 413.559244 -401.105878)
		(width 0.1016)
		(layer "F.Cu")
		(net "P5E_CPU0_P2_RX_BUF_DP<9>")
	)
	(segment
		(start 413.812482 -401.359116)
		(end 414.105598 -401.359116)
		(width 0.1016)
		(layer "F.Cu")
		(net "P5E_CPU0_P2_RX_BUF_DP<9>")
	)
	(segment
		(start 400.414998 -423.519092)
		(end 400.307302 -423.357802)
		(width 0.14224)
		(layer "In15.Cu")
		(net "P5E_CPU0_P2_RX_BUF_DP<9>")
	)
	(segment
		(start 400.750024 -438.191148)
		(end 400.59991 -438.341262)
		(width 0.14224)
		(layer "In15.Cu")
		(net "P5E_CPU0_P2_RX_BUF_DP<9>")
	)
	(segment
		(start 402.236432 -416.477958)
		(end 402.236432 -416.051238)
		(width 0.14224)
		(layer "In15.Cu")
		(net "P5E_CPU0_P2_RX_BUF_DP<9>")
	)
	(segment
		(start 400.787362 -420.042086)
		(end 401.597114 -419.706552)
		(width 0.14224)
		(layer "In15.Cu")
		(net "P5E_CPU0_P2_RX_BUF_DP<9>")
	)
	(segment
		(start 411.107382 -407.20137)
		(end 411.52572 -406.783286)
		(width 0.14224)
		(layer "In15.Cu")
		(net "P5E_CPU0_P2_RX_BUF_DP<9>")
	)
	(segment
		(start 414.244282 -401.526756)
		(end 414.244282 -401.674838)
		(width 0.14224)
		(layer "In15.Cu")
		(net "P5E_CPU0_P2_RX_BUF_DP<9>")
	)
	(segment
		(start 401.796758 -419.569392)
		(end 401.975574 -419.381686)
		(width 0.14224)
		(layer "In15.Cu")
		(net "P5E_CPU0_P2_RX_BUF_DP<9>")
	)
	(segment
		(start 414.117282 -401.399756)
		(end 414.244282 -401.526756)
		(width 0.14224)
		(layer "In15.Cu")
		(net "P5E_CPU0_P2_RX_BUF_DP<9>")
	)
	(segment
		(start 402.690584 -414.267142)
		(end 402.966174 -414.153096)
		(width 0.14224)
		(layer "In15.Cu")
		(net "P5E_CPU0_P2_RX_BUF_DP<9>")
	)
	(segment
		(start 409.81376 -408.494738)
		(end 410.007562 -408.494738)
		(width 0.14224)
		(layer "In15.Cu")
		(net "P5E_CPU0_P2_RX_BUF_DP<9>")
	)
	(segment
		(start 400.567652 -421.9575)
		(end 400.567652 -420.371016)
		(width 0.14224)
		(layer "In15.Cu")
		(net "P5E_CPU0_P2_RX_BUF_DP<9>")
	)
	(segment
		(start 410.309822 -407.99893)
		(end 410.611574 -407.697432)
		(width 0.14224)
		(layer "In15.Cu")
		(net "P5E_CPU0_P2_RX_BUF_DP<9>")
	)
	(segment
		(start 403.281642 -413.942276)
		(end 403.428454 -413.795464)
		(width 0.14224)
		(layer "In15.Cu")
		(net "P5E_CPU0_P2_RX_BUF_DP<9>")
	)
	(segment
		(start 409.512008 -408.796236)
		(end 409.81376 -408.494738)
		(width 0.14224)
		(layer "In15.Cu")
		(net "P5E_CPU0_P2_RX_BUF_DP<9>")
	)
	(segment
		(start 400.331686 -423.937938)
		(end 400.414998 -423.519092)
		(width 0.14224)
		(layer "In15.Cu")
		(net "P5E_CPU0_P2_RX_BUF_DP<9>")
	)
	(segment
		(start 406.939242 -410.34081)
		(end 407.74366 -410.007562)
		(width 0.14224)
		(layer "In15.Cu")
		(net "P5E_CPU0_P2_RX_BUF_DP<9>")
	)
	(segment
		(start 400.083782 -424.480228)
		(end 400.170142 -424.045634)
		(width 0.14224)
		(layer "In15.Cu")
		(net "P5E_CPU0_P2_RX_BUF_DP<9>")
	)
	(segment
		(start 410.007562 -408.494738)
		(end 410.309822 -408.192732)
		(width 0.14224)
		(layer "In15.Cu")
		(net "P5E_CPU0_P2_RX_BUF_DP<9>")
	)
	(segment
		(start 410.611574 -407.697432)
		(end 410.805376 -407.697432)
		(width 0.14224)
		(layer "In15.Cu")
		(net "P5E_CPU0_P2_RX_BUF_DP<9>")
	)
	(segment
		(start 411.79623 -406.453594)
		(end 411.98927 -406.434544)
		(width 0.14224)
		(layer "In15.Cu")
		(net "P5E_CPU0_P2_RX_BUF_DP<9>")
	)
	(segment
		(start 405.867616 -410.784802)
		(end 406.291542 -410.609288)
		(width 0.14224)
		(layer "In15.Cu")
		(net "P5E_CPU0_P2_RX_BUF_DP<9>")
	)
	(segment
		(start 405.398986 -411.127702)
		(end 405.793448 -410.96438)
		(width 0.14224)
		(layer "In15.Cu")
		(net "P5E_CPU0_P2_RX_BUF_DP<9>")
	)
	(segment
		(start 402.236432 -416.051238)
		(end 402.099272 -415.914078)
		(width 0.14224)
		(layer "In15.Cu")
		(net "P5E_CPU0_P2_RX_BUF_DP<9>")
	)
	(segment
		(start 413.785304 -403.919182)
		(end 413.785304 -401.541996)
		(width 0.14224)
		(layer "In15.Cu")
		(net "P5E_CPU0_P2_RX_BUF_DP<9>")
	)
	(segment
		(start 413.785304 -401.541996)
		(end 413.927544 -401.399756)
		(width 0.14224)
		(layer "In15.Cu")
		(net "P5E_CPU0_P2_RX_BUF_DP<9>")
	)
	(segment
		(start 407.888694 -409.93695)
		(end 408.17927 -409.772358)
		(width 0.14224)
		(layer "In15.Cu")
		(net "P5E_CPU0_P2_RX_BUF_DP<9>")
	)
	(segment
		(start 403.746208 -412.179516)
		(end 404.4696 -411.454854)
		(width 0.14224)
		(layer "In15.Cu")
		(net "P5E_CPU0_P2_RX_BUF_DP<9>")
	)
	(segment
		(start 402.966174 -414.153096)
		(end 403.281642 -413.942276)
		(width 0.14224)
		(layer "In15.Cu")
		(net "P5E_CPU0_P2_RX_BUF_DP<9>")
	)
	(segment
		(start 402.236432 -417.178998)
		(end 402.099272 -417.041838)
		(width 0.14224)
		(layer "In15.Cu")
		(net "P5E_CPU0_P2_RX_BUF_DP<9>")
	)
	(segment
		(start 402.099272 -416.615118)
		(end 402.236432 -416.477958)
		(width 0.14224)
		(layer "In15.Cu")
		(net "P5E_CPU0_P2_RX_BUF_DP<9>")
	)
	(segment
		(start 400.59991 -438.341262)
		(end 400.208496 -438.341262)
		(width 0.14224)
		(layer "In15.Cu")
		(net "P5E_CPU0_P2_RX_BUF_DP<9>")
	)
	(segment
		(start 400.071082 -438.203848)
		(end 400.071082 -424.608752)
		(width 0.14224)
		(layer "In15.Cu")
		(net "P5E_CPU0_P2_RX_BUF_DP<9>")
	)
	(segment
		(start 410.309822 -408.192732)
		(end 410.309822 -407.99893)
		(width 0.14224)
		(layer "In15.Cu")
		(net "P5E_CPU0_P2_RX_BUF_DP<9>")
	)
	(segment
		(start 402.099272 -417.041838)
		(end 402.099272 -416.615118)
		(width 0.14224)
		(layer "In15.Cu")
		(net "P5E_CPU0_P2_RX_BUF_DP<9>")
	)
	(segment
		(start 413.927544 -401.399756)
		(end 414.117282 -401.399756)
		(width 0.14224)
		(layer "In15.Cu")
		(net "P5E_CPU0_P2_RX_BUF_DP<9>")
	)
	(segment
		(start 405.219916 -411.05328)
		(end 405.398986 -411.127702)
		(width 0.14224)
		(layer "In15.Cu")
		(net "P5E_CPU0_P2_RX_BUF_DP<9>")
	)
	(segment
		(start 404.825708 -411.216602)
		(end 405.219916 -411.05328)
		(width 0.14224)
		(layer "In15.Cu")
		(net "P5E_CPU0_P2_RX_BUF_DP<9>")
	)
	(segment
		(start 400.208496 -438.341262)
		(end 400.071082 -438.203848)
		(width 0.14224)
		(layer "In15.Cu")
		(net "P5E_CPU0_P2_RX_BUF_DP<9>")
	)
	(segment
		(start 412.260288 -406.104598)
		(end 412.241492 -405.911558)
		(width 0.14224)
		(layer "In15.Cu")
		(net "P5E_CPU0_P2_RX_BUF_DP<9>")
	)
	(segment
		(start 408.312112 -409.685744)
		(end 409.512008 -408.796236)
		(width 0.14224)
		(layer "In15.Cu")
		(net "P5E_CPU0_P2_RX_BUF_DP<9>")
	)
	(segment
		(start 402.099272 -419.072822)
		(end 402.099272 -417.742878)
		(width 0.14224)
		(layer "In15.Cu")
		(net "P5E_CPU0_P2_RX_BUF_DP<9>")
	)
	(segment
		(start 405.793448 -410.96438)
		(end 405.867616 -410.784802)
		(width 0.14224)
		(layer "In15.Cu")
		(net "P5E_CPU0_P2_RX_BUF_DP<9>")
	)
	(segment
		(start 402.236432 -417.605718)
		(end 402.236432 -417.178998)
		(width 0.14224)
		(layer "In15.Cu")
		(net "P5E_CPU0_P2_RX_BUF_DP<9>")
	)
	(segment
		(start 411.52572 -406.783286)
		(end 411.79623 -406.453594)
		(width 0.14224)
		(layer "In15.Cu")
		(net "P5E_CPU0_P2_RX_BUF_DP<9>")
	)
	(segment
		(start 411.107382 -407.395426)
		(end 411.107382 -407.20137)
		(width 0.14224)
		(layer "In15.Cu")
		(net "P5E_CPU0_P2_RX_BUF_DP<9>")
	)
	(segment
		(start 406.291542 -410.609288)
		(end 406.470612 -410.683456)
		(width 0.14224)
		(layer "In15.Cu")
		(net "P5E_CPU0_P2_RX_BUF_DP<9>")
	)
	(segment
		(start 411.98927 -406.434544)
		(end 412.260288 -406.104598)
		(width 0.14224)
		(layer "In15.Cu")
		(net "P5E_CPU0_P2_RX_BUF_DP<9>")
	)
	(segment
		(start 400.750024 -437.889904)
		(end 400.750024 -438.191148)
		(width 0.14224)
		(layer "In15.Cu")
		(net "P5E_CPU0_P2_RX_BUF_DP<9>")
	)
	(segment
		(start 406.865074 -410.520134)
		(end 406.939242 -410.34081)
		(width 0.14224)
		(layer "In15.Cu")
		(net "P5E_CPU0_P2_RX_BUF_DP<9>")
	)
	(segment
		(start 410.805376 -407.697432)
		(end 411.107382 -407.395426)
		(width 0.14224)
		(layer "In15.Cu")
		(net "P5E_CPU0_P2_RX_BUF_DP<9>")
	)
	(segment
		(start 403.630892 -413.306514)
		(end 403.630892 -412.458154)
		(width 0.14224)
		(layer "In15.Cu")
		(net "P5E_CPU0_P2_RX_BUF_DP<9>")
	)
	(segment
		(start 400.307302 -423.357802)
		(end 400.549872 -422.138094)
		(width 0.14224)
		(layer "In15.Cu")
		(net "P5E_CPU0_P2_RX_BUF_DP<9>")
	)
	(segment
		(start 402.099272 -415.914078)
		(end 402.099272 -415.020252)
		(width 0.14224)
		(layer "In15.Cu")
		(net "P5E_CPU0_P2_RX_BUF_DP<9>")
	)
	(segment
		(start 412.241492 -405.911558)
		(end 413.385254 -404.51786)
		(width 0.14224)
		(layer "In15.Cu")
		(net "P5E_CPU0_P2_RX_BUF_DP<9>")
	)
	(segment
		(start 406.470612 -410.683456)
		(end 406.865074 -410.520134)
		(width 0.14224)
		(layer "In15.Cu")
		(net "P5E_CPU0_P2_RX_BUF_DP<9>")
	)
	(segment
		(start 413.385254 -404.51786)
		(end 413.785304 -403.919182)
		(width 0.14224)
		(layer "In15.Cu")
		(net "P5E_CPU0_P2_RX_BUF_DP<9>")
	)
	(segment
		(start 400.170142 -424.045634)
		(end 400.331686 -423.937938)
		(width 0.14224)
		(layer "In15.Cu")
		(net "P5E_CPU0_P2_RX_BUF_DP<9>")
	)
	(segment
		(start 402.099272 -417.742878)
		(end 402.236432 -417.605718)
		(width 0.14224)
		(layer "In15.Cu")
		(net "P5E_CPU0_P2_RX_BUF_DP<9>")
	)
	(arc
		(start 403.630892 -412.458154)
		(mid 403.66085 -412.307366)
		(end 403.746208 -412.179516)
		(width 0.14224)
		(layer "In15.Cu")
		(net "P5E_CPU0_P2_RX_BUF_DP<9>")
	)
	(arc
		(start 400.549872 -422.138094)
		(mid 400.563192 -422.048233)
		(end 400.567652 -421.9575)
		(width 0.14224)
		(layer "In15.Cu")
		(net "P5E_CPU0_P2_RX_BUF_DP<9>")
	)
	(arc
		(start 408.17927 -409.772358)
		(mid 408.246998 -409.731055)
		(end 408.312112 -409.685744)
		(width 0.14224)
		(layer "In15.Cu")
		(net "P5E_CPU0_P2_RX_BUF_DP<9>")
	)
	(arc
		(start 403.428454 -413.795464)
		(mid 403.578294 -413.571118)
		(end 403.630892 -413.306514)
		(width 0.14224)
		(layer "In15.Cu")
		(net "P5E_CPU0_P2_RX_BUF_DP<9>")
	)
	(arc
		(start 407.74366 -410.007562)
		(mid 407.817266 -409.974492)
		(end 407.888694 -409.93695)
		(width 0.14224)
		(layer "In15.Cu")
		(net "P5E_CPU0_P2_RX_BUF_DP<9>")
	)
	(arc
		(start 401.597114 -419.706552)
		(mid 401.704115 -419.648417)
		(end 401.796758 -419.569392)
		(width 0.14224)
		(layer "In15.Cu")
		(net "P5E_CPU0_P2_RX_BUF_DP<9>")
	)
	(arc
		(start 400.567652 -420.371016)
		(mid 400.627651 -420.173274)
		(end 400.787362 -420.042086)
		(width 0.14224)
		(layer "In15.Cu")
		(net "P5E_CPU0_P2_RX_BUF_DP<9>")
	)
	(arc
		(start 402.099272 -415.020252)
		(mid 402.152501 -414.752451)
		(end 402.30425 -414.52546)
		(width 0.14224)
		(layer "In15.Cu")
		(net "P5E_CPU0_P2_RX_BUF_DP<9>")
	)
	(arc
		(start 400.071082 -424.608752)
		(mid 400.07426 -424.544176)
		(end 400.083782 -424.480228)
		(width 0.14224)
		(layer "In15.Cu")
		(net "P5E_CPU0_P2_RX_BUF_DP<9>")
	)
	(arc
		(start 404.4696 -411.454854)
		(mid 404.635901 -411.318164)
		(end 404.825708 -411.216602)
		(width 0.14224)
		(layer "In15.Cu")
		(net "P5E_CPU0_P2_RX_BUF_DP<9>")
	)
	(arc
		(start 402.30425 -414.52546)
		(mid 402.48472 -414.377314)
		(end 402.690584 -414.267142)
		(width 0.14224)
		(layer "In15.Cu")
		(net "P5E_CPU0_P2_RX_BUF_DP<9>")
	)
	(arc
		(start 401.975574 -419.381686)
		(mid 402.067159 -419.239162)
		(end 402.099272 -419.072822)
		(width 0.14224)
		(layer "In15.Cu")
		(net "P5E_CPU0_P2_RX_BUF_DP<9>")
	)
	(segment
		(start 413.044386 -401.498054)
		(end 413.044386 -401.674838)
		(width 0.1016)
		(layer "F.Cu")
		(net "P5E_CPU0_P2_RX_BUF_DP<8>")
	)
	(segment
		(start 412.905448 -401.359116)
		(end 413.044386 -401.498054)
		(width 0.1016)
		(layer "F.Cu")
		(net "P5E_CPU0_P2_RX_BUF_DP<8>")
	)
	(segment
		(start 412.341568 -401.105878)
		(end 412.594806 -401.359116)
		(width 0.1016)
		(layer "F.Cu")
		(net "P5E_CPU0_P2_RX_BUF_DP<8>")
	)
	(segment
		(start 412.341568 -399.959322)
		(end 412.341568 -401.105878)
		(width 0.1016)
		(layer "F.Cu")
		(net "P5E_CPU0_P2_RX_BUF_DP<8>")
	)
	(segment
		(start 412.345632 -399.663158)
		(end 412.430214 -399.74774)
		(width 0.1016)
		(layer "F.Cu")
		(net "P5E_CPU0_P2_RX_BUF_DP<8>")
	)
	(segment
		(start 412.594806 -401.359116)
		(end 412.905448 -401.359116)
		(width 0.1016)
		(layer "F.Cu")
		(net "P5E_CPU0_P2_RX_BUF_DP<8>")
	)
	(segment
		(start 412.430214 -399.74774)
		(end 412.430214 -399.870676)
		(width 0.1016)
		(layer "F.Cu")
		(net "P5E_CPU0_P2_RX_BUF_DP<8>")
	)
	(segment
		(start 412.430214 -399.870676)
		(end 412.341568 -399.959322)
		(width 0.1016)
		(layer "F.Cu")
		(net "P5E_CPU0_P2_RX_BUF_DP<8>")
	)
	(segment
		(start 401.502372 -411.455362)
		(end 401.682458 -411.527752)
		(width 0.14224)
		(layer "In15.Cu")
		(net "P5E_CPU0_P2_RX_BUF_DP<8>")
	)
	(segment
		(start 397.641572 -422.600882)
		(end 397.504412 -422.463722)
		(width 0.14224)
		(layer "In15.Cu")
		(net "P5E_CPU0_P2_RX_BUF_DP<8>")
	)
	(segment
		(start 399.036032 -416.122358)
		(end 399.036032 -415.020252)
		(width 0.14224)
		(layer "In15.Cu")
		(net "P5E_CPU0_P2_RX_BUF_DP<8>")
	)
	(segment
		(start 402.075142 -411.360366)
		(end 402.147532 -411.18028)
		(width 0.14224)
		(layer "In15.Cu")
		(net "P5E_CPU0_P2_RX_BUF_DP<8>")
	)
	(segment
		(start 402.147532 -411.18028)
		(end 402.820632 -410.893768)
		(width 0.14224)
		(layer "In15.Cu")
		(net "P5E_CPU0_P2_RX_BUF_DP<8>")
	)
	(segment
		(start 412.917386 -401.399756)
		(end 413.044386 -401.526756)
		(width 0.14224)
		(layer "In15.Cu")
		(net "P5E_CPU0_P2_RX_BUF_DP<8>")
	)
	(segment
		(start 403.000464 -410.966158)
		(end 403.393402 -410.798772)
		(width 0.14224)
		(layer "In15.Cu")
		(net "P5E_CPU0_P2_RX_BUF_DP<8>")
	)
	(segment
		(start 402.820632 -410.893768)
		(end 403.000464 -410.966158)
		(width 0.14224)
		(layer "In15.Cu")
		(net "P5E_CPU0_P2_RX_BUF_DP<8>")
	)
	(segment
		(start 409.504896 -407.471626)
		(end 411.216094 -405.582882)
		(width 0.14224)
		(layer "In15.Cu")
		(net "P5E_CPU0_P2_RX_BUF_DP<8>")
	)
	(segment
		(start 403.393402 -410.798772)
		(end 403.465792 -410.618686)
		(width 0.14224)
		(layer "In15.Cu")
		(net "P5E_CPU0_P2_RX_BUF_DP<8>")
	)
	(segment
		(start 406.56764 -409.483814)
		(end 407.526236 -409.067508)
		(width 0.14224)
		(layer "In15.Cu")
		(net "P5E_CPU0_P2_RX_BUF_DP<8>")
	)
	(segment
		(start 397.641572 -423.728642)
		(end 397.504412 -423.591482)
		(width 0.14224)
		(layer "In15.Cu")
		(net "P5E_CPU0_P2_RX_BUF_DP<8>")
	)
	(segment
		(start 399.627344 -414.267142)
		(end 399.902934 -414.153096)
		(width 0.14224)
		(layer "In15.Cu")
		(net "P5E_CPU0_P2_RX_BUF_DP<8>")
	)
	(segment
		(start 397.504412 -422.463722)
		(end 397.504412 -422.037002)
		(width 0.14224)
		(layer "In15.Cu")
		(net "P5E_CPU0_P2_RX_BUF_DP<8>")
	)
	(segment
		(start 399.902934 -414.153096)
		(end 400.218402 -413.942276)
		(width 0.14224)
		(layer "In15.Cu")
		(net "P5E_CPU0_P2_RX_BUF_DP<8>")
	)
	(segment
		(start 399.036032 -416.823398)
		(end 399.173192 -416.686238)
		(width 0.14224)
		(layer "In15.Cu")
		(net "P5E_CPU0_P2_RX_BUF_DP<8>")
	)
	(segment
		(start 403.858222 -410.451554)
		(end 404.038054 -410.523944)
		(width 0.14224)
		(layer "In15.Cu")
		(net "P5E_CPU0_P2_RX_BUF_DP<8>")
	)
	(segment
		(start 412.33979 -403.986746)
		(end 412.585408 -403.638004)
		(width 0.14224)
		(layer "In15.Cu")
		(net "P5E_CPU0_P2_RX_BUF_DP<8>")
	)
	(segment
		(start 397.504412 -421.335962)
		(end 397.504412 -420.22776)
		(width 0.14224)
		(layer "In15.Cu")
		(net "P5E_CPU0_P2_RX_BUF_DP<8>")
	)
	(segment
		(start 397.504412 -423.164762)
		(end 397.641572 -423.027602)
		(width 0.14224)
		(layer "In15.Cu")
		(net "P5E_CPU0_P2_RX_BUF_DP<8>")
	)
	(segment
		(start 401.682458 -411.527752)
		(end 402.075142 -411.360366)
		(width 0.14224)
		(layer "In15.Cu")
		(net "P5E_CPU0_P2_RX_BUF_DP<8>")
	)
	(segment
		(start 412.585408 -401.541996)
		(end 412.727648 -401.399756)
		(width 0.14224)
		(layer "In15.Cu")
		(net "P5E_CPU0_P2_RX_BUF_DP<8>")
	)
	(segment
		(start 407.526236 -409.067508)
		(end 407.949908 -408.763724)
		(width 0.14224)
		(layer "In15.Cu")
		(net "P5E_CPU0_P2_RX_BUF_DP<8>")
	)
	(segment
		(start 412.727648 -401.399756)
		(end 412.917386 -401.399756)
		(width 0.14224)
		(layer "In15.Cu")
		(net "P5E_CPU0_P2_RX_BUF_DP<8>")
	)
	(segment
		(start 397.641572 -421.473122)
		(end 397.504412 -421.335962)
		(width 0.14224)
		(layer "In15.Cu")
		(net "P5E_CPU0_P2_RX_BUF_DP<8>")
	)
	(segment
		(start 400.593306 -412.150052)
		(end 400.68881 -411.92958)
		(width 0.14224)
		(layer "In15.Cu")
		(net "P5E_CPU0_P2_RX_BUF_DP<8>")
	)
	(segment
		(start 397.504412 -422.037002)
		(end 397.641572 -421.899842)
		(width 0.14224)
		(layer "In15.Cu")
		(net "P5E_CPU0_P2_RX_BUF_DP<8>")
	)
	(segment
		(start 399.173192 -416.686238)
		(end 399.173192 -416.259518)
		(width 0.14224)
		(layer "In15.Cu")
		(net "P5E_CPU0_P2_RX_BUF_DP<8>")
	)
	(segment
		(start 400.567652 -413.306514)
		(end 400.567652 -412.273242)
		(width 0.14224)
		(layer "In15.Cu")
		(net "P5E_CPU0_P2_RX_BUF_DP<8>")
	)
	(segment
		(start 407.949908 -408.763724)
		(end 409.504896 -407.471626)
		(width 0.14224)
		(layer "In15.Cu")
		(net "P5E_CPU0_P2_RX_BUF_DP<8>")
	)
	(segment
		(start 412.585408 -403.638004)
		(end 412.585408 -401.541996)
		(width 0.14224)
		(layer "In15.Cu")
		(net "P5E_CPU0_P2_RX_BUF_DP<8>")
	)
	(segment
		(start 401.109942 -411.622494)
		(end 401.502372 -411.455362)
		(width 0.14224)
		(layer "In15.Cu")
		(net "P5E_CPU0_P2_RX_BUF_DP<8>")
	)
	(segment
		(start 397.641572 -423.027602)
		(end 397.641572 -422.600882)
		(width 0.14224)
		(layer "In15.Cu")
		(net "P5E_CPU0_P2_RX_BUF_DP<8>")
	)
	(segment
		(start 412.127192 -404.527004)
		(end 412.373064 -404.178008)
		(width 0.14224)
		(layer "In15.Cu")
		(net "P5E_CPU0_P2_RX_BUF_DP<8>")
	)
	(segment
		(start 399.173192 -417.813998)
		(end 399.173192 -417.387278)
		(width 0.14224)
		(layer "In15.Cu")
		(net "P5E_CPU0_P2_RX_BUF_DP<8>")
	)
	(segment
		(start 399.036032 -417.250118)
		(end 399.036032 -416.823398)
		(width 0.14224)
		(layer "In15.Cu")
		(net "P5E_CPU0_P2_RX_BUF_DP<8>")
	)
	(segment
		(start 398.19961 -437.3372)
		(end 397.504412 -436.642002)
		(width 0.14224)
		(layer "In15.Cu")
		(net "P5E_CPU0_P2_RX_BUF_DP<8>")
	)
	(segment
		(start 399.036032 -417.951158)
		(end 399.173192 -417.813998)
		(width 0.14224)
		(layer "In15.Cu")
		(net "P5E_CPU0_P2_RX_BUF_DP<8>")
	)
	(segment
		(start 404.503382 -410.176472)
		(end 404.895812 -410.00934)
		(width 0.14224)
		(layer "In15.Cu")
		(net "P5E_CPU0_P2_RX_BUF_DP<8>")
	)
	(segment
		(start 398.603978 -437.3372)
		(end 398.19961 -437.3372)
		(width 0.14224)
		(layer "In15.Cu")
		(net "P5E_CPU0_P2_RX_BUF_DP<8>")
	)
	(segment
		(start 398.744948 -419.56482)
		(end 398.912334 -419.388798)
		(width 0.14224)
		(layer "In15.Cu")
		(net "P5E_CPU0_P2_RX_BUF_DP<8>")
	)
	(segment
		(start 404.430992 -410.356558)
		(end 404.503382 -410.176472)
		(width 0.14224)
		(layer "In15.Cu")
		(net "P5E_CPU0_P2_RX_BUF_DP<8>")
	)
	(segment
		(start 412.373064 -404.178008)
		(end 412.33979 -403.986746)
		(width 0.14224)
		(layer "In15.Cu")
		(net "P5E_CPU0_P2_RX_BUF_DP<8>")
	)
	(segment
		(start 397.504412 -423.591482)
		(end 397.504412 -423.164762)
		(width 0.14224)
		(layer "In15.Cu")
		(net "P5E_CPU0_P2_RX_BUF_DP<8>")
	)
	(segment
		(start 398.750028 -437.19115)
		(end 398.603978 -437.3372)
		(width 0.14224)
		(layer "In15.Cu")
		(net "P5E_CPU0_P2_RX_BUF_DP<8>")
	)
	(segment
		(start 404.038054 -410.523944)
		(end 404.430992 -410.356558)
		(width 0.14224)
		(layer "In15.Cu")
		(net "P5E_CPU0_P2_RX_BUF_DP<8>")
	)
	(segment
		(start 411.216094 -405.582882)
		(end 411.93593 -404.560278)
		(width 0.14224)
		(layer "In15.Cu")
		(net "P5E_CPU0_P2_RX_BUF_DP<8>")
	)
	(segment
		(start 403.465792 -410.618686)
		(end 403.858222 -410.451554)
		(width 0.14224)
		(layer "In15.Cu")
		(net "P5E_CPU0_P2_RX_BUF_DP<8>")
	)
	(segment
		(start 399.036032 -419.079172)
		(end 399.036032 -417.951158)
		(width 0.14224)
		(layer "In15.Cu")
		(net "P5E_CPU0_P2_RX_BUF_DP<8>")
	)
	(segment
		(start 397.504412 -424.292522)
		(end 397.641572 -424.155362)
		(width 0.14224)
		(layer "In15.Cu")
		(net "P5E_CPU0_P2_RX_BUF_DP<8>")
	)
	(segment
		(start 406.309576 -409.580842)
		(end 406.56764 -409.483814)
		(width 0.14224)
		(layer "In15.Cu")
		(net "P5E_CPU0_P2_RX_BUF_DP<8>")
	)
	(segment
		(start 397.641572 -421.899842)
		(end 397.641572 -421.473122)
		(width 0.14224)
		(layer "In15.Cu")
		(net "P5E_CPU0_P2_RX_BUF_DP<8>")
	)
	(segment
		(start 398.750028 -436.889906)
		(end 398.750028 -437.19115)
		(width 0.14224)
		(layer "In15.Cu")
		(net "P5E_CPU0_P2_RX_BUF_DP<8>")
	)
	(segment
		(start 411.93593 -404.560278)
		(end 412.127192 -404.527004)
		(width 0.14224)
		(layer "In15.Cu")
		(net "P5E_CPU0_P2_RX_BUF_DP<8>")
	)
	(segment
		(start 397.504412 -436.642002)
		(end 397.504412 -424.292522)
		(width 0.14224)
		(layer "In15.Cu")
		(net "P5E_CPU0_P2_RX_BUF_DP<8>")
	)
	(segment
		(start 413.044386 -401.526756)
		(end 413.044386 -401.674838)
		(width 0.14224)
		(layer "In15.Cu")
		(net "P5E_CPU0_P2_RX_BUF_DP<8>")
	)
	(segment
		(start 404.895812 -410.00934)
		(end 406.309576 -409.580842)
		(width 0.14224)
		(layer "In15.Cu")
		(net "P5E_CPU0_P2_RX_BUF_DP<8>")
	)
	(segment
		(start 400.218402 -413.942276)
		(end 400.365214 -413.795464)
		(width 0.14224)
		(layer "In15.Cu")
		(net "P5E_CPU0_P2_RX_BUF_DP<8>")
	)
	(segment
		(start 399.173192 -416.259518)
		(end 399.036032 -416.122358)
		(width 0.14224)
		(layer "In15.Cu")
		(net "P5E_CPU0_P2_RX_BUF_DP<8>")
	)
	(segment
		(start 397.641572 -424.155362)
		(end 397.641572 -423.728642)
		(width 0.14224)
		(layer "In15.Cu")
		(net "P5E_CPU0_P2_RX_BUF_DP<8>")
	)
	(segment
		(start 397.592042 -420.09695)
		(end 398.544542 -419.70198)
		(width 0.14224)
		(layer "In15.Cu")
		(net "P5E_CPU0_P2_RX_BUF_DP<8>")
	)
	(segment
		(start 399.173192 -417.387278)
		(end 399.036032 -417.250118)
		(width 0.14224)
		(layer "In15.Cu")
		(net "P5E_CPU0_P2_RX_BUF_DP<8>")
	)
	(arc
		(start 398.912334 -419.388798)
		(mid 399.00401 -419.245907)
		(end 399.036032 -419.079172)
		(width 0.14224)
		(layer "In15.Cu")
		(net "P5E_CPU0_P2_RX_BUF_DP<8>")
	)
	(arc
		(start 399.24101 -414.52546)
		(mid 399.42148 -414.377314)
		(end 399.627344 -414.267142)
		(width 0.14224)
		(layer "In15.Cu")
		(net "P5E_CPU0_P2_RX_BUF_DP<8>")
	)
	(arc
		(start 400.765518 -411.828996)
		(mid 400.930601 -411.713856)
		(end 401.109942 -411.622494)
		(width 0.14224)
		(layer "In15.Cu")
		(net "P5E_CPU0_P2_RX_BUF_DP<8>")
	)
	(arc
		(start 397.504412 -420.22776)
		(mid 397.528416 -420.149095)
		(end 397.592042 -420.09695)
		(width 0.14224)
		(layer "In15.Cu")
		(net "P5E_CPU0_P2_RX_BUF_DP<8>")
	)
	(arc
		(start 398.544542 -419.70198)
		(mid 398.65194 -419.643911)
		(end 398.744948 -419.56482)
		(width 0.14224)
		(layer "In15.Cu")
		(net "P5E_CPU0_P2_RX_BUF_DP<8>")
	)
	(arc
		(start 400.567652 -412.273242)
		(mid 400.574123 -412.210321)
		(end 400.593306 -412.150052)
		(width 0.14224)
		(layer "In15.Cu")
		(net "P5E_CPU0_P2_RX_BUF_DP<8>")
	)
	(arc
		(start 400.68881 -411.92958)
		(mid 400.721057 -411.874629)
		(end 400.765518 -411.828996)
		(width 0.14224)
		(layer "In15.Cu")
		(net "P5E_CPU0_P2_RX_BUF_DP<8>")
	)
	(arc
		(start 400.365214 -413.795464)
		(mid 400.515054 -413.571118)
		(end 400.567652 -413.306514)
		(width 0.14224)
		(layer "In15.Cu")
		(net "P5E_CPU0_P2_RX_BUF_DP<8>")
	)
	(arc
		(start 399.036032 -415.020252)
		(mid 399.089261 -414.752451)
		(end 399.24101 -414.52546)
		(width 0.14224)
		(layer "In15.Cu")
		(net "P5E_CPU0_P2_RX_BUF_DP<8>")
	)
	(segment
		(start 411.705552 -401.359116)
		(end 411.844236 -401.4978)
		(width 0.1016)
		(layer "F.Cu")
		(net "P5E_CPU0_P2_RX_BUF_DP<7>")
	)
	(segment
		(start 411.230318 -399.870676)
		(end 411.141672 -399.959322)
		(width 0.1016)
		(layer "F.Cu")
		(net "P5E_CPU0_P2_RX_BUF_DP<7>")
	)
	(segment
		(start 411.844236 -401.4978)
		(end 411.844236 -401.674838)
		(width 0.1016)
		(layer "F.Cu")
		(net "P5E_CPU0_P2_RX_BUF_DP<7>")
	)
	(segment
		(start 411.145736 -399.663158)
		(end 411.230318 -399.74774)
		(width 0.1016)
		(layer "F.Cu")
		(net "P5E_CPU0_P2_RX_BUF_DP<7>")
	)
	(segment
		(start 411.39491 -401.359116)
		(end 411.705552 -401.359116)
		(width 0.1016)
		(layer "F.Cu")
		(net "P5E_CPU0_P2_RX_BUF_DP<7>")
	)
	(segment
		(start 411.230318 -399.74774)
		(end 411.230318 -399.870676)
		(width 0.1016)
		(layer "F.Cu")
		(net "P5E_CPU0_P2_RX_BUF_DP<7>")
	)
	(segment
		(start 411.141672 -399.959322)
		(end 411.141672 -401.105878)
		(width 0.1016)
		(layer "F.Cu")
		(net "P5E_CPU0_P2_RX_BUF_DP<7>")
	)
	(segment
		(start 411.141672 -401.105878)
		(end 411.39491 -401.359116)
		(width 0.1016)
		(layer "F.Cu")
		(net "P5E_CPU0_P2_RX_BUF_DP<7>")
	)
	(segment
		(start 396.057374 -414.76803)
		(end 396.305786 -414.430972)
		(width 0.14224)
		(layer "In15.Cu")
		(net "P5E_CPU0_P2_RX_BUF_DP<7>")
	)
	(segment
		(start 395.74978 -437.889904)
		(end 395.74978 -438.191148)
		(width 0.14224)
		(layer "In15.Cu")
		(net "P5E_CPU0_P2_RX_BUF_DP<7>")
	)
	(segment
		(start 406.85593 -408.290776)
		(end 407.178002 -408.11069)
		(width 0.14224)
		(layer "In15.Cu")
		(net "P5E_CPU0_P2_RX_BUF_DP<7>")
	)
	(segment
		(start 401.152868 -410.426408)
		(end 401.544282 -410.255974)
		(width 0.14224)
		(layer "In15.Cu")
		(net "P5E_CPU0_P2_RX_BUF_DP<7>")
	)
	(segment
		(start 411.33395 -401.593304)
		(end 411.527498 -401.399756)
		(width 0.14224)
		(layer "In15.Cu")
		(net "P5E_CPU0_P2_RX_BUF_DP<7>")
	)
	(segment
		(start 408.130502 -407.348182)
		(end 410.145484 -405.358346)
		(width 0.14224)
		(layer "In15.Cu")
		(net "P5E_CPU0_P2_RX_BUF_DP<7>")
	)
	(segment
		(start 394.441426 -420.88816)
		(end 394.441426 -420.317168)
		(width 0.14224)
		(layer "In15.Cu")
		(net "P5E_CPU0_P2_RX_BUF_DP<7>")
	)
	(segment
		(start 400.119088 -410.877258)
		(end 400.510502 -410.706824)
		(width 0.14224)
		(layer "In15.Cu")
		(net "P5E_CPU0_P2_RX_BUF_DP<7>")
	)
	(segment
		(start 395.972792 -416.09264)
		(end 395.972792 -415.025332)
		(width 0.14224)
		(layer "In15.Cu")
		(net "P5E_CPU0_P2_RX_BUF_DP<7>")
	)
	(segment
		(start 395.071092 -438.195212)
		(end 395.071092 -424.749468)
		(width 0.14224)
		(layer "In15.Cu")
		(net "P5E_CPU0_P2_RX_BUF_DP<7>")
	)
	(segment
		(start 399.085308 -411.328108)
		(end 399.476722 -411.157674)
		(width 0.14224)
		(layer "In15.Cu")
		(net "P5E_CPU0_P2_RX_BUF_DP<7>")
	)
	(segment
		(start 410.662374 -404.732236)
		(end 411.18409 -403.95144)
		(width 0.14224)
		(layer "In15.Cu")
		(net "P5E_CPU0_P2_RX_BUF_DP<7>")
	)
	(segment
		(start 402.651722 -409.62326)
		(end 403.061424 -409.504388)
		(width 0.14224)
		(layer "In15.Cu")
		(net "P5E_CPU0_P2_RX_BUF_DP<7>")
	)
	(segment
		(start 401.615148 -410.075126)
		(end 402.651722 -409.62326)
		(width 0.14224)
		(layer "In15.Cu")
		(net "P5E_CPU0_P2_RX_BUF_DP<7>")
	)
	(segment
		(start 411.527498 -401.399756)
		(end 411.717236 -401.399756)
		(width 0.14224)
		(layer "In15.Cu")
		(net "P5E_CPU0_P2_RX_BUF_DP<7>")
	)
	(segment
		(start 399.547588 -410.976826)
		(end 399.938494 -410.806392)
		(width 0.14224)
		(layer "In15.Cu")
		(net "P5E_CPU0_P2_RX_BUF_DP<7>")
	)
	(segment
		(start 410.145484 -405.358346)
		(end 410.662374 -404.732236)
		(width 0.14224)
		(layer "In15.Cu")
		(net "P5E_CPU0_P2_RX_BUF_DP<7>")
	)
	(segment
		(start 411.33395 -403.35327)
		(end 411.33395 -401.593304)
		(width 0.14224)
		(layer "In15.Cu")
		(net "P5E_CPU0_P2_RX_BUF_DP<7>")
	)
	(segment
		(start 411.717236 -401.399756)
		(end 411.844236 -401.526756)
		(width 0.14224)
		(layer "In15.Cu")
		(net "P5E_CPU0_P2_RX_BUF_DP<7>")
	)
	(segment
		(start 396.109952 -417.35756)
		(end 395.972792 -417.2204)
		(width 0.14224)
		(layer "In15.Cu")
		(net "P5E_CPU0_P2_RX_BUF_DP<7>")
	)
	(segment
		(start 403.64156 -409.479242)
		(end 403.735032 -409.308808)
		(width 0.14224)
		(layer "In15.Cu")
		(net "P5E_CPU0_P2_RX_BUF_DP<7>")
	)
	(segment
		(start 394.744194 -422.121076)
		(end 394.669518 -421.700706)
		(width 0.14224)
		(layer "In15.Cu")
		(net "P5E_CPU0_P2_RX_BUF_DP<7>")
	)
	(segment
		(start 396.109952 -416.65652)
		(end 396.109952 -416.2298)
		(width 0.14224)
		(layer "In15.Cu")
		(net "P5E_CPU0_P2_RX_BUF_DP<7>")
	)
	(segment
		(start 407.178002 -408.11069)
		(end 408.130502 -407.348182)
		(width 0.14224)
		(layer "In15.Cu")
		(net "P5E_CPU0_P2_RX_BUF_DP<7>")
	)
	(segment
		(start 396.4559 -414.313116)
		(end 396.839186 -414.153858)
		(width 0.14224)
		(layer "In15.Cu")
		(net "P5E_CPU0_P2_RX_BUF_DP<7>")
	)
	(segment
		(start 403.23135 -409.598114)
		(end 403.64156 -409.479242)
		(width 0.14224)
		(layer "In15.Cu")
		(net "P5E_CPU0_P2_RX_BUF_DP<7>")
	)
	(segment
		(start 397.504412 -413.306514)
		(end 397.504412 -412.502604)
		(width 0.14224)
		(layer "In15.Cu")
		(net "P5E_CPU0_P2_RX_BUF_DP<7>")
	)
	(segment
		(start 394.669518 -421.700706)
		(end 394.510514 -421.589454)
		(width 0.14224)
		(layer "In15.Cu")
		(net "P5E_CPU0_P2_RX_BUF_DP<7>")
	)
	(segment
		(start 394.632942 -422.28008)
		(end 394.744194 -422.121076)
		(width 0.14224)
		(layer "In15.Cu")
		(net "P5E_CPU0_P2_RX_BUF_DP<7>")
	)
	(segment
		(start 397.697706 -412.036006)
		(end 397.861028 -411.872684)
		(width 0.14224)
		(layer "In15.Cu")
		(net "P5E_CPU0_P2_RX_BUF_DP<7>")
	)
	(segment
		(start 394.933678 -423.974006)
		(end 395.044676 -423.815002)
		(width 0.14224)
		(layer "In15.Cu")
		(net "P5E_CPU0_P2_RX_BUF_DP<7>")
	)
	(segment
		(start 405.69261 -408.79268)
		(end 406.201118 -408.610816)
		(width 0.14224)
		(layer "In15.Cu")
		(net "P5E_CPU0_P2_RX_BUF_DP<7>")
	)
	(segment
		(start 396.109952 -416.2298)
		(end 395.972792 -416.09264)
		(width 0.14224)
		(layer "In15.Cu")
		(net "P5E_CPU0_P2_RX_BUF_DP<7>")
	)
	(segment
		(start 395.603476 -438.337452)
		(end 395.213332 -438.337452)
		(width 0.14224)
		(layer "In15.Cu")
		(net "P5E_CPU0_P2_RX_BUF_DP<7>")
	)
	(segment
		(start 400.972274 -410.355542)
		(end 401.152868 -410.426408)
		(width 0.14224)
		(layer "In15.Cu")
		(net "P5E_CPU0_P2_RX_BUF_DP<7>")
	)
	(segment
		(start 394.441172 -420.888414)
		(end 394.441426 -420.88816)
		(width 0.14224)
		(layer "In15.Cu")
		(net "P5E_CPU0_P2_RX_BUF_DP<7>")
	)
	(segment
		(start 399.476722 -411.157674)
		(end 399.547588 -410.976826)
		(width 0.14224)
		(layer "In15.Cu")
		(net "P5E_CPU0_P2_RX_BUF_DP<7>")
	)
	(segment
		(start 395.972792 -417.2204)
		(end 395.972792 -416.79368)
		(width 0.14224)
		(layer "In15.Cu")
		(net "P5E_CPU0_P2_RX_BUF_DP<7>")
	)
	(segment
		(start 411.844236 -401.526756)
		(end 411.844236 -401.674838)
		(width 0.14224)
		(layer "In15.Cu")
		(net "P5E_CPU0_P2_RX_BUF_DP<7>")
	)
	(segment
		(start 405.187912 -408.887676)
		(end 405.589486 -408.743912)
		(width 0.14224)
		(layer "In15.Cu")
		(net "P5E_CPU0_P2_RX_BUF_DP<7>")
	)
	(segment
		(start 394.970254 -423.394632)
		(end 394.810996 -423.283634)
		(width 0.14224)
		(layer "In15.Cu")
		(net "P5E_CPU0_P2_RX_BUF_DP<7>")
	)
	(segment
		(start 401.544282 -410.255974)
		(end 401.615148 -410.075126)
		(width 0.14224)
		(layer "In15.Cu")
		(net "P5E_CPU0_P2_RX_BUF_DP<7>")
	)
	(segment
		(start 411.18409 -403.95144)
		(end 411.33395 -403.35327)
		(width 0.14224)
		(layer "In15.Cu")
		(net "P5E_CPU0_P2_RX_BUF_DP<7>")
	)
	(segment
		(start 398.904714 -411.257242)
		(end 399.085308 -411.328108)
		(width 0.14224)
		(layer "In15.Cu")
		(net "P5E_CPU0_P2_RX_BUF_DP<7>")
	)
	(segment
		(start 395.972792 -416.79368)
		(end 396.109952 -416.65652)
		(width 0.14224)
		(layer "In15.Cu")
		(net "P5E_CPU0_P2_RX_BUF_DP<7>")
	)
	(segment
		(start 406.201118 -408.610816)
		(end 406.249886 -408.507692)
		(width 0.14224)
		(layer "In15.Cu")
		(net "P5E_CPU0_P2_RX_BUF_DP<7>")
	)
	(segment
		(start 395.972792 -418.8968)
		(end 395.972792 -417.92144)
		(width 0.14224)
		(layer "In15.Cu")
		(net "P5E_CPU0_P2_RX_BUF_DP<7>")
	)
	(segment
		(start 395.044676 -423.815002)
		(end 394.970254 -423.394632)
		(width 0.14224)
		(layer "In15.Cu")
		(net "P5E_CPU0_P2_RX_BUF_DP<7>")
	)
	(segment
		(start 394.62583 -420.041324)
		(end 395.64183 -419.619938)
		(width 0.14224)
		(layer "In15.Cu")
		(net "P5E_CPU0_P2_RX_BUF_DP<7>")
	)
	(segment
		(start 394.441172 -421.19931)
		(end 394.441172 -420.888414)
		(width 0.14224)
		(layer "In15.Cu")
		(net "P5E_CPU0_P2_RX_BUF_DP<7>")
	)
	(segment
		(start 399.938494 -410.806392)
		(end 400.119088 -410.877258)
		(width 0.14224)
		(layer "In15.Cu")
		(net "P5E_CPU0_P2_RX_BUF_DP<7>")
	)
	(segment
		(start 400.581368 -410.525976)
		(end 400.972274 -410.355542)
		(width 0.14224)
		(layer "In15.Cu")
		(net "P5E_CPU0_P2_RX_BUF_DP<7>")
	)
	(segment
		(start 395.972792 -417.92144)
		(end 396.109952 -417.78428)
		(width 0.14224)
		(layer "In15.Cu")
		(net "P5E_CPU0_P2_RX_BUF_DP<7>")
	)
	(segment
		(start 403.735032 -409.308808)
		(end 405.187912 -408.887676)
		(width 0.14224)
		(layer "In15.Cu")
		(net "P5E_CPU0_P2_RX_BUF_DP<7>")
	)
	(segment
		(start 397.155162 -413.942276)
		(end 397.301974 -413.795464)
		(width 0.14224)
		(layer "In15.Cu")
		(net "P5E_CPU0_P2_RX_BUF_DP<7>")
	)
	(segment
		(start 395.071092 -424.749468)
		(end 394.933678 -423.974006)
		(width 0.14224)
		(layer "In15.Cu")
		(net "P5E_CPU0_P2_RX_BUF_DP<7>")
	)
	(segment
		(start 394.441426 -420.317168)
		(end 394.44168 -420.317422)
		(width 0.14224)
		(layer "In15.Cu")
		(net "P5E_CPU0_P2_RX_BUF_DP<7>")
	)
	(segment
		(start 406.249886 -408.507692)
		(end 406.85593 -408.290776)
		(width 0.14224)
		(layer "In15.Cu")
		(net "P5E_CPU0_P2_RX_BUF_DP<7>")
	)
	(segment
		(start 394.810996 -423.283634)
		(end 394.632942 -422.28008)
		(width 0.14224)
		(layer "In15.Cu")
		(net "P5E_CPU0_P2_RX_BUF_DP<7>")
	)
	(segment
		(start 396.109952 -417.78428)
		(end 396.109952 -417.35756)
		(width 0.14224)
		(layer "In15.Cu")
		(net "P5E_CPU0_P2_RX_BUF_DP<7>")
	)
	(segment
		(start 395.213332 -438.337452)
		(end 395.071092 -438.195212)
		(width 0.14224)
		(layer "In15.Cu")
		(net "P5E_CPU0_P2_RX_BUF_DP<7>")
	)
	(segment
		(start 403.061424 -409.504388)
		(end 403.23135 -409.598114)
		(width 0.14224)
		(layer "In15.Cu")
		(net "P5E_CPU0_P2_RX_BUF_DP<7>")
	)
	(segment
		(start 400.510502 -410.706824)
		(end 400.581368 -410.525976)
		(width 0.14224)
		(layer "In15.Cu")
		(net "P5E_CPU0_P2_RX_BUF_DP<7>")
	)
	(segment
		(start 395.74978 -438.191148)
		(end 395.603476 -438.337452)
		(width 0.14224)
		(layer "In15.Cu")
		(net "P5E_CPU0_P2_RX_BUF_DP<7>")
	)
	(segment
		(start 394.510514 -421.589454)
		(end 394.441172 -421.19931)
		(width 0.14224)
		(layer "In15.Cu")
		(net "P5E_CPU0_P2_RX_BUF_DP<7>")
	)
	(segment
		(start 405.589486 -408.743912)
		(end 405.69261 -408.79268)
		(width 0.14224)
		(layer "In15.Cu")
		(net "P5E_CPU0_P2_RX_BUF_DP<7>")
	)
	(segment
		(start 398.513808 -411.427676)
		(end 398.904714 -411.257242)
		(width 0.14224)
		(layer "In15.Cu")
		(net "P5E_CPU0_P2_RX_BUF_DP<7>")
	)
	(segment
		(start 396.839186 -414.153858)
		(end 397.155162 -413.942276)
		(width 0.14224)
		(layer "In15.Cu")
		(net "P5E_CPU0_P2_RX_BUF_DP<7>")
	)
	(arc
		(start 395.972792 -415.025332)
		(mid 395.994422 -414.889882)
		(end 396.057374 -414.76803)
		(width 0.14224)
		(layer "In15.Cu")
		(net "P5E_CPU0_P2_RX_BUF_DP<7>")
	)
	(arc
		(start 396.305786 -414.430972)
		(mid 396.372839 -414.361852)
		(end 396.4559 -414.313116)
		(width 0.14224)
		(layer "In15.Cu")
		(net "P5E_CPU0_P2_RX_BUF_DP<7>")
	)
	(arc
		(start 397.504412 -412.502604)
		(mid 397.554643 -412.250074)
		(end 397.697706 -412.036006)
		(width 0.14224)
		(layer "In15.Cu")
		(net "P5E_CPU0_P2_RX_BUF_DP<7>")
	)
	(arc
		(start 394.44168 -420.317422)
		(mid 394.491874 -420.151436)
		(end 394.62583 -420.041324)
		(width 0.14224)
		(layer "In15.Cu")
		(net "P5E_CPU0_P2_RX_BUF_DP<7>")
	)
	(arc
		(start 397.301974 -413.795464)
		(mid 397.451814 -413.571118)
		(end 397.504412 -413.306514)
		(width 0.14224)
		(layer "In15.Cu")
		(net "P5E_CPU0_P2_RX_BUF_DP<7>")
	)
	(arc
		(start 395.64183 -419.619938)
		(mid 395.886107 -419.294434)
		(end 395.972792 -418.8968)
		(width 0.14224)
		(layer "In15.Cu")
		(net "P5E_CPU0_P2_RX_BUF_DP<7>")
	)
	(arc
		(start 397.861028 -411.872684)
		(mid 398.166516 -411.619517)
		(end 398.513808 -411.427676)
		(width 0.14224)
		(layer "In15.Cu")
		(net "P5E_CPU0_P2_RX_BUF_DP<7>")
	)
	(segment
		(start 410.030168 -399.870676)
		(end 409.950412 -399.950432)
		(width 0.1016)
		(layer "F.Cu")
		(net "P5E_CPU0_P2_RX_BUF_DP<6>")
	)
	(segment
		(start 410.030168 -399.74774)
		(end 410.030168 -399.870676)
		(width 0.1016)
		(layer "F.Cu")
		(net "P5E_CPU0_P2_RX_BUF_DP<6>")
	)
	(segment
		(start 409.945586 -399.663158)
		(end 410.030168 -399.74774)
		(width 0.1016)
		(layer "F.Cu")
		(net "P5E_CPU0_P2_RX_BUF_DP<6>")
	)
	(segment
		(start 409.950412 -401.105878)
		(end 410.20365 -401.359116)
		(width 0.1016)
		(layer "F.Cu")
		(net "P5E_CPU0_P2_RX_BUF_DP<6>")
	)
	(segment
		(start 409.950412 -399.950432)
		(end 409.950412 -401.105878)
		(width 0.1016)
		(layer "F.Cu")
		(net "P5E_CPU0_P2_RX_BUF_DP<6>")
	)
	(segment
		(start 410.505402 -401.359116)
		(end 410.64434 -401.498054)
		(width 0.1016)
		(layer "F.Cu")
		(net "P5E_CPU0_P2_RX_BUF_DP<6>")
	)
	(segment
		(start 410.64434 -401.498054)
		(end 410.64434 -401.674838)
		(width 0.1016)
		(layer "F.Cu")
		(net "P5E_CPU0_P2_RX_BUF_DP<6>")
	)
	(segment
		(start 410.20365 -401.359116)
		(end 410.505402 -401.359116)
		(width 0.1016)
		(layer "F.Cu")
		(net "P5E_CPU0_P2_RX_BUF_DP<6>")
	)
	(segment
		(start 410.64434 -401.674838)
		(end 410.64434 -401.526756)
		(width 0.14224)
		(layer "In15.Cu")
		(net "P5E_CPU0_P2_RX_BUF_DP<6>")
	)
	(segment
		(start 392.900662 -424.318938)
		(end 392.83513 -424.501564)
		(width 0.14224)
		(layer "In15.Cu")
		(net "P5E_CPU0_P2_RX_BUF_DP<6>")
	)
	(segment
		(start 410.64434 -401.526756)
		(end 410.51734 -401.399756)
		(width 0.14224)
		(layer "In15.Cu")
		(net "P5E_CPU0_P2_RX_BUF_DP<6>")
	)
	(segment
		(start 393.046712 -416.561778)
		(end 392.909552 -416.698938)
		(width 0.14224)
		(layer "In15.Cu")
		(net "P5E_CPU0_P2_RX_BUF_DP<6>")
	)
	(segment
		(start 393.046712 -417.262818)
		(end 393.046712 -417.689538)
		(width 0.14224)
		(layer "In15.Cu")
		(net "P5E_CPU0_P2_RX_BUF_DP<6>")
	)
	(segment
		(start 392.785854 -419.388798)
		(end 392.618468 -419.56482)
		(width 0.14224)
		(layer "In15.Cu")
		(net "P5E_CPU0_P2_RX_BUF_DP<6>")
	)
	(segment
		(start 392.83513 -424.501564)
		(end 393.031726 -424.917362)
		(width 0.14224)
		(layer "In15.Cu")
		(net "P5E_CPU0_P2_RX_BUF_DP<6>")
	)
	(segment
		(start 401.55241 -408.93365)
		(end 400.64817 -409.321254)
		(width 0.14224)
		(layer "In15.Cu")
		(net "P5E_CPU0_P2_RX_BUF_DP<6>")
	)
	(segment
		(start 392.909552 -416.698938)
		(end 392.909552 -417.125658)
		(width 0.14224)
		(layer "In15.Cu")
		(net "P5E_CPU0_P2_RX_BUF_DP<6>")
	)
	(segment
		(start 406.396698 -407.418286)
		(end 405.640286 -407.731722)
		(width 0.14224)
		(layer "In15.Cu")
		(net "P5E_CPU0_P2_RX_BUF_DP<6>")
	)
	(segment
		(start 394.238734 -413.795464)
		(end 394.091922 -413.942276)
		(width 0.14224)
		(layer "In15.Cu")
		(net "P5E_CPU0_P2_RX_BUF_DP<6>")
	)
	(segment
		(start 396.37843 -411.300676)
		(end 395.986 -411.46857)
		(width 0.14224)
		(layer "In15.Cu")
		(net "P5E_CPU0_P2_RX_BUF_DP<6>")
	)
	(segment
		(start 393.208256 -437.341264)
		(end 393.59967 -437.341264)
		(width 0.14224)
		(layer "In15.Cu")
		(net "P5E_CPU0_P2_RX_BUF_DP<6>")
	)
	(segment
		(start 393.59967 -437.341264)
		(end 393.749784 -437.19115)
		(width 0.14224)
		(layer "In15.Cu")
		(net "P5E_CPU0_P2_RX_BUF_DP<6>")
	)
	(segment
		(start 395.986 -411.46857)
		(end 395.805914 -411.396688)
		(width 0.14224)
		(layer "In15.Cu")
		(net "P5E_CPU0_P2_RX_BUF_DP<6>")
	)
	(segment
		(start 398.96669 -410.041852)
		(end 398.523968 -410.23159)
		(width 0.14224)
		(layer "In15.Cu")
		(net "P5E_CPU0_P2_RX_BUF_DP<6>")
	)
	(segment
		(start 395.309852 -411.611826)
		(end 395.075156 -411.724856)
		(width 0.14224)
		(layer "In15.Cu")
		(net "P5E_CPU0_P2_RX_BUF_DP<6>")
	)
	(segment
		(start 397.022574 -411.02407)
		(end 396.842488 -410.952188)
		(width 0.14224)
		(layer "In15.Cu")
		(net "P5E_CPU0_P2_RX_BUF_DP<6>")
	)
	(segment
		(start 393.046712 -417.689538)
		(end 392.909552 -417.826698)
		(width 0.14224)
		(layer "In15.Cu")
		(net "P5E_CPU0_P2_RX_BUF_DP<6>")
	)
	(segment
		(start 391.82167 -422.486836)
		(end 392.007344 -422.543224)
		(width 0.14224)
		(layer "In15.Cu")
		(net "P5E_CPU0_P2_RX_BUF_DP<6>")
	)
	(segment
		(start 394.995146 -411.78099)
		(end 394.644118 -412.125414)
		(width 0.14224)
		(layer "In15.Cu")
		(net "P5E_CPU0_P2_RX_BUF_DP<6>")
	)
	(segment
		(start 410.185362 -403.414738)
		(end 409.991306 -403.883114)
		(width 0.14224)
		(layer "In15.Cu")
		(net "P5E_CPU0_P2_RX_BUF_DP<6>")
	)
	(segment
		(start 399.611342 -409.7655)
		(end 399.539206 -409.94584)
		(width 0.14224)
		(layer "In15.Cu")
		(net "P5E_CPU0_P2_RX_BUF_DP<6>")
	)
	(segment
		(start 409.991306 -403.883114)
		(end 409.624022 -404.43277)
		(width 0.14224)
		(layer "In15.Cu")
		(net "P5E_CPU0_P2_RX_BUF_DP<6>")
	)
	(segment
		(start 405.640286 -407.731722)
		(end 404.068534 -408.170126)
		(width 0.14224)
		(layer "In15.Cu")
		(net "P5E_CPU0_P2_RX_BUF_DP<6>")
	)
	(segment
		(start 392.909552 -415.997898)
		(end 393.046712 -416.135058)
		(width 0.14224)
		(layer "In15.Cu")
		(net "P5E_CPU0_P2_RX_BUF_DP<6>")
	)
	(segment
		(start 393.046712 -416.135058)
		(end 393.046712 -416.561778)
		(width 0.14224)
		(layer "In15.Cu")
		(net "P5E_CPU0_P2_RX_BUF_DP<6>")
	)
	(segment
		(start 410.185362 -401.541996)
		(end 410.185362 -403.414738)
		(width 0.14224)
		(layer "In15.Cu")
		(net "P5E_CPU0_P2_RX_BUF_DP<6>")
	)
	(segment
		(start 392.152124 -423.10558)
		(end 392.353038 -423.481754)
		(width 0.14224)
		(layer "In15.Cu")
		(net "P5E_CPU0_P2_RX_BUF_DP<6>")
	)
	(segment
		(start 396.842488 -410.952188)
		(end 396.450312 -411.120082)
		(width 0.14224)
		(layer "In15.Cu")
		(net "P5E_CPU0_P2_RX_BUF_DP<6>")
	)
	(segment
		(start 392.909552 -417.826698)
		(end 392.909552 -419.079172)
		(width 0.14224)
		(layer "In15.Cu")
		(net "P5E_CPU0_P2_RX_BUF_DP<6>")
	)
	(segment
		(start 398.451832 -410.41193)
		(end 398.059402 -410.579824)
		(width 0.14224)
		(layer "In15.Cu")
		(net "P5E_CPU0_P2_RX_BUF_DP<6>")
	)
	(segment
		(start 393.071096 -425.092368)
		(end 393.071096 -437.204104)
		(width 0.14224)
		(layer "In15.Cu")
		(net "P5E_CPU0_P2_RX_BUF_DP<6>")
	)
	(segment
		(start 404.068534 -408.170126)
		(end 401.55241 -408.93365)
		(width 0.14224)
		(layer "In15.Cu")
		(net "P5E_CPU0_P2_RX_BUF_DP<6>")
	)
	(segment
		(start 393.071096 -437.204104)
		(end 393.208256 -437.341264)
		(width 0.14224)
		(layer "In15.Cu")
		(net "P5E_CPU0_P2_RX_BUF_DP<6>")
	)
	(segment
		(start 397.879316 -410.507942)
		(end 397.48714 -410.675836)
		(width 0.14224)
		(layer "In15.Cu")
		(net "P5E_CPU0_P2_RX_BUF_DP<6>")
	)
	(segment
		(start 392.909552 -417.125658)
		(end 393.046712 -417.262818)
		(width 0.14224)
		(layer "In15.Cu")
		(net "P5E_CPU0_P2_RX_BUF_DP<6>")
	)
	(segment
		(start 392.418062 -419.70198)
		(end 391.465562 -420.09695)
		(width 0.14224)
		(layer "In15.Cu")
		(net "P5E_CPU0_P2_RX_BUF_DP<6>")
	)
	(segment
		(start 392.353038 -423.481754)
		(end 392.53541 -423.867326)
		(width 0.14224)
		(layer "In15.Cu")
		(net "P5E_CPU0_P2_RX_BUF_DP<6>")
	)
	(segment
		(start 410.51734 -401.399756)
		(end 410.327602 -401.399756)
		(width 0.14224)
		(layer "In15.Cu")
		(net "P5E_CPU0_P2_RX_BUF_DP<6>")
	)
	(segment
		(start 395.805914 -411.396688)
		(end 395.413738 -411.564582)
		(width 0.14224)
		(layer "In15.Cu")
		(net "P5E_CPU0_P2_RX_BUF_DP<6>")
	)
	(segment
		(start 400.64817 -409.321254)
		(end 400.576034 -409.501594)
		(width 0.14224)
		(layer "In15.Cu")
		(net "P5E_CPU0_P2_RX_BUF_DP<6>")
	)
	(segment
		(start 400.576034 -409.501594)
		(end 400.183604 -409.669488)
		(width 0.14224)
		(layer "In15.Cu")
		(net "P5E_CPU0_P2_RX_BUF_DP<6>")
	)
	(segment
		(start 399.539206 -409.94584)
		(end 399.146776 -410.113988)
		(width 0.14224)
		(layer "In15.Cu")
		(net "P5E_CPU0_P2_RX_BUF_DP<6>")
	)
	(segment
		(start 400.183604 -409.669488)
		(end 400.003518 -409.597606)
		(width 0.14224)
		(layer "In15.Cu")
		(net "P5E_CPU0_P2_RX_BUF_DP<6>")
	)
	(segment
		(start 397.48714 -410.675836)
		(end 397.415004 -410.856176)
		(width 0.14224)
		(layer "In15.Cu")
		(net "P5E_CPU0_P2_RX_BUF_DP<6>")
	)
	(segment
		(start 392.007344 -422.543224)
		(end 392.208512 -422.919906)
		(width 0.14224)
		(layer "In15.Cu")
		(net "P5E_CPU0_P2_RX_BUF_DP<6>")
	)
	(segment
		(start 398.059402 -410.579824)
		(end 397.879316 -410.507942)
		(width 0.14224)
		(layer "In15.Cu")
		(net "P5E_CPU0_P2_RX_BUF_DP<6>")
	)
	(segment
		(start 392.208512 -422.919906)
		(end 392.152124 -423.10558)
		(width 0.14224)
		(layer "In15.Cu")
		(net "P5E_CPU0_P2_RX_BUF_DP<6>")
	)
	(segment
		(start 392.71829 -423.932858)
		(end 392.900662 -424.318938)
		(width 0.14224)
		(layer "In15.Cu")
		(net "P5E_CPU0_P2_RX_BUF_DP<6>")
	)
	(segment
		(start 397.415004 -410.856176)
		(end 397.022574 -411.02407)
		(width 0.14224)
		(layer "In15.Cu")
		(net "P5E_CPU0_P2_RX_BUF_DP<6>")
	)
	(segment
		(start 407.125678 -406.931114)
		(end 406.396698 -407.418286)
		(width 0.14224)
		(layer "In15.Cu")
		(net "P5E_CPU0_P2_RX_BUF_DP<6>")
	)
	(segment
		(start 410.327602 -401.399756)
		(end 410.185362 -401.541996)
		(width 0.14224)
		(layer "In15.Cu")
		(net "P5E_CPU0_P2_RX_BUF_DP<6>")
	)
	(segment
		(start 392.53541 -423.867326)
		(end 392.71829 -423.932858)
		(width 0.14224)
		(layer "In15.Cu")
		(net "P5E_CPU0_P2_RX_BUF_DP<6>")
	)
	(segment
		(start 396.450312 -411.120082)
		(end 396.37843 -411.300676)
		(width 0.14224)
		(layer "In15.Cu")
		(net "P5E_CPU0_P2_RX_BUF_DP<6>")
	)
	(segment
		(start 400.003518 -409.597606)
		(end 399.611342 -409.7655)
		(width 0.14224)
		(layer "In15.Cu")
		(net "P5E_CPU0_P2_RX_BUF_DP<6>")
	)
	(segment
		(start 391.377932 -420.228014)
		(end 391.377932 -421.476932)
		(width 0.14224)
		(layer "In15.Cu")
		(net "P5E_CPU0_P2_RX_BUF_DP<6>")
	)
	(segment
		(start 409.624022 -404.43277)
		(end 407.125678 -406.931114)
		(width 0.14224)
		(layer "In15.Cu")
		(net "P5E_CPU0_P2_RX_BUF_DP<6>")
	)
	(segment
		(start 393.749784 -437.19115)
		(end 393.749784 -436.889906)
		(width 0.14224)
		(layer "In15.Cu")
		(net "P5E_CPU0_P2_RX_BUF_DP<6>")
	)
	(segment
		(start 398.523968 -410.23159)
		(end 398.451832 -410.41193)
		(width 0.14224)
		(layer "In15.Cu")
		(net "P5E_CPU0_P2_RX_BUF_DP<6>")
	)
	(segment
		(start 394.441172 -412.495492)
		(end 394.441172 -413.306514)
		(width 0.14224)
		(layer "In15.Cu")
		(net "P5E_CPU0_P2_RX_BUF_DP<6>")
	)
	(segment
		(start 393.776454 -414.153096)
		(end 393.500864 -414.267142)
		(width 0.14224)
		(layer "In15.Cu")
		(net "P5E_CPU0_P2_RX_BUF_DP<6>")
	)
	(segment
		(start 394.091922 -413.942276)
		(end 393.776454 -414.153096)
		(width 0.14224)
		(layer "In15.Cu")
		(net "P5E_CPU0_P2_RX_BUF_DP<6>")
	)
	(segment
		(start 391.463022 -421.815514)
		(end 391.82167 -422.486836)
		(width 0.14224)
		(layer "In15.Cu")
		(net "P5E_CPU0_P2_RX_BUF_DP<6>")
	)
	(segment
		(start 394.565124 -412.225236)
		(end 394.4747 -412.375096)
		(width 0.14224)
		(layer "In15.Cu")
		(net "P5E_CPU0_P2_RX_BUF_DP<6>")
	)
	(segment
		(start 392.909552 -415.020252)
		(end 392.909552 -415.997898)
		(width 0.14224)
		(layer "In15.Cu")
		(net "P5E_CPU0_P2_RX_BUF_DP<6>")
	)
	(segment
		(start 399.146776 -410.113988)
		(end 398.96669 -410.041852)
		(width 0.14224)
		(layer "In15.Cu")
		(net "P5E_CPU0_P2_RX_BUF_DP<6>")
	)
	(arc
		(start 393.500864 -414.267142)
		(mid 393.294982 -414.377288)
		(end 393.11453 -414.52546)
		(width 0.14224)
		(layer "In15.Cu")
		(net "P5E_CPU0_P2_RX_BUF_DP<6>")
	)
	(arc
		(start 395.413738 -411.564582)
		(mid 395.361538 -411.587638)
		(end 395.309852 -411.611826)
		(width 0.14224)
		(layer "In15.Cu")
		(net "P5E_CPU0_P2_RX_BUF_DP<6>")
	)
	(arc
		(start 394.4747 -412.375096)
		(mid 394.449736 -412.433008)
		(end 394.441172 -412.495492)
		(width 0.14224)
		(layer "In15.Cu")
		(net "P5E_CPU0_P2_RX_BUF_DP<6>")
	)
	(arc
		(start 392.618468 -419.56482)
		(mid 392.52545 -419.643897)
		(end 392.418062 -419.70198)
		(width 0.14224)
		(layer "In15.Cu")
		(net "P5E_CPU0_P2_RX_BUF_DP<6>")
	)
	(arc
		(start 391.465562 -420.09695)
		(mid 391.401817 -420.149167)
		(end 391.377932 -420.228014)
		(width 0.14224)
		(layer "In15.Cu")
		(net "P5E_CPU0_P2_RX_BUF_DP<6>")
	)
	(arc
		(start 393.11453 -414.52546)
		(mid 392.962767 -414.752445)
		(end 392.909552 -415.020252)
		(width 0.14224)
		(layer "In15.Cu")
		(net "P5E_CPU0_P2_RX_BUF_DP<6>")
	)
	(arc
		(start 395.075156 -411.724856)
		(mid 395.032861 -411.749656)
		(end 394.995146 -411.78099)
		(width 0.14224)
		(layer "In15.Cu")
		(net "P5E_CPU0_P2_RX_BUF_DP<6>")
	)
	(arc
		(start 394.644118 -412.125414)
		(mid 394.601492 -412.172847)
		(end 394.565124 -412.225236)
		(width 0.14224)
		(layer "In15.Cu")
		(net "P5E_CPU0_P2_RX_BUF_DP<6>")
	)
	(arc
		(start 392.909552 -419.079172)
		(mid 392.877587 -419.24593)
		(end 392.785854 -419.388798)
		(width 0.14224)
		(layer "In15.Cu")
		(net "P5E_CPU0_P2_RX_BUF_DP<6>")
	)
	(arc
		(start 394.441172 -413.306514)
		(mid 394.388558 -413.571111)
		(end 394.238734 -413.795464)
		(width 0.14224)
		(layer "In15.Cu")
		(net "P5E_CPU0_P2_RX_BUF_DP<6>")
	)
	(arc
		(start 391.377932 -421.476932)
		(mid 391.399588 -421.651474)
		(end 391.463022 -421.815514)
		(width 0.14224)
		(layer "In15.Cu")
		(net "P5E_CPU0_P2_RX_BUF_DP<6>")
	)
	(arc
		(start 393.031726 -424.917362)
		(mid 393.061128 -425.002681)
		(end 393.071096 -425.092368)
		(width 0.14224)
		(layer "In15.Cu")
		(net "P5E_CPU0_P2_RX_BUF_DP<6>")
	)
	(segment
		(start 408.830272 -399.870676)
		(end 408.741626 -399.959322)
		(width 0.1016)
		(layer "F.Cu")
		(net "P5E_CPU0_P2_RX_BUF_DP<5>")
	)
	(segment
		(start 408.830272 -399.74774)
		(end 408.830272 -399.870676)
		(width 0.1016)
		(layer "F.Cu")
		(net "P5E_CPU0_P2_RX_BUF_DP<5>")
	)
	(segment
		(start 409.305506 -401.359116)
		(end 409.44419 -401.4978)
		(width 0.1016)
		(layer "F.Cu")
		(net "P5E_CPU0_P2_RX_BUF_DP<5>")
	)
	(segment
		(start 408.994864 -401.359116)
		(end 409.305506 -401.359116)
		(width 0.1016)
		(layer "F.Cu")
		(net "P5E_CPU0_P2_RX_BUF_DP<5>")
	)
	(segment
		(start 408.741626 -399.959322)
		(end 408.741626 -401.105878)
		(width 0.1016)
		(layer "F.Cu")
		(net "P5E_CPU0_P2_RX_BUF_DP<5>")
	)
	(segment
		(start 408.741626 -401.105878)
		(end 408.994864 -401.359116)
		(width 0.1016)
		(layer "F.Cu")
		(net "P5E_CPU0_P2_RX_BUF_DP<5>")
	)
	(segment
		(start 408.74569 -399.663158)
		(end 408.830272 -399.74774)
		(width 0.1016)
		(layer "F.Cu")
		(net "P5E_CPU0_P2_RX_BUF_DP<5>")
	)
	(segment
		(start 409.44419 -401.4978)
		(end 409.44419 -401.674838)
		(width 0.1016)
		(layer "F.Cu")
		(net "P5E_CPU0_P2_RX_BUF_DP<5>")
	)
	(segment
		(start 399.271236 -408.794204)
		(end 399.094198 -408.714956)
		(width 0.14224)
		(layer "In15.Cu")
		(net "P5E_CPU0_P2_RX_BUF_DP<5>")
	)
	(segment
		(start 406.395682 -406.196546)
		(end 405.751792 -406.626822)
		(width 0.14224)
		(layer "In15.Cu")
		(net "P5E_CPU0_P2_RX_BUF_DP<5>")
	)
	(segment
		(start 388.314692 -420.318946)
		(end 388.314692 -421.484298)
		(width 0.14224)
		(layer "In15.Cu")
		(net "P5E_CPU0_P2_RX_BUF_DP<5>")
	)
	(segment
		(start 389.983472 -416.006534)
		(end 389.983472 -416.433254)
		(width 0.14224)
		(layer "In15.Cu")
		(net "P5E_CPU0_P2_RX_BUF_DP<5>")
	)
	(segment
		(start 389.846312 -416.570414)
		(end 389.846312 -416.997134)
		(width 0.14224)
		(layer "In15.Cu")
		(net "P5E_CPU0_P2_RX_BUF_DP<5>")
	)
	(segment
		(start 407.041604 -405.666194)
		(end 406.395682 -406.196546)
		(width 0.14224)
		(layer "In15.Cu")
		(net "P5E_CPU0_P2_RX_BUF_DP<5>")
	)
	(segment
		(start 409.44419 -401.674838)
		(end 409.44419 -401.526756)
		(width 0.14224)
		(layer "In15.Cu")
		(net "P5E_CPU0_P2_RX_BUF_DP<5>")
	)
	(segment
		(start 388.465822 -420.026846)
		(end 388.371334 -420.095934)
		(width 0.14224)
		(layer "In15.Cu")
		(net "P5E_CPU0_P2_RX_BUF_DP<5>")
	)
	(segment
		(start 394.39977 -410.650182)
		(end 394.000736 -410.802074)
		(width 0.14224)
		(layer "In15.Cu")
		(net "P5E_CPU0_P2_RX_BUF_DP<5>")
	)
	(segment
		(start 389.846312 -417.698174)
		(end 389.846312 -419.034722)
		(width 0.14224)
		(layer "In15.Cu")
		(net "P5E_CPU0_P2_RX_BUF_DP<5>")
	)
	(segment
		(start 391.275062 -438.341262)
		(end 391.599674 -438.341262)
		(width 0.14224)
		(layer "In15.Cu")
		(net "P5E_CPU0_P2_RX_BUF_DP<5>")
	)
	(segment
		(start 395.533372 -410.071316)
		(end 395.45387 -410.248608)
		(width 0.14224)
		(layer "In15.Cu")
		(net "P5E_CPU0_P2_RX_BUF_DP<5>")
	)
	(segment
		(start 391.082784 -438.148984)
		(end 391.275062 -438.341262)
		(width 0.14224)
		(layer "In15.Cu")
		(net "P5E_CPU0_P2_RX_BUF_DP<5>")
	)
	(segment
		(start 390.713214 -414.153096)
		(end 390.437624 -414.267142)
		(width 0.14224)
		(layer "In15.Cu")
		(net "P5E_CPU0_P2_RX_BUF_DP<5>")
	)
	(segment
		(start 395.054836 -410.4005)
		(end 394.877798 -410.320998)
		(width 0.14224)
		(layer "In15.Cu")
		(net "P5E_CPU0_P2_RX_BUF_DP<5>")
	)
	(segment
		(start 393.425172 -410.874464)
		(end 392.381486 -411.442662)
		(width 0.14224)
		(layer "In15.Cu")
		(net "P5E_CPU0_P2_RX_BUF_DP<5>")
	)
	(segment
		(start 389.337296 -419.74262)
		(end 388.465822 -420.026846)
		(width 0.14224)
		(layer "In15.Cu")
		(net "P5E_CPU0_P2_RX_BUF_DP<5>")
	)
	(segment
		(start 398.61617 -409.043886)
		(end 398.217136 -409.195778)
		(width 0.14224)
		(layer "In15.Cu")
		(net "P5E_CPU0_P2_RX_BUF_DP<5>")
	)
	(segment
		(start 394.877798 -410.320998)
		(end 394.479272 -410.47289)
		(width 0.14224)
		(layer "In15.Cu")
		(net "P5E_CPU0_P2_RX_BUF_DP<5>")
	)
	(segment
		(start 399.094198 -408.714956)
		(end 398.695672 -408.866594)
		(width 0.14224)
		(layer "In15.Cu")
		(net "P5E_CPU0_P2_RX_BUF_DP<5>")
	)
	(segment
		(start 389.983472 -417.134294)
		(end 389.983472 -417.561014)
		(width 0.14224)
		(layer "In15.Cu")
		(net "P5E_CPU0_P2_RX_BUF_DP<5>")
	)
	(segment
		(start 391.749788 -438.191148)
		(end 391.749788 -437.889904)
		(width 0.14224)
		(layer "In15.Cu")
		(net "P5E_CPU0_P2_RX_BUF_DP<5>")
	)
	(segment
		(start 395.931898 -409.919424)
		(end 395.533372 -410.071316)
		(width 0.14224)
		(layer "In15.Cu")
		(net "P5E_CPU0_P2_RX_BUF_DP<5>")
	)
	(segment
		(start 398.217136 -409.195778)
		(end 398.040098 -409.116276)
		(width 0.14224)
		(layer "In15.Cu")
		(net "P5E_CPU0_P2_RX_BUF_DP<5>")
	)
	(segment
		(start 398.040098 -409.116276)
		(end 397.641572 -409.268168)
		(width 0.14224)
		(layer "In15.Cu")
		(net "P5E_CPU0_P2_RX_BUF_DP<5>")
	)
	(segment
		(start 389.706612 -423.159174)
		(end 390.008872 -423.527474)
		(width 0.14224)
		(layer "In15.Cu")
		(net "P5E_CPU0_P2_RX_BUF_DP<5>")
	)
	(segment
		(start 397.56207 -409.44546)
		(end 397.163036 -409.597352)
		(width 0.14224)
		(layer "In15.Cu")
		(net "P5E_CPU0_P2_RX_BUF_DP<5>")
	)
	(segment
		(start 391.692384 -411.958028)
		(end 391.523474 -412.126938)
		(width 0.14224)
		(layer "In15.Cu")
		(net "P5E_CPU0_P2_RX_BUF_DP<5>")
	)
	(segment
		(start 396.587472 -409.669742)
		(end 396.50797 -409.847034)
		(width 0.14224)
		(layer "In15.Cu")
		(net "P5E_CPU0_P2_RX_BUF_DP<5>")
	)
	(segment
		(start 390.47293 -423.87647)
		(end 390.45388 -424.06951)
		(width 0.14224)
		(layer "In15.Cu")
		(net "P5E_CPU0_P2_RX_BUF_DP<5>")
	)
	(segment
		(start 397.641572 -409.268168)
		(end 397.56207 -409.44546)
		(width 0.14224)
		(layer "In15.Cu")
		(net "P5E_CPU0_P2_RX_BUF_DP<5>")
	)
	(segment
		(start 390.944608 -424.730164)
		(end 391.045446 -425.016422)
		(width 0.14224)
		(layer "In15.Cu")
		(net "P5E_CPU0_P2_RX_BUF_DP<5>")
	)
	(segment
		(start 388.514844 -421.967406)
		(end 389.706612 -423.159174)
		(width 0.14224)
		(layer "In15.Cu")
		(net "P5E_CPU0_P2_RX_BUF_DP<5>")
	)
	(segment
		(start 409.44419 -401.526756)
		(end 409.31719 -401.399756)
		(width 0.14224)
		(layer "In15.Cu")
		(net "P5E_CPU0_P2_RX_BUF_DP<5>")
	)
	(segment
		(start 391.377932 -412.47822)
		(end 391.377932 -413.306514)
		(width 0.14224)
		(layer "In15.Cu")
		(net "P5E_CPU0_P2_RX_BUF_DP<5>")
	)
	(segment
		(start 390.201912 -423.546524)
		(end 390.47293 -423.87647)
		(width 0.14224)
		(layer "In15.Cu")
		(net "P5E_CPU0_P2_RX_BUF_DP<5>")
	)
	(segment
		(start 391.599674 -438.341262)
		(end 391.749788 -438.191148)
		(width 0.14224)
		(layer "In15.Cu")
		(net "P5E_CPU0_P2_RX_BUF_DP<5>")
	)
	(segment
		(start 403.45741 -407.21407)
		(end 400.264884 -408.268932)
		(width 0.14224)
		(layer "In15.Cu")
		(net "P5E_CPU0_P2_RX_BUF_DP<5>")
	)
	(segment
		(start 397.163036 -409.597352)
		(end 396.985998 -409.51785)
		(width 0.14224)
		(layer "In15.Cu")
		(net "P5E_CPU0_P2_RX_BUF_DP<5>")
	)
	(segment
		(start 390.008872 -423.527474)
		(end 390.201912 -423.546524)
		(width 0.14224)
		(layer "In15.Cu")
		(net "P5E_CPU0_P2_RX_BUF_DP<5>")
	)
	(segment
		(start 399.67027 -408.642312)
		(end 399.271236 -408.794204)
		(width 0.14224)
		(layer "In15.Cu")
		(net "P5E_CPU0_P2_RX_BUF_DP<5>")
	)
	(segment
		(start 408.83332 -403.874224)
		(end 407.041604 -405.666194)
		(width 0.14224)
		(layer "In15.Cu")
		(net "P5E_CPU0_P2_RX_BUF_DP<5>")
	)
	(segment
		(start 391.175494 -413.795464)
		(end 391.028682 -413.942276)
		(width 0.14224)
		(layer "In15.Cu")
		(net "P5E_CPU0_P2_RX_BUF_DP<5>")
	)
	(segment
		(start 405.143208 -406.87879)
		(end 403.45741 -407.21407)
		(width 0.14224)
		(layer "In15.Cu")
		(net "P5E_CPU0_P2_RX_BUF_DP<5>")
	)
	(segment
		(start 398.695672 -408.866594)
		(end 398.61617 -409.043886)
		(width 0.14224)
		(layer "In15.Cu")
		(net "P5E_CPU0_P2_RX_BUF_DP<5>")
	)
	(segment
		(start 400.264884 -408.268932)
		(end 399.749772 -408.46502)
		(width 0.14224)
		(layer "In15.Cu")
		(net "P5E_CPU0_P2_RX_BUF_DP<5>")
	)
	(segment
		(start 389.846312 -415.020252)
		(end 389.846312 -415.869374)
		(width 0.14224)
		(layer "In15.Cu")
		(net "P5E_CPU0_P2_RX_BUF_DP<5>")
	)
	(segment
		(start 389.846312 -416.997134)
		(end 389.983472 -417.134294)
		(width 0.14224)
		(layer "In15.Cu")
		(net "P5E_CPU0_P2_RX_BUF_DP<5>")
	)
	(segment
		(start 408.985212 -403.507448)
		(end 408.83332 -403.874224)
		(width 0.14224)
		(layer "In15.Cu")
		(net "P5E_CPU0_P2_RX_BUF_DP<5>")
	)
	(segment
		(start 394.479272 -410.47289)
		(end 394.39977 -410.650182)
		(width 0.14224)
		(layer "In15.Cu")
		(net "P5E_CPU0_P2_RX_BUF_DP<5>")
	)
	(segment
		(start 391.028682 -413.942276)
		(end 390.713214 -414.153096)
		(width 0.14224)
		(layer "In15.Cu")
		(net "P5E_CPU0_P2_RX_BUF_DP<5>")
	)
	(segment
		(start 396.50797 -409.847034)
		(end 396.108936 -409.998926)
		(width 0.14224)
		(layer "In15.Cu")
		(net "P5E_CPU0_P2_RX_BUF_DP<5>")
	)
	(segment
		(start 408.985212 -401.541996)
		(end 408.985212 -403.507448)
		(width 0.14224)
		(layer "In15.Cu")
		(net "P5E_CPU0_P2_RX_BUF_DP<5>")
	)
	(segment
		(start 405.751792 -406.626822)
		(end 405.143208 -406.87879)
		(width 0.14224)
		(layer "In15.Cu")
		(net "P5E_CPU0_P2_RX_BUF_DP<5>")
	)
	(segment
		(start 396.985998 -409.51785)
		(end 396.587472 -409.669742)
		(width 0.14224)
		(layer "In15.Cu")
		(net "P5E_CPU0_P2_RX_BUF_DP<5>")
	)
	(segment
		(start 399.749772 -408.46502)
		(end 399.67027 -408.642312)
		(width 0.14224)
		(layer "In15.Cu")
		(net "P5E_CPU0_P2_RX_BUF_DP<5>")
	)
	(segment
		(start 390.45388 -424.06951)
		(end 390.832848 -424.531282)
		(width 0.14224)
		(layer "In15.Cu")
		(net "P5E_CPU0_P2_RX_BUF_DP<5>")
	)
	(segment
		(start 409.31719 -401.399756)
		(end 409.127452 -401.399756)
		(width 0.14224)
		(layer "In15.Cu")
		(net "P5E_CPU0_P2_RX_BUF_DP<5>")
	)
	(segment
		(start 389.983472 -417.561014)
		(end 389.846312 -417.698174)
		(width 0.14224)
		(layer "In15.Cu")
		(net "P5E_CPU0_P2_RX_BUF_DP<5>")
	)
	(segment
		(start 389.983472 -416.433254)
		(end 389.846312 -416.570414)
		(width 0.14224)
		(layer "In15.Cu")
		(net "P5E_CPU0_P2_RX_BUF_DP<5>")
	)
	(segment
		(start 396.108936 -409.998926)
		(end 395.931898 -409.919424)
		(width 0.14224)
		(layer "In15.Cu")
		(net "P5E_CPU0_P2_RX_BUF_DP<5>")
	)
	(segment
		(start 395.45387 -410.248608)
		(end 395.054836 -410.4005)
		(width 0.14224)
		(layer "In15.Cu")
		(net "P5E_CPU0_P2_RX_BUF_DP<5>")
	)
	(segment
		(start 394.000736 -410.802074)
		(end 393.823698 -410.722572)
		(width 0.14224)
		(layer "In15.Cu")
		(net "P5E_CPU0_P2_RX_BUF_DP<5>")
	)
	(segment
		(start 391.082784 -425.2341)
		(end 391.082784 -438.148984)
		(width 0.14224)
		(layer "In15.Cu")
		(net "P5E_CPU0_P2_RX_BUF_DP<5>")
	)
	(segment
		(start 388.371334 -420.095934)
		(end 388.363714 -420.111174)
		(width 0.14224)
		(layer "In15.Cu")
		(net "P5E_CPU0_P2_RX_BUF_DP<5>")
	)
	(segment
		(start 389.846312 -415.869374)
		(end 389.983472 -416.006534)
		(width 0.14224)
		(layer "In15.Cu")
		(net "P5E_CPU0_P2_RX_BUF_DP<5>")
	)
	(segment
		(start 409.127452 -401.399756)
		(end 408.985212 -401.541996)
		(width 0.14224)
		(layer "In15.Cu")
		(net "P5E_CPU0_P2_RX_BUF_DP<5>")
	)
	(segment
		(start 393.823698 -410.722572)
		(end 393.425172 -410.874464)
		(width 0.14224)
		(layer "In15.Cu")
		(net "P5E_CPU0_P2_RX_BUF_DP<5>")
	)
	(segment
		(start 389.676894 -419.457632)
		(end 389.50646 -419.636194)
		(width 0.14224)
		(layer "In15.Cu")
		(net "P5E_CPU0_P2_RX_BUF_DP<5>")
	)
	(arc
		(start 390.437624 -414.267142)
		(mid 390.231742 -414.377288)
		(end 390.05129 -414.52546)
		(width 0.14224)
		(layer "In15.Cu")
		(net "P5E_CPU0_P2_RX_BUF_DP<5>")
	)
	(arc
		(start 390.05129 -414.52546)
		(mid 389.899527 -414.752445)
		(end 389.846312 -415.020252)
		(width 0.14224)
		(layer "In15.Cu")
		(net "P5E_CPU0_P2_RX_BUF_DP<5>")
	)
	(arc
		(start 390.832848 -424.531282)
		(mid 390.897405 -424.625846)
		(end 390.944608 -424.730164)
		(width 0.14224)
		(layer "In15.Cu")
		(net "P5E_CPU0_P2_RX_BUF_DP<5>")
	)
	(arc
		(start 391.523474 -412.126938)
		(mid 391.415784 -412.288108)
		(end 391.377932 -412.47822)
		(width 0.14224)
		(layer "In15.Cu")
		(net "P5E_CPU0_P2_RX_BUF_DP<5>")
	)
	(arc
		(start 391.377932 -413.306514)
		(mid 391.325318 -413.571111)
		(end 391.175494 -413.795464)
		(width 0.14224)
		(layer "In15.Cu")
		(net "P5E_CPU0_P2_RX_BUF_DP<5>")
	)
	(arc
		(start 389.50646 -419.636194)
		(mid 389.428474 -419.699891)
		(end 389.337296 -419.74262)
		(width 0.14224)
		(layer "In15.Cu")
		(net "P5E_CPU0_P2_RX_BUF_DP<5>")
	)
	(arc
		(start 388.314692 -421.484298)
		(mid 388.366717 -421.745756)
		(end 388.514844 -421.967406)
		(width 0.14224)
		(layer "In15.Cu")
		(net "P5E_CPU0_P2_RX_BUF_DP<5>")
	)
	(arc
		(start 391.045446 -425.016422)
		(mid 391.073333 -425.123678)
		(end 391.082784 -425.2341)
		(width 0.14224)
		(layer "In15.Cu")
		(net "P5E_CPU0_P2_RX_BUF_DP<5>")
	)
	(arc
		(start 392.381486 -411.442662)
		(mid 392.018425 -411.675596)
		(end 391.692384 -411.958028)
		(width 0.14224)
		(layer "In15.Cu")
		(net "P5E_CPU0_P2_RX_BUF_DP<5>")
	)
	(arc
		(start 389.846312 -419.034722)
		(mid 389.80244 -419.262543)
		(end 389.676894 -419.457632)
		(width 0.14224)
		(layer "In15.Cu")
		(net "P5E_CPU0_P2_RX_BUF_DP<5>")
	)
	(arc
		(start 388.363714 -420.111174)
		(mid 388.327114 -420.212208)
		(end 388.314692 -420.318946)
		(width 0.14224)
		(layer "In15.Cu")
		(net "P5E_CPU0_P2_RX_BUF_DP<5>")
	)
	(segment
		(start 407.54173 -401.105878)
		(end 407.794968 -401.359116)
		(width 0.1016)
		(layer "F.Cu")
		(net "P5E_CPU0_P2_RX_BUF_DP<4>")
	)
	(segment
		(start 407.630376 -399.74774)
		(end 407.630376 -399.870676)
		(width 0.1016)
		(layer "F.Cu")
		(net "P5E_CPU0_P2_RX_BUF_DP<4>")
	)
	(segment
		(start 407.794968 -401.359116)
		(end 408.10561 -401.359116)
		(width 0.1016)
		(layer "F.Cu")
		(net "P5E_CPU0_P2_RX_BUF_DP<4>")
	)
	(segment
		(start 407.630376 -399.870676)
		(end 407.54173 -399.959322)
		(width 0.1016)
		(layer "F.Cu")
		(net "P5E_CPU0_P2_RX_BUF_DP<4>")
	)
	(segment
		(start 408.10561 -401.359116)
		(end 408.244294 -401.4978)
		(width 0.1016)
		(layer "F.Cu")
		(net "P5E_CPU0_P2_RX_BUF_DP<4>")
	)
	(segment
		(start 408.244294 -401.4978)
		(end 408.244294 -401.674838)
		(width 0.1016)
		(layer "F.Cu")
		(net "P5E_CPU0_P2_RX_BUF_DP<4>")
	)
	(segment
		(start 407.54173 -399.959322)
		(end 407.54173 -401.105878)
		(width 0.1016)
		(layer "F.Cu")
		(net "P5E_CPU0_P2_RX_BUF_DP<4>")
	)
	(segment
		(start 407.545794 -399.663158)
		(end 407.630376 -399.74774)
		(width 0.1016)
		(layer "F.Cu")
		(net "P5E_CPU0_P2_RX_BUF_DP<4>")
	)
	(segment
		(start 408.117294 -401.399756)
		(end 407.927556 -401.399756)
		(width 0.14224)
		(layer "In15.Cu")
		(net "P5E_CPU0_P2_RX_BUF_DP<4>")
	)
	(segment
		(start 386.920232 -416.57143)
		(end 386.783072 -416.70859)
		(width 0.14224)
		(layer "In15.Cu")
		(net "P5E_CPU0_P2_RX_BUF_DP<4>")
	)
	(segment
		(start 396.795244 -408.435556)
		(end 396.621762 -408.348434)
		(width 0.14224)
		(layer "In15.Cu")
		(net "P5E_CPU0_P2_RX_BUF_DP<4>")
	)
	(segment
		(start 387.165342 -422.959784)
		(end 387.355588 -422.921938)
		(width 0.14224)
		(layer "In15.Cu")
		(net "P5E_CPU0_P2_RX_BUF_DP<4>")
	)
	(segment
		(start 395.724634 -408.79014)
		(end 395.551152 -408.703018)
		(width 0.14224)
		(layer "In15.Cu")
		(net "P5E_CPU0_P2_RX_BUF_DP<4>")
	)
	(segment
		(start 396.621762 -408.348434)
		(end 396.216886 -408.482546)
		(width 0.14224)
		(layer "In15.Cu")
		(net "P5E_CPU0_P2_RX_BUF_DP<4>")
	)
	(segment
		(start 386.920232 -417.742624)
		(end 386.783072 -417.879784)
		(width 0.14224)
		(layer "In15.Cu")
		(net "P5E_CPU0_P2_RX_BUF_DP<4>")
	)
	(segment
		(start 395.551152 -408.703018)
		(end 395.146276 -408.83713)
		(width 0.14224)
		(layer "In15.Cu")
		(net "P5E_CPU0_P2_RX_BUF_DP<4>")
	)
	(segment
		(start 401.72132 -406.659588)
		(end 397.287496 -408.127962)
		(width 0.14224)
		(layer "In15.Cu")
		(net "P5E_CPU0_P2_RX_BUF_DP<4>")
	)
	(segment
		(start 389.599678 -437.341264)
		(end 389.749792 -437.19115)
		(width 0.14224)
		(layer "In15.Cu")
		(net "P5E_CPU0_P2_RX_BUF_DP<4>")
	)
	(segment
		(start 391.124186 -410.560774)
		(end 390.73201 -410.728668)
		(width 0.14224)
		(layer "In15.Cu")
		(net "P5E_CPU0_P2_RX_BUF_DP<4>")
	)
	(segment
		(start 391.768838 -410.284422)
		(end 391.696702 -410.464762)
		(width 0.14224)
		(layer "In15.Cu")
		(net "P5E_CPU0_P2_RX_BUF_DP<4>")
	)
	(segment
		(start 393.842494 -409.39593)
		(end 393.770358 -409.57627)
		(width 0.14224)
		(layer "In15.Cu")
		(net "P5E_CPU0_P2_RX_BUF_DP<4>")
	)
	(segment
		(start 386.783072 -417.879784)
		(end 386.783072 -419.079172)
		(width 0.14224)
		(layer "In15.Cu")
		(net "P5E_CPU0_P2_RX_BUF_DP<4>")
	)
	(segment
		(start 386.783072 -415.020252)
		(end 386.783072 -416.00755)
		(width 0.14224)
		(layer "In15.Cu")
		(net "P5E_CPU0_P2_RX_BUF_DP<4>")
	)
	(segment
		(start 408.244294 -401.674838)
		(end 408.244294 -401.526756)
		(width 0.14224)
		(layer "In15.Cu")
		(net "P5E_CPU0_P2_RX_BUF_DP<4>")
	)
	(segment
		(start 406.183592 -405.155908)
		(end 405.365712 -405.702262)
		(width 0.14224)
		(layer "In15.Cu")
		(net "P5E_CPU0_P2_RX_BUF_DP<4>")
	)
	(segment
		(start 388.454646 -423.921936)
		(end 388.971282 -424.617642)
		(width 0.14224)
		(layer "In15.Cu")
		(net "P5E_CPU0_P2_RX_BUF_DP<4>")
	)
	(segment
		(start 388.570978 -411.933644)
		(end 388.505954 -411.998668)
		(width 0.14224)
		(layer "In15.Cu")
		(net "P5E_CPU0_P2_RX_BUF_DP<4>")
	)
	(segment
		(start 388.112254 -413.795464)
		(end 387.965442 -413.942276)
		(width 0.14224)
		(layer "In15.Cu")
		(net "P5E_CPU0_P2_RX_BUF_DP<4>")
	)
	(segment
		(start 397.287496 -408.127962)
		(end 397.200628 -408.301444)
		(width 0.14224)
		(layer "In15.Cu")
		(net "P5E_CPU0_P2_RX_BUF_DP<4>")
	)
	(segment
		(start 391.696702 -410.464762)
		(end 391.304272 -410.632656)
		(width 0.14224)
		(layer "In15.Cu")
		(net "P5E_CPU0_P2_RX_BUF_DP<4>")
	)
	(segment
		(start 386.920232 -417.315904)
		(end 386.920232 -417.742624)
		(width 0.14224)
		(layer "In15.Cu")
		(net "P5E_CPU0_P2_RX_BUF_DP<4>")
	)
	(segment
		(start 404.970742 -405.865838)
		(end 403.99081 -406.060656)
		(width 0.14224)
		(layer "In15.Cu")
		(net "P5E_CPU0_P2_RX_BUF_DP<4>")
	)
	(segment
		(start 387.748272 -423.349674)
		(end 388.102856 -423.58691)
		(width 0.14224)
		(layer "In15.Cu")
		(net "P5E_CPU0_P2_RX_BUF_DP<4>")
	)
	(segment
		(start 392.161014 -410.116528)
		(end 391.768838 -410.284422)
		(width 0.14224)
		(layer "In15.Cu")
		(net "P5E_CPU0_P2_RX_BUF_DP<4>")
	)
	(segment
		(start 388.314692 -412.46044)
		(end 388.314692 -413.306514)
		(width 0.14224)
		(layer "In15.Cu")
		(net "P5E_CPU0_P2_RX_BUF_DP<4>")
	)
	(segment
		(start 396.130018 -408.656028)
		(end 395.724634 -408.79014)
		(width 0.14224)
		(layer "In15.Cu")
		(net "P5E_CPU0_P2_RX_BUF_DP<4>")
	)
	(segment
		(start 390.659874 -410.909008)
		(end 390.267444 -411.076902)
		(width 0.14224)
		(layer "In15.Cu")
		(net "P5E_CPU0_P2_RX_BUF_DP<4>")
	)
	(segment
		(start 387.355588 -422.921938)
		(end 387.710426 -423.159428)
		(width 0.14224)
		(layer "In15.Cu")
		(net "P5E_CPU0_P2_RX_BUF_DP<4>")
	)
	(segment
		(start 407.325068 -404.014432)
		(end 406.183592 -405.155908)
		(width 0.14224)
		(layer "In15.Cu")
		(net "P5E_CPU0_P2_RX_BUF_DP<4>")
	)
	(segment
		(start 390.087358 -411.00502)
		(end 389.695182 -411.172914)
		(width 0.14224)
		(layer "In15.Cu")
		(net "P5E_CPU0_P2_RX_BUF_DP<4>")
	)
	(segment
		(start 407.785316 -401.541996)
		(end 407.785316 -403.151594)
		(width 0.14224)
		(layer "In15.Cu")
		(net "P5E_CPU0_P2_RX_BUF_DP<4>")
	)
	(segment
		(start 408.244294 -401.526756)
		(end 408.117294 -401.399756)
		(width 0.14224)
		(layer "In15.Cu")
		(net "P5E_CPU0_P2_RX_BUF_DP<4>")
	)
	(segment
		(start 389.208264 -437.341264)
		(end 389.599678 -437.341264)
		(width 0.14224)
		(layer "In15.Cu")
		(net "P5E_CPU0_P2_RX_BUF_DP<4>")
	)
	(segment
		(start 386.783072 -417.178744)
		(end 386.920232 -417.315904)
		(width 0.14224)
		(layer "In15.Cu")
		(net "P5E_CPU0_P2_RX_BUF_DP<4>")
	)
	(segment
		(start 407.595578 -403.609556)
		(end 407.325068 -404.014432)
		(width 0.14224)
		(layer "In15.Cu")
		(net "P5E_CPU0_P2_RX_BUF_DP<4>")
	)
	(segment
		(start 392.805666 -409.840176)
		(end 392.73353 -410.020516)
		(width 0.14224)
		(layer "In15.Cu")
		(net "P5E_CPU0_P2_RX_BUF_DP<4>")
	)
	(segment
		(start 387.649974 -414.153096)
		(end 387.374384 -414.267142)
		(width 0.14224)
		(layer "In15.Cu")
		(net "P5E_CPU0_P2_RX_BUF_DP<4>")
	)
	(segment
		(start 385.251452 -420.22776)
		(end 385.251452 -421.218106)
		(width 0.14224)
		(layer "In15.Cu")
		(net "P5E_CPU0_P2_RX_BUF_DP<4>")
	)
	(segment
		(start 396.216886 -408.482546)
		(end 396.130018 -408.656028)
		(width 0.14224)
		(layer "In15.Cu")
		(net "P5E_CPU0_P2_RX_BUF_DP<4>")
	)
	(segment
		(start 392.3411 -410.18841)
		(end 392.161014 -410.116528)
		(width 0.14224)
		(layer "In15.Cu")
		(net "P5E_CPU0_P2_RX_BUF_DP<4>")
	)
	(segment
		(start 393.770358 -409.57627)
		(end 393.377928 -409.744164)
		(width 0.14224)
		(layer "In15.Cu")
		(net "P5E_CPU0_P2_RX_BUF_DP<4>")
	)
	(segment
		(start 386.783072 -416.70859)
		(end 386.783072 -417.178744)
		(width 0.14224)
		(layer "In15.Cu")
		(net "P5E_CPU0_P2_RX_BUF_DP<4>")
	)
	(segment
		(start 397.200628 -408.301444)
		(end 396.795244 -408.435556)
		(width 0.14224)
		(layer "In15.Cu")
		(net "P5E_CPU0_P2_RX_BUF_DP<4>")
	)
	(segment
		(start 390.73201 -410.728668)
		(end 390.659874 -410.909008)
		(width 0.14224)
		(layer "In15.Cu")
		(net "P5E_CPU0_P2_RX_BUF_DP<4>")
	)
	(segment
		(start 387.710426 -423.159428)
		(end 387.748272 -423.349674)
		(width 0.14224)
		(layer "In15.Cu")
		(net "P5E_CPU0_P2_RX_BUF_DP<4>")
	)
	(segment
		(start 407.785316 -403.151594)
		(end 407.595578 -403.609556)
		(width 0.14224)
		(layer "In15.Cu")
		(net "P5E_CPU0_P2_RX_BUF_DP<4>")
	)
	(segment
		(start 393.197842 -409.672282)
		(end 392.805666 -409.840176)
		(width 0.14224)
		(layer "In15.Cu")
		(net "P5E_CPU0_P2_RX_BUF_DP<4>")
	)
	(segment
		(start 395.146276 -408.83713)
		(end 393.842494 -409.39593)
		(width 0.14224)
		(layer "In15.Cu")
		(net "P5E_CPU0_P2_RX_BUF_DP<4>")
	)
	(segment
		(start 386.920232 -416.14471)
		(end 386.920232 -416.57143)
		(width 0.14224)
		(layer "In15.Cu")
		(net "P5E_CPU0_P2_RX_BUF_DP<4>")
	)
	(segment
		(start 385.887722 -422.105328)
		(end 387.165342 -422.959784)
		(width 0.14224)
		(layer "In15.Cu")
		(net "P5E_CPU0_P2_RX_BUF_DP<4>")
	)
	(segment
		(start 387.965442 -413.942276)
		(end 387.649974 -414.153096)
		(width 0.14224)
		(layer "In15.Cu")
		(net "P5E_CPU0_P2_RX_BUF_DP<4>")
	)
	(segment
		(start 389.071104 -437.204104)
		(end 389.208264 -437.341264)
		(width 0.14224)
		(layer "In15.Cu")
		(net "P5E_CPU0_P2_RX_BUF_DP<4>")
	)
	(segment
		(start 390.267444 -411.076902)
		(end 390.087358 -411.00502)
		(width 0.14224)
		(layer "In15.Cu")
		(net "P5E_CPU0_P2_RX_BUF_DP<4>")
	)
	(segment
		(start 405.365712 -405.702262)
		(end 404.970742 -405.865838)
		(width 0.14224)
		(layer "In15.Cu")
		(net "P5E_CPU0_P2_RX_BUF_DP<4>")
	)
	(segment
		(start 407.927556 -401.399756)
		(end 407.785316 -401.541996)
		(width 0.14224)
		(layer "In15.Cu")
		(net "P5E_CPU0_P2_RX_BUF_DP<4>")
	)
	(segment
		(start 389.749792 -437.19115)
		(end 389.749792 -436.889906)
		(width 0.14224)
		(layer "In15.Cu")
		(net "P5E_CPU0_P2_RX_BUF_DP<4>")
	)
	(segment
		(start 392.73353 -410.020516)
		(end 392.3411 -410.18841)
		(width 0.14224)
		(layer "In15.Cu")
		(net "P5E_CPU0_P2_RX_BUF_DP<4>")
	)
	(segment
		(start 386.783072 -416.00755)
		(end 386.920232 -416.14471)
		(width 0.14224)
		(layer "In15.Cu")
		(net "P5E_CPU0_P2_RX_BUF_DP<4>")
	)
	(segment
		(start 403.99081 -406.060656)
		(end 401.72132 -406.659588)
		(width 0.14224)
		(layer "In15.Cu")
		(net "P5E_CPU0_P2_RX_BUF_DP<4>")
	)
	(segment
		(start 393.377928 -409.744164)
		(end 393.197842 -409.672282)
		(width 0.14224)
		(layer "In15.Cu")
		(net "P5E_CPU0_P2_RX_BUF_DP<4>")
	)
	(segment
		(start 391.304272 -410.632656)
		(end 391.124186 -410.560774)
		(width 0.14224)
		(layer "In15.Cu")
		(net "P5E_CPU0_P2_RX_BUF_DP<4>")
	)
	(segment
		(start 385.287774 -421.36314)
		(end 385.460748 -421.687498)
		(width 0.14224)
		(layer "In15.Cu")
		(net "P5E_CPU0_P2_RX_BUF_DP<4>")
	)
	(segment
		(start 386.291582 -419.70198)
		(end 385.339082 -420.09695)
		(width 0.14224)
		(layer "In15.Cu")
		(net "P5E_CPU0_P2_RX_BUF_DP<4>")
	)
	(segment
		(start 385.537202 -421.787574)
		(end 385.788916 -422.026334)
		(width 0.14224)
		(layer "In15.Cu")
		(net "P5E_CPU0_P2_RX_BUF_DP<4>")
	)
	(segment
		(start 389.071104 -424.919648)
		(end 389.071104 -437.204104)
		(width 0.14224)
		(layer "In15.Cu")
		(net "P5E_CPU0_P2_RX_BUF_DP<4>")
	)
	(segment
		(start 386.659374 -419.388798)
		(end 386.491988 -419.56482)
		(width 0.14224)
		(layer "In15.Cu")
		(net "P5E_CPU0_P2_RX_BUF_DP<4>")
	)
	(arc
		(start 386.491988 -419.56482)
		(mid 386.39897 -419.643897)
		(end 386.291582 -419.70198)
		(width 0.14224)
		(layer "In15.Cu")
		(net "P5E_CPU0_P2_RX_BUF_DP<4>")
	)
	(arc
		(start 389.695182 -411.172914)
		(mid 389.096781 -411.499634)
		(end 388.570978 -411.933644)
		(width 0.14224)
		(layer "In15.Cu")
		(net "P5E_CPU0_P2_RX_BUF_DP<4>")
	)
	(arc
		(start 385.460748 -421.687498)
		(mid 385.494938 -421.74062)
		(end 385.537202 -421.787574)
		(width 0.14224)
		(layer "In15.Cu")
		(net "P5E_CPU0_P2_RX_BUF_DP<4>")
	)
	(arc
		(start 387.374384 -414.267142)
		(mid 387.168502 -414.377288)
		(end 386.98805 -414.52546)
		(width 0.14224)
		(layer "In15.Cu")
		(net "P5E_CPU0_P2_RX_BUF_DP<4>")
	)
	(arc
		(start 388.971282 -424.617642)
		(mid 389.045506 -424.760609)
		(end 389.071104 -424.919648)
		(width 0.14224)
		(layer "In15.Cu")
		(net "P5E_CPU0_P2_RX_BUF_DP<4>")
	)
	(arc
		(start 388.102856 -423.58691)
		(mid 388.293123 -423.739332)
		(end 388.454646 -423.921936)
		(width 0.14224)
		(layer "In15.Cu")
		(net "P5E_CPU0_P2_RX_BUF_DP<4>")
	)
	(arc
		(start 385.339082 -420.09695)
		(mid 385.275407 -420.149062)
		(end 385.251452 -420.22776)
		(width 0.14224)
		(layer "In15.Cu")
		(net "P5E_CPU0_P2_RX_BUF_DP<4>")
	)
	(arc
		(start 388.505954 -411.998668)
		(mid 388.364392 -412.210531)
		(end 388.314692 -412.46044)
		(width 0.14224)
		(layer "In15.Cu")
		(net "P5E_CPU0_P2_RX_BUF_DP<4>")
	)
	(arc
		(start 385.788916 -422.026334)
		(mid 385.836647 -422.067922)
		(end 385.887722 -422.105328)
		(width 0.14224)
		(layer "In15.Cu")
		(net "P5E_CPU0_P2_RX_BUF_DP<4>")
	)
	(arc
		(start 386.783072 -419.079172)
		(mid 386.751107 -419.24593)
		(end 386.659374 -419.388798)
		(width 0.14224)
		(layer "In15.Cu")
		(net "P5E_CPU0_P2_RX_BUF_DP<4>")
	)
	(arc
		(start 386.98805 -414.52546)
		(mid 386.836287 -414.752445)
		(end 386.783072 -415.020252)
		(width 0.14224)
		(layer "In15.Cu")
		(net "P5E_CPU0_P2_RX_BUF_DP<4>")
	)
	(arc
		(start 388.314692 -413.306514)
		(mid 388.262078 -413.571111)
		(end 388.112254 -413.795464)
		(width 0.14224)
		(layer "In15.Cu")
		(net "P5E_CPU0_P2_RX_BUF_DP<4>")
	)
	(arc
		(start 385.251452 -421.218106)
		(mid 385.260711 -421.292849)
		(end 385.287774 -421.36314)
		(width 0.14224)
		(layer "In15.Cu")
		(net "P5E_CPU0_P2_RX_BUF_DP<4>")
	)
	(segment
		(start 406.608026 -401.359116)
		(end 406.90546 -401.359116)
		(width 0.1016)
		(layer "F.Cu")
		(net "P5E_CPU0_P2_RX_BUF_DP<3>")
	)
	(segment
		(start 406.345644 -399.663158)
		(end 406.430226 -399.74774)
		(width 0.1016)
		(layer "F.Cu")
		(net "P5E_CPU0_P2_RX_BUF_DP<3>")
	)
	(segment
		(start 406.354788 -399.946114)
		(end 406.354788 -401.105878)
		(width 0.1016)
		(layer "F.Cu")
		(net "P5E_CPU0_P2_RX_BUF_DP<3>")
	)
	(segment
		(start 406.90546 -401.359116)
		(end 407.044144 -401.4978)
		(width 0.1016)
		(layer "F.Cu")
		(net "P5E_CPU0_P2_RX_BUF_DP<3>")
	)
	(segment
		(start 406.430226 -399.74774)
		(end 406.430226 -399.870676)
		(width 0.1016)
		(layer "F.Cu")
		(net "P5E_CPU0_P2_RX_BUF_DP<3>")
	)
	(segment
		(start 406.354788 -401.105878)
		(end 406.608026 -401.359116)
		(width 0.1016)
		(layer "F.Cu")
		(net "P5E_CPU0_P2_RX_BUF_DP<3>")
	)
	(segment
		(start 406.430226 -399.870676)
		(end 406.354788 -399.946114)
		(width 0.1016)
		(layer "F.Cu")
		(net "P5E_CPU0_P2_RX_BUF_DP<3>")
	)
	(segment
		(start 407.044144 -401.4978)
		(end 407.044144 -401.674838)
		(width 0.1016)
		(layer "F.Cu")
		(net "P5E_CPU0_P2_RX_BUF_DP<3>")
	)
	(segment
		(start 385.951476 -423.68851)
		(end 385.596892 -423.451528)
		(width 0.14224)
		(layer "In15.Cu")
		(net "P5E_CPU0_P2_RX_BUF_DP<3>")
	)
	(segment
		(start 405.075898 -404.722076)
		(end 405.637746 -404.316184)
		(width 0.14224)
		(layer "In15.Cu")
		(net "P5E_CPU0_P2_RX_BUF_DP<3>")
	)
	(segment
		(start 384.511804 -422.726612)
		(end 384.117596 -422.563544)
		(width 0.14224)
		(layer "In15.Cu")
		(net "P5E_CPU0_P2_RX_BUF_DP<3>")
	)
	(segment
		(start 392.822176 -408.77871)
		(end 393.269724 -408.606244)
		(width 0.14224)
		(layer "In15.Cu")
		(net "P5E_CPU0_P2_RX_BUF_DP<3>")
	)
	(segment
		(start 392.678666 -408.71521)
		(end 392.822176 -408.77871)
		(width 0.14224)
		(layer "In15.Cu")
		(net "P5E_CPU0_P2_RX_BUF_DP<3>")
	)
	(segment
		(start 384.311144 -414.267142)
		(end 384.586734 -414.153096)
		(width 0.14224)
		(layer "In15.Cu")
		(net "P5E_CPU0_P2_RX_BUF_DP<3>")
	)
	(segment
		(start 390.176258 -409.826968)
		(end 390.254998 -409.649422)
		(width 0.14224)
		(layer "In15.Cu")
		(net "P5E_CPU0_P2_RX_BUF_DP<3>")
	)
	(segment
		(start 387.208268 -438.341262)
		(end 387.071108 -438.204102)
		(width 0.14224)
		(layer "In15.Cu")
		(net "P5E_CPU0_P2_RX_BUF_DP<3>")
	)
	(segment
		(start 395.228826 -407.731976)
		(end 401.04314 -405.850852)
		(width 0.14224)
		(layer "In15.Cu")
		(net "P5E_CPU0_P2_RX_BUF_DP<3>")
	)
	(segment
		(start 387.23697 -410.960062)
		(end 387.635242 -410.806646)
		(width 0.14224)
		(layer "In15.Cu")
		(net "P5E_CPU0_P2_RX_BUF_DP<3>")
	)
	(segment
		(start 387.749796 -438.191148)
		(end 387.599682 -438.341262)
		(width 0.14224)
		(layer "In15.Cu")
		(net "P5E_CPU0_P2_RX_BUF_DP<3>")
	)
	(segment
		(start 385.013708 -423.061892)
		(end 384.511804 -422.726612)
		(width 0.14224)
		(layer "In15.Cu")
		(net "P5E_CPU0_P2_RX_BUF_DP<3>")
	)
	(segment
		(start 383.719832 -417.260278)
		(end 383.719832 -416.833558)
		(width 0.14224)
		(layer "In15.Cu")
		(net "P5E_CPU0_P2_RX_BUF_DP<3>")
	)
	(segment
		(start 386.113782 -411.246066)
		(end 387.059424 -410.881576)
		(width 0.14224)
		(layer "In15.Cu")
		(net "P5E_CPU0_P2_RX_BUF_DP<3>")
	)
	(segment
		(start 406.917144 -401.399756)
		(end 407.044144 -401.526756)
		(width 0.14224)
		(layer "In15.Cu")
		(net "P5E_CPU0_P2_RX_BUF_DP<3>")
	)
	(segment
		(start 391.49401 -409.318714)
		(end 391.892536 -409.165298)
		(width 0.14224)
		(layer "In15.Cu")
		(net "P5E_CPU0_P2_RX_BUF_DP<3>")
	)
	(segment
		(start 387.599682 -438.341262)
		(end 387.208268 -438.341262)
		(width 0.14224)
		(layer "In15.Cu")
		(net "P5E_CPU0_P2_RX_BUF_DP<3>")
	)
	(segment
		(start 406.727406 -401.399756)
		(end 406.917144 -401.399756)
		(width 0.14224)
		(layer "In15.Cu")
		(net "P5E_CPU0_P2_RX_BUF_DP<3>")
	)
	(segment
		(start 383.391156 -419.59911)
		(end 383.567686 -419.45052)
		(width 0.14224)
		(layer "In15.Cu")
		(net "P5E_CPU0_P2_RX_BUF_DP<3>")
	)
	(segment
		(start 383.856992 -417.824158)
		(end 383.856992 -417.397438)
		(width 0.14224)
		(layer "In15.Cu")
		(net "P5E_CPU0_P2_RX_BUF_DP<3>")
	)
	(segment
		(start 387.713982 -410.6291)
		(end 388.334504 -410.390086)
		(width 0.14224)
		(layer "In15.Cu")
		(net "P5E_CPU0_P2_RX_BUF_DP<3>")
	)
	(segment
		(start 383.719832 -416.833558)
		(end 383.856992 -416.696398)
		(width 0.14224)
		(layer "In15.Cu")
		(net "P5E_CPU0_P2_RX_BUF_DP<3>")
	)
	(segment
		(start 387.635242 -410.806646)
		(end 387.713982 -410.6291)
		(width 0.14224)
		(layer "In15.Cu")
		(net "P5E_CPU0_P2_RX_BUF_DP<3>")
	)
	(segment
		(start 382.295908 -420.088568)
		(end 383.2098 -419.7096)
		(width 0.14224)
		(layer "In15.Cu")
		(net "P5E_CPU0_P2_RX_BUF_DP<3>")
	)
	(segment
		(start 385.596892 -423.451528)
		(end 385.559046 -423.261282)
		(width 0.14224)
		(layer "In15.Cu")
		(net "P5E_CPU0_P2_RX_BUF_DP<3>")
	)
	(segment
		(start 387.013958 -425.098972)
		(end 386.703062 -424.517312)
		(width 0.14224)
		(layer "In15.Cu")
		(net "P5E_CPU0_P2_RX_BUF_DP<3>")
	)
	(segment
		(start 393.269724 -408.606244)
		(end 393.333224 -408.462734)
		(width 0.14224)
		(layer "In15.Cu")
		(net "P5E_CPU0_P2_RX_BUF_DP<3>")
	)
	(segment
		(start 382.188212 -421.43426)
		(end 382.188212 -420.250112)
		(width 0.14224)
		(layer "In15.Cu")
		(net "P5E_CPU0_P2_RX_BUF_DP<3>")
	)
	(segment
		(start 383.469896 -422.294812)
		(end 382.634236 -421.948864)
		(width 0.14224)
		(layer "In15.Cu")
		(net "P5E_CPU0_P2_RX_BUF_DP<3>")
	)
	(segment
		(start 384.117596 -422.563544)
		(end 384.043428 -422.383966)
		(width 0.14224)
		(layer "In15.Cu")
		(net "P5E_CPU0_P2_RX_BUF_DP<3>")
	)
	(segment
		(start 388.334504 -410.390086)
		(end 388.511796 -410.468572)
		(width 0.14224)
		(layer "In15.Cu")
		(net "P5E_CPU0_P2_RX_BUF_DP<3>")
	)
	(segment
		(start 391.316718 -409.240228)
		(end 391.49401 -409.318714)
		(width 0.14224)
		(layer "In15.Cu")
		(net "P5E_CPU0_P2_RX_BUF_DP<3>")
	)
	(segment
		(start 382.236472 -421.550846)
		(end 382.188212 -421.43426)
		(width 0.14224)
		(layer "In15.Cu")
		(net "P5E_CPU0_P2_RX_BUF_DP<3>")
	)
	(segment
		(start 383.648966 -422.220644)
		(end 383.469896 -422.294812)
		(width 0.14224)
		(layer "In15.Cu")
		(net "P5E_CPU0_P2_RX_BUF_DP<3>")
	)
	(segment
		(start 388.988808 -410.13761)
		(end 389.60044 -409.901898)
		(width 0.14224)
		(layer "In15.Cu")
		(net "P5E_CPU0_P2_RX_BUF_DP<3>")
	)
	(segment
		(start 383.719832 -416.132518)
		(end 383.719832 -415.020252)
		(width 0.14224)
		(layer "In15.Cu")
		(net "P5E_CPU0_P2_RX_BUF_DP<3>")
	)
	(segment
		(start 383.856992 -416.269678)
		(end 383.719832 -416.132518)
		(width 0.14224)
		(layer "In15.Cu")
		(net "P5E_CPU0_P2_RX_BUF_DP<3>")
	)
	(segment
		(start 387.071108 -438.204102)
		(end 387.071108 -425.326556)
		(width 0.14224)
		(layer "In15.Cu")
		(net "P5E_CPU0_P2_RX_BUF_DP<3>")
	)
	(segment
		(start 393.333224 -408.462734)
		(end 395.228826 -407.731976)
		(width 0.14224)
		(layer "In15.Cu")
		(net "P5E_CPU0_P2_RX_BUF_DP<3>")
	)
	(segment
		(start 383.856992 -416.696398)
		(end 383.856992 -416.269678)
		(width 0.14224)
		(layer "In15.Cu")
		(net "P5E_CPU0_P2_RX_BUF_DP<3>")
	)
	(segment
		(start 388.910322 -410.315156)
		(end 388.988808 -410.13761)
		(width 0.14224)
		(layer "In15.Cu")
		(net "P5E_CPU0_P2_RX_BUF_DP<3>")
	)
	(segment
		(start 385.203954 -423.024046)
		(end 385.013708 -423.061892)
		(width 0.14224)
		(layer "In15.Cu")
		(net "P5E_CPU0_P2_RX_BUF_DP<3>")
	)
	(segment
		(start 389.777732 -409.980384)
		(end 390.176258 -409.826968)
		(width 0.14224)
		(layer "In15.Cu")
		(net "P5E_CPU0_P2_RX_BUF_DP<3>")
	)
	(segment
		(start 387.749796 -437.889904)
		(end 387.749796 -438.191148)
		(width 0.14224)
		(layer "In15.Cu")
		(net "P5E_CPU0_P2_RX_BUF_DP<3>")
	)
	(segment
		(start 384.043428 -422.383966)
		(end 383.648966 -422.220644)
		(width 0.14224)
		(layer "In15.Cu")
		(net "P5E_CPU0_P2_RX_BUF_DP<3>")
	)
	(segment
		(start 407.044144 -401.526756)
		(end 407.044144 -401.674838)
		(width 0.14224)
		(layer "In15.Cu")
		(net "P5E_CPU0_P2_RX_BUF_DP<3>")
	)
	(segment
		(start 391.971276 -408.987752)
		(end 392.678666 -408.71521)
		(width 0.14224)
		(layer "In15.Cu")
		(net "P5E_CPU0_P2_RX_BUF_DP<3>")
	)
	(segment
		(start 388.511796 -410.468572)
		(end 388.910322 -410.315156)
		(width 0.14224)
		(layer "In15.Cu")
		(net "P5E_CPU0_P2_RX_BUF_DP<3>")
	)
	(segment
		(start 406.585166 -401.541996)
		(end 406.727406 -401.399756)
		(width 0.14224)
		(layer "In15.Cu")
		(net "P5E_CPU0_P2_RX_BUF_DP<3>")
	)
	(segment
		(start 389.60044 -409.901898)
		(end 389.777732 -409.980384)
		(width 0.14224)
		(layer "In15.Cu")
		(net "P5E_CPU0_P2_RX_BUF_DP<3>")
	)
	(segment
		(start 383.856992 -417.397438)
		(end 383.719832 -417.260278)
		(width 0.14224)
		(layer "In15.Cu")
		(net "P5E_CPU0_P2_RX_BUF_DP<3>")
	)
	(segment
		(start 385.559046 -423.261282)
		(end 385.203954 -423.024046)
		(width 0.14224)
		(layer "In15.Cu")
		(net "P5E_CPU0_P2_RX_BUF_DP<3>")
	)
	(segment
		(start 391.892536 -409.165298)
		(end 391.971276 -408.987752)
		(width 0.14224)
		(layer "In15.Cu")
		(net "P5E_CPU0_P2_RX_BUF_DP<3>")
	)
	(segment
		(start 384.902202 -413.942276)
		(end 385.049014 -413.795464)
		(width 0.14224)
		(layer "In15.Cu")
		(net "P5E_CPU0_P2_RX_BUF_DP<3>")
	)
	(segment
		(start 406.357328 -403.596602)
		(end 406.585166 -403.046692)
		(width 0.14224)
		(layer "In15.Cu")
		(net "P5E_CPU0_P2_RX_BUF_DP<3>")
	)
	(segment
		(start 401.04314 -405.850852)
		(end 404.80234 -404.859744)
		(width 0.14224)
		(layer "In15.Cu")
		(net "P5E_CPU0_P2_RX_BUF_DP<3>")
	)
	(segment
		(start 385.251452 -413.306514)
		(end 385.251452 -412.106872)
		(width 0.14224)
		(layer "In15.Cu")
		(net "P5E_CPU0_P2_RX_BUF_DP<3>")
	)
	(segment
		(start 387.059424 -410.881576)
		(end 387.23697 -410.960062)
		(width 0.14224)
		(layer "In15.Cu")
		(net "P5E_CPU0_P2_RX_BUF_DP<3>")
	)
	(segment
		(start 404.80234 -404.859744)
		(end 405.075898 -404.722076)
		(width 0.14224)
		(layer "In15.Cu")
		(net "P5E_CPU0_P2_RX_BUF_DP<3>")
	)
	(segment
		(start 383.719832 -417.961318)
		(end 383.856992 -417.824158)
		(width 0.14224)
		(layer "In15.Cu")
		(net "P5E_CPU0_P2_RX_BUF_DP<3>")
	)
	(segment
		(start 383.719832 -419.123876)
		(end 383.719832 -417.961318)
		(width 0.14224)
		(layer "In15.Cu")
		(net "P5E_CPU0_P2_RX_BUF_DP<3>")
	)
	(segment
		(start 405.637746 -404.316184)
		(end 406.357328 -403.596602)
		(width 0.14224)
		(layer "In15.Cu")
		(net "P5E_CPU0_P2_RX_BUF_DP<3>")
	)
	(segment
		(start 390.254998 -409.649422)
		(end 391.316718 -409.240228)
		(width 0.14224)
		(layer "In15.Cu")
		(net "P5E_CPU0_P2_RX_BUF_DP<3>")
	)
	(segment
		(start 406.585166 -403.046692)
		(end 406.585166 -401.541996)
		(width 0.14224)
		(layer "In15.Cu")
		(net "P5E_CPU0_P2_RX_BUF_DP<3>")
	)
	(segment
		(start 384.586734 -414.153096)
		(end 384.902202 -413.942276)
		(width 0.14224)
		(layer "In15.Cu")
		(net "P5E_CPU0_P2_RX_BUF_DP<3>")
	)
	(segment
		(start 382.634236 -421.948864)
		(end 382.236472 -421.550846)
		(width 0.14224)
		(layer "In15.Cu")
		(net "P5E_CPU0_P2_RX_BUF_DP<3>")
	)
	(arc
		(start 383.719832 -415.020252)
		(mid 383.773061 -414.752451)
		(end 383.92481 -414.52546)
		(width 0.14224)
		(layer "In15.Cu")
		(net "P5E_CPU0_P2_RX_BUF_DP<3>")
	)
	(arc
		(start 385.414266 -411.70733)
		(mid 385.745797 -411.449055)
		(end 386.113782 -411.246066)
		(width 0.14224)
		(layer "In15.Cu")
		(net "P5E_CPU0_P2_RX_BUF_DP<3>")
	)
	(arc
		(start 385.049014 -413.795464)
		(mid 385.198854 -413.571118)
		(end 385.251452 -413.306514)
		(width 0.14224)
		(layer "In15.Cu")
		(net "P5E_CPU0_P2_RX_BUF_DP<3>")
	)
	(arc
		(start 386.703062 -424.517312)
		(mid 386.378342 -424.056598)
		(end 385.951476 -423.68851)
		(width 0.14224)
		(layer "In15.Cu")
		(net "P5E_CPU0_P2_RX_BUF_DP<3>")
	)
	(arc
		(start 382.188212 -420.250112)
		(mid 382.217604 -420.153036)
		(end 382.295908 -420.088568)
		(width 0.14224)
		(layer "In15.Cu")
		(net "P5E_CPU0_P2_RX_BUF_DP<3>")
	)
	(arc
		(start 383.92481 -414.52546)
		(mid 384.10528 -414.377314)
		(end 384.311144 -414.267142)
		(width 0.14224)
		(layer "In15.Cu")
		(net "P5E_CPU0_P2_RX_BUF_DP<3>")
	)
	(arc
		(start 383.2098 -419.7096)
		(mid 383.304733 -419.661337)
		(end 383.391156 -419.59911)
		(width 0.14224)
		(layer "In15.Cu")
		(net "P5E_CPU0_P2_RX_BUF_DP<3>")
	)
	(arc
		(start 387.071108 -425.326556)
		(mid 387.056568 -425.209241)
		(end 387.013958 -425.098972)
		(width 0.14224)
		(layer "In15.Cu")
		(net "P5E_CPU0_P2_RX_BUF_DP<3>")
	)
	(arc
		(start 383.567686 -419.45052)
		(mid 383.679886 -419.304024)
		(end 383.719832 -419.123876)
		(width 0.14224)
		(layer "In15.Cu")
		(net "P5E_CPU0_P2_RX_BUF_DP<3>")
	)
	(arc
		(start 385.251452 -412.106872)
		(mid 385.293764 -411.89117)
		(end 385.414266 -411.70733)
		(width 0.14224)
		(layer "In15.Cu")
		(net "P5E_CPU0_P2_RX_BUF_DP<3>")
	)
	(segment
		(start 405.141684 -401.105878)
		(end 405.394922 -401.359116)
		(width 0.1016)
		(layer "F.Cu")
		(net "P5E_CPU0_P2_RX_BUF_DP<2>")
	)
	(segment
		(start 405.23033 -399.74774)
		(end 405.23033 -399.870676)
		(width 0.1016)
		(layer "F.Cu")
		(net "P5E_CPU0_P2_RX_BUF_DP<2>")
	)
	(segment
		(start 405.705564 -401.359116)
		(end 405.844248 -401.4978)
		(width 0.1016)
		(layer "F.Cu")
		(net "P5E_CPU0_P2_RX_BUF_DP<2>")
	)
	(segment
		(start 405.844248 -401.4978)
		(end 405.844248 -401.674838)
		(width 0.1016)
		(layer "F.Cu")
		(net "P5E_CPU0_P2_RX_BUF_DP<2>")
	)
	(segment
		(start 405.23033 -399.870676)
		(end 405.141684 -399.959322)
		(width 0.1016)
		(layer "F.Cu")
		(net "P5E_CPU0_P2_RX_BUF_DP<2>")
	)
	(segment
		(start 405.394922 -401.359116)
		(end 405.705564 -401.359116)
		(width 0.1016)
		(layer "F.Cu")
		(net "P5E_CPU0_P2_RX_BUF_DP<2>")
	)
	(segment
		(start 405.145748 -399.663158)
		(end 405.23033 -399.74774)
		(width 0.1016)
		(layer "F.Cu")
		(net "P5E_CPU0_P2_RX_BUF_DP<2>")
	)
	(segment
		(start 405.141684 -399.959322)
		(end 405.141684 -401.105878)
		(width 0.1016)
		(layer "F.Cu")
		(net "P5E_CPU0_P2_RX_BUF_DP<2>")
	)
	(segment
		(start 405.52751 -401.399756)
		(end 405.38527 -401.541996)
		(width 0.14224)
		(layer "In15.Cu")
		(net "P5E_CPU0_P2_RX_BUF_DP<2>")
	)
	(segment
		(start 392.28268 -407.704544)
		(end 392.206734 -407.883106)
		(width 0.14224)
		(layer "In15.Cu")
		(net "P5E_CPU0_P2_RX_BUF_DP<2>")
	)
	(segment
		(start 379.455426 -419.981126)
		(end 379.267974 -420.178738)
		(width 0.14224)
		(layer "In15.Cu")
		(net "P5E_CPU0_P2_RX_BUF_DP<2>")
	)
	(segment
		(start 395.510512 -406.552908)
		(end 395.114272 -406.71242)
		(width 0.14224)
		(layer "In15.Cu")
		(net "P5E_CPU0_P2_RX_BUF_DP<2>")
	)
	(segment
		(start 380.656592 -415.020252)
		(end 380.656592 -416.24758)
		(width 0.14224)
		(layer "In15.Cu")
		(net "P5E_CPU0_P2_RX_BUF_DP<2>")
	)
	(segment
		(start 405.844248 -401.526756)
		(end 405.717248 -401.399756)
		(width 0.14224)
		(layer "In15.Cu")
		(net "P5E_CPU0_P2_RX_BUF_DP<2>")
	)
	(segment
		(start 405.38527 -403.018752)
		(end 405.137366 -403.482556)
		(width 0.14224)
		(layer "In15.Cu")
		(net "P5E_CPU0_P2_RX_BUF_DP<2>")
	)
	(segment
		(start 393.195048 -407.33726)
		(end 392.28268 -407.704544)
		(width 0.14224)
		(layer "In15.Cu")
		(net "P5E_CPU0_P2_RX_BUF_DP<2>")
	)
	(segment
		(start 394.935964 -406.636474)
		(end 393.845796 -407.075132)
		(width 0.14224)
		(layer "In15.Cu")
		(net "P5E_CPU0_P2_RX_BUF_DP<2>")
	)
	(segment
		(start 380.196852 -419.567614)
		(end 379.941074 -419.738302)
		(width 0.14224)
		(layer "In15.Cu")
		(net "P5E_CPU0_P2_RX_BUF_DP<2>")
	)
	(segment
		(start 393.76985 -407.253948)
		(end 393.37361 -407.413206)
		(width 0.14224)
		(layer "In15.Cu")
		(net "P5E_CPU0_P2_RX_BUF_DP<2>")
	)
	(segment
		(start 383.55651 -411.3657)
		(end 383.378202 -411.289754)
		(width 0.14224)
		(layer "In15.Cu")
		(net "P5E_CPU0_P2_RX_BUF_DP<2>")
	)
	(segment
		(start 392.206734 -407.883106)
		(end 391.810494 -408.042618)
		(width 0.14224)
		(layer "In15.Cu")
		(net "P5E_CPU0_P2_RX_BUF_DP<2>")
	)
	(segment
		(start 391.810494 -408.042618)
		(end 391.632186 -407.966418)
		(width 0.14224)
		(layer "In15.Cu")
		(net "P5E_CPU0_P2_RX_BUF_DP<2>")
	)
	(segment
		(start 382.197864 -422.798494)
		(end 382.272032 -422.978072)
		(width 0.14224)
		(layer "In15.Cu")
		(net "P5E_CPU0_P2_RX_BUF_DP<2>")
	)
	(segment
		(start 384.11912 -423.806366)
		(end 384.845052 -424.565064)
		(width 0.14224)
		(layer "In15.Cu")
		(net "P5E_CPU0_P2_RX_BUF_DP<2>")
	)
	(segment
		(start 391.632186 -407.966418)
		(end 384.028696 -411.027626)
		(width 0.14224)
		(layer "In15.Cu")
		(net "P5E_CPU0_P2_RX_BUF_DP<2>")
	)
	(segment
		(start 380.793752 -416.81146)
		(end 380.656592 -416.94862)
		(width 0.14224)
		(layer "In15.Cu")
		(net "P5E_CPU0_P2_RX_BUF_DP<2>")
	)
	(segment
		(start 383.378202 -411.289754)
		(end 382.677416 -411.571694)
		(width 0.14224)
		(layer "In15.Cu")
		(net "P5E_CPU0_P2_RX_BUF_DP<2>")
	)
	(segment
		(start 397.849598 -405.617934)
		(end 396.693898 -405.928576)
		(width 0.14224)
		(layer "In15.Cu")
		(net "P5E_CPU0_P2_RX_BUF_DP<2>")
	)
	(segment
		(start 393.845796 -407.075132)
		(end 393.76985 -407.253948)
		(width 0.14224)
		(layer "In15.Cu")
		(net "P5E_CPU0_P2_RX_BUF_DP<2>")
	)
	(segment
		(start 405.38527 -401.541996)
		(end 405.38527 -403.018752)
		(width 0.14224)
		(layer "In15.Cu")
		(net "P5E_CPU0_P2_RX_BUF_DP<2>")
	)
	(segment
		(start 380.656592 -418.07638)
		(end 380.656592 -418.933122)
		(width 0.14224)
		(layer "In15.Cu")
		(net "P5E_CPU0_P2_RX_BUF_DP<2>")
	)
	(segment
		(start 380.793752 -417.93922)
		(end 380.656592 -418.07638)
		(width 0.14224)
		(layer "In15.Cu")
		(net "P5E_CPU0_P2_RX_BUF_DP<2>")
	)
	(segment
		(start 379.124972 -420.537386)
		(end 379.124972 -421.316912)
		(width 0.14224)
		(layer "In15.Cu")
		(net "P5E_CPU0_P2_RX_BUF_DP<2>")
	)
	(segment
		(start 381.523494 -414.153096)
		(end 381.247904 -414.267142)
		(width 0.14224)
		(layer "In15.Cu")
		(net "P5E_CPU0_P2_RX_BUF_DP<2>")
	)
	(segment
		(start 385.071112 -425.14139)
		(end 385.071112 -437.204104)
		(width 0.14224)
		(layer "In15.Cu")
		(net "P5E_CPU0_P2_RX_BUF_DP<2>")
	)
	(segment
		(start 405.844248 -401.674838)
		(end 405.844248 -401.526756)
		(width 0.14224)
		(layer "In15.Cu")
		(net "P5E_CPU0_P2_RX_BUF_DP<2>")
	)
	(segment
		(start 404.021544 -404.081742)
		(end 402.38553 -404.459186)
		(width 0.14224)
		(layer "In15.Cu")
		(net "P5E_CPU0_P2_RX_BUF_DP<2>")
	)
	(segment
		(start 382.568196 -411.635194)
		(end 382.389888 -411.776926)
		(width 0.14224)
		(layer "In15.Cu")
		(net "P5E_CPU0_P2_RX_BUF_DP<2>")
	)
	(segment
		(start 381.838962 -413.942276)
		(end 381.523494 -414.153096)
		(width 0.14224)
		(layer "In15.Cu")
		(net "P5E_CPU0_P2_RX_BUF_DP<2>")
	)
	(segment
		(start 380.793752 -416.38474)
		(end 380.793752 -416.81146)
		(width 0.14224)
		(layer "In15.Cu")
		(net "P5E_CPU0_P2_RX_BUF_DP<2>")
	)
	(segment
		(start 380.793752 -417.5125)
		(end 380.793752 -417.93922)
		(width 0.14224)
		(layer "In15.Cu")
		(net "P5E_CPU0_P2_RX_BUF_DP<2>")
	)
	(segment
		(start 400.776948 -404.830534)
		(end 398.527016 -405.435562)
		(width 0.14224)
		(layer "In15.Cu")
		(net "P5E_CPU0_P2_RX_BUF_DP<2>")
	)
	(segment
		(start 382.66624 -423.14114)
		(end 382.845564 -423.066972)
		(width 0.14224)
		(layer "In15.Cu")
		(net "P5E_CPU0_P2_RX_BUF_DP<2>")
	)
	(segment
		(start 385.208272 -437.341264)
		(end 385.599686 -437.341264)
		(width 0.14224)
		(layer "In15.Cu")
		(net "P5E_CPU0_P2_RX_BUF_DP<2>")
	)
	(segment
		(start 382.286256 -411.933136)
		(end 382.22174 -412.165546)
		(width 0.14224)
		(layer "In15.Cu")
		(net "P5E_CPU0_P2_RX_BUF_DP<2>")
	)
	(segment
		(start 404.327614 -403.954996)
		(end 404.021544 -404.081742)
		(width 0.14224)
		(layer "In15.Cu")
		(net "P5E_CPU0_P2_RX_BUF_DP<2>")
	)
	(segment
		(start 395.114272 -406.71242)
		(end 394.935964 -406.636474)
		(width 0.14224)
		(layer "In15.Cu")
		(net "P5E_CPU0_P2_RX_BUF_DP<2>")
	)
	(segment
		(start 380.647448 -422.304972)
		(end 381.624078 -422.70934)
		(width 0.14224)
		(layer "In15.Cu")
		(net "P5E_CPU0_P2_RX_BUF_DP<2>")
	)
	(segment
		(start 379.737112 -422.026334)
		(end 380.42088 -422.22547)
		(width 0.14224)
		(layer "In15.Cu")
		(net "P5E_CPU0_P2_RX_BUF_DP<2>")
	)
	(segment
		(start 404.842218 -403.67966)
		(end 404.327614 -403.954996)
		(width 0.14224)
		(layer "In15.Cu")
		(net "P5E_CPU0_P2_RX_BUF_DP<2>")
	)
	(segment
		(start 379.829314 -419.797992)
		(end 379.558804 -419.910006)
		(width 0.14224)
		(layer "In15.Cu")
		(net "P5E_CPU0_P2_RX_BUF_DP<2>")
	)
	(segment
		(start 385.071112 -437.204104)
		(end 385.208272 -437.341264)
		(width 0.14224)
		(layer "In15.Cu")
		(net "P5E_CPU0_P2_RX_BUF_DP<2>")
	)
	(segment
		(start 382.272032 -422.978072)
		(end 382.66624 -423.14114)
		(width 0.14224)
		(layer "In15.Cu")
		(net "P5E_CPU0_P2_RX_BUF_DP<2>")
	)
	(segment
		(start 396.693898 -405.928576)
		(end 395.586458 -406.374346)
		(width 0.14224)
		(layer "In15.Cu")
		(net "P5E_CPU0_P2_RX_BUF_DP<2>")
	)
	(segment
		(start 381.624078 -422.70934)
		(end 381.803402 -422.635172)
		(width 0.14224)
		(layer "In15.Cu")
		(net "P5E_CPU0_P2_RX_BUF_DP<2>")
	)
	(segment
		(start 382.188212 -412.410656)
		(end 382.188212 -413.306514)
		(width 0.14224)
		(layer "In15.Cu")
		(net "P5E_CPU0_P2_RX_BUF_DP<2>")
	)
	(segment
		(start 383.240026 -423.230294)
		(end 383.314194 -423.409618)
		(width 0.14224)
		(layer "In15.Cu")
		(net "P5E_CPU0_P2_RX_BUF_DP<2>")
	)
	(segment
		(start 380.656592 -416.94862)
		(end 380.656592 -417.37534)
		(width 0.14224)
		(layer "In15.Cu")
		(net "P5E_CPU0_P2_RX_BUF_DP<2>")
	)
	(segment
		(start 381.803402 -422.635172)
		(end 382.197864 -422.798494)
		(width 0.14224)
		(layer "In15.Cu")
		(net "P5E_CPU0_P2_RX_BUF_DP<2>")
	)
	(segment
		(start 385.599686 -437.341264)
		(end 385.7498 -437.19115)
		(width 0.14224)
		(layer "In15.Cu")
		(net "P5E_CPU0_P2_RX_BUF_DP<2>")
	)
	(segment
		(start 379.367288 -421.787828)
		(end 379.623828 -421.971216)
		(width 0.14224)
		(layer "In15.Cu")
		(net "P5E_CPU0_P2_RX_BUF_DP<2>")
	)
	(segment
		(start 393.37361 -407.413206)
		(end 393.195048 -407.33726)
		(width 0.14224)
		(layer "In15.Cu")
		(net "P5E_CPU0_P2_RX_BUF_DP<2>")
	)
	(segment
		(start 381.985774 -413.795464)
		(end 381.838962 -413.942276)
		(width 0.14224)
		(layer "In15.Cu")
		(net "P5E_CPU0_P2_RX_BUF_DP<2>")
	)
	(segment
		(start 405.137366 -403.482556)
		(end 404.842218 -403.67966)
		(width 0.14224)
		(layer "In15.Cu")
		(net "P5E_CPU0_P2_RX_BUF_DP<2>")
	)
	(segment
		(start 398.527016 -405.435562)
		(end 398.429988 -405.603964)
		(width 0.14224)
		(layer "In15.Cu")
		(net "P5E_CPU0_P2_RX_BUF_DP<2>")
	)
	(segment
		(start 380.656592 -417.37534)
		(end 380.793752 -417.5125)
		(width 0.14224)
		(layer "In15.Cu")
		(net "P5E_CPU0_P2_RX_BUF_DP<2>")
	)
	(segment
		(start 395.586458 -406.374346)
		(end 395.510512 -406.552908)
		(width 0.14224)
		(layer "In15.Cu")
		(net "P5E_CPU0_P2_RX_BUF_DP<2>")
	)
	(segment
		(start 405.717248 -401.399756)
		(end 405.52751 -401.399756)
		(width 0.14224)
		(layer "In15.Cu")
		(net "P5E_CPU0_P2_RX_BUF_DP<2>")
	)
	(segment
		(start 398.429988 -405.603964)
		(end 398.017746 -405.714708)
		(width 0.14224)
		(layer "In15.Cu")
		(net "P5E_CPU0_P2_RX_BUF_DP<2>")
	)
	(segment
		(start 384.028696 -411.027626)
		(end 383.95275 -411.206442)
		(width 0.14224)
		(layer "In15.Cu")
		(net "P5E_CPU0_P2_RX_BUF_DP<2>")
	)
	(segment
		(start 402.38553 -404.459186)
		(end 400.776948 -404.830534)
		(width 0.14224)
		(layer "In15.Cu")
		(net "P5E_CPU0_P2_RX_BUF_DP<2>")
	)
	(segment
		(start 383.314194 -423.409618)
		(end 383.884424 -423.645838)
		(width 0.14224)
		(layer "In15.Cu")
		(net "P5E_CPU0_P2_RX_BUF_DP<2>")
	)
	(segment
		(start 385.7498 -437.19115)
		(end 385.7498 -436.889906)
		(width 0.14224)
		(layer "In15.Cu")
		(net "P5E_CPU0_P2_RX_BUF_DP<2>")
	)
	(segment
		(start 382.845564 -423.066972)
		(end 383.240026 -423.230294)
		(width 0.14224)
		(layer "In15.Cu")
		(net "P5E_CPU0_P2_RX_BUF_DP<2>")
	)
	(segment
		(start 398.017746 -405.714708)
		(end 397.849598 -405.617934)
		(width 0.14224)
		(layer "In15.Cu")
		(net "P5E_CPU0_P2_RX_BUF_DP<2>")
	)
	(segment
		(start 380.656592 -416.24758)
		(end 380.793752 -416.38474)
		(width 0.14224)
		(layer "In15.Cu")
		(net "P5E_CPU0_P2_RX_BUF_DP<2>")
	)
	(segment
		(start 380.520956 -419.260782)
		(end 380.294642 -419.48735)
		(width 0.14224)
		(layer "In15.Cu")
		(net "P5E_CPU0_P2_RX_BUF_DP<2>")
	)
	(segment
		(start 383.95275 -411.206442)
		(end 383.55651 -411.3657)
		(width 0.14224)
		(layer "In15.Cu")
		(net "P5E_CPU0_P2_RX_BUF_DP<2>")
	)
	(arc
		(start 379.558804 -419.910006)
		(mid 379.503363 -419.940116)
		(end 379.455426 -419.981126)
		(width 0.14224)
		(layer "In15.Cu")
		(net "P5E_CPU0_P2_RX_BUF_DP<2>")
	)
	(arc
		(start 380.42088 -422.22547)
		(mid 380.535249 -422.262127)
		(end 380.647448 -422.304972)
		(width 0.14224)
		(layer "In15.Cu")
		(net "P5E_CPU0_P2_RX_BUF_DP<2>")
	)
	(arc
		(start 380.656592 -418.933122)
		(mid 380.621341 -419.110432)
		(end 380.520956 -419.260782)
		(width 0.14224)
		(layer "In15.Cu")
		(net "P5E_CPU0_P2_RX_BUF_DP<2>")
	)
	(arc
		(start 379.124972 -421.316912)
		(mid 379.189095 -421.581725)
		(end 379.367288 -421.787828)
		(width 0.14224)
		(layer "In15.Cu")
		(net "P5E_CPU0_P2_RX_BUF_DP<2>")
	)
	(arc
		(start 379.623828 -421.971216)
		(mid 379.678142 -422.003559)
		(end 379.737112 -422.026334)
		(width 0.14224)
		(layer "In15.Cu")
		(net "P5E_CPU0_P2_RX_BUF_DP<2>")
	)
	(arc
		(start 380.294642 -419.48735)
		(mid 380.247727 -419.529894)
		(end 380.196852 -419.567614)
		(width 0.14224)
		(layer "In15.Cu")
		(net "P5E_CPU0_P2_RX_BUF_DP<2>")
	)
	(arc
		(start 380.86157 -414.52546)
		(mid 380.709807 -414.752445)
		(end 380.656592 -415.020252)
		(width 0.14224)
		(layer "In15.Cu")
		(net "P5E_CPU0_P2_RX_BUF_DP<2>")
	)
	(arc
		(start 382.389888 -411.776926)
		(mid 382.32575 -411.846847)
		(end 382.286256 -411.933136)
		(width 0.14224)
		(layer "In15.Cu")
		(net "P5E_CPU0_P2_RX_BUF_DP<2>")
	)
	(arc
		(start 382.677416 -411.571694)
		(mid 382.620522 -411.599512)
		(end 382.568196 -411.635194)
		(width 0.14224)
		(layer "In15.Cu")
		(net "P5E_CPU0_P2_RX_BUF_DP<2>")
	)
	(arc
		(start 379.941074 -419.738302)
		(mid 379.886661 -419.770895)
		(end 379.829314 -419.797992)
		(width 0.14224)
		(layer "In15.Cu")
		(net "P5E_CPU0_P2_RX_BUF_DP<2>")
	)
	(arc
		(start 381.247904 -414.267142)
		(mid 381.042022 -414.377288)
		(end 380.86157 -414.52546)
		(width 0.14224)
		(layer "In15.Cu")
		(net "P5E_CPU0_P2_RX_BUF_DP<2>")
	)
	(arc
		(start 383.884424 -423.645838)
		(mid 384.010111 -423.713907)
		(end 384.11912 -423.806366)
		(width 0.14224)
		(layer "In15.Cu")
		(net "P5E_CPU0_P2_RX_BUF_DP<2>")
	)
	(arc
		(start 379.267974 -420.178738)
		(mid 379.161983 -420.344318)
		(end 379.124972 -420.537386)
		(width 0.14224)
		(layer "In15.Cu")
		(net "P5E_CPU0_P2_RX_BUF_DP<2>")
	)
	(arc
		(start 382.188212 -413.306514)
		(mid 382.135598 -413.571111)
		(end 381.985774 -413.795464)
		(width 0.14224)
		(layer "In15.Cu")
		(net "P5E_CPU0_P2_RX_BUF_DP<2>")
	)
	(arc
		(start 384.845052 -424.565064)
		(mid 385.012592 -424.831848)
		(end 385.071112 -425.14139)
		(width 0.14224)
		(layer "In15.Cu")
		(net "P5E_CPU0_P2_RX_BUF_DP<2>")
	)
	(arc
		(start 382.22174 -412.165546)
		(mid 382.196644 -412.286961)
		(end 382.188212 -412.410656)
		(width 0.14224)
		(layer "In15.Cu")
		(net "P5E_CPU0_P2_RX_BUF_DP<2>")
	)
	(segment
		(start 404.03018 -399.74774)
		(end 404.03018 -399.870676)
		(width 0.1016)
		(layer "F.Cu")
		(net "P5E_CPU0_P2_RX_BUF_DP<1>")
	)
	(segment
		(start 403.945598 -399.663158)
		(end 404.03018 -399.74774)
		(width 0.1016)
		(layer "F.Cu")
		(net "P5E_CPU0_P2_RX_BUF_DP<1>")
	)
	(segment
		(start 404.03018 -399.870676)
		(end 403.941534 -399.959322)
		(width 0.1016)
		(layer "F.Cu")
		(net "P5E_CPU0_P2_RX_BUF_DP<1>")
	)
	(segment
		(start 404.505414 -401.359116)
		(end 404.644098 -401.4978)
		(width 0.1016)
		(layer "F.Cu")
		(net "P5E_CPU0_P2_RX_BUF_DP<1>")
	)
	(segment
		(start 404.644098 -401.4978)
		(end 404.644098 -401.674838)
		(width 0.1016)
		(layer "F.Cu")
		(net "P5E_CPU0_P2_RX_BUF_DP<1>")
	)
	(segment
		(start 404.194772 -401.359116)
		(end 404.505414 -401.359116)
		(width 0.1016)
		(layer "F.Cu")
		(net "P5E_CPU0_P2_RX_BUF_DP<1>")
	)
	(segment
		(start 403.941534 -399.959322)
		(end 403.941534 -401.105878)
		(width 0.1016)
		(layer "F.Cu")
		(net "P5E_CPU0_P2_RX_BUF_DP<1>")
	)
	(segment
		(start 403.941534 -401.105878)
		(end 404.194772 -401.359116)
		(width 0.1016)
		(layer "F.Cu")
		(net "P5E_CPU0_P2_RX_BUF_DP<1>")
	)
	(segment
		(start 381.581914 -410.950918)
		(end 381.507492 -411.130242)
		(width 0.14224)
		(layer "In15.Cu")
		(net "P5E_CPU0_P2_RX_BUF_DP<1>")
	)
	(segment
		(start 383.603754 -438.337198)
		(end 383.749804 -438.191148)
		(width 0.14224)
		(layer "In15.Cu")
		(net "P5E_CPU0_P2_RX_BUF_DP<1>")
	)
	(segment
		(start 383.749804 -438.191148)
		(end 383.749804 -437.889904)
		(width 0.14224)
		(layer "In15.Cu")
		(net "P5E_CPU0_P2_RX_BUF_DP<1>")
	)
	(segment
		(start 383.071116 -425.26077)
		(end 383.071116 -438.208928)
		(width 0.14224)
		(layer "In15.Cu")
		(net "P5E_CPU0_P2_RX_BUF_DP<1>")
	)
	(segment
		(start 396.677388 -404.929594)
		(end 393.775692 -405.906986)
		(width 0.14224)
		(layer "In15.Cu")
		(net "P5E_CPU0_P2_RX_BUF_DP<1>")
	)
	(segment
		(start 377.072144 -422.358058)
		(end 377.246642 -422.273476)
		(width 0.14224)
		(layer "In15.Cu")
		(net "P5E_CPU0_P2_RX_BUF_DP<1>")
	)
	(segment
		(start 377.101862 -419.70198)
		(end 376.149362 -420.09695)
		(width 0.14224)
		(layer "In15.Cu")
		(net "P5E_CPU0_P2_RX_BUF_DP<1>")
	)
	(segment
		(start 403.932136 -403.102826)
		(end 403.801072 -403.160992)
		(width 0.14224)
		(layer "In15.Cu")
		(net "P5E_CPU0_P2_RX_BUF_DP<1>")
	)
	(segment
		(start 383.053844 -425.172632)
		(end 383.071116 -425.26077)
		(width 0.14224)
		(layer "In15.Cu")
		(net "P5E_CPU0_P2_RX_BUF_DP<1>")
	)
	(segment
		(start 377.649994 -422.413684)
		(end 377.734576 -422.58869)
		(width 0.14224)
		(layer "In15.Cu")
		(net "P5E_CPU0_P2_RX_BUF_DP<1>")
	)
	(segment
		(start 383.071116 -438.208928)
		(end 383.199386 -438.337198)
		(width 0.14224)
		(layer "In15.Cu")
		(net "P5E_CPU0_P2_RX_BUF_DP<1>")
	)
	(segment
		(start 378.922534 -413.795464)
		(end 378.775722 -413.942276)
		(width 0.14224)
		(layer "In15.Cu")
		(net "P5E_CPU0_P2_RX_BUF_DP<1>")
	)
	(segment
		(start 378.775722 -413.942276)
		(end 378.460254 -414.153096)
		(width 0.14224)
		(layer "In15.Cu")
		(net "P5E_CPU0_P2_RX_BUF_DP<1>")
	)
	(segment
		(start 381.11303 -411.29331)
		(end 380.93396 -411.219142)
		(width 0.14224)
		(layer "In15.Cu")
		(net "P5E_CPU0_P2_RX_BUF_DP<1>")
	)
	(segment
		(start 378.145294 -422.731438)
		(end 378.320046 -422.646856)
		(width 0.14224)
		(layer "In15.Cu")
		(net "P5E_CPU0_P2_RX_BUF_DP<1>")
	)
	(segment
		(start 378.320046 -422.646856)
		(end 378.723144 -422.787064)
		(width 0.14224)
		(layer "In15.Cu")
		(net "P5E_CPU0_P2_RX_BUF_DP<1>")
	)
	(segment
		(start 378.723144 -422.787064)
		(end 378.807726 -422.961816)
		(width 0.14224)
		(layer "In15.Cu")
		(net "P5E_CPU0_P2_RX_BUF_DP<1>")
	)
	(segment
		(start 404.517098 -401.399756)
		(end 404.32736 -401.399756)
		(width 0.14224)
		(layer "In15.Cu")
		(net "P5E_CPU0_P2_RX_BUF_DP<1>")
	)
	(segment
		(start 393.381484 -406.070054)
		(end 393.307062 -406.249378)
		(width 0.14224)
		(layer "In15.Cu")
		(net "P5E_CPU0_P2_RX_BUF_DP<1>")
	)
	(segment
		(start 377.734576 -422.58869)
		(end 378.145294 -422.731438)
		(width 0.14224)
		(layer "In15.Cu")
		(net "P5E_CPU0_P2_RX_BUF_DP<1>")
	)
	(segment
		(start 377.730512 -415.923222)
		(end 377.730512 -416.349942)
		(width 0.14224)
		(layer "In15.Cu")
		(net "P5E_CPU0_P2_RX_BUF_DP<1>")
	)
	(segment
		(start 392.232896 -406.693878)
		(end 391.83818 -406.8572)
		(width 0.14224)
		(layer "In15.Cu")
		(net "P5E_CPU0_P2_RX_BUF_DP<1>")
	)
	(segment
		(start 404.644098 -401.526756)
		(end 404.517098 -401.399756)
		(width 0.14224)
		(layer "In15.Cu")
		(net "P5E_CPU0_P2_RX_BUF_DP<1>")
	)
	(segment
		(start 404.18512 -402.88464)
		(end 403.932136 -403.102826)
		(width 0.14224)
		(layer "In15.Cu")
		(net "P5E_CPU0_P2_RX_BUF_DP<1>")
	)
	(segment
		(start 382.764792 -424.47591)
		(end 383.053844 -425.172632)
		(width 0.14224)
		(layer "In15.Cu")
		(net "P5E_CPU0_P2_RX_BUF_DP<1>")
	)
	(segment
		(start 404.644098 -401.674838)
		(end 404.644098 -401.526756)
		(width 0.14224)
		(layer "In15.Cu")
		(net "P5E_CPU0_P2_RX_BUF_DP<1>")
	)
	(segment
		(start 377.469654 -419.388798)
		(end 377.302268 -419.56482)
		(width 0.14224)
		(layer "In15.Cu")
		(net "P5E_CPU0_P2_RX_BUF_DP<1>")
	)
	(segment
		(start 381.029972 -423.604944)
		(end 381.441452 -423.71772)
		(width 0.14224)
		(layer "In15.Cu")
		(net "P5E_CPU0_P2_RX_BUF_DP<1>")
	)
	(segment
		(start 392.307318 -406.514554)
		(end 392.232896 -406.693878)
		(width 0.14224)
		(layer "In15.Cu")
		(net "P5E_CPU0_P2_RX_BUF_DP<1>")
	)
	(segment
		(start 376.593354 -422.191434)
		(end 377.072144 -422.358058)
		(width 0.14224)
		(layer "In15.Cu")
		(net "P5E_CPU0_P2_RX_BUF_DP<1>")
	)
	(segment
		(start 380.93396 -423.436288)
		(end 381.029972 -423.604944)
		(width 0.14224)
		(layer "In15.Cu")
		(net "P5E_CPU0_P2_RX_BUF_DP<1>")
	)
	(segment
		(start 379.124972 -412.371286)
		(end 379.124972 -413.306514)
		(width 0.14224)
		(layer "In15.Cu")
		(net "P5E_CPU0_P2_RX_BUF_DP<1>")
	)
	(segment
		(start 403.801072 -403.160992)
		(end 399.447004 -404.150576)
		(width 0.14224)
		(layer "In15.Cu")
		(net "P5E_CPU0_P2_RX_BUF_DP<1>")
	)
	(segment
		(start 380.522226 -423.323258)
		(end 380.93396 -423.436288)
		(width 0.14224)
		(layer "In15.Cu")
		(net "P5E_CPU0_P2_RX_BUF_DP<1>")
	)
	(segment
		(start 377.593352 -416.983418)
		(end 377.730512 -417.120578)
		(width 0.14224)
		(layer "In15.Cu")
		(net "P5E_CPU0_P2_RX_BUF_DP<1>")
	)
	(segment
		(start 382.632712 -424.278044)
		(end 382.764792 -424.47591)
		(width 0.14224)
		(layer "In15.Cu")
		(net "P5E_CPU0_P2_RX_BUF_DP<1>")
	)
	(segment
		(start 377.730512 -417.120578)
		(end 377.730512 -417.547298)
		(width 0.14224)
		(layer "In15.Cu")
		(net "P5E_CPU0_P2_RX_BUF_DP<1>")
	)
	(segment
		(start 393.307062 -406.249378)
		(end 392.9126 -406.412446)
		(width 0.14224)
		(layer "In15.Cu")
		(net "P5E_CPU0_P2_RX_BUF_DP<1>")
	)
	(segment
		(start 378.460254 -414.153096)
		(end 378.184664 -414.267142)
		(width 0.14224)
		(layer "In15.Cu")
		(net "P5E_CPU0_P2_RX_BUF_DP<1>")
	)
	(segment
		(start 383.199386 -438.337198)
		(end 383.603754 -438.337198)
		(width 0.14224)
		(layer "In15.Cu")
		(net "P5E_CPU0_P2_RX_BUF_DP<1>")
	)
	(segment
		(start 381.595376 -423.770552)
		(end 382.449578 -424.127422)
		(width 0.14224)
		(layer "In15.Cu")
		(net "P5E_CPU0_P2_RX_BUF_DP<1>")
	)
	(segment
		(start 377.593352 -415.020252)
		(end 377.593352 -415.786062)
		(width 0.14224)
		(layer "In15.Cu")
		(net "P5E_CPU0_P2_RX_BUF_DP<1>")
	)
	(segment
		(start 392.73353 -406.338278)
		(end 392.307318 -406.514554)
		(width 0.14224)
		(layer "In15.Cu")
		(net "P5E_CPU0_P2_RX_BUF_DP<1>")
	)
	(segment
		(start 404.32736 -401.399756)
		(end 404.18512 -401.541996)
		(width 0.14224)
		(layer "In15.Cu")
		(net "P5E_CPU0_P2_RX_BUF_DP<1>")
	)
	(segment
		(start 381.507492 -411.130242)
		(end 381.11303 -411.29331)
		(width 0.14224)
		(layer "In15.Cu")
		(net "P5E_CPU0_P2_RX_BUF_DP<1>")
	)
	(segment
		(start 376.061732 -420.228014)
		(end 376.061732 -421.327326)
		(width 0.14224)
		(layer "In15.Cu")
		(net "P5E_CPU0_P2_RX_BUF_DP<1>")
	)
	(segment
		(start 377.246642 -422.273476)
		(end 377.649994 -422.413684)
		(width 0.14224)
		(layer "In15.Cu")
		(net "P5E_CPU0_P2_RX_BUF_DP<1>")
	)
	(segment
		(start 379.312932 -423.134028)
		(end 380.353824 -423.41927)
		(width 0.14224)
		(layer "In15.Cu")
		(net "P5E_CPU0_P2_RX_BUF_DP<1>")
	)
	(segment
		(start 377.730512 -416.349942)
		(end 377.593352 -416.487102)
		(width 0.14224)
		(layer "In15.Cu")
		(net "P5E_CPU0_P2_RX_BUF_DP<1>")
	)
	(segment
		(start 377.593352 -415.786062)
		(end 377.730512 -415.923222)
		(width 0.14224)
		(layer "In15.Cu")
		(net "P5E_CPU0_P2_RX_BUF_DP<1>")
	)
	(segment
		(start 392.9126 -406.412446)
		(end 392.73353 -406.338278)
		(width 0.14224)
		(layer "In15.Cu")
		(net "P5E_CPU0_P2_RX_BUF_DP<1>")
	)
	(segment
		(start 380.93396 -411.219142)
		(end 379.498352 -411.81274)
		(width 0.14224)
		(layer "In15.Cu")
		(net "P5E_CPU0_P2_RX_BUF_DP<1>")
	)
	(segment
		(start 378.807726 -422.961816)
		(end 379.21057 -423.102024)
		(width 0.14224)
		(layer "In15.Cu")
		(net "P5E_CPU0_P2_RX_BUF_DP<1>")
	)
	(segment
		(start 393.775692 -405.906986)
		(end 393.381484 -406.070054)
		(width 0.14224)
		(layer "In15.Cu")
		(net "P5E_CPU0_P2_RX_BUF_DP<1>")
	)
	(segment
		(start 399.447004 -404.150576)
		(end 396.677388 -404.929594)
		(width 0.14224)
		(layer "In15.Cu")
		(net "P5E_CPU0_P2_RX_BUF_DP<1>")
	)
	(segment
		(start 380.353824 -423.41927)
		(end 380.522226 -423.323258)
		(width 0.14224)
		(layer "In15.Cu")
		(net "P5E_CPU0_P2_RX_BUF_DP<1>")
	)
	(segment
		(start 391.65911 -406.782778)
		(end 381.581914 -410.950918)
		(width 0.14224)
		(layer "In15.Cu")
		(net "P5E_CPU0_P2_RX_BUF_DP<1>")
	)
	(segment
		(start 377.593352 -417.684458)
		(end 377.593352 -419.079172)
		(width 0.14224)
		(layer "In15.Cu")
		(net "P5E_CPU0_P2_RX_BUF_DP<1>")
	)
	(segment
		(start 377.730512 -417.547298)
		(end 377.593352 -417.684458)
		(width 0.14224)
		(layer "In15.Cu")
		(net "P5E_CPU0_P2_RX_BUF_DP<1>")
	)
	(segment
		(start 377.593352 -416.487102)
		(end 377.593352 -416.983418)
		(width 0.14224)
		(layer "In15.Cu")
		(net "P5E_CPU0_P2_RX_BUF_DP<1>")
	)
	(segment
		(start 391.83818 -406.8572)
		(end 391.65911 -406.782778)
		(width 0.14224)
		(layer "In15.Cu")
		(net "P5E_CPU0_P2_RX_BUF_DP<1>")
	)
	(segment
		(start 404.18512 -401.541996)
		(end 404.18512 -402.88464)
		(width 0.14224)
		(layer "In15.Cu")
		(net "P5E_CPU0_P2_RX_BUF_DP<1>")
	)
	(arc
		(start 381.441452 -423.71772)
		(mid 381.519261 -423.74167)
		(end 381.595376 -423.770552)
		(width 0.14224)
		(layer "In15.Cu")
		(net "P5E_CPU0_P2_RX_BUF_DP<1>")
	)
	(arc
		(start 377.302268 -419.56482)
		(mid 377.20925 -419.643897)
		(end 377.101862 -419.70198)
		(width 0.14224)
		(layer "In15.Cu")
		(net "P5E_CPU0_P2_RX_BUF_DP<1>")
	)
	(arc
		(start 377.593352 -419.079172)
		(mid 377.561387 -419.24593)
		(end 377.469654 -419.388798)
		(width 0.14224)
		(layer "In15.Cu")
		(net "P5E_CPU0_P2_RX_BUF_DP<1>")
	)
	(arc
		(start 377.79833 -414.52546)
		(mid 377.646567 -414.752445)
		(end 377.593352 -415.020252)
		(width 0.14224)
		(layer "In15.Cu")
		(net "P5E_CPU0_P2_RX_BUF_DP<1>")
	)
	(arc
		(start 379.124972 -413.306514)
		(mid 379.072358 -413.571111)
		(end 378.922534 -413.795464)
		(width 0.14224)
		(layer "In15.Cu")
		(net "P5E_CPU0_P2_RX_BUF_DP<1>")
	)
	(arc
		(start 378.184664 -414.267142)
		(mid 377.978782 -414.377288)
		(end 377.79833 -414.52546)
		(width 0.14224)
		(layer "In15.Cu")
		(net "P5E_CPU0_P2_RX_BUF_DP<1>")
	)
	(arc
		(start 376.484134 -422.126918)
		(mid 376.535495 -422.16468)
		(end 376.593354 -422.191434)
		(width 0.14224)
		(layer "In15.Cu")
		(net "P5E_CPU0_P2_RX_BUF_DP<1>")
	)
	(arc
		(start 382.449578 -424.127422)
		(mid 382.552281 -424.189189)
		(end 382.632712 -424.278044)
		(width 0.14224)
		(layer "In15.Cu")
		(net "P5E_CPU0_P2_RX_BUF_DP<1>")
	)
	(arc
		(start 376.149362 -420.09695)
		(mid 376.085617 -420.149167)
		(end 376.061732 -420.228014)
		(width 0.14224)
		(layer "In15.Cu")
		(net "P5E_CPU0_P2_RX_BUF_DP<1>")
	)
	(arc
		(start 379.21057 -423.102024)
		(mid 379.261483 -423.118885)
		(end 379.312932 -423.134028)
		(width 0.14224)
		(layer "In15.Cu")
		(net "P5E_CPU0_P2_RX_BUF_DP<1>")
	)
	(arc
		(start 376.26925 -421.902382)
		(mid 376.372648 -422.01852)
		(end 376.484134 -422.126918)
		(width 0.14224)
		(layer "In15.Cu")
		(net "P5E_CPU0_P2_RX_BUF_DP<1>")
	)
	(arc
		(start 376.061732 -421.327326)
		(mid 376.115191 -421.633009)
		(end 376.26925 -421.902382)
		(width 0.14224)
		(layer "In15.Cu")
		(net "P5E_CPU0_P2_RX_BUF_DP<1>")
	)
	(arc
		(start 379.498352 -411.81274)
		(mid 379.226939 -412.03537)
		(end 379.124972 -412.371286)
		(width 0.14224)
		(layer "In15.Cu")
		(net "P5E_CPU0_P2_RX_BUF_DP<1>")
	)
	(segment
		(start 420.745666 -399.663158)
		(end 420.830248 -399.74774)
		(width 0.1016)
		(layer "F.Cu")
		(net "P5E_CPU0_P2_RX_BUF_DP<15>")
	)
	(segment
		(start 421.444166 -401.51431)
		(end 421.444166 -401.674838)
		(width 0.1016)
		(layer "F.Cu")
		(net "P5E_CPU0_P2_RX_BUF_DP<15>")
	)
	(segment
		(start 420.741602 -399.959322)
		(end 420.741602 -401.105878)
		(width 0.1016)
		(layer "F.Cu")
		(net "P5E_CPU0_P2_RX_BUF_DP<15>")
	)
	(segment
		(start 420.99484 -401.359116)
		(end 421.288972 -401.359116)
		(width 0.1016)
		(layer "F.Cu")
		(net "P5E_CPU0_P2_RX_BUF_DP<15>")
	)
	(segment
		(start 420.830248 -399.870676)
		(end 420.741602 -399.959322)
		(width 0.1016)
		(layer "F.Cu")
		(net "P5E_CPU0_P2_RX_BUF_DP<15>")
	)
	(segment
		(start 420.830248 -399.74774)
		(end 420.830248 -399.870676)
		(width 0.1016)
		(layer "F.Cu")
		(net "P5E_CPU0_P2_RX_BUF_DP<15>")
	)
	(segment
		(start 420.741602 -401.105878)
		(end 420.99484 -401.359116)
		(width 0.1016)
		(layer "F.Cu")
		(net "P5E_CPU0_P2_RX_BUF_DP<15>")
	)
	(segment
		(start 421.288972 -401.359116)
		(end 421.444166 -401.51431)
		(width 0.1016)
		(layer "F.Cu")
		(net "P5E_CPU0_P2_RX_BUF_DP<15>")
	)
	(segment
		(start 419.407848 -420.961566)
		(end 419.438582 -421.153082)
		(width 0.14224)
		(layer "In15.Cu")
		(net "P5E_CPU0_P2_RX_BUF_DP<15>")
	)
	(segment
		(start 412.071058 -438.203848)
		(end 412.208472 -438.341262)
		(width 0.14224)
		(layer "In15.Cu")
		(net "P5E_CPU0_P2_RX_BUF_DP<15>")
	)
	(segment
		(start 421.444166 -401.526756)
		(end 421.317166 -401.399756)
		(width 0.14224)
		(layer "In15.Cu")
		(net "P5E_CPU0_P2_RX_BUF_DP<15>")
	)
	(segment
		(start 421.122348 -416.628834)
		(end 421.122348 -417.055554)
		(width 0.14224)
		(layer "In15.Cu")
		(net "P5E_CPU0_P2_RX_BUF_DP<15>")
	)
	(segment
		(start 414.868614 -423.491152)
		(end 414.463484 -423.624756)
		(width 0.14224)
		(layer "In15.Cu")
		(net "P5E_CPU0_P2_RX_BUF_DP<15>")
	)
	(segment
		(start 421.122348 -415.927794)
		(end 420.985188 -416.064954)
		(width 0.14224)
		(layer "In15.Cu")
		(net "P5E_CPU0_P2_RX_BUF_DP<15>")
	)
	(segment
		(start 418.996876 -421.529764)
		(end 418.74694 -421.875458)
		(width 0.14224)
		(layer "In15.Cu")
		(net "P5E_CPU0_P2_RX_BUF_DP<15>")
	)
	(segment
		(start 420.985188 -414.236154)
		(end 421.122348 -414.373314)
		(width 0.14224)
		(layer "In15.Cu")
		(net "P5E_CPU0_P2_RX_BUF_DP<15>")
	)
	(segment
		(start 420.473632 -419.365938)
		(end 420.300912 -419.756336)
		(width 0.14224)
		(layer "In15.Cu")
		(net "P5E_CPU0_P2_RX_BUF_DP<15>")
	)
	(segment
		(start 420.985188 -416.064954)
		(end 420.985188 -416.491674)
		(width 0.14224)
		(layer "In15.Cu")
		(net "P5E_CPU0_P2_RX_BUF_DP<15>")
	)
	(segment
		(start 420.985188 -416.491674)
		(end 421.122348 -416.628834)
		(width 0.14224)
		(layer "In15.Cu")
		(net "P5E_CPU0_P2_RX_BUF_DP<15>")
	)
	(segment
		(start 412.636208 -424.082972)
		(end 412.342076 -424.204892)
		(width 0.14224)
		(layer "In15.Cu")
		(net "P5E_CPU0_P2_RX_BUF_DP<15>")
	)
	(segment
		(start 415.041842 -423.578274)
		(end 414.868614 -423.491152)
		(width 0.14224)
		(layer "In15.Cu")
		(net "P5E_CPU0_P2_RX_BUF_DP<15>")
	)
	(segment
		(start 420.985188 -401.541996)
		(end 420.985188 -413.108394)
		(width 0.14224)
		(layer "In15.Cu")
		(net "P5E_CPU0_P2_RX_BUF_DP<15>")
	)
	(segment
		(start 421.122348 -417.055554)
		(end 420.985188 -417.192714)
		(width 0.14224)
		(layer "In15.Cu")
		(net "P5E_CPU0_P2_RX_BUF_DP<15>")
	)
	(segment
		(start 413.630618 -423.975276)
		(end 413.216344 -424.078908)
		(width 0.14224)
		(layer "In15.Cu")
		(net "P5E_CPU0_P2_RX_BUF_DP<15>")
	)
	(segment
		(start 419.946836 -420.216076)
		(end 419.407848 -420.961566)
		(width 0.14224)
		(layer "In15.Cu")
		(net "P5E_CPU0_P2_RX_BUF_DP<15>")
	)
	(segment
		(start 419.438582 -421.153082)
		(end 419.188392 -421.49903)
		(width 0.14224)
		(layer "In15.Cu")
		(net "P5E_CPU0_P2_RX_BUF_DP<15>")
	)
	(segment
		(start 413.216344 -424.078908)
		(end 413.049974 -423.97934)
		(width 0.14224)
		(layer "In15.Cu")
		(net "P5E_CPU0_P2_RX_BUF_DP<15>")
	)
	(segment
		(start 421.444166 -401.674838)
		(end 421.444166 -401.526756)
		(width 0.14224)
		(layer "In15.Cu")
		(net "P5E_CPU0_P2_RX_BUF_DP<15>")
	)
	(segment
		(start 416.11296 -423.224452)
		(end 415.939732 -423.13733)
		(width 0.14224)
		(layer "In15.Cu")
		(net "P5E_CPU0_P2_RX_BUF_DP<15>")
	)
	(segment
		(start 412.208472 -438.341262)
		(end 412.599886 -438.341262)
		(width 0.14224)
		(layer "In15.Cu")
		(net "P5E_CPU0_P2_RX_BUF_DP<15>")
	)
	(segment
		(start 419.188392 -421.49903)
		(end 418.996876 -421.529764)
		(width 0.14224)
		(layer "In15.Cu")
		(net "P5E_CPU0_P2_RX_BUF_DP<15>")
	)
	(segment
		(start 412.75 -438.191148)
		(end 412.75 -437.889904)
		(width 0.14224)
		(layer "In15.Cu")
		(net "P5E_CPU0_P2_RX_BUF_DP<15>")
	)
	(segment
		(start 418.74694 -421.875458)
		(end 418.267388 -422.269158)
		(width 0.14224)
		(layer "In15.Cu")
		(net "P5E_CPU0_P2_RX_BUF_DP<15>")
	)
	(segment
		(start 420.985188 -415.363914)
		(end 421.122348 -415.501074)
		(width 0.14224)
		(layer "In15.Cu")
		(net "P5E_CPU0_P2_RX_BUF_DP<15>")
	)
	(segment
		(start 421.122348 -413.245554)
		(end 421.122348 -413.672274)
		(width 0.14224)
		(layer "In15.Cu")
		(net "P5E_CPU0_P2_RX_BUF_DP<15>")
	)
	(segment
		(start 421.122348 -413.672274)
		(end 420.985188 -413.809434)
		(width 0.14224)
		(layer "In15.Cu")
		(net "P5E_CPU0_P2_RX_BUF_DP<15>")
	)
	(segment
		(start 420.985188 -413.809434)
		(end 420.985188 -414.236154)
		(width 0.14224)
		(layer "In15.Cu")
		(net "P5E_CPU0_P2_RX_BUF_DP<15>")
	)
	(segment
		(start 421.122348 -414.373314)
		(end 421.122348 -414.800034)
		(width 0.14224)
		(layer "In15.Cu")
		(net "P5E_CPU0_P2_RX_BUF_DP<15>")
	)
	(segment
		(start 420.985188 -417.192714)
		(end 420.985188 -417.619434)
		(width 0.14224)
		(layer "In15.Cu")
		(net "P5E_CPU0_P2_RX_BUF_DP<15>")
	)
	(segment
		(start 416.518344 -423.090848)
		(end 416.11296 -423.224452)
		(width 0.14224)
		(layer "In15.Cu")
		(net "P5E_CPU0_P2_RX_BUF_DP<15>")
	)
	(segment
		(start 412.342076 -424.204892)
		(end 412.10865 -424.438318)
		(width 0.14224)
		(layer "In15.Cu")
		(net "P5E_CPU0_P2_RX_BUF_DP<15>")
	)
	(segment
		(start 420.403782 -419.184836)
		(end 420.473632 -419.365938)
		(width 0.14224)
		(layer "In15.Cu")
		(net "P5E_CPU0_P2_RX_BUF_DP<15>")
	)
	(segment
		(start 414.463484 -423.624756)
		(end 413.730186 -423.808652)
		(width 0.14224)
		(layer "In15.Cu")
		(net "P5E_CPU0_P2_RX_BUF_DP<15>")
	)
	(segment
		(start 415.939732 -423.13733)
		(end 415.534602 -423.270934)
		(width 0.14224)
		(layer "In15.Cu")
		(net "P5E_CPU0_P2_RX_BUF_DP<15>")
	)
	(segment
		(start 413.730186 -423.808652)
		(end 413.630618 -423.975276)
		(width 0.14224)
		(layer "In15.Cu")
		(net "P5E_CPU0_P2_RX_BUF_DP<15>")
	)
	(segment
		(start 420.119556 -419.826186)
		(end 419.946836 -420.216076)
		(width 0.14224)
		(layer "In15.Cu")
		(net "P5E_CPU0_P2_RX_BUF_DP<15>")
	)
	(segment
		(start 421.127428 -401.399756)
		(end 420.985188 -401.541996)
		(width 0.14224)
		(layer "In15.Cu")
		(net "P5E_CPU0_P2_RX_BUF_DP<15>")
	)
	(segment
		(start 420.985188 -413.108394)
		(end 421.122348 -413.245554)
		(width 0.14224)
		(layer "In15.Cu")
		(net "P5E_CPU0_P2_RX_BUF_DP<15>")
	)
	(segment
		(start 421.317166 -401.399756)
		(end 421.127428 -401.399756)
		(width 0.14224)
		(layer "In15.Cu")
		(net "P5E_CPU0_P2_RX_BUF_DP<15>")
	)
	(segment
		(start 412.071058 -424.528742)
		(end 412.071058 -438.203848)
		(width 0.14224)
		(layer "In15.Cu")
		(net "P5E_CPU0_P2_RX_BUF_DP<15>")
	)
	(segment
		(start 421.122348 -415.501074)
		(end 421.122348 -415.927794)
		(width 0.14224)
		(layer "In15.Cu")
		(net "P5E_CPU0_P2_RX_BUF_DP<15>")
	)
	(segment
		(start 415.534602 -423.270934)
		(end 415.447226 -423.444416)
		(width 0.14224)
		(layer "In15.Cu")
		(net "P5E_CPU0_P2_RX_BUF_DP<15>")
	)
	(segment
		(start 420.882318 -418.105082)
		(end 420.403782 -419.184836)
		(width 0.14224)
		(layer "In15.Cu")
		(net "P5E_CPU0_P2_RX_BUF_DP<15>")
	)
	(segment
		(start 421.122348 -414.800034)
		(end 420.985188 -414.937194)
		(width 0.14224)
		(layer "In15.Cu")
		(net "P5E_CPU0_P2_RX_BUF_DP<15>")
	)
	(segment
		(start 420.985188 -417.619434)
		(end 420.882318 -418.105082)
		(width 0.14224)
		(layer "In15.Cu")
		(net "P5E_CPU0_P2_RX_BUF_DP<15>")
	)
	(segment
		(start 412.599886 -438.341262)
		(end 412.75 -438.191148)
		(width 0.14224)
		(layer "In15.Cu")
		(net "P5E_CPU0_P2_RX_BUF_DP<15>")
	)
	(segment
		(start 413.049974 -423.97934)
		(end 412.636208 -424.082972)
		(width 0.14224)
		(layer "In15.Cu")
		(net "P5E_CPU0_P2_RX_BUF_DP<15>")
	)
	(segment
		(start 420.300912 -419.756336)
		(end 420.119556 -419.826186)
		(width 0.14224)
		(layer "In15.Cu")
		(net "P5E_CPU0_P2_RX_BUF_DP<15>")
	)
	(segment
		(start 417.81476 -422.518078)
		(end 416.60572 -422.917112)
		(width 0.14224)
		(layer "In15.Cu")
		(net "P5E_CPU0_P2_RX_BUF_DP<15>")
	)
	(segment
		(start 415.447226 -423.444416)
		(end 415.041842 -423.578274)
		(width 0.14224)
		(layer "In15.Cu")
		(net "P5E_CPU0_P2_RX_BUF_DP<15>")
	)
	(segment
		(start 420.985188 -414.937194)
		(end 420.985188 -415.363914)
		(width 0.14224)
		(layer "In15.Cu")
		(net "P5E_CPU0_P2_RX_BUF_DP<15>")
	)
	(segment
		(start 416.60572 -422.917112)
		(end 416.518344 -423.090848)
		(width 0.14224)
		(layer "In15.Cu")
		(net "P5E_CPU0_P2_RX_BUF_DP<15>")
	)
	(arc
		(start 418.267388 -422.269158)
		(mid 418.052535 -422.414455)
		(end 417.81476 -422.518078)
		(width 0.14224)
		(layer "In15.Cu")
		(net "P5E_CPU0_P2_RX_BUF_DP<15>")
	)
	(arc
		(start 412.10865 -424.438318)
		(mid 412.080876 -424.479791)
		(end 412.071058 -424.528742)
		(width 0.14224)
		(layer "In15.Cu")
		(net "P5E_CPU0_P2_RX_BUF_DP<15>")
	)
	(segment
		(start 419.54577 -399.663158)
		(end 419.630352 -399.74774)
		(width 0.1016)
		(layer "F.Cu")
		(net "P5E_CPU0_P2_RX_BUF_DP<14>")
	)
	(segment
		(start 420.087552 -401.359116)
		(end 420.24427 -401.515834)
		(width 0.1016)
		(layer "F.Cu")
		(net "P5E_CPU0_P2_RX_BUF_DP<14>")
	)
	(segment
		(start 420.24427 -401.515834)
		(end 420.24427 -401.674838)
		(width 0.1016)
		(layer "F.Cu")
		(net "P5E_CPU0_P2_RX_BUF_DP<14>")
	)
	(segment
		(start 419.794944 -401.359116)
		(end 420.087552 -401.359116)
		(width 0.1016)
		(layer "F.Cu")
		(net "P5E_CPU0_P2_RX_BUF_DP<14>")
	)
	(segment
		(start 419.541706 -401.105878)
		(end 419.794944 -401.359116)
		(width 0.1016)
		(layer "F.Cu")
		(net "P5E_CPU0_P2_RX_BUF_DP<14>")
	)
	(segment
		(start 419.630352 -399.870676)
		(end 419.541706 -399.959322)
		(width 0.1016)
		(layer "F.Cu")
		(net "P5E_CPU0_P2_RX_BUF_DP<14>")
	)
	(segment
		(start 419.541706 -399.959322)
		(end 419.541706 -401.105878)
		(width 0.1016)
		(layer "F.Cu")
		(net "P5E_CPU0_P2_RX_BUF_DP<14>")
	)
	(segment
		(start 419.630352 -399.74774)
		(end 419.630352 -399.870676)
		(width 0.1016)
		(layer "F.Cu")
		(net "P5E_CPU0_P2_RX_BUF_DP<14>")
	)
	(segment
		(start 419.238938 -411.75305)
		(end 419.088824 -411.87624)
		(width 0.14224)
		(layer "In15.Cu")
		(net "P5E_CPU0_P2_RX_BUF_DP<14>")
	)
	(segment
		(start 419.700456 -405.663146)
		(end 419.620192 -406.479502)
		(width 0.14224)
		(layer "In15.Cu")
		(net "P5E_CPU0_P2_RX_BUF_DP<14>")
	)
	(segment
		(start 417.415472 -416.70732)
		(end 417.415472 -417.13404)
		(width 0.14224)
		(layer "In15.Cu")
		(net "P5E_CPU0_P2_RX_BUF_DP<14>")
	)
	(segment
		(start 419.309804 -409.631388)
		(end 419.268148 -410.055822)
		(width 0.14224)
		(layer "In15.Cu")
		(net "P5E_CPU0_P2_RX_BUF_DP<14>")
	)
	(segment
		(start 419.157658 -411.178248)
		(end 419.280848 -411.328108)
		(width 0.14224)
		(layer "In15.Cu")
		(net "P5E_CPU0_P2_RX_BUF_DP<14>")
	)
	(segment
		(start 415.242502 -422.287954)
		(end 414.477962 -422.499536)
		(width 0.14224)
		(layer "In15.Cu")
		(net "P5E_CPU0_P2_RX_BUF_DP<14>")
	)
	(segment
		(start 415.883852 -420.228014)
		(end 415.883852 -421.583104)
		(width 0.14224)
		(layer "In15.Cu")
		(net "P5E_CPU0_P2_RX_BUF_DP<14>")
	)
	(segment
		(start 419.701472 -407.054304)
		(end 419.551358 -407.177494)
		(width 0.14224)
		(layer "In15.Cu")
		(net "P5E_CPU0_P2_RX_BUF_DP<14>")
	)
	(segment
		(start 414.382458 -422.6687)
		(end 413.970978 -422.782492)
		(width 0.14224)
		(layer "In15.Cu")
		(net "P5E_CPU0_P2_RX_BUF_DP<14>")
	)
	(segment
		(start 418.573966 -413.97428)
		(end 417.649914 -414.48609)
		(width 0.14224)
		(layer "In15.Cu")
		(net "P5E_CPU0_P2_RX_BUF_DP<14>")
	)
	(segment
		(start 419.268148 -410.055822)
		(end 419.391338 -410.205682)
		(width 0.14224)
		(layer "In15.Cu")
		(net "P5E_CPU0_P2_RX_BUF_DP<14>")
	)
	(segment
		(start 419.612318 -407.96083)
		(end 419.570408 -408.385772)
		(width 0.14224)
		(layer "In15.Cu")
		(net "P5E_CPU0_P2_RX_BUF_DP<14>")
	)
	(segment
		(start 413.077152 -422.887648)
		(end 411.041342 -423.730928)
		(width 0.14224)
		(layer "In15.Cu")
		(net "P5E_CPU0_P2_RX_BUF_DP<14>")
	)
	(segment
		(start 419.047168 -412.300674)
		(end 419.170104 -412.450534)
		(width 0.14224)
		(layer "In15.Cu")
		(net "P5E_CPU0_P2_RX_BUF_DP<14>")
	)
	(segment
		(start 414.477962 -422.499536)
		(end 414.382458 -422.6687)
		(width 0.14224)
		(layer "In15.Cu")
		(net "P5E_CPU0_P2_RX_BUF_DP<14>")
	)
	(segment
		(start 419.170104 -412.450534)
		(end 419.128194 -412.875476)
		(width 0.14224)
		(layer "In15.Cu")
		(net "P5E_CPU0_P2_RX_BUF_DP<14>")
	)
	(segment
		(start 418.97808 -412.998666)
		(end 418.936424 -413.4231)
		(width 0.14224)
		(layer "In15.Cu")
		(net "P5E_CPU0_P2_RX_BUF_DP<14>")
	)
	(segment
		(start 417.415472 -417.83508)
		(end 417.415472 -419.079172)
		(width 0.14224)
		(layer "In15.Cu")
		(net "P5E_CPU0_P2_RX_BUF_DP<14>")
	)
	(segment
		(start 419.459918 -409.508198)
		(end 419.309804 -409.631388)
		(width 0.14224)
		(layer "In15.Cu")
		(net "P5E_CPU0_P2_RX_BUF_DP<14>")
	)
	(segment
		(start 417.552632 -417.2712)
		(end 417.552632 -417.69792)
		(width 0.14224)
		(layer "In15.Cu")
		(net "P5E_CPU0_P2_RX_BUF_DP<14>")
	)
	(segment
		(start 410.750004 -437.19115)
		(end 410.750004 -436.889906)
		(width 0.14224)
		(layer "In15.Cu")
		(net "P5E_CPU0_P2_RX_BUF_DP<14>")
	)
	(segment
		(start 419.620192 -406.479502)
		(end 419.743382 -406.629362)
		(width 0.14224)
		(layer "In15.Cu")
		(net "P5E_CPU0_P2_RX_BUF_DP<14>")
	)
	(segment
		(start 415.496502 -422.139872)
		(end 415.242502 -422.287954)
		(width 0.14224)
		(layer "In15.Cu")
		(net "P5E_CPU0_P2_RX_BUF_DP<14>")
	)
	(segment
		(start 410.071062 -437.20385)
		(end 410.208476 -437.341264)
		(width 0.14224)
		(layer "In15.Cu")
		(net "P5E_CPU0_P2_RX_BUF_DP<14>")
	)
	(segment
		(start 419.088824 -411.87624)
		(end 419.047168 -412.300674)
		(width 0.14224)
		(layer "In15.Cu")
		(net "P5E_CPU0_P2_RX_BUF_DP<14>")
	)
	(segment
		(start 417.415472 -417.13404)
		(end 417.552632 -417.2712)
		(width 0.14224)
		(layer "In15.Cu")
		(net "P5E_CPU0_P2_RX_BUF_DP<14>")
	)
	(segment
		(start 419.551358 -407.177494)
		(end 419.489128 -407.81097)
		(width 0.14224)
		(layer "In15.Cu")
		(net "P5E_CPU0_P2_RX_BUF_DP<14>")
	)
	(segment
		(start 417.415472 -415.019744)
		(end 417.415472 -416.00628)
		(width 0.14224)
		(layer "In15.Cu")
		(net "P5E_CPU0_P2_RX_BUF_DP<14>")
	)
	(segment
		(start 419.489128 -407.81097)
		(end 419.612318 -407.96083)
		(width 0.14224)
		(layer "In15.Cu")
		(net "P5E_CPU0_P2_RX_BUF_DP<14>")
	)
	(segment
		(start 419.570408 -408.385772)
		(end 419.420294 -408.508962)
		(width 0.14224)
		(layer "In15.Cu")
		(net "P5E_CPU0_P2_RX_BUF_DP<14>")
	)
	(segment
		(start 419.349428 -410.630624)
		(end 419.199314 -410.753814)
		(width 0.14224)
		(layer "In15.Cu")
		(net "P5E_CPU0_P2_RX_BUF_DP<14>")
	)
	(segment
		(start 419.743382 -406.629362)
		(end 419.701472 -407.054304)
		(width 0.14224)
		(layer "In15.Cu")
		(net "P5E_CPU0_P2_RX_BUF_DP<14>")
	)
	(segment
		(start 410.59989 -437.341264)
		(end 410.750004 -437.19115)
		(width 0.14224)
		(layer "In15.Cu")
		(net "P5E_CPU0_P2_RX_BUF_DP<14>")
	)
	(segment
		(start 419.199314 -410.753814)
		(end 419.157658 -411.178248)
		(width 0.14224)
		(layer "In15.Cu")
		(net "P5E_CPU0_P2_RX_BUF_DP<14>")
	)
	(segment
		(start 419.280848 -411.328108)
		(end 419.238938 -411.75305)
		(width 0.14224)
		(layer "In15.Cu")
		(net "P5E_CPU0_P2_RX_BUF_DP<14>")
	)
	(segment
		(start 419.378638 -408.933396)
		(end 419.501828 -409.083256)
		(width 0.14224)
		(layer "In15.Cu")
		(net "P5E_CPU0_P2_RX_BUF_DP<14>")
	)
	(segment
		(start 417.552632 -416.14344)
		(end 417.552632 -416.57016)
		(width 0.14224)
		(layer "In15.Cu")
		(net "P5E_CPU0_P2_RX_BUF_DP<14>")
	)
	(segment
		(start 419.785292 -401.541996)
		(end 419.785292 -403.935946)
		(width 0.14224)
		(layer "In15.Cu")
		(net "P5E_CPU0_P2_RX_BUF_DP<14>")
	)
	(segment
		(start 417.415472 -416.00628)
		(end 417.552632 -416.14344)
		(width 0.14224)
		(layer "In15.Cu")
		(net "P5E_CPU0_P2_RX_BUF_DP<14>")
	)
	(segment
		(start 419.420294 -408.508962)
		(end 419.378638 -408.933396)
		(width 0.14224)
		(layer "In15.Cu")
		(net "P5E_CPU0_P2_RX_BUF_DP<14>")
	)
	(segment
		(start 420.24427 -401.674838)
		(end 420.24427 -401.526756)
		(width 0.14224)
		(layer "In15.Cu")
		(net "P5E_CPU0_P2_RX_BUF_DP<14>")
	)
	(segment
		(start 419.501828 -409.083256)
		(end 419.459918 -409.508198)
		(width 0.14224)
		(layer "In15.Cu")
		(net "P5E_CPU0_P2_RX_BUF_DP<14>")
	)
	(segment
		(start 420.11727 -401.399756)
		(end 419.927532 -401.399756)
		(width 0.14224)
		(layer "In15.Cu")
		(net "P5E_CPU0_P2_RX_BUF_DP<14>")
	)
	(segment
		(start 413.970978 -422.782492)
		(end 413.802322 -422.686988)
		(width 0.14224)
		(layer "In15.Cu")
		(net "P5E_CPU0_P2_RX_BUF_DP<14>")
	)
	(segment
		(start 419.391338 -410.205682)
		(end 419.349428 -410.630624)
		(width 0.14224)
		(layer "In15.Cu")
		(net "P5E_CPU0_P2_RX_BUF_DP<14>")
	)
	(segment
		(start 410.308806 -424.23207)
		(end 410.152342 -424.448478)
		(width 0.14224)
		(layer "In15.Cu")
		(net "P5E_CPU0_P2_RX_BUF_DP<14>")
	)
	(segment
		(start 417.291774 -419.388798)
		(end 417.124388 -419.56482)
		(width 0.14224)
		(layer "In15.Cu")
		(net "P5E_CPU0_P2_RX_BUF_DP<14>")
	)
	(segment
		(start 415.763964 -421.87241)
		(end 415.496502 -422.139872)
		(width 0.14224)
		(layer "In15.Cu")
		(net "P5E_CPU0_P2_RX_BUF_DP<14>")
	)
	(segment
		(start 410.071062 -424.699684)
		(end 410.071062 -437.20385)
		(width 0.14224)
		(layer "In15.Cu")
		(net "P5E_CPU0_P2_RX_BUF_DP<14>")
	)
	(segment
		(start 410.208476 -437.341264)
		(end 410.59989 -437.341264)
		(width 0.14224)
		(layer "In15.Cu")
		(net "P5E_CPU0_P2_RX_BUF_DP<14>")
	)
	(segment
		(start 410.929836 -423.790618)
		(end 410.399484 -424.144694)
		(width 0.14224)
		(layer "In15.Cu")
		(net "P5E_CPU0_P2_RX_BUF_DP<14>")
	)
	(segment
		(start 417.552632 -416.57016)
		(end 417.415472 -416.70732)
		(width 0.14224)
		(layer "In15.Cu")
		(net "P5E_CPU0_P2_RX_BUF_DP<14>")
	)
	(segment
		(start 417.552632 -417.69792)
		(end 417.415472 -417.83508)
		(width 0.14224)
		(layer "In15.Cu")
		(net "P5E_CPU0_P2_RX_BUF_DP<14>")
	)
	(segment
		(start 413.802322 -422.686988)
		(end 413.077152 -422.887648)
		(width 0.14224)
		(layer "In15.Cu")
		(net "P5E_CPU0_P2_RX_BUF_DP<14>")
	)
	(segment
		(start 419.128194 -412.875476)
		(end 418.97808 -412.998666)
		(width 0.14224)
		(layer "In15.Cu")
		(net "P5E_CPU0_P2_RX_BUF_DP<14>")
	)
	(segment
		(start 416.923982 -419.70198)
		(end 415.971482 -420.09695)
		(width 0.14224)
		(layer "In15.Cu")
		(net "P5E_CPU0_P2_RX_BUF_DP<14>")
	)
	(segment
		(start 419.927532 -401.399756)
		(end 419.785292 -401.541996)
		(width 0.14224)
		(layer "In15.Cu")
		(net "P5E_CPU0_P2_RX_BUF_DP<14>")
	)
	(segment
		(start 420.24427 -401.526756)
		(end 420.11727 -401.399756)
		(width 0.14224)
		(layer "In15.Cu")
		(net "P5E_CPU0_P2_RX_BUF_DP<14>")
	)
	(arc
		(start 410.399484 -424.144694)
		(mid 410.350241 -424.184331)
		(end 410.308806 -424.23207)
		(width 0.14224)
		(layer "In15.Cu")
		(net "P5E_CPU0_P2_RX_BUF_DP<14>")
	)
	(arc
		(start 417.124388 -419.56482)
		(mid 417.03137 -419.643897)
		(end 416.923982 -419.70198)
		(width 0.14224)
		(layer "In15.Cu")
		(net "P5E_CPU0_P2_RX_BUF_DP<14>")
	)
	(arc
		(start 417.555934 -414.570926)
		(mid 417.451389 -414.784598)
		(end 417.415472 -415.019744)
		(width 0.14224)
		(layer "In15.Cu")
		(net "P5E_CPU0_P2_RX_BUF_DP<14>")
	)
	(arc
		(start 410.152342 -424.448478)
		(mid 410.091877 -424.567668)
		(end 410.071062 -424.699684)
		(width 0.14224)
		(layer "In15.Cu")
		(net "P5E_CPU0_P2_RX_BUF_DP<14>")
	)
	(arc
		(start 418.936424 -413.4231)
		(mid 418.823108 -413.743357)
		(end 418.573966 -413.97428)
		(width 0.14224)
		(layer "In15.Cu")
		(net "P5E_CPU0_P2_RX_BUF_DP<14>")
	)
	(arc
		(start 417.649914 -414.48609)
		(mid 417.598038 -414.523095)
		(end 417.555934 -414.570926)
		(width 0.14224)
		(layer "In15.Cu")
		(net "P5E_CPU0_P2_RX_BUF_DP<14>")
	)
	(arc
		(start 419.785292 -403.935946)
		(mid 419.764061 -404.800587)
		(end 419.700456 -405.663146)
		(width 0.14224)
		(layer "In15.Cu")
		(net "P5E_CPU0_P2_RX_BUF_DP<14>")
	)
	(arc
		(start 415.971482 -420.09695)
		(mid 415.907737 -420.149167)
		(end 415.883852 -420.228014)
		(width 0.14224)
		(layer "In15.Cu")
		(net "P5E_CPU0_P2_RX_BUF_DP<14>")
	)
	(arc
		(start 411.041342 -423.730928)
		(mid 410.984129 -423.758045)
		(end 410.929836 -423.790618)
		(width 0.14224)
		(layer "In15.Cu")
		(net "P5E_CPU0_P2_RX_BUF_DP<14>")
	)
	(arc
		(start 415.883852 -421.583104)
		(mid 415.852689 -421.739682)
		(end 415.763964 -421.87241)
		(width 0.14224)
		(layer "In15.Cu")
		(net "P5E_CPU0_P2_RX_BUF_DP<14>")
	)
	(arc
		(start 417.415472 -419.079172)
		(mid 417.383507 -419.24593)
		(end 417.291774 -419.388798)
		(width 0.14224)
		(layer "In15.Cu")
		(net "P5E_CPU0_P2_RX_BUF_DP<14>")
	)
	(segment
		(start 418.350192 -399.950686)
		(end 418.350192 -401.105878)
		(width 0.1016)
		(layer "F.Cu")
		(net "P5E_CPU0_P2_RX_BUF_DP<13>")
	)
	(segment
		(start 418.905436 -401.359116)
		(end 419.04412 -401.4978)
		(width 0.1016)
		(layer "F.Cu")
		(net "P5E_CPU0_P2_RX_BUF_DP<13>")
	)
	(segment
		(start 418.34562 -399.663158)
		(end 418.430202 -399.74774)
		(width 0.1016)
		(layer "F.Cu")
		(net "P5E_CPU0_P2_RX_BUF_DP<13>")
	)
	(segment
		(start 418.60343 -401.359116)
		(end 418.905436 -401.359116)
		(width 0.1016)
		(layer "F.Cu")
		(net "P5E_CPU0_P2_RX_BUF_DP<13>")
	)
	(segment
		(start 419.04412 -401.4978)
		(end 419.04412 -401.674838)
		(width 0.1016)
		(layer "F.Cu")
		(net "P5E_CPU0_P2_RX_BUF_DP<13>")
	)
	(segment
		(start 418.430202 -399.74774)
		(end 418.430202 -399.870676)
		(width 0.1016)
		(layer "F.Cu")
		(net "P5E_CPU0_P2_RX_BUF_DP<13>")
	)
	(segment
		(start 418.350192 -401.105878)
		(end 418.60343 -401.359116)
		(width 0.1016)
		(layer "F.Cu")
		(net "P5E_CPU0_P2_RX_BUF_DP<13>")
	)
	(segment
		(start 418.430202 -399.870676)
		(end 418.350192 -399.950686)
		(width 0.1016)
		(layer "F.Cu")
		(net "P5E_CPU0_P2_RX_BUF_DP<13>")
	)
	(segment
		(start 416.990784 -407.817574)
		(end 417.166298 -407.734516)
		(width 0.14224)
		(layer "In15.Cu")
		(net "P5E_CPU0_P2_RX_BUF_DP<13>")
	)
	(segment
		(start 414.352232 -419.079172)
		(end 414.352232 -417.930584)
		(width 0.14224)
		(layer "In15.Cu")
		(net "P5E_CPU0_P2_RX_BUF_DP<13>")
	)
	(segment
		(start 408.599894 -438.341262)
		(end 408.213306 -438.341262)
		(width 0.14224)
		(layer "In15.Cu")
		(net "P5E_CPU0_P2_RX_BUF_DP<13>")
	)
	(segment
		(start 418.91712 -401.399756)
		(end 419.04412 -401.526756)
		(width 0.14224)
		(layer "In15.Cu")
		(net "P5E_CPU0_P2_RX_BUF_DP<13>")
	)
	(segment
		(start 418.267134 -404.250652)
		(end 418.271452 -404.237444)
		(width 0.14224)
		(layer "In15.Cu")
		(net "P5E_CPU0_P2_RX_BUF_DP<13>")
	)
	(segment
		(start 419.04412 -401.526756)
		(end 419.04412 -401.674838)
		(width 0.14224)
		(layer "In15.Cu")
		(net "P5E_CPU0_P2_RX_BUF_DP<13>")
	)
	(segment
		(start 414.489392 -416.665664)
		(end 414.489392 -416.238944)
		(width 0.14224)
		(layer "In15.Cu")
		(net "P5E_CPU0_P2_RX_BUF_DP<13>")
	)
	(segment
		(start 418.271452 -404.237444)
		(end 418.585142 -403.042628)
		(width 0.14224)
		(layer "In15.Cu")
		(net "P5E_CPU0_P2_RX_BUF_DP<13>")
	)
	(segment
		(start 417.227004 -407.157174)
		(end 417.370768 -406.7556)
		(width 0.14224)
		(layer "In15.Cu")
		(net "P5E_CPU0_P2_RX_BUF_DP<13>")
	)
	(segment
		(start 414.352232 -417.229544)
		(end 414.352232 -416.802824)
		(width 0.14224)
		(layer "In15.Cu")
		(net "P5E_CPU0_P2_RX_BUF_DP<13>")
	)
	(segment
		(start 416.609784 -408.882596)
		(end 416.6108 -408.879548)
		(width 0.14224)
		(layer "In15.Cu")
		(net "P5E_CPU0_P2_RX_BUF_DP<13>")
	)
	(segment
		(start 414.943544 -414.267142)
		(end 415.257488 -414.137348)
		(width 0.14224)
		(layer "In15.Cu")
		(net "P5E_CPU0_P2_RX_BUF_DP<13>")
	)
	(segment
		(start 414.489392 -417.366704)
		(end 414.352232 -417.229544)
		(width 0.14224)
		(layer "In15.Cu")
		(net "P5E_CPU0_P2_RX_BUF_DP<13>")
	)
	(segment
		(start 416.430206 -409.573476)
		(end 416.512248 -409.154884)
		(width 0.14224)
		(layer "In15.Cu")
		(net "P5E_CPU0_P2_RX_BUF_DP<13>")
	)
	(segment
		(start 417.926266 -405.610568)
		(end 418.07003 -405.20874)
		(width 0.14224)
		(layer "In15.Cu")
		(net "P5E_CPU0_P2_RX_BUF_DP<13>")
	)
	(segment
		(start 408.213306 -438.341262)
		(end 408.071066 -438.199022)
		(width 0.14224)
		(layer "In15.Cu")
		(net "P5E_CPU0_P2_RX_BUF_DP<13>")
	)
	(segment
		(start 416.190176 -411.509718)
		(end 416.272218 -411.090872)
		(width 0.14224)
		(layer "In15.Cu")
		(net "P5E_CPU0_P2_RX_BUF_DP<13>")
	)
	(segment
		(start 417.987226 -405.033226)
		(end 417.987734 -405.031702)
		(width 0.14224)
		(layer "In15.Cu")
		(net "P5E_CPU0_P2_RX_BUF_DP<13>")
	)
	(segment
		(start 416.512248 -409.154884)
		(end 416.512502 -409.154122)
		(width 0.14224)
		(layer "In15.Cu")
		(net "P5E_CPU0_P2_RX_BUF_DP<13>")
	)
	(segment
		(start 408.41422 -424.044364)
		(end 408.80665 -423.83456)
		(width 0.14224)
		(layer "In15.Cu")
		(net "P5E_CPU0_P2_RX_BUF_DP<13>")
	)
	(segment
		(start 417.606988 -406.0952)
		(end 417.750752 -405.693626)
		(width 0.14224)
		(layer "In15.Cu")
		(net "P5E_CPU0_P2_RX_BUF_DP<13>")
	)
	(segment
		(start 417.987734 -405.031702)
		(end 418.267134 -404.250652)
		(width 0.14224)
		(layer "In15.Cu")
		(net "P5E_CPU0_P2_RX_BUF_DP<13>")
	)
	(segment
		(start 418.585142 -403.042628)
		(end 418.585142 -401.541996)
		(width 0.14224)
		(layer "In15.Cu")
		(net "P5E_CPU0_P2_RX_BUF_DP<13>")
	)
	(segment
		(start 416.295078 -410.261562)
		(end 416.456368 -410.153612)
		(width 0.14224)
		(layer "In15.Cu")
		(net "P5E_CPU0_P2_RX_BUF_DP<13>")
	)
	(segment
		(start 408.106372 -424.493436)
		(end 408.270964 -424.218608)
		(width 0.14224)
		(layer "In15.Cu")
		(net "P5E_CPU0_P2_RX_BUF_DP<13>")
	)
	(segment
		(start 416.272218 -411.090872)
		(end 416.164014 -410.929836)
		(width 0.14224)
		(layer "In15.Cu")
		(net "P5E_CPU0_P2_RX_BUF_DP<13>")
	)
	(segment
		(start 416.028886 -411.617922)
		(end 416.190176 -411.509718)
		(width 0.14224)
		(layer "In15.Cu")
		(net "P5E_CPU0_P2_RX_BUF_DP<13>")
	)
	(segment
		(start 408.992324 -423.890948)
		(end 409.368752 -423.68978)
		(width 0.14224)
		(layer "In15.Cu")
		(net "P5E_CPU0_P2_RX_BUF_DP<13>")
	)
	(segment
		(start 414.352232 -416.101784)
		(end 414.352232 -415.020252)
		(width 0.14224)
		(layer "In15.Cu")
		(net "P5E_CPU0_P2_RX_BUF_DP<13>")
	)
	(segment
		(start 412.908242 -420.09695)
		(end 413.860742 -419.70198)
		(width 0.14224)
		(layer "In15.Cu")
		(net "P5E_CPU0_P2_RX_BUF_DP<13>")
	)
	(segment
		(start 408.750008 -438.191148)
		(end 408.599894 -438.341262)
		(width 0.14224)
		(layer "In15.Cu")
		(net "P5E_CPU0_P2_RX_BUF_DP<13>")
	)
	(segment
		(start 414.489392 -416.238944)
		(end 414.352232 -416.101784)
		(width 0.14224)
		(layer "In15.Cu")
		(net "P5E_CPU0_P2_RX_BUF_DP<13>")
	)
	(segment
		(start 416.53841 -409.734512)
		(end 416.430206 -409.573476)
		(width 0.14224)
		(layer "In15.Cu")
		(net "P5E_CPU0_P2_RX_BUF_DP<13>")
	)
	(segment
		(start 418.585142 -401.541996)
		(end 418.727382 -401.399756)
		(width 0.14224)
		(layer "In15.Cu")
		(net "P5E_CPU0_P2_RX_BUF_DP<13>")
	)
	(segment
		(start 417.310062 -407.332434)
		(end 417.227004 -407.157174)
		(width 0.14224)
		(layer "In15.Cu")
		(net "P5E_CPU0_P2_RX_BUF_DP<13>")
	)
	(segment
		(start 417.546282 -406.672542)
		(end 417.690046 -406.27046)
		(width 0.14224)
		(layer "In15.Cu")
		(net "P5E_CPU0_P2_RX_BUF_DP<13>")
	)
	(segment
		(start 409.368752 -423.68978)
		(end 409.42514 -423.503852)
		(width 0.14224)
		(layer "In15.Cu")
		(net "P5E_CPU0_P2_RX_BUF_DP<13>")
	)
	(segment
		(start 417.370768 -406.7556)
		(end 417.546282 -406.672542)
		(width 0.14224)
		(layer "In15.Cu")
		(net "P5E_CPU0_P2_RX_BUF_DP<13>")
	)
	(segment
		(start 417.750752 -405.693626)
		(end 417.926266 -405.610568)
		(width 0.14224)
		(layer "In15.Cu")
		(net "P5E_CPU0_P2_RX_BUF_DP<13>")
	)
	(segment
		(start 417.166298 -407.734516)
		(end 417.310062 -407.332434)
		(width 0.14224)
		(layer "In15.Cu")
		(net "P5E_CPU0_P2_RX_BUF_DP<13>")
	)
	(segment
		(start 416.164014 -410.929836)
		(end 416.295078 -410.261562)
		(width 0.14224)
		(layer "In15.Cu")
		(net "P5E_CPU0_P2_RX_BUF_DP<13>")
	)
	(segment
		(start 418.727382 -401.399756)
		(end 418.91712 -401.399756)
		(width 0.14224)
		(layer "In15.Cu")
		(net "P5E_CPU0_P2_RX_BUF_DP<13>")
	)
	(segment
		(start 412.54045 -421.940482)
		(end 412.700724 -421.780208)
		(width 0.14224)
		(layer "In15.Cu")
		(net "P5E_CPU0_P2_RX_BUF_DP<13>")
	)
	(segment
		(start 416.84702 -408.219148)
		(end 416.988752 -407.82367)
		(width 0.14224)
		(layer "In15.Cu")
		(net "P5E_CPU0_P2_RX_BUF_DP<13>")
	)
	(segment
		(start 417.690046 -406.27046)
		(end 417.606988 -406.0952)
		(width 0.14224)
		(layer "In15.Cu")
		(net "P5E_CPU0_P2_RX_BUF_DP<13>")
	)
	(segment
		(start 414.352232 -417.930584)
		(end 414.489392 -417.793424)
		(width 0.14224)
		(layer "In15.Cu")
		(net "P5E_CPU0_P2_RX_BUF_DP<13>")
	)
	(segment
		(start 408.80665 -423.83456)
		(end 408.992324 -423.890948)
		(width 0.14224)
		(layer "In15.Cu")
		(net "P5E_CPU0_P2_RX_BUF_DP<13>")
	)
	(segment
		(start 415.788094 -413.615124)
		(end 415.78784 -413.615124)
		(width 0.14224)
		(layer "In15.Cu")
		(net "P5E_CPU0_P2_RX_BUF_DP<13>")
	)
	(segment
		(start 409.42514 -423.503852)
		(end 410.374846 -422.99636)
		(width 0.14224)
		(layer "In15.Cu")
		(net "P5E_CPU0_P2_RX_BUF_DP<13>")
	)
	(segment
		(start 418.07003 -405.20874)
		(end 417.987226 -405.033226)
		(width 0.14224)
		(layer "In15.Cu")
		(net "P5E_CPU0_P2_RX_BUF_DP<13>")
	)
	(segment
		(start 416.786314 -408.79649)
		(end 416.930078 -408.394408)
		(width 0.14224)
		(layer "In15.Cu")
		(net "P5E_CPU0_P2_RX_BUF_DP<13>")
	)
	(segment
		(start 412.820612 -421.490902)
		(end 412.820612 -420.228014)
		(width 0.14224)
		(layer "In15.Cu")
		(net "P5E_CPU0_P2_RX_BUF_DP<13>")
	)
	(segment
		(start 408.750008 -437.889904)
		(end 408.750008 -438.191148)
		(width 0.14224)
		(layer "In15.Cu")
		(net "P5E_CPU0_P2_RX_BUF_DP<13>")
	)
	(segment
		(start 408.071066 -438.199022)
		(end 408.071066 -424.629326)
		(width 0.14224)
		(layer "In15.Cu")
		(net "P5E_CPU0_P2_RX_BUF_DP<13>")
	)
	(segment
		(start 416.456368 -410.153612)
		(end 416.53841 -409.734512)
		(width 0.14224)
		(layer "In15.Cu")
		(net "P5E_CPU0_P2_RX_BUF_DP<13>")
	)
	(segment
		(start 416.930078 -408.394408)
		(end 416.84702 -408.219148)
		(width 0.14224)
		(layer "In15.Cu")
		(net "P5E_CPU0_P2_RX_BUF_DP<13>")
	)
	(segment
		(start 414.061148 -419.56482)
		(end 414.228534 -419.388798)
		(width 0.14224)
		(layer "In15.Cu")
		(net "P5E_CPU0_P2_RX_BUF_DP<13>")
	)
	(segment
		(start 416.988752 -407.82367)
		(end 416.990784 -407.817574)
		(width 0.14224)
		(layer "In15.Cu")
		(net "P5E_CPU0_P2_RX_BUF_DP<13>")
	)
	(segment
		(start 415.88436 -413.304228)
		(end 415.88436 -412.418784)
		(width 0.14224)
		(layer "In15.Cu")
		(net "P5E_CPU0_P2_RX_BUF_DP<13>")
	)
	(segment
		(start 408.270964 -424.218608)
		(end 408.323796 -424.13047)
		(width 0.14224)
		(layer "In15.Cu")
		(net "P5E_CPU0_P2_RX_BUF_DP<13>")
	)
	(segment
		(start 416.512502 -409.154122)
		(end 416.609784 -408.882596)
		(width 0.14224)
		(layer "In15.Cu")
		(net "P5E_CPU0_P2_RX_BUF_DP<13>")
	)
	(segment
		(start 415.327592 -414.10001)
		(end 415.497264 -413.987234)
		(width 0.14224)
		(layer "In15.Cu")
		(net "P5E_CPU0_P2_RX_BUF_DP<13>")
	)
	(segment
		(start 410.489146 -422.942258)
		(end 411.938978 -422.34231)
		(width 0.14224)
		(layer "In15.Cu")
		(net "P5E_CPU0_P2_RX_BUF_DP<13>")
	)
	(segment
		(start 415.896552 -412.293054)
		(end 416.028886 -411.617922)
		(width 0.14224)
		(layer "In15.Cu")
		(net "P5E_CPU0_P2_RX_BUF_DP<13>")
	)
	(segment
		(start 416.6108 -408.879548)
		(end 416.786314 -408.79649)
		(width 0.14224)
		(layer "In15.Cu")
		(net "P5E_CPU0_P2_RX_BUF_DP<13>")
	)
	(segment
		(start 414.352232 -416.802824)
		(end 414.489392 -416.665664)
		(width 0.14224)
		(layer "In15.Cu")
		(net "P5E_CPU0_P2_RX_BUF_DP<13>")
	)
	(segment
		(start 415.609024 -413.87649)
		(end 415.788094 -413.615124)
		(width 0.14224)
		(layer "In15.Cu")
		(net "P5E_CPU0_P2_RX_BUF_DP<13>")
	)
	(segment
		(start 414.489392 -417.793424)
		(end 414.489392 -417.366704)
		(width 0.14224)
		(layer "In15.Cu")
		(net "P5E_CPU0_P2_RX_BUF_DP<13>")
	)
	(arc
		(start 412.700724 -421.780208)
		(mid 412.789468 -421.647488)
		(end 412.820612 -421.490902)
		(width 0.14224)
		(layer "In15.Cu")
		(net "P5E_CPU0_P2_RX_BUF_DP<13>")
	)
	(arc
		(start 414.352232 -415.020252)
		(mid 414.405461 -414.752451)
		(end 414.55721 -414.52546)
		(width 0.14224)
		(layer "In15.Cu")
		(net "P5E_CPU0_P2_RX_BUF_DP<13>")
	)
	(arc
		(start 410.374846 -422.99636)
		(mid 410.43133 -422.967902)
		(end 410.489146 -422.942258)
		(width 0.14224)
		(layer "In15.Cu")
		(net "P5E_CPU0_P2_RX_BUF_DP<13>")
	)
	(arc
		(start 408.071066 -424.629326)
		(mid 408.08006 -424.559129)
		(end 408.106372 -424.493436)
		(width 0.14224)
		(layer "In15.Cu")
		(net "P5E_CPU0_P2_RX_BUF_DP<13>")
	)
	(arc
		(start 414.55721 -414.52546)
		(mid 414.73768 -414.377314)
		(end 414.943544 -414.267142)
		(width 0.14224)
		(layer "In15.Cu")
		(net "P5E_CPU0_P2_RX_BUF_DP<13>")
	)
	(arc
		(start 415.257488 -414.137348)
		(mid 415.293441 -414.120373)
		(end 415.327592 -414.10001)
		(width 0.14224)
		(layer "In15.Cu")
		(net "P5E_CPU0_P2_RX_BUF_DP<13>")
	)
	(arc
		(start 415.78784 -413.615124)
		(mid 415.859711 -413.46701)
		(end 415.88436 -413.304228)
		(width 0.14224)
		(layer "In15.Cu")
		(net "P5E_CPU0_P2_RX_BUF_DP<13>")
	)
	(arc
		(start 415.88436 -412.418784)
		(mid 415.887417 -412.355624)
		(end 415.896552 -412.293054)
		(width 0.14224)
		(layer "In15.Cu")
		(net "P5E_CPU0_P2_RX_BUF_DP<13>")
	)
	(arc
		(start 411.938978 -422.34231)
		(mid 412.259508 -422.171027)
		(end 412.54045 -421.940482)
		(width 0.14224)
		(layer "In15.Cu")
		(net "P5E_CPU0_P2_RX_BUF_DP<13>")
	)
	(arc
		(start 414.228534 -419.388798)
		(mid 414.32021 -419.245907)
		(end 414.352232 -419.079172)
		(width 0.14224)
		(layer "In15.Cu")
		(net "P5E_CPU0_P2_RX_BUF_DP<13>")
	)
	(arc
		(start 408.323796 -424.13047)
		(mid 408.363197 -424.081321)
		(end 408.41422 -424.044364)
		(width 0.14224)
		(layer "In15.Cu")
		(net "P5E_CPU0_P2_RX_BUF_DP<13>")
	)
	(arc
		(start 413.860742 -419.70198)
		(mid 413.96814 -419.643911)
		(end 414.061148 -419.56482)
		(width 0.14224)
		(layer "In15.Cu")
		(net "P5E_CPU0_P2_RX_BUF_DP<13>")
	)
	(arc
		(start 415.497264 -413.987234)
		(mid 415.558471 -413.937239)
		(end 415.609024 -413.87649)
		(width 0.14224)
		(layer "In15.Cu")
		(net "P5E_CPU0_P2_RX_BUF_DP<13>")
	)
	(arc
		(start 412.820612 -420.228014)
		(mid 412.844546 -420.1492)
		(end 412.908242 -420.09695)
		(width 0.14224)
		(layer "In15.Cu")
		(net "P5E_CPU0_P2_RX_BUF_DP<13>")
	)
	(segment
		(start 417.14166 -401.105878)
		(end 417.394898 -401.359116)
		(width 0.1016)
		(layer "F.Cu")
		(net "P5E_CPU0_P2_RX_BUF_DP<12>")
	)
	(segment
		(start 417.230306 -399.74774)
		(end 417.230306 -399.870676)
		(width 0.1016)
		(layer "F.Cu")
		(net "P5E_CPU0_P2_RX_BUF_DP<12>")
	)
	(segment
		(start 417.230306 -399.870676)
		(end 417.14166 -399.959322)
		(width 0.1016)
		(layer "F.Cu")
		(net "P5E_CPU0_P2_RX_BUF_DP<12>")
	)
	(segment
		(start 417.14166 -399.959322)
		(end 417.14166 -401.105878)
		(width 0.1016)
		(layer "F.Cu")
		(net "P5E_CPU0_P2_RX_BUF_DP<12>")
	)
	(segment
		(start 417.394898 -401.359116)
		(end 417.702238 -401.359116)
		(width 0.1016)
		(layer "F.Cu")
		(net "P5E_CPU0_P2_RX_BUF_DP<12>")
	)
	(segment
		(start 417.844224 -401.501102)
		(end 417.844224 -401.674838)
		(width 0.1016)
		(layer "F.Cu")
		(net "P5E_CPU0_P2_RX_BUF_DP<12>")
	)
	(segment
		(start 417.702238 -401.359116)
		(end 417.844224 -401.501102)
		(width 0.1016)
		(layer "F.Cu")
		(net "P5E_CPU0_P2_RX_BUF_DP<12>")
	)
	(segment
		(start 417.145724 -399.663158)
		(end 417.230306 -399.74774)
		(width 0.1016)
		(layer "F.Cu")
		(net "P5E_CPU0_P2_RX_BUF_DP<12>")
	)
	(segment
		(start 409.757372 -421.466518)
		(end 409.757372 -420.228014)
		(width 0.14224)
		(layer "In15.Cu")
		(net "P5E_CPU0_P2_RX_BUF_DP<12>")
	)
	(segment
		(start 414.081722 -410.042868)
		(end 414.300924 -409.6766)
		(width 0.14224)
		(layer "In15.Cu")
		(net "P5E_CPU0_P2_RX_BUF_DP<12>")
	)
	(segment
		(start 406.160224 -424.394122)
		(end 406.256998 -424.188128)
		(width 0.14224)
		(layer "In15.Cu")
		(net "P5E_CPU0_P2_RX_BUF_DP<12>")
	)
	(segment
		(start 412.471362 -413.942276)
		(end 412.618174 -413.795464)
		(width 0.14224)
		(layer "In15.Cu")
		(net "P5E_CPU0_P2_RX_BUF_DP<12>")
	)
	(segment
		(start 411.426152 -416.757104)
		(end 411.426152 -416.330384)
		(width 0.14224)
		(layer "In15.Cu")
		(net "P5E_CPU0_P2_RX_BUF_DP<12>")
	)
	(segment
		(start 416.864292 -404.839932)
		(end 417.385246 -403.582124)
		(width 0.14224)
		(layer "In15.Cu")
		(net "P5E_CPU0_P2_RX_BUF_DP<12>")
	)
	(segment
		(start 415.94405 -406.556972)
		(end 416.581844 -405.422608)
		(width 0.14224)
		(layer "In15.Cu")
		(net "P5E_CPU0_P2_RX_BUF_DP<12>")
	)
	(segment
		(start 406.273 -424.170094)
		(end 406.617424 -423.940732)
		(width 0.14224)
		(layer "In15.Cu")
		(net "P5E_CPU0_P2_RX_BUF_DP<12>")
	)
	(segment
		(start 406.256998 -424.188128)
		(end 406.273 -424.170094)
		(width 0.14224)
		(layer "In15.Cu")
		(net "P5E_CPU0_P2_RX_BUF_DP<12>")
	)
	(segment
		(start 409.845002 -420.09695)
		(end 410.79674 -419.702742)
		(width 0.14224)
		(layer "In15.Cu")
		(net "P5E_CPU0_P2_RX_BUF_DP<12>")
	)
	(segment
		(start 406.80767 -423.978832)
		(end 407.16327 -423.742358)
		(width 0.14224)
		(layer "In15.Cu")
		(net "P5E_CPU0_P2_RX_BUF_DP<12>")
	)
	(segment
		(start 406.599898 -437.341264)
		(end 406.208484 -437.341264)
		(width 0.14224)
		(layer "In15.Cu")
		(net "P5E_CPU0_P2_RX_BUF_DP<12>")
	)
	(segment
		(start 412.155894 -414.153096)
		(end 412.471362 -413.942276)
		(width 0.14224)
		(layer "In15.Cu")
		(net "P5E_CPU0_P2_RX_BUF_DP<12>")
	)
	(segment
		(start 406.07107 -437.20385)
		(end 406.07107 -424.791886)
		(width 0.14224)
		(layer "In15.Cu")
		(net "P5E_CPU0_P2_RX_BUF_DP<12>")
	)
	(segment
		(start 411.426152 -417.458144)
		(end 411.288992 -417.320984)
		(width 0.14224)
		(layer "In15.Cu")
		(net "P5E_CPU0_P2_RX_BUF_DP<12>")
	)
	(segment
		(start 414.473136 -409.122626)
		(end 414.661604 -409.075382)
		(width 0.14224)
		(layer "In15.Cu")
		(net "P5E_CPU0_P2_RX_BUF_DP<12>")
	)
	(segment
		(start 408.538426 -422.827196)
		(end 408.57678 -422.63695)
		(width 0.14224)
		(layer "In15.Cu")
		(net "P5E_CPU0_P2_RX_BUF_DP<12>")
	)
	(segment
		(start 415.59861 -407.167588)
		(end 415.785808 -407.115772)
		(width 0.14224)
		(layer "In15.Cu")
		(net "P5E_CPU0_P2_RX_BUF_DP<12>")
	)
	(segment
		(start 413.561784 -410.910024)
		(end 413.51454 -410.72181)
		(width 0.14224)
		(layer "In15.Cu")
		(net "P5E_CPU0_P2_RX_BUF_DP<12>")
	)
	(segment
		(start 411.288992 -416.894264)
		(end 411.426152 -416.757104)
		(width 0.14224)
		(layer "In15.Cu")
		(net "P5E_CPU0_P2_RX_BUF_DP<12>")
	)
	(segment
		(start 417.527486 -401.399756)
		(end 417.717224 -401.399756)
		(width 0.14224)
		(layer "In15.Cu")
		(net "P5E_CPU0_P2_RX_BUF_DP<12>")
	)
	(segment
		(start 414.300924 -409.6766)
		(end 414.253934 -409.488386)
		(width 0.14224)
		(layer "In15.Cu")
		(net "P5E_CPU0_P2_RX_BUF_DP<12>")
	)
	(segment
		(start 417.385246 -403.582124)
		(end 417.385246 -401.541996)
		(width 0.14224)
		(layer "In15.Cu")
		(net "P5E_CPU0_P2_RX_BUF_DP<12>")
	)
	(segment
		(start 412.820612 -413.306514)
		(end 412.820612 -412.401258)
		(width 0.14224)
		(layer "In15.Cu")
		(net "P5E_CPU0_P2_RX_BUF_DP<12>")
	)
	(segment
		(start 417.385246 -401.541996)
		(end 417.527486 -401.399756)
		(width 0.14224)
		(layer "In15.Cu")
		(net "P5E_CPU0_P2_RX_BUF_DP<12>")
	)
	(segment
		(start 413.342328 -411.276292)
		(end 413.561784 -410.910024)
		(width 0.14224)
		(layer "In15.Cu")
		(net "P5E_CPU0_P2_RX_BUF_DP<12>")
	)
	(segment
		(start 414.88106 -408.709114)
		(end 414.833816 -408.5209)
		(width 0.14224)
		(layer "In15.Cu")
		(net "P5E_CPU0_P2_RX_BUF_DP<12>")
	)
	(segment
		(start 411.288992 -417.320984)
		(end 411.288992 -416.894264)
		(width 0.14224)
		(layer "In15.Cu")
		(net "P5E_CPU0_P2_RX_BUF_DP<12>")
	)
	(segment
		(start 414.253934 -409.488386)
		(end 414.473136 -409.122626)
		(width 0.14224)
		(layer "In15.Cu")
		(net "P5E_CPU0_P2_RX_BUF_DP<12>")
	)
	(segment
		(start 414.833816 -408.5209)
		(end 415.04362 -408.149552)
		(width 0.14224)
		(layer "In15.Cu")
		(net "P5E_CPU0_P2_RX_BUF_DP<12>")
	)
	(segment
		(start 415.440876 -407.72588)
		(end 415.388806 -407.538936)
		(width 0.14224)
		(layer "In15.Cu")
		(net "P5E_CPU0_P2_RX_BUF_DP<12>")
	)
	(segment
		(start 413.15386 -411.323536)
		(end 413.342328 -411.276292)
		(width 0.14224)
		(layer "In15.Cu")
		(net "P5E_CPU0_P2_RX_BUF_DP<12>")
	)
	(segment
		(start 406.750012 -436.889906)
		(end 406.750012 -437.19115)
		(width 0.14224)
		(layer "In15.Cu")
		(net "P5E_CPU0_P2_RX_BUF_DP<12>")
	)
	(segment
		(start 411.288992 -419.079172)
		(end 411.288992 -418.022024)
		(width 0.14224)
		(layer "In15.Cu")
		(net "P5E_CPU0_P2_RX_BUF_DP<12>")
	)
	(segment
		(start 411.288992 -416.193224)
		(end 411.288992 -415.020252)
		(width 0.14224)
		(layer "In15.Cu")
		(net "P5E_CPU0_P2_RX_BUF_DP<12>")
	)
	(segment
		(start 407.16327 -423.742358)
		(end 407.20137 -423.552112)
		(width 0.14224)
		(layer "In15.Cu")
		(net "P5E_CPU0_P2_RX_BUF_DP<12>")
	)
	(segment
		(start 406.617424 -423.940732)
		(end 406.80767 -423.978832)
		(width 0.14224)
		(layer "In15.Cu")
		(net "P5E_CPU0_P2_RX_BUF_DP<12>")
	)
	(segment
		(start 408.57678 -422.63695)
		(end 408.931872 -422.40073)
		(width 0.14224)
		(layer "In15.Cu")
		(net "P5E_CPU0_P2_RX_BUF_DP<12>")
	)
	(segment
		(start 416.581844 -405.422608)
		(end 416.864292 -404.839932)
		(width 0.14224)
		(layer "In15.Cu")
		(net "P5E_CPU0_P2_RX_BUF_DP<12>")
	)
	(segment
		(start 407.20137 -423.552112)
		(end 407.992834 -423.02557)
		(width 0.14224)
		(layer "In15.Cu")
		(net "P5E_CPU0_P2_RX_BUF_DP<12>")
	)
	(segment
		(start 408.18308 -423.06367)
		(end 408.538426 -422.827196)
		(width 0.14224)
		(layer "In15.Cu")
		(net "P5E_CPU0_P2_RX_BUF_DP<12>")
	)
	(segment
		(start 415.230818 -408.097736)
		(end 415.440876 -407.72588)
		(width 0.14224)
		(layer "In15.Cu")
		(net "P5E_CPU0_P2_RX_BUF_DP<12>")
	)
	(segment
		(start 411.426152 -416.330384)
		(end 411.288992 -416.193224)
		(width 0.14224)
		(layer "In15.Cu")
		(net "P5E_CPU0_P2_RX_BUF_DP<12>")
	)
	(segment
		(start 417.717224 -401.399756)
		(end 417.844224 -401.526756)
		(width 0.14224)
		(layer "In15.Cu")
		(net "P5E_CPU0_P2_RX_BUF_DP<12>")
	)
	(segment
		(start 409.348432 -422.059354)
		(end 409.627578 -421.780208)
		(width 0.14224)
		(layer "In15.Cu")
		(net "P5E_CPU0_P2_RX_BUF_DP<12>")
	)
	(segment
		(start 417.844224 -401.526756)
		(end 417.844224 -401.674838)
		(width 0.14224)
		(layer "In15.Cu")
		(net "P5E_CPU0_P2_RX_BUF_DP<12>")
	)
	(segment
		(start 415.388806 -407.538936)
		(end 415.59861 -407.167588)
		(width 0.14224)
		(layer "In15.Cu")
		(net "P5E_CPU0_P2_RX_BUF_DP<12>")
	)
	(segment
		(start 406.750012 -437.19115)
		(end 406.599898 -437.341264)
		(width 0.14224)
		(layer "In15.Cu")
		(net "P5E_CPU0_P2_RX_BUF_DP<12>")
	)
	(segment
		(start 412.829248 -412.27502)
		(end 412.893002 -411.807914)
		(width 0.14224)
		(layer "In15.Cu")
		(net "P5E_CPU0_P2_RX_BUF_DP<12>")
	)
	(segment
		(start 412.934658 -411.689296)
		(end 413.15386 -411.323536)
		(width 0.14224)
		(layer "In15.Cu")
		(net "P5E_CPU0_P2_RX_BUF_DP<12>")
	)
	(segment
		(start 407.992834 -423.02557)
		(end 408.18308 -423.06367)
		(width 0.14224)
		(layer "In15.Cu")
		(net "P5E_CPU0_P2_RX_BUF_DP<12>")
	)
	(segment
		(start 415.995866 -406.743916)
		(end 415.94405 -406.556972)
		(width 0.14224)
		(layer "In15.Cu")
		(net "P5E_CPU0_P2_RX_BUF_DP<12>")
	)
	(segment
		(start 406.208484 -437.341264)
		(end 406.07107 -437.20385)
		(width 0.14224)
		(layer "In15.Cu")
		(net "P5E_CPU0_P2_RX_BUF_DP<12>")
	)
	(segment
		(start 411.288992 -418.022024)
		(end 411.426152 -417.884864)
		(width 0.14224)
		(layer "In15.Cu")
		(net "P5E_CPU0_P2_RX_BUF_DP<12>")
	)
	(segment
		(start 415.785808 -407.115772)
		(end 415.995866 -406.743916)
		(width 0.14224)
		(layer "In15.Cu")
		(net "P5E_CPU0_P2_RX_BUF_DP<12>")
	)
	(segment
		(start 413.893254 -410.090112)
		(end 414.081722 -410.042868)
		(width 0.14224)
		(layer "In15.Cu")
		(net "P5E_CPU0_P2_RX_BUF_DP<12>")
	)
	(segment
		(start 410.997908 -419.56482)
		(end 411.165294 -419.388798)
		(width 0.14224)
		(layer "In15.Cu")
		(net "P5E_CPU0_P2_RX_BUF_DP<12>")
	)
	(segment
		(start 411.426152 -417.884864)
		(end 411.426152 -417.458144)
		(width 0.14224)
		(layer "In15.Cu")
		(net "P5E_CPU0_P2_RX_BUF_DP<12>")
	)
	(segment
		(start 411.880304 -414.267142)
		(end 412.155894 -414.153096)
		(width 0.14224)
		(layer "In15.Cu")
		(net "P5E_CPU0_P2_RX_BUF_DP<12>")
	)
	(segment
		(start 414.661604 -409.075382)
		(end 414.88106 -408.709114)
		(width 0.14224)
		(layer "In15.Cu")
		(net "P5E_CPU0_P2_RX_BUF_DP<12>")
	)
	(segment
		(start 415.04362 -408.149552)
		(end 415.230818 -408.097736)
		(width 0.14224)
		(layer "In15.Cu")
		(net "P5E_CPU0_P2_RX_BUF_DP<12>")
	)
	(segment
		(start 413.51454 -410.72181)
		(end 413.893254 -410.090112)
		(width 0.14224)
		(layer "In15.Cu")
		(net "P5E_CPU0_P2_RX_BUF_DP<12>")
	)
	(arc
		(start 410.79674 -419.702742)
		(mid 410.904553 -419.644325)
		(end 410.997908 -419.56482)
		(width 0.14224)
		(layer "In15.Cu")
		(net "P5E_CPU0_P2_RX_BUF_DP<12>")
	)
	(arc
		(start 408.931872 -422.40073)
		(mid 409.148617 -422.240372)
		(end 409.348432 -422.059354)
		(width 0.14224)
		(layer "In15.Cu")
		(net "P5E_CPU0_P2_RX_BUF_DP<12>")
	)
	(arc
		(start 409.757372 -420.228014)
		(mid 409.781284 -420.149157)
		(end 409.845002 -420.09695)
		(width 0.14224)
		(layer "In15.Cu")
		(net "P5E_CPU0_P2_RX_BUF_DP<12>")
	)
	(arc
		(start 411.165294 -419.388798)
		(mid 411.25697 -419.245907)
		(end 411.288992 -419.079172)
		(width 0.14224)
		(layer "In15.Cu")
		(net "P5E_CPU0_P2_RX_BUF_DP<12>")
	)
	(arc
		(start 412.893002 -411.807914)
		(mid 412.907826 -411.746497)
		(end 412.934658 -411.689296)
		(width 0.14224)
		(layer "In15.Cu")
		(net "P5E_CPU0_P2_RX_BUF_DP<12>")
	)
	(arc
		(start 411.49397 -414.52546)
		(mid 411.67444 -414.377314)
		(end 411.880304 -414.267142)
		(width 0.14224)
		(layer "In15.Cu")
		(net "P5E_CPU0_P2_RX_BUF_DP<12>")
	)
	(arc
		(start 406.07107 -424.791886)
		(mid 406.093697 -424.588087)
		(end 406.160224 -424.394122)
		(width 0.14224)
		(layer "In15.Cu")
		(net "P5E_CPU0_P2_RX_BUF_DP<12>")
	)
	(arc
		(start 409.627578 -421.780208)
		(mid 409.723714 -421.636285)
		(end 409.757372 -421.466518)
		(width 0.14224)
		(layer "In15.Cu")
		(net "P5E_CPU0_P2_RX_BUF_DP<12>")
	)
	(arc
		(start 412.820612 -412.401258)
		(mid 412.822795 -412.337993)
		(end 412.829248 -412.27502)
		(width 0.14224)
		(layer "In15.Cu")
		(net "P5E_CPU0_P2_RX_BUF_DP<12>")
	)
	(arc
		(start 412.618174 -413.795464)
		(mid 412.768014 -413.571118)
		(end 412.820612 -413.306514)
		(width 0.14224)
		(layer "In15.Cu")
		(net "P5E_CPU0_P2_RX_BUF_DP<12>")
	)
	(arc
		(start 411.288992 -415.020252)
		(mid 411.342221 -414.752451)
		(end 411.49397 -414.52546)
		(width 0.14224)
		(layer "In15.Cu")
		(net "P5E_CPU0_P2_RX_BUF_DP<12>")
	)
	(segment
		(start 415.945574 -399.663158)
		(end 416.030156 -399.74774)
		(width 0.1016)
		(layer "F.Cu")
		(net "P5E_CPU0_P2_RX_BUF_DP<11>")
	)
	(segment
		(start 415.94151 -401.105878)
		(end 416.194748 -401.359116)
		(width 0.1016)
		(layer "F.Cu")
		(net "P5E_CPU0_P2_RX_BUF_DP<11>")
	)
	(segment
		(start 416.50539 -401.359116)
		(end 416.644328 -401.498054)
		(width 0.1016)
		(layer "F.Cu")
		(net "P5E_CPU0_P2_RX_BUF_DP<11>")
	)
	(segment
		(start 416.194748 -401.359116)
		(end 416.50539 -401.359116)
		(width 0.1016)
		(layer "F.Cu")
		(net "P5E_CPU0_P2_RX_BUF_DP<11>")
	)
	(segment
		(start 416.030156 -399.870676)
		(end 415.94151 -399.959322)
		(width 0.1016)
		(layer "F.Cu")
		(net "P5E_CPU0_P2_RX_BUF_DP<11>")
	)
	(segment
		(start 416.644328 -401.498054)
		(end 416.644328 -401.674838)
		(width 0.1016)
		(layer "F.Cu")
		(net "P5E_CPU0_P2_RX_BUF_DP<11>")
	)
	(segment
		(start 415.94151 -399.959322)
		(end 415.94151 -401.105878)
		(width 0.1016)
		(layer "F.Cu")
		(net "P5E_CPU0_P2_RX_BUF_DP<11>")
	)
	(segment
		(start 416.030156 -399.74774)
		(end 416.030156 -399.870676)
		(width 0.1016)
		(layer "F.Cu")
		(net "P5E_CPU0_P2_RX_BUF_DP<11>")
	)
	(segment
		(start 413.417766 -408.036522)
		(end 413.000952 -408.496516)
		(width 0.14224)
		(layer "In15.Cu")
		(net "P5E_CPU0_P2_RX_BUF_DP<11>")
	)
	(segment
		(start 412.530036 -409.0162)
		(end 412.243524 -409.332176)
		(width 0.14224)
		(layer "In15.Cu")
		(net "P5E_CPU0_P2_RX_BUF_DP<11>")
	)
	(segment
		(start 408.225752 -417.769294)
		(end 408.225752 -419.079172)
		(width 0.14224)
		(layer "In15.Cu")
		(net "P5E_CPU0_P2_RX_BUF_DP<11>")
	)
	(segment
		(start 413.000952 -408.496516)
		(end 413.010604 -408.690064)
		(width 0.14224)
		(layer "In15.Cu")
		(net "P5E_CPU0_P2_RX_BUF_DP<11>")
	)
	(segment
		(start 408.225752 -417.068254)
		(end 408.362912 -417.205414)
		(width 0.14224)
		(layer "In15.Cu")
		(net "P5E_CPU0_P2_RX_BUF_DP<11>")
	)
	(segment
		(start 409.888436 -411.956758)
		(end 409.821634 -412.09341)
		(width 0.14224)
		(layer "In15.Cu")
		(net "P5E_CPU0_P2_RX_BUF_DP<11>")
	)
	(segment
		(start 412.723584 -409.006548)
		(end 412.530036 -409.0162)
		(width 0.14224)
		(layer "In15.Cu")
		(net "P5E_CPU0_P2_RX_BUF_DP<11>")
	)
	(segment
		(start 414.56864 -406.512268)
		(end 414.331658 -406.866852)
		(width 0.14224)
		(layer "In15.Cu")
		(net "P5E_CPU0_P2_RX_BUF_DP<11>")
	)
	(segment
		(start 411.208728 -410.677868)
		(end 411.01518 -410.68752)
		(width 0.14224)
		(layer "In15.Cu")
		(net "P5E_CPU0_P2_RX_BUF_DP<11>")
	)
	(segment
		(start 412.253176 -409.525724)
		(end 411.966156 -409.842208)
		(width 0.14224)
		(layer "In15.Cu")
		(net "P5E_CPU0_P2_RX_BUF_DP<11>")
	)
	(segment
		(start 405.923242 -422.527222)
		(end 405.925528 -422.721024)
		(width 0.14224)
		(layer "In15.Cu")
		(net "P5E_CPU0_P2_RX_BUF_DP<11>")
	)
	(segment
		(start 408.362912 -417.632134)
		(end 408.225752 -417.769294)
		(width 0.14224)
		(layer "In15.Cu")
		(net "P5E_CPU0_P2_RX_BUF_DP<11>")
	)
	(segment
		(start 409.408122 -413.942276)
		(end 409.092654 -414.153096)
		(width 0.14224)
		(layer "In15.Cu")
		(net "P5E_CPU0_P2_RX_BUF_DP<11>")
	)
	(segment
		(start 405.134826 -423.333672)
		(end 405.136858 -423.527474)
		(width 0.14224)
		(layer "In15.Cu")
		(net "P5E_CPU0_P2_RX_BUF_DP<11>")
	)
	(segment
		(start 413.010604 -408.690064)
		(end 412.723584 -409.006548)
		(width 0.14224)
		(layer "In15.Cu")
		(net "P5E_CPU0_P2_RX_BUF_DP<11>")
	)
	(segment
		(start 404.071074 -438.203848)
		(end 404.208488 -438.341262)
		(width 0.14224)
		(layer "In15.Cu")
		(net "P5E_CPU0_P2_RX_BUF_DP<11>")
	)
	(segment
		(start 411.772608 -409.85186)
		(end 411.486096 -410.167836)
		(width 0.14224)
		(layer "In15.Cu")
		(net "P5E_CPU0_P2_RX_BUF_DP<11>")
	)
	(segment
		(start 405.627078 -423.026586)
		(end 405.433022 -423.028618)
		(width 0.14224)
		(layer "In15.Cu")
		(net "P5E_CPU0_P2_RX_BUF_DP<11>")
	)
	(segment
		(start 416.644328 -401.674838)
		(end 416.644328 -401.526756)
		(width 0.14224)
		(layer "In15.Cu")
		(net "P5E_CPU0_P2_RX_BUF_DP<11>")
	)
	(segment
		(start 404.071074 -424.590464)
		(end 404.071074 -438.203848)
		(width 0.14224)
		(layer "In15.Cu")
		(net "P5E_CPU0_P2_RX_BUF_DP<11>")
	)
	(segment
		(start 411.01518 -410.68752)
		(end 410.728668 -411.003496)
		(width 0.14224)
		(layer "In15.Cu")
		(net "P5E_CPU0_P2_RX_BUF_DP<11>")
	)
	(segment
		(start 408.102054 -419.388798)
		(end 407.934668 -419.56482)
		(width 0.14224)
		(layer "In15.Cu")
		(net "P5E_CPU0_P2_RX_BUF_DP<11>")
	)
	(segment
		(start 409.80614 -412.140654)
		(end 409.768802 -412.343092)
		(width 0.14224)
		(layer "In15.Cu")
		(net "P5E_CPU0_P2_RX_BUF_DP<11>")
	)
	(segment
		(start 415.91484 -404.498302)
		(end 414.95853 -405.929084)
		(width 0.14224)
		(layer "In15.Cu")
		(net "P5E_CPU0_P2_RX_BUF_DP<11>")
	)
	(segment
		(start 408.225752 -416.641534)
		(end 408.225752 -417.068254)
		(width 0.14224)
		(layer "In15.Cu")
		(net "P5E_CPU0_P2_RX_BUF_DP<11>")
	)
	(segment
		(start 408.225752 -415.020252)
		(end 408.225752 -415.940494)
		(width 0.14224)
		(layer "In15.Cu")
		(net "P5E_CPU0_P2_RX_BUF_DP<11>")
	)
	(segment
		(start 411.486096 -410.167836)
		(end 411.495748 -410.361384)
		(width 0.14224)
		(layer "In15.Cu")
		(net "P5E_CPU0_P2_RX_BUF_DP<11>")
	)
	(segment
		(start 406.694132 -420.228268)
		(end 406.694132 -421.571928)
		(width 0.14224)
		(layer "In15.Cu")
		(net "P5E_CPU0_P2_RX_BUF_DP<11>")
	)
	(segment
		(start 416.517328 -401.399756)
		(end 416.32759 -401.399756)
		(width 0.14224)
		(layer "In15.Cu")
		(net "P5E_CPU0_P2_RX_BUF_DP<11>")
	)
	(segment
		(start 414.95853 -405.929084)
		(end 414.996376 -406.11933)
		(width 0.14224)
		(layer "In15.Cu")
		(net "P5E_CPU0_P2_RX_BUF_DP<11>")
	)
	(segment
		(start 410.728668 -411.003496)
		(end 410.73832 -411.197044)
		(width 0.14224)
		(layer "In15.Cu")
		(net "P5E_CPU0_P2_RX_BUF_DP<11>")
	)
	(segment
		(start 404.346156 -424.140122)
		(end 404.092918 -424.518836)
		(width 0.14224)
		(layer "In15.Cu")
		(net "P5E_CPU0_P2_RX_BUF_DP<11>")
	)
	(segment
		(start 404.644352 -423.835068)
		(end 404.346156 -424.140122)
		(width 0.14224)
		(layer "In15.Cu")
		(net "P5E_CPU0_P2_RX_BUF_DP<11>")
	)
	(segment
		(start 410.73832 -411.197044)
		(end 410.451554 -411.513528)
		(width 0.14224)
		(layer "In15.Cu")
		(net "P5E_CPU0_P2_RX_BUF_DP<11>")
	)
	(segment
		(start 408.362912 -417.205414)
		(end 408.362912 -417.632134)
		(width 0.14224)
		(layer "In15.Cu")
		(net "P5E_CPU0_P2_RX_BUF_DP<11>")
	)
	(segment
		(start 416.32759 -401.399756)
		(end 416.18535 -401.541996)
		(width 0.14224)
		(layer "In15.Cu")
		(net "P5E_CPU0_P2_RX_BUF_DP<11>")
	)
	(segment
		(start 416.18535 -403.606)
		(end 415.91484 -404.498302)
		(width 0.14224)
		(layer "In15.Cu")
		(net "P5E_CPU0_P2_RX_BUF_DP<11>")
	)
	(segment
		(start 412.243524 -409.332176)
		(end 412.253176 -409.525724)
		(width 0.14224)
		(layer "In15.Cu")
		(net "P5E_CPU0_P2_RX_BUF_DP<11>")
	)
	(segment
		(start 409.757372 -412.469076)
		(end 409.757372 -413.306514)
		(width 0.14224)
		(layer "In15.Cu")
		(net "P5E_CPU0_P2_RX_BUF_DP<11>")
	)
	(segment
		(start 406.577546 -421.857932)
		(end 405.923242 -422.527222)
		(width 0.14224)
		(layer "In15.Cu")
		(net "P5E_CPU0_P2_RX_BUF_DP<11>")
	)
	(segment
		(start 404.599902 -438.341262)
		(end 404.750016 -438.191148)
		(width 0.14224)
		(layer "In15.Cu")
		(net "P5E_CPU0_P2_RX_BUF_DP<11>")
	)
	(segment
		(start 405.433022 -423.028618)
		(end 405.134826 -423.333672)
		(width 0.14224)
		(layer "In15.Cu")
		(net "P5E_CPU0_P2_RX_BUF_DP<11>")
	)
	(segment
		(start 409.092654 -414.153096)
		(end 408.817064 -414.267142)
		(width 0.14224)
		(layer "In15.Cu")
		(net "P5E_CPU0_P2_RX_BUF_DP<11>")
	)
	(segment
		(start 408.225752 -415.940494)
		(end 408.362912 -416.077654)
		(width 0.14224)
		(layer "In15.Cu")
		(net "P5E_CPU0_P2_RX_BUF_DP<11>")
	)
	(segment
		(start 411.966156 -409.842208)
		(end 411.772608 -409.85186)
		(width 0.14224)
		(layer "In15.Cu")
		(net "P5E_CPU0_P2_RX_BUF_DP<11>")
	)
	(segment
		(start 404.208488 -438.341262)
		(end 404.599902 -438.341262)
		(width 0.14224)
		(layer "In15.Cu")
		(net "P5E_CPU0_P2_RX_BUF_DP<11>")
	)
	(segment
		(start 410.451554 -411.513528)
		(end 410.257752 -411.52318)
		(width 0.14224)
		(layer "In15.Cu")
		(net "P5E_CPU0_P2_RX_BUF_DP<11>")
	)
	(segment
		(start 405.925528 -422.721024)
		(end 405.627078 -423.026586)
		(width 0.14224)
		(layer "In15.Cu")
		(net "P5E_CPU0_P2_RX_BUF_DP<11>")
	)
	(segment
		(start 414.758886 -406.474422)
		(end 414.56864 -406.512268)
		(width 0.14224)
		(layer "In15.Cu")
		(net "P5E_CPU0_P2_RX_BUF_DP<11>")
	)
	(segment
		(start 404.750016 -438.191148)
		(end 404.750016 -437.889904)
		(width 0.14224)
		(layer "In15.Cu")
		(net "P5E_CPU0_P2_RX_BUF_DP<11>")
	)
	(segment
		(start 407.734262 -419.70198)
		(end 406.781762 -420.09695)
		(width 0.14224)
		(layer "In15.Cu")
		(net "P5E_CPU0_P2_RX_BUF_DP<11>")
	)
	(segment
		(start 416.644328 -401.526756)
		(end 416.517328 -401.399756)
		(width 0.14224)
		(layer "In15.Cu")
		(net "P5E_CPU0_P2_RX_BUF_DP<11>")
	)
	(segment
		(start 408.362912 -416.504374)
		(end 408.225752 -416.641534)
		(width 0.14224)
		(layer "In15.Cu")
		(net "P5E_CPU0_P2_RX_BUF_DP<11>")
	)
	(segment
		(start 404.838408 -423.833036)
		(end 404.644352 -423.835068)
		(width 0.14224)
		(layer "In15.Cu")
		(net "P5E_CPU0_P2_RX_BUF_DP<11>")
	)
	(segment
		(start 408.362912 -416.077654)
		(end 408.362912 -416.504374)
		(width 0.14224)
		(layer "In15.Cu")
		(net "P5E_CPU0_P2_RX_BUF_DP<11>")
	)
	(segment
		(start 410.257752 -411.52318)
		(end 409.959302 -411.852364)
		(width 0.14224)
		(layer "In15.Cu")
		(net "P5E_CPU0_P2_RX_BUF_DP<11>")
	)
	(segment
		(start 414.996376 -406.11933)
		(end 414.758886 -406.474422)
		(width 0.14224)
		(layer "In15.Cu")
		(net "P5E_CPU0_P2_RX_BUF_DP<11>")
	)
	(segment
		(start 416.18535 -401.541996)
		(end 416.18535 -403.606)
		(width 0.14224)
		(layer "In15.Cu")
		(net "P5E_CPU0_P2_RX_BUF_DP<11>")
	)
	(segment
		(start 409.554934 -413.795464)
		(end 409.408122 -413.942276)
		(width 0.14224)
		(layer "In15.Cu")
		(net "P5E_CPU0_P2_RX_BUF_DP<11>")
	)
	(segment
		(start 411.495748 -410.361384)
		(end 411.208728 -410.677868)
		(width 0.14224)
		(layer "In15.Cu")
		(net "P5E_CPU0_P2_RX_BUF_DP<11>")
	)
	(segment
		(start 405.136858 -423.527474)
		(end 404.838408 -423.833036)
		(width 0.14224)
		(layer "In15.Cu")
		(net "P5E_CPU0_P2_RX_BUF_DP<11>")
	)
	(arc
		(start 408.225752 -419.079172)
		(mid 408.193787 -419.24593)
		(end 408.102054 -419.388798)
		(width 0.14224)
		(layer "In15.Cu")
		(net "P5E_CPU0_P2_RX_BUF_DP<11>")
	)
	(arc
		(start 409.959302 -411.852364)
		(mid 409.920202 -411.902071)
		(end 409.888436 -411.956758)
		(width 0.14224)
		(layer "In15.Cu")
		(net "P5E_CPU0_P2_RX_BUF_DP<11>")
	)
	(arc
		(start 404.092918 -424.518836)
		(mid 404.076677 -424.553026)
		(end 404.071074 -424.590464)
		(width 0.14224)
		(layer "In15.Cu")
		(net "P5E_CPU0_P2_RX_BUF_DP<11>")
	)
	(arc
		(start 408.43073 -414.52546)
		(mid 408.278967 -414.752445)
		(end 408.225752 -415.020252)
		(width 0.14224)
		(layer "In15.Cu")
		(net "P5E_CPU0_P2_RX_BUF_DP<11>")
	)
	(arc
		(start 414.331658 -406.866852)
		(mid 413.896346 -407.46859)
		(end 413.417766 -408.036522)
		(width 0.14224)
		(layer "In15.Cu")
		(net "P5E_CPU0_P2_RX_BUF_DP<11>")
	)
	(arc
		(start 407.934668 -419.56482)
		(mid 407.84165 -419.643897)
		(end 407.734262 -419.70198)
		(width 0.14224)
		(layer "In15.Cu")
		(net "P5E_CPU0_P2_RX_BUF_DP<11>")
	)
	(arc
		(start 408.817064 -414.267142)
		(mid 408.611182 -414.377288)
		(end 408.43073 -414.52546)
		(width 0.14224)
		(layer "In15.Cu")
		(net "P5E_CPU0_P2_RX_BUF_DP<11>")
	)
	(arc
		(start 406.781762 -420.09695)
		(mid 406.717957 -420.149294)
		(end 406.694132 -420.228268)
		(width 0.14224)
		(layer "In15.Cu")
		(net "P5E_CPU0_P2_RX_BUF_DP<11>")
	)
	(arc
		(start 409.821634 -412.09341)
		(mid 409.812279 -412.116504)
		(end 409.80614 -412.140654)
		(width 0.14224)
		(layer "In15.Cu")
		(net "P5E_CPU0_P2_RX_BUF_DP<11>")
	)
	(arc
		(start 409.757372 -413.306514)
		(mid 409.704758 -413.571111)
		(end 409.554934 -413.795464)
		(width 0.14224)
		(layer "In15.Cu")
		(net "P5E_CPU0_P2_RX_BUF_DP<11>")
	)
	(arc
		(start 409.768802 -412.343092)
		(mid 409.760225 -412.405824)
		(end 409.757372 -412.469076)
		(width 0.14224)
		(layer "In15.Cu")
		(net "P5E_CPU0_P2_RX_BUF_DP<11>")
	)
	(arc
		(start 406.694132 -421.571928)
		(mid 406.663871 -421.72636)
		(end 406.577546 -421.857932)
		(width 0.14224)
		(layer "In15.Cu")
		(net "P5E_CPU0_P2_RX_BUF_DP<11>")
	)
	(segment
		(start 415.444432 -401.498054)
		(end 415.305494 -401.359116)
		(width 0.1016)
		(layer "F.Cu")
		(net "P5E_CPU0_P2_RX_BUF_DP<10>")
	)
	(segment
		(start 414.994852 -401.359116)
		(end 414.741614 -401.105878)
		(width 0.1016)
		(layer "F.Cu")
		(net "P5E_CPU0_P2_RX_BUF_DP<10>")
	)
	(segment
		(start 415.444432 -401.674838)
		(end 415.444432 -401.498054)
		(width 0.1016)
		(layer "F.Cu")
		(net "P5E_CPU0_P2_RX_BUF_DP<10>")
	)
	(segment
		(start 414.741614 -399.959322)
		(end 414.829752 -399.871184)
		(width 0.1016)
		(layer "F.Cu")
		(net "P5E_CPU0_P2_RX_BUF_DP<10>")
	)
	(segment
		(start 415.305494 -401.359116)
		(end 414.994852 -401.359116)
		(width 0.1016)
		(layer "F.Cu")
		(net "P5E_CPU0_P2_RX_BUF_DP<10>")
	)
	(segment
		(start 414.829752 -399.871184)
		(end 414.829752 -399.747232)
		(width 0.1016)
		(layer "F.Cu")
		(net "P5E_CPU0_P2_RX_BUF_DP<10>")
	)
	(segment
		(start 414.829752 -399.747232)
		(end 414.745678 -399.663158)
		(width 0.1016)
		(layer "F.Cu")
		(net "P5E_CPU0_P2_RX_BUF_DP<10>")
	)
	(segment
		(start 414.741614 -401.105878)
		(end 414.741614 -399.959322)
		(width 0.1016)
		(layer "F.Cu")
		(net "P5E_CPU0_P2_RX_BUF_DP<10>")
	)
	(segment
		(start 411.904688 -407.967688)
		(end 412.782512 -407.090118)
		(width 0.14224)
		(layer "In15.Cu")
		(net "P5E_CPU0_P2_RX_BUF_DP<10>")
	)
	(segment
		(start 403.411944 -422.33342)
		(end 403.630892 -421.967406)
		(width 0.14224)
		(layer "In15.Cu")
		(net "P5E_CPU0_P2_RX_BUF_DP<10>")
	)
	(segment
		(start 408.016964 -411.130242)
		(end 408.369008 -410.88945)
		(width 0.14224)
		(layer "In15.Cu")
		(net "P5E_CPU0_P2_RX_BUF_DP<10>")
	)
	(segment
		(start 406.694132 -413.306514)
		(end 406.694132 -412.488888)
		(width 0.14224)
		(layer "In15.Cu")
		(net "P5E_CPU0_P2_RX_BUF_DP<10>")
	)
	(segment
		(start 408.559762 -410.925264)
		(end 408.912314 -410.684218)
		(width 0.14224)
		(layer "In15.Cu")
		(net "P5E_CPU0_P2_RX_BUF_DP<10>")
	)
	(segment
		(start 413.222186 -406.704038)
		(end 413.468058 -406.354788)
		(width 0.14224)
		(layer "In15.Cu")
		(net "P5E_CPU0_P2_RX_BUF_DP<10>")
	)
	(segment
		(start 403.239732 -422.887902)
		(end 403.458934 -422.521634)
		(width 0.14224)
		(layer "In15.Cu")
		(net "P5E_CPU0_P2_RX_BUF_DP<10>")
	)
	(segment
		(start 405.162512 -418.925502)
		(end 405.162512 -417.797234)
		(width 0.14224)
		(layer "In15.Cu")
		(net "P5E_CPU0_P2_RX_BUF_DP<10>")
	)
	(segment
		(start 402.75002 -436.889906)
		(end 402.75002 -437.19115)
		(width 0.14224)
		(layer "In15.Cu")
		(net "P5E_CPU0_P2_RX_BUF_DP<10>")
	)
	(segment
		(start 411.602682 -408.46375)
		(end 411.904688 -408.161744)
		(width 0.14224)
		(layer "In15.Cu")
		(net "P5E_CPU0_P2_RX_BUF_DP<10>")
	)
	(segment
		(start 408.369008 -410.88945)
		(end 408.559762 -410.925264)
		(width 0.14224)
		(layer "In15.Cu")
		(net "P5E_CPU0_P2_RX_BUF_DP<10>")
	)
	(segment
		(start 403.051518 -422.935146)
		(end 403.239732 -422.887902)
		(width 0.14224)
		(layer "In15.Cu")
		(net "P5E_CPU0_P2_RX_BUF_DP<10>")
	)
	(segment
		(start 402.213318 -437.341264)
		(end 402.071078 -437.199024)
		(width 0.14224)
		(layer "In15.Cu")
		(net "P5E_CPU0_P2_RX_BUF_DP<10>")
	)
	(segment
		(start 409.843478 -410.047694)
		(end 409.879292 -409.85694)
		(width 0.14224)
		(layer "In15.Cu")
		(net "P5E_CPU0_P2_RX_BUF_DP<10>")
	)
	(segment
		(start 405.162512 -417.797234)
		(end 405.299672 -417.660074)
		(width 0.14224)
		(layer "In15.Cu")
		(net "P5E_CPU0_P2_RX_BUF_DP<10>")
	)
	(segment
		(start 403.630892 -421.967406)
		(end 403.630892 -420.339012)
		(width 0.14224)
		(layer "In15.Cu")
		(net "P5E_CPU0_P2_RX_BUF_DP<10>")
	)
	(segment
		(start 406.029414 -414.153096)
		(end 406.344882 -413.942276)
		(width 0.14224)
		(layer "In15.Cu")
		(net "P5E_CPU0_P2_RX_BUF_DP<10>")
	)
	(segment
		(start 403.458934 -422.521634)
		(end 403.411944 -422.33342)
		(width 0.14224)
		(layer "In15.Cu")
		(net "P5E_CPU0_P2_RX_BUF_DP<10>")
	)
	(segment
		(start 411.40888 -408.46375)
		(end 411.602682 -408.46375)
		(width 0.14224)
		(layer "In15.Cu")
		(net "P5E_CPU0_P2_RX_BUF_DP<10>")
	)
	(segment
		(start 402.071078 -437.199024)
		(end 402.071078 -424.945556)
		(width 0.14224)
		(layer "In15.Cu")
		(net "P5E_CPU0_P2_RX_BUF_DP<10>")
	)
	(segment
		(start 405.162512 -416.669474)
		(end 405.299672 -416.532314)
		(width 0.14224)
		(layer "In15.Cu")
		(net "P5E_CPU0_P2_RX_BUF_DP<10>")
	)
	(segment
		(start 405.299672 -417.660074)
		(end 405.299672 -417.233354)
		(width 0.14224)
		(layer "In15.Cu")
		(net "P5E_CPU0_P2_RX_BUF_DP<10>")
	)
	(segment
		(start 415.127694 -401.399756)
		(end 415.317432 -401.399756)
		(width 0.14224)
		(layer "In15.Cu")
		(net "P5E_CPU0_P2_RX_BUF_DP<10>")
	)
	(segment
		(start 413.468058 -406.354788)
		(end 413.435038 -406.16378)
		(width 0.14224)
		(layer "In15.Cu")
		(net "P5E_CPU0_P2_RX_BUF_DP<10>")
	)
	(segment
		(start 406.344882 -413.942276)
		(end 406.491694 -413.795464)
		(width 0.14224)
		(layer "In15.Cu")
		(net "P5E_CPU0_P2_RX_BUF_DP<10>")
	)
	(segment
		(start 402.14296 -424.64228)
		(end 402.409152 -424.111166)
		(width 0.14224)
		(layer "In15.Cu")
		(net "P5E_CPU0_P2_RX_BUF_DP<10>")
	)
	(segment
		(start 402.75002 -437.19115)
		(end 402.599906 -437.341264)
		(width 0.14224)
		(layer "In15.Cu")
		(net "P5E_CPU0_P2_RX_BUF_DP<10>")
	)
	(segment
		(start 405.753824 -414.267142)
		(end 406.029414 -414.153096)
		(width 0.14224)
		(layer "In15.Cu")
		(net "P5E_CPU0_P2_RX_BUF_DP<10>")
	)
	(segment
		(start 409.490926 -410.28874)
		(end 409.843478 -410.047694)
		(width 0.14224)
		(layer "In15.Cu")
		(net "P5E_CPU0_P2_RX_BUF_DP<10>")
	)
	(segment
		(start 402.731732 -423.469308)
		(end 402.732748 -423.46753)
		(width 0.14224)
		(layer "In15.Cu")
		(net "P5E_CPU0_P2_RX_BUF_DP<10>")
	)
	(segment
		(start 408.912314 -410.684218)
		(end 408.948128 -410.493718)
		(width 0.14224)
		(layer "In15.Cu")
		(net "P5E_CPU0_P2_RX_BUF_DP<10>")
	)
	(segment
		(start 407.61666 -411.451552)
		(end 407.915618 -411.206188)
		(width 0.14224)
		(layer "In15.Cu")
		(net "P5E_CPU0_P2_RX_BUF_DP<10>")
	)
	(segment
		(start 415.444432 -401.526756)
		(end 415.444432 -401.674838)
		(width 0.14224)
		(layer "In15.Cu")
		(net "P5E_CPU0_P2_RX_BUF_DP<10>")
	)
	(segment
		(start 414.985454 -403.962108)
		(end 414.985454 -401.541996)
		(width 0.14224)
		(layer "In15.Cu")
		(net "P5E_CPU0_P2_RX_BUF_DP<10>")
	)
	(segment
		(start 415.317432 -401.399756)
		(end 415.444432 -401.526756)
		(width 0.14224)
		(layer "In15.Cu")
		(net "P5E_CPU0_P2_RX_BUF_DP<10>")
	)
	(segment
		(start 408.948128 -410.493718)
		(end 409.300172 -410.252926)
		(width 0.14224)
		(layer "In15.Cu")
		(net "P5E_CPU0_P2_RX_BUF_DP<10>")
	)
	(segment
		(start 413.435038 -406.16378)
		(end 414.985454 -403.962108)
		(width 0.14224)
		(layer "In15.Cu")
		(net "P5E_CPU0_P2_RX_BUF_DP<10>")
	)
	(segment
		(start 410.61132 -409.26131)
		(end 410.805122 -409.26131)
		(width 0.14224)
		(layer "In15.Cu")
		(net "P5E_CPU0_P2_RX_BUF_DP<10>")
	)
	(segment
		(start 409.879292 -409.85694)
		(end 410.309568 -409.562808)
		(width 0.14224)
		(layer "In15.Cu")
		(net "P5E_CPU0_P2_RX_BUF_DP<10>")
	)
	(segment
		(start 402.599906 -437.341264)
		(end 402.213318 -437.341264)
		(width 0.14224)
		(layer "In15.Cu")
		(net "P5E_CPU0_P2_RX_BUF_DP<10>")
	)
	(segment
		(start 410.309568 -409.562808)
		(end 410.61132 -409.26131)
		(width 0.14224)
		(layer "In15.Cu")
		(net "P5E_CPU0_P2_RX_BUF_DP<10>")
	)
	(segment
		(start 405.299672 -416.532314)
		(end 405.299672 -416.105594)
		(width 0.14224)
		(layer "In15.Cu")
		(net "P5E_CPU0_P2_RX_BUF_DP<10>")
	)
	(segment
		(start 411.107128 -408.959304)
		(end 411.107128 -408.765248)
		(width 0.14224)
		(layer "In15.Cu")
		(net "P5E_CPU0_P2_RX_BUF_DP<10>")
	)
	(segment
		(start 406.720294 -412.365952)
		(end 406.79243 -412.203138)
		(width 0.14224)
		(layer "In15.Cu")
		(net "P5E_CPU0_P2_RX_BUF_DP<10>")
	)
	(segment
		(start 403.820884 -420.054786)
		(end 404.737824 -419.674294)
		(width 0.14224)
		(layer "In15.Cu")
		(net "P5E_CPU0_P2_RX_BUF_DP<10>")
	)
	(segment
		(start 414.985454 -401.541996)
		(end 415.127694 -401.399756)
		(width 0.14224)
		(layer "In15.Cu")
		(net "P5E_CPU0_P2_RX_BUF_DP<10>")
	)
	(segment
		(start 405.162512 -417.096194)
		(end 405.162512 -416.669474)
		(width 0.14224)
		(layer "In15.Cu")
		(net "P5E_CPU0_P2_RX_BUF_DP<10>")
	)
	(segment
		(start 412.782512 -407.090118)
		(end 413.030924 -406.737312)
		(width 0.14224)
		(layer "In15.Cu")
		(net "P5E_CPU0_P2_RX_BUF_DP<10>")
	)
	(segment
		(start 402.732748 -423.46753)
		(end 403.051518 -422.935146)
		(width 0.14224)
		(layer "In15.Cu")
		(net "P5E_CPU0_P2_RX_BUF_DP<10>")
	)
	(segment
		(start 405.299672 -417.233354)
		(end 405.162512 -417.096194)
		(width 0.14224)
		(layer "In15.Cu")
		(net "P5E_CPU0_P2_RX_BUF_DP<10>")
	)
	(segment
		(start 402.409152 -424.111166)
		(end 402.593556 -424.050206)
		(width 0.14224)
		(layer "In15.Cu")
		(net "P5E_CPU0_P2_RX_BUF_DP<10>")
	)
	(segment
		(start 411.904688 -408.161744)
		(end 411.904688 -407.967688)
		(width 0.14224)
		(layer "In15.Cu")
		(net "P5E_CPU0_P2_RX_BUF_DP<10>")
	)
	(segment
		(start 411.107128 -408.765248)
		(end 411.40888 -408.46375)
		(width 0.14224)
		(layer "In15.Cu")
		(net "P5E_CPU0_P2_RX_BUF_DP<10>")
	)
	(segment
		(start 405.026368 -419.38321)
		(end 405.118316 -419.154356)
		(width 0.14224)
		(layer "In15.Cu")
		(net "P5E_CPU0_P2_RX_BUF_DP<10>")
	)
	(segment
		(start 402.784818 -423.668444)
		(end 402.723604 -423.484294)
		(width 0.14224)
		(layer "In15.Cu")
		(net "P5E_CPU0_P2_RX_BUF_DP<10>")
	)
	(segment
		(start 413.030924 -406.737312)
		(end 413.222186 -406.704038)
		(width 0.14224)
		(layer "In15.Cu")
		(net "P5E_CPU0_P2_RX_BUF_DP<10>")
	)
	(segment
		(start 410.805122 -409.26131)
		(end 411.107128 -408.959304)
		(width 0.14224)
		(layer "In15.Cu")
		(net "P5E_CPU0_P2_RX_BUF_DP<10>")
	)
	(segment
		(start 402.723604 -423.484294)
		(end 402.72843 -423.474896)
		(width 0.14224)
		(layer "In15.Cu")
		(net "P5E_CPU0_P2_RX_BUF_DP<10>")
	)
	(segment
		(start 409.300172 -410.252926)
		(end 409.490926 -410.28874)
		(width 0.14224)
		(layer "In15.Cu")
		(net "P5E_CPU0_P2_RX_BUF_DP<10>")
	)
	(segment
		(start 405.162512 -415.968434)
		(end 405.162512 -415.020252)
		(width 0.14224)
		(layer "In15.Cu")
		(net "P5E_CPU0_P2_RX_BUF_DP<10>")
	)
	(segment
		(start 405.299672 -416.105594)
		(end 405.162512 -415.968434)
		(width 0.14224)
		(layer "In15.Cu")
		(net "P5E_CPU0_P2_RX_BUF_DP<10>")
	)
	(segment
		(start 402.593556 -424.050206)
		(end 402.784818 -423.668444)
		(width 0.14224)
		(layer "In15.Cu")
		(net "P5E_CPU0_P2_RX_BUF_DP<10>")
	)
	(arc
		(start 405.118316 -419.154356)
		(mid 405.151407 -419.042051)
		(end 405.162512 -418.925502)
		(width 0.14224)
		(layer "In15.Cu")
		(net "P5E_CPU0_P2_RX_BUF_DP<10>")
	)
	(arc
		(start 402.72843 -423.474896)
		(mid 402.730046 -423.472082)
		(end 402.731732 -423.469308)
		(width 0.14224)
		(layer "In15.Cu")
		(net "P5E_CPU0_P2_RX_BUF_DP<10>")
	)
	(arc
		(start 407.300938 -411.71622)
		(mid 407.458099 -411.58305)
		(end 407.61666 -411.451552)
		(width 0.14224)
		(layer "In15.Cu")
		(net "P5E_CPU0_P2_RX_BUF_DP<10>")
	)
	(arc
		(start 406.491694 -413.795464)
		(mid 406.641534 -413.571118)
		(end 406.694132 -413.306514)
		(width 0.14224)
		(layer "In15.Cu")
		(net "P5E_CPU0_P2_RX_BUF_DP<10>")
	)
	(arc
		(start 406.866598 -412.100268)
		(mid 407.082269 -411.906549)
		(end 407.300938 -411.71622)
		(width 0.14224)
		(layer "In15.Cu")
		(net "P5E_CPU0_P2_RX_BUF_DP<10>")
	)
	(arc
		(start 402.071078 -424.945556)
		(mid 402.089235 -424.789703)
		(end 402.14296 -424.64228)
		(width 0.14224)
		(layer "In15.Cu")
		(net "P5E_CPU0_P2_RX_BUF_DP<10>")
	)
	(arc
		(start 405.162512 -415.020252)
		(mid 405.215741 -414.752451)
		(end 405.36749 -414.52546)
		(width 0.14224)
		(layer "In15.Cu")
		(net "P5E_CPU0_P2_RX_BUF_DP<10>")
	)
	(arc
		(start 406.79243 -412.203138)
		(mid 406.824152 -412.147834)
		(end 406.866598 -412.100268)
		(width 0.14224)
		(layer "In15.Cu")
		(net "P5E_CPU0_P2_RX_BUF_DP<10>")
	)
	(arc
		(start 403.630892 -420.339012)
		(mid 403.682764 -420.168073)
		(end 403.820884 -420.054786)
		(width 0.14224)
		(layer "In15.Cu")
		(net "P5E_CPU0_P2_RX_BUF_DP<10>")
	)
	(arc
		(start 404.737824 -419.674294)
		(mid 404.91142 -419.557822)
		(end 405.026368 -419.38321)
		(width 0.14224)
		(layer "In15.Cu")
		(net "P5E_CPU0_P2_RX_BUF_DP<10>")
	)
	(arc
		(start 405.36749 -414.52546)
		(mid 405.54796 -414.377314)
		(end 405.753824 -414.267142)
		(width 0.14224)
		(layer "In15.Cu")
		(net "P5E_CPU0_P2_RX_BUF_DP<10>")
	)
	(arc
		(start 406.694132 -412.488888)
		(mid 406.700778 -412.426052)
		(end 406.720294 -412.365952)
		(width 0.14224)
		(layer "In15.Cu")
		(net "P5E_CPU0_P2_RX_BUF_DP<10>")
	)
	(arc
		(start 407.915618 -411.206188)
		(mid 407.965463 -411.16711)
		(end 408.016964 -411.130242)
		(width 0.14224)
		(layer "In15.Cu")
		(net "P5E_CPU0_P2_RX_BUF_DP<10>")
	)
	(segment
		(start 402.994876 -401.359116)
		(end 403.305518 -401.359116)
		(width 0.1016)
		(layer "F.Cu")
		(net "P5E_CPU0_P2_RX_BUF_DP<0>")
	)
	(segment
		(start 402.830284 -399.870676)
		(end 402.719286 -399.981674)
		(width 0.1016)
		(layer "F.Cu")
		(net "P5E_CPU0_P2_RX_BUF_DP<0>")
	)
	(segment
		(start 402.719286 -399.981674)
		(end 402.719286 -401.083526)
		(width 0.1016)
		(layer "F.Cu")
		(net "P5E_CPU0_P2_RX_BUF_DP<0>")
	)
	(segment
		(start 403.444202 -401.4978)
		(end 403.444202 -401.674838)
		(width 0.1016)
		(layer "F.Cu")
		(net "P5E_CPU0_P2_RX_BUF_DP<0>")
	)
	(segment
		(start 402.745702 -399.663158)
		(end 402.830284 -399.74774)
		(width 0.1016)
		(layer "F.Cu")
		(net "P5E_CPU0_P2_RX_BUF_DP<0>")
	)
	(segment
		(start 402.719286 -401.083526)
		(end 402.994876 -401.359116)
		(width 0.1016)
		(layer "F.Cu")
		(net "P5E_CPU0_P2_RX_BUF_DP<0>")
	)
	(segment
		(start 403.305518 -401.359116)
		(end 403.444202 -401.4978)
		(width 0.1016)
		(layer "F.Cu")
		(net "P5E_CPU0_P2_RX_BUF_DP<0>")
	)
	(segment
		(start 402.830284 -399.74774)
		(end 402.830284 -399.870676)
		(width 0.1016)
		(layer "F.Cu")
		(net "P5E_CPU0_P2_RX_BUF_DP<0>")
	)
	(segment
		(start 403.153372 -401.384008)
		(end 403.444202 -401.674838)
		(width 0.14224)
		(layer "In15.Cu")
		(net "P5E_CPU0_P2_RX_BUF_DP<0>")
	)
	(segment
		(start 380.237746 -429.56099)
		(end 379.610366 -428.93361)
		(width 0.14224)
		(layer "In15.Cu")
		(net "P5E_CPU0_P2_RX_BUF_DP<0>")
	)
	(segment
		(start 376.08637 -412.32074)
		(end 376.211592 -412.019242)
		(width 0.14224)
		(layer "In15.Cu")
		(net "P5E_CPU0_P2_RX_BUF_DP<0>")
	)
	(segment
		(start 375.397014 -414.153096)
		(end 375.712482 -413.942276)
		(width 0.14224)
		(layer "In15.Cu")
		(net "P5E_CPU0_P2_RX_BUF_DP<0>")
	)
	(segment
		(start 381.749808 -437.19115)
		(end 381.603758 -437.3372)
		(width 0.14224)
		(layer "In15.Cu")
		(net "P5E_CPU0_P2_RX_BUF_DP<0>")
	)
	(segment
		(start 381.603758 -437.3372)
		(end 381.077978 -437.3372)
		(width 0.14224)
		(layer "In15.Cu")
		(net "P5E_CPU0_P2_RX_BUF_DP<0>")
	)
	(segment
		(start 374.667272 -417.026344)
		(end 374.530112 -416.889184)
		(width 0.14224)
		(layer "In15.Cu")
		(net "P5E_CPU0_P2_RX_BUF_DP<0>")
	)
	(segment
		(start 401.987766 -401.690332)
		(end 402.836126 -401.384008)
		(width 0.14224)
		(layer "In15.Cu")
		(net "P5E_CPU0_P2_RX_BUF_DP<0>")
	)
	(segment
		(start 402.836126 -401.384008)
		(end 403.153372 -401.384008)
		(width 0.14224)
		(layer "In15.Cu")
		(net "P5E_CPU0_P2_RX_BUF_DP<0>")
	)
	(segment
		(start 381.749808 -436.889906)
		(end 381.749808 -437.19115)
		(width 0.14224)
		(layer "In15.Cu")
		(net "P5E_CPU0_P2_RX_BUF_DP<0>")
	)
	(segment
		(start 378.316998 -427.640242)
		(end 378.0155 -427.338744)
		(width 0.14224)
		(layer "In15.Cu")
		(net "P5E_CPU0_P2_RX_BUF_DP<0>")
	)
	(segment
		(start 376.061732 -413.306514)
		(end 376.061732 -412.44393)
		(width 0.14224)
		(layer "In15.Cu")
		(net "P5E_CPU0_P2_RX_BUF_DP<0>")
	)
	(segment
		(start 372.998492 -422.066212)
		(end 372.998492 -420.211504)
		(width 0.14224)
		(layer "In15.Cu")
		(net "P5E_CPU0_P2_RX_BUF_DP<0>")
	)
	(segment
		(start 380.590044 -436.849266)
		(end 380.590044 -430.411636)
		(width 0.14224)
		(layer "In15.Cu")
		(net "P5E_CPU0_P2_RX_BUF_DP<0>")
	)
	(segment
		(start 374.667272 -416.325304)
		(end 374.667272 -415.898584)
		(width 0.14224)
		(layer "In15.Cu")
		(net "P5E_CPU0_P2_RX_BUF_DP<0>")
	)
	(segment
		(start 378.0155 -427.144688)
		(end 377.713494 -426.842682)
		(width 0.14224)
		(layer "In15.Cu")
		(net "P5E_CPU0_P2_RX_BUF_DP<0>")
	)
	(segment
		(start 376.722894 -426.046138)
		(end 376.722894 -425.852082)
		(width 0.14224)
		(layer "In15.Cu")
		(net "P5E_CPU0_P2_RX_BUF_DP<0>")
	)
	(segment
		(start 375.429526 -424.75277)
		(end 375.128028 -424.451272)
		(width 0.14224)
		(layer "In15.Cu")
		(net "P5E_CPU0_P2_RX_BUF_DP<0>")
	)
	(segment
		(start 373.076724 -420.094664)
		(end 374.170702 -419.641274)
		(width 0.14224)
		(layer "In15.Cu")
		(net "P5E_CPU0_P2_RX_BUF_DP<0>")
	)
	(segment
		(start 378.972318 -410.527246)
		(end 379.153674 -410.595826)
		(width 0.14224)
		(layer "In15.Cu")
		(net "P5E_CPU0_P2_RX_BUF_DP<0>")
	)
	(segment
		(start 386.128514 -407.356818)
		(end 395.078204 -404.119842)
		(width 0.14224)
		(layer "In15.Cu")
		(net "P5E_CPU0_P2_RX_BUF_DP<0>")
	)
	(segment
		(start 377.519438 -426.842682)
		(end 376.722894 -426.046138)
		(width 0.14224)
		(layer "In15.Cu")
		(net "P5E_CPU0_P2_RX_BUF_DP<0>")
	)
	(segment
		(start 375.712482 -413.942276)
		(end 375.859294 -413.795464)
		(width 0.14224)
		(layer "In15.Cu")
		(net "P5E_CPU0_P2_RX_BUF_DP<0>")
	)
	(segment
		(start 374.530112 -416.889184)
		(end 374.530112 -416.462464)
		(width 0.14224)
		(layer "In15.Cu")
		(net "P5E_CPU0_P2_RX_BUF_DP<0>")
	)
	(segment
		(start 374.826022 -423.95521)
		(end 374.631966 -423.95521)
		(width 0.14224)
		(layer "In15.Cu")
		(net "P5E_CPU0_P2_RX_BUF_DP<0>")
	)
	(segment
		(start 376.420888 -425.550076)
		(end 376.226832 -425.550076)
		(width 0.14224)
		(layer "In15.Cu")
		(net "P5E_CPU0_P2_RX_BUF_DP<0>")
	)
	(segment
		(start 375.925334 -425.248578)
		(end 375.925334 -425.054776)
		(width 0.14224)
		(layer "In15.Cu")
		(net "P5E_CPU0_P2_RX_BUF_DP<0>")
	)
	(segment
		(start 375.128028 -424.257216)
		(end 374.826022 -423.95521)
		(width 0.14224)
		(layer "In15.Cu")
		(net "P5E_CPU0_P2_RX_BUF_DP<0>")
	)
	(segment
		(start 379.611382 -410.238194)
		(end 384.72237 -407.928064)
		(width 0.14224)
		(layer "In15.Cu")
		(net "P5E_CPU0_P2_RX_BUF_DP<0>")
	)
	(segment
		(start 379.610366 -428.93361)
		(end 379.610366 -428.739808)
		(width 0.14224)
		(layer "In15.Cu")
		(net "P5E_CPU0_P2_RX_BUF_DP<0>")
	)
	(segment
		(start 375.925334 -425.054776)
		(end 375.623328 -424.75277)
		(width 0.14224)
		(layer "In15.Cu")
		(net "P5E_CPU0_P2_RX_BUF_DP<0>")
	)
	(segment
		(start 374.631966 -423.95521)
		(end 373.179086 -422.50233)
		(width 0.14224)
		(layer "In15.Cu")
		(net "P5E_CPU0_P2_RX_BUF_DP<0>")
	)
	(segment
		(start 376.285506 -411.917896)
		(end 376.679968 -411.583124)
		(width 0.14224)
		(layer "In15.Cu")
		(net "P5E_CPU0_P2_RX_BUF_DP<0>")
	)
	(segment
		(start 379.114558 -428.437802)
		(end 378.81306 -428.136304)
		(width 0.14224)
		(layer "In15.Cu")
		(net "P5E_CPU0_P2_RX_BUF_DP<0>")
	)
	(segment
		(start 374.530112 -416.462464)
		(end 374.667272 -416.325304)
		(width 0.14224)
		(layer "In15.Cu")
		(net "P5E_CPU0_P2_RX_BUF_DP<0>")
	)
	(segment
		(start 376.226832 -425.550076)
		(end 375.925334 -425.248578)
		(width 0.14224)
		(layer "In15.Cu")
		(net "P5E_CPU0_P2_RX_BUF_DP<0>")
	)
	(segment
		(start 374.667272 -415.898584)
		(end 374.530112 -415.761424)
		(width 0.14224)
		(layer "In15.Cu")
		(net "P5E_CPU0_P2_RX_BUF_DP<0>")
	)
	(segment
		(start 376.722894 -425.852082)
		(end 376.420888 -425.550076)
		(width 0.14224)
		(layer "In15.Cu")
		(net "P5E_CPU0_P2_RX_BUF_DP<0>")
	)
	(segment
		(start 376.789696 -411.513782)
		(end 378.972318 -410.527246)
		(width 0.14224)
		(layer "In15.Cu")
		(net "P5E_CPU0_P2_RX_BUF_DP<0>")
	)
	(segment
		(start 379.610366 -428.739808)
		(end 379.30836 -428.437802)
		(width 0.14224)
		(layer "In15.Cu")
		(net "P5E_CPU0_P2_RX_BUF_DP<0>")
	)
	(segment
		(start 375.121424 -414.267142)
		(end 375.397014 -414.153096)
		(width 0.14224)
		(layer "In15.Cu")
		(net "P5E_CPU0_P2_RX_BUF_DP<0>")
	)
	(segment
		(start 375.623328 -424.75277)
		(end 375.429526 -424.75277)
		(width 0.14224)
		(layer "In15.Cu")
		(net "P5E_CPU0_P2_RX_BUF_DP<0>")
	)
	(segment
		(start 375.128028 -424.451272)
		(end 375.128028 -424.257216)
		(width 0.14224)
		(layer "In15.Cu")
		(net "P5E_CPU0_P2_RX_BUF_DP<0>")
	)
	(segment
		(start 395.200632 -404.0886)
		(end 395.914626 -403.980142)
		(width 0.14224)
		(layer "In15.Cu")
		(net "P5E_CPU0_P2_RX_BUF_DP<0>")
	)
	(segment
		(start 396.614396 -403.801834)
		(end 400.355308 -402.449284)
		(width 0.14224)
		(layer "In15.Cu")
		(net "P5E_CPU0_P2_RX_BUF_DP<0>")
	)
	(segment
		(start 381.077978 -437.3372)
		(end 380.590044 -436.849266)
		(width 0.14224)
		(layer "In15.Cu")
		(net "P5E_CPU0_P2_RX_BUF_DP<0>")
	)
	(segment
		(start 379.30836 -428.437802)
		(end 379.114558 -428.437802)
		(width 0.14224)
		(layer "In15.Cu")
		(net "P5E_CPU0_P2_RX_BUF_DP<0>")
	)
	(segment
		(start 378.511054 -427.640242)
		(end 378.316998 -427.640242)
		(width 0.14224)
		(layer "In15.Cu")
		(net "P5E_CPU0_P2_RX_BUF_DP<0>")
	)
	(segment
		(start 374.530112 -415.761424)
		(end 374.530112 -415.020252)
		(width 0.14224)
		(layer "In15.Cu")
		(net "P5E_CPU0_P2_RX_BUF_DP<0>")
	)
	(segment
		(start 377.713494 -426.842682)
		(end 377.519438 -426.842682)
		(width 0.14224)
		(layer "In15.Cu")
		(net "P5E_CPU0_P2_RX_BUF_DP<0>")
	)
	(segment
		(start 378.81306 -427.942248)
		(end 378.511054 -427.640242)
		(width 0.14224)
		(layer "In15.Cu")
		(net "P5E_CPU0_P2_RX_BUF_DP<0>")
	)
	(segment
		(start 374.530112 -419.103302)
		(end 374.530112 -417.590224)
		(width 0.14224)
		(layer "In15.Cu")
		(net "P5E_CPU0_P2_RX_BUF_DP<0>")
	)
	(segment
		(start 378.0155 -427.338744)
		(end 378.0155 -427.144688)
		(width 0.14224)
		(layer "In15.Cu")
		(net "P5E_CPU0_P2_RX_BUF_DP<0>")
	)
	(segment
		(start 374.667272 -417.453064)
		(end 374.667272 -417.026344)
		(width 0.14224)
		(layer "In15.Cu")
		(net "P5E_CPU0_P2_RX_BUF_DP<0>")
	)
	(segment
		(start 374.530112 -417.590224)
		(end 374.667272 -417.453064)
		(width 0.14224)
		(layer "In15.Cu")
		(net "P5E_CPU0_P2_RX_BUF_DP<0>")
	)
	(segment
		(start 378.81306 -428.136304)
		(end 378.81306 -427.942248)
		(width 0.14224)
		(layer "In15.Cu")
		(net "P5E_CPU0_P2_RX_BUF_DP<0>")
	)
	(segment
		(start 379.542802 -410.420058)
		(end 379.611382 -410.238194)
		(width 0.14224)
		(layer "In15.Cu")
		(net "P5E_CPU0_P2_RX_BUF_DP<0>")
	)
	(segment
		(start 400.472402 -402.40077)
		(end 401.72005 -401.816824)
		(width 0.14224)
		(layer "In15.Cu")
		(net "P5E_CPU0_P2_RX_BUF_DP<0>")
	)
	(segment
		(start 379.153674 -410.595826)
		(end 379.542802 -410.420058)
		(width 0.14224)
		(layer "In15.Cu")
		(net "P5E_CPU0_P2_RX_BUF_DP<0>")
	)
	(arc
		(start 395.914626 -403.980142)
		(mid 396.268915 -403.908272)
		(end 396.614396 -403.801834)
		(width 0.14224)
		(layer "In15.Cu")
		(net "P5E_CPU0_P2_RX_BUF_DP<0>")
	)
	(arc
		(start 374.170702 -419.641274)
		(mid 374.431954 -419.426778)
		(end 374.530112 -419.103302)
		(width 0.14224)
		(layer "In15.Cu")
		(net "P5E_CPU0_P2_RX_BUF_DP<0>")
	)
	(arc
		(start 401.72005 -401.816824)
		(mid 401.776986 -401.789081)
		(end 401.83308 -401.759674)
		(width 0.14224)
		(layer "In15.Cu")
		(net "P5E_CPU0_P2_RX_BUF_DP<0>")
	)
	(arc
		(start 372.998492 -420.211504)
		(mid 373.019845 -420.141176)
		(end 373.076724 -420.094664)
		(width 0.14224)
		(layer "In15.Cu")
		(net "P5E_CPU0_P2_RX_BUF_DP<0>")
	)
	(arc
		(start 374.73509 -414.52546)
		(mid 374.91556 -414.377314)
		(end 375.121424 -414.267142)
		(width 0.14224)
		(layer "In15.Cu")
		(net "P5E_CPU0_P2_RX_BUF_DP<0>")
	)
	(arc
		(start 384.72237 -407.928064)
		(mid 385.41991 -407.628823)
		(end 386.128514 -407.356818)
		(width 0.14224)
		(layer "In15.Cu")
		(net "P5E_CPU0_P2_RX_BUF_DP<0>")
	)
	(arc
		(start 376.679968 -411.583124)
		(mid 376.73241 -411.544618)
		(end 376.789696 -411.513782)
		(width 0.14224)
		(layer "In15.Cu")
		(net "P5E_CPU0_P2_RX_BUF_DP<0>")
	)
	(arc
		(start 376.211592 -412.019242)
		(mid 376.242509 -411.964162)
		(end 376.285506 -411.917896)
		(width 0.14224)
		(layer "In15.Cu")
		(net "P5E_CPU0_P2_RX_BUF_DP<0>")
	)
	(arc
		(start 401.83308 -401.759674)
		(mid 401.909144 -401.722151)
		(end 401.987766 -401.690332)
		(width 0.14224)
		(layer "In15.Cu")
		(net "P5E_CPU0_P2_RX_BUF_DP<0>")
	)
	(arc
		(start 374.530112 -415.020252)
		(mid 374.583341 -414.752451)
		(end 374.73509 -414.52546)
		(width 0.14224)
		(layer "In15.Cu")
		(net "P5E_CPU0_P2_RX_BUF_DP<0>")
	)
	(arc
		(start 380.590044 -430.411636)
		(mid 380.49849 -429.951275)
		(end 380.237746 -429.56099)
		(width 0.14224)
		(layer "In15.Cu")
		(net "P5E_CPU0_P2_RX_BUF_DP<0>")
	)
	(arc
		(start 376.061732 -412.44393)
		(mid 376.067976 -412.38112)
		(end 376.08637 -412.32074)
		(width 0.14224)
		(layer "In15.Cu")
		(net "P5E_CPU0_P2_RX_BUF_DP<0>")
	)
	(arc
		(start 400.355308 -402.449284)
		(mid 400.414409 -402.426364)
		(end 400.472402 -402.40077)
		(width 0.14224)
		(layer "In15.Cu")
		(net "P5E_CPU0_P2_RX_BUF_DP<0>")
	)
	(arc
		(start 375.859294 -413.795464)
		(mid 376.009134 -413.571118)
		(end 376.061732 -413.306514)
		(width 0.14224)
		(layer "In15.Cu")
		(net "P5E_CPU0_P2_RX_BUF_DP<0>")
	)
	(arc
		(start 373.179086 -422.50233)
		(mid 373.045442 -422.302223)
		(end 372.998492 -422.066212)
		(width 0.14224)
		(layer "In15.Cu")
		(net "P5E_CPU0_P2_RX_BUF_DP<0>")
	)
	(arc
		(start 395.078204 -404.119842)
		(mid 395.138653 -404.101226)
		(end 395.200632 -404.0886)
		(width 0.14224)
		(layer "In15.Cu")
		(net "P5E_CPU0_P2_RX_BUF_DP<0>")
	)
	(segment
		(start 414.244282 -401.0025)
		(end 414.244282 -400.811238)
		(width 0.1016)
		(layer "F.Cu")
		(net "P5E_CPU0_P2_RX_BUF_DN<9>")
	)
	(segment
		(start 413.775144 -401.016216)
		(end 413.902144 -401.143216)
		(width 0.1016)
		(layer "F.Cu")
		(net "P5E_CPU0_P2_RX_BUF_DN<9>")
	)
	(segment
		(start 413.846264 -399.143982)
		(end 413.846264 -399.960338)
		(width 0.1016)
		(layer "F.Cu")
		(net "P5E_CPU0_P2_RX_BUF_DN<9>")
	)
	(segment
		(start 413.845756 -399.143474)
		(end 413.846264 -399.143982)
		(width 0.1016)
		(layer "F.Cu")
		(net "P5E_CPU0_P2_RX_BUF_DN<9>")
	)
	(segment
		(start 413.775144 -400.031458)
		(end 413.775144 -401.016216)
		(width 0.1016)
		(layer "F.Cu")
		(net "P5E_CPU0_P2_RX_BUF_DN<9>")
	)
	(segment
		(start 414.103566 -401.143216)
		(end 414.244282 -401.0025)
		(width 0.1016)
		(layer "F.Cu")
		(net "P5E_CPU0_P2_RX_BUF_DN<9>")
	)
	(segment
		(start 413.846264 -399.960338)
		(end 413.775144 -400.031458)
		(width 0.1016)
		(layer "F.Cu")
		(net "P5E_CPU0_P2_RX_BUF_DN<9>")
	)
	(segment
		(start 413.902144 -401.143216)
		(end 414.103566 -401.143216)
		(width 0.1016)
		(layer "F.Cu")
		(net "P5E_CPU0_P2_RX_BUF_DN<9>")
	)
	(segment
		(start 411.316424 -406.593548)
		(end 413.158432 -404.349712)
		(width 0.14224)
		(layer "In15.Cu")
		(net "P5E_CPU0_P2_RX_BUF_DN<9>")
	)
	(segment
		(start 403.348952 -413.306514)
		(end 403.348952 -412.458154)
		(width 0.14224)
		(layer "In15.Cu")
		(net "P5E_CPU0_P2_RX_BUF_DN<9>")
	)
	(segment
		(start 409.32735 -408.582114)
		(end 411.316424 -406.593548)
		(width 0.14224)
		(layer "In15.Cu")
		(net "P5E_CPU0_P2_RX_BUF_DN<9>")
	)
	(segment
		(start 413.158432 -404.349712)
		(end 413.503364 -403.833584)
		(width 0.14224)
		(layer "In15.Cu")
		(net "P5E_CPU0_P2_RX_BUF_DN<9>")
	)
	(segment
		(start 399.789142 -438.320688)
		(end 399.789142 -424.608498)
		(width 0.14224)
		(layer "In15.Cu")
		(net "P5E_CPU0_P2_RX_BUF_DN<9>")
	)
	(segment
		(start 408.145996 -409.457906)
		(end 409.32735 -408.582114)
		(width 0.14224)
		(layer "In15.Cu")
		(net "P5E_CPU0_P2_RX_BUF_DN<9>")
	)
	(segment
		(start 413.503364 -401.425156)
		(end 413.810704 -401.117816)
		(width 0.14224)
		(layer "In15.Cu")
		(net "P5E_CPU0_P2_RX_BUF_DN<9>")
	)
	(segment
		(start 414.105852 -401.117816)
		(end 414.244282 -400.979386)
		(width 0.14224)
		(layer "In15.Cu")
		(net "P5E_CPU0_P2_RX_BUF_DN<9>")
	)
	(segment
		(start 403.546564 -411.98038)
		(end 404.269956 -411.255718)
		(width 0.14224)
		(layer "In15.Cu")
		(net "P5E_CPU0_P2_RX_BUF_DN<9>")
	)
	(segment
		(start 400.750024 -438.76976)
		(end 400.603466 -438.623202)
		(width 0.14224)
		(layer "In15.Cu")
		(net "P5E_CPU0_P2_RX_BUF_DN<9>")
	)
	(segment
		(start 403.10181 -413.723328)
		(end 403.229064 -413.596074)
		(width 0.14224)
		(layer "In15.Cu")
		(net "P5E_CPU0_P2_RX_BUF_DN<9>")
	)
	(segment
		(start 401.817332 -419.072568)
		(end 401.817332 -415.020252)
		(width 0.14224)
		(layer "In15.Cu")
		(net "P5E_CPU0_P2_RX_BUF_DN<9>")
	)
	(segment
		(start 400.679666 -419.781482)
		(end 401.48891 -419.445948)
		(width 0.14224)
		(layer "In15.Cu")
		(net "P5E_CPU0_P2_RX_BUF_DN<9>")
	)
	(segment
		(start 413.503364 -403.833584)
		(end 413.503364 -401.425156)
		(width 0.14224)
		(layer "In15.Cu")
		(net "P5E_CPU0_P2_RX_BUF_DN<9>")
	)
	(segment
		(start 407.749756 -409.691586)
		(end 408.040078 -409.526994)
		(width 0.14224)
		(layer "In15.Cu")
		(net "P5E_CPU0_P2_RX_BUF_DN<9>")
	)
	(segment
		(start 399.807176 -424.42511)
		(end 399.893282 -423.991024)
		(width 0.14224)
		(layer "In15.Cu")
		(net "P5E_CPU0_P2_RX_BUF_DN<9>")
	)
	(segment
		(start 400.750024 -439.0898)
		(end 400.750024 -438.76976)
		(width 0.14224)
		(layer "In15.Cu")
		(net "P5E_CPU0_P2_RX_BUF_DN<9>")
	)
	(segment
		(start 400.603466 -438.623202)
		(end 400.091656 -438.623202)
		(width 0.14224)
		(layer "In15.Cu")
		(net "P5E_CPU0_P2_RX_BUF_DN<9>")
	)
	(segment
		(start 399.893282 -423.991024)
		(end 399.893536 -423.991024)
		(width 0.14224)
		(layer "In15.Cu")
		(net "P5E_CPU0_P2_RX_BUF_DN<9>")
	)
	(segment
		(start 402.582634 -414.006538)
		(end 402.83257 -413.90316)
		(width 0.14224)
		(layer "In15.Cu")
		(net "P5E_CPU0_P2_RX_BUF_DN<9>")
	)
	(segment
		(start 414.244282 -400.979386)
		(end 414.244282 -400.811238)
		(width 0.14224)
		(layer "In15.Cu")
		(net "P5E_CPU0_P2_RX_BUF_DN<9>")
	)
	(segment
		(start 400.091656 -438.623202)
		(end 399.789142 -438.320688)
		(width 0.14224)
		(layer "In15.Cu")
		(net "P5E_CPU0_P2_RX_BUF_DN<9>")
	)
	(segment
		(start 404.717758 -410.955998)
		(end 407.635964 -409.746958)
		(width 0.14224)
		(layer "In15.Cu")
		(net "P5E_CPU0_P2_RX_BUF_DN<9>")
	)
	(segment
		(start 400.285712 -421.957246)
		(end 400.285712 -420.37127)
		(width 0.14224)
		(layer "In15.Cu")
		(net "P5E_CPU0_P2_RX_BUF_DN<9>")
	)
	(segment
		(start 401.592542 -419.374828)
		(end 401.771358 -419.187122)
		(width 0.14224)
		(layer "In15.Cu")
		(net "P5E_CPU0_P2_RX_BUF_DN<9>")
	)
	(segment
		(start 413.810704 -401.117816)
		(end 414.105852 -401.117816)
		(width 0.14224)
		(layer "In15.Cu")
		(net "P5E_CPU0_P2_RX_BUF_DN<9>")
	)
	(segment
		(start 402.83257 -413.90316)
		(end 403.10181 -413.723328)
		(width 0.14224)
		(layer "In15.Cu")
		(net "P5E_CPU0_P2_RX_BUF_DN<9>")
	)
	(segment
		(start 399.893536 -423.991024)
		(end 400.273266 -422.082976)
		(width 0.14224)
		(layer "In15.Cu")
		(net "P5E_CPU0_P2_RX_BUF_DN<9>")
	)
	(arc
		(start 403.348952 -412.458154)
		(mid 403.400318 -412.199652)
		(end 403.546564 -411.98038)
		(width 0.14224)
		(layer "In15.Cu")
		(net "P5E_CPU0_P2_RX_BUF_DN<9>")
	)
	(arc
		(start 404.269956 -411.255718)
		(mid 404.479057 -411.083744)
		(end 404.717758 -410.955998)
		(width 0.14224)
		(layer "In15.Cu")
		(net "P5E_CPU0_P2_RX_BUF_DN<9>")
	)
	(arc
		(start 403.229064 -413.596074)
		(mid 403.317779 -413.463209)
		(end 403.348952 -413.306514)
		(width 0.14224)
		(layer "In15.Cu")
		(net "P5E_CPU0_P2_RX_BUF_DN<9>")
	)
	(arc
		(start 407.635964 -409.746958)
		(mid 407.693711 -409.721022)
		(end 407.749756 -409.691586)
		(width 0.14224)
		(layer "In15.Cu")
		(net "P5E_CPU0_P2_RX_BUF_DN<9>")
	)
	(arc
		(start 400.285712 -420.37127)
		(mid 400.393197 -420.016603)
		(end 400.679666 -419.781482)
		(width 0.14224)
		(layer "In15.Cu")
		(net "P5E_CPU0_P2_RX_BUF_DN<9>")
	)
	(arc
		(start 401.48891 -419.445948)
		(mid 401.544438 -419.415797)
		(end 401.592542 -419.374828)
		(width 0.14224)
		(layer "In15.Cu")
		(net "P5E_CPU0_P2_RX_BUF_DN<9>")
	)
	(arc
		(start 401.817332 -415.020252)
		(mid 401.892022 -414.644557)
		(end 402.10486 -414.32607)
		(width 0.14224)
		(layer "In15.Cu")
		(net "P5E_CPU0_P2_RX_BUF_DN<9>")
	)
	(arc
		(start 408.040078 -409.526994)
		(mid 408.094092 -409.494067)
		(end 408.145996 -409.457906)
		(width 0.14224)
		(layer "In15.Cu")
		(net "P5E_CPU0_P2_RX_BUF_DN<9>")
	)
	(arc
		(start 401.771358 -419.187122)
		(mid 401.805409 -419.134279)
		(end 401.817332 -419.072568)
		(width 0.14224)
		(layer "In15.Cu")
		(net "P5E_CPU0_P2_RX_BUF_DN<9>")
	)
	(arc
		(start 402.10486 -414.32607)
		(mid 402.328025 -414.142796)
		(end 402.582634 -414.006538)
		(width 0.14224)
		(layer "In15.Cu")
		(net "P5E_CPU0_P2_RX_BUF_DN<9>")
	)
	(arc
		(start 399.789142 -424.608498)
		(mid 399.793645 -424.51636)
		(end 399.807176 -424.42511)
		(width 0.14224)
		(layer "In15.Cu")
		(net "P5E_CPU0_P2_RX_BUF_DN<9>")
	)
	(arc
		(start 400.273266 -422.082976)
		(mid 400.282573 -422.020417)
		(end 400.285712 -421.957246)
		(width 0.14224)
		(layer "In15.Cu")
		(net "P5E_CPU0_P2_RX_BUF_DN<9>")
	)
	(segment
		(start 412.684468 -401.143216)
		(end 412.557468 -401.016216)
		(width 0.1016)
		(layer "F.Cu")
		(net "P5E_CPU0_P2_RX_BUF_DN<8>")
	)
	(segment
		(start 412.557468 -400.048984)
		(end 412.646114 -399.960338)
		(width 0.1016)
		(layer "F.Cu")
		(net "P5E_CPU0_P2_RX_BUF_DN<8>")
	)
	(segment
		(start 412.646114 -399.143982)
		(end 412.645606 -399.143474)
		(width 0.1016)
		(layer "F.Cu")
		(net "P5E_CPU0_P2_RX_BUF_DN<8>")
	)
	(segment
		(start 413.044386 -400.811238)
		(end 413.044386 -401.002246)
		(width 0.1016)
		(layer "F.Cu")
		(net "P5E_CPU0_P2_RX_BUF_DN<8>")
	)
	(segment
		(start 413.044386 -401.002246)
		(end 412.903416 -401.143216)
		(width 0.1016)
		(layer "F.Cu")
		(net "P5E_CPU0_P2_RX_BUF_DN<8>")
	)
	(segment
		(start 412.903416 -401.143216)
		(end 412.684468 -401.143216)
		(width 0.1016)
		(layer "F.Cu")
		(net "P5E_CPU0_P2_RX_BUF_DN<8>")
	)
	(segment
		(start 412.557468 -401.016216)
		(end 412.557468 -400.048984)
		(width 0.1016)
		(layer "F.Cu")
		(net "P5E_CPU0_P2_RX_BUF_DN<8>")
	)
	(segment
		(start 412.646114 -399.960338)
		(end 412.646114 -399.143982)
		(width 0.1016)
		(layer "F.Cu")
		(net "P5E_CPU0_P2_RX_BUF_DN<8>")
	)
	(segment
		(start 412.905956 -401.117816)
		(end 413.044386 -400.979386)
		(width 0.14224)
		(layer "In15.Cu")
		(net "P5E_CPU0_P2_RX_BUF_DN<8>")
	)
	(segment
		(start 398.754092 -419.079426)
		(end 398.754092 -415.020252)
		(width 0.14224)
		(layer "In15.Cu")
		(net "P5E_CPU0_P2_RX_BUF_DN<8>")
	)
	(segment
		(start 398.750028 -438.089802)
		(end 398.750028 -437.769762)
		(width 0.14224)
		(layer "In15.Cu")
		(net "P5E_CPU0_P2_RX_BUF_DN<8>")
	)
	(segment
		(start 412.303468 -403.548596)
		(end 412.303468 -401.425156)
		(width 0.14224)
		(layer "In15.Cu")
		(net "P5E_CPU0_P2_RX_BUF_DN<8>")
	)
	(segment
		(start 413.044386 -400.979386)
		(end 413.044386 -400.811238)
		(width 0.14224)
		(layer "In15.Cu")
		(net "P5E_CPU0_P2_RX_BUF_DN<8>")
	)
	(segment
		(start 397.484092 -419.836346)
		(end 398.436846 -419.441376)
		(width 0.14224)
		(layer "In15.Cu")
		(net "P5E_CPU0_P2_RX_BUF_DN<8>")
	)
	(segment
		(start 398.08277 -437.61914)
		(end 397.222472 -436.758842)
		(width 0.14224)
		(layer "In15.Cu")
		(net "P5E_CPU0_P2_RX_BUF_DN<8>")
	)
	(segment
		(start 407.386282 -408.820874)
		(end 407.777442 -408.540458)
		(width 0.14224)
		(layer "In15.Cu")
		(net "P5E_CPU0_P2_RX_BUF_DN<8>")
	)
	(segment
		(start 411.772354 -404.302468)
		(end 412.303468 -403.548596)
		(width 0.14224)
		(layer "In15.Cu")
		(net "P5E_CPU0_P2_RX_BUF_DN<8>")
	)
	(segment
		(start 400.33448 -412.037784)
		(end 400.429984 -411.817312)
		(width 0.14224)
		(layer "In15.Cu")
		(net "P5E_CPU0_P2_RX_BUF_DN<8>")
	)
	(segment
		(start 407.777442 -408.540458)
		(end 409.309316 -407.26741)
		(width 0.14224)
		(layer "In15.Cu")
		(net "P5E_CPU0_P2_RX_BUF_DN<8>")
	)
	(segment
		(start 398.750028 -437.769762)
		(end 398.599406 -437.61914)
		(width 0.14224)
		(layer "In15.Cu")
		(net "P5E_CPU0_P2_RX_BUF_DN<8>")
	)
	(segment
		(start 412.610808 -401.117816)
		(end 412.905956 -401.117816)
		(width 0.14224)
		(layer "In15.Cu")
		(net "P5E_CPU0_P2_RX_BUF_DN<8>")
	)
	(segment
		(start 398.599406 -437.61914)
		(end 398.08277 -437.61914)
		(width 0.14224)
		(layer "In15.Cu")
		(net "P5E_CPU0_P2_RX_BUF_DN<8>")
	)
	(segment
		(start 398.540478 -419.370256)
		(end 398.708118 -419.194234)
		(width 0.14224)
		(layer "In15.Cu")
		(net "P5E_CPU0_P2_RX_BUF_DN<8>")
	)
	(segment
		(start 399.519394 -414.006538)
		(end 399.76933 -413.90316)
		(width 0.14224)
		(layer "In15.Cu")
		(net "P5E_CPU0_P2_RX_BUF_DN<8>")
	)
	(segment
		(start 412.303468 -401.425156)
		(end 412.610808 -401.117816)
		(width 0.14224)
		(layer "In15.Cu")
		(net "P5E_CPU0_P2_RX_BUF_DN<8>")
	)
	(segment
		(start 404.799292 -409.74391)
		(end 406.218898 -409.313634)
		(width 0.14224)
		(layer "In15.Cu")
		(net "P5E_CPU0_P2_RX_BUF_DN<8>")
	)
	(segment
		(start 406.461722 -409.222194)
		(end 407.386282 -408.820874)
		(width 0.14224)
		(layer "In15.Cu")
		(net "P5E_CPU0_P2_RX_BUF_DN<8>")
	)
	(segment
		(start 411.772608 -404.302468)
		(end 411.772354 -404.302468)
		(width 0.14224)
		(layer "In15.Cu")
		(net "P5E_CPU0_P2_RX_BUF_DN<8>")
	)
	(segment
		(start 400.03857 -413.723328)
		(end 400.165824 -413.596074)
		(width 0.14224)
		(layer "In15.Cu")
		(net "P5E_CPU0_P2_RX_BUF_DN<8>")
	)
	(segment
		(start 409.309316 -407.26741)
		(end 410.995368 -405.406352)
		(width 0.14224)
		(layer "In15.Cu")
		(net "P5E_CPU0_P2_RX_BUF_DN<8>")
	)
	(segment
		(start 400.285712 -413.306514)
		(end 400.285712 -412.272988)
		(width 0.14224)
		(layer "In15.Cu")
		(net "P5E_CPU0_P2_RX_BUF_DN<8>")
	)
	(segment
		(start 399.76933 -413.90316)
		(end 400.03857 -413.723328)
		(width 0.14224)
		(layer "In15.Cu")
		(net "P5E_CPU0_P2_RX_BUF_DN<8>")
	)
	(segment
		(start 397.222472 -436.758842)
		(end 397.222472 -420.22776)
		(width 0.14224)
		(layer "In15.Cu")
		(net "P5E_CPU0_P2_RX_BUF_DN<8>")
	)
	(segment
		(start 406.218898 -409.313634)
		(end 406.461722 -409.222194)
		(width 0.14224)
		(layer "In15.Cu")
		(net "P5E_CPU0_P2_RX_BUF_DN<8>")
	)
	(segment
		(start 400.999452 -411.362906)
		(end 404.799292 -409.74391)
		(width 0.14224)
		(layer "In15.Cu")
		(net "P5E_CPU0_P2_RX_BUF_DN<8>")
	)
	(segment
		(start 410.995368 -405.406352)
		(end 411.772608 -404.302468)
		(width 0.14224)
		(layer "In15.Cu")
		(net "P5E_CPU0_P2_RX_BUF_DN<8>")
	)
	(arc
		(start 400.588734 -411.609286)
		(mid 400.785596 -411.471934)
		(end 400.999452 -411.362906)
		(width 0.14224)
		(layer "In15.Cu")
		(net "P5E_CPU0_P2_RX_BUF_DN<8>")
	)
	(arc
		(start 400.285712 -412.272988)
		(mid 400.298042 -412.152889)
		(end 400.33448 -412.037784)
		(width 0.14224)
		(layer "In15.Cu")
		(net "P5E_CPU0_P2_RX_BUF_DN<8>")
	)
	(arc
		(start 398.754092 -415.020252)
		(mid 398.828782 -414.644557)
		(end 399.04162 -414.32607)
		(width 0.14224)
		(layer "In15.Cu")
		(net "P5E_CPU0_P2_RX_BUF_DN<8>")
	)
	(arc
		(start 397.222472 -420.22776)
		(mid 397.293893 -419.992351)
		(end 397.484092 -419.836346)
		(width 0.14224)
		(layer "In15.Cu")
		(net "P5E_CPU0_P2_RX_BUF_DN<8>")
	)
	(arc
		(start 399.04162 -414.32607)
		(mid 399.264785 -414.142796)
		(end 399.519394 -414.006538)
		(width 0.14224)
		(layer "In15.Cu")
		(net "P5E_CPU0_P2_RX_BUF_DN<8>")
	)
	(arc
		(start 398.708118 -419.194234)
		(mid 398.742165 -419.14126)
		(end 398.754092 -419.079426)
		(width 0.14224)
		(layer "In15.Cu")
		(net "P5E_CPU0_P2_RX_BUF_DN<8>")
	)
	(arc
		(start 398.436846 -419.441376)
		(mid 398.492384 -419.41124)
		(end 398.540478 -419.370256)
		(width 0.14224)
		(layer "In15.Cu")
		(net "P5E_CPU0_P2_RX_BUF_DN<8>")
	)
	(arc
		(start 400.165824 -413.596074)
		(mid 400.254539 -413.463209)
		(end 400.285712 -413.306514)
		(width 0.14224)
		(layer "In15.Cu")
		(net "P5E_CPU0_P2_RX_BUF_DN<8>")
	)
	(arc
		(start 400.429984 -411.817312)
		(mid 400.496736 -411.703668)
		(end 400.588734 -411.609286)
		(width 0.14224)
		(layer "In15.Cu")
		(net "P5E_CPU0_P2_RX_BUF_DN<8>")
	)
	(segment
		(start 411.484572 -401.143216)
		(end 411.70352 -401.143216)
		(width 0.1016)
		(layer "F.Cu")
		(net "P5E_CPU0_P2_RX_BUF_DN<7>")
	)
	(segment
		(start 411.70352 -401.143216)
		(end 411.844236 -401.0025)
		(width 0.1016)
		(layer "F.Cu")
		(net "P5E_CPU0_P2_RX_BUF_DN<7>")
	)
	(segment
		(start 411.446218 -399.143982)
		(end 411.446218 -399.960338)
		(width 0.1016)
		(layer "F.Cu")
		(net "P5E_CPU0_P2_RX_BUF_DN<7>")
	)
	(segment
		(start 411.844236 -401.0025)
		(end 411.844236 -400.811238)
		(width 0.1016)
		(layer "F.Cu")
		(net "P5E_CPU0_P2_RX_BUF_DN<7>")
	)
	(segment
		(start 411.44571 -399.143474)
		(end 411.446218 -399.143982)
		(width 0.1016)
		(layer "F.Cu")
		(net "P5E_CPU0_P2_RX_BUF_DN<7>")
	)
	(segment
		(start 411.446218 -399.960338)
		(end 411.357572 -400.048984)
		(width 0.1016)
		(layer "F.Cu")
		(net "P5E_CPU0_P2_RX_BUF_DN<7>")
	)
	(segment
		(start 411.357572 -401.016216)
		(end 411.484572 -401.143216)
		(width 0.1016)
		(layer "F.Cu")
		(net "P5E_CPU0_P2_RX_BUF_DN<7>")
	)
	(segment
		(start 411.357572 -400.048984)
		(end 411.357572 -401.016216)
		(width 0.1016)
		(layer "F.Cu")
		(net "P5E_CPU0_P2_RX_BUF_DN<7>")
	)
	(segment
		(start 411.844236 -400.979386)
		(end 411.844236 -400.811238)
		(width 0.14224)
		(layer "In15.Cu")
		(net "P5E_CPU0_P2_RX_BUF_DN<7>")
	)
	(segment
		(start 397.222472 -413.306514)
		(end 397.222472 -412.502604)
		(width 0.14224)
		(layer "In15.Cu")
		(net "P5E_CPU0_P2_RX_BUF_DN<7>")
	)
	(segment
		(start 395.690852 -418.8968)
		(end 395.690852 -415.025332)
		(width 0.14224)
		(layer "In15.Cu")
		(net "P5E_CPU0_P2_RX_BUF_DN<7>")
	)
	(segment
		(start 396.347442 -414.052766)
		(end 396.705328 -413.903922)
		(width 0.14224)
		(layer "In15.Cu")
		(net "P5E_CPU0_P2_RX_BUF_DN<7>")
	)
	(segment
		(start 406.738582 -408.03322)
		(end 407.020014 -407.875994)
		(width 0.14224)
		(layer "In15.Cu")
		(net "P5E_CPU0_P2_RX_BUF_DN<7>")
	)
	(segment
		(start 411.705806 -401.117816)
		(end 411.844236 -400.979386)
		(width 0.14224)
		(layer "In15.Cu")
		(net "P5E_CPU0_P2_RX_BUF_DN<7>")
	)
	(segment
		(start 410.92247 -403.835362)
		(end 411.05201 -403.318472)
		(width 0.14224)
		(layer "In15.Cu")
		(net "P5E_CPU0_P2_RX_BUF_DN<7>")
	)
	(segment
		(start 411.05201 -403.318472)
		(end 411.05201 -401.476464)
		(width 0.14224)
		(layer "In15.Cu")
		(net "P5E_CPU0_P2_RX_BUF_DN<7>")
	)
	(segment
		(start 403.656292 -409.038044)
		(end 405.101044 -408.619198)
		(width 0.14224)
		(layer "In15.Cu")
		(net "P5E_CPU0_P2_RX_BUF_DN<7>")
	)
	(segment
		(start 407.020014 -407.875994)
		(end 407.942796 -407.137108)
		(width 0.14224)
		(layer "In15.Cu")
		(net "P5E_CPU0_P2_RX_BUF_DN<7>")
	)
	(segment
		(start 394.159232 -421.224202)
		(end 394.159232 -420.771574)
		(width 0.14224)
		(layer "In15.Cu")
		(net "P5E_CPU0_P2_RX_BUF_DN<7>")
	)
	(segment
		(start 395.096492 -438.619392)
		(end 394.789152 -438.312052)
		(width 0.14224)
		(layer "In15.Cu")
		(net "P5E_CPU0_P2_RX_BUF_DN<7>")
	)
	(segment
		(start 410.435552 -404.56358)
		(end 410.92247 -403.835362)
		(width 0.14224)
		(layer "In15.Cu")
		(net "P5E_CPU0_P2_RX_BUF_DN<7>")
	)
	(segment
		(start 399.435066 -410.718254)
		(end 402.55571 -409.357322)
		(width 0.14224)
		(layer "In15.Cu")
		(net "P5E_CPU0_P2_RX_BUF_DN<7>")
	)
	(segment
		(start 394.51788 -419.78072)
		(end 395.487906 -419.378384)
		(width 0.14224)
		(layer "In15.Cu")
		(net "P5E_CPU0_P2_RX_BUF_DN<7>")
	)
	(segment
		(start 396.97533 -413.723328)
		(end 397.102584 -413.596074)
		(width 0.14224)
		(layer "In15.Cu")
		(net "P5E_CPU0_P2_RX_BUF_DN<7>")
	)
	(segment
		(start 394.159232 -420.771574)
		(end 394.159486 -420.77132)
		(width 0.14224)
		(layer "In15.Cu")
		(net "P5E_CPU0_P2_RX_BUF_DN<7>")
	)
	(segment
		(start 399.434812 -410.718254)
		(end 399.435066 -410.718254)
		(width 0.14224)
		(layer "In15.Cu")
		(net "P5E_CPU0_P2_RX_BUF_DN<7>")
	)
	(segment
		(start 403.656292 -409.03779)
		(end 403.656292 -409.038044)
		(width 0.14224)
		(layer "In15.Cu")
		(net "P5E_CPU0_P2_RX_BUF_DN<7>")
	)
	(segment
		(start 395.830298 -414.600898)
		(end 396.07871 -414.263586)
		(width 0.14224)
		(layer "In15.Cu")
		(net "P5E_CPU0_P2_RX_BUF_DN<7>")
	)
	(segment
		(start 394.159232 -420.426642)
		(end 394.159486 -420.426642)
		(width 0.14224)
		(layer "In15.Cu")
		(net "P5E_CPU0_P2_RX_BUF_DN<7>")
	)
	(segment
		(start 394.159486 -420.426896)
		(end 394.159232 -420.426642)
		(width 0.14224)
		(layer "In15.Cu")
		(net "P5E_CPU0_P2_RX_BUF_DN<7>")
	)
	(segment
		(start 394.159486 -420.77132)
		(end 394.159486 -420.426896)
		(width 0.14224)
		(layer "In15.Cu")
		(net "P5E_CPU0_P2_RX_BUF_DN<7>")
	)
	(segment
		(start 411.410658 -401.117816)
		(end 411.705806 -401.117816)
		(width 0.14224)
		(layer "In15.Cu")
		(net "P5E_CPU0_P2_RX_BUF_DN<7>")
	)
	(segment
		(start 397.498316 -411.836616)
		(end 397.661638 -411.673294)
		(width 0.14224)
		(layer "In15.Cu")
		(net "P5E_CPU0_P2_RX_BUF_DN<7>")
	)
	(segment
		(start 405.101044 -408.619198)
		(end 406.738582 -408.03322)
		(width 0.14224)
		(layer "In15.Cu")
		(net "P5E_CPU0_P2_RX_BUF_DN<7>")
	)
	(segment
		(start 394.159486 -420.426642)
		(end 394.159486 -420.317422)
		(width 0.14224)
		(layer "In15.Cu")
		(net "P5E_CPU0_P2_RX_BUF_DN<7>")
	)
	(segment
		(start 407.942796 -407.137108)
		(end 409.93695 -405.167592)
		(width 0.14224)
		(layer "In15.Cu")
		(net "P5E_CPU0_P2_RX_BUF_DN<7>")
	)
	(segment
		(start 395.599412 -438.619392)
		(end 395.096492 -438.619392)
		(width 0.14224)
		(layer "In15.Cu")
		(net "P5E_CPU0_P2_RX_BUF_DN<7>")
	)
	(segment
		(start 409.93695 -405.167592)
		(end 410.435552 -404.56358)
		(width 0.14224)
		(layer "In15.Cu")
		(net "P5E_CPU0_P2_RX_BUF_DN<7>")
	)
	(segment
		(start 398.401032 -411.169104)
		(end 399.434812 -410.718254)
		(width 0.14224)
		(layer "In15.Cu")
		(net "P5E_CPU0_P2_RX_BUF_DN<7>")
	)
	(segment
		(start 395.74978 -439.0898)
		(end 395.74978 -438.76976)
		(width 0.14224)
		(layer "In15.Cu")
		(net "P5E_CPU0_P2_RX_BUF_DN<7>")
	)
	(segment
		(start 394.789152 -438.312052)
		(end 394.789152 -424.77436)
		(width 0.14224)
		(layer "In15.Cu")
		(net "P5E_CPU0_P2_RX_BUF_DN<7>")
	)
	(segment
		(start 395.74978 -438.76976)
		(end 395.599412 -438.619392)
		(width 0.14224)
		(layer "In15.Cu")
		(net "P5E_CPU0_P2_RX_BUF_DN<7>")
	)
	(segment
		(start 396.705328 -413.903922)
		(end 396.97533 -413.723328)
		(width 0.14224)
		(layer "In15.Cu")
		(net "P5E_CPU0_P2_RX_BUF_DN<7>")
	)
	(segment
		(start 402.55571 -409.357322)
		(end 403.656292 -409.03779)
		(width 0.14224)
		(layer "In15.Cu")
		(net "P5E_CPU0_P2_RX_BUF_DN<7>")
	)
	(segment
		(start 394.789152 -424.77436)
		(end 394.159232 -421.224202)
		(width 0.14224)
		(layer "In15.Cu")
		(net "P5E_CPU0_P2_RX_BUF_DN<7>")
	)
	(segment
		(start 411.05201 -401.476464)
		(end 411.410658 -401.117816)
		(width 0.14224)
		(layer "In15.Cu")
		(net "P5E_CPU0_P2_RX_BUF_DN<7>")
	)
	(arc
		(start 395.690852 -415.025332)
		(mid 395.726552 -414.80193)
		(end 395.830298 -414.600898)
		(width 0.14224)
		(layer "In15.Cu")
		(net "P5E_CPU0_P2_RX_BUF_DN<7>")
	)
	(arc
		(start 397.661638 -411.673294)
		(mid 398.007668 -411.386492)
		(end 398.401032 -411.169104)
		(width 0.14224)
		(layer "In15.Cu")
		(net "P5E_CPU0_P2_RX_BUF_DN<7>")
	)
	(arc
		(start 395.487906 -419.378384)
		(mid 395.63802 -419.158086)
		(end 395.690852 -418.8968)
		(width 0.14224)
		(layer "In15.Cu")
		(net "P5E_CPU0_P2_RX_BUF_DN<7>")
	)
	(arc
		(start 396.07871 -414.263586)
		(mid 396.198732 -414.139887)
		(end 396.347442 -414.052766)
		(width 0.14224)
		(layer "In15.Cu")
		(net "P5E_CPU0_P2_RX_BUF_DN<7>")
	)
	(arc
		(start 397.102584 -413.596074)
		(mid 397.191299 -413.463209)
		(end 397.222472 -413.306514)
		(width 0.14224)
		(layer "In15.Cu")
		(net "P5E_CPU0_P2_RX_BUF_DN<7>")
	)
	(arc
		(start 394.159486 -420.317422)
		(mid 394.25726 -419.994703)
		(end 394.51788 -419.78072)
		(width 0.14224)
		(layer "In15.Cu")
		(net "P5E_CPU0_P2_RX_BUF_DN<7>")
	)
	(arc
		(start 397.222472 -412.502604)
		(mid 397.294165 -412.14218)
		(end 397.498316 -411.836616)
		(width 0.14224)
		(layer "In15.Cu")
		(net "P5E_CPU0_P2_RX_BUF_DN<7>")
	)
	(segment
		(start 410.245814 -399.143474)
		(end 410.246322 -399.143982)
		(width 0.1016)
		(layer "F.Cu")
		(net "P5E_CPU0_P2_RX_BUF_DN<6>")
	)
	(segment
		(start 410.64434 -401.0025)
		(end 410.64434 -400.811238)
		(width 0.1016)
		(layer "F.Cu")
		(net "P5E_CPU0_P2_RX_BUF_DN<6>")
	)
	(segment
		(start 410.166312 -400.040094)
		(end 410.166312 -401.016216)
		(width 0.1016)
		(layer "F.Cu")
		(net "P5E_CPU0_P2_RX_BUF_DN<6>")
	)
	(segment
		(start 410.503624 -401.143216)
		(end 410.64434 -401.0025)
		(width 0.1016)
		(layer "F.Cu")
		(net "P5E_CPU0_P2_RX_BUF_DN<6>")
	)
	(segment
		(start 410.166312 -401.016216)
		(end 410.293312 -401.143216)
		(width 0.1016)
		(layer "F.Cu")
		(net "P5E_CPU0_P2_RX_BUF_DN<6>")
	)
	(segment
		(start 410.293312 -401.143216)
		(end 410.503624 -401.143216)
		(width 0.1016)
		(layer "F.Cu")
		(net "P5E_CPU0_P2_RX_BUF_DN<6>")
	)
	(segment
		(start 410.246322 -399.143982)
		(end 410.246322 -399.747486)
		(width 0.1016)
		(layer "F.Cu")
		(net "P5E_CPU0_P2_RX_BUF_DN<6>")
	)
	(segment
		(start 410.246322 -399.747486)
		(end 410.246068 -399.74774)
		(width 0.1016)
		(layer "F.Cu")
		(net "P5E_CPU0_P2_RX_BUF_DN<6>")
	)
	(segment
		(start 410.246068 -399.960338)
		(end 410.166312 -400.040094)
		(width 0.1016)
		(layer "F.Cu")
		(net "P5E_CPU0_P2_RX_BUF_DN<6>")
	)
	(segment
		(start 410.246068 -399.74774)
		(end 410.246068 -399.960338)
		(width 0.1016)
		(layer "F.Cu")
		(net "P5E_CPU0_P2_RX_BUF_DN<6>")
	)
	(segment
		(start 405.548084 -407.464514)
		(end 403.989794 -407.899362)
		(width 0.14224)
		(layer "In15.Cu")
		(net "P5E_CPU0_P2_RX_BUF_DN<6>")
	)
	(segment
		(start 410.64434 -400.811238)
		(end 410.64434 -400.979386)
		(width 0.14224)
		(layer "In15.Cu")
		(net "P5E_CPU0_P2_RX_BUF_DN<6>")
	)
	(segment
		(start 391.095992 -420.22776)
		(end 391.095992 -421.477186)
		(width 0.14224)
		(layer "In15.Cu")
		(net "P5E_CPU0_P2_RX_BUF_DN<6>")
	)
	(segment
		(start 406.945846 -406.712166)
		(end 406.263094 -407.16835)
		(width 0.14224)
		(layer "In15.Cu")
		(net "P5E_CPU0_P2_RX_BUF_DN<6>")
	)
	(segment
		(start 394.323824 -412.079186)
		(end 394.233146 -412.2293)
		(width 0.14224)
		(layer "In15.Cu")
		(net "P5E_CPU0_P2_RX_BUF_DN<6>")
	)
	(segment
		(start 410.50591 -401.117816)
		(end 410.210762 -401.117816)
		(width 0.14224)
		(layer "In15.Cu")
		(net "P5E_CPU0_P2_RX_BUF_DN<6>")
	)
	(segment
		(start 392.10107 -423.6085)
		(end 392.77671 -425.038012)
		(width 0.14224)
		(layer "In15.Cu")
		(net "P5E_CPU0_P2_RX_BUF_DN<6>")
	)
	(segment
		(start 393.603226 -437.623204)
		(end 393.749784 -437.769762)
		(width 0.14224)
		(layer "In15.Cu")
		(net "P5E_CPU0_P2_RX_BUF_DN<6>")
	)
	(segment
		(start 394.039344 -413.596074)
		(end 393.91209 -413.723328)
		(width 0.14224)
		(layer "In15.Cu")
		(net "P5E_CPU0_P2_RX_BUF_DN<6>")
	)
	(segment
		(start 409.405074 -404.252938)
		(end 406.945846 -406.712166)
		(width 0.14224)
		(layer "In15.Cu")
		(net "P5E_CPU0_P2_RX_BUF_DN<6>")
	)
	(segment
		(start 392.789156 -425.092622)
		(end 392.789156 -437.320944)
		(width 0.14224)
		(layer "In15.Cu")
		(net "P5E_CPU0_P2_RX_BUF_DN<6>")
	)
	(segment
		(start 394.797534 -411.579568)
		(end 394.446506 -411.924246)
		(width 0.14224)
		(layer "In15.Cu")
		(net "P5E_CPU0_P2_RX_BUF_DN<6>")
	)
	(segment
		(start 392.310366 -419.441376)
		(end 391.357612 -419.836346)
		(width 0.14224)
		(layer "In15.Cu")
		(net "P5E_CPU0_P2_RX_BUF_DN<6>")
	)
	(segment
		(start 394.159232 -412.495238)
		(end 394.159232 -413.306514)
		(width 0.14224)
		(layer "In15.Cu")
		(net "P5E_CPU0_P2_RX_BUF_DN<6>")
	)
	(segment
		(start 393.091416 -437.623204)
		(end 393.603226 -437.623204)
		(width 0.14224)
		(layer "In15.Cu")
		(net "P5E_CPU0_P2_RX_BUF_DN<6>")
	)
	(segment
		(start 393.91209 -413.723328)
		(end 393.64285 -413.90316)
		(width 0.14224)
		(layer "In15.Cu")
		(net "P5E_CPU0_P2_RX_BUF_DN<6>")
	)
	(segment
		(start 409.74137 -403.74951)
		(end 409.405074 -404.252938)
		(width 0.14224)
		(layer "In15.Cu")
		(net "P5E_CPU0_P2_RX_BUF_DN<6>")
	)
	(segment
		(start 410.64434 -400.979386)
		(end 410.50591 -401.117816)
		(width 0.14224)
		(layer "In15.Cu")
		(net "P5E_CPU0_P2_RX_BUF_DN<6>")
	)
	(segment
		(start 409.903422 -401.425156)
		(end 409.903422 -403.358604)
		(width 0.14224)
		(layer "In15.Cu")
		(net "P5E_CPU0_P2_RX_BUF_DN<6>")
	)
	(segment
		(start 392.581638 -419.194234)
		(end 392.413998 -419.370256)
		(width 0.14224)
		(layer "In15.Cu")
		(net "P5E_CPU0_P2_RX_BUF_DN<6>")
	)
	(segment
		(start 392.627612 -415.020252)
		(end 392.627612 -419.079426)
		(width 0.14224)
		(layer "In15.Cu")
		(net "P5E_CPU0_P2_RX_BUF_DN<6>")
	)
	(segment
		(start 393.749784 -437.769762)
		(end 393.749784 -438.089802)
		(width 0.14224)
		(layer "In15.Cu")
		(net "P5E_CPU0_P2_RX_BUF_DN<6>")
	)
	(segment
		(start 406.263094 -407.16835)
		(end 405.548084 -407.464514)
		(width 0.14224)
		(layer "In15.Cu")
		(net "P5E_CPU0_P2_RX_BUF_DN<6>")
	)
	(segment
		(start 393.64285 -413.90316)
		(end 393.392914 -414.006538)
		(width 0.14224)
		(layer "In15.Cu")
		(net "P5E_CPU0_P2_RX_BUF_DN<6>")
	)
	(segment
		(start 409.903422 -403.358604)
		(end 409.74137 -403.74951)
		(width 0.14224)
		(layer "In15.Cu")
		(net "P5E_CPU0_P2_RX_BUF_DN<6>")
	)
	(segment
		(start 403.989794 -407.899362)
		(end 401.455636 -408.66822)
		(width 0.14224)
		(layer "In15.Cu")
		(net "P5E_CPU0_P2_RX_BUF_DN<6>")
	)
	(segment
		(start 395.187424 -411.357572)
		(end 394.952728 -411.470602)
		(width 0.14224)
		(layer "In15.Cu")
		(net "P5E_CPU0_P2_RX_BUF_DN<6>")
	)
	(segment
		(start 401.455636 -408.66822)
		(end 395.302486 -411.305248)
		(width 0.14224)
		(layer "In15.Cu")
		(net "P5E_CPU0_P2_RX_BUF_DN<6>")
	)
	(segment
		(start 391.214356 -421.94861)
		(end 392.10107 -423.6085)
		(width 0.14224)
		(layer "In15.Cu")
		(net "P5E_CPU0_P2_RX_BUF_DN<6>")
	)
	(segment
		(start 410.210762 -401.117816)
		(end 409.903422 -401.425156)
		(width 0.14224)
		(layer "In15.Cu")
		(net "P5E_CPU0_P2_RX_BUF_DN<6>")
	)
	(segment
		(start 392.789156 -437.320944)
		(end 393.091416 -437.623204)
		(width 0.14224)
		(layer "In15.Cu")
		(net "P5E_CPU0_P2_RX_BUF_DN<6>")
	)
	(arc
		(start 393.392914 -414.006538)
		(mid 393.13831 -414.142803)
		(end 392.91514 -414.32607)
		(width 0.14224)
		(layer "In15.Cu")
		(net "P5E_CPU0_P2_RX_BUF_DN<6>")
	)
	(arc
		(start 392.627612 -419.079426)
		(mid 392.615693 -419.141263)
		(end 392.581638 -419.194234)
		(width 0.14224)
		(layer "In15.Cu")
		(net "P5E_CPU0_P2_RX_BUF_DN<6>")
	)
	(arc
		(start 391.095992 -421.477186)
		(mid 391.126089 -421.720202)
		(end 391.214356 -421.94861)
		(width 0.14224)
		(layer "In15.Cu")
		(net "P5E_CPU0_P2_RX_BUF_DN<6>")
	)
	(arc
		(start 394.233146 -412.2293)
		(mid 394.178054 -412.357229)
		(end 394.159232 -412.495238)
		(width 0.14224)
		(layer "In15.Cu")
		(net "P5E_CPU0_P2_RX_BUF_DN<6>")
	)
	(arc
		(start 392.91514 -414.32607)
		(mid 392.702251 -414.644536)
		(end 392.627612 -415.020252)
		(width 0.14224)
		(layer "In15.Cu")
		(net "P5E_CPU0_P2_RX_BUF_DN<6>")
	)
	(arc
		(start 392.413998 -419.370256)
		(mid 392.365909 -419.411248)
		(end 392.310366 -419.441376)
		(width 0.14224)
		(layer "In15.Cu")
		(net "P5E_CPU0_P2_RX_BUF_DN<6>")
	)
	(arc
		(start 391.357612 -419.836346)
		(mid 391.167445 -419.992372)
		(end 391.095992 -420.22776)
		(width 0.14224)
		(layer "In15.Cu")
		(net "P5E_CPU0_P2_RX_BUF_DN<6>")
	)
	(arc
		(start 395.302486 -411.305248)
		(mid 395.244669 -411.330781)
		(end 395.187424 -411.357572)
		(width 0.14224)
		(layer "In15.Cu")
		(net "P5E_CPU0_P2_RX_BUF_DN<6>")
	)
	(arc
		(start 394.952728 -411.470602)
		(mid 394.870669 -411.518729)
		(end 394.797534 -411.579568)
		(width 0.14224)
		(layer "In15.Cu")
		(net "P5E_CPU0_P2_RX_BUF_DN<6>")
	)
	(arc
		(start 394.159232 -413.306514)
		(mid 394.12808 -413.463217)
		(end 394.039344 -413.596074)
		(width 0.14224)
		(layer "In15.Cu")
		(net "P5E_CPU0_P2_RX_BUF_DN<6>")
	)
	(arc
		(start 392.77671 -425.038012)
		(mid 392.785951 -425.064627)
		(end 392.789156 -425.092622)
		(width 0.14224)
		(layer "In15.Cu")
		(net "P5E_CPU0_P2_RX_BUF_DN<6>")
	)
	(arc
		(start 394.446506 -411.924246)
		(mid 394.380301 -411.997864)
		(end 394.323824 -412.079186)
		(width 0.14224)
		(layer "In15.Cu")
		(net "P5E_CPU0_P2_RX_BUF_DN<6>")
	)
	(segment
		(start 409.045664 -399.143474)
		(end 409.046172 -399.143982)
		(width 0.1016)
		(layer "F.Cu")
		(net "P5E_CPU0_P2_RX_BUF_DN<5>")
	)
	(segment
		(start 409.046172 -399.960338)
		(end 408.957526 -400.048984)
		(width 0.1016)
		(layer "F.Cu")
		(net "P5E_CPU0_P2_RX_BUF_DN<5>")
	)
	(segment
		(start 409.084526 -401.143216)
		(end 409.303474 -401.143216)
		(width 0.1016)
		(layer "F.Cu")
		(net "P5E_CPU0_P2_RX_BUF_DN<5>")
	)
	(segment
		(start 408.957526 -401.016216)
		(end 409.084526 -401.143216)
		(width 0.1016)
		(layer "F.Cu")
		(net "P5E_CPU0_P2_RX_BUF_DN<5>")
	)
	(segment
		(start 409.44419 -401.0025)
		(end 409.44419 -400.811238)
		(width 0.1016)
		(layer "F.Cu")
		(net "P5E_CPU0_P2_RX_BUF_DN<5>")
	)
	(segment
		(start 409.303474 -401.143216)
		(end 409.44419 -401.0025)
		(width 0.1016)
		(layer "F.Cu")
		(net "P5E_CPU0_P2_RX_BUF_DN<5>")
	)
	(segment
		(start 409.046172 -399.143982)
		(end 409.046172 -399.960338)
		(width 0.1016)
		(layer "F.Cu")
		(net "P5E_CPU0_P2_RX_BUF_DN<5>")
	)
	(segment
		(start 408.957526 -400.048984)
		(end 408.957526 -401.016216)
		(width 0.1016)
		(layer "F.Cu")
		(net "P5E_CPU0_P2_RX_BUF_DN<5>")
	)
	(segment
		(start 409.30576 -401.117816)
		(end 409.010612 -401.117816)
		(width 0.14224)
		(layer "In15.Cu")
		(net "P5E_CPU0_P2_RX_BUF_DN<5>")
	)
	(segment
		(start 388.33552 -419.772592)
		(end 388.149592 -419.908482)
		(width 0.14224)
		(layer "In15.Cu")
		(net "P5E_CPU0_P2_RX_BUF_DN<5>")
	)
	(segment
		(start 389.24992 -419.474396)
		(end 388.33552 -419.772592)
		(width 0.14224)
		(layer "In15.Cu")
		(net "P5E_CPU0_P2_RX_BUF_DN<5>")
	)
	(segment
		(start 406.227534 -405.969724)
		(end 405.618188 -406.376886)
		(width 0.14224)
		(layer "In15.Cu")
		(net "P5E_CPU0_P2_RX_BUF_DN<5>")
	)
	(segment
		(start 408.703272 -401.425156)
		(end 408.703272 -403.451314)
		(width 0.14224)
		(layer "In15.Cu")
		(net "P5E_CPU0_P2_RX_BUF_DN<5>")
	)
	(segment
		(start 391.749788 -438.76976)
		(end 391.749788 -439.0898)
		(width 0.14224)
		(layer "In15.Cu")
		(net "P5E_CPU0_P2_RX_BUF_DN<5>")
	)
	(segment
		(start 406.851866 -405.456898)
		(end 406.227534 -405.969724)
		(width 0.14224)
		(layer "In15.Cu")
		(net "P5E_CPU0_P2_RX_BUF_DN<5>")
	)
	(segment
		(start 389.564372 -415.020252)
		(end 389.564372 -419.034722)
		(width 0.14224)
		(layer "In15.Cu")
		(net "P5E_CPU0_P2_RX_BUF_DN<5>")
	)
	(segment
		(start 390.800844 -425.234354)
		(end 390.800844 -438.265824)
		(width 0.14224)
		(layer "In15.Cu")
		(net "P5E_CPU0_P2_RX_BUF_DN<5>")
	)
	(segment
		(start 391.095992 -412.47822)
		(end 391.095992 -413.306514)
		(width 0.14224)
		(layer "In15.Cu")
		(net "P5E_CPU0_P2_RX_BUF_DN<5>")
	)
	(segment
		(start 390.57961 -413.90316)
		(end 390.329674 -414.006538)
		(width 0.14224)
		(layer "In15.Cu")
		(net "P5E_CPU0_P2_RX_BUF_DN<5>")
	)
	(segment
		(start 389.472932 -419.262814)
		(end 389.302498 -419.441376)
		(width 0.14224)
		(layer "In15.Cu")
		(net "P5E_CPU0_P2_RX_BUF_DN<5>")
	)
	(segment
		(start 405.618188 -406.376886)
		(end 405.060912 -406.607518)
		(width 0.14224)
		(layer "In15.Cu")
		(net "P5E_CPU0_P2_RX_BUF_DN<5>")
	)
	(segment
		(start 390.67867 -424.82389)
		(end 390.779508 -425.110148)
		(width 0.14224)
		(layer "In15.Cu")
		(net "P5E_CPU0_P2_RX_BUF_DN<5>")
	)
	(segment
		(start 388.149592 -419.908482)
		(end 388.111238 -419.984936)
		(width 0.14224)
		(layer "In15.Cu")
		(net "P5E_CPU0_P2_RX_BUF_DN<5>")
	)
	(segment
		(start 403.385274 -406.940766)
		(end 400.170396 -408.002994)
		(width 0.14224)
		(layer "In15.Cu")
		(net "P5E_CPU0_P2_RX_BUF_DN<5>")
	)
	(segment
		(start 409.44419 -400.979386)
		(end 409.30576 -401.117816)
		(width 0.14224)
		(layer "In15.Cu")
		(net "P5E_CPU0_P2_RX_BUF_DN<5>")
	)
	(segment
		(start 400.170396 -408.002994)
		(end 393.307062 -410.61767)
		(width 0.14224)
		(layer "In15.Cu")
		(net "P5E_CPU0_P2_RX_BUF_DN<5>")
	)
	(segment
		(start 408.594306 -403.714458)
		(end 406.851866 -405.456898)
		(width 0.14224)
		(layer "In15.Cu")
		(net "P5E_CPU0_P2_RX_BUF_DN<5>")
	)
	(segment
		(start 390.800844 -438.265824)
		(end 391.158222 -438.623202)
		(width 0.14224)
		(layer "In15.Cu")
		(net "P5E_CPU0_P2_RX_BUF_DN<5>")
	)
	(segment
		(start 408.703272 -403.451314)
		(end 408.594306 -403.714458)
		(width 0.14224)
		(layer "In15.Cu")
		(net "P5E_CPU0_P2_RX_BUF_DN<5>")
	)
	(segment
		(start 393.307062 -410.61767)
		(end 392.246612 -411.195012)
		(width 0.14224)
		(layer "In15.Cu")
		(net "P5E_CPU0_P2_RX_BUF_DN<5>")
	)
	(segment
		(start 389.497316 -423.348912)
		(end 390.614662 -424.710352)
		(width 0.14224)
		(layer "In15.Cu")
		(net "P5E_CPU0_P2_RX_BUF_DN<5>")
	)
	(segment
		(start 391.60323 -438.623202)
		(end 391.749788 -438.76976)
		(width 0.14224)
		(layer "In15.Cu")
		(net "P5E_CPU0_P2_RX_BUF_DN<5>")
	)
	(segment
		(start 390.84885 -413.723328)
		(end 390.57961 -413.90316)
		(width 0.14224)
		(layer "In15.Cu")
		(net "P5E_CPU0_P2_RX_BUF_DN<5>")
	)
	(segment
		(start 390.976104 -413.596074)
		(end 390.84885 -413.723328)
		(width 0.14224)
		(layer "In15.Cu")
		(net "P5E_CPU0_P2_RX_BUF_DN<5>")
	)
	(segment
		(start 391.492994 -411.758638)
		(end 391.324084 -411.927548)
		(width 0.14224)
		(layer "In15.Cu")
		(net "P5E_CPU0_P2_RX_BUF_DN<5>")
	)
	(segment
		(start 391.158222 -438.623202)
		(end 391.60323 -438.623202)
		(width 0.14224)
		(layer "In15.Cu")
		(net "P5E_CPU0_P2_RX_BUF_DN<5>")
	)
	(segment
		(start 409.44419 -400.811238)
		(end 409.44419 -400.979386)
		(width 0.14224)
		(layer "In15.Cu")
		(net "P5E_CPU0_P2_RX_BUF_DN<5>")
	)
	(segment
		(start 409.010612 -401.117816)
		(end 408.703272 -401.425156)
		(width 0.14224)
		(layer "In15.Cu")
		(net "P5E_CPU0_P2_RX_BUF_DN<5>")
	)
	(segment
		(start 388.315454 -422.166796)
		(end 389.497316 -423.348912)
		(width 0.14224)
		(layer "In15.Cu")
		(net "P5E_CPU0_P2_RX_BUF_DN<5>")
	)
	(segment
		(start 388.032752 -420.318946)
		(end 388.032752 -421.484298)
		(width 0.14224)
		(layer "In15.Cu")
		(net "P5E_CPU0_P2_RX_BUF_DN<5>")
	)
	(segment
		(start 405.060912 -406.607518)
		(end 403.385274 -406.940766)
		(width 0.14224)
		(layer "In15.Cu")
		(net "P5E_CPU0_P2_RX_BUF_DN<5>")
	)
	(arc
		(start 389.302498 -419.441376)
		(mid 389.278264 -419.461162)
		(end 389.24992 -419.474396)
		(width 0.14224)
		(layer "In15.Cu")
		(net "P5E_CPU0_P2_RX_BUF_DN<5>")
	)
	(arc
		(start 389.564372 -419.034722)
		(mid 389.540661 -419.157591)
		(end 389.472932 -419.262814)
		(width 0.14224)
		(layer "In15.Cu")
		(net "P5E_CPU0_P2_RX_BUF_DN<5>")
	)
	(arc
		(start 391.324084 -411.927548)
		(mid 391.155268 -412.180198)
		(end 391.095992 -412.47822)
		(width 0.14224)
		(layer "In15.Cu")
		(net "P5E_CPU0_P2_RX_BUF_DN<5>")
	)
	(arc
		(start 390.614662 -424.710352)
		(mid 390.65163 -424.764323)
		(end 390.67867 -424.82389)
		(width 0.14224)
		(layer "In15.Cu")
		(net "P5E_CPU0_P2_RX_BUF_DN<5>")
	)
	(arc
		(start 392.246612 -411.195012)
		(mid 391.849555 -411.449754)
		(end 391.492994 -411.758638)
		(width 0.14224)
		(layer "In15.Cu")
		(net "P5E_CPU0_P2_RX_BUF_DN<5>")
	)
	(arc
		(start 390.779508 -425.110148)
		(mid 390.795462 -425.171344)
		(end 390.800844 -425.234354)
		(width 0.14224)
		(layer "In15.Cu")
		(net "P5E_CPU0_P2_RX_BUF_DN<5>")
	)
	(arc
		(start 388.032752 -421.484298)
		(mid 388.106223 -421.853664)
		(end 388.315454 -422.166796)
		(width 0.14224)
		(layer "In15.Cu")
		(net "P5E_CPU0_P2_RX_BUF_DN<5>")
	)
	(arc
		(start 389.8519 -414.32607)
		(mid 389.639011 -414.644536)
		(end 389.564372 -415.020252)
		(width 0.14224)
		(layer "In15.Cu")
		(net "P5E_CPU0_P2_RX_BUF_DN<5>")
	)
	(arc
		(start 391.095992 -413.306514)
		(mid 391.06484 -413.463217)
		(end 390.976104 -413.596074)
		(width 0.14224)
		(layer "In15.Cu")
		(net "P5E_CPU0_P2_RX_BUF_DN<5>")
	)
	(arc
		(start 390.329674 -414.006538)
		(mid 390.07507 -414.142803)
		(end 389.8519 -414.32607)
		(width 0.14224)
		(layer "In15.Cu")
		(net "P5E_CPU0_P2_RX_BUF_DN<5>")
	)
	(arc
		(start 388.111238 -419.984936)
		(mid 388.052574 -420.147376)
		(end 388.032752 -420.318946)
		(width 0.14224)
		(layer "In15.Cu")
		(net "P5E_CPU0_P2_RX_BUF_DN<5>")
	)
	(segment
		(start 407.88463 -401.143216)
		(end 408.103578 -401.143216)
		(width 0.1016)
		(layer "F.Cu")
		(net "P5E_CPU0_P2_RX_BUF_DN<4>")
	)
	(segment
		(start 407.846276 -399.143982)
		(end 407.846276 -399.960338)
		(width 0.1016)
		(layer "F.Cu")
		(net "P5E_CPU0_P2_RX_BUF_DN<4>")
	)
	(segment
		(start 407.845768 -399.143474)
		(end 407.846276 -399.143982)
		(width 0.1016)
		(layer "F.Cu")
		(net "P5E_CPU0_P2_RX_BUF_DN<4>")
	)
	(segment
		(start 408.103578 -401.143216)
		(end 408.244294 -401.0025)
		(width 0.1016)
		(layer "F.Cu")
		(net "P5E_CPU0_P2_RX_BUF_DN<4>")
	)
	(segment
		(start 407.75763 -400.048984)
		(end 407.75763 -401.016216)
		(width 0.1016)
		(layer "F.Cu")
		(net "P5E_CPU0_P2_RX_BUF_DN<4>")
	)
	(segment
		(start 407.846276 -399.960338)
		(end 407.75763 -400.048984)
		(width 0.1016)
		(layer "F.Cu")
		(net "P5E_CPU0_P2_RX_BUF_DN<4>")
	)
	(segment
		(start 408.244294 -401.0025)
		(end 408.244294 -400.811238)
		(width 0.1016)
		(layer "F.Cu")
		(net "P5E_CPU0_P2_RX_BUF_DN<4>")
	)
	(segment
		(start 407.75763 -401.016216)
		(end 407.88463 -401.143216)
		(width 0.1016)
		(layer "F.Cu")
		(net "P5E_CPU0_P2_RX_BUF_DN<4>")
	)
	(segment
		(start 384.969512 -420.22776)
		(end 384.969512 -421.21836)
		(width 0.14224)
		(layer "In15.Cu")
		(net "P5E_CPU0_P2_RX_BUF_DN<4>")
	)
	(segment
		(start 386.501132 -415.020252)
		(end 386.501132 -419.079426)
		(width 0.14224)
		(layer "In15.Cu")
		(net "P5E_CPU0_P2_RX_BUF_DN<4>")
	)
	(segment
		(start 389.603234 -437.623204)
		(end 389.749792 -437.769762)
		(width 0.14224)
		(layer "In15.Cu")
		(net "P5E_CPU0_P2_RX_BUF_DN<4>")
	)
	(segment
		(start 407.810716 -401.117816)
		(end 407.503376 -401.425156)
		(width 0.14224)
		(layer "In15.Cu")
		(net "P5E_CPU0_P2_RX_BUF_DN<4>")
	)
	(segment
		(start 408.244294 -400.811238)
		(end 408.244294 -400.979386)
		(width 0.14224)
		(layer "In15.Cu")
		(net "P5E_CPU0_P2_RX_BUF_DN<4>")
	)
	(segment
		(start 405.232108 -405.452326)
		(end 404.888446 -405.594566)
		(width 0.14224)
		(layer "In15.Cu")
		(net "P5E_CPU0_P2_RX_BUF_DN<4>")
	)
	(segment
		(start 407.345642 -403.475952)
		(end 407.10612 -403.8346)
		(width 0.14224)
		(layer "In15.Cu")
		(net "P5E_CPU0_P2_RX_BUF_DN<4>")
	)
	(segment
		(start 387.51637 -413.90316)
		(end 387.266434 -414.006538)
		(width 0.14224)
		(layer "In15.Cu")
		(net "P5E_CPU0_P2_RX_BUF_DN<4>")
	)
	(segment
		(start 386.183886 -419.441376)
		(end 385.231132 -419.836346)
		(width 0.14224)
		(layer "In15.Cu")
		(net "P5E_CPU0_P2_RX_BUF_DN<4>")
	)
	(segment
		(start 387.78561 -413.723328)
		(end 387.51637 -413.90316)
		(width 0.14224)
		(layer "In15.Cu")
		(net "P5E_CPU0_P2_RX_BUF_DN<4>")
	)
	(segment
		(start 408.244294 -400.979386)
		(end 408.105864 -401.117816)
		(width 0.14224)
		(layer "In15.Cu")
		(net "P5E_CPU0_P2_RX_BUF_DN<4>")
	)
	(segment
		(start 408.105864 -401.117816)
		(end 407.810716 -401.117816)
		(width 0.14224)
		(layer "In15.Cu")
		(net "P5E_CPU0_P2_RX_BUF_DN<4>")
	)
	(segment
		(start 388.371588 -411.734254)
		(end 388.306564 -411.799278)
		(width 0.14224)
		(layer "In15.Cu")
		(net "P5E_CPU0_P2_RX_BUF_DN<4>")
	)
	(segment
		(start 386.455158 -419.194234)
		(end 386.287518 -419.370256)
		(width 0.14224)
		(layer "In15.Cu")
		(net "P5E_CPU0_P2_RX_BUF_DN<4>")
	)
	(segment
		(start 407.503376 -401.425156)
		(end 407.503376 -403.09546)
		(width 0.14224)
		(layer "In15.Cu")
		(net "P5E_CPU0_P2_RX_BUF_DN<4>")
	)
	(segment
		(start 403.92731 -405.785574)
		(end 401.641056 -406.389078)
		(width 0.14224)
		(layer "In15.Cu")
		(net "P5E_CPU0_P2_RX_BUF_DN<4>")
	)
	(segment
		(start 407.10612 -403.8346)
		(end 406.00376 -404.93696)
		(width 0.14224)
		(layer "In15.Cu")
		(net "P5E_CPU0_P2_RX_BUF_DN<4>")
	)
	(segment
		(start 404.888446 -405.594566)
		(end 403.92731 -405.785574)
		(width 0.14224)
		(layer "In15.Cu")
		(net "P5E_CPU0_P2_RX_BUF_DN<4>")
	)
	(segment
		(start 389.749792 -437.769762)
		(end 389.749792 -438.089802)
		(width 0.14224)
		(layer "In15.Cu")
		(net "P5E_CPU0_P2_RX_BUF_DN<4>")
	)
	(segment
		(start 388.789164 -424.919648)
		(end 388.789164 -437.320944)
		(width 0.14224)
		(layer "In15.Cu")
		(net "P5E_CPU0_P2_RX_BUF_DN<4>")
	)
	(segment
		(start 407.503376 -403.09546)
		(end 407.345642 -403.475952)
		(width 0.14224)
		(layer "In15.Cu")
		(net "P5E_CPU0_P2_RX_BUF_DN<4>")
	)
	(segment
		(start 401.641056 -406.389078)
		(end 395.0462 -408.573224)
		(width 0.14224)
		(layer "In15.Cu")
		(net "P5E_CPU0_P2_RX_BUF_DN<4>")
	)
	(segment
		(start 387.912864 -413.596074)
		(end 387.78561 -413.723328)
		(width 0.14224)
		(layer "In15.Cu")
		(net "P5E_CPU0_P2_RX_BUF_DN<4>")
	)
	(segment
		(start 388.032752 -412.46044)
		(end 388.032752 -413.306514)
		(width 0.14224)
		(layer "In15.Cu")
		(net "P5E_CPU0_P2_RX_BUF_DN<4>")
	)
	(segment
		(start 385.731004 -422.33977)
		(end 387.946138 -423.821352)
		(width 0.14224)
		(layer "In15.Cu")
		(net "P5E_CPU0_P2_RX_BUF_DN<4>")
	)
	(segment
		(start 388.228332 -424.090084)
		(end 388.744968 -424.78579)
		(width 0.14224)
		(layer "In15.Cu")
		(net "P5E_CPU0_P2_RX_BUF_DN<4>")
	)
	(segment
		(start 389.091424 -437.623204)
		(end 389.603234 -437.623204)
		(width 0.14224)
		(layer "In15.Cu")
		(net "P5E_CPU0_P2_RX_BUF_DN<4>")
	)
	(segment
		(start 406.00376 -404.93696)
		(end 405.232108 -405.452326)
		(width 0.14224)
		(layer "In15.Cu")
		(net "P5E_CPU0_P2_RX_BUF_DN<4>")
	)
	(segment
		(start 388.789164 -437.320944)
		(end 389.091424 -437.623204)
		(width 0.14224)
		(layer "In15.Cu")
		(net "P5E_CPU0_P2_RX_BUF_DN<4>")
	)
	(segment
		(start 385.343146 -421.992298)
		(end 385.59486 -422.231058)
		(width 0.14224)
		(layer "In15.Cu")
		(net "P5E_CPU0_P2_RX_BUF_DN<4>")
	)
	(segment
		(start 395.0462 -408.573224)
		(end 389.58393 -410.91358)
		(width 0.14224)
		(layer "In15.Cu")
		(net "P5E_CPU0_P2_RX_BUF_DN<4>")
	)
	(segment
		(start 385.038854 -421.495982)
		(end 385.211828 -421.82034)
		(width 0.14224)
		(layer "In15.Cu")
		(net "P5E_CPU0_P2_RX_BUF_DN<4>")
	)
	(arc
		(start 388.306564 -411.799278)
		(mid 388.10393 -412.102636)
		(end 388.032752 -412.46044)
		(width 0.14224)
		(layer "In15.Cu")
		(net "P5E_CPU0_P2_RX_BUF_DN<4>")
	)
	(arc
		(start 389.58393 -410.91358)
		(mid 388.938604 -411.266073)
		(end 388.371588 -411.734254)
		(width 0.14224)
		(layer "In15.Cu")
		(net "P5E_CPU0_P2_RX_BUF_DN<4>")
	)
	(arc
		(start 386.78866 -414.32607)
		(mid 386.575771 -414.644536)
		(end 386.501132 -415.020252)
		(width 0.14224)
		(layer "In15.Cu")
		(net "P5E_CPU0_P2_RX_BUF_DN<4>")
	)
	(arc
		(start 384.969512 -421.21836)
		(mid 384.987113 -421.361434)
		(end 385.038854 -421.495982)
		(width 0.14224)
		(layer "In15.Cu")
		(net "P5E_CPU0_P2_RX_BUF_DN<4>")
	)
	(arc
		(start 385.231132 -419.836346)
		(mid 385.040965 -419.992372)
		(end 384.969512 -420.22776)
		(width 0.14224)
		(layer "In15.Cu")
		(net "P5E_CPU0_P2_RX_BUF_DN<4>")
	)
	(arc
		(start 388.032752 -413.306514)
		(mid 388.0016 -413.463217)
		(end 387.912864 -413.596074)
		(width 0.14224)
		(layer "In15.Cu")
		(net "P5E_CPU0_P2_RX_BUF_DN<4>")
	)
	(arc
		(start 386.501132 -419.079426)
		(mid 386.489213 -419.141263)
		(end 386.455158 -419.194234)
		(width 0.14224)
		(layer "In15.Cu")
		(net "P5E_CPU0_P2_RX_BUF_DN<4>")
	)
	(arc
		(start 387.946138 -423.821352)
		(mid 388.098766 -423.94361)
		(end 388.228332 -424.090084)
		(width 0.14224)
		(layer "In15.Cu")
		(net "P5E_CPU0_P2_RX_BUF_DN<4>")
	)
	(arc
		(start 388.744968 -424.78579)
		(mid 388.777832 -424.849165)
		(end 388.789164 -424.919648)
		(width 0.14224)
		(layer "In15.Cu")
		(net "P5E_CPU0_P2_RX_BUF_DN<4>")
	)
	(arc
		(start 386.287518 -419.370256)
		(mid 386.239429 -419.411248)
		(end 386.183886 -419.441376)
		(width 0.14224)
		(layer "In15.Cu")
		(net "P5E_CPU0_P2_RX_BUF_DN<4>")
	)
	(arc
		(start 385.59486 -422.231058)
		(mid 385.660634 -422.288292)
		(end 385.731004 -422.33977)
		(width 0.14224)
		(layer "In15.Cu")
		(net "P5E_CPU0_P2_RX_BUF_DN<4>")
	)
	(arc
		(start 385.211828 -421.82034)
		(mid 385.270552 -421.911616)
		(end 385.343146 -421.992298)
		(width 0.14224)
		(layer "In15.Cu")
		(net "P5E_CPU0_P2_RX_BUF_DN<4>")
	)
	(arc
		(start 387.266434 -414.006538)
		(mid 387.01183 -414.142803)
		(end 386.78866 -414.32607)
		(width 0.14224)
		(layer "In15.Cu")
		(net "P5E_CPU0_P2_RX_BUF_DN<4>")
	)
	(segment
		(start 406.645618 -399.143474)
		(end 406.646126 -399.143982)
		(width 0.1016)
		(layer "F.Cu")
		(net "P5E_CPU0_P2_RX_BUF_DN<3>")
	)
	(segment
		(start 406.570688 -400.035776)
		(end 406.570688 -401.016216)
		(width 0.1016)
		(layer "F.Cu")
		(net "P5E_CPU0_P2_RX_BUF_DN<3>")
	)
	(segment
		(start 406.570688 -401.016216)
		(end 406.697688 -401.143216)
		(width 0.1016)
		(layer "F.Cu")
		(net "P5E_CPU0_P2_RX_BUF_DN<3>")
	)
	(segment
		(start 406.646126 -399.143982)
		(end 406.646126 -399.960338)
		(width 0.1016)
		(layer "F.Cu")
		(net "P5E_CPU0_P2_RX_BUF_DN<3>")
	)
	(segment
		(start 406.646126 -399.960338)
		(end 406.570688 -400.035776)
		(width 0.1016)
		(layer "F.Cu")
		(net "P5E_CPU0_P2_RX_BUF_DN<3>")
	)
	(segment
		(start 407.044144 -401.0025)
		(end 407.044144 -400.811238)
		(width 0.1016)
		(layer "F.Cu")
		(net "P5E_CPU0_P2_RX_BUF_DN<3>")
	)
	(segment
		(start 406.697688 -401.143216)
		(end 406.903428 -401.143216)
		(width 0.1016)
		(layer "F.Cu")
		(net "P5E_CPU0_P2_RX_BUF_DN<3>")
	)
	(segment
		(start 406.903428 -401.143216)
		(end 407.044144 -401.0025)
		(width 0.1016)
		(layer "F.Cu")
		(net "P5E_CPU0_P2_RX_BUF_DN<3>")
	)
	(segment
		(start 407.044144 -400.811238)
		(end 407.044144 -400.979386)
		(width 0.14224)
		(layer "In15.Cu")
		(net "P5E_CPU0_P2_RX_BUF_DN<3>")
	)
	(segment
		(start 382.47447 -422.187878)
		(end 384.3782 -422.976548)
		(width 0.14224)
		(layer "In15.Cu")
		(net "P5E_CPU0_P2_RX_BUF_DN<3>")
	)
	(segment
		(start 381.997204 -421.710612)
		(end 382.47447 -422.187878)
		(width 0.14224)
		(layer "In15.Cu")
		(net "P5E_CPU0_P2_RX_BUF_DN<3>")
	)
	(segment
		(start 386.789168 -438.320942)
		(end 387.091428 -438.623202)
		(width 0.14224)
		(layer "In15.Cu")
		(net "P5E_CPU0_P2_RX_BUF_DN<3>")
	)
	(segment
		(start 381.906272 -420.250112)
		(end 381.906272 -421.490902)
		(width 0.14224)
		(layer "In15.Cu")
		(net "P5E_CPU0_P2_RX_BUF_DN<3>")
	)
	(segment
		(start 406.118314 -403.436836)
		(end 405.454358 -404.100792)
		(width 0.14224)
		(layer "In15.Cu")
		(net "P5E_CPU0_P2_RX_BUF_DN<3>")
	)
	(segment
		(start 387.603238 -438.623202)
		(end 387.749796 -438.76976)
		(width 0.14224)
		(layer "In15.Cu")
		(net "P5E_CPU0_P2_RX_BUF_DN<3>")
	)
	(segment
		(start 384.969512 -412.106618)
		(end 384.969512 -413.306514)
		(width 0.14224)
		(layer "In15.Cu")
		(net "P5E_CPU0_P2_RX_BUF_DN<3>")
	)
	(segment
		(start 384.849624 -413.596074)
		(end 384.72237 -413.723328)
		(width 0.14224)
		(layer "In15.Cu")
		(net "P5E_CPU0_P2_RX_BUF_DN<3>")
	)
	(segment
		(start 404.70201 -404.594568)
		(end 400.963638 -405.580088)
		(width 0.14224)
		(layer "In15.Cu")
		(net "P5E_CPU0_P2_RX_BUF_DN<3>")
	)
	(segment
		(start 386.454142 -424.650408)
		(end 386.765292 -425.232322)
		(width 0.14224)
		(layer "In15.Cu")
		(net "P5E_CPU0_P2_RX_BUF_DN<3>")
	)
	(segment
		(start 406.905714 -401.117816)
		(end 406.610566 -401.117816)
		(width 0.14224)
		(layer "In15.Cu")
		(net "P5E_CPU0_P2_RX_BUF_DN<3>")
	)
	(segment
		(start 384.3782 -422.976548)
		(end 385.794758 -423.922952)
		(width 0.14224)
		(layer "In15.Cu")
		(net "P5E_CPU0_P2_RX_BUF_DN<3>")
	)
	(segment
		(start 381.906272 -421.490902)
		(end 381.997204 -421.710612)
		(width 0.14224)
		(layer "In15.Cu")
		(net "P5E_CPU0_P2_RX_BUF_DN<3>")
	)
	(segment
		(start 387.749796 -438.76976)
		(end 387.749796 -439.0898)
		(width 0.14224)
		(layer "In15.Cu")
		(net "P5E_CPU0_P2_RX_BUF_DN<3>")
	)
	(segment
		(start 384.72237 -413.723328)
		(end 384.45313 -413.90316)
		(width 0.14224)
		(layer "In15.Cu")
		(net "P5E_CPU0_P2_RX_BUF_DN<3>")
	)
	(segment
		(start 383.386076 -419.23462)
		(end 383.209292 -419.383464)
		(width 0.14224)
		(layer "In15.Cu")
		(net "P5E_CPU0_P2_RX_BUF_DN<3>")
	)
	(segment
		(start 384.45313 -413.90316)
		(end 384.203194 -414.006538)
		(width 0.14224)
		(layer "In15.Cu")
		(net "P5E_CPU0_P2_RX_BUF_DN<3>")
	)
	(segment
		(start 383.437892 -415.020252)
		(end 383.437892 -419.123622)
		(width 0.14224)
		(layer "In15.Cu")
		(net "P5E_CPU0_P2_RX_BUF_DN<3>")
	)
	(segment
		(start 400.963638 -405.580088)
		(end 395.134592 -407.466038)
		(width 0.14224)
		(layer "In15.Cu")
		(net "P5E_CPU0_P2_RX_BUF_DN<3>")
	)
	(segment
		(start 406.303226 -401.425156)
		(end 406.303226 -402.990558)
		(width 0.14224)
		(layer "In15.Cu")
		(net "P5E_CPU0_P2_RX_BUF_DN<3>")
	)
	(segment
		(start 404.928832 -404.480268)
		(end 404.70201 -404.594568)
		(width 0.14224)
		(layer "In15.Cu")
		(net "P5E_CPU0_P2_RX_BUF_DN<3>")
	)
	(segment
		(start 406.610566 -401.117816)
		(end 406.303226 -401.425156)
		(width 0.14224)
		(layer "In15.Cu")
		(net "P5E_CPU0_P2_RX_BUF_DN<3>")
	)
	(segment
		(start 405.454358 -404.100792)
		(end 404.929086 -404.480268)
		(width 0.14224)
		(layer "In15.Cu")
		(net "P5E_CPU0_P2_RX_BUF_DN<3>")
	)
	(segment
		(start 404.929086 -404.480268)
		(end 404.928832 -404.480268)
		(width 0.14224)
		(layer "In15.Cu")
		(net "P5E_CPU0_P2_RX_BUF_DN<3>")
	)
	(segment
		(start 383.101596 -419.44925)
		(end 382.187704 -419.828218)
		(width 0.14224)
		(layer "In15.Cu")
		(net "P5E_CPU0_P2_RX_BUF_DN<3>")
	)
	(segment
		(start 387.091428 -438.623202)
		(end 387.603238 -438.623202)
		(width 0.14224)
		(layer "In15.Cu")
		(net "P5E_CPU0_P2_RX_BUF_DN<3>")
	)
	(segment
		(start 386.789168 -425.32681)
		(end 386.789168 -438.320942)
		(width 0.14224)
		(layer "In15.Cu")
		(net "P5E_CPU0_P2_RX_BUF_DN<3>")
	)
	(segment
		(start 395.134592 -407.466038)
		(end 386.00507 -410.985716)
		(width 0.14224)
		(layer "In15.Cu")
		(net "P5E_CPU0_P2_RX_BUF_DN<3>")
	)
	(segment
		(start 407.044144 -400.979386)
		(end 406.905714 -401.117816)
		(width 0.14224)
		(layer "In15.Cu")
		(net "P5E_CPU0_P2_RX_BUF_DN<3>")
	)
	(segment
		(start 406.303226 -402.990558)
		(end 406.118314 -403.436836)
		(width 0.14224)
		(layer "In15.Cu")
		(net "P5E_CPU0_P2_RX_BUF_DN<3>")
	)
	(arc
		(start 384.203194 -414.006538)
		(mid 383.94859 -414.142803)
		(end 383.72542 -414.32607)
		(width 0.14224)
		(layer "In15.Cu")
		(net "P5E_CPU0_P2_RX_BUF_DN<3>")
	)
	(arc
		(start 385.219702 -411.50286)
		(mid 385.034583 -411.779866)
		(end 384.969512 -412.106618)
		(width 0.14224)
		(layer "In15.Cu")
		(net "P5E_CPU0_P2_RX_BUF_DN<3>")
	)
	(arc
		(start 386.00507 -410.985716)
		(mid 385.591648 -411.212793)
		(end 385.219702 -411.50286)
		(width 0.14224)
		(layer "In15.Cu")
		(net "P5E_CPU0_P2_RX_BUF_DN<3>")
	)
	(arc
		(start 385.794758 -423.922952)
		(mid 386.169296 -424.246032)
		(end 386.454142 -424.650408)
		(width 0.14224)
		(layer "In15.Cu")
		(net "P5E_CPU0_P2_RX_BUF_DN<3>")
	)
	(arc
		(start 382.187704 -419.828218)
		(mid 381.983086 -419.996538)
		(end 381.906272 -420.250112)
		(width 0.14224)
		(layer "In15.Cu")
		(net "P5E_CPU0_P2_RX_BUF_DN<3>")
	)
	(arc
		(start 383.437892 -419.123622)
		(mid 383.424246 -419.184843)
		(end 383.386076 -419.23462)
		(width 0.14224)
		(layer "In15.Cu")
		(net "P5E_CPU0_P2_RX_BUF_DN<3>")
	)
	(arc
		(start 386.765292 -425.232322)
		(mid 386.783068 -425.278093)
		(end 386.789168 -425.32681)
		(width 0.14224)
		(layer "In15.Cu")
		(net "P5E_CPU0_P2_RX_BUF_DN<3>")
	)
	(arc
		(start 384.969512 -413.306514)
		(mid 384.93836 -413.463217)
		(end 384.849624 -413.596074)
		(width 0.14224)
		(layer "In15.Cu")
		(net "P5E_CPU0_P2_RX_BUF_DN<3>")
	)
	(arc
		(start 383.72542 -414.32607)
		(mid 383.512531 -414.644536)
		(end 383.437892 -415.020252)
		(width 0.14224)
		(layer "In15.Cu")
		(net "P5E_CPU0_P2_RX_BUF_DN<3>")
	)
	(arc
		(start 383.209292 -419.383464)
		(mid 383.157988 -419.420525)
		(end 383.101596 -419.44925)
		(width 0.14224)
		(layer "In15.Cu")
		(net "P5E_CPU0_P2_RX_BUF_DN<3>")
	)
	(segment
		(start 405.445722 -399.143474)
		(end 405.44623 -399.143982)
		(width 0.1016)
		(layer "F.Cu")
		(net "P5E_CPU0_P2_RX_BUF_DN<2>")
	)
	(segment
		(start 405.357584 -401.016216)
		(end 405.484584 -401.143216)
		(width 0.1016)
		(layer "F.Cu")
		(net "P5E_CPU0_P2_RX_BUF_DN<2>")
	)
	(segment
		(start 405.703532 -401.143216)
		(end 405.844248 -401.0025)
		(width 0.1016)
		(layer "F.Cu")
		(net "P5E_CPU0_P2_RX_BUF_DN<2>")
	)
	(segment
		(start 405.44623 -399.143982)
		(end 405.44623 -399.960338)
		(width 0.1016)
		(layer "F.Cu")
		(net "P5E_CPU0_P2_RX_BUF_DN<2>")
	)
	(segment
		(start 405.484584 -401.143216)
		(end 405.703532 -401.143216)
		(width 0.1016)
		(layer "F.Cu")
		(net "P5E_CPU0_P2_RX_BUF_DN<2>")
	)
	(segment
		(start 405.357584 -400.048984)
		(end 405.357584 -401.016216)
		(width 0.1016)
		(layer "F.Cu")
		(net "P5E_CPU0_P2_RX_BUF_DN<2>")
	)
	(segment
		(start 405.44623 -399.960338)
		(end 405.357584 -400.048984)
		(width 0.1016)
		(layer "F.Cu")
		(net "P5E_CPU0_P2_RX_BUF_DN<2>")
	)
	(segment
		(start 405.844248 -401.0025)
		(end 405.844248 -400.811238)
		(width 0.1016)
		(layer "F.Cu")
		(net "P5E_CPU0_P2_RX_BUF_DN<2>")
	)
	(segment
		(start 383.915412 -424.001438)
		(end 384.6322 -424.750738)
		(width 0.14224)
		(layer "In15.Cu")
		(net "P5E_CPU0_P2_RX_BUF_DN<2>")
	)
	(segment
		(start 379.250702 -419.78707)
		(end 379.06325 -419.984682)
		(width 0.14224)
		(layer "In15.Cu")
		(net "P5E_CPU0_P2_RX_BUF_DN<2>")
	)
	(segment
		(start 382.392682 -411.414214)
		(end 382.214374 -411.555946)
		(width 0.14224)
		(layer "In15.Cu")
		(net "P5E_CPU0_P2_RX_BUF_DN<2>")
	)
	(segment
		(start 405.10333 -401.425156)
		(end 405.10333 -402.947886)
		(width 0.14224)
		(layer "In15.Cu")
		(net "P5E_CPU0_P2_RX_BUF_DN<2>")
	)
	(segment
		(start 379.459744 -422.201086)
		(end 379.459744 -422.200578)
		(width 0.14224)
		(layer "In15.Cu")
		(net "P5E_CPU0_P2_RX_BUF_DN<2>")
	)
	(segment
		(start 404.69693 -403.437344)
		(end 404.206964 -403.699726)
		(width 0.14224)
		(layer "In15.Cu")
		(net "P5E_CPU0_P2_RX_BUF_DN<2>")
	)
	(segment
		(start 381.38989 -413.90316)
		(end 381.139954 -414.006538)
		(width 0.14224)
		(layer "In15.Cu")
		(net "P5E_CPU0_P2_RX_BUF_DN<2>")
	)
	(segment
		(start 379.658118 -422.297098)
		(end 380.34214 -422.496234)
		(width 0.14224)
		(layer "In15.Cu")
		(net "P5E_CPU0_P2_RX_BUF_DN<2>")
	)
	(segment
		(start 384.789172 -437.320944)
		(end 385.091432 -437.623204)
		(width 0.14224)
		(layer "In15.Cu")
		(net "P5E_CPU0_P2_RX_BUF_DN<2>")
	)
	(segment
		(start 405.10333 -402.947886)
		(end 404.921974 -403.28723)
		(width 0.14224)
		(layer "In15.Cu")
		(net "P5E_CPU0_P2_RX_BUF_DN<2>")
	)
	(segment
		(start 380.374652 -415.020252)
		(end 380.374652 -418.933122)
		(width 0.14224)
		(layer "In15.Cu")
		(net "P5E_CPU0_P2_RX_BUF_DN<2>")
	)
	(segment
		(start 404.921974 -403.28723)
		(end 404.69693 -403.437344)
		(width 0.14224)
		(layer "In15.Cu")
		(net "P5E_CPU0_P2_RX_BUF_DN<2>")
	)
	(segment
		(start 380.321566 -419.061392)
		(end 380.094998 -419.28796)
		(width 0.14224)
		(layer "In15.Cu")
		(net "P5E_CPU0_P2_RX_BUF_DN<2>")
	)
	(segment
		(start 396.604236 -405.660606)
		(end 382.57226 -411.310074)
		(width 0.14224)
		(layer "In15.Cu")
		(net "P5E_CPU0_P2_RX_BUF_DN<2>")
	)
	(segment
		(start 385.091432 -437.623204)
		(end 385.603242 -437.623204)
		(width 0.14224)
		(layer "In15.Cu")
		(net "P5E_CPU0_P2_RX_BUF_DN<2>")
	)
	(segment
		(start 404.206964 -403.699726)
		(end 403.935184 -403.811994)
		(width 0.14224)
		(layer "In15.Cu")
		(net "P5E_CPU0_P2_RX_BUF_DN<2>")
	)
	(segment
		(start 380.539498 -422.565576)
		(end 383.776474 -423.906442)
		(width 0.14224)
		(layer "In15.Cu")
		(net "P5E_CPU0_P2_RX_BUF_DN<2>")
	)
	(segment
		(start 405.705818 -401.117816)
		(end 405.41067 -401.117816)
		(width 0.14224)
		(layer "In15.Cu")
		(net "P5E_CPU0_P2_RX_BUF_DN<2>")
	)
	(segment
		(start 384.789172 -425.14139)
		(end 384.789172 -437.320944)
		(width 0.14224)
		(layer "In15.Cu")
		(net "P5E_CPU0_P2_RX_BUF_DN<2>")
	)
	(segment
		(start 405.41067 -401.117816)
		(end 405.10333 -401.425156)
		(width 0.14224)
		(layer "In15.Cu")
		(net "P5E_CPU0_P2_RX_BUF_DN<2>")
	)
	(segment
		(start 400.708622 -404.556722)
		(end 396.604236 -405.660606)
		(width 0.14224)
		(layer "In15.Cu")
		(net "P5E_CPU0_P2_RX_BUF_DN<2>")
	)
	(segment
		(start 381.906272 -412.410402)
		(end 381.906272 -413.306514)
		(width 0.14224)
		(layer "In15.Cu")
		(net "P5E_CPU0_P2_RX_BUF_DN<2>")
	)
	(segment
		(start 380.040134 -419.332918)
		(end 379.784356 -419.503606)
		(width 0.14224)
		(layer "In15.Cu")
		(net "P5E_CPU0_P2_RX_BUF_DN<2>")
	)
	(segment
		(start 405.844248 -400.811238)
		(end 405.844248 -400.979386)
		(width 0.14224)
		(layer "In15.Cu")
		(net "P5E_CPU0_P2_RX_BUF_DN<2>")
	)
	(segment
		(start 379.721364 -419.537388)
		(end 379.451108 -419.649148)
		(width 0.14224)
		(layer "In15.Cu")
		(net "P5E_CPU0_P2_RX_BUF_DN<2>")
	)
	(segment
		(start 382.014476 -411.857444)
		(end 381.94996 -412.089854)
		(width 0.14224)
		(layer "In15.Cu")
		(net "P5E_CPU0_P2_RX_BUF_DN<2>")
	)
	(segment
		(start 379.203204 -422.01719)
		(end 379.459744 -422.201086)
		(width 0.14224)
		(layer "In15.Cu")
		(net "P5E_CPU0_P2_RX_BUF_DN<2>")
	)
	(segment
		(start 405.844248 -400.979386)
		(end 405.705818 -401.117816)
		(width 0.14224)
		(layer "In15.Cu")
		(net "P5E_CPU0_P2_RX_BUF_DN<2>")
	)
	(segment
		(start 381.65913 -413.723328)
		(end 381.38989 -413.90316)
		(width 0.14224)
		(layer "In15.Cu")
		(net "P5E_CPU0_P2_RX_BUF_DN<2>")
	)
	(segment
		(start 379.450346 -419.649402)
		(end 379.4506 -419.649656)
		(width 0.14224)
		(layer "In15.Cu")
		(net "P5E_CPU0_P2_RX_BUF_DN<2>")
	)
	(segment
		(start 378.843032 -420.53764)
		(end 378.843032 -421.317166)
		(width 0.14224)
		(layer "In15.Cu")
		(net "P5E_CPU0_P2_RX_BUF_DN<2>")
	)
	(segment
		(start 403.935184 -403.811994)
		(end 400.708622 -404.556722)
		(width 0.14224)
		(layer "In15.Cu")
		(net "P5E_CPU0_P2_RX_BUF_DN<2>")
	)
	(segment
		(start 385.603242 -437.623204)
		(end 385.7498 -437.769762)
		(width 0.14224)
		(layer "In15.Cu")
		(net "P5E_CPU0_P2_RX_BUF_DN<2>")
	)
	(segment
		(start 379.451108 -419.649148)
		(end 379.450346 -419.649402)
		(width 0.14224)
		(layer "In15.Cu")
		(net "P5E_CPU0_P2_RX_BUF_DN<2>")
	)
	(segment
		(start 381.786384 -413.596074)
		(end 381.65913 -413.723328)
		(width 0.14224)
		(layer "In15.Cu")
		(net "P5E_CPU0_P2_RX_BUF_DN<2>")
	)
	(segment
		(start 385.7498 -437.769762)
		(end 385.7498 -438.089802)
		(width 0.14224)
		(layer "In15.Cu")
		(net "P5E_CPU0_P2_RX_BUF_DN<2>")
	)
	(arc
		(start 379.4506 -419.649656)
		(mid 379.343436 -419.707867)
		(end 379.250702 -419.78707)
		(width 0.14224)
		(layer "In15.Cu")
		(net "P5E_CPU0_P2_RX_BUF_DN<2>")
	)
	(arc
		(start 380.66218 -414.32607)
		(mid 380.449291 -414.644536)
		(end 380.374652 -415.020252)
		(width 0.14224)
		(layer "In15.Cu")
		(net "P5E_CPU0_P2_RX_BUF_DN<2>")
	)
	(arc
		(start 379.784356 -419.503606)
		(mid 379.753687 -419.522039)
		(end 379.721364 -419.537388)
		(width 0.14224)
		(layer "In15.Cu")
		(net "P5E_CPU0_P2_RX_BUF_DN<2>")
	)
	(arc
		(start 378.843032 -421.317166)
		(mid 378.938414 -421.710756)
		(end 379.203204 -422.01719)
		(width 0.14224)
		(layer "In15.Cu")
		(net "P5E_CPU0_P2_RX_BUF_DN<2>")
	)
	(arc
		(start 381.94996 -412.089854)
		(mid 381.917203 -412.248642)
		(end 381.906272 -412.410402)
		(width 0.14224)
		(layer "In15.Cu")
		(net "P5E_CPU0_P2_RX_BUF_DN<2>")
	)
	(arc
		(start 383.776474 -423.906442)
		(mid 383.850896 -423.946699)
		(end 383.915412 -424.001438)
		(width 0.14224)
		(layer "In15.Cu")
		(net "P5E_CPU0_P2_RX_BUF_DN<2>")
	)
	(arc
		(start 381.139954 -414.006538)
		(mid 380.88535 -414.142803)
		(end 380.66218 -414.32607)
		(width 0.14224)
		(layer "In15.Cu")
		(net "P5E_CPU0_P2_RX_BUF_DN<2>")
	)
	(arc
		(start 384.6322 -424.750738)
		(mid 384.748379 -424.930913)
		(end 384.789172 -425.14139)
		(width 0.14224)
		(layer "In15.Cu")
		(net "P5E_CPU0_P2_RX_BUF_DN<2>")
	)
	(arc
		(start 381.906272 -413.306514)
		(mid 381.87512 -413.463217)
		(end 381.786384 -413.596074)
		(width 0.14224)
		(layer "In15.Cu")
		(net "P5E_CPU0_P2_RX_BUF_DN<2>")
	)
	(arc
		(start 380.34214 -422.496234)
		(mid 380.441767 -422.528208)
		(end 380.539498 -422.565576)
		(width 0.14224)
		(layer "In15.Cu")
		(net "P5E_CPU0_P2_RX_BUF_DN<2>")
	)
	(arc
		(start 382.57226 -411.310074)
		(mid 382.478709 -411.355656)
		(end 382.392682 -411.414214)
		(width 0.14224)
		(layer "In15.Cu")
		(net "P5E_CPU0_P2_RX_BUF_DN<2>")
	)
	(arc
		(start 379.459744 -422.200578)
		(mid 379.554848 -422.257232)
		(end 379.658118 -422.297098)
		(width 0.14224)
		(layer "In15.Cu")
		(net "P5E_CPU0_P2_RX_BUF_DN<2>")
	)
	(arc
		(start 380.374652 -418.933122)
		(mid 380.360862 -419.002538)
		(end 380.321566 -419.061392)
		(width 0.14224)
		(layer "In15.Cu")
		(net "P5E_CPU0_P2_RX_BUF_DN<2>")
	)
	(arc
		(start 382.214374 -411.555946)
		(mid 382.090569 -411.690876)
		(end 382.014476 -411.857444)
		(width 0.14224)
		(layer "In15.Cu")
		(net "P5E_CPU0_P2_RX_BUF_DN<2>")
	)
	(arc
		(start 380.094998 -419.28796)
		(mid 380.06868 -419.311799)
		(end 380.040134 -419.332918)
		(width 0.14224)
		(layer "In15.Cu")
		(net "P5E_CPU0_P2_RX_BUF_DN<2>")
	)
	(arc
		(start 379.06325 -419.984682)
		(mid 378.899988 -420.239997)
		(end 378.843032 -420.53764)
		(width 0.14224)
		(layer "In15.Cu")
		(net "P5E_CPU0_P2_RX_BUF_DN<2>")
	)
	(segment
		(start 404.24608 -399.960338)
		(end 404.157434 -400.048984)
		(width 0.1016)
		(layer "F.Cu")
		(net "P5E_CPU0_P2_RX_BUF_DN<1>")
	)
	(segment
		(start 404.284434 -401.143216)
		(end 404.503382 -401.143216)
		(width 0.1016)
		(layer "F.Cu")
		(net "P5E_CPU0_P2_RX_BUF_DN<1>")
	)
	(segment
		(start 404.157434 -400.048984)
		(end 404.157434 -401.016216)
		(width 0.1016)
		(layer "F.Cu")
		(net "P5E_CPU0_P2_RX_BUF_DN<1>")
	)
	(segment
		(start 404.24608 -399.143982)
		(end 404.24608 -399.960338)
		(width 0.1016)
		(layer "F.Cu")
		(net "P5E_CPU0_P2_RX_BUF_DN<1>")
	)
	(segment
		(start 404.644098 -401.0025)
		(end 404.644098 -400.811238)
		(width 0.1016)
		(layer "F.Cu")
		(net "P5E_CPU0_P2_RX_BUF_DN<1>")
	)
	(segment
		(start 404.245572 -399.143474)
		(end 404.24608 -399.143982)
		(width 0.1016)
		(layer "F.Cu")
		(net "P5E_CPU0_P2_RX_BUF_DN<1>")
	)
	(segment
		(start 404.503382 -401.143216)
		(end 404.644098 -401.0025)
		(width 0.1016)
		(layer "F.Cu")
		(net "P5E_CPU0_P2_RX_BUF_DN<1>")
	)
	(segment
		(start 404.157434 -401.016216)
		(end 404.284434 -401.143216)
		(width 0.1016)
		(layer "F.Cu")
		(net "P5E_CPU0_P2_RX_BUF_DN<1>")
	)
	(segment
		(start 377.265438 -419.194234)
		(end 377.097798 -419.370256)
		(width 0.14224)
		(layer "In15.Cu")
		(net "P5E_CPU0_P2_RX_BUF_DN<1>")
	)
	(segment
		(start 375.779792 -420.22776)
		(end 375.779792 -421.32758)
		(width 0.14224)
		(layer "In15.Cu")
		(net "P5E_CPU0_P2_RX_BUF_DN<1>")
	)
	(segment
		(start 376.500898 -422.45788)
		(end 379.117606 -423.36847)
		(width 0.14224)
		(layer "In15.Cu")
		(net "P5E_CPU0_P2_RX_BUF_DN<1>")
	)
	(segment
		(start 378.32665 -413.90316)
		(end 378.076714 -414.006538)
		(width 0.14224)
		(layer "In15.Cu")
		(net "P5E_CPU0_P2_RX_BUF_DN<1>")
	)
	(segment
		(start 382.398016 -424.434508)
		(end 382.514602 -424.609514)
		(width 0.14224)
		(layer "In15.Cu")
		(net "P5E_CPU0_P2_RX_BUF_DN<1>")
	)
	(segment
		(start 382.789176 -438.325768)
		(end 383.082546 -438.619138)
		(width 0.14224)
		(layer "In15.Cu")
		(net "P5E_CPU0_P2_RX_BUF_DN<1>")
	)
	(segment
		(start 399.377408 -403.877018)
		(end 396.594076 -404.6601)
		(width 0.14224)
		(layer "In15.Cu")
		(net "P5E_CPU0_P2_RX_BUF_DN<1>")
	)
	(segment
		(start 383.082546 -438.619138)
		(end 383.599182 -438.619138)
		(width 0.14224)
		(layer "In15.Cu")
		(net "P5E_CPU0_P2_RX_BUF_DN<1>")
	)
	(segment
		(start 383.749804 -438.76976)
		(end 383.749804 -439.0898)
		(width 0.14224)
		(layer "In15.Cu")
		(net "P5E_CPU0_P2_RX_BUF_DN<1>")
	)
	(segment
		(start 396.594076 -404.6601)
		(end 393.676632 -405.642826)
		(width 0.14224)
		(layer "In15.Cu")
		(net "P5E_CPU0_P2_RX_BUF_DN<1>")
	)
	(segment
		(start 382.789176 -425.28871)
		(end 382.789176 -438.325768)
		(width 0.14224)
		(layer "In15.Cu")
		(net "P5E_CPU0_P2_RX_BUF_DN<1>")
	)
	(segment
		(start 381.486664 -424.030902)
		(end 382.34112 -424.387772)
		(width 0.14224)
		(layer "In15.Cu")
		(net "P5E_CPU0_P2_RX_BUF_DN<1>")
	)
	(segment
		(start 378.723144 -413.596074)
		(end 378.59589 -413.723328)
		(width 0.14224)
		(layer "In15.Cu")
		(net "P5E_CPU0_P2_RX_BUF_DN<1>")
	)
	(segment
		(start 376.994166 -419.441376)
		(end 376.041412 -419.836346)
		(width 0.14224)
		(layer "In15.Cu")
		(net "P5E_CPU0_P2_RX_BUF_DN<1>")
	)
	(segment
		(start 382.782318 -425.25442)
		(end 382.789176 -425.28871)
		(width 0.14224)
		(layer "In15.Cu")
		(net "P5E_CPU0_P2_RX_BUF_DN<1>")
	)
	(segment
		(start 378.843032 -412.371286)
		(end 378.843032 -413.306514)
		(width 0.14224)
		(layer "In15.Cu")
		(net "P5E_CPU0_P2_RX_BUF_DN<1>")
	)
	(segment
		(start 379.238256 -423.406062)
		(end 381.36703 -423.989754)
		(width 0.14224)
		(layer "In15.Cu")
		(net "P5E_CPU0_P2_RX_BUF_DN<1>")
	)
	(segment
		(start 404.21052 -401.117816)
		(end 403.90318 -401.425156)
		(width 0.14224)
		(layer "In15.Cu")
		(net "P5E_CPU0_P2_RX_BUF_DN<1>")
	)
	(segment
		(start 383.599182 -438.619138)
		(end 383.749804 -438.76976)
		(width 0.14224)
		(layer "In15.Cu")
		(net "P5E_CPU0_P2_RX_BUF_DN<1>")
	)
	(segment
		(start 404.644098 -400.811238)
		(end 404.644098 -400.979386)
		(width 0.14224)
		(layer "In15.Cu")
		(net "P5E_CPU0_P2_RX_BUF_DN<1>")
	)
	(segment
		(start 393.676632 -405.642826)
		(end 379.390656 -411.552136)
		(width 0.14224)
		(layer "In15.Cu")
		(net "P5E_CPU0_P2_RX_BUF_DN<1>")
	)
	(segment
		(start 378.59589 -413.723328)
		(end 378.32665 -413.90316)
		(width 0.14224)
		(layer "In15.Cu")
		(net "P5E_CPU0_P2_RX_BUF_DN<1>")
	)
	(segment
		(start 403.90318 -401.425156)
		(end 403.90318 -402.755354)
		(width 0.14224)
		(layer "In15.Cu")
		(net "P5E_CPU0_P2_RX_BUF_DN<1>")
	)
	(segment
		(start 404.644098 -400.979386)
		(end 404.505668 -401.117816)
		(width 0.14224)
		(layer "In15.Cu")
		(net "P5E_CPU0_P2_RX_BUF_DN<1>")
	)
	(segment
		(start 404.505668 -401.117816)
		(end 404.21052 -401.117816)
		(width 0.14224)
		(layer "In15.Cu")
		(net "P5E_CPU0_P2_RX_BUF_DN<1>")
	)
	(segment
		(start 403.90318 -402.755354)
		(end 403.779482 -402.86178)
		(width 0.14224)
		(layer "In15.Cu")
		(net "P5E_CPU0_P2_RX_BUF_DN<1>")
	)
	(segment
		(start 382.514602 -424.609514)
		(end 382.782318 -425.25442)
		(width 0.14224)
		(layer "In15.Cu")
		(net "P5E_CPU0_P2_RX_BUF_DN<1>")
	)
	(segment
		(start 403.779482 -402.86178)
		(end 403.711664 -402.892006)
		(width 0.14224)
		(layer "In15.Cu")
		(net "P5E_CPU0_P2_RX_BUF_DN<1>")
	)
	(segment
		(start 403.711664 -402.892006)
		(end 399.377408 -403.877018)
		(width 0.14224)
		(layer "In15.Cu")
		(net "P5E_CPU0_P2_RX_BUF_DN<1>")
	)
	(segment
		(start 377.311412 -415.020252)
		(end 377.311412 -419.079426)
		(width 0.14224)
		(layer "In15.Cu")
		(net "P5E_CPU0_P2_RX_BUF_DN<1>")
	)
	(arc
		(start 377.097798 -419.370256)
		(mid 377.049709 -419.411248)
		(end 376.994166 -419.441376)
		(width 0.14224)
		(layer "In15.Cu")
		(net "P5E_CPU0_P2_RX_BUF_DN<1>")
	)
	(arc
		(start 376.041412 -419.836346)
		(mid 375.851245 -419.992372)
		(end 375.779792 -420.22776)
		(width 0.14224)
		(layer "In15.Cu")
		(net "P5E_CPU0_P2_RX_BUF_DN<1>")
	)
	(arc
		(start 379.390656 -411.552136)
		(mid 378.992545 -411.878614)
		(end 378.843032 -412.371286)
		(width 0.14224)
		(layer "In15.Cu")
		(net "P5E_CPU0_P2_RX_BUF_DN<1>")
	)
	(arc
		(start 379.117606 -423.36847)
		(mid 379.177616 -423.388276)
		(end 379.238256 -423.406062)
		(width 0.14224)
		(layer "In15.Cu")
		(net "P5E_CPU0_P2_RX_BUF_DN<1>")
	)
	(arc
		(start 381.36703 -423.989754)
		(mid 381.427506 -424.008412)
		(end 381.486664 -424.030902)
		(width 0.14224)
		(layer "In15.Cu")
		(net "P5E_CPU0_P2_RX_BUF_DN<1>")
	)
	(arc
		(start 376.295158 -422.336214)
		(mid 376.391918 -422.407379)
		(end 376.500898 -422.45788)
		(width 0.14224)
		(layer "In15.Cu")
		(net "P5E_CPU0_P2_RX_BUF_DN<1>")
	)
	(arc
		(start 377.59894 -414.32607)
		(mid 377.386051 -414.644536)
		(end 377.311412 -415.020252)
		(width 0.14224)
		(layer "In15.Cu")
		(net "P5E_CPU0_P2_RX_BUF_DN<1>")
	)
	(arc
		(start 377.311412 -419.079426)
		(mid 377.299493 -419.141263)
		(end 377.265438 -419.194234)
		(width 0.14224)
		(layer "In15.Cu")
		(net "P5E_CPU0_P2_RX_BUF_DN<1>")
	)
	(arc
		(start 375.779792 -421.32758)
		(mid 375.849985 -421.728695)
		(end 376.05208 -422.082214)
		(width 0.14224)
		(layer "In15.Cu")
		(net "P5E_CPU0_P2_RX_BUF_DN<1>")
	)
	(arc
		(start 378.076714 -414.006538)
		(mid 377.82211 -414.142803)
		(end 377.59894 -414.32607)
		(width 0.14224)
		(layer "In15.Cu")
		(net "P5E_CPU0_P2_RX_BUF_DN<1>")
	)
	(arc
		(start 382.34112 -424.387772)
		(mid 382.373024 -424.406932)
		(end 382.398016 -424.434508)
		(width 0.14224)
		(layer "In15.Cu")
		(net "P5E_CPU0_P2_RX_BUF_DN<1>")
	)
	(arc
		(start 378.843032 -413.306514)
		(mid 378.81188 -413.463217)
		(end 378.723144 -413.596074)
		(width 0.14224)
		(layer "In15.Cu")
		(net "P5E_CPU0_P2_RX_BUF_DN<1>")
	)
	(arc
		(start 376.05208 -422.082214)
		(mid 376.169033 -422.213604)
		(end 376.295158 -422.336214)
		(width 0.14224)
		(layer "In15.Cu")
		(net "P5E_CPU0_P2_RX_BUF_DN<1>")
	)
	(segment
		(start 421.282876 -401.143216)
		(end 421.084502 -401.143216)
		(width 0.1016)
		(layer "F.Cu")
		(net "P5E_CPU0_P2_RX_BUF_DN<15>")
	)
	(segment
		(start 420.957502 -401.016216)
		(end 420.957502 -400.048984)
		(width 0.1016)
		(layer "F.Cu")
		(net "P5E_CPU0_P2_RX_BUF_DN<15>")
	)
	(segment
		(start 421.046148 -399.960338)
		(end 421.046148 -399.143982)
		(width 0.1016)
		(layer "F.Cu")
		(net "P5E_CPU0_P2_RX_BUF_DN<15>")
	)
	(segment
		(start 421.444166 -400.811238)
		(end 421.444166 -400.981926)
		(width 0.1016)
		(layer "F.Cu")
		(net "P5E_CPU0_P2_RX_BUF_DN<15>")
	)
	(segment
		(start 421.084502 -401.143216)
		(end 420.957502 -401.016216)
		(width 0.1016)
		(layer "F.Cu")
		(net "P5E_CPU0_P2_RX_BUF_DN<15>")
	)
	(segment
		(start 420.957502 -400.048984)
		(end 421.046148 -399.960338)
		(width 0.1016)
		(layer "F.Cu")
		(net "P5E_CPU0_P2_RX_BUF_DN<15>")
	)
	(segment
		(start 421.046148 -399.143982)
		(end 421.04564 -399.143474)
		(width 0.1016)
		(layer "F.Cu")
		(net "P5E_CPU0_P2_RX_BUF_DN<15>")
	)
	(segment
		(start 421.444166 -400.981926)
		(end 421.282876 -401.143216)
		(width 0.1016)
		(layer "F.Cu")
		(net "P5E_CPU0_P2_RX_BUF_DN<15>")
	)
	(segment
		(start 421.444166 -400.811238)
		(end 421.444166 -400.979386)
		(width 0.14224)
		(layer "In15.Cu")
		(net "P5E_CPU0_P2_RX_BUF_DN<15>")
	)
	(segment
		(start 418.539676 -421.68064)
		(end 418.088318 -422.050972)
		(width 0.14224)
		(layer "In15.Cu")
		(net "P5E_CPU0_P2_RX_BUF_DN<15>")
	)
	(segment
		(start 412.547562 -423.814494)
		(end 412.18231 -423.965878)
		(width 0.14224)
		(layer "In15.Cu")
		(net "P5E_CPU0_P2_RX_BUF_DN<15>")
	)
	(segment
		(start 420.703248 -417.589716)
		(end 420.61257 -418.017706)
		(width 0.14224)
		(layer "In15.Cu")
		(net "P5E_CPU0_P2_RX_BUF_DN<15>")
	)
	(segment
		(start 412.091632 -438.623202)
		(end 412.603442 -438.623202)
		(width 0.14224)
		(layer "In15.Cu")
		(net "P5E_CPU0_P2_RX_BUF_DN<15>")
	)
	(segment
		(start 411.789118 -438.320688)
		(end 412.091632 -438.623202)
		(width 0.14224)
		(layer "In15.Cu")
		(net "P5E_CPU0_P2_RX_BUF_DN<15>")
	)
	(segment
		(start 414.384998 -423.353738)
		(end 412.547562 -423.814494)
		(width 0.14224)
		(layer "In15.Cu")
		(net "P5E_CPU0_P2_RX_BUF_DN<15>")
	)
	(segment
		(start 420.61257 -418.017706)
		(end 419.700964 -420.074852)
		(width 0.14224)
		(layer "In15.Cu")
		(net "P5E_CPU0_P2_RX_BUF_DN<15>")
	)
	(segment
		(start 421.444166 -400.979386)
		(end 421.305736 -401.117816)
		(width 0.14224)
		(layer "In15.Cu")
		(net "P5E_CPU0_P2_RX_BUF_DN<15>")
	)
	(segment
		(start 421.305736 -401.117816)
		(end 421.010588 -401.117816)
		(width 0.14224)
		(layer "In15.Cu")
		(net "P5E_CPU0_P2_RX_BUF_DN<15>")
	)
	(segment
		(start 412.18231 -423.965878)
		(end 411.90926 -424.238674)
		(width 0.14224)
		(layer "In15.Cu")
		(net "P5E_CPU0_P2_RX_BUF_DN<15>")
	)
	(segment
		(start 412.603442 -438.623202)
		(end 412.75 -438.76976)
		(width 0.14224)
		(layer "In15.Cu")
		(net "P5E_CPU0_P2_RX_BUF_DN<15>")
	)
	(segment
		(start 412.75 -438.76976)
		(end 412.75 -439.0898)
		(width 0.14224)
		(layer "In15.Cu")
		(net "P5E_CPU0_P2_RX_BUF_DN<15>")
	)
	(segment
		(start 417.726114 -422.250108)
		(end 414.384998 -423.353738)
		(width 0.14224)
		(layer "In15.Cu")
		(net "P5E_CPU0_P2_RX_BUF_DN<15>")
	)
	(segment
		(start 421.010588 -401.117816)
		(end 420.703248 -401.425156)
		(width 0.14224)
		(layer "In15.Cu")
		(net "P5E_CPU0_P2_RX_BUF_DN<15>")
	)
	(segment
		(start 420.703248 -401.425156)
		(end 420.703248 -417.589716)
		(width 0.14224)
		(layer "In15.Cu")
		(net "P5E_CPU0_P2_RX_BUF_DN<15>")
	)
	(segment
		(start 419.700964 -420.074852)
		(end 418.539676 -421.68064)
		(width 0.14224)
		(layer "In15.Cu")
		(net "P5E_CPU0_P2_RX_BUF_DN<15>")
	)
	(segment
		(start 411.789118 -424.528488)
		(end 411.789118 -438.320688)
		(width 0.14224)
		(layer "In15.Cu")
		(net "P5E_CPU0_P2_RX_BUF_DN<15>")
	)
	(arc
		(start 411.90926 -424.238674)
		(mid 411.82036 -424.371628)
		(end 411.789118 -424.528488)
		(width 0.14224)
		(layer "In15.Cu")
		(net "P5E_CPU0_P2_RX_BUF_DN<15>")
	)
	(arc
		(start 418.088318 -422.050972)
		(mid 417.916395 -422.16724)
		(end 417.726114 -422.250108)
		(width 0.14224)
		(layer "In15.Cu")
		(net "P5E_CPU0_P2_RX_BUF_DN<15>")
	)
	(segment
		(start 420.24427 -400.97583)
		(end 420.076884 -401.143216)
		(width 0.1016)
		(layer "F.Cu")
		(net "P5E_CPU0_P2_RX_BUF_DN<14>")
	)
	(segment
		(start 420.24427 -400.811238)
		(end 420.24427 -400.97583)
		(width 0.1016)
		(layer "F.Cu")
		(net "P5E_CPU0_P2_RX_BUF_DN<14>")
	)
	(segment
		(start 419.884606 -401.143216)
		(end 419.757606 -401.016216)
		(width 0.1016)
		(layer "F.Cu")
		(net "P5E_CPU0_P2_RX_BUF_DN<14>")
	)
	(segment
		(start 419.757606 -400.048984)
		(end 419.846252 -399.960338)
		(width 0.1016)
		(layer "F.Cu")
		(net "P5E_CPU0_P2_RX_BUF_DN<14>")
	)
	(segment
		(start 419.757606 -401.016216)
		(end 419.757606 -400.048984)
		(width 0.1016)
		(layer "F.Cu")
		(net "P5E_CPU0_P2_RX_BUF_DN<14>")
	)
	(segment
		(start 419.846252 -399.143982)
		(end 419.845744 -399.143474)
		(width 0.1016)
		(layer "F.Cu")
		(net "P5E_CPU0_P2_RX_BUF_DN<14>")
	)
	(segment
		(start 420.076884 -401.143216)
		(end 419.884606 -401.143216)
		(width 0.1016)
		(layer "F.Cu")
		(net "P5E_CPU0_P2_RX_BUF_DN<14>")
	)
	(segment
		(start 419.846252 -399.960338)
		(end 419.846252 -399.143982)
		(width 0.1016)
		(layer "F.Cu")
		(net "P5E_CPU0_P2_RX_BUF_DN<14>")
	)
	(segment
		(start 420.24427 -400.979386)
		(end 420.10584 -401.117816)
		(width 0.14224)
		(layer "In15.Cu")
		(net "P5E_CPU0_P2_RX_BUF_DN<14>")
	)
	(segment
		(start 417.133532 -415.019998)
		(end 417.133532 -419.079426)
		(width 0.14224)
		(layer "In15.Cu")
		(net "P5E_CPU0_P2_RX_BUF_DN<14>")
	)
	(segment
		(start 409.789122 -437.32069)
		(end 410.091636 -437.623204)
		(width 0.14224)
		(layer "In15.Cu")
		(net "P5E_CPU0_P2_RX_BUF_DN<14>")
	)
	(segment
		(start 418.43706 -413.727392)
		(end 417.513262 -414.239202)
		(width 0.14224)
		(layer "In15.Cu")
		(net "P5E_CPU0_P2_RX_BUF_DN<14>")
	)
	(segment
		(start 420.24427 -400.811238)
		(end 420.24427 -400.979386)
		(width 0.14224)
		(layer "In15.Cu")
		(net "P5E_CPU0_P2_RX_BUF_DN<14>")
	)
	(segment
		(start 410.750004 -437.769762)
		(end 410.750004 -438.089802)
		(width 0.14224)
		(layer "In15.Cu")
		(net "P5E_CPU0_P2_RX_BUF_DN<14>")
	)
	(segment
		(start 415.132012 -422.025826)
		(end 412.985204 -422.62044)
		(width 0.14224)
		(layer "In15.Cu")
		(net "P5E_CPU0_P2_RX_BUF_DN<14>")
	)
	(segment
		(start 419.810692 -401.117816)
		(end 419.503352 -401.425156)
		(width 0.14224)
		(layer "In15.Cu")
		(net "P5E_CPU0_P2_RX_BUF_DN<14>")
	)
	(segment
		(start 420.10584 -401.117816)
		(end 419.810692 -401.117816)
		(width 0.14224)
		(layer "In15.Cu")
		(net "P5E_CPU0_P2_RX_BUF_DN<14>")
	)
	(segment
		(start 415.564574 -421.67302)
		(end 415.32302 -421.914574)
		(width 0.14224)
		(layer "In15.Cu")
		(net "P5E_CPU0_P2_RX_BUF_DN<14>")
	)
	(segment
		(start 409.789122 -424.69943)
		(end 409.789122 -437.32069)
		(width 0.14224)
		(layer "In15.Cu")
		(net "P5E_CPU0_P2_RX_BUF_DN<14>")
	)
	(segment
		(start 415.32302 -421.914574)
		(end 415.132012 -422.025826)
		(width 0.14224)
		(layer "In15.Cu")
		(net "P5E_CPU0_P2_RX_BUF_DN<14>")
	)
	(segment
		(start 410.080206 -424.06697)
		(end 409.923742 -424.283378)
		(width 0.14224)
		(layer "In15.Cu")
		(net "P5E_CPU0_P2_RX_BUF_DN<14>")
	)
	(segment
		(start 416.816286 -419.441376)
		(end 415.863532 -419.836346)
		(width 0.14224)
		(layer "In15.Cu")
		(net "P5E_CPU0_P2_RX_BUF_DN<14>")
	)
	(segment
		(start 417.087558 -419.194234)
		(end 416.919918 -419.370256)
		(width 0.14224)
		(layer "In15.Cu")
		(net "P5E_CPU0_P2_RX_BUF_DN<14>")
	)
	(segment
		(start 419.503352 -401.425156)
		(end 419.503352 -403.935692)
		(width 0.14224)
		(layer "In15.Cu")
		(net "P5E_CPU0_P2_RX_BUF_DN<14>")
	)
	(segment
		(start 412.985204 -422.62044)
		(end 410.933392 -423.470324)
		(width 0.14224)
		(layer "In15.Cu")
		(net "P5E_CPU0_P2_RX_BUF_DN<14>")
	)
	(segment
		(start 410.773118 -423.556176)
		(end 410.242766 -423.910252)
		(width 0.14224)
		(layer "In15.Cu")
		(net "P5E_CPU0_P2_RX_BUF_DN<14>")
	)
	(segment
		(start 419.419786 -405.63546)
		(end 418.655754 -413.395414)
		(width 0.14224)
		(layer "In15.Cu")
		(net "P5E_CPU0_P2_RX_BUF_DN<14>")
	)
	(segment
		(start 415.601912 -420.228014)
		(end 415.601912 -421.583104)
		(width 0.14224)
		(layer "In15.Cu")
		(net "P5E_CPU0_P2_RX_BUF_DN<14>")
	)
	(segment
		(start 410.091636 -437.623204)
		(end 410.603446 -437.623204)
		(width 0.14224)
		(layer "In15.Cu")
		(net "P5E_CPU0_P2_RX_BUF_DN<14>")
	)
	(segment
		(start 410.603446 -437.623204)
		(end 410.750004 -437.769762)
		(width 0.14224)
		(layer "In15.Cu")
		(net "P5E_CPU0_P2_RX_BUF_DN<14>")
	)
	(arc
		(start 415.863532 -419.836346)
		(mid 415.673294 -419.992478)
		(end 415.601912 -420.228014)
		(width 0.14224)
		(layer "In15.Cu")
		(net "P5E_CPU0_P2_RX_BUF_DN<14>")
	)
	(arc
		(start 415.601912 -421.583104)
		(mid 415.59221 -421.631788)
		(end 415.564574 -421.67302)
		(width 0.14224)
		(layer "In15.Cu")
		(net "P5E_CPU0_P2_RX_BUF_DN<14>")
	)
	(arc
		(start 419.503352 -403.935692)
		(mid 419.482431 -404.786602)
		(end 419.419786 -405.63546)
		(width 0.14224)
		(layer "In15.Cu")
		(net "P5E_CPU0_P2_RX_BUF_DN<14>")
	)
	(arc
		(start 417.133532 -419.079426)
		(mid 417.121613 -419.141263)
		(end 417.087558 -419.194234)
		(width 0.14224)
		(layer "In15.Cu")
		(net "P5E_CPU0_P2_RX_BUF_DN<14>")
	)
	(arc
		(start 409.923742 -424.283378)
		(mid 409.823573 -424.480777)
		(end 409.789122 -424.69943)
		(width 0.14224)
		(layer "In15.Cu")
		(net "P5E_CPU0_P2_RX_BUF_DN<14>")
	)
	(arc
		(start 417.513262 -414.239202)
		(mid 417.40895 -414.313808)
		(end 417.324286 -414.410144)
		(width 0.14224)
		(layer "In15.Cu")
		(net "P5E_CPU0_P2_RX_BUF_DN<14>")
	)
	(arc
		(start 410.933392 -423.470324)
		(mid 410.851144 -423.509309)
		(end 410.773118 -423.556176)
		(width 0.14224)
		(layer "In15.Cu")
		(net "P5E_CPU0_P2_RX_BUF_DN<14>")
	)
	(arc
		(start 410.242766 -423.910252)
		(mid 410.154482 -423.981348)
		(end 410.080206 -424.06697)
		(width 0.14224)
		(layer "In15.Cu")
		(net "P5E_CPU0_P2_RX_BUF_DN<14>")
	)
	(arc
		(start 417.324286 -414.410144)
		(mid 417.18225 -414.700482)
		(end 417.133532 -415.019998)
		(width 0.14224)
		(layer "In15.Cu")
		(net "P5E_CPU0_P2_RX_BUF_DN<14>")
	)
	(arc
		(start 416.919918 -419.370256)
		(mid 416.871829 -419.411248)
		(end 416.816286 -419.441376)
		(width 0.14224)
		(layer "In15.Cu")
		(net "P5E_CPU0_P2_RX_BUF_DN<14>")
	)
	(arc
		(start 418.655754 -413.395414)
		(mid 418.587333 -413.588382)
		(end 418.43706 -413.727392)
		(width 0.14224)
		(layer "In15.Cu")
		(net "P5E_CPU0_P2_RX_BUF_DN<14>")
	)
	(segment
		(start 418.903404 -401.143216)
		(end 419.04412 -401.0025)
		(width 0.1016)
		(layer "F.Cu")
		(net "P5E_CPU0_P2_RX_BUF_DN<13>")
	)
	(segment
		(start 418.645594 -399.143474)
		(end 418.646102 -399.143982)
		(width 0.1016)
		(layer "F.Cu")
		(net "P5E_CPU0_P2_RX_BUF_DN<13>")
	)
	(segment
		(start 418.646102 -399.143982)
		(end 418.646102 -399.960338)
		(width 0.1016)
		(layer "F.Cu")
		(net "P5E_CPU0_P2_RX_BUF_DN<13>")
	)
	(segment
		(start 418.566092 -401.016216)
		(end 418.693092 -401.143216)
		(width 0.1016)
		(layer "F.Cu")
		(net "P5E_CPU0_P2_RX_BUF_DN<13>")
	)
	(segment
		(start 418.646102 -399.960338)
		(end 418.566092 -400.040348)
		(width 0.1016)
		(layer "F.Cu")
		(net "P5E_CPU0_P2_RX_BUF_DN<13>")
	)
	(segment
		(start 418.566092 -400.040348)
		(end 418.566092 -401.016216)
		(width 0.1016)
		(layer "F.Cu")
		(net "P5E_CPU0_P2_RX_BUF_DN<13>")
	)
	(segment
		(start 418.693092 -401.143216)
		(end 418.903404 -401.143216)
		(width 0.1016)
		(layer "F.Cu")
		(net "P5E_CPU0_P2_RX_BUF_DN<13>")
	)
	(segment
		(start 419.04412 -401.0025)
		(end 419.04412 -400.811238)
		(width 0.1016)
		(layer "F.Cu")
		(net "P5E_CPU0_P2_RX_BUF_DN<13>")
	)
	(segment
		(start 418.000434 -404.15845)
		(end 418.000942 -404.156926)
		(width 0.14224)
		(layer "In15.Cu")
		(net "P5E_CPU0_P2_RX_BUF_DN<13>")
	)
	(segment
		(start 415.171636 -413.86506)
		(end 415.3408 -413.752538)
		(width 0.14224)
		(layer "In15.Cu")
		(net "P5E_CPU0_P2_RX_BUF_DN<13>")
	)
	(segment
		(start 416.7251 -407.72207)
		(end 417.721288 -404.938484)
		(width 0.14224)
		(layer "In15.Cu")
		(net "P5E_CPU0_P2_RX_BUF_DN<13>")
	)
	(segment
		(start 415.75228 -411.564074)
		(end 416.238944 -409.082748)
		(width 0.14224)
		(layer "In15.Cu")
		(net "P5E_CPU0_P2_RX_BUF_DN<13>")
	)
	(segment
		(start 418.90569 -401.117816)
		(end 419.04412 -400.979386)
		(width 0.14224)
		(layer "In15.Cu")
		(net "P5E_CPU0_P2_RX_BUF_DN<13>")
	)
	(segment
		(start 418.303202 -403.006052)
		(end 418.303202 -401.425156)
		(width 0.14224)
		(layer "In15.Cu")
		(net "P5E_CPU0_P2_RX_BUF_DN<13>")
	)
	(segment
		(start 415.60242 -413.304482)
		(end 415.60242 -412.419038)
		(width 0.14224)
		(layer "In15.Cu")
		(net "P5E_CPU0_P2_RX_BUF_DN<13>")
	)
	(segment
		(start 407.862278 -424.351704)
		(end 408.081988 -423.985182)
		(width 0.14224)
		(layer "In15.Cu")
		(net "P5E_CPU0_P2_RX_BUF_DN<13>")
	)
	(segment
		(start 408.281124 -423.795698)
		(end 410.24175 -422.74744)
		(width 0.14224)
		(layer "In15.Cu")
		(net "P5E_CPU0_P2_RX_BUF_DN<13>")
	)
	(segment
		(start 412.34106 -421.741092)
		(end 412.501334 -421.580818)
		(width 0.14224)
		(layer "In15.Cu")
		(net "P5E_CPU0_P2_RX_BUF_DN<13>")
	)
	(segment
		(start 416.238944 -409.082748)
		(end 416.245802 -409.061666)
		(width 0.14224)
		(layer "In15.Cu")
		(net "P5E_CPU0_P2_RX_BUF_DN<13>")
	)
	(segment
		(start 408.60345 -438.623202)
		(end 408.096466 -438.623202)
		(width 0.14224)
		(layer "In15.Cu")
		(net "P5E_CPU0_P2_RX_BUF_DN<13>")
	)
	(segment
		(start 408.750008 -438.76976)
		(end 408.60345 -438.623202)
		(width 0.14224)
		(layer "In15.Cu")
		(net "P5E_CPU0_P2_RX_BUF_DN<13>")
	)
	(segment
		(start 417.721288 -404.938484)
		(end 418.000434 -404.15845)
		(width 0.14224)
		(layer "In15.Cu")
		(net "P5E_CPU0_P2_RX_BUF_DN<13>")
	)
	(segment
		(start 413.856678 -419.370256)
		(end 414.024318 -419.194234)
		(width 0.14224)
		(layer "In15.Cu")
		(net "P5E_CPU0_P2_RX_BUF_DN<13>")
	)
	(segment
		(start 415.619692 -412.238952)
		(end 415.751772 -411.564074)
		(width 0.14224)
		(layer "In15.Cu")
		(net "P5E_CPU0_P2_RX_BUF_DN<13>")
	)
	(segment
		(start 408.750008 -439.0898)
		(end 408.750008 -438.76976)
		(width 0.14224)
		(layer "In15.Cu")
		(net "P5E_CPU0_P2_RX_BUF_DN<13>")
	)
	(segment
		(start 418.610542 -401.117816)
		(end 418.90569 -401.117816)
		(width 0.14224)
		(layer "In15.Cu")
		(net "P5E_CPU0_P2_RX_BUF_DN<13>")
	)
	(segment
		(start 416.245802 -409.061666)
		(end 416.3441 -408.787092)
		(width 0.14224)
		(layer "In15.Cu")
		(net "P5E_CPU0_P2_RX_BUF_DN<13>")
	)
	(segment
		(start 412.538672 -421.490902)
		(end 412.538672 -420.228014)
		(width 0.14224)
		(layer "In15.Cu")
		(net "P5E_CPU0_P2_RX_BUF_DN<13>")
	)
	(segment
		(start 414.070292 -419.079426)
		(end 414.070292 -415.020252)
		(width 0.14224)
		(layer "In15.Cu")
		(net "P5E_CPU0_P2_RX_BUF_DN<13>")
	)
	(segment
		(start 418.303202 -401.425156)
		(end 418.610542 -401.117816)
		(width 0.14224)
		(layer "In15.Cu")
		(net "P5E_CPU0_P2_RX_BUF_DN<13>")
	)
	(segment
		(start 416.722814 -407.728928)
		(end 416.7251 -407.72207)
		(width 0.14224)
		(layer "In15.Cu")
		(net "P5E_CPU0_P2_RX_BUF_DN<13>")
	)
	(segment
		(start 412.800292 -419.836346)
		(end 413.753046 -419.441376)
		(width 0.14224)
		(layer "In15.Cu")
		(net "P5E_CPU0_P2_RX_BUF_DN<13>")
	)
	(segment
		(start 407.789126 -438.315862)
		(end 407.789126 -424.629072)
		(width 0.14224)
		(layer "In15.Cu")
		(net "P5E_CPU0_P2_RX_BUF_DN<13>")
	)
	(segment
		(start 415.376106 -413.717486)
		(end 415.55543 -413.455358)
		(width 0.14224)
		(layer "In15.Cu")
		(net "P5E_CPU0_P2_RX_BUF_DN<13>")
	)
	(segment
		(start 410.381196 -422.681654)
		(end 411.831028 -422.081706)
		(width 0.14224)
		(layer "In15.Cu")
		(net "P5E_CPU0_P2_RX_BUF_DN<13>")
	)
	(segment
		(start 415.751772 -411.564074)
		(end 415.75228 -411.564074)
		(width 0.14224)
		(layer "In15.Cu")
		(net "P5E_CPU0_P2_RX_BUF_DN<13>")
	)
	(segment
		(start 416.344608 -408.785568)
		(end 416.722814 -407.728928)
		(width 0.14224)
		(layer "In15.Cu")
		(net "P5E_CPU0_P2_RX_BUF_DN<13>")
	)
	(segment
		(start 418.000942 -404.156926)
		(end 418.303202 -403.006052)
		(width 0.14224)
		(layer "In15.Cu")
		(net "P5E_CPU0_P2_RX_BUF_DN<13>")
	)
	(segment
		(start 408.096466 -438.623202)
		(end 407.789126 -438.315862)
		(width 0.14224)
		(layer "In15.Cu")
		(net "P5E_CPU0_P2_RX_BUF_DN<13>")
	)
	(segment
		(start 414.835594 -414.006538)
		(end 415.149792 -413.876744)
		(width 0.14224)
		(layer "In15.Cu")
		(net "P5E_CPU0_P2_RX_BUF_DN<13>")
	)
	(segment
		(start 419.04412 -400.979386)
		(end 419.04412 -400.811238)
		(width 0.14224)
		(layer "In15.Cu")
		(net "P5E_CPU0_P2_RX_BUF_DN<13>")
	)
	(segment
		(start 416.3441 -408.787092)
		(end 416.344608 -408.785568)
		(width 0.14224)
		(layer "In15.Cu")
		(net "P5E_CPU0_P2_RX_BUF_DN<13>")
	)
	(arc
		(start 415.149792 -413.876744)
		(mid 415.160997 -413.871432)
		(end 415.171636 -413.86506)
		(width 0.14224)
		(layer "In15.Cu")
		(net "P5E_CPU0_P2_RX_BUF_DN<13>")
	)
	(arc
		(start 415.3408 -413.752538)
		(mid 415.360141 -413.736713)
		(end 415.376106 -413.717486)
		(width 0.14224)
		(layer "In15.Cu")
		(net "P5E_CPU0_P2_RX_BUF_DN<13>")
	)
	(arc
		(start 414.024318 -419.194234)
		(mid 414.058365 -419.14126)
		(end 414.070292 -419.079426)
		(width 0.14224)
		(layer "In15.Cu")
		(net "P5E_CPU0_P2_RX_BUF_DN<13>")
	)
	(arc
		(start 414.35782 -414.32607)
		(mid 414.580985 -414.142796)
		(end 414.835594 -414.006538)
		(width 0.14224)
		(layer "In15.Cu")
		(net "P5E_CPU0_P2_RX_BUF_DN<13>")
	)
	(arc
		(start 412.501334 -421.580818)
		(mid 412.528953 -421.539578)
		(end 412.538672 -421.490902)
		(width 0.14224)
		(layer "In15.Cu")
		(net "P5E_CPU0_P2_RX_BUF_DN<13>")
	)
	(arc
		(start 415.55543 -413.455358)
		(mid 415.590404 -413.383495)
		(end 415.60242 -413.304482)
		(width 0.14224)
		(layer "In15.Cu")
		(net "P5E_CPU0_P2_RX_BUF_DN<13>")
	)
	(arc
		(start 408.081988 -423.985182)
		(mid 408.168731 -423.876963)
		(end 408.281124 -423.795698)
		(width 0.14224)
		(layer "In15.Cu")
		(net "P5E_CPU0_P2_RX_BUF_DN<13>")
	)
	(arc
		(start 413.753046 -419.441376)
		(mid 413.808584 -419.41124)
		(end 413.856678 -419.370256)
		(width 0.14224)
		(layer "In15.Cu")
		(net "P5E_CPU0_P2_RX_BUF_DN<13>")
	)
	(arc
		(start 410.24175 -422.74744)
		(mid 410.310663 -422.71283)
		(end 410.381196 -422.681654)
		(width 0.14224)
		(layer "In15.Cu")
		(net "P5E_CPU0_P2_RX_BUF_DN<13>")
	)
	(arc
		(start 415.60242 -412.419038)
		(mid 415.606703 -412.328578)
		(end 415.619692 -412.238952)
		(width 0.14224)
		(layer "In15.Cu")
		(net "P5E_CPU0_P2_RX_BUF_DN<13>")
	)
	(arc
		(start 407.789126 -424.629072)
		(mid 407.807723 -424.485647)
		(end 407.862278 -424.351704)
		(width 0.14224)
		(layer "In15.Cu")
		(net "P5E_CPU0_P2_RX_BUF_DN<13>")
	)
	(arc
		(start 412.538672 -420.228014)
		(mid 412.610023 -419.992456)
		(end 412.800292 -419.836346)
		(width 0.14224)
		(layer "In15.Cu")
		(net "P5E_CPU0_P2_RX_BUF_DN<13>")
	)
	(arc
		(start 411.831028 -422.081706)
		(mid 412.102821 -421.936524)
		(end 412.34106 -421.741092)
		(width 0.14224)
		(layer "In15.Cu")
		(net "P5E_CPU0_P2_RX_BUF_DN<13>")
	)
	(arc
		(start 414.070292 -415.020252)
		(mid 414.144982 -414.644557)
		(end 414.35782 -414.32607)
		(width 0.14224)
		(layer "In15.Cu")
		(net "P5E_CPU0_P2_RX_BUF_DN<13>")
	)
	(segment
		(start 417.844224 -400.977862)
		(end 417.67887 -401.143216)
		(width 0.1016)
		(layer "F.Cu")
		(net "P5E_CPU0_P2_RX_BUF_DN<12>")
	)
	(segment
		(start 417.35756 -401.016216)
		(end 417.35756 -400.048984)
		(width 0.1016)
		(layer "F.Cu")
		(net "P5E_CPU0_P2_RX_BUF_DN<12>")
	)
	(segment
		(start 417.446206 -399.143982)
		(end 417.445698 -399.143474)
		(width 0.1016)
		(layer "F.Cu")
		(net "P5E_CPU0_P2_RX_BUF_DN<12>")
	)
	(segment
		(start 417.844224 -400.811238)
		(end 417.844224 -400.977862)
		(width 0.1016)
		(layer "F.Cu")
		(net "P5E_CPU0_P2_RX_BUF_DN<12>")
	)
	(segment
		(start 417.35756 -400.048984)
		(end 417.446206 -399.960338)
		(width 0.1016)
		(layer "F.Cu")
		(net "P5E_CPU0_P2_RX_BUF_DN<12>")
	)
	(segment
		(start 417.48456 -401.143216)
		(end 417.35756 -401.016216)
		(width 0.1016)
		(layer "F.Cu")
		(net "P5E_CPU0_P2_RX_BUF_DN<12>")
	)
	(segment
		(start 417.67887 -401.143216)
		(end 417.48456 -401.143216)
		(width 0.1016)
		(layer "F.Cu")
		(net "P5E_CPU0_P2_RX_BUF_DN<12>")
	)
	(segment
		(start 417.446206 -399.960338)
		(end 417.446206 -399.143982)
		(width 0.1016)
		(layer "F.Cu")
		(net "P5E_CPU0_P2_RX_BUF_DN<12>")
	)
	(segment
		(start 409.737052 -419.836346)
		(end 410.68879 -419.442138)
		(width 0.14224)
		(layer "In15.Cu")
		(net "P5E_CPU0_P2_RX_BUF_DN<12>")
	)
	(segment
		(start 411.007052 -419.079426)
		(end 411.007052 -415.020252)
		(width 0.14224)
		(layer "In15.Cu")
		(net "P5E_CPU0_P2_RX_BUF_DN<12>")
	)
	(segment
		(start 406.750012 -437.769762)
		(end 406.603454 -437.623204)
		(width 0.14224)
		(layer "In15.Cu")
		(net "P5E_CPU0_P2_RX_BUF_DN<12>")
	)
	(segment
		(start 406.750012 -438.089802)
		(end 406.750012 -437.769762)
		(width 0.14224)
		(layer "In15.Cu")
		(net "P5E_CPU0_P2_RX_BUF_DN<12>")
	)
	(segment
		(start 406.603454 -437.623204)
		(end 406.091644 -437.623204)
		(width 0.14224)
		(layer "In15.Cu")
		(net "P5E_CPU0_P2_RX_BUF_DN<12>")
	)
	(segment
		(start 410.793438 -419.370256)
		(end 410.961078 -419.194234)
		(width 0.14224)
		(layer "In15.Cu")
		(net "P5E_CPU0_P2_RX_BUF_DN<12>")
	)
	(segment
		(start 417.103306 -401.425156)
		(end 417.410646 -401.117816)
		(width 0.14224)
		(layer "In15.Cu")
		(net "P5E_CPU0_P2_RX_BUF_DN<12>")
	)
	(segment
		(start 414.591754 -408.37612)
		(end 414.592008 -408.375866)
		(width 0.14224)
		(layer "In15.Cu")
		(net "P5E_CPU0_P2_RX_BUF_DN<12>")
	)
	(segment
		(start 412.69285 -411.544262)
		(end 414.591754 -408.37612)
		(width 0.14224)
		(layer "In15.Cu")
		(net "P5E_CPU0_P2_RX_BUF_DN<12>")
	)
	(segment
		(start 417.103306 -403.52599)
		(end 417.103306 -401.425156)
		(width 0.14224)
		(layer "In15.Cu")
		(net "P5E_CPU0_P2_RX_BUF_DN<12>")
	)
	(segment
		(start 417.844224 -400.979386)
		(end 417.844224 -400.811238)
		(width 0.14224)
		(layer "In15.Cu")
		(net "P5E_CPU0_P2_RX_BUF_DN<12>")
	)
	(segment
		(start 405.904954 -424.27398)
		(end 406.018238 -424.033188)
		(width 0.14224)
		(layer "In15.Cu")
		(net "P5E_CPU0_P2_RX_BUF_DN<12>")
	)
	(segment
		(start 412.538672 -413.306514)
		(end 412.538672 -412.401004)
		(width 0.14224)
		(layer "In15.Cu")
		(net "P5E_CPU0_P2_RX_BUF_DN<12>")
	)
	(segment
		(start 412.02229 -413.90316)
		(end 412.29153 -413.723328)
		(width 0.14224)
		(layer "In15.Cu")
		(net "P5E_CPU0_P2_RX_BUF_DN<12>")
	)
	(segment
		(start 406.091644 -437.623204)
		(end 405.78913 -437.32069)
		(width 0.14224)
		(layer "In15.Cu")
		(net "P5E_CPU0_P2_RX_BUF_DN<12>")
	)
	(segment
		(start 414.591754 -408.375866)
		(end 415.695892 -406.418796)
		(width 0.14224)
		(layer "In15.Cu")
		(net "P5E_CPU0_P2_RX_BUF_DN<12>")
	)
	(segment
		(start 405.78913 -437.32069)
		(end 405.78913 -424.791886)
		(width 0.14224)
		(layer "In15.Cu")
		(net "P5E_CPU0_P2_RX_BUF_DN<12>")
	)
	(segment
		(start 412.549848 -412.23692)
		(end 412.613602 -411.769814)
		(width 0.14224)
		(layer "In15.Cu")
		(net "P5E_CPU0_P2_RX_BUF_DN<12>")
	)
	(segment
		(start 417.410646 -401.117816)
		(end 417.705794 -401.117816)
		(width 0.14224)
		(layer "In15.Cu")
		(net "P5E_CPU0_P2_RX_BUF_DN<12>")
	)
	(segment
		(start 412.29153 -413.723328)
		(end 412.418784 -413.596074)
		(width 0.14224)
		(layer "In15.Cu")
		(net "P5E_CPU0_P2_RX_BUF_DN<12>")
	)
	(segment
		(start 411.772354 -414.006538)
		(end 412.02229 -413.90316)
		(width 0.14224)
		(layer "In15.Cu")
		(net "P5E_CPU0_P2_RX_BUF_DN<12>")
	)
	(segment
		(start 415.698432 -406.418288)
		(end 416.331908 -405.291798)
		(width 0.14224)
		(layer "In15.Cu")
		(net "P5E_CPU0_P2_RX_BUF_DN<12>")
	)
	(segment
		(start 414.592008 -408.375866)
		(end 414.591754 -408.375866)
		(width 0.14224)
		(layer "In15.Cu")
		(net "P5E_CPU0_P2_RX_BUF_DN<12>")
	)
	(segment
		(start 416.331908 -405.291798)
		(end 416.60699 -404.724362)
		(width 0.14224)
		(layer "In15.Cu")
		(net "P5E_CPU0_P2_RX_BUF_DN<12>")
	)
	(segment
		(start 406.084532 -423.95648)
		(end 408.775408 -422.16578)
		(width 0.14224)
		(layer "In15.Cu")
		(net "P5E_CPU0_P2_RX_BUF_DN<12>")
	)
	(segment
		(start 417.705794 -401.117816)
		(end 417.844224 -400.979386)
		(width 0.14224)
		(layer "In15.Cu")
		(net "P5E_CPU0_P2_RX_BUF_DN<12>")
	)
	(segment
		(start 409.475432 -421.466772)
		(end 409.475432 -420.22776)
		(width 0.14224)
		(layer "In15.Cu")
		(net "P5E_CPU0_P2_RX_BUF_DN<12>")
	)
	(segment
		(start 416.60699 -404.724362)
		(end 417.103306 -403.52599)
		(width 0.14224)
		(layer "In15.Cu")
		(net "P5E_CPU0_P2_RX_BUF_DN<12>")
	)
	(segment
		(start 415.695892 -406.418796)
		(end 415.698432 -406.418288)
		(width 0.14224)
		(layer "In15.Cu")
		(net "P5E_CPU0_P2_RX_BUF_DN<12>")
	)
	(segment
		(start 406.018238 -424.033188)
		(end 406.084532 -423.95648)
		(width 0.14224)
		(layer "In15.Cu")
		(net "P5E_CPU0_P2_RX_BUF_DN<12>")
	)
	(segment
		(start 409.149042 -421.859964)
		(end 409.428188 -421.580818)
		(width 0.14224)
		(layer "In15.Cu")
		(net "P5E_CPU0_P2_RX_BUF_DN<12>")
	)
	(arc
		(start 408.775408 -422.16578)
		(mid 408.969817 -422.022147)
		(end 409.149042 -421.859964)
		(width 0.14224)
		(layer "In15.Cu")
		(net "P5E_CPU0_P2_RX_BUF_DN<12>")
	)
	(arc
		(start 412.418784 -413.596074)
		(mid 412.507499 -413.463209)
		(end 412.538672 -413.306514)
		(width 0.14224)
		(layer "In15.Cu")
		(net "P5E_CPU0_P2_RX_BUF_DN<12>")
	)
	(arc
		(start 410.961078 -419.194234)
		(mid 410.995125 -419.14126)
		(end 411.007052 -419.079426)
		(width 0.14224)
		(layer "In15.Cu")
		(net "P5E_CPU0_P2_RX_BUF_DN<12>")
	)
	(arc
		(start 409.475432 -420.22776)
		(mid 409.546853 -419.992351)
		(end 409.737052 -419.836346)
		(width 0.14224)
		(layer "In15.Cu")
		(net "P5E_CPU0_P2_RX_BUF_DN<12>")
	)
	(arc
		(start 411.29458 -414.32607)
		(mid 411.517745 -414.142796)
		(end 411.772354 -414.006538)
		(width 0.14224)
		(layer "In15.Cu")
		(net "P5E_CPU0_P2_RX_BUF_DN<12>")
	)
	(arc
		(start 410.68879 -419.442138)
		(mid 410.744862 -419.411659)
		(end 410.793438 -419.370256)
		(width 0.14224)
		(layer "In15.Cu")
		(net "P5E_CPU0_P2_RX_BUF_DN<12>")
	)
	(arc
		(start 411.007052 -415.020252)
		(mid 411.081742 -414.644557)
		(end 411.29458 -414.32607)
		(width 0.14224)
		(layer "In15.Cu")
		(net "P5E_CPU0_P2_RX_BUF_DN<12>")
	)
	(arc
		(start 405.78913 -424.791886)
		(mid 405.818443 -424.526538)
		(end 405.904954 -424.27398)
		(width 0.14224)
		(layer "In15.Cu")
		(net "P5E_CPU0_P2_RX_BUF_DN<12>")
	)
	(arc
		(start 412.613602 -411.769814)
		(mid 412.641785 -411.653018)
		(end 412.69285 -411.544262)
		(width 0.14224)
		(layer "In15.Cu")
		(net "P5E_CPU0_P2_RX_BUF_DN<12>")
	)
	(arc
		(start 409.428188 -421.580818)
		(mid 409.46315 -421.528493)
		(end 409.475432 -421.466772)
		(width 0.14224)
		(layer "In15.Cu")
		(net "P5E_CPU0_P2_RX_BUF_DN<12>")
	)
	(arc
		(start 412.538672 -412.401004)
		(mid 412.541476 -412.318772)
		(end 412.549848 -412.23692)
		(width 0.14224)
		(layer "In15.Cu")
		(net "P5E_CPU0_P2_RX_BUF_DN<12>")
	)
	(segment
		(start 416.15741 -401.016216)
		(end 416.15741 -400.048984)
		(width 0.1016)
		(layer "F.Cu")
		(net "P5E_CPU0_P2_RX_BUF_DN<11>")
	)
	(segment
		(start 416.28441 -401.143216)
		(end 416.15741 -401.016216)
		(width 0.1016)
		(layer "F.Cu")
		(net "P5E_CPU0_P2_RX_BUF_DN<11>")
	)
	(segment
		(start 416.15741 -400.048984)
		(end 416.246056 -399.960338)
		(width 0.1016)
		(layer "F.Cu")
		(net "P5E_CPU0_P2_RX_BUF_DN<11>")
	)
	(segment
		(start 416.644328 -401.002246)
		(end 416.503358 -401.143216)
		(width 0.1016)
		(layer "F.Cu")
		(net "P5E_CPU0_P2_RX_BUF_DN<11>")
	)
	(segment
		(start 416.644328 -400.811238)
		(end 416.644328 -401.002246)
		(width 0.1016)
		(layer "F.Cu")
		(net "P5E_CPU0_P2_RX_BUF_DN<11>")
	)
	(segment
		(start 416.246056 -399.143728)
		(end 416.245802 -399.143474)
		(width 0.1016)
		(layer "F.Cu")
		(net "P5E_CPU0_P2_RX_BUF_DN<11>")
	)
	(segment
		(start 416.246056 -399.960338)
		(end 416.246056 -399.143728)
		(width 0.1016)
		(layer "F.Cu")
		(net "P5E_CPU0_P2_RX_BUF_DN<11>")
	)
	(segment
		(start 416.503358 -401.143216)
		(end 416.28441 -401.143216)
		(width 0.1016)
		(layer "F.Cu")
		(net "P5E_CPU0_P2_RX_BUF_DN<11>")
	)
	(segment
		(start 416.644328 -400.979386)
		(end 416.505898 -401.117816)
		(width 0.14224)
		(layer "In15.Cu")
		(net "P5E_CPU0_P2_RX_BUF_DN<11>")
	)
	(segment
		(start 409.22829 -413.723328)
		(end 408.95905 -413.90316)
		(width 0.14224)
		(layer "In15.Cu")
		(net "P5E_CPU0_P2_RX_BUF_DN<11>")
	)
	(segment
		(start 413.208978 -407.847038)
		(end 409.75026 -411.663134)
		(width 0.14224)
		(layer "In15.Cu")
		(net "P5E_CPU0_P2_RX_BUF_DN<11>")
	)
	(segment
		(start 416.21075 -401.117816)
		(end 415.90341 -401.425156)
		(width 0.14224)
		(layer "In15.Cu")
		(net "P5E_CPU0_P2_RX_BUF_DN<11>")
	)
	(segment
		(start 404.750016 -438.76976)
		(end 404.750016 -439.0898)
		(width 0.14224)
		(layer "In15.Cu")
		(net "P5E_CPU0_P2_RX_BUF_DN<11>")
	)
	(segment
		(start 416.505898 -401.117816)
		(end 416.21075 -401.117816)
		(width 0.14224)
		(layer "In15.Cu")
		(net "P5E_CPU0_P2_RX_BUF_DN<11>")
	)
	(segment
		(start 403.789134 -424.59021)
		(end 403.789134 -438.320688)
		(width 0.14224)
		(layer "In15.Cu")
		(net "P5E_CPU0_P2_RX_BUF_DN<11>")
	)
	(segment
		(start 415.65703 -404.376382)
		(end 414.097216 -406.710134)
		(width 0.14224)
		(layer "In15.Cu")
		(net "P5E_CPU0_P2_RX_BUF_DN<11>")
	)
	(segment
		(start 406.412192 -420.228268)
		(end 406.412192 -421.571928)
		(width 0.14224)
		(layer "In15.Cu")
		(net "P5E_CPU0_P2_RX_BUF_DN<11>")
	)
	(segment
		(start 407.626566 -419.441376)
		(end 406.673558 -419.836346)
		(width 0.14224)
		(layer "In15.Cu")
		(net "P5E_CPU0_P2_RX_BUF_DN<11>")
	)
	(segment
		(start 415.90341 -401.425156)
		(end 415.90341 -403.56409)
		(width 0.14224)
		(layer "In15.Cu")
		(net "P5E_CPU0_P2_RX_BUF_DN<11>")
	)
	(segment
		(start 404.091648 -438.623202)
		(end 404.603458 -438.623202)
		(width 0.14224)
		(layer "In15.Cu")
		(net "P5E_CPU0_P2_RX_BUF_DN<11>")
	)
	(segment
		(start 406.37587 -421.660828)
		(end 404.126192 -423.96156)
		(width 0.14224)
		(layer "In15.Cu")
		(net "P5E_CPU0_P2_RX_BUF_DN<11>")
	)
	(segment
		(start 409.635198 -411.832806)
		(end 409.568396 -411.969458)
		(width 0.14224)
		(layer "In15.Cu")
		(net "P5E_CPU0_P2_RX_BUF_DN<11>")
	)
	(segment
		(start 404.126192 -423.96156)
		(end 403.858476 -424.361864)
		(width 0.14224)
		(layer "In15.Cu")
		(net "P5E_CPU0_P2_RX_BUF_DN<11>")
	)
	(segment
		(start 409.475432 -412.46933)
		(end 409.475432 -413.306514)
		(width 0.14224)
		(layer "In15.Cu")
		(net "P5E_CPU0_P2_RX_BUF_DN<11>")
	)
	(segment
		(start 409.355544 -413.596074)
		(end 409.22829 -413.723328)
		(width 0.14224)
		(layer "In15.Cu")
		(net "P5E_CPU0_P2_RX_BUF_DN<11>")
	)
	(segment
		(start 416.644328 -400.811238)
		(end 416.644328 -400.979386)
		(width 0.14224)
		(layer "In15.Cu")
		(net "P5E_CPU0_P2_RX_BUF_DN<11>")
	)
	(segment
		(start 408.95905 -413.90316)
		(end 408.709114 -414.006538)
		(width 0.14224)
		(layer "In15.Cu")
		(net "P5E_CPU0_P2_RX_BUF_DN<11>")
	)
	(segment
		(start 407.943812 -415.020252)
		(end 407.943812 -419.079426)
		(width 0.14224)
		(layer "In15.Cu")
		(net "P5E_CPU0_P2_RX_BUF_DN<11>")
	)
	(segment
		(start 403.789134 -438.320688)
		(end 404.091648 -438.623202)
		(width 0.14224)
		(layer "In15.Cu")
		(net "P5E_CPU0_P2_RX_BUF_DN<11>")
	)
	(segment
		(start 407.897838 -419.194234)
		(end 407.730198 -419.370256)
		(width 0.14224)
		(layer "In15.Cu")
		(net "P5E_CPU0_P2_RX_BUF_DN<11>")
	)
	(segment
		(start 404.603458 -438.623202)
		(end 404.750016 -438.76976)
		(width 0.14224)
		(layer "In15.Cu")
		(net "P5E_CPU0_P2_RX_BUF_DN<11>")
	)
	(segment
		(start 409.528772 -412.089346)
		(end 409.491434 -412.292038)
		(width 0.14224)
		(layer "In15.Cu")
		(net "P5E_CPU0_P2_RX_BUF_DN<11>")
	)
	(segment
		(start 415.90341 -403.56409)
		(end 415.65703 -404.376382)
		(width 0.14224)
		(layer "In15.Cu")
		(net "P5E_CPU0_P2_RX_BUF_DN<11>")
	)
	(arc
		(start 406.412192 -421.571928)
		(mid 406.402764 -421.619947)
		(end 406.37587 -421.660828)
		(width 0.14224)
		(layer "In15.Cu")
		(net "P5E_CPU0_P2_RX_BUF_DN<11>")
	)
	(arc
		(start 409.75026 -411.663134)
		(mid 409.686759 -411.743922)
		(end 409.635198 -411.832806)
		(width 0.14224)
		(layer "In15.Cu")
		(net "P5E_CPU0_P2_RX_BUF_DN<11>")
	)
	(arc
		(start 409.475432 -413.306514)
		(mid 409.44428 -413.463217)
		(end 409.355544 -413.596074)
		(width 0.14224)
		(layer "In15.Cu")
		(net "P5E_CPU0_P2_RX_BUF_DN<11>")
	)
	(arc
		(start 409.568396 -411.969458)
		(mid 409.544487 -412.028048)
		(end 409.528772 -412.089346)
		(width 0.14224)
		(layer "In15.Cu")
		(net "P5E_CPU0_P2_RX_BUF_DN<11>")
	)
	(arc
		(start 409.491434 -412.292038)
		(mid 409.479399 -412.380319)
		(end 409.475432 -412.46933)
		(width 0.14224)
		(layer "In15.Cu")
		(net "P5E_CPU0_P2_RX_BUF_DN<11>")
	)
	(arc
		(start 407.730198 -419.370256)
		(mid 407.682109 -419.411248)
		(end 407.626566 -419.441376)
		(width 0.14224)
		(layer "In15.Cu")
		(net "P5E_CPU0_P2_RX_BUF_DN<11>")
	)
	(arc
		(start 407.943812 -419.079426)
		(mid 407.931893 -419.141263)
		(end 407.897838 -419.194234)
		(width 0.14224)
		(layer "In15.Cu")
		(net "P5E_CPU0_P2_RX_BUF_DN<11>")
	)
	(arc
		(start 406.673558 -419.836346)
		(mid 406.483476 -419.992691)
		(end 406.412192 -420.228268)
		(width 0.14224)
		(layer "In15.Cu")
		(net "P5E_CPU0_P2_RX_BUF_DN<11>")
	)
	(arc
		(start 403.858476 -424.361864)
		(mid 403.80686 -424.470891)
		(end 403.789134 -424.59021)
		(width 0.14224)
		(layer "In15.Cu")
		(net "P5E_CPU0_P2_RX_BUF_DN<11>")
	)
	(arc
		(start 408.709114 -414.006538)
		(mid 408.45451 -414.142803)
		(end 408.23134 -414.32607)
		(width 0.14224)
		(layer "In15.Cu")
		(net "P5E_CPU0_P2_RX_BUF_DN<11>")
	)
	(arc
		(start 408.23134 -414.32607)
		(mid 408.018451 -414.644536)
		(end 407.943812 -415.020252)
		(width 0.14224)
		(layer "In15.Cu")
		(net "P5E_CPU0_P2_RX_BUF_DN<11>")
	)
	(arc
		(start 414.097216 -406.710134)
		(mid 413.674127 -407.295016)
		(end 413.208978 -407.847038)
		(width 0.14224)
		(layer "In15.Cu")
		(net "P5E_CPU0_P2_RX_BUF_DN<11>")
	)
	(segment
		(start 415.084514 -401.143216)
		(end 414.957514 -401.016216)
		(width 0.1016)
		(layer "F.Cu")
		(net "P5E_CPU0_P2_RX_BUF_DN<10>")
	)
	(segment
		(start 415.444432 -401.002246)
		(end 415.303462 -401.143216)
		(width 0.1016)
		(layer "F.Cu")
		(net "P5E_CPU0_P2_RX_BUF_DN<10>")
	)
	(segment
		(start 415.303462 -401.143216)
		(end 415.084514 -401.143216)
		(width 0.1016)
		(layer "F.Cu")
		(net "P5E_CPU0_P2_RX_BUF_DN<10>")
	)
	(segment
		(start 414.957514 -400.048984)
		(end 415.045652 -399.960846)
		(width 0.1016)
		(layer "F.Cu")
		(net "P5E_CPU0_P2_RX_BUF_DN<10>")
	)
	(segment
		(start 415.444432 -400.811238)
		(end 415.444432 -401.002246)
		(width 0.1016)
		(layer "F.Cu")
		(net "P5E_CPU0_P2_RX_BUF_DN<10>")
	)
	(segment
		(start 415.045652 -399.960846)
		(end 415.045652 -399.143474)
		(width 0.1016)
		(layer "F.Cu")
		(net "P5E_CPU0_P2_RX_BUF_DN<10>")
	)
	(segment
		(start 414.957514 -401.016216)
		(end 414.957514 -400.048984)
		(width 0.1016)
		(layer "F.Cu")
		(net "P5E_CPU0_P2_RX_BUF_DN<10>")
	)
	(segment
		(start 405.645874 -414.006538)
		(end 405.89581 -413.90316)
		(width 0.14224)
		(layer "In15.Cu")
		(net "P5E_CPU0_P2_RX_BUF_DN<10>")
	)
	(segment
		(start 415.306002 -401.117816)
		(end 415.444432 -400.979386)
		(width 0.14224)
		(layer "In15.Cu")
		(net "P5E_CPU0_P2_RX_BUF_DN<10>")
	)
	(segment
		(start 406.16505 -413.723328)
		(end 406.292304 -413.596074)
		(width 0.14224)
		(layer "In15.Cu")
		(net "P5E_CPU0_P2_RX_BUF_DN<10>")
	)
	(segment
		(start 402.75002 -437.769762)
		(end 402.603462 -437.623204)
		(width 0.14224)
		(layer "In15.Cu")
		(net "P5E_CPU0_P2_RX_BUF_DN<10>")
	)
	(segment
		(start 402.490686 -423.32275)
		(end 403.348952 -421.889428)
		(width 0.14224)
		(layer "In15.Cu")
		(net "P5E_CPU0_P2_RX_BUF_DN<10>")
	)
	(segment
		(start 404.880572 -418.925756)
		(end 404.880572 -415.020252)
		(width 0.14224)
		(layer "In15.Cu")
		(net "P5E_CPU0_P2_RX_BUF_DN<10>")
	)
	(segment
		(start 414.703514 -401.425156)
		(end 415.010854 -401.117816)
		(width 0.14224)
		(layer "In15.Cu")
		(net "P5E_CPU0_P2_RX_BUF_DN<10>")
	)
	(segment
		(start 407.43759 -411.233366)
		(end 407.736548 -410.988002)
		(width 0.14224)
		(layer "In15.Cu")
		(net "P5E_CPU0_P2_RX_BUF_DN<10>")
	)
	(segment
		(start 402.471636 -423.357548)
		(end 402.472906 -423.355262)
		(width 0.14224)
		(layer "In15.Cu")
		(net "P5E_CPU0_P2_RX_BUF_DN<10>")
	)
	(segment
		(start 405.89581 -413.90316)
		(end 406.16505 -413.723328)
		(width 0.14224)
		(layer "In15.Cu")
		(net "P5E_CPU0_P2_RX_BUF_DN<10>")
	)
	(segment
		(start 403.71268 -419.794182)
		(end 404.629874 -419.41369)
		(width 0.14224)
		(layer "In15.Cu")
		(net "P5E_CPU0_P2_RX_BUF_DN<10>")
	)
	(segment
		(start 407.857706 -410.897324)
		(end 410.12872 -409.344876)
		(width 0.14224)
		(layer "In15.Cu")
		(net "P5E_CPU0_P2_RX_BUF_DN<10>")
	)
	(segment
		(start 402.472906 -423.355262)
		(end 402.479002 -423.34307)
		(width 0.14224)
		(layer "In15.Cu")
		(net "P5E_CPU0_P2_RX_BUF_DN<10>")
	)
	(segment
		(start 402.75002 -438.089802)
		(end 402.75002 -437.769762)
		(width 0.14224)
		(layer "In15.Cu")
		(net "P5E_CPU0_P2_RX_BUF_DN<10>")
	)
	(segment
		(start 401.890738 -424.515788)
		(end 402.471636 -423.357548)
		(width 0.14224)
		(layer "In15.Cu")
		(net "P5E_CPU0_P2_RX_BUF_DN<10>")
	)
	(segment
		(start 404.764748 -419.2778)
		(end 404.856696 -419.0492)
		(width 0.14224)
		(layer "In15.Cu")
		(net "P5E_CPU0_P2_RX_BUF_DN<10>")
	)
	(segment
		(start 406.412192 -413.306514)
		(end 406.412192 -412.488634)
		(width 0.14224)
		(layer "In15.Cu")
		(net "P5E_CPU0_P2_RX_BUF_DN<10>")
	)
	(segment
		(start 415.010854 -401.117816)
		(end 415.306002 -401.117816)
		(width 0.14224)
		(layer "In15.Cu")
		(net "P5E_CPU0_P2_RX_BUF_DN<10>")
	)
	(segment
		(start 410.12872 -409.344876)
		(end 412.56585 -406.907746)
		(width 0.14224)
		(layer "In15.Cu")
		(net "P5E_CPU0_P2_RX_BUF_DN<10>")
	)
	(segment
		(start 402.603462 -437.623204)
		(end 402.096478 -437.623204)
		(width 0.14224)
		(layer "In15.Cu")
		(net "P5E_CPU0_P2_RX_BUF_DN<10>")
	)
	(segment
		(start 412.56585 -406.907746)
		(end 414.703514 -403.8727)
		(width 0.14224)
		(layer "In15.Cu")
		(net "P5E_CPU0_P2_RX_BUF_DN<10>")
	)
	(segment
		(start 402.096478 -437.623204)
		(end 401.789138 -437.315864)
		(width 0.14224)
		(layer "In15.Cu")
		(net "P5E_CPU0_P2_RX_BUF_DN<10>")
	)
	(segment
		(start 401.789138 -437.315864)
		(end 401.789138 -424.94581)
		(width 0.14224)
		(layer "In15.Cu")
		(net "P5E_CPU0_P2_RX_BUF_DN<10>")
	)
	(segment
		(start 414.703514 -403.8727)
		(end 414.703514 -401.425156)
		(width 0.14224)
		(layer "In15.Cu")
		(net "P5E_CPU0_P2_RX_BUF_DN<10>")
	)
	(segment
		(start 415.444432 -400.979386)
		(end 415.444432 -400.811238)
		(width 0.14224)
		(layer "In15.Cu")
		(net "P5E_CPU0_P2_RX_BUF_DN<10>")
	)
	(segment
		(start 406.462484 -412.251652)
		(end 406.53462 -412.088838)
		(width 0.14224)
		(layer "In15.Cu")
		(net "P5E_CPU0_P2_RX_BUF_DN<10>")
	)
	(segment
		(start 403.348952 -421.889428)
		(end 403.348952 -420.339012)
		(width 0.14224)
		(layer "In15.Cu")
		(net "P5E_CPU0_P2_RX_BUF_DN<10>")
	)
	(arc
		(start 402.479002 -423.34307)
		(mid 402.484697 -423.332826)
		(end 402.490686 -423.32275)
		(width 0.14224)
		(layer "In15.Cu")
		(net "P5E_CPU0_P2_RX_BUF_DN<10>")
	)
	(arc
		(start 407.117296 -411.501844)
		(mid 407.276732 -411.366756)
		(end 407.43759 -411.233366)
		(width 0.14224)
		(layer "In15.Cu")
		(net "P5E_CPU0_P2_RX_BUF_DN<10>")
	)
	(arc
		(start 404.629874 -419.41369)
		(mid 404.710996 -419.359333)
		(end 404.764748 -419.2778)
		(width 0.14224)
		(layer "In15.Cu")
		(net "P5E_CPU0_P2_RX_BUF_DN<10>")
	)
	(arc
		(start 404.856696 -419.0492)
		(mid 404.874553 -418.988623)
		(end 404.880572 -418.925756)
		(width 0.14224)
		(layer "In15.Cu")
		(net "P5E_CPU0_P2_RX_BUF_DN<10>")
	)
	(arc
		(start 406.676352 -411.891988)
		(mid 406.895301 -411.695194)
		(end 407.117296 -411.501844)
		(width 0.14224)
		(layer "In15.Cu")
		(net "P5E_CPU0_P2_RX_BUF_DN<10>")
	)
	(arc
		(start 407.736548 -410.988002)
		(mid 407.796136 -410.941339)
		(end 407.857706 -410.897324)
		(width 0.14224)
		(layer "In15.Cu")
		(net "P5E_CPU0_P2_RX_BUF_DN<10>")
	)
	(arc
		(start 406.292304 -413.596074)
		(mid 406.381019 -413.463209)
		(end 406.412192 -413.306514)
		(width 0.14224)
		(layer "In15.Cu")
		(net "P5E_CPU0_P2_RX_BUF_DN<10>")
	)
	(arc
		(start 406.412192 -412.488634)
		(mid 406.424929 -412.367509)
		(end 406.462484 -412.251652)
		(width 0.14224)
		(layer "In15.Cu")
		(net "P5E_CPU0_P2_RX_BUF_DN<10>")
	)
	(arc
		(start 404.880572 -415.020252)
		(mid 404.955262 -414.644557)
		(end 405.1681 -414.32607)
		(width 0.14224)
		(layer "In15.Cu")
		(net "P5E_CPU0_P2_RX_BUF_DN<10>")
	)
	(arc
		(start 406.53462 -412.088838)
		(mid 406.59528 -411.983067)
		(end 406.676352 -411.891988)
		(width 0.14224)
		(layer "In15.Cu")
		(net "P5E_CPU0_P2_RX_BUF_DN<10>")
	)
	(arc
		(start 401.789138 -424.94581)
		(mid 401.81473 -424.724841)
		(end 401.890738 -424.515788)
		(width 0.14224)
		(layer "In15.Cu")
		(net "P5E_CPU0_P2_RX_BUF_DN<10>")
	)
	(arc
		(start 405.1681 -414.32607)
		(mid 405.391265 -414.142796)
		(end 405.645874 -414.006538)
		(width 0.14224)
		(layer "In15.Cu")
		(net "P5E_CPU0_P2_RX_BUF_DN<10>")
	)
	(arc
		(start 403.348952 -420.339012)
		(mid 403.448228 -420.011447)
		(end 403.71268 -419.794182)
		(width 0.14224)
		(layer "In15.Cu")
		(net "P5E_CPU0_P2_RX_BUF_DN<10>")
	)
	(segment
		(start 403.045676 -399.143474)
		(end 403.046184 -399.143982)
		(width 0.1016)
		(layer "F.Cu")
		(net "P5E_CPU0_P2_RX_BUF_DN<0>")
	)
	(segment
		(start 403.303486 -401.143216)
		(end 403.444202 -401.0025)
		(width 0.1016)
		(layer "F.Cu")
		(net "P5E_CPU0_P2_RX_BUF_DN<0>")
	)
	(segment
		(start 402.935186 -400.993864)
		(end 403.084538 -401.143216)
		(width 0.1016)
		(layer "F.Cu")
		(net "P5E_CPU0_P2_RX_BUF_DN<0>")
	)
	(segment
		(start 402.935186 -400.071336)
		(end 402.935186 -400.993864)
		(width 0.1016)
		(layer "F.Cu")
		(net "P5E_CPU0_P2_RX_BUF_DN<0>")
	)
	(segment
		(start 403.046184 -399.143982)
		(end 403.046184 -399.960338)
		(width 0.1016)
		(layer "F.Cu")
		(net "P5E_CPU0_P2_RX_BUF_DN<0>")
	)
	(segment
		(start 403.444202 -401.0025)
		(end 403.444202 -400.811238)
		(width 0.1016)
		(layer "F.Cu")
		(net "P5E_CPU0_P2_RX_BUF_DN<0>")
	)
	(segment
		(start 403.046184 -399.960338)
		(end 402.935186 -400.071336)
		(width 0.1016)
		(layer "F.Cu")
		(net "P5E_CPU0_P2_RX_BUF_DN<0>")
	)
	(segment
		(start 403.084538 -401.143216)
		(end 403.303486 -401.143216)
		(width 0.1016)
		(layer "F.Cu")
		(net "P5E_CPU0_P2_RX_BUF_DN<0>")
	)
	(segment
		(start 381.599186 -437.61914)
		(end 380.961138 -437.61914)
		(width 0.14224)
		(layer "In15.Cu")
		(net "P5E_CPU0_P2_RX_BUF_DN<0>")
	)
	(segment
		(start 376.10288 -411.703012)
		(end 376.497596 -411.367986)
		(width 0.14224)
		(layer "In15.Cu")
		(net "P5E_CPU0_P2_RX_BUF_DN<0>")
	)
	(segment
		(start 375.82602 -412.212536)
		(end 375.951242 -411.911038)
		(width 0.14224)
		(layer "In15.Cu")
		(net "P5E_CPU0_P2_RX_BUF_DN<0>")
	)
	(segment
		(start 402.786596 -401.102068)
		(end 403.153372 -401.102068)
		(width 0.14224)
		(layer "In15.Cu")
		(net "P5E_CPU0_P2_RX_BUF_DN<0>")
	)
	(segment
		(start 375.53265 -413.723328)
		(end 375.659904 -413.596074)
		(width 0.14224)
		(layer "In15.Cu")
		(net "P5E_CPU0_P2_RX_BUF_DN<0>")
	)
	(segment
		(start 375.779792 -413.306514)
		(end 375.779792 -412.443676)
		(width 0.14224)
		(layer "In15.Cu")
		(net "P5E_CPU0_P2_RX_BUF_DN<0>")
	)
	(segment
		(start 381.749808 -437.769762)
		(end 381.599186 -437.61914)
		(width 0.14224)
		(layer "In15.Cu")
		(net "P5E_CPU0_P2_RX_BUF_DN<0>")
	)
	(segment
		(start 375.013474 -414.006538)
		(end 375.26341 -413.90316)
		(width 0.14224)
		(layer "In15.Cu")
		(net "P5E_CPU0_P2_RX_BUF_DN<0>")
	)
	(segment
		(start 372.968774 -419.83406)
		(end 373.51589 -419.607238)
		(width 0.14224)
		(layer "In15.Cu")
		(net "P5E_CPU0_P2_RX_BUF_DN<0>")
	)
	(segment
		(start 403.153372 -401.102068)
		(end 403.444202 -400.811238)
		(width 0.14224)
		(layer "In15.Cu")
		(net "P5E_CPU0_P2_RX_BUF_DN<0>")
	)
	(segment
		(start 401.891754 -401.425156)
		(end 402.786596 -401.102068)
		(width 0.14224)
		(layer "In15.Cu")
		(net "P5E_CPU0_P2_RX_BUF_DN<0>")
	)
	(segment
		(start 380.961138 -437.61914)
		(end 380.308104 -436.966106)
		(width 0.14224)
		(layer "In15.Cu")
		(net "P5E_CPU0_P2_RX_BUF_DN<0>")
	)
	(segment
		(start 380.038356 -429.76038)
		(end 372.979696 -422.70172)
		(width 0.14224)
		(layer "In15.Cu")
		(net "P5E_CPU0_P2_RX_BUF_DN<0>")
	)
	(segment
		(start 381.749808 -438.089802)
		(end 381.749808 -437.769762)
		(width 0.14224)
		(layer "In15.Cu")
		(net "P5E_CPU0_P2_RX_BUF_DN<0>")
	)
	(segment
		(start 400.352768 -402.145246)
		(end 401.600416 -401.5613)
		(width 0.14224)
		(layer "In15.Cu")
		(net "P5E_CPU0_P2_RX_BUF_DN<0>")
	)
	(segment
		(start 380.308104 -436.966106)
		(end 380.308104 -430.411636)
		(width 0.14224)
		(layer "In15.Cu")
		(net "P5E_CPU0_P2_RX_BUF_DN<0>")
	)
	(segment
		(start 396.518384 -403.536658)
		(end 400.259296 -402.184108)
		(width 0.14224)
		(layer "In15.Cu")
		(net "P5E_CPU0_P2_RX_BUF_DN<0>")
	)
	(segment
		(start 395.158214 -403.809708)
		(end 395.872208 -403.70125)
		(width 0.14224)
		(layer "In15.Cu")
		(net "P5E_CPU0_P2_RX_BUF_DN<0>")
	)
	(segment
		(start 375.26341 -413.90316)
		(end 375.53265 -413.723328)
		(width 0.14224)
		(layer "In15.Cu")
		(net "P5E_CPU0_P2_RX_BUF_DN<0>")
	)
	(segment
		(start 374.248172 -419.103302)
		(end 374.248172 -415.020252)
		(width 0.14224)
		(layer "In15.Cu")
		(net "P5E_CPU0_P2_RX_BUF_DN<0>")
	)
	(segment
		(start 373.51589 -419.607238)
		(end 373.515636 -419.607238)
		(width 0.14224)
		(layer "In15.Cu")
		(net "P5E_CPU0_P2_RX_BUF_DN<0>")
	)
	(segment
		(start 372.716552 -422.066212)
		(end 372.716552 -420.21125)
		(width 0.14224)
		(layer "In15.Cu")
		(net "P5E_CPU0_P2_RX_BUF_DN<0>")
	)
	(segment
		(start 386.032502 -407.091642)
		(end 394.982192 -403.854666)
		(width 0.14224)
		(layer "In15.Cu")
		(net "P5E_CPU0_P2_RX_BUF_DN<0>")
	)
	(segment
		(start 376.673618 -411.256734)
		(end 384.606038 -407.671016)
		(width 0.14224)
		(layer "In15.Cu")
		(net "P5E_CPU0_P2_RX_BUF_DN<0>")
	)
	(segment
		(start 373.515636 -419.607238)
		(end 374.062498 -419.38067)
		(width 0.14224)
		(layer "In15.Cu")
		(net "P5E_CPU0_P2_RX_BUF_DN<0>")
	)
	(arc
		(start 394.982192 -403.854666)
		(mid 395.069099 -403.827866)
		(end 395.158214 -403.809708)
		(width 0.14224)
		(layer "In15.Cu")
		(net "P5E_CPU0_P2_RX_BUF_DN<0>")
	)
	(arc
		(start 375.951242 -411.911038)
		(mid 376.014694 -411.798008)
		(end 376.10288 -411.703012)
		(width 0.14224)
		(layer "In15.Cu")
		(net "P5E_CPU0_P2_RX_BUF_DN<0>")
	)
	(arc
		(start 374.248172 -415.020252)
		(mid 374.322862 -414.644557)
		(end 374.5357 -414.32607)
		(width 0.14224)
		(layer "In15.Cu")
		(net "P5E_CPU0_P2_RX_BUF_DN<0>")
	)
	(arc
		(start 380.308104 -430.411636)
		(mid 380.237997 -430.059183)
		(end 380.038356 -429.76038)
		(width 0.14224)
		(layer "In15.Cu")
		(net "P5E_CPU0_P2_RX_BUF_DN<0>")
	)
	(arc
		(start 384.606038 -407.671016)
		(mid 385.313659 -407.367514)
		(end 386.032502 -407.091642)
		(width 0.14224)
		(layer "In15.Cu")
		(net "P5E_CPU0_P2_RX_BUF_DN<0>")
	)
	(arc
		(start 375.779792 -412.443676)
		(mid 375.791511 -412.325827)
		(end 375.82602 -412.212536)
		(width 0.14224)
		(layer "In15.Cu")
		(net "P5E_CPU0_P2_RX_BUF_DN<0>")
	)
	(arc
		(start 376.497596 -411.367986)
		(mid 376.581723 -411.306212)
		(end 376.673618 -411.256734)
		(width 0.14224)
		(layer "In15.Cu")
		(net "P5E_CPU0_P2_RX_BUF_DN<0>")
	)
	(arc
		(start 374.5357 -414.32607)
		(mid 374.758865 -414.142796)
		(end 375.013474 -414.006538)
		(width 0.14224)
		(layer "In15.Cu")
		(net "P5E_CPU0_P2_RX_BUF_DN<0>")
	)
	(arc
		(start 401.600416 -401.5613)
		(mid 401.64993 -401.537259)
		(end 401.698714 -401.51177)
		(width 0.14224)
		(layer "In15.Cu")
		(net "P5E_CPU0_P2_RX_BUF_DN<0>")
	)
	(arc
		(start 400.259296 -402.184108)
		(mid 400.306476 -402.165745)
		(end 400.352768 -402.145246)
		(width 0.14224)
		(layer "In15.Cu")
		(net "P5E_CPU0_P2_RX_BUF_DN<0>")
	)
	(arc
		(start 395.872208 -403.70125)
		(mid 396.199368 -403.634936)
		(end 396.518384 -403.536658)
		(width 0.14224)
		(layer "In15.Cu")
		(net "P5E_CPU0_P2_RX_BUF_DN<0>")
	)
	(arc
		(start 372.716552 -420.21125)
		(mid 372.78549 -419.984435)
		(end 372.968774 -419.83406)
		(width 0.14224)
		(layer "In15.Cu")
		(net "P5E_CPU0_P2_RX_BUF_DN<0>")
	)
	(arc
		(start 372.979696 -422.70172)
		(mid 372.784926 -422.410132)
		(end 372.716552 -422.066212)
		(width 0.14224)
		(layer "In15.Cu")
		(net "P5E_CPU0_P2_RX_BUF_DN<0>")
	)
	(arc
		(start 401.698714 -401.51177)
		(mid 401.793635 -401.464901)
		(end 401.891754 -401.425156)
		(width 0.14224)
		(layer "In15.Cu")
		(net "P5E_CPU0_P2_RX_BUF_DN<0>")
	)
	(arc
		(start 375.659904 -413.596074)
		(mid 375.748619 -413.463209)
		(end 375.779792 -413.306514)
		(width 0.14224)
		(layer "In15.Cu")
		(net "P5E_CPU0_P2_RX_BUF_DN<0>")
	)
	(arc
		(start 374.062498 -419.38067)
		(mid 374.197473 -419.270176)
		(end 374.248172 -419.103302)
		(width 0.14224)
		(layer "In15.Cu")
		(net "P5E_CPU0_P2_RX_BUF_DN<0>")
	)
	(segment
		(start 346.998036 -397.849344)
		(end 347.518736 -397.849344)
		(width 0.127)
		(layer "F.Cu")
		(net "P5E_CPU0_P1_TX_BUF_DP<9>")
	)
	(segment
		(start 333.487776 -415.65703)
		(end 333.758286 -415.38652)
		(width 0.12954)
		(layer "B.Cu")
		(net "P5E_CPU0_P1_TX_BUF_DP<9>")
	)
	(segment
		(start 333.487776 -416.336734)
		(end 333.487776 -415.65703)
		(width 0.12954)
		(layer "B.Cu")
		(net "P5E_CPU0_P1_TX_BUF_DP<9>")
	)
	(segment
		(start 333.783686 -416.632644)
		(end 333.487776 -416.336734)
		(width 0.12954)
		(layer "B.Cu")
		(net "P5E_CPU0_P1_TX_BUF_DP<9>")
	)
	(segment
		(start 335.91119 -410.667962)
		(end 335.395824 -410.943552)
		(width 0.14224)
		(layer "In6.Cu")
		(net "P5E_CPU0_P1_TX_BUF_DP<9>")
	)
	(segment
		(start 347.403928 -397.734536)
		(end 347.223842 -397.734536)
		(width 0.14224)
		(layer "In6.Cu")
		(net "P5E_CPU0_P1_TX_BUF_DP<9>")
	)
	(segment
		(start 334.777334 -411.27426)
		(end 333.98841 -411.6959)
		(width 0.14224)
		(layer "In6.Cu")
		(net "P5E_CPU0_P1_TX_BUF_DP<9>")
	)
	(segment
		(start 334.963008 -411.330394)
		(end 334.777334 -411.27426)
		(width 0.14224)
		(layer "In6.Cu")
		(net "P5E_CPU0_P1_TX_BUF_DP<9>")
	)
	(segment
		(start 347.486732 -398.608296)
		(end 347.480636 -398.677384)
		(width 0.14224)
		(layer "In6.Cu")
		(net "P5E_CPU0_P1_TX_BUF_DP<9>")
	)
	(segment
		(start 346.723462 -400.311366)
		(end 346.723462 -402.696426)
		(width 0.14224)
		(layer "In6.Cu")
		(net "P5E_CPU0_P1_TX_BUF_DP<9>")
	)
	(segment
		(start 346.860622 -403.260306)
		(end 346.723462 -403.397466)
		(width 0.14224)
		(layer "In6.Cu")
		(net "P5E_CPU0_P1_TX_BUF_DP<9>")
	)
	(segment
		(start 347.518736 -397.849344)
		(end 347.403928 -397.734536)
		(width 0.14224)
		(layer "In6.Cu")
		(net "P5E_CPU0_P1_TX_BUF_DP<9>")
	)
	(segment
		(start 346.723462 -402.696426)
		(end 346.860622 -402.833586)
		(width 0.14224)
		(layer "In6.Cu")
		(net "P5E_CPU0_P1_TX_BUF_DP<9>")
	)
	(segment
		(start 341.30361 -408.586686)
		(end 338.50072 -409.74772)
		(width 0.14224)
		(layer "In6.Cu")
		(net "P5E_CPU0_P1_TX_BUF_DP<9>")
	)
	(segment
		(start 335.339436 -411.129226)
		(end 334.963008 -411.330394)
		(width 0.14224)
		(layer "In6.Cu")
		(net "P5E_CPU0_P1_TX_BUF_DP<9>")
	)
	(segment
		(start 338.368894 -409.798266)
		(end 337.966812 -409.940506)
		(width 0.14224)
		(layer "In6.Cu")
		(net "P5E_CPU0_P1_TX_BUF_DP<9>")
	)
	(segment
		(start 347.222826 -398.095724)
		(end 347.344492 -398.21739)
		(width 0.14224)
		(layer "In6.Cu")
		(net "P5E_CPU0_P1_TX_BUF_DP<9>")
	)
	(segment
		(start 333.467456 -412.565088)
		(end 333.467456 -415.09569)
		(width 0.14224)
		(layer "In6.Cu")
		(net "P5E_CPU0_P1_TX_BUF_DP<9>")
	)
	(segment
		(start 337.966812 -409.940506)
		(end 337.883246 -410.115766)
		(width 0.14224)
		(layer "In6.Cu")
		(net "P5E_CPU0_P1_TX_BUF_DP<9>")
	)
	(segment
		(start 347.223842 -397.734536)
		(end 347.133164 -397.825214)
		(width 0.14224)
		(layer "In6.Cu")
		(net "P5E_CPU0_P1_TX_BUF_DP<9>")
	)
	(segment
		(start 337.883246 -410.115766)
		(end 337.480656 -410.258006)
		(width 0.14224)
		(layer "In6.Cu")
		(net "P5E_CPU0_P1_TX_BUF_DP<9>")
	)
	(segment
		(start 346.860622 -402.833586)
		(end 346.860622 -403.260306)
		(width 0.14224)
		(layer "In6.Cu")
		(net "P5E_CPU0_P1_TX_BUF_DP<9>")
	)
	(segment
		(start 347.175582 -399.331434)
		(end 347.102176 -399.40484)
		(width 0.14224)
		(layer "In6.Cu")
		(net "P5E_CPU0_P1_TX_BUF_DP<9>")
	)
	(segment
		(start 346.723462 -403.397466)
		(end 346.723462 -403.654768)
		(width 0.14224)
		(layer "In6.Cu")
		(net "P5E_CPU0_P1_TX_BUF_DP<9>")
	)
	(segment
		(start 337.30565 -410.17444)
		(end 335.91119 -410.667962)
		(width 0.14224)
		(layer "In6.Cu")
		(net "P5E_CPU0_P1_TX_BUF_DP<9>")
	)
	(segment
		(start 347.133164 -397.825214)
		(end 347.133164 -397.879316)
		(width 0.14224)
		(layer "In6.Cu")
		(net "P5E_CPU0_P1_TX_BUF_DP<9>")
	)
	(segment
		(start 335.395824 -410.943552)
		(end 335.339436 -411.129226)
		(width 0.14224)
		(layer "In6.Cu")
		(net "P5E_CPU0_P1_TX_BUF_DP<9>")
	)
	(segment
		(start 333.467456 -415.09569)
		(end 333.758286 -415.38652)
		(width 0.14224)
		(layer "In6.Cu")
		(net "P5E_CPU0_P1_TX_BUF_DP<9>")
	)
	(segment
		(start 337.480656 -410.258006)
		(end 337.30565 -410.17444)
		(width 0.14224)
		(layer "In6.Cu")
		(net "P5E_CPU0_P1_TX_BUF_DP<9>")
	)
	(segment
		(start 346.603574 -403.944074)
		(end 343.285064 -407.262584)
		(width 0.14224)
		(layer "In6.Cu")
		(net "P5E_CPU0_P1_TX_BUF_DP<9>")
	)
	(arc
		(start 347.344492 -398.21739)
		(mid 347.458958 -398.397073)
		(end 347.486732 -398.608296)
		(width 0.14224)
		(layer "In6.Cu")
		(net "P5E_CPU0_P1_TX_BUF_DP<9>")
	)
	(arc
		(start 333.98841 -411.6959)
		(mid 333.607647 -412.058405)
		(end 333.467456 -412.565088)
		(width 0.14224)
		(layer "In6.Cu")
		(net "P5E_CPU0_P1_TX_BUF_DP<9>")
	)
	(arc
		(start 346.723462 -403.654768)
		(mid 346.692299 -403.811346)
		(end 346.603574 -403.944074)
		(width 0.14224)
		(layer "In6.Cu")
		(net "P5E_CPU0_P1_TX_BUF_DP<9>")
	)
	(arc
		(start 343.285064 -407.262584)
		(mid 342.359536 -408.022201)
		(end 341.30361 -408.586686)
		(width 0.14224)
		(layer "In6.Cu")
		(net "P5E_CPU0_P1_TX_BUF_DP<9>")
	)
	(arc
		(start 347.133164 -397.879316)
		(mid 347.156477 -397.99643)
		(end 347.222826 -398.095724)
		(width 0.14224)
		(layer "In6.Cu")
		(net "P5E_CPU0_P1_TX_BUF_DP<9>")
	)
	(arc
		(start 338.50072 -409.74772)
		(mid 338.435138 -409.773857)
		(end 338.368894 -409.798266)
		(width 0.14224)
		(layer "In6.Cu")
		(net "P5E_CPU0_P1_TX_BUF_DP<9>")
	)
	(arc
		(start 347.102176 -399.40484)
		(mid 346.832759 -399.824662)
		(end 346.723462 -400.311366)
		(width 0.14224)
		(layer "In6.Cu")
		(net "P5E_CPU0_P1_TX_BUF_DP<9>")
	)
	(arc
		(start 347.480636 -398.677384)
		(mid 347.385871 -399.031358)
		(end 347.175582 -399.331434)
		(width 0.14224)
		(layer "In6.Cu")
		(net "P5E_CPU0_P1_TX_BUF_DP<9>")
	)
	(segment
		(start 345.79814 -397.849344)
		(end 346.31884 -397.849344)
		(width 0.127)
		(layer "F.Cu")
		(net "P5E_CPU0_P1_TX_BUF_DP<8>")
	)
	(segment
		(start 330.424536 -415.65703)
		(end 330.695046 -415.38652)
		(width 0.12954)
		(layer "B.Cu")
		(net "P5E_CPU0_P1_TX_BUF_DP<8>")
	)
	(segment
		(start 330.720446 -416.632644)
		(end 330.424536 -416.336734)
		(width 0.12954)
		(layer "B.Cu")
		(net "P5E_CPU0_P1_TX_BUF_DP<8>")
	)
	(segment
		(start 330.424536 -416.336734)
		(end 330.424536 -415.65703)
		(width 0.12954)
		(layer "B.Cu")
		(net "P5E_CPU0_P1_TX_BUF_DP<8>")
	)
	(segment
		(start 332.38186 -411.24886)
		(end 332.20279 -411.174692)
		(width 0.14224)
		(layer "In6.Cu")
		(net "P5E_CPU0_P1_TX_BUF_DP<8>")
	)
	(segment
		(start 330.76642 -411.76956)
		(end 330.659486 -411.876494)
		(width 0.14224)
		(layer "In6.Cu")
		(net "P5E_CPU0_P1_TX_BUF_DP<8>")
	)
	(segment
		(start 331.73416 -411.517338)
		(end 331.339698 -411.68066)
		(width 0.14224)
		(layer "In6.Cu")
		(net "P5E_CPU0_P1_TX_BUF_DP<8>")
	)
	(segment
		(start 336.533998 -409.38069)
		(end 333.892906 -410.474668)
		(width 0.14224)
		(layer "In6.Cu")
		(net "P5E_CPU0_P1_TX_BUF_DP<8>")
	)
	(segment
		(start 333.244952 -410.743146)
		(end 332.850744 -410.906214)
		(width 0.14224)
		(layer "In6.Cu")
		(net "P5E_CPU0_P1_TX_BUF_DP<8>")
	)
	(segment
		(start 345.59494 -400.001232)
		(end 345.45778 -400.332702)
		(width 0.14224)
		(layer "In6.Cu")
		(net "P5E_CPU0_P1_TX_BUF_DP<8>")
	)
	(segment
		(start 346.204032 -397.734536)
		(end 346.023946 -397.734536)
		(width 0.14224)
		(layer "In6.Cu")
		(net "P5E_CPU0_P1_TX_BUF_DP<8>")
	)
	(segment
		(start 337.88604 -408.97048)
		(end 336.533998 -409.38069)
		(width 0.14224)
		(layer "In6.Cu")
		(net "P5E_CPU0_P1_TX_BUF_DP<8>")
	)
	(segment
		(start 341.000334 -407.680922)
		(end 337.88604 -408.97048)
		(width 0.14224)
		(layer "In6.Cu")
		(net "P5E_CPU0_P1_TX_BUF_DP<8>")
	)
	(segment
		(start 345.45778 -400.332702)
		(end 345.45778 -402.952204)
		(width 0.14224)
		(layer "In6.Cu")
		(net "P5E_CPU0_P1_TX_BUF_DP<8>")
	)
	(segment
		(start 332.776322 -411.085538)
		(end 332.38186 -411.24886)
		(width 0.14224)
		(layer "In6.Cu")
		(net "P5E_CPU0_P1_TX_BUF_DP<8>")
	)
	(segment
		(start 330.404216 -412.492698)
		(end 330.404216 -415.09569)
		(width 0.14224)
		(layer "In6.Cu")
		(net "P5E_CPU0_P1_TX_BUF_DP<8>")
	)
	(segment
		(start 333.892906 -410.474668)
		(end 333.818484 -410.653992)
		(width 0.14224)
		(layer "In6.Cu")
		(net "P5E_CPU0_P1_TX_BUF_DP<8>")
	)
	(segment
		(start 345.934538 -397.823944)
		(end 345.934538 -397.95069)
		(width 0.14224)
		(layer "In6.Cu")
		(net "P5E_CPU0_P1_TX_BUF_DP<8>")
	)
	(segment
		(start 346.023946 -397.734536)
		(end 345.934538 -397.823944)
		(width 0.14224)
		(layer "In6.Cu")
		(net "P5E_CPU0_P1_TX_BUF_DP<8>")
	)
	(segment
		(start 346.258896 -398.781778)
		(end 346.180664 -398.985486)
		(width 0.14224)
		(layer "In6.Cu")
		(net "P5E_CPU0_P1_TX_BUF_DP<8>")
	)
	(segment
		(start 344.992452 -404.075392)
		(end 342.165178 -406.902666)
		(width 0.14224)
		(layer "In6.Cu")
		(net "P5E_CPU0_P1_TX_BUF_DP<8>")
	)
	(segment
		(start 332.850744 -410.906214)
		(end 332.776322 -411.085538)
		(width 0.14224)
		(layer "In6.Cu")
		(net "P5E_CPU0_P1_TX_BUF_DP<8>")
	)
	(segment
		(start 332.20279 -411.174692)
		(end 331.808582 -411.33776)
		(width 0.14224)
		(layer "In6.Cu")
		(net "P5E_CPU0_P1_TX_BUF_DP<8>")
	)
	(segment
		(start 333.424022 -410.817314)
		(end 333.244952 -410.743146)
		(width 0.14224)
		(layer "In6.Cu")
		(net "P5E_CPU0_P1_TX_BUF_DP<8>")
	)
	(segment
		(start 331.339698 -411.68066)
		(end 331.160628 -411.606492)
		(width 0.14224)
		(layer "In6.Cu")
		(net "P5E_CPU0_P1_TX_BUF_DP<8>")
	)
	(segment
		(start 331.160628 -411.606492)
		(end 330.76642 -411.76956)
		(width 0.14224)
		(layer "In6.Cu")
		(net "P5E_CPU0_P1_TX_BUF_DP<8>")
	)
	(segment
		(start 330.404216 -415.09569)
		(end 330.695046 -415.38652)
		(width 0.14224)
		(layer "In6.Cu")
		(net "P5E_CPU0_P1_TX_BUF_DP<8>")
	)
	(segment
		(start 333.818484 -410.653992)
		(end 333.424022 -410.817314)
		(width 0.14224)
		(layer "In6.Cu")
		(net "P5E_CPU0_P1_TX_BUF_DP<8>")
	)
	(segment
		(start 345.981782 -398.064736)
		(end 346.132658 -398.215612)
		(width 0.14224)
		(layer "In6.Cu")
		(net "P5E_CPU0_P1_TX_BUF_DP<8>")
	)
	(segment
		(start 346.31884 -397.849344)
		(end 346.204032 -397.734536)
		(width 0.14224)
		(layer "In6.Cu")
		(net "P5E_CPU0_P1_TX_BUF_DP<8>")
	)
	(segment
		(start 331.808582 -411.33776)
		(end 331.73416 -411.517338)
		(width 0.14224)
		(layer "In6.Cu")
		(net "P5E_CPU0_P1_TX_BUF_DP<8>")
	)
	(arc
		(start 345.97213 -399.364454)
		(mid 345.766894 -399.672986)
		(end 345.59494 -400.001232)
		(width 0.14224)
		(layer "In6.Cu")
		(net "P5E_CPU0_P1_TX_BUF_DP<8>")
	)
	(arc
		(start 345.45778 -402.952204)
		(mid 345.336846 -403.560089)
		(end 344.992452 -404.075392)
		(width 0.14224)
		(layer "In6.Cu")
		(net "P5E_CPU0_P1_TX_BUF_DP<8>")
	)
	(arc
		(start 346.284042 -398.501362)
		(mid 346.291042 -398.643321)
		(end 346.258896 -398.781778)
		(width 0.14224)
		(layer "In6.Cu")
		(net "P5E_CPU0_P1_TX_BUF_DP<8>")
	)
	(arc
		(start 346.132658 -398.215612)
		(mid 346.229855 -398.3471)
		(end 346.284042 -398.501362)
		(width 0.14224)
		(layer "In6.Cu")
		(net "P5E_CPU0_P1_TX_BUF_DP<8>")
	)
	(arc
		(start 342.165178 -406.902666)
		(mid 341.621086 -407.349161)
		(end 341.000334 -407.680922)
		(width 0.14224)
		(layer "In6.Cu")
		(net "P5E_CPU0_P1_TX_BUF_DP<8>")
	)
	(arc
		(start 345.934538 -397.95069)
		(mid 345.946815 -398.012413)
		(end 345.981782 -398.064736)
		(width 0.14224)
		(layer "In6.Cu")
		(net "P5E_CPU0_P1_TX_BUF_DP<8>")
	)
	(arc
		(start 346.180664 -398.985486)
		(mid 346.089339 -399.182091)
		(end 345.97213 -399.364454)
		(width 0.14224)
		(layer "In6.Cu")
		(net "P5E_CPU0_P1_TX_BUF_DP<8>")
	)
	(arc
		(start 330.659486 -411.876494)
		(mid 330.470581 -412.159211)
		(end 330.404216 -412.492698)
		(width 0.14224)
		(layer "In6.Cu")
		(net "P5E_CPU0_P1_TX_BUF_DP<8>")
	)
	(segment
		(start 344.59799 -397.849344)
		(end 345.11869 -397.849344)
		(width 0.127)
		(layer "F.Cu")
		(net "P5E_CPU0_P1_TX_BUF_DP<7>")
	)
	(segment
		(start 327.657206 -416.632644)
		(end 327.361296 -416.336734)
		(width 0.12954)
		(layer "B.Cu")
		(net "P5E_CPU0_P1_TX_BUF_DP<7>")
	)
	(segment
		(start 327.361296 -415.65703)
		(end 327.631806 -415.38652)
		(width 0.12954)
		(layer "B.Cu")
		(net "P5E_CPU0_P1_TX_BUF_DP<7>")
	)
	(segment
		(start 327.361296 -416.336734)
		(end 327.361296 -415.65703)
		(width 0.12954)
		(layer "B.Cu")
		(net "P5E_CPU0_P1_TX_BUF_DP<7>")
	)
	(segment
		(start 327.340976 -412.460948)
		(end 327.340976 -415.09569)
		(width 0.14224)
		(layer "In6.Cu")
		(net "P5E_CPU0_P1_TX_BUF_DP<7>")
	)
	(segment
		(start 345.003882 -397.734536)
		(end 344.82405 -397.734536)
		(width 0.14224)
		(layer "In6.Cu")
		(net "P5E_CPU0_P1_TX_BUF_DP<7>")
	)
	(segment
		(start 328.003916 -411.642306)
		(end 327.704196 -411.805882)
		(width 0.14224)
		(layer "In6.Cu")
		(net "P5E_CPU0_P1_TX_BUF_DP<7>")
	)
	(segment
		(start 331.089508 -410.623512)
		(end 330.689966 -410.774134)
		(width 0.14224)
		(layer "In6.Cu")
		(net "P5E_CPU0_P1_TX_BUF_DP<7>")
	)
	(segment
		(start 344.741754 -397.816832)
		(end 344.741754 -397.980662)
		(width 0.14224)
		(layer "In6.Cu")
		(net "P5E_CPU0_P1_TX_BUF_DP<7>")
	)
	(segment
		(start 330.034392 -411.022038)
		(end 329.63485 -411.17266)
		(width 0.14224)
		(layer "In6.Cu")
		(net "P5E_CPU0_P1_TX_BUF_DP<7>")
	)
	(segment
		(start 330.689966 -410.774134)
		(end 330.513182 -410.694378)
		(width 0.14224)
		(layer "In6.Cu")
		(net "P5E_CPU0_P1_TX_BUF_DP<7>")
	)
	(segment
		(start 329.059032 -411.243526)
		(end 328.979276 -411.420564)
		(width 0.14224)
		(layer "In6.Cu")
		(net "P5E_CPU0_P1_TX_BUF_DP<7>")
	)
	(segment
		(start 332.592172 -409.90901)
		(end 331.169264 -410.446474)
		(width 0.14224)
		(layer "In6.Cu")
		(net "P5E_CPU0_P1_TX_BUF_DP<7>")
	)
	(segment
		(start 337.67903 -408.046936)
		(end 336.134456 -408.519122)
		(width 0.14224)
		(layer "In6.Cu")
		(net "P5E_CPU0_P1_TX_BUF_DP<7>")
	)
	(segment
		(start 330.513182 -410.694378)
		(end 330.114148 -410.845)
		(width 0.14224)
		(layer "In6.Cu")
		(net "P5E_CPU0_P1_TX_BUF_DP<7>")
	)
	(segment
		(start 331.169264 -410.446474)
		(end 331.089508 -410.623512)
		(width 0.14224)
		(layer "In6.Cu")
		(net "P5E_CPU0_P1_TX_BUF_DP<7>")
	)
	(segment
		(start 345.095322 -398.55775)
		(end 345.095322 -398.690338)
		(width 0.14224)
		(layer "In6.Cu")
		(net "P5E_CPU0_P1_TX_BUF_DP<7>")
	)
	(segment
		(start 328.979276 -411.420564)
		(end 328.579734 -411.57144)
		(width 0.14224)
		(layer "In6.Cu")
		(net "P5E_CPU0_P1_TX_BUF_DP<7>")
	)
	(segment
		(start 344.82405 -397.734536)
		(end 344.741754 -397.816832)
		(width 0.14224)
		(layer "In6.Cu")
		(net "P5E_CPU0_P1_TX_BUF_DP<7>")
	)
	(segment
		(start 336.134456 -408.519122)
		(end 334.732122 -409.02255)
		(width 0.14224)
		(layer "In6.Cu")
		(net "P5E_CPU0_P1_TX_BUF_DP<7>")
	)
	(segment
		(start 328.579734 -411.57144)
		(end 328.40295 -411.491684)
		(width 0.14224)
		(layer "In6.Cu")
		(net "P5E_CPU0_P1_TX_BUF_DP<7>")
	)
	(segment
		(start 345.11869 -397.849344)
		(end 345.003882 -397.734536)
		(width 0.14224)
		(layer "In6.Cu")
		(net "P5E_CPU0_P1_TX_BUF_DP<7>")
	)
	(segment
		(start 330.114148 -410.845)
		(end 330.034392 -411.022038)
		(width 0.14224)
		(layer "In6.Cu")
		(net "P5E_CPU0_P1_TX_BUF_DP<7>")
	)
	(segment
		(start 328.40295 -411.491684)
		(end 328.003916 -411.642306)
		(width 0.14224)
		(layer "In6.Cu")
		(net "P5E_CPU0_P1_TX_BUF_DP<7>")
	)
	(segment
		(start 327.340976 -415.09569)
		(end 327.631806 -415.38652)
		(width 0.14224)
		(layer "In6.Cu")
		(net "P5E_CPU0_P1_TX_BUF_DP<7>")
	)
	(segment
		(start 344.779092 -398.070578)
		(end 344.974164 -398.26565)
		(width 0.14224)
		(layer "In6.Cu")
		(net "P5E_CPU0_P1_TX_BUF_DP<7>")
	)
	(segment
		(start 340.61019 -406.832054)
		(end 337.67903 -408.046936)
		(width 0.14224)
		(layer "In6.Cu")
		(net "P5E_CPU0_P1_TX_BUF_DP<7>")
	)
	(segment
		(start 344.808556 -399.382488)
		(end 344.417396 -399.773648)
		(width 0.14224)
		(layer "In6.Cu")
		(net "P5E_CPU0_P1_TX_BUF_DP<7>")
	)
	(segment
		(start 327.704196 -411.805882)
		(end 327.581514 -411.923738)
		(width 0.14224)
		(layer "In6.Cu")
		(net "P5E_CPU0_P1_TX_BUF_DP<7>")
	)
	(segment
		(start 327.581514 -411.923738)
		(end 327.40854 -412.21533)
		(width 0.14224)
		(layer "In6.Cu")
		(net "P5E_CPU0_P1_TX_BUF_DP<7>")
	)
	(segment
		(start 329.458066 -411.092904)
		(end 329.059032 -411.243526)
		(width 0.14224)
		(layer "In6.Cu")
		(net "P5E_CPU0_P1_TX_BUF_DP<7>")
	)
	(segment
		(start 344.317066 -400.015964)
		(end 344.317066 -402.917914)
		(width 0.14224)
		(layer "In6.Cu")
		(net "P5E_CPU0_P1_TX_BUF_DP<7>")
	)
	(segment
		(start 343.992708 -403.700996)
		(end 341.366602 -406.326594)
		(width 0.14224)
		(layer "In6.Cu")
		(net "P5E_CPU0_P1_TX_BUF_DP<7>")
	)
	(segment
		(start 329.63485 -411.17266)
		(end 329.458066 -411.092904)
		(width 0.14224)
		(layer "In6.Cu")
		(net "P5E_CPU0_P1_TX_BUF_DP<7>")
	)
	(segment
		(start 334.732122 -409.02255)
		(end 332.592172 -409.90901)
		(width 0.14224)
		(layer "In6.Cu")
		(net "P5E_CPU0_P1_TX_BUF_DP<7>")
	)
	(arc
		(start 345.095322 -398.690338)
		(mid 345.020791 -399.064939)
		(end 344.808556 -399.382488)
		(width 0.14224)
		(layer "In6.Cu")
		(net "P5E_CPU0_P1_TX_BUF_DP<7>")
	)
	(arc
		(start 344.417396 -399.773648)
		(mid 344.343165 -399.884838)
		(end 344.317066 -400.015964)
		(width 0.14224)
		(layer "In6.Cu")
		(net "P5E_CPU0_P1_TX_BUF_DP<7>")
	)
	(arc
		(start 341.366602 -406.326594)
		(mid 341.01326 -406.616529)
		(end 340.61019 -406.832054)
		(width 0.14224)
		(layer "In6.Cu")
		(net "P5E_CPU0_P1_TX_BUF_DP<7>")
	)
	(arc
		(start 344.974164 -398.26565)
		(mid 345.063769 -398.399665)
		(end 345.095322 -398.55775)
		(width 0.14224)
		(layer "In6.Cu")
		(net "P5E_CPU0_P1_TX_BUF_DP<7>")
	)
	(arc
		(start 344.317066 -402.917914)
		(mid 344.232767 -403.341713)
		(end 343.992708 -403.700996)
		(width 0.14224)
		(layer "In6.Cu")
		(net "P5E_CPU0_P1_TX_BUF_DP<7>")
	)
	(arc
		(start 327.40854 -412.21533)
		(mid 327.358226 -412.33359)
		(end 327.340976 -412.460948)
		(width 0.14224)
		(layer "In6.Cu")
		(net "P5E_CPU0_P1_TX_BUF_DP<7>")
	)
	(arc
		(start 344.741754 -397.980662)
		(mid 344.751456 -398.029346)
		(end 344.779092 -398.070578)
		(width 0.14224)
		(layer "In6.Cu")
		(net "P5E_CPU0_P1_TX_BUF_DP<7>")
	)
	(segment
		(start 343.398094 -397.849344)
		(end 343.918794 -397.849344)
		(width 0.127)
		(layer "F.Cu")
		(net "P5E_CPU0_P1_TX_BUF_DP<6>")
	)
	(segment
		(start 324.593966 -416.632644)
		(end 324.298056 -416.336734)
		(width 0.12954)
		(layer "B.Cu")
		(net "P5E_CPU0_P1_TX_BUF_DP<6>")
	)
	(segment
		(start 324.298056 -416.336734)
		(end 324.298056 -415.65703)
		(width 0.12954)
		(layer "B.Cu")
		(net "P5E_CPU0_P1_TX_BUF_DP<6>")
	)
	(segment
		(start 324.298056 -415.65703)
		(end 324.568566 -415.38652)
		(width 0.12954)
		(layer "B.Cu")
		(net "P5E_CPU0_P1_TX_BUF_DP<6>")
	)
	(segment
		(start 343.803986 -397.734536)
		(end 343.6239 -397.734536)
		(width 0.14224)
		(layer "In6.Cu")
		(net "P5E_CPU0_P1_TX_BUF_DP<6>")
	)
	(segment
		(start 325.10857 -411.624526)
		(end 324.93458 -411.538928)
		(width 0.14224)
		(layer "In6.Cu")
		(net "P5E_CPU0_P1_TX_BUF_DP<6>")
	)
	(segment
		(start 326.176386 -411.26156)
		(end 326.002396 -411.175962)
		(width 0.14224)
		(layer "In6.Cu")
		(net "P5E_CPU0_P1_TX_BUF_DP<6>")
	)
	(segment
		(start 335.307686 -407.769568)
		(end 332.257654 -409.033218)
		(width 0.14224)
		(layer "In6.Cu")
		(net "P5E_CPU0_P1_TX_BUF_DP<6>")
	)
	(segment
		(start 332.257654 -409.033218)
		(end 331.800708 -409.205176)
		(width 0.14224)
		(layer "In6.Cu")
		(net "P5E_CPU0_P1_TX_BUF_DP<6>")
	)
	(segment
		(start 343.6239 -397.734536)
		(end 343.534492 -397.823944)
		(width 0.14224)
		(layer "In6.Cu")
		(net "P5E_CPU0_P1_TX_BUF_DP<6>")
	)
	(segment
		(start 340.21776 -405.985472)
		(end 337.584034 -407.076402)
		(width 0.14224)
		(layer "In6.Cu")
		(net "P5E_CPU0_P1_TX_BUF_DP<6>")
	)
	(segment
		(start 327.734168 -410.58719)
		(end 327.64857 -410.761434)
		(width 0.14224)
		(layer "In6.Cu")
		(net "P5E_CPU0_P1_TX_BUF_DP<6>")
	)
	(segment
		(start 331.800708 -409.205176)
		(end 327.734168 -410.58719)
		(width 0.14224)
		(layer "In6.Cu")
		(net "P5E_CPU0_P1_TX_BUF_DP<6>")
	)
	(segment
		(start 337.584034 -407.076402)
		(end 335.307686 -407.769568)
		(width 0.14224)
		(layer "In6.Cu")
		(net "P5E_CPU0_P1_TX_BUF_DP<6>")
	)
	(segment
		(start 343.918794 -397.849344)
		(end 343.803986 -397.734536)
		(width 0.14224)
		(layer "In6.Cu")
		(net "P5E_CPU0_P1_TX_BUF_DP<6>")
	)
	(segment
		(start 324.277736 -412.35376)
		(end 324.277736 -415.09569)
		(width 0.14224)
		(layer "In6.Cu")
		(net "P5E_CPU0_P1_TX_BUF_DP<6>")
	)
	(segment
		(start 326.666352 -410.950156)
		(end 326.580754 -411.1244)
		(width 0.14224)
		(layer "In6.Cu")
		(net "P5E_CPU0_P1_TX_BUF_DP<6>")
	)
	(segment
		(start 342.77808 -403.552406)
		(end 340.6013 -405.729186)
		(width 0.14224)
		(layer "In6.Cu")
		(net "P5E_CPU0_P1_TX_BUF_DP<6>")
	)
	(segment
		(start 343.092786 -400.1135)
		(end 343.092786 -402.792692)
		(width 0.14224)
		(layer "In6.Cu")
		(net "P5E_CPU0_P1_TX_BUF_DP<6>")
	)
	(segment
		(start 343.610438 -398.104106)
		(end 343.719658 -398.213326)
		(width 0.14224)
		(layer "In6.Cu")
		(net "P5E_CPU0_P1_TX_BUF_DP<6>")
	)
	(segment
		(start 326.002396 -411.175962)
		(end 325.598536 -411.313122)
		(width 0.14224)
		(layer "In6.Cu")
		(net "P5E_CPU0_P1_TX_BUF_DP<6>")
	)
	(segment
		(start 326.580754 -411.1244)
		(end 326.176386 -411.26156)
		(width 0.14224)
		(layer "In6.Cu")
		(net "P5E_CPU0_P1_TX_BUF_DP<6>")
	)
	(segment
		(start 324.277736 -415.09569)
		(end 324.568566 -415.38652)
		(width 0.14224)
		(layer "In6.Cu")
		(net "P5E_CPU0_P1_TX_BUF_DP<6>")
	)
	(segment
		(start 325.512938 -411.487366)
		(end 325.10857 -411.624526)
		(width 0.14224)
		(layer "In6.Cu")
		(net "P5E_CPU0_P1_TX_BUF_DP<6>")
	)
	(segment
		(start 327.64857 -410.761434)
		(end 327.244202 -410.898594)
		(width 0.14224)
		(layer "In6.Cu")
		(net "P5E_CPU0_P1_TX_BUF_DP<6>")
	)
	(segment
		(start 324.93458 -411.538928)
		(end 324.597014 -411.653482)
		(width 0.14224)
		(layer "In6.Cu")
		(net "P5E_CPU0_P1_TX_BUF_DP<6>")
	)
	(segment
		(start 325.598536 -411.313122)
		(end 325.512938 -411.487366)
		(width 0.14224)
		(layer "In6.Cu")
		(net "P5E_CPU0_P1_TX_BUF_DP<6>")
	)
	(segment
		(start 327.070212 -410.812996)
		(end 326.666352 -410.950156)
		(width 0.14224)
		(layer "In6.Cu")
		(net "P5E_CPU0_P1_TX_BUF_DP<6>")
	)
	(segment
		(start 343.534492 -397.823944)
		(end 343.534492 -397.920972)
		(width 0.14224)
		(layer "In6.Cu")
		(net "P5E_CPU0_P1_TX_BUF_DP<6>")
	)
	(segment
		(start 327.244202 -410.898594)
		(end 327.070212 -410.812996)
		(width 0.14224)
		(layer "In6.Cu")
		(net "P5E_CPU0_P1_TX_BUF_DP<6>")
	)
	(segment
		(start 343.794588 -398.959578)
		(end 343.150444 -399.923254)
		(width 0.14224)
		(layer "In6.Cu")
		(net "P5E_CPU0_P1_TX_BUF_DP<6>")
	)
	(arc
		(start 343.884504 -398.727422)
		(mid 343.852327 -398.84845)
		(end 343.794588 -398.959578)
		(width 0.14224)
		(layer "In6.Cu")
		(net "P5E_CPU0_P1_TX_BUF_DP<6>")
	)
	(arc
		(start 324.494398 -411.727904)
		(mid 324.337572 -412.02404)
		(end 324.277736 -412.35376)
		(width 0.14224)
		(layer "In6.Cu")
		(net "P5E_CPU0_P1_TX_BUF_DP<6>")
	)
	(arc
		(start 343.092786 -402.792692)
		(mid 343.011001 -403.203855)
		(end 342.77808 -403.552406)
		(width 0.14224)
		(layer "In6.Cu")
		(net "P5E_CPU0_P1_TX_BUF_DP<6>")
	)
	(arc
		(start 343.85377 -398.422622)
		(mid 343.888281 -398.573092)
		(end 343.884504 -398.727422)
		(width 0.14224)
		(layer "In6.Cu")
		(net "P5E_CPU0_P1_TX_BUF_DP<6>")
	)
	(arc
		(start 343.534492 -397.920972)
		(mid 343.554228 -398.020103)
		(end 343.610438 -398.104106)
		(width 0.14224)
		(layer "In6.Cu")
		(net "P5E_CPU0_P1_TX_BUF_DP<6>")
	)
	(arc
		(start 324.597014 -411.653482)
		(mid 324.540072 -411.682921)
		(end 324.494398 -411.727904)
		(width 0.14224)
		(layer "In6.Cu")
		(net "P5E_CPU0_P1_TX_BUF_DP<6>")
	)
	(arc
		(start 343.150444 -399.923254)
		(mid 343.107511 -400.014103)
		(end 343.092786 -400.1135)
		(width 0.14224)
		(layer "In6.Cu")
		(net "P5E_CPU0_P1_TX_BUF_DP<6>")
	)
	(arc
		(start 343.719658 -398.213326)
		(mid 343.798171 -398.310633)
		(end 343.85377 -398.422622)
		(width 0.14224)
		(layer "In6.Cu")
		(net "P5E_CPU0_P1_TX_BUF_DP<6>")
	)
	(arc
		(start 340.6013 -405.729186)
		(mid 340.422148 -405.876211)
		(end 340.21776 -405.985472)
		(width 0.14224)
		(layer "In6.Cu")
		(net "P5E_CPU0_P1_TX_BUF_DP<6>")
	)
	(segment
		(start 342.198198 -397.849344)
		(end 342.718898 -397.849344)
		(width 0.127)
		(layer "F.Cu")
		(net "P5E_CPU0_P1_TX_BUF_DP<5>")
	)
	(segment
		(start 321.530726 -416.632644)
		(end 321.234816 -416.336734)
		(width 0.12954)
		(layer "B.Cu")
		(net "P5E_CPU0_P1_TX_BUF_DP<5>")
	)
	(segment
		(start 321.234816 -416.336734)
		(end 321.234816 -415.65703)
		(width 0.12954)
		(layer "B.Cu")
		(net "P5E_CPU0_P1_TX_BUF_DP<5>")
	)
	(segment
		(start 321.234816 -415.65703)
		(end 321.505326 -415.38652)
		(width 0.12954)
		(layer "B.Cu")
		(net "P5E_CPU0_P1_TX_BUF_DP<5>")
	)
	(segment
		(start 342.334596 -397.869918)
		(end 342.334596 -397.956278)
		(width 0.14224)
		(layer "In6.Cu")
		(net "P5E_CPU0_P1_TX_BUF_DP<5>")
	)
	(segment
		(start 342.371934 -398.046194)
		(end 342.408002 -398.082262)
		(width 0.14224)
		(layer "In6.Cu")
		(net "P5E_CPU0_P1_TX_BUF_DP<5>")
	)
	(segment
		(start 341.896446 -400.104864)
		(end 341.896446 -402.793708)
		(width 0.14224)
		(layer "In6.Cu")
		(net "P5E_CPU0_P1_TX_BUF_DP<5>")
	)
	(segment
		(start 341.715852 -403.229826)
		(end 339.882988 -405.06269)
		(width 0.14224)
		(layer "In6.Cu")
		(net "P5E_CPU0_P1_TX_BUF_DP<5>")
	)
	(segment
		(start 342.469978 -397.734536)
		(end 342.334596 -397.869918)
		(width 0.14224)
		(layer "In6.Cu")
		(net "P5E_CPU0_P1_TX_BUF_DP<5>")
	)
	(segment
		(start 337.589876 -406.064466)
		(end 337.057238 -406.230328)
		(width 0.14224)
		(layer "In6.Cu")
		(net "P5E_CPU0_P1_TX_BUF_DP<5>")
	)
	(segment
		(start 342.60409 -397.734536)
		(end 342.469978 -397.734536)
		(width 0.14224)
		(layer "In6.Cu")
		(net "P5E_CPU0_P1_TX_BUF_DP<5>")
	)
	(segment
		(start 342.718898 -397.849344)
		(end 342.60409 -397.734536)
		(width 0.14224)
		(layer "In6.Cu")
		(net "P5E_CPU0_P1_TX_BUF_DP<5>")
	)
	(segment
		(start 324.588632 -410.513784)
		(end 324.168516 -410.64688)
		(width 0.14224)
		(layer "In6.Cu")
		(net "P5E_CPU0_P1_TX_BUF_DP<5>")
	)
	(segment
		(start 342.637364 -398.895062)
		(end 342.377522 -399.380202)
		(width 0.14224)
		(layer "In6.Cu")
		(net "P5E_CPU0_P1_TX_BUF_DP<5>")
	)
	(segment
		(start 324.168516 -410.64688)
		(end 324.075298 -410.826712)
		(width 0.14224)
		(layer "In6.Cu")
		(net "P5E_CPU0_P1_TX_BUF_DP<5>")
	)
	(segment
		(start 325.242428 -410.311346)
		(end 325.159878 -410.470096)
		(width 0.14224)
		(layer "In6.Cu")
		(net "P5E_CPU0_P1_TX_BUF_DP<5>")
	)
	(segment
		(start 321.214496 -415.09569)
		(end 321.505326 -415.38652)
		(width 0.14224)
		(layer "In6.Cu")
		(net "P5E_CPU0_P1_TX_BUF_DP<5>")
	)
	(segment
		(start 342.253062 -399.547842)
		(end 342.038178 -399.762726)
		(width 0.14224)
		(layer "In6.Cu")
		(net "P5E_CPU0_P1_TX_BUF_DP<5>")
	)
	(segment
		(start 337.590892 -406.063958)
		(end 337.589876 -406.064466)
		(width 0.14224)
		(layer "In6.Cu")
		(net "P5E_CPU0_P1_TX_BUF_DP<5>")
	)
	(segment
		(start 323.489066 -410.862526)
		(end 323.070728 -410.995114)
		(width 0.14224)
		(layer "In6.Cu")
		(net "P5E_CPU0_P1_TX_BUF_DP<5>")
	)
	(segment
		(start 333.81315 -407.282904)
		(end 331.109828 -408.373072)
		(width 0.14224)
		(layer "In6.Cu")
		(net "P5E_CPU0_P1_TX_BUF_DP<5>")
	)
	(segment
		(start 324.75297 -410.598874)
		(end 324.588632 -410.513784)
		(width 0.14224)
		(layer "In6.Cu")
		(net "P5E_CPU0_P1_TX_BUF_DP<5>")
	)
	(segment
		(start 322.40093 -411.206696)
		(end 322.369688 -411.216602)
		(width 0.14224)
		(layer "In6.Cu")
		(net "P5E_CPU0_P1_TX_BUF_DP<5>")
	)
	(segment
		(start 322.401438 -411.20695)
		(end 322.40093 -411.206696)
		(width 0.14224)
		(layer "In6.Cu")
		(net "P5E_CPU0_P1_TX_BUF_DP<5>")
	)
	(segment
		(start 327.685146 -409.5369)
		(end 325.242428 -410.311346)
		(width 0.14224)
		(layer "In6.Cu")
		(net "P5E_CPU0_P1_TX_BUF_DP<5>")
	)
	(segment
		(start 321.214496 -412.529528)
		(end 321.214496 -415.09569)
		(width 0.14224)
		(layer "In6.Cu")
		(net "P5E_CPU0_P1_TX_BUF_DP<5>")
	)
	(segment
		(start 325.159878 -410.470096)
		(end 324.75297 -410.598874)
		(width 0.14224)
		(layer "In6.Cu")
		(net "P5E_CPU0_P1_TX_BUF_DP<5>")
	)
	(segment
		(start 322.98132 -411.16758)
		(end 322.574412 -411.296358)
		(width 0.14224)
		(layer "In6.Cu")
		(net "P5E_CPU0_P1_TX_BUF_DP<5>")
	)
	(segment
		(start 323.66839 -410.95549)
		(end 323.489066 -410.862526)
		(width 0.14224)
		(layer "In6.Cu")
		(net "P5E_CPU0_P1_TX_BUF_DP<5>")
	)
	(segment
		(start 322.574412 -411.296358)
		(end 322.4022 -411.207204)
		(width 0.14224)
		(layer "In6.Cu")
		(net "P5E_CPU0_P1_TX_BUF_DP<5>")
	)
	(segment
		(start 324.075298 -410.826712)
		(end 323.66839 -410.95549)
		(width 0.14224)
		(layer "In6.Cu")
		(net "P5E_CPU0_P1_TX_BUF_DP<5>")
	)
	(segment
		(start 336.766154 -406.35047)
		(end 334.503776 -407.039064)
		(width 0.14224)
		(layer "In6.Cu")
		(net "P5E_CPU0_P1_TX_BUF_DP<5>")
	)
	(segment
		(start 337.057238 -406.230328)
		(end 336.766154 -406.35047)
		(width 0.14224)
		(layer "In6.Cu")
		(net "P5E_CPU0_P1_TX_BUF_DP<5>")
	)
	(segment
		(start 323.070728 -410.995114)
		(end 322.98132 -411.16758)
		(width 0.14224)
		(layer "In6.Cu")
		(net "P5E_CPU0_P1_TX_BUF_DP<5>")
	)
	(segment
		(start 339.678264 -405.199596)
		(end 337.590892 -406.063958)
		(width 0.14224)
		(layer "In6.Cu")
		(net "P5E_CPU0_P1_TX_BUF_DP<5>")
	)
	(segment
		(start 321.646804 -411.656276)
		(end 321.526408 -411.776672)
		(width 0.14224)
		(layer "In6.Cu")
		(net "P5E_CPU0_P1_TX_BUF_DP<5>")
	)
	(segment
		(start 331.109828 -408.373072)
		(end 327.685146 -409.5369)
		(width 0.14224)
		(layer "In6.Cu")
		(net "P5E_CPU0_P1_TX_BUF_DP<5>")
	)
	(segment
		(start 322.4022 -411.207204)
		(end 322.401438 -411.20695)
		(width 0.14224)
		(layer "In6.Cu")
		(net "P5E_CPU0_P1_TX_BUF_DP<5>")
	)
	(arc
		(start 322.369688 -411.216602)
		(mid 321.981876 -411.393077)
		(end 321.646804 -411.656276)
		(width 0.14224)
		(layer "In6.Cu")
		(net "P5E_CPU0_P1_TX_BUF_DP<5>")
	)
	(arc
		(start 342.408002 -398.082262)
		(mid 342.539286 -398.236783)
		(end 342.643968 -398.41043)
		(width 0.14224)
		(layer "In6.Cu")
		(net "P5E_CPU0_P1_TX_BUF_DP<5>")
	)
	(arc
		(start 321.526408 -411.776672)
		(mid 321.295557 -412.122071)
		(end 321.214496 -412.529528)
		(width 0.14224)
		(layer "In6.Cu")
		(net "P5E_CPU0_P1_TX_BUF_DP<5>")
	)
	(arc
		(start 342.038178 -399.762726)
		(mid 341.933291 -399.9197)
		(end 341.896446 -400.104864)
		(width 0.14224)
		(layer "In6.Cu")
		(net "P5E_CPU0_P1_TX_BUF_DP<5>")
	)
	(arc
		(start 342.334596 -397.956278)
		(mid 342.344298 -398.004962)
		(end 342.371934 -398.046194)
		(width 0.14224)
		(layer "In6.Cu")
		(net "P5E_CPU0_P1_TX_BUF_DP<5>")
	)
	(arc
		(start 341.896446 -402.793708)
		(mid 341.849517 -403.029728)
		(end 341.715852 -403.229826)
		(width 0.14224)
		(layer "In6.Cu")
		(net "P5E_CPU0_P1_TX_BUF_DP<5>")
	)
	(arc
		(start 339.882988 -405.06269)
		(mid 339.78736 -405.141209)
		(end 339.678264 -405.199596)
		(width 0.14224)
		(layer "In6.Cu")
		(net "P5E_CPU0_P1_TX_BUF_DP<5>")
	)
	(arc
		(start 334.503776 -407.039064)
		(mid 334.155772 -407.153361)
		(end 333.81315 -407.282904)
		(width 0.14224)
		(layer "In6.Cu")
		(net "P5E_CPU0_P1_TX_BUF_DP<5>")
	)
	(arc
		(start 342.643968 -398.41043)
		(mid 342.69957 -398.653553)
		(end 342.637364 -398.895062)
		(width 0.14224)
		(layer "In6.Cu")
		(net "P5E_CPU0_P1_TX_BUF_DP<5>")
	)
	(arc
		(start 342.377522 -399.380202)
		(mid 342.321469 -399.468608)
		(end 342.253062 -399.547842)
		(width 0.14224)
		(layer "In6.Cu")
		(net "P5E_CPU0_P1_TX_BUF_DP<5>")
	)
	(segment
		(start 340.998048 -397.849344)
		(end 341.518748 -397.849344)
		(width 0.127)
		(layer "F.Cu")
		(net "P5E_CPU0_P1_TX_BUF_DP<4>")
	)
	(segment
		(start 318.467486 -416.632644)
		(end 318.171576 -416.336734)
		(width 0.12954)
		(layer "B.Cu")
		(net "P5E_CPU0_P1_TX_BUF_DP<4>")
	)
	(segment
		(start 318.171576 -415.65703)
		(end 318.442086 -415.38652)
		(width 0.12954)
		(layer "B.Cu")
		(net "P5E_CPU0_P1_TX_BUF_DP<4>")
	)
	(segment
		(start 318.171576 -416.336734)
		(end 318.171576 -415.65703)
		(width 0.12954)
		(layer "B.Cu")
		(net "P5E_CPU0_P1_TX_BUF_DP<4>")
	)
	(segment
		(start 340.717378 -400.164554)
		(end 340.717378 -402.630894)
		(width 0.14224)
		(layer "In6.Cu")
		(net "P5E_CPU0_P1_TX_BUF_DP<4>")
	)
	(segment
		(start 320.550794 -410.86786)
		(end 320.144902 -410.999686)
		(width 0.14224)
		(layer "In6.Cu")
		(net "P5E_CPU0_P1_TX_BUF_DP<4>")
	)
	(segment
		(start 319.478152 -411.216856)
		(end 319.07226 -411.348682)
		(width 0.14224)
		(layer "In6.Cu")
		(net "P5E_CPU0_P1_TX_BUF_DP<4>")
	)
	(segment
		(start 334.786224 -405.978106)
		(end 333.84744 -406.263856)
		(width 0.14224)
		(layer "In6.Cu")
		(net "P5E_CPU0_P1_TX_BUF_DP<4>")
	)
	(segment
		(start 335.550002 -405.70912)
		(end 335.356962 -405.767286)
		(width 0.14224)
		(layer "In6.Cu")
		(net "P5E_CPU0_P1_TX_BUF_DP<4>")
	)
	(segment
		(start 319.971928 -410.911802)
		(end 319.56629 -411.043628)
		(width 0.14224)
		(layer "In6.Cu")
		(net "P5E_CPU0_P1_TX_BUF_DP<4>")
	)
	(segment
		(start 337.274154 -405.18588)
		(end 335.550002 -405.70912)
		(width 0.14224)
		(layer "In6.Cu")
		(net "P5E_CPU0_P1_TX_BUF_DP<4>")
	)
	(segment
		(start 318.899286 -411.260798)
		(end 318.628268 -411.348682)
		(width 0.14224)
		(layer "In6.Cu")
		(net "P5E_CPU0_P1_TX_BUF_DP<4>")
	)
	(segment
		(start 341.485982 -398.563592)
		(end 341.485982 -398.812004)
		(width 0.14224)
		(layer "In6.Cu")
		(net "P5E_CPU0_P1_TX_BUF_DP<4>")
	)
	(segment
		(start 341.134446 -397.823944)
		(end 341.134446 -397.890746)
		(width 0.14224)
		(layer "In6.Cu")
		(net "P5E_CPU0_P1_TX_BUF_DP<4>")
	)
	(segment
		(start 341.40394 -397.734536)
		(end 341.223854 -397.734536)
		(width 0.14224)
		(layer "In6.Cu")
		(net "P5E_CPU0_P1_TX_BUF_DP<4>")
	)
	(segment
		(start 341.223854 -397.734536)
		(end 341.134446 -397.823944)
		(width 0.14224)
		(layer "In6.Cu")
		(net "P5E_CPU0_P1_TX_BUF_DP<4>")
	)
	(segment
		(start 320.144902 -410.999686)
		(end 319.971928 -410.911802)
		(width 0.14224)
		(layer "In6.Cu")
		(net "P5E_CPU0_P1_TX_BUF_DP<4>")
	)
	(segment
		(start 321.623436 -410.518864)
		(end 321.217544 -410.650944)
		(width 0.14224)
		(layer "In6.Cu")
		(net "P5E_CPU0_P1_TX_BUF_DP<4>")
	)
	(segment
		(start 333.84744 -406.263856)
		(end 331.95006 -407.01722)
		(width 0.14224)
		(layer "In6.Cu")
		(net "P5E_CPU0_P1_TX_BUF_DP<4>")
	)
	(segment
		(start 319.07226 -411.348682)
		(end 318.899286 -411.260798)
		(width 0.14224)
		(layer "In6.Cu")
		(net "P5E_CPU0_P1_TX_BUF_DP<4>")
	)
	(segment
		(start 321.217544 -410.650944)
		(end 321.04457 -410.562806)
		(width 0.14224)
		(layer "In6.Cu")
		(net "P5E_CPU0_P1_TX_BUF_DP<4>")
	)
	(segment
		(start 338.904072 -404.510748)
		(end 337.274154 -405.18588)
		(width 0.14224)
		(layer "In6.Cu")
		(net "P5E_CPU0_P1_TX_BUF_DP<4>")
	)
	(segment
		(start 319.56629 -411.043628)
		(end 319.478152 -411.216856)
		(width 0.14224)
		(layer "In6.Cu")
		(net "P5E_CPU0_P1_TX_BUF_DP<4>")
	)
	(segment
		(start 341.518748 -397.849344)
		(end 341.40394 -397.734536)
		(width 0.14224)
		(layer "In6.Cu")
		(net "P5E_CPU0_P1_TX_BUF_DP<4>")
	)
	(segment
		(start 335.356962 -405.767286)
		(end 334.786224 -405.978106)
		(width 0.14224)
		(layer "In6.Cu")
		(net "P5E_CPU0_P1_TX_BUF_DP<4>")
	)
	(segment
		(start 320.638932 -410.694632)
		(end 320.550794 -410.86786)
		(width 0.14224)
		(layer "In6.Cu")
		(net "P5E_CPU0_P1_TX_BUF_DP<4>")
	)
	(segment
		(start 318.151256 -412.12643)
		(end 318.151256 -415.09569)
		(width 0.14224)
		(layer "In6.Cu")
		(net "P5E_CPU0_P1_TX_BUF_DP<4>")
	)
	(segment
		(start 341.231728 -398.125442)
		(end 341.356188 -398.249902)
		(width 0.14224)
		(layer "In6.Cu")
		(net "P5E_CPU0_P1_TX_BUF_DP<4>")
	)
	(segment
		(start 341.356188 -399.12544)
		(end 341.000588 -399.48104)
		(width 0.14224)
		(layer "In6.Cu")
		(net "P5E_CPU0_P1_TX_BUF_DP<4>")
	)
	(segment
		(start 318.151256 -415.09569)
		(end 318.442086 -415.38652)
		(width 0.14224)
		(layer "In6.Cu")
		(net "P5E_CPU0_P1_TX_BUF_DP<4>")
	)
	(segment
		(start 340.554056 -403.025102)
		(end 339.399372 -404.179786)
		(width 0.14224)
		(layer "In6.Cu")
		(net "P5E_CPU0_P1_TX_BUF_DP<4>")
	)
	(segment
		(start 331.95006 -407.01722)
		(end 321.711066 -410.346652)
		(width 0.14224)
		(layer "In6.Cu")
		(net "P5E_CPU0_P1_TX_BUF_DP<4>")
	)
	(segment
		(start 321.711066 -410.346652)
		(end 321.623436 -410.518864)
		(width 0.14224)
		(layer "In6.Cu")
		(net "P5E_CPU0_P1_TX_BUF_DP<4>")
	)
	(segment
		(start 321.04457 -410.562806)
		(end 320.638932 -410.694632)
		(width 0.14224)
		(layer "In6.Cu")
		(net "P5E_CPU0_P1_TX_BUF_DP<4>")
	)
	(arc
		(start 341.356188 -398.249902)
		(mid 341.452324 -398.393825)
		(end 341.485982 -398.563592)
		(width 0.14224)
		(layer "In6.Cu")
		(net "P5E_CPU0_P1_TX_BUF_DP<4>")
	)
	(arc
		(start 339.399372 -404.179786)
		(mid 339.168017 -404.369652)
		(end 338.904072 -404.510748)
		(width 0.14224)
		(layer "In6.Cu")
		(net "P5E_CPU0_P1_TX_BUF_DP<4>")
	)
	(arc
		(start 341.485982 -398.812004)
		(mid 341.452243 -398.981621)
		(end 341.356188 -399.12544)
		(width 0.14224)
		(layer "In6.Cu")
		(net "P5E_CPU0_P1_TX_BUF_DP<4>")
	)
	(arc
		(start 318.359536 -411.534356)
		(mid 318.204838 -411.812609)
		(end 318.151256 -412.12643)
		(width 0.14224)
		(layer "In6.Cu")
		(net "P5E_CPU0_P1_TX_BUF_DP<4>")
	)
	(arc
		(start 341.000588 -399.48104)
		(mid 340.790994 -399.794625)
		(end 340.717378 -400.164554)
		(width 0.14224)
		(layer "In6.Cu")
		(net "P5E_CPU0_P1_TX_BUF_DP<4>")
	)
	(arc
		(start 318.628268 -411.348682)
		(mid 318.480338 -411.421887)
		(end 318.359536 -411.534356)
		(width 0.14224)
		(layer "In6.Cu")
		(net "P5E_CPU0_P1_TX_BUF_DP<4>")
	)
	(arc
		(start 340.717378 -402.630894)
		(mid 340.674939 -402.844251)
		(end 340.554056 -403.025102)
		(width 0.14224)
		(layer "In6.Cu")
		(net "P5E_CPU0_P1_TX_BUF_DP<4>")
	)
	(arc
		(start 341.134446 -397.890746)
		(mid 341.159731 -398.017774)
		(end 341.231728 -398.125442)
		(width 0.14224)
		(layer "In6.Cu")
		(net "P5E_CPU0_P1_TX_BUF_DP<4>")
	)
	(segment
		(start 339.798152 -397.849344)
		(end 340.318852 -397.849344)
		(width 0.127)
		(layer "F.Cu")
		(net "P5E_CPU0_P1_TX_BUF_DP<3>")
	)
	(segment
		(start 315.108336 -416.336734)
		(end 315.108336 -415.65703)
		(width 0.12954)
		(layer "B.Cu")
		(net "P5E_CPU0_P1_TX_BUF_DP<3>")
	)
	(segment
		(start 315.404246 -416.632644)
		(end 315.108336 -416.336734)
		(width 0.12954)
		(layer "B.Cu")
		(net "P5E_CPU0_P1_TX_BUF_DP<3>")
	)
	(segment
		(start 315.108336 -415.65703)
		(end 315.378846 -415.38652)
		(width 0.12954)
		(layer "B.Cu")
		(net "P5E_CPU0_P1_TX_BUF_DP<3>")
	)
	(segment
		(start 316.128908 -411.262322)
		(end 315.754004 -411.465522)
		(width 0.14224)
		(layer "In6.Cu")
		(net "P5E_CPU0_P1_TX_BUF_DP<3>")
	)
	(segment
		(start 321.459098 -409.296108)
		(end 321.374008 -409.454858)
		(width 0.14224)
		(layer "In6.Cu")
		(net "P5E_CPU0_P1_TX_BUF_DP<3>")
	)
	(segment
		(start 338.421472 -403.700742)
		(end 337.20151 -404.20671)
		(width 0.14224)
		(layer "In6.Cu")
		(net "P5E_CPU0_P1_TX_BUF_DP<3>")
	)
	(segment
		(start 319.87109 -409.913836)
		(end 319.708276 -409.826714)
		(width 0.14224)
		(layer "In6.Cu")
		(net "P5E_CPU0_P1_TX_BUF_DP<3>")
	)
	(segment
		(start 315.754004 -411.465522)
		(end 315.395356 -411.82417)
		(width 0.14224)
		(layer "In6.Cu")
		(net "P5E_CPU0_P1_TX_BUF_DP<3>")
	)
	(segment
		(start 340.29523 -398.558258)
		(end 340.29523 -398.60093)
		(width 0.14224)
		(layer "In6.Cu")
		(net "P5E_CPU0_P1_TX_BUF_DP<3>")
	)
	(segment
		(start 318.628776 -410.153612)
		(end 317.935356 -410.363416)
		(width 0.14224)
		(layer "In6.Cu")
		(net "P5E_CPU0_P1_TX_BUF_DP<3>")
	)
	(segment
		(start 315.088016 -412.566104)
		(end 315.088016 -415.09569)
		(width 0.14224)
		(layer "In6.Cu")
		(net "P5E_CPU0_P1_TX_BUF_DP<3>")
	)
	(segment
		(start 316.300866 -411.313376)
		(end 316.128908 -411.262322)
		(width 0.14224)
		(layer "In6.Cu")
		(net "P5E_CPU0_P1_TX_BUF_DP<3>")
	)
	(segment
		(start 339.880448 -399.416016)
		(end 339.687154 -399.60931)
		(width 0.14224)
		(layer "In6.Cu")
		(net "P5E_CPU0_P1_TX_BUF_DP<3>")
	)
	(segment
		(start 340.318852 -397.849344)
		(end 340.204044 -397.734536)
		(width 0.14224)
		(layer "In6.Cu")
		(net "P5E_CPU0_P1_TX_BUF_DP<3>")
	)
	(segment
		(start 316.745366 -410.927804)
		(end 316.694312 -411.100016)
		(width 0.14224)
		(layer "In6.Cu")
		(net "P5E_CPU0_P1_TX_BUF_DP<3>")
	)
	(segment
		(start 320.292222 -409.786328)
		(end 319.87109 -409.913836)
		(width 0.14224)
		(layer "In6.Cu")
		(net "P5E_CPU0_P1_TX_BUF_DP<3>")
	)
	(segment
		(start 320.787776 -409.499562)
		(end 320.379598 -409.623006)
		(width 0.14224)
		(layer "In6.Cu")
		(net "P5E_CPU0_P1_TX_BUF_DP<3>")
	)
	(segment
		(start 318.79032 -410.239972)
		(end 318.628776 -410.153612)
		(width 0.14224)
		(layer "In6.Cu")
		(net "P5E_CPU0_P1_TX_BUF_DP<3>")
	)
	(segment
		(start 320.379598 -409.623006)
		(end 320.292222 -409.786328)
		(width 0.14224)
		(layer "In6.Cu")
		(net "P5E_CPU0_P1_TX_BUF_DP<3>")
	)
	(segment
		(start 317.285878 -410.634688)
		(end 316.745366 -410.927804)
		(width 0.14224)
		(layer "In6.Cu")
		(net "P5E_CPU0_P1_TX_BUF_DP<3>")
	)
	(segment
		(start 319.300098 -409.950158)
		(end 319.213484 -410.11221)
		(width 0.14224)
		(layer "In6.Cu")
		(net "P5E_CPU0_P1_TX_BUF_DP<3>")
	)
	(segment
		(start 334.08874 -405.156924)
		(end 332.911196 -405.624538)
		(width 0.14224)
		(layer "In6.Cu")
		(net "P5E_CPU0_P1_TX_BUF_DP<3>")
	)
	(segment
		(start 339.93455 -397.823944)
		(end 339.93455 -397.974058)
		(width 0.14224)
		(layer "In6.Cu")
		(net "P5E_CPU0_P1_TX_BUF_DP<3>")
	)
	(segment
		(start 326.18172 -407.86558)
		(end 321.459098 -409.296108)
		(width 0.14224)
		(layer "In6.Cu")
		(net "P5E_CPU0_P1_TX_BUF_DP<3>")
	)
	(segment
		(start 339.971888 -398.063974)
		(end 340.174326 -398.266412)
		(width 0.14224)
		(layer "In6.Cu")
		(net "P5E_CPU0_P1_TX_BUF_DP<3>")
	)
	(segment
		(start 321.374008 -409.454858)
		(end 320.946272 -409.584398)
		(width 0.14224)
		(layer "In6.Cu")
		(net "P5E_CPU0_P1_TX_BUF_DP<3>")
	)
	(segment
		(start 339.40115 -402.84019)
		(end 338.780628 -403.460712)
		(width 0.14224)
		(layer "In6.Cu")
		(net "P5E_CPU0_P1_TX_BUF_DP<3>")
	)
	(segment
		(start 340.023958 -397.734536)
		(end 339.93455 -397.823944)
		(width 0.14224)
		(layer "In6.Cu")
		(net "P5E_CPU0_P1_TX_BUF_DP<3>")
	)
	(segment
		(start 315.088016 -415.09569)
		(end 315.378846 -415.38652)
		(width 0.14224)
		(layer "In6.Cu")
		(net "P5E_CPU0_P1_TX_BUF_DP<3>")
	)
	(segment
		(start 319.708276 -409.826714)
		(end 319.300098 -409.950158)
		(width 0.14224)
		(layer "In6.Cu")
		(net "P5E_CPU0_P1_TX_BUF_DP<3>")
	)
	(segment
		(start 320.946272 -409.584398)
		(end 320.787776 -409.499562)
		(width 0.14224)
		(layer "In6.Cu")
		(net "P5E_CPU0_P1_TX_BUF_DP<3>")
	)
	(segment
		(start 337.20151 -404.20671)
		(end 334.08874 -405.156924)
		(width 0.14224)
		(layer "In6.Cu")
		(net "P5E_CPU0_P1_TX_BUF_DP<3>")
	)
	(segment
		(start 332.911196 -405.624538)
		(end 326.18172 -407.86558)
		(width 0.14224)
		(layer "In6.Cu")
		(net "P5E_CPU0_P1_TX_BUF_DP<3>")
	)
	(segment
		(start 319.213484 -410.11221)
		(end 318.79032 -410.239972)
		(width 0.14224)
		(layer "In6.Cu")
		(net "P5E_CPU0_P1_TX_BUF_DP<3>")
	)
	(segment
		(start 316.694312 -411.100016)
		(end 316.300866 -411.313376)
		(width 0.14224)
		(layer "In6.Cu")
		(net "P5E_CPU0_P1_TX_BUF_DP<3>")
	)
	(segment
		(start 317.935356 -410.363416)
		(end 317.285878 -410.634688)
		(width 0.14224)
		(layer "In6.Cu")
		(net "P5E_CPU0_P1_TX_BUF_DP<3>")
	)
	(segment
		(start 340.204044 -397.734536)
		(end 340.023958 -397.734536)
		(width 0.14224)
		(layer "In6.Cu")
		(net "P5E_CPU0_P1_TX_BUF_DP<3>")
	)
	(segment
		(start 339.521038 -400.010376)
		(end 339.521038 -402.550884)
		(width 0.14224)
		(layer "In6.Cu")
		(net "P5E_CPU0_P1_TX_BUF_DP<3>")
	)
	(arc
		(start 339.687154 -399.60931)
		(mid 339.564202 -399.793321)
		(end 339.521038 -400.010376)
		(width 0.14224)
		(layer "In6.Cu")
		(net "P5E_CPU0_P1_TX_BUF_DP<3>")
	)
	(arc
		(start 315.395356 -411.82417)
		(mid 315.167907 -412.164572)
		(end 315.088016 -412.566104)
		(width 0.14224)
		(layer "In6.Cu")
		(net "P5E_CPU0_P1_TX_BUF_DP<3>")
	)
	(arc
		(start 339.93455 -397.974058)
		(mid 339.944252 -398.022742)
		(end 339.971888 -398.063974)
		(width 0.14224)
		(layer "In6.Cu")
		(net "P5E_CPU0_P1_TX_BUF_DP<3>")
	)
	(arc
		(start 340.174326 -398.266412)
		(mid 340.263795 -398.400312)
		(end 340.29523 -398.558258)
		(width 0.14224)
		(layer "In6.Cu")
		(net "P5E_CPU0_P1_TX_BUF_DP<3>")
	)
	(arc
		(start 340.209378 -398.851628)
		(mid 340.165193 -398.920647)
		(end 340.13394 -398.996408)
		(width 0.14224)
		(layer "In6.Cu")
		(net "P5E_CPU0_P1_TX_BUF_DP<3>")
	)
	(arc
		(start 340.13394 -398.996408)
		(mid 340.032718 -399.221636)
		(end 339.880448 -399.416016)
		(width 0.14224)
		(layer "In6.Cu")
		(net "P5E_CPU0_P1_TX_BUF_DP<3>")
	)
	(arc
		(start 339.521038 -402.550884)
		(mid 339.489875 -402.707462)
		(end 339.40115 -402.84019)
		(width 0.14224)
		(layer "In6.Cu")
		(net "P5E_CPU0_P1_TX_BUF_DP<3>")
	)
	(arc
		(start 338.780628 -403.460712)
		(mid 338.612863 -403.598401)
		(end 338.421472 -403.700742)
		(width 0.14224)
		(layer "In6.Cu")
		(net "P5E_CPU0_P1_TX_BUF_DP<3>")
	)
	(arc
		(start 340.29523 -398.60093)
		(mid 340.273222 -398.733446)
		(end 340.209378 -398.851628)
		(width 0.14224)
		(layer "In6.Cu")
		(net "P5E_CPU0_P1_TX_BUF_DP<3>")
	)
	(segment
		(start 338.598002 -397.849344)
		(end 339.118702 -397.849344)
		(width 0.127)
		(layer "F.Cu")
		(net "P5E_CPU0_P1_TX_BUF_DP<2>")
	)
	(segment
		(start 312.341006 -416.632644)
		(end 312.045096 -416.336734)
		(width 0.12954)
		(layer "B.Cu")
		(net "P5E_CPU0_P1_TX_BUF_DP<2>")
	)
	(segment
		(start 312.045096 -415.65703)
		(end 312.315606 -415.38652)
		(width 0.12954)
		(layer "B.Cu")
		(net "P5E_CPU0_P1_TX_BUF_DP<2>")
	)
	(segment
		(start 312.045096 -416.336734)
		(end 312.045096 -415.65703)
		(width 0.12954)
		(layer "B.Cu")
		(net "P5E_CPU0_P1_TX_BUF_DP<2>")
	)
	(segment
		(start 314.274708 -410.644594)
		(end 314.18911 -410.819092)
		(width 0.14224)
		(layer "In6.Cu")
		(net "P5E_CPU0_P1_TX_BUF_DP<2>")
	)
	(segment
		(start 313.611006 -410.871416)
		(end 313.188858 -411.015434)
		(width 0.14224)
		(layer "In6.Cu")
		(net "P5E_CPU0_P1_TX_BUF_DP<2>")
	)
	(segment
		(start 317.061088 -409.69311)
		(end 316.409324 -409.915614)
		(width 0.14224)
		(layer "In6.Cu")
		(net "P5E_CPU0_P1_TX_BUF_DP<2>")
	)
	(segment
		(start 316.409324 -409.915614)
		(end 316.32398 -410.089858)
		(width 0.14224)
		(layer "In6.Cu")
		(net "P5E_CPU0_P1_TX_BUF_DP<2>")
	)
	(segment
		(start 313.784996 -410.957014)
		(end 313.611006 -410.871416)
		(width 0.14224)
		(layer "In6.Cu")
		(net "P5E_CPU0_P1_TX_BUF_DP<2>")
	)
	(segment
		(start 314.678314 -410.506926)
		(end 314.274708 -410.644594)
		(width 0.14224)
		(layer "In6.Cu")
		(net "P5E_CPU0_P1_TX_BUF_DP<2>")
	)
	(segment
		(start 314.18911 -410.819092)
		(end 313.784996 -410.957014)
		(width 0.14224)
		(layer "In6.Cu")
		(net "P5E_CPU0_P1_TX_BUF_DP<2>")
	)
	(segment
		(start 339.118702 -397.849344)
		(end 339.002878 -397.73352)
		(width 0.14224)
		(layer "In6.Cu")
		(net "P5E_CPU0_P1_TX_BUF_DP<2>")
	)
	(segment
		(start 338.814156 -398.107916)
		(end 338.888324 -398.18183)
		(width 0.14224)
		(layer "In6.Cu")
		(net "P5E_CPU0_P1_TX_BUF_DP<2>")
	)
	(segment
		(start 312.768996 -411.277054)
		(end 312.461402 -411.584902)
		(width 0.14224)
		(layer "In6.Cu")
		(net "P5E_CPU0_P1_TX_BUF_DP<2>")
	)
	(segment
		(start 331.47381 -405.120348)
		(end 325.745094 -407.023316)
		(width 0.14224)
		(layer "In6.Cu")
		(net "P5E_CPU0_P1_TX_BUF_DP<2>")
	)
	(segment
		(start 338.853018 -397.73352)
		(end 338.736178 -397.85036)
		(width 0.14224)
		(layer "In6.Cu")
		(net "P5E_CPU0_P1_TX_BUF_DP<2>")
	)
	(segment
		(start 339.008212 -398.47139)
		(end 339.008212 -398.677638)
		(width 0.14224)
		(layer "In6.Cu")
		(net "P5E_CPU0_P1_TX_BUF_DP<2>")
	)
	(segment
		(start 338.310982 -399.93951)
		(end 338.310982 -402.439124)
		(width 0.14224)
		(layer "In6.Cu")
		(net "P5E_CPU0_P1_TX_BUF_DP<2>")
	)
	(segment
		(start 315.919866 -410.22778)
		(end 315.745622 -410.142436)
		(width 0.14224)
		(layer "In6.Cu")
		(net "P5E_CPU0_P1_TX_BUF_DP<2>")
	)
	(segment
		(start 312.024776 -415.09569)
		(end 312.315606 -415.38652)
		(width 0.14224)
		(layer "In6.Cu")
		(net "P5E_CPU0_P1_TX_BUF_DP<2>")
	)
	(segment
		(start 315.745622 -410.142436)
		(end 315.342016 -410.280104)
		(width 0.14224)
		(layer "In6.Cu")
		(net "P5E_CPU0_P1_TX_BUF_DP<2>")
	)
	(segment
		(start 332.389988 -404.757636)
		(end 331.47381 -405.120348)
		(width 0.14224)
		(layer "In6.Cu")
		(net "P5E_CPU0_P1_TX_BUF_DP<2>")
	)
	(segment
		(start 314.852304 -410.592524)
		(end 314.678314 -410.506926)
		(width 0.14224)
		(layer "In6.Cu")
		(net "P5E_CPU0_P1_TX_BUF_DP<2>")
	)
	(segment
		(start 336.972148 -403.290278)
		(end 334.193642 -404.133812)
		(width 0.14224)
		(layer "In6.Cu")
		(net "P5E_CPU0_P1_TX_BUF_DP<2>")
	)
	(segment
		(start 338.779866 -399.228564)
		(end 338.414106 -399.594324)
		(width 0.14224)
		(layer "In6.Cu")
		(net "P5E_CPU0_P1_TX_BUF_DP<2>")
	)
	(segment
		(start 325.745094 -407.023316)
		(end 317.401702 -409.55087)
		(width 0.14224)
		(layer "In6.Cu")
		(net "P5E_CPU0_P1_TX_BUF_DP<2>")
	)
	(segment
		(start 338.017358 -402.858224)
		(end 336.972148 -403.290278)
		(width 0.14224)
		(layer "In6.Cu")
		(net "P5E_CPU0_P1_TX_BUF_DP<2>")
	)
	(segment
		(start 339.002878 -397.73352)
		(end 338.853018 -397.73352)
		(width 0.14224)
		(layer "In6.Cu")
		(net "P5E_CPU0_P1_TX_BUF_DP<2>")
	)
	(segment
		(start 315.256418 -410.454602)
		(end 314.852304 -410.592524)
		(width 0.14224)
		(layer "In6.Cu")
		(net "P5E_CPU0_P1_TX_BUF_DP<2>")
	)
	(segment
		(start 338.191094 -402.728684)
		(end 338.150454 -402.769324)
		(width 0.14224)
		(layer "In6.Cu")
		(net "P5E_CPU0_P1_TX_BUF_DP<2>")
	)
	(segment
		(start 315.342016 -410.280104)
		(end 315.256418 -410.454602)
		(width 0.14224)
		(layer "In6.Cu")
		(net "P5E_CPU0_P1_TX_BUF_DP<2>")
	)
	(segment
		(start 312.024776 -412.63951)
		(end 312.024776 -415.09569)
		(width 0.14224)
		(layer "In6.Cu")
		(net "P5E_CPU0_P1_TX_BUF_DP<2>")
	)
	(segment
		(start 317.401702 -409.55087)
		(end 317.061088 -409.69311)
		(width 0.14224)
		(layer "In6.Cu")
		(net "P5E_CPU0_P1_TX_BUF_DP<2>")
	)
	(segment
		(start 316.32398 -410.089858)
		(end 315.919866 -410.22778)
		(width 0.14224)
		(layer "In6.Cu")
		(net "P5E_CPU0_P1_TX_BUF_DP<2>")
	)
	(segment
		(start 334.193642 -404.133812)
		(end 332.389988 -404.757636)
		(width 0.14224)
		(layer "In6.Cu")
		(net "P5E_CPU0_P1_TX_BUF_DP<2>")
	)
	(segment
		(start 338.736178 -397.85036)
		(end 338.736178 -397.919956)
		(width 0.14224)
		(layer "In6.Cu")
		(net "P5E_CPU0_P1_TX_BUF_DP<2>")
	)
	(arc
		(start 313.188858 -411.015434)
		(mid 312.963899 -411.122129)
		(end 312.768996 -411.277054)
		(width 0.14224)
		(layer "In6.Cu")
		(net "P5E_CPU0_P1_TX_BUF_DP<2>")
	)
	(arc
		(start 338.150454 -402.769324)
		(mid 338.088285 -402.820327)
		(end 338.017358 -402.858224)
		(width 0.14224)
		(layer "In6.Cu")
		(net "P5E_CPU0_P1_TX_BUF_DP<2>")
	)
	(arc
		(start 339.008212 -398.677638)
		(mid 338.948863 -398.975824)
		(end 338.779866 -399.228564)
		(width 0.14224)
		(layer "In6.Cu")
		(net "P5E_CPU0_P1_TX_BUF_DP<2>")
	)
	(arc
		(start 338.310982 -402.439124)
		(mid 338.27983 -402.595827)
		(end 338.191094 -402.728684)
		(width 0.14224)
		(layer "In6.Cu")
		(net "P5E_CPU0_P1_TX_BUF_DP<2>")
	)
	(arc
		(start 338.888324 -398.18183)
		(mid 338.977117 -398.314668)
		(end 339.008212 -398.47139)
		(width 0.14224)
		(layer "In6.Cu")
		(net "P5E_CPU0_P1_TX_BUF_DP<2>")
	)
	(arc
		(start 338.736178 -397.919956)
		(mid 338.756451 -398.021698)
		(end 338.814156 -398.107916)
		(width 0.14224)
		(layer "In6.Cu")
		(net "P5E_CPU0_P1_TX_BUF_DP<2>")
	)
	(arc
		(start 312.461402 -411.584902)
		(mid 312.138284 -412.068816)
		(end 312.024776 -412.63951)
		(width 0.14224)
		(layer "In6.Cu")
		(net "P5E_CPU0_P1_TX_BUF_DP<2>")
	)
	(arc
		(start 338.347812 -399.702528)
		(mid 338.320185 -399.819588)
		(end 338.310982 -399.93951)
		(width 0.14224)
		(layer "In6.Cu")
		(net "P5E_CPU0_P1_TX_BUF_DP<2>")
	)
	(arc
		(start 338.414106 -399.594324)
		(mid 338.37448 -399.644456)
		(end 338.347812 -399.702528)
		(width 0.14224)
		(layer "In6.Cu")
		(net "P5E_CPU0_P1_TX_BUF_DP<2>")
	)
	(segment
		(start 337.398106 -397.849344)
		(end 337.918806 -397.849344)
		(width 0.127)
		(layer "F.Cu")
		(net "P5E_CPU0_P1_TX_BUF_DP<1>")
	)
	(segment
		(start 308.981856 -415.65703)
		(end 309.252366 -415.38652)
		(width 0.12954)
		(layer "B.Cu")
		(net "P5E_CPU0_P1_TX_BUF_DP<1>")
	)
	(segment
		(start 309.277766 -416.632644)
		(end 308.981856 -416.336734)
		(width 0.12954)
		(layer "B.Cu")
		(net "P5E_CPU0_P1_TX_BUF_DP<1>")
	)
	(segment
		(start 308.981856 -416.336734)
		(end 308.981856 -415.65703)
		(width 0.12954)
		(layer "B.Cu")
		(net "P5E_CPU0_P1_TX_BUF_DP<1>")
	)
	(segment
		(start 335.71434 -400.280378)
		(end 335.71434 -401.077684)
		(width 0.14224)
		(layer "In6.Cu")
		(net "P5E_CPU0_P1_TX_BUF_DP<1>")
	)
	(segment
		(start 308.961536 -412.566104)
		(end 308.961536 -415.09569)
		(width 0.14224)
		(layer "In6.Cu")
		(net "P5E_CPU0_P1_TX_BUF_DP<1>")
	)
	(segment
		(start 337.581748 -398.065752)
		(end 337.73364 -398.217644)
		(width 0.14224)
		(layer "In6.Cu")
		(net "P5E_CPU0_P1_TX_BUF_DP<1>")
	)
	(segment
		(start 313.158886 -409.853892)
		(end 313.067446 -410.025088)
		(width 0.14224)
		(layer "In6.Cu")
		(net "P5E_CPU0_P1_TX_BUF_DP<1>")
	)
	(segment
		(start 332.47965 -403.738588)
		(end 327.753726 -405.170132)
		(width 0.14224)
		(layer "In6.Cu")
		(net "P5E_CPU0_P1_TX_BUF_DP<1>")
	)
	(segment
		(start 309.581296 -411.251908)
		(end 309.452772 -411.380432)
		(width 0.14224)
		(layer "In6.Cu")
		(net "P5E_CPU0_P1_TX_BUF_DP<1>")
	)
	(segment
		(start 336.687922 -399.667984)
		(end 336.127852 -399.667984)
		(width 0.14224)
		(layer "In6.Cu")
		(net "P5E_CPU0_P1_TX_BUF_DP<1>")
	)
	(segment
		(start 325.14286 -406.231344)
		(end 314.23864 -409.527502)
		(width 0.14224)
		(layer "In6.Cu")
		(net "P5E_CPU0_P1_TX_BUF_DP<1>")
	)
	(segment
		(start 337.918806 -397.849344)
		(end 337.803998 -397.734536)
		(width 0.14224)
		(layer "In6.Cu")
		(net "P5E_CPU0_P1_TX_BUF_DP<1>")
	)
	(segment
		(start 335.490312 -401.61845)
		(end 334.076802 -403.03196)
		(width 0.14224)
		(layer "In6.Cu")
		(net "P5E_CPU0_P1_TX_BUF_DP<1>")
	)
	(segment
		(start 311.40781 -410.383228)
		(end 310.648604 -410.612844)
		(width 0.14224)
		(layer "In6.Cu")
		(net "P5E_CPU0_P1_TX_BUF_DP<1>")
	)
	(segment
		(start 308.961536 -415.09569)
		(end 309.252366 -415.38652)
		(width 0.14224)
		(layer "In6.Cu")
		(net "P5E_CPU0_P1_TX_BUF_DP<1>")
	)
	(segment
		(start 312.487564 -410.056838)
		(end 312.079132 -410.180282)
		(width 0.14224)
		(layer "In6.Cu")
		(net "P5E_CPU0_P1_TX_BUF_DP<1>")
	)
	(segment
		(start 311.987692 -410.351478)
		(end 311.579006 -410.474922)
		(width 0.14224)
		(layer "In6.Cu")
		(net "P5E_CPU0_P1_TX_BUF_DP<1>")
	)
	(segment
		(start 311.579006 -410.474922)
		(end 311.40781 -410.383228)
		(width 0.14224)
		(layer "In6.Cu")
		(net "P5E_CPU0_P1_TX_BUF_DP<1>")
	)
	(segment
		(start 313.067446 -410.025088)
		(end 312.65876 -410.148532)
		(width 0.14224)
		(layer "In6.Cu")
		(net "P5E_CPU0_P1_TX_BUF_DP<1>")
	)
	(segment
		(start 312.079132 -410.180282)
		(end 311.987692 -410.351478)
		(width 0.14224)
		(layer "In6.Cu")
		(net "P5E_CPU0_P1_TX_BUF_DP<1>")
	)
	(segment
		(start 337.73364 -398.941036)
		(end 337.231736 -399.442686)
		(width 0.14224)
		(layer "In6.Cu")
		(net "P5E_CPU0_P1_TX_BUF_DP<1>")
	)
	(segment
		(start 337.534504 -397.823944)
		(end 337.534504 -397.951706)
		(width 0.14224)
		(layer "In6.Cu")
		(net "P5E_CPU0_P1_TX_BUF_DP<1>")
	)
	(segment
		(start 327.753726 -405.170132)
		(end 325.14286 -406.231344)
		(width 0.14224)
		(layer "In6.Cu")
		(net "P5E_CPU0_P1_TX_BUF_DP<1>")
	)
	(segment
		(start 337.803998 -397.734536)
		(end 337.623912 -397.734536)
		(width 0.14224)
		(layer "In6.Cu")
		(net "P5E_CPU0_P1_TX_BUF_DP<1>")
	)
	(segment
		(start 314.146946 -409.698698)
		(end 313.73826 -409.822142)
		(width 0.14224)
		(layer "In6.Cu")
		(net "P5E_CPU0_P1_TX_BUF_DP<1>")
	)
	(segment
		(start 313.567318 -409.730448)
		(end 313.158886 -409.853892)
		(width 0.14224)
		(layer "In6.Cu")
		(net "P5E_CPU0_P1_TX_BUF_DP<1>")
	)
	(segment
		(start 313.73826 -409.822142)
		(end 313.567318 -409.730448)
		(width 0.14224)
		(layer "In6.Cu")
		(net "P5E_CPU0_P1_TX_BUF_DP<1>")
	)
	(segment
		(start 312.65876 -410.148532)
		(end 312.487564 -410.056838)
		(width 0.14224)
		(layer "In6.Cu")
		(net "P5E_CPU0_P1_TX_BUF_DP<1>")
	)
	(segment
		(start 333.899764 -403.150324)
		(end 332.47965 -403.738588)
		(width 0.14224)
		(layer "In6.Cu")
		(net "P5E_CPU0_P1_TX_BUF_DP<1>")
	)
	(segment
		(start 314.23864 -409.527502)
		(end 314.146946 -409.698698)
		(width 0.14224)
		(layer "In6.Cu")
		(net "P5E_CPU0_P1_TX_BUF_DP<1>")
	)
	(segment
		(start 337.623912 -397.734536)
		(end 337.534504 -397.823944)
		(width 0.14224)
		(layer "In6.Cu")
		(net "P5E_CPU0_P1_TX_BUF_DP<1>")
	)
	(arc
		(start 309.452772 -411.380432)
		(mid 309.089181 -411.924394)
		(end 308.961536 -412.566104)
		(width 0.14224)
		(layer "In6.Cu")
		(net "P5E_CPU0_P1_TX_BUF_DP<1>")
	)
	(arc
		(start 337.231736 -399.442686)
		(mid 336.982246 -399.609453)
		(end 336.687922 -399.667984)
		(width 0.14224)
		(layer "In6.Cu")
		(net "P5E_CPU0_P1_TX_BUF_DP<1>")
	)
	(arc
		(start 334.076802 -403.03196)
		(mid 333.994115 -403.099866)
		(end 333.899764 -403.150324)
		(width 0.14224)
		(layer "In6.Cu")
		(net "P5E_CPU0_P1_TX_BUF_DP<1>")
	)
	(arc
		(start 336.127852 -399.667984)
		(mid 336.023418 -399.688681)
		(end 335.934812 -399.74774)
		(width 0.14224)
		(layer "In6.Cu")
		(net "P5E_CPU0_P1_TX_BUF_DP<1>")
	)
	(arc
		(start 310.648604 -410.612844)
		(mid 310.075474 -410.866444)
		(end 309.581296 -411.251908)
		(width 0.14224)
		(layer "In6.Cu")
		(net "P5E_CPU0_P1_TX_BUF_DP<1>")
	)
	(arc
		(start 335.934812 -399.74774)
		(mid 335.77153 -399.992104)
		(end 335.71434 -400.280378)
		(width 0.14224)
		(layer "In6.Cu")
		(net "P5E_CPU0_P1_TX_BUF_DP<1>")
	)
	(arc
		(start 337.73364 -398.217644)
		(mid 337.883534 -398.57934)
		(end 337.73364 -398.941036)
		(width 0.14224)
		(layer "In6.Cu")
		(net "P5E_CPU0_P1_TX_BUF_DP<1>")
	)
	(arc
		(start 335.71434 -401.077684)
		(mid 335.656124 -401.370358)
		(end 335.490312 -401.61845)
		(width 0.14224)
		(layer "In6.Cu")
		(net "P5E_CPU0_P1_TX_BUF_DP<1>")
	)
	(arc
		(start 337.534504 -397.951706)
		(mid 337.546781 -398.013429)
		(end 337.581748 -398.065752)
		(width 0.14224)
		(layer "In6.Cu")
		(net "P5E_CPU0_P1_TX_BUF_DP<1>")
	)
	(segment
		(start 354.198174 -397.849344)
		(end 354.718874 -397.849344)
		(width 0.127)
		(layer "F.Cu")
		(net "P5E_CPU0_P1_TX_BUF_DP<15>")
	)
	(segment
		(start 352.163126 -416.632644)
		(end 351.867216 -416.336734)
		(width 0.12954)
		(layer "B.Cu")
		(net "P5E_CPU0_P1_TX_BUF_DP<15>")
	)
	(segment
		(start 351.867216 -416.336734)
		(end 351.867216 -415.65703)
		(width 0.12954)
		(layer "B.Cu")
		(net "P5E_CPU0_P1_TX_BUF_DP<15>")
	)
	(segment
		(start 351.867216 -415.65703)
		(end 352.137726 -415.38652)
		(width 0.12954)
		(layer "B.Cu")
		(net "P5E_CPU0_P1_TX_BUF_DP<15>")
	)
	(segment
		(start 351.845118 -415.093912)
		(end 352.137726 -415.38652)
		(width 0.14224)
		(layer "In6.Cu")
		(net "P5E_CPU0_P1_TX_BUF_DP<15>")
	)
	(segment
		(start 353.850194 -405.188928)
		(end 353.478592 -406.672542)
		(width 0.14224)
		(layer "In6.Cu")
		(net "P5E_CPU0_P1_TX_BUF_DP<15>")
	)
	(segment
		(start 353.578414 -406.838912)
		(end 353.474782 -407.253186)
		(width 0.14224)
		(layer "In6.Cu")
		(net "P5E_CPU0_P1_TX_BUF_DP<15>")
	)
	(segment
		(start 353.030282 -409.026868)
		(end 352.92665 -409.441142)
		(width 0.14224)
		(layer "In6.Cu")
		(net "P5E_CPU0_P1_TX_BUF_DP<15>")
	)
	(segment
		(start 352.758756 -409.541726)
		(end 351.845118 -413.189166)
		(width 0.14224)
		(layer "In6.Cu")
		(net "P5E_CPU0_P1_TX_BUF_DP<15>")
	)
	(segment
		(start 353.478592 -406.672542)
		(end 353.578414 -406.838912)
		(width 0.14224)
		(layer "In6.Cu")
		(net "P5E_CPU0_P1_TX_BUF_DP<15>")
	)
	(segment
		(start 353.474782 -407.253186)
		(end 353.308158 -407.352754)
		(width 0.14224)
		(layer "In6.Cu")
		(net "P5E_CPU0_P1_TX_BUF_DP<15>")
	)
	(segment
		(start 354.718874 -397.849344)
		(end 354.604066 -397.734536)
		(width 0.14224)
		(layer "In6.Cu")
		(net "P5E_CPU0_P1_TX_BUF_DP<15>")
	)
	(segment
		(start 352.75901 -409.541472)
		(end 352.758756 -409.541726)
		(width 0.14224)
		(layer "In6.Cu")
		(net "P5E_CPU0_P1_TX_BUF_DP<15>")
	)
	(segment
		(start 353.200716 -408.347164)
		(end 353.038156 -408.444192)
		(width 0.14224)
		(layer "In6.Cu")
		(net "P5E_CPU0_P1_TX_BUF_DP<15>")
	)
	(segment
		(start 353.304348 -407.93289)
		(end 353.200716 -408.347164)
		(width 0.14224)
		(layer "In6.Cu")
		(net "P5E_CPU0_P1_TX_BUF_DP<15>")
	)
	(segment
		(start 354.153978 -399.678906)
		(end 354.02393 -399.808954)
		(width 0.14224)
		(layer "In6.Cu")
		(net "P5E_CPU0_P1_TX_BUF_DP<15>")
	)
	(segment
		(start 354.42779 -398.121378)
		(end 354.568506 -398.26184)
		(width 0.14224)
		(layer "In6.Cu")
		(net "P5E_CPU0_P1_TX_BUF_DP<15>")
	)
	(segment
		(start 351.845118 -413.189166)
		(end 351.845118 -415.093912)
		(width 0.14224)
		(layer "In6.Cu")
		(net "P5E_CPU0_P1_TX_BUF_DP<15>")
	)
	(segment
		(start 352.933 -408.864562)
		(end 353.030282 -409.026868)
		(width 0.14224)
		(layer "In6.Cu")
		(net "P5E_CPU0_P1_TX_BUF_DP<15>")
	)
	(segment
		(start 353.038156 -408.444192)
		(end 352.933 -408.864562)
		(width 0.14224)
		(layer "In6.Cu")
		(net "P5E_CPU0_P1_TX_BUF_DP<15>")
	)
	(segment
		(start 353.308158 -407.352754)
		(end 353.204526 -407.76652)
		(width 0.14224)
		(layer "In6.Cu")
		(net "P5E_CPU0_P1_TX_BUF_DP<15>")
	)
	(segment
		(start 353.204526 -407.76652)
		(end 353.304348 -407.93289)
		(width 0.14224)
		(layer "In6.Cu")
		(net "P5E_CPU0_P1_TX_BUF_DP<15>")
	)
	(segment
		(start 354.42398 -397.734536)
		(end 354.334572 -397.823944)
		(width 0.14224)
		(layer "In6.Cu")
		(net "P5E_CPU0_P1_TX_BUF_DP<15>")
	)
	(segment
		(start 352.92665 -409.441142)
		(end 352.75901 -409.541472)
		(width 0.14224)
		(layer "In6.Cu")
		(net "P5E_CPU0_P1_TX_BUF_DP<15>")
	)
	(segment
		(start 353.930204 -400.035014)
		(end 353.930204 -404.540974)
		(width 0.14224)
		(layer "In6.Cu")
		(net "P5E_CPU0_P1_TX_BUF_DP<15>")
	)
	(segment
		(start 354.604066 -397.734536)
		(end 354.42398 -397.734536)
		(width 0.14224)
		(layer "In6.Cu")
		(net "P5E_CPU0_P1_TX_BUF_DP<15>")
	)
	(segment
		(start 354.334572 -397.823944)
		(end 354.334572 -397.896334)
		(width 0.14224)
		(layer "In6.Cu")
		(net "P5E_CPU0_P1_TX_BUF_DP<15>")
	)
	(arc
		(start 354.432616 -399.147538)
		(mid 354.333821 -399.434477)
		(end 354.153978 -399.678906)
		(width 0.14224)
		(layer "In6.Cu")
		(net "P5E_CPU0_P1_TX_BUF_DP<15>")
	)
	(arc
		(start 353.930204 -404.540974)
		(mid 353.910091 -404.867407)
		(end 353.850194 -405.188928)
		(width 0.14224)
		(layer "In6.Cu")
		(net "P5E_CPU0_P1_TX_BUF_DP<15>")
	)
	(arc
		(start 354.69322 -398.60728)
		(mid 354.648008 -398.775794)
		(end 354.54971 -398.919954)
		(width 0.14224)
		(layer "In6.Cu")
		(net "P5E_CPU0_P1_TX_BUF_DP<15>")
	)
	(arc
		(start 354.54971 -398.919954)
		(mid 354.474354 -399.0251)
		(end 354.432616 -399.147538)
		(width 0.14224)
		(layer "In6.Cu")
		(net "P5E_CPU0_P1_TX_BUF_DP<15>")
	)
	(arc
		(start 354.568506 -398.26184)
		(mid 354.669495 -398.420609)
		(end 354.69322 -398.60728)
		(width 0.14224)
		(layer "In6.Cu")
		(net "P5E_CPU0_P1_TX_BUF_DP<15>")
	)
	(arc
		(start 354.02393 -399.808954)
		(mid 353.954575 -399.912657)
		(end 353.930204 -400.035014)
		(width 0.14224)
		(layer "In6.Cu")
		(net "P5E_CPU0_P1_TX_BUF_DP<15>")
	)
	(arc
		(start 354.334572 -397.896334)
		(mid 354.358798 -398.018128)
		(end 354.42779 -398.121378)
		(width 0.14224)
		(layer "In6.Cu")
		(net "P5E_CPU0_P1_TX_BUF_DP<15>")
	)
	(segment
		(start 352.998024 -397.849344)
		(end 353.518724 -397.849344)
		(width 0.127)
		(layer "F.Cu")
		(net "P5E_CPU0_P1_TX_BUF_DP<14>")
	)
	(segment
		(start 348.803976 -416.336734)
		(end 348.803976 -415.65703)
		(width 0.12954)
		(layer "B.Cu")
		(net "P5E_CPU0_P1_TX_BUF_DP<14>")
	)
	(segment
		(start 349.099886 -416.632644)
		(end 348.803976 -416.336734)
		(width 0.12954)
		(layer "B.Cu")
		(net "P5E_CPU0_P1_TX_BUF_DP<14>")
	)
	(segment
		(start 348.803976 -415.65703)
		(end 349.074486 -415.38652)
		(width 0.12954)
		(layer "B.Cu")
		(net "P5E_CPU0_P1_TX_BUF_DP<14>")
	)
	(segment
		(start 353.518724 -397.849344)
		(end 353.403916 -397.734536)
		(width 0.14224)
		(layer "In6.Cu")
		(net "P5E_CPU0_P1_TX_BUF_DP<14>")
	)
	(segment
		(start 350.92259 -408.141932)
		(end 350.987868 -408.324558)
		(width 0.14224)
		(layer "In6.Cu")
		(net "P5E_CPU0_P1_TX_BUF_DP<14>")
	)
	(segment
		(start 352.730054 -400.053302)
		(end 352.730054 -403.805136)
		(width 0.14224)
		(layer "In6.Cu")
		(net "P5E_CPU0_P1_TX_BUF_DP<14>")
	)
	(segment
		(start 348.783656 -412.662624)
		(end 348.783656 -415.09569)
		(width 0.14224)
		(layer "In6.Cu")
		(net "P5E_CPU0_P1_TX_BUF_DP<14>")
	)
	(segment
		(start 351.952052 -406.284938)
		(end 351.76968 -406.671018)
		(width 0.14224)
		(layer "In6.Cu")
		(net "P5E_CPU0_P1_TX_BUF_DP<14>")
	)
	(segment
		(start 351.46996 -407.304748)
		(end 351.287588 -407.690828)
		(width 0.14224)
		(layer "In6.Cu")
		(net "P5E_CPU0_P1_TX_BUF_DP<14>")
	)
	(segment
		(start 351.404682 -407.122122)
		(end 351.46996 -407.304748)
		(width 0.14224)
		(layer "In6.Cu")
		(net "P5E_CPU0_P1_TX_BUF_DP<14>")
	)
	(segment
		(start 348.783656 -415.09569)
		(end 349.074486 -415.38652)
		(width 0.14224)
		(layer "In6.Cu")
		(net "P5E_CPU0_P1_TX_BUF_DP<14>")
	)
	(segment
		(start 351.76968 -406.671018)
		(end 351.5868 -406.73655)
		(width 0.14224)
		(layer "In6.Cu")
		(net "P5E_CPU0_P1_TX_BUF_DP<14>")
	)
	(segment
		(start 352.068892 -405.71674)
		(end 351.886774 -406.102312)
		(width 0.14224)
		(layer "In6.Cu")
		(net "P5E_CPU0_P1_TX_BUF_DP<14>")
	)
	(segment
		(start 352.970592 -399.639028)
		(end 352.85299 -399.75663)
		(width 0.14224)
		(layer "In6.Cu")
		(net "P5E_CPU0_P1_TX_BUF_DP<14>")
	)
	(segment
		(start 350.987868 -408.324558)
		(end 350.805496 -408.710638)
		(width 0.14224)
		(layer "In6.Cu")
		(net "P5E_CPU0_P1_TX_BUF_DP<14>")
	)
	(segment
		(start 353.224084 -397.734536)
		(end 353.134676 -397.823944)
		(width 0.14224)
		(layer "In6.Cu")
		(net "P5E_CPU0_P1_TX_BUF_DP<14>")
	)
	(segment
		(start 353.403916 -397.734536)
		(end 353.224084 -397.734536)
		(width 0.14224)
		(layer "In6.Cu")
		(net "P5E_CPU0_P1_TX_BUF_DP<14>")
	)
	(segment
		(start 353.134676 -397.823944)
		(end 353.134676 -397.965422)
		(width 0.14224)
		(layer "In6.Cu")
		(net "P5E_CPU0_P1_TX_BUF_DP<14>")
	)
	(segment
		(start 351.5868 -406.73655)
		(end 351.404682 -407.122122)
		(width 0.14224)
		(layer "In6.Cu")
		(net "P5E_CPU0_P1_TX_BUF_DP<14>")
	)
	(segment
		(start 350.620076 -408.777186)
		(end 348.783656 -412.662624)
		(width 0.14224)
		(layer "In6.Cu")
		(net "P5E_CPU0_P1_TX_BUF_DP<14>")
	)
	(segment
		(start 353.344734 -398.904714)
		(end 353.334574 -398.914874)
		(width 0.14224)
		(layer "In6.Cu")
		(net "P5E_CPU0_P1_TX_BUF_DP<14>")
	)
	(segment
		(start 351.104708 -407.75636)
		(end 350.92259 -408.141932)
		(width 0.14224)
		(layer "In6.Cu")
		(net "P5E_CPU0_P1_TX_BUF_DP<14>")
	)
	(segment
		(start 351.886774 -406.102312)
		(end 351.952052 -406.284938)
		(width 0.14224)
		(layer "In6.Cu")
		(net "P5E_CPU0_P1_TX_BUF_DP<14>")
	)
	(segment
		(start 350.805496 -408.710638)
		(end 350.620076 -408.777186)
		(width 0.14224)
		(layer "In6.Cu")
		(net "P5E_CPU0_P1_TX_BUF_DP<14>")
	)
	(segment
		(start 353.172014 -398.055338)
		(end 353.344734 -398.22755)
		(width 0.14224)
		(layer "In6.Cu")
		(net "P5E_CPU0_P1_TX_BUF_DP<14>")
	)
	(segment
		(start 351.287588 -407.690828)
		(end 351.104708 -407.75636)
		(width 0.14224)
		(layer "In6.Cu")
		(net "P5E_CPU0_P1_TX_BUF_DP<14>")
	)
	(arc
		(start 352.85299 -399.75663)
		(mid 352.761988 -399.89273)
		(end 352.730054 -400.053302)
		(width 0.14224)
		(layer "In6.Cu")
		(net "P5E_CPU0_P1_TX_BUF_DP<14>")
	)
	(arc
		(start 353.167696 -399.24736)
		(mid 353.10072 -399.459085)
		(end 352.970592 -399.639028)
		(width 0.14224)
		(layer "In6.Cu")
		(net "P5E_CPU0_P1_TX_BUF_DP<14>")
	)
	(arc
		(start 353.344734 -398.22755)
		(mid 353.485054 -398.566132)
		(end 353.344734 -398.904714)
		(width 0.14224)
		(layer "In6.Cu")
		(net "P5E_CPU0_P1_TX_BUF_DP<14>")
	)
	(arc
		(start 353.334574 -398.914874)
		(mid 353.224399 -399.067704)
		(end 353.167696 -399.24736)
		(width 0.14224)
		(layer "In6.Cu")
		(net "P5E_CPU0_P1_TX_BUF_DP<14>")
	)
	(arc
		(start 352.730054 -403.805136)
		(mid 352.560154 -404.816519)
		(end 352.068892 -405.71674)
		(width 0.14224)
		(layer "In6.Cu")
		(net "P5E_CPU0_P1_TX_BUF_DP<14>")
	)
	(arc
		(start 353.134676 -397.965422)
		(mid 353.144378 -398.014106)
		(end 353.172014 -398.055338)
		(width 0.14224)
		(layer "In6.Cu")
		(net "P5E_CPU0_P1_TX_BUF_DP<14>")
	)
	(segment
		(start 351.798128 -397.849344)
		(end 352.318828 -397.849344)
		(width 0.127)
		(layer "F.Cu")
		(net "P5E_CPU0_P1_TX_BUF_DP<13>")
	)
	(segment
		(start 345.740736 -415.65703)
		(end 346.011246 -415.38652)
		(width 0.12954)
		(layer "B.Cu")
		(net "P5E_CPU0_P1_TX_BUF_DP<13>")
	)
	(segment
		(start 346.036646 -416.632644)
		(end 345.740736 -416.336734)
		(width 0.12954)
		(layer "B.Cu")
		(net "P5E_CPU0_P1_TX_BUF_DP<13>")
	)
	(segment
		(start 345.740736 -416.336734)
		(end 345.740736 -415.65703)
		(width 0.12954)
		(layer "B.Cu")
		(net "P5E_CPU0_P1_TX_BUF_DP<13>")
	)
	(segment
		(start 351.530158 -399.955512)
		(end 351.530158 -403.977094)
		(width 0.14224)
		(layer "In6.Cu")
		(net "P5E_CPU0_P1_TX_BUF_DP<13>")
	)
	(segment
		(start 347.82252 -409.60294)
		(end 347.569028 -409.944062)
		(width 0.14224)
		(layer "In6.Cu")
		(net "P5E_CPU0_P1_TX_BUF_DP<13>")
	)
	(segment
		(start 352.318828 -397.849344)
		(end 352.20402 -397.734536)
		(width 0.14224)
		(layer "In6.Cu")
		(net "P5E_CPU0_P1_TX_BUF_DP<13>")
	)
	(segment
		(start 345.720416 -412.678626)
		(end 345.720416 -415.09569)
		(width 0.14224)
		(layer "In6.Cu")
		(net "P5E_CPU0_P1_TX_BUF_DP<13>")
	)
	(segment
		(start 348.688152 -408.668728)
		(end 348.496128 -408.697176)
		(width 0.14224)
		(layer "In6.Cu")
		(net "P5E_CPU0_P1_TX_BUF_DP<13>")
	)
	(segment
		(start 347.342968 -410.480002)
		(end 347.151198 -410.508196)
		(width 0.14224)
		(layer "In6.Cu")
		(net "P5E_CPU0_P1_TX_BUF_DP<13>")
	)
	(segment
		(start 348.94266 -408.326082)
		(end 348.688152 -408.668728)
		(width 0.14224)
		(layer "In6.Cu")
		(net "P5E_CPU0_P1_TX_BUF_DP<13>")
	)
	(segment
		(start 351.970086 -399.13814)
		(end 351.970086 -399.278856)
		(width 0.14224)
		(layer "In6.Cu")
		(net "P5E_CPU0_P1_TX_BUF_DP<13>")
	)
	(segment
		(start 350.394778 -406.141174)
		(end 348.914466 -408.134058)
		(width 0.14224)
		(layer "In6.Cu")
		(net "P5E_CPU0_P1_TX_BUF_DP<13>")
	)
	(segment
		(start 347.569028 -409.944062)
		(end 347.59773 -410.137102)
		(width 0.14224)
		(layer "In6.Cu")
		(net "P5E_CPU0_P1_TX_BUF_DP<13>")
	)
	(segment
		(start 348.270068 -409.231592)
		(end 348.01556 -409.574238)
		(width 0.14224)
		(layer "In6.Cu")
		(net "P5E_CPU0_P1_TX_BUF_DP<13>")
	)
	(segment
		(start 352.20402 -397.734536)
		(end 352.023934 -397.734536)
		(width 0.14224)
		(layer "In6.Cu")
		(net "P5E_CPU0_P1_TX_BUF_DP<13>")
	)
	(segment
		(start 347.59773 -410.137102)
		(end 347.342968 -410.480002)
		(width 0.14224)
		(layer "In6.Cu")
		(net "P5E_CPU0_P1_TX_BUF_DP<13>")
	)
	(segment
		(start 346.151962 -411.871414)
		(end 345.809824 -412.383224)
		(width 0.14224)
		(layer "In6.Cu")
		(net "P5E_CPU0_P1_TX_BUF_DP<13>")
	)
	(segment
		(start 351.934526 -397.823944)
		(end 351.934526 -397.863314)
		(width 0.14224)
		(layer "In6.Cu")
		(net "P5E_CPU0_P1_TX_BUF_DP<13>")
	)
	(segment
		(start 352.161094 -398.88033)
		(end 352.01733 -399.024094)
		(width 0.14224)
		(layer "In6.Cu")
		(net "P5E_CPU0_P1_TX_BUF_DP<13>")
	)
	(segment
		(start 348.01556 -409.574238)
		(end 347.82252 -409.60294)
		(width 0.14224)
		(layer "In6.Cu")
		(net "P5E_CPU0_P1_TX_BUF_DP<13>")
	)
	(segment
		(start 351.840292 -399.592546)
		(end 351.567496 -399.865342)
		(width 0.14224)
		(layer "In6.Cu")
		(net "P5E_CPU0_P1_TX_BUF_DP<13>")
	)
	(segment
		(start 347.151198 -410.508196)
		(end 346.390468 -411.532324)
		(width 0.14224)
		(layer "In6.Cu")
		(net "P5E_CPU0_P1_TX_BUF_DP<13>")
	)
	(segment
		(start 352.023934 -397.734536)
		(end 351.934526 -397.823944)
		(width 0.14224)
		(layer "In6.Cu")
		(net "P5E_CPU0_P1_TX_BUF_DP<13>")
	)
	(segment
		(start 348.914466 -408.134058)
		(end 348.94266 -408.326082)
		(width 0.14224)
		(layer "In6.Cu")
		(net "P5E_CPU0_P1_TX_BUF_DP<13>")
	)
	(segment
		(start 348.496128 -408.697176)
		(end 348.241874 -409.039568)
		(width 0.14224)
		(layer "In6.Cu")
		(net "P5E_CPU0_P1_TX_BUF_DP<13>")
	)
	(segment
		(start 348.241874 -409.039568)
		(end 348.270068 -409.231592)
		(width 0.14224)
		(layer "In6.Cu")
		(net "P5E_CPU0_P1_TX_BUF_DP<13>")
	)
	(segment
		(start 352.051366 -398.145254)
		(end 352.161094 -398.254982)
		(width 0.14224)
		(layer "In6.Cu")
		(net "P5E_CPU0_P1_TX_BUF_DP<13>")
	)
	(segment
		(start 345.720416 -415.09569)
		(end 346.011246 -415.38652)
		(width 0.14224)
		(layer "In6.Cu")
		(net "P5E_CPU0_P1_TX_BUF_DP<13>")
	)
	(arc
		(start 346.390468 -411.532324)
		(mid 346.269173 -411.700433)
		(end 346.151962 -411.871414)
		(width 0.14224)
		(layer "In6.Cu")
		(net "P5E_CPU0_P1_TX_BUF_DP<13>")
	)
	(arc
		(start 351.222564 -405.001984)
		(mid 350.811482 -405.573621)
		(end 350.394778 -406.141174)
		(width 0.14224)
		(layer "In6.Cu")
		(net "P5E_CPU0_P1_TX_BUF_DP<13>")
	)
	(arc
		(start 351.567496 -399.865342)
		(mid 351.539853 -399.906712)
		(end 351.530158 -399.955512)
		(width 0.14224)
		(layer "In6.Cu")
		(net "P5E_CPU0_P1_TX_BUF_DP<13>")
	)
	(arc
		(start 351.530158 -403.977094)
		(mid 351.527945 -404.05634)
		(end 351.521268 -404.135336)
		(width 0.14224)
		(layer "In6.Cu")
		(net "P5E_CPU0_P1_TX_BUF_DP<13>")
	)
	(arc
		(start 345.809824 -412.383224)
		(mid 345.743281 -412.524313)
		(end 345.720416 -412.678626)
		(width 0.14224)
		(layer "In6.Cu")
		(net "P5E_CPU0_P1_TX_BUF_DP<13>")
	)
	(arc
		(start 351.350326 -404.77948)
		(mid 351.292654 -404.894298)
		(end 351.222564 -405.001984)
		(width 0.14224)
		(layer "In6.Cu")
		(net "P5E_CPU0_P1_TX_BUF_DP<13>")
	)
	(arc
		(start 351.970086 -399.278856)
		(mid 351.936396 -399.448609)
		(end 351.840292 -399.592546)
		(width 0.14224)
		(layer "In6.Cu")
		(net "P5E_CPU0_P1_TX_BUF_DP<13>")
	)
	(arc
		(start 351.521268 -404.135336)
		(mid 351.459517 -404.463704)
		(end 351.350326 -404.77948)
		(width 0.14224)
		(layer "In6.Cu")
		(net "P5E_CPU0_P1_TX_BUF_DP<13>")
	)
	(arc
		(start 351.934526 -397.863314)
		(mid 351.964896 -398.015906)
		(end 352.051366 -398.145254)
		(width 0.14224)
		(layer "In6.Cu")
		(net "P5E_CPU0_P1_TX_BUF_DP<13>")
	)
	(arc
		(start 352.01733 -399.024094)
		(mid 351.982368 -399.076419)
		(end 351.970086 -399.13814)
		(width 0.14224)
		(layer "In6.Cu")
		(net "P5E_CPU0_P1_TX_BUF_DP<13>")
	)
	(arc
		(start 352.161094 -398.254982)
		(mid 352.290608 -398.567656)
		(end 352.161094 -398.88033)
		(width 0.14224)
		(layer "In6.Cu")
		(net "P5E_CPU0_P1_TX_BUF_DP<13>")
	)
	(segment
		(start 350.597978 -397.849344)
		(end 351.118678 -397.849344)
		(width 0.127)
		(layer "F.Cu")
		(net "P5E_CPU0_P1_TX_BUF_DP<12>")
	)
	(segment
		(start 342.670638 -416.329876)
		(end 342.973406 -416.632644)
		(width 0.12954)
		(layer "B.Cu")
		(net "P5E_CPU0_P1_TX_BUF_DP<12>")
	)
	(segment
		(start 342.670638 -415.663888)
		(end 342.670638 -416.329876)
		(width 0.12954)
		(layer "B.Cu")
		(net "P5E_CPU0_P1_TX_BUF_DP<12>")
	)
	(segment
		(start 342.948006 -415.38652)
		(end 342.670638 -415.663888)
		(width 0.12954)
		(layer "B.Cu")
		(net "P5E_CPU0_P1_TX_BUF_DP<12>")
	)
	(segment
		(start 343.687654 -411.617668)
		(end 343.49563 -411.58922)
		(width 0.14224)
		(layer "In6.Cu")
		(net "P5E_CPU0_P1_TX_BUF_DP<12>")
	)
	(segment
		(start 346.43949 -409.179522)
		(end 346.168472 -409.509468)
		(width 0.14224)
		(layer "In6.Cu")
		(net "P5E_CPU0_P1_TX_BUF_DP<12>")
	)
	(segment
		(start 350.079056 -404.529036)
		(end 346.42044 -408.986482)
		(width 0.14224)
		(layer "In6.Cu")
		(net "P5E_CPU0_P1_TX_BUF_DP<12>")
	)
	(segment
		(start 344.030554 -411.36316)
		(end 343.687654 -411.617668)
		(width 0.14224)
		(layer "In6.Cu")
		(net "P5E_CPU0_P1_TX_BUF_DP<12>")
	)
	(segment
		(start 351.00387 -397.734536)
		(end 350.824038 -397.734536)
		(width 0.14224)
		(layer "In6.Cu")
		(net "P5E_CPU0_P1_TX_BUF_DP<12>")
	)
	(segment
		(start 351.118678 -397.849344)
		(end 351.00387 -397.734536)
		(width 0.14224)
		(layer "In6.Cu")
		(net "P5E_CPU0_P1_TX_BUF_DP<12>")
	)
	(segment
		(start 350.330008 -400.2151)
		(end 350.330008 -403.827234)
		(width 0.14224)
		(layer "In6.Cu")
		(net "P5E_CPU0_P1_TX_BUF_DP<12>")
	)
	(segment
		(start 344.936572 -410.69133)
		(end 344.593418 -410.945838)
		(width 0.14224)
		(layer "In6.Cu")
		(net "P5E_CPU0_P1_TX_BUF_DP<12>")
	)
	(segment
		(start 350.73463 -397.823944)
		(end 350.73463 -397.903954)
		(width 0.14224)
		(layer "In6.Cu")
		(net "P5E_CPU0_P1_TX_BUF_DP<12>")
	)
	(segment
		(start 344.593418 -410.945838)
		(end 344.401648 -410.91739)
		(width 0.14224)
		(layer "In6.Cu")
		(net "P5E_CPU0_P1_TX_BUF_DP<12>")
	)
	(segment
		(start 344.96502 -410.49956)
		(end 344.936572 -410.69133)
		(width 0.14224)
		(layer "In6.Cu")
		(net "P5E_CPU0_P1_TX_BUF_DP<12>")
	)
	(segment
		(start 344.401648 -410.91739)
		(end 344.059002 -411.17139)
		(width 0.14224)
		(layer "In6.Cu")
		(net "P5E_CPU0_P1_TX_BUF_DP<12>")
	)
	(segment
		(start 350.815402 -398.098772)
		(end 350.949768 -398.232884)
		(width 0.14224)
		(layer "In6.Cu")
		(net "P5E_CPU0_P1_TX_BUF_DP<12>")
	)
	(segment
		(start 350.824038 -397.734536)
		(end 350.73463 -397.823944)
		(width 0.14224)
		(layer "In6.Cu")
		(net "P5E_CPU0_P1_TX_BUF_DP<12>")
	)
	(segment
		(start 350.70415 -399.434304)
		(end 350.617536 -399.520918)
		(width 0.14224)
		(layer "In6.Cu")
		(net "P5E_CPU0_P1_TX_BUF_DP<12>")
	)
	(segment
		(start 346.42044 -408.986482)
		(end 346.43949 -409.179522)
		(width 0.14224)
		(layer "In6.Cu")
		(net "P5E_CPU0_P1_TX_BUF_DP<12>")
	)
	(segment
		(start 345.416632 -410.164788)
		(end 344.96502 -410.49956)
		(width 0.14224)
		(layer "In6.Cu")
		(net "P5E_CPU0_P1_TX_BUF_DP<12>")
	)
	(segment
		(start 342.657176 -415.09569)
		(end 342.948006 -415.38652)
		(width 0.14224)
		(layer "In6.Cu")
		(net "P5E_CPU0_P1_TX_BUF_DP<12>")
	)
	(segment
		(start 343.49563 -411.58922)
		(end 342.946482 -411.996382)
		(width 0.14224)
		(layer "In6.Cu")
		(net "P5E_CPU0_P1_TX_BUF_DP<12>")
	)
	(segment
		(start 345.975432 -409.528518)
		(end 345.583256 -410.006292)
		(width 0.14224)
		(layer "In6.Cu")
		(net "P5E_CPU0_P1_TX_BUF_DP<12>")
	)
	(segment
		(start 351.06991 -398.522444)
		(end 351.06991 -398.5514)
		(width 0.14224)
		(layer "In6.Cu")
		(net "P5E_CPU0_P1_TX_BUF_DP<12>")
	)
	(segment
		(start 346.168472 -409.509468)
		(end 345.975432 -409.528518)
		(width 0.14224)
		(layer "In6.Cu")
		(net "P5E_CPU0_P1_TX_BUF_DP<12>")
	)
	(segment
		(start 344.059002 -411.17139)
		(end 344.030554 -411.36316)
		(width 0.14224)
		(layer "In6.Cu")
		(net "P5E_CPU0_P1_TX_BUF_DP<12>")
	)
	(segment
		(start 342.657176 -412.730188)
		(end 342.657176 -415.09569)
		(width 0.14224)
		(layer "In6.Cu")
		(net "P5E_CPU0_P1_TX_BUF_DP<12>")
	)
	(arc
		(start 342.870028 -412.091632)
		(mid 342.740606 -412.336722)
		(end 342.667082 -412.60395)
		(width 0.14224)
		(layer "In6.Cu")
		(net "P5E_CPU0_P1_TX_BUF_DP<12>")
	)
	(arc
		(start 350.73463 -397.903954)
		(mid 350.755623 -398.009403)
		(end 350.815402 -398.098772)
		(width 0.14224)
		(layer "In6.Cu")
		(net "P5E_CPU0_P1_TX_BUF_DP<12>")
	)
	(arc
		(start 350.330008 -403.827234)
		(mid 350.265366 -404.19988)
		(end 350.079056 -404.529036)
		(width 0.14224)
		(layer "In6.Cu")
		(net "P5E_CPU0_P1_TX_BUF_DP<12>")
	)
	(arc
		(start 350.949768 -398.232884)
		(mid 351.038698 -398.365692)
		(end 351.06991 -398.522444)
		(width 0.14224)
		(layer "In6.Cu")
		(net "P5E_CPU0_P1_TX_BUF_DP<12>")
	)
	(arc
		(start 342.667082 -412.60395)
		(mid 342.659612 -412.666871)
		(end 342.657176 -412.730188)
		(width 0.14224)
		(layer "In6.Cu")
		(net "P5E_CPU0_P1_TX_BUF_DP<12>")
	)
	(arc
		(start 351.06991 -398.5514)
		(mid 350.974846 -399.029229)
		(end 350.70415 -399.434304)
		(width 0.14224)
		(layer "In6.Cu")
		(net "P5E_CPU0_P1_TX_BUF_DP<12>")
	)
	(arc
		(start 350.617536 -399.520918)
		(mid 350.404726 -399.839411)
		(end 350.330008 -400.2151)
		(width 0.14224)
		(layer "In6.Cu")
		(net "P5E_CPU0_P1_TX_BUF_DP<12>")
	)
	(arc
		(start 345.583256 -410.006292)
		(mid 345.504799 -410.090644)
		(end 345.416632 -410.164788)
		(width 0.14224)
		(layer "In6.Cu")
		(net "P5E_CPU0_P1_TX_BUF_DP<12>")
	)
	(arc
		(start 342.946482 -411.996382)
		(mid 342.906325 -412.042458)
		(end 342.870028 -412.091632)
		(width 0.14224)
		(layer "In6.Cu")
		(net "P5E_CPU0_P1_TX_BUF_DP<12>")
	)
	(segment
		(start 349.398082 -397.849344)
		(end 349.918782 -397.849344)
		(width 0.127)
		(layer "F.Cu")
		(net "P5E_CPU0_P1_TX_BUF_DP<11>")
	)
	(segment
		(start 339.910166 -416.632644)
		(end 339.614256 -416.336734)
		(width 0.12954)
		(layer "B.Cu")
		(net "P5E_CPU0_P1_TX_BUF_DP<11>")
	)
	(segment
		(start 339.614256 -416.336734)
		(end 339.614256 -415.65703)
		(width 0.12954)
		(layer "B.Cu")
		(net "P5E_CPU0_P1_TX_BUF_DP<11>")
	)
	(segment
		(start 339.614256 -415.65703)
		(end 339.884766 -415.38652)
		(width 0.12954)
		(layer "B.Cu")
		(net "P5E_CPU0_P1_TX_BUF_DP<11>")
	)
	(segment
		(start 349.623888 -397.734536)
		(end 349.53448 -397.823944)
		(width 0.14224)
		(layer "In6.Cu")
		(net "P5E_CPU0_P1_TX_BUF_DP<11>")
	)
	(segment
		(start 349.565722 -399.348198)
		(end 349.54083 -399.37309)
		(width 0.14224)
		(layer "In6.Cu")
		(net "P5E_CPU0_P1_TX_BUF_DP<11>")
	)
	(segment
		(start 339.593936 -412.619444)
		(end 339.593936 -415.09569)
		(width 0.14224)
		(layer "In6.Cu")
		(net "P5E_CPU0_P1_TX_BUF_DP<11>")
	)
	(segment
		(start 347.141038 -406.30856)
		(end 346.839286 -406.610566)
		(width 0.14224)
		(layer "In6.Cu")
		(net "P5E_CPU0_P1_TX_BUF_DP<11>")
	)
	(segment
		(start 345.84767 -407.408126)
		(end 344.110564 -409.144978)
		(width 0.14224)
		(layer "In6.Cu")
		(net "P5E_CPU0_P1_TX_BUF_DP<11>")
	)
	(segment
		(start 347.938598 -405.511)
		(end 347.636592 -405.813006)
		(width 0.14224)
		(layer "In6.Cu")
		(net "P5E_CPU0_P1_TX_BUF_DP<11>")
	)
	(segment
		(start 346.041472 -407.408126)
		(end 345.84767 -407.408126)
		(width 0.14224)
		(layer "In6.Cu")
		(net "P5E_CPU0_P1_TX_BUF_DP<11>")
	)
	(segment
		(start 348.74327 -404.512526)
		(end 347.938598 -405.317198)
		(width 0.14224)
		(layer "In6.Cu")
		(net "P5E_CPU0_P1_TX_BUF_DP<11>")
	)
	(segment
		(start 347.44279 -405.813006)
		(end 347.141292 -406.114504)
		(width 0.14224)
		(layer "In6.Cu")
		(net "P5E_CPU0_P1_TX_BUF_DP<11>")
	)
	(segment
		(start 344.110564 -409.144978)
		(end 343.171526 -409.83408)
		(width 0.14224)
		(layer "In6.Cu")
		(net "P5E_CPU0_P1_TX_BUF_DP<11>")
	)
	(segment
		(start 349.53448 -397.823944)
		(end 349.53448 -397.926814)
		(width 0.14224)
		(layer "In6.Cu")
		(net "P5E_CPU0_P1_TX_BUF_DP<11>")
	)
	(segment
		(start 340.578948 -411.390592)
		(end 339.873336 -411.817058)
		(width 0.14224)
		(layer "In6.Cu")
		(net "P5E_CPU0_P1_TX_BUF_DP<11>")
	)
	(segment
		(start 347.636592 -405.813006)
		(end 347.44279 -405.813006)
		(width 0.14224)
		(layer "In6.Cu")
		(net "P5E_CPU0_P1_TX_BUF_DP<11>")
	)
	(segment
		(start 343.171526 -409.83408)
		(end 342.061546 -410.53893)
		(width 0.14224)
		(layer "In6.Cu")
		(net "P5E_CPU0_P1_TX_BUF_DP<11>")
	)
	(segment
		(start 347.938598 -405.317198)
		(end 347.938598 -405.511)
		(width 0.14224)
		(layer "In6.Cu")
		(net "P5E_CPU0_P1_TX_BUF_DP<11>")
	)
	(segment
		(start 349.918782 -397.849344)
		(end 349.803974 -397.734536)
		(width 0.14224)
		(layer "In6.Cu")
		(net "P5E_CPU0_P1_TX_BUF_DP<11>")
	)
	(segment
		(start 346.343478 -407.10612)
		(end 346.041472 -407.408126)
		(width 0.14224)
		(layer "In6.Cu")
		(net "P5E_CPU0_P1_TX_BUF_DP<11>")
	)
	(segment
		(start 349.130112 -400.364452)
		(end 349.130112 -403.578822)
		(width 0.14224)
		(layer "In6.Cu")
		(net "P5E_CPU0_P1_TX_BUF_DP<11>")
	)
	(segment
		(start 346.64523 -406.610566)
		(end 346.343732 -406.912064)
		(width 0.14224)
		(layer "In6.Cu")
		(net "P5E_CPU0_P1_TX_BUF_DP<11>")
	)
	(segment
		(start 349.803974 -397.734536)
		(end 349.623888 -397.734536)
		(width 0.14224)
		(layer "In6.Cu")
		(net "P5E_CPU0_P1_TX_BUF_DP<11>")
	)
	(segment
		(start 346.343732 -406.912064)
		(end 346.343478 -407.10612)
		(width 0.14224)
		(layer "In6.Cu")
		(net "P5E_CPU0_P1_TX_BUF_DP<11>")
	)
	(segment
		(start 349.811086 -398.488662)
		(end 349.811086 -398.75587)
		(width 0.14224)
		(layer "In6.Cu")
		(net "P5E_CPU0_P1_TX_BUF_DP<11>")
	)
	(segment
		(start 347.141292 -406.114504)
		(end 347.141038 -406.30856)
		(width 0.14224)
		(layer "In6.Cu")
		(net "P5E_CPU0_P1_TX_BUF_DP<11>")
	)
	(segment
		(start 339.593936 -415.09569)
		(end 339.884766 -415.38652)
		(width 0.14224)
		(layer "In6.Cu")
		(net "P5E_CPU0_P1_TX_BUF_DP<11>")
	)
	(segment
		(start 346.839286 -406.610566)
		(end 346.64523 -406.610566)
		(width 0.14224)
		(layer "In6.Cu")
		(net "P5E_CPU0_P1_TX_BUF_DP<11>")
	)
	(segment
		(start 349.606362 -398.100042)
		(end 349.681292 -398.174972)
		(width 0.14224)
		(layer "In6.Cu")
		(net "P5E_CPU0_P1_TX_BUF_DP<11>")
	)
	(arc
		(start 339.873336 -411.817058)
		(mid 339.823138 -411.856762)
		(end 339.784436 -411.907736)
		(width 0.14224)
		(layer "In6.Cu")
		(net "P5E_CPU0_P1_TX_BUF_DP<11>")
	)
	(arc
		(start 349.811086 -398.75587)
		(mid 349.74732 -399.076441)
		(end 349.565722 -399.348198)
		(width 0.14224)
		(layer "In6.Cu")
		(net "P5E_CPU0_P1_TX_BUF_DP<11>")
	)
	(arc
		(start 349.681292 -398.174972)
		(mid 349.777428 -398.318895)
		(end 349.811086 -398.488662)
		(width 0.14224)
		(layer "In6.Cu")
		(net "P5E_CPU0_P1_TX_BUF_DP<11>")
	)
	(arc
		(start 349.54083 -399.37309)
		(mid 349.236861 -399.827917)
		(end 349.130112 -400.364452)
		(width 0.14224)
		(layer "In6.Cu")
		(net "P5E_CPU0_P1_TX_BUF_DP<11>")
	)
	(arc
		(start 342.061546 -410.53893)
		(mid 341.315459 -410.956427)
		(end 340.578948 -411.390592)
		(width 0.14224)
		(layer "In6.Cu")
		(net "P5E_CPU0_P1_TX_BUF_DP<11>")
	)
	(arc
		(start 339.784436 -411.907736)
		(mid 339.642303 -412.251043)
		(end 339.593936 -412.619444)
		(width 0.14224)
		(layer "In6.Cu")
		(net "P5E_CPU0_P1_TX_BUF_DP<11>")
	)
	(arc
		(start 349.130112 -403.578822)
		(mid 349.029576 -404.084159)
		(end 348.74327 -404.512526)
		(width 0.14224)
		(layer "In6.Cu")
		(net "P5E_CPU0_P1_TX_BUF_DP<11>")
	)
	(arc
		(start 349.53448 -397.926814)
		(mid 349.553168 -398.020585)
		(end 349.606362 -398.100042)
		(width 0.14224)
		(layer "In6.Cu")
		(net "P5E_CPU0_P1_TX_BUF_DP<11>")
	)
	(segment
		(start 348.198186 -397.849344)
		(end 348.718886 -397.849344)
		(width 0.127)
		(layer "F.Cu")
		(net "P5E_CPU0_P1_TX_BUF_DP<10>")
	)
	(segment
		(start 336.846926 -416.632644)
		(end 336.551016 -416.336734)
		(width 0.12954)
		(layer "B.Cu")
		(net "P5E_CPU0_P1_TX_BUF_DP<10>")
	)
	(segment
		(start 336.551016 -416.336734)
		(end 336.551016 -415.65703)
		(width 0.12954)
		(layer "B.Cu")
		(net "P5E_CPU0_P1_TX_BUF_DP<10>")
	)
	(segment
		(start 336.551016 -415.65703)
		(end 336.821526 -415.38652)
		(width 0.12954)
		(layer "B.Cu")
		(net "P5E_CPU0_P1_TX_BUF_DP<10>")
	)
	(segment
		(start 347.864176 -402.567648)
		(end 348.001336 -402.704808)
		(width 0.14224)
		(layer "In6.Cu")
		(net "P5E_CPU0_P1_TX_BUF_DP<10>")
	)
	(segment
		(start 337.768438 -411.472634)
		(end 336.757518 -411.974284)
		(width 0.14224)
		(layer "In6.Cu")
		(net "P5E_CPU0_P1_TX_BUF_DP<10>")
	)
	(segment
		(start 348.683326 -398.560798)
		(end 348.683326 -398.691608)
		(width 0.14224)
		(layer "In6.Cu")
		(net "P5E_CPU0_P1_TX_BUF_DP<10>")
	)
	(segment
		(start 339.407246 -410.659326)
		(end 339.34527 -410.843476)
		(width 0.14224)
		(layer "In6.Cu")
		(net "P5E_CPU0_P1_TX_BUF_DP<10>")
	)
	(segment
		(start 348.61119 -398.955514)
		(end 348.396814 -399.31848)
		(width 0.14224)
		(layer "In6.Cu")
		(net "P5E_CPU0_P1_TX_BUF_DP<10>")
	)
	(segment
		(start 347.817948 -403.926802)
		(end 347.768672 -404.045166)
		(width 0.14224)
		(layer "In6.Cu")
		(net "P5E_CPU0_P1_TX_BUF_DP<10>")
	)
	(segment
		(start 347.864176 -403.268688)
		(end 347.864176 -403.695408)
		(width 0.14224)
		(layer "In6.Cu")
		(net "P5E_CPU0_P1_TX_BUF_DP<10>")
	)
	(segment
		(start 338.334858 -411.344872)
		(end 337.952334 -411.53461)
		(width 0.14224)
		(layer "In6.Cu")
		(net "P5E_CPU0_P1_TX_BUF_DP<10>")
	)
	(segment
		(start 348.250764 -399.507202)
		(end 348.228158 -399.529808)
		(width 0.14224)
		(layer "In6.Cu")
		(net "P5E_CPU0_P1_TX_BUF_DP<10>")
	)
	(segment
		(start 338.962746 -411.03296)
		(end 338.77885 -410.971238)
		(width 0.14224)
		(layer "In6.Cu")
		(net "P5E_CPU0_P1_TX_BUF_DP<10>")
	)
	(segment
		(start 348.001336 -403.131528)
		(end 347.864176 -403.268688)
		(width 0.14224)
		(layer "In6.Cu")
		(net "P5E_CPU0_P1_TX_BUF_DP<10>")
	)
	(segment
		(start 347.864176 -400.408394)
		(end 347.864176 -402.567648)
		(width 0.14224)
		(layer "In6.Cu")
		(net "P5E_CPU0_P1_TX_BUF_DP<10>")
	)
	(segment
		(start 347.638116 -404.240238)
		(end 344.04173 -407.836624)
		(width 0.14224)
		(layer "In6.Cu")
		(net "P5E_CPU0_P1_TX_BUF_DP<10>")
	)
	(segment
		(start 348.334584 -397.823944)
		(end 348.334584 -397.888206)
		(width 0.14224)
		(layer "In6.Cu")
		(net "P5E_CPU0_P1_TX_BUF_DP<10>")
	)
	(segment
		(start 341.689944 -409.526486)
		(end 339.407246 -410.659326)
		(width 0.14224)
		(layer "In6.Cu")
		(net "P5E_CPU0_P1_TX_BUF_DP<10>")
	)
	(segment
		(start 348.718886 -397.849344)
		(end 348.604078 -397.734536)
		(width 0.14224)
		(layer "In6.Cu")
		(net "P5E_CPU0_P1_TX_BUF_DP<10>")
	)
	(segment
		(start 336.530696 -415.09569)
		(end 336.821526 -415.38652)
		(width 0.14224)
		(layer "In6.Cu")
		(net "P5E_CPU0_P1_TX_BUF_DP<10>")
	)
	(segment
		(start 348.604078 -397.734536)
		(end 348.423992 -397.734536)
		(width 0.14224)
		(layer "In6.Cu")
		(net "P5E_CPU0_P1_TX_BUF_DP<10>")
	)
	(segment
		(start 348.423992 -397.734536)
		(end 348.334584 -397.823944)
		(width 0.14224)
		(layer "In6.Cu")
		(net "P5E_CPU0_P1_TX_BUF_DP<10>")
	)
	(segment
		(start 338.77885 -410.971238)
		(end 338.396834 -411.160722)
		(width 0.14224)
		(layer "In6.Cu")
		(net "P5E_CPU0_P1_TX_BUF_DP<10>")
	)
	(segment
		(start 338.396834 -411.160722)
		(end 338.334858 -411.344872)
		(width 0.14224)
		(layer "In6.Cu")
		(net "P5E_CPU0_P1_TX_BUF_DP<10>")
	)
	(segment
		(start 337.952334 -411.53461)
		(end 337.768438 -411.472634)
		(width 0.14224)
		(layer "In6.Cu")
		(net "P5E_CPU0_P1_TX_BUF_DP<10>")
	)
	(segment
		(start 336.530696 -412.340044)
		(end 336.530696 -415.09569)
		(width 0.14224)
		(layer "In6.Cu")
		(net "P5E_CPU0_P1_TX_BUF_DP<10>")
	)
	(segment
		(start 348.001336 -402.704808)
		(end 348.001336 -403.131528)
		(width 0.14224)
		(layer "In6.Cu")
		(net "P5E_CPU0_P1_TX_BUF_DP<10>")
	)
	(segment
		(start 348.433644 -398.12722)
		(end 348.553532 -398.247108)
		(width 0.14224)
		(layer "In6.Cu")
		(net "P5E_CPU0_P1_TX_BUF_DP<10>")
	)
	(segment
		(start 339.34527 -410.843476)
		(end 338.962746 -411.03296)
		(width 0.14224)
		(layer "In6.Cu")
		(net "P5E_CPU0_P1_TX_BUF_DP<10>")
	)
	(arc
		(start 336.757518 -411.974284)
		(mid 336.59205 -412.124871)
		(end 336.530696 -412.340044)
		(width 0.14224)
		(layer "In6.Cu")
		(net "P5E_CPU0_P1_TX_BUF_DP<10>")
	)
	(arc
		(start 347.768672 -404.045166)
		(mid 347.712923 -404.14908)
		(end 347.638116 -404.240238)
		(width 0.14224)
		(layer "In6.Cu")
		(net "P5E_CPU0_P1_TX_BUF_DP<10>")
	)
	(arc
		(start 344.04173 -407.836624)
		(mid 342.934562 -408.7772)
		(end 341.689944 -409.526486)
		(width 0.14224)
		(layer "In6.Cu")
		(net "P5E_CPU0_P1_TX_BUF_DP<10>")
	)
	(arc
		(start 347.864176 -403.695408)
		(mid 347.852511 -403.813393)
		(end 347.817948 -403.926802)
		(width 0.14224)
		(layer "In6.Cu")
		(net "P5E_CPU0_P1_TX_BUF_DP<10>")
	)
	(arc
		(start 348.683326 -398.691608)
		(mid 348.664979 -398.828408)
		(end 348.61119 -398.955514)
		(width 0.14224)
		(layer "In6.Cu")
		(net "P5E_CPU0_P1_TX_BUF_DP<10>")
	)
	(arc
		(start 348.553532 -398.247108)
		(mid 348.649668 -398.391031)
		(end 348.683326 -398.560798)
		(width 0.14224)
		(layer "In6.Cu")
		(net "P5E_CPU0_P1_TX_BUF_DP<10>")
	)
	(arc
		(start 348.334584 -397.888206)
		(mid 348.360333 -398.017567)
		(end 348.433644 -398.12722)
		(width 0.14224)
		(layer "In6.Cu")
		(net "P5E_CPU0_P1_TX_BUF_DP<10>")
	)
	(arc
		(start 348.228158 -399.529808)
		(mid 347.958762 -399.932892)
		(end 347.864176 -400.408394)
		(width 0.14224)
		(layer "In6.Cu")
		(net "P5E_CPU0_P1_TX_BUF_DP<10>")
	)
	(arc
		(start 348.396814 -399.31848)
		(mid 348.329735 -399.417442)
		(end 348.250764 -399.507202)
		(width 0.14224)
		(layer "In6.Cu")
		(net "P5E_CPU0_P1_TX_BUF_DP<10>")
	)
	(segment
		(start 336.19821 -397.849344)
		(end 336.71891 -397.849344)
		(width 0.127)
		(layer "F.Cu")
		(net "P5E_CPU0_P1_TX_BUF_DP<0>")
	)
	(segment
		(start 305.918616 -415.65703)
		(end 306.189126 -415.38652)
		(width 0.12954)
		(layer "B.Cu")
		(net "P5E_CPU0_P1_TX_BUF_DP<0>")
	)
	(segment
		(start 305.918616 -416.336734)
		(end 305.918616 -415.65703)
		(width 0.12954)
		(layer "B.Cu")
		(net "P5E_CPU0_P1_TX_BUF_DP<0>")
	)
	(segment
		(start 306.214526 -416.632644)
		(end 305.918616 -416.336734)
		(width 0.12954)
		(layer "B.Cu")
		(net "P5E_CPU0_P1_TX_BUF_DP<0>")
	)
	(segment
		(start 312.286396 -408.953208)
		(end 311.87644 -409.07081)
		(width 0.14224)
		(layer "In6.Cu")
		(net "P5E_CPU0_P1_TX_BUF_DP<0>")
	)
	(segment
		(start 335.081626 -398.580356)
		(end 334.952594 -398.89176)
		(width 0.14224)
		(layer "In6.Cu")
		(net "P5E_CPU0_P1_TX_BUF_DP<0>")
	)
	(segment
		(start 334.681576 -399.784824)
		(end 334.597502 -400.207226)
		(width 0.14224)
		(layer "In6.Cu")
		(net "P5E_CPU0_P1_TX_BUF_DP<0>")
	)
	(segment
		(start 310.118252 -409.575762)
		(end 308.932834 -409.915868)
		(width 0.14224)
		(layer "In6.Cu")
		(net "P5E_CPU0_P1_TX_BUF_DP<0>")
	)
	(segment
		(start 336.71891 -397.849344)
		(end 336.596228 -397.726662)
		(width 0.14224)
		(layer "In6.Cu")
		(net "P5E_CPU0_P1_TX_BUF_DP<0>")
	)
	(segment
		(start 335.480406 -398.181576)
		(end 335.081626 -398.580356)
		(width 0.14224)
		(layer "In6.Cu")
		(net "P5E_CPU0_P1_TX_BUF_DP<0>")
	)
	(segment
		(start 310.792368 -409.382214)
		(end 310.698388 -409.55214)
		(width 0.14224)
		(layer "In6.Cu")
		(net "P5E_CPU0_P1_TX_BUF_DP<0>")
	)
	(segment
		(start 308.128162 -410.283152)
		(end 306.613052 -411.269434)
		(width 0.14224)
		(layer "In6.Cu")
		(net "P5E_CPU0_P1_TX_BUF_DP<0>")
	)
	(segment
		(start 333.394304 -402.335492)
		(end 332.043278 -402.88464)
		(width 0.14224)
		(layer "In6.Cu")
		(net "P5E_CPU0_P1_TX_BUF_DP<0>")
	)
	(segment
		(start 311.371996 -409.358592)
		(end 311.202324 -409.264612)
		(width 0.14224)
		(layer "In6.Cu")
		(net "P5E_CPU0_P1_TX_BUF_DP<0>")
	)
	(segment
		(start 311.78246 -409.240736)
		(end 311.371996 -409.358592)
		(width 0.14224)
		(layer "In6.Cu")
		(net "P5E_CPU0_P1_TX_BUF_DP<0>")
	)
	(segment
		(start 332.043278 -402.88464)
		(end 327.81748 -404.136352)
		(width 0.14224)
		(layer "In6.Cu")
		(net "P5E_CPU0_P1_TX_BUF_DP<0>")
	)
	(segment
		(start 336.596228 -397.726662)
		(end 336.418428 -397.726662)
		(width 0.14224)
		(layer "In6.Cu")
		(net "P5E_CPU0_P1_TX_BUF_DP<0>")
	)
	(segment
		(start 334.334358 -401.450048)
		(end 333.556864 -402.227542)
		(width 0.14224)
		(layer "In6.Cu")
		(net "P5E_CPU0_P1_TX_BUF_DP<0>")
	)
	(segment
		(start 305.898296 -412.587694)
		(end 305.898296 -415.09569)
		(width 0.14224)
		(layer "In6.Cu")
		(net "P5E_CPU0_P1_TX_BUF_DP<0>")
	)
	(segment
		(start 335.907126 -398.068546)
		(end 335.753456 -398.068546)
		(width 0.14224)
		(layer "In6.Cu")
		(net "P5E_CPU0_P1_TX_BUF_DP<0>")
	)
	(segment
		(start 312.866532 -408.929332)
		(end 312.456068 -409.047188)
		(width 0.14224)
		(layer "In6.Cu")
		(net "P5E_CPU0_P1_TX_BUF_DP<0>")
	)
	(segment
		(start 310.698388 -409.55214)
		(end 310.287924 -409.669742)
		(width 0.14224)
		(layer "In6.Cu")
		(net "P5E_CPU0_P1_TX_BUF_DP<0>")
	)
	(segment
		(start 336.418428 -397.726662)
		(end 336.196432 -397.948658)
		(width 0.14224)
		(layer "In6.Cu")
		(net "P5E_CPU0_P1_TX_BUF_DP<0>")
	)
	(segment
		(start 310.287924 -409.669742)
		(end 310.118252 -409.575762)
		(width 0.14224)
		(layer "In6.Cu")
		(net "P5E_CPU0_P1_TX_BUF_DP<0>")
	)
	(segment
		(start 312.960512 -408.759406)
		(end 312.866532 -408.929332)
		(width 0.14224)
		(layer "In6.Cu")
		(net "P5E_CPU0_P1_TX_BUF_DP<0>")
	)
	(segment
		(start 305.898296 -415.09569)
		(end 306.189126 -415.38652)
		(width 0.14224)
		(layer "In6.Cu")
		(net "P5E_CPU0_P1_TX_BUF_DP<0>")
	)
	(segment
		(start 311.87644 -409.07081)
		(end 311.78246 -409.240736)
		(width 0.14224)
		(layer "In6.Cu")
		(net "P5E_CPU0_P1_TX_BUF_DP<0>")
	)
	(segment
		(start 327.81748 -404.136352)
		(end 324.819772 -405.35479)
		(width 0.14224)
		(layer "In6.Cu")
		(net "P5E_CPU0_P1_TX_BUF_DP<0>")
	)
	(segment
		(start 334.597502 -400.207226)
		(end 334.597502 -400.81454)
		(width 0.14224)
		(layer "In6.Cu")
		(net "P5E_CPU0_P1_TX_BUF_DP<0>")
	)
	(segment
		(start 324.819772 -405.35479)
		(end 312.960512 -408.759406)
		(width 0.14224)
		(layer "In6.Cu")
		(net "P5E_CPU0_P1_TX_BUF_DP<0>")
	)
	(segment
		(start 334.952594 -398.89176)
		(end 334.681576 -399.784824)
		(width 0.14224)
		(layer "In6.Cu")
		(net "P5E_CPU0_P1_TX_BUF_DP<0>")
	)
	(segment
		(start 312.456068 -409.047188)
		(end 312.286396 -408.953208)
		(width 0.14224)
		(layer "In6.Cu")
		(net "P5E_CPU0_P1_TX_BUF_DP<0>")
	)
	(segment
		(start 311.202324 -409.264612)
		(end 310.792368 -409.382214)
		(width 0.14224)
		(layer "In6.Cu")
		(net "P5E_CPU0_P1_TX_BUF_DP<0>")
	)
	(arc
		(start 335.753456 -398.068546)
		(mid 335.605695 -398.09792)
		(end 335.480406 -398.181576)
		(width 0.14224)
		(layer "In6.Cu")
		(net "P5E_CPU0_P1_TX_BUF_DP<0>")
	)
	(arc
		(start 306.613052 -411.269434)
		(mid 306.088475 -411.837911)
		(end 305.898296 -412.587694)
		(width 0.14224)
		(layer "In6.Cu")
		(net "P5E_CPU0_P1_TX_BUF_DP<0>")
	)
	(arc
		(start 333.556864 -402.227542)
		(mid 333.480986 -402.28965)
		(end 333.394304 -402.335492)
		(width 0.14224)
		(layer "In6.Cu")
		(net "P5E_CPU0_P1_TX_BUF_DP<0>")
	)
	(arc
		(start 336.196432 -397.948658)
		(mid 336.063712 -398.037402)
		(end 335.907126 -398.068546)
		(width 0.14224)
		(layer "In6.Cu")
		(net "P5E_CPU0_P1_TX_BUF_DP<0>")
	)
	(arc
		(start 308.932834 -409.915868)
		(mid 308.516803 -410.069508)
		(end 308.128162 -410.283152)
		(width 0.14224)
		(layer "In6.Cu")
		(net "P5E_CPU0_P1_TX_BUF_DP<0>")
	)
	(arc
		(start 334.597502 -400.81454)
		(mid 334.529111 -401.158453)
		(end 334.334358 -401.450048)
		(width 0.14224)
		(layer "In6.Cu")
		(net "P5E_CPU0_P1_TX_BUF_DP<0>")
	)
	(segment
		(start 346.597986 -397.156432)
		(end 347.118686 -397.156432)
		(width 0.127)
		(layer "F.Cu")
		(net "P5E_CPU0_P1_TX_BUF_DN<9>")
	)
	(segment
		(start 333.165196 -416.336734)
		(end 333.165196 -415.65703)
		(width 0.12954)
		(layer "B.Cu")
		(net "P5E_CPU0_P1_TX_BUF_DN<9>")
	)
	(segment
		(start 332.869286 -416.632644)
		(end 333.165196 -416.336734)
		(width 0.12954)
		(layer "B.Cu")
		(net "P5E_CPU0_P1_TX_BUF_DN<9>")
	)
	(segment
		(start 333.165196 -415.65703)
		(end 332.894686 -415.38652)
		(width 0.12954)
		(layer "B.Cu")
		(net "P5E_CPU0_P1_TX_BUF_DN<9>")
	)
	(segment
		(start 346.851224 -397.708374)
		(end 346.851224 -397.879316)
		(width 0.14224)
		(layer "In6.Cu")
		(net "P5E_CPU0_P1_TX_BUF_DN<9>")
	)
	(segment
		(start 346.404184 -403.744684)
		(end 343.085674 -407.063194)
		(width 0.14224)
		(layer "In6.Cu")
		(net "P5E_CPU0_P1_TX_BUF_DN<9>")
	)
	(segment
		(start 341.19566 -408.326082)
		(end 338.39277 -409.487116)
		(width 0.14224)
		(layer "In6.Cu")
		(net "P5E_CPU0_P1_TX_BUF_DN<9>")
	)
	(segment
		(start 335.79689 -410.409136)
		(end 334.644238 -411.025594)
		(width 0.14224)
		(layer "In6.Cu")
		(net "P5E_CPU0_P1_TX_BUF_DN<9>")
	)
	(segment
		(start 347.205808 -398.583658)
		(end 347.199712 -398.652746)
		(width 0.14224)
		(layer "In6.Cu")
		(net "P5E_CPU0_P1_TX_BUF_DN<9>")
	)
	(segment
		(start 347.023436 -398.295114)
		(end 347.145102 -398.41678)
		(width 0.14224)
		(layer "In6.Cu")
		(net "P5E_CPU0_P1_TX_BUF_DN<9>")
	)
	(segment
		(start 346.441522 -400.305016)
		(end 346.441522 -403.654768)
		(width 0.14224)
		(layer "In6.Cu")
		(net "P5E_CPU0_P1_TX_BUF_DN<9>")
	)
	(segment
		(start 333.185516 -415.09569)
		(end 332.894686 -415.38652)
		(width 0.14224)
		(layer "In6.Cu")
		(net "P5E_CPU0_P1_TX_BUF_DN<9>")
	)
	(segment
		(start 346.976192 -399.132044)
		(end 346.898976 -399.20926)
		(width 0.14224)
		(layer "In6.Cu")
		(net "P5E_CPU0_P1_TX_BUF_DN<9>")
	)
	(segment
		(start 334.644238 -411.025594)
		(end 333.855314 -411.44698)
		(width 0.14224)
		(layer "In6.Cu")
		(net "P5E_CPU0_P1_TX_BUF_DN<9>")
	)
	(segment
		(start 347.17101 -397.388588)
		(end 346.851224 -397.708374)
		(width 0.14224)
		(layer "In6.Cu")
		(net "P5E_CPU0_P1_TX_BUF_DN<9>")
	)
	(segment
		(start 347.17101 -397.208756)
		(end 347.17101 -397.388588)
		(width 0.14224)
		(layer "In6.Cu")
		(net "P5E_CPU0_P1_TX_BUF_DN<9>")
	)
	(segment
		(start 333.185516 -412.565342)
		(end 333.185516 -415.09569)
		(width 0.14224)
		(layer "In6.Cu")
		(net "P5E_CPU0_P1_TX_BUF_DN<9>")
	)
	(segment
		(start 338.274914 -409.532328)
		(end 335.79689 -410.409136)
		(width 0.14224)
		(layer "In6.Cu")
		(net "P5E_CPU0_P1_TX_BUF_DN<9>")
	)
	(segment
		(start 347.118686 -397.156432)
		(end 347.17101 -397.208756)
		(width 0.14224)
		(layer "In6.Cu")
		(net "P5E_CPU0_P1_TX_BUF_DN<9>")
	)
	(arc
		(start 333.855314 -411.44698)
		(mid 333.365557 -411.913437)
		(end 333.185516 -412.565342)
		(width 0.14224)
		(layer "In6.Cu")
		(net "P5E_CPU0_P1_TX_BUF_DN<9>")
	)
	(arc
		(start 346.441522 -403.654768)
		(mid 346.43182 -403.703452)
		(end 346.404184 -403.744684)
		(width 0.14224)
		(layer "In6.Cu")
		(net "P5E_CPU0_P1_TX_BUF_DN<9>")
	)
	(arc
		(start 347.145102 -398.41678)
		(mid 347.193973 -398.493488)
		(end 347.205808 -398.583658)
		(width 0.14224)
		(layer "In6.Cu")
		(net "P5E_CPU0_P1_TX_BUF_DN<9>")
	)
	(arc
		(start 347.199712 -398.652746)
		(mid 347.130303 -398.912152)
		(end 346.976192 -399.132044)
		(width 0.14224)
		(layer "In6.Cu")
		(net "P5E_CPU0_P1_TX_BUF_DN<9>")
	)
	(arc
		(start 343.085674 -407.063194)
		(mid 342.202859 -407.787716)
		(end 341.19566 -408.326082)
		(width 0.14224)
		(layer "In6.Cu")
		(net "P5E_CPU0_P1_TX_BUF_DN<9>")
	)
	(arc
		(start 338.39277 -409.487116)
		(mid 338.334139 -409.510497)
		(end 338.274914 -409.532328)
		(width 0.14224)
		(layer "In6.Cu")
		(net "P5E_CPU0_P1_TX_BUF_DN<9>")
	)
	(arc
		(start 346.851224 -397.879316)
		(mid 346.895999 -398.104323)
		(end 347.023436 -398.295114)
		(width 0.14224)
		(layer "In6.Cu")
		(net "P5E_CPU0_P1_TX_BUF_DN<9>")
	)
	(arc
		(start 346.898976 -399.20926)
		(mid 346.572502 -399.716324)
		(end 346.441522 -400.305016)
		(width 0.14224)
		(layer "In6.Cu")
		(net "P5E_CPU0_P1_TX_BUF_DN<9>")
	)
	(segment
		(start 345.39809 -397.156432)
		(end 345.91879 -397.156432)
		(width 0.127)
		(layer "F.Cu")
		(net "P5E_CPU0_P1_TX_BUF_DN<8>")
	)
	(segment
		(start 330.101956 -415.65703)
		(end 329.831446 -415.38652)
		(width 0.12954)
		(layer "B.Cu")
		(net "P5E_CPU0_P1_TX_BUF_DN<8>")
	)
	(segment
		(start 330.101956 -416.336734)
		(end 330.101956 -415.65703)
		(width 0.12954)
		(layer "B.Cu")
		(net "P5E_CPU0_P1_TX_BUF_DN<8>")
	)
	(segment
		(start 329.806046 -416.632644)
		(end 330.101956 -416.336734)
		(width 0.12954)
		(layer "B.Cu")
		(net "P5E_CPU0_P1_TX_BUF_DN<8>")
	)
	(segment
		(start 330.122276 -415.09569)
		(end 329.831446 -415.38652)
		(width 0.14224)
		(layer "In6.Cu")
		(net "P5E_CPU0_P1_TX_BUF_DN<8>")
	)
	(segment
		(start 333.784956 -410.214064)
		(end 331.052678 -411.345634)
		(width 0.14224)
		(layer "In6.Cu")
		(net "P5E_CPU0_P1_TX_BUF_DN<8>")
	)
	(segment
		(start 331.052678 -411.345634)
		(end 331.052678 -411.345888)
		(width 0.14224)
		(layer "In6.Cu")
		(net "P5E_CPU0_P1_TX_BUF_DN<8>")
	)
	(segment
		(start 337.79079 -408.704542)
		(end 336.438748 -409.114752)
		(width 0.14224)
		(layer "In6.Cu")
		(net "P5E_CPU0_P1_TX_BUF_DN<8>")
	)
	(segment
		(start 345.652598 -397.707104)
		(end 345.652598 -397.95069)
		(width 0.14224)
		(layer "In6.Cu")
		(net "P5E_CPU0_P1_TX_BUF_DN<8>")
	)
	(segment
		(start 345.782392 -398.264126)
		(end 345.933268 -398.415002)
		(width 0.14224)
		(layer "In6.Cu")
		(net "P5E_CPU0_P1_TX_BUF_DN<8>")
	)
	(segment
		(start 331.052678 -411.345888)
		(end 330.606654 -411.530292)
		(width 0.14224)
		(layer "In6.Cu")
		(net "P5E_CPU0_P1_TX_BUF_DN<8>")
	)
	(segment
		(start 330.606654 -411.530292)
		(end 330.460096 -411.677104)
		(width 0.14224)
		(layer "In6.Cu")
		(net "P5E_CPU0_P1_TX_BUF_DN<8>")
	)
	(segment
		(start 333.78521 -410.21381)
		(end 333.784956 -410.214064)
		(width 0.14224)
		(layer "In6.Cu")
		(net "P5E_CPU0_P1_TX_BUF_DN<8>")
	)
	(segment
		(start 340.892384 -407.420318)
		(end 337.79079 -408.704542)
		(width 0.14224)
		(layer "In6.Cu")
		(net "P5E_CPU0_P1_TX_BUF_DN<8>")
	)
	(segment
		(start 333.78521 -410.214064)
		(end 333.78521 -410.21381)
		(width 0.14224)
		(layer "In6.Cu")
		(net "P5E_CPU0_P1_TX_BUF_DN<8>")
	)
	(segment
		(start 345.336368 -399.888456)
		(end 345.17584 -400.276568)
		(width 0.14224)
		(layer "In6.Cu")
		(net "P5E_CPU0_P1_TX_BUF_DN<8>")
	)
	(segment
		(start 345.971114 -397.388588)
		(end 345.652598 -397.707104)
		(width 0.14224)
		(layer "In6.Cu")
		(net "P5E_CPU0_P1_TX_BUF_DN<8>")
	)
	(segment
		(start 345.91879 -397.156432)
		(end 345.971114 -397.208756)
		(width 0.14224)
		(layer "In6.Cu")
		(net "P5E_CPU0_P1_TX_BUF_DN<8>")
	)
	(segment
		(start 330.122276 -412.492698)
		(end 330.122276 -415.09569)
		(width 0.14224)
		(layer "In6.Cu")
		(net "P5E_CPU0_P1_TX_BUF_DN<8>")
	)
	(segment
		(start 344.793062 -403.876002)
		(end 341.965788 -406.703276)
		(width 0.14224)
		(layer "In6.Cu")
		(net "P5E_CPU0_P1_TX_BUF_DN<8>")
	)
	(segment
		(start 345.995498 -398.680432)
		(end 345.917266 -398.884394)
		(width 0.14224)
		(layer "In6.Cu")
		(net "P5E_CPU0_P1_TX_BUF_DN<8>")
	)
	(segment
		(start 336.438748 -409.114752)
		(end 333.78521 -410.214064)
		(width 0.14224)
		(layer "In6.Cu")
		(net "P5E_CPU0_P1_TX_BUF_DN<8>")
	)
	(segment
		(start 345.971114 -397.208756)
		(end 345.971114 -397.388588)
		(width 0.14224)
		(layer "In6.Cu")
		(net "P5E_CPU0_P1_TX_BUF_DN<8>")
	)
	(segment
		(start 345.17584 -400.276568)
		(end 345.17584 -402.952204)
		(width 0.14224)
		(layer "In6.Cu")
		(net "P5E_CPU0_P1_TX_BUF_DN<8>")
	)
	(arc
		(start 330.460096 -411.677104)
		(mid 330.210065 -412.051302)
		(end 330.122276 -412.492698)
		(width 0.14224)
		(layer "In6.Cu")
		(net "P5E_CPU0_P1_TX_BUF_DN<8>")
	)
	(arc
		(start 345.17584 -402.952204)
		(mid 345.076353 -403.452181)
		(end 344.793062 -403.876002)
		(width 0.14224)
		(layer "In6.Cu")
		(net "P5E_CPU0_P1_TX_BUF_DN<8>")
	)
	(arc
		(start 345.652598 -397.95069)
		(mid 345.686337 -398.120307)
		(end 345.782392 -398.264126)
		(width 0.14224)
		(layer "In6.Cu")
		(net "P5E_CPU0_P1_TX_BUF_DN<8>")
	)
	(arc
		(start 345.917266 -398.884394)
		(mid 345.842207 -399.046214)
		(end 345.745816 -399.196306)
		(width 0.14224)
		(layer "In6.Cu")
		(net "P5E_CPU0_P1_TX_BUF_DN<8>")
	)
	(arc
		(start 346.006928 -398.554194)
		(mid 346.010064 -398.618118)
		(end 345.995498 -398.680432)
		(width 0.14224)
		(layer "In6.Cu")
		(net "P5E_CPU0_P1_TX_BUF_DN<8>")
	)
	(arc
		(start 345.745816 -399.196306)
		(mid 345.52427 -399.529326)
		(end 345.338654 -399.88363)
		(width 0.14224)
		(layer "In6.Cu")
		(net "P5E_CPU0_P1_TX_BUF_DN<8>")
	)
	(arc
		(start 345.338654 -399.88363)
		(mid 345.33751 -399.886043)
		(end 345.336368 -399.888456)
		(width 0.14224)
		(layer "In6.Cu")
		(net "P5E_CPU0_P1_TX_BUF_DN<8>")
	)
	(arc
		(start 341.965788 -406.703276)
		(mid 341.46441 -407.114677)
		(end 340.892384 -407.420318)
		(width 0.14224)
		(layer "In6.Cu")
		(net "P5E_CPU0_P1_TX_BUF_DN<8>")
	)
	(arc
		(start 345.933268 -398.415002)
		(mid 345.980544 -398.47907)
		(end 346.006928 -398.554194)
		(width 0.14224)
		(layer "In6.Cu")
		(net "P5E_CPU0_P1_TX_BUF_DN<8>")
	)
	(segment
		(start 344.198194 -397.156432)
		(end 344.718894 -397.156432)
		(width 0.127)
		(layer "F.Cu")
		(net "P5E_CPU0_P1_TX_BUF_DN<7>")
	)
	(segment
		(start 326.742806 -416.632644)
		(end 327.038716 -416.336734)
		(width 0.12954)
		(layer "B.Cu")
		(net "P5E_CPU0_P1_TX_BUF_DN<7>")
	)
	(segment
		(start 327.038716 -415.65703)
		(end 326.768206 -415.38652)
		(width 0.12954)
		(layer "B.Cu")
		(net "P5E_CPU0_P1_TX_BUF_DN<7>")
	)
	(segment
		(start 327.038716 -416.336734)
		(end 327.038716 -415.65703)
		(width 0.12954)
		(layer "B.Cu")
		(net "P5E_CPU0_P1_TX_BUF_DN<7>")
	)
	(segment
		(start 344.813382 -398.558004)
		(end 344.813382 -398.690338)
		(width 0.14224)
		(layer "In6.Cu")
		(net "P5E_CPU0_P1_TX_BUF_DN<7>")
	)
	(segment
		(start 332.488286 -409.646628)
		(end 327.88606 -411.385258)
		(width 0.14224)
		(layer "In6.Cu")
		(net "P5E_CPU0_P1_TX_BUF_DN<7>")
	)
	(segment
		(start 337.583526 -407.781252)
		(end 336.045556 -408.251406)
		(width 0.14224)
		(layer "In6.Cu")
		(net "P5E_CPU0_P1_TX_BUF_DN<7>")
	)
	(segment
		(start 327.059036 -412.460948)
		(end 327.059036 -415.09569)
		(width 0.14224)
		(layer "In6.Cu")
		(net "P5E_CPU0_P1_TX_BUF_DN<7>")
	)
	(segment
		(start 344.579702 -398.269968)
		(end 344.774774 -398.46504)
		(width 0.14224)
		(layer "In6.Cu")
		(net "P5E_CPU0_P1_TX_BUF_DN<7>")
	)
	(segment
		(start 344.771218 -397.208756)
		(end 344.771218 -397.388588)
		(width 0.14224)
		(layer "In6.Cu")
		(net "P5E_CPU0_P1_TX_BUF_DN<7>")
	)
	(segment
		(start 327.535794 -411.576266)
		(end 327.358502 -411.746954)
		(width 0.14224)
		(layer "In6.Cu")
		(net "P5E_CPU0_P1_TX_BUF_DN<7>")
	)
	(segment
		(start 344.459814 -397.699992)
		(end 344.459814 -397.980662)
		(width 0.14224)
		(layer "In6.Cu")
		(net "P5E_CPU0_P1_TX_BUF_DN<7>")
	)
	(segment
		(start 343.793318 -403.501606)
		(end 341.167212 -406.127204)
		(width 0.14224)
		(layer "In6.Cu")
		(net "P5E_CPU0_P1_TX_BUF_DN<7>")
	)
	(segment
		(start 344.718894 -397.156432)
		(end 344.771218 -397.208756)
		(width 0.14224)
		(layer "In6.Cu")
		(net "P5E_CPU0_P1_TX_BUF_DN<7>")
	)
	(segment
		(start 344.771218 -397.388588)
		(end 344.459814 -397.699992)
		(width 0.14224)
		(layer "In6.Cu")
		(net "P5E_CPU0_P1_TX_BUF_DN<7>")
	)
	(segment
		(start 340.50224 -406.57145)
		(end 337.583526 -407.781252)
		(width 0.14224)
		(layer "In6.Cu")
		(net "P5E_CPU0_P1_TX_BUF_DN<7>")
	)
	(segment
		(start 327.88606 -411.385258)
		(end 327.535794 -411.576266)
		(width 0.14224)
		(layer "In6.Cu")
		(net "P5E_CPU0_P1_TX_BUF_DN<7>")
	)
	(segment
		(start 327.059036 -415.09569)
		(end 326.768206 -415.38652)
		(width 0.14224)
		(layer "In6.Cu")
		(net "P5E_CPU0_P1_TX_BUF_DN<7>")
	)
	(segment
		(start 344.609166 -399.183098)
		(end 344.218006 -399.574258)
		(width 0.14224)
		(layer "In6.Cu")
		(net "P5E_CPU0_P1_TX_BUF_DN<7>")
	)
	(segment
		(start 336.045556 -408.251406)
		(end 334.630522 -408.759406)
		(width 0.14224)
		(layer "In6.Cu")
		(net "P5E_CPU0_P1_TX_BUF_DN<7>")
	)
	(segment
		(start 334.630522 -408.759406)
		(end 332.488286 -409.646628)
		(width 0.14224)
		(layer "In6.Cu")
		(net "P5E_CPU0_P1_TX_BUF_DN<7>")
	)
	(segment
		(start 344.035126 -400.015964)
		(end 344.035126 -402.917914)
		(width 0.14224)
		(layer "In6.Cu")
		(net "P5E_CPU0_P1_TX_BUF_DN<7>")
	)
	(segment
		(start 327.358502 -411.746954)
		(end 327.16597 -412.071312)
		(width 0.14224)
		(layer "In6.Cu")
		(net "P5E_CPU0_P1_TX_BUF_DN<7>")
	)
	(arc
		(start 344.035126 -402.917914)
		(mid 343.972289 -403.233819)
		(end 343.793318 -403.501606)
		(width 0.14224)
		(layer "In6.Cu")
		(net "P5E_CPU0_P1_TX_BUF_DN<7>")
	)
	(arc
		(start 341.167212 -406.127204)
		(mid 340.856581 -406.382038)
		(end 340.50224 -406.57145)
		(width 0.14224)
		(layer "In6.Cu")
		(net "P5E_CPU0_P1_TX_BUF_DN<7>")
	)
	(arc
		(start 344.459814 -397.980662)
		(mid 344.490977 -398.13724)
		(end 344.579702 -398.269968)
		(width 0.14224)
		(layer "In6.Cu")
		(net "P5E_CPU0_P1_TX_BUF_DN<7>")
	)
	(arc
		(start 344.813382 -398.690338)
		(mid 344.760313 -398.957045)
		(end 344.609166 -399.183098)
		(width 0.14224)
		(layer "In6.Cu")
		(net "P5E_CPU0_P1_TX_BUF_DN<7>")
	)
	(arc
		(start 344.774774 -398.46504)
		(mid 344.803303 -398.507691)
		(end 344.813382 -398.558004)
		(width 0.14224)
		(layer "In6.Cu")
		(net "P5E_CPU0_P1_TX_BUF_DN<7>")
	)
	(arc
		(start 344.218006 -399.574258)
		(mid 344.082649 -399.776929)
		(end 344.035126 -400.015964)
		(width 0.14224)
		(layer "In6.Cu")
		(net "P5E_CPU0_P1_TX_BUF_DN<7>")
	)
	(arc
		(start 327.16597 -412.071312)
		(mid 327.086249 -412.258925)
		(end 327.059036 -412.460948)
		(width 0.14224)
		(layer "In6.Cu")
		(net "P5E_CPU0_P1_TX_BUF_DN<7>")
	)
	(segment
		(start 342.998044 -397.156432)
		(end 343.518744 -397.156432)
		(width 0.127)
		(layer "F.Cu")
		(net "P5E_CPU0_P1_TX_BUF_DN<6>")
	)
	(segment
		(start 323.679566 -416.632644)
		(end 323.975476 -416.336734)
		(width 0.12954)
		(layer "B.Cu")
		(net "P5E_CPU0_P1_TX_BUF_DN<6>")
	)
	(segment
		(start 323.975476 -416.336734)
		(end 323.975476 -415.65703)
		(width 0.12954)
		(layer "B.Cu")
		(net "P5E_CPU0_P1_TX_BUF_DN<6>")
	)
	(segment
		(start 323.975476 -415.65703)
		(end 323.704966 -415.38652)
		(width 0.12954)
		(layer "B.Cu")
		(net "P5E_CPU0_P1_TX_BUF_DN<6>")
	)
	(segment
		(start 331.705712 -408.939492)
		(end 331.705458 -408.939492)
		(width 0.14224)
		(layer "In6.Cu")
		(net "P5E_CPU0_P1_TX_BUF_DN<6>")
	)
	(segment
		(start 340.10981 -405.724868)
		(end 337.488784 -406.810464)
		(width 0.14224)
		(layer "In6.Cu")
		(net "P5E_CPU0_P1_TX_BUF_DN<6>")
	)
	(segment
		(start 323.995796 -412.350204)
		(end 323.995796 -415.09569)
		(width 0.14224)
		(layer "In6.Cu")
		(net "P5E_CPU0_P1_TX_BUF_DN<6>")
	)
	(segment
		(start 343.571068 -397.208756)
		(end 343.571068 -397.388588)
		(width 0.14224)
		(layer "In6.Cu")
		(net "P5E_CPU0_P1_TX_BUF_DN<6>")
	)
	(segment
		(start 343.411048 -398.303496)
		(end 343.520522 -398.41297)
		(width 0.14224)
		(layer "In6.Cu")
		(net "P5E_CPU0_P1_TX_BUF_DN<6>")
	)
	(segment
		(start 343.559638 -398.803368)
		(end 342.916002 -399.766536)
		(width 0.14224)
		(layer "In6.Cu")
		(net "P5E_CPU0_P1_TX_BUF_DN<6>")
	)
	(segment
		(start 343.571068 -397.388588)
		(end 343.252552 -397.707104)
		(width 0.14224)
		(layer "In6.Cu")
		(net "P5E_CPU0_P1_TX_BUF_DN<6>")
	)
	(segment
		(start 335.212436 -407.50363)
		(end 332.154022 -408.770836)
		(width 0.14224)
		(layer "In6.Cu")
		(net "P5E_CPU0_P1_TX_BUF_DN<6>")
	)
	(segment
		(start 343.518744 -397.156432)
		(end 343.571068 -397.208756)
		(width 0.14224)
		(layer "In6.Cu")
		(net "P5E_CPU0_P1_TX_BUF_DN<6>")
	)
	(segment
		(start 332.154022 -408.770836)
		(end 331.705712 -408.939492)
		(width 0.14224)
		(layer "In6.Cu")
		(net "P5E_CPU0_P1_TX_BUF_DN<6>")
	)
	(segment
		(start 331.705458 -408.939492)
		(end 324.506844 -411.386274)
		(width 0.14224)
		(layer "In6.Cu")
		(net "P5E_CPU0_P1_TX_BUF_DN<6>")
	)
	(segment
		(start 323.995796 -415.09569)
		(end 323.704966 -415.38652)
		(width 0.14224)
		(layer "In6.Cu")
		(net "P5E_CPU0_P1_TX_BUF_DN<6>")
	)
	(segment
		(start 343.252552 -397.707104)
		(end 343.252552 -397.920972)
		(width 0.14224)
		(layer "In6.Cu")
		(net "P5E_CPU0_P1_TX_BUF_DN<6>")
	)
	(segment
		(start 337.488784 -406.810464)
		(end 335.212436 -407.50363)
		(width 0.14224)
		(layer "In6.Cu")
		(net "P5E_CPU0_P1_TX_BUF_DN<6>")
	)
	(segment
		(start 342.57869 -403.353016)
		(end 340.40191 -405.529796)
		(width 0.14224)
		(layer "In6.Cu")
		(net "P5E_CPU0_P1_TX_BUF_DN<6>")
	)
	(segment
		(start 342.810846 -400.1135)
		(end 342.810846 -402.792692)
		(width 0.14224)
		(layer "In6.Cu")
		(net "P5E_CPU0_P1_TX_BUF_DN<6>")
	)
	(arc
		(start 343.252552 -397.920972)
		(mid 343.29375 -398.127997)
		(end 343.411048 -398.303496)
		(width 0.14224)
		(layer "In6.Cu")
		(net "P5E_CPU0_P1_TX_BUF_DN<6>")
	)
	(arc
		(start 343.520522 -398.41297)
		(mid 343.560531 -398.462567)
		(end 343.588848 -398.51965)
		(width 0.14224)
		(layer "In6.Cu")
		(net "P5E_CPU0_P1_TX_BUF_DN<6>")
	)
	(arc
		(start 343.588848 -398.51965)
		(mid 343.607636 -398.601404)
		(end 343.605612 -398.685258)
		(width 0.14224)
		(layer "In6.Cu")
		(net "P5E_CPU0_P1_TX_BUF_DN<6>")
	)
	(arc
		(start 342.810846 -402.792692)
		(mid 342.750507 -403.095947)
		(end 342.57869 -403.353016)
		(width 0.14224)
		(layer "In6.Cu")
		(net "P5E_CPU0_P1_TX_BUF_DN<6>")
	)
	(arc
		(start 324.506844 -411.386274)
		(mid 324.37685 -411.452854)
		(end 324.271894 -411.554422)
		(width 0.14224)
		(layer "In6.Cu")
		(net "P5E_CPU0_P1_TX_BUF_DN<6>")
	)
	(arc
		(start 343.605612 -398.685258)
		(mid 343.589142 -398.746848)
		(end 343.559638 -398.803368)
		(width 0.14224)
		(layer "In6.Cu")
		(net "P5E_CPU0_P1_TX_BUF_DN<6>")
	)
	(arc
		(start 324.271894 -411.554422)
		(mid 324.071422 -411.930659)
		(end 323.995796 -412.350204)
		(width 0.14224)
		(layer "In6.Cu")
		(net "P5E_CPU0_P1_TX_BUF_DN<6>")
	)
	(arc
		(start 340.40191 -405.529796)
		(mid 340.265468 -405.64172)
		(end 340.10981 -405.724868)
		(width 0.14224)
		(layer "In6.Cu")
		(net "P5E_CPU0_P1_TX_BUF_DN<6>")
	)
	(arc
		(start 342.916002 -399.766536)
		(mid 342.837726 -399.932228)
		(end 342.810846 -400.1135)
		(width 0.14224)
		(layer "In6.Cu")
		(net "P5E_CPU0_P1_TX_BUF_DN<6>")
	)
	(segment
		(start 341.798148 -397.156432)
		(end 342.318848 -397.156432)
		(width 0.127)
		(layer "F.Cu")
		(net "P5E_CPU0_P1_TX_BUF_DN<5>")
	)
	(segment
		(start 320.616326 -416.632644)
		(end 320.912236 -416.336734)
		(width 0.12954)
		(layer "B.Cu")
		(net "P5E_CPU0_P1_TX_BUF_DN<5>")
	)
	(segment
		(start 320.912236 -415.65703)
		(end 320.641726 -415.38652)
		(width 0.12954)
		(layer "B.Cu")
		(net "P5E_CPU0_P1_TX_BUF_DN<5>")
	)
	(segment
		(start 320.912236 -416.336734)
		(end 320.912236 -415.65703)
		(width 0.12954)
		(layer "B.Cu")
		(net "P5E_CPU0_P1_TX_BUF_DN<5>")
	)
	(segment
		(start 342.053672 -399.348452)
		(end 341.838788 -399.563336)
		(width 0.14224)
		(layer "In6.Cu")
		(net "P5E_CPU0_P1_TX_BUF_DN<5>")
	)
	(segment
		(start 341.516462 -403.030436)
		(end 339.683598 -404.8633)
		(width 0.14224)
		(layer "In6.Cu")
		(net "P5E_CPU0_P1_TX_BUF_DN<5>")
	)
	(segment
		(start 342.388444 -398.761966)
		(end 342.128856 -399.247106)
		(width 0.14224)
		(layer "In6.Cu")
		(net "P5E_CPU0_P1_TX_BUF_DN<5>")
	)
	(segment
		(start 333.707486 -407.021284)
		(end 331.01153 -408.108404)
		(width 0.14224)
		(layer "In6.Cu")
		(net "P5E_CPU0_P1_TX_BUF_DN<5>")
	)
	(segment
		(start 324.508876 -410.24302)
		(end 323.97192 -410.4132)
		(width 0.14224)
		(layer "In6.Cu")
		(net "P5E_CPU0_P1_TX_BUF_DN<5>")
	)
	(segment
		(start 320.932556 -415.09569)
		(end 320.641726 -415.38652)
		(width 0.14224)
		(layer "In6.Cu")
		(net "P5E_CPU0_P1_TX_BUF_DN<5>")
	)
	(segment
		(start 327.597262 -409.26893)
		(end 325.045832 -410.077666)
		(width 0.14224)
		(layer "In6.Cu")
		(net "P5E_CPU0_P1_TX_BUF_DN<5>")
	)
	(segment
		(start 337.4898 -405.800306)
		(end 337.485482 -405.801576)
		(width 0.14224)
		(layer "In6.Cu")
		(net "P5E_CPU0_P1_TX_BUF_DN<5>")
	)
	(segment
		(start 337.48472 -405.801576)
		(end 337.483958 -405.80183)
		(width 0.14224)
		(layer "In6.Cu")
		(net "P5E_CPU0_P1_TX_BUF_DN<5>")
	)
	(segment
		(start 336.961226 -405.964898)
		(end 336.670904 -406.084532)
		(width 0.14224)
		(layer "In6.Cu")
		(net "P5E_CPU0_P1_TX_BUF_DN<5>")
	)
	(segment
		(start 342.365584 -397.203168)
		(end 342.365584 -397.44015)
		(width 0.14224)
		(layer "In6.Cu")
		(net "P5E_CPU0_P1_TX_BUF_DN<5>")
	)
	(segment
		(start 321.447414 -411.456886)
		(end 321.327018 -411.577282)
		(width 0.14224)
		(layer "In6.Cu")
		(net "P5E_CPU0_P1_TX_BUF_DN<5>")
	)
	(segment
		(start 325.045832 -410.077666)
		(end 325.039736 -410.07411)
		(width 0.14224)
		(layer "In6.Cu")
		(net "P5E_CPU0_P1_TX_BUF_DN<5>")
	)
	(segment
		(start 323.97192 -410.4132)
		(end 323.971666 -410.412946)
		(width 0.14224)
		(layer "In6.Cu")
		(net "P5E_CPU0_P1_TX_BUF_DN<5>")
	)
	(segment
		(start 342.318848 -397.156432)
		(end 342.365584 -397.203168)
		(width 0.14224)
		(layer "In6.Cu")
		(net "P5E_CPU0_P1_TX_BUF_DN<5>")
	)
	(segment
		(start 342.052656 -397.753078)
		(end 342.052656 -397.956278)
		(width 0.14224)
		(layer "In6.Cu")
		(net "P5E_CPU0_P1_TX_BUF_DN<5>")
	)
	(segment
		(start 341.614506 -400.104864)
		(end 341.614506 -402.793708)
		(width 0.14224)
		(layer "In6.Cu")
		(net "P5E_CPU0_P1_TX_BUF_DN<5>")
	)
	(segment
		(start 325.039736 -410.07411)
		(end 324.508876 -410.242766)
		(width 0.14224)
		(layer "In6.Cu")
		(net "P5E_CPU0_P1_TX_BUF_DN<5>")
	)
	(segment
		(start 337.485482 -405.801576)
		(end 337.48472 -405.801576)
		(width 0.14224)
		(layer "In6.Cu")
		(net "P5E_CPU0_P1_TX_BUF_DN<5>")
	)
	(segment
		(start 336.670904 -406.084532)
		(end 334.421734 -406.769316)
		(width 0.14224)
		(layer "In6.Cu")
		(net "P5E_CPU0_P1_TX_BUF_DN<5>")
	)
	(segment
		(start 339.570314 -404.938992)
		(end 337.491832 -405.799544)
		(width 0.14224)
		(layer "In6.Cu")
		(net "P5E_CPU0_P1_TX_BUF_DN<5>")
	)
	(segment
		(start 331.01153 -408.108404)
		(end 327.597262 -409.26893)
		(width 0.14224)
		(layer "In6.Cu")
		(net "P5E_CPU0_P1_TX_BUF_DN<5>")
	)
	(segment
		(start 323.971666 -410.412946)
		(end 322.284344 -410.94787)
		(width 0.14224)
		(layer "In6.Cu")
		(net "P5E_CPU0_P1_TX_BUF_DN<5>")
	)
	(segment
		(start 337.483958 -405.80183)
		(end 336.961226 -405.964898)
		(width 0.14224)
		(layer "In6.Cu")
		(net "P5E_CPU0_P1_TX_BUF_DN<5>")
	)
	(segment
		(start 337.491832 -405.799544)
		(end 337.4898 -405.800306)
		(width 0.14224)
		(layer "In6.Cu")
		(net "P5E_CPU0_P1_TX_BUF_DN<5>")
	)
	(segment
		(start 320.932556 -412.529528)
		(end 320.932556 -415.09569)
		(width 0.14224)
		(layer "In6.Cu")
		(net "P5E_CPU0_P1_TX_BUF_DN<5>")
	)
	(segment
		(start 342.365584 -397.44015)
		(end 342.052656 -397.753078)
		(width 0.14224)
		(layer "In6.Cu")
		(net "P5E_CPU0_P1_TX_BUF_DN<5>")
	)
	(segment
		(start 324.508876 -410.242766)
		(end 324.508876 -410.24302)
		(width 0.14224)
		(layer "In6.Cu")
		(net "P5E_CPU0_P1_TX_BUF_DN<5>")
	)
	(segment
		(start 342.172544 -398.245584)
		(end 342.208612 -398.281652)
		(width 0.14224)
		(layer "In6.Cu")
		(net "P5E_CPU0_P1_TX_BUF_DN<5>")
	)
	(arc
		(start 322.284344 -410.94787)
		(mid 321.835353 -411.152179)
		(end 321.447414 -411.456886)
		(width 0.14224)
		(layer "In6.Cu")
		(net "P5E_CPU0_P1_TX_BUF_DN<5>")
	)
	(arc
		(start 341.838788 -399.563336)
		(mid 341.672776 -399.811791)
		(end 341.614506 -400.104864)
		(width 0.14224)
		(layer "In6.Cu")
		(net "P5E_CPU0_P1_TX_BUF_DN<5>")
	)
	(arc
		(start 321.327018 -411.577282)
		(mid 321.035095 -412.014176)
		(end 320.932556 -412.529528)
		(width 0.14224)
		(layer "In6.Cu")
		(net "P5E_CPU0_P1_TX_BUF_DN<5>")
	)
	(arc
		(start 342.391492 -398.53616)
		(mid 342.417433 -398.649437)
		(end 342.388444 -398.761966)
		(width 0.14224)
		(layer "In6.Cu")
		(net "P5E_CPU0_P1_TX_BUF_DN<5>")
	)
	(arc
		(start 342.208612 -398.281652)
		(mid 342.310372 -398.401492)
		(end 342.391492 -398.53616)
		(width 0.14224)
		(layer "In6.Cu")
		(net "P5E_CPU0_P1_TX_BUF_DN<5>")
	)
	(arc
		(start 342.128856 -399.247106)
		(mid 342.095 -399.30055)
		(end 342.053672 -399.348452)
		(width 0.14224)
		(layer "In6.Cu")
		(net "P5E_CPU0_P1_TX_BUF_DN<5>")
	)
	(arc
		(start 334.421734 -406.769316)
		(mid 334.061827 -406.887411)
		(end 333.707486 -407.021284)
		(width 0.14224)
		(layer "In6.Cu")
		(net "P5E_CPU0_P1_TX_BUF_DN<5>")
	)
	(arc
		(start 341.614506 -402.793708)
		(mid 341.589023 -402.92182)
		(end 341.516462 -403.030436)
		(width 0.14224)
		(layer "In6.Cu")
		(net "P5E_CPU0_P1_TX_BUF_DN<5>")
	)
	(arc
		(start 342.052656 -397.956278)
		(mid 342.083819 -398.112856)
		(end 342.172544 -398.245584)
		(width 0.14224)
		(layer "In6.Cu")
		(net "P5E_CPU0_P1_TX_BUF_DN<5>")
	)
	(arc
		(start 339.683598 -404.8633)
		(mid 339.630699 -404.906753)
		(end 339.570314 -404.938992)
		(width 0.14224)
		(layer "In6.Cu")
		(net "P5E_CPU0_P1_TX_BUF_DN<5>")
	)
	(segment
		(start 340.597998 -397.156432)
		(end 341.118698 -397.156432)
		(width 0.127)
		(layer "F.Cu")
		(net "P5E_CPU0_P1_TX_BUF_DN<4>")
	)
	(segment
		(start 317.848996 -415.65703)
		(end 317.578486 -415.38652)
		(width 0.12954)
		(layer "B.Cu")
		(net "P5E_CPU0_P1_TX_BUF_DN<4>")
	)
	(segment
		(start 317.553086 -416.632644)
		(end 317.848996 -416.336734)
		(width 0.12954)
		(layer "B.Cu")
		(net "P5E_CPU0_P1_TX_BUF_DN<4>")
	)
	(segment
		(start 317.848996 -416.336734)
		(end 317.848996 -415.65703)
		(width 0.12954)
		(layer "B.Cu")
		(net "P5E_CPU0_P1_TX_BUF_DN<4>")
	)
	(segment
		(start 331.854302 -406.75179)
		(end 321.512692 -410.114496)
		(width 0.14224)
		(layer "In6.Cu")
		(net "P5E_CPU0_P1_TX_BUF_DN<4>")
	)
	(segment
		(start 321.512438 -410.113988)
		(end 318.81191 -410.99232)
		(width 0.14224)
		(layer "In6.Cu")
		(net "P5E_CPU0_P1_TX_BUF_DN<4>")
	)
	(segment
		(start 340.852506 -397.707104)
		(end 340.852506 -397.890746)
		(width 0.14224)
		(layer "In6.Cu")
		(net "P5E_CPU0_P1_TX_BUF_DN<4>")
	)
	(segment
		(start 337.178904 -404.919942)
		(end 335.2673 -405.499824)
		(width 0.14224)
		(layer "In6.Cu")
		(net "P5E_CPU0_P1_TX_BUF_DN<4>")
	)
	(segment
		(start 318.812164 -410.992574)
		(end 318.541146 -411.080458)
		(width 0.14224)
		(layer "In6.Cu")
		(net "P5E_CPU0_P1_TX_BUF_DN<4>")
	)
	(segment
		(start 317.869316 -415.09569)
		(end 317.578486 -415.38652)
		(width 0.14224)
		(layer "In6.Cu")
		(net "P5E_CPU0_P1_TX_BUF_DN<4>")
	)
	(segment
		(start 340.354666 -402.825712)
		(end 339.199982 -403.980396)
		(width 0.14224)
		(layer "In6.Cu")
		(net "P5E_CPU0_P1_TX_BUF_DN<4>")
	)
	(segment
		(start 341.032338 -398.324832)
		(end 341.156798 -398.449292)
		(width 0.14224)
		(layer "In6.Cu")
		(net "P5E_CPU0_P1_TX_BUF_DN<4>")
	)
	(segment
		(start 341.204042 -398.563338)
		(end 341.204042 -398.812004)
		(width 0.14224)
		(layer "In6.Cu")
		(net "P5E_CPU0_P1_TX_BUF_DN<4>")
	)
	(segment
		(start 333.754222 -405.99741)
		(end 331.854302 -406.75179)
		(width 0.14224)
		(layer "In6.Cu")
		(net "P5E_CPU0_P1_TX_BUF_DN<4>")
	)
	(segment
		(start 334.696054 -405.710644)
		(end 333.754222 -405.99741)
		(width 0.14224)
		(layer "In6.Cu")
		(net "P5E_CPU0_P1_TX_BUF_DN<4>")
	)
	(segment
		(start 341.171022 -397.388588)
		(end 340.852506 -397.707104)
		(width 0.14224)
		(layer "In6.Cu")
		(net "P5E_CPU0_P1_TX_BUF_DN<4>")
	)
	(segment
		(start 317.869316 -412.12643)
		(end 317.869316 -415.09569)
		(width 0.14224)
		(layer "In6.Cu")
		(net "P5E_CPU0_P1_TX_BUF_DN<4>")
	)
	(segment
		(start 341.171022 -397.208756)
		(end 341.171022 -397.388588)
		(width 0.14224)
		(layer "In6.Cu")
		(net "P5E_CPU0_P1_TX_BUF_DN<4>")
	)
	(segment
		(start 335.2673 -405.499824)
		(end 334.696054 -405.710644)
		(width 0.14224)
		(layer "In6.Cu")
		(net "P5E_CPU0_P1_TX_BUF_DN<4>")
	)
	(segment
		(start 341.156798 -398.92605)
		(end 340.801198 -399.28165)
		(width 0.14224)
		(layer "In6.Cu")
		(net "P5E_CPU0_P1_TX_BUF_DN<4>")
	)
	(segment
		(start 338.796122 -404.250144)
		(end 337.178904 -404.919942)
		(width 0.14224)
		(layer "In6.Cu")
		(net "P5E_CPU0_P1_TX_BUF_DN<4>")
	)
	(segment
		(start 341.118698 -397.156432)
		(end 341.171022 -397.208756)
		(width 0.14224)
		(layer "In6.Cu")
		(net "P5E_CPU0_P1_TX_BUF_DN<4>")
	)
	(segment
		(start 318.81191 -410.99232)
		(end 318.812164 -410.992574)
		(width 0.14224)
		(layer "In6.Cu")
		(net "P5E_CPU0_P1_TX_BUF_DN<4>")
	)
	(segment
		(start 340.435438 -400.164554)
		(end 340.435438 -402.630894)
		(width 0.14224)
		(layer "In6.Cu")
		(net "P5E_CPU0_P1_TX_BUF_DN<4>")
	)
	(segment
		(start 321.512692 -410.114496)
		(end 321.512438 -410.113988)
		(width 0.14224)
		(layer "In6.Cu")
		(net "P5E_CPU0_P1_TX_BUF_DN<4>")
	)
	(arc
		(start 340.801198 -399.28165)
		(mid 340.530479 -399.686716)
		(end 340.435438 -400.164554)
		(width 0.14224)
		(layer "In6.Cu")
		(net "P5E_CPU0_P1_TX_BUF_DN<4>")
	)
	(arc
		(start 341.204042 -398.812004)
		(mid 341.191765 -398.873727)
		(end 341.156798 -398.92605)
		(width 0.14224)
		(layer "In6.Cu")
		(net "P5E_CPU0_P1_TX_BUF_DN<4>")
	)
	(arc
		(start 318.541146 -411.080458)
		(mid 318.320102 -411.189811)
		(end 318.139572 -411.357826)
		(width 0.14224)
		(layer "In6.Cu")
		(net "P5E_CPU0_P1_TX_BUF_DN<4>")
	)
	(arc
		(start 339.199982 -403.980396)
		(mid 339.011323 -404.135133)
		(end 338.796122 -404.250144)
		(width 0.14224)
		(layer "In6.Cu")
		(net "P5E_CPU0_P1_TX_BUF_DN<4>")
	)
	(arc
		(start 341.156798 -398.449292)
		(mid 341.19176 -398.501617)
		(end 341.204042 -398.563338)
		(width 0.14224)
		(layer "In6.Cu")
		(net "P5E_CPU0_P1_TX_BUF_DN<4>")
	)
	(arc
		(start 318.139572 -411.357826)
		(mid 317.938844 -411.719057)
		(end 317.869316 -412.12643)
		(width 0.14224)
		(layer "In6.Cu")
		(net "P5E_CPU0_P1_TX_BUF_DN<4>")
	)
	(arc
		(start 340.435438 -402.630894)
		(mid 340.414445 -402.736343)
		(end 340.354666 -402.825712)
		(width 0.14224)
		(layer "In6.Cu")
		(net "P5E_CPU0_P1_TX_BUF_DN<4>")
	)
	(arc
		(start 340.852506 -397.890746)
		(mid 340.899238 -398.125682)
		(end 341.032338 -398.324832)
		(width 0.14224)
		(layer "In6.Cu")
		(net "P5E_CPU0_P1_TX_BUF_DN<4>")
	)
	(segment
		(start 339.398102 -397.156432)
		(end 339.918802 -397.156432)
		(width 0.127)
		(layer "F.Cu")
		(net "P5E_CPU0_P1_TX_BUF_DN<3>")
	)
	(segment
		(start 314.489846 -416.632644)
		(end 314.785756 -416.336734)
		(width 0.12954)
		(layer "B.Cu")
		(net "P5E_CPU0_P1_TX_BUF_DN<3>")
	)
	(segment
		(start 314.785756 -416.336734)
		(end 314.785756 -415.65703)
		(width 0.12954)
		(layer "B.Cu")
		(net "P5E_CPU0_P1_TX_BUF_DN<3>")
	)
	(segment
		(start 314.785756 -415.65703)
		(end 314.515246 -415.38652)
		(width 0.12954)
		(layer "B.Cu")
		(net "P5E_CPU0_P1_TX_BUF_DN<3>")
	)
	(segment
		(start 339.65261 -397.707104)
		(end 339.65261 -397.974058)
		(width 0.14224)
		(layer "In6.Cu")
		(net "P5E_CPU0_P1_TX_BUF_DN<3>")
	)
	(segment
		(start 339.971126 -397.208756)
		(end 339.971126 -397.388588)
		(width 0.14224)
		(layer "In6.Cu")
		(net "P5E_CPU0_P1_TX_BUF_DN<3>")
	)
	(segment
		(start 339.681058 -399.216626)
		(end 339.487764 -399.40992)
		(width 0.14224)
		(layer "In6.Cu")
		(net "P5E_CPU0_P1_TX_BUF_DN<3>")
	)
	(segment
		(start 339.239098 -400.010376)
		(end 339.239098 -402.550884)
		(width 0.14224)
		(layer "In6.Cu")
		(net "P5E_CPU0_P1_TX_BUF_DN<3>")
	)
	(segment
		(start 339.772498 -398.263364)
		(end 339.974936 -398.465802)
		(width 0.14224)
		(layer "In6.Cu")
		(net "P5E_CPU0_P1_TX_BUF_DN<3>")
	)
	(segment
		(start 314.806076 -415.09569)
		(end 314.515246 -415.38652)
		(width 0.14224)
		(layer "In6.Cu")
		(net "P5E_CPU0_P1_TX_BUF_DN<3>")
	)
	(segment
		(start 314.806076 -412.566104)
		(end 314.806076 -415.09569)
		(width 0.14224)
		(layer "In6.Cu")
		(net "P5E_CPU0_P1_TX_BUF_DN<3>")
	)
	(segment
		(start 315.58357 -411.237176)
		(end 315.195966 -411.62478)
		(width 0.14224)
		(layer "In6.Cu")
		(net "P5E_CPU0_P1_TX_BUF_DN<3>")
	)
	(segment
		(start 337.106006 -403.940772)
		(end 333.995268 -404.890478)
		(width 0.14224)
		(layer "In6.Cu")
		(net "P5E_CPU0_P1_TX_BUF_DN<3>")
	)
	(segment
		(start 339.971126 -397.388588)
		(end 339.65261 -397.707104)
		(width 0.14224)
		(layer "In6.Cu")
		(net "P5E_CPU0_P1_TX_BUF_DN<3>")
	)
	(segment
		(start 317.839852 -410.097732)
		(end 317.163958 -410.379926)
		(width 0.14224)
		(layer "In6.Cu")
		(net "P5E_CPU0_P1_TX_BUF_DN<3>")
	)
	(segment
		(start 332.814422 -405.359362)
		(end 326.096122 -407.596594)
		(width 0.14224)
		(layer "In6.Cu")
		(net "P5E_CPU0_P1_TX_BUF_DN<3>")
	)
	(segment
		(start 340.01329 -398.558258)
		(end 340.01329 -398.60093)
		(width 0.14224)
		(layer "In6.Cu")
		(net "P5E_CPU0_P1_TX_BUF_DN<3>")
	)
	(segment
		(start 326.096122 -407.596594)
		(end 317.839852 -410.097732)
		(width 0.14224)
		(layer "In6.Cu")
		(net "P5E_CPU0_P1_TX_BUF_DN<3>")
	)
	(segment
		(start 339.918802 -397.156432)
		(end 339.971126 -397.208756)
		(width 0.14224)
		(layer "In6.Cu")
		(net "P5E_CPU0_P1_TX_BUF_DN<3>")
	)
	(segment
		(start 339.20176 -402.6408)
		(end 338.581238 -403.261322)
		(width 0.14224)
		(layer "In6.Cu")
		(net "P5E_CPU0_P1_TX_BUF_DN<3>")
	)
	(segment
		(start 338.313522 -403.440138)
		(end 337.106006 -403.940772)
		(width 0.14224)
		(layer "In6.Cu")
		(net "P5E_CPU0_P1_TX_BUF_DN<3>")
	)
	(segment
		(start 333.995268 -404.890478)
		(end 332.814422 -405.359362)
		(width 0.14224)
		(layer "In6.Cu")
		(net "P5E_CPU0_P1_TX_BUF_DN<3>")
	)
	(segment
		(start 317.163958 -410.379926)
		(end 315.58357 -411.237176)
		(width 0.14224)
		(layer "In6.Cu")
		(net "P5E_CPU0_P1_TX_BUF_DN<3>")
	)
	(arc
		(start 339.65261 -397.974058)
		(mid 339.683773 -398.130636)
		(end 339.772498 -398.263364)
		(width 0.14224)
		(layer "In6.Cu")
		(net "P5E_CPU0_P1_TX_BUF_DN<3>")
	)
	(arc
		(start 338.581238 -403.261322)
		(mid 338.456184 -403.36391)
		(end 338.313522 -403.440138)
		(width 0.14224)
		(layer "In6.Cu")
		(net "P5E_CPU0_P1_TX_BUF_DN<3>")
	)
	(arc
		(start 339.487764 -399.40992)
		(mid 339.30374 -399.685426)
		(end 339.239098 -400.010376)
		(width 0.14224)
		(layer "In6.Cu")
		(net "P5E_CPU0_P1_TX_BUF_DN<3>")
	)
	(arc
		(start 339.239098 -402.550884)
		(mid 339.229396 -402.599568)
		(end 339.20176 -402.6408)
		(width 0.14224)
		(layer "In6.Cu")
		(net "P5E_CPU0_P1_TX_BUF_DN<3>")
	)
	(arc
		(start 339.8647 -398.912588)
		(mid 339.791381 -399.075786)
		(end 339.681058 -399.216626)
		(width 0.14224)
		(layer "In6.Cu")
		(net "P5E_CPU0_P1_TX_BUF_DN<3>")
	)
	(arc
		(start 340.01329 -398.60093)
		(mid 340.006433 -398.642013)
		(end 339.98662 -398.678654)
		(width 0.14224)
		(layer "In6.Cu")
		(net "P5E_CPU0_P1_TX_BUF_DN<3>")
	)
	(arc
		(start 315.195966 -411.62478)
		(mid 314.907391 -412.056663)
		(end 314.806076 -412.566104)
		(width 0.14224)
		(layer "In6.Cu")
		(net "P5E_CPU0_P1_TX_BUF_DN<3>")
	)
	(arc
		(start 339.98662 -398.678654)
		(mid 339.915169 -398.790153)
		(end 339.8647 -398.912588)
		(width 0.14224)
		(layer "In6.Cu")
		(net "P5E_CPU0_P1_TX_BUF_DN<3>")
	)
	(arc
		(start 339.974936 -398.465802)
		(mid 340.003333 -398.508207)
		(end 340.01329 -398.558258)
		(width 0.14224)
		(layer "In6.Cu")
		(net "P5E_CPU0_P1_TX_BUF_DN<3>")
	)
	(segment
		(start 338.198206 -397.156432)
		(end 338.718906 -397.156432)
		(width 0.127)
		(layer "F.Cu")
		(net "P5E_CPU0_P1_TX_BUF_DN<2>")
	)
	(segment
		(start 311.426606 -416.632644)
		(end 311.722516 -416.336734)
		(width 0.12954)
		(layer "B.Cu")
		(net "P5E_CPU0_P1_TX_BUF_DN<2>")
	)
	(segment
		(start 311.722516 -415.65703)
		(end 311.452006 -415.38652)
		(width 0.12954)
		(layer "B.Cu")
		(net "P5E_CPU0_P1_TX_BUF_DN<2>")
	)
	(segment
		(start 311.722516 -416.336734)
		(end 311.722516 -415.65703)
		(width 0.12954)
		(layer "B.Cu")
		(net "P5E_CPU0_P1_TX_BUF_DN<2>")
	)
	(segment
		(start 338.770214 -397.417544)
		(end 338.454238 -397.73352)
		(width 0.14224)
		(layer "In6.Cu")
		(net "P5E_CPU0_P1_TX_BUF_DN<2>")
	)
	(segment
		(start 338.029042 -399.939764)
		(end 338.029042 -402.439124)
		(width 0.14224)
		(layer "In6.Cu")
		(net "P5E_CPU0_P1_TX_BUF_DN<2>")
	)
	(segment
		(start 311.742836 -415.09569)
		(end 311.452006 -415.38652)
		(width 0.14224)
		(layer "In6.Cu")
		(net "P5E_CPU0_P1_TX_BUF_DN<2>")
	)
	(segment
		(start 338.770214 -397.20774)
		(end 338.770214 -397.417544)
		(width 0.14224)
		(layer "In6.Cu")
		(net "P5E_CPU0_P1_TX_BUF_DN<2>")
	)
	(segment
		(start 312.569606 -411.077664)
		(end 312.261758 -411.385512)
		(width 0.14224)
		(layer "In6.Cu")
		(net "P5E_CPU0_P1_TX_BUF_DN<2>")
	)
	(segment
		(start 311.742836 -412.639256)
		(end 311.742836 -415.09569)
		(width 0.14224)
		(layer "In6.Cu")
		(net "P5E_CPU0_P1_TX_BUF_DN<2>")
	)
	(segment
		(start 313.520074 -410.604462)
		(end 313.097926 -410.74848)
		(width 0.14224)
		(layer "In6.Cu")
		(net "P5E_CPU0_P1_TX_BUF_DN<2>")
	)
	(segment
		(start 313.51982 -410.604208)
		(end 313.520074 -410.604462)
		(width 0.14224)
		(layer "In6.Cu")
		(net "P5E_CPU0_P1_TX_BUF_DN<2>")
	)
	(segment
		(start 338.614766 -398.307306)
		(end 338.688934 -398.381474)
		(width 0.14224)
		(layer "In6.Cu")
		(net "P5E_CPU0_P1_TX_BUF_DN<2>")
	)
	(segment
		(start 325.65975 -406.75433)
		(end 317.306198 -409.285186)
		(width 0.14224)
		(layer "In6.Cu")
		(net "P5E_CPU0_P1_TX_BUF_DN<2>")
	)
	(segment
		(start 317.306198 -409.285186)
		(end 316.961012 -409.429204)
		(width 0.14224)
		(layer "In6.Cu")
		(net "P5E_CPU0_P1_TX_BUF_DN<2>")
	)
	(segment
		(start 336.877152 -403.02434)
		(end 334.10652 -403.865588)
		(width 0.14224)
		(layer "In6.Cu")
		(net "P5E_CPU0_P1_TX_BUF_DN<2>")
	)
	(segment
		(start 338.454238 -397.73352)
		(end 338.454238 -397.919956)
		(width 0.14224)
		(layer "In6.Cu")
		(net "P5E_CPU0_P1_TX_BUF_DN<2>")
	)
	(segment
		(start 337.991704 -402.529294)
		(end 337.951064 -402.569934)
		(width 0.14224)
		(layer "In6.Cu")
		(net "P5E_CPU0_P1_TX_BUF_DN<2>")
	)
	(segment
		(start 337.909662 -402.59762)
		(end 336.877152 -403.02434)
		(width 0.14224)
		(layer "In6.Cu")
		(net "P5E_CPU0_P1_TX_BUF_DN<2>")
	)
	(segment
		(start 338.580476 -399.029174)
		(end 338.21497 -399.39468)
		(width 0.14224)
		(layer "In6.Cu")
		(net "P5E_CPU0_P1_TX_BUF_DN<2>")
	)
	(segment
		(start 316.961012 -409.429204)
		(end 313.51982 -410.604208)
		(width 0.14224)
		(layer "In6.Cu")
		(net "P5E_CPU0_P1_TX_BUF_DN<2>")
	)
	(segment
		(start 338.718906 -397.156432)
		(end 338.770214 -397.20774)
		(width 0.14224)
		(layer "In6.Cu")
		(net "P5E_CPU0_P1_TX_BUF_DN<2>")
	)
	(segment
		(start 331.37729 -404.855172)
		(end 325.65975 -406.75433)
		(width 0.14224)
		(layer "In6.Cu")
		(net "P5E_CPU0_P1_TX_BUF_DN<2>")
	)
	(segment
		(start 332.291944 -404.492968)
		(end 331.37729 -404.855172)
		(width 0.14224)
		(layer "In6.Cu")
		(net "P5E_CPU0_P1_TX_BUF_DN<2>")
	)
	(segment
		(start 338.726272 -398.47139)
		(end 338.726272 -398.677638)
		(width 0.14224)
		(layer "In6.Cu")
		(net "P5E_CPU0_P1_TX_BUF_DN<2>")
	)
	(segment
		(start 334.10652 -403.865588)
		(end 332.291944 -404.492968)
		(width 0.14224)
		(layer "In6.Cu")
		(net "P5E_CPU0_P1_TX_BUF_DN<2>")
	)
	(arc
		(start 338.21497 -399.39468)
		(mid 338.133768 -399.497424)
		(end 338.07908 -399.616422)
		(width 0.14224)
		(layer "In6.Cu")
		(net "P5E_CPU0_P1_TX_BUF_DN<2>")
	)
	(arc
		(start 337.951064 -402.569934)
		(mid 337.931721 -402.585805)
		(end 337.909662 -402.59762)
		(width 0.14224)
		(layer "In6.Cu")
		(net "P5E_CPU0_P1_TX_BUF_DN<2>")
	)
	(arc
		(start 313.097926 -410.74848)
		(mid 312.81485 -410.882718)
		(end 312.569606 -411.077664)
		(width 0.14224)
		(layer "In6.Cu")
		(net "P5E_CPU0_P1_TX_BUF_DN<2>")
	)
	(arc
		(start 338.07908 -399.616422)
		(mid 338.041513 -399.77615)
		(end 338.029042 -399.939764)
		(width 0.14224)
		(layer "In6.Cu")
		(net "P5E_CPU0_P1_TX_BUF_DN<2>")
	)
	(arc
		(start 338.454238 -397.919956)
		(mid 338.495958 -398.129606)
		(end 338.614766 -398.307306)
		(width 0.14224)
		(layer "In6.Cu")
		(net "P5E_CPU0_P1_TX_BUF_DN<2>")
	)
	(arc
		(start 338.726272 -398.677638)
		(mid 338.688385 -398.86793)
		(end 338.580476 -399.029174)
		(width 0.14224)
		(layer "In6.Cu")
		(net "P5E_CPU0_P1_TX_BUF_DN<2>")
	)
	(arc
		(start 312.261758 -411.385512)
		(mid 311.877753 -411.960833)
		(end 311.742836 -412.639256)
		(width 0.14224)
		(layer "In6.Cu")
		(net "P5E_CPU0_P1_TX_BUF_DN<2>")
	)
	(arc
		(start 338.688934 -398.381474)
		(mid 338.716553 -398.422714)
		(end 338.726272 -398.47139)
		(width 0.14224)
		(layer "In6.Cu")
		(net "P5E_CPU0_P1_TX_BUF_DN<2>")
	)
	(arc
		(start 338.029042 -402.439124)
		(mid 338.019336 -402.487919)
		(end 337.991704 -402.529294)
		(width 0.14224)
		(layer "In6.Cu")
		(net "P5E_CPU0_P1_TX_BUF_DN<2>")
	)
	(segment
		(start 336.998056 -397.156432)
		(end 337.518756 -397.156432)
		(width 0.127)
		(layer "F.Cu")
		(net "P5E_CPU0_P1_TX_BUF_DN<1>")
	)
	(segment
		(start 308.363366 -416.632644)
		(end 308.659276 -416.336734)
		(width 0.12954)
		(layer "B.Cu")
		(net "P5E_CPU0_P1_TX_BUF_DN<1>")
	)
	(segment
		(start 308.659276 -415.65703)
		(end 308.388766 -415.38652)
		(width 0.12954)
		(layer "B.Cu")
		(net "P5E_CPU0_P1_TX_BUF_DN<1>")
	)
	(segment
		(start 308.659276 -416.336734)
		(end 308.659276 -415.65703)
		(width 0.12954)
		(layer "B.Cu")
		(net "P5E_CPU0_P1_TX_BUF_DN<1>")
	)
	(segment
		(start 337.57108 -397.388588)
		(end 337.252564 -397.707104)
		(width 0.14224)
		(layer "In6.Cu")
		(net "P5E_CPU0_P1_TX_BUF_DN<1>")
	)
	(segment
		(start 308.679596 -412.566104)
		(end 308.679596 -415.09569)
		(width 0.14224)
		(layer "In6.Cu")
		(net "P5E_CPU0_P1_TX_BUF_DN<1>")
	)
	(segment
		(start 335.4324 -400.280632)
		(end 335.4324 -401.077684)
		(width 0.14224)
		(layer "In6.Cu")
		(net "P5E_CPU0_P1_TX_BUF_DN<1>")
	)
	(segment
		(start 327.659492 -404.90394)
		(end 325.04888 -405.965152)
		(width 0.14224)
		(layer "In6.Cu")
		(net "P5E_CPU0_P1_TX_BUF_DN<1>")
	)
	(segment
		(start 308.679596 -415.09569)
		(end 308.388766 -415.38652)
		(width 0.14224)
		(layer "In6.Cu")
		(net "P5E_CPU0_P1_TX_BUF_DN<1>")
	)
	(segment
		(start 337.518756 -397.156432)
		(end 337.57108 -397.208756)
		(width 0.14224)
		(layer "In6.Cu")
		(net "P5E_CPU0_P1_TX_BUF_DN<1>")
	)
	(segment
		(start 337.53425 -398.741646)
		(end 337.032346 -399.243296)
		(width 0.14224)
		(layer "In6.Cu")
		(net "P5E_CPU0_P1_TX_BUF_DN<1>")
	)
	(segment
		(start 309.381906 -411.052518)
		(end 309.253382 -411.181042)
		(width 0.14224)
		(layer "In6.Cu")
		(net "P5E_CPU0_P1_TX_BUF_DN<1>")
	)
	(segment
		(start 337.252564 -397.707104)
		(end 337.252564 -397.951706)
		(width 0.14224)
		(layer "In6.Cu")
		(net "P5E_CPU0_P1_TX_BUF_DN<1>")
	)
	(segment
		(start 335.290922 -401.41906)
		(end 333.877412 -402.83257)
		(width 0.14224)
		(layer "In6.Cu")
		(net "P5E_CPU0_P1_TX_BUF_DN<1>")
	)
	(segment
		(start 336.687922 -399.386044)
		(end 336.128106 -399.386044)
		(width 0.14224)
		(layer "In6.Cu")
		(net "P5E_CPU0_P1_TX_BUF_DN<1>")
	)
	(segment
		(start 325.04888 -405.965152)
		(end 310.566816 -410.342842)
		(width 0.14224)
		(layer "In6.Cu")
		(net "P5E_CPU0_P1_TX_BUF_DN<1>")
	)
	(segment
		(start 337.57108 -397.208756)
		(end 337.57108 -397.388588)
		(width 0.14224)
		(layer "In6.Cu")
		(net "P5E_CPU0_P1_TX_BUF_DN<1>")
	)
	(segment
		(start 332.3844 -403.47265)
		(end 327.659492 -404.90394)
		(width 0.14224)
		(layer "In6.Cu")
		(net "P5E_CPU0_P1_TX_BUF_DN<1>")
	)
	(segment
		(start 337.382358 -398.265142)
		(end 337.53425 -398.417034)
		(width 0.14224)
		(layer "In6.Cu")
		(net "P5E_CPU0_P1_TX_BUF_DN<1>")
	)
	(segment
		(start 333.791814 -402.88972)
		(end 332.3844 -403.47265)
		(width 0.14224)
		(layer "In6.Cu")
		(net "P5E_CPU0_P1_TX_BUF_DN<1>")
	)
	(arc
		(start 310.566816 -410.342842)
		(mid 309.930535 -410.6245)
		(end 309.381906 -411.052518)
		(width 0.14224)
		(layer "In6.Cu")
		(net "P5E_CPU0_P1_TX_BUF_DN<1>")
	)
	(arc
		(start 337.032346 -399.243296)
		(mid 336.874337 -399.348937)
		(end 336.687922 -399.386044)
		(width 0.14224)
		(layer "In6.Cu")
		(net "P5E_CPU0_P1_TX_BUF_DN<1>")
	)
	(arc
		(start 333.877412 -402.83257)
		(mid 333.83742 -402.865347)
		(end 333.791814 -402.88972)
		(width 0.14224)
		(layer "In6.Cu")
		(net "P5E_CPU0_P1_TX_BUF_DN<1>")
	)
	(arc
		(start 336.128106 -399.386044)
		(mid 335.915588 -399.428071)
		(end 335.735422 -399.54835)
		(width 0.14224)
		(layer "In6.Cu")
		(net "P5E_CPU0_P1_TX_BUF_DN<1>")
	)
	(arc
		(start 335.735422 -399.54835)
		(mid 335.510966 -399.884312)
		(end 335.4324 -400.280632)
		(width 0.14224)
		(layer "In6.Cu")
		(net "P5E_CPU0_P1_TX_BUF_DN<1>")
	)
	(arc
		(start 337.252564 -397.951706)
		(mid 337.286303 -398.121323)
		(end 337.382358 -398.265142)
		(width 0.14224)
		(layer "In6.Cu")
		(net "P5E_CPU0_P1_TX_BUF_DN<1>")
	)
	(arc
		(start 335.4324 -401.077684)
		(mid 335.39563 -401.26245)
		(end 335.290922 -401.41906)
		(width 0.14224)
		(layer "In6.Cu")
		(net "P5E_CPU0_P1_TX_BUF_DN<1>")
	)
	(arc
		(start 309.253382 -411.181042)
		(mid 308.82872 -411.8165)
		(end 308.679596 -412.566104)
		(width 0.14224)
		(layer "In6.Cu")
		(net "P5E_CPU0_P1_TX_BUF_DN<1>")
	)
	(arc
		(start 337.53425 -398.417034)
		(mid 337.601554 -398.57934)
		(end 337.53425 -398.741646)
		(width 0.14224)
		(layer "In6.Cu")
		(net "P5E_CPU0_P1_TX_BUF_DN<1>")
	)
	(segment
		(start 353.798124 -397.156432)
		(end 354.318824 -397.156432)
		(width 0.127)
		(layer "F.Cu")
		(net "P5E_CPU0_P1_TX_BUF_DN<15>")
	)
	(segment
		(start 351.248726 -416.632644)
		(end 351.544636 -416.336734)
		(width 0.12954)
		(layer "B.Cu")
		(net "P5E_CPU0_P1_TX_BUF_DN<15>")
	)
	(segment
		(start 351.544636 -416.336734)
		(end 351.544636 -415.65703)
		(width 0.12954)
		(layer "B.Cu")
		(net "P5E_CPU0_P1_TX_BUF_DN<15>")
	)
	(segment
		(start 351.544636 -415.65703)
		(end 351.274126 -415.38652)
		(width 0.12954)
		(layer "B.Cu")
		(net "P5E_CPU0_P1_TX_BUF_DN<15>")
	)
	(segment
		(start 354.2284 -398.320768)
		(end 354.369116 -398.461484)
		(width 0.14224)
		(layer "In6.Cu")
		(net "P5E_CPU0_P1_TX_BUF_DN<15>")
	)
	(segment
		(start 352.656394 -408.79522)
		(end 352.51517 -409.358338)
		(width 0.14224)
		(layer "In6.Cu")
		(net "P5E_CPU0_P1_TX_BUF_DN<15>")
	)
	(segment
		(start 354.318824 -397.156432)
		(end 354.371148 -397.208756)
		(width 0.14224)
		(layer "In6.Cu")
		(net "P5E_CPU0_P1_TX_BUF_DN<15>")
	)
	(segment
		(start 352.51517 -409.358338)
		(end 352.513392 -409.359354)
		(width 0.14224)
		(layer "In6.Cu")
		(net "P5E_CPU0_P1_TX_BUF_DN<15>")
	)
	(segment
		(start 352.793046 -408.262074)
		(end 352.65995 -408.793188)
		(width 0.14224)
		(layer "In6.Cu")
		(net "P5E_CPU0_P1_TX_BUF_DN<15>")
	)
	(segment
		(start 354.371148 -397.208756)
		(end 354.371148 -397.388588)
		(width 0.14224)
		(layer "In6.Cu")
		(net "P5E_CPU0_P1_TX_BUF_DN<15>")
	)
	(segment
		(start 352.65995 -408.793188)
		(end 352.656394 -408.79522)
		(width 0.14224)
		(layer "In6.Cu")
		(net "P5E_CPU0_P1_TX_BUF_DN<15>")
	)
	(segment
		(start 352.790506 -408.258264)
		(end 352.793046 -408.262074)
		(width 0.14224)
		(layer "In6.Cu")
		(net "P5E_CPU0_P1_TX_BUF_DN<15>")
	)
	(segment
		(start 354.052632 -397.707104)
		(end 354.052632 -397.896334)
		(width 0.14224)
		(layer "In6.Cu")
		(net "P5E_CPU0_P1_TX_BUF_DN<15>")
	)
	(segment
		(start 354.371148 -397.388588)
		(end 354.052632 -397.707104)
		(width 0.14224)
		(layer "In6.Cu")
		(net "P5E_CPU0_P1_TX_BUF_DN<15>")
	)
	(segment
		(start 352.513392 -409.359354)
		(end 351.563178 -413.154368)
		(width 0.14224)
		(layer "In6.Cu")
		(net "P5E_CPU0_P1_TX_BUF_DN<15>")
	)
	(segment
		(start 351.563178 -415.097468)
		(end 351.274126 -415.38652)
		(width 0.14224)
		(layer "In6.Cu")
		(net "P5E_CPU0_P1_TX_BUF_DN<15>")
	)
	(segment
		(start 353.576636 -405.120348)
		(end 352.790506 -408.258264)
		(width 0.14224)
		(layer "In6.Cu")
		(net "P5E_CPU0_P1_TX_BUF_DN<15>")
	)
	(segment
		(start 353.954588 -399.479516)
		(end 353.82454 -399.609564)
		(width 0.14224)
		(layer "In6.Cu")
		(net "P5E_CPU0_P1_TX_BUF_DN<15>")
	)
	(segment
		(start 353.648264 -400.035014)
		(end 353.648264 -404.54072)
		(width 0.14224)
		(layer "In6.Cu")
		(net "P5E_CPU0_P1_TX_BUF_DN<15>")
	)
	(segment
		(start 351.563178 -413.154368)
		(end 351.563178 -415.097468)
		(width 0.14224)
		(layer "In6.Cu")
		(net "P5E_CPU0_P1_TX_BUF_DN<15>")
	)
	(arc
		(start 354.34651 -398.72412)
		(mid 354.223364 -398.896311)
		(end 354.155248 -399.096738)
		(width 0.14224)
		(layer "In6.Cu")
		(net "P5E_CPU0_P1_TX_BUF_DN<15>")
	)
	(arc
		(start 354.412296 -398.580864)
		(mid 354.391572 -398.658079)
		(end 354.34651 -398.72412)
		(width 0.14224)
		(layer "In6.Cu")
		(net "P5E_CPU0_P1_TX_BUF_DN<15>")
	)
	(arc
		(start 354.369116 -398.461484)
		(mid 354.40407 -398.516337)
		(end 354.412296 -398.580864)
		(width 0.14224)
		(layer "In6.Cu")
		(net "P5E_CPU0_P1_TX_BUF_DN<15>")
	)
	(arc
		(start 354.155248 -399.096738)
		(mid 354.084132 -399.303446)
		(end 353.954588 -399.479516)
		(width 0.14224)
		(layer "In6.Cu")
		(net "P5E_CPU0_P1_TX_BUF_DN<15>")
	)
	(arc
		(start 354.052632 -397.896334)
		(mid 354.098305 -398.126036)
		(end 354.2284 -398.320768)
		(width 0.14224)
		(layer "In6.Cu")
		(net "P5E_CPU0_P1_TX_BUF_DN<15>")
	)
	(arc
		(start 353.648264 -404.54072)
		(mid 353.630259 -404.832735)
		(end 353.576636 -405.120348)
		(width 0.14224)
		(layer "In6.Cu")
		(net "P5E_CPU0_P1_TX_BUF_DN<15>")
	)
	(arc
		(start 353.82454 -399.609564)
		(mid 353.694059 -399.804748)
		(end 353.648264 -400.035014)
		(width 0.14224)
		(layer "In6.Cu")
		(net "P5E_CPU0_P1_TX_BUF_DN<15>")
	)
	(segment
		(start 352.598228 -397.156432)
		(end 353.118928 -397.156432)
		(width 0.127)
		(layer "F.Cu")
		(net "P5E_CPU0_P1_TX_BUF_DN<14>")
	)
	(segment
		(start 348.185486 -416.632644)
		(end 348.481396 -416.336734)
		(width 0.12954)
		(layer "B.Cu")
		(net "P5E_CPU0_P1_TX_BUF_DN<14>")
	)
	(segment
		(start 348.481396 -415.65703)
		(end 348.210886 -415.38652)
		(width 0.12954)
		(layer "B.Cu")
		(net "P5E_CPU0_P1_TX_BUF_DN<14>")
	)
	(segment
		(start 348.481396 -416.336734)
		(end 348.481396 -415.65703)
		(width 0.12954)
		(layer "B.Cu")
		(net "P5E_CPU0_P1_TX_BUF_DN<14>")
	)
	(segment
		(start 353.145344 -398.705324)
		(end 353.135184 -398.715484)
		(width 0.14224)
		(layer "In6.Cu")
		(net "P5E_CPU0_P1_TX_BUF_DN<14>")
	)
	(segment
		(start 353.171252 -397.208756)
		(end 353.171252 -397.388588)
		(width 0.14224)
		(layer "In6.Cu")
		(net "P5E_CPU0_P1_TX_BUF_DN<14>")
	)
	(segment
		(start 348.501716 -412.599124)
		(end 348.501716 -415.09569)
		(width 0.14224)
		(layer "In6.Cu")
		(net "P5E_CPU0_P1_TX_BUF_DN<14>")
	)
	(segment
		(start 352.972624 -398.254728)
		(end 353.145344 -398.427194)
		(width 0.14224)
		(layer "In6.Cu")
		(net "P5E_CPU0_P1_TX_BUF_DN<14>")
	)
	(segment
		(start 352.771202 -399.439638)
		(end 352.6536 -399.55724)
		(width 0.14224)
		(layer "In6.Cu")
		(net "P5E_CPU0_P1_TX_BUF_DN<14>")
	)
	(segment
		(start 350.414844 -408.551126)
		(end 348.501716 -412.599124)
		(width 0.14224)
		(layer "In6.Cu")
		(net "P5E_CPU0_P1_TX_BUF_DN<14>")
	)
	(segment
		(start 348.501716 -415.09569)
		(end 348.210886 -415.38652)
		(width 0.14224)
		(layer "In6.Cu")
		(net "P5E_CPU0_P1_TX_BUF_DN<14>")
	)
	(segment
		(start 353.118928 -397.156432)
		(end 353.171252 -397.208756)
		(width 0.14224)
		(layer "In6.Cu")
		(net "P5E_CPU0_P1_TX_BUF_DN<14>")
	)
	(segment
		(start 352.852736 -397.707104)
		(end 352.852736 -397.965422)
		(width 0.14224)
		(layer "In6.Cu")
		(net "P5E_CPU0_P1_TX_BUF_DN<14>")
	)
	(segment
		(start 350.417638 -408.55011)
		(end 350.414844 -408.551126)
		(width 0.14224)
		(layer "In6.Cu")
		(net "P5E_CPU0_P1_TX_BUF_DN<14>")
	)
	(segment
		(start 351.827846 -405.56688)
		(end 350.417638 -408.55011)
		(width 0.14224)
		(layer "In6.Cu")
		(net "P5E_CPU0_P1_TX_BUF_DN<14>")
	)
	(segment
		(start 353.171252 -397.388588)
		(end 352.852736 -397.707104)
		(width 0.14224)
		(layer "In6.Cu")
		(net "P5E_CPU0_P1_TX_BUF_DN<14>")
	)
	(segment
		(start 352.448114 -400.053302)
		(end 352.448114 -403.805136)
		(width 0.14224)
		(layer "In6.Cu")
		(net "P5E_CPU0_P1_TX_BUF_DN<14>")
	)
	(arc
		(start 352.6536 -399.55724)
		(mid 352.501526 -399.784835)
		(end 352.448114 -400.053302)
		(width 0.14224)
		(layer "In6.Cu")
		(net "P5E_CPU0_P1_TX_BUF_DN<14>")
	)
	(arc
		(start 353.135184 -398.715484)
		(mid 352.972426 -398.941021)
		(end 352.88855 -399.206212)
		(width 0.14224)
		(layer "In6.Cu")
		(net "P5E_CPU0_P1_TX_BUF_DN<14>")
	)
	(arc
		(start 352.852736 -397.965422)
		(mid 352.883899 -398.122)
		(end 352.972624 -398.254728)
		(width 0.14224)
		(layer "In6.Cu")
		(net "P5E_CPU0_P1_TX_BUF_DN<14>")
	)
	(arc
		(start 352.448114 -403.805136)
		(mid 352.288504 -404.738998)
		(end 351.827846 -405.56688)
		(width 0.14224)
		(layer "In6.Cu")
		(net "P5E_CPU0_P1_TX_BUF_DN<14>")
	)
	(arc
		(start 352.88855 -399.206212)
		(mid 352.84871 -399.332397)
		(end 352.771202 -399.439638)
		(width 0.14224)
		(layer "In6.Cu")
		(net "P5E_CPU0_P1_TX_BUF_DN<14>")
	)
	(arc
		(start 353.145344 -398.427194)
		(mid 353.203074 -398.566296)
		(end 353.145344 -398.705324)
		(width 0.14224)
		(layer "In6.Cu")
		(net "P5E_CPU0_P1_TX_BUF_DN<14>")
	)
	(segment
		(start 351.398078 -397.156432)
		(end 351.918778 -397.156432)
		(width 0.127)
		(layer "F.Cu")
		(net "P5E_CPU0_P1_TX_BUF_DN<13>")
	)
	(segment
		(start 345.418156 -416.336734)
		(end 345.418156 -415.65703)
		(width 0.12954)
		(layer "B.Cu")
		(net "P5E_CPU0_P1_TX_BUF_DN<13>")
	)
	(segment
		(start 345.122246 -416.632644)
		(end 345.418156 -416.336734)
		(width 0.12954)
		(layer "B.Cu")
		(net "P5E_CPU0_P1_TX_BUF_DN<13>")
	)
	(segment
		(start 345.418156 -415.65703)
		(end 345.147646 -415.38652)
		(width 0.12954)
		(layer "B.Cu")
		(net "P5E_CPU0_P1_TX_BUF_DN<13>")
	)
	(segment
		(start 351.961704 -398.68094)
		(end 351.81794 -398.824704)
		(width 0.14224)
		(layer "In6.Cu")
		(net "P5E_CPU0_P1_TX_BUF_DN<13>")
	)
	(segment
		(start 347.665802 -409.340812)
		(end 347.665548 -409.341066)
		(width 0.14224)
		(layer "In6.Cu")
		(net "P5E_CPU0_P1_TX_BUF_DN<13>")
	)
	(segment
		(start 351.971102 -397.388588)
		(end 351.652586 -397.707104)
		(width 0.14224)
		(layer "In6.Cu")
		(net "P5E_CPU0_P1_TX_BUF_DN<13>")
	)
	(segment
		(start 351.248218 -399.955512)
		(end 351.248218 -403.977094)
		(width 0.14224)
		(layer "In6.Cu")
		(net "P5E_CPU0_P1_TX_BUF_DN<13>")
	)
	(segment
		(start 345.438476 -412.678372)
		(end 345.438476 -415.09569)
		(width 0.14224)
		(layer "In6.Cu")
		(net "P5E_CPU0_P1_TX_BUF_DN<13>")
	)
	(segment
		(start 347.666818 -409.340812)
		(end 347.665802 -409.340812)
		(width 0.14224)
		(layer "In6.Cu")
		(net "P5E_CPU0_P1_TX_BUF_DN<13>")
	)
	(segment
		(start 351.851976 -398.344644)
		(end 351.961704 -398.454372)
		(width 0.14224)
		(layer "In6.Cu")
		(net "P5E_CPU0_P1_TX_BUF_DN<13>")
	)
	(segment
		(start 350.16821 -405.97328)
		(end 349.427546 -406.969976)
		(width 0.14224)
		(layer "In6.Cu")
		(net "P5E_CPU0_P1_TX_BUF_DN<13>")
	)
	(segment
		(start 347.665548 -409.341066)
		(end 347.272864 -409.869894)
		(width 0.14224)
		(layer "In6.Cu")
		(net "P5E_CPU0_P1_TX_BUF_DN<13>")
	)
	(segment
		(start 345.91752 -411.714696)
		(end 345.575128 -412.226506)
		(width 0.14224)
		(layer "In6.Cu")
		(net "P5E_CPU0_P1_TX_BUF_DN<13>")
	)
	(segment
		(start 345.438476 -415.09569)
		(end 345.147646 -415.38652)
		(width 0.14224)
		(layer "In6.Cu")
		(net "P5E_CPU0_P1_TX_BUF_DN<13>")
	)
	(segment
		(start 351.918778 -397.156432)
		(end 351.971102 -397.208756)
		(width 0.14224)
		(layer "In6.Cu")
		(net "P5E_CPU0_P1_TX_BUF_DN<13>")
	)
	(segment
		(start 351.688146 -399.138394)
		(end 351.688146 -399.27911)
		(width 0.14224)
		(layer "In6.Cu")
		(net "P5E_CPU0_P1_TX_BUF_DN<13>")
	)
	(segment
		(start 351.971102 -397.208756)
		(end 351.971102 -397.388588)
		(width 0.14224)
		(layer "In6.Cu")
		(net "P5E_CPU0_P1_TX_BUF_DN<13>")
	)
	(segment
		(start 349.4278 -406.969976)
		(end 347.666818 -409.340812)
		(width 0.14224)
		(layer "In6.Cu")
		(net "P5E_CPU0_P1_TX_BUF_DN<13>")
	)
	(segment
		(start 351.652586 -397.707104)
		(end 351.652586 -397.863314)
		(width 0.14224)
		(layer "In6.Cu")
		(net "P5E_CPU0_P1_TX_BUF_DN<13>")
	)
	(segment
		(start 347.272864 -409.869894)
		(end 347.273118 -409.87091)
		(width 0.14224)
		(layer "In6.Cu")
		(net "P5E_CPU0_P1_TX_BUF_DN<13>")
	)
	(segment
		(start 347.273118 -409.87091)
		(end 346.1639 -411.36443)
		(width 0.14224)
		(layer "In6.Cu")
		(net "P5E_CPU0_P1_TX_BUF_DN<13>")
	)
	(segment
		(start 351.640902 -399.393156)
		(end 351.368106 -399.665952)
		(width 0.14224)
		(layer "In6.Cu")
		(net "P5E_CPU0_P1_TX_BUF_DN<13>")
	)
	(segment
		(start 349.427546 -406.969976)
		(end 349.4278 -406.969976)
		(width 0.14224)
		(layer "In6.Cu")
		(net "P5E_CPU0_P1_TX_BUF_DN<13>")
	)
	(arc
		(start 351.0915 -404.667466)
		(mid 351.047478 -404.754784)
		(end 350.993964 -404.83663)
		(width 0.14224)
		(layer "In6.Cu")
		(net "P5E_CPU0_P1_TX_BUF_DN<13>")
	)
	(arc
		(start 345.575128 -412.226506)
		(mid 345.473382 -412.442329)
		(end 345.438476 -412.678372)
		(width 0.14224)
		(layer "In6.Cu")
		(net "P5E_CPU0_P1_TX_BUF_DN<13>")
	)
	(arc
		(start 346.1639 -411.36443)
		(mid 346.038602 -411.53808)
		(end 345.91752 -411.714696)
		(width 0.14224)
		(layer "In6.Cu")
		(net "P5E_CPU0_P1_TX_BUF_DN<13>")
	)
	(arc
		(start 350.993964 -404.83663)
		(mid 350.583895 -405.406995)
		(end 350.16821 -405.97328)
		(width 0.14224)
		(layer "In6.Cu")
		(net "P5E_CPU0_P1_TX_BUF_DN<13>")
	)
	(arc
		(start 351.81794 -398.824704)
		(mid 351.721804 -398.968627)
		(end 351.688146 -399.138394)
		(width 0.14224)
		(layer "In6.Cu")
		(net "P5E_CPU0_P1_TX_BUF_DN<13>")
	)
	(arc
		(start 351.652586 -397.863314)
		(mid 351.704403 -398.123814)
		(end 351.851976 -398.344644)
		(width 0.14224)
		(layer "In6.Cu")
		(net "P5E_CPU0_P1_TX_BUF_DN<13>")
	)
	(arc
		(start 351.368106 -399.665952)
		(mid 351.279391 -399.798817)
		(end 351.248218 -399.955512)
		(width 0.14224)
		(layer "In6.Cu")
		(net "P5E_CPU0_P1_TX_BUF_DN<13>")
	)
	(arc
		(start 351.241106 -404.103586)
		(mid 351.18705 -404.391031)
		(end 351.0915 -404.667466)
		(width 0.14224)
		(layer "In6.Cu")
		(net "P5E_CPU0_P1_TX_BUF_DN<13>")
	)
	(arc
		(start 351.248218 -403.977094)
		(mid 351.246454 -404.040441)
		(end 351.241106 -404.103586)
		(width 0.14224)
		(layer "In6.Cu")
		(net "P5E_CPU0_P1_TX_BUF_DN<13>")
	)
	(arc
		(start 351.688146 -399.27911)
		(mid 351.675869 -399.340833)
		(end 351.640902 -399.393156)
		(width 0.14224)
		(layer "In6.Cu")
		(net "P5E_CPU0_P1_TX_BUF_DN<13>")
	)
	(arc
		(start 351.961704 -398.454372)
		(mid 352.008628 -398.567656)
		(end 351.961704 -398.68094)
		(width 0.14224)
		(layer "In6.Cu")
		(net "P5E_CPU0_P1_TX_BUF_DN<13>")
	)
	(segment
		(start 350.198182 -397.156432)
		(end 350.718882 -397.156432)
		(width 0.127)
		(layer "F.Cu")
		(net "P5E_CPU0_P1_TX_BUF_DN<12>")
	)
	(segment
		(start 342.348058 -415.650172)
		(end 342.348058 -416.343592)
		(width 0.12954)
		(layer "B.Cu")
		(net "P5E_CPU0_P1_TX_BUF_DN<12>")
	)
	(segment
		(start 342.348058 -416.343592)
		(end 342.059006 -416.632644)
		(width 0.12954)
		(layer "B.Cu")
		(net "P5E_CPU0_P1_TX_BUF_DN<12>")
	)
	(segment
		(start 342.084406 -415.38652)
		(end 342.348058 -415.650172)
		(width 0.12954)
		(layer "B.Cu")
		(net "P5E_CPU0_P1_TX_BUF_DN<12>")
	)
	(segment
		(start 350.78797 -398.522444)
		(end 350.78797 -398.5514)
		(width 0.14224)
		(layer "In6.Cu")
		(net "P5E_CPU0_P1_TX_BUF_DN<12>")
	)
	(segment
		(start 350.771206 -397.388588)
		(end 350.45269 -397.707104)
		(width 0.14224)
		(layer "In6.Cu")
		(net "P5E_CPU0_P1_TX_BUF_DN<12>")
	)
	(segment
		(start 350.616012 -398.298162)
		(end 350.750632 -398.432528)
		(width 0.14224)
		(layer "In6.Cu")
		(net "P5E_CPU0_P1_TX_BUF_DN<12>")
	)
	(segment
		(start 342.375236 -415.09569)
		(end 342.084406 -415.38652)
		(width 0.14224)
		(layer "In6.Cu")
		(net "P5E_CPU0_P1_TX_BUF_DN<12>")
	)
	(segment
		(start 350.048068 -400.2151)
		(end 350.048068 -403.827488)
		(width 0.14224)
		(layer "In6.Cu")
		(net "P5E_CPU0_P1_TX_BUF_DN<12>")
	)
	(segment
		(start 350.718882 -397.156432)
		(end 350.771206 -397.208756)
		(width 0.14224)
		(layer "In6.Cu")
		(net "P5E_CPU0_P1_TX_BUF_DN<12>")
	)
	(segment
		(start 350.50476 -399.234914)
		(end 350.418146 -399.321528)
		(width 0.14224)
		(layer "In6.Cu")
		(net "P5E_CPU0_P1_TX_BUF_DN<12>")
	)
	(segment
		(start 345.248738 -409.93822)
		(end 342.760046 -411.783276)
		(width 0.14224)
		(layer "In6.Cu")
		(net "P5E_CPU0_P1_TX_BUF_DN<12>")
	)
	(segment
		(start 350.45269 -397.707104)
		(end 350.45269 -397.903954)
		(width 0.14224)
		(layer "In6.Cu")
		(net "P5E_CPU0_P1_TX_BUF_DN<12>")
	)
	(segment
		(start 349.86087 -404.349966)
		(end 345.365324 -409.827222)
		(width 0.14224)
		(layer "In6.Cu")
		(net "P5E_CPU0_P1_TX_BUF_DN<12>")
	)
	(segment
		(start 342.375236 -412.730442)
		(end 342.375236 -415.09569)
		(width 0.14224)
		(layer "In6.Cu")
		(net "P5E_CPU0_P1_TX_BUF_DN<12>")
	)
	(segment
		(start 350.771206 -397.208756)
		(end 350.771206 -397.388588)
		(width 0.14224)
		(layer "In6.Cu")
		(net "P5E_CPU0_P1_TX_BUF_DN<12>")
	)
	(arc
		(start 345.365324 -409.827222)
		(mid 345.310419 -409.886279)
		(end 345.248738 -409.93822)
		(width 0.14224)
		(layer "In6.Cu")
		(net "P5E_CPU0_P1_TX_BUF_DN<12>")
	)
	(arc
		(start 342.636348 -411.93339)
		(mid 342.478399 -412.232813)
		(end 342.388698 -412.559246)
		(width 0.14224)
		(layer "In6.Cu")
		(net "P5E_CPU0_P1_TX_BUF_DN<12>")
	)
	(arc
		(start 342.760046 -411.783276)
		(mid 342.694669 -411.855426)
		(end 342.636348 -411.93339)
		(width 0.14224)
		(layer "In6.Cu")
		(net "P5E_CPU0_P1_TX_BUF_DN<12>")
	)
	(arc
		(start 342.388698 -412.559246)
		(mid 342.378544 -412.644575)
		(end 342.375236 -412.730442)
		(width 0.14224)
		(layer "In6.Cu")
		(net "P5E_CPU0_P1_TX_BUF_DN<12>")
	)
	(arc
		(start 350.418146 -399.321528)
		(mid 350.144264 -399.731517)
		(end 350.048068 -400.2151)
		(width 0.14224)
		(layer "In6.Cu")
		(net "P5E_CPU0_P1_TX_BUF_DN<12>")
	)
	(arc
		(start 350.45269 -397.903954)
		(mid 350.495129 -398.117311)
		(end 350.616012 -398.298162)
		(width 0.14224)
		(layer "In6.Cu")
		(net "P5E_CPU0_P1_TX_BUF_DN<12>")
	)
	(arc
		(start 350.750632 -398.432528)
		(mid 350.778251 -398.473768)
		(end 350.78797 -398.522444)
		(width 0.14224)
		(layer "In6.Cu")
		(net "P5E_CPU0_P1_TX_BUF_DN<12>")
	)
	(arc
		(start 350.78797 -398.5514)
		(mid 350.714367 -398.921335)
		(end 350.50476 -399.234914)
		(width 0.14224)
		(layer "In6.Cu")
		(net "P5E_CPU0_P1_TX_BUF_DN<12>")
	)
	(arc
		(start 350.048068 -403.827488)
		(mid 349.999789 -404.104972)
		(end 349.86087 -404.349966)
		(width 0.14224)
		(layer "In6.Cu")
		(net "P5E_CPU0_P1_TX_BUF_DN<12>")
	)
	(segment
		(start 348.998032 -397.156432)
		(end 349.518732 -397.156432)
		(width 0.127)
		(layer "F.Cu")
		(net "P5E_CPU0_P1_TX_BUF_DN<11>")
	)
	(segment
		(start 339.291676 -415.65703)
		(end 339.021166 -415.38652)
		(width 0.12954)
		(layer "B.Cu")
		(net "P5E_CPU0_P1_TX_BUF_DN<11>")
	)
	(segment
		(start 338.995766 -416.632644)
		(end 339.291676 -416.336734)
		(width 0.12954)
		(layer "B.Cu")
		(net "P5E_CPU0_P1_TX_BUF_DN<11>")
	)
	(segment
		(start 339.291676 -416.336734)
		(end 339.291676 -415.65703)
		(width 0.12954)
		(layer "B.Cu")
		(net "P5E_CPU0_P1_TX_BUF_DN<11>")
	)
	(segment
		(start 349.406972 -398.299432)
		(end 349.481902 -398.374362)
		(width 0.14224)
		(layer "In6.Cu")
		(net "P5E_CPU0_P1_TX_BUF_DN<11>")
	)
	(segment
		(start 349.25254 -397.707104)
		(end 349.25254 -397.926814)
		(width 0.14224)
		(layer "In6.Cu")
		(net "P5E_CPU0_P1_TX_BUF_DN<11>")
	)
	(segment
		(start 340.432898 -411.149038)
		(end 339.727286 -411.575504)
		(width 0.14224)
		(layer "In6.Cu")
		(net "P5E_CPU0_P1_TX_BUF_DN<11>")
	)
	(segment
		(start 349.571056 -397.388588)
		(end 349.25254 -397.707104)
		(width 0.14224)
		(layer "In6.Cu")
		(net "P5E_CPU0_P1_TX_BUF_DN<11>")
	)
	(segment
		(start 349.366332 -399.148808)
		(end 349.34144 -399.1737)
		(width 0.14224)
		(layer "In6.Cu")
		(net "P5E_CPU0_P1_TX_BUF_DN<11>")
	)
	(segment
		(start 339.311996 -415.09569)
		(end 339.021166 -415.38652)
		(width 0.14224)
		(layer "In6.Cu")
		(net "P5E_CPU0_P1_TX_BUF_DN<11>")
	)
	(segment
		(start 349.529146 -398.488408)
		(end 349.529146 -398.75587)
		(width 0.14224)
		(layer "In6.Cu")
		(net "P5E_CPU0_P1_TX_BUF_DN<11>")
	)
	(segment
		(start 348.54388 -404.313136)
		(end 348.141544 -404.715472)
		(width 0.14224)
		(layer "In6.Cu")
		(net "P5E_CPU0_P1_TX_BUF_DN<11>")
	)
	(segment
		(start 349.571056 -397.208756)
		(end 349.571056 -397.388588)
		(width 0.14224)
		(layer "In6.Cu")
		(net "P5E_CPU0_P1_TX_BUF_DN<11>")
	)
	(segment
		(start 343.926414 -408.930348)
		(end 343.012268 -409.601162)
		(width 0.14224)
		(layer "In6.Cu")
		(net "P5E_CPU0_P1_TX_BUF_DN<11>")
	)
	(segment
		(start 348.848172 -400.364452)
		(end 348.848172 -403.578822)
		(width 0.14224)
		(layer "In6.Cu")
		(net "P5E_CPU0_P1_TX_BUF_DN<11>")
	)
	(segment
		(start 349.518732 -397.156432)
		(end 349.571056 -397.208756)
		(width 0.14224)
		(layer "In6.Cu")
		(net "P5E_CPU0_P1_TX_BUF_DN<11>")
	)
	(segment
		(start 343.012268 -409.601162)
		(end 341.91829 -410.295852)
		(width 0.14224)
		(layer "In6.Cu")
		(net "P5E_CPU0_P1_TX_BUF_DN<11>")
	)
	(segment
		(start 339.311996 -412.619698)
		(end 339.311996 -415.09569)
		(width 0.14224)
		(layer "In6.Cu")
		(net "P5E_CPU0_P1_TX_BUF_DN<11>")
	)
	(segment
		(start 348.141544 -404.715472)
		(end 343.926414 -408.930348)
		(width 0.14224)
		(layer "In6.Cu")
		(net "P5E_CPU0_P1_TX_BUF_DN<11>")
	)
	(arc
		(start 339.540088 -411.766766)
		(mid 339.369836 -412.178205)
		(end 339.311996 -412.619698)
		(width 0.14224)
		(layer "In6.Cu")
		(net "P5E_CPU0_P1_TX_BUF_DN<11>")
	)
	(arc
		(start 349.481902 -398.374362)
		(mid 349.516864 -398.426687)
		(end 349.529146 -398.488408)
		(width 0.14224)
		(layer "In6.Cu")
		(net "P5E_CPU0_P1_TX_BUF_DN<11>")
	)
	(arc
		(start 339.727286 -411.575504)
		(mid 339.621573 -411.659279)
		(end 339.540088 -411.766766)
		(width 0.14224)
		(layer "In6.Cu")
		(net "P5E_CPU0_P1_TX_BUF_DN<11>")
	)
	(arc
		(start 349.34144 -399.1737)
		(mid 348.976346 -399.720007)
		(end 348.848172 -400.364452)
		(width 0.14224)
		(layer "In6.Cu")
		(net "P5E_CPU0_P1_TX_BUF_DN<11>")
	)
	(arc
		(start 349.529146 -398.75587)
		(mid 349.486827 -398.968533)
		(end 349.366332 -399.148808)
		(width 0.14224)
		(layer "In6.Cu")
		(net "P5E_CPU0_P1_TX_BUF_DN<11>")
	)
	(arc
		(start 349.25254 -397.926814)
		(mid 349.292674 -398.128493)
		(end 349.406972 -398.299432)
		(width 0.14224)
		(layer "In6.Cu")
		(net "P5E_CPU0_P1_TX_BUF_DN<11>")
	)
	(arc
		(start 341.91829 -410.295852)
		(mid 341.170825 -410.714142)
		(end 340.432898 -411.149038)
		(width 0.14224)
		(layer "In6.Cu")
		(net "P5E_CPU0_P1_TX_BUF_DN<11>")
	)
	(arc
		(start 348.848172 -403.578822)
		(mid 348.769083 -403.976251)
		(end 348.54388 -404.313136)
		(width 0.14224)
		(layer "In6.Cu")
		(net "P5E_CPU0_P1_TX_BUF_DN<11>")
	)
	(segment
		(start 347.798136 -397.156432)
		(end 348.318836 -397.156432)
		(width 0.127)
		(layer "F.Cu")
		(net "P5E_CPU0_P1_TX_BUF_DN<10>")
	)
	(segment
		(start 336.228436 -416.336734)
		(end 336.228436 -415.65703)
		(width 0.12954)
		(layer "B.Cu")
		(net "P5E_CPU0_P1_TX_BUF_DN<10>")
	)
	(segment
		(start 335.932526 -416.632644)
		(end 336.228436 -416.336734)
		(width 0.12954)
		(layer "B.Cu")
		(net "P5E_CPU0_P1_TX_BUF_DN<10>")
	)
	(segment
		(start 336.228436 -415.65703)
		(end 335.957926 -415.38652)
		(width 0.12954)
		(layer "B.Cu")
		(net "P5E_CPU0_P1_TX_BUF_DN<10>")
	)
	(segment
		(start 348.05112 -399.308066)
		(end 348.028768 -399.330418)
		(width 0.14224)
		(layer "In6.Cu")
		(net "P5E_CPU0_P1_TX_BUF_DN<10>")
	)
	(segment
		(start 347.438218 -404.041102)
		(end 343.84234 -407.637234)
		(width 0.14224)
		(layer "In6.Cu")
		(net "P5E_CPU0_P1_TX_BUF_DN<10>")
	)
	(segment
		(start 348.052644 -397.707104)
		(end 348.052644 -397.888206)
		(width 0.14224)
		(layer "In6.Cu")
		(net "P5E_CPU0_P1_TX_BUF_DN<10>")
	)
	(segment
		(start 347.557598 -403.818344)
		(end 347.508322 -403.936454)
		(width 0.14224)
		(layer "In6.Cu")
		(net "P5E_CPU0_P1_TX_BUF_DN<10>")
	)
	(segment
		(start 348.37116 -397.388588)
		(end 348.052644 -397.707104)
		(width 0.14224)
		(layer "In6.Cu")
		(net "P5E_CPU0_P1_TX_BUF_DN<10>")
	)
	(segment
		(start 348.401386 -398.560544)
		(end 348.401386 -398.691354)
		(width 0.14224)
		(layer "In6.Cu")
		(net "P5E_CPU0_P1_TX_BUF_DN<10>")
	)
	(segment
		(start 336.248756 -415.09569)
		(end 335.957926 -415.38652)
		(width 0.14224)
		(layer "In6.Cu")
		(net "P5E_CPU0_P1_TX_BUF_DN<10>")
	)
	(segment
		(start 341.564468 -409.273756)
		(end 336.632042 -411.721554)
		(width 0.14224)
		(layer "In6.Cu")
		(net "P5E_CPU0_P1_TX_BUF_DN<10>")
	)
	(segment
		(start 336.248756 -412.33979)
		(end 336.248756 -415.09569)
		(width 0.14224)
		(layer "In6.Cu")
		(net "P5E_CPU0_P1_TX_BUF_DN<10>")
	)
	(segment
		(start 348.37116 -397.208756)
		(end 348.37116 -397.388588)
		(width 0.14224)
		(layer "In6.Cu")
		(net "P5E_CPU0_P1_TX_BUF_DN<10>")
	)
	(segment
		(start 348.318836 -397.156432)
		(end 348.37116 -397.208756)
		(width 0.14224)
		(layer "In6.Cu")
		(net "P5E_CPU0_P1_TX_BUF_DN<10>")
	)
	(segment
		(start 347.582236 -400.408394)
		(end 347.582236 -403.695154)
		(width 0.14224)
		(layer "In6.Cu")
		(net "P5E_CPU0_P1_TX_BUF_DN<10>")
	)
	(segment
		(start 348.368366 -398.812004)
		(end 348.153736 -399.175224)
		(width 0.14224)
		(layer "In6.Cu")
		(net "P5E_CPU0_P1_TX_BUF_DN<10>")
	)
	(segment
		(start 348.234254 -398.32661)
		(end 348.354142 -398.446498)
		(width 0.14224)
		(layer "In6.Cu")
		(net "P5E_CPU0_P1_TX_BUF_DN<10>")
	)
	(arc
		(start 336.632042 -411.721554)
		(mid 336.3524 -411.976104)
		(end 336.248756 -412.33979)
		(width 0.14224)
		(layer "In6.Cu")
		(net "P5E_CPU0_P1_TX_BUF_DN<10>")
	)
	(arc
		(start 348.028768 -399.330418)
		(mid 347.6983 -399.824998)
		(end 347.582236 -400.408394)
		(width 0.14224)
		(layer "In6.Cu")
		(net "P5E_CPU0_P1_TX_BUF_DN<10>")
	)
	(arc
		(start 348.153736 -399.175224)
		(mid 348.106603 -399.244869)
		(end 348.05112 -399.308066)
		(width 0.14224)
		(layer "In6.Cu")
		(net "P5E_CPU0_P1_TX_BUF_DN<10>")
	)
	(arc
		(start 348.052644 -397.888206)
		(mid 348.09984 -398.125475)
		(end 348.234254 -398.32661)
		(width 0.14224)
		(layer "In6.Cu")
		(net "P5E_CPU0_P1_TX_BUF_DN<10>")
	)
	(arc
		(start 347.508322 -403.936454)
		(mid 347.47841 -403.992223)
		(end 347.438218 -404.041102)
		(width 0.14224)
		(layer "In6.Cu")
		(net "P5E_CPU0_P1_TX_BUF_DN<10>")
	)
	(arc
		(start 343.84234 -407.637234)
		(mid 342.769961 -408.548137)
		(end 341.564468 -409.273756)
		(width 0.14224)
		(layer "In6.Cu")
		(net "P5E_CPU0_P1_TX_BUF_DN<10>")
	)
	(arc
		(start 348.354142 -398.446498)
		(mid 348.389104 -398.498823)
		(end 348.401386 -398.560544)
		(width 0.14224)
		(layer "In6.Cu")
		(net "P5E_CPU0_P1_TX_BUF_DN<10>")
	)
	(arc
		(start 348.401386 -398.691354)
		(mid 348.392992 -398.753903)
		(end 348.368366 -398.812004)
		(width 0.14224)
		(layer "In6.Cu")
		(net "P5E_CPU0_P1_TX_BUF_DN<10>")
	)
	(arc
		(start 347.582236 -403.695154)
		(mid 347.576016 -403.757969)
		(end 347.557598 -403.818344)
		(width 0.14224)
		(layer "In6.Cu")
		(net "P5E_CPU0_P1_TX_BUF_DN<10>")
	)
	(segment
		(start 335.79816 -397.156432)
		(end 336.31886 -397.156432)
		(width 0.127)
		(layer "F.Cu")
		(net "P5E_CPU0_P1_TX_BUF_DN<0>")
	)
	(segment
		(start 305.596036 -416.336734)
		(end 305.596036 -415.65703)
		(width 0.12954)
		(layer "B.Cu")
		(net "P5E_CPU0_P1_TX_BUF_DN<0>")
	)
	(segment
		(start 305.300126 -416.632644)
		(end 305.596036 -416.336734)
		(width 0.12954)
		(layer "B.Cu")
		(net "P5E_CPU0_P1_TX_BUF_DN<0>")
	)
	(segment
		(start 305.596036 -415.65703)
		(end 305.325526 -415.38652)
		(width 0.12954)
		(layer "B.Cu")
		(net "P5E_CPU0_P1_TX_BUF_DN<0>")
	)
	(segment
		(start 310.040274 -409.304236)
		(end 310.040528 -409.304744)
		(width 0.14224)
		(layer "In6.Cu")
		(net "P5E_CPU0_P1_TX_BUF_DN<0>")
	)
	(segment
		(start 327.724008 -403.869906)
		(end 324.72757 -405.087836)
		(width 0.14224)
		(layer "In6.Cu")
		(net "P5E_CPU0_P1_TX_BUF_DN<0>")
	)
	(segment
		(start 334.842612 -398.42059)
		(end 334.686656 -398.79651)
		(width 0.14224)
		(layer "In6.Cu")
		(net "P5E_CPU0_P1_TX_BUF_DN<0>")
	)
	(segment
		(start 335.907126 -397.786606)
		(end 335.753456 -397.786606)
		(width 0.14224)
		(layer "In6.Cu")
		(net "P5E_CPU0_P1_TX_BUF_DN<0>")
	)
	(segment
		(start 334.40751 -399.716244)
		(end 334.315562 -400.179286)
		(width 0.14224)
		(layer "In6.Cu")
		(net "P5E_CPU0_P1_TX_BUF_DN<0>")
	)
	(segment
		(start 305.616356 -415.09569)
		(end 305.325526 -415.38652)
		(width 0.14224)
		(layer "In6.Cu")
		(net "P5E_CPU0_P1_TX_BUF_DN<0>")
	)
	(segment
		(start 331.949806 -402.61794)
		(end 327.724008 -403.869906)
		(width 0.14224)
		(layer "In6.Cu")
		(net "P5E_CPU0_P1_TX_BUF_DN<0>")
	)
	(segment
		(start 310.040528 -409.304744)
		(end 308.85511 -409.644596)
		(width 0.14224)
		(layer "In6.Cu")
		(net "P5E_CPU0_P1_TX_BUF_DN<0>")
	)
	(segment
		(start 336.31886 -397.156432)
		(end 336.364326 -397.201898)
		(width 0.14224)
		(layer "In6.Cu")
		(net "P5E_CPU0_P1_TX_BUF_DN<0>")
	)
	(segment
		(start 333.287878 -402.074126)
		(end 331.949806 -402.61794)
		(width 0.14224)
		(layer "In6.Cu")
		(net "P5E_CPU0_P1_TX_BUF_DN<0>")
	)
	(segment
		(start 336.364326 -397.201898)
		(end 336.364326 -397.381984)
		(width 0.14224)
		(layer "In6.Cu")
		(net "P5E_CPU0_P1_TX_BUF_DN<0>")
	)
	(segment
		(start 334.686656 -398.79651)
		(end 334.40751 -399.716244)
		(width 0.14224)
		(layer "In6.Cu")
		(net "P5E_CPU0_P1_TX_BUF_DN<0>")
	)
	(segment
		(start 305.616356 -412.587694)
		(end 305.616356 -415.09569)
		(width 0.14224)
		(layer "In6.Cu")
		(net "P5E_CPU0_P1_TX_BUF_DN<0>")
	)
	(segment
		(start 334.315562 -400.179286)
		(end 334.315562 -400.81454)
		(width 0.14224)
		(layer "In6.Cu")
		(net "P5E_CPU0_P1_TX_BUF_DN<0>")
	)
	(segment
		(start 307.974238 -410.046932)
		(end 306.459128 -411.033214)
		(width 0.14224)
		(layer "In6.Cu")
		(net "P5E_CPU0_P1_TX_BUF_DN<0>")
	)
	(segment
		(start 324.72757 -405.087836)
		(end 310.040274 -409.304236)
		(width 0.14224)
		(layer "In6.Cu")
		(net "P5E_CPU0_P1_TX_BUF_DN<0>")
	)
	(segment
		(start 334.134968 -401.250658)
		(end 333.357474 -402.028152)
		(width 0.14224)
		(layer "In6.Cu")
		(net "P5E_CPU0_P1_TX_BUF_DN<0>")
	)
	(segment
		(start 335.281016 -397.982186)
		(end 334.842612 -398.42059)
		(width 0.14224)
		(layer "In6.Cu")
		(net "P5E_CPU0_P1_TX_BUF_DN<0>")
	)
	(segment
		(start 336.364326 -397.381984)
		(end 335.997042 -397.749268)
		(width 0.14224)
		(layer "In6.Cu")
		(net "P5E_CPU0_P1_TX_BUF_DN<0>")
	)
	(arc
		(start 335.997042 -397.749268)
		(mid 335.955802 -397.776887)
		(end 335.907126 -397.786606)
		(width 0.14224)
		(layer "In6.Cu")
		(net "P5E_CPU0_P1_TX_BUF_DN<0>")
	)
	(arc
		(start 308.85511 -409.644596)
		(mid 308.399674 -409.812923)
		(end 307.974238 -410.046932)
		(width 0.14224)
		(layer "In6.Cu")
		(net "P5E_CPU0_P1_TX_BUF_DN<0>")
	)
	(arc
		(start 334.315562 -400.81454)
		(mid 334.268633 -401.05056)
		(end 334.134968 -401.250658)
		(width 0.14224)
		(layer "In6.Cu")
		(net "P5E_CPU0_P1_TX_BUF_DN<0>")
	)
	(arc
		(start 335.753456 -397.786606)
		(mid 335.497802 -397.837441)
		(end 335.281016 -397.982186)
		(width 0.14224)
		(layer "In6.Cu")
		(net "P5E_CPU0_P1_TX_BUF_DN<0>")
	)
	(arc
		(start 306.459128 -411.033214)
		(mid 305.840593 -411.703571)
		(end 305.616356 -412.587694)
		(width 0.14224)
		(layer "In6.Cu")
		(net "P5E_CPU0_P1_TX_BUF_DN<0>")
	)
	(arc
		(start 333.357474 -402.028152)
		(mid 333.324979 -402.054624)
		(end 333.287878 -402.074126)
		(width 0.14224)
		(layer "In6.Cu")
		(net "P5E_CPU0_P1_TX_BUF_DN<0>")
	)
	(segment
		(start 333.487776 -417.461954)
		(end 333.487776 -418.141658)
		(width 0.12954)
		(layer "B.Cu")
		(net "P5E_CPU0_P1_TX_BUF_C_DP<9>")
	)
	(segment
		(start 333.487776 -418.141658)
		(end 333.758286 -418.412168)
		(width 0.12954)
		(layer "B.Cu")
		(net "P5E_CPU0_P1_TX_BUF_C_DP<9>")
	)
	(segment
		(start 333.783686 -417.166044)
		(end 333.487776 -417.461954)
		(width 0.12954)
		(layer "B.Cu")
		(net "P5E_CPU0_P1_TX_BUF_C_DP<9>")
	)
	(segment
		(start 333.133446 -423.602404)
		(end 333.256382 -423.752264)
		(width 0.14224)
		(layer "In6.Cu")
		(net "P5E_CPU0_P1_TX_BUF_C_DP<9>")
	)
	(segment
		(start 333.604616 -420.253922)
		(end 333.467456 -420.391082)
		(width 0.14224)
		(layer "In6.Cu")
		(net "P5E_CPU0_P1_TX_BUF_C_DP<9>")
	)
	(segment
		(start 333.467456 -421.147494)
		(end 333.283814 -422.070784)
		(width 0.14224)
		(layer "In6.Cu")
		(net "P5E_CPU0_P1_TX_BUF_C_DP<9>")
	)
	(segment
		(start 333.507588 -427.548802)
		(end 333.649828 -427.406562)
		(width 0.14224)
		(layer "In6.Cu")
		(net "P5E_CPU0_P1_TX_BUF_C_DP<9>")
	)
	(segment
		(start 333.256382 -423.752264)
		(end 333.214726 -424.177206)
		(width 0.14224)
		(layer "In6.Cu")
		(net "P5E_CPU0_P1_TX_BUF_C_DP<9>")
	)
	(segment
		(start 333.649828 -427.406562)
		(end 333.649828 -427.089824)
		(width 0.14224)
		(layer "In6.Cu")
		(net "P5E_CPU0_P1_TX_BUF_C_DP<9>")
	)
	(segment
		(start 333.325216 -423.05478)
		(end 333.175102 -423.17797)
		(width 0.14224)
		(layer "In6.Cu")
		(net "P5E_CPU0_P1_TX_BUF_C_DP<9>")
	)
	(segment
		(start 333.300324 -427.548802)
		(end 333.507588 -427.548802)
		(width 0.14224)
		(layer "In6.Cu")
		(net "P5E_CPU0_P1_TX_BUF_C_DP<9>")
	)
	(segment
		(start 333.214726 -424.177206)
		(end 333.064358 -424.300396)
		(width 0.14224)
		(layer "In6.Cu")
		(net "P5E_CPU0_P1_TX_BUF_C_DP<9>")
	)
	(segment
		(start 333.758286 -418.412168)
		(end 333.467456 -418.702998)
		(width 0.14224)
		(layer "In6.Cu")
		(net "P5E_CPU0_P1_TX_BUF_C_DP<9>")
	)
	(segment
		(start 333.467456 -419.690042)
		(end 333.604616 -419.827202)
		(width 0.14224)
		(layer "In6.Cu")
		(net "P5E_CPU0_P1_TX_BUF_C_DP<9>")
	)
	(segment
		(start 332.983586 -425.124118)
		(end 332.983586 -427.19498)
		(width 0.14224)
		(layer "In6.Cu")
		(net "P5E_CPU0_P1_TX_BUF_C_DP<9>")
	)
	(segment
		(start 333.604616 -419.827202)
		(end 333.604616 -420.253922)
		(width 0.14224)
		(layer "In6.Cu")
		(net "P5E_CPU0_P1_TX_BUF_C_DP<9>")
	)
	(segment
		(start 333.283814 -422.070784)
		(end 333.243682 -422.479978)
		(width 0.14224)
		(layer "In6.Cu")
		(net "P5E_CPU0_P1_TX_BUF_C_DP<9>")
	)
	(segment
		(start 333.467456 -418.702998)
		(end 333.467456 -419.690042)
		(width 0.14224)
		(layer "In6.Cu")
		(net "P5E_CPU0_P1_TX_BUF_C_DP<9>")
	)
	(segment
		(start 333.366872 -422.629838)
		(end 333.325216 -423.05478)
		(width 0.14224)
		(layer "In6.Cu")
		(net "P5E_CPU0_P1_TX_BUF_C_DP<9>")
	)
	(segment
		(start 333.243682 -422.479978)
		(end 333.366872 -422.629838)
		(width 0.14224)
		(layer "In6.Cu")
		(net "P5E_CPU0_P1_TX_BUF_C_DP<9>")
	)
	(segment
		(start 333.175102 -423.17797)
		(end 333.133446 -423.602404)
		(width 0.14224)
		(layer "In6.Cu")
		(net "P5E_CPU0_P1_TX_BUF_C_DP<9>")
	)
	(segment
		(start 333.467456 -420.391082)
		(end 333.467456 -421.147494)
		(width 0.14224)
		(layer "In6.Cu")
		(net "P5E_CPU0_P1_TX_BUF_C_DP<9>")
	)
	(segment
		(start 333.085694 -427.44136)
		(end 333.11719 -427.472856)
		(width 0.14224)
		(layer "In6.Cu")
		(net "P5E_CPU0_P1_TX_BUF_C_DP<9>")
	)
	(segment
		(start 333.064358 -424.300396)
		(end 332.983586 -425.124118)
		(width 0.14224)
		(layer "In6.Cu")
		(net "P5E_CPU0_P1_TX_BUF_C_DP<9>")
	)
	(arc
		(start 333.11719 -427.472856)
		(mid 333.201198 -427.529052)
		(end 333.300324 -427.548802)
		(width 0.14224)
		(layer "In6.Cu")
		(net "P5E_CPU0_P1_TX_BUF_C_DP<9>")
	)
	(arc
		(start 332.983586 -427.19498)
		(mid 333.010128 -427.328326)
		(end 333.085694 -427.44136)
		(width 0.14224)
		(layer "In6.Cu")
		(net "P5E_CPU0_P1_TX_BUF_C_DP<9>")
	)
	(segment
		(start 330.720446 -417.166044)
		(end 330.424536 -417.461954)
		(width 0.12954)
		(layer "B.Cu")
		(net "P5E_CPU0_P1_TX_BUF_C_DP<8>")
	)
	(segment
		(start 330.424536 -417.461954)
		(end 330.424536 -418.141658)
		(width 0.12954)
		(layer "B.Cu")
		(net "P5E_CPU0_P1_TX_BUF_C_DP<8>")
	)
	(segment
		(start 330.424536 -418.141658)
		(end 330.695046 -418.412168)
		(width 0.12954)
		(layer "B.Cu")
		(net "P5E_CPU0_P1_TX_BUF_C_DP<8>")
	)
	(segment
		(start 330.404216 -425.294806)
		(end 330.404216 -425.588938)
		(width 0.14224)
		(layer "In6.Cu")
		(net "P5E_CPU0_P1_TX_BUF_C_DP<8>")
	)
	(segment
		(start 330.404216 -422.338246)
		(end 330.541376 -422.475406)
		(width 0.14224)
		(layer "In6.Cu")
		(net "P5E_CPU0_P1_TX_BUF_C_DP<8>")
	)
	(segment
		(start 330.404216 -418.702998)
		(end 330.404216 -419.541452)
		(width 0.14224)
		(layer "In6.Cu")
		(net "P5E_CPU0_P1_TX_BUF_C_DP<8>")
	)
	(segment
		(start 330.404216 -421.210486)
		(end 330.541376 -421.347646)
		(width 0.14224)
		(layer "In6.Cu")
		(net "P5E_CPU0_P1_TX_BUF_C_DP<8>")
	)
	(segment
		(start 330.404216 -419.541452)
		(end 330.541376 -419.678612)
		(width 0.14224)
		(layer "In6.Cu")
		(net "P5E_CPU0_P1_TX_BUF_C_DP<8>")
	)
	(segment
		(start 330.404216 -420.242492)
		(end 330.404216 -421.210486)
		(width 0.14224)
		(layer "In6.Cu")
		(net "P5E_CPU0_P1_TX_BUF_C_DP<8>")
	)
	(segment
		(start 330.541376 -423.603166)
		(end 330.541376 -424.029886)
		(width 0.14224)
		(layer "In6.Cu")
		(net "P5E_CPU0_P1_TX_BUF_C_DP<8>")
	)
	(segment
		(start 330.541376 -424.029886)
		(end 330.404216 -424.167046)
		(width 0.14224)
		(layer "In6.Cu")
		(net "P5E_CPU0_P1_TX_BUF_C_DP<8>")
	)
	(segment
		(start 330.541376 -422.902126)
		(end 330.404216 -423.039286)
		(width 0.14224)
		(layer "In6.Cu")
		(net "P5E_CPU0_P1_TX_BUF_C_DP<8>")
	)
	(segment
		(start 330.541376 -421.347646)
		(end 330.541376 -421.774366)
		(width 0.14224)
		(layer "In6.Cu")
		(net "P5E_CPU0_P1_TX_BUF_C_DP<8>")
	)
	(segment
		(start 330.541376 -425.157646)
		(end 330.404216 -425.294806)
		(width 0.14224)
		(layer "In6.Cu")
		(net "P5E_CPU0_P1_TX_BUF_C_DP<8>")
	)
	(segment
		(start 330.404216 -424.593766)
		(end 330.541376 -424.730926)
		(width 0.14224)
		(layer "In6.Cu")
		(net "P5E_CPU0_P1_TX_BUF_C_DP<8>")
	)
	(segment
		(start 330.404216 -423.039286)
		(end 330.404216 -423.466006)
		(width 0.14224)
		(layer "In6.Cu")
		(net "P5E_CPU0_P1_TX_BUF_C_DP<8>")
	)
	(segment
		(start 330.541376 -422.475406)
		(end 330.541376 -422.902126)
		(width 0.14224)
		(layer "In6.Cu")
		(net "P5E_CPU0_P1_TX_BUF_C_DP<8>")
	)
	(segment
		(start 330.404216 -423.466006)
		(end 330.541376 -423.603166)
		(width 0.14224)
		(layer "In6.Cu")
		(net "P5E_CPU0_P1_TX_BUF_C_DP<8>")
	)
	(segment
		(start 330.404216 -421.911526)
		(end 330.404216 -422.338246)
		(width 0.14224)
		(layer "In6.Cu")
		(net "P5E_CPU0_P1_TX_BUF_C_DP<8>")
	)
	(segment
		(start 330.541376 -419.678612)
		(end 330.541376 -420.105332)
		(width 0.14224)
		(layer "In6.Cu")
		(net "P5E_CPU0_P1_TX_BUF_C_DP<8>")
	)
	(segment
		(start 330.541376 -421.774366)
		(end 330.404216 -421.911526)
		(width 0.14224)
		(layer "In6.Cu")
		(net "P5E_CPU0_P1_TX_BUF_C_DP<8>")
	)
	(segment
		(start 330.695046 -418.412168)
		(end 330.404216 -418.702998)
		(width 0.14224)
		(layer "In6.Cu")
		(net "P5E_CPU0_P1_TX_BUF_C_DP<8>")
	)
	(segment
		(start 330.404216 -424.167046)
		(end 330.404216 -424.593766)
		(width 0.14224)
		(layer "In6.Cu")
		(net "P5E_CPU0_P1_TX_BUF_C_DP<8>")
	)
	(segment
		(start 331.507592 -426.548804)
		(end 331.649832 -426.406564)
		(width 0.14224)
		(layer "In6.Cu")
		(net "P5E_CPU0_P1_TX_BUF_C_DP<8>")
	)
	(segment
		(start 331.224382 -426.548804)
		(end 331.507592 -426.548804)
		(width 0.14224)
		(layer "In6.Cu")
		(net "P5E_CPU0_P1_TX_BUF_C_DP<8>")
	)
	(segment
		(start 330.6699 -426.230288)
		(end 330.821538 -426.381926)
		(width 0.14224)
		(layer "In6.Cu")
		(net "P5E_CPU0_P1_TX_BUF_C_DP<8>")
	)
	(segment
		(start 330.541376 -424.730926)
		(end 330.541376 -425.157646)
		(width 0.14224)
		(layer "In6.Cu")
		(net "P5E_CPU0_P1_TX_BUF_C_DP<8>")
	)
	(segment
		(start 331.649832 -426.406564)
		(end 331.649832 -426.089826)
		(width 0.14224)
		(layer "In6.Cu")
		(net "P5E_CPU0_P1_TX_BUF_C_DP<8>")
	)
	(segment
		(start 330.541376 -420.105332)
		(end 330.404216 -420.242492)
		(width 0.14224)
		(layer "In6.Cu")
		(net "P5E_CPU0_P1_TX_BUF_C_DP<8>")
	)
	(arc
		(start 330.404216 -425.588938)
		(mid 330.47326 -425.936045)
		(end 330.6699 -426.230288)
		(width 0.14224)
		(layer "In6.Cu")
		(net "P5E_CPU0_P1_TX_BUF_C_DP<8>")
	)
	(arc
		(start 330.821538 -426.381926)
		(mid 331.006364 -426.505423)
		(end 331.224382 -426.548804)
		(width 0.14224)
		(layer "In6.Cu")
		(net "P5E_CPU0_P1_TX_BUF_C_DP<8>")
	)
	(segment
		(start 327.361296 -418.141658)
		(end 327.631806 -418.412168)
		(width 0.12954)
		(layer "B.Cu")
		(net "P5E_CPU0_P1_TX_BUF_C_DP<7>")
	)
	(segment
		(start 327.657206 -417.166044)
		(end 327.361296 -417.461954)
		(width 0.12954)
		(layer "B.Cu")
		(net "P5E_CPU0_P1_TX_BUF_C_DP<7>")
	)
	(segment
		(start 327.361296 -417.461954)
		(end 327.361296 -418.141658)
		(width 0.12954)
		(layer "B.Cu")
		(net "P5E_CPU0_P1_TX_BUF_C_DP<7>")
	)
	(segment
		(start 327.66889 -422.266618)
		(end 327.561194 -422.427908)
		(width 0.14224)
		(layer "In6.Cu")
		(net "P5E_CPU0_P1_TX_BUF_C_DP<7>")
	)
	(segment
		(start 327.561194 -422.427908)
		(end 327.644252 -422.846246)
		(width 0.14224)
		(layer "In6.Cu")
		(net "P5E_CPU0_P1_TX_BUF_C_DP<7>")
	)
	(segment
		(start 327.340976 -420.42969)
		(end 327.340976 -421.321738)
		(width 0.14224)
		(layer "In6.Cu")
		(net "P5E_CPU0_P1_TX_BUF_C_DP<7>")
	)
	(segment
		(start 327.644252 -422.846246)
		(end 327.805796 -422.954196)
		(width 0.14224)
		(layer "In6.Cu")
		(net "P5E_CPU0_P1_TX_BUF_C_DP<7>")
	)
	(segment
		(start 327.340976 -421.321738)
		(end 327.424034 -421.740076)
		(width 0.14224)
		(layer "In6.Cu")
		(net "P5E_CPU0_P1_TX_BUF_C_DP<7>")
	)
	(segment
		(start 328.34834 -427.548802)
		(end 328.507344 -427.548802)
		(width 0.14224)
		(layer "In6.Cu")
		(net "P5E_CPU0_P1_TX_BUF_C_DP<7>")
	)
	(segment
		(start 327.424034 -421.740076)
		(end 327.585578 -421.848026)
		(width 0.14224)
		(layer "In6.Cu")
		(net "P5E_CPU0_P1_TX_BUF_C_DP<7>")
	)
	(segment
		(start 327.889108 -423.372788)
		(end 327.781158 -423.534078)
		(width 0.14224)
		(layer "In6.Cu")
		(net "P5E_CPU0_P1_TX_BUF_C_DP<7>")
	)
	(segment
		(start 327.340976 -418.702998)
		(end 327.340976 -419.72865)
		(width 0.14224)
		(layer "In6.Cu")
		(net "P5E_CPU0_P1_TX_BUF_C_DP<7>")
	)
	(segment
		(start 328.079608 -427.42739)
		(end 328.09688 -427.444662)
		(width 0.14224)
		(layer "In6.Cu")
		(net "P5E_CPU0_P1_TX_BUF_C_DP<7>")
	)
	(segment
		(start 327.805796 -422.954196)
		(end 327.889108 -423.372788)
		(width 0.14224)
		(layer "In6.Cu")
		(net "P5E_CPU0_P1_TX_BUF_C_DP<7>")
	)
	(segment
		(start 327.478136 -419.86581)
		(end 327.478136 -420.29253)
		(width 0.14224)
		(layer "In6.Cu")
		(net "P5E_CPU0_P1_TX_BUF_C_DP<7>")
	)
	(segment
		(start 328.507344 -427.548802)
		(end 328.649584 -427.406562)
		(width 0.14224)
		(layer "In6.Cu")
		(net "P5E_CPU0_P1_TX_BUF_C_DP<7>")
	)
	(segment
		(start 327.585578 -421.848026)
		(end 327.66889 -422.266618)
		(width 0.14224)
		(layer "In6.Cu")
		(net "P5E_CPU0_P1_TX_BUF_C_DP<7>")
	)
	(segment
		(start 327.781158 -423.534078)
		(end 327.991978 -424.594782)
		(width 0.14224)
		(layer "In6.Cu")
		(net "P5E_CPU0_P1_TX_BUF_C_DP<7>")
	)
	(segment
		(start 327.991978 -424.594782)
		(end 327.991978 -427.215808)
		(width 0.14224)
		(layer "In6.Cu")
		(net "P5E_CPU0_P1_TX_BUF_C_DP<7>")
	)
	(segment
		(start 327.340976 -419.72865)
		(end 327.478136 -419.86581)
		(width 0.14224)
		(layer "In6.Cu")
		(net "P5E_CPU0_P1_TX_BUF_C_DP<7>")
	)
	(segment
		(start 327.478136 -420.29253)
		(end 327.340976 -420.42969)
		(width 0.14224)
		(layer "In6.Cu")
		(net "P5E_CPU0_P1_TX_BUF_C_DP<7>")
	)
	(segment
		(start 328.649584 -427.406562)
		(end 328.649584 -427.089824)
		(width 0.14224)
		(layer "In6.Cu")
		(net "P5E_CPU0_P1_TX_BUF_C_DP<7>")
	)
	(segment
		(start 327.631806 -418.412168)
		(end 327.340976 -418.702998)
		(width 0.14224)
		(layer "In6.Cu")
		(net "P5E_CPU0_P1_TX_BUF_C_DP<7>")
	)
	(arc
		(start 328.09688 -427.444662)
		(mid 328.212251 -427.52175)
		(end 328.34834 -427.548802)
		(width 0.14224)
		(layer "In6.Cu")
		(net "P5E_CPU0_P1_TX_BUF_C_DP<7>")
	)
	(arc
		(start 327.991978 -427.215808)
		(mid 328.014754 -427.330311)
		(end 328.079608 -427.42739)
		(width 0.14224)
		(layer "In6.Cu")
		(net "P5E_CPU0_P1_TX_BUF_C_DP<7>")
	)
	(segment
		(start 324.298056 -417.461954)
		(end 324.298056 -418.141658)
		(width 0.12954)
		(layer "B.Cu")
		(net "P5E_CPU0_P1_TX_BUF_C_DP<6>")
	)
	(segment
		(start 324.593966 -417.166044)
		(end 324.298056 -417.461954)
		(width 0.12954)
		(layer "B.Cu")
		(net "P5E_CPU0_P1_TX_BUF_C_DP<6>")
	)
	(segment
		(start 324.298056 -418.141658)
		(end 324.568566 -418.412168)
		(width 0.12954)
		(layer "B.Cu")
		(net "P5E_CPU0_P1_TX_BUF_C_DP<6>")
	)
	(segment
		(start 324.414896 -420.1795)
		(end 324.277736 -420.31666)
		(width 0.14224)
		(layer "In6.Cu")
		(net "P5E_CPU0_P1_TX_BUF_C_DP<6>")
	)
	(segment
		(start 324.277736 -420.31666)
		(end 324.277736 -421.377364)
		(width 0.14224)
		(layer "In6.Cu")
		(net "P5E_CPU0_P1_TX_BUF_C_DP<6>")
	)
	(segment
		(start 326.488298 -426.567854)
		(end 326.649588 -426.406564)
		(width 0.14224)
		(layer "In6.Cu")
		(net "P5E_CPU0_P1_TX_BUF_C_DP<6>")
	)
	(segment
		(start 324.620382 -421.84574)
		(end 324.783704 -422.240202)
		(width 0.14224)
		(layer "In6.Cu")
		(net "P5E_CPU0_P1_TX_BUF_C_DP<6>")
	)
	(segment
		(start 325.303896 -423.855896)
		(end 325.483474 -423.930064)
		(width 0.14224)
		(layer "In6.Cu")
		(net "P5E_CPU0_P1_TX_BUF_C_DP<6>")
	)
	(segment
		(start 326.649588 -426.406564)
		(end 326.649588 -426.089826)
		(width 0.14224)
		(layer "In6.Cu")
		(net "P5E_CPU0_P1_TX_BUF_C_DP<6>")
	)
	(segment
		(start 324.440804 -421.771572)
		(end 324.620382 -421.84574)
		(width 0.14224)
		(layer "In6.Cu")
		(net "P5E_CPU0_P1_TX_BUF_C_DP<6>")
	)
	(segment
		(start 325.140828 -423.461688)
		(end 325.303896 -423.855896)
		(width 0.14224)
		(layer "In6.Cu")
		(net "P5E_CPU0_P1_TX_BUF_C_DP<6>")
	)
	(segment
		(start 324.277736 -421.377364)
		(end 324.440804 -421.771572)
		(width 0.14224)
		(layer "In6.Cu")
		(net "P5E_CPU0_P1_TX_BUF_C_DP<6>")
	)
	(segment
		(start 325.051928 -422.887902)
		(end 325.21525 -423.282364)
		(width 0.14224)
		(layer "In6.Cu")
		(net "P5E_CPU0_P1_TX_BUF_C_DP<6>")
	)
	(segment
		(start 324.783704 -422.240202)
		(end 324.709282 -422.419526)
		(width 0.14224)
		(layer "In6.Cu")
		(net "P5E_CPU0_P1_TX_BUF_C_DP<6>")
	)
	(segment
		(start 324.277736 -418.702998)
		(end 324.277736 -419.61562)
		(width 0.14224)
		(layer "In6.Cu")
		(net "P5E_CPU0_P1_TX_BUF_C_DP<6>")
	)
	(segment
		(start 326.072246 -426.459396)
		(end 326.098916 -426.48505)
		(width 0.14224)
		(layer "In6.Cu")
		(net "P5E_CPU0_P1_TX_BUF_C_DP<6>")
	)
	(segment
		(start 324.414896 -419.75278)
		(end 324.414896 -420.1795)
		(width 0.14224)
		(layer "In6.Cu")
		(net "P5E_CPU0_P1_TX_BUF_C_DP<6>")
	)
	(segment
		(start 325.836788 -425.537884)
		(end 325.836788 -425.887388)
		(width 0.14224)
		(layer "In6.Cu")
		(net "P5E_CPU0_P1_TX_BUF_C_DP<6>")
	)
	(segment
		(start 324.277736 -419.61562)
		(end 324.414896 -419.75278)
		(width 0.14224)
		(layer "In6.Cu")
		(net "P5E_CPU0_P1_TX_BUF_C_DP<6>")
	)
	(segment
		(start 325.572628 -424.50385)
		(end 325.685658 -424.776392)
		(width 0.14224)
		(layer "In6.Cu")
		(net "P5E_CPU0_P1_TX_BUF_C_DP<6>")
	)
	(segment
		(start 324.87235 -422.813734)
		(end 325.051928 -422.887902)
		(width 0.14224)
		(layer "In6.Cu")
		(net "P5E_CPU0_P1_TX_BUF_C_DP<6>")
	)
	(segment
		(start 326.488044 -426.567854)
		(end 326.488298 -426.567854)
		(width 0.14224)
		(layer "In6.Cu")
		(net "P5E_CPU0_P1_TX_BUF_C_DP<6>")
	)
	(segment
		(start 324.568566 -418.412168)
		(end 324.277736 -418.702998)
		(width 0.14224)
		(layer "In6.Cu")
		(net "P5E_CPU0_P1_TX_BUF_C_DP<6>")
	)
	(segment
		(start 325.21525 -423.282364)
		(end 325.140828 -423.461688)
		(width 0.14224)
		(layer "In6.Cu")
		(net "P5E_CPU0_P1_TX_BUF_C_DP<6>")
	)
	(segment
		(start 325.483474 -423.930064)
		(end 325.646796 -424.324526)
		(width 0.14224)
		(layer "In6.Cu")
		(net "P5E_CPU0_P1_TX_BUF_C_DP<6>")
	)
	(segment
		(start 325.646796 -424.324526)
		(end 325.572628 -424.50385)
		(width 0.14224)
		(layer "In6.Cu")
		(net "P5E_CPU0_P1_TX_BUF_C_DP<6>")
	)
	(segment
		(start 326.301608 -426.566838)
		(end 326.488044 -426.567854)
		(width 0.14224)
		(layer "In6.Cu")
		(net "P5E_CPU0_P1_TX_BUF_C_DP<6>")
	)
	(segment
		(start 324.709282 -422.419526)
		(end 324.87235 -422.813734)
		(width 0.14224)
		(layer "In6.Cu")
		(net "P5E_CPU0_P1_TX_BUF_C_DP<6>")
	)
	(arc
		(start 325.836788 -425.887388)
		(mid 325.898007 -426.196651)
		(end 326.072246 -426.459396)
		(width 0.14224)
		(layer "In6.Cu")
		(net "P5E_CPU0_P1_TX_BUF_C_DP<6>")
	)
	(arc
		(start 326.098916 -426.48505)
		(mid 326.192449 -426.545284)
		(end 326.301608 -426.566838)
		(width 0.14224)
		(layer "In6.Cu")
		(net "P5E_CPU0_P1_TX_BUF_C_DP<6>")
	)
	(arc
		(start 325.685658 -424.776392)
		(mid 325.798748 -425.149693)
		(end 325.836788 -425.537884)
		(width 0.14224)
		(layer "In6.Cu")
		(net "P5E_CPU0_P1_TX_BUF_C_DP<6>")
	)
	(segment
		(start 321.234816 -417.461954)
		(end 321.234816 -418.141658)
		(width 0.12954)
		(layer "B.Cu")
		(net "P5E_CPU0_P1_TX_BUF_C_DP<5>")
	)
	(segment
		(start 321.530726 -417.166044)
		(end 321.234816 -417.461954)
		(width 0.12954)
		(layer "B.Cu")
		(net "P5E_CPU0_P1_TX_BUF_C_DP<5>")
	)
	(segment
		(start 321.234816 -418.141658)
		(end 321.505326 -418.412168)
		(width 0.12954)
		(layer "B.Cu")
		(net "P5E_CPU0_P1_TX_BUF_C_DP<5>")
	)
	(segment
		(start 323.988938 -425.48175)
		(end 323.988938 -427.22927)
		(width 0.14224)
		(layer "In6.Cu")
		(net "P5E_CPU0_P1_TX_BUF_C_DP<5>")
	)
	(segment
		(start 324.649592 -427.406562)
		(end 324.649592 -427.089824)
		(width 0.14224)
		(layer "In6.Cu")
		(net "P5E_CPU0_P1_TX_BUF_C_DP<5>")
	)
	(segment
		(start 323.135752 -423.775632)
		(end 323.40677 -424.105832)
		(width 0.14224)
		(layer "In6.Cu")
		(net "P5E_CPU0_P1_TX_BUF_C_DP<5>")
	)
	(segment
		(start 323.40677 -424.105832)
		(end 323.38772 -424.298364)
		(width 0.14224)
		(layer "In6.Cu")
		(net "P5E_CPU0_P1_TX_BUF_C_DP<5>")
	)
	(segment
		(start 321.505326 -418.412168)
		(end 321.214496 -418.702998)
		(width 0.14224)
		(layer "In6.Cu")
		(net "P5E_CPU0_P1_TX_BUF_C_DP<5>")
	)
	(segment
		(start 321.214496 -418.702998)
		(end 321.214496 -419.578028)
		(width 0.14224)
		(layer "In6.Cu")
		(net "P5E_CPU0_P1_TX_BUF_C_DP<5>")
	)
	(segment
		(start 322.942712 -423.756582)
		(end 323.135752 -423.775632)
		(width 0.14224)
		(layer "In6.Cu")
		(net "P5E_CPU0_P1_TX_BUF_C_DP<5>")
	)
	(segment
		(start 321.214496 -419.578028)
		(end 321.351656 -419.715188)
		(width 0.14224)
		(layer "In6.Cu")
		(net "P5E_CPU0_P1_TX_BUF_C_DP<5>")
	)
	(segment
		(start 323.38772 -424.298364)
		(end 323.703696 -424.683428)
		(width 0.14224)
		(layer "In6.Cu")
		(net "P5E_CPU0_P1_TX_BUF_C_DP<5>")
	)
	(segment
		(start 321.54876 -422.05783)
		(end 322.227194 -422.8846)
		(width 0.14224)
		(layer "In6.Cu")
		(net "P5E_CPU0_P1_TX_BUF_C_DP<5>")
	)
	(segment
		(start 322.672202 -423.42689)
		(end 322.942712 -423.756582)
		(width 0.14224)
		(layer "In6.Cu")
		(net "P5E_CPU0_P1_TX_BUF_C_DP<5>")
	)
	(segment
		(start 322.420234 -422.90365)
		(end 322.691252 -423.23385)
		(width 0.14224)
		(layer "In6.Cu")
		(net "P5E_CPU0_P1_TX_BUF_C_DP<5>")
	)
	(segment
		(start 321.214496 -420.279068)
		(end 321.214496 -421.123364)
		(width 0.14224)
		(layer "In6.Cu")
		(net "P5E_CPU0_P1_TX_BUF_C_DP<5>")
	)
	(segment
		(start 321.351656 -420.141908)
		(end 321.214496 -420.279068)
		(width 0.14224)
		(layer "In6.Cu")
		(net "P5E_CPU0_P1_TX_BUF_C_DP<5>")
	)
	(segment
		(start 324.507352 -427.548802)
		(end 324.649592 -427.406562)
		(width 0.14224)
		(layer "In6.Cu")
		(net "P5E_CPU0_P1_TX_BUF_C_DP<5>")
	)
	(segment
		(start 322.691252 -423.23385)
		(end 322.672202 -423.42689)
		(width 0.14224)
		(layer "In6.Cu")
		(net "P5E_CPU0_P1_TX_BUF_C_DP<5>")
	)
	(segment
		(start 324.040246 -427.352968)
		(end 324.198234 -427.510956)
		(width 0.14224)
		(layer "In6.Cu")
		(net "P5E_CPU0_P1_TX_BUF_C_DP<5>")
	)
	(segment
		(start 324.28942 -427.548802)
		(end 324.507352 -427.548802)
		(width 0.14224)
		(layer "In6.Cu")
		(net "P5E_CPU0_P1_TX_BUF_C_DP<5>")
	)
	(segment
		(start 321.351656 -419.715188)
		(end 321.351656 -420.141908)
		(width 0.14224)
		(layer "In6.Cu")
		(net "P5E_CPU0_P1_TX_BUF_C_DP<5>")
	)
	(segment
		(start 322.227194 -422.8846)
		(end 322.420234 -422.90365)
		(width 0.14224)
		(layer "In6.Cu")
		(net "P5E_CPU0_P1_TX_BUF_C_DP<5>")
	)
	(arc
		(start 321.214496 -421.123364)
		(mid 321.300583 -421.619585)
		(end 321.54876 -422.05783)
		(width 0.14224)
		(layer "In6.Cu")
		(net "P5E_CPU0_P1_TX_BUF_C_DP<5>")
	)
	(arc
		(start 323.703696 -424.683428)
		(mid 323.915533 -425.057853)
		(end 323.988938 -425.48175)
		(width 0.14224)
		(layer "In6.Cu")
		(net "P5E_CPU0_P1_TX_BUF_C_DP<5>")
	)
	(arc
		(start 324.198234 -427.510956)
		(mid 324.240056 -427.538964)
		(end 324.28942 -427.548802)
		(width 0.14224)
		(layer "In6.Cu")
		(net "P5E_CPU0_P1_TX_BUF_C_DP<5>")
	)
	(arc
		(start 323.988938 -427.22927)
		(mid 324.002275 -427.296228)
		(end 324.040246 -427.352968)
		(width 0.14224)
		(layer "In6.Cu")
		(net "P5E_CPU0_P1_TX_BUF_C_DP<5>")
	)
	(segment
		(start 318.171576 -417.461954)
		(end 318.171576 -418.141658)
		(width 0.12954)
		(layer "B.Cu")
		(net "P5E_CPU0_P1_TX_BUF_C_DP<4>")
	)
	(segment
		(start 318.467486 -417.166044)
		(end 318.171576 -417.461954)
		(width 0.12954)
		(layer "B.Cu")
		(net "P5E_CPU0_P1_TX_BUF_C_DP<4>")
	)
	(segment
		(start 318.171576 -418.141658)
		(end 318.442086 -418.412168)
		(width 0.12954)
		(layer "B.Cu")
		(net "P5E_CPU0_P1_TX_BUF_C_DP<4>")
	)
	(segment
		(start 321.225164 -423.857674)
		(end 321.253612 -424.049444)
		(width 0.14224)
		(layer "In6.Cu")
		(net "P5E_CPU0_P1_TX_BUF_C_DP<4>")
	)
	(segment
		(start 318.151256 -418.702998)
		(end 318.151256 -419.552882)
		(width 0.14224)
		(layer "In6.Cu")
		(net "P5E_CPU0_P1_TX_BUF_C_DP<4>")
	)
	(segment
		(start 319.784222 -422.95953)
		(end 319.975992 -422.931082)
		(width 0.14224)
		(layer "In6.Cu")
		(net "P5E_CPU0_P1_TX_BUF_C_DP<4>")
	)
	(segment
		(start 319.441576 -422.70553)
		(end 319.784222 -422.95953)
		(width 0.14224)
		(layer "In6.Cu")
		(net "P5E_CPU0_P1_TX_BUF_C_DP<4>")
	)
	(segment
		(start 318.535812 -422.033446)
		(end 318.878458 -422.287446)
		(width 0.14224)
		(layer "In6.Cu")
		(net "P5E_CPU0_P1_TX_BUF_C_DP<4>")
	)
	(segment
		(start 322.40601 -426.569886)
		(end 322.522342 -426.569886)
		(width 0.14224)
		(layer "In6.Cu")
		(net "P5E_CPU0_P1_TX_BUF_C_DP<4>")
	)
	(segment
		(start 322.649596 -426.442632)
		(end 322.649596 -426.089826)
		(width 0.14224)
		(layer "In6.Cu")
		(net "P5E_CPU0_P1_TX_BUF_C_DP<4>")
	)
	(segment
		(start 320.347594 -423.377614)
		(end 320.69024 -423.631614)
		(width 0.14224)
		(layer "In6.Cu")
		(net "P5E_CPU0_P1_TX_BUF_C_DP<4>")
	)
	(segment
		(start 318.288416 -419.690042)
		(end 318.288416 -420.116762)
		(width 0.14224)
		(layer "In6.Cu")
		(net "P5E_CPU0_P1_TX_BUF_C_DP<4>")
	)
	(segment
		(start 322.522342 -426.569886)
		(end 322.649596 -426.442632)
		(width 0.14224)
		(layer "In6.Cu")
		(net "P5E_CPU0_P1_TX_BUF_C_DP<4>")
	)
	(segment
		(start 319.070228 -422.258998)
		(end 319.413128 -422.513506)
		(width 0.14224)
		(layer "In6.Cu")
		(net "P5E_CPU0_P1_TX_BUF_C_DP<4>")
	)
	(segment
		(start 318.442086 -418.412168)
		(end 318.151256 -418.702998)
		(width 0.14224)
		(layer "In6.Cu")
		(net "P5E_CPU0_P1_TX_BUF_C_DP<4>")
	)
	(segment
		(start 321.602354 -424.308016)
		(end 321.783202 -424.66768)
		(width 0.14224)
		(layer "In6.Cu")
		(net "P5E_CPU0_P1_TX_BUF_C_DP<4>")
	)
	(segment
		(start 319.975992 -422.931082)
		(end 320.319146 -423.18559)
		(width 0.14224)
		(layer "In6.Cu")
		(net "P5E_CPU0_P1_TX_BUF_C_DP<4>")
	)
	(segment
		(start 320.88201 -423.603166)
		(end 321.225164 -423.857674)
		(width 0.14224)
		(layer "In6.Cu")
		(net "P5E_CPU0_P1_TX_BUF_C_DP<4>")
	)
	(segment
		(start 321.253612 -424.049444)
		(end 321.602354 -424.308016)
		(width 0.14224)
		(layer "In6.Cu")
		(net "P5E_CPU0_P1_TX_BUF_C_DP<4>")
	)
	(segment
		(start 318.450214 -421.947848)
		(end 318.535812 -422.033446)
		(width 0.14224)
		(layer "In6.Cu")
		(net "P5E_CPU0_P1_TX_BUF_C_DP<4>")
	)
	(segment
		(start 321.977258 -426.269658)
		(end 322.186554 -426.478954)
		(width 0.14224)
		(layer "In6.Cu")
		(net "P5E_CPU0_P1_TX_BUF_C_DP<4>")
	)
	(segment
		(start 318.151256 -419.552882)
		(end 318.288416 -419.690042)
		(width 0.14224)
		(layer "In6.Cu")
		(net "P5E_CPU0_P1_TX_BUF_C_DP<4>")
	)
	(segment
		(start 318.878458 -422.287446)
		(end 319.070228 -422.258998)
		(width 0.14224)
		(layer "In6.Cu")
		(net "P5E_CPU0_P1_TX_BUF_C_DP<4>")
	)
	(segment
		(start 320.319146 -423.18559)
		(end 320.347594 -423.377614)
		(width 0.14224)
		(layer "In6.Cu")
		(net "P5E_CPU0_P1_TX_BUF_C_DP<4>")
	)
	(segment
		(start 319.413128 -422.513506)
		(end 319.441576 -422.70553)
		(width 0.14224)
		(layer "In6.Cu")
		(net "P5E_CPU0_P1_TX_BUF_C_DP<4>")
	)
	(segment
		(start 318.151256 -420.253922)
		(end 318.151256 -421.226234)
		(width 0.14224)
		(layer "In6.Cu")
		(net "P5E_CPU0_P1_TX_BUF_C_DP<4>")
	)
	(segment
		(start 321.783202 -424.66768)
		(end 321.783202 -425.801282)
		(width 0.14224)
		(layer "In6.Cu")
		(net "P5E_CPU0_P1_TX_BUF_C_DP<4>")
	)
	(segment
		(start 318.288416 -420.116762)
		(end 318.151256 -420.253922)
		(width 0.14224)
		(layer "In6.Cu")
		(net "P5E_CPU0_P1_TX_BUF_C_DP<4>")
	)
	(segment
		(start 320.69024 -423.631614)
		(end 320.88201 -423.603166)
		(width 0.14224)
		(layer "In6.Cu")
		(net "P5E_CPU0_P1_TX_BUF_C_DP<4>")
	)
	(arc
		(start 322.186554 -426.478954)
		(mid 322.287213 -426.546339)
		(end 322.40601 -426.569886)
		(width 0.14224)
		(layer "In6.Cu")
		(net "P5E_CPU0_P1_TX_BUF_C_DP<4>")
	)
	(arc
		(start 321.783202 -425.801282)
		(mid 321.833642 -426.05477)
		(end 321.977258 -426.269658)
		(width 0.14224)
		(layer "In6.Cu")
		(net "P5E_CPU0_P1_TX_BUF_C_DP<4>")
	)
	(arc
		(start 318.151256 -421.226234)
		(mid 318.228957 -421.616776)
		(end 318.450214 -421.947848)
		(width 0.14224)
		(layer "In6.Cu")
		(net "P5E_CPU0_P1_TX_BUF_C_DP<4>")
	)
	(segment
		(start 315.108336 -417.461954)
		(end 315.108336 -418.141658)
		(width 0.12954)
		(layer "B.Cu")
		(net "P5E_CPU0_P1_TX_BUF_C_DP<3>")
	)
	(segment
		(start 315.404246 -417.166044)
		(end 315.108336 -417.461954)
		(width 0.12954)
		(layer "B.Cu")
		(net "P5E_CPU0_P1_TX_BUF_C_DP<3>")
	)
	(segment
		(start 315.108336 -418.141658)
		(end 315.378846 -418.412168)
		(width 0.12954)
		(layer "B.Cu")
		(net "P5E_CPU0_P1_TX_BUF_C_DP<3>")
	)
	(segment
		(start 317.561722 -423.024554)
		(end 317.916306 -423.261536)
		(width 0.14224)
		(layer "In6.Cu")
		(net "P5E_CPU0_P1_TX_BUF_C_DP<3>")
	)
	(segment
		(start 318.461644 -423.460926)
		(end 318.49949 -423.651172)
		(width 0.14224)
		(layer "In6.Cu")
		(net "P5E_CPU0_P1_TX_BUF_C_DP<3>")
	)
	(segment
		(start 315.225176 -419.724586)
		(end 315.225176 -420.151306)
		(width 0.14224)
		(layer "In6.Cu")
		(net "P5E_CPU0_P1_TX_BUF_C_DP<3>")
	)
	(segment
		(start 319.97396 -424.992546)
		(end 319.97396 -427.256702)
		(width 0.14224)
		(layer "In6.Cu")
		(net "P5E_CPU0_P1_TX_BUF_C_DP<3>")
	)
	(segment
		(start 317.916306 -423.261536)
		(end 318.106552 -423.22369)
		(width 0.14224)
		(layer "In6.Cu")
		(net "P5E_CPU0_P1_TX_BUF_C_DP<3>")
	)
	(segment
		(start 315.378846 -418.412168)
		(end 315.088016 -418.702998)
		(width 0.14224)
		(layer "In6.Cu")
		(net "P5E_CPU0_P1_TX_BUF_C_DP<3>")
	)
	(segment
		(start 320.6496 -427.406562)
		(end 320.6496 -427.089824)
		(width 0.14224)
		(layer "In6.Cu")
		(net "P5E_CPU0_P1_TX_BUF_C_DP<3>")
	)
	(segment
		(start 320.50736 -427.548802)
		(end 320.6496 -427.406562)
		(width 0.14224)
		(layer "In6.Cu")
		(net "P5E_CPU0_P1_TX_BUF_C_DP<3>")
	)
	(segment
		(start 320.020188 -427.368208)
		(end 320.080386 -427.428406)
		(width 0.14224)
		(layer "In6.Cu")
		(net "P5E_CPU0_P1_TX_BUF_C_DP<3>")
	)
	(segment
		(start 315.558932 -421.956738)
		(end 316.623954 -422.397936)
		(width 0.14224)
		(layer "In6.Cu")
		(net "P5E_CPU0_P1_TX_BUF_C_DP<3>")
	)
	(segment
		(start 315.318648 -421.716454)
		(end 315.558932 -421.956738)
		(width 0.14224)
		(layer "In6.Cu")
		(net "P5E_CPU0_P1_TX_BUF_C_DP<3>")
	)
	(segment
		(start 315.225176 -420.151306)
		(end 315.088016 -420.288466)
		(width 0.14224)
		(layer "In6.Cu")
		(net "P5E_CPU0_P1_TX_BUF_C_DP<3>")
	)
	(segment
		(start 317.523876 -422.834308)
		(end 317.561722 -423.024554)
		(width 0.14224)
		(layer "In6.Cu")
		(net "P5E_CPU0_P1_TX_BUF_C_DP<3>")
	)
	(segment
		(start 316.623954 -422.397936)
		(end 316.978538 -422.634918)
		(width 0.14224)
		(layer "In6.Cu")
		(net "P5E_CPU0_P1_TX_BUF_C_DP<3>")
	)
	(segment
		(start 315.088016 -420.288466)
		(end 315.088016 -421.15994)
		(width 0.14224)
		(layer "In6.Cu")
		(net "P5E_CPU0_P1_TX_BUF_C_DP<3>")
	)
	(segment
		(start 318.106552 -423.22369)
		(end 318.461644 -423.460926)
		(width 0.14224)
		(layer "In6.Cu")
		(net "P5E_CPU0_P1_TX_BUF_C_DP<3>")
	)
	(segment
		(start 315.088016 -418.702998)
		(end 315.088016 -419.587426)
		(width 0.14224)
		(layer "In6.Cu")
		(net "P5E_CPU0_P1_TX_BUF_C_DP<3>")
	)
	(segment
		(start 316.978538 -422.634918)
		(end 317.168784 -422.597072)
		(width 0.14224)
		(layer "In6.Cu")
		(net "P5E_CPU0_P1_TX_BUF_C_DP<3>")
	)
	(segment
		(start 320.370962 -427.548802)
		(end 320.50736 -427.548802)
		(width 0.14224)
		(layer "In6.Cu")
		(net "P5E_CPU0_P1_TX_BUF_C_DP<3>")
	)
	(segment
		(start 317.168784 -422.597072)
		(end 317.523876 -422.834308)
		(width 0.14224)
		(layer "In6.Cu")
		(net "P5E_CPU0_P1_TX_BUF_C_DP<3>")
	)
	(segment
		(start 315.088016 -419.587426)
		(end 315.225176 -419.724586)
		(width 0.14224)
		(layer "In6.Cu")
		(net "P5E_CPU0_P1_TX_BUF_C_DP<3>")
	)
	(segment
		(start 318.49949 -423.651172)
		(end 319.678304 -424.43908)
		(width 0.14224)
		(layer "In6.Cu")
		(net "P5E_CPU0_P1_TX_BUF_C_DP<3>")
	)
	(arc
		(start 320.080386 -427.428406)
		(mid 320.213703 -427.517486)
		(end 320.370962 -427.548802)
		(width 0.14224)
		(layer "In6.Cu")
		(net "P5E_CPU0_P1_TX_BUF_C_DP<3>")
	)
	(arc
		(start 319.97396 -427.256702)
		(mid 319.985982 -427.31705)
		(end 320.020188 -427.368208)
		(width 0.14224)
		(layer "In6.Cu")
		(net "P5E_CPU0_P1_TX_BUF_C_DP<3>")
	)
	(arc
		(start 315.088016 -421.15994)
		(mid 315.148017 -421.461114)
		(end 315.318648 -421.716454)
		(width 0.14224)
		(layer "In6.Cu")
		(net "P5E_CPU0_P1_TX_BUF_C_DP<3>")
	)
	(arc
		(start 319.678304 -424.43908)
		(mid 319.895376 -424.678816)
		(end 319.97396 -424.992546)
		(width 0.14224)
		(layer "In6.Cu")
		(net "P5E_CPU0_P1_TX_BUF_C_DP<3>")
	)
	(segment
		(start 312.045096 -417.461954)
		(end 312.045096 -418.141658)
		(width 0.12954)
		(layer "B.Cu")
		(net "P5E_CPU0_P1_TX_BUF_C_DP<2>")
	)
	(segment
		(start 312.045096 -418.141658)
		(end 312.315606 -418.412168)
		(width 0.12954)
		(layer "B.Cu")
		(net "P5E_CPU0_P1_TX_BUF_C_DP<2>")
	)
	(segment
		(start 312.341006 -417.166044)
		(end 312.045096 -417.461954)
		(width 0.12954)
		(layer "B.Cu")
		(net "P5E_CPU0_P1_TX_BUF_C_DP<2>")
	)
	(segment
		(start 317.740538 -425.09186)
		(end 317.740538 -425.586398)
		(width 0.14224)
		(layer "In6.Cu")
		(net "P5E_CPU0_P1_TX_BUF_C_DP<2>")
	)
	(segment
		(start 316.150498 -423.324274)
		(end 316.54496 -423.487596)
		(width 0.14224)
		(layer "In6.Cu")
		(net "P5E_CPU0_P1_TX_BUF_C_DP<2>")
	)
	(segment
		(start 316.54496 -423.487596)
		(end 316.619382 -423.66692)
		(width 0.14224)
		(layer "In6.Cu")
		(net "P5E_CPU0_P1_TX_BUF_C_DP<2>")
	)
	(segment
		(start 314.929266 -422.966896)
		(end 315.108336 -422.892728)
		(width 0.14224)
		(layer "In6.Cu")
		(net "P5E_CPU0_P1_TX_BUF_C_DP<2>")
	)
	(segment
		(start 313.887104 -422.53535)
		(end 314.066174 -422.461182)
		(width 0.14224)
		(layer "In6.Cu")
		(net "P5E_CPU0_P1_TX_BUF_C_DP<2>")
	)
	(segment
		(start 314.535058 -422.803828)
		(end 314.929266 -422.966896)
		(width 0.14224)
		(layer "In6.Cu")
		(net "P5E_CPU0_P1_TX_BUF_C_DP<2>")
	)
	(segment
		(start 318.402462 -426.548804)
		(end 318.507364 -426.548804)
		(width 0.14224)
		(layer "In6.Cu")
		(net "P5E_CPU0_P1_TX_BUF_C_DP<2>")
	)
	(segment
		(start 316.799976 -423.741342)
		(end 316.799976 -423.74185)
		(width 0.14224)
		(layer "In6.Cu")
		(net "P5E_CPU0_P1_TX_BUF_C_DP<2>")
	)
	(segment
		(start 316.799976 -423.74185)
		(end 317.032894 -423.83837)
		(width 0.14224)
		(layer "In6.Cu")
		(net "P5E_CPU0_P1_TX_BUF_C_DP<2>")
	)
	(segment
		(start 312.35396 -421.900604)
		(end 312.844942 -422.103804)
		(width 0.14224)
		(layer "In6.Cu")
		(net "P5E_CPU0_P1_TX_BUF_C_DP<2>")
	)
	(segment
		(start 312.024776 -420.178738)
		(end 312.024776 -421.30726)
		(width 0.14224)
		(layer "In6.Cu")
		(net "P5E_CPU0_P1_TX_BUF_C_DP<2>")
	)
	(segment
		(start 317.032894 -423.83837)
		(end 317.354458 -424.159934)
		(width 0.14224)
		(layer "In6.Cu")
		(net "P5E_CPU0_P1_TX_BUF_C_DP<2>")
	)
	(segment
		(start 312.161936 -419.614858)
		(end 312.161936 -420.041578)
		(width 0.14224)
		(layer "In6.Cu")
		(net "P5E_CPU0_P1_TX_BUF_C_DP<2>")
	)
	(segment
		(start 315.502798 -423.05605)
		(end 315.57722 -423.235374)
		(width 0.14224)
		(layer "In6.Cu")
		(net "P5E_CPU0_P1_TX_BUF_C_DP<2>")
	)
	(segment
		(start 312.211466 -421.75811)
		(end 312.35396 -421.900604)
		(width 0.14224)
		(layer "In6.Cu")
		(net "P5E_CPU0_P1_TX_BUF_C_DP<2>")
	)
	(segment
		(start 314.460636 -422.624504)
		(end 314.535058 -422.803828)
		(width 0.14224)
		(layer "In6.Cu")
		(net "P5E_CPU0_P1_TX_BUF_C_DP<2>")
	)
	(segment
		(start 315.57722 -423.235374)
		(end 315.971428 -423.398442)
		(width 0.14224)
		(layer "In6.Cu")
		(net "P5E_CPU0_P1_TX_BUF_C_DP<2>")
	)
	(segment
		(start 318.507364 -426.548804)
		(end 318.649604 -426.406564)
		(width 0.14224)
		(layer "In6.Cu")
		(net "P5E_CPU0_P1_TX_BUF_C_DP<2>")
	)
	(segment
		(start 313.024012 -422.029636)
		(end 313.418728 -422.192704)
		(width 0.14224)
		(layer "In6.Cu")
		(net "P5E_CPU0_P1_TX_BUF_C_DP<2>")
	)
	(segment
		(start 312.024776 -419.477698)
		(end 312.161936 -419.614858)
		(width 0.14224)
		(layer "In6.Cu")
		(net "P5E_CPU0_P1_TX_BUF_C_DP<2>")
	)
	(segment
		(start 314.066174 -422.461182)
		(end 314.460636 -422.624504)
		(width 0.14224)
		(layer "In6.Cu")
		(net "P5E_CPU0_P1_TX_BUF_C_DP<2>")
	)
	(segment
		(start 312.024776 -418.702998)
		(end 312.024776 -419.477698)
		(width 0.14224)
		(layer "In6.Cu")
		(net "P5E_CPU0_P1_TX_BUF_C_DP<2>")
	)
	(segment
		(start 318.649604 -426.406564)
		(end 318.649604 -426.089826)
		(width 0.14224)
		(layer "In6.Cu")
		(net "P5E_CPU0_P1_TX_BUF_C_DP<2>")
	)
	(segment
		(start 313.492896 -422.372282)
		(end 313.887104 -422.53535)
		(width 0.14224)
		(layer "In6.Cu")
		(net "P5E_CPU0_P1_TX_BUF_C_DP<2>")
	)
	(segment
		(start 315.108336 -422.892728)
		(end 315.502798 -423.05605)
		(width 0.14224)
		(layer "In6.Cu")
		(net "P5E_CPU0_P1_TX_BUF_C_DP<2>")
	)
	(segment
		(start 316.619382 -423.66692)
		(end 316.799976 -423.741342)
		(width 0.14224)
		(layer "In6.Cu")
		(net "P5E_CPU0_P1_TX_BUF_C_DP<2>")
	)
	(segment
		(start 313.418728 -422.192704)
		(end 313.492896 -422.372282)
		(width 0.14224)
		(layer "In6.Cu")
		(net "P5E_CPU0_P1_TX_BUF_C_DP<2>")
	)
	(segment
		(start 315.971428 -423.398442)
		(end 316.150498 -423.324274)
		(width 0.14224)
		(layer "In6.Cu")
		(net "P5E_CPU0_P1_TX_BUF_C_DP<2>")
	)
	(segment
		(start 312.844942 -422.103804)
		(end 313.024012 -422.029636)
		(width 0.14224)
		(layer "In6.Cu")
		(net "P5E_CPU0_P1_TX_BUF_C_DP<2>")
	)
	(segment
		(start 312.161936 -420.041578)
		(end 312.024776 -420.178738)
		(width 0.14224)
		(layer "In6.Cu")
		(net "P5E_CPU0_P1_TX_BUF_C_DP<2>")
	)
	(segment
		(start 312.315606 -418.412168)
		(end 312.024776 -418.702998)
		(width 0.14224)
		(layer "In6.Cu")
		(net "P5E_CPU0_P1_TX_BUF_C_DP<2>")
	)
	(arc
		(start 318.084454 -426.416978)
		(mid 318.230343 -426.514521)
		(end 318.402462 -426.548804)
		(width 0.14224)
		(layer "In6.Cu")
		(net "P5E_CPU0_P1_TX_BUF_C_DP<2>")
	)
	(arc
		(start 312.024776 -421.30726)
		(mid 312.073291 -421.55125)
		(end 312.211466 -421.75811)
		(width 0.14224)
		(layer "In6.Cu")
		(net "P5E_CPU0_P1_TX_BUF_C_DP<2>")
	)
	(arc
		(start 317.740538 -425.586398)
		(mid 317.829911 -426.035887)
		(end 318.084454 -426.416978)
		(width 0.14224)
		(layer "In6.Cu")
		(net "P5E_CPU0_P1_TX_BUF_C_DP<2>")
	)
	(arc
		(start 317.354458 -424.159934)
		(mid 317.640206 -424.587491)
		(end 317.740538 -425.09186)
		(width 0.14224)
		(layer "In6.Cu")
		(net "P5E_CPU0_P1_TX_BUF_C_DP<2>")
	)
	(segment
		(start 308.981856 -417.461954)
		(end 308.981856 -418.141658)
		(width 0.12954)
		(layer "B.Cu")
		(net "P5E_CPU0_P1_TX_BUF_C_DP<1>")
	)
	(segment
		(start 309.277766 -417.166044)
		(end 308.981856 -417.461954)
		(width 0.12954)
		(layer "B.Cu")
		(net "P5E_CPU0_P1_TX_BUF_C_DP<1>")
	)
	(segment
		(start 308.981856 -418.141658)
		(end 309.252366 -418.412168)
		(width 0.12954)
		(layer "B.Cu")
		(net "P5E_CPU0_P1_TX_BUF_C_DP<1>")
	)
	(segment
		(start 308.961536 -420.72433)
		(end 308.961536 -421.516302)
		(width 0.14224)
		(layer "In6.Cu")
		(net "P5E_CPU0_P1_TX_BUF_C_DP<1>")
	)
	(segment
		(start 308.961536 -420.04361)
		(end 309.088536 -420.17061)
		(width 0.14224)
		(layer "In6.Cu")
		(net "P5E_CPU0_P1_TX_BUF_C_DP<1>")
	)
	(segment
		(start 310.749188 -422.497758)
		(end 311.150762 -422.641268)
		(width 0.14224)
		(layer "In6.Cu")
		(net "P5E_CPU0_P1_TX_BUF_C_DP<1>")
	)
	(segment
		(start 309.088536 -420.59733)
		(end 308.961536 -420.72433)
		(width 0.14224)
		(layer "In6.Cu")
		(net "P5E_CPU0_P1_TX_BUF_C_DP<1>")
	)
	(segment
		(start 316.522354 -427.548802)
		(end 316.649608 -427.421548)
		(width 0.14224)
		(layer "In6.Cu")
		(net "P5E_CPU0_P1_TX_BUF_C_DP<1>")
	)
	(segment
		(start 311.150762 -422.641268)
		(end 311.313322 -422.56456)
		(width 0.14224)
		(layer "In6.Cu")
		(net "P5E_CPU0_P1_TX_BUF_C_DP<1>")
	)
	(segment
		(start 309.010304 -421.633904)
		(end 309.337964 -421.961564)
		(width 0.14224)
		(layer "In6.Cu")
		(net "P5E_CPU0_P1_TX_BUF_C_DP<1>")
	)
	(segment
		(start 311.792112 -422.870884)
		(end 314.96762 -424.006264)
		(width 0.14224)
		(layer "In6.Cu")
		(net "P5E_CPU0_P1_TX_BUF_C_DP<1>")
	)
	(segment
		(start 309.252366 -418.412168)
		(end 308.961536 -418.702998)
		(width 0.14224)
		(layer "In6.Cu")
		(net "P5E_CPU0_P1_TX_BUF_C_DP<1>")
	)
	(segment
		(start 308.961536 -418.702998)
		(end 308.961536 -420.04361)
		(width 0.14224)
		(layer "In6.Cu")
		(net "P5E_CPU0_P1_TX_BUF_C_DP<1>")
	)
	(segment
		(start 311.71515 -422.70807)
		(end 311.792112 -422.870884)
		(width 0.14224)
		(layer "In6.Cu")
		(net "P5E_CPU0_P1_TX_BUF_C_DP<1>")
	)
	(segment
		(start 309.088536 -420.17061)
		(end 309.088536 -420.59733)
		(width 0.14224)
		(layer "In6.Cu")
		(net "P5E_CPU0_P1_TX_BUF_C_DP<1>")
	)
	(segment
		(start 311.313322 -422.56456)
		(end 311.71515 -422.70807)
		(width 0.14224)
		(layer "In6.Cu")
		(net "P5E_CPU0_P1_TX_BUF_C_DP<1>")
	)
	(segment
		(start 310.270144 -422.191434)
		(end 310.672226 -422.335198)
		(width 0.14224)
		(layer "In6.Cu")
		(net "P5E_CPU0_P1_TX_BUF_C_DP<1>")
	)
	(segment
		(start 309.451756 -422.0337)
		(end 310.107838 -422.268142)
		(width 0.14224)
		(layer "In6.Cu")
		(net "P5E_CPU0_P1_TX_BUF_C_DP<1>")
	)
	(segment
		(start 310.107838 -422.268142)
		(end 310.270144 -422.191434)
		(width 0.14224)
		(layer "In6.Cu")
		(net "P5E_CPU0_P1_TX_BUF_C_DP<1>")
	)
	(segment
		(start 316.377828 -427.548802)
		(end 316.522354 -427.548802)
		(width 0.14224)
		(layer "In6.Cu")
		(net "P5E_CPU0_P1_TX_BUF_C_DP<1>")
	)
	(segment
		(start 315.986668 -425.336716)
		(end 315.986668 -427.157642)
		(width 0.14224)
		(layer "In6.Cu")
		(net "P5E_CPU0_P1_TX_BUF_C_DP<1>")
	)
	(segment
		(start 310.672226 -422.335198)
		(end 310.749188 -422.497758)
		(width 0.14224)
		(layer "In6.Cu")
		(net "P5E_CPU0_P1_TX_BUF_C_DP<1>")
	)
	(segment
		(start 315.55182 -424.358562)
		(end 315.602366 -424.409108)
		(width 0.14224)
		(layer "In6.Cu")
		(net "P5E_CPU0_P1_TX_BUF_C_DP<1>")
	)
	(segment
		(start 316.649608 -427.421548)
		(end 316.649608 -427.089824)
		(width 0.14224)
		(layer "In6.Cu")
		(net "P5E_CPU0_P1_TX_BUF_C_DP<1>")
	)
	(arc
		(start 315.986668 -427.157642)
		(mid 316.101236 -427.434234)
		(end 316.377828 -427.548802)
		(width 0.14224)
		(layer "In6.Cu")
		(net "P5E_CPU0_P1_TX_BUF_C_DP<1>")
	)
	(arc
		(start 315.602366 -424.409108)
		(mid 315.88679 -424.834684)
		(end 315.986668 -425.336716)
		(width 0.14224)
		(layer "In6.Cu")
		(net "P5E_CPU0_P1_TX_BUF_C_DP<1>")
	)
	(arc
		(start 314.96762 -424.006264)
		(mid 315.28124 -424.146728)
		(end 315.55182 -424.358562)
		(width 0.14224)
		(layer "In6.Cu")
		(net "P5E_CPU0_P1_TX_BUF_C_DP<1>")
	)
	(arc
		(start 309.337964 -421.961564)
		(mid 309.390859 -422.003944)
		(end 309.451756 -422.0337)
		(width 0.14224)
		(layer "In6.Cu")
		(net "P5E_CPU0_P1_TX_BUF_C_DP<1>")
	)
	(arc
		(start 308.961536 -421.516302)
		(mid 308.974215 -421.579955)
		(end 309.010304 -421.633904)
		(width 0.14224)
		(layer "In6.Cu")
		(net "P5E_CPU0_P1_TX_BUF_C_DP<1>")
	)
	(segment
		(start 352.163126 -417.166044)
		(end 351.867216 -417.461954)
		(width 0.12954)
		(layer "B.Cu")
		(net "P5E_CPU0_P1_TX_BUF_C_DP<15>")
	)
	(segment
		(start 351.867216 -417.461954)
		(end 351.867216 -418.141658)
		(width 0.12954)
		(layer "B.Cu")
		(net "P5E_CPU0_P1_TX_BUF_C_DP<15>")
	)
	(segment
		(start 351.867216 -418.141658)
		(end 352.137726 -418.412168)
		(width 0.12954)
		(layer "B.Cu")
		(net "P5E_CPU0_P1_TX_BUF_C_DP<15>")
	)
	(segment
		(start 348.012766 -423.580052)
		(end 347.90507 -423.741342)
		(width 0.14224)
		(layer "In6.Cu")
		(net "P5E_CPU0_P1_TX_BUF_C_DP<15>")
	)
	(segment
		(start 350.145096 -422.845484)
		(end 350.070928 -423.024808)
		(width 0.14224)
		(layer "In6.Cu")
		(net "P5E_CPU0_P1_TX_BUF_C_DP<15>")
	)
	(segment
		(start 345.24569 -424.241976)
		(end 344.973656 -424.51401)
		(width 0.14224)
		(layer "In6.Cu")
		(net "P5E_CPU0_P1_TX_BUF_C_DP<15>")
	)
	(segment
		(start 351.03308 -422.477692)
		(end 350.145096 -422.845484)
		(width 0.14224)
		(layer "In6.Cu")
		(net "P5E_CPU0_P1_TX_BUF_C_DP<15>")
	)
	(segment
		(start 351.846896 -419.478714)
		(end 351.984056 -419.615874)
		(width 0.14224)
		(layer "In6.Cu")
		(net "P5E_CPU0_P1_TX_BUF_C_DP<15>")
	)
	(segment
		(start 345.649804 -427.406562)
		(end 345.649804 -427.089824)
		(width 0.14224)
		(layer "In6.Cu")
		(net "P5E_CPU0_P1_TX_BUF_C_DP<15>")
	)
	(segment
		(start 345.580462 -424.062906)
		(end 345.24569 -424.241976)
		(width 0.14224)
		(layer "In6.Cu")
		(net "P5E_CPU0_P1_TX_BUF_C_DP<15>")
	)
	(segment
		(start 351.984056 -420.042594)
		(end 351.846896 -420.179754)
		(width 0.14224)
		(layer "In6.Cu")
		(net "P5E_CPU0_P1_TX_BUF_C_DP<15>")
	)
	(segment
		(start 349.676212 -423.18813)
		(end 349.497142 -423.113962)
		(width 0.14224)
		(layer "In6.Cu")
		(net "P5E_CPU0_P1_TX_BUF_C_DP<15>")
	)
	(segment
		(start 345.341194 -427.548802)
		(end 345.507564 -427.548802)
		(width 0.14224)
		(layer "In6.Cu")
		(net "P5E_CPU0_P1_TX_BUF_C_DP<15>")
	)
	(segment
		(start 349.497142 -423.113962)
		(end 348.785434 -423.408602)
		(width 0.14224)
		(layer "In6.Cu")
		(net "P5E_CPU0_P1_TX_BUF_C_DP<15>")
	)
	(segment
		(start 351.846896 -418.702998)
		(end 351.846896 -419.478714)
		(width 0.14224)
		(layer "In6.Cu")
		(net "P5E_CPU0_P1_TX_BUF_C_DP<15>")
	)
	(segment
		(start 348.612714 -423.460926)
		(end 348.012766 -423.580052)
		(width 0.14224)
		(layer "In6.Cu")
		(net "P5E_CPU0_P1_TX_BUF_C_DP<15>")
	)
	(segment
		(start 344.973656 -424.51401)
		(end 344.973656 -427.267116)
		(width 0.14224)
		(layer "In6.Cu")
		(net "P5E_CPU0_P1_TX_BUF_C_DP<15>")
	)
	(segment
		(start 347.324934 -423.716704)
		(end 345.580462 -424.062906)
		(width 0.14224)
		(layer "In6.Cu")
		(net "P5E_CPU0_P1_TX_BUF_C_DP<15>")
	)
	(segment
		(start 347.90507 -423.741342)
		(end 347.486224 -423.824654)
		(width 0.14224)
		(layer "In6.Cu")
		(net "P5E_CPU0_P1_TX_BUF_C_DP<15>")
	)
	(segment
		(start 345.024964 -427.390814)
		(end 345.070938 -427.436788)
		(width 0.14224)
		(layer "In6.Cu")
		(net "P5E_CPU0_P1_TX_BUF_C_DP<15>")
	)
	(segment
		(start 347.486224 -423.824654)
		(end 347.324934 -423.716704)
		(width 0.14224)
		(layer "In6.Cu")
		(net "P5E_CPU0_P1_TX_BUF_C_DP<15>")
	)
	(segment
		(start 351.846896 -420.179754)
		(end 351.846896 -421.544496)
		(width 0.14224)
		(layer "In6.Cu")
		(net "P5E_CPU0_P1_TX_BUF_C_DP<15>")
	)
	(segment
		(start 351.717102 -421.858186)
		(end 351.229168 -422.34612)
		(width 0.14224)
		(layer "In6.Cu")
		(net "P5E_CPU0_P1_TX_BUF_C_DP<15>")
	)
	(segment
		(start 345.507564 -427.548802)
		(end 345.649804 -427.406562)
		(width 0.14224)
		(layer "In6.Cu")
		(net "P5E_CPU0_P1_TX_BUF_C_DP<15>")
	)
	(segment
		(start 351.984056 -419.615874)
		(end 351.984056 -420.042594)
		(width 0.14224)
		(layer "In6.Cu")
		(net "P5E_CPU0_P1_TX_BUF_C_DP<15>")
	)
	(segment
		(start 352.137726 -418.412168)
		(end 351.846896 -418.702998)
		(width 0.14224)
		(layer "In6.Cu")
		(net "P5E_CPU0_P1_TX_BUF_C_DP<15>")
	)
	(segment
		(start 350.070928 -423.024808)
		(end 349.676212 -423.18813)
		(width 0.14224)
		(layer "In6.Cu")
		(net "P5E_CPU0_P1_TX_BUF_C_DP<15>")
	)
	(arc
		(start 351.846896 -421.544496)
		(mid 351.813206 -421.714249)
		(end 351.717102 -421.858186)
		(width 0.14224)
		(layer "In6.Cu")
		(net "P5E_CPU0_P1_TX_BUF_C_DP<15>")
	)
	(arc
		(start 348.785434 -423.408602)
		(mid 348.700349 -423.438972)
		(end 348.612714 -423.460926)
		(width 0.14224)
		(layer "In6.Cu")
		(net "P5E_CPU0_P1_TX_BUF_C_DP<15>")
	)
	(arc
		(start 345.070938 -427.436788)
		(mid 345.194918 -427.519692)
		(end 345.341194 -427.548802)
		(width 0.14224)
		(layer "In6.Cu")
		(net "P5E_CPU0_P1_TX_BUF_C_DP<15>")
	)
	(arc
		(start 351.229168 -422.34612)
		(mid 351.137623 -422.421597)
		(end 351.03308 -422.477692)
		(width 0.14224)
		(layer "In6.Cu")
		(net "P5E_CPU0_P1_TX_BUF_C_DP<15>")
	)
	(arc
		(start 344.973656 -427.267116)
		(mid 344.986993 -427.334074)
		(end 345.024964 -427.390814)
		(width 0.14224)
		(layer "In6.Cu")
		(net "P5E_CPU0_P1_TX_BUF_C_DP<15>")
	)
	(segment
		(start 348.803976 -417.461954)
		(end 348.803976 -418.141658)
		(width 0.12954)
		(layer "B.Cu")
		(net "P5E_CPU0_P1_TX_BUF_C_DP<14>")
	)
	(segment
		(start 349.099886 -417.166044)
		(end 348.803976 -417.461954)
		(width 0.12954)
		(layer "B.Cu")
		(net "P5E_CPU0_P1_TX_BUF_C_DP<14>")
	)
	(segment
		(start 348.803976 -418.141658)
		(end 349.074486 -418.412168)
		(width 0.12954)
		(layer "B.Cu")
		(net "P5E_CPU0_P1_TX_BUF_C_DP<14>")
	)
	(segment
		(start 343.493344 -426.583856)
		(end 343.649808 -426.427392)
		(width 0.14224)
		(layer "In6.Cu")
		(net "P5E_CPU0_P1_TX_BUF_C_DP<14>")
	)
	(segment
		(start 348.783656 -420.146988)
		(end 348.922848 -420.28618)
		(width 0.14224)
		(layer "In6.Cu")
		(net "P5E_CPU0_P1_TX_BUF_C_DP<14>")
	)
	(segment
		(start 348.922848 -420.28618)
		(end 348.922848 -420.57066)
		(width 0.14224)
		(layer "In6.Cu")
		(net "P5E_CPU0_P1_TX_BUF_C_DP<14>")
	)
	(segment
		(start 348.783656 -421.546274)
		(end 347.970348 -422.358566)
		(width 0.14224)
		(layer "In6.Cu")
		(net "P5E_CPU0_P1_TX_BUF_C_DP<14>")
	)
	(segment
		(start 343.649808 -426.427392)
		(end 343.649808 -426.089826)
		(width 0.14224)
		(layer "In6.Cu")
		(net "P5E_CPU0_P1_TX_BUF_C_DP<14>")
	)
	(segment
		(start 348.922848 -419.723316)
		(end 348.783656 -419.862508)
		(width 0.14224)
		(layer "In6.Cu")
		(net "P5E_CPU0_P1_TX_BUF_C_DP<14>")
	)
	(segment
		(start 349.074486 -418.412168)
		(end 348.783656 -418.702998)
		(width 0.14224)
		(layer "In6.Cu")
		(net "P5E_CPU0_P1_TX_BUF_C_DP<14>")
	)
	(segment
		(start 348.783656 -420.709852)
		(end 348.783656 -421.546274)
		(width 0.14224)
		(layer "In6.Cu")
		(net "P5E_CPU0_P1_TX_BUF_C_DP<14>")
	)
	(segment
		(start 343.228168 -426.583856)
		(end 343.493344 -426.583856)
		(width 0.14224)
		(layer "In6.Cu")
		(net "P5E_CPU0_P1_TX_BUF_C_DP<14>")
	)
	(segment
		(start 348.783656 -419.299644)
		(end 348.922848 -419.438836)
		(width 0.14224)
		(layer "In6.Cu")
		(net "P5E_CPU0_P1_TX_BUF_C_DP<14>")
	)
	(segment
		(start 346.930472 -422.674288)
		(end 344.777314 -423.327576)
		(width 0.14224)
		(layer "In6.Cu")
		(net "P5E_CPU0_P1_TX_BUF_C_DP<14>")
	)
	(segment
		(start 344.284046 -423.610024)
		(end 344.12555 -423.525442)
		(width 0.14224)
		(layer "In6.Cu")
		(net "P5E_CPU0_P1_TX_BUF_C_DP<14>")
	)
	(segment
		(start 348.783656 -418.702998)
		(end 348.783656 -419.299644)
		(width 0.14224)
		(layer "In6.Cu")
		(net "P5E_CPU0_P1_TX_BUF_C_DP<14>")
	)
	(segment
		(start 347.5101 -422.641776)
		(end 347.101414 -422.765728)
		(width 0.14224)
		(layer "In6.Cu")
		(net "P5E_CPU0_P1_TX_BUF_C_DP<14>")
	)
	(segment
		(start 347.60154 -422.470326)
		(end 347.5101 -422.641776)
		(width 0.14224)
		(layer "In6.Cu")
		(net "P5E_CPU0_P1_TX_BUF_C_DP<14>")
	)
	(segment
		(start 344.692478 -423.486072)
		(end 344.284046 -423.610024)
		(width 0.14224)
		(layer "In6.Cu")
		(net "P5E_CPU0_P1_TX_BUF_C_DP<14>")
	)
	(segment
		(start 348.922848 -419.438836)
		(end 348.922848 -419.723316)
		(width 0.14224)
		(layer "In6.Cu")
		(net "P5E_CPU0_P1_TX_BUF_C_DP<14>")
	)
	(segment
		(start 347.101414 -422.765728)
		(end 346.930472 -422.674288)
		(width 0.14224)
		(layer "In6.Cu")
		(net "P5E_CPU0_P1_TX_BUF_C_DP<14>")
	)
	(segment
		(start 348.783656 -419.862508)
		(end 348.783656 -420.146988)
		(width 0.14224)
		(layer "In6.Cu")
		(net "P5E_CPU0_P1_TX_BUF_C_DP<14>")
	)
	(segment
		(start 343.717372 -423.64914)
		(end 343.005664 -424.360848)
		(width 0.14224)
		(layer "In6.Cu")
		(net "P5E_CPU0_P1_TX_BUF_C_DP<14>")
	)
	(segment
		(start 342.903048 -424.608498)
		(end 342.903048 -426.09008)
		(width 0.14224)
		(layer "In6.Cu")
		(net "P5E_CPU0_P1_TX_BUF_C_DP<14>")
	)
	(segment
		(start 347.970348 -422.358566)
		(end 347.60154 -422.470326)
		(width 0.14224)
		(layer "In6.Cu")
		(net "P5E_CPU0_P1_TX_BUF_C_DP<14>")
	)
	(segment
		(start 348.922848 -420.57066)
		(end 348.783656 -420.709852)
		(width 0.14224)
		(layer "In6.Cu")
		(net "P5E_CPU0_P1_TX_BUF_C_DP<14>")
	)
	(segment
		(start 344.12555 -423.525442)
		(end 343.717372 -423.64914)
		(width 0.14224)
		(layer "In6.Cu")
		(net "P5E_CPU0_P1_TX_BUF_C_DP<14>")
	)
	(segment
		(start 343.073736 -426.501814)
		(end 343.104724 -426.532802)
		(width 0.14224)
		(layer "In6.Cu")
		(net "P5E_CPU0_P1_TX_BUF_C_DP<14>")
	)
	(segment
		(start 344.777314 -423.327576)
		(end 344.692478 -423.486072)
		(width 0.14224)
		(layer "In6.Cu")
		(net "P5E_CPU0_P1_TX_BUF_C_DP<14>")
	)
	(arc
		(start 343.104724 -426.532802)
		(mid 343.161361 -426.570645)
		(end 343.228168 -426.583856)
		(width 0.14224)
		(layer "In6.Cu")
		(net "P5E_CPU0_P1_TX_BUF_C_DP<14>")
	)
	(arc
		(start 342.903048 -426.09008)
		(mid 342.909663 -426.177826)
		(end 342.929464 -426.263562)
		(width 0.14224)
		(layer "In6.Cu")
		(net "P5E_CPU0_P1_TX_BUF_C_DP<14>")
	)
	(arc
		(start 343.005664 -424.360848)
		(mid 342.929744 -424.474471)
		(end 342.903048 -424.608498)
		(width 0.14224)
		(layer "In6.Cu")
		(net "P5E_CPU0_P1_TX_BUF_C_DP<14>")
	)
	(arc
		(start 342.929464 -426.263562)
		(mid 342.987121 -426.391458)
		(end 343.073736 -426.501814)
		(width 0.14224)
		(layer "In6.Cu")
		(net "P5E_CPU0_P1_TX_BUF_C_DP<14>")
	)
	(segment
		(start 346.036646 -417.166044)
		(end 345.740736 -417.461954)
		(width 0.12954)
		(layer "B.Cu")
		(net "P5E_CPU0_P1_TX_BUF_C_DP<13>")
	)
	(segment
		(start 345.740736 -417.461954)
		(end 345.740736 -418.141658)
		(width 0.12954)
		(layer "B.Cu")
		(net "P5E_CPU0_P1_TX_BUF_C_DP<13>")
	)
	(segment
		(start 345.740736 -418.141658)
		(end 346.011246 -418.412168)
		(width 0.12954)
		(layer "B.Cu")
		(net "P5E_CPU0_P1_TX_BUF_C_DP<13>")
	)
	(segment
		(start 345.720416 -418.702998)
		(end 345.720416 -419.495478)
		(width 0.14224)
		(layer "In6.Cu")
		(net "P5E_CPU0_P1_TX_BUF_C_DP<13>")
	)
	(segment
		(start 345.385136 -421.917876)
		(end 345.179904 -422.123362)
		(width 0.14224)
		(layer "In6.Cu")
		(net "P5E_CPU0_P1_TX_BUF_C_DP<13>")
	)
	(segment
		(start 342.690196 -423.07637)
		(end 342.360504 -423.34688)
		(width 0.14224)
		(layer "In6.Cu")
		(net "P5E_CPU0_P1_TX_BUF_C_DP<13>")
	)
	(segment
		(start 341.649812 -427.406562)
		(end 341.649812 -427.089824)
		(width 0.14224)
		(layer "In6.Cu")
		(net "P5E_CPU0_P1_TX_BUF_C_DP<13>")
	)
	(segment
		(start 345.857576 -420.059358)
		(end 345.720416 -420.196518)
		(width 0.14224)
		(layer "In6.Cu")
		(net "P5E_CPU0_P1_TX_BUF_C_DP<13>")
	)
	(segment
		(start 345.720416 -419.495478)
		(end 345.857576 -419.632638)
		(width 0.14224)
		(layer "In6.Cu")
		(net "P5E_CPU0_P1_TX_BUF_C_DP<13>")
	)
	(segment
		(start 341.507572 -427.548802)
		(end 341.649812 -427.406562)
		(width 0.14224)
		(layer "In6.Cu")
		(net "P5E_CPU0_P1_TX_BUF_C_DP<13>")
	)
	(segment
		(start 344.677492 -422.326562)
		(end 343.657428 -422.326562)
		(width 0.14224)
		(layer "In6.Cu")
		(net "P5E_CPU0_P1_TX_BUF_C_DP<13>")
	)
	(segment
		(start 340.989412 -424.87215)
		(end 340.989158 -424.871896)
		(width 0.14224)
		(layer "In6.Cu")
		(net "P5E_CPU0_P1_TX_BUF_C_DP<13>")
	)
	(segment
		(start 342.011508 -423.810938)
		(end 341.818468 -423.791888)
		(width 0.14224)
		(layer "In6.Cu")
		(net "P5E_CPU0_P1_TX_BUF_C_DP<13>")
	)
	(segment
		(start 341.061802 -427.420786)
		(end 341.07882 -427.437804)
		(width 0.14224)
		(layer "In6.Cu")
		(net "P5E_CPU0_P1_TX_BUF_C_DP<13>")
	)
	(segment
		(start 343.561924 -422.360852)
		(end 343.232232 -422.631362)
		(width 0.14224)
		(layer "In6.Cu")
		(net "P5E_CPU0_P1_TX_BUF_C_DP<13>")
	)
	(segment
		(start 342.341454 -423.53992)
		(end 342.011508 -423.810938)
		(width 0.14224)
		(layer "In6.Cu")
		(net "P5E_CPU0_P1_TX_BUF_C_DP<13>")
	)
	(segment
		(start 345.720416 -420.196518)
		(end 345.720416 -421.108378)
		(width 0.14224)
		(layer "In6.Cu")
		(net "P5E_CPU0_P1_TX_BUF_C_DP<13>")
	)
	(segment
		(start 343.232232 -422.631362)
		(end 343.213182 -422.824402)
		(width 0.14224)
		(layer "In6.Cu")
		(net "P5E_CPU0_P1_TX_BUF_C_DP<13>")
	)
	(segment
		(start 340.989158 -424.871896)
		(end 340.989158 -427.245526)
		(width 0.14224)
		(layer "In6.Cu")
		(net "P5E_CPU0_P1_TX_BUF_C_DP<13>")
	)
	(segment
		(start 345.857576 -419.632638)
		(end 345.857576 -420.059358)
		(width 0.14224)
		(layer "In6.Cu")
		(net "P5E_CPU0_P1_TX_BUF_C_DP<13>")
	)
	(segment
		(start 342.883236 -423.09542)
		(end 342.690196 -423.07637)
		(width 0.14224)
		(layer "In6.Cu")
		(net "P5E_CPU0_P1_TX_BUF_C_DP<13>")
	)
	(segment
		(start 341.34679 -427.548802)
		(end 341.507572 -427.548802)
		(width 0.14224)
		(layer "In6.Cu")
		(net "P5E_CPU0_P1_TX_BUF_C_DP<13>")
	)
	(segment
		(start 343.213182 -422.824402)
		(end 342.883236 -423.09542)
		(width 0.14224)
		(layer "In6.Cu")
		(net "P5E_CPU0_P1_TX_BUF_C_DP<13>")
	)
	(segment
		(start 346.011246 -418.412168)
		(end 345.720416 -418.702998)
		(width 0.14224)
		(layer "In6.Cu")
		(net "P5E_CPU0_P1_TX_BUF_C_DP<13>")
	)
	(segment
		(start 341.818468 -423.791888)
		(end 341.298276 -424.218862)
		(width 0.14224)
		(layer "In6.Cu")
		(net "P5E_CPU0_P1_TX_BUF_C_DP<13>")
	)
	(segment
		(start 344.921078 -422.282874)
		(end 344.890598 -422.293034)
		(width 0.14224)
		(layer "In6.Cu")
		(net "P5E_CPU0_P1_TX_BUF_C_DP<13>")
	)
	(segment
		(start 342.360504 -423.34688)
		(end 342.341454 -423.53992)
		(width 0.14224)
		(layer "In6.Cu")
		(net "P5E_CPU0_P1_TX_BUF_C_DP<13>")
	)
	(arc
		(start 343.657428 -422.326562)
		(mid 343.606715 -422.335447)
		(end 343.561924 -422.360852)
		(width 0.14224)
		(layer "In6.Cu")
		(net "P5E_CPU0_P1_TX_BUF_C_DP<13>")
	)
	(arc
		(start 341.298276 -424.218862)
		(mid 341.070515 -424.510838)
		(end 340.989412 -424.87215)
		(width 0.14224)
		(layer "In6.Cu")
		(net "P5E_CPU0_P1_TX_BUF_C_DP<13>")
	)
	(arc
		(start 344.890598 -422.293034)
		(mid 344.78538 -422.318295)
		(end 344.677492 -422.326562)
		(width 0.14224)
		(layer "In6.Cu")
		(net "P5E_CPU0_P1_TX_BUF_C_DP<13>")
	)
	(arc
		(start 345.720416 -421.108378)
		(mid 345.633275 -421.546466)
		(end 345.385136 -421.917876)
		(width 0.14224)
		(layer "In6.Cu")
		(net "P5E_CPU0_P1_TX_BUF_C_DP<13>")
	)
	(arc
		(start 345.179904 -422.123362)
		(mid 345.059877 -422.218353)
		(end 344.921078 -422.282874)
		(width 0.14224)
		(layer "In6.Cu")
		(net "P5E_CPU0_P1_TX_BUF_C_DP<13>")
	)
	(arc
		(start 340.989158 -427.245526)
		(mid 341.008044 -427.340381)
		(end 341.061802 -427.420786)
		(width 0.14224)
		(layer "In6.Cu")
		(net "P5E_CPU0_P1_TX_BUF_C_DP<13>")
	)
	(arc
		(start 341.07882 -427.437804)
		(mid 341.201766 -427.519954)
		(end 341.34679 -427.548802)
		(width 0.14224)
		(layer "In6.Cu")
		(net "P5E_CPU0_P1_TX_BUF_C_DP<13>")
	)
	(segment
		(start 342.660224 -418.124386)
		(end 342.948006 -418.412168)
		(width 0.12954)
		(layer "B.Cu")
		(net "P5E_CPU0_P1_TX_BUF_C_DP<12>")
	)
	(segment
		(start 342.660224 -417.479226)
		(end 342.660224 -418.124386)
		(width 0.12954)
		(layer "B.Cu")
		(net "P5E_CPU0_P1_TX_BUF_C_DP<12>")
	)
	(segment
		(start 342.973406 -417.166044)
		(end 342.660224 -417.479226)
		(width 0.12954)
		(layer "B.Cu")
		(net "P5E_CPU0_P1_TX_BUF_C_DP<12>")
	)
	(segment
		(start 340.990428 -423.155618)
		(end 340.650576 -423.41419)
		(width 0.14224)
		(layer "In6.Cu")
		(net "P5E_CPU0_P1_TX_BUF_C_DP<12>")
	)
	(segment
		(start 339.332316 -426.548804)
		(end 339.522816 -426.548804)
		(width 0.14224)
		(layer "In6.Cu")
		(net "P5E_CPU0_P1_TX_BUF_C_DP<12>")
	)
	(segment
		(start 342.446102 -421.829484)
		(end 342.25357 -422.022016)
		(width 0.14224)
		(layer "In6.Cu")
		(net "P5E_CPU0_P1_TX_BUF_C_DP<12>")
	)
	(segment
		(start 340.458298 -423.388028)
		(end 340.118954 -423.646346)
		(width 0.14224)
		(layer "In6.Cu")
		(net "P5E_CPU0_P1_TX_BUF_C_DP<12>")
	)
	(segment
		(start 341.01659 -422.96334)
		(end 340.990428 -423.155618)
		(width 0.14224)
		(layer "In6.Cu")
		(net "P5E_CPU0_P1_TX_BUF_C_DP<12>")
	)
	(segment
		(start 342.25357 -422.022016)
		(end 341.914226 -422.280334)
		(width 0.14224)
		(layer "In6.Cu")
		(net "P5E_CPU0_P1_TX_BUF_C_DP<12>")
	)
	(segment
		(start 342.794336 -419.64102)
		(end 342.794336 -420.06774)
		(width 0.14224)
		(layer "In6.Cu")
		(net "P5E_CPU0_P1_TX_BUF_C_DP<12>")
	)
	(segment
		(start 339.050884 -426.438568)
		(end 339.057742 -426.445426)
		(width 0.14224)
		(layer "In6.Cu")
		(net "P5E_CPU0_P1_TX_BUF_C_DP<12>")
	)
	(segment
		(start 339.522816 -426.548804)
		(end 339.649816 -426.421804)
		(width 0.14224)
		(layer "In6.Cu")
		(net "P5E_CPU0_P1_TX_BUF_C_DP<12>")
	)
	(segment
		(start 339.560916 -424.071034)
		(end 339.160358 -424.375834)
		(width 0.14224)
		(layer "In6.Cu")
		(net "P5E_CPU0_P1_TX_BUF_C_DP<12>")
	)
	(segment
		(start 342.794336 -420.06774)
		(end 342.657176 -420.2049)
		(width 0.14224)
		(layer "In6.Cu")
		(net "P5E_CPU0_P1_TX_BUF_C_DP<12>")
	)
	(segment
		(start 339.649816 -426.421804)
		(end 339.649816 -426.089826)
		(width 0.14224)
		(layer "In6.Cu")
		(net "P5E_CPU0_P1_TX_BUF_C_DP<12>")
	)
	(segment
		(start 340.092792 -423.838624)
		(end 339.75294 -424.097196)
		(width 0.14224)
		(layer "In6.Cu")
		(net "P5E_CPU0_P1_TX_BUF_C_DP<12>")
	)
	(segment
		(start 341.548212 -422.731184)
		(end 341.355934 -422.705022)
		(width 0.14224)
		(layer "In6.Cu")
		(net "P5E_CPU0_P1_TX_BUF_C_DP<12>")
	)
	(segment
		(start 342.657176 -420.2049)
		(end 342.657176 -421.31996)
		(width 0.14224)
		(layer "In6.Cu")
		(net "P5E_CPU0_P1_TX_BUF_C_DP<12>")
	)
	(segment
		(start 342.657176 -419.50386)
		(end 342.794336 -419.64102)
		(width 0.14224)
		(layer "In6.Cu")
		(net "P5E_CPU0_P1_TX_BUF_C_DP<12>")
	)
	(segment
		(start 339.75294 -424.097196)
		(end 339.560916 -424.071034)
		(width 0.14224)
		(layer "In6.Cu")
		(net "P5E_CPU0_P1_TX_BUF_C_DP<12>")
	)
	(segment
		(start 342.657176 -418.702998)
		(end 342.657176 -419.50386)
		(width 0.14224)
		(layer "In6.Cu")
		(net "P5E_CPU0_P1_TX_BUF_C_DP<12>")
	)
	(segment
		(start 340.650576 -423.41419)
		(end 340.458298 -423.388028)
		(width 0.14224)
		(layer "In6.Cu")
		(net "P5E_CPU0_P1_TX_BUF_C_DP<12>")
	)
	(segment
		(start 341.914226 -422.280334)
		(end 341.888064 -422.472612)
		(width 0.14224)
		(layer "In6.Cu")
		(net "P5E_CPU0_P1_TX_BUF_C_DP<12>")
	)
	(segment
		(start 338.95919 -424.781218)
		(end 338.95919 -426.217334)
		(width 0.14224)
		(layer "In6.Cu")
		(net "P5E_CPU0_P1_TX_BUF_C_DP<12>")
	)
	(segment
		(start 340.118954 -423.646346)
		(end 340.092792 -423.838624)
		(width 0.14224)
		(layer "In6.Cu")
		(net "P5E_CPU0_P1_TX_BUF_C_DP<12>")
	)
	(segment
		(start 342.948006 -418.412168)
		(end 342.657176 -418.702998)
		(width 0.14224)
		(layer "In6.Cu")
		(net "P5E_CPU0_P1_TX_BUF_C_DP<12>")
	)
	(segment
		(start 341.355934 -422.705022)
		(end 341.01659 -422.96334)
		(width 0.14224)
		(layer "In6.Cu")
		(net "P5E_CPU0_P1_TX_BUF_C_DP<12>")
	)
	(segment
		(start 341.888064 -422.472612)
		(end 341.548212 -422.731184)
		(width 0.14224)
		(layer "In6.Cu")
		(net "P5E_CPU0_P1_TX_BUF_C_DP<12>")
	)
	(arc
		(start 339.057742 -426.445426)
		(mid 339.106933 -426.485766)
		(end 339.163152 -426.51553)
		(width 0.14224)
		(layer "In6.Cu")
		(net "P5E_CPU0_P1_TX_BUF_C_DP<12>")
	)
	(arc
		(start 338.95919 -426.217334)
		(mid 338.983025 -426.337072)
		(end 339.050884 -426.438568)
		(width 0.14224)
		(layer "In6.Cu")
		(net "P5E_CPU0_P1_TX_BUF_C_DP<12>")
	)
	(arc
		(start 342.657176 -421.31996)
		(mid 342.602324 -421.595721)
		(end 342.446102 -421.829484)
		(width 0.14224)
		(layer "In6.Cu")
		(net "P5E_CPU0_P1_TX_BUF_C_DP<12>")
	)
	(arc
		(start 339.160358 -424.375834)
		(mid 339.012293 -424.554965)
		(end 338.95919 -424.781218)
		(width 0.14224)
		(layer "In6.Cu")
		(net "P5E_CPU0_P1_TX_BUF_C_DP<12>")
	)
	(arc
		(start 339.163152 -426.51553)
		(mid 339.246119 -426.540376)
		(end 339.332316 -426.548804)
		(width 0.14224)
		(layer "In6.Cu")
		(net "P5E_CPU0_P1_TX_BUF_C_DP<12>")
	)
	(segment
		(start 339.614256 -417.461954)
		(end 339.614256 -418.141658)
		(width 0.12954)
		(layer "B.Cu")
		(net "P5E_CPU0_P1_TX_BUF_C_DP<11>")
	)
	(segment
		(start 339.614256 -418.141658)
		(end 339.884766 -418.412168)
		(width 0.12954)
		(layer "B.Cu")
		(net "P5E_CPU0_P1_TX_BUF_C_DP<11>")
	)
	(segment
		(start 339.910166 -417.166044)
		(end 339.614256 -417.461954)
		(width 0.12954)
		(layer "B.Cu")
		(net "P5E_CPU0_P1_TX_BUF_C_DP<11>")
	)
	(segment
		(start 339.593936 -418.702998)
		(end 339.593936 -419.566344)
		(width 0.14224)
		(layer "In6.Cu")
		(net "P5E_CPU0_P1_TX_BUF_C_DP<11>")
	)
	(segment
		(start 337.86445 -423.553636)
		(end 337.562444 -423.855642)
		(width 0.14224)
		(layer "In6.Cu")
		(net "P5E_CPU0_P1_TX_BUF_C_DP<11>")
	)
	(segment
		(start 338.66201 -422.75633)
		(end 338.360004 -423.058336)
		(width 0.14224)
		(layer "In6.Cu")
		(net "P5E_CPU0_P1_TX_BUF_C_DP<11>")
	)
	(segment
		(start 338.66201 -422.562274)
		(end 338.66201 -422.75633)
		(width 0.14224)
		(layer "In6.Cu")
		(net "P5E_CPU0_P1_TX_BUF_C_DP<11>")
	)
	(segment
		(start 339.593936 -419.566344)
		(end 339.731096 -419.703504)
		(width 0.14224)
		(layer "In6.Cu")
		(net "P5E_CPU0_P1_TX_BUF_C_DP<11>")
	)
	(segment
		(start 337.368642 -423.855642)
		(end 337.104736 -424.119548)
		(width 0.14224)
		(layer "In6.Cu")
		(net "P5E_CPU0_P1_TX_BUF_C_DP<11>")
	)
	(segment
		(start 339.731096 -419.703504)
		(end 339.731096 -420.130224)
		(width 0.14224)
		(layer "In6.Cu")
		(net "P5E_CPU0_P1_TX_BUF_C_DP<11>")
	)
	(segment
		(start 339.593936 -420.267384)
		(end 339.593936 -421.264334)
		(width 0.14224)
		(layer "In6.Cu")
		(net "P5E_CPU0_P1_TX_BUF_C_DP<11>")
	)
	(segment
		(start 337.86445 -423.359834)
		(end 337.86445 -423.553636)
		(width 0.14224)
		(layer "In6.Cu")
		(net "P5E_CPU0_P1_TX_BUF_C_DP<11>")
	)
	(segment
		(start 339.884766 -418.412168)
		(end 339.593936 -418.702998)
		(width 0.14224)
		(layer "In6.Cu")
		(net "P5E_CPU0_P1_TX_BUF_C_DP<11>")
	)
	(segment
		(start 337.562444 -423.855642)
		(end 337.368642 -423.855642)
		(width 0.14224)
		(layer "In6.Cu")
		(net "P5E_CPU0_P1_TX_BUF_C_DP<11>")
	)
	(segment
		(start 337.64982 -427.406562)
		(end 337.64982 -427.089824)
		(width 0.14224)
		(layer "In6.Cu")
		(net "P5E_CPU0_P1_TX_BUF_C_DP<11>")
	)
	(segment
		(start 337.248246 -427.548802)
		(end 337.50758 -427.548802)
		(width 0.14224)
		(layer "In6.Cu")
		(net "P5E_CPU0_P1_TX_BUF_C_DP<11>")
	)
	(segment
		(start 338.360004 -423.058336)
		(end 338.165948 -423.058336)
		(width 0.14224)
		(layer "In6.Cu")
		(net "P5E_CPU0_P1_TX_BUF_C_DP<11>")
	)
	(segment
		(start 337.083654 -427.479968)
		(end 337.08467 -427.480984)
		(width 0.14224)
		(layer "In6.Cu")
		(net "P5E_CPU0_P1_TX_BUF_C_DP<11>")
	)
	(segment
		(start 337.50758 -427.548802)
		(end 337.64982 -427.406562)
		(width 0.14224)
		(layer "In6.Cu")
		(net "P5E_CPU0_P1_TX_BUF_C_DP<11>")
	)
	(segment
		(start 339.33511 -421.889174)
		(end 338.66201 -422.562274)
		(width 0.14224)
		(layer "In6.Cu")
		(net "P5E_CPU0_P1_TX_BUF_C_DP<11>")
	)
	(segment
		(start 339.731096 -420.130224)
		(end 339.593936 -420.267384)
		(width 0.14224)
		(layer "In6.Cu")
		(net "P5E_CPU0_P1_TX_BUF_C_DP<11>")
	)
	(segment
		(start 336.9945 -424.38574)
		(end 336.9945 -427.26483)
		(width 0.14224)
		(layer "In6.Cu")
		(net "P5E_CPU0_P1_TX_BUF_C_DP<11>")
	)
	(segment
		(start 338.165948 -423.058336)
		(end 337.86445 -423.359834)
		(width 0.14224)
		(layer "In6.Cu")
		(net "P5E_CPU0_P1_TX_BUF_C_DP<11>")
	)
	(arc
		(start 339.593936 -421.264334)
		(mid 339.526671 -421.602498)
		(end 339.33511 -421.889174)
		(width 0.14224)
		(layer "In6.Cu")
		(net "P5E_CPU0_P1_TX_BUF_C_DP<11>")
	)
	(arc
		(start 337.104736 -424.119548)
		(mid 337.023131 -424.241678)
		(end 336.9945 -424.38574)
		(width 0.14224)
		(layer "In6.Cu")
		(net "P5E_CPU0_P1_TX_BUF_C_DP<11>")
	)
	(arc
		(start 337.08467 -427.480984)
		(mid 337.159705 -427.531184)
		(end 337.248246 -427.548802)
		(width 0.14224)
		(layer "In6.Cu")
		(net "P5E_CPU0_P1_TX_BUF_C_DP<11>")
	)
	(arc
		(start 336.9945 -427.26483)
		(mid 337.017678 -427.381263)
		(end 337.083654 -427.479968)
		(width 0.14224)
		(layer "In6.Cu")
		(net "P5E_CPU0_P1_TX_BUF_C_DP<11>")
	)
	(segment
		(start 336.846926 -417.166044)
		(end 336.551016 -417.461954)
		(width 0.12954)
		(layer "B.Cu")
		(net "P5E_CPU0_P1_TX_BUF_C_DP<10>")
	)
	(segment
		(start 336.551016 -417.461954)
		(end 336.551016 -418.141658)
		(width 0.12954)
		(layer "B.Cu")
		(net "P5E_CPU0_P1_TX_BUF_C_DP<10>")
	)
	(segment
		(start 336.551016 -418.141658)
		(end 336.821526 -418.412168)
		(width 0.12954)
		(layer "B.Cu")
		(net "P5E_CPU0_P1_TX_BUF_C_DP<10>")
	)
	(segment
		(start 336.530696 -418.702998)
		(end 336.530696 -419.502082)
		(width 0.14224)
		(layer "In6.Cu")
		(net "P5E_CPU0_P1_TX_BUF_C_DP<10>")
	)
	(segment
		(start 336.821526 -418.412168)
		(end 336.530696 -418.702998)
		(width 0.14224)
		(layer "In6.Cu")
		(net "P5E_CPU0_P1_TX_BUF_C_DP<10>")
	)
	(segment
		(start 335.266792 -424.265344)
		(end 335.083912 -424.330622)
		(width 0.14224)
		(layer "In6.Cu")
		(net "P5E_CPU0_P1_TX_BUF_C_DP<10>")
	)
	(segment
		(start 336.04835 -422.29151)
		(end 335.865978 -422.677082)
		(width 0.14224)
		(layer "In6.Cu")
		(net "P5E_CPU0_P1_TX_BUF_C_DP<10>")
	)
	(segment
		(start 335.047844 -426.457618)
		(end 335.049876 -426.45965)
		(width 0.14224)
		(layer "In6.Cu")
		(net "P5E_CPU0_P1_TX_BUF_C_DP<10>")
	)
	(segment
		(start 335.305908 -426.565822)
		(end 335.490566 -426.565822)
		(width 0.14224)
		(layer "In6.Cu")
		(net "P5E_CPU0_P1_TX_BUF_C_DP<10>")
	)
	(segment
		(start 336.23123 -422.226232)
		(end 336.04835 -422.29151)
		(width 0.14224)
		(layer "In6.Cu")
		(net "P5E_CPU0_P1_TX_BUF_C_DP<10>")
	)
	(segment
		(start 336.667856 -420.065962)
		(end 336.530696 -420.203122)
		(width 0.14224)
		(layer "In6.Cu")
		(net "P5E_CPU0_P1_TX_BUF_C_DP<10>")
	)
	(segment
		(start 335.649824 -426.406564)
		(end 335.649824 -426.089826)
		(width 0.14224)
		(layer "In6.Cu")
		(net "P5E_CPU0_P1_TX_BUF_C_DP<10>")
	)
	(segment
		(start 335.383886 -423.696638)
		(end 335.449164 -423.879264)
		(width 0.14224)
		(layer "In6.Cu")
		(net "P5E_CPU0_P1_TX_BUF_C_DP<10>")
	)
	(segment
		(start 335.566258 -423.311066)
		(end 335.383886 -423.696638)
		(width 0.14224)
		(layer "In6.Cu")
		(net "P5E_CPU0_P1_TX_BUF_C_DP<10>")
	)
	(segment
		(start 336.348324 -421.657526)
		(end 336.413602 -421.840152)
		(width 0.14224)
		(layer "In6.Cu")
		(net "P5E_CPU0_P1_TX_BUF_C_DP<10>")
	)
	(segment
		(start 334.898746 -424.722036)
		(end 334.898746 -426.097954)
		(width 0.14224)
		(layer "In6.Cu")
		(net "P5E_CPU0_P1_TX_BUF_C_DP<10>")
	)
	(segment
		(start 336.530696 -421.271954)
		(end 336.348324 -421.657526)
		(width 0.14224)
		(layer "In6.Cu")
		(net "P5E_CPU0_P1_TX_BUF_C_DP<10>")
	)
	(segment
		(start 336.530696 -420.203122)
		(end 336.530696 -421.271954)
		(width 0.14224)
		(layer "In6.Cu")
		(net "P5E_CPU0_P1_TX_BUF_C_DP<10>")
	)
	(segment
		(start 335.490566 -426.565822)
		(end 335.649824 -426.406564)
		(width 0.14224)
		(layer "In6.Cu")
		(net "P5E_CPU0_P1_TX_BUF_C_DP<10>")
	)
	(segment
		(start 335.931256 -422.859708)
		(end 335.748884 -423.245788)
		(width 0.14224)
		(layer "In6.Cu")
		(net "P5E_CPU0_P1_TX_BUF_C_DP<10>")
	)
	(segment
		(start 336.530696 -419.502082)
		(end 336.667856 -419.639242)
		(width 0.14224)
		(layer "In6.Cu")
		(net "P5E_CPU0_P1_TX_BUF_C_DP<10>")
	)
	(segment
		(start 336.413602 -421.840152)
		(end 336.23123 -422.226232)
		(width 0.14224)
		(layer "In6.Cu")
		(net "P5E_CPU0_P1_TX_BUF_C_DP<10>")
	)
	(segment
		(start 335.865978 -422.677082)
		(end 335.931256 -422.859708)
		(width 0.14224)
		(layer "In6.Cu")
		(net "P5E_CPU0_P1_TX_BUF_C_DP<10>")
	)
	(segment
		(start 336.667856 -419.639242)
		(end 336.667856 -420.065962)
		(width 0.14224)
		(layer "In6.Cu")
		(net "P5E_CPU0_P1_TX_BUF_C_DP<10>")
	)
	(segment
		(start 334.898746 -426.097954)
		(end 334.899 -426.0977)
		(width 0.14224)
		(layer "In6.Cu")
		(net "P5E_CPU0_P1_TX_BUF_C_DP<10>")
	)
	(segment
		(start 335.748884 -423.245788)
		(end 335.566258 -423.311066)
		(width 0.14224)
		(layer "In6.Cu")
		(net "P5E_CPU0_P1_TX_BUF_C_DP<10>")
	)
	(segment
		(start 335.083912 -424.330622)
		(end 334.898746 -424.722036)
		(width 0.14224)
		(layer "In6.Cu")
		(net "P5E_CPU0_P1_TX_BUF_C_DP<10>")
	)
	(segment
		(start 335.449164 -423.879264)
		(end 335.266792 -424.265344)
		(width 0.14224)
		(layer "In6.Cu")
		(net "P5E_CPU0_P1_TX_BUF_C_DP<10>")
	)
	(arc
		(start 334.899 -426.0977)
		(mid 334.937644 -426.292449)
		(end 335.047844 -426.457618)
		(width 0.14224)
		(layer "In6.Cu")
		(net "P5E_CPU0_P1_TX_BUF_C_DP<10>")
	)
	(arc
		(start 335.049876 -426.45965)
		(mid 335.167344 -426.538169)
		(end 335.305908 -426.565822)
		(width 0.14224)
		(layer "In6.Cu")
		(net "P5E_CPU0_P1_TX_BUF_C_DP<10>")
	)
	(segment
		(start 306.214526 -417.166044)
		(end 305.918616 -417.461954)
		(width 0.12954)
		(layer "B.Cu")
		(net "P5E_CPU0_P1_TX_BUF_C_DP<0>")
	)
	(segment
		(start 305.918616 -418.141658)
		(end 306.189126 -418.412168)
		(width 0.12954)
		(layer "B.Cu")
		(net "P5E_CPU0_P1_TX_BUF_C_DP<0>")
	)
	(segment
		(start 305.918616 -417.461954)
		(end 305.918616 -418.141658)
		(width 0.12954)
		(layer "B.Cu")
		(net "P5E_CPU0_P1_TX_BUF_C_DP<0>")
	)
	(segment
		(start 308.251352 -423.046906)
		(end 308.298596 -423.235374)
		(width 0.14224)
		(layer "In6.Cu")
		(net "P5E_CPU0_P1_TX_BUF_C_DP<0>")
	)
	(segment
		(start 307.69687 -422.874694)
		(end 307.885084 -422.82745)
		(width 0.14224)
		(layer "In6.Cu")
		(net "P5E_CPU0_P1_TX_BUF_C_DP<0>")
	)
	(segment
		(start 314.649612 -426.406564)
		(end 314.649612 -426.089826)
		(width 0.14224)
		(layer "In6.Cu")
		(net "P5E_CPU0_P1_TX_BUF_C_DP<0>")
	)
	(segment
		(start 309.631842 -424.034458)
		(end 309.820056 -423.987214)
		(width 0.14224)
		(layer "In6.Cu")
		(net "P5E_CPU0_P1_TX_BUF_C_DP<0>")
	)
	(segment
		(start 311.15381 -424.786552)
		(end 311.201054 -424.97502)
		(width 0.14224)
		(layer "In6.Cu")
		(net "P5E_CPU0_P1_TX_BUF_C_DP<0>")
	)
	(segment
		(start 306.372768 -422.080944)
		(end 307.69687 -422.874694)
		(width 0.14224)
		(layer "In6.Cu")
		(net "P5E_CPU0_P1_TX_BUF_C_DP<0>")
	)
	(segment
		(start 312.5343 -425.774104)
		(end 313.98337 -426.548804)
		(width 0.14224)
		(layer "In6.Cu")
		(net "P5E_CPU0_P1_TX_BUF_C_DP<0>")
	)
	(segment
		(start 307.885084 -422.82745)
		(end 308.251352 -423.046906)
		(width 0.14224)
		(layer "In6.Cu")
		(net "P5E_CPU0_P1_TX_BUF_C_DP<0>")
	)
	(segment
		(start 311.566814 -425.194222)
		(end 311.755028 -425.146978)
		(width 0.14224)
		(layer "In6.Cu")
		(net "P5E_CPU0_P1_TX_BUF_C_DP<0>")
	)
	(segment
		(start 310.233568 -424.395138)
		(end 310.599328 -424.61434)
		(width 0.14224)
		(layer "In6.Cu")
		(net "P5E_CPU0_P1_TX_BUF_C_DP<0>")
	)
	(segment
		(start 314.507372 -426.548804)
		(end 314.649612 -426.406564)
		(width 0.14224)
		(layer "In6.Cu")
		(net "P5E_CPU0_P1_TX_BUF_C_DP<0>")
	)
	(segment
		(start 308.664356 -423.454576)
		(end 308.85257 -423.407332)
		(width 0.14224)
		(layer "In6.Cu")
		(net "P5E_CPU0_P1_TX_BUF_C_DP<0>")
	)
	(segment
		(start 309.266082 -423.815256)
		(end 309.631842 -424.034458)
		(width 0.14224)
		(layer "In6.Cu")
		(net "P5E_CPU0_P1_TX_BUF_C_DP<0>")
	)
	(segment
		(start 309.820056 -423.987214)
		(end 310.186324 -424.20667)
		(width 0.14224)
		(layer "In6.Cu")
		(net "P5E_CPU0_P1_TX_BUF_C_DP<0>")
	)
	(segment
		(start 312.16854 -425.554902)
		(end 312.5343 -425.774104)
		(width 0.14224)
		(layer "In6.Cu")
		(net "P5E_CPU0_P1_TX_BUF_C_DP<0>")
	)
	(segment
		(start 312.121296 -425.366434)
		(end 312.16854 -425.554902)
		(width 0.14224)
		(layer "In6.Cu")
		(net "P5E_CPU0_P1_TX_BUF_C_DP<0>")
	)
	(segment
		(start 308.298596 -423.235374)
		(end 308.664356 -423.454576)
		(width 0.14224)
		(layer "In6.Cu")
		(net "P5E_CPU0_P1_TX_BUF_C_DP<0>")
	)
	(segment
		(start 309.218838 -423.626788)
		(end 309.266082 -423.815256)
		(width 0.14224)
		(layer "In6.Cu")
		(net "P5E_CPU0_P1_TX_BUF_C_DP<0>")
	)
	(segment
		(start 305.898296 -418.702998)
		(end 305.898296 -421.193214)
		(width 0.14224)
		(layer "In6.Cu")
		(net "P5E_CPU0_P1_TX_BUF_C_DP<0>")
	)
	(segment
		(start 310.599328 -424.61434)
		(end 310.787542 -424.567096)
		(width 0.14224)
		(layer "In6.Cu")
		(net "P5E_CPU0_P1_TX_BUF_C_DP<0>")
	)
	(segment
		(start 310.186324 -424.20667)
		(end 310.233568 -424.395138)
		(width 0.14224)
		(layer "In6.Cu")
		(net "P5E_CPU0_P1_TX_BUF_C_DP<0>")
	)
	(segment
		(start 306.189126 -418.412168)
		(end 305.898296 -418.702998)
		(width 0.14224)
		(layer "In6.Cu")
		(net "P5E_CPU0_P1_TX_BUF_C_DP<0>")
	)
	(segment
		(start 311.755028 -425.146978)
		(end 312.121296 -425.366434)
		(width 0.14224)
		(layer "In6.Cu")
		(net "P5E_CPU0_P1_TX_BUF_C_DP<0>")
	)
	(segment
		(start 310.787542 -424.567096)
		(end 311.15381 -424.786552)
		(width 0.14224)
		(layer "In6.Cu")
		(net "P5E_CPU0_P1_TX_BUF_C_DP<0>")
	)
	(segment
		(start 308.85257 -423.407332)
		(end 309.218838 -423.626788)
		(width 0.14224)
		(layer "In6.Cu")
		(net "P5E_CPU0_P1_TX_BUF_C_DP<0>")
	)
	(segment
		(start 313.98337 -426.548804)
		(end 314.507372 -426.548804)
		(width 0.14224)
		(layer "In6.Cu")
		(net "P5E_CPU0_P1_TX_BUF_C_DP<0>")
	)
	(segment
		(start 311.201054 -424.97502)
		(end 311.566814 -425.194222)
		(width 0.14224)
		(layer "In6.Cu")
		(net "P5E_CPU0_P1_TX_BUF_C_DP<0>")
	)
	(arc
		(start 305.898296 -421.193214)
		(mid 306.024347 -421.696512)
		(end 306.372768 -422.080944)
		(width 0.14224)
		(layer "In6.Cu")
		(net "P5E_CPU0_P1_TX_BUF_C_DP<0>")
	)
	(segment
		(start 333.165196 -418.141658)
		(end 332.894686 -418.412168)
		(width 0.12954)
		(layer "B.Cu")
		(net "P5E_CPU0_P1_TX_BUF_C_DN<9>")
	)
	(segment
		(start 332.869286 -417.166044)
		(end 333.165196 -417.461954)
		(width 0.12954)
		(layer "B.Cu")
		(net "P5E_CPU0_P1_TX_BUF_C_DN<9>")
	)
	(segment
		(start 333.165196 -417.461954)
		(end 333.165196 -418.141658)
		(width 0.12954)
		(layer "B.Cu")
		(net "P5E_CPU0_P1_TX_BUF_C_DN<9>")
	)
	(segment
		(start 333.185516 -418.702998)
		(end 333.185516 -421.119554)
		(width 0.14224)
		(layer "In6.Cu")
		(net "P5E_CPU0_P1_TX_BUF_C_DN<9>")
	)
	(segment
		(start 332.886304 -427.64075)
		(end 332.9178 -427.672246)
		(width 0.14224)
		(layer "In6.Cu")
		(net "P5E_CPU0_P1_TX_BUF_C_DN<9>")
	)
	(segment
		(start 332.894686 -418.412168)
		(end 333.185516 -418.702998)
		(width 0.14224)
		(layer "In6.Cu")
		(net "P5E_CPU0_P1_TX_BUF_C_DN<9>")
	)
	(segment
		(start 333.300324 -427.830742)
		(end 333.507588 -427.830742)
		(width 0.14224)
		(layer "In6.Cu")
		(net "P5E_CPU0_P1_TX_BUF_C_DN<9>")
	)
	(segment
		(start 333.185516 -421.119554)
		(end 333.004414 -422.029382)
		(width 0.14224)
		(layer "In6.Cu")
		(net "P5E_CPU0_P1_TX_BUF_C_DN<9>")
	)
	(segment
		(start 333.507588 -427.830742)
		(end 333.649828 -427.972982)
		(width 0.14224)
		(layer "In6.Cu")
		(net "P5E_CPU0_P1_TX_BUF_C_DN<9>")
	)
	(segment
		(start 333.649828 -427.972982)
		(end 333.649828 -428.28972)
		(width 0.14224)
		(layer "In6.Cu")
		(net "P5E_CPU0_P1_TX_BUF_C_DN<9>")
	)
	(segment
		(start 332.701646 -425.110148)
		(end 332.701646 -427.19498)
		(width 0.14224)
		(layer "In6.Cu")
		(net "P5E_CPU0_P1_TX_BUF_C_DN<9>")
	)
	(segment
		(start 333.004414 -422.029382)
		(end 332.701646 -425.110148)
		(width 0.14224)
		(layer "In6.Cu")
		(net "P5E_CPU0_P1_TX_BUF_C_DN<9>")
	)
	(arc
		(start 332.9178 -427.672246)
		(mid 333.093289 -427.789567)
		(end 333.300324 -427.830742)
		(width 0.14224)
		(layer "In6.Cu")
		(net "P5E_CPU0_P1_TX_BUF_C_DN<9>")
	)
	(arc
		(start 332.701646 -427.19498)
		(mid 332.749634 -427.436234)
		(end 332.886304 -427.64075)
		(width 0.14224)
		(layer "In6.Cu")
		(net "P5E_CPU0_P1_TX_BUF_C_DN<9>")
	)
	(segment
		(start 329.806046 -417.166044)
		(end 330.101956 -417.461954)
		(width 0.12954)
		(layer "B.Cu")
		(net "P5E_CPU0_P1_TX_BUF_C_DN<8>")
	)
	(segment
		(start 330.101956 -417.461954)
		(end 330.101956 -418.141658)
		(width 0.12954)
		(layer "B.Cu")
		(net "P5E_CPU0_P1_TX_BUF_C_DN<8>")
	)
	(segment
		(start 330.101956 -418.141658)
		(end 329.831446 -418.412168)
		(width 0.12954)
		(layer "B.Cu")
		(net "P5E_CPU0_P1_TX_BUF_C_DN<8>")
	)
	(segment
		(start 330.47051 -426.429678)
		(end 330.622148 -426.581316)
		(width 0.14224)
		(layer "In6.Cu")
		(net "P5E_CPU0_P1_TX_BUF_C_DN<8>")
	)
	(segment
		(start 329.831446 -418.412168)
		(end 330.122276 -418.702998)
		(width 0.14224)
		(layer "In6.Cu")
		(net "P5E_CPU0_P1_TX_BUF_C_DN<8>")
	)
	(segment
		(start 330.122276 -418.702998)
		(end 330.122276 -425.588938)
		(width 0.14224)
		(layer "In6.Cu")
		(net "P5E_CPU0_P1_TX_BUF_C_DN<8>")
	)
	(segment
		(start 331.507592 -426.830744)
		(end 331.649832 -426.972984)
		(width 0.14224)
		(layer "In6.Cu")
		(net "P5E_CPU0_P1_TX_BUF_C_DN<8>")
	)
	(segment
		(start 331.649832 -426.972984)
		(end 331.649832 -427.289976)
		(width 0.14224)
		(layer "In6.Cu")
		(net "P5E_CPU0_P1_TX_BUF_C_DN<8>")
	)
	(segment
		(start 331.224382 -426.830744)
		(end 331.507592 -426.830744)
		(width 0.14224)
		(layer "In6.Cu")
		(net "P5E_CPU0_P1_TX_BUF_C_DN<8>")
	)
	(arc
		(start 330.122276 -425.588938)
		(mid 330.212781 -426.043939)
		(end 330.47051 -426.429678)
		(width 0.14224)
		(layer "In6.Cu")
		(net "P5E_CPU0_P1_TX_BUF_C_DN<8>")
	)
	(arc
		(start 330.622148 -426.581316)
		(mid 330.898455 -426.765939)
		(end 331.224382 -426.830744)
		(width 0.14224)
		(layer "In6.Cu")
		(net "P5E_CPU0_P1_TX_BUF_C_DN<8>")
	)
	(segment
		(start 327.038716 -417.461954)
		(end 327.038716 -418.141658)
		(width 0.12954)
		(layer "B.Cu")
		(net "P5E_CPU0_P1_TX_BUF_C_DN<7>")
	)
	(segment
		(start 326.742806 -417.166044)
		(end 327.038716 -417.461954)
		(width 0.12954)
		(layer "B.Cu")
		(net "P5E_CPU0_P1_TX_BUF_C_DN<7>")
	)
	(segment
		(start 327.038716 -418.141658)
		(end 326.768206 -418.412168)
		(width 0.12954)
		(layer "B.Cu")
		(net "P5E_CPU0_P1_TX_BUF_C_DN<7>")
	)
	(segment
		(start 328.649584 -427.972982)
		(end 328.649584 -428.28972)
		(width 0.14224)
		(layer "In6.Cu")
		(net "P5E_CPU0_P1_TX_BUF_C_DN<7>")
	)
	(segment
		(start 327.880218 -427.62678)
		(end 327.89749 -427.644052)
		(width 0.14224)
		(layer "In6.Cu")
		(net "P5E_CPU0_P1_TX_BUF_C_DN<7>")
	)
	(segment
		(start 327.059036 -421.349678)
		(end 327.606914 -424.105832)
		(width 0.14224)
		(layer "In6.Cu")
		(net "P5E_CPU0_P1_TX_BUF_C_DN<7>")
	)
	(segment
		(start 327.059036 -418.702998)
		(end 327.059036 -421.349678)
		(width 0.14224)
		(layer "In6.Cu")
		(net "P5E_CPU0_P1_TX_BUF_C_DN<7>")
	)
	(segment
		(start 326.768206 -418.412168)
		(end 327.059036 -418.702998)
		(width 0.14224)
		(layer "In6.Cu")
		(net "P5E_CPU0_P1_TX_BUF_C_DN<7>")
	)
	(segment
		(start 328.507344 -427.830742)
		(end 328.649584 -427.972982)
		(width 0.14224)
		(layer "In6.Cu")
		(net "P5E_CPU0_P1_TX_BUF_C_DN<7>")
	)
	(segment
		(start 328.34834 -427.830742)
		(end 328.507344 -427.830742)
		(width 0.14224)
		(layer "In6.Cu")
		(net "P5E_CPU0_P1_TX_BUF_C_DN<7>")
	)
	(segment
		(start 327.710038 -424.622722)
		(end 327.710038 -427.215808)
		(width 0.14224)
		(layer "In6.Cu")
		(net "P5E_CPU0_P1_TX_BUF_C_DN<7>")
	)
	(segment
		(start 327.607168 -424.105832)
		(end 327.710038 -424.622722)
		(width 0.14224)
		(layer "In6.Cu")
		(net "P5E_CPU0_P1_TX_BUF_C_DN<7>")
	)
	(segment
		(start 327.606914 -424.105832)
		(end 327.607168 -424.105832)
		(width 0.14224)
		(layer "In6.Cu")
		(net "P5E_CPU0_P1_TX_BUF_C_DN<7>")
	)
	(arc
		(start 327.710038 -427.215808)
		(mid 327.754261 -427.438219)
		(end 327.880218 -427.62678)
		(width 0.14224)
		(layer "In6.Cu")
		(net "P5E_CPU0_P1_TX_BUF_C_DN<7>")
	)
	(arc
		(start 327.89749 -427.644052)
		(mid 328.104356 -427.782212)
		(end 328.34834 -427.830742)
		(width 0.14224)
		(layer "In6.Cu")
		(net "P5E_CPU0_P1_TX_BUF_C_DN<7>")
	)
	(segment
		(start 323.679566 -417.166044)
		(end 323.975476 -417.461954)
		(width 0.12954)
		(layer "B.Cu")
		(net "P5E_CPU0_P1_TX_BUF_C_DN<6>")
	)
	(segment
		(start 323.975476 -417.461954)
		(end 323.975476 -418.141658)
		(width 0.12954)
		(layer "B.Cu")
		(net "P5E_CPU0_P1_TX_BUF_C_DN<6>")
	)
	(segment
		(start 323.975476 -418.141658)
		(end 323.704966 -418.412168)
		(width 0.12954)
		(layer "B.Cu")
		(net "P5E_CPU0_P1_TX_BUF_C_DN<6>")
	)
	(segment
		(start 325.874126 -426.660056)
		(end 325.904352 -426.689266)
		(width 0.14224)
		(layer "In6.Cu")
		(net "P5E_CPU0_P1_TX_BUF_C_DN<6>")
	)
	(segment
		(start 326.300338 -426.848778)
		(end 326.487028 -426.849794)
		(width 0.14224)
		(layer "In6.Cu")
		(net "P5E_CPU0_P1_TX_BUF_C_DN<6>")
	)
	(segment
		(start 325.554848 -425.53763)
		(end 325.554848 -425.887642)
		(width 0.14224)
		(layer "In6.Cu")
		(net "P5E_CPU0_P1_TX_BUF_C_DN<6>")
	)
	(segment
		(start 326.487028 -426.849794)
		(end 326.518524 -426.849794)
		(width 0.14224)
		(layer "In6.Cu")
		(net "P5E_CPU0_P1_TX_BUF_C_DN<6>")
	)
	(segment
		(start 326.649588 -426.980858)
		(end 326.649588 -427.289976)
		(width 0.14224)
		(layer "In6.Cu")
		(net "P5E_CPU0_P1_TX_BUF_C_DN<6>")
	)
	(segment
		(start 323.995796 -418.702998)
		(end 323.995796 -421.433498)
		(width 0.14224)
		(layer "In6.Cu")
		(net "P5E_CPU0_P1_TX_BUF_C_DN<6>")
	)
	(segment
		(start 323.995796 -421.433498)
		(end 325.425054 -424.884342)
		(width 0.14224)
		(layer "In6.Cu")
		(net "P5E_CPU0_P1_TX_BUF_C_DN<6>")
	)
	(segment
		(start 323.704966 -418.412168)
		(end 323.995796 -418.702998)
		(width 0.14224)
		(layer "In6.Cu")
		(net "P5E_CPU0_P1_TX_BUF_C_DN<6>")
	)
	(segment
		(start 326.518524 -426.849794)
		(end 326.649588 -426.980858)
		(width 0.14224)
		(layer "In6.Cu")
		(net "P5E_CPU0_P1_TX_BUF_C_DN<6>")
	)
	(arc
		(start 325.554848 -425.887642)
		(mid 325.637919 -426.305492)
		(end 325.874126 -426.660056)
		(width 0.14224)
		(layer "In6.Cu")
		(net "P5E_CPU0_P1_TX_BUF_C_DN<6>")
	)
	(arc
		(start 325.425054 -424.884342)
		(mid 325.522114 -425.204596)
		(end 325.554848 -425.53763)
		(width 0.14224)
		(layer "In6.Cu")
		(net "P5E_CPU0_P1_TX_BUF_C_DN<6>")
	)
	(arc
		(start 325.904352 -426.689266)
		(mid 326.087079 -426.806926)
		(end 326.300338 -426.848778)
		(width 0.14224)
		(layer "In6.Cu")
		(net "P5E_CPU0_P1_TX_BUF_C_DN<6>")
	)
	(segment
		(start 320.912236 -417.461954)
		(end 320.912236 -418.141658)
		(width 0.12954)
		(layer "B.Cu")
		(net "P5E_CPU0_P1_TX_BUF_C_DN<5>")
	)
	(segment
		(start 320.616326 -417.166044)
		(end 320.912236 -417.461954)
		(width 0.12954)
		(layer "B.Cu")
		(net "P5E_CPU0_P1_TX_BUF_C_DN<5>")
	)
	(segment
		(start 320.912236 -418.141658)
		(end 320.641726 -418.412168)
		(width 0.12954)
		(layer "B.Cu")
		(net "P5E_CPU0_P1_TX_BUF_C_DN<5>")
	)
	(segment
		(start 324.507352 -427.830742)
		(end 324.649592 -427.972982)
		(width 0.14224)
		(layer "In6.Cu")
		(net "P5E_CPU0_P1_TX_BUF_C_DN<5>")
	)
	(segment
		(start 323.706998 -425.48175)
		(end 323.706998 -427.22927)
		(width 0.14224)
		(layer "In6.Cu")
		(net "P5E_CPU0_P1_TX_BUF_C_DN<5>")
	)
	(segment
		(start 324.649592 -427.972982)
		(end 324.649592 -428.28972)
		(width 0.14224)
		(layer "In6.Cu")
		(net "P5E_CPU0_P1_TX_BUF_C_DN<5>")
	)
	(segment
		(start 321.330574 -422.2369)
		(end 323.48551 -424.862498)
		(width 0.14224)
		(layer "In6.Cu")
		(net "P5E_CPU0_P1_TX_BUF_C_DN<5>")
	)
	(segment
		(start 324.28942 -427.830742)
		(end 324.507352 -427.830742)
		(width 0.14224)
		(layer "In6.Cu")
		(net "P5E_CPU0_P1_TX_BUF_C_DN<5>")
	)
	(segment
		(start 323.840856 -427.552358)
		(end 323.998844 -427.710346)
		(width 0.14224)
		(layer "In6.Cu")
		(net "P5E_CPU0_P1_TX_BUF_C_DN<5>")
	)
	(segment
		(start 320.932556 -418.702998)
		(end 320.932556 -421.123364)
		(width 0.14224)
		(layer "In6.Cu")
		(net "P5E_CPU0_P1_TX_BUF_C_DN<5>")
	)
	(segment
		(start 320.641726 -418.412168)
		(end 320.932556 -418.702998)
		(width 0.14224)
		(layer "In6.Cu")
		(net "P5E_CPU0_P1_TX_BUF_C_DN<5>")
	)
	(arc
		(start 323.706998 -427.22927)
		(mid 323.741781 -427.404136)
		(end 323.840856 -427.552358)
		(width 0.14224)
		(layer "In6.Cu")
		(net "P5E_CPU0_P1_TX_BUF_C_DN<5>")
	)
	(arc
		(start 320.932556 -421.123364)
		(mid 321.034961 -421.714665)
		(end 321.330574 -422.2369)
		(width 0.14224)
		(layer "In6.Cu")
		(net "P5E_CPU0_P1_TX_BUF_C_DN<5>")
	)
	(arc
		(start 323.48551 -424.862498)
		(mid 323.649967 -425.152913)
		(end 323.706998 -425.48175)
		(width 0.14224)
		(layer "In6.Cu")
		(net "P5E_CPU0_P1_TX_BUF_C_DN<5>")
	)
	(arc
		(start 323.998844 -427.710346)
		(mid 324.132161 -427.799426)
		(end 324.28942 -427.830742)
		(width 0.14224)
		(layer "In6.Cu")
		(net "P5E_CPU0_P1_TX_BUF_C_DN<5>")
	)
	(segment
		(start 317.553086 -417.166044)
		(end 317.848996 -417.461954)
		(width 0.12954)
		(layer "B.Cu")
		(net "P5E_CPU0_P1_TX_BUF_C_DN<4>")
	)
	(segment
		(start 317.848996 -418.141658)
		(end 317.578486 -418.412168)
		(width 0.12954)
		(layer "B.Cu")
		(net "P5E_CPU0_P1_TX_BUF_C_DN<4>")
	)
	(segment
		(start 317.848996 -417.461954)
		(end 317.848996 -418.141658)
		(width 0.12954)
		(layer "B.Cu")
		(net "P5E_CPU0_P1_TX_BUF_C_DN<4>")
	)
	(segment
		(start 321.380358 -424.494706)
		(end 321.501262 -424.734736)
		(width 0.14224)
		(layer "In6.Cu")
		(net "P5E_CPU0_P1_TX_BUF_C_DN<4>")
	)
	(segment
		(start 318.351154 -422.247568)
		(end 318.71031 -422.51376)
		(width 0.14224)
		(layer "In6.Cu")
		(net "P5E_CPU0_P1_TX_BUF_C_DN<4>")
	)
	(segment
		(start 322.649596 -427.01337)
		(end 322.649596 -427.289976)
		(width 0.14224)
		(layer "In6.Cu")
		(net "P5E_CPU0_P1_TX_BUF_C_DN<4>")
	)
	(segment
		(start 322.488052 -426.851826)
		(end 322.649596 -427.01337)
		(width 0.14224)
		(layer "In6.Cu")
		(net "P5E_CPU0_P1_TX_BUF_C_DN<4>")
	)
	(segment
		(start 322.406264 -426.851826)
		(end 322.488052 -426.851826)
		(width 0.14224)
		(layer "In6.Cu")
		(net "P5E_CPU0_P1_TX_BUF_C_DN<4>")
	)
	(segment
		(start 321.085464 -424.276012)
		(end 321.085464 -424.275758)
		(width 0.14224)
		(layer "In6.Cu")
		(net "P5E_CPU0_P1_TX_BUF_C_DN<4>")
	)
	(segment
		(start 318.71031 -422.514014)
		(end 321.085464 -424.276012)
		(width 0.14224)
		(layer "In6.Cu")
		(net "P5E_CPU0_P1_TX_BUF_C_DN<4>")
	)
	(segment
		(start 317.869316 -418.702998)
		(end 317.869316 -421.226234)
		(width 0.14224)
		(layer "In6.Cu")
		(net "P5E_CPU0_P1_TX_BUF_C_DN<4>")
	)
	(segment
		(start 317.578486 -418.412168)
		(end 317.869316 -418.702998)
		(width 0.14224)
		(layer "In6.Cu")
		(net "P5E_CPU0_P1_TX_BUF_C_DN<4>")
	)
	(segment
		(start 318.250824 -422.147238)
		(end 318.351154 -422.247568)
		(width 0.14224)
		(layer "In6.Cu")
		(net "P5E_CPU0_P1_TX_BUF_C_DN<4>")
	)
	(segment
		(start 321.085464 -424.275758)
		(end 321.380358 -424.494706)
		(width 0.14224)
		(layer "In6.Cu")
		(net "P5E_CPU0_P1_TX_BUF_C_DN<4>")
	)
	(segment
		(start 321.501262 -424.734736)
		(end 321.501262 -425.801282)
		(width 0.14224)
		(layer "In6.Cu")
		(net "P5E_CPU0_P1_TX_BUF_C_DN<4>")
	)
	(segment
		(start 321.777868 -426.469048)
		(end 321.987164 -426.678344)
		(width 0.14224)
		(layer "In6.Cu")
		(net "P5E_CPU0_P1_TX_BUF_C_DN<4>")
	)
	(segment
		(start 318.71031 -422.51376)
		(end 318.71031 -422.514014)
		(width 0.14224)
		(layer "In6.Cu")
		(net "P5E_CPU0_P1_TX_BUF_C_DN<4>")
	)
	(arc
		(start 321.501262 -425.801282)
		(mid 321.573148 -426.162678)
		(end 321.777868 -426.469048)
		(width 0.14224)
		(layer "In6.Cu")
		(net "P5E_CPU0_P1_TX_BUF_C_DN<4>")
	)
	(arc
		(start 321.987164 -426.678344)
		(mid 322.179436 -426.80682)
		(end 322.406264 -426.851826)
		(width 0.14224)
		(layer "In6.Cu")
		(net "P5E_CPU0_P1_TX_BUF_C_DN<4>")
	)
	(arc
		(start 317.869316 -421.226234)
		(mid 317.968464 -421.724684)
		(end 318.250824 -422.147238)
		(width 0.14224)
		(layer "In6.Cu")
		(net "P5E_CPU0_P1_TX_BUF_C_DN<4>")
	)
	(segment
		(start 314.785756 -417.461954)
		(end 314.785756 -418.141658)
		(width 0.12954)
		(layer "B.Cu")
		(net "P5E_CPU0_P1_TX_BUF_C_DN<3>")
	)
	(segment
		(start 314.785756 -418.141658)
		(end 314.515246 -418.412168)
		(width 0.12954)
		(layer "B.Cu")
		(net "P5E_CPU0_P1_TX_BUF_C_DN<3>")
	)
	(segment
		(start 314.489846 -417.166044)
		(end 314.785756 -417.461954)
		(width 0.12954)
		(layer "B.Cu")
		(net "P5E_CPU0_P1_TX_BUF_C_DN<3>")
	)
	(segment
		(start 314.806076 -418.702998)
		(end 314.806076 -421.160194)
		(width 0.14224)
		(layer "In6.Cu")
		(net "P5E_CPU0_P1_TX_BUF_C_DN<3>")
	)
	(segment
		(start 315.119258 -421.915844)
		(end 315.399166 -422.195752)
		(width 0.14224)
		(layer "In6.Cu")
		(net "P5E_CPU0_P1_TX_BUF_C_DN<3>")
	)
	(segment
		(start 314.515246 -418.412168)
		(end 314.806076 -418.702998)
		(width 0.14224)
		(layer "In6.Cu")
		(net "P5E_CPU0_P1_TX_BUF_C_DN<3>")
	)
	(segment
		(start 320.370962 -427.830742)
		(end 320.50736 -427.830742)
		(width 0.14224)
		(layer "In6.Cu")
		(net "P5E_CPU0_P1_TX_BUF_C_DN<3>")
	)
	(segment
		(start 319.69202 -424.992546)
		(end 319.69202 -427.256702)
		(width 0.14224)
		(layer "In6.Cu")
		(net "P5E_CPU0_P1_TX_BUF_C_DN<3>")
	)
	(segment
		(start 316.49035 -422.647872)
		(end 319.521586 -424.673522)
		(width 0.14224)
		(layer "In6.Cu")
		(net "P5E_CPU0_P1_TX_BUF_C_DN<3>")
	)
	(segment
		(start 320.6496 -427.972982)
		(end 320.6496 -428.28972)
		(width 0.14224)
		(layer "In6.Cu")
		(net "P5E_CPU0_P1_TX_BUF_C_DN<3>")
	)
	(segment
		(start 315.399166 -422.195752)
		(end 316.49035 -422.647872)
		(width 0.14224)
		(layer "In6.Cu")
		(net "P5E_CPU0_P1_TX_BUF_C_DN<3>")
	)
	(segment
		(start 320.50736 -427.830742)
		(end 320.6496 -427.972982)
		(width 0.14224)
		(layer "In6.Cu")
		(net "P5E_CPU0_P1_TX_BUF_C_DN<3>")
	)
	(segment
		(start 319.820798 -427.567598)
		(end 319.880996 -427.627796)
		(width 0.14224)
		(layer "In6.Cu")
		(net "P5E_CPU0_P1_TX_BUF_C_DN<3>")
	)
	(arc
		(start 314.806076 -421.160194)
		(mid 314.887504 -421.569179)
		(end 315.119258 -421.915844)
		(width 0.14224)
		(layer "In6.Cu")
		(net "P5E_CPU0_P1_TX_BUF_C_DN<3>")
	)
	(arc
		(start 319.880996 -427.627796)
		(mid 320.105794 -427.778001)
		(end 320.370962 -427.830742)
		(width 0.14224)
		(layer "In6.Cu")
		(net "P5E_CPU0_P1_TX_BUF_C_DN<3>")
	)
	(arc
		(start 319.521586 -424.673522)
		(mid 319.646741 -424.811698)
		(end 319.69202 -424.992546)
		(width 0.14224)
		(layer "In6.Cu")
		(net "P5E_CPU0_P1_TX_BUF_C_DN<3>")
	)
	(arc
		(start 319.69202 -427.256702)
		(mid 319.725488 -427.424958)
		(end 319.820798 -427.567598)
		(width 0.14224)
		(layer "In6.Cu")
		(net "P5E_CPU0_P1_TX_BUF_C_DN<3>")
	)
	(segment
		(start 311.426606 -417.166044)
		(end 311.722516 -417.461954)
		(width 0.12954)
		(layer "B.Cu")
		(net "P5E_CPU0_P1_TX_BUF_C_DN<2>")
	)
	(segment
		(start 311.722516 -418.141658)
		(end 311.452006 -418.412168)
		(width 0.12954)
		(layer "B.Cu")
		(net "P5E_CPU0_P1_TX_BUF_C_DN<2>")
	)
	(segment
		(start 311.722516 -417.461954)
		(end 311.722516 -418.141658)
		(width 0.12954)
		(layer "B.Cu")
		(net "P5E_CPU0_P1_TX_BUF_C_DN<2>")
	)
	(segment
		(start 312.194194 -422.139618)
		(end 312.858658 -422.4147)
		(width 0.14224)
		(layer "In6.Cu")
		(net "P5E_CPU0_P1_TX_BUF_C_DN<2>")
	)
	(segment
		(start 312.012076 -421.9575)
		(end 312.194194 -422.139618)
		(width 0.14224)
		(layer "In6.Cu")
		(net "P5E_CPU0_P1_TX_BUF_C_DN<2>")
	)
	(segment
		(start 318.649604 -426.972984)
		(end 318.649604 -427.289976)
		(width 0.14224)
		(layer "In6.Cu")
		(net "P5E_CPU0_P1_TX_BUF_C_DN<2>")
	)
	(segment
		(start 312.858658 -422.4147)
		(end 316.691772 -424.0022)
		(width 0.14224)
		(layer "In6.Cu")
		(net "P5E_CPU0_P1_TX_BUF_C_DN<2>")
	)
	(segment
		(start 316.873128 -424.077384)
		(end 317.155068 -424.359324)
		(width 0.14224)
		(layer "In6.Cu")
		(net "P5E_CPU0_P1_TX_BUF_C_DN<2>")
	)
	(segment
		(start 316.69228 -424.002454)
		(end 316.873128 -424.077384)
		(width 0.14224)
		(layer "In6.Cu")
		(net "P5E_CPU0_P1_TX_BUF_C_DN<2>")
	)
	(segment
		(start 318.507364 -426.830744)
		(end 318.649604 -426.972984)
		(width 0.14224)
		(layer "In6.Cu")
		(net "P5E_CPU0_P1_TX_BUF_C_DN<2>")
	)
	(segment
		(start 318.402462 -426.830744)
		(end 318.507364 -426.830744)
		(width 0.14224)
		(layer "In6.Cu")
		(net "P5E_CPU0_P1_TX_BUF_C_DN<2>")
	)
	(segment
		(start 311.742836 -418.702998)
		(end 311.742836 -421.30726)
		(width 0.14224)
		(layer "In6.Cu")
		(net "P5E_CPU0_P1_TX_BUF_C_DN<2>")
	)
	(segment
		(start 316.691772 -424.0022)
		(end 316.69228 -424.002454)
		(width 0.14224)
		(layer "In6.Cu")
		(net "P5E_CPU0_P1_TX_BUF_C_DN<2>")
	)
	(segment
		(start 317.458598 -425.09186)
		(end 317.458598 -425.586398)
		(width 0.14224)
		(layer "In6.Cu")
		(net "P5E_CPU0_P1_TX_BUF_C_DN<2>")
	)
	(segment
		(start 311.452006 -418.412168)
		(end 311.742836 -418.702998)
		(width 0.14224)
		(layer "In6.Cu")
		(net "P5E_CPU0_P1_TX_BUF_C_DN<2>")
	)
	(arc
		(start 317.155068 -424.359324)
		(mid 317.37969 -424.6954)
		(end 317.458598 -425.09186)
		(width 0.14224)
		(layer "In6.Cu")
		(net "P5E_CPU0_P1_TX_BUF_C_DN<2>")
	)
	(arc
		(start 317.885064 -426.616368)
		(mid 318.122434 -426.775037)
		(end 318.402462 -426.830744)
		(width 0.14224)
		(layer "In6.Cu")
		(net "P5E_CPU0_P1_TX_BUF_C_DN<2>")
	)
	(arc
		(start 317.458598 -425.586398)
		(mid 317.569433 -426.14378)
		(end 317.885064 -426.616368)
		(width 0.14224)
		(layer "In6.Cu")
		(net "P5E_CPU0_P1_TX_BUF_C_DN<2>")
	)
	(arc
		(start 311.742836 -421.30726)
		(mid 311.812812 -421.659144)
		(end 312.012076 -421.9575)
		(width 0.14224)
		(layer "In6.Cu")
		(net "P5E_CPU0_P1_TX_BUF_C_DN<2>")
	)
	(segment
		(start 308.659276 -417.461954)
		(end 308.659276 -418.141658)
		(width 0.12954)
		(layer "B.Cu")
		(net "P5E_CPU0_P1_TX_BUF_C_DN<1>")
	)
	(segment
		(start 308.363366 -417.166044)
		(end 308.659276 -417.461954)
		(width 0.12954)
		(layer "B.Cu")
		(net "P5E_CPU0_P1_TX_BUF_C_DN<1>")
	)
	(segment
		(start 308.659276 -418.141658)
		(end 308.388766 -418.412168)
		(width 0.12954)
		(layer "B.Cu")
		(net "P5E_CPU0_P1_TX_BUF_C_DN<1>")
	)
	(segment
		(start 308.810914 -421.833294)
		(end 309.138574 -422.160954)
		(width 0.14224)
		(layer "In6.Cu")
		(net "P5E_CPU0_P1_TX_BUF_C_DN<1>")
	)
	(segment
		(start 316.512702 -427.830742)
		(end 316.649608 -427.967648)
		(width 0.14224)
		(layer "In6.Cu")
		(net "P5E_CPU0_P1_TX_BUF_C_DN<1>")
	)
	(segment
		(start 315.35243 -424.557952)
		(end 315.402976 -424.608498)
		(width 0.14224)
		(layer "In6.Cu")
		(net "P5E_CPU0_P1_TX_BUF_C_DN<1>")
	)
	(segment
		(start 308.679596 -418.702998)
		(end 308.679596 -421.516302)
		(width 0.14224)
		(layer "In6.Cu")
		(net "P5E_CPU0_P1_TX_BUF_C_DN<1>")
	)
	(segment
		(start 309.35676 -422.299384)
		(end 310.013096 -422.533826)
		(width 0.14224)
		(layer "In6.Cu")
		(net "P5E_CPU0_P1_TX_BUF_C_DN<1>")
	)
	(segment
		(start 316.377828 -427.830742)
		(end 316.512702 -427.830742)
		(width 0.14224)
		(layer "In6.Cu")
		(net "P5E_CPU0_P1_TX_BUF_C_DN<1>")
	)
	(segment
		(start 316.649608 -427.967648)
		(end 316.649608 -428.28972)
		(width 0.14224)
		(layer "In6.Cu")
		(net "P5E_CPU0_P1_TX_BUF_C_DN<1>")
	)
	(segment
		(start 310.012842 -422.53408)
		(end 314.87872 -424.274234)
		(width 0.14224)
		(layer "In6.Cu")
		(net "P5E_CPU0_P1_TX_BUF_C_DN<1>")
	)
	(segment
		(start 315.704728 -425.336716)
		(end 315.704728 -427.157642)
		(width 0.14224)
		(layer "In6.Cu")
		(net "P5E_CPU0_P1_TX_BUF_C_DN<1>")
	)
	(segment
		(start 308.388766 -418.412168)
		(end 308.679596 -418.702998)
		(width 0.14224)
		(layer "In6.Cu")
		(net "P5E_CPU0_P1_TX_BUF_C_DN<1>")
	)
	(segment
		(start 310.013096 -422.533826)
		(end 310.012842 -422.53408)
		(width 0.14224)
		(layer "In6.Cu")
		(net "P5E_CPU0_P1_TX_BUF_C_DN<1>")
	)
	(arc
		(start 309.138574 -422.160954)
		(mid 309.239992 -422.242264)
		(end 309.35676 -422.299384)
		(width 0.14224)
		(layer "In6.Cu")
		(net "P5E_CPU0_P1_TX_BUF_C_DN<1>")
	)
	(arc
		(start 308.679596 -421.516302)
		(mid 308.713722 -421.687863)
		(end 308.810914 -421.833294)
		(width 0.14224)
		(layer "In6.Cu")
		(net "P5E_CPU0_P1_TX_BUF_C_DN<1>")
	)
	(arc
		(start 314.87872 -424.274234)
		(mid 315.133096 -424.386839)
		(end 315.35243 -424.557952)
		(width 0.14224)
		(layer "In6.Cu")
		(net "P5E_CPU0_P1_TX_BUF_C_DN<1>")
	)
	(arc
		(start 315.402976 -424.608498)
		(mid 315.626328 -424.942579)
		(end 315.704728 -425.336716)
		(width 0.14224)
		(layer "In6.Cu")
		(net "P5E_CPU0_P1_TX_BUF_C_DN<1>")
	)
	(arc
		(start 315.704728 -427.157642)
		(mid 315.901874 -427.633596)
		(end 316.377828 -427.830742)
		(width 0.14224)
		(layer "In6.Cu")
		(net "P5E_CPU0_P1_TX_BUF_C_DN<1>")
	)
	(segment
		(start 351.544636 -418.141658)
		(end 351.274126 -418.412168)
		(width 0.12954)
		(layer "B.Cu")
		(net "P5E_CPU0_P1_TX_BUF_C_DN<15>")
	)
	(segment
		(start 351.248726 -417.166044)
		(end 351.544636 -417.461954)
		(width 0.12954)
		(layer "B.Cu")
		(net "P5E_CPU0_P1_TX_BUF_C_DN<15>")
	)
	(segment
		(start 351.544636 -417.461954)
		(end 351.544636 -418.141658)
		(width 0.12954)
		(layer "B.Cu")
		(net "P5E_CPU0_P1_TX_BUF_C_DN<15>")
	)
	(segment
		(start 348.55658 -423.184574)
		(end 345.48445 -423.794428)
		(width 0.14224)
		(layer "In6.Cu")
		(net "P5E_CPU0_P1_TX_BUF_C_DN<15>")
	)
	(segment
		(start 345.341194 -427.830742)
		(end 345.507564 -427.830742)
		(width 0.14224)
		(layer "In6.Cu")
		(net "P5E_CPU0_P1_TX_BUF_C_DN<15>")
	)
	(segment
		(start 350.924876 -422.217088)
		(end 348.677738 -423.147998)
		(width 0.14224)
		(layer "In6.Cu")
		(net "P5E_CPU0_P1_TX_BUF_C_DN<15>")
	)
	(segment
		(start 345.075764 -424.013122)
		(end 344.691716 -424.39717)
		(width 0.14224)
		(layer "In6.Cu")
		(net "P5E_CPU0_P1_TX_BUF_C_DN<15>")
	)
	(segment
		(start 351.517712 -421.658796)
		(end 351.029524 -422.146984)
		(width 0.14224)
		(layer "In6.Cu")
		(net "P5E_CPU0_P1_TX_BUF_C_DN<15>")
	)
	(segment
		(start 345.649804 -427.972982)
		(end 345.649804 -428.28972)
		(width 0.14224)
		(layer "In6.Cu")
		(net "P5E_CPU0_P1_TX_BUF_C_DN<15>")
	)
	(segment
		(start 345.48445 -423.794428)
		(end 345.075764 -424.013122)
		(width 0.14224)
		(layer "In6.Cu")
		(net "P5E_CPU0_P1_TX_BUF_C_DN<15>")
	)
	(segment
		(start 344.691716 -424.39717)
		(end 344.691716 -427.267116)
		(width 0.14224)
		(layer "In6.Cu")
		(net "P5E_CPU0_P1_TX_BUF_C_DN<15>")
	)
	(segment
		(start 344.825574 -427.590204)
		(end 344.871548 -427.636178)
		(width 0.14224)
		(layer "In6.Cu")
		(net "P5E_CPU0_P1_TX_BUF_C_DN<15>")
	)
	(segment
		(start 345.507564 -427.830742)
		(end 345.649804 -427.972982)
		(width 0.14224)
		(layer "In6.Cu")
		(net "P5E_CPU0_P1_TX_BUF_C_DN<15>")
	)
	(segment
		(start 351.274126 -418.412168)
		(end 351.564956 -418.702998)
		(width 0.14224)
		(layer "In6.Cu")
		(net "P5E_CPU0_P1_TX_BUF_C_DN<15>")
	)
	(segment
		(start 351.564956 -418.702998)
		(end 351.564956 -421.54475)
		(width 0.14224)
		(layer "In6.Cu")
		(net "P5E_CPU0_P1_TX_BUF_C_DN<15>")
	)
	(arc
		(start 344.691716 -427.267116)
		(mid 344.726499 -427.441982)
		(end 344.825574 -427.590204)
		(width 0.14224)
		(layer "In6.Cu")
		(net "P5E_CPU0_P1_TX_BUF_C_DN<15>")
	)
	(arc
		(start 344.871548 -427.636178)
		(mid 345.087023 -427.780154)
		(end 345.341194 -427.830742)
		(width 0.14224)
		(layer "In6.Cu")
		(net "P5E_CPU0_P1_TX_BUF_C_DN<15>")
	)
	(arc
		(start 351.029524 -422.146984)
		(mid 350.980663 -422.187208)
		(end 350.924876 -422.217088)
		(width 0.14224)
		(layer "In6.Cu")
		(net "P5E_CPU0_P1_TX_BUF_C_DN<15>")
	)
	(arc
		(start 348.677738 -423.147998)
		(mid 348.618059 -423.169265)
		(end 348.55658 -423.184574)
		(width 0.14224)
		(layer "In6.Cu")
		(net "P5E_CPU0_P1_TX_BUF_C_DN<15>")
	)
	(arc
		(start 351.564956 -421.54475)
		(mid 351.552679 -421.606473)
		(end 351.517712 -421.658796)
		(width 0.14224)
		(layer "In6.Cu")
		(net "P5E_CPU0_P1_TX_BUF_C_DN<15>")
	)
	(segment
		(start 348.481396 -418.141658)
		(end 348.210886 -418.412168)
		(width 0.12954)
		(layer "B.Cu")
		(net "P5E_CPU0_P1_TX_BUF_C_DN<14>")
	)
	(segment
		(start 348.481396 -417.461954)
		(end 348.481396 -418.141658)
		(width 0.12954)
		(layer "B.Cu")
		(net "P5E_CPU0_P1_TX_BUF_C_DN<14>")
	)
	(segment
		(start 348.185486 -417.166044)
		(end 348.481396 -417.461954)
		(width 0.12954)
		(layer "B.Cu")
		(net "P5E_CPU0_P1_TX_BUF_C_DN<14>")
	)
	(segment
		(start 343.228422 -426.865796)
		(end 343.522808 -426.865796)
		(width 0.14224)
		(layer "In6.Cu")
		(net "P5E_CPU0_P1_TX_BUF_C_DN<14>")
	)
	(segment
		(start 343.56802 -423.399712)
		(end 342.806274 -424.161458)
		(width 0.14224)
		(layer "In6.Cu")
		(net "P5E_CPU0_P1_TX_BUF_C_DN<14>")
	)
	(segment
		(start 343.649808 -426.992796)
		(end 343.649808 -427.289976)
		(width 0.14224)
		(layer "In6.Cu")
		(net "P5E_CPU0_P1_TX_BUF_C_DN<14>")
	)
	(segment
		(start 342.621108 -424.608498)
		(end 342.621108 -426.09008)
		(width 0.14224)
		(layer "In6.Cu")
		(net "P5E_CPU0_P1_TX_BUF_C_DN<14>")
	)
	(segment
		(start 347.407738 -422.23436)
		(end 347.407484 -422.234614)
		(width 0.14224)
		(layer "In6.Cu")
		(net "P5E_CPU0_P1_TX_BUF_C_DN<14>")
	)
	(segment
		(start 346.84843 -422.404286)
		(end 346.84843 -422.40454)
		(width 0.14224)
		(layer "In6.Cu")
		(net "P5E_CPU0_P1_TX_BUF_C_DN<14>")
	)
	(segment
		(start 346.84843 -422.40454)
		(end 343.56802 -423.399712)
		(width 0.14224)
		(layer "In6.Cu")
		(net "P5E_CPU0_P1_TX_BUF_C_DN<14>")
	)
	(segment
		(start 348.501716 -418.702998)
		(end 348.501716 -421.42918)
		(width 0.14224)
		(layer "In6.Cu")
		(net "P5E_CPU0_P1_TX_BUF_C_DN<14>")
	)
	(segment
		(start 343.522808 -426.865796)
		(end 343.649808 -426.992796)
		(width 0.14224)
		(layer "In6.Cu")
		(net "P5E_CPU0_P1_TX_BUF_C_DN<14>")
	)
	(segment
		(start 348.210886 -418.412168)
		(end 348.501716 -418.702998)
		(width 0.14224)
		(layer "In6.Cu")
		(net "P5E_CPU0_P1_TX_BUF_C_DN<14>")
	)
	(segment
		(start 342.874346 -426.701204)
		(end 342.905334 -426.732192)
		(width 0.14224)
		(layer "In6.Cu")
		(net "P5E_CPU0_P1_TX_BUF_C_DN<14>")
	)
	(segment
		(start 348.501716 -421.42918)
		(end 347.820996 -422.109138)
		(width 0.14224)
		(layer "In6.Cu")
		(net "P5E_CPU0_P1_TX_BUF_C_DN<14>")
	)
	(segment
		(start 347.407484 -422.234614)
		(end 346.84843 -422.404286)
		(width 0.14224)
		(layer "In6.Cu")
		(net "P5E_CPU0_P1_TX_BUF_C_DN<14>")
	)
	(segment
		(start 347.820996 -422.109138)
		(end 347.407738 -422.23436)
		(width 0.14224)
		(layer "In6.Cu")
		(net "P5E_CPU0_P1_TX_BUF_C_DN<14>")
	)
	(arc
		(start 342.806274 -424.161458)
		(mid 342.669228 -424.366562)
		(end 342.621108 -424.608498)
		(width 0.14224)
		(layer "In6.Cu")
		(net "P5E_CPU0_P1_TX_BUF_C_DN<14>")
	)
	(arc
		(start 342.905334 -426.732192)
		(mid 343.053569 -426.83121)
		(end 343.228422 -426.865796)
		(width 0.14224)
		(layer "In6.Cu")
		(net "P5E_CPU0_P1_TX_BUF_C_DN<14>")
	)
	(arc
		(start 342.660224 -426.347382)
		(mid 342.745828 -426.537274)
		(end 342.874346 -426.701204)
		(width 0.14224)
		(layer "In6.Cu")
		(net "P5E_CPU0_P1_TX_BUF_C_DN<14>")
	)
	(arc
		(start 342.621108 -426.09008)
		(mid 342.630924 -426.220212)
		(end 342.660224 -426.347382)
		(width 0.14224)
		(layer "In6.Cu")
		(net "P5E_CPU0_P1_TX_BUF_C_DN<14>")
	)
	(segment
		(start 345.418156 -418.141658)
		(end 345.147646 -418.412168)
		(width 0.12954)
		(layer "B.Cu")
		(net "P5E_CPU0_P1_TX_BUF_C_DN<13>")
	)
	(segment
		(start 345.122246 -417.166044)
		(end 345.418156 -417.461954)
		(width 0.12954)
		(layer "B.Cu")
		(net "P5E_CPU0_P1_TX_BUF_C_DN<13>")
	)
	(segment
		(start 345.418156 -417.461954)
		(end 345.418156 -418.141658)
		(width 0.12954)
		(layer "B.Cu")
		(net "P5E_CPU0_P1_TX_BUF_C_DN<13>")
	)
	(segment
		(start 345.438476 -418.702998)
		(end 345.438476 -421.108378)
		(width 0.14224)
		(layer "In6.Cu")
		(net "P5E_CPU0_P1_TX_BUF_C_DN<13>")
	)
	(segment
		(start 340.862412 -427.620176)
		(end 340.87943 -427.637194)
		(width 0.14224)
		(layer "In6.Cu")
		(net "P5E_CPU0_P1_TX_BUF_C_DN<13>")
	)
	(segment
		(start 340.707218 -424.87215)
		(end 340.707218 -427.245526)
		(width 0.14224)
		(layer "In6.Cu")
		(net "P5E_CPU0_P1_TX_BUF_C_DN<13>")
	)
	(segment
		(start 345.185746 -421.718486)
		(end 344.98026 -421.923972)
		(width 0.14224)
		(layer "In6.Cu")
		(net "P5E_CPU0_P1_TX_BUF_C_DN<13>")
	)
	(segment
		(start 344.83294 -422.014904)
		(end 344.802714 -422.02481)
		(width 0.14224)
		(layer "In6.Cu")
		(net "P5E_CPU0_P1_TX_BUF_C_DN<13>")
	)
	(segment
		(start 344.677746 -422.044622)
		(end 343.657428 -422.044622)
		(width 0.14224)
		(layer "In6.Cu")
		(net "P5E_CPU0_P1_TX_BUF_C_DN<13>")
	)
	(segment
		(start 341.34679 -427.830742)
		(end 341.507572 -427.830742)
		(width 0.14224)
		(layer "In6.Cu")
		(net "P5E_CPU0_P1_TX_BUF_C_DN<13>")
	)
	(segment
		(start 341.507572 -427.830742)
		(end 341.649812 -427.972982)
		(width 0.14224)
		(layer "In6.Cu")
		(net "P5E_CPU0_P1_TX_BUF_C_DN<13>")
	)
	(segment
		(start 343.382854 -422.14292)
		(end 341.119206 -424.000676)
		(width 0.14224)
		(layer "In6.Cu")
		(net "P5E_CPU0_P1_TX_BUF_C_DN<13>")
	)
	(segment
		(start 345.147646 -418.412168)
		(end 345.438476 -418.702998)
		(width 0.14224)
		(layer "In6.Cu")
		(net "P5E_CPU0_P1_TX_BUF_C_DN<13>")
	)
	(segment
		(start 341.649812 -427.972982)
		(end 341.649812 -428.28972)
		(width 0.14224)
		(layer "In6.Cu")
		(net "P5E_CPU0_P1_TX_BUF_C_DN<13>")
	)
	(segment
		(start 343.383108 -422.142666)
		(end 343.382854 -422.14292)
		(width 0.14224)
		(layer "In6.Cu")
		(net "P5E_CPU0_P1_TX_BUF_C_DN<13>")
	)
	(arc
		(start 344.98026 -421.923972)
		(mid 344.911939 -421.978085)
		(end 344.83294 -422.014904)
		(width 0.14224)
		(layer "In6.Cu")
		(net "P5E_CPU0_P1_TX_BUF_C_DN<13>")
	)
	(arc
		(start 344.802714 -422.02481)
		(mid 344.741017 -422.039668)
		(end 344.677746 -422.044622)
		(width 0.14224)
		(layer "In6.Cu")
		(net "P5E_CPU0_P1_TX_BUF_C_DN<13>")
	)
	(arc
		(start 340.87943 -427.637194)
		(mid 341.093871 -427.780416)
		(end 341.34679 -427.830742)
		(width 0.14224)
		(layer "In6.Cu")
		(net "P5E_CPU0_P1_TX_BUF_C_DN<13>")
	)
	(arc
		(start 340.707218 -427.245526)
		(mid 340.74755 -427.448289)
		(end 340.862412 -427.620176)
		(width 0.14224)
		(layer "In6.Cu")
		(net "P5E_CPU0_P1_TX_BUF_C_DN<13>")
	)
	(arc
		(start 345.438476 -421.108378)
		(mid 345.372796 -421.438572)
		(end 345.185746 -421.718486)
		(width 0.14224)
		(layer "In6.Cu")
		(net "P5E_CPU0_P1_TX_BUF_C_DN<13>")
	)
	(arc
		(start 341.119206 -424.000676)
		(mid 340.815375 -424.390157)
		(end 340.707218 -424.87215)
		(width 0.14224)
		(layer "In6.Cu")
		(net "P5E_CPU0_P1_TX_BUF_C_DN<13>")
	)
	(arc
		(start 343.657428 -422.044622)
		(mid 343.51177 -422.069868)
		(end 343.383108 -422.142666)
		(width 0.14224)
		(layer "In6.Cu")
		(net "P5E_CPU0_P1_TX_BUF_C_DN<13>")
	)
	(segment
		(start 342.337644 -418.15893)
		(end 342.084406 -418.412168)
		(width 0.12954)
		(layer "B.Cu")
		(net "P5E_CPU0_P1_TX_BUF_C_DN<12>")
	)
	(segment
		(start 342.337644 -417.444682)
		(end 342.337644 -418.15893)
		(width 0.12954)
		(layer "B.Cu")
		(net "P5E_CPU0_P1_TX_BUF_C_DN<12>")
	)
	(segment
		(start 342.059006 -417.166044)
		(end 342.337644 -417.444682)
		(width 0.12954)
		(layer "B.Cu")
		(net "P5E_CPU0_P1_TX_BUF_C_DN<12>")
	)
	(segment
		(start 342.067642 -421.809164)
		(end 338.989416 -424.151298)
		(width 0.14224)
		(layer "In6.Cu")
		(net "P5E_CPU0_P1_TX_BUF_C_DN<12>")
	)
	(segment
		(start 342.375236 -418.702998)
		(end 342.375236 -421.31996)
		(width 0.14224)
		(layer "In6.Cu")
		(net "P5E_CPU0_P1_TX_BUF_C_DN<12>")
	)
	(segment
		(start 339.056472 -426.776642)
		(end 339.056726 -426.776642)
		(width 0.14224)
		(layer "In6.Cu")
		(net "P5E_CPU0_P1_TX_BUF_C_DN<12>")
	)
	(segment
		(start 342.246712 -421.630094)
		(end 342.067642 -421.809164)
		(width 0.14224)
		(layer "In6.Cu")
		(net "P5E_CPU0_P1_TX_BUF_C_DN<12>")
	)
	(segment
		(start 342.084406 -418.412168)
		(end 342.375236 -418.702998)
		(width 0.14224)
		(layer "In6.Cu")
		(net "P5E_CPU0_P1_TX_BUF_C_DN<12>")
	)
	(segment
		(start 338.67725 -424.781218)
		(end 338.67725 -426.217334)
		(width 0.14224)
		(layer "In6.Cu")
		(net "P5E_CPU0_P1_TX_BUF_C_DN<12>")
	)
	(segment
		(start 338.851494 -426.637958)
		(end 338.858352 -426.644816)
		(width 0.14224)
		(layer "In6.Cu")
		(net "P5E_CPU0_P1_TX_BUF_C_DN<12>")
	)
	(segment
		(start 339.33257 -426.830744)
		(end 339.495384 -426.830744)
		(width 0.14224)
		(layer "In6.Cu")
		(net "P5E_CPU0_P1_TX_BUF_C_DN<12>")
	)
	(segment
		(start 339.495384 -426.830744)
		(end 339.649816 -426.985176)
		(width 0.14224)
		(layer "In6.Cu")
		(net "P5E_CPU0_P1_TX_BUF_C_DN<12>")
	)
	(segment
		(start 339.649816 -426.985176)
		(end 339.649816 -427.289976)
		(width 0.14224)
		(layer "In6.Cu")
		(net "P5E_CPU0_P1_TX_BUF_C_DN<12>")
	)
	(arc
		(start 338.858352 -426.644816)
		(mid 338.95084 -426.720602)
		(end 339.056472 -426.776642)
		(width 0.14224)
		(layer "In6.Cu")
		(net "P5E_CPU0_P1_TX_BUF_C_DN<12>")
	)
	(arc
		(start 338.67725 -426.217334)
		(mid 338.722532 -426.44498)
		(end 338.851494 -426.637958)
		(width 0.14224)
		(layer "In6.Cu")
		(net "P5E_CPU0_P1_TX_BUF_C_DN<12>")
	)
	(arc
		(start 338.989416 -424.151298)
		(mid 338.759593 -424.429711)
		(end 338.67725 -424.781218)
		(width 0.14224)
		(layer "In6.Cu")
		(net "P5E_CPU0_P1_TX_BUF_C_DN<12>")
	)
	(arc
		(start 342.375236 -421.31996)
		(mid 342.34183 -421.487813)
		(end 342.246712 -421.630094)
		(width 0.14224)
		(layer "In6.Cu")
		(net "P5E_CPU0_P1_TX_BUF_C_DN<12>")
	)
	(arc
		(start 339.056726 -426.776642)
		(mid 339.192018 -426.817105)
		(end 339.33257 -426.830744)
		(width 0.14224)
		(layer "In6.Cu")
		(net "P5E_CPU0_P1_TX_BUF_C_DN<12>")
	)
	(segment
		(start 338.995766 -417.166044)
		(end 339.291676 -417.461954)
		(width 0.12954)
		(layer "B.Cu")
		(net "P5E_CPU0_P1_TX_BUF_C_DN<11>")
	)
	(segment
		(start 339.291676 -417.461954)
		(end 339.291676 -418.141658)
		(width 0.12954)
		(layer "B.Cu")
		(net "P5E_CPU0_P1_TX_BUF_C_DN<11>")
	)
	(segment
		(start 339.291676 -418.141658)
		(end 339.021166 -418.412168)
		(width 0.12954)
		(layer "B.Cu")
		(net "P5E_CPU0_P1_TX_BUF_C_DN<11>")
	)
	(segment
		(start 339.021166 -418.412168)
		(end 339.311996 -418.702998)
		(width 0.14224)
		(layer "In6.Cu")
		(net "P5E_CPU0_P1_TX_BUF_C_DN<11>")
	)
	(segment
		(start 336.884264 -427.679358)
		(end 336.88528 -427.680374)
		(width 0.14224)
		(layer "In6.Cu")
		(net "P5E_CPU0_P1_TX_BUF_C_DN<11>")
	)
	(segment
		(start 336.71256 -424.38574)
		(end 336.71256 -427.26483)
		(width 0.14224)
		(layer "In6.Cu")
		(net "P5E_CPU0_P1_TX_BUF_C_DN<11>")
	)
	(segment
		(start 337.50758 -427.830742)
		(end 337.64982 -427.972982)
		(width 0.14224)
		(layer "In6.Cu")
		(net "P5E_CPU0_P1_TX_BUF_C_DN<11>")
	)
	(segment
		(start 339.13572 -421.689784)
		(end 336.905346 -423.920158)
		(width 0.14224)
		(layer "In6.Cu")
		(net "P5E_CPU0_P1_TX_BUF_C_DN<11>")
	)
	(segment
		(start 339.311996 -418.702998)
		(end 339.311996 -421.264334)
		(width 0.14224)
		(layer "In6.Cu")
		(net "P5E_CPU0_P1_TX_BUF_C_DN<11>")
	)
	(segment
		(start 337.248246 -427.830742)
		(end 337.50758 -427.830742)
		(width 0.14224)
		(layer "In6.Cu")
		(net "P5E_CPU0_P1_TX_BUF_C_DN<11>")
	)
	(segment
		(start 337.64982 -427.972982)
		(end 337.64982 -428.28972)
		(width 0.14224)
		(layer "In6.Cu")
		(net "P5E_CPU0_P1_TX_BUF_C_DN<11>")
	)
	(arc
		(start 336.71256 -427.26483)
		(mid 336.757184 -427.489171)
		(end 336.884264 -427.679358)
		(width 0.14224)
		(layer "In6.Cu")
		(net "P5E_CPU0_P1_TX_BUF_C_DN<11>")
	)
	(arc
		(start 336.905346 -423.920158)
		(mid 336.762669 -424.133783)
		(end 336.71256 -424.38574)
		(width 0.14224)
		(layer "In6.Cu")
		(net "P5E_CPU0_P1_TX_BUF_C_DN<11>")
	)
	(arc
		(start 339.311996 -421.264334)
		(mid 339.266177 -421.49459)
		(end 339.13572 -421.689784)
		(width 0.14224)
		(layer "In6.Cu")
		(net "P5E_CPU0_P1_TX_BUF_C_DN<11>")
	)
	(arc
		(start 336.88528 -427.680374)
		(mid 337.05181 -427.791646)
		(end 337.248246 -427.830742)
		(width 0.14224)
		(layer "In6.Cu")
		(net "P5E_CPU0_P1_TX_BUF_C_DN<11>")
	)
	(segment
		(start 336.228436 -418.141658)
		(end 335.957926 -418.412168)
		(width 0.12954)
		(layer "B.Cu")
		(net "P5E_CPU0_P1_TX_BUF_C_DN<10>")
	)
	(segment
		(start 335.932526 -417.166044)
		(end 336.228436 -417.461954)
		(width 0.12954)
		(layer "B.Cu")
		(net "P5E_CPU0_P1_TX_BUF_C_DN<10>")
	)
	(segment
		(start 336.228436 -417.461954)
		(end 336.228436 -418.141658)
		(width 0.12954)
		(layer "B.Cu")
		(net "P5E_CPU0_P1_TX_BUF_C_DN<10>")
	)
	(segment
		(start 334.616806 -424.658536)
		(end 334.616806 -426.0977)
		(width 0.14224)
		(layer "In6.Cu")
		(net "P5E_CPU0_P1_TX_BUF_C_DN<10>")
	)
	(segment
		(start 335.514696 -426.847762)
		(end 335.649824 -426.98289)
		(width 0.14224)
		(layer "In6.Cu")
		(net "P5E_CPU0_P1_TX_BUF_C_DN<10>")
	)
	(segment
		(start 334.848454 -426.657008)
		(end 334.850486 -426.65904)
		(width 0.14224)
		(layer "In6.Cu")
		(net "P5E_CPU0_P1_TX_BUF_C_DN<10>")
	)
	(segment
		(start 335.306162 -426.847762)
		(end 335.514696 -426.847762)
		(width 0.14224)
		(layer "In6.Cu")
		(net "P5E_CPU0_P1_TX_BUF_C_DN<10>")
	)
	(segment
		(start 336.248756 -418.702998)
		(end 336.248756 -421.208454)
		(width 0.14224)
		(layer "In6.Cu")
		(net "P5E_CPU0_P1_TX_BUF_C_DN<10>")
	)
	(segment
		(start 335.649824 -426.98289)
		(end 335.649824 -427.289976)
		(width 0.14224)
		(layer "In6.Cu")
		(net "P5E_CPU0_P1_TX_BUF_C_DN<10>")
	)
	(segment
		(start 335.957926 -418.412168)
		(end 336.248756 -418.702998)
		(width 0.14224)
		(layer "In6.Cu")
		(net "P5E_CPU0_P1_TX_BUF_C_DN<10>")
	)
	(segment
		(start 336.248756 -421.208454)
		(end 334.616806 -424.658536)
		(width 0.14224)
		(layer "In6.Cu")
		(net "P5E_CPU0_P1_TX_BUF_C_DN<10>")
	)
	(arc
		(start 334.616806 -426.0977)
		(mid 334.677029 -426.400372)
		(end 334.848454 -426.657008)
		(width 0.14224)
		(layer "In6.Cu")
		(net "P5E_CPU0_P1_TX_BUF_C_DN<10>")
	)
	(arc
		(start 334.850486 -426.65904)
		(mid 335.059552 -426.798733)
		(end 335.306162 -426.847762)
		(width 0.14224)
		(layer "In6.Cu")
		(net "P5E_CPU0_P1_TX_BUF_C_DN<10>")
	)
	(segment
		(start 305.596036 -418.141658)
		(end 305.325526 -418.412168)
		(width 0.12954)
		(layer "B.Cu")
		(net "P5E_CPU0_P1_TX_BUF_C_DN<0>")
	)
	(segment
		(start 305.596036 -417.461954)
		(end 305.596036 -418.141658)
		(width 0.12954)
		(layer "B.Cu")
		(net "P5E_CPU0_P1_TX_BUF_C_DN<0>")
	)
	(segment
		(start 305.300126 -417.166044)
		(end 305.596036 -417.461954)
		(width 0.12954)
		(layer "B.Cu")
		(net "P5E_CPU0_P1_TX_BUF_C_DN<0>")
	)
	(segment
		(start 314.649612 -426.972984)
		(end 314.649612 -427.289976)
		(width 0.14224)
		(layer "In6.Cu")
		(net "P5E_CPU0_P1_TX_BUF_C_DN<0>")
	)
	(segment
		(start 314.507372 -426.830744)
		(end 314.649612 -426.972984)
		(width 0.14224)
		(layer "In6.Cu")
		(net "P5E_CPU0_P1_TX_BUF_C_DN<0>")
	)
	(segment
		(start 306.222146 -422.31945)
		(end 312.395108 -426.019722)
		(width 0.14224)
		(layer "In6.Cu")
		(net "P5E_CPU0_P1_TX_BUF_C_DN<0>")
	)
	(segment
		(start 305.325526 -418.412168)
		(end 305.616356 -418.702998)
		(width 0.14224)
		(layer "In6.Cu")
		(net "P5E_CPU0_P1_TX_BUF_C_DN<0>")
	)
	(segment
		(start 312.395108 -426.019722)
		(end 313.912504 -426.830744)
		(width 0.14224)
		(layer "In6.Cu")
		(net "P5E_CPU0_P1_TX_BUF_C_DN<0>")
	)
	(segment
		(start 313.912504 -426.830744)
		(end 314.507372 -426.830744)
		(width 0.14224)
		(layer "In6.Cu")
		(net "P5E_CPU0_P1_TX_BUF_C_DN<0>")
	)
	(segment
		(start 305.616356 -418.702998)
		(end 305.616356 -421.193214)
		(width 0.14224)
		(layer "In6.Cu")
		(net "P5E_CPU0_P1_TX_BUF_C_DN<0>")
	)
	(arc
		(start 305.616356 -421.193214)
		(mid 305.777415 -421.832621)
		(end 306.222146 -422.31945)
		(width 0.14224)
		(layer "In6.Cu")
		(net "P5E_CPU0_P1_TX_BUF_C_DN<0>")
	)
	(segment
		(start 347.144086 -401.4978)
		(end 347.144086 -401.674838)
		(width 0.1016)
		(layer "F.Cu")
		(net "P5E_CPU0_P1_RX_BUF_DP<9>")
	)
	(segment
		(start 346.459048 -399.941796)
		(end 346.459048 -401.105878)
		(width 0.1016)
		(layer "F.Cu")
		(net "P5E_CPU0_P1_RX_BUF_DP<9>")
	)
	(segment
		(start 346.712286 -401.359116)
		(end 347.005402 -401.359116)
		(width 0.1016)
		(layer "F.Cu")
		(net "P5E_CPU0_P1_RX_BUF_DP<9>")
	)
	(segment
		(start 347.005402 -401.359116)
		(end 347.144086 -401.4978)
		(width 0.1016)
		(layer "F.Cu")
		(net "P5E_CPU0_P1_RX_BUF_DP<9>")
	)
	(segment
		(start 346.530168 -399.870676)
		(end 346.459048 -399.941796)
		(width 0.1016)
		(layer "F.Cu")
		(net "P5E_CPU0_P1_RX_BUF_DP<9>")
	)
	(segment
		(start 346.530168 -399.74774)
		(end 346.530168 -399.870676)
		(width 0.1016)
		(layer "F.Cu")
		(net "P5E_CPU0_P1_RX_BUF_DP<9>")
	)
	(segment
		(start 346.459048 -401.105878)
		(end 346.712286 -401.359116)
		(width 0.1016)
		(layer "F.Cu")
		(net "P5E_CPU0_P1_RX_BUF_DP<9>")
	)
	(segment
		(start 346.445586 -399.663158)
		(end 346.530168 -399.74774)
		(width 0.1016)
		(layer "F.Cu")
		(net "P5E_CPU0_P1_RX_BUF_DP<9>")
	)
	(segment
		(start 343.209626 -407.99893)
		(end 343.511378 -407.697432)
		(width 0.14224)
		(layer "In13.Cu")
		(net "P5E_CPU0_P1_RX_BUF_DP<9>")
	)
	(segment
		(start 333.066644 -424.06189)
		(end 333.228188 -423.95394)
		(width 0.14224)
		(layer "In13.Cu")
		(net "P5E_CPU0_P1_RX_BUF_DP<9>")
	)
	(segment
		(start 334.707992 -419.56482)
		(end 334.875378 -419.388798)
		(width 0.14224)
		(layer "In13.Cu")
		(net "P5E_CPU0_P1_RX_BUF_DP<9>")
	)
	(segment
		(start 333.555086 -420.09695)
		(end 334.507586 -419.70198)
		(width 0.14224)
		(layer "In13.Cu")
		(net "P5E_CPU0_P1_RX_BUF_DP<9>")
	)
	(segment
		(start 333.649828 -434.289962)
		(end 333.649828 -434.594254)
		(width 0.14224)
		(layer "In13.Cu")
		(net "P5E_CPU0_P1_RX_BUF_DP<9>")
	)
	(segment
		(start 345.556332 -405.566372)
		(end 345.870784 -405.182832)
		(width 0.14224)
		(layer "In13.Cu")
		(net "P5E_CPU0_P1_RX_BUF_DP<9>")
	)
	(segment
		(start 333.20355 -423.374058)
		(end 333.459582 -422.0845)
		(width 0.14224)
		(layer "In13.Cu")
		(net "P5E_CPU0_P1_RX_BUF_DP<9>")
	)
	(segment
		(start 345.856814 -405.039576)
		(end 346.50934 -404.244556)
		(width 0.14224)
		(layer "In13.Cu")
		(net "P5E_CPU0_P1_RX_BUF_DP<9>")
	)
	(segment
		(start 346.685108 -402.793962)
		(end 346.685108 -401.541996)
		(width 0.14224)
		(layer "In13.Cu")
		(net "P5E_CPU0_P1_RX_BUF_DP<9>")
	)
	(segment
		(start 332.983586 -424.480228)
		(end 333.066644 -424.06189)
		(width 0.14224)
		(layer "In13.Cu")
		(net "P5E_CPU0_P1_RX_BUF_DP<9>")
	)
	(segment
		(start 339.764878 -410.520134)
		(end 339.839046 -410.341064)
		(width 0.14224)
		(layer "In13.Cu")
		(net "P5E_CPU0_P1_RX_BUF_DP<9>")
	)
	(segment
		(start 335.136236 -416.051238)
		(end 334.999076 -415.914078)
		(width 0.14224)
		(layer "In13.Cu")
		(net "P5E_CPU0_P1_RX_BUF_DP<9>")
	)
	(segment
		(start 335.865978 -414.153096)
		(end 336.181446 -413.942276)
		(width 0.14224)
		(layer "In13.Cu")
		(net "P5E_CPU0_P1_RX_BUF_DP<9>")
	)
	(segment
		(start 335.136236 -416.477958)
		(end 335.136236 -416.051238)
		(width 0.14224)
		(layer "In13.Cu")
		(net "P5E_CPU0_P1_RX_BUF_DP<9>")
	)
	(segment
		(start 343.70518 -407.697432)
		(end 344.007186 -407.395426)
		(width 0.14224)
		(layer "In13.Cu")
		(net "P5E_CPU0_P1_RX_BUF_DP<9>")
	)
	(segment
		(start 344.007186 -407.395426)
		(end 344.007186 -407.20137)
		(width 0.14224)
		(layer "In13.Cu")
		(net "P5E_CPU0_P1_RX_BUF_DP<9>")
	)
	(segment
		(start 341.49538 -409.478226)
		(end 341.645494 -409.500578)
		(width 0.14224)
		(layer "In13.Cu")
		(net "P5E_CPU0_P1_RX_BUF_DP<9>")
	)
	(segment
		(start 345.141296 -405.911558)
		(end 345.413076 -405.580342)
		(width 0.14224)
		(layer "In13.Cu")
		(net "P5E_CPU0_P1_RX_BUF_DP<9>")
	)
	(segment
		(start 339.370416 -410.683456)
		(end 339.764878 -410.520134)
		(width 0.14224)
		(layer "In13.Cu")
		(net "P5E_CPU0_P1_RX_BUF_DP<9>")
	)
	(segment
		(start 341.645494 -409.500578)
		(end 342.0364 -409.210764)
		(width 0.14224)
		(layer "In13.Cu")
		(net "P5E_CPU0_P1_RX_BUF_DP<9>")
	)
	(segment
		(start 333.228188 -423.95394)
		(end 333.311246 -423.535348)
		(width 0.14224)
		(layer "In13.Cu")
		(net "P5E_CPU0_P1_RX_BUF_DP<9>")
	)
	(segment
		(start 344.889074 -406.434544)
		(end 345.160092 -406.104598)
		(width 0.14224)
		(layer "In13.Cu")
		(net "P5E_CPU0_P1_RX_BUF_DP<9>")
	)
	(segment
		(start 343.511378 -407.697432)
		(end 343.70518 -407.697432)
		(width 0.14224)
		(layer "In13.Cu")
		(net "P5E_CPU0_P1_RX_BUF_DP<9>")
	)
	(segment
		(start 346.685108 -403.75332)
		(end 346.685108 -403.495002)
		(width 0.14224)
		(layer "In13.Cu")
		(net "P5E_CPU0_P1_RX_BUF_DP<9>")
	)
	(segment
		(start 334.999076 -415.914078)
		(end 334.999076 -415.020252)
		(width 0.14224)
		(layer "In13.Cu")
		(net "P5E_CPU0_P1_RX_BUF_DP<9>")
	)
	(segment
		(start 336.181446 -413.942276)
		(end 336.328258 -413.795464)
		(width 0.14224)
		(layer "In13.Cu")
		(net "P5E_CPU0_P1_RX_BUF_DP<9>")
	)
	(segment
		(start 343.209626 -408.192732)
		(end 343.209626 -407.99893)
		(width 0.14224)
		(layer "In13.Cu")
		(net "P5E_CPU0_P1_RX_BUF_DP<9>")
	)
	(segment
		(start 334.999076 -417.041838)
		(end 334.999076 -416.615118)
		(width 0.14224)
		(layer "In13.Cu")
		(net "P5E_CPU0_P1_RX_BUF_DP<9>")
	)
	(segment
		(start 337.79206 -411.188916)
		(end 338.11972 -411.05328)
		(width 0.14224)
		(layer "In13.Cu")
		(net "P5E_CPU0_P1_RX_BUF_DP<9>")
	)
	(segment
		(start 338.693252 -410.96438)
		(end 338.76742 -410.784802)
		(width 0.14224)
		(layer "In13.Cu")
		(net "P5E_CPU0_P1_RX_BUF_DP<9>")
	)
	(segment
		(start 346.685108 -401.541996)
		(end 346.827348 -401.399756)
		(width 0.14224)
		(layer "In13.Cu")
		(net "P5E_CPU0_P1_RX_BUF_DP<9>")
	)
	(segment
		(start 340.782656 -409.949904)
		(end 341.109554 -409.76423)
		(width 0.14224)
		(layer "In13.Cu")
		(net "P5E_CPU0_P1_RX_BUF_DP<9>")
	)
	(segment
		(start 333.311246 -423.535348)
		(end 333.20355 -423.374058)
		(width 0.14224)
		(layer "In13.Cu")
		(net "P5E_CPU0_P1_RX_BUF_DP<9>")
	)
	(segment
		(start 344.425524 -406.783286)
		(end 344.696034 -406.453594)
		(width 0.14224)
		(layer "In13.Cu")
		(net "P5E_CPU0_P1_RX_BUF_DP<9>")
	)
	(segment
		(start 346.822268 -403.357842)
		(end 346.822268 -402.931122)
		(width 0.14224)
		(layer "In13.Cu")
		(net "P5E_CPU0_P1_RX_BUF_DP<9>")
	)
	(segment
		(start 345.413076 -405.580342)
		(end 345.556332 -405.566372)
		(width 0.14224)
		(layer "In13.Cu")
		(net "P5E_CPU0_P1_RX_BUF_DP<9>")
	)
	(segment
		(start 342.907366 -408.494738)
		(end 343.209626 -408.192732)
		(width 0.14224)
		(layer "In13.Cu")
		(net "P5E_CPU0_P1_RX_BUF_DP<9>")
	)
	(segment
		(start 334.999076 -417.742878)
		(end 335.136236 -417.605718)
		(width 0.14224)
		(layer "In13.Cu")
		(net "P5E_CPU0_P1_RX_BUF_DP<9>")
	)
	(segment
		(start 332.970886 -434.62194)
		(end 332.970886 -424.608752)
		(width 0.14224)
		(layer "In13.Cu")
		(net "P5E_CPU0_P1_RX_BUF_DP<9>")
	)
	(segment
		(start 341.109554 -409.76423)
		(end 341.49538 -409.478226)
		(width 0.14224)
		(layer "In13.Cu")
		(net "P5E_CPU0_P1_RX_BUF_DP<9>")
	)
	(segment
		(start 344.696034 -406.453594)
		(end 344.889074 -406.434544)
		(width 0.14224)
		(layer "In13.Cu")
		(net "P5E_CPU0_P1_RX_BUF_DP<9>")
	)
	(segment
		(start 346.822268 -402.931122)
		(end 346.685108 -402.793962)
		(width 0.14224)
		(layer "In13.Cu")
		(net "P5E_CPU0_P1_RX_BUF_DP<9>")
	)
	(segment
		(start 344.007186 -407.20137)
		(end 344.425524 -406.783286)
		(width 0.14224)
		(layer "In13.Cu")
		(net "P5E_CPU0_P1_RX_BUF_DP<9>")
	)
	(segment
		(start 346.827348 -401.399756)
		(end 347.017086 -401.399756)
		(width 0.14224)
		(layer "In13.Cu")
		(net "P5E_CPU0_P1_RX_BUF_DP<9>")
	)
	(segment
		(start 345.160092 -406.104598)
		(end 345.141296 -405.911558)
		(width 0.14224)
		(layer "In13.Cu")
		(net "P5E_CPU0_P1_RX_BUF_DP<9>")
	)
	(segment
		(start 333.495142 -434.74894)
		(end 333.097886 -434.74894)
		(width 0.14224)
		(layer "In13.Cu")
		(net "P5E_CPU0_P1_RX_BUF_DP<9>")
	)
	(segment
		(start 333.097886 -434.74894)
		(end 332.970886 -434.62194)
		(width 0.14224)
		(layer "In13.Cu")
		(net "P5E_CPU0_P1_RX_BUF_DP<9>")
	)
	(segment
		(start 347.017086 -401.399756)
		(end 347.144086 -401.526756)
		(width 0.14224)
		(layer "In13.Cu")
		(net "P5E_CPU0_P1_RX_BUF_DP<9>")
	)
	(segment
		(start 335.136236 -417.178998)
		(end 334.999076 -417.041838)
		(width 0.14224)
		(layer "In13.Cu")
		(net "P5E_CPU0_P1_RX_BUF_DP<9>")
	)
	(segment
		(start 334.999076 -416.615118)
		(end 335.136236 -416.477958)
		(width 0.14224)
		(layer "In13.Cu")
		(net "P5E_CPU0_P1_RX_BUF_DP<9>")
	)
	(segment
		(start 339.839046 -410.341064)
		(end 340.782656 -409.949904)
		(width 0.14224)
		(layer "In13.Cu")
		(net "P5E_CPU0_P1_RX_BUF_DP<9>")
	)
	(segment
		(start 342.0364 -409.210764)
		(end 342.058752 -409.06065)
		(width 0.14224)
		(layer "In13.Cu")
		(net "P5E_CPU0_P1_RX_BUF_DP<9>")
	)
	(segment
		(start 338.29879 -411.127702)
		(end 338.693252 -410.96438)
		(width 0.14224)
		(layer "In13.Cu")
		(net "P5E_CPU0_P1_RX_BUF_DP<9>")
	)
	(segment
		(start 335.590388 -414.267142)
		(end 335.865978 -414.153096)
		(width 0.14224)
		(layer "In13.Cu")
		(net "P5E_CPU0_P1_RX_BUF_DP<9>")
	)
	(segment
		(start 338.11972 -411.05328)
		(end 338.29879 -411.127702)
		(width 0.14224)
		(layer "In13.Cu")
		(net "P5E_CPU0_P1_RX_BUF_DP<9>")
	)
	(segment
		(start 335.136236 -417.605718)
		(end 335.136236 -417.178998)
		(width 0.14224)
		(layer "In13.Cu")
		(net "P5E_CPU0_P1_RX_BUF_DP<9>")
	)
	(segment
		(start 333.467456 -422.00449)
		(end 333.467456 -420.22776)
		(width 0.14224)
		(layer "In13.Cu")
		(net "P5E_CPU0_P1_RX_BUF_DP<9>")
	)
	(segment
		(start 338.76742 -410.784802)
		(end 339.191346 -410.609288)
		(width 0.14224)
		(layer "In13.Cu")
		(net "P5E_CPU0_P1_RX_BUF_DP<9>")
	)
	(segment
		(start 342.401398 -408.80665)
		(end 342.713564 -408.494738)
		(width 0.14224)
		(layer "In13.Cu")
		(net "P5E_CPU0_P1_RX_BUF_DP<9>")
	)
	(segment
		(start 333.649828 -434.594254)
		(end 333.495142 -434.74894)
		(width 0.14224)
		(layer "In13.Cu")
		(net "P5E_CPU0_P1_RX_BUF_DP<9>")
	)
	(segment
		(start 334.999076 -419.079172)
		(end 334.999076 -417.742878)
		(width 0.14224)
		(layer "In13.Cu")
		(net "P5E_CPU0_P1_RX_BUF_DP<9>")
	)
	(segment
		(start 339.191346 -410.609288)
		(end 339.370416 -410.683456)
		(width 0.14224)
		(layer "In13.Cu")
		(net "P5E_CPU0_P1_RX_BUF_DP<9>")
	)
	(segment
		(start 336.686906 -412.138876)
		(end 337.319112 -411.5054)
		(width 0.14224)
		(layer "In13.Cu")
		(net "P5E_CPU0_P1_RX_BUF_DP<9>")
	)
	(segment
		(start 347.144086 -401.526756)
		(end 347.144086 -401.674838)
		(width 0.14224)
		(layer "In13.Cu")
		(net "P5E_CPU0_P1_RX_BUF_DP<9>")
	)
	(segment
		(start 346.685108 -403.495002)
		(end 346.822268 -403.357842)
		(width 0.14224)
		(layer "In13.Cu")
		(net "P5E_CPU0_P1_RX_BUF_DP<9>")
	)
	(segment
		(start 345.870784 -405.182832)
		(end 345.856814 -405.039576)
		(width 0.14224)
		(layer "In13.Cu")
		(net "P5E_CPU0_P1_RX_BUF_DP<9>")
	)
	(segment
		(start 342.058752 -409.06065)
		(end 342.401398 -408.80665)
		(width 0.14224)
		(layer "In13.Cu")
		(net "P5E_CPU0_P1_RX_BUF_DP<9>")
	)
	(segment
		(start 336.530696 -413.306514)
		(end 336.530696 -412.515812)
		(width 0.14224)
		(layer "In13.Cu")
		(net "P5E_CPU0_P1_RX_BUF_DP<9>")
	)
	(segment
		(start 342.713564 -408.494738)
		(end 342.907366 -408.494738)
		(width 0.14224)
		(layer "In13.Cu")
		(net "P5E_CPU0_P1_RX_BUF_DP<9>")
	)
	(arc
		(start 335.204054 -414.52546)
		(mid 335.384524 -414.377314)
		(end 335.590388 -414.267142)
		(width 0.14224)
		(layer "In13.Cu")
		(net "P5E_CPU0_P1_RX_BUF_DP<9>")
	)
	(arc
		(start 332.970886 -424.608752)
		(mid 332.974064 -424.544176)
		(end 332.983586 -424.480228)
		(width 0.14224)
		(layer "In13.Cu")
		(net "P5E_CPU0_P1_RX_BUF_DP<9>")
	)
	(arc
		(start 334.507586 -419.70198)
		(mid 334.614984 -419.643911)
		(end 334.707992 -419.56482)
		(width 0.14224)
		(layer "In13.Cu")
		(net "P5E_CPU0_P1_RX_BUF_DP<9>")
	)
	(arc
		(start 337.319112 -411.5054)
		(mid 337.53998 -411.323839)
		(end 337.79206 -411.188916)
		(width 0.14224)
		(layer "In13.Cu")
		(net "P5E_CPU0_P1_RX_BUF_DP<9>")
	)
	(arc
		(start 334.875378 -419.388798)
		(mid 334.967054 -419.245907)
		(end 334.999076 -419.079172)
		(width 0.14224)
		(layer "In13.Cu")
		(net "P5E_CPU0_P1_RX_BUF_DP<9>")
	)
	(arc
		(start 333.459582 -422.0845)
		(mid 333.465482 -422.044688)
		(end 333.467456 -422.00449)
		(width 0.14224)
		(layer "In13.Cu")
		(net "P5E_CPU0_P1_RX_BUF_DP<9>")
	)
	(arc
		(start 334.999076 -415.020252)
		(mid 335.052305 -414.752451)
		(end 335.204054 -414.52546)
		(width 0.14224)
		(layer "In13.Cu")
		(net "P5E_CPU0_P1_RX_BUF_DP<9>")
	)
	(arc
		(start 346.50934 -404.244556)
		(mid 346.639825 -404.014183)
		(end 346.685108 -403.75332)
		(width 0.14224)
		(layer "In13.Cu")
		(net "P5E_CPU0_P1_RX_BUF_DP<9>")
	)
	(arc
		(start 336.530696 -412.515812)
		(mid 336.571347 -412.311825)
		(end 336.686906 -412.138876)
		(width 0.14224)
		(layer "In13.Cu")
		(net "P5E_CPU0_P1_RX_BUF_DP<9>")
	)
	(arc
		(start 333.467456 -420.22776)
		(mid 333.49146 -420.149095)
		(end 333.555086 -420.09695)
		(width 0.14224)
		(layer "In13.Cu")
		(net "P5E_CPU0_P1_RX_BUF_DP<9>")
	)
	(arc
		(start 336.328258 -413.795464)
		(mid 336.478098 -413.571118)
		(end 336.530696 -413.306514)
		(width 0.14224)
		(layer "In13.Cu")
		(net "P5E_CPU0_P1_RX_BUF_DP<9>")
	)
	(segment
		(start 345.330018 -399.870676)
		(end 345.241372 -399.959322)
		(width 0.1016)
		(layer "F.Cu")
		(net "P5E_CPU0_P1_RX_BUF_DP<8>")
	)
	(segment
		(start 345.49461 -401.359116)
		(end 345.805252 -401.359116)
		(width 0.1016)
		(layer "F.Cu")
		(net "P5E_CPU0_P1_RX_BUF_DP<8>")
	)
	(segment
		(start 345.94419 -401.498054)
		(end 345.94419 -401.674838)
		(width 0.1016)
		(layer "F.Cu")
		(net "P5E_CPU0_P1_RX_BUF_DP<8>")
	)
	(segment
		(start 345.245436 -399.663158)
		(end 345.330018 -399.74774)
		(width 0.1016)
		(layer "F.Cu")
		(net "P5E_CPU0_P1_RX_BUF_DP<8>")
	)
	(segment
		(start 345.330018 -399.74774)
		(end 345.330018 -399.870676)
		(width 0.1016)
		(layer "F.Cu")
		(net "P5E_CPU0_P1_RX_BUF_DP<8>")
	)
	(segment
		(start 345.241372 -399.959322)
		(end 345.241372 -401.105878)
		(width 0.1016)
		(layer "F.Cu")
		(net "P5E_CPU0_P1_RX_BUF_DP<8>")
	)
	(segment
		(start 345.805252 -401.359116)
		(end 345.94419 -401.498054)
		(width 0.1016)
		(layer "F.Cu")
		(net "P5E_CPU0_P1_RX_BUF_DP<8>")
	)
	(segment
		(start 345.241372 -401.105878)
		(end 345.49461 -401.359116)
		(width 0.1016)
		(layer "F.Cu")
		(net "P5E_CPU0_P1_RX_BUF_DP<8>")
	)
	(segment
		(start 337.190334 -410.444696)
		(end 337.263232 -410.264864)
		(width 0.14224)
		(layer "In13.Cu")
		(net "P5E_CPU0_P1_RX_BUF_DP<8>")
	)
	(segment
		(start 333.671926 -411.96895)
		(end 333.898748 -411.758638)
		(width 0.14224)
		(layer "In13.Cu")
		(net "P5E_CPU0_P1_RX_BUF_DP<8>")
	)
	(segment
		(start 336.797142 -410.611066)
		(end 337.190334 -410.444696)
		(width 0.14224)
		(layer "In13.Cu")
		(net "P5E_CPU0_P1_RX_BUF_DP<8>")
	)
	(segment
		(start 330.404216 -422.463722)
		(end 330.404216 -422.037002)
		(width 0.14224)
		(layer "In13.Cu")
		(net "P5E_CPU0_P1_RX_BUF_DP<8>")
	)
	(segment
		(start 345.485212 -403.407626)
		(end 345.622372 -403.270466)
		(width 0.14224)
		(layer "In13.Cu")
		(net "P5E_CPU0_P1_RX_BUF_DP<8>")
	)
	(segment
		(start 345.272868 -404.230078)
		(end 345.239594 -404.03907)
		(width 0.14224)
		(layer "In13.Cu")
		(net "P5E_CPU0_P1_RX_BUF_DP<8>")
	)
	(segment
		(start 345.026742 -404.579328)
		(end 345.272868 -404.230078)
		(width 0.14224)
		(layer "In13.Cu")
		(net "P5E_CPU0_P1_RX_BUF_DP<8>")
	)
	(segment
		(start 343.449148 -406.43937)
		(end 343.784936 -406.068784)
		(width 0.14224)
		(layer "In13.Cu")
		(net "P5E_CPU0_P1_RX_BUF_DP<8>")
	)
	(segment
		(start 330.541376 -424.155362)
		(end 330.541376 -423.728642)
		(width 0.14224)
		(layer "In13.Cu")
		(net "P5E_CPU0_P1_RX_BUF_DP<8>")
	)
	(segment
		(start 340.60765 -408.937206)
		(end 340.849712 -408.763724)
		(width 0.14224)
		(layer "In13.Cu")
		(net "P5E_CPU0_P1_RX_BUF_DP<8>")
	)
	(segment
		(start 330.404216 -422.037002)
		(end 330.541376 -421.899842)
		(width 0.14224)
		(layer "In13.Cu")
		(net "P5E_CPU0_P1_RX_BUF_DP<8>")
	)
	(segment
		(start 343.307162 -406.446228)
		(end 343.449148 -406.43937)
		(width 0.14224)
		(layer "In13.Cu")
		(net "P5E_CPU0_P1_RX_BUF_DP<8>")
	)
	(segment
		(start 330.404216 -423.591482)
		(end 330.404216 -423.164762)
		(width 0.14224)
		(layer "In13.Cu")
		(net "P5E_CPU0_P1_RX_BUF_DP<8>")
	)
	(segment
		(start 333.118206 -413.942276)
		(end 333.265018 -413.795464)
		(width 0.14224)
		(layer "In13.Cu")
		(net "P5E_CPU0_P1_RX_BUF_DP<8>")
	)
	(segment
		(start 330.404216 -421.335962)
		(end 330.404216 -420.22776)
		(width 0.14224)
		(layer "In13.Cu")
		(net "P5E_CPU0_P1_RX_BUF_DP<8>")
	)
	(segment
		(start 331.935836 -416.122358)
		(end 331.935836 -415.020252)
		(width 0.14224)
		(layer "In13.Cu")
		(net "P5E_CPU0_P1_RX_BUF_DP<8>")
	)
	(segment
		(start 335.113122 -411.324298)
		(end 335.18602 -411.144212)
		(width 0.14224)
		(layer "In13.Cu")
		(net "P5E_CPU0_P1_RX_BUF_DP<8>")
	)
	(segment
		(start 336.151728 -410.88437)
		(end 336.224626 -410.704538)
		(width 0.14224)
		(layer "In13.Cu")
		(net "P5E_CPU0_P1_RX_BUF_DP<8>")
	)
	(segment
		(start 330.404216 -433.043076)
		(end 330.404216 -424.292522)
		(width 0.14224)
		(layer "In13.Cu")
		(net "P5E_CPU0_P1_RX_BUF_DP<8>")
	)
	(segment
		(start 338.922614 -409.657804)
		(end 340.136988 -409.20162)
		(width 0.14224)
		(layer "In13.Cu")
		(net "P5E_CPU0_P1_RX_BUF_DP<8>")
	)
	(segment
		(start 335.578958 -410.978096)
		(end 335.758536 -411.05074)
		(width 0.14224)
		(layer "In13.Cu")
		(net "P5E_CPU0_P1_RX_BUF_DP<8>")
	)
	(segment
		(start 345.485212 -401.541996)
		(end 345.627452 -401.399756)
		(width 0.14224)
		(layer "In13.Cu")
		(net "P5E_CPU0_P1_RX_BUF_DP<8>")
	)
	(segment
		(start 331.935836 -416.823398)
		(end 332.072996 -416.686238)
		(width 0.14224)
		(layer "In13.Cu")
		(net "P5E_CPU0_P1_RX_BUF_DP<8>")
	)
	(segment
		(start 345.81719 -401.399756)
		(end 345.94419 -401.526756)
		(width 0.14224)
		(layer "In13.Cu")
		(net "P5E_CPU0_P1_RX_BUF_DP<8>")
	)
	(segment
		(start 330.541376 -421.473122)
		(end 330.404216 -421.335962)
		(width 0.14224)
		(layer "In13.Cu")
		(net "P5E_CPU0_P1_RX_BUF_DP<8>")
	)
	(segment
		(start 342.297766 -407.560526)
		(end 343.307162 -406.446228)
		(width 0.14224)
		(layer "In13.Cu")
		(net "P5E_CPU0_P1_RX_BUF_DP<8>")
	)
	(segment
		(start 332.072996 -417.813998)
		(end 332.072996 -417.387278)
		(width 0.14224)
		(layer "In13.Cu")
		(net "P5E_CPU0_P1_RX_BUF_DP<8>")
	)
	(segment
		(start 334.71993 -411.490668)
		(end 335.113122 -411.324298)
		(width 0.14224)
		(layer "In13.Cu")
		(net "P5E_CPU0_P1_RX_BUF_DP<8>")
	)
	(segment
		(start 345.94419 -401.526756)
		(end 345.94419 -401.674838)
		(width 0.14224)
		(layer "In13.Cu")
		(net "P5E_CPU0_P1_RX_BUF_DP<8>")
	)
	(segment
		(start 345.622372 -402.843746)
		(end 345.485212 -402.706586)
		(width 0.14224)
		(layer "In13.Cu")
		(net "P5E_CPU0_P1_RX_BUF_DP<8>")
	)
	(segment
		(start 335.758536 -411.05074)
		(end 336.151728 -410.88437)
		(width 0.14224)
		(layer "In13.Cu")
		(net "P5E_CPU0_P1_RX_BUF_DP<8>")
	)
	(segment
		(start 332.072996 -416.259518)
		(end 331.935836 -416.122358)
		(width 0.14224)
		(layer "In13.Cu")
		(net "P5E_CPU0_P1_RX_BUF_DP<8>")
	)
	(segment
		(start 331.644752 -419.56482)
		(end 331.812138 -419.388798)
		(width 0.14224)
		(layer "In13.Cu")
		(net "P5E_CPU0_P1_RX_BUF_DP<8>")
	)
	(segment
		(start 344.835734 -404.612602)
		(end 345.026742 -404.579328)
		(width 0.14224)
		(layer "In13.Cu")
		(net "P5E_CPU0_P1_RX_BUF_DP<8>")
	)
	(segment
		(start 331.935836 -419.079172)
		(end 331.935836 -417.951158)
		(width 0.14224)
		(layer "In13.Cu")
		(net "P5E_CPU0_P1_RX_BUF_DP<8>")
	)
	(segment
		(start 336.224626 -410.704538)
		(end 336.617564 -410.538422)
		(width 0.14224)
		(layer "In13.Cu")
		(net "P5E_CPU0_P1_RX_BUF_DP<8>")
	)
	(segment
		(start 334.147414 -411.58414)
		(end 334.540352 -411.41777)
		(width 0.14224)
		(layer "In13.Cu")
		(net "P5E_CPU0_P1_RX_BUF_DP<8>")
	)
	(segment
		(start 331.935836 -417.250118)
		(end 331.935836 -416.823398)
		(width 0.14224)
		(layer "In13.Cu")
		(net "P5E_CPU0_P1_RX_BUF_DP<8>")
	)
	(segment
		(start 345.627452 -401.399756)
		(end 345.81719 -401.399756)
		(width 0.14224)
		(layer "In13.Cu")
		(net "P5E_CPU0_P1_RX_BUF_DP<8>")
	)
	(segment
		(start 330.404216 -423.164762)
		(end 330.541376 -423.027602)
		(width 0.14224)
		(layer "In13.Cu")
		(net "P5E_CPU0_P1_RX_BUF_DP<8>")
	)
	(segment
		(start 345.622372 -403.270466)
		(end 345.622372 -402.843746)
		(width 0.14224)
		(layer "In13.Cu")
		(net "P5E_CPU0_P1_RX_BUF_DP<8>")
	)
	(segment
		(start 332.072996 -416.686238)
		(end 332.072996 -416.259518)
		(width 0.14224)
		(layer "In13.Cu")
		(net "P5E_CPU0_P1_RX_BUF_DP<8>")
	)
	(segment
		(start 331.935836 -417.951158)
		(end 332.072996 -417.813998)
		(width 0.14224)
		(layer "In13.Cu")
		(net "P5E_CPU0_P1_RX_BUF_DP<8>")
	)
	(segment
		(start 330.404216 -424.292522)
		(end 330.541376 -424.155362)
		(width 0.14224)
		(layer "In13.Cu")
		(net "P5E_CPU0_P1_RX_BUF_DP<8>")
	)
	(segment
		(start 331.649832 -433.621942)
		(end 331.522832 -433.748942)
		(width 0.14224)
		(layer "In13.Cu")
		(net "P5E_CPU0_P1_RX_BUF_DP<8>")
	)
	(segment
		(start 337.263232 -410.264864)
		(end 337.998816 -409.95346)
		(width 0.14224)
		(layer "In13.Cu")
		(net "P5E_CPU0_P1_RX_BUF_DP<8>")
	)
	(segment
		(start 343.784936 -406.068784)
		(end 343.778078 -405.926544)
		(width 0.14224)
		(layer "In13.Cu")
		(net "P5E_CPU0_P1_RX_BUF_DP<8>")
	)
	(segment
		(start 330.541376 -422.600882)
		(end 330.404216 -422.463722)
		(width 0.14224)
		(layer "In13.Cu")
		(net "P5E_CPU0_P1_RX_BUF_DP<8>")
	)
	(segment
		(start 335.18602 -411.144212)
		(end 335.578958 -410.978096)
		(width 0.14224)
		(layer "In13.Cu")
		(net "P5E_CPU0_P1_RX_BUF_DP<8>")
	)
	(segment
		(start 332.527148 -414.267142)
		(end 332.802738 -414.153096)
		(width 0.14224)
		(layer "In13.Cu")
		(net "P5E_CPU0_P1_RX_BUF_DP<8>")
	)
	(segment
		(start 330.541376 -423.027602)
		(end 330.541376 -422.600882)
		(width 0.14224)
		(layer "In13.Cu")
		(net "P5E_CPU0_P1_RX_BUF_DP<8>")
	)
	(segment
		(start 345.485212 -403.560534)
		(end 345.485212 -403.407626)
		(width 0.14224)
		(layer "In13.Cu")
		(net "P5E_CPU0_P1_RX_BUF_DP<8>")
	)
	(segment
		(start 333.467456 -413.306514)
		(end 333.467456 -412.43758)
		(width 0.14224)
		(layer "In13.Cu")
		(net "P5E_CPU0_P1_RX_BUF_DP<8>")
	)
	(segment
		(start 330.541376 -421.899842)
		(end 330.541376 -421.473122)
		(width 0.14224)
		(layer "In13.Cu")
		(net "P5E_CPU0_P1_RX_BUF_DP<8>")
	)
	(segment
		(start 343.778078 -405.926544)
		(end 344.372946 -405.2697)
		(width 0.14224)
		(layer "In13.Cu")
		(net "P5E_CPU0_P1_RX_BUF_DP<8>")
	)
	(segment
		(start 332.802738 -414.153096)
		(end 333.118206 -413.942276)
		(width 0.14224)
		(layer "In13.Cu")
		(net "P5E_CPU0_P1_RX_BUF_DP<8>")
	)
	(segment
		(start 340.849712 -408.763724)
		(end 342.297766 -407.560526)
		(width 0.14224)
		(layer "In13.Cu")
		(net "P5E_CPU0_P1_RX_BUF_DP<8>")
	)
	(segment
		(start 336.617564 -410.538422)
		(end 336.797142 -410.611066)
		(width 0.14224)
		(layer "In13.Cu")
		(net "P5E_CPU0_P1_RX_BUF_DP<8>")
	)
	(segment
		(start 334.540352 -411.41777)
		(end 334.71993 -411.490668)
		(width 0.14224)
		(layer "In13.Cu")
		(net "P5E_CPU0_P1_RX_BUF_DP<8>")
	)
	(segment
		(start 331.649832 -433.289964)
		(end 331.649832 -433.621942)
		(width 0.14224)
		(layer "In13.Cu")
		(net "P5E_CPU0_P1_RX_BUF_DP<8>")
	)
	(segment
		(start 338.117688 -409.91028)
		(end 338.787994 -409.703778)
		(width 0.14224)
		(layer "In13.Cu")
		(net "P5E_CPU0_P1_RX_BUF_DP<8>")
	)
	(segment
		(start 330.541376 -423.728642)
		(end 330.404216 -423.591482)
		(width 0.14224)
		(layer "In13.Cu")
		(net "P5E_CPU0_P1_RX_BUF_DP<8>")
	)
	(segment
		(start 332.072996 -417.387278)
		(end 331.935836 -417.250118)
		(width 0.14224)
		(layer "In13.Cu")
		(net "P5E_CPU0_P1_RX_BUF_DP<8>")
	)
	(segment
		(start 345.485212 -402.706586)
		(end 345.485212 -401.541996)
		(width 0.14224)
		(layer "In13.Cu")
		(net "P5E_CPU0_P1_RX_BUF_DP<8>")
	)
	(segment
		(start 330.491846 -420.09695)
		(end 331.444346 -419.70198)
		(width 0.14224)
		(layer "In13.Cu")
		(net "P5E_CPU0_P1_RX_BUF_DP<8>")
	)
	(segment
		(start 331.522832 -433.748942)
		(end 331.110082 -433.748942)
		(width 0.14224)
		(layer "In13.Cu")
		(net "P5E_CPU0_P1_RX_BUF_DP<8>")
	)
	(segment
		(start 344.372946 -405.2697)
		(end 344.835734 -404.612602)
		(width 0.14224)
		(layer "In13.Cu")
		(net "P5E_CPU0_P1_RX_BUF_DP<8>")
	)
	(segment
		(start 331.110082 -433.748942)
		(end 330.404216 -433.043076)
		(width 0.14224)
		(layer "In13.Cu")
		(net "P5E_CPU0_P1_RX_BUF_DP<8>")
	)
	(segment
		(start 345.239594 -404.03907)
		(end 345.41079 -403.795992)
		(width 0.14224)
		(layer "In13.Cu")
		(net "P5E_CPU0_P1_RX_BUF_DP<8>")
	)
	(arc
		(start 338.787994 -409.703778)
		(mid 338.855653 -409.681811)
		(end 338.922614 -409.657804)
		(width 0.14224)
		(layer "In13.Cu")
		(net "P5E_CPU0_P1_RX_BUF_DP<8>")
	)
	(arc
		(start 340.283546 -409.136342)
		(mid 340.449168 -409.042583)
		(end 340.60765 -408.937206)
		(width 0.14224)
		(layer "In13.Cu")
		(net "P5E_CPU0_P1_RX_BUF_DP<8>")
	)
	(arc
		(start 334.03667 -411.646116)
		(mid 334.090336 -411.612079)
		(end 334.147414 -411.58414)
		(width 0.14224)
		(layer "In13.Cu")
		(net "P5E_CPU0_P1_RX_BUF_DP<8>")
	)
	(arc
		(start 333.898748 -411.758638)
		(mid 333.965896 -411.700154)
		(end 334.03667 -411.646116)
		(width 0.14224)
		(layer "In13.Cu")
		(net "P5E_CPU0_P1_RX_BUF_DP<8>")
	)
	(arc
		(start 331.812138 -419.388798)
		(mid 331.903814 -419.245907)
		(end 331.935836 -419.079172)
		(width 0.14224)
		(layer "In13.Cu")
		(net "P5E_CPU0_P1_RX_BUF_DP<8>")
	)
	(arc
		(start 331.935836 -415.020252)
		(mid 331.989065 -414.752451)
		(end 332.140814 -414.52546)
		(width 0.14224)
		(layer "In13.Cu")
		(net "P5E_CPU0_P1_RX_BUF_DP<8>")
	)
	(arc
		(start 333.265018 -413.795464)
		(mid 333.414858 -413.571118)
		(end 333.467456 -413.306514)
		(width 0.14224)
		(layer "In13.Cu")
		(net "P5E_CPU0_P1_RX_BUF_DP<8>")
	)
	(arc
		(start 330.404216 -420.22776)
		(mid 330.42822 -420.149095)
		(end 330.491846 -420.09695)
		(width 0.14224)
		(layer "In13.Cu")
		(net "P5E_CPU0_P1_RX_BUF_DP<8>")
	)
	(arc
		(start 345.41079 -403.795992)
		(mid 345.466193 -403.684014)
		(end 345.485212 -403.560534)
		(width 0.14224)
		(layer "In13.Cu")
		(net "P5E_CPU0_P1_RX_BUF_DP<8>")
	)
	(arc
		(start 340.136988 -409.20162)
		(mid 340.21124 -409.171165)
		(end 340.283546 -409.136342)
		(width 0.14224)
		(layer "In13.Cu")
		(net "P5E_CPU0_P1_RX_BUF_DP<8>")
	)
	(arc
		(start 337.998816 -409.95346)
		(mid 338.057701 -409.930353)
		(end 338.117688 -409.91028)
		(width 0.14224)
		(layer "In13.Cu")
		(net "P5E_CPU0_P1_RX_BUF_DP<8>")
	)
	(arc
		(start 331.444346 -419.70198)
		(mid 331.551744 -419.643911)
		(end 331.644752 -419.56482)
		(width 0.14224)
		(layer "In13.Cu")
		(net "P5E_CPU0_P1_RX_BUF_DP<8>")
	)
	(arc
		(start 333.467456 -412.43758)
		(mid 333.520796 -412.18193)
		(end 333.671926 -411.96895)
		(width 0.14224)
		(layer "In13.Cu")
		(net "P5E_CPU0_P1_RX_BUF_DP<8>")
	)
	(arc
		(start 332.140814 -414.52546)
		(mid 332.321284 -414.377314)
		(end 332.527148 -414.267142)
		(width 0.14224)
		(layer "In13.Cu")
		(net "P5E_CPU0_P1_RX_BUF_DP<8>")
	)
	(segment
		(start 344.041476 -399.959322)
		(end 344.041476 -401.105878)
		(width 0.1016)
		(layer "F.Cu")
		(net "P5E_CPU0_P1_RX_BUF_DP<7>")
	)
	(segment
		(start 344.130122 -399.870676)
		(end 344.041476 -399.959322)
		(width 0.1016)
		(layer "F.Cu")
		(net "P5E_CPU0_P1_RX_BUF_DP<7>")
	)
	(segment
		(start 344.04554 -399.663158)
		(end 344.130122 -399.74774)
		(width 0.1016)
		(layer "F.Cu")
		(net "P5E_CPU0_P1_RX_BUF_DP<7>")
	)
	(segment
		(start 344.130122 -399.74774)
		(end 344.130122 -399.870676)
		(width 0.1016)
		(layer "F.Cu")
		(net "P5E_CPU0_P1_RX_BUF_DP<7>")
	)
	(segment
		(start 344.041476 -401.105878)
		(end 344.294714 -401.359116)
		(width 0.1016)
		(layer "F.Cu")
		(net "P5E_CPU0_P1_RX_BUF_DP<7>")
	)
	(segment
		(start 344.294714 -401.359116)
		(end 344.605356 -401.359116)
		(width 0.1016)
		(layer "F.Cu")
		(net "P5E_CPU0_P1_RX_BUF_DP<7>")
	)
	(segment
		(start 344.74404 -401.4978)
		(end 344.74404 -401.674838)
		(width 0.1016)
		(layer "F.Cu")
		(net "P5E_CPU0_P1_RX_BUF_DP<7>")
	)
	(segment
		(start 344.605356 -401.359116)
		(end 344.74404 -401.4978)
		(width 0.1016)
		(layer "F.Cu")
		(net "P5E_CPU0_P1_RX_BUF_DP<7>")
	)
	(segment
		(start 343.189052 -405.184102)
		(end 343.793064 -404.452582)
		(width 0.14224)
		(layer "In13.Cu")
		(net "P5E_CPU0_P1_RX_BUF_DP<7>")
	)
	(segment
		(start 339.499194 -408.434286)
		(end 340.077806 -408.11069)
		(width 0.14224)
		(layer "In13.Cu")
		(net "P5E_CPU0_P1_RX_BUF_DP<7>")
	)
	(segment
		(start 327.941432 -423.793412)
		(end 327.858374 -423.374566)
		(width 0.14224)
		(layer "In13.Cu")
		(net "P5E_CPU0_P1_RX_BUF_DP<7>")
	)
	(segment
		(start 344.39098 -403.023578)
		(end 344.39098 -402.596858)
		(width 0.14224)
		(layer "In13.Cu")
		(net "P5E_CPU0_P1_RX_BUF_DP<7>")
	)
	(segment
		(start 334.906112 -409.904692)
		(end 335.086452 -409.975558)
		(width 0.14224)
		(layer "In13.Cu")
		(net "P5E_CPU0_P1_RX_BUF_DP<7>")
	)
	(segment
		(start 334.444086 -410.255974)
		(end 334.514952 -410.075126)
		(width 0.14224)
		(layer "In13.Cu")
		(net "P5E_CPU0_P1_RX_BUF_DP<7>")
	)
	(segment
		(start 328.872596 -417.2204)
		(end 328.872596 -416.79368)
		(width 0.14224)
		(layer "In13.Cu")
		(net "P5E_CPU0_P1_RX_BUF_DP<7>")
	)
	(segment
		(start 344.61704 -401.399756)
		(end 344.74404 -401.526756)
		(width 0.14224)
		(layer "In13.Cu")
		(net "P5E_CPU0_P1_RX_BUF_DP<7>")
	)
	(segment
		(start 344.39098 -402.596858)
		(end 344.25382 -402.459698)
		(width 0.14224)
		(layer "In13.Cu")
		(net "P5E_CPU0_P1_RX_BUF_DP<7>")
	)
	(segment
		(start 340.077806 -408.11069)
		(end 341.324438 -407.112724)
		(width 0.14224)
		(layer "In13.Cu")
		(net "P5E_CPU0_P1_RX_BUF_DP<7>")
	)
	(segment
		(start 328.649584 -434.62194)
		(end 328.522584 -434.74894)
		(width 0.14224)
		(layer "In13.Cu")
		(net "P5E_CPU0_P1_RX_BUF_DP<7>")
	)
	(segment
		(start 341.324438 -407.112724)
		(end 342.362536 -406.087326)
		(width 0.14224)
		(layer "In13.Cu")
		(net "P5E_CPU0_P1_RX_BUF_DP<7>")
	)
	(segment
		(start 328.872596 -417.92144)
		(end 329.009756 -417.78428)
		(width 0.14224)
		(layer "In13.Cu")
		(net "P5E_CPU0_P1_RX_BUF_DP<7>")
	)
	(segment
		(start 327.605644 -422.80459)
		(end 327.71334 -422.6433)
		(width 0.14224)
		(layer "In13.Cu")
		(net "P5E_CPU0_P1_RX_BUF_DP<7>")
	)
	(segment
		(start 329.009756 -417.78428)
		(end 329.009756 -417.35756)
		(width 0.14224)
		(layer "In13.Cu")
		(net "P5E_CPU0_P1_RX_BUF_DP<7>")
	)
	(segment
		(start 329.009756 -417.35756)
		(end 328.872596 -417.2204)
		(width 0.14224)
		(layer "In13.Cu")
		(net "P5E_CPU0_P1_RX_BUF_DP<7>")
	)
	(segment
		(start 331.413612 -411.427676)
		(end 331.804518 -411.257242)
		(width 0.14224)
		(layer "In13.Cu")
		(net "P5E_CPU0_P1_RX_BUF_DP<7>")
	)
	(segment
		(start 329.009756 -416.2298)
		(end 328.872596 -416.09264)
		(width 0.14224)
		(layer "In13.Cu")
		(net "P5E_CPU0_P1_RX_BUF_DP<7>")
	)
	(segment
		(start 335.086452 -409.975558)
		(end 335.477866 -409.805124)
		(width 0.14224)
		(layer "In13.Cu")
		(net "P5E_CPU0_P1_RX_BUF_DP<7>")
	)
	(segment
		(start 344.25382 -403.587458)
		(end 344.25382 -403.160738)
		(width 0.14224)
		(layer "In13.Cu")
		(net "P5E_CPU0_P1_RX_BUF_DP<7>")
	)
	(segment
		(start 344.25382 -403.160738)
		(end 344.39098 -403.023578)
		(width 0.14224)
		(layer "In13.Cu")
		(net "P5E_CPU0_P1_RX_BUF_DP<7>")
	)
	(segment
		(start 328.957178 -414.76803)
		(end 329.20559 -414.430972)
		(width 0.14224)
		(layer "In13.Cu")
		(net "P5E_CPU0_P1_RX_BUF_DP<7>")
	)
	(segment
		(start 342.362536 -406.087326)
		(end 343.189052 -405.184102)
		(width 0.14224)
		(layer "In13.Cu")
		(net "P5E_CPU0_P1_RX_BUF_DP<7>")
	)
	(segment
		(start 327.858374 -423.374566)
		(end 327.697084 -423.266616)
		(width 0.14224)
		(layer "In13.Cu")
		(net "P5E_CPU0_P1_RX_BUF_DP<7>")
	)
	(segment
		(start 328.872596 -416.79368)
		(end 329.009756 -416.65652)
		(width 0.14224)
		(layer "In13.Cu")
		(net "P5E_CPU0_P1_RX_BUF_DP<7>")
	)
	(segment
		(start 327.71334 -422.6433)
		(end 327.630536 -422.224454)
		(width 0.14224)
		(layer "In13.Cu")
		(net "P5E_CPU0_P1_RX_BUF_DP<7>")
	)
	(segment
		(start 331.985112 -411.328108)
		(end 332.376526 -411.157674)
		(width 0.14224)
		(layer "In13.Cu")
		(net "P5E_CPU0_P1_RX_BUF_DP<7>")
	)
	(segment
		(start 329.009756 -416.65652)
		(end 329.009756 -416.2298)
		(width 0.14224)
		(layer "In13.Cu")
		(net "P5E_CPU0_P1_RX_BUF_DP<7>")
	)
	(segment
		(start 333.481172 -410.525976)
		(end 333.872078 -410.355542)
		(width 0.14224)
		(layer "In13.Cu")
		(net "P5E_CPU0_P1_RX_BUF_DP<7>")
	)
	(segment
		(start 327.833482 -423.954448)
		(end 327.941432 -423.793412)
		(width 0.14224)
		(layer "In13.Cu")
		(net "P5E_CPU0_P1_RX_BUF_DP<7>")
	)
	(segment
		(start 343.793064 -404.452582)
		(end 344.15603 -403.90953)
		(width 0.14224)
		(layer "In13.Cu")
		(net "P5E_CPU0_P1_RX_BUF_DP<7>")
	)
	(segment
		(start 336.269584 -409.370022)
		(end 336.43951 -409.463494)
		(width 0.14224)
		(layer "In13.Cu")
		(net "P5E_CPU0_P1_RX_BUF_DP<7>")
	)
	(segment
		(start 335.477866 -409.805124)
		(end 335.548986 -409.624276)
		(width 0.14224)
		(layer "In13.Cu")
		(net "P5E_CPU0_P1_RX_BUF_DP<7>")
	)
	(segment
		(start 327.630536 -422.224454)
		(end 327.468992 -422.116504)
		(width 0.14224)
		(layer "In13.Cu")
		(net "P5E_CPU0_P1_RX_BUF_DP<7>")
	)
	(segment
		(start 344.74404 -401.526756)
		(end 344.74404 -401.674838)
		(width 0.14224)
		(layer "In13.Cu")
		(net "P5E_CPU0_P1_RX_BUF_DP<7>")
	)
	(segment
		(start 335.548986 -409.624276)
		(end 335.859882 -409.48864)
		(width 0.14224)
		(layer "In13.Cu")
		(net "P5E_CPU0_P1_RX_BUF_DP<7>")
	)
	(segment
		(start 329.73899 -414.153858)
		(end 330.054966 -413.942276)
		(width 0.14224)
		(layer "In13.Cu")
		(net "P5E_CPU0_P1_RX_BUF_DP<7>")
	)
	(segment
		(start 334.052672 -410.426408)
		(end 334.444086 -410.255974)
		(width 0.14224)
		(layer "In13.Cu")
		(net "P5E_CPU0_P1_RX_BUF_DP<7>")
	)
	(segment
		(start 330.59751 -412.036006)
		(end 330.760832 -411.872684)
		(width 0.14224)
		(layer "In13.Cu")
		(net "P5E_CPU0_P1_RX_BUF_DP<7>")
	)
	(segment
		(start 328.522584 -434.74894)
		(end 328.100436 -434.74894)
		(width 0.14224)
		(layer "In13.Cu")
		(net "P5E_CPU0_P1_RX_BUF_DP<7>")
	)
	(segment
		(start 328.872596 -418.8968)
		(end 328.872596 -417.92144)
		(width 0.14224)
		(layer "In13.Cu")
		(net "P5E_CPU0_P1_RX_BUF_DP<7>")
	)
	(segment
		(start 333.018892 -410.877258)
		(end 333.410306 -410.706824)
		(width 0.14224)
		(layer "In13.Cu")
		(net "P5E_CPU0_P1_RX_BUF_DP<7>")
	)
	(segment
		(start 328.649584 -434.289962)
		(end 328.649584 -434.62194)
		(width 0.14224)
		(layer "In13.Cu")
		(net "P5E_CPU0_P1_RX_BUF_DP<7>")
	)
	(segment
		(start 333.872078 -410.355542)
		(end 334.052672 -410.426408)
		(width 0.14224)
		(layer "In13.Cu")
		(net "P5E_CPU0_P1_RX_BUF_DP<7>")
	)
	(segment
		(start 335.859882 -409.48864)
		(end 336.269584 -409.370022)
		(width 0.14224)
		(layer "In13.Cu")
		(net "P5E_CPU0_P1_RX_BUF_DP<7>")
	)
	(segment
		(start 328.100436 -434.74894)
		(end 327.970896 -434.6194)
		(width 0.14224)
		(layer "In13.Cu")
		(net "P5E_CPU0_P1_RX_BUF_DP<7>")
	)
	(segment
		(start 327.468992 -422.116504)
		(end 327.386188 -421.698166)
		(width 0.14224)
		(layer "In13.Cu")
		(net "P5E_CPU0_P1_RX_BUF_DP<7>")
	)
	(segment
		(start 330.404216 -413.306514)
		(end 330.404216 -412.502604)
		(width 0.14224)
		(layer "In13.Cu")
		(net "P5E_CPU0_P1_RX_BUF_DP<7>")
	)
	(segment
		(start 332.376526 -411.157674)
		(end 332.447392 -410.976826)
		(width 0.14224)
		(layer "In13.Cu")
		(net "P5E_CPU0_P1_RX_BUF_DP<7>")
	)
	(segment
		(start 330.054966 -413.942276)
		(end 330.201778 -413.795464)
		(width 0.14224)
		(layer "In13.Cu")
		(net "P5E_CPU0_P1_RX_BUF_DP<7>")
	)
	(segment
		(start 344.301064 -401.525994)
		(end 344.427302 -401.399756)
		(width 0.14224)
		(layer "In13.Cu")
		(net "P5E_CPU0_P1_RX_BUF_DP<7>")
	)
	(segment
		(start 344.25382 -402.459698)
		(end 344.25382 -401.64004)
		(width 0.14224)
		(layer "In13.Cu")
		(net "P5E_CPU0_P1_RX_BUF_DP<7>")
	)
	(segment
		(start 333.410306 -410.706824)
		(end 333.481172 -410.525976)
		(width 0.14224)
		(layer "In13.Cu")
		(net "P5E_CPU0_P1_RX_BUF_DP<7>")
	)
	(segment
		(start 327.970896 -434.6194)
		(end 327.970896 -424.749468)
		(width 0.14224)
		(layer "In13.Cu")
		(net "P5E_CPU0_P1_RX_BUF_DP<7>")
	)
	(segment
		(start 327.951338 -424.54957)
		(end 327.833482 -423.954448)
		(width 0.14224)
		(layer "In13.Cu")
		(net "P5E_CPU0_P1_RX_BUF_DP<7>")
	)
	(segment
		(start 328.872596 -416.09264)
		(end 328.872596 -415.025332)
		(width 0.14224)
		(layer "In13.Cu")
		(net "P5E_CPU0_P1_RX_BUF_DP<7>")
	)
	(segment
		(start 327.697084 -423.266616)
		(end 327.605644 -422.80459)
		(width 0.14224)
		(layer "In13.Cu")
		(net "P5E_CPU0_P1_RX_BUF_DP<7>")
	)
	(segment
		(start 344.427302 -401.399756)
		(end 344.61704 -401.399756)
		(width 0.14224)
		(layer "In13.Cu")
		(net "P5E_CPU0_P1_RX_BUF_DP<7>")
	)
	(segment
		(start 336.84972 -409.344876)
		(end 336.943192 -409.174696)
		(width 0.14224)
		(layer "In13.Cu")
		(net "P5E_CPU0_P1_RX_BUF_DP<7>")
	)
	(segment
		(start 332.838298 -410.806392)
		(end 333.018892 -410.877258)
		(width 0.14224)
		(layer "In13.Cu")
		(net "P5E_CPU0_P1_RX_BUF_DP<7>")
	)
	(segment
		(start 327.525634 -420.041324)
		(end 328.541634 -419.619938)
		(width 0.14224)
		(layer "In13.Cu")
		(net "P5E_CPU0_P1_RX_BUF_DP<7>")
	)
	(segment
		(start 332.447392 -410.976826)
		(end 332.838298 -410.806392)
		(width 0.14224)
		(layer "In13.Cu")
		(net "P5E_CPU0_P1_RX_BUF_DP<7>")
	)
	(segment
		(start 327.340976 -421.316912)
		(end 327.340976 -420.317676)
		(width 0.14224)
		(layer "In13.Cu")
		(net "P5E_CPU0_P1_RX_BUF_DP<7>")
	)
	(segment
		(start 336.43951 -409.463494)
		(end 336.84972 -409.344876)
		(width 0.14224)
		(layer "In13.Cu")
		(net "P5E_CPU0_P1_RX_BUF_DP<7>")
	)
	(segment
		(start 336.943192 -409.174696)
		(end 339.499194 -408.434286)
		(width 0.14224)
		(layer "In13.Cu")
		(net "P5E_CPU0_P1_RX_BUF_DP<7>")
	)
	(segment
		(start 329.355704 -414.313116)
		(end 329.73899 -414.153858)
		(width 0.14224)
		(layer "In13.Cu")
		(net "P5E_CPU0_P1_RX_BUF_DP<7>")
	)
	(segment
		(start 331.804518 -411.257242)
		(end 331.985112 -411.328108)
		(width 0.14224)
		(layer "In13.Cu")
		(net "P5E_CPU0_P1_RX_BUF_DP<7>")
	)
	(segment
		(start 334.514952 -410.075126)
		(end 334.906112 -409.904692)
		(width 0.14224)
		(layer "In13.Cu")
		(net "P5E_CPU0_P1_RX_BUF_DP<7>")
	)
	(arc
		(start 344.15603 -403.90953)
		(mid 344.228852 -403.755757)
		(end 344.25382 -403.587458)
		(width 0.14224)
		(layer "In13.Cu")
		(net "P5E_CPU0_P1_RX_BUF_DP<7>")
	)
	(arc
		(start 330.201778 -413.795464)
		(mid 330.351618 -413.571118)
		(end 330.404216 -413.306514)
		(width 0.14224)
		(layer "In13.Cu")
		(net "P5E_CPU0_P1_RX_BUF_DP<7>")
	)
	(arc
		(start 330.760832 -411.872684)
		(mid 331.06632 -411.619517)
		(end 331.413612 -411.427676)
		(width 0.14224)
		(layer "In13.Cu")
		(net "P5E_CPU0_P1_RX_BUF_DP<7>")
	)
	(arc
		(start 327.340976 -420.317676)
		(mid 327.39138 -420.151475)
		(end 327.525634 -420.041324)
		(width 0.14224)
		(layer "In13.Cu")
		(net "P5E_CPU0_P1_RX_BUF_DP<7>")
	)
	(arc
		(start 328.541634 -419.619938)
		(mid 328.785911 -419.294434)
		(end 328.872596 -418.8968)
		(width 0.14224)
		(layer "In13.Cu")
		(net "P5E_CPU0_P1_RX_BUF_DP<7>")
	)
	(arc
		(start 327.970896 -424.749468)
		(mid 327.966001 -424.649042)
		(end 327.951338 -424.54957)
		(width 0.14224)
		(layer "In13.Cu")
		(net "P5E_CPU0_P1_RX_BUF_DP<7>")
	)
	(arc
		(start 329.20559 -414.430972)
		(mid 329.272643 -414.361852)
		(end 329.355704 -414.313116)
		(width 0.14224)
		(layer "In13.Cu")
		(net "P5E_CPU0_P1_RX_BUF_DP<7>")
	)
	(arc
		(start 328.872596 -415.025332)
		(mid 328.894226 -414.889882)
		(end 328.957178 -414.76803)
		(width 0.14224)
		(layer "In13.Cu")
		(net "P5E_CPU0_P1_RX_BUF_DP<7>")
	)
	(arc
		(start 327.386188 -421.698166)
		(mid 327.364182 -421.573122)
		(end 327.347834 -421.447214)
		(width 0.14224)
		(layer "In13.Cu")
		(net "P5E_CPU0_P1_RX_BUF_DP<7>")
	)
	(arc
		(start 330.404216 -412.502604)
		(mid 330.454447 -412.250074)
		(end 330.59751 -412.036006)
		(width 0.14224)
		(layer "In13.Cu")
		(net "P5E_CPU0_P1_RX_BUF_DP<7>")
	)
	(arc
		(start 344.25382 -401.64004)
		(mid 344.266097 -401.578317)
		(end 344.301064 -401.525994)
		(width 0.14224)
		(layer "In13.Cu")
		(net "P5E_CPU0_P1_RX_BUF_DP<7>")
	)
	(arc
		(start 327.347834 -421.447214)
		(mid 327.342682 -421.382154)
		(end 327.340976 -421.316912)
		(width 0.14224)
		(layer "In13.Cu")
		(net "P5E_CPU0_P1_RX_BUF_DP<7>")
	)
	(segment
		(start 343.405206 -401.359116)
		(end 343.544144 -401.498054)
		(width 0.1016)
		(layer "F.Cu")
		(net "P5E_CPU0_P1_RX_BUF_DP<6>")
	)
	(segment
		(start 342.850216 -399.950432)
		(end 342.850216 -401.105878)
		(width 0.1016)
		(layer "F.Cu")
		(net "P5E_CPU0_P1_RX_BUF_DP<6>")
	)
	(segment
		(start 342.929972 -399.74774)
		(end 342.929972 -399.870676)
		(width 0.1016)
		(layer "F.Cu")
		(net "P5E_CPU0_P1_RX_BUF_DP<6>")
	)
	(segment
		(start 342.850216 -401.105878)
		(end 343.103454 -401.359116)
		(width 0.1016)
		(layer "F.Cu")
		(net "P5E_CPU0_P1_RX_BUF_DP<6>")
	)
	(segment
		(start 343.103454 -401.359116)
		(end 343.405206 -401.359116)
		(width 0.1016)
		(layer "F.Cu")
		(net "P5E_CPU0_P1_RX_BUF_DP<6>")
	)
	(segment
		(start 342.929972 -399.870676)
		(end 342.850216 -399.950432)
		(width 0.1016)
		(layer "F.Cu")
		(net "P5E_CPU0_P1_RX_BUF_DP<6>")
	)
	(segment
		(start 343.544144 -401.498054)
		(end 343.544144 -401.674838)
		(width 0.1016)
		(layer "F.Cu")
		(net "P5E_CPU0_P1_RX_BUF_DP<6>")
	)
	(segment
		(start 342.84539 -399.663158)
		(end 342.929972 -399.74774)
		(width 0.1016)
		(layer "F.Cu")
		(net "P5E_CPU0_P1_RX_BUF_DP<6>")
	)
	(segment
		(start 343.417144 -401.399756)
		(end 343.227406 -401.399756)
		(width 0.14224)
		(layer "In13.Cu")
		(net "P5E_CPU0_P1_RX_BUF_DP<6>")
	)
	(segment
		(start 326.991726 -413.942276)
		(end 326.676258 -414.153096)
		(width 0.14224)
		(layer "In13.Cu")
		(net "P5E_CPU0_P1_RX_BUF_DP<6>")
	)
	(segment
		(start 327.340976 -412.495492)
		(end 327.340976 -413.306514)
		(width 0.14224)
		(layer "In13.Cu")
		(net "P5E_CPU0_P1_RX_BUF_DP<6>")
	)
	(segment
		(start 343.222326 -403.384258)
		(end 343.085166 -403.521418)
		(width 0.14224)
		(layer "In13.Cu")
		(net "P5E_CPU0_P1_RX_BUF_DP<6>")
	)
	(segment
		(start 326.522588 -433.748942)
		(end 326.649588 -433.621942)
		(width 0.14224)
		(layer "In13.Cu")
		(net "P5E_CPU0_P1_RX_BUF_DP<6>")
	)
	(segment
		(start 343.544144 -401.526756)
		(end 343.417144 -401.399756)
		(width 0.14224)
		(layer "In13.Cu")
		(net "P5E_CPU0_P1_RX_BUF_DP<6>")
	)
	(segment
		(start 325.734934 -424.501564)
		(end 325.93153 -424.917362)
		(width 0.14224)
		(layer "In13.Cu")
		(net "P5E_CPU0_P1_RX_BUF_DP<6>")
	)
	(segment
		(start 325.252842 -423.481754)
		(end 325.435214 -423.867326)
		(width 0.14224)
		(layer "In13.Cu")
		(net "P5E_CPU0_P1_RX_BUF_DP<6>")
	)
	(segment
		(start 325.809356 -417.826698)
		(end 325.809356 -419.079172)
		(width 0.14224)
		(layer "In13.Cu")
		(net "P5E_CPU0_P1_RX_BUF_DP<6>")
	)
	(segment
		(start 325.809356 -416.698938)
		(end 325.809356 -417.125658)
		(width 0.14224)
		(layer "In13.Cu")
		(net "P5E_CPU0_P1_RX_BUF_DP<6>")
	)
	(segment
		(start 324.277736 -420.228014)
		(end 324.277736 -421.476932)
		(width 0.14224)
		(layer "In13.Cu")
		(net "P5E_CPU0_P1_RX_BUF_DP<6>")
	)
	(segment
		(start 325.051928 -423.10558)
		(end 325.252842 -423.481754)
		(width 0.14224)
		(layer "In13.Cu")
		(net "P5E_CPU0_P1_RX_BUF_DP<6>")
	)
	(segment
		(start 327.464928 -412.225236)
		(end 327.374504 -412.375096)
		(width 0.14224)
		(layer "In13.Cu")
		(net "P5E_CPU0_P1_RX_BUF_DP<6>")
	)
	(segment
		(start 333.083408 -409.669488)
		(end 332.903322 -409.597606)
		(width 0.14224)
		(layer "In13.Cu")
		(net "P5E_CPU0_P1_RX_BUF_DP<6>")
	)
	(segment
		(start 325.9709 -425.092368)
		(end 325.9709 -433.621942)
		(width 0.14224)
		(layer "In13.Cu")
		(net "P5E_CPU0_P1_RX_BUF_DP<6>")
	)
	(segment
		(start 325.800466 -424.318938)
		(end 325.734934 -424.501564)
		(width 0.14224)
		(layer "In13.Cu")
		(net "P5E_CPU0_P1_RX_BUF_DP<6>")
	)
	(segment
		(start 339.296502 -407.418286)
		(end 338.54009 -407.731722)
		(width 0.14224)
		(layer "In13.Cu")
		(net "P5E_CPU0_P1_RX_BUF_DP<6>")
	)
	(segment
		(start 324.721474 -422.486836)
		(end 324.907148 -422.543224)
		(width 0.14224)
		(layer "In13.Cu")
		(net "P5E_CPU0_P1_RX_BUF_DP<6>")
	)
	(segment
		(start 330.959206 -410.579824)
		(end 330.77912 -410.507942)
		(width 0.14224)
		(layer "In13.Cu")
		(net "P5E_CPU0_P1_RX_BUF_DP<6>")
	)
	(segment
		(start 324.907148 -422.543224)
		(end 325.108316 -422.919906)
		(width 0.14224)
		(layer "In13.Cu")
		(net "P5E_CPU0_P1_RX_BUF_DP<6>")
	)
	(segment
		(start 332.04658 -410.113988)
		(end 331.866494 -410.041852)
		(width 0.14224)
		(layer "In13.Cu")
		(net "P5E_CPU0_P1_RX_BUF_DP<6>")
	)
	(segment
		(start 325.809356 -415.020252)
		(end 325.809356 -415.997898)
		(width 0.14224)
		(layer "In13.Cu")
		(net "P5E_CPU0_P1_RX_BUF_DP<6>")
	)
	(segment
		(start 332.511146 -409.7655)
		(end 332.43901 -409.94584)
		(width 0.14224)
		(layer "In13.Cu")
		(net "P5E_CPU0_P1_RX_BUF_DP<6>")
	)
	(segment
		(start 343.085166 -402.820378)
		(end 343.222326 -402.957538)
		(width 0.14224)
		(layer "In13.Cu")
		(net "P5E_CPU0_P1_RX_BUF_DP<6>")
	)
	(segment
		(start 343.085166 -401.541996)
		(end 343.085166 -402.820378)
		(width 0.14224)
		(layer "In13.Cu")
		(net "P5E_CPU0_P1_RX_BUF_DP<6>")
	)
	(segment
		(start 325.946516 -417.689538)
		(end 325.809356 -417.826698)
		(width 0.14224)
		(layer "In13.Cu")
		(net "P5E_CPU0_P1_RX_BUF_DP<6>")
	)
	(segment
		(start 326.649588 -433.621942)
		(end 326.649588 -433.289964)
		(width 0.14224)
		(layer "In13.Cu")
		(net "P5E_CPU0_P1_RX_BUF_DP<6>")
	)
	(segment
		(start 333.475838 -409.501594)
		(end 333.083408 -409.669488)
		(width 0.14224)
		(layer "In13.Cu")
		(net "P5E_CPU0_P1_RX_BUF_DP<6>")
	)
	(segment
		(start 342.965278 -403.97303)
		(end 342.191086 -404.747222)
		(width 0.14224)
		(layer "In13.Cu")
		(net "P5E_CPU0_P1_RX_BUF_DP<6>")
	)
	(segment
		(start 325.946516 -416.135058)
		(end 325.946516 -416.561778)
		(width 0.14224)
		(layer "In13.Cu")
		(net "P5E_CPU0_P1_RX_BUF_DP<6>")
	)
	(segment
		(start 336.968338 -408.170126)
		(end 334.452214 -408.93365)
		(width 0.14224)
		(layer "In13.Cu")
		(net "P5E_CPU0_P1_RX_BUF_DP<6>")
	)
	(segment
		(start 326.676258 -414.153096)
		(end 326.400668 -414.267142)
		(width 0.14224)
		(layer "In13.Cu")
		(net "P5E_CPU0_P1_RX_BUF_DP<6>")
	)
	(segment
		(start 329.742292 -410.952188)
		(end 329.350116 -411.120082)
		(width 0.14224)
		(layer "In13.Cu")
		(net "P5E_CPU0_P1_RX_BUF_DP<6>")
	)
	(segment
		(start 343.222326 -402.957538)
		(end 343.222326 -403.384258)
		(width 0.14224)
		(layer "In13.Cu")
		(net "P5E_CPU0_P1_RX_BUF_DP<6>")
	)
	(segment
		(start 327.138538 -413.795464)
		(end 326.991726 -413.942276)
		(width 0.14224)
		(layer "In13.Cu")
		(net "P5E_CPU0_P1_RX_BUF_DP<6>")
	)
	(segment
		(start 338.54009 -407.731722)
		(end 336.968338 -408.170126)
		(width 0.14224)
		(layer "In13.Cu")
		(net "P5E_CPU0_P1_RX_BUF_DP<6>")
	)
	(segment
		(start 325.809356 -415.997898)
		(end 325.946516 -416.135058)
		(width 0.14224)
		(layer "In13.Cu")
		(net "P5E_CPU0_P1_RX_BUF_DP<6>")
	)
	(segment
		(start 325.946516 -416.561778)
		(end 325.809356 -416.698938)
		(width 0.14224)
		(layer "In13.Cu")
		(net "P5E_CPU0_P1_RX_BUF_DP<6>")
	)
	(segment
		(start 342.191086 -404.892764)
		(end 341.84082 -405.24303)
		(width 0.14224)
		(layer "In13.Cu")
		(net "P5E_CPU0_P1_RX_BUF_DP<6>")
	)
	(segment
		(start 328.209656 -411.611826)
		(end 327.97496 -411.724856)
		(width 0.14224)
		(layer "In13.Cu")
		(net "P5E_CPU0_P1_RX_BUF_DP<6>")
	)
	(segment
		(start 339.917532 -407.00325)
		(end 339.296502 -407.418286)
		(width 0.14224)
		(layer "In13.Cu")
		(net "P5E_CPU0_P1_RX_BUF_DP<6>")
	)
	(segment
		(start 329.922378 -411.02407)
		(end 329.742292 -410.952188)
		(width 0.14224)
		(layer "In13.Cu")
		(net "P5E_CPU0_P1_RX_BUF_DP<6>")
	)
	(segment
		(start 343.085166 -403.521418)
		(end 343.085166 -403.683724)
		(width 0.14224)
		(layer "In13.Cu")
		(net "P5E_CPU0_P1_RX_BUF_DP<6>")
	)
	(segment
		(start 343.227406 -401.399756)
		(end 343.085166 -401.541996)
		(width 0.14224)
		(layer "In13.Cu")
		(net "P5E_CPU0_P1_RX_BUF_DP<6>")
	)
	(segment
		(start 341.84082 -405.24303)
		(end 341.695278 -405.24303)
		(width 0.14224)
		(layer "In13.Cu")
		(net "P5E_CPU0_P1_RX_BUF_DP<6>")
	)
	(segment
		(start 329.278234 -411.300676)
		(end 328.885804 -411.46857)
		(width 0.14224)
		(layer "In13.Cu")
		(net "P5E_CPU0_P1_RX_BUF_DP<6>")
	)
	(segment
		(start 331.351636 -410.41193)
		(end 330.959206 -410.579824)
		(width 0.14224)
		(layer "In13.Cu")
		(net "P5E_CPU0_P1_RX_BUF_DP<6>")
	)
	(segment
		(start 330.386944 -410.675836)
		(end 330.314808 -410.856176)
		(width 0.14224)
		(layer "In13.Cu")
		(net "P5E_CPU0_P1_RX_BUF_DP<6>")
	)
	(segment
		(start 326.0979 -433.748942)
		(end 326.522588 -433.748942)
		(width 0.14224)
		(layer "In13.Cu")
		(net "P5E_CPU0_P1_RX_BUF_DP<6>")
	)
	(segment
		(start 334.452214 -408.93365)
		(end 333.547974 -409.321254)
		(width 0.14224)
		(layer "In13.Cu")
		(net "P5E_CPU0_P1_RX_BUF_DP<6>")
	)
	(segment
		(start 333.547974 -409.321254)
		(end 333.475838 -409.501594)
		(width 0.14224)
		(layer "In13.Cu")
		(net "P5E_CPU0_P1_RX_BUF_DP<6>")
	)
	(segment
		(start 328.885804 -411.46857)
		(end 328.705718 -411.396688)
		(width 0.14224)
		(layer "In13.Cu")
		(net "P5E_CPU0_P1_RX_BUF_DP<6>")
	)
	(segment
		(start 324.362826 -421.815514)
		(end 324.721474 -422.486836)
		(width 0.14224)
		(layer "In13.Cu")
		(net "P5E_CPU0_P1_RX_BUF_DP<6>")
	)
	(segment
		(start 342.191086 -404.747222)
		(end 342.191086 -404.892764)
		(width 0.14224)
		(layer "In13.Cu")
		(net "P5E_CPU0_P1_RX_BUF_DP<6>")
	)
	(segment
		(start 325.435214 -423.867326)
		(end 325.618094 -423.932858)
		(width 0.14224)
		(layer "In13.Cu")
		(net "P5E_CPU0_P1_RX_BUF_DP<6>")
	)
	(segment
		(start 325.9709 -433.621942)
		(end 326.0979 -433.748942)
		(width 0.14224)
		(layer "In13.Cu")
		(net "P5E_CPU0_P1_RX_BUF_DP<6>")
	)
	(segment
		(start 325.946516 -417.262818)
		(end 325.946516 -417.689538)
		(width 0.14224)
		(layer "In13.Cu")
		(net "P5E_CPU0_P1_RX_BUF_DP<6>")
	)
	(segment
		(start 331.423772 -410.23159)
		(end 331.351636 -410.41193)
		(width 0.14224)
		(layer "In13.Cu")
		(net "P5E_CPU0_P1_RX_BUF_DP<6>")
	)
	(segment
		(start 332.903322 -409.597606)
		(end 332.511146 -409.7655)
		(width 0.14224)
		(layer "In13.Cu")
		(net "P5E_CPU0_P1_RX_BUF_DP<6>")
	)
	(segment
		(start 330.77912 -410.507942)
		(end 330.386944 -410.675836)
		(width 0.14224)
		(layer "In13.Cu")
		(net "P5E_CPU0_P1_RX_BUF_DP<6>")
	)
	(segment
		(start 325.317866 -419.70198)
		(end 324.365366 -420.09695)
		(width 0.14224)
		(layer "In13.Cu")
		(net "P5E_CPU0_P1_RX_BUF_DP<6>")
	)
	(segment
		(start 325.685658 -419.388798)
		(end 325.518272 -419.56482)
		(width 0.14224)
		(layer "In13.Cu")
		(net "P5E_CPU0_P1_RX_BUF_DP<6>")
	)
	(segment
		(start 343.544144 -401.674838)
		(end 343.544144 -401.526756)
		(width 0.14224)
		(layer "In13.Cu")
		(net "P5E_CPU0_P1_RX_BUF_DP<6>")
	)
	(segment
		(start 325.809356 -417.125658)
		(end 325.946516 -417.262818)
		(width 0.14224)
		(layer "In13.Cu")
		(net "P5E_CPU0_P1_RX_BUF_DP<6>")
	)
	(segment
		(start 325.618094 -423.932858)
		(end 325.800466 -424.318938)
		(width 0.14224)
		(layer "In13.Cu")
		(net "P5E_CPU0_P1_RX_BUF_DP<6>")
	)
	(segment
		(start 327.89495 -411.78099)
		(end 327.543922 -412.125414)
		(width 0.14224)
		(layer "In13.Cu")
		(net "P5E_CPU0_P1_RX_BUF_DP<6>")
	)
	(segment
		(start 331.866494 -410.041852)
		(end 331.423772 -410.23159)
		(width 0.14224)
		(layer "In13.Cu")
		(net "P5E_CPU0_P1_RX_BUF_DP<6>")
	)
	(segment
		(start 329.350116 -411.120082)
		(end 329.278234 -411.300676)
		(width 0.14224)
		(layer "In13.Cu")
		(net "P5E_CPU0_P1_RX_BUF_DP<6>")
	)
	(segment
		(start 341.695278 -405.24303)
		(end 340.015322 -406.922986)
		(width 0.14224)
		(layer "In13.Cu")
		(net "P5E_CPU0_P1_RX_BUF_DP<6>")
	)
	(segment
		(start 332.43901 -409.94584)
		(end 332.04658 -410.113988)
		(width 0.14224)
		(layer "In13.Cu")
		(net "P5E_CPU0_P1_RX_BUF_DP<6>")
	)
	(segment
		(start 328.705718 -411.396688)
		(end 328.313542 -411.564582)
		(width 0.14224)
		(layer "In13.Cu")
		(net "P5E_CPU0_P1_RX_BUF_DP<6>")
	)
	(segment
		(start 330.314808 -410.856176)
		(end 329.922378 -411.02407)
		(width 0.14224)
		(layer "In13.Cu")
		(net "P5E_CPU0_P1_RX_BUF_DP<6>")
	)
	(segment
		(start 325.108316 -422.919906)
		(end 325.051928 -423.10558)
		(width 0.14224)
		(layer "In13.Cu")
		(net "P5E_CPU0_P1_RX_BUF_DP<6>")
	)
	(arc
		(start 340.015322 -406.922986)
		(mid 339.968406 -406.96553)
		(end 339.917532 -407.00325)
		(width 0.14224)
		(layer "In13.Cu")
		(net "P5E_CPU0_P1_RX_BUF_DP<6>")
	)
	(arc
		(start 326.400668 -414.267142)
		(mid 326.194786 -414.377288)
		(end 326.014334 -414.52546)
		(width 0.14224)
		(layer "In13.Cu")
		(net "P5E_CPU0_P1_RX_BUF_DP<6>")
	)
	(arc
		(start 324.277736 -421.476932)
		(mid 324.299392 -421.651474)
		(end 324.362826 -421.815514)
		(width 0.14224)
		(layer "In13.Cu")
		(net "P5E_CPU0_P1_RX_BUF_DP<6>")
	)
	(arc
		(start 327.374504 -412.375096)
		(mid 327.34954 -412.433008)
		(end 327.340976 -412.495492)
		(width 0.14224)
		(layer "In13.Cu")
		(net "P5E_CPU0_P1_RX_BUF_DP<6>")
	)
	(arc
		(start 325.93153 -424.917362)
		(mid 325.960932 -425.002681)
		(end 325.9709 -425.092368)
		(width 0.14224)
		(layer "In13.Cu")
		(net "P5E_CPU0_P1_RX_BUF_DP<6>")
	)
	(arc
		(start 327.340976 -413.306514)
		(mid 327.288362 -413.571111)
		(end 327.138538 -413.795464)
		(width 0.14224)
		(layer "In13.Cu")
		(net "P5E_CPU0_P1_RX_BUF_DP<6>")
	)
	(arc
		(start 328.313542 -411.564582)
		(mid 328.261342 -411.587638)
		(end 328.209656 -411.611826)
		(width 0.14224)
		(layer "In13.Cu")
		(net "P5E_CPU0_P1_RX_BUF_DP<6>")
	)
	(arc
		(start 327.97496 -411.724856)
		(mid 327.932665 -411.749656)
		(end 327.89495 -411.78099)
		(width 0.14224)
		(layer "In13.Cu")
		(net "P5E_CPU0_P1_RX_BUF_DP<6>")
	)
	(arc
		(start 343.085166 -403.683724)
		(mid 343.054003 -403.840302)
		(end 342.965278 -403.97303)
		(width 0.14224)
		(layer "In13.Cu")
		(net "P5E_CPU0_P1_RX_BUF_DP<6>")
	)
	(arc
		(start 327.543922 -412.125414)
		(mid 327.501296 -412.172847)
		(end 327.464928 -412.225236)
		(width 0.14224)
		(layer "In13.Cu")
		(net "P5E_CPU0_P1_RX_BUF_DP<6>")
	)
	(arc
		(start 325.518272 -419.56482)
		(mid 325.425254 -419.643897)
		(end 325.317866 -419.70198)
		(width 0.14224)
		(layer "In13.Cu")
		(net "P5E_CPU0_P1_RX_BUF_DP<6>")
	)
	(arc
		(start 325.809356 -419.079172)
		(mid 325.777391 -419.24593)
		(end 325.685658 -419.388798)
		(width 0.14224)
		(layer "In13.Cu")
		(net "P5E_CPU0_P1_RX_BUF_DP<6>")
	)
	(arc
		(start 326.014334 -414.52546)
		(mid 325.862571 -414.752445)
		(end 325.809356 -415.020252)
		(width 0.14224)
		(layer "In13.Cu")
		(net "P5E_CPU0_P1_RX_BUF_DP<6>")
	)
	(arc
		(start 324.365366 -420.09695)
		(mid 324.301621 -420.149167)
		(end 324.277736 -420.228014)
		(width 0.14224)
		(layer "In13.Cu")
		(net "P5E_CPU0_P1_RX_BUF_DP<6>")
	)
	(segment
		(start 341.645494 -399.663158)
		(end 341.730076 -399.74774)
		(width 0.1016)
		(layer "F.Cu")
		(net "P5E_CPU0_P1_RX_BUF_DP<5>")
	)
	(segment
		(start 341.730076 -399.870676)
		(end 341.64143 -399.959322)
		(width 0.1016)
		(layer "F.Cu")
		(net "P5E_CPU0_P1_RX_BUF_DP<5>")
	)
	(segment
		(start 341.730076 -399.74774)
		(end 341.730076 -399.870676)
		(width 0.1016)
		(layer "F.Cu")
		(net "P5E_CPU0_P1_RX_BUF_DP<5>")
	)
	(segment
		(start 341.64143 -401.105878)
		(end 341.894668 -401.359116)
		(width 0.1016)
		(layer "F.Cu")
		(net "P5E_CPU0_P1_RX_BUF_DP<5>")
	)
	(segment
		(start 342.343994 -401.4978)
		(end 342.343994 -401.674838)
		(width 0.1016)
		(layer "F.Cu")
		(net "P5E_CPU0_P1_RX_BUF_DP<5>")
	)
	(segment
		(start 342.20531 -401.359116)
		(end 342.343994 -401.4978)
		(width 0.1016)
		(layer "F.Cu")
		(net "P5E_CPU0_P1_RX_BUF_DP<5>")
	)
	(segment
		(start 341.64143 -399.959322)
		(end 341.64143 -401.105878)
		(width 0.1016)
		(layer "F.Cu")
		(net "P5E_CPU0_P1_RX_BUF_DP<5>")
	)
	(segment
		(start 341.894668 -401.359116)
		(end 342.20531 -401.359116)
		(width 0.1016)
		(layer "F.Cu")
		(net "P5E_CPU0_P1_RX_BUF_DP<5>")
	)
	(segment
		(start 342.022176 -403.273514)
		(end 341.885016 -403.410674)
		(width 0.14224)
		(layer "In13.Cu")
		(net "P5E_CPU0_P1_RX_BUF_DP<5>")
	)
	(segment
		(start 341.761064 -403.842474)
		(end 339.918548 -405.68499)
		(width 0.14224)
		(layer "In13.Cu")
		(net "P5E_CPU0_P1_RX_BUF_DP<5>")
	)
	(segment
		(start 339.295486 -406.196546)
		(end 338.651596 -406.626822)
		(width 0.14224)
		(layer "In13.Cu")
		(net "P5E_CPU0_P1_RX_BUF_DP<5>")
	)
	(segment
		(start 341.885016 -401.541996)
		(end 341.885016 -402.709634)
		(width 0.14224)
		(layer "In13.Cu")
		(net "P5E_CPU0_P1_RX_BUF_DP<5>")
	)
	(segment
		(start 321.414648 -421.967406)
		(end 322.606416 -423.159174)
		(width 0.14224)
		(layer "In13.Cu")
		(net "P5E_CPU0_P1_RX_BUF_DP<5>")
	)
	(segment
		(start 342.216994 -401.399756)
		(end 342.027256 -401.399756)
		(width 0.14224)
		(layer "In13.Cu")
		(net "P5E_CPU0_P1_RX_BUF_DP<5>")
	)
	(segment
		(start 322.883276 -416.433254)
		(end 322.746116 -416.570414)
		(width 0.14224)
		(layer "In13.Cu")
		(net "P5E_CPU0_P1_RX_BUF_DP<5>")
	)
	(segment
		(start 322.576698 -419.457632)
		(end 322.406264 -419.636194)
		(width 0.14224)
		(layer "In13.Cu")
		(net "P5E_CPU0_P1_RX_BUF_DP<5>")
	)
	(segment
		(start 328.353674 -410.248608)
		(end 327.95464 -410.4005)
		(width 0.14224)
		(layer "In13.Cu")
		(net "P5E_CPU0_P1_RX_BUF_DP<5>")
	)
	(segment
		(start 331.994002 -408.714956)
		(end 331.595476 -408.866594)
		(width 0.14224)
		(layer "In13.Cu")
		(net "P5E_CPU0_P1_RX_BUF_DP<5>")
	)
	(segment
		(start 323.353684 -424.06951)
		(end 323.732652 -424.531282)
		(width 0.14224)
		(layer "In13.Cu")
		(net "P5E_CPU0_P1_RX_BUF_DP<5>")
	)
	(segment
		(start 342.343994 -401.526756)
		(end 342.216994 -401.399756)
		(width 0.14224)
		(layer "In13.Cu")
		(net "P5E_CPU0_P1_RX_BUF_DP<5>")
	)
	(segment
		(start 324.075298 -413.795464)
		(end 323.928486 -413.942276)
		(width 0.14224)
		(layer "In13.Cu")
		(net "P5E_CPU0_P1_RX_BUF_DP<5>")
	)
	(segment
		(start 324.649592 -434.62194)
		(end 324.649592 -434.289962)
		(width 0.14224)
		(layer "In13.Cu")
		(net "P5E_CPU0_P1_RX_BUF_DP<5>")
	)
	(segment
		(start 328.433176 -410.071316)
		(end 328.353674 -410.248608)
		(width 0.14224)
		(layer "In13.Cu")
		(net "P5E_CPU0_P1_RX_BUF_DP<5>")
	)
	(segment
		(start 322.883276 -417.134294)
		(end 322.883276 -417.561014)
		(width 0.14224)
		(layer "In13.Cu")
		(net "P5E_CPU0_P1_RX_BUF_DP<5>")
	)
	(segment
		(start 324.522592 -434.74894)
		(end 324.649592 -434.62194)
		(width 0.14224)
		(layer "In13.Cu")
		(net "P5E_CPU0_P1_RX_BUF_DP<5>")
	)
	(segment
		(start 323.844412 -424.730164)
		(end 323.94525 -425.016422)
		(width 0.14224)
		(layer "In13.Cu")
		(net "P5E_CPU0_P1_RX_BUF_DP<5>")
	)
	(segment
		(start 322.746116 -416.570414)
		(end 322.746116 -416.997134)
		(width 0.14224)
		(layer "In13.Cu")
		(net "P5E_CPU0_P1_RX_BUF_DP<5>")
	)
	(segment
		(start 322.883276 -417.561014)
		(end 322.746116 -417.698174)
		(width 0.14224)
		(layer "In13.Cu")
		(net "P5E_CPU0_P1_RX_BUF_DP<5>")
	)
	(segment
		(start 324.592188 -411.958028)
		(end 324.423278 -412.126938)
		(width 0.14224)
		(layer "In13.Cu")
		(net "P5E_CPU0_P1_RX_BUF_DP<5>")
	)
	(segment
		(start 329.487276 -409.669742)
		(end 329.407774 -409.847034)
		(width 0.14224)
		(layer "In13.Cu")
		(net "P5E_CPU0_P1_RX_BUF_DP<5>")
	)
	(segment
		(start 328.831702 -409.919424)
		(end 328.433176 -410.071316)
		(width 0.14224)
		(layer "In13.Cu")
		(net "P5E_CPU0_P1_RX_BUF_DP<5>")
	)
	(segment
		(start 339.918548 -405.68499)
		(end 339.295486 -406.196546)
		(width 0.14224)
		(layer "In13.Cu")
		(net "P5E_CPU0_P1_RX_BUF_DP<5>")
	)
	(segment
		(start 329.00874 -409.998926)
		(end 328.831702 -409.919424)
		(width 0.14224)
		(layer "In13.Cu")
		(net "P5E_CPU0_P1_RX_BUF_DP<5>")
	)
	(segment
		(start 331.595476 -408.866594)
		(end 331.515974 -409.043886)
		(width 0.14224)
		(layer "In13.Cu")
		(net "P5E_CPU0_P1_RX_BUF_DP<5>")
	)
	(segment
		(start 323.928486 -413.942276)
		(end 323.613018 -414.153096)
		(width 0.14224)
		(layer "In13.Cu")
		(net "P5E_CPU0_P1_RX_BUF_DP<5>")
	)
	(segment
		(start 336.357214 -407.21407)
		(end 333.164688 -408.268932)
		(width 0.14224)
		(layer "In13.Cu")
		(net "P5E_CPU0_P1_RX_BUF_DP<5>")
	)
	(segment
		(start 322.746116 -415.020252)
		(end 322.746116 -415.869374)
		(width 0.14224)
		(layer "In13.Cu")
		(net "P5E_CPU0_P1_RX_BUF_DP<5>")
	)
	(segment
		(start 323.613018 -414.153096)
		(end 323.337428 -414.267142)
		(width 0.14224)
		(layer "In13.Cu")
		(net "P5E_CPU0_P1_RX_BUF_DP<5>")
	)
	(segment
		(start 324.17512 -434.74894)
		(end 324.522592 -434.74894)
		(width 0.14224)
		(layer "In13.Cu")
		(net "P5E_CPU0_P1_RX_BUF_DP<5>")
	)
	(segment
		(start 329.407774 -409.847034)
		(end 329.00874 -409.998926)
		(width 0.14224)
		(layer "In13.Cu")
		(net "P5E_CPU0_P1_RX_BUF_DP<5>")
	)
	(segment
		(start 322.908676 -423.527474)
		(end 323.101716 -423.546524)
		(width 0.14224)
		(layer "In13.Cu")
		(net "P5E_CPU0_P1_RX_BUF_DP<5>")
	)
	(segment
		(start 331.515974 -409.043886)
		(end 331.11694 -409.195778)
		(width 0.14224)
		(layer "In13.Cu")
		(net "P5E_CPU0_P1_RX_BUF_DP<5>")
	)
	(segment
		(start 327.95464 -410.4005)
		(end 327.777602 -410.320998)
		(width 0.14224)
		(layer "In13.Cu")
		(net "P5E_CPU0_P1_RX_BUF_DP<5>")
	)
	(segment
		(start 329.885802 -409.51785)
		(end 329.487276 -409.669742)
		(width 0.14224)
		(layer "In13.Cu")
		(net "P5E_CPU0_P1_RX_BUF_DP<5>")
	)
	(segment
		(start 331.11694 -409.195778)
		(end 330.939902 -409.116276)
		(width 0.14224)
		(layer "In13.Cu")
		(net "P5E_CPU0_P1_RX_BUF_DP<5>")
	)
	(segment
		(start 342.027256 -401.399756)
		(end 341.885016 -401.541996)
		(width 0.14224)
		(layer "In13.Cu")
		(net "P5E_CPU0_P1_RX_BUF_DP<5>")
	)
	(segment
		(start 326.723502 -410.722572)
		(end 326.324976 -410.874464)
		(width 0.14224)
		(layer "In13.Cu")
		(net "P5E_CPU0_P1_RX_BUF_DP<5>")
	)
	(segment
		(start 322.2371 -419.74262)
		(end 321.365626 -420.026846)
		(width 0.14224)
		(layer "In13.Cu")
		(net "P5E_CPU0_P1_RX_BUF_DP<5>")
	)
	(segment
		(start 327.777602 -410.320998)
		(end 327.379076 -410.47289)
		(width 0.14224)
		(layer "In13.Cu")
		(net "P5E_CPU0_P1_RX_BUF_DP<5>")
	)
	(segment
		(start 326.90054 -410.802074)
		(end 326.723502 -410.722572)
		(width 0.14224)
		(layer "In13.Cu")
		(net "P5E_CPU0_P1_RX_BUF_DP<5>")
	)
	(segment
		(start 327.379076 -410.47289)
		(end 327.299574 -410.650182)
		(width 0.14224)
		(layer "In13.Cu")
		(net "P5E_CPU0_P1_RX_BUF_DP<5>")
	)
	(segment
		(start 323.982588 -425.2341)
		(end 323.982588 -434.556408)
		(width 0.14224)
		(layer "In13.Cu")
		(net "P5E_CPU0_P1_RX_BUF_DP<5>")
	)
	(segment
		(start 333.164688 -408.268932)
		(end 332.649576 -408.46502)
		(width 0.14224)
		(layer "In13.Cu")
		(net "P5E_CPU0_P1_RX_BUF_DP<5>")
	)
	(segment
		(start 323.372734 -423.87647)
		(end 323.353684 -424.06951)
		(width 0.14224)
		(layer "In13.Cu")
		(net "P5E_CPU0_P1_RX_BUF_DP<5>")
	)
	(segment
		(start 338.043012 -406.87879)
		(end 336.357214 -407.21407)
		(width 0.14224)
		(layer "In13.Cu")
		(net "P5E_CPU0_P1_RX_BUF_DP<5>")
	)
	(segment
		(start 338.651596 -406.626822)
		(end 338.043012 -406.87879)
		(width 0.14224)
		(layer "In13.Cu")
		(net "P5E_CPU0_P1_RX_BUF_DP<5>")
	)
	(segment
		(start 322.606416 -423.159174)
		(end 322.908676 -423.527474)
		(width 0.14224)
		(layer "In13.Cu")
		(net "P5E_CPU0_P1_RX_BUF_DP<5>")
	)
	(segment
		(start 342.022176 -402.846794)
		(end 342.022176 -403.273514)
		(width 0.14224)
		(layer "In13.Cu")
		(net "P5E_CPU0_P1_RX_BUF_DP<5>")
	)
	(segment
		(start 323.101716 -423.546524)
		(end 323.372734 -423.87647)
		(width 0.14224)
		(layer "In13.Cu")
		(net "P5E_CPU0_P1_RX_BUF_DP<5>")
	)
	(segment
		(start 330.541376 -409.268168)
		(end 330.461874 -409.44546)
		(width 0.14224)
		(layer "In13.Cu")
		(net "P5E_CPU0_P1_RX_BUF_DP<5>")
	)
	(segment
		(start 341.885016 -403.410674)
		(end 341.885016 -403.543262)
		(width 0.14224)
		(layer "In13.Cu")
		(net "P5E_CPU0_P1_RX_BUF_DP<5>")
	)
	(segment
		(start 330.461874 -409.44546)
		(end 330.06284 -409.597352)
		(width 0.14224)
		(layer "In13.Cu")
		(net "P5E_CPU0_P1_RX_BUF_DP<5>")
	)
	(segment
		(start 330.939902 -409.116276)
		(end 330.541376 -409.268168)
		(width 0.14224)
		(layer "In13.Cu")
		(net "P5E_CPU0_P1_RX_BUF_DP<5>")
	)
	(segment
		(start 330.06284 -409.597352)
		(end 329.885802 -409.51785)
		(width 0.14224)
		(layer "In13.Cu")
		(net "P5E_CPU0_P1_RX_BUF_DP<5>")
	)
	(segment
		(start 321.214496 -420.318946)
		(end 321.214496 -421.484298)
		(width 0.14224)
		(layer "In13.Cu")
		(net "P5E_CPU0_P1_RX_BUF_DP<5>")
	)
	(segment
		(start 342.343994 -401.674838)
		(end 342.343994 -401.526756)
		(width 0.14224)
		(layer "In13.Cu")
		(net "P5E_CPU0_P1_RX_BUF_DP<5>")
	)
	(segment
		(start 332.17104 -408.794204)
		(end 331.994002 -408.714956)
		(width 0.14224)
		(layer "In13.Cu")
		(net "P5E_CPU0_P1_RX_BUF_DP<5>")
	)
	(segment
		(start 321.271138 -420.095934)
		(end 321.263518 -420.111174)
		(width 0.14224)
		(layer "In13.Cu")
		(net "P5E_CPU0_P1_RX_BUF_DP<5>")
	)
	(segment
		(start 332.570074 -408.642312)
		(end 332.17104 -408.794204)
		(width 0.14224)
		(layer "In13.Cu")
		(net "P5E_CPU0_P1_RX_BUF_DP<5>")
	)
	(segment
		(start 322.746116 -415.869374)
		(end 322.883276 -416.006534)
		(width 0.14224)
		(layer "In13.Cu")
		(net "P5E_CPU0_P1_RX_BUF_DP<5>")
	)
	(segment
		(start 323.982588 -434.556408)
		(end 324.17512 -434.74894)
		(width 0.14224)
		(layer "In13.Cu")
		(net "P5E_CPU0_P1_RX_BUF_DP<5>")
	)
	(segment
		(start 327.299574 -410.650182)
		(end 326.90054 -410.802074)
		(width 0.14224)
		(layer "In13.Cu")
		(net "P5E_CPU0_P1_RX_BUF_DP<5>")
	)
	(segment
		(start 322.883276 -416.006534)
		(end 322.883276 -416.433254)
		(width 0.14224)
		(layer "In13.Cu")
		(net "P5E_CPU0_P1_RX_BUF_DP<5>")
	)
	(segment
		(start 326.324976 -410.874464)
		(end 325.28129 -411.442662)
		(width 0.14224)
		(layer "In13.Cu")
		(net "P5E_CPU0_P1_RX_BUF_DP<5>")
	)
	(segment
		(start 341.885016 -402.709634)
		(end 342.022176 -402.846794)
		(width 0.14224)
		(layer "In13.Cu")
		(net "P5E_CPU0_P1_RX_BUF_DP<5>")
	)
	(segment
		(start 322.746116 -417.698174)
		(end 322.746116 -419.034722)
		(width 0.14224)
		(layer "In13.Cu")
		(net "P5E_CPU0_P1_RX_BUF_DP<5>")
	)
	(segment
		(start 332.649576 -408.46502)
		(end 332.570074 -408.642312)
		(width 0.14224)
		(layer "In13.Cu")
		(net "P5E_CPU0_P1_RX_BUF_DP<5>")
	)
	(segment
		(start 322.746116 -416.997134)
		(end 322.883276 -417.134294)
		(width 0.14224)
		(layer "In13.Cu")
		(net "P5E_CPU0_P1_RX_BUF_DP<5>")
	)
	(segment
		(start 324.277736 -412.47822)
		(end 324.277736 -413.306514)
		(width 0.14224)
		(layer "In13.Cu")
		(net "P5E_CPU0_P1_RX_BUF_DP<5>")
	)
	(segment
		(start 321.365626 -420.026846)
		(end 321.271138 -420.095934)
		(width 0.14224)
		(layer "In13.Cu")
		(net "P5E_CPU0_P1_RX_BUF_DP<5>")
	)
	(arc
		(start 324.277736 -413.306514)
		(mid 324.225122 -413.571111)
		(end 324.075298 -413.795464)
		(width 0.14224)
		(layer "In13.Cu")
		(net "P5E_CPU0_P1_RX_BUF_DP<5>")
	)
	(arc
		(start 325.28129 -411.442662)
		(mid 324.918229 -411.675596)
		(end 324.592188 -411.958028)
		(width 0.14224)
		(layer "In13.Cu")
		(net "P5E_CPU0_P1_RX_BUF_DP<5>")
	)
	(arc
		(start 321.263518 -420.111174)
		(mid 321.226918 -420.212208)
		(end 321.214496 -420.318946)
		(width 0.14224)
		(layer "In13.Cu")
		(net "P5E_CPU0_P1_RX_BUF_DP<5>")
	)
	(arc
		(start 322.746116 -419.034722)
		(mid 322.702244 -419.262543)
		(end 322.576698 -419.457632)
		(width 0.14224)
		(layer "In13.Cu")
		(net "P5E_CPU0_P1_RX_BUF_DP<5>")
	)
	(arc
		(start 341.885016 -403.543262)
		(mid 341.852805 -403.7052)
		(end 341.761064 -403.842474)
		(width 0.14224)
		(layer "In13.Cu")
		(net "P5E_CPU0_P1_RX_BUF_DP<5>")
	)
	(arc
		(start 321.214496 -421.484298)
		(mid 321.266521 -421.745756)
		(end 321.414648 -421.967406)
		(width 0.14224)
		(layer "In13.Cu")
		(net "P5E_CPU0_P1_RX_BUF_DP<5>")
	)
	(arc
		(start 322.406264 -419.636194)
		(mid 322.328278 -419.699891)
		(end 322.2371 -419.74262)
		(width 0.14224)
		(layer "In13.Cu")
		(net "P5E_CPU0_P1_RX_BUF_DP<5>")
	)
	(arc
		(start 323.94525 -425.016422)
		(mid 323.973137 -425.123678)
		(end 323.982588 -425.2341)
		(width 0.14224)
		(layer "In13.Cu")
		(net "P5E_CPU0_P1_RX_BUF_DP<5>")
	)
	(arc
		(start 324.423278 -412.126938)
		(mid 324.315588 -412.288108)
		(end 324.277736 -412.47822)
		(width 0.14224)
		(layer "In13.Cu")
		(net "P5E_CPU0_P1_RX_BUF_DP<5>")
	)
	(arc
		(start 322.951094 -414.52546)
		(mid 322.799331 -414.752445)
		(end 322.746116 -415.020252)
		(width 0.14224)
		(layer "In13.Cu")
		(net "P5E_CPU0_P1_RX_BUF_DP<5>")
	)
	(arc
		(start 323.732652 -424.531282)
		(mid 323.797209 -424.625846)
		(end 323.844412 -424.730164)
		(width 0.14224)
		(layer "In13.Cu")
		(net "P5E_CPU0_P1_RX_BUF_DP<5>")
	)
	(arc
		(start 323.337428 -414.267142)
		(mid 323.131546 -414.377288)
		(end 322.951094 -414.52546)
		(width 0.14224)
		(layer "In13.Cu")
		(net "P5E_CPU0_P1_RX_BUF_DP<5>")
	)
	(segment
		(start 340.694772 -401.359116)
		(end 341.005414 -401.359116)
		(width 0.1016)
		(layer "F.Cu")
		(net "P5E_CPU0_P1_RX_BUF_DP<4>")
	)
	(segment
		(start 340.53018 -399.74774)
		(end 340.53018 -399.870676)
		(width 0.1016)
		(layer "F.Cu")
		(net "P5E_CPU0_P1_RX_BUF_DP<4>")
	)
	(segment
		(start 340.53018 -399.870676)
		(end 340.441534 -399.959322)
		(width 0.1016)
		(layer "F.Cu")
		(net "P5E_CPU0_P1_RX_BUF_DP<4>")
	)
	(segment
		(start 340.441534 -399.959322)
		(end 340.441534 -401.105878)
		(width 0.1016)
		(layer "F.Cu")
		(net "P5E_CPU0_P1_RX_BUF_DP<4>")
	)
	(segment
		(start 340.445598 -399.663158)
		(end 340.53018 -399.74774)
		(width 0.1016)
		(layer "F.Cu")
		(net "P5E_CPU0_P1_RX_BUF_DP<4>")
	)
	(segment
		(start 341.005414 -401.359116)
		(end 341.144098 -401.4978)
		(width 0.1016)
		(layer "F.Cu")
		(net "P5E_CPU0_P1_RX_BUF_DP<4>")
	)
	(segment
		(start 340.441534 -401.105878)
		(end 340.694772 -401.359116)
		(width 0.1016)
		(layer "F.Cu")
		(net "P5E_CPU0_P1_RX_BUF_DP<4>")
	)
	(segment
		(start 341.144098 -401.4978)
		(end 341.144098 -401.674838)
		(width 0.1016)
		(layer "F.Cu")
		(net "P5E_CPU0_P1_RX_BUF_DP<4>")
	)
	(segment
		(start 321.214496 -412.46044)
		(end 321.214496 -413.306514)
		(width 0.14224)
		(layer "In13.Cu")
		(net "P5E_CPU0_P1_RX_BUF_DP<4>")
	)
	(segment
		(start 321.970908 -433.619402)
		(end 322.100448 -433.748942)
		(width 0.14224)
		(layer "In13.Cu")
		(net "P5E_CPU0_P1_RX_BUF_DP<4>")
	)
	(segment
		(start 318.187578 -421.36314)
		(end 318.360552 -421.687498)
		(width 0.14224)
		(layer "In13.Cu")
		(net "P5E_CPU0_P1_RX_BUF_DP<4>")
	)
	(segment
		(start 325.240904 -410.18841)
		(end 325.060818 -410.116528)
		(width 0.14224)
		(layer "In13.Cu")
		(net "P5E_CPU0_P1_RX_BUF_DP<4>")
	)
	(segment
		(start 325.70547 -409.840176)
		(end 325.633334 -410.020516)
		(width 0.14224)
		(layer "In13.Cu")
		(net "P5E_CPU0_P1_RX_BUF_DP<4>")
	)
	(segment
		(start 321.012058 -413.795464)
		(end 320.865246 -413.942276)
		(width 0.14224)
		(layer "In13.Cu")
		(net "P5E_CPU0_P1_RX_BUF_DP<4>")
	)
	(segment
		(start 321.35445 -423.921936)
		(end 321.871086 -424.617642)
		(width 0.14224)
		(layer "In13.Cu")
		(net "P5E_CPU0_P1_RX_BUF_DP<4>")
	)
	(segment
		(start 322.522596 -433.748942)
		(end 322.649596 -433.621942)
		(width 0.14224)
		(layer "In13.Cu")
		(net "P5E_CPU0_P1_RX_BUF_DP<4>")
	)
	(segment
		(start 328.04608 -408.83713)
		(end 326.742298 -409.39593)
		(width 0.14224)
		(layer "In13.Cu")
		(net "P5E_CPU0_P1_RX_BUF_DP<4>")
	)
	(segment
		(start 328.624438 -408.79014)
		(end 328.450956 -408.703018)
		(width 0.14224)
		(layer "In13.Cu")
		(net "P5E_CPU0_P1_RX_BUF_DP<4>")
	)
	(segment
		(start 331.25791 -407.773378)
		(end 331.171042 -407.94686)
		(width 0.14224)
		(layer "In13.Cu")
		(net "P5E_CPU0_P1_RX_BUF_DP<4>")
	)
	(segment
		(start 326.670162 -409.57627)
		(end 326.277732 -409.744164)
		(width 0.14224)
		(layer "In13.Cu")
		(net "P5E_CPU0_P1_RX_BUF_DP<4>")
	)
	(segment
		(start 324.596506 -410.464762)
		(end 324.204076 -410.632656)
		(width 0.14224)
		(layer "In13.Cu")
		(net "P5E_CPU0_P1_RX_BUF_DP<4>")
	)
	(segment
		(start 329.029822 -408.656028)
		(end 328.624438 -408.79014)
		(width 0.14224)
		(layer "In13.Cu")
		(net "P5E_CPU0_P1_RX_BUF_DP<4>")
	)
	(segment
		(start 340.68512 -401.541996)
		(end 340.68512 -403.151594)
		(width 0.14224)
		(layer "In13.Cu")
		(net "P5E_CPU0_P1_RX_BUF_DP<4>")
	)
	(segment
		(start 319.682876 -416.00755)
		(end 319.820036 -416.14471)
		(width 0.14224)
		(layer "In13.Cu")
		(net "P5E_CPU0_P1_RX_BUF_DP<4>")
	)
	(segment
		(start 333.625952 -407.133806)
		(end 333.220568 -407.267918)
		(width 0.14224)
		(layer "In13.Cu")
		(net "P5E_CPU0_P1_RX_BUF_DP<4>")
	)
	(segment
		(start 319.682876 -417.879784)
		(end 319.682876 -419.079172)
		(width 0.14224)
		(layer "In13.Cu")
		(net "P5E_CPU0_P1_RX_BUF_DP<4>")
	)
	(segment
		(start 320.065146 -422.959784)
		(end 320.255392 -422.921938)
		(width 0.14224)
		(layer "In13.Cu")
		(net "P5E_CPU0_P1_RX_BUF_DP<4>")
	)
	(segment
		(start 319.191386 -419.70198)
		(end 318.238886 -420.09695)
		(width 0.14224)
		(layer "In13.Cu")
		(net "P5E_CPU0_P1_RX_BUF_DP<4>")
	)
	(segment
		(start 319.820036 -417.742624)
		(end 319.682876 -417.879784)
		(width 0.14224)
		(layer "In13.Cu")
		(net "P5E_CPU0_P1_RX_BUF_DP<4>")
	)
	(segment
		(start 320.549778 -414.153096)
		(end 320.274188 -414.267142)
		(width 0.14224)
		(layer "In13.Cu")
		(net "P5E_CPU0_P1_RX_BUF_DP<4>")
	)
	(segment
		(start 325.633334 -410.020516)
		(end 325.240904 -410.18841)
		(width 0.14224)
		(layer "In13.Cu")
		(net "P5E_CPU0_P1_RX_BUF_DP<4>")
	)
	(segment
		(start 321.970908 -424.919648)
		(end 321.970908 -433.619402)
		(width 0.14224)
		(layer "In13.Cu")
		(net "P5E_CPU0_P1_RX_BUF_DP<4>")
	)
	(segment
		(start 328.450956 -408.703018)
		(end 328.04608 -408.83713)
		(width 0.14224)
		(layer "In13.Cu")
		(net "P5E_CPU0_P1_RX_BUF_DP<4>")
	)
	(segment
		(start 319.559178 -419.388798)
		(end 319.391792 -419.56482)
		(width 0.14224)
		(layer "In13.Cu")
		(net "P5E_CPU0_P1_RX_BUF_DP<4>")
	)
	(segment
		(start 320.61023 -423.159428)
		(end 320.648076 -423.349674)
		(width 0.14224)
		(layer "In13.Cu")
		(net "P5E_CPU0_P1_RX_BUF_DP<4>")
	)
	(segment
		(start 319.682876 -416.70859)
		(end 319.682876 -417.178744)
		(width 0.14224)
		(layer "In13.Cu")
		(net "P5E_CPU0_P1_RX_BUF_DP<4>")
	)
	(segment
		(start 323.631814 -410.728668)
		(end 323.559678 -410.909008)
		(width 0.14224)
		(layer "In13.Cu")
		(net "P5E_CPU0_P1_RX_BUF_DP<4>")
	)
	(segment
		(start 318.437006 -421.787574)
		(end 318.68872 -422.026334)
		(width 0.14224)
		(layer "In13.Cu")
		(net "P5E_CPU0_P1_RX_BUF_DP<4>")
	)
	(segment
		(start 330.1873 -408.127962)
		(end 330.100432 -408.301444)
		(width 0.14224)
		(layer "In13.Cu")
		(net "P5E_CPU0_P1_RX_BUF_DP<4>")
	)
	(segment
		(start 329.11669 -408.482546)
		(end 329.029822 -408.656028)
		(width 0.14224)
		(layer "In13.Cu")
		(net "P5E_CPU0_P1_RX_BUF_DP<4>")
	)
	(segment
		(start 326.742298 -409.39593)
		(end 326.670162 -409.57627)
		(width 0.14224)
		(layer "In13.Cu")
		(net "P5E_CPU0_P1_RX_BUF_DP<4>")
	)
	(segment
		(start 336.890614 -406.060656)
		(end 334.621124 -406.659588)
		(width 0.14224)
		(layer "In13.Cu")
		(net "P5E_CPU0_P1_RX_BUF_DP<4>")
	)
	(segment
		(start 319.682876 -417.178744)
		(end 319.820036 -417.315904)
		(width 0.14224)
		(layer "In13.Cu")
		(net "P5E_CPU0_P1_RX_BUF_DP<4>")
	)
	(segment
		(start 324.02399 -410.560774)
		(end 323.631814 -410.728668)
		(width 0.14224)
		(layer "In13.Cu")
		(net "P5E_CPU0_P1_RX_BUF_DP<4>")
	)
	(segment
		(start 320.865246 -413.942276)
		(end 320.549778 -414.153096)
		(width 0.14224)
		(layer "In13.Cu")
		(net "P5E_CPU0_P1_RX_BUF_DP<4>")
	)
	(segment
		(start 333.713074 -406.960324)
		(end 333.625952 -407.133806)
		(width 0.14224)
		(layer "In13.Cu")
		(net "P5E_CPU0_P1_RX_BUF_DP<4>")
	)
	(segment
		(start 333.220568 -407.267918)
		(end 333.04734 -407.180796)
		(width 0.14224)
		(layer "In13.Cu")
		(net "P5E_CPU0_P1_RX_BUF_DP<4>")
	)
	(segment
		(start 326.277732 -409.744164)
		(end 326.097646 -409.672282)
		(width 0.14224)
		(layer "In13.Cu")
		(net "P5E_CPU0_P1_RX_BUF_DP<4>")
	)
	(segment
		(start 338.265516 -405.702262)
		(end 337.870546 -405.865838)
		(width 0.14224)
		(layer "In13.Cu")
		(net "P5E_CPU0_P1_RX_BUF_DP<4>")
	)
	(segment
		(start 340.495382 -403.609556)
		(end 340.224872 -404.014432)
		(width 0.14224)
		(layer "In13.Cu")
		(net "P5E_CPU0_P1_RX_BUF_DP<4>")
	)
	(segment
		(start 325.060818 -410.116528)
		(end 324.668642 -410.284422)
		(width 0.14224)
		(layer "In13.Cu")
		(net "P5E_CPU0_P1_RX_BUF_DP<4>")
	)
	(segment
		(start 334.621124 -406.659588)
		(end 333.713074 -406.960324)
		(width 0.14224)
		(layer "In13.Cu")
		(net "P5E_CPU0_P1_RX_BUF_DP<4>")
	)
	(segment
		(start 322.987162 -411.00502)
		(end 322.594986 -411.172914)
		(width 0.14224)
		(layer "In13.Cu")
		(net "P5E_CPU0_P1_RX_BUF_DP<4>")
	)
	(segment
		(start 329.521566 -408.348434)
		(end 329.11669 -408.482546)
		(width 0.14224)
		(layer "In13.Cu")
		(net "P5E_CPU0_P1_RX_BUF_DP<4>")
	)
	(segment
		(start 318.787526 -422.105328)
		(end 320.065146 -422.959784)
		(width 0.14224)
		(layer "In13.Cu")
		(net "P5E_CPU0_P1_RX_BUF_DP<4>")
	)
	(segment
		(start 323.559678 -410.909008)
		(end 323.167248 -411.076902)
		(width 0.14224)
		(layer "In13.Cu")
		(net "P5E_CPU0_P1_RX_BUF_DP<4>")
	)
	(segment
		(start 321.470782 -411.933644)
		(end 321.405758 -411.998668)
		(width 0.14224)
		(layer "In13.Cu")
		(net "P5E_CPU0_P1_RX_BUF_DP<4>")
	)
	(segment
		(start 329.695048 -408.435556)
		(end 329.521566 -408.348434)
		(width 0.14224)
		(layer "In13.Cu")
		(net "P5E_CPU0_P1_RX_BUF_DP<4>")
	)
	(segment
		(start 319.682876 -415.020252)
		(end 319.682876 -416.00755)
		(width 0.14224)
		(layer "In13.Cu")
		(net "P5E_CPU0_P1_RX_BUF_DP<4>")
	)
	(segment
		(start 330.765658 -408.080972)
		(end 330.592176 -407.99385)
		(width 0.14224)
		(layer "In13.Cu")
		(net "P5E_CPU0_P1_RX_BUF_DP<4>")
	)
	(segment
		(start 322.649596 -433.621942)
		(end 322.649596 -433.289964)
		(width 0.14224)
		(layer "In13.Cu")
		(net "P5E_CPU0_P1_RX_BUF_DP<4>")
	)
	(segment
		(start 324.204076 -410.632656)
		(end 324.02399 -410.560774)
		(width 0.14224)
		(layer "In13.Cu")
		(net "P5E_CPU0_P1_RX_BUF_DP<4>")
	)
	(segment
		(start 337.870546 -405.865838)
		(end 336.890614 -406.060656)
		(width 0.14224)
		(layer "In13.Cu")
		(net "P5E_CPU0_P1_RX_BUF_DP<4>")
	)
	(segment
		(start 319.820036 -416.57143)
		(end 319.682876 -416.70859)
		(width 0.14224)
		(layer "In13.Cu")
		(net "P5E_CPU0_P1_RX_BUF_DP<4>")
	)
	(segment
		(start 324.668642 -410.284422)
		(end 324.596506 -410.464762)
		(width 0.14224)
		(layer "In13.Cu")
		(net "P5E_CPU0_P1_RX_BUF_DP<4>")
	)
	(segment
		(start 339.083396 -405.155908)
		(end 338.265516 -405.702262)
		(width 0.14224)
		(layer "In13.Cu")
		(net "P5E_CPU0_P1_RX_BUF_DP<4>")
	)
	(segment
		(start 320.255392 -422.921938)
		(end 320.61023 -423.159428)
		(width 0.14224)
		(layer "In13.Cu")
		(net "P5E_CPU0_P1_RX_BUF_DP<4>")
	)
	(segment
		(start 341.144098 -401.526756)
		(end 341.017098 -401.399756)
		(width 0.14224)
		(layer "In13.Cu")
		(net "P5E_CPU0_P1_RX_BUF_DP<4>")
	)
	(segment
		(start 341.144098 -401.674838)
		(end 341.144098 -401.526756)
		(width 0.14224)
		(layer "In13.Cu")
		(net "P5E_CPU0_P1_RX_BUF_DP<4>")
	)
	(segment
		(start 319.820036 -416.14471)
		(end 319.820036 -416.57143)
		(width 0.14224)
		(layer "In13.Cu")
		(net "P5E_CPU0_P1_RX_BUF_DP<4>")
	)
	(segment
		(start 330.100432 -408.301444)
		(end 329.695048 -408.435556)
		(width 0.14224)
		(layer "In13.Cu")
		(net "P5E_CPU0_P1_RX_BUF_DP<4>")
	)
	(segment
		(start 318.151256 -420.22776)
		(end 318.151256 -421.218106)
		(width 0.14224)
		(layer "In13.Cu")
		(net "P5E_CPU0_P1_RX_BUF_DP<4>")
	)
	(segment
		(start 323.167248 -411.076902)
		(end 322.987162 -411.00502)
		(width 0.14224)
		(layer "In13.Cu")
		(net "P5E_CPU0_P1_RX_BUF_DP<4>")
	)
	(segment
		(start 340.68512 -403.151594)
		(end 340.495382 -403.609556)
		(width 0.14224)
		(layer "In13.Cu")
		(net "P5E_CPU0_P1_RX_BUF_DP<4>")
	)
	(segment
		(start 331.171042 -407.94686)
		(end 330.765658 -408.080972)
		(width 0.14224)
		(layer "In13.Cu")
		(net "P5E_CPU0_P1_RX_BUF_DP<4>")
	)
	(segment
		(start 340.224872 -404.014432)
		(end 339.083396 -405.155908)
		(width 0.14224)
		(layer "In13.Cu")
		(net "P5E_CPU0_P1_RX_BUF_DP<4>")
	)
	(segment
		(start 322.100448 -433.748942)
		(end 322.522596 -433.748942)
		(width 0.14224)
		(layer "In13.Cu")
		(net "P5E_CPU0_P1_RX_BUF_DP<4>")
	)
	(segment
		(start 333.04734 -407.180796)
		(end 331.25791 -407.773378)
		(width 0.14224)
		(layer "In13.Cu")
		(net "P5E_CPU0_P1_RX_BUF_DP<4>")
	)
	(segment
		(start 320.648076 -423.349674)
		(end 321.00266 -423.58691)
		(width 0.14224)
		(layer "In13.Cu")
		(net "P5E_CPU0_P1_RX_BUF_DP<4>")
	)
	(segment
		(start 341.017098 -401.399756)
		(end 340.82736 -401.399756)
		(width 0.14224)
		(layer "In13.Cu")
		(net "P5E_CPU0_P1_RX_BUF_DP<4>")
	)
	(segment
		(start 319.820036 -417.315904)
		(end 319.820036 -417.742624)
		(width 0.14224)
		(layer "In13.Cu")
		(net "P5E_CPU0_P1_RX_BUF_DP<4>")
	)
	(segment
		(start 330.592176 -407.99385)
		(end 330.1873 -408.127962)
		(width 0.14224)
		(layer "In13.Cu")
		(net "P5E_CPU0_P1_RX_BUF_DP<4>")
	)
	(segment
		(start 340.82736 -401.399756)
		(end 340.68512 -401.541996)
		(width 0.14224)
		(layer "In13.Cu")
		(net "P5E_CPU0_P1_RX_BUF_DP<4>")
	)
	(segment
		(start 326.097646 -409.672282)
		(end 325.70547 -409.840176)
		(width 0.14224)
		(layer "In13.Cu")
		(net "P5E_CPU0_P1_RX_BUF_DP<4>")
	)
	(arc
		(start 322.594986 -411.172914)
		(mid 321.996585 -411.499634)
		(end 321.470782 -411.933644)
		(width 0.14224)
		(layer "In13.Cu")
		(net "P5E_CPU0_P1_RX_BUF_DP<4>")
	)
	(arc
		(start 321.214496 -413.306514)
		(mid 321.161882 -413.571111)
		(end 321.012058 -413.795464)
		(width 0.14224)
		(layer "In13.Cu")
		(net "P5E_CPU0_P1_RX_BUF_DP<4>")
	)
	(arc
		(start 318.151256 -421.218106)
		(mid 318.160515 -421.292849)
		(end 318.187578 -421.36314)
		(width 0.14224)
		(layer "In13.Cu")
		(net "P5E_CPU0_P1_RX_BUF_DP<4>")
	)
	(arc
		(start 318.238886 -420.09695)
		(mid 318.175211 -420.149062)
		(end 318.151256 -420.22776)
		(width 0.14224)
		(layer "In13.Cu")
		(net "P5E_CPU0_P1_RX_BUF_DP<4>")
	)
	(arc
		(start 319.391792 -419.56482)
		(mid 319.298774 -419.643897)
		(end 319.191386 -419.70198)
		(width 0.14224)
		(layer "In13.Cu")
		(net "P5E_CPU0_P1_RX_BUF_DP<4>")
	)
	(arc
		(start 319.887854 -414.52546)
		(mid 319.736091 -414.752445)
		(end 319.682876 -415.020252)
		(width 0.14224)
		(layer "In13.Cu")
		(net "P5E_CPU0_P1_RX_BUF_DP<4>")
	)
	(arc
		(start 320.274188 -414.267142)
		(mid 320.068306 -414.377288)
		(end 319.887854 -414.52546)
		(width 0.14224)
		(layer "In13.Cu")
		(net "P5E_CPU0_P1_RX_BUF_DP<4>")
	)
	(arc
		(start 318.68872 -422.026334)
		(mid 318.736451 -422.067922)
		(end 318.787526 -422.105328)
		(width 0.14224)
		(layer "In13.Cu")
		(net "P5E_CPU0_P1_RX_BUF_DP<4>")
	)
	(arc
		(start 321.871086 -424.617642)
		(mid 321.94531 -424.760609)
		(end 321.970908 -424.919648)
		(width 0.14224)
		(layer "In13.Cu")
		(net "P5E_CPU0_P1_RX_BUF_DP<4>")
	)
	(arc
		(start 318.360552 -421.687498)
		(mid 318.394742 -421.74062)
		(end 318.437006 -421.787574)
		(width 0.14224)
		(layer "In13.Cu")
		(net "P5E_CPU0_P1_RX_BUF_DP<4>")
	)
	(arc
		(start 321.00266 -423.58691)
		(mid 321.192927 -423.739332)
		(end 321.35445 -423.921936)
		(width 0.14224)
		(layer "In13.Cu")
		(net "P5E_CPU0_P1_RX_BUF_DP<4>")
	)
	(arc
		(start 319.682876 -419.079172)
		(mid 319.650911 -419.24593)
		(end 319.559178 -419.388798)
		(width 0.14224)
		(layer "In13.Cu")
		(net "P5E_CPU0_P1_RX_BUF_DP<4>")
	)
	(arc
		(start 321.405758 -411.998668)
		(mid 321.264196 -412.210531)
		(end 321.214496 -412.46044)
		(width 0.14224)
		(layer "In13.Cu")
		(net "P5E_CPU0_P1_RX_BUF_DP<4>")
	)
	(segment
		(start 339.245448 -399.663158)
		(end 339.33003 -399.74774)
		(width 0.1016)
		(layer "F.Cu")
		(net "P5E_CPU0_P1_RX_BUF_DP<3>")
	)
	(segment
		(start 339.33003 -399.870676)
		(end 339.254592 -399.946114)
		(width 0.1016)
		(layer "F.Cu")
		(net "P5E_CPU0_P1_RX_BUF_DP<3>")
	)
	(segment
		(start 339.805264 -401.359116)
		(end 339.943948 -401.4978)
		(width 0.1016)
		(layer "F.Cu")
		(net "P5E_CPU0_P1_RX_BUF_DP<3>")
	)
	(segment
		(start 339.50783 -401.359116)
		(end 339.805264 -401.359116)
		(width 0.1016)
		(layer "F.Cu")
		(net "P5E_CPU0_P1_RX_BUF_DP<3>")
	)
	(segment
		(start 339.254592 -399.946114)
		(end 339.254592 -401.105878)
		(width 0.1016)
		(layer "F.Cu")
		(net "P5E_CPU0_P1_RX_BUF_DP<3>")
	)
	(segment
		(start 339.33003 -399.74774)
		(end 339.33003 -399.870676)
		(width 0.1016)
		(layer "F.Cu")
		(net "P5E_CPU0_P1_RX_BUF_DP<3>")
	)
	(segment
		(start 339.943948 -401.4978)
		(end 339.943948 -401.674838)
		(width 0.1016)
		(layer "F.Cu")
		(net "P5E_CPU0_P1_RX_BUF_DP<3>")
	)
	(segment
		(start 339.254592 -401.105878)
		(end 339.50783 -401.359116)
		(width 0.1016)
		(layer "F.Cu")
		(net "P5E_CPU0_P1_RX_BUF_DP<3>")
	)
	(segment
		(start 316.756796 -417.824158)
		(end 316.619636 -417.961318)
		(width 0.14224)
		(layer "In13.Cu")
		(net "P5E_CPU0_P1_RX_BUF_DP<3>")
	)
	(segment
		(start 338.203794 -404.55723)
		(end 337.493356 -404.914862)
		(width 0.14224)
		(layer "In13.Cu")
		(net "P5E_CPU0_P1_RX_BUF_DP<3>")
	)
	(segment
		(start 339.48497 -403.022816)
		(end 339.348572 -403.352254)
		(width 0.14224)
		(layer "In13.Cu")
		(net "P5E_CPU0_P1_RX_BUF_DP<3>")
	)
	(segment
		(start 317.411608 -422.726612)
		(end 317.913512 -423.061892)
		(width 0.14224)
		(layer "In13.Cu")
		(net "P5E_CPU0_P1_RX_BUF_DP<3>")
	)
	(segment
		(start 319.6971 -411.004512)
		(end 319.618868 -411.182312)
		(width 0.14224)
		(layer "In13.Cu")
		(net "P5E_CPU0_P1_RX_BUF_DP<3>")
	)
	(segment
		(start 317.948818 -413.795464)
		(end 317.802006 -413.942276)
		(width 0.14224)
		(layer "In13.Cu")
		(net "P5E_CPU0_P1_RX_BUF_DP<3>")
	)
	(segment
		(start 316.619636 -416.833558)
		(end 316.619636 -417.260278)
		(width 0.14224)
		(layer "In13.Cu")
		(net "P5E_CPU0_P1_RX_BUF_DP<3>")
	)
	(segment
		(start 317.802006 -413.942276)
		(end 317.486538 -414.153096)
		(width 0.14224)
		(layer "In13.Cu")
		(net "P5E_CPU0_P1_RX_BUF_DP<3>")
	)
	(segment
		(start 339.48497 -401.541996)
		(end 339.48497 -403.022816)
		(width 0.14224)
		(layer "In13.Cu")
		(net "P5E_CPU0_P1_RX_BUF_DP<3>")
	)
	(segment
		(start 315.088016 -420.250112)
		(end 315.088016 -421.43426)
		(width 0.14224)
		(layer "In13.Cu")
		(net "P5E_CPU0_P1_RX_BUF_DP<3>")
	)
	(segment
		(start 333.942944 -405.850852)
		(end 328.12863 -407.731976)
		(width 0.14224)
		(layer "In13.Cu")
		(net "P5E_CPU0_P1_RX_BUF_DP<3>")
	)
	(segment
		(start 320.670428 -410.774134)
		(end 320.272156 -410.928566)
		(width 0.14224)
		(layer "In13.Cu")
		(net "P5E_CPU0_P1_RX_BUF_DP<3>")
	)
	(segment
		(start 316.109604 -419.7096)
		(end 315.195712 -420.088568)
		(width 0.14224)
		(layer "In13.Cu")
		(net "P5E_CPU0_P1_RX_BUF_DP<3>")
	)
	(segment
		(start 316.3697 -422.294812)
		(end 316.54877 -422.220644)
		(width 0.14224)
		(layer "In13.Cu")
		(net "P5E_CPU0_P1_RX_BUF_DP<3>")
	)
	(segment
		(start 322.85178 -409.779978)
		(end 322.773548 -409.957778)
		(width 0.14224)
		(layer "In13.Cu")
		(net "P5E_CPU0_P1_RX_BUF_DP<3>")
	)
	(segment
		(start 315.136276 -421.550846)
		(end 315.53404 -421.948864)
		(width 0.14224)
		(layer "In13.Cu")
		(net "P5E_CPU0_P1_RX_BUF_DP<3>")
	)
	(segment
		(start 319.220596 -411.336744)
		(end 319.043304 -411.258512)
		(width 0.14224)
		(layer "In13.Cu")
		(net "P5E_CPU0_P1_RX_BUF_DP<3>")
	)
	(segment
		(start 321.80022 -410.188156)
		(end 321.721988 -410.365956)
		(width 0.14224)
		(layer "In13.Cu")
		(net "P5E_CPU0_P1_RX_BUF_DP<3>")
	)
	(segment
		(start 319.043304 -411.258512)
		(end 318.64554 -411.41269)
		(width 0.14224)
		(layer "In13.Cu")
		(net "P5E_CPU0_P1_RX_BUF_DP<3>")
	)
	(segment
		(start 323.426836 -409.704032)
		(end 323.249544 -409.6258)
		(width 0.14224)
		(layer "In13.Cu")
		(net "P5E_CPU0_P1_RX_BUF_DP<3>")
	)
	(segment
		(start 320.5226 -434.74894)
		(end 320.6496 -434.62194)
		(width 0.14224)
		(layer "In13.Cu")
		(net "P5E_CPU0_P1_RX_BUF_DP<3>")
	)
	(segment
		(start 316.619636 -416.132518)
		(end 316.756796 -416.269678)
		(width 0.14224)
		(layer "In13.Cu")
		(net "P5E_CPU0_P1_RX_BUF_DP<3>")
	)
	(segment
		(start 319.618868 -411.182312)
		(end 319.220596 -411.336744)
		(width 0.14224)
		(layer "In13.Cu")
		(net "P5E_CPU0_P1_RX_BUF_DP<3>")
	)
	(segment
		(start 319.602866 -424.517312)
		(end 319.913762 -425.099226)
		(width 0.14224)
		(layer "In13.Cu")
		(net "P5E_CPU0_P1_RX_BUF_DP<3>")
	)
	(segment
		(start 318.45885 -423.261282)
		(end 318.496696 -423.451528)
		(width 0.14224)
		(layer "In13.Cu")
		(net "P5E_CPU0_P1_RX_BUF_DP<3>")
	)
	(segment
		(start 320.6496 -434.62194)
		(end 320.6496 -434.289962)
		(width 0.14224)
		(layer "In13.Cu")
		(net "P5E_CPU0_P1_RX_BUF_DP<3>")
	)
	(segment
		(start 315.53404 -421.948864)
		(end 316.3697 -422.294812)
		(width 0.14224)
		(layer "In13.Cu")
		(net "P5E_CPU0_P1_RX_BUF_DP<3>")
	)
	(segment
		(start 316.619636 -415.020252)
		(end 316.619636 -416.132518)
		(width 0.14224)
		(layer "In13.Cu")
		(net "P5E_CPU0_P1_RX_BUF_DP<3>")
	)
	(segment
		(start 323.90334 -409.3718)
		(end 323.825108 -409.5496)
		(width 0.14224)
		(layer "In13.Cu")
		(net "P5E_CPU0_P1_RX_BUF_DP<3>")
	)
	(segment
		(start 319.970912 -434.544724)
		(end 320.175128 -434.74894)
		(width 0.14224)
		(layer "In13.Cu")
		(net "P5E_CPU0_P1_RX_BUF_DP<3>")
	)
	(segment
		(start 339.040216 -403.813518)
		(end 338.53755 -404.316184)
		(width 0.14224)
		(layer "In13.Cu")
		(net "P5E_CPU0_P1_RX_BUF_DP<3>")
	)
	(segment
		(start 339.943948 -401.674838)
		(end 339.943948 -401.526756)
		(width 0.14224)
		(layer "In13.Cu")
		(net "P5E_CPU0_P1_RX_BUF_DP<3>")
	)
	(segment
		(start 318.612266 -411.434788)
		(end 318.31407 -411.70733)
		(width 0.14224)
		(layer "In13.Cu")
		(net "P5E_CPU0_P1_RX_BUF_DP<3>")
	)
	(segment
		(start 322.375276 -410.11221)
		(end 322.197984 -410.033978)
		(width 0.14224)
		(layer "In13.Cu")
		(net "P5E_CPU0_P1_RX_BUF_DP<3>")
	)
	(segment
		(start 318.151256 -412.106872)
		(end 318.151256 -413.306514)
		(width 0.14224)
		(layer "In13.Cu")
		(net "P5E_CPU0_P1_RX_BUF_DP<3>")
	)
	(segment
		(start 317.913512 -423.061892)
		(end 318.103758 -423.024046)
		(width 0.14224)
		(layer "In13.Cu")
		(net "P5E_CPU0_P1_RX_BUF_DP<3>")
	)
	(segment
		(start 316.943232 -422.383966)
		(end 317.0174 -422.563544)
		(width 0.14224)
		(layer "In13.Cu")
		(net "P5E_CPU0_P1_RX_BUF_DP<3>")
	)
	(segment
		(start 321.146424 -410.442156)
		(end 320.74866 -410.596334)
		(width 0.14224)
		(layer "In13.Cu")
		(net "P5E_CPU0_P1_RX_BUF_DP<3>")
	)
	(segment
		(start 321.323716 -410.520388)
		(end 321.146424 -410.442156)
		(width 0.14224)
		(layer "In13.Cu")
		(net "P5E_CPU0_P1_RX_BUF_DP<3>")
	)
	(segment
		(start 328.12863 -407.731976)
		(end 324.9549 -408.963622)
		(width 0.14224)
		(layer "In13.Cu")
		(net "P5E_CPU0_P1_RX_BUF_DP<3>")
	)
	(segment
		(start 321.721988 -410.365956)
		(end 321.323716 -410.520388)
		(width 0.14224)
		(layer "In13.Cu")
		(net "P5E_CPU0_P1_RX_BUF_DP<3>")
	)
	(segment
		(start 323.825108 -409.5496)
		(end 323.426836 -409.704032)
		(width 0.14224)
		(layer "In13.Cu")
		(net "P5E_CPU0_P1_RX_BUF_DP<3>")
	)
	(segment
		(start 319.970912 -425.326556)
		(end 319.970912 -434.544724)
		(width 0.14224)
		(layer "In13.Cu")
		(net "P5E_CPU0_P1_RX_BUF_DP<3>")
	)
	(segment
		(start 316.46749 -419.45052)
		(end 316.29096 -419.59911)
		(width 0.14224)
		(layer "In13.Cu")
		(net "P5E_CPU0_P1_RX_BUF_DP<3>")
	)
	(segment
		(start 320.175128 -434.74894)
		(end 320.5226 -434.74894)
		(width 0.14224)
		(layer "In13.Cu")
		(net "P5E_CPU0_P1_RX_BUF_DP<3>")
	)
	(segment
		(start 324.9549 -408.963622)
		(end 324.876668 -409.141422)
		(width 0.14224)
		(layer "In13.Cu")
		(net "P5E_CPU0_P1_RX_BUF_DP<3>")
	)
	(segment
		(start 324.876668 -409.141422)
		(end 324.478396 -409.295854)
		(width 0.14224)
		(layer "In13.Cu")
		(net "P5E_CPU0_P1_RX_BUF_DP<3>")
	)
	(segment
		(start 322.773548 -409.957778)
		(end 322.375276 -410.11221)
		(width 0.14224)
		(layer "In13.Cu")
		(net "P5E_CPU0_P1_RX_BUF_DP<3>")
	)
	(segment
		(start 324.301104 -409.217622)
		(end 323.90334 -409.3718)
		(width 0.14224)
		(layer "In13.Cu")
		(net "P5E_CPU0_P1_RX_BUF_DP<3>")
	)
	(segment
		(start 318.103758 -423.024046)
		(end 318.45885 -423.261282)
		(width 0.14224)
		(layer "In13.Cu")
		(net "P5E_CPU0_P1_RX_BUF_DP<3>")
	)
	(segment
		(start 316.619636 -417.961318)
		(end 316.619636 -419.123876)
		(width 0.14224)
		(layer "In13.Cu")
		(net "P5E_CPU0_P1_RX_BUF_DP<3>")
	)
	(segment
		(start 339.943948 -401.526756)
		(end 339.816948 -401.399756)
		(width 0.14224)
		(layer "In13.Cu")
		(net "P5E_CPU0_P1_RX_BUF_DP<3>")
	)
	(segment
		(start 339.816948 -401.399756)
		(end 339.62721 -401.399756)
		(width 0.14224)
		(layer "In13.Cu")
		(net "P5E_CPU0_P1_RX_BUF_DP<3>")
	)
	(segment
		(start 320.74866 -410.596334)
		(end 320.670428 -410.774134)
		(width 0.14224)
		(layer "In13.Cu")
		(net "P5E_CPU0_P1_RX_BUF_DP<3>")
	)
	(segment
		(start 316.756796 -416.269678)
		(end 316.756796 -416.696398)
		(width 0.14224)
		(layer "In13.Cu")
		(net "P5E_CPU0_P1_RX_BUF_DP<3>")
	)
	(segment
		(start 318.496696 -423.451528)
		(end 318.85128 -423.68851)
		(width 0.14224)
		(layer "In13.Cu")
		(net "P5E_CPU0_P1_RX_BUF_DP<3>")
	)
	(segment
		(start 322.197984 -410.033978)
		(end 321.80022 -410.188156)
		(width 0.14224)
		(layer "In13.Cu")
		(net "P5E_CPU0_P1_RX_BUF_DP<3>")
	)
	(segment
		(start 317.486538 -414.153096)
		(end 317.210948 -414.267142)
		(width 0.14224)
		(layer "In13.Cu")
		(net "P5E_CPU0_P1_RX_BUF_DP<3>")
	)
	(segment
		(start 339.62721 -401.399756)
		(end 339.48497 -401.541996)
		(width 0.14224)
		(layer "In13.Cu")
		(net "P5E_CPU0_P1_RX_BUF_DP<3>")
	)
	(segment
		(start 320.272156 -410.928566)
		(end 320.094864 -410.850334)
		(width 0.14224)
		(layer "In13.Cu")
		(net "P5E_CPU0_P1_RX_BUF_DP<3>")
	)
	(segment
		(start 316.756796 -417.397438)
		(end 316.756796 -417.824158)
		(width 0.14224)
		(layer "In13.Cu")
		(net "P5E_CPU0_P1_RX_BUF_DP<3>")
	)
	(segment
		(start 337.493356 -404.914862)
		(end 333.942944 -405.850852)
		(width 0.14224)
		(layer "In13.Cu")
		(net "P5E_CPU0_P1_RX_BUF_DP<3>")
	)
	(segment
		(start 320.094864 -410.850334)
		(end 319.6971 -411.004512)
		(width 0.14224)
		(layer "In13.Cu")
		(net "P5E_CPU0_P1_RX_BUF_DP<3>")
	)
	(segment
		(start 315.088016 -421.43426)
		(end 315.136276 -421.550846)
		(width 0.14224)
		(layer "In13.Cu")
		(net "P5E_CPU0_P1_RX_BUF_DP<3>")
	)
	(segment
		(start 338.53755 -404.316184)
		(end 338.203794 -404.55723)
		(width 0.14224)
		(layer "In13.Cu")
		(net "P5E_CPU0_P1_RX_BUF_DP<3>")
	)
	(segment
		(start 324.478396 -409.295854)
		(end 324.301104 -409.217622)
		(width 0.14224)
		(layer "In13.Cu")
		(net "P5E_CPU0_P1_RX_BUF_DP<3>")
	)
	(segment
		(start 316.619636 -417.260278)
		(end 316.756796 -417.397438)
		(width 0.14224)
		(layer "In13.Cu")
		(net "P5E_CPU0_P1_RX_BUF_DP<3>")
	)
	(segment
		(start 317.0174 -422.563544)
		(end 317.411608 -422.726612)
		(width 0.14224)
		(layer "In13.Cu")
		(net "P5E_CPU0_P1_RX_BUF_DP<3>")
	)
	(segment
		(start 323.249544 -409.6258)
		(end 322.85178 -409.779978)
		(width 0.14224)
		(layer "In13.Cu")
		(net "P5E_CPU0_P1_RX_BUF_DP<3>")
	)
	(segment
		(start 316.756796 -416.696398)
		(end 316.619636 -416.833558)
		(width 0.14224)
		(layer "In13.Cu")
		(net "P5E_CPU0_P1_RX_BUF_DP<3>")
	)
	(segment
		(start 316.54877 -422.220644)
		(end 316.943232 -422.383966)
		(width 0.14224)
		(layer "In13.Cu")
		(net "P5E_CPU0_P1_RX_BUF_DP<3>")
	)
	(arc
		(start 318.31407 -411.70733)
		(mid 318.193568 -411.89117)
		(end 318.151256 -412.106872)
		(width 0.14224)
		(layer "In13.Cu")
		(net "P5E_CPU0_P1_RX_BUF_DP<3>")
	)
	(arc
		(start 316.29096 -419.59911)
		(mid 316.204529 -419.661325)
		(end 316.109604 -419.7096)
		(width 0.14224)
		(layer "In13.Cu")
		(net "P5E_CPU0_P1_RX_BUF_DP<3>")
	)
	(arc
		(start 315.195712 -420.088568)
		(mid 315.117408 -420.153036)
		(end 315.088016 -420.250112)
		(width 0.14224)
		(layer "In13.Cu")
		(net "P5E_CPU0_P1_RX_BUF_DP<3>")
	)
	(arc
		(start 318.64554 -411.41269)
		(mid 318.628034 -411.422429)
		(end 318.612266 -411.434788)
		(width 0.14224)
		(layer "In13.Cu")
		(net "P5E_CPU0_P1_RX_BUF_DP<3>")
	)
	(arc
		(start 318.151256 -413.306514)
		(mid 318.098642 -413.571111)
		(end 317.948818 -413.795464)
		(width 0.14224)
		(layer "In13.Cu")
		(net "P5E_CPU0_P1_RX_BUF_DP<3>")
	)
	(arc
		(start 339.348572 -403.352254)
		(mid 339.217099 -403.598063)
		(end 339.040216 -403.813518)
		(width 0.14224)
		(layer "In13.Cu")
		(net "P5E_CPU0_P1_RX_BUF_DP<3>")
	)
	(arc
		(start 316.619636 -419.123876)
		(mid 316.579681 -419.30402)
		(end 316.46749 -419.45052)
		(width 0.14224)
		(layer "In13.Cu")
		(net "P5E_CPU0_P1_RX_BUF_DP<3>")
	)
	(arc
		(start 317.210948 -414.267142)
		(mid 317.005066 -414.377288)
		(end 316.824614 -414.52546)
		(width 0.14224)
		(layer "In13.Cu")
		(net "P5E_CPU0_P1_RX_BUF_DP<3>")
	)
	(arc
		(start 319.913762 -425.099226)
		(mid 319.956356 -425.209368)
		(end 319.970912 -425.326556)
		(width 0.14224)
		(layer "In13.Cu")
		(net "P5E_CPU0_P1_RX_BUF_DP<3>")
	)
	(arc
		(start 316.824614 -414.52546)
		(mid 316.672851 -414.752445)
		(end 316.619636 -415.020252)
		(width 0.14224)
		(layer "In13.Cu")
		(net "P5E_CPU0_P1_RX_BUF_DP<3>")
	)
	(arc
		(start 318.85128 -423.68851)
		(mid 319.27816 -424.056585)
		(end 319.602866 -424.517312)
		(width 0.14224)
		(layer "In13.Cu")
		(net "P5E_CPU0_P1_RX_BUF_DP<3>")
	)
	(segment
		(start 338.294726 -401.359116)
		(end 338.605368 -401.359116)
		(width 0.1016)
		(layer "F.Cu")
		(net "P5E_CPU0_P1_RX_BUF_DP<2>")
	)
	(segment
		(start 338.130134 -399.74774)
		(end 338.130134 -399.870676)
		(width 0.1016)
		(layer "F.Cu")
		(net "P5E_CPU0_P1_RX_BUF_DP<2>")
	)
	(segment
		(start 338.041488 -399.959322)
		(end 338.041488 -401.105878)
		(width 0.1016)
		(layer "F.Cu")
		(net "P5E_CPU0_P1_RX_BUF_DP<2>")
	)
	(segment
		(start 338.041488 -401.105878)
		(end 338.294726 -401.359116)
		(width 0.1016)
		(layer "F.Cu")
		(net "P5E_CPU0_P1_RX_BUF_DP<2>")
	)
	(segment
		(start 338.130134 -399.870676)
		(end 338.041488 -399.959322)
		(width 0.1016)
		(layer "F.Cu")
		(net "P5E_CPU0_P1_RX_BUF_DP<2>")
	)
	(segment
		(start 338.605368 -401.359116)
		(end 338.744052 -401.4978)
		(width 0.1016)
		(layer "F.Cu")
		(net "P5E_CPU0_P1_RX_BUF_DP<2>")
	)
	(segment
		(start 338.744052 -401.4978)
		(end 338.744052 -401.674838)
		(width 0.1016)
		(layer "F.Cu")
		(net "P5E_CPU0_P1_RX_BUF_DP<2>")
	)
	(segment
		(start 338.045552 -399.663158)
		(end 338.130134 -399.74774)
		(width 0.1016)
		(layer "F.Cu")
		(net "P5E_CPU0_P1_RX_BUF_DP<2>")
	)
	(segment
		(start 337.742022 -403.67966)
		(end 337.227418 -403.954996)
		(width 0.14224)
		(layer "In13.Cu")
		(net "P5E_CPU0_P1_RX_BUF_DP<2>")
	)
	(segment
		(start 323.664072 -408.46375)
		(end 323.485764 -408.387804)
		(width 0.14224)
		(layer "In13.Cu")
		(net "P5E_CPU0_P1_RX_BUF_DP<2>")
	)
	(segment
		(start 313.693556 -416.81146)
		(end 313.556396 -416.94862)
		(width 0.14224)
		(layer "In13.Cu")
		(net "P5E_CPU0_P1_RX_BUF_DP<2>")
	)
	(segment
		(start 324.710298 -408.042618)
		(end 324.53199 -407.966418)
		(width 0.14224)
		(layer "In13.Cu")
		(net "P5E_CPU0_P1_RX_BUF_DP<2>")
	)
	(segment
		(start 312.024776 -420.537386)
		(end 312.024776 -421.316912)
		(width 0.14224)
		(layer "In13.Cu")
		(net "P5E_CPU0_P1_RX_BUF_DP<2>")
	)
	(segment
		(start 315.18606 -411.933136)
		(end 315.121544 -412.165546)
		(width 0.14224)
		(layer "In13.Cu")
		(net "P5E_CPU0_P1_RX_BUF_DP<2>")
	)
	(segment
		(start 326.7456 -407.075132)
		(end 326.669654 -407.253948)
		(width 0.14224)
		(layer "In13.Cu")
		(net "P5E_CPU0_P1_RX_BUF_DP<2>")
	)
	(segment
		(start 313.693556 -416.38474)
		(end 313.693556 -416.81146)
		(width 0.14224)
		(layer "In13.Cu")
		(net "P5E_CPU0_P1_RX_BUF_DP<2>")
	)
	(segment
		(start 338.285074 -403.018752)
		(end 338.03717 -403.482556)
		(width 0.14224)
		(layer "In13.Cu")
		(net "P5E_CPU0_P1_RX_BUF_DP<2>")
	)
	(segment
		(start 317.018924 -423.806366)
		(end 317.735966 -424.555666)
		(width 0.14224)
		(layer "In13.Cu")
		(net "P5E_CPU0_P1_RX_BUF_DP<2>")
	)
	(segment
		(start 316.278006 -411.289754)
		(end 315.57722 -411.571694)
		(width 0.14224)
		(layer "In13.Cu")
		(net "P5E_CPU0_P1_RX_BUF_DP<2>")
	)
	(segment
		(start 332.64602 -405.249888)
		(end 332.478126 -405.153114)
		(width 0.14224)
		(layer "In13.Cu")
		(net "P5E_CPU0_P1_RX_BUF_DP<2>")
	)
	(segment
		(start 328.410316 -406.552908)
		(end 328.014076 -406.71242)
		(width 0.14224)
		(layer "In13.Cu")
		(net "P5E_CPU0_P1_RX_BUF_DP<2>")
	)
	(segment
		(start 315.088016 -412.410656)
		(end 315.088016 -413.306514)
		(width 0.14224)
		(layer "In13.Cu")
		(net "P5E_CPU0_P1_RX_BUF_DP<2>")
	)
	(segment
		(start 327.835768 -406.636474)
		(end 326.7456 -407.075132)
		(width 0.14224)
		(layer "In13.Cu")
		(net "P5E_CPU0_P1_RX_BUF_DP<2>")
	)
	(segment
		(start 317.970916 -425.141136)
		(end 317.970916 -433.59959)
		(width 0.14224)
		(layer "In13.Cu")
		(net "P5E_CPU0_P1_RX_BUF_DP<2>")
	)
	(segment
		(start 316.13983 -423.230294)
		(end 316.213998 -423.409618)
		(width 0.14224)
		(layer "In13.Cu")
		(net "P5E_CPU0_P1_RX_BUF_DP<2>")
	)
	(segment
		(start 313.556396 -418.07638)
		(end 313.556396 -418.933122)
		(width 0.14224)
		(layer "In13.Cu")
		(net "P5E_CPU0_P1_RX_BUF_DP<2>")
	)
	(segment
		(start 312.35523 -419.981126)
		(end 312.167778 -420.178738)
		(width 0.14224)
		(layer "In13.Cu")
		(net "P5E_CPU0_P1_RX_BUF_DP<2>")
	)
	(segment
		(start 324.53199 -407.966418)
		(end 324.136258 -408.125676)
		(width 0.14224)
		(layer "In13.Cu")
		(net "P5E_CPU0_P1_RX_BUF_DP<2>")
	)
	(segment
		(start 313.693556 -417.5125)
		(end 313.693556 -417.93922)
		(width 0.14224)
		(layer "In13.Cu")
		(net "P5E_CPU0_P1_RX_BUF_DP<2>")
	)
	(segment
		(start 328.486262 -406.374346)
		(end 328.410316 -406.552908)
		(width 0.14224)
		(layer "In13.Cu")
		(net "P5E_CPU0_P1_RX_BUF_DP<2>")
	)
	(segment
		(start 333.058516 -405.13889)
		(end 332.64602 -405.249888)
		(width 0.14224)
		(layer "In13.Cu")
		(net "P5E_CPU0_P1_RX_BUF_DP<2>")
	)
	(segment
		(start 335.285334 -404.459186)
		(end 333.676752 -404.830534)
		(width 0.14224)
		(layer "In13.Cu")
		(net "P5E_CPU0_P1_RX_BUF_DP<2>")
	)
	(segment
		(start 315.097668 -422.798494)
		(end 315.171836 -422.978072)
		(width 0.14224)
		(layer "In13.Cu")
		(net "P5E_CPU0_P1_RX_BUF_DP<2>")
	)
	(segment
		(start 331.003402 -405.691594)
		(end 330.835508 -405.59482)
		(width 0.14224)
		(layer "In13.Cu")
		(net "P5E_CPU0_P1_RX_BUF_DP<2>")
	)
	(segment
		(start 314.885578 -413.795464)
		(end 314.738766 -413.942276)
		(width 0.14224)
		(layer "In13.Cu")
		(net "P5E_CPU0_P1_RX_BUF_DP<2>")
	)
	(segment
		(start 316.456314 -411.3657)
		(end 316.278006 -411.289754)
		(width 0.14224)
		(layer "In13.Cu")
		(net "P5E_CPU0_P1_RX_BUF_DP<2>")
	)
	(segment
		(start 326.094852 -407.33726)
		(end 325.182484 -407.704544)
		(width 0.14224)
		(layer "In13.Cu")
		(net "P5E_CPU0_P1_RX_BUF_DP<2>")
	)
	(segment
		(start 312.729118 -419.797992)
		(end 312.458608 -419.910006)
		(width 0.14224)
		(layer "In13.Cu")
		(net "P5E_CPU0_P1_RX_BUF_DP<2>")
	)
	(segment
		(start 313.693556 -417.93922)
		(end 313.556396 -418.07638)
		(width 0.14224)
		(layer "In13.Cu")
		(net "P5E_CPU0_P1_RX_BUF_DP<2>")
	)
	(segment
		(start 325.182484 -407.704544)
		(end 325.106538 -407.883106)
		(width 0.14224)
		(layer "In13.Cu")
		(net "P5E_CPU0_P1_RX_BUF_DP<2>")
	)
	(segment
		(start 316.213998 -423.409618)
		(end 316.784228 -423.645838)
		(width 0.14224)
		(layer "In13.Cu")
		(net "P5E_CPU0_P1_RX_BUF_DP<2>")
	)
	(segment
		(start 316.852554 -411.206442)
		(end 316.456314 -411.3657)
		(width 0.14224)
		(layer "In13.Cu")
		(net "P5E_CPU0_P1_RX_BUF_DP<2>")
	)
	(segment
		(start 313.556396 -415.020252)
		(end 313.556396 -416.24758)
		(width 0.14224)
		(layer "In13.Cu")
		(net "P5E_CPU0_P1_RX_BUF_DP<2>")
	)
	(segment
		(start 332.478126 -405.153114)
		(end 331.512672 -405.412702)
		(width 0.14224)
		(layer "In13.Cu")
		(net "P5E_CPU0_P1_RX_BUF_DP<2>")
	)
	(segment
		(start 313.096656 -419.567614)
		(end 312.840878 -419.738302)
		(width 0.14224)
		(layer "In13.Cu")
		(net "P5E_CPU0_P1_RX_BUF_DP<2>")
	)
	(segment
		(start 329.593702 -405.928576)
		(end 328.486262 -406.374346)
		(width 0.14224)
		(layer "In13.Cu")
		(net "P5E_CPU0_P1_RX_BUF_DP<2>")
	)
	(segment
		(start 324.060312 -408.304492)
		(end 323.664072 -408.46375)
		(width 0.14224)
		(layer "In13.Cu")
		(net "P5E_CPU0_P1_RX_BUF_DP<2>")
	)
	(segment
		(start 318.120268 -433.748942)
		(end 318.522604 -433.748942)
		(width 0.14224)
		(layer "In13.Cu")
		(net "P5E_CPU0_P1_RX_BUF_DP<2>")
	)
	(segment
		(start 331.415898 -405.58085)
		(end 331.003402 -405.691594)
		(width 0.14224)
		(layer "In13.Cu")
		(net "P5E_CPU0_P1_RX_BUF_DP<2>")
	)
	(segment
		(start 314.523882 -422.70934)
		(end 314.703206 -422.635172)
		(width 0.14224)
		(layer "In13.Cu")
		(net "P5E_CPU0_P1_RX_BUF_DP<2>")
	)
	(segment
		(start 331.512672 -405.412702)
		(end 331.415898 -405.58085)
		(width 0.14224)
		(layer "In13.Cu")
		(net "P5E_CPU0_P1_RX_BUF_DP<2>")
	)
	(segment
		(start 337.227418 -403.954996)
		(end 336.921348 -404.081742)
		(width 0.14224)
		(layer "In13.Cu")
		(net "P5E_CPU0_P1_RX_BUF_DP<2>")
	)
	(segment
		(start 317.970916 -433.59959)
		(end 318.120268 -433.748942)
		(width 0.14224)
		(layer "In13.Cu")
		(net "P5E_CPU0_P1_RX_BUF_DP<2>")
	)
	(segment
		(start 323.485764 -408.387804)
		(end 316.9285 -411.027626)
		(width 0.14224)
		(layer "In13.Cu")
		(net "P5E_CPU0_P1_RX_BUF_DP<2>")
	)
	(segment
		(start 315.171836 -422.978072)
		(end 315.566044 -423.14114)
		(width 0.14224)
		(layer "In13.Cu")
		(net "P5E_CPU0_P1_RX_BUF_DP<2>")
	)
	(segment
		(start 315.468 -411.635194)
		(end 315.289692 -411.776926)
		(width 0.14224)
		(layer "In13.Cu")
		(net "P5E_CPU0_P1_RX_BUF_DP<2>")
	)
	(segment
		(start 338.744052 -401.674838)
		(end 338.744052 -401.526756)
		(width 0.14224)
		(layer "In13.Cu")
		(net "P5E_CPU0_P1_RX_BUF_DP<2>")
	)
	(segment
		(start 314.703206 -422.635172)
		(end 315.097668 -422.798494)
		(width 0.14224)
		(layer "In13.Cu")
		(net "P5E_CPU0_P1_RX_BUF_DP<2>")
	)
	(segment
		(start 318.649604 -433.621942)
		(end 318.649604 -433.289964)
		(width 0.14224)
		(layer "In13.Cu")
		(net "P5E_CPU0_P1_RX_BUF_DP<2>")
	)
	(segment
		(start 316.9285 -411.027626)
		(end 316.852554 -411.206442)
		(width 0.14224)
		(layer "In13.Cu")
		(net "P5E_CPU0_P1_RX_BUF_DP<2>")
	)
	(segment
		(start 312.636916 -422.026334)
		(end 313.320684 -422.22547)
		(width 0.14224)
		(layer "In13.Cu")
		(net "P5E_CPU0_P1_RX_BUF_DP<2>")
	)
	(segment
		(start 338.427314 -401.399756)
		(end 338.285074 -401.541996)
		(width 0.14224)
		(layer "In13.Cu")
		(net "P5E_CPU0_P1_RX_BUF_DP<2>")
	)
	(segment
		(start 330.835508 -405.59482)
		(end 329.593702 -405.928576)
		(width 0.14224)
		(layer "In13.Cu")
		(net "P5E_CPU0_P1_RX_BUF_DP<2>")
	)
	(segment
		(start 333.15529 -404.970742)
		(end 333.058516 -405.13889)
		(width 0.14224)
		(layer "In13.Cu")
		(net "P5E_CPU0_P1_RX_BUF_DP<2>")
	)
	(segment
		(start 338.285074 -401.541996)
		(end 338.285074 -403.018752)
		(width 0.14224)
		(layer "In13.Cu")
		(net "P5E_CPU0_P1_RX_BUF_DP<2>")
	)
	(segment
		(start 313.556396 -416.24758)
		(end 313.693556 -416.38474)
		(width 0.14224)
		(layer "In13.Cu")
		(net "P5E_CPU0_P1_RX_BUF_DP<2>")
	)
	(segment
		(start 313.547252 -422.304972)
		(end 314.523882 -422.70934)
		(width 0.14224)
		(layer "In13.Cu")
		(net "P5E_CPU0_P1_RX_BUF_DP<2>")
	)
	(segment
		(start 325.106538 -407.883106)
		(end 324.710298 -408.042618)
		(width 0.14224)
		(layer "In13.Cu")
		(net "P5E_CPU0_P1_RX_BUF_DP<2>")
	)
	(segment
		(start 314.423298 -414.153096)
		(end 314.147708 -414.267142)
		(width 0.14224)
		(layer "In13.Cu")
		(net "P5E_CPU0_P1_RX_BUF_DP<2>")
	)
	(segment
		(start 318.522604 -433.748942)
		(end 318.649604 -433.621942)
		(width 0.14224)
		(layer "In13.Cu")
		(net "P5E_CPU0_P1_RX_BUF_DP<2>")
	)
	(segment
		(start 312.267092 -421.787828)
		(end 312.523632 -421.971216)
		(width 0.14224)
		(layer "In13.Cu")
		(net "P5E_CPU0_P1_RX_BUF_DP<2>")
	)
	(segment
		(start 336.921348 -404.081742)
		(end 335.285334 -404.459186)
		(width 0.14224)
		(layer "In13.Cu")
		(net "P5E_CPU0_P1_RX_BUF_DP<2>")
	)
	(segment
		(start 314.738766 -413.942276)
		(end 314.423298 -414.153096)
		(width 0.14224)
		(layer "In13.Cu")
		(net "P5E_CPU0_P1_RX_BUF_DP<2>")
	)
	(segment
		(start 333.676752 -404.830534)
		(end 333.15529 -404.970742)
		(width 0.14224)
		(layer "In13.Cu")
		(net "P5E_CPU0_P1_RX_BUF_DP<2>")
	)
	(segment
		(start 326.669654 -407.253948)
		(end 326.273414 -407.413206)
		(width 0.14224)
		(layer "In13.Cu")
		(net "P5E_CPU0_P1_RX_BUF_DP<2>")
	)
	(segment
		(start 324.136258 -408.125676)
		(end 324.060312 -408.304492)
		(width 0.14224)
		(layer "In13.Cu")
		(net "P5E_CPU0_P1_RX_BUF_DP<2>")
	)
	(segment
		(start 313.42076 -419.260782)
		(end 313.194446 -419.48735)
		(width 0.14224)
		(layer "In13.Cu")
		(net "P5E_CPU0_P1_RX_BUF_DP<2>")
	)
	(segment
		(start 313.556396 -417.37534)
		(end 313.693556 -417.5125)
		(width 0.14224)
		(layer "In13.Cu")
		(net "P5E_CPU0_P1_RX_BUF_DP<2>")
	)
	(segment
		(start 326.273414 -407.413206)
		(end 326.094852 -407.33726)
		(width 0.14224)
		(layer "In13.Cu")
		(net "P5E_CPU0_P1_RX_BUF_DP<2>")
	)
	(segment
		(start 338.03717 -403.482556)
		(end 337.742022 -403.67966)
		(width 0.14224)
		(layer "In13.Cu")
		(net "P5E_CPU0_P1_RX_BUF_DP<2>")
	)
	(segment
		(start 338.744052 -401.526756)
		(end 338.617052 -401.399756)
		(width 0.14224)
		(layer "In13.Cu")
		(net "P5E_CPU0_P1_RX_BUF_DP<2>")
	)
	(segment
		(start 313.556396 -416.94862)
		(end 313.556396 -417.37534)
		(width 0.14224)
		(layer "In13.Cu")
		(net "P5E_CPU0_P1_RX_BUF_DP<2>")
	)
	(segment
		(start 328.014076 -406.71242)
		(end 327.835768 -406.636474)
		(width 0.14224)
		(layer "In13.Cu")
		(net "P5E_CPU0_P1_RX_BUF_DP<2>")
	)
	(segment
		(start 338.617052 -401.399756)
		(end 338.427314 -401.399756)
		(width 0.14224)
		(layer "In13.Cu")
		(net "P5E_CPU0_P1_RX_BUF_DP<2>")
	)
	(segment
		(start 315.745368 -423.066972)
		(end 316.13983 -423.230294)
		(width 0.14224)
		(layer "In13.Cu")
		(net "P5E_CPU0_P1_RX_BUF_DP<2>")
	)
	(segment
		(start 315.566044 -423.14114)
		(end 315.745368 -423.066972)
		(width 0.14224)
		(layer "In13.Cu")
		(net "P5E_CPU0_P1_RX_BUF_DP<2>")
	)
	(arc
		(start 313.194446 -419.48735)
		(mid 313.147531 -419.529894)
		(end 313.096656 -419.567614)
		(width 0.14224)
		(layer "In13.Cu")
		(net "P5E_CPU0_P1_RX_BUF_DP<2>")
	)
	(arc
		(start 312.458608 -419.910006)
		(mid 312.403167 -419.940116)
		(end 312.35523 -419.981126)
		(width 0.14224)
		(layer "In13.Cu")
		(net "P5E_CPU0_P1_RX_BUF_DP<2>")
	)
	(arc
		(start 312.523632 -421.971216)
		(mid 312.577946 -422.003559)
		(end 312.636916 -422.026334)
		(width 0.14224)
		(layer "In13.Cu")
		(net "P5E_CPU0_P1_RX_BUF_DP<2>")
	)
	(arc
		(start 312.167778 -420.178738)
		(mid 312.061787 -420.344318)
		(end 312.024776 -420.537386)
		(width 0.14224)
		(layer "In13.Cu")
		(net "P5E_CPU0_P1_RX_BUF_DP<2>")
	)
	(arc
		(start 315.088016 -413.306514)
		(mid 315.035402 -413.571111)
		(end 314.885578 -413.795464)
		(width 0.14224)
		(layer "In13.Cu")
		(net "P5E_CPU0_P1_RX_BUF_DP<2>")
	)
	(arc
		(start 312.024776 -421.316912)
		(mid 312.088899 -421.581725)
		(end 312.267092 -421.787828)
		(width 0.14224)
		(layer "In13.Cu")
		(net "P5E_CPU0_P1_RX_BUF_DP<2>")
	)
	(arc
		(start 314.147708 -414.267142)
		(mid 313.941826 -414.377288)
		(end 313.761374 -414.52546)
		(width 0.14224)
		(layer "In13.Cu")
		(net "P5E_CPU0_P1_RX_BUF_DP<2>")
	)
	(arc
		(start 313.761374 -414.52546)
		(mid 313.609611 -414.752445)
		(end 313.556396 -415.020252)
		(width 0.14224)
		(layer "In13.Cu")
		(net "P5E_CPU0_P1_RX_BUF_DP<2>")
	)
	(arc
		(start 317.735966 -424.555666)
		(mid 317.909936 -424.825729)
		(end 317.970916 -425.141136)
		(width 0.14224)
		(layer "In13.Cu")
		(net "P5E_CPU0_P1_RX_BUF_DP<2>")
	)
	(arc
		(start 316.784228 -423.645838)
		(mid 316.909915 -423.713907)
		(end 317.018924 -423.806366)
		(width 0.14224)
		(layer "In13.Cu")
		(net "P5E_CPU0_P1_RX_BUF_DP<2>")
	)
	(arc
		(start 315.121544 -412.165546)
		(mid 315.096448 -412.286961)
		(end 315.088016 -412.410656)
		(width 0.14224)
		(layer "In13.Cu")
		(net "P5E_CPU0_P1_RX_BUF_DP<2>")
	)
	(arc
		(start 313.556396 -418.933122)
		(mid 313.521145 -419.110432)
		(end 313.42076 -419.260782)
		(width 0.14224)
		(layer "In13.Cu")
		(net "P5E_CPU0_P1_RX_BUF_DP<2>")
	)
	(arc
		(start 315.57722 -411.571694)
		(mid 315.520326 -411.599512)
		(end 315.468 -411.635194)
		(width 0.14224)
		(layer "In13.Cu")
		(net "P5E_CPU0_P1_RX_BUF_DP<2>")
	)
	(arc
		(start 312.840878 -419.738302)
		(mid 312.786465 -419.770895)
		(end 312.729118 -419.797992)
		(width 0.14224)
		(layer "In13.Cu")
		(net "P5E_CPU0_P1_RX_BUF_DP<2>")
	)
	(arc
		(start 313.320684 -422.22547)
		(mid 313.435053 -422.262127)
		(end 313.547252 -422.304972)
		(width 0.14224)
		(layer "In13.Cu")
		(net "P5E_CPU0_P1_RX_BUF_DP<2>")
	)
	(arc
		(start 315.289692 -411.776926)
		(mid 315.225554 -411.846847)
		(end 315.18606 -411.933136)
		(width 0.14224)
		(layer "In13.Cu")
		(net "P5E_CPU0_P1_RX_BUF_DP<2>")
	)
	(segment
		(start 336.841338 -401.105878)
		(end 337.094576 -401.359116)
		(width 0.1016)
		(layer "F.Cu")
		(net "P5E_CPU0_P1_RX_BUF_DP<1>")
	)
	(segment
		(start 337.543902 -401.4978)
		(end 337.543902 -401.674838)
		(width 0.1016)
		(layer "F.Cu")
		(net "P5E_CPU0_P1_RX_BUF_DP<1>")
	)
	(segment
		(start 337.405218 -401.359116)
		(end 337.543902 -401.4978)
		(width 0.1016)
		(layer "F.Cu")
		(net "P5E_CPU0_P1_RX_BUF_DP<1>")
	)
	(segment
		(start 336.841338 -399.959322)
		(end 336.841338 -401.105878)
		(width 0.1016)
		(layer "F.Cu")
		(net "P5E_CPU0_P1_RX_BUF_DP<1>")
	)
	(segment
		(start 336.929984 -399.870676)
		(end 336.841338 -399.959322)
		(width 0.1016)
		(layer "F.Cu")
		(net "P5E_CPU0_P1_RX_BUF_DP<1>")
	)
	(segment
		(start 337.094576 -401.359116)
		(end 337.405218 -401.359116)
		(width 0.1016)
		(layer "F.Cu")
		(net "P5E_CPU0_P1_RX_BUF_DP<1>")
	)
	(segment
		(start 336.845402 -399.663158)
		(end 336.929984 -399.74774)
		(width 0.1016)
		(layer "F.Cu")
		(net "P5E_CPU0_P1_RX_BUF_DP<1>")
	)
	(segment
		(start 336.929984 -399.74774)
		(end 336.929984 -399.870676)
		(width 0.1016)
		(layer "F.Cu")
		(net "P5E_CPU0_P1_RX_BUF_DP<1>")
	)
	(segment
		(start 314.012834 -411.29331)
		(end 313.833764 -411.219142)
		(width 0.14224)
		(layer "In13.Cu")
		(net "P5E_CPU0_P1_RX_BUF_DP<1>")
	)
	(segment
		(start 315.95822 -425.196)
		(end 315.95822 -434.506116)
		(width 0.14224)
		(layer "In13.Cu")
		(net "P5E_CPU0_P1_RX_BUF_DP<1>")
	)
	(segment
		(start 324.558914 -406.782778)
		(end 323.890894 -407.05913)
		(width 0.14224)
		(layer "In13.Cu")
		(net "P5E_CPU0_P1_RX_BUF_DP<1>")
	)
	(segment
		(start 314.49518 -423.770552)
		(end 315.349382 -424.127422)
		(width 0.14224)
		(layer "In13.Cu")
		(net "P5E_CPU0_P1_RX_BUF_DP<1>")
	)
	(segment
		(start 309.971948 -422.358058)
		(end 310.146446 -422.273476)
		(width 0.14224)
		(layer "In13.Cu")
		(net "P5E_CPU0_P1_RX_BUF_DP<1>")
	)
	(segment
		(start 314.407296 -411.130242)
		(end 314.012834 -411.29331)
		(width 0.14224)
		(layer "In13.Cu")
		(net "P5E_CPU0_P1_RX_BUF_DP<1>")
	)
	(segment
		(start 311.360058 -414.153096)
		(end 311.084468 -414.267142)
		(width 0.14224)
		(layer "In13.Cu")
		(net "P5E_CPU0_P1_RX_BUF_DP<1>")
	)
	(segment
		(start 325.1327 -406.693878)
		(end 324.737984 -406.8572)
		(width 0.14224)
		(layer "In13.Cu")
		(net "P5E_CPU0_P1_RX_BUF_DP<1>")
	)
	(segment
		(start 314.481718 -410.950918)
		(end 314.407296 -411.130242)
		(width 0.14224)
		(layer "In13.Cu")
		(net "P5E_CPU0_P1_RX_BUF_DP<1>")
	)
	(segment
		(start 337.416902 -401.399756)
		(end 337.227164 -401.399756)
		(width 0.14224)
		(layer "In13.Cu")
		(net "P5E_CPU0_P1_RX_BUF_DP<1>")
	)
	(segment
		(start 337.084924 -401.541996)
		(end 337.084924 -402.88464)
		(width 0.14224)
		(layer "In13.Cu")
		(net "P5E_CPU0_P1_RX_BUF_DP<1>")
	)
	(segment
		(start 327.249282 -405.81834)
		(end 326.854566 -405.981408)
		(width 0.14224)
		(layer "In13.Cu")
		(net "P5E_CPU0_P1_RX_BUF_DP<1>")
	)
	(segment
		(start 313.929776 -423.604944)
		(end 314.341256 -423.71772)
		(width 0.14224)
		(layer "In13.Cu")
		(net "P5E_CPU0_P1_RX_BUF_DP<1>")
	)
	(segment
		(start 310.630316 -417.120578)
		(end 310.630316 -417.547298)
		(width 0.14224)
		(layer "In13.Cu")
		(net "P5E_CPU0_P1_RX_BUF_DP<1>")
	)
	(segment
		(start 311.822338 -413.795464)
		(end 311.675526 -413.942276)
		(width 0.14224)
		(layer "In13.Cu")
		(net "P5E_CPU0_P1_RX_BUF_DP<1>")
	)
	(segment
		(start 325.812404 -406.412446)
		(end 325.633334 -406.338278)
		(width 0.14224)
		(layer "In13.Cu")
		(net "P5E_CPU0_P1_RX_BUF_DP<1>")
	)
	(segment
		(start 327.984612 -405.37765)
		(end 327.827386 -405.430482)
		(width 0.14224)
		(layer "In13.Cu")
		(net "P5E_CPU0_P1_RX_BUF_DP<1>")
	)
	(segment
		(start 315.532516 -424.278044)
		(end 315.664596 -424.47591)
		(width 0.14224)
		(layer "In13.Cu")
		(net "P5E_CPU0_P1_RX_BUF_DP<1>")
	)
	(segment
		(start 313.833764 -411.219142)
		(end 312.398156 -411.81274)
		(width 0.14224)
		(layer "In13.Cu")
		(net "P5E_CPU0_P1_RX_BUF_DP<1>")
	)
	(segment
		(start 313.253628 -423.41927)
		(end 313.42203 -423.323258)
		(width 0.14224)
		(layer "In13.Cu")
		(net "P5E_CPU0_P1_RX_BUF_DP<1>")
	)
	(segment
		(start 311.675526 -413.942276)
		(end 311.360058 -414.153096)
		(width 0.14224)
		(layer "In13.Cu")
		(net "P5E_CPU0_P1_RX_BUF_DP<1>")
	)
	(segment
		(start 336.700876 -403.160992)
		(end 332.346808 -404.150576)
		(width 0.14224)
		(layer "In13.Cu")
		(net "P5E_CPU0_P1_RX_BUF_DP<1>")
	)
	(segment
		(start 326.206866 -406.249378)
		(end 325.812404 -406.412446)
		(width 0.14224)
		(layer "In13.Cu")
		(net "P5E_CPU0_P1_RX_BUF_DP<1>")
	)
	(segment
		(start 313.833764 -423.436288)
		(end 313.929776 -423.604944)
		(width 0.14224)
		(layer "In13.Cu")
		(net "P5E_CPU0_P1_RX_BUF_DP<1>")
	)
	(segment
		(start 337.543902 -401.674838)
		(end 337.543902 -401.526756)
		(width 0.14224)
		(layer "In13.Cu")
		(net "P5E_CPU0_P1_RX_BUF_DP<1>")
	)
	(segment
		(start 308.961536 -420.228014)
		(end 308.961536 -421.327326)
		(width 0.14224)
		(layer "In13.Cu")
		(net "P5E_CPU0_P1_RX_BUF_DP<1>")
	)
	(segment
		(start 327.32345 -405.638762)
		(end 327.249282 -405.81834)
		(width 0.14224)
		(layer "In13.Cu")
		(net "P5E_CPU0_P1_RX_BUF_DP<1>")
	)
	(segment
		(start 326.281288 -406.070054)
		(end 326.206866 -406.249378)
		(width 0.14224)
		(layer "In13.Cu")
		(net "P5E_CPU0_P1_RX_BUF_DP<1>")
	)
	(segment
		(start 310.630316 -416.349942)
		(end 310.493156 -416.487102)
		(width 0.14224)
		(layer "In13.Cu")
		(net "P5E_CPU0_P1_RX_BUF_DP<1>")
	)
	(segment
		(start 310.549798 -422.413684)
		(end 310.63438 -422.58869)
		(width 0.14224)
		(layer "In13.Cu")
		(net "P5E_CPU0_P1_RX_BUF_DP<1>")
	)
	(segment
		(start 325.207122 -406.514554)
		(end 325.1327 -406.693878)
		(width 0.14224)
		(layer "In13.Cu")
		(net "P5E_CPU0_P1_RX_BUF_DP<1>")
	)
	(segment
		(start 313.42203 -423.323258)
		(end 313.833764 -423.436288)
		(width 0.14224)
		(layer "In13.Cu")
		(net "P5E_CPU0_P1_RX_BUF_DP<1>")
	)
	(segment
		(start 323.421756 -407.401522)
		(end 323.242686 -407.327354)
		(width 0.14224)
		(layer "In13.Cu")
		(net "P5E_CPU0_P1_RX_BUF_DP<1>")
	)
	(segment
		(start 323.890894 -407.05913)
		(end 323.816472 -407.238454)
		(width 0.14224)
		(layer "In13.Cu")
		(net "P5E_CPU0_P1_RX_BUF_DP<1>")
	)
	(segment
		(start 310.146446 -422.273476)
		(end 310.549798 -422.413684)
		(width 0.14224)
		(layer "In13.Cu")
		(net "P5E_CPU0_P1_RX_BUF_DP<1>")
	)
	(segment
		(start 324.737984 -406.8572)
		(end 324.558914 -406.782778)
		(width 0.14224)
		(layer "In13.Cu")
		(net "P5E_CPU0_P1_RX_BUF_DP<1>")
	)
	(segment
		(start 326.854566 -405.981408)
		(end 326.675496 -405.906986)
		(width 0.14224)
		(layer "In13.Cu")
		(net "P5E_CPU0_P1_RX_BUF_DP<1>")
	)
	(segment
		(start 315.953648 -425.172632)
		(end 315.95822 -425.196)
		(width 0.14224)
		(layer "In13.Cu")
		(net "P5E_CPU0_P1_RX_BUF_DP<1>")
	)
	(segment
		(start 326.675496 -405.906986)
		(end 326.281288 -406.070054)
		(width 0.14224)
		(layer "In13.Cu")
		(net "P5E_CPU0_P1_RX_BUF_DP<1>")
	)
	(segment
		(start 316.649608 -434.594254)
		(end 316.649608 -434.289962)
		(width 0.14224)
		(layer "In13.Cu")
		(net "P5E_CPU0_P1_RX_BUF_DP<1>")
	)
	(segment
		(start 310.63438 -422.58869)
		(end 311.045098 -422.731438)
		(width 0.14224)
		(layer "In13.Cu")
		(net "P5E_CPU0_P1_RX_BUF_DP<1>")
	)
	(segment
		(start 311.21985 -422.646856)
		(end 311.622948 -422.787064)
		(width 0.14224)
		(layer "In13.Cu")
		(net "P5E_CPU0_P1_RX_BUF_DP<1>")
	)
	(segment
		(start 310.630316 -417.547298)
		(end 310.493156 -417.684458)
		(width 0.14224)
		(layer "In13.Cu")
		(net "P5E_CPU0_P1_RX_BUF_DP<1>")
	)
	(segment
		(start 310.493156 -415.786062)
		(end 310.630316 -415.923222)
		(width 0.14224)
		(layer "In13.Cu")
		(net "P5E_CPU0_P1_RX_BUF_DP<1>")
	)
	(segment
		(start 325.633334 -406.338278)
		(end 325.207122 -406.514554)
		(width 0.14224)
		(layer "In13.Cu")
		(net "P5E_CPU0_P1_RX_BUF_DP<1>")
	)
	(segment
		(start 311.622948 -422.787064)
		(end 311.70753 -422.961816)
		(width 0.14224)
		(layer "In13.Cu")
		(net "P5E_CPU0_P1_RX_BUF_DP<1>")
	)
	(segment
		(start 337.227164 -401.399756)
		(end 337.084924 -401.541996)
		(width 0.14224)
		(layer "In13.Cu")
		(net "P5E_CPU0_P1_RX_BUF_DP<1>")
	)
	(segment
		(start 309.493158 -422.191434)
		(end 309.971948 -422.358058)
		(width 0.14224)
		(layer "In13.Cu")
		(net "P5E_CPU0_P1_RX_BUF_DP<1>")
	)
	(segment
		(start 310.630316 -415.923222)
		(end 310.630316 -416.349942)
		(width 0.14224)
		(layer "In13.Cu")
		(net "P5E_CPU0_P1_RX_BUF_DP<1>")
	)
	(segment
		(start 316.201044 -434.74894)
		(end 316.494922 -434.74894)
		(width 0.14224)
		(layer "In13.Cu")
		(net "P5E_CPU0_P1_RX_BUF_DP<1>")
	)
	(segment
		(start 323.816472 -407.238454)
		(end 323.421756 -407.401522)
		(width 0.14224)
		(layer "In13.Cu")
		(net "P5E_CPU0_P1_RX_BUF_DP<1>")
	)
	(segment
		(start 310.493156 -416.983418)
		(end 310.630316 -417.120578)
		(width 0.14224)
		(layer "In13.Cu")
		(net "P5E_CPU0_P1_RX_BUF_DP<1>")
	)
	(segment
		(start 310.493156 -416.487102)
		(end 310.493156 -416.983418)
		(width 0.14224)
		(layer "In13.Cu")
		(net "P5E_CPU0_P1_RX_BUF_DP<1>")
	)
	(segment
		(start 311.70753 -422.961816)
		(end 312.110374 -423.102024)
		(width 0.14224)
		(layer "In13.Cu")
		(net "P5E_CPU0_P1_RX_BUF_DP<1>")
	)
	(segment
		(start 337.084924 -402.88464)
		(end 336.83194 -403.102826)
		(width 0.14224)
		(layer "In13.Cu")
		(net "P5E_CPU0_P1_RX_BUF_DP<1>")
	)
	(segment
		(start 310.493156 -417.684458)
		(end 310.493156 -419.079172)
		(width 0.14224)
		(layer "In13.Cu")
		(net "P5E_CPU0_P1_RX_BUF_DP<1>")
	)
	(segment
		(start 337.543902 -401.526756)
		(end 337.416902 -401.399756)
		(width 0.14224)
		(layer "In13.Cu")
		(net "P5E_CPU0_P1_RX_BUF_DP<1>")
	)
	(segment
		(start 315.95822 -434.506116)
		(end 316.201044 -434.74894)
		(width 0.14224)
		(layer "In13.Cu")
		(net "P5E_CPU0_P1_RX_BUF_DP<1>")
	)
	(segment
		(start 315.664596 -424.47591)
		(end 315.953648 -425.172632)
		(width 0.14224)
		(layer "In13.Cu")
		(net "P5E_CPU0_P1_RX_BUF_DP<1>")
	)
	(segment
		(start 311.045098 -422.731438)
		(end 311.21985 -422.646856)
		(width 0.14224)
		(layer "In13.Cu")
		(net "P5E_CPU0_P1_RX_BUF_DP<1>")
	)
	(segment
		(start 312.024776 -412.371286)
		(end 312.024776 -413.306514)
		(width 0.14224)
		(layer "In13.Cu")
		(net "P5E_CPU0_P1_RX_BUF_DP<1>")
	)
	(segment
		(start 327.827386 -405.430482)
		(end 327.32345 -405.638762)
		(width 0.14224)
		(layer "In13.Cu")
		(net "P5E_CPU0_P1_RX_BUF_DP<1>")
	)
	(segment
		(start 332.346808 -404.150576)
		(end 327.984612 -405.37765)
		(width 0.14224)
		(layer "In13.Cu")
		(net "P5E_CPU0_P1_RX_BUF_DP<1>")
	)
	(segment
		(start 310.001666 -419.70198)
		(end 309.049166 -420.09695)
		(width 0.14224)
		(layer "In13.Cu")
		(net "P5E_CPU0_P1_RX_BUF_DP<1>")
	)
	(segment
		(start 312.212736 -423.134028)
		(end 313.253628 -423.41927)
		(width 0.14224)
		(layer "In13.Cu")
		(net "P5E_CPU0_P1_RX_BUF_DP<1>")
	)
	(segment
		(start 310.493156 -415.020252)
		(end 310.493156 -415.786062)
		(width 0.14224)
		(layer "In13.Cu")
		(net "P5E_CPU0_P1_RX_BUF_DP<1>")
	)
	(segment
		(start 323.242686 -407.327354)
		(end 314.481718 -410.950918)
		(width 0.14224)
		(layer "In13.Cu")
		(net "P5E_CPU0_P1_RX_BUF_DP<1>")
	)
	(segment
		(start 316.494922 -434.74894)
		(end 316.649608 -434.594254)
		(width 0.14224)
		(layer "In13.Cu")
		(net "P5E_CPU0_P1_RX_BUF_DP<1>")
	)
	(segment
		(start 336.83194 -403.102826)
		(end 336.700876 -403.160992)
		(width 0.14224)
		(layer "In13.Cu")
		(net "P5E_CPU0_P1_RX_BUF_DP<1>")
	)
	(segment
		(start 310.369458 -419.388798)
		(end 310.202072 -419.56482)
		(width 0.14224)
		(layer "In13.Cu")
		(net "P5E_CPU0_P1_RX_BUF_DP<1>")
	)
	(arc
		(start 314.341256 -423.71772)
		(mid 314.419065 -423.74167)
		(end 314.49518 -423.770552)
		(width 0.14224)
		(layer "In13.Cu")
		(net "P5E_CPU0_P1_RX_BUF_DP<1>")
	)
	(arc
		(start 311.084468 -414.267142)
		(mid 310.878586 -414.377288)
		(end 310.698134 -414.52546)
		(width 0.14224)
		(layer "In13.Cu")
		(net "P5E_CPU0_P1_RX_BUF_DP<1>")
	)
	(arc
		(start 312.398156 -411.81274)
		(mid 312.126743 -412.03537)
		(end 312.024776 -412.371286)
		(width 0.14224)
		(layer "In13.Cu")
		(net "P5E_CPU0_P1_RX_BUF_DP<1>")
	)
	(arc
		(start 309.169054 -421.902382)
		(mid 309.272452 -422.01852)
		(end 309.383938 -422.126918)
		(width 0.14224)
		(layer "In13.Cu")
		(net "P5E_CPU0_P1_RX_BUF_DP<1>")
	)
	(arc
		(start 309.049166 -420.09695)
		(mid 308.985421 -420.149167)
		(end 308.961536 -420.228014)
		(width 0.14224)
		(layer "In13.Cu")
		(net "P5E_CPU0_P1_RX_BUF_DP<1>")
	)
	(arc
		(start 312.024776 -413.306514)
		(mid 311.972162 -413.571111)
		(end 311.822338 -413.795464)
		(width 0.14224)
		(layer "In13.Cu")
		(net "P5E_CPU0_P1_RX_BUF_DP<1>")
	)
	(arc
		(start 310.493156 -419.079172)
		(mid 310.461191 -419.24593)
		(end 310.369458 -419.388798)
		(width 0.14224)
		(layer "In13.Cu")
		(net "P5E_CPU0_P1_RX_BUF_DP<1>")
	)
	(arc
		(start 310.202072 -419.56482)
		(mid 310.109054 -419.643897)
		(end 310.001666 -419.70198)
		(width 0.14224)
		(layer "In13.Cu")
		(net "P5E_CPU0_P1_RX_BUF_DP<1>")
	)
	(arc
		(start 309.383938 -422.126918)
		(mid 309.435299 -422.16468)
		(end 309.493158 -422.191434)
		(width 0.14224)
		(layer "In13.Cu")
		(net "P5E_CPU0_P1_RX_BUF_DP<1>")
	)
	(arc
		(start 310.698134 -414.52546)
		(mid 310.546371 -414.752445)
		(end 310.493156 -415.020252)
		(width 0.14224)
		(layer "In13.Cu")
		(net "P5E_CPU0_P1_RX_BUF_DP<1>")
	)
	(arc
		(start 312.110374 -423.102024)
		(mid 312.161287 -423.118885)
		(end 312.212736 -423.134028)
		(width 0.14224)
		(layer "In13.Cu")
		(net "P5E_CPU0_P1_RX_BUF_DP<1>")
	)
	(arc
		(start 315.349382 -424.127422)
		(mid 315.452085 -424.189189)
		(end 315.532516 -424.278044)
		(width 0.14224)
		(layer "In13.Cu")
		(net "P5E_CPU0_P1_RX_BUF_DP<1>")
	)
	(arc
		(start 308.961536 -421.327326)
		(mid 309.014995 -421.633009)
		(end 309.169054 -421.902382)
		(width 0.14224)
		(layer "In13.Cu")
		(net "P5E_CPU0_P1_RX_BUF_DP<1>")
	)
	(segment
		(start 353.730052 -399.74774)
		(end 353.730052 -399.870676)
		(width 0.1016)
		(layer "F.Cu")
		(net "P5E_CPU0_P1_RX_BUF_DP<15>")
	)
	(segment
		(start 353.894644 -401.359116)
		(end 354.188776 -401.359116)
		(width 0.1016)
		(layer "F.Cu")
		(net "P5E_CPU0_P1_RX_BUF_DP<15>")
	)
	(segment
		(start 353.641406 -401.105878)
		(end 353.894644 -401.359116)
		(width 0.1016)
		(layer "F.Cu")
		(net "P5E_CPU0_P1_RX_BUF_DP<15>")
	)
	(segment
		(start 354.34397 -401.51431)
		(end 354.34397 -401.674838)
		(width 0.1016)
		(layer "F.Cu")
		(net "P5E_CPU0_P1_RX_BUF_DP<15>")
	)
	(segment
		(start 354.188776 -401.359116)
		(end 354.34397 -401.51431)
		(width 0.1016)
		(layer "F.Cu")
		(net "P5E_CPU0_P1_RX_BUF_DP<15>")
	)
	(segment
		(start 353.730052 -399.870676)
		(end 353.641406 -399.959322)
		(width 0.1016)
		(layer "F.Cu")
		(net "P5E_CPU0_P1_RX_BUF_DP<15>")
	)
	(segment
		(start 353.641406 -399.959322)
		(end 353.641406 -401.105878)
		(width 0.1016)
		(layer "F.Cu")
		(net "P5E_CPU0_P1_RX_BUF_DP<15>")
	)
	(segment
		(start 353.64547 -399.663158)
		(end 353.730052 -399.74774)
		(width 0.1016)
		(layer "F.Cu")
		(net "P5E_CPU0_P1_RX_BUF_DP<15>")
	)
	(segment
		(start 353.884992 -417.192714)
		(end 354.022152 -417.055554)
		(width 0.14224)
		(layer "In13.Cu")
		(net "P5E_CPU0_P1_RX_BUF_DP<15>")
	)
	(segment
		(start 351.646744 -421.875458)
		(end 351.89668 -421.529764)
		(width 0.14224)
		(layer "In13.Cu")
		(net "P5E_CPU0_P1_RX_BUF_DP<15>")
	)
	(segment
		(start 345.949778 -423.97934)
		(end 346.116148 -424.078908)
		(width 0.14224)
		(layer "In13.Cu")
		(net "P5E_CPU0_P1_RX_BUF_DP<15>")
	)
	(segment
		(start 353.884992 -413.108394)
		(end 353.884992 -412.681674)
		(width 0.14224)
		(layer "In13.Cu")
		(net "P5E_CPU0_P1_RX_BUF_DP<15>")
	)
	(segment
		(start 354.022152 -417.055554)
		(end 354.022152 -416.628834)
		(width 0.14224)
		(layer "In13.Cu")
		(net "P5E_CPU0_P1_RX_BUF_DP<15>")
	)
	(segment
		(start 353.884992 -417.619434)
		(end 353.884992 -417.192714)
		(width 0.14224)
		(layer "In13.Cu")
		(net "P5E_CPU0_P1_RX_BUF_DP<15>")
	)
	(segment
		(start 354.34397 -401.526756)
		(end 354.34397 -401.674838)
		(width 0.14224)
		(layer "In13.Cu")
		(net "P5E_CPU0_P1_RX_BUF_DP<15>")
	)
	(segment
		(start 346.530422 -423.975276)
		(end 346.62999 -423.808652)
		(width 0.14224)
		(layer "In13.Cu")
		(net "P5E_CPU0_P1_RX_BUF_DP<15>")
	)
	(segment
		(start 353.373436 -419.365938)
		(end 353.303586 -419.184836)
		(width 0.14224)
		(layer "In13.Cu")
		(net "P5E_CPU0_P1_RX_BUF_DP<15>")
	)
	(segment
		(start 352.84664 -420.216076)
		(end 353.01936 -419.826186)
		(width 0.14224)
		(layer "In13.Cu")
		(net "P5E_CPU0_P1_RX_BUF_DP<15>")
	)
	(segment
		(start 353.884992 -414.937194)
		(end 354.022152 -414.800034)
		(width 0.14224)
		(layer "In13.Cu")
		(net "P5E_CPU0_P1_RX_BUF_DP<15>")
	)
	(segment
		(start 353.884992 -401.541996)
		(end 354.027232 -401.399756)
		(width 0.14224)
		(layer "In13.Cu")
		(net "P5E_CPU0_P1_RX_BUF_DP<15>")
	)
	(segment
		(start 354.022152 -414.800034)
		(end 354.022152 -414.373314)
		(width 0.14224)
		(layer "In13.Cu")
		(net "P5E_CPU0_P1_RX_BUF_DP<15>")
	)
	(segment
		(start 354.022152 -412.544514)
		(end 354.022152 -412.117794)
		(width 0.14224)
		(layer "In13.Cu")
		(net "P5E_CPU0_P1_RX_BUF_DP<15>")
	)
	(segment
		(start 351.89668 -421.529764)
		(end 352.088196 -421.49903)
		(width 0.14224)
		(layer "In13.Cu")
		(net "P5E_CPU0_P1_RX_BUF_DP<15>")
	)
	(segment
		(start 345.116658 -424.330368)
		(end 345.405456 -424.137074)
		(width 0.14224)
		(layer "In13.Cu")
		(net "P5E_CPU0_P1_RX_BUF_DP<15>")
	)
	(segment
		(start 345.405456 -424.137074)
		(end 345.536012 -424.082972)
		(width 0.14224)
		(layer "In13.Cu")
		(net "P5E_CPU0_P1_RX_BUF_DP<15>")
	)
	(segment
		(start 348.434406 -423.270934)
		(end 348.839536 -423.13733)
		(width 0.14224)
		(layer "In13.Cu")
		(net "P5E_CPU0_P1_RX_BUF_DP<15>")
	)
	(segment
		(start 346.62999 -423.808652)
		(end 347.363288 -423.624756)
		(width 0.14224)
		(layer "In13.Cu")
		(net "P5E_CPU0_P1_RX_BUF_DP<15>")
	)
	(segment
		(start 354.022152 -416.628834)
		(end 353.884992 -416.491674)
		(width 0.14224)
		(layer "In13.Cu")
		(net "P5E_CPU0_P1_RX_BUF_DP<15>")
	)
	(segment
		(start 354.022152 -412.117794)
		(end 353.884992 -411.980634)
		(width 0.14224)
		(layer "In13.Cu")
		(net "P5E_CPU0_P1_RX_BUF_DP<15>")
	)
	(segment
		(start 345.649804 -434.62194)
		(end 345.522804 -434.74894)
		(width 0.14224)
		(layer "In13.Cu")
		(net "P5E_CPU0_P1_RX_BUF_DP<15>")
	)
	(segment
		(start 345.10853 -434.74894)
		(end 344.970862 -434.611272)
		(width 0.14224)
		(layer "In13.Cu")
		(net "P5E_CPU0_P1_RX_BUF_DP<15>")
	)
	(segment
		(start 353.01936 -419.826186)
		(end 353.200716 -419.756336)
		(width 0.14224)
		(layer "In13.Cu")
		(net "P5E_CPU0_P1_RX_BUF_DP<15>")
	)
	(segment
		(start 354.022152 -415.501074)
		(end 353.884992 -415.363914)
		(width 0.14224)
		(layer "In13.Cu")
		(net "P5E_CPU0_P1_RX_BUF_DP<15>")
	)
	(segment
		(start 354.022152 -415.927794)
		(end 354.022152 -415.501074)
		(width 0.14224)
		(layer "In13.Cu")
		(net "P5E_CPU0_P1_RX_BUF_DP<15>")
	)
	(segment
		(start 348.839536 -423.13733)
		(end 349.012764 -423.224452)
		(width 0.14224)
		(layer "In13.Cu")
		(net "P5E_CPU0_P1_RX_BUF_DP<15>")
	)
	(segment
		(start 345.649804 -434.289962)
		(end 345.649804 -434.62194)
		(width 0.14224)
		(layer "In13.Cu")
		(net "P5E_CPU0_P1_RX_BUF_DP<15>")
	)
	(segment
		(start 347.363288 -423.624756)
		(end 347.768418 -423.491152)
		(width 0.14224)
		(layer "In13.Cu")
		(net "P5E_CPU0_P1_RX_BUF_DP<15>")
	)
	(segment
		(start 352.088196 -421.49903)
		(end 352.338386 -421.153082)
		(width 0.14224)
		(layer "In13.Cu")
		(net "P5E_CPU0_P1_RX_BUF_DP<15>")
	)
	(segment
		(start 346.116148 -424.078908)
		(end 346.530422 -423.975276)
		(width 0.14224)
		(layer "In13.Cu")
		(net "P5E_CPU0_P1_RX_BUF_DP<15>")
	)
	(segment
		(start 353.884992 -414.236154)
		(end 353.884992 -413.809434)
		(width 0.14224)
		(layer "In13.Cu")
		(net "P5E_CPU0_P1_RX_BUF_DP<15>")
	)
	(segment
		(start 345.536012 -424.082972)
		(end 345.949778 -423.97934)
		(width 0.14224)
		(layer "In13.Cu")
		(net "P5E_CPU0_P1_RX_BUF_DP<15>")
	)
	(segment
		(start 353.782122 -418.105082)
		(end 353.884992 -417.619434)
		(width 0.14224)
		(layer "In13.Cu")
		(net "P5E_CPU0_P1_RX_BUF_DP<15>")
	)
	(segment
		(start 349.012764 -423.224452)
		(end 349.418148 -423.090848)
		(width 0.14224)
		(layer "In13.Cu")
		(net "P5E_CPU0_P1_RX_BUF_DP<15>")
	)
	(segment
		(start 352.307652 -420.961566)
		(end 352.84664 -420.216076)
		(width 0.14224)
		(layer "In13.Cu")
		(net "P5E_CPU0_P1_RX_BUF_DP<15>")
	)
	(segment
		(start 349.505524 -422.917112)
		(end 350.714564 -422.518078)
		(width 0.14224)
		(layer "In13.Cu")
		(net "P5E_CPU0_P1_RX_BUF_DP<15>")
	)
	(segment
		(start 354.022152 -413.245554)
		(end 353.884992 -413.108394)
		(width 0.14224)
		(layer "In13.Cu")
		(net "P5E_CPU0_P1_RX_BUF_DP<15>")
	)
	(segment
		(start 353.884992 -413.809434)
		(end 354.022152 -413.672274)
		(width 0.14224)
		(layer "In13.Cu")
		(net "P5E_CPU0_P1_RX_BUF_DP<15>")
	)
	(segment
		(start 345.522804 -434.74894)
		(end 345.10853 -434.74894)
		(width 0.14224)
		(layer "In13.Cu")
		(net "P5E_CPU0_P1_RX_BUF_DP<15>")
	)
	(segment
		(start 352.338386 -421.153082)
		(end 352.307652 -420.961566)
		(width 0.14224)
		(layer "In13.Cu")
		(net "P5E_CPU0_P1_RX_BUF_DP<15>")
	)
	(segment
		(start 354.022152 -413.672274)
		(end 354.022152 -413.245554)
		(width 0.14224)
		(layer "In13.Cu")
		(net "P5E_CPU0_P1_RX_BUF_DP<15>")
	)
	(segment
		(start 353.303586 -419.184836)
		(end 353.782122 -418.105082)
		(width 0.14224)
		(layer "In13.Cu")
		(net "P5E_CPU0_P1_RX_BUF_DP<15>")
	)
	(segment
		(start 353.884992 -416.491674)
		(end 353.884992 -416.064954)
		(width 0.14224)
		(layer "In13.Cu")
		(net "P5E_CPU0_P1_RX_BUF_DP<15>")
	)
	(segment
		(start 349.418148 -423.090848)
		(end 349.505524 -422.917112)
		(width 0.14224)
		(layer "In13.Cu")
		(net "P5E_CPU0_P1_RX_BUF_DP<15>")
	)
	(segment
		(start 353.884992 -411.980634)
		(end 353.884992 -401.541996)
		(width 0.14224)
		(layer "In13.Cu")
		(net "P5E_CPU0_P1_RX_BUF_DP<15>")
	)
	(segment
		(start 353.884992 -416.064954)
		(end 354.022152 -415.927794)
		(width 0.14224)
		(layer "In13.Cu")
		(net "P5E_CPU0_P1_RX_BUF_DP<15>")
	)
	(segment
		(start 353.884992 -412.681674)
		(end 354.022152 -412.544514)
		(width 0.14224)
		(layer "In13.Cu")
		(net "P5E_CPU0_P1_RX_BUF_DP<15>")
	)
	(segment
		(start 345.008454 -424.438318)
		(end 345.116658 -424.330368)
		(width 0.14224)
		(layer "In13.Cu")
		(net "P5E_CPU0_P1_RX_BUF_DP<15>")
	)
	(segment
		(start 351.167192 -422.269158)
		(end 351.646744 -421.875458)
		(width 0.14224)
		(layer "In13.Cu")
		(net "P5E_CPU0_P1_RX_BUF_DP<15>")
	)
	(segment
		(start 354.027232 -401.399756)
		(end 354.21697 -401.399756)
		(width 0.14224)
		(layer "In13.Cu")
		(net "P5E_CPU0_P1_RX_BUF_DP<15>")
	)
	(segment
		(start 353.200716 -419.756336)
		(end 353.373436 -419.365938)
		(width 0.14224)
		(layer "In13.Cu")
		(net "P5E_CPU0_P1_RX_BUF_DP<15>")
	)
	(segment
		(start 354.022152 -414.373314)
		(end 353.884992 -414.236154)
		(width 0.14224)
		(layer "In13.Cu")
		(net "P5E_CPU0_P1_RX_BUF_DP<15>")
	)
	(segment
		(start 347.768418 -423.491152)
		(end 347.941646 -423.578274)
		(width 0.14224)
		(layer "In13.Cu")
		(net "P5E_CPU0_P1_RX_BUF_DP<15>")
	)
	(segment
		(start 344.970862 -434.611272)
		(end 344.970862 -424.528742)
		(width 0.14224)
		(layer "In13.Cu")
		(net "P5E_CPU0_P1_RX_BUF_DP<15>")
	)
	(segment
		(start 347.941646 -423.578274)
		(end 348.34703 -423.444416)
		(width 0.14224)
		(layer "In13.Cu")
		(net "P5E_CPU0_P1_RX_BUF_DP<15>")
	)
	(segment
		(start 354.21697 -401.399756)
		(end 354.34397 -401.526756)
		(width 0.14224)
		(layer "In13.Cu")
		(net "P5E_CPU0_P1_RX_BUF_DP<15>")
	)
	(segment
		(start 348.34703 -423.444416)
		(end 348.434406 -423.270934)
		(width 0.14224)
		(layer "In13.Cu")
		(net "P5E_CPU0_P1_RX_BUF_DP<15>")
	)
	(segment
		(start 353.884992 -415.363914)
		(end 353.884992 -414.937194)
		(width 0.14224)
		(layer "In13.Cu")
		(net "P5E_CPU0_P1_RX_BUF_DP<15>")
	)
	(arc
		(start 344.970862 -424.528742)
		(mid 344.980622 -424.479767)
		(end 345.008454 -424.438318)
		(width 0.14224)
		(layer "In13.Cu")
		(net "P5E_CPU0_P1_RX_BUF_DP<15>")
	)
	(arc
		(start 350.714564 -422.518078)
		(mid 350.952356 -422.414486)
		(end 351.167192 -422.269158)
		(width 0.14224)
		(layer "In13.Cu")
		(net "P5E_CPU0_P1_RX_BUF_DP<15>")
	)
	(segment
		(start 352.44151 -401.105878)
		(end 352.694748 -401.359116)
		(width 0.1016)
		(layer "F.Cu")
		(net "P5E_CPU0_P1_RX_BUF_DP<14>")
	)
	(segment
		(start 352.987356 -401.359116)
		(end 353.144074 -401.515834)
		(width 0.1016)
		(layer "F.Cu")
		(net "P5E_CPU0_P1_RX_BUF_DP<14>")
	)
	(segment
		(start 352.694748 -401.359116)
		(end 352.987356 -401.359116)
		(width 0.1016)
		(layer "F.Cu")
		(net "P5E_CPU0_P1_RX_BUF_DP<14>")
	)
	(segment
		(start 352.445574 -399.663158)
		(end 352.530156 -399.74774)
		(width 0.1016)
		(layer "F.Cu")
		(net "P5E_CPU0_P1_RX_BUF_DP<14>")
	)
	(segment
		(start 352.530156 -399.870676)
		(end 352.44151 -399.959322)
		(width 0.1016)
		(layer "F.Cu")
		(net "P5E_CPU0_P1_RX_BUF_DP<14>")
	)
	(segment
		(start 353.144074 -401.515834)
		(end 353.144074 -401.674838)
		(width 0.1016)
		(layer "F.Cu")
		(net "P5E_CPU0_P1_RX_BUF_DP<14>")
	)
	(segment
		(start 352.530156 -399.74774)
		(end 352.530156 -399.870676)
		(width 0.1016)
		(layer "F.Cu")
		(net "P5E_CPU0_P1_RX_BUF_DP<14>")
	)
	(segment
		(start 352.44151 -399.959322)
		(end 352.44151 -401.105878)
		(width 0.1016)
		(layer "F.Cu")
		(net "P5E_CPU0_P1_RX_BUF_DP<14>")
	)
	(segment
		(start 351.836228 -413.4231)
		(end 351.877884 -412.998666)
		(width 0.14224)
		(layer "In13.Cu")
		(net "P5E_CPU0_P1_RX_BUF_DP<14>")
	)
	(segment
		(start 348.871286 -420.09695)
		(end 349.823786 -419.70198)
		(width 0.14224)
		(layer "In13.Cu")
		(net "P5E_CPU0_P1_RX_BUF_DP<14>")
	)
	(segment
		(start 352.291142 -410.205682)
		(end 352.167952 -410.055822)
		(width 0.14224)
		(layer "In13.Cu")
		(net "P5E_CPU0_P1_RX_BUF_DP<14>")
	)
	(segment
		(start 348.396306 -422.139872)
		(end 348.663768 -421.87241)
		(width 0.14224)
		(layer "In13.Cu")
		(net "P5E_CPU0_P1_RX_BUF_DP<14>")
	)
	(segment
		(start 348.783656 -421.583104)
		(end 348.783656 -420.228014)
		(width 0.14224)
		(layer "In13.Cu")
		(net "P5E_CPU0_P1_RX_BUF_DP<14>")
	)
	(segment
		(start 343.299288 -424.144694)
		(end 345.788996 -422.900094)
		(width 0.14224)
		(layer "In13.Cu")
		(net "P5E_CPU0_P1_RX_BUF_DP<14>")
	)
	(segment
		(start 350.549718 -414.48609)
		(end 351.47377 -413.97428)
		(width 0.14224)
		(layer "In13.Cu")
		(net "P5E_CPU0_P1_RX_BUF_DP<14>")
	)
	(segment
		(start 351.988628 -411.87624)
		(end 352.138742 -411.75305)
		(width 0.14224)
		(layer "In13.Cu")
		(net "P5E_CPU0_P1_RX_BUF_DP<14>")
	)
	(segment
		(start 347.313758 -422.62044)
		(end 347.725238 -422.506648)
		(width 0.14224)
		(layer "In13.Cu")
		(net "P5E_CPU0_P1_RX_BUF_DP<14>")
	)
	(segment
		(start 353.144074 -401.526756)
		(end 353.144074 -401.674838)
		(width 0.14224)
		(layer "In13.Cu")
		(net "P5E_CPU0_P1_RX_BUF_DP<14>")
	)
	(segment
		(start 350.452436 -417.2712)
		(end 350.315276 -417.13404)
		(width 0.14224)
		(layer "In13.Cu")
		(net "P5E_CPU0_P1_RX_BUF_DP<14>")
	)
	(segment
		(start 347.14434 -422.52519)
		(end 347.144848 -422.524936)
		(width 0.14224)
		(layer "In13.Cu")
		(net "P5E_CPU0_P1_RX_BUF_DP<14>")
	)
	(segment
		(start 352.249232 -410.630624)
		(end 352.291142 -410.205682)
		(width 0.14224)
		(layer "In13.Cu")
		(net "P5E_CPU0_P1_RX_BUF_DP<14>")
	)
	(segment
		(start 346.63761 -422.807638)
		(end 346.733114 -422.638728)
		(width 0.14224)
		(layer "In13.Cu")
		(net "P5E_CPU0_P1_RX_BUF_DP<14>")
	)
	(segment
		(start 352.401632 -409.083256)
		(end 352.278442 -408.933396)
		(width 0.14224)
		(layer "In13.Cu")
		(net "P5E_CPU0_P1_RX_BUF_DP<14>")
	)
	(segment
		(start 352.685096 -403.935946)
		(end 352.685096 -403.509226)
		(width 0.14224)
		(layer "In13.Cu")
		(net "P5E_CPU0_P1_RX_BUF_DP<14>")
	)
	(segment
		(start 352.822256 -402.945346)
		(end 352.685096 -402.808186)
		(width 0.14224)
		(layer "In13.Cu")
		(net "P5E_CPU0_P1_RX_BUF_DP<14>")
	)
	(segment
		(start 352.278442 -408.933396)
		(end 352.320098 -408.508962)
		(width 0.14224)
		(layer "In13.Cu")
		(net "P5E_CPU0_P1_RX_BUF_DP<14>")
	)
	(segment
		(start 353.017074 -401.399756)
		(end 353.144074 -401.526756)
		(width 0.14224)
		(layer "In13.Cu")
		(net "P5E_CPU0_P1_RX_BUF_DP<14>")
	)
	(segment
		(start 347.144848 -422.524936)
		(end 347.313758 -422.62044)
		(width 0.14224)
		(layer "In13.Cu")
		(net "P5E_CPU0_P1_RX_BUF_DP<14>")
	)
	(segment
		(start 347.820742 -422.337738)
		(end 348.271084 -422.213024)
		(width 0.14224)
		(layer "In13.Cu")
		(net "P5E_CPU0_P1_RX_BUF_DP<14>")
	)
	(segment
		(start 352.499422 -406.688544)
		(end 352.60026 -405.663146)
		(width 0.14224)
		(layer "In13.Cu")
		(net "P5E_CPU0_P1_RX_BUF_DP<14>")
	)
	(segment
		(start 350.452436 -417.69792)
		(end 350.452436 -417.2712)
		(width 0.14224)
		(layer "In13.Cu")
		(net "P5E_CPU0_P1_RX_BUF_DP<14>")
	)
	(segment
		(start 352.685096 -403.509226)
		(end 352.822256 -403.372066)
		(width 0.14224)
		(layer "In13.Cu")
		(net "P5E_CPU0_P1_RX_BUF_DP<14>")
	)
	(segment
		(start 352.057462 -411.178248)
		(end 352.099118 -410.753814)
		(width 0.14224)
		(layer "In13.Cu")
		(net "P5E_CPU0_P1_RX_BUF_DP<14>")
	)
	(segment
		(start 342.970866 -433.621942)
		(end 342.970866 -424.699684)
		(width 0.14224)
		(layer "In13.Cu")
		(net "P5E_CPU0_P1_RX_BUF_DP<14>")
	)
	(segment
		(start 352.209608 -409.631388)
		(end 352.359722 -409.508198)
		(width 0.14224)
		(layer "In13.Cu")
		(net "P5E_CPU0_P1_RX_BUF_DP<14>")
	)
	(segment
		(start 348.271084 -422.213024)
		(end 348.396306 -422.139872)
		(width 0.14224)
		(layer "In13.Cu")
		(net "P5E_CPU0_P1_RX_BUF_DP<14>")
	)
	(segment
		(start 352.512122 -407.96083)
		(end 352.388932 -407.81097)
		(width 0.14224)
		(layer "In13.Cu")
		(net "P5E_CPU0_P1_RX_BUF_DP<14>")
	)
	(segment
		(start 345.788996 -422.900094)
		(end 346.05722 -422.825926)
		(width 0.14224)
		(layer "In13.Cu")
		(net "P5E_CPU0_P1_RX_BUF_DP<14>")
	)
	(segment
		(start 352.069908 -412.450534)
		(end 351.946972 -412.300674)
		(width 0.14224)
		(layer "In13.Cu")
		(net "P5E_CPU0_P1_RX_BUF_DP<14>")
	)
	(segment
		(start 343.649808 -433.621942)
		(end 343.522808 -433.748942)
		(width 0.14224)
		(layer "In13.Cu")
		(net "P5E_CPU0_P1_RX_BUF_DP<14>")
	)
	(segment
		(start 346.733114 -422.638728)
		(end 347.14434 -422.524936)
		(width 0.14224)
		(layer "In13.Cu")
		(net "P5E_CPU0_P1_RX_BUF_DP<14>")
	)
	(segment
		(start 350.452436 -416.14344)
		(end 350.315276 -416.00628)
		(width 0.14224)
		(layer "In13.Cu")
		(net "P5E_CPU0_P1_RX_BUF_DP<14>")
	)
	(segment
		(start 352.685096 -402.808186)
		(end 352.685096 -401.541996)
		(width 0.14224)
		(layer "In13.Cu")
		(net "P5E_CPU0_P1_RX_BUF_DP<14>")
	)
	(segment
		(start 352.685096 -401.541996)
		(end 352.827336 -401.399756)
		(width 0.14224)
		(layer "In13.Cu")
		(net "P5E_CPU0_P1_RX_BUF_DP<14>")
	)
	(segment
		(start 352.430588 -407.386536)
		(end 352.580702 -407.263346)
		(width 0.14224)
		(layer "In13.Cu")
		(net "P5E_CPU0_P1_RX_BUF_DP<14>")
	)
	(segment
		(start 343.649808 -433.289964)
		(end 343.649808 -433.621942)
		(width 0.14224)
		(layer "In13.Cu")
		(net "P5E_CPU0_P1_RX_BUF_DP<14>")
	)
	(segment
		(start 352.167952 -410.055822)
		(end 352.209608 -409.631388)
		(width 0.14224)
		(layer "In13.Cu")
		(net "P5E_CPU0_P1_RX_BUF_DP<14>")
	)
	(segment
		(start 343.052146 -424.448478)
		(end 343.20861 -424.23207)
		(width 0.14224)
		(layer "In13.Cu")
		(net "P5E_CPU0_P1_RX_BUF_DP<14>")
	)
	(segment
		(start 352.138742 -411.75305)
		(end 352.180652 -411.328108)
		(width 0.14224)
		(layer "In13.Cu")
		(net "P5E_CPU0_P1_RX_BUF_DP<14>")
	)
	(segment
		(start 350.452436 -416.57016)
		(end 350.452436 -416.14344)
		(width 0.14224)
		(layer "In13.Cu")
		(net "P5E_CPU0_P1_RX_BUF_DP<14>")
	)
	(segment
		(start 352.822256 -403.372066)
		(end 352.822256 -402.945346)
		(width 0.14224)
		(layer "In13.Cu")
		(net "P5E_CPU0_P1_RX_BUF_DP<14>")
	)
	(segment
		(start 352.388932 -407.81097)
		(end 352.430588 -407.386536)
		(width 0.14224)
		(layer "In13.Cu")
		(net "P5E_CPU0_P1_RX_BUF_DP<14>")
	)
	(segment
		(start 346.22613 -422.92143)
		(end 346.63761 -422.807638)
		(width 0.14224)
		(layer "In13.Cu")
		(net "P5E_CPU0_P1_RX_BUF_DP<14>")
	)
	(segment
		(start 346.05722 -422.825926)
		(end 346.22613 -422.92143)
		(width 0.14224)
		(layer "In13.Cu")
		(net "P5E_CPU0_P1_RX_BUF_DP<14>")
	)
	(segment
		(start 352.580702 -407.263346)
		(end 352.622612 -406.838404)
		(width 0.14224)
		(layer "In13.Cu")
		(net "P5E_CPU0_P1_RX_BUF_DP<14>")
	)
	(segment
		(start 350.024192 -419.56482)
		(end 350.191578 -419.388798)
		(width 0.14224)
		(layer "In13.Cu")
		(net "P5E_CPU0_P1_RX_BUF_DP<14>")
	)
	(segment
		(start 350.315276 -416.00628)
		(end 350.315276 -415.019744)
		(width 0.14224)
		(layer "In13.Cu")
		(net "P5E_CPU0_P1_RX_BUF_DP<14>")
	)
	(segment
		(start 351.877884 -412.998666)
		(end 352.027998 -412.875476)
		(width 0.14224)
		(layer "In13.Cu")
		(net "P5E_CPU0_P1_RX_BUF_DP<14>")
	)
	(segment
		(start 352.320098 -408.508962)
		(end 352.470212 -408.385772)
		(width 0.14224)
		(layer "In13.Cu")
		(net "P5E_CPU0_P1_RX_BUF_DP<14>")
	)
	(segment
		(start 343.522808 -433.748942)
		(end 343.097866 -433.748942)
		(width 0.14224)
		(layer "In13.Cu")
		(net "P5E_CPU0_P1_RX_BUF_DP<14>")
	)
	(segment
		(start 347.14434 -422.524936)
		(end 347.14434 -422.52519)
		(width 0.14224)
		(layer "In13.Cu")
		(net "P5E_CPU0_P1_RX_BUF_DP<14>")
	)
	(segment
		(start 352.027998 -412.875476)
		(end 352.069908 -412.450534)
		(width 0.14224)
		(layer "In13.Cu")
		(net "P5E_CPU0_P1_RX_BUF_DP<14>")
	)
	(segment
		(start 352.470212 -408.385772)
		(end 352.512122 -407.96083)
		(width 0.14224)
		(layer "In13.Cu")
		(net "P5E_CPU0_P1_RX_BUF_DP<14>")
	)
	(segment
		(start 352.827336 -401.399756)
		(end 353.017074 -401.399756)
		(width 0.14224)
		(layer "In13.Cu")
		(net "P5E_CPU0_P1_RX_BUF_DP<14>")
	)
	(segment
		(start 350.315276 -416.70732)
		(end 350.452436 -416.57016)
		(width 0.14224)
		(layer "In13.Cu")
		(net "P5E_CPU0_P1_RX_BUF_DP<14>")
	)
	(segment
		(start 352.359722 -409.508198)
		(end 352.401632 -409.083256)
		(width 0.14224)
		(layer "In13.Cu")
		(net "P5E_CPU0_P1_RX_BUF_DP<14>")
	)
	(segment
		(start 350.315276 -417.83508)
		(end 350.452436 -417.69792)
		(width 0.14224)
		(layer "In13.Cu")
		(net "P5E_CPU0_P1_RX_BUF_DP<14>")
	)
	(segment
		(start 350.315276 -419.079172)
		(end 350.315276 -417.83508)
		(width 0.14224)
		(layer "In13.Cu")
		(net "P5E_CPU0_P1_RX_BUF_DP<14>")
	)
	(segment
		(start 343.097866 -433.748942)
		(end 342.970866 -433.621942)
		(width 0.14224)
		(layer "In13.Cu")
		(net "P5E_CPU0_P1_RX_BUF_DP<14>")
	)
	(segment
		(start 347.725238 -422.506648)
		(end 347.820742 -422.337738)
		(width 0.14224)
		(layer "In13.Cu")
		(net "P5E_CPU0_P1_RX_BUF_DP<14>")
	)
	(segment
		(start 352.099118 -410.753814)
		(end 352.249232 -410.630624)
		(width 0.14224)
		(layer "In13.Cu")
		(net "P5E_CPU0_P1_RX_BUF_DP<14>")
	)
	(segment
		(start 350.315276 -417.13404)
		(end 350.315276 -416.70732)
		(width 0.14224)
		(layer "In13.Cu")
		(net "P5E_CPU0_P1_RX_BUF_DP<14>")
	)
	(segment
		(start 351.946972 -412.300674)
		(end 351.988628 -411.87624)
		(width 0.14224)
		(layer "In13.Cu")
		(net "P5E_CPU0_P1_RX_BUF_DP<14>")
	)
	(segment
		(start 352.180652 -411.328108)
		(end 352.057462 -411.178248)
		(width 0.14224)
		(layer "In13.Cu")
		(net "P5E_CPU0_P1_RX_BUF_DP<14>")
	)
	(segment
		(start 352.622612 -406.838404)
		(end 352.499422 -406.688544)
		(width 0.14224)
		(layer "In13.Cu")
		(net "P5E_CPU0_P1_RX_BUF_DP<14>")
	)
	(arc
		(start 348.663768 -421.87241)
		(mid 348.752512 -421.73969)
		(end 348.783656 -421.583104)
		(width 0.14224)
		(layer "In13.Cu")
		(net "P5E_CPU0_P1_RX_BUF_DP<14>")
	)
	(arc
		(start 349.823786 -419.70198)
		(mid 349.931184 -419.643911)
		(end 350.024192 -419.56482)
		(width 0.14224)
		(layer "In13.Cu")
		(net "P5E_CPU0_P1_RX_BUF_DP<14>")
	)
	(arc
		(start 342.970866 -424.699684)
		(mid 342.991695 -424.567672)
		(end 343.052146 -424.448478)
		(width 0.14224)
		(layer "In13.Cu")
		(net "P5E_CPU0_P1_RX_BUF_DP<14>")
	)
	(arc
		(start 352.60026 -405.663146)
		(mid 352.663877 -404.800587)
		(end 352.685096 -403.935946)
		(width 0.14224)
		(layer "In13.Cu")
		(net "P5E_CPU0_P1_RX_BUF_DP<14>")
	)
	(arc
		(start 351.47377 -413.97428)
		(mid 351.72287 -413.74333)
		(end 351.836228 -413.4231)
		(width 0.14224)
		(layer "In13.Cu")
		(net "P5E_CPU0_P1_RX_BUF_DP<14>")
	)
	(arc
		(start 350.455738 -414.570926)
		(mid 350.497838 -414.523091)
		(end 350.549718 -414.48609)
		(width 0.14224)
		(layer "In13.Cu")
		(net "P5E_CPU0_P1_RX_BUF_DP<14>")
	)
	(arc
		(start 350.191578 -419.388798)
		(mid 350.283254 -419.245907)
		(end 350.315276 -419.079172)
		(width 0.14224)
		(layer "In13.Cu")
		(net "P5E_CPU0_P1_RX_BUF_DP<14>")
	)
	(arc
		(start 343.20861 -424.23207)
		(mid 343.25006 -424.184347)
		(end 343.299288 -424.144694)
		(width 0.14224)
		(layer "In13.Cu")
		(net "P5E_CPU0_P1_RX_BUF_DP<14>")
	)
	(arc
		(start 348.783656 -420.228014)
		(mid 348.80759 -420.1492)
		(end 348.871286 -420.09695)
		(width 0.14224)
		(layer "In13.Cu")
		(net "P5E_CPU0_P1_RX_BUF_DP<14>")
	)
	(arc
		(start 350.315276 -415.019744)
		(mid 350.351217 -414.784606)
		(end 350.455738 -414.570926)
		(width 0.14224)
		(layer "In13.Cu")
		(net "P5E_CPU0_P1_RX_BUF_DP<14>")
	)
	(segment
		(start 351.249996 -399.950686)
		(end 351.249996 -401.105878)
		(width 0.1016)
		(layer "F.Cu")
		(net "P5E_CPU0_P1_RX_BUF_DP<13>")
	)
	(segment
		(start 351.503234 -401.359116)
		(end 351.80524 -401.359116)
		(width 0.1016)
		(layer "F.Cu")
		(net "P5E_CPU0_P1_RX_BUF_DP<13>")
	)
	(segment
		(start 351.245424 -399.663158)
		(end 351.330006 -399.74774)
		(width 0.1016)
		(layer "F.Cu")
		(net "P5E_CPU0_P1_RX_BUF_DP<13>")
	)
	(segment
		(start 351.330006 -399.870676)
		(end 351.249996 -399.950686)
		(width 0.1016)
		(layer "F.Cu")
		(net "P5E_CPU0_P1_RX_BUF_DP<13>")
	)
	(segment
		(start 351.943924 -401.4978)
		(end 351.943924 -401.674838)
		(width 0.1016)
		(layer "F.Cu")
		(net "P5E_CPU0_P1_RX_BUF_DP<13>")
	)
	(segment
		(start 351.80524 -401.359116)
		(end 351.943924 -401.4978)
		(width 0.1016)
		(layer "F.Cu")
		(net "P5E_CPU0_P1_RX_BUF_DP<13>")
	)
	(segment
		(start 351.330006 -399.74774)
		(end 351.330006 -399.870676)
		(width 0.1016)
		(layer "F.Cu")
		(net "P5E_CPU0_P1_RX_BUF_DP<13>")
	)
	(segment
		(start 351.249996 -401.105878)
		(end 351.503234 -401.359116)
		(width 0.1016)
		(layer "F.Cu")
		(net "P5E_CPU0_P1_RX_BUF_DP<13>")
	)
	(segment
		(start 347.389196 -416.238944)
		(end 347.252036 -416.101784)
		(width 0.14224)
		(layer "In13.Cu")
		(net "P5E_CPU0_P1_RX_BUF_DP<13>")
	)
	(segment
		(start 351.816924 -401.399756)
		(end 351.943924 -401.526756)
		(width 0.14224)
		(layer "In13.Cu")
		(net "P5E_CPU0_P1_RX_BUF_DP<13>")
	)
	(segment
		(start 351.078546 -404.6347)
		(end 351.216722 -404.496524)
		(width 0.14224)
		(layer "In13.Cu")
		(net "P5E_CPU0_P1_RX_BUF_DP<13>")
	)
	(segment
		(start 349.057722 -410.849826)
		(end 349.14078 -410.431488)
		(width 0.14224)
		(layer "In13.Cu")
		(net "P5E_CPU0_P1_RX_BUF_DP<13>")
	)
	(segment
		(start 348.920816 -411.537658)
		(end 349.08236 -411.429962)
		(width 0.14224)
		(layer "In13.Cu")
		(net "P5E_CPU0_P1_RX_BUF_DP<13>")
	)
	(segment
		(start 349.686118 -408.79649)
		(end 349.829882 -408.394408)
		(width 0.14224)
		(layer "In13.Cu")
		(net "P5E_CPU0_P1_RX_BUF_DP<13>")
	)
	(segment
		(start 350.58985 -406.27046)
		(end 350.506792 -406.0952)
		(width 0.14224)
		(layer "In13.Cu")
		(net "P5E_CPU0_P1_RX_BUF_DP<13>")
	)
	(segment
		(start 346.960952 -419.56482)
		(end 347.128338 -419.388798)
		(width 0.14224)
		(layer "In13.Cu")
		(net "P5E_CPU0_P1_RX_BUF_DP<13>")
	)
	(segment
		(start 347.252036 -416.802824)
		(end 347.389196 -416.665664)
		(width 0.14224)
		(layer "In13.Cu")
		(net "P5E_CPU0_P1_RX_BUF_DP<13>")
	)
	(segment
		(start 347.252036 -416.101784)
		(end 347.252036 -415.020252)
		(width 0.14224)
		(layer "In13.Cu")
		(net "P5E_CPU0_P1_RX_BUF_DP<13>")
	)
	(segment
		(start 347.252036 -417.930584)
		(end 347.389196 -417.793424)
		(width 0.14224)
		(layer "In13.Cu")
		(net "P5E_CPU0_P1_RX_BUF_DP<13>")
	)
	(segment
		(start 350.506792 -406.0952)
		(end 350.650556 -405.693626)
		(width 0.14224)
		(layer "In13.Cu")
		(net "P5E_CPU0_P1_RX_BUF_DP<13>")
	)
	(segment
		(start 351.622106 -402.988272)
		(end 351.484946 -402.851112)
		(width 0.14224)
		(layer "In13.Cu")
		(net "P5E_CPU0_P1_RX_BUF_DP<13>")
	)
	(segment
		(start 350.270572 -406.7556)
		(end 350.446086 -406.672542)
		(width 0.14224)
		(layer "In13.Cu")
		(net "P5E_CPU0_P1_RX_BUF_DP<13>")
	)
	(segment
		(start 351.622106 -403.414992)
		(end 351.622106 -402.988272)
		(width 0.14224)
		(layer "In13.Cu")
		(net "P5E_CPU0_P1_RX_BUF_DP<13>")
	)
	(segment
		(start 351.484946 -403.552152)
		(end 351.622106 -403.414992)
		(width 0.14224)
		(layer "In13.Cu")
		(net "P5E_CPU0_P1_RX_BUF_DP<13>")
	)
	(segment
		(start 341.892128 -423.890948)
		(end 342.268556 -423.68978)
		(width 0.14224)
		(layer "In13.Cu")
		(net "P5E_CPU0_P1_RX_BUF_DP<13>")
	)
	(segment
		(start 351.484946 -401.541996)
		(end 351.627186 -401.399756)
		(width 0.14224)
		(layer "In13.Cu")
		(net "P5E_CPU0_P1_RX_BUF_DP<13>")
	)
	(segment
		(start 350.887792 -405.03094)
		(end 350.96577 -404.812754)
		(width 0.14224)
		(layer "In13.Cu")
		(net "P5E_CPU0_P1_RX_BUF_DP<13>")
	)
	(segment
		(start 347.389196 -417.366704)
		(end 347.252036 -417.229544)
		(width 0.14224)
		(layer "In13.Cu")
		(net "P5E_CPU0_P1_RX_BUF_DP<13>")
	)
	(segment
		(start 348.783656 -413.306514)
		(end 348.783656 -412.29153)
		(width 0.14224)
		(layer "In13.Cu")
		(net "P5E_CPU0_P1_RX_BUF_DP<13>")
	)
	(segment
		(start 345.808046 -420.09695)
		(end 346.760546 -419.70198)
		(width 0.14224)
		(layer "In13.Cu")
		(net "P5E_CPU0_P1_RX_BUF_DP<13>")
	)
	(segment
		(start 341.127842 -434.74894)
		(end 340.97087 -434.591968)
		(width 0.14224)
		(layer "In13.Cu")
		(net "P5E_CPU0_P1_RX_BUF_DP<13>")
	)
	(segment
		(start 347.252036 -419.079172)
		(end 347.252036 -417.930584)
		(width 0.14224)
		(layer "In13.Cu")
		(net "P5E_CPU0_P1_RX_BUF_DP<13>")
	)
	(segment
		(start 349.746824 -408.219148)
		(end 349.890588 -407.817574)
		(width 0.14224)
		(layer "In13.Cu")
		(net "P5E_CPU0_P1_RX_BUF_DP<13>")
	)
	(segment
		(start 341.706454 -423.83456)
		(end 341.892128 -423.890948)
		(width 0.14224)
		(layer "In13.Cu")
		(net "P5E_CPU0_P1_RX_BUF_DP<13>")
	)
	(segment
		(start 350.82607 -405.610568)
		(end 350.969834 -405.20874)
		(width 0.14224)
		(layer "In13.Cu")
		(net "P5E_CPU0_P1_RX_BUF_DP<13>")
	)
	(segment
		(start 341.314024 -424.044364)
		(end 341.706454 -423.83456)
		(width 0.14224)
		(layer "In13.Cu")
		(net "P5E_CPU0_P1_RX_BUF_DP<13>")
	)
	(segment
		(start 349.385382 -409.904946)
		(end 349.277686 -409.743656)
		(width 0.14224)
		(layer "In13.Cu")
		(net "P5E_CPU0_P1_RX_BUF_DP<13>")
	)
	(segment
		(start 347.389196 -417.793424)
		(end 347.389196 -417.366704)
		(width 0.14224)
		(layer "In13.Cu")
		(net "P5E_CPU0_P1_RX_BUF_DP<13>")
	)
	(segment
		(start 351.484946 -403.849078)
		(end 351.484946 -403.552152)
		(width 0.14224)
		(layer "In13.Cu")
		(net "P5E_CPU0_P1_RX_BUF_DP<13>")
	)
	(segment
		(start 349.510604 -408.879548)
		(end 349.686118 -408.79649)
		(width 0.14224)
		(layer "In13.Cu")
		(net "P5E_CPU0_P1_RX_BUF_DP<13>")
	)
	(segment
		(start 350.650556 -405.693626)
		(end 350.82607 -405.610568)
		(width 0.14224)
		(layer "In13.Cu")
		(net "P5E_CPU0_P1_RX_BUF_DP<13>")
	)
	(segment
		(start 344.26271 -422.5544)
		(end 344.941144 -422.27373)
		(width 0.14224)
		(layer "In13.Cu")
		(net "P5E_CPU0_P1_RX_BUF_DP<13>")
	)
	(segment
		(start 349.14078 -410.431488)
		(end 349.302324 -410.323792)
		(width 0.14224)
		(layer "In13.Cu")
		(net "P5E_CPU0_P1_RX_BUF_DP<13>")
	)
	(segment
		(start 350.88703 -405.033226)
		(end 350.887792 -405.03094)
		(width 0.14224)
		(layer "In13.Cu")
		(net "P5E_CPU0_P1_RX_BUF_DP<13>")
	)
	(segment
		(start 348.118938 -414.153096)
		(end 348.434406 -413.942276)
		(width 0.14224)
		(layer "In13.Cu")
		(net "P5E_CPU0_P1_RX_BUF_DP<13>")
	)
	(segment
		(start 348.434406 -413.942276)
		(end 348.581218 -413.795464)
		(width 0.14224)
		(layer "In13.Cu")
		(net "P5E_CPU0_P1_RX_BUF_DP<13>")
	)
	(segment
		(start 341.649812 -434.289962)
		(end 341.649812 -434.62194)
		(width 0.14224)
		(layer "In13.Cu")
		(net "P5E_CPU0_P1_RX_BUF_DP<13>")
	)
	(segment
		(start 349.829882 -408.394408)
		(end 349.746824 -408.219148)
		(width 0.14224)
		(layer "In13.Cu")
		(net "P5E_CPU0_P1_RX_BUF_DP<13>")
	)
	(segment
		(start 342.324944 -423.503852)
		(end 342.866726 -423.214292)
		(width 0.14224)
		(layer "In13.Cu")
		(net "P5E_CPU0_P1_RX_BUF_DP<13>")
	)
	(segment
		(start 347.389196 -416.665664)
		(end 347.389196 -416.238944)
		(width 0.14224)
		(layer "In13.Cu")
		(net "P5E_CPU0_P1_RX_BUF_DP<13>")
	)
	(segment
		(start 348.796102 -412.1658)
		(end 348.920816 -411.537658)
		(width 0.14224)
		(layer "In13.Cu")
		(net "P5E_CPU0_P1_RX_BUF_DP<13>")
	)
	(segment
		(start 347.252036 -417.229544)
		(end 347.252036 -416.802824)
		(width 0.14224)
		(layer "In13.Cu")
		(net "P5E_CPU0_P1_RX_BUF_DP<13>")
	)
	(segment
		(start 351.943924 -401.526756)
		(end 351.943924 -401.674838)
		(width 0.14224)
		(layer "In13.Cu")
		(net "P5E_CPU0_P1_RX_BUF_DP<13>")
	)
	(segment
		(start 351.627186 -401.399756)
		(end 351.816924 -401.399756)
		(width 0.14224)
		(layer "In13.Cu")
		(net "P5E_CPU0_P1_RX_BUF_DP<13>")
	)
	(segment
		(start 347.843348 -414.267142)
		(end 348.118938 -414.153096)
		(width 0.14224)
		(layer "In13.Cu")
		(net "P5E_CPU0_P1_RX_BUF_DP<13>")
	)
	(segment
		(start 342.268556 -423.68978)
		(end 342.324944 -423.503852)
		(width 0.14224)
		(layer "In13.Cu")
		(net "P5E_CPU0_P1_RX_BUF_DP<13>")
	)
	(segment
		(start 351.484946 -402.851112)
		(end 351.484946 -401.541996)
		(width 0.14224)
		(layer "In13.Cu")
		(net "P5E_CPU0_P1_RX_BUF_DP<13>")
	)
	(segment
		(start 345.720416 -421.490902)
		(end 345.720416 -420.228014)
		(width 0.14224)
		(layer "In13.Cu")
		(net "P5E_CPU0_P1_RX_BUF_DP<13>")
	)
	(segment
		(start 349.165418 -411.011116)
		(end 349.057722 -410.849826)
		(width 0.14224)
		(layer "In13.Cu")
		(net "P5E_CPU0_P1_RX_BUF_DP<13>")
	)
	(segment
		(start 341.649812 -434.62194)
		(end 341.522812 -434.74894)
		(width 0.14224)
		(layer "In13.Cu")
		(net "P5E_CPU0_P1_RX_BUF_DP<13>")
	)
	(segment
		(start 350.126808 -407.157174)
		(end 350.270572 -406.7556)
		(width 0.14224)
		(layer "In13.Cu")
		(net "P5E_CPU0_P1_RX_BUF_DP<13>")
	)
	(segment
		(start 350.209866 -407.332434)
		(end 350.126808 -407.157174)
		(width 0.14224)
		(layer "In13.Cu")
		(net "P5E_CPU0_P1_RX_BUF_DP<13>")
	)
	(segment
		(start 345.440254 -421.940482)
		(end 345.600528 -421.780462)
		(width 0.14224)
		(layer "In13.Cu")
		(net "P5E_CPU0_P1_RX_BUF_DP<13>")
	)
	(segment
		(start 349.394526 -409.203398)
		(end 349.510604 -408.879548)
		(width 0.14224)
		(layer "In13.Cu")
		(net "P5E_CPU0_P1_RX_BUF_DP<13>")
	)
	(segment
		(start 349.302324 -410.323792)
		(end 349.385382 -409.904946)
		(width 0.14224)
		(layer "In13.Cu")
		(net "P5E_CPU0_P1_RX_BUF_DP<13>")
	)
	(segment
		(start 349.890588 -407.817574)
		(end 350.066102 -407.734516)
		(width 0.14224)
		(layer "In13.Cu")
		(net "P5E_CPU0_P1_RX_BUF_DP<13>")
	)
	(segment
		(start 341.006176 -424.493436)
		(end 341.2236 -424.13047)
		(width 0.14224)
		(layer "In13.Cu")
		(net "P5E_CPU0_P1_RX_BUF_DP<13>")
	)
	(segment
		(start 350.446086 -406.672542)
		(end 350.58985 -406.27046)
		(width 0.14224)
		(layer "In13.Cu")
		(net "P5E_CPU0_P1_RX_BUF_DP<13>")
	)
	(segment
		(start 340.97087 -434.591968)
		(end 340.97087 -424.629326)
		(width 0.14224)
		(layer "In13.Cu")
		(net "P5E_CPU0_P1_RX_BUF_DP<13>")
	)
	(segment
		(start 341.522812 -434.74894)
		(end 341.127842 -434.74894)
		(width 0.14224)
		(layer "In13.Cu")
		(net "P5E_CPU0_P1_RX_BUF_DP<13>")
	)
	(segment
		(start 349.277686 -409.743656)
		(end 349.360744 -409.325318)
		(width 0.14224)
		(layer "In13.Cu")
		(net "P5E_CPU0_P1_RX_BUF_DP<13>")
	)
	(segment
		(start 349.08236 -411.429962)
		(end 349.165418 -411.011116)
		(width 0.14224)
		(layer "In13.Cu")
		(net "P5E_CPU0_P1_RX_BUF_DP<13>")
	)
	(segment
		(start 350.969834 -405.20874)
		(end 350.88703 -405.033226)
		(width 0.14224)
		(layer "In13.Cu")
		(net "P5E_CPU0_P1_RX_BUF_DP<13>")
	)
	(segment
		(start 350.066102 -407.734516)
		(end 350.209866 -407.332434)
		(width 0.14224)
		(layer "In13.Cu")
		(net "P5E_CPU0_P1_RX_BUF_DP<13>")
	)
	(arc
		(start 346.760546 -419.70198)
		(mid 346.867944 -419.643911)
		(end 346.960952 -419.56482)
		(width 0.14224)
		(layer "In13.Cu")
		(net "P5E_CPU0_P1_RX_BUF_DP<13>")
	)
	(arc
		(start 351.216722 -404.496524)
		(mid 351.415259 -404.199487)
		(end 351.484946 -403.849078)
		(width 0.14224)
		(layer "In13.Cu")
		(net "P5E_CPU0_P1_RX_BUF_DP<13>")
	)
	(arc
		(start 347.252036 -415.020252)
		(mid 347.305265 -414.752451)
		(end 347.457014 -414.52546)
		(width 0.14224)
		(layer "In13.Cu")
		(net "P5E_CPU0_P1_RX_BUF_DP<13>")
	)
	(arc
		(start 349.360744 -409.325318)
		(mid 349.375378 -409.263733)
		(end 349.394526 -409.203398)
		(width 0.14224)
		(layer "In13.Cu")
		(net "P5E_CPU0_P1_RX_BUF_DP<13>")
	)
	(arc
		(start 347.128338 -419.388798)
		(mid 347.220014 -419.245907)
		(end 347.252036 -419.079172)
		(width 0.14224)
		(layer "In13.Cu")
		(net "P5E_CPU0_P1_RX_BUF_DP<13>")
	)
	(arc
		(start 341.2236 -424.13047)
		(mid 341.263001 -424.081321)
		(end 341.314024 -424.044364)
		(width 0.14224)
		(layer "In13.Cu")
		(net "P5E_CPU0_P1_RX_BUF_DP<13>")
	)
	(arc
		(start 345.720416 -420.228014)
		(mid 345.74435 -420.1492)
		(end 345.808046 -420.09695)
		(width 0.14224)
		(layer "In13.Cu")
		(net "P5E_CPU0_P1_RX_BUF_DP<13>")
	)
	(arc
		(start 348.581218 -413.795464)
		(mid 348.731058 -413.571118)
		(end 348.783656 -413.306514)
		(width 0.14224)
		(layer "In13.Cu")
		(net "P5E_CPU0_P1_RX_BUF_DP<13>")
	)
	(arc
		(start 348.783656 -412.29153)
		(mid 348.786782 -412.228358)
		(end 348.796102 -412.1658)
		(width 0.14224)
		(layer "In13.Cu")
		(net "P5E_CPU0_P1_RX_BUF_DP<13>")
	)
	(arc
		(start 344.941144 -422.27373)
		(mid 345.207126 -422.131708)
		(end 345.440254 -421.940482)
		(width 0.14224)
		(layer "In13.Cu")
		(net "P5E_CPU0_P1_RX_BUF_DP<13>")
	)
	(arc
		(start 342.866726 -423.214292)
		(mid 343.556605 -422.867182)
		(end 344.26271 -422.5544)
		(width 0.14224)
		(layer "In13.Cu")
		(net "P5E_CPU0_P1_RX_BUF_DP<13>")
	)
	(arc
		(start 347.457014 -414.52546)
		(mid 347.637484 -414.377314)
		(end 347.843348 -414.267142)
		(width 0.14224)
		(layer "In13.Cu")
		(net "P5E_CPU0_P1_RX_BUF_DP<13>")
	)
	(arc
		(start 340.97087 -424.629326)
		(mid 340.979864 -424.559129)
		(end 341.006176 -424.493436)
		(width 0.14224)
		(layer "In13.Cu")
		(net "P5E_CPU0_P1_RX_BUF_DP<13>")
	)
	(arc
		(start 350.96577 -404.812754)
		(mid 351.0123 -404.717483)
		(end 351.078546 -404.6347)
		(width 0.14224)
		(layer "In13.Cu")
		(net "P5E_CPU0_P1_RX_BUF_DP<13>")
	)
	(arc
		(start 345.600528 -421.780462)
		(mid 345.689321 -421.647624)
		(end 345.720416 -421.490902)
		(width 0.14224)
		(layer "In13.Cu")
		(net "P5E_CPU0_P1_RX_BUF_DP<13>")
	)
	(segment
		(start 350.041464 -401.105878)
		(end 350.294702 -401.359116)
		(width 0.1016)
		(layer "F.Cu")
		(net "P5E_CPU0_P1_RX_BUF_DP<12>")
	)
	(segment
		(start 350.045528 -399.663158)
		(end 350.13011 -399.74774)
		(width 0.1016)
		(layer "F.Cu")
		(net "P5E_CPU0_P1_RX_BUF_DP<12>")
	)
	(segment
		(start 350.13011 -399.870676)
		(end 350.041464 -399.959322)
		(width 0.1016)
		(layer "F.Cu")
		(net "P5E_CPU0_P1_RX_BUF_DP<12>")
	)
	(segment
		(start 350.041464 -399.959322)
		(end 350.041464 -401.105878)
		(width 0.1016)
		(layer "F.Cu")
		(net "P5E_CPU0_P1_RX_BUF_DP<12>")
	)
	(segment
		(start 350.744028 -401.501102)
		(end 350.744028 -401.674838)
		(width 0.1016)
		(layer "F.Cu")
		(net "P5E_CPU0_P1_RX_BUF_DP<12>")
	)
	(segment
		(start 350.13011 -399.74774)
		(end 350.13011 -399.870676)
		(width 0.1016)
		(layer "F.Cu")
		(net "P5E_CPU0_P1_RX_BUF_DP<12>")
	)
	(segment
		(start 350.294702 -401.359116)
		(end 350.602042 -401.359116)
		(width 0.1016)
		(layer "F.Cu")
		(net "P5E_CPU0_P1_RX_BUF_DP<12>")
	)
	(segment
		(start 350.602042 -401.359116)
		(end 350.744028 -401.501102)
		(width 0.1016)
		(layer "F.Cu")
		(net "P5E_CPU0_P1_RX_BUF_DP<12>")
	)
	(segment
		(start 340.063074 -423.742358)
		(end 339.707474 -423.978832)
		(width 0.14224)
		(layer "In13.Cu")
		(net "P5E_CPU0_P1_RX_BUF_DP<12>")
	)
	(segment
		(start 339.649816 -433.621942)
		(end 339.649816 -433.289964)
		(width 0.14224)
		(layer "In13.Cu")
		(net "P5E_CPU0_P1_RX_BUF_DP<12>")
	)
	(segment
		(start 338.970874 -424.791886)
		(end 338.970874 -433.556664)
		(width 0.14224)
		(layer "In13.Cu")
		(net "P5E_CPU0_P1_RX_BUF_DP<12>")
	)
	(segment
		(start 345.371166 -413.942276)
		(end 345.055698 -414.153096)
		(width 0.14224)
		(layer "In13.Cu")
		(net "P5E_CPU0_P1_RX_BUF_DP<12>")
	)
	(segment
		(start 350.42729 -401.399756)
		(end 350.28505 -401.541996)
		(width 0.14224)
		(layer "In13.Cu")
		(net "P5E_CPU0_P1_RX_BUF_DP<12>")
	)
	(segment
		(start 347.561408 -409.075382)
		(end 347.37294 -409.122626)
		(width 0.14224)
		(layer "In13.Cu")
		(net "P5E_CPU0_P1_RX_BUF_DP<12>")
	)
	(segment
		(start 346.981526 -410.042868)
		(end 346.793058 -410.090112)
		(width 0.14224)
		(layer "In13.Cu")
		(net "P5E_CPU0_P1_RX_BUF_DP<12>")
	)
	(segment
		(start 346.461588 -410.910024)
		(end 346.242132 -411.276292)
		(width 0.14224)
		(layer "In13.Cu")
		(net "P5E_CPU0_P1_RX_BUF_DP<12>")
	)
	(segment
		(start 347.73362 -408.5209)
		(end 347.780864 -408.709114)
		(width 0.14224)
		(layer "In13.Cu")
		(net "P5E_CPU0_P1_RX_BUF_DP<12>")
	)
	(segment
		(start 350.28505 -403.752558)
		(end 349.999554 -404.658068)
		(width 0.14224)
		(layer "In13.Cu")
		(net "P5E_CPU0_P1_RX_BUF_DP<12>")
	)
	(segment
		(start 344.325956 -417.458144)
		(end 344.325956 -417.884864)
		(width 0.14224)
		(layer "In13.Cu")
		(net "P5E_CPU0_P1_RX_BUF_DP<12>")
	)
	(segment
		(start 345.792806 -411.807914)
		(end 345.729052 -412.27502)
		(width 0.14224)
		(layer "In13.Cu")
		(net "P5E_CPU0_P1_RX_BUF_DP<12>")
	)
	(segment
		(start 348.313756 -407.553668)
		(end 348.360746 -407.741882)
		(width 0.14224)
		(layer "In13.Cu")
		(net "P5E_CPU0_P1_RX_BUF_DP<12>")
	)
	(segment
		(start 339.172804 -424.170094)
		(end 339.156802 -424.188128)
		(width 0.14224)
		(layer "In13.Cu")
		(net "P5E_CPU0_P1_RX_BUF_DP<12>")
	)
	(segment
		(start 346.793058 -410.090112)
		(end 346.414344 -410.72181)
		(width 0.14224)
		(layer "In13.Cu")
		(net "P5E_CPU0_P1_RX_BUF_DP<12>")
	)
	(segment
		(start 350.744028 -401.526756)
		(end 350.617028 -401.399756)
		(width 0.14224)
		(layer "In13.Cu")
		(net "P5E_CPU0_P1_RX_BUF_DP<12>")
	)
	(segment
		(start 348.532958 -407.187908)
		(end 348.313756 -407.553668)
		(width 0.14224)
		(layer "In13.Cu")
		(net "P5E_CPU0_P1_RX_BUF_DP<12>")
	)
	(segment
		(start 345.055698 -414.153096)
		(end 344.780108 -414.267142)
		(width 0.14224)
		(layer "In13.Cu")
		(net "P5E_CPU0_P1_RX_BUF_DP<12>")
	)
	(segment
		(start 349.348806 -406.094946)
		(end 349.160338 -406.141936)
		(width 0.14224)
		(layer "In13.Cu")
		(net "P5E_CPU0_P1_RX_BUF_DP<12>")
	)
	(segment
		(start 347.153738 -409.488386)
		(end 347.200728 -409.6766)
		(width 0.14224)
		(layer "In13.Cu")
		(net "P5E_CPU0_P1_RX_BUF_DP<12>")
	)
	(segment
		(start 343.696544 -419.702742)
		(end 342.744806 -420.09695)
		(width 0.14224)
		(layer "In13.Cu")
		(net "P5E_CPU0_P1_RX_BUF_DP<12>")
	)
	(segment
		(start 341.040212 -422.927272)
		(end 341.002112 -423.117518)
		(width 0.14224)
		(layer "In13.Cu")
		(net "P5E_CPU0_P1_RX_BUF_DP<12>")
	)
	(segment
		(start 346.053664 -411.323536)
		(end 345.834462 -411.689296)
		(width 0.14224)
		(layer "In13.Cu")
		(net "P5E_CPU0_P1_RX_BUF_DP<12>")
	)
	(segment
		(start 342.347804 -422.057576)
		(end 341.979758 -422.302432)
		(width 0.14224)
		(layer "In13.Cu")
		(net "P5E_CPU0_P1_RX_BUF_DP<12>")
	)
	(segment
		(start 349.846392 -404.998174)
		(end 349.521272 -405.540464)
		(width 0.14224)
		(layer "In13.Cu")
		(net "P5E_CPU0_P1_RX_BUF_DP<12>")
	)
	(segment
		(start 350.744028 -401.674838)
		(end 350.744028 -401.526756)
		(width 0.14224)
		(layer "In13.Cu")
		(net "P5E_CPU0_P1_RX_BUF_DP<12>")
	)
	(segment
		(start 339.707474 -423.978832)
		(end 339.517228 -423.940732)
		(width 0.14224)
		(layer "In13.Cu")
		(net "P5E_CPU0_P1_RX_BUF_DP<12>")
	)
	(segment
		(start 348.721426 -407.140664)
		(end 348.532958 -407.187908)
		(width 0.14224)
		(layer "In13.Cu")
		(net "P5E_CPU0_P1_RX_BUF_DP<12>")
	)
	(segment
		(start 345.517978 -413.795464)
		(end 345.371166 -413.942276)
		(width 0.14224)
		(layer "In13.Cu")
		(net "P5E_CPU0_P1_RX_BUF_DP<12>")
	)
	(segment
		(start 350.617028 -401.399756)
		(end 350.42729 -401.399756)
		(width 0.14224)
		(layer "In13.Cu")
		(net "P5E_CPU0_P1_RX_BUF_DP<12>")
	)
	(segment
		(start 345.720416 -412.401258)
		(end 345.720416 -413.306514)
		(width 0.14224)
		(layer "In13.Cu")
		(net "P5E_CPU0_P1_RX_BUF_DP<12>")
	)
	(segment
		(start 348.14129 -408.107896)
		(end 347.953076 -408.15514)
		(width 0.14224)
		(layer "In13.Cu")
		(net "P5E_CPU0_P1_RX_BUF_DP<12>")
	)
	(segment
		(start 349.160338 -406.141936)
		(end 348.893892 -406.586436)
		(width 0.14224)
		(layer "In13.Cu")
		(net "P5E_CPU0_P1_RX_BUF_DP<12>")
	)
	(segment
		(start 341.002112 -423.117518)
		(end 340.646512 -423.353992)
		(width 0.14224)
		(layer "In13.Cu")
		(net "P5E_CPU0_P1_RX_BUF_DP<12>")
	)
	(segment
		(start 349.568262 -405.728678)
		(end 349.348806 -406.094946)
		(width 0.14224)
		(layer "In13.Cu")
		(net "P5E_CPU0_P1_RX_BUF_DP<12>")
	)
	(segment
		(start 344.188796 -415.020252)
		(end 344.188796 -416.193224)
		(width 0.14224)
		(layer "In13.Cu")
		(net "P5E_CPU0_P1_RX_BUF_DP<12>")
	)
	(segment
		(start 341.586058 -422.729152)
		(end 341.395812 -422.690798)
		(width 0.14224)
		(layer "In13.Cu")
		(net "P5E_CPU0_P1_RX_BUF_DP<12>")
	)
	(segment
		(start 341.04072 -422.927018)
		(end 341.040212 -422.927272)
		(width 0.14224)
		(layer "In13.Cu")
		(net "P5E_CPU0_P1_RX_BUF_DP<12>")
	)
	(segment
		(start 349.521272 -405.540464)
		(end 349.568262 -405.728678)
		(width 0.14224)
		(layer "In13.Cu")
		(net "P5E_CPU0_P1_RX_BUF_DP<12>")
	)
	(segment
		(start 344.188796 -417.320984)
		(end 344.325956 -417.458144)
		(width 0.14224)
		(layer "In13.Cu")
		(net "P5E_CPU0_P1_RX_BUF_DP<12>")
	)
	(segment
		(start 344.188796 -416.894264)
		(end 344.188796 -417.320984)
		(width 0.14224)
		(layer "In13.Cu")
		(net "P5E_CPU0_P1_RX_BUF_DP<12>")
	)
	(segment
		(start 344.188796 -418.022024)
		(end 344.188796 -419.079172)
		(width 0.14224)
		(layer "In13.Cu")
		(net "P5E_CPU0_P1_RX_BUF_DP<12>")
	)
	(segment
		(start 344.188796 -416.193224)
		(end 344.325956 -416.330384)
		(width 0.14224)
		(layer "In13.Cu")
		(net "P5E_CPU0_P1_RX_BUF_DP<12>")
	)
	(segment
		(start 341.941658 -422.492424)
		(end 341.586058 -422.729152)
		(width 0.14224)
		(layer "In13.Cu")
		(net "P5E_CPU0_P1_RX_BUF_DP<12>")
	)
	(segment
		(start 344.065098 -419.388798)
		(end 343.897712 -419.56482)
		(width 0.14224)
		(layer "In13.Cu")
		(net "P5E_CPU0_P1_RX_BUF_DP<12>")
	)
	(segment
		(start 347.200728 -409.6766)
		(end 346.981526 -410.042868)
		(width 0.14224)
		(layer "In13.Cu")
		(net "P5E_CPU0_P1_RX_BUF_DP<12>")
	)
	(segment
		(start 340.456266 -423.315892)
		(end 340.101174 -423.552112)
		(width 0.14224)
		(layer "In13.Cu")
		(net "P5E_CPU0_P1_RX_BUF_DP<12>")
	)
	(segment
		(start 341.395812 -422.690798)
		(end 341.04072 -422.927018)
		(width 0.14224)
		(layer "In13.Cu")
		(net "P5E_CPU0_P1_RX_BUF_DP<12>")
	)
	(segment
		(start 339.156802 -424.188128)
		(end 339.060028 -424.394122)
		(width 0.14224)
		(layer "In13.Cu")
		(net "P5E_CPU0_P1_RX_BUF_DP<12>")
	)
	(segment
		(start 348.893892 -406.586436)
		(end 348.940882 -406.774396)
		(width 0.14224)
		(layer "In13.Cu")
		(net "P5E_CPU0_P1_RX_BUF_DP<12>")
	)
	(segment
		(start 349.999554 -404.658068)
		(end 349.846392 -404.998174)
		(width 0.14224)
		(layer "In13.Cu")
		(net "P5E_CPU0_P1_RX_BUF_DP<12>")
	)
	(segment
		(start 340.101174 -423.552112)
		(end 340.063074 -423.742358)
		(width 0.14224)
		(layer "In13.Cu")
		(net "P5E_CPU0_P1_RX_BUF_DP<12>")
	)
	(segment
		(start 347.953076 -408.15514)
		(end 347.73362 -408.5209)
		(width 0.14224)
		(layer "In13.Cu")
		(net "P5E_CPU0_P1_RX_BUF_DP<12>")
	)
	(segment
		(start 342.537288 -421.868092)
		(end 342.347804 -422.057576)
		(width 0.14224)
		(layer "In13.Cu")
		(net "P5E_CPU0_P1_RX_BUF_DP<12>")
	)
	(segment
		(start 341.979758 -422.302432)
		(end 341.941658 -422.492424)
		(width 0.14224)
		(layer "In13.Cu")
		(net "P5E_CPU0_P1_RX_BUF_DP<12>")
	)
	(segment
		(start 350.28505 -401.541996)
		(end 350.28505 -403.752558)
		(width 0.14224)
		(layer "In13.Cu")
		(net "P5E_CPU0_P1_RX_BUF_DP<12>")
	)
	(segment
		(start 344.325956 -416.757104)
		(end 344.188796 -416.894264)
		(width 0.14224)
		(layer "In13.Cu")
		(net "P5E_CPU0_P1_RX_BUF_DP<12>")
	)
	(segment
		(start 344.325956 -417.884864)
		(end 344.188796 -418.022024)
		(width 0.14224)
		(layer "In13.Cu")
		(net "P5E_CPU0_P1_RX_BUF_DP<12>")
	)
	(segment
		(start 346.242132 -411.276292)
		(end 346.053664 -411.323536)
		(width 0.14224)
		(layer "In13.Cu")
		(net "P5E_CPU0_P1_RX_BUF_DP<12>")
	)
	(segment
		(start 347.780864 -408.709114)
		(end 347.561408 -409.075382)
		(width 0.14224)
		(layer "In13.Cu")
		(net "P5E_CPU0_P1_RX_BUF_DP<12>")
	)
	(segment
		(start 342.657176 -420.228014)
		(end 342.657176 -421.578532)
		(width 0.14224)
		(layer "In13.Cu")
		(net "P5E_CPU0_P1_RX_BUF_DP<12>")
	)
	(segment
		(start 340.646512 -423.353992)
		(end 340.456266 -423.315892)
		(width 0.14224)
		(layer "In13.Cu")
		(net "P5E_CPU0_P1_RX_BUF_DP<12>")
	)
	(segment
		(start 348.360746 -407.741882)
		(end 348.14129 -408.107896)
		(width 0.14224)
		(layer "In13.Cu")
		(net "P5E_CPU0_P1_RX_BUF_DP<12>")
	)
	(segment
		(start 348.940882 -406.774396)
		(end 348.721426 -407.140664)
		(width 0.14224)
		(layer "In13.Cu")
		(net "P5E_CPU0_P1_RX_BUF_DP<12>")
	)
	(segment
		(start 339.522816 -433.748942)
		(end 339.649816 -433.621942)
		(width 0.14224)
		(layer "In13.Cu")
		(net "P5E_CPU0_P1_RX_BUF_DP<12>")
	)
	(segment
		(start 339.163152 -433.748942)
		(end 339.522816 -433.748942)
		(width 0.14224)
		(layer "In13.Cu")
		(net "P5E_CPU0_P1_RX_BUF_DP<12>")
	)
	(segment
		(start 344.325956 -416.330384)
		(end 344.325956 -416.757104)
		(width 0.14224)
		(layer "In13.Cu")
		(net "P5E_CPU0_P1_RX_BUF_DP<12>")
	)
	(segment
		(start 346.414344 -410.72181)
		(end 346.461588 -410.910024)
		(width 0.14224)
		(layer "In13.Cu")
		(net "P5E_CPU0_P1_RX_BUF_DP<12>")
	)
	(segment
		(start 347.37294 -409.122626)
		(end 347.153738 -409.488386)
		(width 0.14224)
		(layer "In13.Cu")
		(net "P5E_CPU0_P1_RX_BUF_DP<12>")
	)
	(segment
		(start 339.517228 -423.940732)
		(end 339.172804 -424.170094)
		(width 0.14224)
		(layer "In13.Cu")
		(net "P5E_CPU0_P1_RX_BUF_DP<12>")
	)
	(arc
		(start 344.780108 -414.267142)
		(mid 344.574226 -414.377288)
		(end 344.393774 -414.52546)
		(width 0.14224)
		(layer "In13.Cu")
		(net "P5E_CPU0_P1_RX_BUF_DP<12>")
	)
	(arc
		(start 342.744806 -420.09695)
		(mid 342.681169 -420.149211)
		(end 342.657176 -420.228014)
		(width 0.14224)
		(layer "In13.Cu")
		(net "P5E_CPU0_P1_RX_BUF_DP<12>")
	)
	(arc
		(start 345.729052 -412.27502)
		(mid 345.722583 -412.337992)
		(end 345.720416 -412.401258)
		(width 0.14224)
		(layer "In13.Cu")
		(net "P5E_CPU0_P1_RX_BUF_DP<12>")
	)
	(arc
		(start 342.657176 -421.578532)
		(mid 342.626024 -421.735235)
		(end 342.537288 -421.868092)
		(width 0.14224)
		(layer "In13.Cu")
		(net "P5E_CPU0_P1_RX_BUF_DP<12>")
	)
	(arc
		(start 339.060028 -424.394122)
		(mid 338.993458 -424.588077)
		(end 338.970874 -424.791886)
		(width 0.14224)
		(layer "In13.Cu")
		(net "P5E_CPU0_P1_RX_BUF_DP<12>")
	)
	(arc
		(start 344.393774 -414.52546)
		(mid 344.242011 -414.752445)
		(end 344.188796 -415.020252)
		(width 0.14224)
		(layer "In13.Cu")
		(net "P5E_CPU0_P1_RX_BUF_DP<12>")
	)
	(arc
		(start 345.834462 -411.689296)
		(mid 345.807615 -411.746492)
		(end 345.792806 -411.807914)
		(width 0.14224)
		(layer "In13.Cu")
		(net "P5E_CPU0_P1_RX_BUF_DP<12>")
	)
	(arc
		(start 343.897712 -419.56482)
		(mid 343.804354 -419.644321)
		(end 343.696544 -419.702742)
		(width 0.14224)
		(layer "In13.Cu")
		(net "P5E_CPU0_P1_RX_BUF_DP<12>")
	)
	(arc
		(start 344.188796 -419.079172)
		(mid 344.156831 -419.24593)
		(end 344.065098 -419.388798)
		(width 0.14224)
		(layer "In13.Cu")
		(net "P5E_CPU0_P1_RX_BUF_DP<12>")
	)
	(arc
		(start 345.720416 -413.306514)
		(mid 345.667802 -413.571111)
		(end 345.517978 -413.795464)
		(width 0.14224)
		(layer "In13.Cu")
		(net "P5E_CPU0_P1_RX_BUF_DP<12>")
	)
	(arc
		(start 338.970874 -433.556664)
		(mid 339.027191 -433.692625)
		(end 339.163152 -433.748942)
		(width 0.14224)
		(layer "In13.Cu")
		(net "P5E_CPU0_P1_RX_BUF_DP<12>")
	)
	(segment
		(start 348.92996 -399.74774)
		(end 348.92996 -399.870676)
		(width 0.1016)
		(layer "F.Cu")
		(net "P5E_CPU0_P1_RX_BUF_DP<11>")
	)
	(segment
		(start 348.845378 -399.663158)
		(end 348.92996 -399.74774)
		(width 0.1016)
		(layer "F.Cu")
		(net "P5E_CPU0_P1_RX_BUF_DP<11>")
	)
	(segment
		(start 349.544132 -401.498054)
		(end 349.544132 -401.674838)
		(width 0.1016)
		(layer "F.Cu")
		(net "P5E_CPU0_P1_RX_BUF_DP<11>")
	)
	(segment
		(start 349.094552 -401.359116)
		(end 349.405194 -401.359116)
		(width 0.1016)
		(layer "F.Cu")
		(net "P5E_CPU0_P1_RX_BUF_DP<11>")
	)
	(segment
		(start 348.841314 -399.959322)
		(end 348.841314 -401.105878)
		(width 0.1016)
		(layer "F.Cu")
		(net "P5E_CPU0_P1_RX_BUF_DP<11>")
	)
	(segment
		(start 349.405194 -401.359116)
		(end 349.544132 -401.498054)
		(width 0.1016)
		(layer "F.Cu")
		(net "P5E_CPU0_P1_RX_BUF_DP<11>")
	)
	(segment
		(start 348.92996 -399.870676)
		(end 348.841314 -399.959322)
		(width 0.1016)
		(layer "F.Cu")
		(net "P5E_CPU0_P1_RX_BUF_DP<11>")
	)
	(segment
		(start 348.841314 -401.105878)
		(end 349.094552 -401.359116)
		(width 0.1016)
		(layer "F.Cu")
		(net "P5E_CPU0_P1_RX_BUF_DP<11>")
	)
	(segment
		(start 341.125556 -417.068254)
		(end 341.125556 -416.641534)
		(width 0.14224)
		(layer "In13.Cu")
		(net "P5E_CPU0_P1_RX_BUF_DP<11>")
	)
	(segment
		(start 349.227394 -401.399756)
		(end 349.417132 -401.399756)
		(width 0.14224)
		(layer "In13.Cu")
		(net "P5E_CPU0_P1_RX_BUF_DP<11>")
	)
	(segment
		(start 344.395552 -410.361384)
		(end 344.3859 -410.167836)
		(width 0.14224)
		(layer "In13.Cu")
		(net "P5E_CPU0_P1_RX_BUF_DP<11>")
	)
	(segment
		(start 338.526882 -423.026586)
		(end 338.825332 -422.721024)
		(width 0.14224)
		(layer "In13.Cu")
		(net "P5E_CPU0_P1_RX_BUF_DP<11>")
	)
	(segment
		(start 343.157556 -411.52318)
		(end 343.351358 -411.513528)
		(width 0.14224)
		(layer "In13.Cu")
		(net "P5E_CPU0_P1_RX_BUF_DP<11>")
	)
	(segment
		(start 341.125556 -416.641534)
		(end 341.262716 -416.504374)
		(width 0.14224)
		(layer "In13.Cu")
		(net "P5E_CPU0_P1_RX_BUF_DP<11>")
	)
	(segment
		(start 348.135956 -405.760682)
		(end 348.373446 -405.40559)
		(width 0.14224)
		(layer "In13.Cu")
		(net "P5E_CPU0_P1_RX_BUF_DP<11>")
	)
	(segment
		(start 345.910408 -408.690064)
		(end 345.900756 -408.496516)
		(width 0.14224)
		(layer "In13.Cu")
		(net "P5E_CPU0_P1_RX_BUF_DP<11>")
	)
	(segment
		(start 347.94571 -405.798528)
		(end 348.135956 -405.760682)
		(width 0.14224)
		(layer "In13.Cu")
		(net "P5E_CPU0_P1_RX_BUF_DP<11>")
	)
	(segment
		(start 341.262716 -416.077654)
		(end 341.125556 -415.940494)
		(width 0.14224)
		(layer "In13.Cu")
		(net "P5E_CPU0_P1_RX_BUF_DP<11>")
	)
	(segment
		(start 342.721438 -412.09341)
		(end 342.78824 -411.956758)
		(width 0.14224)
		(layer "In13.Cu")
		(net "P5E_CPU0_P1_RX_BUF_DP<11>")
	)
	(segment
		(start 337.24596 -424.140122)
		(end 337.544156 -423.835068)
		(width 0.14224)
		(layer "In13.Cu")
		(net "P5E_CPU0_P1_RX_BUF_DP<11>")
	)
	(segment
		(start 349.222314 -402.984208)
		(end 349.085154 -402.847048)
		(width 0.14224)
		(layer "In13.Cu")
		(net "P5E_CPU0_P1_RX_BUF_DP<11>")
	)
	(segment
		(start 338.03463 -423.333672)
		(end 338.332826 -423.028618)
		(width 0.14224)
		(layer "In13.Cu")
		(net "P5E_CPU0_P1_RX_BUF_DP<11>")
	)
	(segment
		(start 349.010478 -404.205694)
		(end 349.085154 -403.959568)
		(width 0.14224)
		(layer "In13.Cu")
		(net "P5E_CPU0_P1_RX_BUF_DP<11>")
	)
	(segment
		(start 349.085154 -403.548088)
		(end 349.222314 -403.410928)
		(width 0.14224)
		(layer "In13.Cu")
		(net "P5E_CPU0_P1_RX_BUF_DP<11>")
	)
	(segment
		(start 345.15298 -409.525724)
		(end 345.143328 -409.332176)
		(width 0.14224)
		(layer "In13.Cu")
		(net "P5E_CPU0_P1_RX_BUF_DP<11>")
	)
	(segment
		(start 338.823046 -422.527222)
		(end 339.47735 -421.857932)
		(width 0.14224)
		(layer "In13.Cu")
		(net "P5E_CPU0_P1_RX_BUF_DP<11>")
	)
	(segment
		(start 349.544132 -401.526756)
		(end 349.544132 -401.674838)
		(width 0.14224)
		(layer "In13.Cu")
		(net "P5E_CPU0_P1_RX_BUF_DP<11>")
	)
	(segment
		(start 347.231462 -406.866852)
		(end 347.94571 -405.798528)
		(width 0.14224)
		(layer "In13.Cu")
		(net "P5E_CPU0_P1_RX_BUF_DP<11>")
	)
	(segment
		(start 342.668606 -412.343092)
		(end 342.705944 -412.140654)
		(width 0.14224)
		(layer "In13.Cu")
		(net "P5E_CPU0_P1_RX_BUF_DP<11>")
	)
	(segment
		(start 341.125556 -417.769294)
		(end 341.262716 -417.632134)
		(width 0.14224)
		(layer "In13.Cu")
		(net "P5E_CPU0_P1_RX_BUF_DP<11>")
	)
	(segment
		(start 345.42984 -409.0162)
		(end 345.623388 -409.006548)
		(width 0.14224)
		(layer "In13.Cu")
		(net "P5E_CPU0_P1_RX_BUF_DP<11>")
	)
	(segment
		(start 342.859106 -411.852364)
		(end 343.157556 -411.52318)
		(width 0.14224)
		(layer "In13.Cu")
		(net "P5E_CPU0_P1_RX_BUF_DP<11>")
	)
	(segment
		(start 342.307926 -413.942276)
		(end 342.454738 -413.795464)
		(width 0.14224)
		(layer "In13.Cu")
		(net "P5E_CPU0_P1_RX_BUF_DP<11>")
	)
	(segment
		(start 339.681566 -420.09695)
		(end 340.634066 -419.70198)
		(width 0.14224)
		(layer "In13.Cu")
		(net "P5E_CPU0_P1_RX_BUF_DP<11>")
	)
	(segment
		(start 339.593936 -421.571928)
		(end 339.593936 -420.228268)
		(width 0.14224)
		(layer "In13.Cu")
		(net "P5E_CPU0_P1_RX_BUF_DP<11>")
	)
	(segment
		(start 341.262716 -416.504374)
		(end 341.262716 -416.077654)
		(width 0.14224)
		(layer "In13.Cu")
		(net "P5E_CPU0_P1_RX_BUF_DP<11>")
	)
	(segment
		(start 349.085154 -403.959568)
		(end 349.085154 -403.548088)
		(width 0.14224)
		(layer "In13.Cu")
		(net "P5E_CPU0_P1_RX_BUF_DP<11>")
	)
	(segment
		(start 344.108532 -410.677868)
		(end 344.395552 -410.361384)
		(width 0.14224)
		(layer "In13.Cu")
		(net "P5E_CPU0_P1_RX_BUF_DP<11>")
	)
	(segment
		(start 341.125556 -419.079172)
		(end 341.125556 -417.769294)
		(width 0.14224)
		(layer "In13.Cu")
		(net "P5E_CPU0_P1_RX_BUF_DP<11>")
	)
	(segment
		(start 341.125556 -415.940494)
		(end 341.125556 -415.020252)
		(width 0.14224)
		(layer "In13.Cu")
		(net "P5E_CPU0_P1_RX_BUF_DP<11>")
	)
	(segment
		(start 345.623388 -409.006548)
		(end 345.910408 -408.690064)
		(width 0.14224)
		(layer "In13.Cu")
		(net "P5E_CPU0_P1_RX_BUF_DP<11>")
	)
	(segment
		(start 341.992458 -414.153096)
		(end 342.307926 -413.942276)
		(width 0.14224)
		(layer "In13.Cu")
		(net "P5E_CPU0_P1_RX_BUF_DP<11>")
	)
	(segment
		(start 344.672412 -409.85186)
		(end 344.86596 -409.842208)
		(width 0.14224)
		(layer "In13.Cu")
		(net "P5E_CPU0_P1_RX_BUF_DP<11>")
	)
	(segment
		(start 338.332826 -423.028618)
		(end 338.526882 -423.026586)
		(width 0.14224)
		(layer "In13.Cu")
		(net "P5E_CPU0_P1_RX_BUF_DP<11>")
	)
	(segment
		(start 344.86596 -409.842208)
		(end 345.15298 -409.525724)
		(width 0.14224)
		(layer "In13.Cu")
		(net "P5E_CPU0_P1_RX_BUF_DP<11>")
	)
	(segment
		(start 341.262716 -417.632134)
		(end 341.262716 -417.205414)
		(width 0.14224)
		(layer "In13.Cu")
		(net "P5E_CPU0_P1_RX_BUF_DP<11>")
	)
	(segment
		(start 349.222314 -403.410928)
		(end 349.222314 -402.984208)
		(width 0.14224)
		(layer "In13.Cu")
		(net "P5E_CPU0_P1_RX_BUF_DP<11>")
	)
	(segment
		(start 349.417132 -401.399756)
		(end 349.544132 -401.526756)
		(width 0.14224)
		(layer "In13.Cu")
		(net "P5E_CPU0_P1_RX_BUF_DP<11>")
	)
	(segment
		(start 349.085154 -402.847048)
		(end 349.085154 -401.541996)
		(width 0.14224)
		(layer "In13.Cu")
		(net "P5E_CPU0_P1_RX_BUF_DP<11>")
	)
	(segment
		(start 337.52282 -434.74894)
		(end 337.097878 -434.74894)
		(width 0.14224)
		(layer "In13.Cu")
		(net "P5E_CPU0_P1_RX_BUF_DP<11>")
	)
	(segment
		(start 343.351358 -411.513528)
		(end 343.638124 -411.197044)
		(width 0.14224)
		(layer "In13.Cu")
		(net "P5E_CPU0_P1_RX_BUF_DP<11>")
	)
	(segment
		(start 348.373446 -405.40559)
		(end 348.3356 -405.215344)
		(width 0.14224)
		(layer "In13.Cu")
		(net "P5E_CPU0_P1_RX_BUF_DP<11>")
	)
	(segment
		(start 343.638124 -411.197044)
		(end 343.628472 -411.003496)
		(width 0.14224)
		(layer "In13.Cu")
		(net "P5E_CPU0_P1_RX_BUF_DP<11>")
	)
	(segment
		(start 341.716868 -414.267142)
		(end 341.992458 -414.153096)
		(width 0.14224)
		(layer "In13.Cu")
		(net "P5E_CPU0_P1_RX_BUF_DP<11>")
	)
	(segment
		(start 337.738212 -423.833036)
		(end 338.036662 -423.527474)
		(width 0.14224)
		(layer "In13.Cu")
		(net "P5E_CPU0_P1_RX_BUF_DP<11>")
	)
	(segment
		(start 342.657176 -413.306514)
		(end 342.657176 -412.469076)
		(width 0.14224)
		(layer "In13.Cu")
		(net "P5E_CPU0_P1_RX_BUF_DP<11>")
	)
	(segment
		(start 337.097878 -434.74894)
		(end 336.970878 -434.62194)
		(width 0.14224)
		(layer "In13.Cu")
		(net "P5E_CPU0_P1_RX_BUF_DP<11>")
	)
	(segment
		(start 338.825332 -422.721024)
		(end 338.823046 -422.527222)
		(width 0.14224)
		(layer "In13.Cu")
		(net "P5E_CPU0_P1_RX_BUF_DP<11>")
	)
	(segment
		(start 345.143328 -409.332176)
		(end 345.42984 -409.0162)
		(width 0.14224)
		(layer "In13.Cu")
		(net "P5E_CPU0_P1_RX_BUF_DP<11>")
	)
	(segment
		(start 343.628472 -411.003496)
		(end 343.914984 -410.68752)
		(width 0.14224)
		(layer "In13.Cu")
		(net "P5E_CPU0_P1_RX_BUF_DP<11>")
	)
	(segment
		(start 337.64982 -434.289962)
		(end 337.64982 -434.62194)
		(width 0.14224)
		(layer "In13.Cu")
		(net "P5E_CPU0_P1_RX_BUF_DP<11>")
	)
	(segment
		(start 337.64982 -434.62194)
		(end 337.52282 -434.74894)
		(width 0.14224)
		(layer "In13.Cu")
		(net "P5E_CPU0_P1_RX_BUF_DP<11>")
	)
	(segment
		(start 345.900756 -408.496516)
		(end 346.31757 -408.036522)
		(width 0.14224)
		(layer "In13.Cu")
		(net "P5E_CPU0_P1_RX_BUF_DP<11>")
	)
	(segment
		(start 348.3356 -405.215344)
		(end 349.010478 -404.205694)
		(width 0.14224)
		(layer "In13.Cu")
		(net "P5E_CPU0_P1_RX_BUF_DP<11>")
	)
	(segment
		(start 338.036662 -423.527474)
		(end 338.03463 -423.333672)
		(width 0.14224)
		(layer "In13.Cu")
		(net "P5E_CPU0_P1_RX_BUF_DP<11>")
	)
	(segment
		(start 344.3859 -410.167836)
		(end 344.672412 -409.85186)
		(width 0.14224)
		(layer "In13.Cu")
		(net "P5E_CPU0_P1_RX_BUF_DP<11>")
	)
	(segment
		(start 340.834472 -419.56482)
		(end 341.001858 -419.388798)
		(width 0.14224)
		(layer "In13.Cu")
		(net "P5E_CPU0_P1_RX_BUF_DP<11>")
	)
	(segment
		(start 349.085154 -401.541996)
		(end 349.227394 -401.399756)
		(width 0.14224)
		(layer "In13.Cu")
		(net "P5E_CPU0_P1_RX_BUF_DP<11>")
	)
	(segment
		(start 343.914984 -410.68752)
		(end 344.108532 -410.677868)
		(width 0.14224)
		(layer "In13.Cu")
		(net "P5E_CPU0_P1_RX_BUF_DP<11>")
	)
	(segment
		(start 337.544156 -423.835068)
		(end 337.738212 -423.833036)
		(width 0.14224)
		(layer "In13.Cu")
		(net "P5E_CPU0_P1_RX_BUF_DP<11>")
	)
	(segment
		(start 341.262716 -417.205414)
		(end 341.125556 -417.068254)
		(width 0.14224)
		(layer "In13.Cu")
		(net "P5E_CPU0_P1_RX_BUF_DP<11>")
	)
	(segment
		(start 336.992722 -424.518836)
		(end 337.24596 -424.140122)
		(width 0.14224)
		(layer "In13.Cu")
		(net "P5E_CPU0_P1_RX_BUF_DP<11>")
	)
	(segment
		(start 336.970878 -434.62194)
		(end 336.970878 -424.590464)
		(width 0.14224)
		(layer "In13.Cu")
		(net "P5E_CPU0_P1_RX_BUF_DP<11>")
	)
	(arc
		(start 339.47735 -421.857932)
		(mid 339.56365 -421.72635)
		(end 339.593936 -421.571928)
		(width 0.14224)
		(layer "In13.Cu")
		(net "P5E_CPU0_P1_RX_BUF_DP<11>")
	)
	(arc
		(start 336.970878 -424.590464)
		(mid 336.976454 -424.553018)
		(end 336.992722 -424.518836)
		(width 0.14224)
		(layer "In13.Cu")
		(net "P5E_CPU0_P1_RX_BUF_DP<11>")
	)
	(arc
		(start 341.001858 -419.388798)
		(mid 341.093534 -419.245907)
		(end 341.125556 -419.079172)
		(width 0.14224)
		(layer "In13.Cu")
		(net "P5E_CPU0_P1_RX_BUF_DP<11>")
	)
	(arc
		(start 342.705944 -412.140654)
		(mid 342.712071 -412.1165)
		(end 342.721438 -412.09341)
		(width 0.14224)
		(layer "In13.Cu")
		(net "P5E_CPU0_P1_RX_BUF_DP<11>")
	)
	(arc
		(start 346.31757 -408.036522)
		(mid 346.796159 -407.468597)
		(end 347.231462 -406.866852)
		(width 0.14224)
		(layer "In13.Cu")
		(net "P5E_CPU0_P1_RX_BUF_DP<11>")
	)
	(arc
		(start 342.657176 -412.469076)
		(mid 342.660012 -412.405822)
		(end 342.668606 -412.343092)
		(width 0.14224)
		(layer "In13.Cu")
		(net "P5E_CPU0_P1_RX_BUF_DP<11>")
	)
	(arc
		(start 341.330534 -414.52546)
		(mid 341.511004 -414.377314)
		(end 341.716868 -414.267142)
		(width 0.14224)
		(layer "In13.Cu")
		(net "P5E_CPU0_P1_RX_BUF_DP<11>")
	)
	(arc
		(start 339.593936 -420.228268)
		(mid 339.617875 -420.14937)
		(end 339.681566 -420.09695)
		(width 0.14224)
		(layer "In13.Cu")
		(net "P5E_CPU0_P1_RX_BUF_DP<11>")
	)
	(arc
		(start 342.454738 -413.795464)
		(mid 342.604578 -413.571118)
		(end 342.657176 -413.306514)
		(width 0.14224)
		(layer "In13.Cu")
		(net "P5E_CPU0_P1_RX_BUF_DP<11>")
	)
	(arc
		(start 340.634066 -419.70198)
		(mid 340.741464 -419.643911)
		(end 340.834472 -419.56482)
		(width 0.14224)
		(layer "In13.Cu")
		(net "P5E_CPU0_P1_RX_BUF_DP<11>")
	)
	(arc
		(start 341.125556 -415.020252)
		(mid 341.178785 -414.752451)
		(end 341.330534 -414.52546)
		(width 0.14224)
		(layer "In13.Cu")
		(net "P5E_CPU0_P1_RX_BUF_DP<11>")
	)
	(arc
		(start 342.78824 -411.956758)
		(mid 342.819997 -411.902065)
		(end 342.859106 -411.852364)
		(width 0.14224)
		(layer "In13.Cu")
		(net "P5E_CPU0_P1_RX_BUF_DP<11>")
	)
	(segment
		(start 347.641418 -399.959322)
		(end 347.729556 -399.871184)
		(width 0.1016)
		(layer "F.Cu")
		(net "P5E_CPU0_P1_RX_BUF_DP<10>")
	)
	(segment
		(start 348.344236 -401.498054)
		(end 348.205298 -401.359116)
		(width 0.1016)
		(layer "F.Cu")
		(net "P5E_CPU0_P1_RX_BUF_DP<10>")
	)
	(segment
		(start 348.205298 -401.359116)
		(end 347.894656 -401.359116)
		(width 0.1016)
		(layer "F.Cu")
		(net "P5E_CPU0_P1_RX_BUF_DP<10>")
	)
	(segment
		(start 347.729556 -399.747232)
		(end 347.645482 -399.663158)
		(width 0.1016)
		(layer "F.Cu")
		(net "P5E_CPU0_P1_RX_BUF_DP<10>")
	)
	(segment
		(start 347.729556 -399.871184)
		(end 347.729556 -399.747232)
		(width 0.1016)
		(layer "F.Cu")
		(net "P5E_CPU0_P1_RX_BUF_DP<10>")
	)
	(segment
		(start 347.641418 -401.105878)
		(end 347.641418 -399.959322)
		(width 0.1016)
		(layer "F.Cu")
		(net "P5E_CPU0_P1_RX_BUF_DP<10>")
	)
	(segment
		(start 347.894656 -401.359116)
		(end 347.641418 -401.105878)
		(width 0.1016)
		(layer "F.Cu")
		(net "P5E_CPU0_P1_RX_BUF_DP<10>")
	)
	(segment
		(start 348.344236 -401.674838)
		(end 348.344236 -401.498054)
		(width 0.1016)
		(layer "F.Cu")
		(net "P5E_CPU0_P1_RX_BUF_DP<10>")
	)
	(segment
		(start 348.217236 -401.399756)
		(end 348.344236 -401.526756)
		(width 0.14224)
		(layer "In13.Cu")
		(net "P5E_CPU0_P1_RX_BUF_DP<10>")
	)
	(segment
		(start 344.308684 -408.46375)
		(end 344.502486 -408.46375)
		(width 0.14224)
		(layer "In13.Cu")
		(net "P5E_CPU0_P1_RX_BUF_DP<10>")
	)
	(segment
		(start 347.23578 -404.884382)
		(end 347.427042 -404.851108)
		(width 0.14224)
		(layer "In13.Cu")
		(net "P5E_CPU0_P1_RX_BUF_DP<10>")
	)
	(segment
		(start 334.970882 -433.596542)
		(end 334.970882 -424.945556)
		(width 0.14224)
		(layer "In13.Cu")
		(net "P5E_CPU0_P1_RX_BUF_DP<10>")
	)
	(segment
		(start 336.618326 -420.09695)
		(end 337.570826 -419.70198)
		(width 0.14224)
		(layer "In13.Cu")
		(net "P5E_CPU0_P1_RX_BUF_DP<10>")
	)
	(segment
		(start 341.459566 -410.925264)
		(end 341.812118 -410.684218)
		(width 0.14224)
		(layer "In13.Cu")
		(net "P5E_CPU0_P1_RX_BUF_DP<10>")
	)
	(segment
		(start 338.653628 -414.267142)
		(end 338.929218 -414.153096)
		(width 0.14224)
		(layer "In13.Cu")
		(net "P5E_CPU0_P1_RX_BUF_DP<10>")
	)
	(segment
		(start 347.885258 -403.962108)
		(end 347.885258 -401.541996)
		(width 0.14224)
		(layer "In13.Cu")
		(net "P5E_CPU0_P1_RX_BUF_DP<10>")
	)
	(segment
		(start 338.199476 -417.660074)
		(end 338.199476 -417.233354)
		(width 0.14224)
		(layer "In13.Cu")
		(net "P5E_CPU0_P1_RX_BUF_DP<10>")
	)
	(segment
		(start 336.190082 -422.660064)
		(end 336.128868 -422.475914)
		(width 0.14224)
		(layer "In13.Cu")
		(net "P5E_CPU0_P1_RX_BUF_DP<10>")
	)
	(segment
		(start 348.344236 -401.526756)
		(end 348.344236 -401.674838)
		(width 0.14224)
		(layer "In13.Cu")
		(net "P5E_CPU0_P1_RX_BUF_DP<10>")
	)
	(segment
		(start 338.199476 -417.233354)
		(end 338.062316 -417.096194)
		(width 0.14224)
		(layer "In13.Cu")
		(net "P5E_CPU0_P1_RX_BUF_DP<10>")
	)
	(segment
		(start 341.268812 -410.88945)
		(end 341.459566 -410.925264)
		(width 0.14224)
		(layer "In13.Cu")
		(net "P5E_CPU0_P1_RX_BUF_DP<10>")
	)
	(segment
		(start 346.12199 -406.704038)
		(end 346.367862 -406.354788)
		(width 0.14224)
		(layer "In13.Cu")
		(net "P5E_CPU0_P1_RX_BUF_DP<10>")
	)
	(segment
		(start 335.623408 -423.484294)
		(end 335.814416 -423.10304)
		(width 0.14224)
		(layer "In13.Cu")
		(net "P5E_CPU0_P1_RX_BUF_DP<10>")
	)
	(segment
		(start 342.199976 -410.252926)
		(end 342.39073 -410.28874)
		(width 0.14224)
		(layer "In13.Cu")
		(net "P5E_CPU0_P1_RX_BUF_DP<10>")
	)
	(segment
		(start 335.649824 -433.289964)
		(end 335.649824 -433.621942)
		(width 0.14224)
		(layer "In13.Cu")
		(net "P5E_CPU0_P1_RX_BUF_DP<10>")
	)
	(segment
		(start 338.062316 -419.079172)
		(end 338.062316 -417.797234)
		(width 0.14224)
		(layer "In13.Cu")
		(net "P5E_CPU0_P1_RX_BUF_DP<10>")
	)
	(segment
		(start 335.123282 -433.748942)
		(end 334.970882 -433.596542)
		(width 0.14224)
		(layer "In13.Cu")
		(net "P5E_CPU0_P1_RX_BUF_DP<10>")
	)
	(segment
		(start 336.128868 -422.475914)
		(end 336.394298 -421.946578)
		(width 0.14224)
		(layer "In13.Cu")
		(net "P5E_CPU0_P1_RX_BUF_DP<10>")
	)
	(segment
		(start 343.209372 -409.562808)
		(end 343.511124 -409.26131)
		(width 0.14224)
		(layer "In13.Cu")
		(net "P5E_CPU0_P1_RX_BUF_DP<10>")
	)
	(segment
		(start 346.334842 -406.16378)
		(end 346.58046 -405.815038)
		(width 0.14224)
		(layer "In13.Cu")
		(net "P5E_CPU0_P1_RX_BUF_DP<10>")
	)
	(segment
		(start 344.804492 -407.967688)
		(end 345.682316 -407.090118)
		(width 0.14224)
		(layer "In13.Cu")
		(net "P5E_CPU0_P1_RX_BUF_DP<10>")
	)
	(segment
		(start 338.199476 -416.105594)
		(end 338.062316 -415.968434)
		(width 0.14224)
		(layer "In13.Cu")
		(net "P5E_CPU0_P1_RX_BUF_DP<10>")
	)
	(segment
		(start 336.530696 -420.22776)
		(end 336.53095 -420.228014)
		(width 0.14224)
		(layer "In13.Cu")
		(net "P5E_CPU0_P1_RX_BUF_DP<10>")
	)
	(segment
		(start 347.427042 -404.851108)
		(end 347.672914 -404.502112)
		(width 0.14224)
		(layer "In13.Cu")
		(net "P5E_CPU0_P1_RX_BUF_DP<10>")
	)
	(segment
		(start 343.704926 -409.26131)
		(end 344.006932 -408.959304)
		(width 0.14224)
		(layer "In13.Cu")
		(net "P5E_CPU0_P1_RX_BUF_DP<10>")
	)
	(segment
		(start 343.511124 -409.26131)
		(end 343.704926 -409.26131)
		(width 0.14224)
		(layer "In13.Cu")
		(net "P5E_CPU0_P1_RX_BUF_DP<10>")
	)
	(segment
		(start 344.006932 -408.959304)
		(end 344.006932 -408.765248)
		(width 0.14224)
		(layer "In13.Cu")
		(net "P5E_CPU0_P1_RX_BUF_DP<10>")
	)
	(segment
		(start 339.620098 -412.365952)
		(end 339.692234 -412.203138)
		(width 0.14224)
		(layer "In13.Cu")
		(net "P5E_CPU0_P1_RX_BUF_DP<10>")
	)
	(segment
		(start 338.062316 -417.797234)
		(end 338.199476 -417.660074)
		(width 0.14224)
		(layer "In13.Cu")
		(net "P5E_CPU0_P1_RX_BUF_DP<10>")
	)
	(segment
		(start 336.394298 -421.946578)
		(end 336.405474 -421.900858)
		(width 0.14224)
		(layer "In13.Cu")
		(net "P5E_CPU0_P1_RX_BUF_DP<10>")
	)
	(segment
		(start 337.771232 -419.56482)
		(end 337.938618 -419.388798)
		(width 0.14224)
		(layer "In13.Cu")
		(net "P5E_CPU0_P1_RX_BUF_DP<10>")
	)
	(segment
		(start 345.682316 -407.090118)
		(end 345.930728 -406.737312)
		(width 0.14224)
		(layer "In13.Cu")
		(net "P5E_CPU0_P1_RX_BUF_DP<10>")
	)
	(segment
		(start 338.062316 -417.096194)
		(end 338.062316 -416.669474)
		(width 0.14224)
		(layer "In13.Cu")
		(net "P5E_CPU0_P1_RX_BUF_DP<10>")
	)
	(segment
		(start 345.930728 -406.737312)
		(end 346.12199 -406.704038)
		(width 0.14224)
		(layer "In13.Cu")
		(net "P5E_CPU0_P1_RX_BUF_DP<10>")
	)
	(segment
		(start 348.027498 -401.399756)
		(end 348.217236 -401.399756)
		(width 0.14224)
		(layer "In13.Cu")
		(net "P5E_CPU0_P1_RX_BUF_DP<10>")
	)
	(segment
		(start 342.743282 -410.047694)
		(end 342.779096 -409.85694)
		(width 0.14224)
		(layer "In13.Cu")
		(net "P5E_CPU0_P1_RX_BUF_DP<10>")
	)
	(segment
		(start 347.885258 -401.541996)
		(end 348.027498 -401.399756)
		(width 0.14224)
		(layer "In13.Cu")
		(net "P5E_CPU0_P1_RX_BUF_DP<10>")
	)
	(segment
		(start 346.98432 -405.241506)
		(end 347.23578 -404.884382)
		(width 0.14224)
		(layer "In13.Cu")
		(net "P5E_CPU0_P1_RX_BUF_DP<10>")
	)
	(segment
		(start 346.367862 -406.354788)
		(end 346.334842 -406.16378)
		(width 0.14224)
		(layer "In13.Cu")
		(net "P5E_CPU0_P1_RX_BUF_DP<10>")
	)
	(segment
		(start 341.812118 -410.684218)
		(end 341.847932 -410.493718)
		(width 0.14224)
		(layer "In13.Cu")
		(net "P5E_CPU0_P1_RX_BUF_DP<10>")
	)
	(segment
		(start 338.929218 -414.153096)
		(end 339.244686 -413.942276)
		(width 0.14224)
		(layer "In13.Cu")
		(net "P5E_CPU0_P1_RX_BUF_DP<10>")
	)
	(segment
		(start 335.814416 -423.10304)
		(end 335.99882 -423.041826)
		(width 0.14224)
		(layer "In13.Cu")
		(net "P5E_CPU0_P1_RX_BUF_DP<10>")
	)
	(segment
		(start 340.916768 -411.130242)
		(end 341.268812 -410.88945)
		(width 0.14224)
		(layer "In13.Cu")
		(net "P5E_CPU0_P1_RX_BUF_DP<10>")
	)
	(segment
		(start 342.39073 -410.28874)
		(end 342.743282 -410.047694)
		(width 0.14224)
		(layer "In13.Cu")
		(net "P5E_CPU0_P1_RX_BUF_DP<10>")
	)
	(segment
		(start 335.49336 -424.050206)
		(end 335.684622 -423.668444)
		(width 0.14224)
		(layer "In13.Cu")
		(net "P5E_CPU0_P1_RX_BUF_DP<10>")
	)
	(segment
		(start 346.58046 -405.815038)
		(end 346.771468 -405.781764)
		(width 0.14224)
		(layer "In13.Cu")
		(net "P5E_CPU0_P1_RX_BUF_DP<10>")
	)
	(segment
		(start 344.006932 -408.765248)
		(end 344.308684 -408.46375)
		(width 0.14224)
		(layer "In13.Cu")
		(net "P5E_CPU0_P1_RX_BUF_DP<10>")
	)
	(segment
		(start 335.684622 -423.668444)
		(end 335.623408 -423.484294)
		(width 0.14224)
		(layer "In13.Cu")
		(net "P5E_CPU0_P1_RX_BUF_DP<10>")
	)
	(segment
		(start 344.804492 -408.161744)
		(end 344.804492 -407.967688)
		(width 0.14224)
		(layer "In13.Cu")
		(net "P5E_CPU0_P1_RX_BUF_DP<10>")
	)
	(segment
		(start 341.847932 -410.493718)
		(end 342.199976 -410.252926)
		(width 0.14224)
		(layer "In13.Cu")
		(net "P5E_CPU0_P1_RX_BUF_DP<10>")
	)
	(segment
		(start 335.042764 -424.64228)
		(end 335.308956 -424.111166)
		(width 0.14224)
		(layer "In13.Cu")
		(net "P5E_CPU0_P1_RX_BUF_DP<10>")
	)
	(segment
		(start 338.062316 -415.968434)
		(end 338.062316 -415.020252)
		(width 0.14224)
		(layer "In13.Cu")
		(net "P5E_CPU0_P1_RX_BUF_DP<10>")
	)
	(segment
		(start 339.593936 -413.306514)
		(end 339.593936 -412.488888)
		(width 0.14224)
		(layer "In13.Cu")
		(net "P5E_CPU0_P1_RX_BUF_DP<10>")
	)
	(segment
		(start 335.522824 -433.748942)
		(end 335.123282 -433.748942)
		(width 0.14224)
		(layer "In13.Cu")
		(net "P5E_CPU0_P1_RX_BUF_DP<10>")
	)
	(segment
		(start 344.502486 -408.46375)
		(end 344.804492 -408.161744)
		(width 0.14224)
		(layer "In13.Cu")
		(net "P5E_CPU0_P1_RX_BUF_DP<10>")
	)
	(segment
		(start 340.516464 -411.451552)
		(end 340.815422 -411.206188)
		(width 0.14224)
		(layer "In13.Cu")
		(net "P5E_CPU0_P1_RX_BUF_DP<10>")
	)
	(segment
		(start 338.199476 -416.532314)
		(end 338.199476 -416.105594)
		(width 0.14224)
		(layer "In13.Cu")
		(net "P5E_CPU0_P1_RX_BUF_DP<10>")
	)
	(segment
		(start 347.63964 -404.31085)
		(end 347.885258 -403.962108)
		(width 0.14224)
		(layer "In13.Cu")
		(net "P5E_CPU0_P1_RX_BUF_DP<10>")
	)
	(segment
		(start 342.779096 -409.85694)
		(end 343.209372 -409.562808)
		(width 0.14224)
		(layer "In13.Cu")
		(net "P5E_CPU0_P1_RX_BUF_DP<10>")
	)
	(segment
		(start 336.405474 -421.900858)
		(end 336.516218 -421.49649)
		(width 0.14224)
		(layer "In13.Cu")
		(net "P5E_CPU0_P1_RX_BUF_DP<10>")
	)
	(segment
		(start 347.672914 -404.502112)
		(end 347.63964 -404.31085)
		(width 0.14224)
		(layer "In13.Cu")
		(net "P5E_CPU0_P1_RX_BUF_DP<10>")
	)
	(segment
		(start 339.244686 -413.942276)
		(end 339.391498 -413.795464)
		(width 0.14224)
		(layer "In13.Cu")
		(net "P5E_CPU0_P1_RX_BUF_DP<10>")
	)
	(segment
		(start 336.530696 -421.388286)
		(end 336.530696 -420.22776)
		(width 0.14224)
		(layer "In13.Cu")
		(net "P5E_CPU0_P1_RX_BUF_DP<10>")
	)
	(segment
		(start 347.01734 -405.432768)
		(end 346.98432 -405.241506)
		(width 0.14224)
		(layer "In13.Cu")
		(net "P5E_CPU0_P1_RX_BUF_DP<10>")
	)
	(segment
		(start 346.771468 -405.781764)
		(end 347.01734 -405.432768)
		(width 0.14224)
		(layer "In13.Cu")
		(net "P5E_CPU0_P1_RX_BUF_DP<10>")
	)
	(segment
		(start 338.062316 -416.669474)
		(end 338.199476 -416.532314)
		(width 0.14224)
		(layer "In13.Cu")
		(net "P5E_CPU0_P1_RX_BUF_DP<10>")
	)
	(segment
		(start 335.649824 -433.621942)
		(end 335.522824 -433.748942)
		(width 0.14224)
		(layer "In13.Cu")
		(net "P5E_CPU0_P1_RX_BUF_DP<10>")
	)
	(segment
		(start 335.99882 -423.041826)
		(end 336.190082 -422.660064)
		(width 0.14224)
		(layer "In13.Cu")
		(net "P5E_CPU0_P1_RX_BUF_DP<10>")
	)
	(segment
		(start 335.308956 -424.111166)
		(end 335.49336 -424.050206)
		(width 0.14224)
		(layer "In13.Cu")
		(net "P5E_CPU0_P1_RX_BUF_DP<10>")
	)
	(arc
		(start 340.815422 -411.206188)
		(mid 340.865267 -411.16711)
		(end 340.916768 -411.130242)
		(width 0.14224)
		(layer "In13.Cu")
		(net "P5E_CPU0_P1_RX_BUF_DP<10>")
	)
	(arc
		(start 340.200742 -411.71622)
		(mid 340.357903 -411.58305)
		(end 340.516464 -411.451552)
		(width 0.14224)
		(layer "In13.Cu")
		(net "P5E_CPU0_P1_RX_BUF_DP<10>")
	)
	(arc
		(start 337.570826 -419.70198)
		(mid 337.678224 -419.643911)
		(end 337.771232 -419.56482)
		(width 0.14224)
		(layer "In13.Cu")
		(net "P5E_CPU0_P1_RX_BUF_DP<10>")
	)
	(arc
		(start 338.062316 -415.020252)
		(mid 338.115545 -414.752451)
		(end 338.267294 -414.52546)
		(width 0.14224)
		(layer "In13.Cu")
		(net "P5E_CPU0_P1_RX_BUF_DP<10>")
	)
	(arc
		(start 337.938618 -419.388798)
		(mid 338.030294 -419.245907)
		(end 338.062316 -419.079172)
		(width 0.14224)
		(layer "In13.Cu")
		(net "P5E_CPU0_P1_RX_BUF_DP<10>")
	)
	(arc
		(start 338.267294 -414.52546)
		(mid 338.447764 -414.377314)
		(end 338.653628 -414.267142)
		(width 0.14224)
		(layer "In13.Cu")
		(net "P5E_CPU0_P1_RX_BUF_DP<10>")
	)
	(arc
		(start 339.766402 -412.100268)
		(mid 339.982073 -411.906549)
		(end 340.200742 -411.71622)
		(width 0.14224)
		(layer "In13.Cu")
		(net "P5E_CPU0_P1_RX_BUF_DP<10>")
	)
	(arc
		(start 339.593936 -412.488888)
		(mid 339.600582 -412.426052)
		(end 339.620098 -412.365952)
		(width 0.14224)
		(layer "In13.Cu")
		(net "P5E_CPU0_P1_RX_BUF_DP<10>")
	)
	(arc
		(start 334.970882 -424.945556)
		(mid 334.989039 -424.789703)
		(end 335.042764 -424.64228)
		(width 0.14224)
		(layer "In13.Cu")
		(net "P5E_CPU0_P1_RX_BUF_DP<10>")
	)
	(arc
		(start 339.692234 -412.203138)
		(mid 339.723956 -412.147834)
		(end 339.766402 -412.100268)
		(width 0.14224)
		(layer "In13.Cu")
		(net "P5E_CPU0_P1_RX_BUF_DP<10>")
	)
	(arc
		(start 336.516218 -421.49649)
		(mid 336.52707 -421.442872)
		(end 336.530696 -421.388286)
		(width 0.14224)
		(layer "In13.Cu")
		(net "P5E_CPU0_P1_RX_BUF_DP<10>")
	)
	(arc
		(start 339.391498 -413.795464)
		(mid 339.541338 -413.571118)
		(end 339.593936 -413.306514)
		(width 0.14224)
		(layer "In13.Cu")
		(net "P5E_CPU0_P1_RX_BUF_DP<10>")
	)
	(arc
		(start 336.53095 -420.228014)
		(mid 336.554743 -420.149233)
		(end 336.618326 -420.09695)
		(width 0.14224)
		(layer "In13.Cu")
		(net "P5E_CPU0_P1_RX_BUF_DP<10>")
	)
	(segment
		(start 336.205322 -401.359116)
		(end 336.344006 -401.4978)
		(width 0.1016)
		(layer "F.Cu")
		(net "P5E_CPU0_P1_RX_BUF_DP<0>")
	)
	(segment
		(start 335.730088 -399.74774)
		(end 335.730088 -399.870676)
		(width 0.1016)
		(layer "F.Cu")
		(net "P5E_CPU0_P1_RX_BUF_DP<0>")
	)
	(segment
		(start 335.61909 -399.981674)
		(end 335.61909 -401.083526)
		(width 0.1016)
		(layer "F.Cu")
		(net "P5E_CPU0_P1_RX_BUF_DP<0>")
	)
	(segment
		(start 335.645506 -399.663158)
		(end 335.730088 -399.74774)
		(width 0.1016)
		(layer "F.Cu")
		(net "P5E_CPU0_P1_RX_BUF_DP<0>")
	)
	(segment
		(start 335.730088 -399.870676)
		(end 335.61909 -399.981674)
		(width 0.1016)
		(layer "F.Cu")
		(net "P5E_CPU0_P1_RX_BUF_DP<0>")
	)
	(segment
		(start 335.61909 -401.083526)
		(end 335.89468 -401.359116)
		(width 0.1016)
		(layer "F.Cu")
		(net "P5E_CPU0_P1_RX_BUF_DP<0>")
	)
	(segment
		(start 335.89468 -401.359116)
		(end 336.205322 -401.359116)
		(width 0.1016)
		(layer "F.Cu")
		(net "P5E_CPU0_P1_RX_BUF_DP<0>")
	)
	(segment
		(start 336.344006 -401.4978)
		(end 336.344006 -401.674838)
		(width 0.1016)
		(layer "F.Cu")
		(net "P5E_CPU0_P1_RX_BUF_DP<0>")
	)
	(segment
		(start 310.452008 -428.604934)
		(end 310.1975 -428.26178)
		(width 0.14224)
		(layer "In13.Cu")
		(net "P5E_CPU0_P1_RX_BUF_DP<0>")
	)
	(segment
		(start 309.677054 -427.790356)
		(end 309.705502 -427.598586)
		(width 0.14224)
		(layer "In13.Cu")
		(net "P5E_CPU0_P1_RX_BUF_DP<0>")
	)
	(segment
		(start 305.898296 -422.58488)
		(end 305.898296 -420.211504)
		(width 0.14224)
		(layer "In13.Cu")
		(net "P5E_CPU0_P1_RX_BUF_DP<0>")
	)
	(segment
		(start 327.749408 -404.167594)
		(end 329.13828 -403.95652)
		(width 0.14224)
		(layer "In13.Cu")
		(net "P5E_CPU0_P1_RX_BUF_DP<0>")
	)
	(segment
		(start 309.450994 -427.255432)
		(end 309.259224 -427.226984)
		(width 0.14224)
		(layer "In13.Cu")
		(net "P5E_CPU0_P1_RX_BUF_DP<0>")
	)
	(segment
		(start 308.247542 -425.632626)
		(end 307.993034 -425.289726)
		(width 0.14224)
		(layer "In13.Cu")
		(net "P5E_CPU0_P1_RX_BUF_DP<0>")
	)
	(segment
		(start 307.567076 -417.453064)
		(end 307.567076 -417.026344)
		(width 0.14224)
		(layer "In13.Cu")
		(net "P5E_CPU0_P1_RX_BUF_DP<0>")
	)
	(segment
		(start 307.993034 -425.289726)
		(end 307.801264 -425.261278)
		(width 0.14224)
		(layer "In13.Cu")
		(net "P5E_CPU0_P1_RX_BUF_DP<0>")
	)
	(segment
		(start 313.627516 -409.73375)
		(end 313.809126 -409.80233)
		(width 0.14224)
		(layer "In13.Cu")
		(net "P5E_CPU0_P1_RX_BUF_DP<0>")
	)
	(segment
		(start 315.294264 -408.980132)
		(end 316.581536 -408.398472)
		(width 0.14224)
		(layer "In13.Cu")
		(net "P5E_CPU0_P1_RX_BUF_DP<0>")
	)
	(segment
		(start 308.986174 -412.32074)
		(end 309.111396 -412.019242)
		(width 0.14224)
		(layer "In13.Cu")
		(net "P5E_CPU0_P1_RX_BUF_DP<0>")
	)
	(segment
		(start 307.061108 -424.03268)
		(end 306.869084 -424.004232)
		(width 0.14224)
		(layer "In13.Cu")
		(net "P5E_CPU0_P1_RX_BUF_DP<0>")
	)
	(segment
		(start 309.02656 -426.682916)
		(end 308.772052 -426.340016)
		(width 0.14224)
		(layer "In13.Cu")
		(net "P5E_CPU0_P1_RX_BUF_DP<0>")
	)
	(segment
		(start 307.429916 -416.462464)
		(end 307.567076 -416.325304)
		(width 0.14224)
		(layer "In13.Cu")
		(net "P5E_CPU0_P1_RX_BUF_DP<0>")
	)
	(segment
		(start 333.802736 -402.269706)
		(end 334.443324 -401.882864)
		(width 0.14224)
		(layer "In13.Cu")
		(net "P5E_CPU0_P1_RX_BUF_DP<0>")
	)
	(segment
		(start 308.296818 -414.153096)
		(end 308.612286 -413.942276)
		(width 0.14224)
		(layer "In13.Cu")
		(net "P5E_CPU0_P1_RX_BUF_DP<0>")
	)
	(segment
		(start 311.43067 -410.877512)
		(end 311.49925 -410.695648)
		(width 0.14224)
		(layer "In13.Cu")
		(net "P5E_CPU0_P1_RX_BUF_DP<0>")
	)
	(segment
		(start 308.961536 -413.306514)
		(end 308.961536 -412.44393)
		(width 0.14224)
		(layer "In13.Cu")
		(net "P5E_CPU0_P1_RX_BUF_DP<0>")
	)
	(segment
		(start 307.567076 -415.898584)
		(end 307.429916 -415.761424)
		(width 0.14224)
		(layer "In13.Cu")
		(net "P5E_CPU0_P1_RX_BUF_DP<0>")
	)
	(segment
		(start 308.772052 -426.340016)
		(end 308.580282 -426.311568)
		(width 0.14224)
		(layer "In13.Cu")
		(net "P5E_CPU0_P1_RX_BUF_DP<0>")
	)
	(segment
		(start 311.041542 -411.05328)
		(end 311.43067 -410.877512)
		(width 0.14224)
		(layer "In13.Cu")
		(net "P5E_CPU0_P1_RX_BUF_DP<0>")
	)
	(segment
		(start 315.225938 -409.161742)
		(end 315.294264 -408.980132)
		(width 0.14224)
		(layer "In13.Cu")
		(net "P5E_CPU0_P1_RX_BUF_DP<0>")
	)
	(segment
		(start 308.998112 -426.87494)
		(end 309.02656 -426.682916)
		(width 0.14224)
		(layer "In13.Cu")
		(net "P5E_CPU0_P1_RX_BUF_DP<0>")
	)
	(segment
		(start 335.822544 -401.384008)
		(end 336.053176 -401.384008)
		(width 0.14224)
		(layer "In13.Cu")
		(net "P5E_CPU0_P1_RX_BUF_DP<0>")
	)
	(segment
		(start 309.18531 -411.917896)
		(end 309.579772 -411.583124)
		(width 0.14224)
		(layer "In13.Cu")
		(net "P5E_CPU0_P1_RX_BUF_DP<0>")
	)
	(segment
		(start 309.259224 -427.226984)
		(end 308.998112 -426.87494)
		(width 0.14224)
		(layer "In13.Cu")
		(net "P5E_CPU0_P1_RX_BUF_DP<0>")
	)
	(segment
		(start 334.443324 -401.882864)
		(end 335.822544 -401.384008)
		(width 0.14224)
		(layer "In13.Cu")
		(net "P5E_CPU0_P1_RX_BUF_DP<0>")
	)
	(segment
		(start 307.429916 -415.761424)
		(end 307.429916 -415.020252)
		(width 0.14224)
		(layer "In13.Cu")
		(net "P5E_CPU0_P1_RX_BUF_DP<0>")
	)
	(segment
		(start 320.89344 -406.647142)
		(end 327.749408 -404.167594)
		(width 0.14224)
		(layer "In13.Cu")
		(net "P5E_CPU0_P1_RX_BUF_DP<0>")
	)
	(segment
		(start 313.809126 -409.80233)
		(end 314.198 -409.626562)
		(width 0.14224)
		(layer "In13.Cu")
		(net "P5E_CPU0_P1_RX_BUF_DP<0>")
	)
	(segment
		(start 314.522612 -433.748942)
		(end 314.1599 -433.748942)
		(width 0.14224)
		(layer "In13.Cu")
		(net "P5E_CPU0_P1_RX_BUF_DP<0>")
	)
	(segment
		(start 308.580282 -426.311568)
		(end 308.219094 -425.82465)
		(width 0.14224)
		(layer "In13.Cu")
		(net "P5E_CPU0_P1_RX_BUF_DP<0>")
	)
	(segment
		(start 314.26658 -409.444698)
		(end 314.6552 -409.269184)
		(width 0.14224)
		(layer "In13.Cu")
		(net "P5E_CPU0_P1_RX_BUF_DP<0>")
	)
	(segment
		(start 310.005476 -428.233332)
		(end 309.677054 -427.790356)
		(width 0.14224)
		(layer "In13.Cu")
		(net "P5E_CPU0_P1_RX_BUF_DP<0>")
	)
	(segment
		(start 314.649612 -433.621942)
		(end 314.522612 -433.748942)
		(width 0.14224)
		(layer "In13.Cu")
		(net "P5E_CPU0_P1_RX_BUF_DP<0>")
	)
	(segment
		(start 305.976528 -420.094664)
		(end 307.070506 -419.641274)
		(width 0.14224)
		(layer "In13.Cu")
		(net "P5E_CPU0_P1_RX_BUF_DP<0>")
	)
	(segment
		(start 311.49925 -410.695648)
		(end 313.627516 -409.73375)
		(width 0.14224)
		(layer "In13.Cu")
		(net "P5E_CPU0_P1_RX_BUF_DP<0>")
	)
	(segment
		(start 308.219094 -425.82465)
		(end 308.247542 -425.632626)
		(width 0.14224)
		(layer "In13.Cu")
		(net "P5E_CPU0_P1_RX_BUF_DP<0>")
	)
	(segment
		(start 307.567076 -417.026344)
		(end 307.429916 -416.889184)
		(width 0.14224)
		(layer "In13.Cu")
		(net "P5E_CPU0_P1_RX_BUF_DP<0>")
	)
	(segment
		(start 307.429916 -419.103302)
		(end 307.429916 -417.590224)
		(width 0.14224)
		(layer "In13.Cu")
		(net "P5E_CPU0_P1_RX_BUF_DP<0>")
	)
	(segment
		(start 307.315362 -424.375834)
		(end 307.061108 -424.03268)
		(width 0.14224)
		(layer "In13.Cu")
		(net "P5E_CPU0_P1_RX_BUF_DP<0>")
	)
	(segment
		(start 310.42356 -428.796704)
		(end 310.452008 -428.604934)
		(width 0.14224)
		(layer "In13.Cu")
		(net "P5E_CPU0_P1_RX_BUF_DP<0>")
	)
	(segment
		(start 309.705502 -427.598586)
		(end 309.450994 -427.255432)
		(width 0.14224)
		(layer "In13.Cu")
		(net "P5E_CPU0_P1_RX_BUF_DP<0>")
	)
	(segment
		(start 308.612286 -413.942276)
		(end 308.759098 -413.795464)
		(width 0.14224)
		(layer "In13.Cu")
		(net "P5E_CPU0_P1_RX_BUF_DP<0>")
	)
	(segment
		(start 310.1975 -428.26178)
		(end 310.005476 -428.233332)
		(width 0.14224)
		(layer "In13.Cu")
		(net "P5E_CPU0_P1_RX_BUF_DP<0>")
	)
	(segment
		(start 336.053176 -401.384008)
		(end 336.344006 -401.674838)
		(width 0.14224)
		(layer "In13.Cu")
		(net "P5E_CPU0_P1_RX_BUF_DP<0>")
	)
	(segment
		(start 307.567076 -416.325304)
		(end 307.567076 -415.898584)
		(width 0.14224)
		(layer "In13.Cu")
		(net "P5E_CPU0_P1_RX_BUF_DP<0>")
	)
	(segment
		(start 307.801264 -425.261278)
		(end 307.286914 -424.567604)
		(width 0.14224)
		(layer "In13.Cu")
		(net "P5E_CPU0_P1_RX_BUF_DP<0>")
	)
	(segment
		(start 314.649612 -433.289964)
		(end 314.649612 -433.621942)
		(width 0.14224)
		(layer "In13.Cu")
		(net "P5E_CPU0_P1_RX_BUF_DP<0>")
	)
	(segment
		(start 306.869084 -424.004232)
		(end 305.964082 -422.783762)
		(width 0.14224)
		(layer "In13.Cu")
		(net "P5E_CPU0_P1_RX_BUF_DP<0>")
	)
	(segment
		(start 309.6895 -411.513782)
		(end 310.859932 -410.9847)
		(width 0.14224)
		(layer "In13.Cu")
		(net "P5E_CPU0_P1_RX_BUF_DP<0>")
	)
	(segment
		(start 314.198 -409.626562)
		(end 314.26658 -409.444698)
		(width 0.14224)
		(layer "In13.Cu")
		(net "P5E_CPU0_P1_RX_BUF_DP<0>")
	)
	(segment
		(start 310.859932 -410.9847)
		(end 311.041542 -411.05328)
		(width 0.14224)
		(layer "In13.Cu")
		(net "P5E_CPU0_P1_RX_BUF_DP<0>")
	)
	(segment
		(start 307.286914 -424.567604)
		(end 307.315362 -424.375834)
		(width 0.14224)
		(layer "In13.Cu")
		(net "P5E_CPU0_P1_RX_BUF_DP<0>")
	)
	(segment
		(start 314.057792 -433.69738)
		(end 310.42356 -428.796704)
		(width 0.14224)
		(layer "In13.Cu")
		(net "P5E_CPU0_P1_RX_BUF_DP<0>")
	)
	(segment
		(start 314.6552 -409.269184)
		(end 314.83681 -409.33751)
		(width 0.14224)
		(layer "In13.Cu")
		(net "P5E_CPU0_P1_RX_BUF_DP<0>")
	)
	(segment
		(start 308.021228 -414.267142)
		(end 308.296818 -414.153096)
		(width 0.14224)
		(layer "In13.Cu")
		(net "P5E_CPU0_P1_RX_BUF_DP<0>")
	)
	(segment
		(start 329.13828 -403.95652)
		(end 333.802736 -402.269706)
		(width 0.14224)
		(layer "In13.Cu")
		(net "P5E_CPU0_P1_RX_BUF_DP<0>")
	)
	(segment
		(start 307.429916 -416.889184)
		(end 307.429916 -416.462464)
		(width 0.14224)
		(layer "In13.Cu")
		(net "P5E_CPU0_P1_RX_BUF_DP<0>")
	)
	(segment
		(start 307.429916 -417.590224)
		(end 307.567076 -417.453064)
		(width 0.14224)
		(layer "In13.Cu")
		(net "P5E_CPU0_P1_RX_BUF_DP<0>")
	)
	(segment
		(start 314.83681 -409.33751)
		(end 315.225938 -409.161742)
		(width 0.14224)
		(layer "In13.Cu")
		(net "P5E_CPU0_P1_RX_BUF_DP<0>")
	)
	(arc
		(start 305.898296 -420.211504)
		(mid 305.919649 -420.141176)
		(end 305.976528 -420.094664)
		(width 0.14224)
		(layer "In13.Cu")
		(net "P5E_CPU0_P1_RX_BUF_DP<0>")
	)
	(arc
		(start 309.579772 -411.583124)
		(mid 309.632214 -411.544618)
		(end 309.6895 -411.513782)
		(width 0.14224)
		(layer "In13.Cu")
		(net "P5E_CPU0_P1_RX_BUF_DP<0>")
	)
	(arc
		(start 308.961536 -412.44393)
		(mid 308.96778 -412.38112)
		(end 308.986174 -412.32074)
		(width 0.14224)
		(layer "In13.Cu")
		(net "P5E_CPU0_P1_RX_BUF_DP<0>")
	)
	(arc
		(start 308.759098 -413.795464)
		(mid 308.908938 -413.571118)
		(end 308.961536 -413.306514)
		(width 0.14224)
		(layer "In13.Cu")
		(net "P5E_CPU0_P1_RX_BUF_DP<0>")
	)
	(arc
		(start 307.070506 -419.641274)
		(mid 307.331758 -419.426778)
		(end 307.429916 -419.103302)
		(width 0.14224)
		(layer "In13.Cu")
		(net "P5E_CPU0_P1_RX_BUF_DP<0>")
	)
	(arc
		(start 309.111396 -412.019242)
		(mid 309.142313 -411.964162)
		(end 309.18531 -411.917896)
		(width 0.14224)
		(layer "In13.Cu")
		(net "P5E_CPU0_P1_RX_BUF_DP<0>")
	)
	(arc
		(start 305.964082 -422.783762)
		(mid 305.91524 -422.689605)
		(end 305.898296 -422.58488)
		(width 0.14224)
		(layer "In13.Cu")
		(net "P5E_CPU0_P1_RX_BUF_DP<0>")
	)
	(arc
		(start 314.1599 -433.748942)
		(mid 314.102745 -433.735257)
		(end 314.057792 -433.69738)
		(width 0.14224)
		(layer "In13.Cu")
		(net "P5E_CPU0_P1_RX_BUF_DP<0>")
	)
	(arc
		(start 307.429916 -415.020252)
		(mid 307.483145 -414.752451)
		(end 307.634894 -414.52546)
		(width 0.14224)
		(layer "In13.Cu")
		(net "P5E_CPU0_P1_RX_BUF_DP<0>")
	)
	(arc
		(start 316.581536 -408.398472)
		(mid 318.720497 -407.480975)
		(end 320.89344 -406.647142)
		(width 0.14224)
		(layer "In13.Cu")
		(net "P5E_CPU0_P1_RX_BUF_DP<0>")
	)
	(arc
		(start 307.634894 -414.52546)
		(mid 307.815364 -414.377314)
		(end 308.021228 -414.267142)
		(width 0.14224)
		(layer "In13.Cu")
		(net "P5E_CPU0_P1_RX_BUF_DP<0>")
	)
	(segment
		(start 346.74556 -399.143474)
		(end 346.746068 -399.143982)
		(width 0.1016)
		(layer "F.Cu")
		(net "P5E_CPU0_P1_RX_BUF_DN<9>")
	)
	(segment
		(start 346.746068 -399.960338)
		(end 346.674948 -400.031458)
		(width 0.1016)
		(layer "F.Cu")
		(net "P5E_CPU0_P1_RX_BUF_DN<9>")
	)
	(segment
		(start 346.674948 -400.031458)
		(end 346.674948 -401.016216)
		(width 0.1016)
		(layer "F.Cu")
		(net "P5E_CPU0_P1_RX_BUF_DN<9>")
	)
	(segment
		(start 346.801948 -401.143216)
		(end 347.00337 -401.143216)
		(width 0.1016)
		(layer "F.Cu")
		(net "P5E_CPU0_P1_RX_BUF_DN<9>")
	)
	(segment
		(start 346.674948 -401.016216)
		(end 346.801948 -401.143216)
		(width 0.1016)
		(layer "F.Cu")
		(net "P5E_CPU0_P1_RX_BUF_DN<9>")
	)
	(segment
		(start 346.746068 -399.143982)
		(end 346.746068 -399.960338)
		(width 0.1016)
		(layer "F.Cu")
		(net "P5E_CPU0_P1_RX_BUF_DN<9>")
	)
	(segment
		(start 347.144086 -401.0025)
		(end 347.144086 -400.811238)
		(width 0.1016)
		(layer "F.Cu")
		(net "P5E_CPU0_P1_RX_BUF_DN<9>")
	)
	(segment
		(start 347.00337 -401.143216)
		(end 347.144086 -401.0025)
		(width 0.1016)
		(layer "F.Cu")
		(net "P5E_CPU0_P1_RX_BUF_DN<9>")
	)
	(segment
		(start 335.732374 -413.90316)
		(end 336.001614 -413.723328)
		(width 0.14224)
		(layer "In13.Cu")
		(net "P5E_CPU0_P1_RX_BUF_DN<9>")
	)
	(segment
		(start 333.649828 -435.489858)
		(end 333.649828 -435.196234)
		(width 0.14224)
		(layer "In13.Cu")
		(net "P5E_CPU0_P1_RX_BUF_DN<9>")
	)
	(segment
		(start 344.92311 -405.732488)
		(end 344.923364 -405.732488)
		(width 0.14224)
		(layer "In13.Cu")
		(net "P5E_CPU0_P1_RX_BUF_DN<9>")
	)
	(segment
		(start 347.144086 -400.979386)
		(end 347.144086 -400.811238)
		(width 0.14224)
		(layer "In13.Cu")
		(net "P5E_CPU0_P1_RX_BUF_DN<9>")
	)
	(segment
		(start 344.216228 -406.593548)
		(end 344.92311 -405.732488)
		(width 0.14224)
		(layer "In13.Cu")
		(net "P5E_CPU0_P1_RX_BUF_DN<9>")
	)
	(segment
		(start 346.403168 -401.425156)
		(end 346.710508 -401.117816)
		(width 0.14224)
		(layer "In13.Cu")
		(net "P5E_CPU0_P1_RX_BUF_DN<9>")
	)
	(segment
		(start 335.482438 -414.006538)
		(end 335.732374 -413.90316)
		(width 0.14224)
		(layer "In13.Cu")
		(net "P5E_CPU0_P1_RX_BUF_DN<9>")
	)
	(segment
		(start 333.185516 -422.00449)
		(end 333.185516 -420.227506)
		(width 0.14224)
		(layer "In13.Cu")
		(net "P5E_CPU0_P1_RX_BUF_DN<9>")
	)
	(segment
		(start 344.923364 -405.732488)
		(end 345.41206 -405.136858)
		(width 0.14224)
		(layer "In13.Cu")
		(net "P5E_CPU0_P1_RX_BUF_DN<9>")
	)
	(segment
		(start 334.717136 -419.079426)
		(end 334.717136 -415.020252)
		(width 0.14224)
		(layer "In13.Cu")
		(net "P5E_CPU0_P1_RX_BUF_DN<9>")
	)
	(segment
		(start 336.487262 -411.939486)
		(end 337.119468 -411.306264)
		(width 0.14224)
		(layer "In13.Cu")
		(net "P5E_CPU0_P1_RX_BUF_DN<9>")
	)
	(segment
		(start 336.001614 -413.723328)
		(end 336.128868 -413.596074)
		(width 0.14224)
		(layer "In13.Cu")
		(net "P5E_CPU0_P1_RX_BUF_DN<9>")
	)
	(segment
		(start 347.005656 -401.117816)
		(end 347.144086 -400.979386)
		(width 0.14224)
		(layer "In13.Cu")
		(net "P5E_CPU0_P1_RX_BUF_DN<9>")
	)
	(segment
		(start 346.710508 -401.117816)
		(end 347.005656 -401.117816)
		(width 0.14224)
		(layer "In13.Cu")
		(net "P5E_CPU0_P1_RX_BUF_DN<9>")
	)
	(segment
		(start 332.70698 -424.425364)
		(end 333.182976 -422.029636)
		(width 0.14224)
		(layer "In13.Cu")
		(net "P5E_CPU0_P1_RX_BUF_DN<9>")
	)
	(segment
		(start 332.688946 -434.73878)
		(end 332.688946 -424.608498)
		(width 0.14224)
		(layer "In13.Cu")
		(net "P5E_CPU0_P1_RX_BUF_DN<9>")
	)
	(segment
		(start 337.68411 -410.928312)
		(end 340.65845 -409.696158)
		(width 0.14224)
		(layer "In13.Cu")
		(net "P5E_CPU0_P1_RX_BUF_DN<9>")
	)
	(segment
		(start 340.955376 -409.527502)
		(end 342.21674 -408.592528)
		(width 0.14224)
		(layer "In13.Cu")
		(net "P5E_CPU0_P1_RX_BUF_DN<9>")
	)
	(segment
		(start 340.65845 -409.696158)
		(end 340.955376 -409.527502)
		(width 0.14224)
		(layer "In13.Cu")
		(net "P5E_CPU0_P1_RX_BUF_DN<9>")
	)
	(segment
		(start 336.248756 -413.306514)
		(end 336.248756 -412.515812)
		(width 0.14224)
		(layer "In13.Cu")
		(net "P5E_CPU0_P1_RX_BUF_DN<9>")
	)
	(segment
		(start 345.41206 -405.136858)
		(end 346.291154 -404.065486)
		(width 0.14224)
		(layer "In13.Cu")
		(net "P5E_CPU0_P1_RX_BUF_DN<9>")
	)
	(segment
		(start 342.21674 -408.592528)
		(end 344.216228 -406.593548)
		(width 0.14224)
		(layer "In13.Cu")
		(net "P5E_CPU0_P1_RX_BUF_DN<9>")
	)
	(segment
		(start 334.503522 -419.370256)
		(end 334.671162 -419.194234)
		(width 0.14224)
		(layer "In13.Cu")
		(net "P5E_CPU0_P1_RX_BUF_DN<9>")
	)
	(segment
		(start 333.447136 -419.836346)
		(end 334.39989 -419.441376)
		(width 0.14224)
		(layer "In13.Cu")
		(net "P5E_CPU0_P1_RX_BUF_DN<9>")
	)
	(segment
		(start 333.484474 -435.03088)
		(end 332.981046 -435.03088)
		(width 0.14224)
		(layer "In13.Cu")
		(net "P5E_CPU0_P1_RX_BUF_DN<9>")
	)
	(segment
		(start 346.403168 -403.75332)
		(end 346.403168 -401.425156)
		(width 0.14224)
		(layer "In13.Cu")
		(net "P5E_CPU0_P1_RX_BUF_DN<9>")
	)
	(segment
		(start 333.649828 -435.196234)
		(end 333.484474 -435.03088)
		(width 0.14224)
		(layer "In13.Cu")
		(net "P5E_CPU0_P1_RX_BUF_DN<9>")
	)
	(segment
		(start 332.981046 -435.03088)
		(end 332.688946 -434.73878)
		(width 0.14224)
		(layer "In13.Cu")
		(net "P5E_CPU0_P1_RX_BUF_DN<9>")
	)
	(arc
		(start 346.291154 -404.065486)
		(mid 346.374259 -403.919123)
		(end 346.403168 -403.75332)
		(width 0.14224)
		(layer "In13.Cu")
		(net "P5E_CPU0_P1_RX_BUF_DN<9>")
	)
	(arc
		(start 336.248756 -412.515812)
		(mid 336.310736 -412.203947)
		(end 336.487262 -411.939486)
		(width 0.14224)
		(layer "In13.Cu")
		(net "P5E_CPU0_P1_RX_BUF_DN<9>")
	)
	(arc
		(start 333.182976 -422.029636)
		(mid 333.184863 -422.017125)
		(end 333.185516 -422.00449)
		(width 0.14224)
		(layer "In13.Cu")
		(net "P5E_CPU0_P1_RX_BUF_DN<9>")
	)
	(arc
		(start 335.004664 -414.32607)
		(mid 335.227829 -414.142796)
		(end 335.482438 -414.006538)
		(width 0.14224)
		(layer "In13.Cu")
		(net "P5E_CPU0_P1_RX_BUF_DN<9>")
	)
	(arc
		(start 336.128868 -413.596074)
		(mid 336.217583 -413.463209)
		(end 336.248756 -413.306514)
		(width 0.14224)
		(layer "In13.Cu")
		(net "P5E_CPU0_P1_RX_BUF_DN<9>")
	)
	(arc
		(start 337.119468 -411.306264)
		(mid 337.383135 -411.08942)
		(end 337.68411 -410.928312)
		(width 0.14224)
		(layer "In13.Cu")
		(net "P5E_CPU0_P1_RX_BUF_DN<9>")
	)
	(arc
		(start 334.717136 -415.020252)
		(mid 334.791826 -414.644557)
		(end 335.004664 -414.32607)
		(width 0.14224)
		(layer "In13.Cu")
		(net "P5E_CPU0_P1_RX_BUF_DN<9>")
	)
	(arc
		(start 332.688946 -424.608498)
		(mid 332.693462 -424.516487)
		(end 332.70698 -424.425364)
		(width 0.14224)
		(layer "In13.Cu")
		(net "P5E_CPU0_P1_RX_BUF_DN<9>")
	)
	(arc
		(start 334.671162 -419.194234)
		(mid 334.705209 -419.14126)
		(end 334.717136 -419.079426)
		(width 0.14224)
		(layer "In13.Cu")
		(net "P5E_CPU0_P1_RX_BUF_DN<9>")
	)
	(arc
		(start 333.185516 -420.227506)
		(mid 333.257008 -419.992245)
		(end 333.447136 -419.836346)
		(width 0.14224)
		(layer "In13.Cu")
		(net "P5E_CPU0_P1_RX_BUF_DN<9>")
	)
	(arc
		(start 334.39989 -419.441376)
		(mid 334.455428 -419.41124)
		(end 334.503522 -419.370256)
		(width 0.14224)
		(layer "In13.Cu")
		(net "P5E_CPU0_P1_RX_BUF_DN<9>")
	)
	(segment
		(start 345.545918 -399.960338)
		(end 345.545918 -399.143982)
		(width 0.1016)
		(layer "F.Cu")
		(net "P5E_CPU0_P1_RX_BUF_DN<8>")
	)
	(segment
		(start 345.545918 -399.143982)
		(end 345.54541 -399.143474)
		(width 0.1016)
		(layer "F.Cu")
		(net "P5E_CPU0_P1_RX_BUF_DN<8>")
	)
	(segment
		(start 345.94419 -400.811238)
		(end 345.94419 -401.002246)
		(width 0.1016)
		(layer "F.Cu")
		(net "P5E_CPU0_P1_RX_BUF_DN<8>")
	)
	(segment
		(start 345.584272 -401.143216)
		(end 345.457272 -401.016216)
		(width 0.1016)
		(layer "F.Cu")
		(net "P5E_CPU0_P1_RX_BUF_DN<8>")
	)
	(segment
		(start 345.94419 -401.002246)
		(end 345.80322 -401.143216)
		(width 0.1016)
		(layer "F.Cu")
		(net "P5E_CPU0_P1_RX_BUF_DN<8>")
	)
	(segment
		(start 345.80322 -401.143216)
		(end 345.584272 -401.143216)
		(width 0.1016)
		(layer "F.Cu")
		(net "P5E_CPU0_P1_RX_BUF_DN<8>")
	)
	(segment
		(start 345.457272 -401.016216)
		(end 345.457272 -400.048984)
		(width 0.1016)
		(layer "F.Cu")
		(net "P5E_CPU0_P1_RX_BUF_DN<8>")
	)
	(segment
		(start 345.457272 -400.048984)
		(end 345.545918 -399.960338)
		(width 0.1016)
		(layer "F.Cu")
		(net "P5E_CPU0_P1_RX_BUF_DN<8>")
	)
	(segment
		(start 340.677246 -408.540204)
		(end 342.101932 -407.35631)
		(width 0.14224)
		(layer "In13.Cu")
		(net "P5E_CPU0_P1_RX_BUF_DN<8>")
	)
	(segment
		(start 331.440282 -419.370256)
		(end 331.607922 -419.194234)
		(width 0.14224)
		(layer "In13.Cu")
		(net "P5E_CPU0_P1_RX_BUF_DN<8>")
	)
	(segment
		(start 344.15222 -405.09317)
		(end 345.180158 -403.633686)
		(width 0.14224)
		(layer "In13.Cu")
		(net "P5E_CPU0_P1_RX_BUF_DN<8>")
	)
	(segment
		(start 331.649832 -434.48986)
		(end 331.649832 -434.157882)
		(width 0.14224)
		(layer "In13.Cu")
		(net "P5E_CPU0_P1_RX_BUF_DN<8>")
	)
	(segment
		(start 331.653896 -419.079426)
		(end 331.653896 -415.020252)
		(width 0.14224)
		(layer "In13.Cu")
		(net "P5E_CPU0_P1_RX_BUF_DN<8>")
	)
	(segment
		(start 330.122276 -433.159916)
		(end 330.122276 -420.22776)
		(width 0.14224)
		(layer "In13.Cu")
		(net "P5E_CPU0_P1_RX_BUF_DN<8>")
	)
	(segment
		(start 345.510612 -401.117816)
		(end 345.80576 -401.117816)
		(width 0.14224)
		(layer "In13.Cu")
		(net "P5E_CPU0_P1_RX_BUF_DN<8>")
	)
	(segment
		(start 332.938374 -413.723328)
		(end 333.065628 -413.596074)
		(width 0.14224)
		(layer "In13.Cu")
		(net "P5E_CPU0_P1_RX_BUF_DN<8>")
	)
	(segment
		(start 332.669134 -413.90316)
		(end 332.938374 -413.723328)
		(width 0.14224)
		(layer "In13.Cu")
		(net "P5E_CPU0_P1_RX_BUF_DN<8>")
	)
	(segment
		(start 342.101932 -407.35631)
		(end 344.15222 -405.09317)
		(width 0.14224)
		(layer "In13.Cu")
		(net "P5E_CPU0_P1_RX_BUF_DN<8>")
	)
	(segment
		(start 330.993242 -434.030882)
		(end 330.122276 -433.159916)
		(width 0.14224)
		(layer "In13.Cu")
		(net "P5E_CPU0_P1_RX_BUF_DN<8>")
	)
	(segment
		(start 340.443312 -408.708098)
		(end 340.677246 -408.540204)
		(width 0.14224)
		(layer "In13.Cu")
		(net "P5E_CPU0_P1_RX_BUF_DN<8>")
	)
	(segment
		(start 334.037432 -411.324298)
		(end 337.888834 -409.693618)
		(width 0.14224)
		(layer "In13.Cu")
		(net "P5E_CPU0_P1_RX_BUF_DN<8>")
	)
	(segment
		(start 333.185516 -413.306514)
		(end 333.185516 -412.43758)
		(width 0.14224)
		(layer "In13.Cu")
		(net "P5E_CPU0_P1_RX_BUF_DN<8>")
	)
	(segment
		(start 331.522832 -434.030882)
		(end 330.993242 -434.030882)
		(width 0.14224)
		(layer "In13.Cu")
		(net "P5E_CPU0_P1_RX_BUF_DN<8>")
	)
	(segment
		(start 333.480156 -411.762194)
		(end 333.706978 -411.551882)
		(width 0.14224)
		(layer "In13.Cu")
		(net "P5E_CPU0_P1_RX_BUF_DN<8>")
	)
	(segment
		(start 345.203272 -401.425156)
		(end 345.510612 -401.117816)
		(width 0.14224)
		(layer "In13.Cu")
		(net "P5E_CPU0_P1_RX_BUF_DN<8>")
	)
	(segment
		(start 345.94419 -400.979386)
		(end 345.94419 -400.811238)
		(width 0.14224)
		(layer "In13.Cu")
		(net "P5E_CPU0_P1_RX_BUF_DN<8>")
	)
	(segment
		(start 345.203272 -403.560788)
		(end 345.203272 -401.425156)
		(width 0.14224)
		(layer "In13.Cu")
		(net "P5E_CPU0_P1_RX_BUF_DN<8>")
	)
	(segment
		(start 338.82457 -409.39339)
		(end 340.037674 -408.93746)
		(width 0.14224)
		(layer "In13.Cu")
		(net "P5E_CPU0_P1_RX_BUF_DN<8>")
	)
	(segment
		(start 332.419198 -414.006538)
		(end 332.669134 -413.90316)
		(width 0.14224)
		(layer "In13.Cu")
		(net "P5E_CPU0_P1_RX_BUF_DN<8>")
	)
	(segment
		(start 345.80576 -401.117816)
		(end 345.94419 -400.979386)
		(width 0.14224)
		(layer "In13.Cu")
		(net "P5E_CPU0_P1_RX_BUF_DN<8>")
	)
	(segment
		(start 331.649832 -434.157882)
		(end 331.522832 -434.030882)
		(width 0.14224)
		(layer "In13.Cu")
		(net "P5E_CPU0_P1_RX_BUF_DN<8>")
	)
	(segment
		(start 338.034884 -409.640532)
		(end 338.704936 -409.434284)
		(width 0.14224)
		(layer "In13.Cu")
		(net "P5E_CPU0_P1_RX_BUF_DN<8>")
	)
	(segment
		(start 330.383896 -419.836346)
		(end 331.33665 -419.441376)
		(width 0.14224)
		(layer "In13.Cu")
		(net "P5E_CPU0_P1_RX_BUF_DN<8>")
	)
	(arc
		(start 337.888834 -409.693618)
		(mid 337.961183 -409.665215)
		(end 338.034884 -409.640532)
		(width 0.14224)
		(layer "In13.Cu")
		(net "P5E_CPU0_P1_RX_BUF_DN<8>")
	)
	(arc
		(start 331.33665 -419.441376)
		(mid 331.392188 -419.41124)
		(end 331.440282 -419.370256)
		(width 0.14224)
		(layer "In13.Cu")
		(net "P5E_CPU0_P1_RX_BUF_DN<8>")
	)
	(arc
		(start 331.941424 -414.32607)
		(mid 332.164589 -414.142796)
		(end 332.419198 -414.006538)
		(width 0.14224)
		(layer "In13.Cu")
		(net "P5E_CPU0_P1_RX_BUF_DN<8>")
	)
	(arc
		(start 338.704936 -409.434284)
		(mid 338.765066 -409.414753)
		(end 338.82457 -409.39339)
		(width 0.14224)
		(layer "In13.Cu")
		(net "P5E_CPU0_P1_RX_BUF_DN<8>")
	)
	(arc
		(start 331.607922 -419.194234)
		(mid 331.641969 -419.14126)
		(end 331.653896 -419.079426)
		(width 0.14224)
		(layer "In13.Cu")
		(net "P5E_CPU0_P1_RX_BUF_DN<8>")
	)
	(arc
		(start 331.653896 -415.020252)
		(mid 331.728586 -414.644557)
		(end 331.941424 -414.32607)
		(width 0.14224)
		(layer "In13.Cu")
		(net "P5E_CPU0_P1_RX_BUF_DN<8>")
	)
	(arc
		(start 330.122276 -420.22776)
		(mid 330.193697 -419.992351)
		(end 330.383896 -419.836346)
		(width 0.14224)
		(layer "In13.Cu")
		(net "P5E_CPU0_P1_RX_BUF_DN<8>")
	)
	(arc
		(start 345.180158 -403.633686)
		(mid 345.197359 -403.599022)
		(end 345.203272 -403.560788)
		(width 0.14224)
		(layer "In13.Cu")
		(net "P5E_CPU0_P1_RX_BUF_DN<8>")
	)
	(arc
		(start 340.153498 -408.885898)
		(mid 340.301584 -408.80218)
		(end 340.443312 -408.708098)
		(width 0.14224)
		(layer "In13.Cu")
		(net "P5E_CPU0_P1_RX_BUF_DN<8>")
	)
	(arc
		(start 333.185516 -412.43758)
		(mid 333.262375 -412.069144)
		(end 333.480156 -411.762194)
		(width 0.14224)
		(layer "In13.Cu")
		(net "P5E_CPU0_P1_RX_BUF_DN<8>")
	)
	(arc
		(start 340.037674 -408.93746)
		(mid 340.096357 -408.91341)
		(end 340.153498 -408.885898)
		(width 0.14224)
		(layer "In13.Cu")
		(net "P5E_CPU0_P1_RX_BUF_DN<8>")
	)
	(arc
		(start 333.872586 -411.4165)
		(mid 333.952468 -411.365855)
		(end 334.037432 -411.324298)
		(width 0.14224)
		(layer "In13.Cu")
		(net "P5E_CPU0_P1_RX_BUF_DN<8>")
	)
	(arc
		(start 333.065628 -413.596074)
		(mid 333.154343 -413.463209)
		(end 333.185516 -413.306514)
		(width 0.14224)
		(layer "In13.Cu")
		(net "P5E_CPU0_P1_RX_BUF_DN<8>")
	)
	(arc
		(start 333.706978 -411.551882)
		(mid 333.787608 -411.481531)
		(end 333.872586 -411.4165)
		(width 0.14224)
		(layer "In13.Cu")
		(net "P5E_CPU0_P1_RX_BUF_DN<8>")
	)
	(segment
		(start 344.346022 -399.143982)
		(end 344.346022 -399.960338)
		(width 0.1016)
		(layer "F.Cu")
		(net "P5E_CPU0_P1_RX_BUF_DN<7>")
	)
	(segment
		(start 344.257376 -401.016216)
		(end 344.384376 -401.143216)
		(width 0.1016)
		(layer "F.Cu")
		(net "P5E_CPU0_P1_RX_BUF_DN<7>")
	)
	(segment
		(start 344.257376 -400.048984)
		(end 344.257376 -401.016216)
		(width 0.1016)
		(layer "F.Cu")
		(net "P5E_CPU0_P1_RX_BUF_DN<7>")
	)
	(segment
		(start 344.346022 -399.960338)
		(end 344.257376 -400.048984)
		(width 0.1016)
		(layer "F.Cu")
		(net "P5E_CPU0_P1_RX_BUF_DN<7>")
	)
	(segment
		(start 344.74404 -401.0025)
		(end 344.74404 -400.811238)
		(width 0.1016)
		(layer "F.Cu")
		(net "P5E_CPU0_P1_RX_BUF_DN<7>")
	)
	(segment
		(start 344.384376 -401.143216)
		(end 344.603324 -401.143216)
		(width 0.1016)
		(layer "F.Cu")
		(net "P5E_CPU0_P1_RX_BUF_DN<7>")
	)
	(segment
		(start 344.345514 -399.143474)
		(end 344.346022 -399.143982)
		(width 0.1016)
		(layer "F.Cu")
		(net "P5E_CPU0_P1_RX_BUF_DN<7>")
	)
	(segment
		(start 344.603324 -401.143216)
		(end 344.74404 -401.0025)
		(width 0.1016)
		(layer "F.Cu")
		(net "P5E_CPU0_P1_RX_BUF_DN<7>")
	)
	(segment
		(start 328.590656 -418.8968)
		(end 328.590656 -415.025332)
		(width 0.14224)
		(layer "In13.Cu")
		(net "P5E_CPU0_P1_RX_BUF_DN<7>")
	)
	(segment
		(start 344.101674 -401.326604)
		(end 344.310462 -401.117816)
		(width 0.14224)
		(layer "In13.Cu")
		(net "P5E_CPU0_P1_RX_BUF_DN<7>")
	)
	(segment
		(start 329.247246 -414.052766)
		(end 329.605132 -413.903922)
		(width 0.14224)
		(layer "In13.Cu")
		(net "P5E_CPU0_P1_RX_BUF_DN<7>")
	)
	(segment
		(start 332.33487 -410.718254)
		(end 334.402176 -409.816554)
		(width 0.14224)
		(layer "In13.Cu")
		(net "P5E_CPU0_P1_RX_BUF_DN<7>")
	)
	(segment
		(start 328.387456 -419.378384)
		(end 328.38771 -419.378384)
		(width 0.14224)
		(layer "In13.Cu")
		(net "P5E_CPU0_P1_RX_BUF_DN<7>")
	)
	(segment
		(start 344.74404 -400.979386)
		(end 344.74404 -400.811238)
		(width 0.14224)
		(layer "In13.Cu")
		(net "P5E_CPU0_P1_RX_BUF_DN<7>")
	)
	(segment
		(start 328.649584 -435.15788)
		(end 328.522584 -435.03088)
		(width 0.14224)
		(layer "In13.Cu")
		(net "P5E_CPU0_P1_RX_BUF_DN<7>")
	)
	(segment
		(start 334.402176 -409.816554)
		(end 334.40243 -409.816554)
		(width 0.14224)
		(layer "In13.Cu")
		(net "P5E_CPU0_P1_RX_BUF_DN<7>")
	)
	(segment
		(start 327.059036 -421.316658)
		(end 327.059036 -420.317422)
		(width 0.14224)
		(layer "In13.Cu")
		(net "P5E_CPU0_P1_RX_BUF_DN<7>")
	)
	(segment
		(start 327.688956 -424.749214)
		(end 327.688702 -424.749468)
		(width 0.14224)
		(layer "In13.Cu")
		(net "P5E_CPU0_P1_RX_BUF_DN<7>")
	)
	(segment
		(start 339.38972 -408.172412)
		(end 339.919818 -407.875994)
		(width 0.14224)
		(layer "In13.Cu")
		(net "P5E_CPU0_P1_RX_BUF_DN<7>")
	)
	(segment
		(start 330.122276 -413.306514)
		(end 330.122276 -412.502604)
		(width 0.14224)
		(layer "In13.Cu")
		(net "P5E_CPU0_P1_RX_BUF_DN<7>")
	)
	(segment
		(start 344.310462 -401.117816)
		(end 344.60561 -401.117816)
		(width 0.14224)
		(layer "In13.Cu")
		(net "P5E_CPU0_P1_RX_BUF_DN<7>")
	)
	(segment
		(start 327.688956 -434.73624)
		(end 327.688956 -424.749214)
		(width 0.14224)
		(layer "In13.Cu")
		(net "P5E_CPU0_P1_RX_BUF_DN<7>")
	)
	(segment
		(start 331.300836 -411.169104)
		(end 332.334616 -410.718254)
		(width 0.14224)
		(layer "In13.Cu")
		(net "P5E_CPU0_P1_RX_BUF_DN<7>")
	)
	(segment
		(start 343.97188 -403.587712)
		(end 343.97188 -401.64004)
		(width 0.14224)
		(layer "In13.Cu")
		(net "P5E_CPU0_P1_RX_BUF_DN<7>")
	)
	(segment
		(start 342.9762 -404.998936)
		(end 343.566496 -404.283926)
		(width 0.14224)
		(layer "In13.Cu")
		(net "P5E_CPU0_P1_RX_BUF_DN<7>")
	)
	(segment
		(start 328.649584 -435.489858)
		(end 328.649584 -435.15788)
		(width 0.14224)
		(layer "In13.Cu")
		(net "P5E_CPU0_P1_RX_BUF_DN<7>")
	)
	(segment
		(start 342.159336 -405.891746)
		(end 342.9762 -404.998936)
		(width 0.14224)
		(layer "In13.Cu")
		(net "P5E_CPU0_P1_RX_BUF_DN<7>")
	)
	(segment
		(start 335.436464 -409.365704)
		(end 335.76387 -409.222702)
		(width 0.14224)
		(layer "In13.Cu")
		(net "P5E_CPU0_P1_RX_BUF_DN<7>")
	)
	(segment
		(start 343.566496 -404.283926)
		(end 343.921588 -403.752812)
		(width 0.14224)
		(layer "In13.Cu")
		(net "P5E_CPU0_P1_RX_BUF_DN<7>")
	)
	(segment
		(start 327.41743 -419.78072)
		(end 328.387456 -419.378384)
		(width 0.14224)
		(layer "In13.Cu")
		(net "P5E_CPU0_P1_RX_BUF_DN<7>")
	)
	(segment
		(start 327.983596 -435.03088)
		(end 327.688956 -434.73624)
		(width 0.14224)
		(layer "In13.Cu")
		(net "P5E_CPU0_P1_RX_BUF_DN<7>")
	)
	(segment
		(start 343.971626 -403.587458)
		(end 343.97188 -403.587712)
		(width 0.14224)
		(layer "In13.Cu")
		(net "P5E_CPU0_P1_RX_BUF_DN<7>")
	)
	(segment
		(start 341.136478 -406.90165)
		(end 342.159336 -405.891746)
		(width 0.14224)
		(layer "In13.Cu")
		(net "P5E_CPU0_P1_RX_BUF_DN<7>")
	)
	(segment
		(start 328.730102 -414.600898)
		(end 328.978514 -414.263586)
		(width 0.14224)
		(layer "In13.Cu")
		(net "P5E_CPU0_P1_RX_BUF_DN<7>")
	)
	(segment
		(start 334.40243 -409.816554)
		(end 335.43621 -409.365958)
		(width 0.14224)
		(layer "In13.Cu")
		(net "P5E_CPU0_P1_RX_BUF_DN<7>")
	)
	(segment
		(start 330.39812 -411.836616)
		(end 330.561442 -411.673294)
		(width 0.14224)
		(layer "In13.Cu")
		(net "P5E_CPU0_P1_RX_BUF_DN<7>")
	)
	(segment
		(start 327.674732 -424.604434)
		(end 327.109582 -421.753284)
		(width 0.14224)
		(layer "In13.Cu")
		(net "P5E_CPU0_P1_RX_BUF_DN<7>")
	)
	(segment
		(start 339.919818 -407.875994)
		(end 341.136478 -406.90165)
		(width 0.14224)
		(layer "In13.Cu")
		(net "P5E_CPU0_P1_RX_BUF_DN<7>")
	)
	(segment
		(start 329.605132 -413.903922)
		(end 329.875134 -413.723328)
		(width 0.14224)
		(layer "In13.Cu")
		(net "P5E_CPU0_P1_RX_BUF_DN<7>")
	)
	(segment
		(start 335.43621 -409.365958)
		(end 335.436464 -409.365704)
		(width 0.14224)
		(layer "In13.Cu")
		(net "P5E_CPU0_P1_RX_BUF_DN<7>")
	)
	(segment
		(start 344.60561 -401.117816)
		(end 344.74404 -400.979386)
		(width 0.14224)
		(layer "In13.Cu")
		(net "P5E_CPU0_P1_RX_BUF_DN<7>")
	)
	(segment
		(start 332.334616 -410.718254)
		(end 332.33487 -410.718254)
		(width 0.14224)
		(layer "In13.Cu")
		(net "P5E_CPU0_P1_RX_BUF_DN<7>")
	)
	(segment
		(start 328.522584 -435.03088)
		(end 327.983596 -435.03088)
		(width 0.14224)
		(layer "In13.Cu")
		(net "P5E_CPU0_P1_RX_BUF_DN<7>")
	)
	(segment
		(start 335.76387 -409.222702)
		(end 339.38972 -408.172412)
		(width 0.14224)
		(layer "In13.Cu")
		(net "P5E_CPU0_P1_RX_BUF_DN<7>")
	)
	(segment
		(start 329.875134 -413.723328)
		(end 330.002388 -413.596074)
		(width 0.14224)
		(layer "In13.Cu")
		(net "P5E_CPU0_P1_RX_BUF_DN<7>")
	)
	(arc
		(start 330.122276 -412.502604)
		(mid 330.193969 -412.14218)
		(end 330.39812 -411.836616)
		(width 0.14224)
		(layer "In13.Cu")
		(net "P5E_CPU0_P1_RX_BUF_DN<7>")
	)
	(arc
		(start 330.002388 -413.596074)
		(mid 330.091103 -413.463209)
		(end 330.122276 -413.306514)
		(width 0.14224)
		(layer "In13.Cu")
		(net "P5E_CPU0_P1_RX_BUF_DN<7>")
	)
	(arc
		(start 330.561442 -411.673294)
		(mid 330.907472 -411.386492)
		(end 331.300836 -411.169104)
		(width 0.14224)
		(layer "In13.Cu")
		(net "P5E_CPU0_P1_RX_BUF_DN<7>")
	)
	(arc
		(start 328.590656 -415.025332)
		(mid 328.626356 -414.80193)
		(end 328.730102 -414.600898)
		(width 0.14224)
		(layer "In13.Cu")
		(net "P5E_CPU0_P1_RX_BUF_DN<7>")
	)
	(arc
		(start 328.38771 -419.378384)
		(mid 328.537824 -419.158086)
		(end 328.590656 -418.8968)
		(width 0.14224)
		(layer "In13.Cu")
		(net "P5E_CPU0_P1_RX_BUF_DN<7>")
	)
	(arc
		(start 327.067418 -421.476932)
		(mid 327.061109 -421.396906)
		(end 327.059036 -421.316658)
		(width 0.14224)
		(layer "In13.Cu")
		(net "P5E_CPU0_P1_RX_BUF_DN<7>")
	)
	(arc
		(start 327.688702 -424.749468)
		(mid 327.685258 -424.67661)
		(end 327.674732 -424.604434)
		(width 0.14224)
		(layer "In13.Cu")
		(net "P5E_CPU0_P1_RX_BUF_DN<7>")
	)
	(arc
		(start 343.921588 -403.752812)
		(mid 343.958936 -403.67386)
		(end 343.971626 -403.587458)
		(width 0.14224)
		(layer "In13.Cu")
		(net "P5E_CPU0_P1_RX_BUF_DN<7>")
	)
	(arc
		(start 327.109582 -421.753284)
		(mid 327.085375 -421.615585)
		(end 327.067418 -421.476932)
		(width 0.14224)
		(layer "In13.Cu")
		(net "P5E_CPU0_P1_RX_BUF_DN<7>")
	)
	(arc
		(start 328.978514 -414.263586)
		(mid 329.098536 -414.139887)
		(end 329.247246 -414.052766)
		(width 0.14224)
		(layer "In13.Cu")
		(net "P5E_CPU0_P1_RX_BUF_DN<7>")
	)
	(arc
		(start 327.059036 -420.317422)
		(mid 327.156863 -419.994724)
		(end 327.41743 -419.78072)
		(width 0.14224)
		(layer "In13.Cu")
		(net "P5E_CPU0_P1_RX_BUF_DN<7>")
	)
	(arc
		(start 343.97188 -401.64004)
		(mid 344.005619 -401.470423)
		(end 344.101674 -401.326604)
		(width 0.14224)
		(layer "In13.Cu")
		(net "P5E_CPU0_P1_RX_BUF_DN<7>")
	)
	(segment
		(start 343.145872 -399.74774)
		(end 343.145872 -399.960338)
		(width 0.1016)
		(layer "F.Cu")
		(net "P5E_CPU0_P1_RX_BUF_DN<6>")
	)
	(segment
		(start 343.193116 -401.143216)
		(end 343.403428 -401.143216)
		(width 0.1016)
		(layer "F.Cu")
		(net "P5E_CPU0_P1_RX_BUF_DN<6>")
	)
	(segment
		(start 343.146126 -399.747486)
		(end 343.145872 -399.74774)
		(width 0.1016)
		(layer "F.Cu")
		(net "P5E_CPU0_P1_RX_BUF_DN<6>")
	)
	(segment
		(start 343.066116 -400.040094)
		(end 343.066116 -401.016216)
		(width 0.1016)
		(layer "F.Cu")
		(net "P5E_CPU0_P1_RX_BUF_DN<6>")
	)
	(segment
		(start 343.145618 -399.143474)
		(end 343.146126 -399.143982)
		(width 0.1016)
		(layer "F.Cu")
		(net "P5E_CPU0_P1_RX_BUF_DN<6>")
	)
	(segment
		(start 343.145872 -399.960338)
		(end 343.066116 -400.040094)
		(width 0.1016)
		(layer "F.Cu")
		(net "P5E_CPU0_P1_RX_BUF_DN<6>")
	)
	(segment
		(start 343.146126 -399.143982)
		(end 343.146126 -399.747486)
		(width 0.1016)
		(layer "F.Cu")
		(net "P5E_CPU0_P1_RX_BUF_DN<6>")
	)
	(segment
		(start 343.403428 -401.143216)
		(end 343.544144 -401.0025)
		(width 0.1016)
		(layer "F.Cu")
		(net "P5E_CPU0_P1_RX_BUF_DN<6>")
	)
	(segment
		(start 343.066116 -401.016216)
		(end 343.193116 -401.143216)
		(width 0.1016)
		(layer "F.Cu")
		(net "P5E_CPU0_P1_RX_BUF_DN<6>")
	)
	(segment
		(start 343.544144 -401.0025)
		(end 343.544144 -400.811238)
		(width 0.1016)
		(layer "F.Cu")
		(net "P5E_CPU0_P1_RX_BUF_DN<6>")
	)
	(segment
		(start 325.68896 -425.092622)
		(end 325.68896 -433.738782)
		(width 0.14224)
		(layer "In13.Cu")
		(net "P5E_CPU0_P1_RX_BUF_DN<6>")
	)
	(segment
		(start 336.889598 -407.899362)
		(end 334.35544 -408.66822)
		(width 0.14224)
		(layer "In13.Cu")
		(net "P5E_CPU0_P1_RX_BUF_DN<6>")
	)
	(segment
		(start 323.995796 -420.22776)
		(end 323.995796 -421.477186)
		(width 0.14224)
		(layer "In13.Cu")
		(net "P5E_CPU0_P1_RX_BUF_DN<6>")
	)
	(segment
		(start 325.98106 -434.030882)
		(end 326.522588 -434.030882)
		(width 0.14224)
		(layer "In13.Cu")
		(net "P5E_CPU0_P1_RX_BUF_DN<6>")
	)
	(segment
		(start 327.697338 -411.579568)
		(end 327.34631 -411.924246)
		(width 0.14224)
		(layer "In13.Cu")
		(net "P5E_CPU0_P1_RX_BUF_DN<6>")
	)
	(segment
		(start 343.405714 -401.117816)
		(end 343.110566 -401.117816)
		(width 0.14224)
		(layer "In13.Cu")
		(net "P5E_CPU0_P1_RX_BUF_DN<6>")
	)
	(segment
		(start 339.162898 -407.16835)
		(end 338.447888 -407.464514)
		(width 0.14224)
		(layer "In13.Cu")
		(net "P5E_CPU0_P1_RX_BUF_DN<6>")
	)
	(segment
		(start 326.542654 -413.90316)
		(end 326.292718 -414.006538)
		(width 0.14224)
		(layer "In13.Cu")
		(net "P5E_CPU0_P1_RX_BUF_DN<6>")
	)
	(segment
		(start 325.481442 -419.194234)
		(end 325.313802 -419.370256)
		(width 0.14224)
		(layer "In13.Cu")
		(net "P5E_CPU0_P1_RX_BUF_DN<6>")
	)
	(segment
		(start 343.544144 -400.979386)
		(end 343.405714 -401.117816)
		(width 0.14224)
		(layer "In13.Cu")
		(net "P5E_CPU0_P1_RX_BUF_DN<6>")
	)
	(segment
		(start 342.803226 -401.425156)
		(end 342.803226 -403.683724)
		(width 0.14224)
		(layer "In13.Cu")
		(net "P5E_CPU0_P1_RX_BUF_DN<6>")
	)
	(segment
		(start 326.649588 -434.157882)
		(end 326.649588 -434.48986)
		(width 0.14224)
		(layer "In13.Cu")
		(net "P5E_CPU0_P1_RX_BUF_DN<6>")
	)
	(segment
		(start 343.544144 -400.811238)
		(end 343.544144 -400.979386)
		(width 0.14224)
		(layer "In13.Cu")
		(net "P5E_CPU0_P1_RX_BUF_DN<6>")
	)
	(segment
		(start 326.939148 -413.596074)
		(end 326.811894 -413.723328)
		(width 0.14224)
		(layer "In13.Cu")
		(net "P5E_CPU0_P1_RX_BUF_DN<6>")
	)
	(segment
		(start 342.765888 -403.77364)
		(end 339.815932 -406.723596)
		(width 0.14224)
		(layer "In13.Cu")
		(net "P5E_CPU0_P1_RX_BUF_DN<6>")
	)
	(segment
		(start 325.000874 -423.6085)
		(end 325.676514 -425.038012)
		(width 0.14224)
		(layer "In13.Cu")
		(net "P5E_CPU0_P1_RX_BUF_DN<6>")
	)
	(segment
		(start 343.110566 -401.117816)
		(end 342.803226 -401.425156)
		(width 0.14224)
		(layer "In13.Cu")
		(net "P5E_CPU0_P1_RX_BUF_DN<6>")
	)
	(segment
		(start 327.059036 -412.495238)
		(end 327.059036 -413.306514)
		(width 0.14224)
		(layer "In13.Cu")
		(net "P5E_CPU0_P1_RX_BUF_DN<6>")
	)
	(segment
		(start 327.223628 -412.079186)
		(end 327.13295 -412.2293)
		(width 0.14224)
		(layer "In13.Cu")
		(net "P5E_CPU0_P1_RX_BUF_DN<6>")
	)
	(segment
		(start 326.522588 -434.030882)
		(end 326.649588 -434.157882)
		(width 0.14224)
		(layer "In13.Cu")
		(net "P5E_CPU0_P1_RX_BUF_DN<6>")
	)
	(segment
		(start 334.35544 -408.66822)
		(end 328.20229 -411.305248)
		(width 0.14224)
		(layer "In13.Cu")
		(net "P5E_CPU0_P1_RX_BUF_DN<6>")
	)
	(segment
		(start 328.087228 -411.357572)
		(end 327.852532 -411.470602)
		(width 0.14224)
		(layer "In13.Cu")
		(net "P5E_CPU0_P1_RX_BUF_DN<6>")
	)
	(segment
		(start 324.11416 -421.94861)
		(end 325.000874 -423.6085)
		(width 0.14224)
		(layer "In13.Cu")
		(net "P5E_CPU0_P1_RX_BUF_DN<6>")
	)
	(segment
		(start 325.21017 -419.441376)
		(end 324.257416 -419.836346)
		(width 0.14224)
		(layer "In13.Cu")
		(net "P5E_CPU0_P1_RX_BUF_DN<6>")
	)
	(segment
		(start 326.811894 -413.723328)
		(end 326.542654 -413.90316)
		(width 0.14224)
		(layer "In13.Cu")
		(net "P5E_CPU0_P1_RX_BUF_DN<6>")
	)
	(segment
		(start 325.68896 -433.738782)
		(end 325.98106 -434.030882)
		(width 0.14224)
		(layer "In13.Cu")
		(net "P5E_CPU0_P1_RX_BUF_DN<6>")
	)
	(segment
		(start 338.447888 -407.464514)
		(end 336.889598 -407.899362)
		(width 0.14224)
		(layer "In13.Cu")
		(net "P5E_CPU0_P1_RX_BUF_DN<6>")
	)
	(segment
		(start 325.527416 -415.020252)
		(end 325.527416 -419.079426)
		(width 0.14224)
		(layer "In13.Cu")
		(net "P5E_CPU0_P1_RX_BUF_DN<6>")
	)
	(segment
		(start 339.760814 -406.768808)
		(end 339.162898 -407.16835)
		(width 0.14224)
		(layer "In13.Cu")
		(net "P5E_CPU0_P1_RX_BUF_DN<6>")
	)
	(arc
		(start 324.257416 -419.836346)
		(mid 324.067249 -419.992372)
		(end 323.995796 -420.22776)
		(width 0.14224)
		(layer "In13.Cu")
		(net "P5E_CPU0_P1_RX_BUF_DN<6>")
	)
	(arc
		(start 328.20229 -411.305248)
		(mid 328.144473 -411.330781)
		(end 328.087228 -411.357572)
		(width 0.14224)
		(layer "In13.Cu")
		(net "P5E_CPU0_P1_RX_BUF_DN<6>")
	)
	(arc
		(start 327.059036 -413.306514)
		(mid 327.027884 -413.463217)
		(end 326.939148 -413.596074)
		(width 0.14224)
		(layer "In13.Cu")
		(net "P5E_CPU0_P1_RX_BUF_DN<6>")
	)
	(arc
		(start 325.814944 -414.32607)
		(mid 325.602055 -414.644536)
		(end 325.527416 -415.020252)
		(width 0.14224)
		(layer "In13.Cu")
		(net "P5E_CPU0_P1_RX_BUF_DN<6>")
	)
	(arc
		(start 323.995796 -421.477186)
		(mid 324.025893 -421.720202)
		(end 324.11416 -421.94861)
		(width 0.14224)
		(layer "In13.Cu")
		(net "P5E_CPU0_P1_RX_BUF_DN<6>")
	)
	(arc
		(start 325.527416 -419.079426)
		(mid 325.515497 -419.141263)
		(end 325.481442 -419.194234)
		(width 0.14224)
		(layer "In13.Cu")
		(net "P5E_CPU0_P1_RX_BUF_DN<6>")
	)
	(arc
		(start 327.13295 -412.2293)
		(mid 327.077858 -412.357229)
		(end 327.059036 -412.495238)
		(width 0.14224)
		(layer "In13.Cu")
		(net "P5E_CPU0_P1_RX_BUF_DN<6>")
	)
	(arc
		(start 327.852532 -411.470602)
		(mid 327.770473 -411.518729)
		(end 327.697338 -411.579568)
		(width 0.14224)
		(layer "In13.Cu")
		(net "P5E_CPU0_P1_RX_BUF_DN<6>")
	)
	(arc
		(start 325.676514 -425.038012)
		(mid 325.685755 -425.064627)
		(end 325.68896 -425.092622)
		(width 0.14224)
		(layer "In13.Cu")
		(net "P5E_CPU0_P1_RX_BUF_DN<6>")
	)
	(arc
		(start 339.815932 -406.723596)
		(mid 339.789487 -406.747561)
		(end 339.760814 -406.768808)
		(width 0.14224)
		(layer "In13.Cu")
		(net "P5E_CPU0_P1_RX_BUF_DN<6>")
	)
	(arc
		(start 326.292718 -414.006538)
		(mid 326.038114 -414.142803)
		(end 325.814944 -414.32607)
		(width 0.14224)
		(layer "In13.Cu")
		(net "P5E_CPU0_P1_RX_BUF_DN<6>")
	)
	(arc
		(start 342.803226 -403.683724)
		(mid 342.793524 -403.732408)
		(end 342.765888 -403.77364)
		(width 0.14224)
		(layer "In13.Cu")
		(net "P5E_CPU0_P1_RX_BUF_DN<6>")
	)
	(arc
		(start 325.313802 -419.370256)
		(mid 325.265713 -419.411248)
		(end 325.21017 -419.441376)
		(width 0.14224)
		(layer "In13.Cu")
		(net "P5E_CPU0_P1_RX_BUF_DN<6>")
	)
	(arc
		(start 327.34631 -411.924246)
		(mid 327.280105 -411.997864)
		(end 327.223628 -412.079186)
		(width 0.14224)
		(layer "In13.Cu")
		(net "P5E_CPU0_P1_RX_BUF_DN<6>")
	)
	(segment
		(start 341.945976 -399.143982)
		(end 341.945976 -399.960338)
		(width 0.1016)
		(layer "F.Cu")
		(net "P5E_CPU0_P1_RX_BUF_DN<5>")
	)
	(segment
		(start 341.85733 -401.016216)
		(end 341.98433 -401.143216)
		(width 0.1016)
		(layer "F.Cu")
		(net "P5E_CPU0_P1_RX_BUF_DN<5>")
	)
	(segment
		(start 342.343994 -401.0025)
		(end 342.343994 -400.811238)
		(width 0.1016)
		(layer "F.Cu")
		(net "P5E_CPU0_P1_RX_BUF_DN<5>")
	)
	(segment
		(start 341.945976 -399.960338)
		(end 341.85733 -400.048984)
		(width 0.1016)
		(layer "F.Cu")
		(net "P5E_CPU0_P1_RX_BUF_DN<5>")
	)
	(segment
		(start 341.98433 -401.143216)
		(end 342.203278 -401.143216)
		(width 0.1016)
		(layer "F.Cu")
		(net "P5E_CPU0_P1_RX_BUF_DN<5>")
	)
	(segment
		(start 341.945468 -399.143474)
		(end 341.945976 -399.143982)
		(width 0.1016)
		(layer "F.Cu")
		(net "P5E_CPU0_P1_RX_BUF_DN<5>")
	)
	(segment
		(start 342.203278 -401.143216)
		(end 342.343994 -401.0025)
		(width 0.1016)
		(layer "F.Cu")
		(net "P5E_CPU0_P1_RX_BUF_DN<5>")
	)
	(segment
		(start 341.85733 -400.048984)
		(end 341.85733 -401.016216)
		(width 0.1016)
		(layer "F.Cu")
		(net "P5E_CPU0_P1_RX_BUF_DN<5>")
	)
	(segment
		(start 342.205564 -401.117816)
		(end 341.910416 -401.117816)
		(width 0.14224)
		(layer "In13.Cu")
		(net "P5E_CPU0_P1_RX_BUF_DN<5>")
	)
	(segment
		(start 324.05828 -435.03088)
		(end 324.522592 -435.03088)
		(width 0.14224)
		(layer "In13.Cu")
		(net "P5E_CPU0_P1_RX_BUF_DN<5>")
	)
	(segment
		(start 323.700648 -434.673248)
		(end 324.05828 -435.03088)
		(width 0.14224)
		(layer "In13.Cu")
		(net "P5E_CPU0_P1_RX_BUF_DN<5>")
	)
	(segment
		(start 324.522592 -435.03088)
		(end 324.649592 -435.15788)
		(width 0.14224)
		(layer "In13.Cu")
		(net "P5E_CPU0_P1_RX_BUF_DN<5>")
	)
	(segment
		(start 323.875908 -413.596074)
		(end 323.748654 -413.723328)
		(width 0.14224)
		(layer "In13.Cu")
		(net "P5E_CPU0_P1_RX_BUF_DN<5>")
	)
	(segment
		(start 321.215258 -422.166796)
		(end 322.39712 -423.348912)
		(width 0.14224)
		(layer "In13.Cu")
		(net "P5E_CPU0_P1_RX_BUF_DN<5>")
	)
	(segment
		(start 323.578474 -424.82389)
		(end 323.679312 -425.110148)
		(width 0.14224)
		(layer "In13.Cu")
		(net "P5E_CPU0_P1_RX_BUF_DN<5>")
	)
	(segment
		(start 341.561674 -403.643084)
		(end 339.72881 -405.475694)
		(width 0.14224)
		(layer "In13.Cu")
		(net "P5E_CPU0_P1_RX_BUF_DN<5>")
	)
	(segment
		(start 333.0702 -408.002994)
		(end 326.206866 -410.61767)
		(width 0.14224)
		(layer "In13.Cu")
		(net "P5E_CPU0_P1_RX_BUF_DN<5>")
	)
	(segment
		(start 336.285078 -406.940766)
		(end 333.0702 -408.002994)
		(width 0.14224)
		(layer "In13.Cu")
		(net "P5E_CPU0_P1_RX_BUF_DN<5>")
	)
	(segment
		(start 324.392798 -411.758638)
		(end 324.223888 -411.927548)
		(width 0.14224)
		(layer "In13.Cu")
		(net "P5E_CPU0_P1_RX_BUF_DN<5>")
	)
	(segment
		(start 323.700648 -425.234354)
		(end 323.700648 -434.673248)
		(width 0.14224)
		(layer "In13.Cu")
		(net "P5E_CPU0_P1_RX_BUF_DN<5>")
	)
	(segment
		(start 339.72881 -405.475694)
		(end 339.127338 -405.969724)
		(width 0.14224)
		(layer "In13.Cu")
		(net "P5E_CPU0_P1_RX_BUF_DN<5>")
	)
	(segment
		(start 341.910416 -401.117816)
		(end 341.603076 -401.425156)
		(width 0.14224)
		(layer "In13.Cu")
		(net "P5E_CPU0_P1_RX_BUF_DN<5>")
	)
	(segment
		(start 320.932556 -420.318946)
		(end 320.932556 -421.484298)
		(width 0.14224)
		(layer "In13.Cu")
		(net "P5E_CPU0_P1_RX_BUF_DN<5>")
	)
	(segment
		(start 323.479414 -413.90316)
		(end 323.229478 -414.006538)
		(width 0.14224)
		(layer "In13.Cu")
		(net "P5E_CPU0_P1_RX_BUF_DN<5>")
	)
	(segment
		(start 322.39712 -423.348912)
		(end 323.514466 -424.710352)
		(width 0.14224)
		(layer "In13.Cu")
		(net "P5E_CPU0_P1_RX_BUF_DN<5>")
	)
	(segment
		(start 342.343994 -400.811238)
		(end 342.343994 -400.979386)
		(width 0.14224)
		(layer "In13.Cu")
		(net "P5E_CPU0_P1_RX_BUF_DN<5>")
	)
	(segment
		(start 322.464176 -415.020252)
		(end 322.464176 -419.034722)
		(width 0.14224)
		(layer "In13.Cu")
		(net "P5E_CPU0_P1_RX_BUF_DN<5>")
	)
	(segment
		(start 322.372736 -419.262814)
		(end 322.202302 -419.441376)
		(width 0.14224)
		(layer "In13.Cu")
		(net "P5E_CPU0_P1_RX_BUF_DN<5>")
	)
	(segment
		(start 341.603076 -401.425156)
		(end 341.603076 -403.543262)
		(width 0.14224)
		(layer "In13.Cu")
		(net "P5E_CPU0_P1_RX_BUF_DN<5>")
	)
	(segment
		(start 342.343994 -400.979386)
		(end 342.205564 -401.117816)
		(width 0.14224)
		(layer "In13.Cu")
		(net "P5E_CPU0_P1_RX_BUF_DN<5>")
	)
	(segment
		(start 326.206866 -410.61767)
		(end 325.146416 -411.195012)
		(width 0.14224)
		(layer "In13.Cu")
		(net "P5E_CPU0_P1_RX_BUF_DN<5>")
	)
	(segment
		(start 322.149724 -419.474396)
		(end 321.235324 -419.772592)
		(width 0.14224)
		(layer "In13.Cu")
		(net "P5E_CPU0_P1_RX_BUF_DN<5>")
	)
	(segment
		(start 321.235324 -419.772592)
		(end 321.049396 -419.908482)
		(width 0.14224)
		(layer "In13.Cu")
		(net "P5E_CPU0_P1_RX_BUF_DN<5>")
	)
	(segment
		(start 324.649592 -435.15788)
		(end 324.649592 -435.489858)
		(width 0.14224)
		(layer "In13.Cu")
		(net "P5E_CPU0_P1_RX_BUF_DN<5>")
	)
	(segment
		(start 339.127338 -405.969724)
		(end 338.517992 -406.376886)
		(width 0.14224)
		(layer "In13.Cu")
		(net "P5E_CPU0_P1_RX_BUF_DN<5>")
	)
	(segment
		(start 321.049396 -419.908482)
		(end 321.011042 -419.984936)
		(width 0.14224)
		(layer "In13.Cu")
		(net "P5E_CPU0_P1_RX_BUF_DN<5>")
	)
	(segment
		(start 337.960716 -406.607518)
		(end 336.285078 -406.940766)
		(width 0.14224)
		(layer "In13.Cu")
		(net "P5E_CPU0_P1_RX_BUF_DN<5>")
	)
	(segment
		(start 323.995796 -412.47822)
		(end 323.995796 -413.306514)
		(width 0.14224)
		(layer "In13.Cu")
		(net "P5E_CPU0_P1_RX_BUF_DN<5>")
	)
	(segment
		(start 323.748654 -413.723328)
		(end 323.479414 -413.90316)
		(width 0.14224)
		(layer "In13.Cu")
		(net "P5E_CPU0_P1_RX_BUF_DN<5>")
	)
	(segment
		(start 338.517992 -406.376886)
		(end 337.960716 -406.607518)
		(width 0.14224)
		(layer "In13.Cu")
		(net "P5E_CPU0_P1_RX_BUF_DN<5>")
	)
	(arc
		(start 322.464176 -419.034722)
		(mid 322.440465 -419.157591)
		(end 322.372736 -419.262814)
		(width 0.14224)
		(layer "In13.Cu")
		(net "P5E_CPU0_P1_RX_BUF_DN<5>")
	)
	(arc
		(start 322.202302 -419.441376)
		(mid 322.178068 -419.461162)
		(end 322.149724 -419.474396)
		(width 0.14224)
		(layer "In13.Cu")
		(net "P5E_CPU0_P1_RX_BUF_DN<5>")
	)
	(arc
		(start 320.932556 -421.484298)
		(mid 321.006027 -421.853664)
		(end 321.215258 -422.166796)
		(width 0.14224)
		(layer "In13.Cu")
		(net "P5E_CPU0_P1_RX_BUF_DN<5>")
	)
	(arc
		(start 323.514466 -424.710352)
		(mid 323.551434 -424.764323)
		(end 323.578474 -424.82389)
		(width 0.14224)
		(layer "In13.Cu")
		(net "P5E_CPU0_P1_RX_BUF_DN<5>")
	)
	(arc
		(start 324.223888 -411.927548)
		(mid 324.055072 -412.180198)
		(end 323.995796 -412.47822)
		(width 0.14224)
		(layer "In13.Cu")
		(net "P5E_CPU0_P1_RX_BUF_DN<5>")
	)
	(arc
		(start 321.011042 -419.984936)
		(mid 320.952378 -420.147376)
		(end 320.932556 -420.318946)
		(width 0.14224)
		(layer "In13.Cu")
		(net "P5E_CPU0_P1_RX_BUF_DN<5>")
	)
	(arc
		(start 323.679312 -425.110148)
		(mid 323.695266 -425.171344)
		(end 323.700648 -425.234354)
		(width 0.14224)
		(layer "In13.Cu")
		(net "P5E_CPU0_P1_RX_BUF_DN<5>")
	)
	(arc
		(start 341.603076 -403.543262)
		(mid 341.592311 -403.597292)
		(end 341.561674 -403.643084)
		(width 0.14224)
		(layer "In13.Cu")
		(net "P5E_CPU0_P1_RX_BUF_DN<5>")
	)
	(arc
		(start 323.229478 -414.006538)
		(mid 322.974874 -414.142803)
		(end 322.751704 -414.32607)
		(width 0.14224)
		(layer "In13.Cu")
		(net "P5E_CPU0_P1_RX_BUF_DN<5>")
	)
	(arc
		(start 323.995796 -413.306514)
		(mid 323.964644 -413.463217)
		(end 323.875908 -413.596074)
		(width 0.14224)
		(layer "In13.Cu")
		(net "P5E_CPU0_P1_RX_BUF_DN<5>")
	)
	(arc
		(start 325.146416 -411.195012)
		(mid 324.749359 -411.449754)
		(end 324.392798 -411.758638)
		(width 0.14224)
		(layer "In13.Cu")
		(net "P5E_CPU0_P1_RX_BUF_DN<5>")
	)
	(arc
		(start 322.751704 -414.32607)
		(mid 322.538815 -414.644536)
		(end 322.464176 -415.020252)
		(width 0.14224)
		(layer "In13.Cu")
		(net "P5E_CPU0_P1_RX_BUF_DN<5>")
	)
	(segment
		(start 340.657434 -400.048984)
		(end 340.657434 -401.016216)
		(width 0.1016)
		(layer "F.Cu")
		(net "P5E_CPU0_P1_RX_BUF_DN<4>")
	)
	(segment
		(start 340.745572 -399.143474)
		(end 340.74608 -399.143982)
		(width 0.1016)
		(layer "F.Cu")
		(net "P5E_CPU0_P1_RX_BUF_DN<4>")
	)
	(segment
		(start 341.003382 -401.143216)
		(end 341.144098 -401.0025)
		(width 0.1016)
		(layer "F.Cu")
		(net "P5E_CPU0_P1_RX_BUF_DN<4>")
	)
	(segment
		(start 340.74608 -399.143982)
		(end 340.74608 -399.960338)
		(width 0.1016)
		(layer "F.Cu")
		(net "P5E_CPU0_P1_RX_BUF_DN<4>")
	)
	(segment
		(start 341.144098 -401.0025)
		(end 341.144098 -400.811238)
		(width 0.1016)
		(layer "F.Cu")
		(net "P5E_CPU0_P1_RX_BUF_DN<4>")
	)
	(segment
		(start 340.74608 -399.960338)
		(end 340.657434 -400.048984)
		(width 0.1016)
		(layer "F.Cu")
		(net "P5E_CPU0_P1_RX_BUF_DN<4>")
	)
	(segment
		(start 340.784434 -401.143216)
		(end 341.003382 -401.143216)
		(width 0.1016)
		(layer "F.Cu")
		(net "P5E_CPU0_P1_RX_BUF_DN<4>")
	)
	(segment
		(start 340.657434 -401.016216)
		(end 340.784434 -401.143216)
		(width 0.1016)
		(layer "F.Cu")
		(net "P5E_CPU0_P1_RX_BUF_DN<4>")
	)
	(segment
		(start 318.630808 -422.33977)
		(end 320.845942 -423.821352)
		(width 0.14224)
		(layer "In13.Cu")
		(net "P5E_CPU0_P1_RX_BUF_DN<4>")
	)
	(segment
		(start 340.245446 -403.475952)
		(end 340.005924 -403.8346)
		(width 0.14224)
		(layer "In13.Cu")
		(net "P5E_CPU0_P1_RX_BUF_DN<4>")
	)
	(segment
		(start 322.649596 -434.157882)
		(end 322.649596 -434.48986)
		(width 0.14224)
		(layer "In13.Cu")
		(net "P5E_CPU0_P1_RX_BUF_DN<4>")
	)
	(segment
		(start 340.40318 -403.09546)
		(end 340.245446 -403.475952)
		(width 0.14224)
		(layer "In13.Cu")
		(net "P5E_CPU0_P1_RX_BUF_DN<4>")
	)
	(segment
		(start 318.24295 -421.992298)
		(end 318.494664 -422.231058)
		(width 0.14224)
		(layer "In13.Cu")
		(net "P5E_CPU0_P1_RX_BUF_DN<4>")
	)
	(segment
		(start 327.946004 -408.573224)
		(end 322.483734 -410.91358)
		(width 0.14224)
		(layer "In13.Cu")
		(net "P5E_CPU0_P1_RX_BUF_DN<4>")
	)
	(segment
		(start 320.416174 -413.90316)
		(end 320.166238 -414.006538)
		(width 0.14224)
		(layer "In13.Cu")
		(net "P5E_CPU0_P1_RX_BUF_DN<4>")
	)
	(segment
		(start 338.131912 -405.452326)
		(end 337.78825 -405.594566)
		(width 0.14224)
		(layer "In13.Cu")
		(net "P5E_CPU0_P1_RX_BUF_DN<4>")
	)
	(segment
		(start 317.938658 -421.495982)
		(end 318.111632 -421.82034)
		(width 0.14224)
		(layer "In13.Cu")
		(net "P5E_CPU0_P1_RX_BUF_DN<4>")
	)
	(segment
		(start 321.688968 -433.736242)
		(end 321.983608 -434.030882)
		(width 0.14224)
		(layer "In13.Cu")
		(net "P5E_CPU0_P1_RX_BUF_DN<4>")
	)
	(segment
		(start 320.932556 -412.46044)
		(end 320.932556 -413.306514)
		(width 0.14224)
		(layer "In13.Cu")
		(net "P5E_CPU0_P1_RX_BUF_DN<4>")
	)
	(segment
		(start 337.78825 -405.594566)
		(end 336.827114 -405.785574)
		(width 0.14224)
		(layer "In13.Cu")
		(net "P5E_CPU0_P1_RX_BUF_DN<4>")
	)
	(segment
		(start 320.812668 -413.596074)
		(end 320.685414 -413.723328)
		(width 0.14224)
		(layer "In13.Cu")
		(net "P5E_CPU0_P1_RX_BUF_DN<4>")
	)
	(segment
		(start 334.54086 -406.389078)
		(end 327.946004 -408.573224)
		(width 0.14224)
		(layer "In13.Cu")
		(net "P5E_CPU0_P1_RX_BUF_DN<4>")
	)
	(segment
		(start 321.983608 -434.030882)
		(end 322.522596 -434.030882)
		(width 0.14224)
		(layer "In13.Cu")
		(net "P5E_CPU0_P1_RX_BUF_DN<4>")
	)
	(segment
		(start 322.522596 -434.030882)
		(end 322.649596 -434.157882)
		(width 0.14224)
		(layer "In13.Cu")
		(net "P5E_CPU0_P1_RX_BUF_DN<4>")
	)
	(segment
		(start 320.685414 -413.723328)
		(end 320.416174 -413.90316)
		(width 0.14224)
		(layer "In13.Cu")
		(net "P5E_CPU0_P1_RX_BUF_DN<4>")
	)
	(segment
		(start 340.005924 -403.8346)
		(end 338.903564 -404.93696)
		(width 0.14224)
		(layer "In13.Cu")
		(net "P5E_CPU0_P1_RX_BUF_DN<4>")
	)
	(segment
		(start 319.08369 -419.441376)
		(end 318.130936 -419.836346)
		(width 0.14224)
		(layer "In13.Cu")
		(net "P5E_CPU0_P1_RX_BUF_DN<4>")
	)
	(segment
		(start 341.144098 -400.979386)
		(end 341.005668 -401.117816)
		(width 0.14224)
		(layer "In13.Cu")
		(net "P5E_CPU0_P1_RX_BUF_DN<4>")
	)
	(segment
		(start 319.400936 -415.020252)
		(end 319.400936 -419.079426)
		(width 0.14224)
		(layer "In13.Cu")
		(net "P5E_CPU0_P1_RX_BUF_DN<4>")
	)
	(segment
		(start 321.128136 -424.090084)
		(end 321.644772 -424.78579)
		(width 0.14224)
		(layer "In13.Cu")
		(net "P5E_CPU0_P1_RX_BUF_DN<4>")
	)
	(segment
		(start 341.144098 -400.811238)
		(end 341.144098 -400.979386)
		(width 0.14224)
		(layer "In13.Cu")
		(net "P5E_CPU0_P1_RX_BUF_DN<4>")
	)
	(segment
		(start 321.271392 -411.734254)
		(end 321.206368 -411.799278)
		(width 0.14224)
		(layer "In13.Cu")
		(net "P5E_CPU0_P1_RX_BUF_DN<4>")
	)
	(segment
		(start 319.354962 -419.194234)
		(end 319.187322 -419.370256)
		(width 0.14224)
		(layer "In13.Cu")
		(net "P5E_CPU0_P1_RX_BUF_DN<4>")
	)
	(segment
		(start 336.827114 -405.785574)
		(end 334.54086 -406.389078)
		(width 0.14224)
		(layer "In13.Cu")
		(net "P5E_CPU0_P1_RX_BUF_DN<4>")
	)
	(segment
		(start 341.005668 -401.117816)
		(end 340.71052 -401.117816)
		(width 0.14224)
		(layer "In13.Cu")
		(net "P5E_CPU0_P1_RX_BUF_DN<4>")
	)
	(segment
		(start 317.869316 -420.22776)
		(end 317.869316 -421.21836)
		(width 0.14224)
		(layer "In13.Cu")
		(net "P5E_CPU0_P1_RX_BUF_DN<4>")
	)
	(segment
		(start 340.40318 -401.425156)
		(end 340.40318 -403.09546)
		(width 0.14224)
		(layer "In13.Cu")
		(net "P5E_CPU0_P1_RX_BUF_DN<4>")
	)
	(segment
		(start 340.71052 -401.117816)
		(end 340.40318 -401.425156)
		(width 0.14224)
		(layer "In13.Cu")
		(net "P5E_CPU0_P1_RX_BUF_DN<4>")
	)
	(segment
		(start 321.688968 -424.919648)
		(end 321.688968 -433.736242)
		(width 0.14224)
		(layer "In13.Cu")
		(net "P5E_CPU0_P1_RX_BUF_DN<4>")
	)
	(segment
		(start 338.903564 -404.93696)
		(end 338.131912 -405.452326)
		(width 0.14224)
		(layer "In13.Cu")
		(net "P5E_CPU0_P1_RX_BUF_DN<4>")
	)
	(arc
		(start 322.483734 -410.91358)
		(mid 321.838408 -411.266073)
		(end 321.271392 -411.734254)
		(width 0.14224)
		(layer "In13.Cu")
		(net "P5E_CPU0_P1_RX_BUF_DN<4>")
	)
	(arc
		(start 318.494664 -422.231058)
		(mid 318.560438 -422.288292)
		(end 318.630808 -422.33977)
		(width 0.14224)
		(layer "In13.Cu")
		(net "P5E_CPU0_P1_RX_BUF_DN<4>")
	)
	(arc
		(start 321.644772 -424.78579)
		(mid 321.677636 -424.849165)
		(end 321.688968 -424.919648)
		(width 0.14224)
		(layer "In13.Cu")
		(net "P5E_CPU0_P1_RX_BUF_DN<4>")
	)
	(arc
		(start 318.130936 -419.836346)
		(mid 317.940769 -419.992372)
		(end 317.869316 -420.22776)
		(width 0.14224)
		(layer "In13.Cu")
		(net "P5E_CPU0_P1_RX_BUF_DN<4>")
	)
	(arc
		(start 320.932556 -413.306514)
		(mid 320.901404 -413.463217)
		(end 320.812668 -413.596074)
		(width 0.14224)
		(layer "In13.Cu")
		(net "P5E_CPU0_P1_RX_BUF_DN<4>")
	)
	(arc
		(start 320.166238 -414.006538)
		(mid 319.911634 -414.142803)
		(end 319.688464 -414.32607)
		(width 0.14224)
		(layer "In13.Cu")
		(net "P5E_CPU0_P1_RX_BUF_DN<4>")
	)
	(arc
		(start 318.111632 -421.82034)
		(mid 318.170356 -421.911616)
		(end 318.24295 -421.992298)
		(width 0.14224)
		(layer "In13.Cu")
		(net "P5E_CPU0_P1_RX_BUF_DN<4>")
	)
	(arc
		(start 321.206368 -411.799278)
		(mid 321.003734 -412.102636)
		(end 320.932556 -412.46044)
		(width 0.14224)
		(layer "In13.Cu")
		(net "P5E_CPU0_P1_RX_BUF_DN<4>")
	)
	(arc
		(start 319.187322 -419.370256)
		(mid 319.139233 -419.411248)
		(end 319.08369 -419.441376)
		(width 0.14224)
		(layer "In13.Cu")
		(net "P5E_CPU0_P1_RX_BUF_DN<4>")
	)
	(arc
		(start 319.688464 -414.32607)
		(mid 319.475575 -414.644536)
		(end 319.400936 -415.020252)
		(width 0.14224)
		(layer "In13.Cu")
		(net "P5E_CPU0_P1_RX_BUF_DN<4>")
	)
	(arc
		(start 320.845942 -423.821352)
		(mid 320.99857 -423.94361)
		(end 321.128136 -424.090084)
		(width 0.14224)
		(layer "In13.Cu")
		(net "P5E_CPU0_P1_RX_BUF_DN<4>")
	)
	(arc
		(start 317.869316 -421.21836)
		(mid 317.886917 -421.361434)
		(end 317.938658 -421.495982)
		(width 0.14224)
		(layer "In13.Cu")
		(net "P5E_CPU0_P1_RX_BUF_DN<4>")
	)
	(arc
		(start 319.400936 -419.079426)
		(mid 319.389017 -419.141263)
		(end 319.354962 -419.194234)
		(width 0.14224)
		(layer "In13.Cu")
		(net "P5E_CPU0_P1_RX_BUF_DN<4>")
	)
	(segment
		(start 339.470492 -401.016216)
		(end 339.597492 -401.143216)
		(width 0.1016)
		(layer "F.Cu")
		(net "P5E_CPU0_P1_RX_BUF_DN<3>")
	)
	(segment
		(start 339.545422 -399.143474)
		(end 339.54593 -399.143982)
		(width 0.1016)
		(layer "F.Cu")
		(net "P5E_CPU0_P1_RX_BUF_DN<3>")
	)
	(segment
		(start 339.597492 -401.143216)
		(end 339.803232 -401.143216)
		(width 0.1016)
		(layer "F.Cu")
		(net "P5E_CPU0_P1_RX_BUF_DN<3>")
	)
	(segment
		(start 339.54593 -399.143982)
		(end 339.54593 -399.960338)
		(width 0.1016)
		(layer "F.Cu")
		(net "P5E_CPU0_P1_RX_BUF_DN<3>")
	)
	(segment
		(start 339.943948 -401.0025)
		(end 339.943948 -400.811238)
		(width 0.1016)
		(layer "F.Cu")
		(net "P5E_CPU0_P1_RX_BUF_DN<3>")
	)
	(segment
		(start 339.54593 -399.960338)
		(end 339.470492 -400.035776)
		(width 0.1016)
		(layer "F.Cu")
		(net "P5E_CPU0_P1_RX_BUF_DN<3>")
	)
	(segment
		(start 339.470492 -400.035776)
		(end 339.470492 -401.016216)
		(width 0.1016)
		(layer "F.Cu")
		(net "P5E_CPU0_P1_RX_BUF_DN<3>")
	)
	(segment
		(start 339.803232 -401.143216)
		(end 339.943948 -401.0025)
		(width 0.1016)
		(layer "F.Cu")
		(net "P5E_CPU0_P1_RX_BUF_DN<3>")
	)
	(segment
		(start 314.806076 -420.250112)
		(end 314.806076 -421.490902)
		(width 0.14224)
		(layer "In13.Cu")
		(net "P5E_CPU0_P1_RX_BUF_DN<3>")
	)
	(segment
		(start 317.749428 -413.596074)
		(end 317.622174 -413.723328)
		(width 0.14224)
		(layer "In13.Cu")
		(net "P5E_CPU0_P1_RX_BUF_DN<3>")
	)
	(segment
		(start 315.374274 -422.187878)
		(end 317.278004 -422.976548)
		(width 0.14224)
		(layer "In13.Cu")
		(net "P5E_CPU0_P1_RX_BUF_DN<3>")
	)
	(segment
		(start 339.51037 -401.117816)
		(end 339.20303 -401.425156)
		(width 0.14224)
		(layer "In13.Cu")
		(net "P5E_CPU0_P1_RX_BUF_DN<3>")
	)
	(segment
		(start 319.688972 -434.661564)
		(end 320.058288 -435.03088)
		(width 0.14224)
		(layer "In13.Cu")
		(net "P5E_CPU0_P1_RX_BUF_DN<3>")
	)
	(segment
		(start 320.5226 -435.03088)
		(end 320.6496 -435.15788)
		(width 0.14224)
		(layer "In13.Cu")
		(net "P5E_CPU0_P1_RX_BUF_DN<3>")
	)
	(segment
		(start 333.863442 -405.580088)
		(end 328.034142 -407.466038)
		(width 0.14224)
		(layer "In13.Cu")
		(net "P5E_CPU0_P1_RX_BUF_DN<3>")
	)
	(segment
		(start 317.869316 -412.106618)
		(end 317.869316 -413.306514)
		(width 0.14224)
		(layer "In13.Cu")
		(net "P5E_CPU0_P1_RX_BUF_DN<3>")
	)
	(segment
		(start 338.354162 -404.100792)
		(end 338.056982 -404.315422)
		(width 0.14224)
		(layer "In13.Cu")
		(net "P5E_CPU0_P1_RX_BUF_DN<3>")
	)
	(segment
		(start 314.897008 -421.710612)
		(end 315.374274 -422.187878)
		(width 0.14224)
		(layer "In13.Cu")
		(net "P5E_CPU0_P1_RX_BUF_DN<3>")
	)
	(segment
		(start 317.622174 -413.723328)
		(end 317.352934 -413.90316)
		(width 0.14224)
		(layer "In13.Cu")
		(net "P5E_CPU0_P1_RX_BUF_DN<3>")
	)
	(segment
		(start 320.058288 -435.03088)
		(end 320.5226 -435.03088)
		(width 0.14224)
		(layer "In13.Cu")
		(net "P5E_CPU0_P1_RX_BUF_DN<3>")
	)
	(segment
		(start 339.20303 -402.966682)
		(end 339.087968 -403.244304)
		(width 0.14224)
		(layer "In13.Cu")
		(net "P5E_CPU0_P1_RX_BUF_DN<3>")
	)
	(segment
		(start 317.278004 -422.976548)
		(end 318.694562 -423.922952)
		(width 0.14224)
		(layer "In13.Cu")
		(net "P5E_CPU0_P1_RX_BUF_DN<3>")
	)
	(segment
		(start 337.393026 -404.649686)
		(end 333.863442 -405.580088)
		(width 0.14224)
		(layer "In13.Cu")
		(net "P5E_CPU0_P1_RX_BUF_DN<3>")
	)
	(segment
		(start 339.805518 -401.117816)
		(end 339.51037 -401.117816)
		(width 0.14224)
		(layer "In13.Cu")
		(net "P5E_CPU0_P1_RX_BUF_DN<3>")
	)
	(segment
		(start 317.352934 -413.90316)
		(end 317.102998 -414.006538)
		(width 0.14224)
		(layer "In13.Cu")
		(net "P5E_CPU0_P1_RX_BUF_DN<3>")
	)
	(segment
		(start 339.20303 -401.425156)
		(end 339.20303 -402.966682)
		(width 0.14224)
		(layer "In13.Cu")
		(net "P5E_CPU0_P1_RX_BUF_DN<3>")
	)
	(segment
		(start 319.353946 -424.650408)
		(end 319.665096 -425.232322)
		(width 0.14224)
		(layer "In13.Cu")
		(net "P5E_CPU0_P1_RX_BUF_DN<3>")
	)
	(segment
		(start 318.421766 -411.226762)
		(end 318.118236 -411.503876)
		(width 0.14224)
		(layer "In13.Cu")
		(net "P5E_CPU0_P1_RX_BUF_DN<3>")
	)
	(segment
		(start 338.840826 -403.614128)
		(end 338.354162 -404.100792)
		(width 0.14224)
		(layer "In13.Cu")
		(net "P5E_CPU0_P1_RX_BUF_DN<3>")
	)
	(segment
		(start 328.034142 -407.466038)
		(end 318.537844 -411.151832)
		(width 0.14224)
		(layer "In13.Cu")
		(net "P5E_CPU0_P1_RX_BUF_DN<3>")
	)
	(segment
		(start 319.688972 -425.32681)
		(end 319.688972 -434.661564)
		(width 0.14224)
		(layer "In13.Cu")
		(net "P5E_CPU0_P1_RX_BUF_DN<3>")
	)
	(segment
		(start 338.056982 -404.315422)
		(end 337.393026 -404.649686)
		(width 0.14224)
		(layer "In13.Cu")
		(net "P5E_CPU0_P1_RX_BUF_DN<3>")
	)
	(segment
		(start 316.337696 -415.020252)
		(end 316.337696 -419.123622)
		(width 0.14224)
		(layer "In13.Cu")
		(net "P5E_CPU0_P1_RX_BUF_DN<3>")
	)
	(segment
		(start 316.28588 -419.23462)
		(end 316.109096 -419.383464)
		(width 0.14224)
		(layer "In13.Cu")
		(net "P5E_CPU0_P1_RX_BUF_DN<3>")
	)
	(segment
		(start 320.6496 -435.15788)
		(end 320.6496 -435.489858)
		(width 0.14224)
		(layer "In13.Cu")
		(net "P5E_CPU0_P1_RX_BUF_DN<3>")
	)
	(segment
		(start 314.806076 -421.490902)
		(end 314.897008 -421.710612)
		(width 0.14224)
		(layer "In13.Cu")
		(net "P5E_CPU0_P1_RX_BUF_DN<3>")
	)
	(segment
		(start 316.0014 -419.44925)
		(end 315.087508 -419.828218)
		(width 0.14224)
		(layer "In13.Cu")
		(net "P5E_CPU0_P1_RX_BUF_DN<3>")
	)
	(segment
		(start 339.943948 -400.811238)
		(end 339.943948 -400.979386)
		(width 0.14224)
		(layer "In13.Cu")
		(net "P5E_CPU0_P1_RX_BUF_DN<3>")
	)
	(segment
		(start 339.943948 -400.979386)
		(end 339.805518 -401.117816)
		(width 0.14224)
		(layer "In13.Cu")
		(net "P5E_CPU0_P1_RX_BUF_DN<3>")
	)
	(arc
		(start 317.869316 -413.306514)
		(mid 317.838164 -413.463217)
		(end 317.749428 -413.596074)
		(width 0.14224)
		(layer "In13.Cu")
		(net "P5E_CPU0_P1_RX_BUF_DN<3>")
	)
	(arc
		(start 318.118236 -411.503876)
		(mid 317.934047 -411.780572)
		(end 317.869316 -412.106618)
		(width 0.14224)
		(layer "In13.Cu")
		(net "P5E_CPU0_P1_RX_BUF_DN<3>")
	)
	(arc
		(start 319.665096 -425.232322)
		(mid 319.682872 -425.278093)
		(end 319.688972 -425.32681)
		(width 0.14224)
		(layer "In13.Cu")
		(net "P5E_CPU0_P1_RX_BUF_DN<3>")
	)
	(arc
		(start 316.109096 -419.383464)
		(mid 316.057792 -419.420525)
		(end 316.0014 -419.44925)
		(width 0.14224)
		(layer "In13.Cu")
		(net "P5E_CPU0_P1_RX_BUF_DN<3>")
	)
	(arc
		(start 317.102998 -414.006538)
		(mid 316.848394 -414.142803)
		(end 316.625224 -414.32607)
		(width 0.14224)
		(layer "In13.Cu")
		(net "P5E_CPU0_P1_RX_BUF_DN<3>")
	)
	(arc
		(start 315.087508 -419.828218)
		(mid 314.88289 -419.996538)
		(end 314.806076 -420.250112)
		(width 0.14224)
		(layer "In13.Cu")
		(net "P5E_CPU0_P1_RX_BUF_DN<3>")
	)
	(arc
		(start 339.087968 -403.244304)
		(mid 338.982613 -403.44139)
		(end 338.840826 -403.614128)
		(width 0.14224)
		(layer "In13.Cu")
		(net "P5E_CPU0_P1_RX_BUF_DN<3>")
	)
	(arc
		(start 318.537844 -411.151832)
		(mid 318.476622 -411.184366)
		(end 318.421766 -411.226762)
		(width 0.14224)
		(layer "In13.Cu")
		(net "P5E_CPU0_P1_RX_BUF_DN<3>")
	)
	(arc
		(start 316.625224 -414.32607)
		(mid 316.412335 -414.644536)
		(end 316.337696 -415.020252)
		(width 0.14224)
		(layer "In13.Cu")
		(net "P5E_CPU0_P1_RX_BUF_DN<3>")
	)
	(arc
		(start 318.694562 -423.922952)
		(mid 319.0691 -424.246032)
		(end 319.353946 -424.650408)
		(width 0.14224)
		(layer "In13.Cu")
		(net "P5E_CPU0_P1_RX_BUF_DN<3>")
	)
	(arc
		(start 316.337696 -419.123622)
		(mid 316.32405 -419.184843)
		(end 316.28588 -419.23462)
		(width 0.14224)
		(layer "In13.Cu")
		(net "P5E_CPU0_P1_RX_BUF_DN<3>")
	)
	(segment
		(start 338.257388 -401.016216)
		(end 338.384388 -401.143216)
		(width 0.1016)
		(layer "F.Cu")
		(net "P5E_CPU0_P1_RX_BUF_DN<2>")
	)
	(segment
		(start 338.603336 -401.143216)
		(end 338.744052 -401.0025)
		(width 0.1016)
		(layer "F.Cu")
		(net "P5E_CPU0_P1_RX_BUF_DN<2>")
	)
	(segment
		(start 338.345526 -399.143474)
		(end 338.346034 -399.143982)
		(width 0.1016)
		(layer "F.Cu")
		(net "P5E_CPU0_P1_RX_BUF_DN<2>")
	)
	(segment
		(start 338.744052 -401.0025)
		(end 338.744052 -400.811238)
		(width 0.1016)
		(layer "F.Cu")
		(net "P5E_CPU0_P1_RX_BUF_DN<2>")
	)
	(segment
		(start 338.257388 -400.048984)
		(end 338.257388 -401.016216)
		(width 0.1016)
		(layer "F.Cu")
		(net "P5E_CPU0_P1_RX_BUF_DN<2>")
	)
	(segment
		(start 338.346034 -399.143982)
		(end 338.346034 -399.960338)
		(width 0.1016)
		(layer "F.Cu")
		(net "P5E_CPU0_P1_RX_BUF_DN<2>")
	)
	(segment
		(start 338.384388 -401.143216)
		(end 338.603336 -401.143216)
		(width 0.1016)
		(layer "F.Cu")
		(net "P5E_CPU0_P1_RX_BUF_DN<2>")
	)
	(segment
		(start 338.346034 -399.960338)
		(end 338.257388 -400.048984)
		(width 0.1016)
		(layer "F.Cu")
		(net "P5E_CPU0_P1_RX_BUF_DN<2>")
	)
	(segment
		(start 313.274456 -415.020252)
		(end 313.274456 -418.933122)
		(width 0.14224)
		(layer "In13.Cu")
		(net "P5E_CPU0_P1_RX_BUF_DN<2>")
	)
	(segment
		(start 314.289694 -413.90316)
		(end 314.039758 -414.006538)
		(width 0.14224)
		(layer "In13.Cu")
		(net "P5E_CPU0_P1_RX_BUF_DN<2>")
	)
	(segment
		(start 313.22137 -419.061392)
		(end 312.994802 -419.28796)
		(width 0.14224)
		(layer "In13.Cu")
		(net "P5E_CPU0_P1_RX_BUF_DN<2>")
	)
	(segment
		(start 338.744052 -400.811238)
		(end 338.744052 -400.979386)
		(width 0.14224)
		(layer "In13.Cu")
		(net "P5E_CPU0_P1_RX_BUF_DN<2>")
	)
	(segment
		(start 311.742836 -420.53764)
		(end 311.742836 -421.317166)
		(width 0.14224)
		(layer "In13.Cu")
		(net "P5E_CPU0_P1_RX_BUF_DN<2>")
	)
	(segment
		(start 314.686188 -413.596074)
		(end 314.558934 -413.723328)
		(width 0.14224)
		(layer "In13.Cu")
		(net "P5E_CPU0_P1_RX_BUF_DN<2>")
	)
	(segment
		(start 312.103008 -422.01719)
		(end 312.359548 -422.201086)
		(width 0.14224)
		(layer "In13.Cu")
		(net "P5E_CPU0_P1_RX_BUF_DN<2>")
	)
	(segment
		(start 314.91428 -411.857444)
		(end 314.849764 -412.089854)
		(width 0.14224)
		(layer "In13.Cu")
		(net "P5E_CPU0_P1_RX_BUF_DN<2>")
	)
	(segment
		(start 333.608426 -404.556722)
		(end 329.50404 -405.660606)
		(width 0.14224)
		(layer "In13.Cu")
		(net "P5E_CPU0_P1_RX_BUF_DN<2>")
	)
	(segment
		(start 314.558934 -413.723328)
		(end 314.289694 -413.90316)
		(width 0.14224)
		(layer "In13.Cu")
		(net "P5E_CPU0_P1_RX_BUF_DN<2>")
	)
	(segment
		(start 318.522604 -434.030882)
		(end 318.649604 -434.157882)
		(width 0.14224)
		(layer "In13.Cu")
		(net "P5E_CPU0_P1_RX_BUF_DN<2>")
	)
	(segment
		(start 338.310474 -401.117816)
		(end 338.003134 -401.425156)
		(width 0.14224)
		(layer "In13.Cu")
		(net "P5E_CPU0_P1_RX_BUF_DN<2>")
	)
	(segment
		(start 316.815216 -424.001438)
		(end 317.532004 -424.750738)
		(width 0.14224)
		(layer "In13.Cu")
		(net "P5E_CPU0_P1_RX_BUF_DN<2>")
	)
	(segment
		(start 337.596734 -403.437344)
		(end 337.106768 -403.699726)
		(width 0.14224)
		(layer "In13.Cu")
		(net "P5E_CPU0_P1_RX_BUF_DN<2>")
	)
	(segment
		(start 312.359548 -422.201086)
		(end 312.359548 -422.200578)
		(width 0.14224)
		(layer "In13.Cu")
		(net "P5E_CPU0_P1_RX_BUF_DN<2>")
	)
	(segment
		(start 312.35015 -419.649402)
		(end 312.350404 -419.649656)
		(width 0.14224)
		(layer "In13.Cu")
		(net "P5E_CPU0_P1_RX_BUF_DN<2>")
	)
	(segment
		(start 312.350912 -419.649148)
		(end 312.35015 -419.649402)
		(width 0.14224)
		(layer "In13.Cu")
		(net "P5E_CPU0_P1_RX_BUF_DN<2>")
	)
	(segment
		(start 338.003134 -402.947886)
		(end 337.821778 -403.28723)
		(width 0.14224)
		(layer "In13.Cu")
		(net "P5E_CPU0_P1_RX_BUF_DN<2>")
	)
	(segment
		(start 313.439302 -422.565576)
		(end 316.676278 -423.906442)
		(width 0.14224)
		(layer "In13.Cu")
		(net "P5E_CPU0_P1_RX_BUF_DN<2>")
	)
	(segment
		(start 317.688976 -425.14139)
		(end 317.688976 -433.71643)
		(width 0.14224)
		(layer "In13.Cu")
		(net "P5E_CPU0_P1_RX_BUF_DN<2>")
	)
	(segment
		(start 312.150506 -419.78707)
		(end 311.963054 -419.984682)
		(width 0.14224)
		(layer "In13.Cu")
		(net "P5E_CPU0_P1_RX_BUF_DN<2>")
	)
	(segment
		(start 312.557922 -422.297098)
		(end 313.241944 -422.496234)
		(width 0.14224)
		(layer "In13.Cu")
		(net "P5E_CPU0_P1_RX_BUF_DN<2>")
	)
	(segment
		(start 337.821778 -403.28723)
		(end 337.596734 -403.437344)
		(width 0.14224)
		(layer "In13.Cu")
		(net "P5E_CPU0_P1_RX_BUF_DN<2>")
	)
	(segment
		(start 338.744052 -400.979386)
		(end 338.605622 -401.117816)
		(width 0.14224)
		(layer "In13.Cu")
		(net "P5E_CPU0_P1_RX_BUF_DN<2>")
	)
	(segment
		(start 315.292486 -411.414214)
		(end 315.114178 -411.555946)
		(width 0.14224)
		(layer "In13.Cu")
		(net "P5E_CPU0_P1_RX_BUF_DN<2>")
	)
	(segment
		(start 338.003134 -401.425156)
		(end 338.003134 -402.947886)
		(width 0.14224)
		(layer "In13.Cu")
		(net "P5E_CPU0_P1_RX_BUF_DN<2>")
	)
	(segment
		(start 318.649604 -434.157882)
		(end 318.649604 -434.48986)
		(width 0.14224)
		(layer "In13.Cu")
		(net "P5E_CPU0_P1_RX_BUF_DN<2>")
	)
	(segment
		(start 314.806076 -412.410402)
		(end 314.806076 -413.306514)
		(width 0.14224)
		(layer "In13.Cu")
		(net "P5E_CPU0_P1_RX_BUF_DN<2>")
	)
	(segment
		(start 337.106768 -403.699726)
		(end 336.834988 -403.811994)
		(width 0.14224)
		(layer "In13.Cu")
		(net "P5E_CPU0_P1_RX_BUF_DN<2>")
	)
	(segment
		(start 318.003428 -434.030882)
		(end 318.522604 -434.030882)
		(width 0.14224)
		(layer "In13.Cu")
		(net "P5E_CPU0_P1_RX_BUF_DN<2>")
	)
	(segment
		(start 336.834988 -403.811994)
		(end 333.608426 -404.556722)
		(width 0.14224)
		(layer "In13.Cu")
		(net "P5E_CPU0_P1_RX_BUF_DN<2>")
	)
	(segment
		(start 338.605622 -401.117816)
		(end 338.310474 -401.117816)
		(width 0.14224)
		(layer "In13.Cu")
		(net "P5E_CPU0_P1_RX_BUF_DN<2>")
	)
	(segment
		(start 317.688976 -433.71643)
		(end 318.003428 -434.030882)
		(width 0.14224)
		(layer "In13.Cu")
		(net "P5E_CPU0_P1_RX_BUF_DN<2>")
	)
	(segment
		(start 329.50404 -405.660606)
		(end 315.472064 -411.310074)
		(width 0.14224)
		(layer "In13.Cu")
		(net "P5E_CPU0_P1_RX_BUF_DN<2>")
	)
	(segment
		(start 312.939938 -419.332918)
		(end 312.68416 -419.503606)
		(width 0.14224)
		(layer "In13.Cu")
		(net "P5E_CPU0_P1_RX_BUF_DN<2>")
	)
	(segment
		(start 312.621168 -419.537388)
		(end 312.350912 -419.649148)
		(width 0.14224)
		(layer "In13.Cu")
		(net "P5E_CPU0_P1_RX_BUF_DN<2>")
	)
	(arc
		(start 314.039758 -414.006538)
		(mid 313.785154 -414.142803)
		(end 313.561984 -414.32607)
		(width 0.14224)
		(layer "In13.Cu")
		(net "P5E_CPU0_P1_RX_BUF_DN<2>")
	)
	(arc
		(start 312.68416 -419.503606)
		(mid 312.653491 -419.522039)
		(end 312.621168 -419.537388)
		(width 0.14224)
		(layer "In13.Cu")
		(net "P5E_CPU0_P1_RX_BUF_DN<2>")
	)
	(arc
		(start 315.472064 -411.310074)
		(mid 315.378513 -411.355656)
		(end 315.292486 -411.414214)
		(width 0.14224)
		(layer "In13.Cu")
		(net "P5E_CPU0_P1_RX_BUF_DN<2>")
	)
	(arc
		(start 312.359548 -422.200578)
		(mid 312.454652 -422.257232)
		(end 312.557922 -422.297098)
		(width 0.14224)
		(layer "In13.Cu")
		(net "P5E_CPU0_P1_RX_BUF_DN<2>")
	)
	(arc
		(start 312.350404 -419.649656)
		(mid 312.24324 -419.707867)
		(end 312.150506 -419.78707)
		(width 0.14224)
		(layer "In13.Cu")
		(net "P5E_CPU0_P1_RX_BUF_DN<2>")
	)
	(arc
		(start 314.849764 -412.089854)
		(mid 314.817007 -412.248642)
		(end 314.806076 -412.410402)
		(width 0.14224)
		(layer "In13.Cu")
		(net "P5E_CPU0_P1_RX_BUF_DN<2>")
	)
	(arc
		(start 316.676278 -423.906442)
		(mid 316.7507 -423.946699)
		(end 316.815216 -424.001438)
		(width 0.14224)
		(layer "In13.Cu")
		(net "P5E_CPU0_P1_RX_BUF_DN<2>")
	)
	(arc
		(start 315.114178 -411.555946)
		(mid 314.990373 -411.690876)
		(end 314.91428 -411.857444)
		(width 0.14224)
		(layer "In13.Cu")
		(net "P5E_CPU0_P1_RX_BUF_DN<2>")
	)
	(arc
		(start 313.274456 -418.933122)
		(mid 313.260666 -419.002538)
		(end 313.22137 -419.061392)
		(width 0.14224)
		(layer "In13.Cu")
		(net "P5E_CPU0_P1_RX_BUF_DN<2>")
	)
	(arc
		(start 317.532004 -424.750738)
		(mid 317.648183 -424.930913)
		(end 317.688976 -425.14139)
		(width 0.14224)
		(layer "In13.Cu")
		(net "P5E_CPU0_P1_RX_BUF_DN<2>")
	)
	(arc
		(start 313.561984 -414.32607)
		(mid 313.349095 -414.644536)
		(end 313.274456 -415.020252)
		(width 0.14224)
		(layer "In13.Cu")
		(net "P5E_CPU0_P1_RX_BUF_DN<2>")
	)
	(arc
		(start 312.994802 -419.28796)
		(mid 312.968484 -419.311799)
		(end 312.939938 -419.332918)
		(width 0.14224)
		(layer "In13.Cu")
		(net "P5E_CPU0_P1_RX_BUF_DN<2>")
	)
	(arc
		(start 311.963054 -419.984682)
		(mid 311.799792 -420.239997)
		(end 311.742836 -420.53764)
		(width 0.14224)
		(layer "In13.Cu")
		(net "P5E_CPU0_P1_RX_BUF_DN<2>")
	)
	(arc
		(start 311.742836 -421.317166)
		(mid 311.838218 -421.710756)
		(end 312.103008 -422.01719)
		(width 0.14224)
		(layer "In13.Cu")
		(net "P5E_CPU0_P1_RX_BUF_DN<2>")
	)
	(arc
		(start 313.241944 -422.496234)
		(mid 313.341571 -422.528208)
		(end 313.439302 -422.565576)
		(width 0.14224)
		(layer "In13.Cu")
		(net "P5E_CPU0_P1_RX_BUF_DN<2>")
	)
	(arc
		(start 314.806076 -413.306514)
		(mid 314.774924 -413.463217)
		(end 314.686188 -413.596074)
		(width 0.14224)
		(layer "In13.Cu")
		(net "P5E_CPU0_P1_RX_BUF_DN<2>")
	)
	(segment
		(start 337.145884 -399.960338)
		(end 337.057238 -400.048984)
		(width 0.1016)
		(layer "F.Cu")
		(net "P5E_CPU0_P1_RX_BUF_DN<1>")
	)
	(segment
		(start 337.057238 -400.048984)
		(end 337.057238 -401.016216)
		(width 0.1016)
		(layer "F.Cu")
		(net "P5E_CPU0_P1_RX_BUF_DN<1>")
	)
	(segment
		(start 337.145884 -399.143982)
		(end 337.145884 -399.960338)
		(width 0.1016)
		(layer "F.Cu")
		(net "P5E_CPU0_P1_RX_BUF_DN<1>")
	)
	(segment
		(start 337.057238 -401.016216)
		(end 337.184238 -401.143216)
		(width 0.1016)
		(layer "F.Cu")
		(net "P5E_CPU0_P1_RX_BUF_DN<1>")
	)
	(segment
		(start 337.403186 -401.143216)
		(end 337.543902 -401.0025)
		(width 0.1016)
		(layer "F.Cu")
		(net "P5E_CPU0_P1_RX_BUF_DN<1>")
	)
	(segment
		(start 337.145376 -399.143474)
		(end 337.145884 -399.143982)
		(width 0.1016)
		(layer "F.Cu")
		(net "P5E_CPU0_P1_RX_BUF_DN<1>")
	)
	(segment
		(start 337.543902 -401.0025)
		(end 337.543902 -400.811238)
		(width 0.1016)
		(layer "F.Cu")
		(net "P5E_CPU0_P1_RX_BUF_DN<1>")
	)
	(segment
		(start 337.184238 -401.143216)
		(end 337.403186 -401.143216)
		(width 0.1016)
		(layer "F.Cu")
		(net "P5E_CPU0_P1_RX_BUF_DN<1>")
	)
	(segment
		(start 311.742836 -412.371286)
		(end 311.742836 -413.306514)
		(width 0.14224)
		(layer "In13.Cu")
		(net "P5E_CPU0_P1_RX_BUF_DN<1>")
	)
	(segment
		(start 310.165242 -419.194234)
		(end 309.997602 -419.370256)
		(width 0.14224)
		(layer "In13.Cu")
		(net "P5E_CPU0_P1_RX_BUF_DN<1>")
	)
	(segment
		(start 337.110324 -401.117816)
		(end 336.802984 -401.425156)
		(width 0.14224)
		(layer "In13.Cu")
		(net "P5E_CPU0_P1_RX_BUF_DN<1>")
	)
	(segment
		(start 315.67628 -434.622956)
		(end 316.084204 -435.03088)
		(width 0.14224)
		(layer "In13.Cu")
		(net "P5E_CPU0_P1_RX_BUF_DN<1>")
	)
	(segment
		(start 315.67628 -425.239942)
		(end 315.67628 -434.622956)
		(width 0.14224)
		(layer "In13.Cu")
		(net "P5E_CPU0_P1_RX_BUF_DN<1>")
	)
	(segment
		(start 311.226454 -413.90316)
		(end 310.976518 -414.006538)
		(width 0.14224)
		(layer "In13.Cu")
		(net "P5E_CPU0_P1_RX_BUF_DN<1>")
	)
	(segment
		(start 336.802984 -401.425156)
		(end 336.802984 -402.755354)
		(width 0.14224)
		(layer "In13.Cu")
		(net "P5E_CPU0_P1_RX_BUF_DN<1>")
	)
	(segment
		(start 314.386468 -424.030902)
		(end 315.240924 -424.387772)
		(width 0.14224)
		(layer "In13.Cu")
		(net "P5E_CPU0_P1_RX_BUF_DN<1>")
	)
	(segment
		(start 315.41466 -424.609768)
		(end 315.67628 -425.239942)
		(width 0.14224)
		(layer "In13.Cu")
		(net "P5E_CPU0_P1_RX_BUF_DN<1>")
	)
	(segment
		(start 311.495694 -413.723328)
		(end 311.226454 -413.90316)
		(width 0.14224)
		(layer "In13.Cu")
		(net "P5E_CPU0_P1_RX_BUF_DN<1>")
	)
	(segment
		(start 308.679596 -420.22776)
		(end 308.679596 -421.32758)
		(width 0.14224)
		(layer "In13.Cu")
		(net "P5E_CPU0_P1_RX_BUF_DN<1>")
	)
	(segment
		(start 337.405472 -401.117816)
		(end 337.110324 -401.117816)
		(width 0.14224)
		(layer "In13.Cu")
		(net "P5E_CPU0_P1_RX_BUF_DN<1>")
	)
	(segment
		(start 316.084204 -435.03088)
		(end 316.484254 -435.03088)
		(width 0.14224)
		(layer "In13.Cu")
		(net "P5E_CPU0_P1_RX_BUF_DN<1>")
	)
	(segment
		(start 336.679286 -402.86178)
		(end 336.611468 -402.892006)
		(width 0.14224)
		(layer "In13.Cu")
		(net "P5E_CPU0_P1_RX_BUF_DN<1>")
	)
	(segment
		(start 316.649608 -435.196234)
		(end 316.649608 -435.489858)
		(width 0.14224)
		(layer "In13.Cu")
		(net "P5E_CPU0_P1_RX_BUF_DN<1>")
	)
	(segment
		(start 327.728326 -405.166068)
		(end 312.29046 -411.552136)
		(width 0.14224)
		(layer "In13.Cu")
		(net "P5E_CPU0_P1_RX_BUF_DN<1>")
	)
	(segment
		(start 311.622948 -413.596074)
		(end 311.495694 -413.723328)
		(width 0.14224)
		(layer "In13.Cu")
		(net "P5E_CPU0_P1_RX_BUF_DN<1>")
	)
	(segment
		(start 337.543902 -400.979386)
		(end 337.405472 -401.117816)
		(width 0.14224)
		(layer "In13.Cu")
		(net "P5E_CPU0_P1_RX_BUF_DN<1>")
	)
	(segment
		(start 337.543902 -400.811238)
		(end 337.543902 -400.979386)
		(width 0.14224)
		(layer "In13.Cu")
		(net "P5E_CPU0_P1_RX_BUF_DN<1>")
	)
	(segment
		(start 310.211216 -415.020252)
		(end 310.211216 -419.079426)
		(width 0.14224)
		(layer "In13.Cu")
		(net "P5E_CPU0_P1_RX_BUF_DN<1>")
	)
	(segment
		(start 336.611468 -402.892006)
		(end 332.277212 -403.877018)
		(width 0.14224)
		(layer "In13.Cu")
		(net "P5E_CPU0_P1_RX_BUF_DN<1>")
	)
	(segment
		(start 309.400702 -422.45788)
		(end 312.01741 -423.36847)
		(width 0.14224)
		(layer "In13.Cu")
		(net "P5E_CPU0_P1_RX_BUF_DN<1>")
	)
	(segment
		(start 336.802984 -402.755354)
		(end 336.679286 -402.86178)
		(width 0.14224)
		(layer "In13.Cu")
		(net "P5E_CPU0_P1_RX_BUF_DN<1>")
	)
	(segment
		(start 316.484254 -435.03088)
		(end 316.649608 -435.196234)
		(width 0.14224)
		(layer "In13.Cu")
		(net "P5E_CPU0_P1_RX_BUF_DN<1>")
	)
	(segment
		(start 309.89397 -419.441376)
		(end 308.941216 -419.836346)
		(width 0.14224)
		(layer "In13.Cu")
		(net "P5E_CPU0_P1_RX_BUF_DN<1>")
	)
	(segment
		(start 312.13806 -423.406062)
		(end 314.266834 -423.989754)
		(width 0.14224)
		(layer "In13.Cu")
		(net "P5E_CPU0_P1_RX_BUF_DN<1>")
	)
	(segment
		(start 327.9013 -405.107902)
		(end 327.728326 -405.166068)
		(width 0.14224)
		(layer "In13.Cu")
		(net "P5E_CPU0_P1_RX_BUF_DN<1>")
	)
	(segment
		(start 332.277212 -403.877018)
		(end 327.9013 -405.107902)
		(width 0.14224)
		(layer "In13.Cu")
		(net "P5E_CPU0_P1_RX_BUF_DN<1>")
	)
	(segment
		(start 315.29782 -424.434508)
		(end 315.41466 -424.609768)
		(width 0.14224)
		(layer "In13.Cu")
		(net "P5E_CPU0_P1_RX_BUF_DN<1>")
	)
	(arc
		(start 312.01741 -423.36847)
		(mid 312.07742 -423.388276)
		(end 312.13806 -423.406062)
		(width 0.14224)
		(layer "In13.Cu")
		(net "P5E_CPU0_P1_RX_BUF_DN<1>")
	)
	(arc
		(start 312.29046 -411.552136)
		(mid 311.892349 -411.878614)
		(end 311.742836 -412.371286)
		(width 0.14224)
		(layer "In13.Cu")
		(net "P5E_CPU0_P1_RX_BUF_DN<1>")
	)
	(arc
		(start 311.742836 -413.306514)
		(mid 311.711684 -413.463217)
		(end 311.622948 -413.596074)
		(width 0.14224)
		(layer "In13.Cu")
		(net "P5E_CPU0_P1_RX_BUF_DN<1>")
	)
	(arc
		(start 308.679596 -421.32758)
		(mid 308.749789 -421.728695)
		(end 308.951884 -422.082214)
		(width 0.14224)
		(layer "In13.Cu")
		(net "P5E_CPU0_P1_RX_BUF_DN<1>")
	)
	(arc
		(start 309.194962 -422.336214)
		(mid 309.291722 -422.407379)
		(end 309.400702 -422.45788)
		(width 0.14224)
		(layer "In13.Cu")
		(net "P5E_CPU0_P1_RX_BUF_DN<1>")
	)
	(arc
		(start 310.976518 -414.006538)
		(mid 310.721914 -414.142803)
		(end 310.498744 -414.32607)
		(width 0.14224)
		(layer "In13.Cu")
		(net "P5E_CPU0_P1_RX_BUF_DN<1>")
	)
	(arc
		(start 310.211216 -419.079426)
		(mid 310.199297 -419.141263)
		(end 310.165242 -419.194234)
		(width 0.14224)
		(layer "In13.Cu")
		(net "P5E_CPU0_P1_RX_BUF_DN<1>")
	)
	(arc
		(start 314.266834 -423.989754)
		(mid 314.32731 -424.008412)
		(end 314.386468 -424.030902)
		(width 0.14224)
		(layer "In13.Cu")
		(net "P5E_CPU0_P1_RX_BUF_DN<1>")
	)
	(arc
		(start 309.997602 -419.370256)
		(mid 309.949513 -419.411248)
		(end 309.89397 -419.441376)
		(width 0.14224)
		(layer "In13.Cu")
		(net "P5E_CPU0_P1_RX_BUF_DN<1>")
	)
	(arc
		(start 308.941216 -419.836346)
		(mid 308.751049 -419.992372)
		(end 308.679596 -420.22776)
		(width 0.14224)
		(layer "In13.Cu")
		(net "P5E_CPU0_P1_RX_BUF_DN<1>")
	)
	(arc
		(start 315.240924 -424.387772)
		(mid 315.272828 -424.406932)
		(end 315.29782 -424.434508)
		(width 0.14224)
		(layer "In13.Cu")
		(net "P5E_CPU0_P1_RX_BUF_DN<1>")
	)
	(arc
		(start 310.498744 -414.32607)
		(mid 310.285855 -414.644536)
		(end 310.211216 -415.020252)
		(width 0.14224)
		(layer "In13.Cu")
		(net "P5E_CPU0_P1_RX_BUF_DN<1>")
	)
	(arc
		(start 308.951884 -422.082214)
		(mid 309.068837 -422.213604)
		(end 309.194962 -422.336214)
		(width 0.14224)
		(layer "In13.Cu")
		(net "P5E_CPU0_P1_RX_BUF_DN<1>")
	)
	(segment
		(start 353.857306 -400.048984)
		(end 353.945952 -399.960338)
		(width 0.1016)
		(layer "F.Cu")
		(net "P5E_CPU0_P1_RX_BUF_DN<15>")
	)
	(segment
		(start 354.34397 -400.811238)
		(end 354.34397 -400.981926)
		(width 0.1016)
		(layer "F.Cu")
		(net "P5E_CPU0_P1_RX_BUF_DN<15>")
	)
	(segment
		(start 353.857306 -401.016216)
		(end 353.857306 -400.048984)
		(width 0.1016)
		(layer "F.Cu")
		(net "P5E_CPU0_P1_RX_BUF_DN<15>")
	)
	(segment
		(start 354.34397 -400.981926)
		(end 354.18268 -401.143216)
		(width 0.1016)
		(layer "F.Cu")
		(net "P5E_CPU0_P1_RX_BUF_DN<15>")
	)
	(segment
		(start 354.18268 -401.143216)
		(end 353.984306 -401.143216)
		(width 0.1016)
		(layer "F.Cu")
		(net "P5E_CPU0_P1_RX_BUF_DN<15>")
	)
	(segment
		(start 353.945952 -399.960338)
		(end 353.945952 -399.143982)
		(width 0.1016)
		(layer "F.Cu")
		(net "P5E_CPU0_P1_RX_BUF_DN<15>")
	)
	(segment
		(start 353.945952 -399.143982)
		(end 353.945444 -399.143474)
		(width 0.1016)
		(layer "F.Cu")
		(net "P5E_CPU0_P1_RX_BUF_DN<15>")
	)
	(segment
		(start 353.984306 -401.143216)
		(end 353.857306 -401.016216)
		(width 0.1016)
		(layer "F.Cu")
		(net "P5E_CPU0_P1_RX_BUF_DN<15>")
	)
	(segment
		(start 345.649804 -435.489858)
		(end 345.649804 -435.15788)
		(width 0.14224)
		(layer "In13.Cu")
		(net "P5E_CPU0_P1_RX_BUF_DN<15>")
	)
	(segment
		(start 345.271852 -423.887138)
		(end 345.447366 -423.814494)
		(width 0.14224)
		(layer "In13.Cu")
		(net "P5E_CPU0_P1_RX_BUF_DN<15>")
	)
	(segment
		(start 344.936826 -424.111166)
		(end 345.271852 -423.887138)
		(width 0.14224)
		(layer "In13.Cu")
		(net "P5E_CPU0_P1_RX_BUF_DN<15>")
	)
	(segment
		(start 345.522804 -435.03088)
		(end 344.99169 -435.03088)
		(width 0.14224)
		(layer "In13.Cu")
		(net "P5E_CPU0_P1_RX_BUF_DN<15>")
	)
	(segment
		(start 352.600768 -420.074852)
		(end 353.512374 -418.017706)
		(width 0.14224)
		(layer "In13.Cu")
		(net "P5E_CPU0_P1_RX_BUF_DN<15>")
	)
	(segment
		(start 344.99169 -435.03088)
		(end 344.688922 -434.728112)
		(width 0.14224)
		(layer "In13.Cu")
		(net "P5E_CPU0_P1_RX_BUF_DN<15>")
	)
	(segment
		(start 351.43948 -421.68064)
		(end 352.600768 -420.074852)
		(width 0.14224)
		(layer "In13.Cu")
		(net "P5E_CPU0_P1_RX_BUF_DN<15>")
	)
	(segment
		(start 353.512374 -418.017706)
		(end 353.603052 -417.589716)
		(width 0.14224)
		(layer "In13.Cu")
		(net "P5E_CPU0_P1_RX_BUF_DN<15>")
	)
	(segment
		(start 354.34397 -400.979386)
		(end 354.34397 -400.811238)
		(width 0.14224)
		(layer "In13.Cu")
		(net "P5E_CPU0_P1_RX_BUF_DN<15>")
	)
	(segment
		(start 344.809064 -424.238674)
		(end 344.936826 -424.111166)
		(width 0.14224)
		(layer "In13.Cu")
		(net "P5E_CPU0_P1_RX_BUF_DN<15>")
	)
	(segment
		(start 345.649804 -435.15788)
		(end 345.522804 -435.03088)
		(width 0.14224)
		(layer "In13.Cu")
		(net "P5E_CPU0_P1_RX_BUF_DN<15>")
	)
	(segment
		(start 347.284802 -423.353738)
		(end 350.625918 -422.250108)
		(width 0.14224)
		(layer "In13.Cu")
		(net "P5E_CPU0_P1_RX_BUF_DN<15>")
	)
	(segment
		(start 345.447366 -423.814494)
		(end 347.284802 -423.353738)
		(width 0.14224)
		(layer "In13.Cu")
		(net "P5E_CPU0_P1_RX_BUF_DN<15>")
	)
	(segment
		(start 353.910392 -401.117816)
		(end 354.20554 -401.117816)
		(width 0.14224)
		(layer "In13.Cu")
		(net "P5E_CPU0_P1_RX_BUF_DN<15>")
	)
	(segment
		(start 353.603052 -401.425156)
		(end 353.910392 -401.117816)
		(width 0.14224)
		(layer "In13.Cu")
		(net "P5E_CPU0_P1_RX_BUF_DN<15>")
	)
	(segment
		(start 344.688922 -434.728112)
		(end 344.688922 -424.528488)
		(width 0.14224)
		(layer "In13.Cu")
		(net "P5E_CPU0_P1_RX_BUF_DN<15>")
	)
	(segment
		(start 350.988122 -422.050972)
		(end 351.43948 -421.68064)
		(width 0.14224)
		(layer "In13.Cu")
		(net "P5E_CPU0_P1_RX_BUF_DN<15>")
	)
	(segment
		(start 353.603052 -417.589716)
		(end 353.603052 -401.425156)
		(width 0.14224)
		(layer "In13.Cu")
		(net "P5E_CPU0_P1_RX_BUF_DN<15>")
	)
	(segment
		(start 354.20554 -401.117816)
		(end 354.34397 -400.979386)
		(width 0.14224)
		(layer "In13.Cu")
		(net "P5E_CPU0_P1_RX_BUF_DN<15>")
	)
	(arc
		(start 350.625918 -422.250108)
		(mid 350.816182 -422.167207)
		(end 350.988122 -422.050972)
		(width 0.14224)
		(layer "In13.Cu")
		(net "P5E_CPU0_P1_RX_BUF_DN<15>")
	)
	(arc
		(start 344.688922 -424.528488)
		(mid 344.720143 -424.371619)
		(end 344.809064 -424.238674)
		(width 0.14224)
		(layer "In13.Cu")
		(net "P5E_CPU0_P1_RX_BUF_DN<15>")
	)
	(segment
		(start 352.746056 -399.960338)
		(end 352.746056 -399.143982)
		(width 0.1016)
		(layer "F.Cu")
		(net "P5E_CPU0_P1_RX_BUF_DN<14>")
	)
	(segment
		(start 353.144074 -400.97583)
		(end 352.976688 -401.143216)
		(width 0.1016)
		(layer "F.Cu")
		(net "P5E_CPU0_P1_RX_BUF_DN<14>")
	)
	(segment
		(start 353.144074 -400.811238)
		(end 353.144074 -400.97583)
		(width 0.1016)
		(layer "F.Cu")
		(net "P5E_CPU0_P1_RX_BUF_DN<14>")
	)
	(segment
		(start 352.65741 -400.048984)
		(end 352.746056 -399.960338)
		(width 0.1016)
		(layer "F.Cu")
		(net "P5E_CPU0_P1_RX_BUF_DN<14>")
	)
	(segment
		(start 352.976688 -401.143216)
		(end 352.78441 -401.143216)
		(width 0.1016)
		(layer "F.Cu")
		(net "P5E_CPU0_P1_RX_BUF_DN<14>")
	)
	(segment
		(start 352.65741 -401.016216)
		(end 352.65741 -400.048984)
		(width 0.1016)
		(layer "F.Cu")
		(net "P5E_CPU0_P1_RX_BUF_DN<14>")
	)
	(segment
		(start 352.746056 -399.143982)
		(end 352.745548 -399.143474)
		(width 0.1016)
		(layer "F.Cu")
		(net "P5E_CPU0_P1_RX_BUF_DN<14>")
	)
	(segment
		(start 352.78441 -401.143216)
		(end 352.65741 -401.016216)
		(width 0.1016)
		(layer "F.Cu")
		(net "P5E_CPU0_P1_RX_BUF_DN<14>")
	)
	(segment
		(start 351.555558 -413.395414)
		(end 352.31959 -405.63546)
		(width 0.14224)
		(layer "In13.Cu")
		(net "P5E_CPU0_P1_RX_BUF_DN<14>")
	)
	(segment
		(start 352.403156 -403.935692)
		(end 352.403156 -401.425156)
		(width 0.14224)
		(layer "In13.Cu")
		(net "P5E_CPU0_P1_RX_BUF_DN<14>")
	)
	(segment
		(start 342.688926 -433.738782)
		(end 342.688926 -424.699684)
		(width 0.14224)
		(layer "In13.Cu")
		(net "P5E_CPU0_P1_RX_BUF_DN<14>")
	)
	(segment
		(start 348.501716 -421.583104)
		(end 348.501716 -420.228014)
		(width 0.14224)
		(layer "In13.Cu")
		(net "P5E_CPU0_P1_RX_BUF_DN<14>")
	)
	(segment
		(start 345.981782 -422.553638)
		(end 348.16034 -421.950896)
		(width 0.14224)
		(layer "In13.Cu")
		(net "P5E_CPU0_P1_RX_BUF_DN<14>")
	)
	(segment
		(start 352.710496 -401.117816)
		(end 353.005644 -401.117816)
		(width 0.14224)
		(layer "In13.Cu")
		(net "P5E_CPU0_P1_RX_BUF_DN<14>")
	)
	(segment
		(start 343.159588 -423.899076)
		(end 345.687396 -422.635426)
		(width 0.14224)
		(layer "In13.Cu")
		(net "P5E_CPU0_P1_RX_BUF_DN<14>")
	)
	(segment
		(start 349.819722 -419.370256)
		(end 349.987362 -419.194234)
		(width 0.14224)
		(layer "In13.Cu")
		(net "P5E_CPU0_P1_RX_BUF_DN<14>")
	)
	(segment
		(start 353.005644 -401.117816)
		(end 353.144074 -400.979386)
		(width 0.14224)
		(layer "In13.Cu")
		(net "P5E_CPU0_P1_RX_BUF_DN<14>")
	)
	(segment
		(start 352.403156 -401.425156)
		(end 352.710496 -401.117816)
		(width 0.14224)
		(layer "In13.Cu")
		(net "P5E_CPU0_P1_RX_BUF_DN<14>")
	)
	(segment
		(start 348.16034 -421.950896)
		(end 348.22257 -421.914828)
		(width 0.14224)
		(layer "In13.Cu")
		(net "P5E_CPU0_P1_RX_BUF_DN<14>")
	)
	(segment
		(start 348.763336 -419.836346)
		(end 349.71609 -419.441376)
		(width 0.14224)
		(layer "In13.Cu")
		(net "P5E_CPU0_P1_RX_BUF_DN<14>")
	)
	(segment
		(start 342.823546 -424.283378)
		(end 342.98001 -424.06697)
		(width 0.14224)
		(layer "In13.Cu")
		(net "P5E_CPU0_P1_RX_BUF_DN<14>")
	)
	(segment
		(start 343.649808 -434.157882)
		(end 343.522808 -434.030882)
		(width 0.14224)
		(layer "In13.Cu")
		(net "P5E_CPU0_P1_RX_BUF_DN<14>")
	)
	(segment
		(start 342.981026 -434.030882)
		(end 342.688926 -433.738782)
		(width 0.14224)
		(layer "In13.Cu")
		(net "P5E_CPU0_P1_RX_BUF_DN<14>")
	)
	(segment
		(start 345.981782 -422.553892)
		(end 345.981782 -422.553638)
		(width 0.14224)
		(layer "In13.Cu")
		(net "P5E_CPU0_P1_RX_BUF_DN<14>")
	)
	(segment
		(start 343.649808 -434.48986)
		(end 343.649808 -434.157882)
		(width 0.14224)
		(layer "In13.Cu")
		(net "P5E_CPU0_P1_RX_BUF_DN<14>")
	)
	(segment
		(start 348.22257 -421.914828)
		(end 348.464378 -421.67302)
		(width 0.14224)
		(layer "In13.Cu")
		(net "P5E_CPU0_P1_RX_BUF_DN<14>")
	)
	(segment
		(start 343.522808 -434.030882)
		(end 342.981026 -434.030882)
		(width 0.14224)
		(layer "In13.Cu")
		(net "P5E_CPU0_P1_RX_BUF_DN<14>")
	)
	(segment
		(start 345.687396 -422.635426)
		(end 345.981782 -422.553892)
		(width 0.14224)
		(layer "In13.Cu")
		(net "P5E_CPU0_P1_RX_BUF_DN<14>")
	)
	(segment
		(start 353.144074 -400.979386)
		(end 353.144074 -400.811238)
		(width 0.14224)
		(layer "In13.Cu")
		(net "P5E_CPU0_P1_RX_BUF_DN<14>")
	)
	(segment
		(start 350.413066 -414.239202)
		(end 351.336864 -413.727392)
		(width 0.14224)
		(layer "In13.Cu")
		(net "P5E_CPU0_P1_RX_BUF_DN<14>")
	)
	(segment
		(start 350.033336 -419.079426)
		(end 350.033336 -415.019998)
		(width 0.14224)
		(layer "In13.Cu")
		(net "P5E_CPU0_P1_RX_BUF_DN<14>")
	)
	(arc
		(start 351.336864 -413.727392)
		(mid 351.487031 -413.588312)
		(end 351.555558 -413.395414)
		(width 0.14224)
		(layer "In13.Cu")
		(net "P5E_CPU0_P1_RX_BUF_DN<14>")
	)
	(arc
		(start 349.71609 -419.441376)
		(mid 349.771628 -419.41124)
		(end 349.819722 -419.370256)
		(width 0.14224)
		(layer "In13.Cu")
		(net "P5E_CPU0_P1_RX_BUF_DN<14>")
	)
	(arc
		(start 348.464378 -421.67302)
		(mid 348.491997 -421.63178)
		(end 348.501716 -421.583104)
		(width 0.14224)
		(layer "In13.Cu")
		(net "P5E_CPU0_P1_RX_BUF_DN<14>")
	)
	(arc
		(start 342.98001 -424.06697)
		(mid 343.06163 -423.974285)
		(end 343.159588 -423.899076)
		(width 0.14224)
		(layer "In13.Cu")
		(net "P5E_CPU0_P1_RX_BUF_DN<14>")
	)
	(arc
		(start 342.688926 -424.699684)
		(mid 342.72336 -424.480893)
		(end 342.823546 -424.283378)
		(width 0.14224)
		(layer "In13.Cu")
		(net "P5E_CPU0_P1_RX_BUF_DN<14>")
	)
	(arc
		(start 349.987362 -419.194234)
		(mid 350.021409 -419.14126)
		(end 350.033336 -419.079426)
		(width 0.14224)
		(layer "In13.Cu")
		(net "P5E_CPU0_P1_RX_BUF_DN<14>")
	)
	(arc
		(start 348.501716 -420.228014)
		(mid 348.573067 -419.992456)
		(end 348.763336 -419.836346)
		(width 0.14224)
		(layer "In13.Cu")
		(net "P5E_CPU0_P1_RX_BUF_DN<14>")
	)
	(arc
		(start 350.033336 -415.019998)
		(mid 350.082114 -414.7005)
		(end 350.22409 -414.410144)
		(width 0.14224)
		(layer "In13.Cu")
		(net "P5E_CPU0_P1_RX_BUF_DN<14>")
	)
	(arc
		(start 350.22409 -414.410144)
		(mid 350.308721 -414.313772)
		(end 350.413066 -414.239202)
		(width 0.14224)
		(layer "In13.Cu")
		(net "P5E_CPU0_P1_RX_BUF_DN<14>")
	)
	(arc
		(start 352.31959 -405.63546)
		(mid 352.382229 -404.786601)
		(end 352.403156 -403.935692)
		(width 0.14224)
		(layer "In13.Cu")
		(net "P5E_CPU0_P1_RX_BUF_DN<14>")
	)
	(segment
		(start 351.465896 -401.016216)
		(end 351.592896 -401.143216)
		(width 0.1016)
		(layer "F.Cu")
		(net "P5E_CPU0_P1_RX_BUF_DN<13>")
	)
	(segment
		(start 351.545906 -399.960338)
		(end 351.465896 -400.040348)
		(width 0.1016)
		(layer "F.Cu")
		(net "P5E_CPU0_P1_RX_BUF_DN<13>")
	)
	(segment
		(start 351.803208 -401.143216)
		(end 351.943924 -401.0025)
		(width 0.1016)
		(layer "F.Cu")
		(net "P5E_CPU0_P1_RX_BUF_DN<13>")
	)
	(segment
		(start 351.545398 -399.143474)
		(end 351.545906 -399.143982)
		(width 0.1016)
		(layer "F.Cu")
		(net "P5E_CPU0_P1_RX_BUF_DN<13>")
	)
	(segment
		(start 351.943924 -401.0025)
		(end 351.943924 -400.811238)
		(width 0.1016)
		(layer "F.Cu")
		(net "P5E_CPU0_P1_RX_BUF_DN<13>")
	)
	(segment
		(start 351.545906 -399.143982)
		(end 351.545906 -399.960338)
		(width 0.1016)
		(layer "F.Cu")
		(net "P5E_CPU0_P1_RX_BUF_DN<13>")
	)
	(segment
		(start 351.592896 -401.143216)
		(end 351.803208 -401.143216)
		(width 0.1016)
		(layer "F.Cu")
		(net "P5E_CPU0_P1_RX_BUF_DN<13>")
	)
	(segment
		(start 351.465896 -400.040348)
		(end 351.465896 -401.016216)
		(width 0.1016)
		(layer "F.Cu")
		(net "P5E_CPU0_P1_RX_BUF_DN<13>")
	)
	(segment
		(start 348.519496 -412.110682)
		(end 349.084138 -409.2702)
		(width 0.14224)
		(layer "In13.Cu")
		(net "P5E_CPU0_P1_RX_BUF_DN<13>")
	)
	(segment
		(start 350.622108 -404.936452)
		(end 350.700086 -404.717758)
		(width 0.14224)
		(layer "In13.Cu")
		(net "P5E_CPU0_P1_RX_BUF_DN<13>")
	)
	(segment
		(start 351.805494 -401.117816)
		(end 351.943924 -400.979386)
		(width 0.14224)
		(layer "In13.Cu")
		(net "P5E_CPU0_P1_RX_BUF_DN<13>")
	)
	(segment
		(start 351.943924 -400.979386)
		(end 351.943924 -400.811238)
		(width 0.14224)
		(layer "In13.Cu")
		(net "P5E_CPU0_P1_RX_BUF_DN<13>")
	)
	(segment
		(start 345.240864 -421.741092)
		(end 345.401138 -421.580818)
		(width 0.14224)
		(layer "In13.Cu")
		(net "P5E_CPU0_P1_RX_BUF_DN<13>")
	)
	(segment
		(start 347.985334 -413.90316)
		(end 348.254574 -413.723328)
		(width 0.14224)
		(layer "In13.Cu")
		(net "P5E_CPU0_P1_RX_BUF_DN<13>")
	)
	(segment
		(start 341.649812 -435.489858)
		(end 341.649812 -435.15788)
		(width 0.14224)
		(layer "In13.Cu")
		(net "P5E_CPU0_P1_RX_BUF_DN<13>")
	)
	(segment
		(start 345.700096 -419.836346)
		(end 346.65285 -419.441376)
		(width 0.14224)
		(layer "In13.Cu")
		(net "P5E_CPU0_P1_RX_BUF_DN<13>")
	)
	(segment
		(start 346.756482 -419.370256)
		(end 346.924122 -419.194234)
		(width 0.14224)
		(layer "In13.Cu")
		(net "P5E_CPU0_P1_RX_BUF_DN<13>")
	)
	(segment
		(start 348.254574 -413.723328)
		(end 348.381828 -413.596074)
		(width 0.14224)
		(layer "In13.Cu")
		(net "P5E_CPU0_P1_RX_BUF_DN<13>")
	)
	(segment
		(start 341.522812 -435.03088)
		(end 341.011002 -435.03088)
		(width 0.14224)
		(layer "In13.Cu")
		(net "P5E_CPU0_P1_RX_BUF_DN<13>")
	)
	(segment
		(start 351.203006 -401.425156)
		(end 351.510346 -401.117816)
		(width 0.14224)
		(layer "In13.Cu")
		(net "P5E_CPU0_P1_RX_BUF_DN<13>")
	)
	(segment
		(start 344.155014 -422.293796)
		(end 344.833448 -422.013126)
		(width 0.14224)
		(layer "In13.Cu")
		(net "P5E_CPU0_P1_RX_BUF_DN<13>")
	)
	(segment
		(start 340.68893 -434.708808)
		(end 340.68893 -424.629072)
		(width 0.14224)
		(layer "In13.Cu")
		(net "P5E_CPU0_P1_RX_BUF_DN<13>")
	)
	(segment
		(start 340.762082 -424.351704)
		(end 340.955122 -424.029632)
		(width 0.14224)
		(layer "In13.Cu")
		(net "P5E_CPU0_P1_RX_BUF_DN<13>")
	)
	(segment
		(start 349.129096 -409.108148)
		(end 350.621854 -404.936452)
		(width 0.14224)
		(layer "In13.Cu")
		(net "P5E_CPU0_P1_RX_BUF_DN<13>")
	)
	(segment
		(start 341.180928 -423.795698)
		(end 342.73363 -422.965372)
		(width 0.14224)
		(layer "In13.Cu")
		(net "P5E_CPU0_P1_RX_BUF_DN<13>")
	)
	(segment
		(start 351.203006 -403.849078)
		(end 351.203006 -401.425156)
		(width 0.14224)
		(layer "In13.Cu")
		(net "P5E_CPU0_P1_RX_BUF_DN<13>")
	)
	(segment
		(start 348.501716 -413.306514)
		(end 348.501716 -412.291276)
		(width 0.14224)
		(layer "In13.Cu")
		(net "P5E_CPU0_P1_RX_BUF_DN<13>")
	)
	(segment
		(start 350.87941 -404.435056)
		(end 351.017332 -404.297134)
		(width 0.14224)
		(layer "In13.Cu")
		(net "P5E_CPU0_P1_RX_BUF_DN<13>")
	)
	(segment
		(start 345.438476 -421.490902)
		(end 345.438476 -420.228014)
		(width 0.14224)
		(layer "In13.Cu")
		(net "P5E_CPU0_P1_RX_BUF_DN<13>")
	)
	(segment
		(start 340.955122 -424.029632)
		(end 340.981792 -423.985182)
		(width 0.14224)
		(layer "In13.Cu")
		(net "P5E_CPU0_P1_RX_BUF_DN<13>")
	)
	(segment
		(start 351.510346 -401.117816)
		(end 351.805494 -401.117816)
		(width 0.14224)
		(layer "In13.Cu")
		(net "P5E_CPU0_P1_RX_BUF_DN<13>")
	)
	(segment
		(start 347.735398 -414.006538)
		(end 347.985334 -413.90316)
		(width 0.14224)
		(layer "In13.Cu")
		(net "P5E_CPU0_P1_RX_BUF_DN<13>")
	)
	(segment
		(start 346.970096 -419.079426)
		(end 346.970096 -415.020252)
		(width 0.14224)
		(layer "In13.Cu")
		(net "P5E_CPU0_P1_RX_BUF_DN<13>")
	)
	(segment
		(start 341.011002 -435.03088)
		(end 340.68893 -434.708808)
		(width 0.14224)
		(layer "In13.Cu")
		(net "P5E_CPU0_P1_RX_BUF_DN<13>")
	)
	(segment
		(start 341.649812 -435.15788)
		(end 341.522812 -435.03088)
		(width 0.14224)
		(layer "In13.Cu")
		(net "P5E_CPU0_P1_RX_BUF_DN<13>")
	)
	(segment
		(start 350.621854 -404.936452)
		(end 350.622108 -404.936452)
		(width 0.14224)
		(layer "In13.Cu")
		(net "P5E_CPU0_P1_RX_BUF_DN<13>")
	)
	(arc
		(start 347.257624 -414.32607)
		(mid 347.480789 -414.142796)
		(end 347.735398 -414.006538)
		(width 0.14224)
		(layer "In13.Cu")
		(net "P5E_CPU0_P1_RX_BUF_DN<13>")
	)
	(arc
		(start 349.084138 -409.2702)
		(mid 349.103616 -409.188341)
		(end 349.129096 -409.108148)
		(width 0.14224)
		(layer "In13.Cu")
		(net "P5E_CPU0_P1_RX_BUF_DN<13>")
	)
	(arc
		(start 348.501716 -412.291276)
		(mid 348.506168 -412.200542)
		(end 348.519496 -412.110682)
		(width 0.14224)
		(layer "In13.Cu")
		(net "P5E_CPU0_P1_RX_BUF_DN<13>")
	)
	(arc
		(start 340.981792 -423.985182)
		(mid 341.068535 -423.876963)
		(end 341.180928 -423.795698)
		(width 0.14224)
		(layer "In13.Cu")
		(net "P5E_CPU0_P1_RX_BUF_DN<13>")
	)
	(arc
		(start 342.73363 -422.965372)
		(mid 343.436066 -422.612111)
		(end 344.155014 -422.293796)
		(width 0.14224)
		(layer "In13.Cu")
		(net "P5E_CPU0_P1_RX_BUF_DN<13>")
	)
	(arc
		(start 350.700086 -404.717758)
		(mid 350.774057 -404.566452)
		(end 350.87941 -404.435056)
		(width 0.14224)
		(layer "In13.Cu")
		(net "P5E_CPU0_P1_RX_BUF_DN<13>")
	)
	(arc
		(start 346.924122 -419.194234)
		(mid 346.958169 -419.14126)
		(end 346.970096 -419.079426)
		(width 0.14224)
		(layer "In13.Cu")
		(net "P5E_CPU0_P1_RX_BUF_DN<13>")
	)
	(arc
		(start 344.833448 -422.013126)
		(mid 345.050562 -421.897186)
		(end 345.240864 -421.741092)
		(width 0.14224)
		(layer "In13.Cu")
		(net "P5E_CPU0_P1_RX_BUF_DN<13>")
	)
	(arc
		(start 345.401138 -421.580818)
		(mid 345.428757 -421.539578)
		(end 345.438476 -421.490902)
		(width 0.14224)
		(layer "In13.Cu")
		(net "P5E_CPU0_P1_RX_BUF_DN<13>")
	)
	(arc
		(start 348.381828 -413.596074)
		(mid 348.470543 -413.463209)
		(end 348.501716 -413.306514)
		(width 0.14224)
		(layer "In13.Cu")
		(net "P5E_CPU0_P1_RX_BUF_DN<13>")
	)
	(arc
		(start 346.970096 -415.020252)
		(mid 347.044786 -414.644557)
		(end 347.257624 -414.32607)
		(width 0.14224)
		(layer "In13.Cu")
		(net "P5E_CPU0_P1_RX_BUF_DN<13>")
	)
	(arc
		(start 340.68893 -424.629072)
		(mid 340.70752 -424.485643)
		(end 340.762082 -424.351704)
		(width 0.14224)
		(layer "In13.Cu")
		(net "P5E_CPU0_P1_RX_BUF_DN<13>")
	)
	(arc
		(start 345.438476 -420.228014)
		(mid 345.509827 -419.992456)
		(end 345.700096 -419.836346)
		(width 0.14224)
		(layer "In13.Cu")
		(net "P5E_CPU0_P1_RX_BUF_DN<13>")
	)
	(arc
		(start 351.017332 -404.297134)
		(mid 351.154743 -404.091578)
		(end 351.203006 -403.849078)
		(width 0.14224)
		(layer "In13.Cu")
		(net "P5E_CPU0_P1_RX_BUF_DN<13>")
	)
	(arc
		(start 346.65285 -419.441376)
		(mid 346.708388 -419.41124)
		(end 346.756482 -419.370256)
		(width 0.14224)
		(layer "In13.Cu")
		(net "P5E_CPU0_P1_RX_BUF_DN<13>")
	)
	(segment
		(start 350.384364 -401.143216)
		(end 350.257364 -401.016216)
		(width 0.1016)
		(layer "F.Cu")
		(net "P5E_CPU0_P1_RX_BUF_DN<12>")
	)
	(segment
		(start 350.34601 -399.143982)
		(end 350.345502 -399.143474)
		(width 0.1016)
		(layer "F.Cu")
		(net "P5E_CPU0_P1_RX_BUF_DN<12>")
	)
	(segment
		(start 350.744028 -400.977862)
		(end 350.578674 -401.143216)
		(width 0.1016)
		(layer "F.Cu")
		(net "P5E_CPU0_P1_RX_BUF_DN<12>")
	)
	(segment
		(start 350.744028 -400.811238)
		(end 350.744028 -400.977862)
		(width 0.1016)
		(layer "F.Cu")
		(net "P5E_CPU0_P1_RX_BUF_DN<12>")
	)
	(segment
		(start 350.257364 -400.048984)
		(end 350.34601 -399.960338)
		(width 0.1016)
		(layer "F.Cu")
		(net "P5E_CPU0_P1_RX_BUF_DN<12>")
	)
	(segment
		(start 350.34601 -399.960338)
		(end 350.34601 -399.143982)
		(width 0.1016)
		(layer "F.Cu")
		(net "P5E_CPU0_P1_RX_BUF_DN<12>")
	)
	(segment
		(start 350.257364 -401.016216)
		(end 350.257364 -400.048984)
		(width 0.1016)
		(layer "F.Cu")
		(net "P5E_CPU0_P1_RX_BUF_DN<12>")
	)
	(segment
		(start 350.578674 -401.143216)
		(end 350.384364 -401.143216)
		(width 0.1016)
		(layer "F.Cu")
		(net "P5E_CPU0_P1_RX_BUF_DN<12>")
	)
	(segment
		(start 347.491812 -408.375866)
		(end 347.491558 -408.375866)
		(width 0.14224)
		(layer "In13.Cu")
		(net "P5E_CPU0_P1_RX_BUF_DN<12>")
	)
	(segment
		(start 342.337898 -421.668702)
		(end 342.168226 -421.838374)
		(width 0.14224)
		(layer "In13.Cu")
		(net "P5E_CPU0_P1_RX_BUF_DN<12>")
	)
	(segment
		(start 345.318588 -413.596074)
		(end 345.191334 -413.723328)
		(width 0.14224)
		(layer "In13.Cu")
		(net "P5E_CPU0_P1_RX_BUF_DN<12>")
	)
	(segment
		(start 339.522816 -434.030882)
		(end 339.649816 -434.157882)
		(width 0.14224)
		(layer "In13.Cu")
		(net "P5E_CPU0_P1_RX_BUF_DN<12>")
	)
	(segment
		(start 338.984336 -423.95648)
		(end 338.918042 -424.033188)
		(width 0.14224)
		(layer "In13.Cu")
		(net "P5E_CPU0_P1_RX_BUF_DN<12>")
	)
	(segment
		(start 345.438476 -412.401004)
		(end 345.438476 -413.306514)
		(width 0.14224)
		(layer "In13.Cu")
		(net "P5E_CPU0_P1_RX_BUF_DN<12>")
	)
	(segment
		(start 343.906856 -415.020252)
		(end 343.906856 -419.079426)
		(width 0.14224)
		(layer "In13.Cu")
		(net "P5E_CPU0_P1_RX_BUF_DN<12>")
	)
	(segment
		(start 347.491558 -408.37612)
		(end 345.592654 -411.544262)
		(width 0.14224)
		(layer "In13.Cu")
		(net "P5E_CPU0_P1_RX_BUF_DN<12>")
	)
	(segment
		(start 345.513406 -411.769814)
		(end 345.449652 -412.23692)
		(width 0.14224)
		(layer "In13.Cu")
		(net "P5E_CPU0_P1_RX_BUF_DN<12>")
	)
	(segment
		(start 342.375236 -420.22776)
		(end 342.375236 -421.578532)
		(width 0.14224)
		(layer "In13.Cu")
		(net "P5E_CPU0_P1_RX_BUF_DN<12>")
	)
	(segment
		(start 345.191334 -413.723328)
		(end 344.922094 -413.90316)
		(width 0.14224)
		(layer "In13.Cu")
		(net "P5E_CPU0_P1_RX_BUF_DN<12>")
	)
	(segment
		(start 338.688934 -433.55641)
		(end 338.68868 -433.55641)
		(width 0.14224)
		(layer "In13.Cu")
		(net "P5E_CPU0_P1_RX_BUF_DN<12>")
	)
	(segment
		(start 339.649816 -434.157882)
		(end 339.649816 -434.48986)
		(width 0.14224)
		(layer "In13.Cu")
		(net "P5E_CPU0_P1_RX_BUF_DN<12>")
	)
	(segment
		(start 339.163406 -434.030882)
		(end 339.522816 -434.030882)
		(width 0.14224)
		(layer "In13.Cu")
		(net "P5E_CPU0_P1_RX_BUF_DN<12>")
	)
	(segment
		(start 350.00311 -403.709124)
		(end 349.735394 -404.557484)
		(width 0.14224)
		(layer "In13.Cu")
		(net "P5E_CPU0_P1_RX_BUF_DN<12>")
	)
	(segment
		(start 343.588594 -419.442138)
		(end 342.636856 -419.836346)
		(width 0.14224)
		(layer "In13.Cu")
		(net "P5E_CPU0_P1_RX_BUF_DN<12>")
	)
	(segment
		(start 338.918042 -424.033188)
		(end 338.804758 -424.27398)
		(width 0.14224)
		(layer "In13.Cu")
		(net "P5E_CPU0_P1_RX_BUF_DN<12>")
	)
	(segment
		(start 350.744028 -400.979386)
		(end 350.605598 -401.117816)
		(width 0.14224)
		(layer "In13.Cu")
		(net "P5E_CPU0_P1_RX_BUF_DN<12>")
	)
	(segment
		(start 340.884256 -422.692322)
		(end 340.884002 -422.692322)
		(width 0.14224)
		(layer "In13.Cu")
		(net "P5E_CPU0_P1_RX_BUF_DN<12>")
	)
	(segment
		(start 347.491558 -408.375866)
		(end 347.491558 -408.37612)
		(width 0.14224)
		(layer "In13.Cu")
		(net "P5E_CPU0_P1_RX_BUF_DN<12>")
	)
	(segment
		(start 349.735394 -404.557484)
		(end 349.595948 -404.867364)
		(width 0.14224)
		(layer "In13.Cu")
		(net "P5E_CPU0_P1_RX_BUF_DN<12>")
	)
	(segment
		(start 350.00311 -401.425156)
		(end 350.00311 -403.709124)
		(width 0.14224)
		(layer "In13.Cu")
		(net "P5E_CPU0_P1_RX_BUF_DN<12>")
	)
	(segment
		(start 338.688934 -424.791632)
		(end 338.688934 -433.55641)
		(width 0.14224)
		(layer "In13.Cu")
		(net "P5E_CPU0_P1_RX_BUF_DN<12>")
	)
	(segment
		(start 344.922094 -413.90316)
		(end 344.672158 -414.006538)
		(width 0.14224)
		(layer "In13.Cu")
		(net "P5E_CPU0_P1_RX_BUF_DN<12>")
	)
	(segment
		(start 342.168226 -421.838374)
		(end 340.884256 -422.692322)
		(width 0.14224)
		(layer "In13.Cu")
		(net "P5E_CPU0_P1_RX_BUF_DN<12>")
	)
	(segment
		(start 350.31045 -401.117816)
		(end 350.00311 -401.425156)
		(width 0.14224)
		(layer "In13.Cu")
		(net "P5E_CPU0_P1_RX_BUF_DN<12>")
	)
	(segment
		(start 349.595948 -404.867364)
		(end 347.491812 -408.375866)
		(width 0.14224)
		(layer "In13.Cu")
		(net "P5E_CPU0_P1_RX_BUF_DN<12>")
	)
	(segment
		(start 339.944964 -423.317162)
		(end 338.984336 -423.95648)
		(width 0.14224)
		(layer "In13.Cu")
		(net "P5E_CPU0_P1_RX_BUF_DN<12>")
	)
	(segment
		(start 339.945218 -423.317162)
		(end 339.944964 -423.317162)
		(width 0.14224)
		(layer "In13.Cu")
		(net "P5E_CPU0_P1_RX_BUF_DN<12>")
	)
	(segment
		(start 343.860882 -419.194234)
		(end 343.693242 -419.370256)
		(width 0.14224)
		(layer "In13.Cu")
		(net "P5E_CPU0_P1_RX_BUF_DN<12>")
	)
	(segment
		(start 340.884002 -422.692322)
		(end 339.945218 -423.317162)
		(width 0.14224)
		(layer "In13.Cu")
		(net "P5E_CPU0_P1_RX_BUF_DN<12>")
	)
	(segment
		(start 350.744028 -400.811238)
		(end 350.744028 -400.979386)
		(width 0.14224)
		(layer "In13.Cu")
		(net "P5E_CPU0_P1_RX_BUF_DN<12>")
	)
	(segment
		(start 350.605598 -401.117816)
		(end 350.31045 -401.117816)
		(width 0.14224)
		(layer "In13.Cu")
		(net "P5E_CPU0_P1_RX_BUF_DN<12>")
	)
	(arc
		(start 344.672158 -414.006538)
		(mid 344.417554 -414.142803)
		(end 344.194384 -414.32607)
		(width 0.14224)
		(layer "In13.Cu")
		(net "P5E_CPU0_P1_RX_BUF_DN<12>")
	)
	(arc
		(start 342.636856 -419.836346)
		(mid 342.446699 -419.992393)
		(end 342.375236 -420.22776)
		(width 0.14224)
		(layer "In13.Cu")
		(net "P5E_CPU0_P1_RX_BUF_DN<12>")
	)
	(arc
		(start 343.693242 -419.370256)
		(mid 343.6447 -419.411708)
		(end 343.588594 -419.442138)
		(width 0.14224)
		(layer "In13.Cu")
		(net "P5E_CPU0_P1_RX_BUF_DN<12>")
	)
	(arc
		(start 345.438476 -413.306514)
		(mid 345.407324 -413.463217)
		(end 345.318588 -413.596074)
		(width 0.14224)
		(layer "In13.Cu")
		(net "P5E_CPU0_P1_RX_BUF_DN<12>")
	)
	(arc
		(start 338.68868 -433.55641)
		(mid 338.827665 -433.892077)
		(end 339.163406 -434.030882)
		(width 0.14224)
		(layer "In13.Cu")
		(net "P5E_CPU0_P1_RX_BUF_DN<12>")
	)
	(arc
		(start 343.906856 -419.079426)
		(mid 343.894937 -419.141263)
		(end 343.860882 -419.194234)
		(width 0.14224)
		(layer "In13.Cu")
		(net "P5E_CPU0_P1_RX_BUF_DN<12>")
	)
	(arc
		(start 344.194384 -414.32607)
		(mid 343.981495 -414.644536)
		(end 343.906856 -415.020252)
		(width 0.14224)
		(layer "In13.Cu")
		(net "P5E_CPU0_P1_RX_BUF_DN<12>")
	)
	(arc
		(start 345.592654 -411.544262)
		(mid 345.541591 -411.653019)
		(end 345.513406 -411.769814)
		(width 0.14224)
		(layer "In13.Cu")
		(net "P5E_CPU0_P1_RX_BUF_DN<12>")
	)
	(arc
		(start 345.449652 -412.23692)
		(mid 345.441287 -412.318773)
		(end 345.438476 -412.401004)
		(width 0.14224)
		(layer "In13.Cu")
		(net "P5E_CPU0_P1_RX_BUF_DN<12>")
	)
	(arc
		(start 342.375236 -421.578532)
		(mid 342.36553 -421.627327)
		(end 342.337898 -421.668702)
		(width 0.14224)
		(layer "In13.Cu")
		(net "P5E_CPU0_P1_RX_BUF_DN<12>")
	)
	(arc
		(start 338.804758 -424.27398)
		(mid 338.718259 -424.526411)
		(end 338.688934 -424.791632)
		(width 0.14224)
		(layer "In13.Cu")
		(net "P5E_CPU0_P1_RX_BUF_DN<12>")
	)
	(segment
		(start 349.14586 -399.143728)
		(end 349.145606 -399.143474)
		(width 0.1016)
		(layer "F.Cu")
		(net "P5E_CPU0_P1_RX_BUF_DN<11>")
	)
	(segment
		(start 349.184214 -401.143216)
		(end 349.057214 -401.016216)
		(width 0.1016)
		(layer "F.Cu")
		(net "P5E_CPU0_P1_RX_BUF_DN<11>")
	)
	(segment
		(start 349.057214 -401.016216)
		(end 349.057214 -400.048984)
		(width 0.1016)
		(layer "F.Cu")
		(net "P5E_CPU0_P1_RX_BUF_DN<11>")
	)
	(segment
		(start 349.544132 -400.811238)
		(end 349.544132 -401.002246)
		(width 0.1016)
		(layer "F.Cu")
		(net "P5E_CPU0_P1_RX_BUF_DN<11>")
	)
	(segment
		(start 349.403162 -401.143216)
		(end 349.184214 -401.143216)
		(width 0.1016)
		(layer "F.Cu")
		(net "P5E_CPU0_P1_RX_BUF_DN<11>")
	)
	(segment
		(start 349.544132 -401.002246)
		(end 349.403162 -401.143216)
		(width 0.1016)
		(layer "F.Cu")
		(net "P5E_CPU0_P1_RX_BUF_DN<11>")
	)
	(segment
		(start 349.057214 -400.048984)
		(end 349.14586 -399.960338)
		(width 0.1016)
		(layer "F.Cu")
		(net "P5E_CPU0_P1_RX_BUF_DN<11>")
	)
	(segment
		(start 349.14586 -399.960338)
		(end 349.14586 -399.143728)
		(width 0.1016)
		(layer "F.Cu")
		(net "P5E_CPU0_P1_RX_BUF_DN<11>")
	)
	(segment
		(start 342.4682 -411.969458)
		(end 342.535002 -411.832806)
		(width 0.14224)
		(layer "In13.Cu")
		(net "P5E_CPU0_P1_RX_BUF_DN<11>")
	)
	(segment
		(start 336.981038 -435.03088)
		(end 336.688938 -434.73878)
		(width 0.14224)
		(layer "In13.Cu")
		(net "P5E_CPU0_P1_RX_BUF_DN<11>")
	)
	(segment
		(start 348.752668 -404.08352)
		(end 348.803214 -403.917404)
		(width 0.14224)
		(layer "In13.Cu")
		(net "P5E_CPU0_P1_RX_BUF_DN<11>")
	)
	(segment
		(start 349.110554 -401.117816)
		(end 349.405702 -401.117816)
		(width 0.14224)
		(layer "In13.Cu")
		(net "P5E_CPU0_P1_RX_BUF_DN<11>")
	)
	(segment
		(start 342.128094 -413.723328)
		(end 342.255348 -413.596074)
		(width 0.14224)
		(layer "In13.Cu")
		(net "P5E_CPU0_P1_RX_BUF_DN<11>")
	)
	(segment
		(start 346.99702 -406.710134)
		(end 348.752668 -404.08352)
		(width 0.14224)
		(layer "In13.Cu")
		(net "P5E_CPU0_P1_RX_BUF_DN<11>")
	)
	(segment
		(start 340.843616 -419.079426)
		(end 340.843616 -415.020252)
		(width 0.14224)
		(layer "In13.Cu")
		(net "P5E_CPU0_P1_RX_BUF_DN<11>")
	)
	(segment
		(start 341.608918 -414.006538)
		(end 341.858854 -413.90316)
		(width 0.14224)
		(layer "In13.Cu")
		(net "P5E_CPU0_P1_RX_BUF_DN<11>")
	)
	(segment
		(start 348.803214 -403.917404)
		(end 348.803214 -401.425156)
		(width 0.14224)
		(layer "In13.Cu")
		(net "P5E_CPU0_P1_RX_BUF_DN<11>")
	)
	(segment
		(start 342.650064 -411.663134)
		(end 346.108782 -407.847038)
		(width 0.14224)
		(layer "In13.Cu")
		(net "P5E_CPU0_P1_RX_BUF_DN<11>")
	)
	(segment
		(start 337.64982 -435.15788)
		(end 337.52282 -435.03088)
		(width 0.14224)
		(layer "In13.Cu")
		(net "P5E_CPU0_P1_RX_BUF_DN<11>")
	)
	(segment
		(start 341.858854 -413.90316)
		(end 342.128094 -413.723328)
		(width 0.14224)
		(layer "In13.Cu")
		(net "P5E_CPU0_P1_RX_BUF_DN<11>")
	)
	(segment
		(start 339.573362 -419.836346)
		(end 340.52637 -419.441376)
		(width 0.14224)
		(layer "In13.Cu")
		(net "P5E_CPU0_P1_RX_BUF_DN<11>")
	)
	(segment
		(start 337.011518 -423.983404)
		(end 337.011264 -423.983404)
		(width 0.14224)
		(layer "In13.Cu")
		(net "P5E_CPU0_P1_RX_BUF_DN<11>")
	)
	(segment
		(start 337.52282 -435.03088)
		(end 336.981038 -435.03088)
		(width 0.14224)
		(layer "In13.Cu")
		(net "P5E_CPU0_P1_RX_BUF_DN<11>")
	)
	(segment
		(start 340.630002 -419.370256)
		(end 340.797642 -419.194234)
		(width 0.14224)
		(layer "In13.Cu")
		(net "P5E_CPU0_P1_RX_BUF_DN<11>")
	)
	(segment
		(start 349.405702 -401.117816)
		(end 349.544132 -400.979386)
		(width 0.14224)
		(layer "In13.Cu")
		(net "P5E_CPU0_P1_RX_BUF_DN<11>")
	)
	(segment
		(start 349.544132 -400.979386)
		(end 349.544132 -400.811238)
		(width 0.14224)
		(layer "In13.Cu")
		(net "P5E_CPU0_P1_RX_BUF_DN<11>")
	)
	(segment
		(start 336.688938 -434.73878)
		(end 336.688938 -424.59021)
		(width 0.14224)
		(layer "In13.Cu")
		(net "P5E_CPU0_P1_RX_BUF_DN<11>")
	)
	(segment
		(start 348.803214 -401.425156)
		(end 349.110554 -401.117816)
		(width 0.14224)
		(layer "In13.Cu")
		(net "P5E_CPU0_P1_RX_BUF_DN<11>")
	)
	(segment
		(start 336.75828 -424.361864)
		(end 337.011518 -423.983404)
		(width 0.14224)
		(layer "In13.Cu")
		(net "P5E_CPU0_P1_RX_BUF_DN<11>")
	)
	(segment
		(start 342.375236 -413.306514)
		(end 342.375236 -412.46933)
		(width 0.14224)
		(layer "In13.Cu")
		(net "P5E_CPU0_P1_RX_BUF_DN<11>")
	)
	(segment
		(start 342.391238 -412.292038)
		(end 342.428576 -412.089346)
		(width 0.14224)
		(layer "In13.Cu")
		(net "P5E_CPU0_P1_RX_BUF_DN<11>")
	)
	(segment
		(start 339.311996 -421.571928)
		(end 339.311996 -420.228268)
		(width 0.14224)
		(layer "In13.Cu")
		(net "P5E_CPU0_P1_RX_BUF_DN<11>")
	)
	(segment
		(start 337.025996 -423.96156)
		(end 339.275674 -421.660828)
		(width 0.14224)
		(layer "In13.Cu")
		(net "P5E_CPU0_P1_RX_BUF_DN<11>")
	)
	(segment
		(start 337.011264 -423.983404)
		(end 337.025996 -423.96156)
		(width 0.14224)
		(layer "In13.Cu")
		(net "P5E_CPU0_P1_RX_BUF_DN<11>")
	)
	(segment
		(start 337.64982 -435.489858)
		(end 337.64982 -435.15788)
		(width 0.14224)
		(layer "In13.Cu")
		(net "P5E_CPU0_P1_RX_BUF_DN<11>")
	)
	(arc
		(start 340.797642 -419.194234)
		(mid 340.831689 -419.14126)
		(end 340.843616 -419.079426)
		(width 0.14224)
		(layer "In13.Cu")
		(net "P5E_CPU0_P1_RX_BUF_DN<11>")
	)
	(arc
		(start 342.255348 -413.596074)
		(mid 342.344063 -413.463209)
		(end 342.375236 -413.306514)
		(width 0.14224)
		(layer "In13.Cu")
		(net "P5E_CPU0_P1_RX_BUF_DN<11>")
	)
	(arc
		(start 336.688938 -424.59021)
		(mid 336.706653 -424.470887)
		(end 336.75828 -424.361864)
		(width 0.14224)
		(layer "In13.Cu")
		(net "P5E_CPU0_P1_RX_BUF_DN<11>")
	)
	(arc
		(start 339.311996 -420.228268)
		(mid 339.383264 -419.992681)
		(end 339.573362 -419.836346)
		(width 0.14224)
		(layer "In13.Cu")
		(net "P5E_CPU0_P1_RX_BUF_DN<11>")
	)
	(arc
		(start 340.52637 -419.441376)
		(mid 340.581908 -419.41124)
		(end 340.630002 -419.370256)
		(width 0.14224)
		(layer "In13.Cu")
		(net "P5E_CPU0_P1_RX_BUF_DN<11>")
	)
	(arc
		(start 342.375236 -412.46933)
		(mid 342.379182 -412.380317)
		(end 342.391238 -412.292038)
		(width 0.14224)
		(layer "In13.Cu")
		(net "P5E_CPU0_P1_RX_BUF_DN<11>")
	)
	(arc
		(start 346.108782 -407.847038)
		(mid 346.573937 -407.295021)
		(end 346.99702 -406.710134)
		(width 0.14224)
		(layer "In13.Cu")
		(net "P5E_CPU0_P1_RX_BUF_DN<11>")
	)
	(arc
		(start 342.428576 -412.089346)
		(mid 342.444303 -412.028052)
		(end 342.4682 -411.969458)
		(width 0.14224)
		(layer "In13.Cu")
		(net "P5E_CPU0_P1_RX_BUF_DN<11>")
	)
	(arc
		(start 339.275674 -421.660828)
		(mid 339.302556 -421.619942)
		(end 339.311996 -421.571928)
		(width 0.14224)
		(layer "In13.Cu")
		(net "P5E_CPU0_P1_RX_BUF_DN<11>")
	)
	(arc
		(start 340.843616 -415.020252)
		(mid 340.918306 -414.644557)
		(end 341.131144 -414.32607)
		(width 0.14224)
		(layer "In13.Cu")
		(net "P5E_CPU0_P1_RX_BUF_DN<11>")
	)
	(arc
		(start 341.131144 -414.32607)
		(mid 341.354309 -414.142796)
		(end 341.608918 -414.006538)
		(width 0.14224)
		(layer "In13.Cu")
		(net "P5E_CPU0_P1_RX_BUF_DN<11>")
	)
	(arc
		(start 342.535002 -411.832806)
		(mid 342.586573 -411.743929)
		(end 342.650064 -411.663134)
		(width 0.14224)
		(layer "In13.Cu")
		(net "P5E_CPU0_P1_RX_BUF_DN<11>")
	)
	(segment
		(start 347.945456 -399.960846)
		(end 347.945456 -399.143474)
		(width 0.1016)
		(layer "F.Cu")
		(net "P5E_CPU0_P1_RX_BUF_DN<10>")
	)
	(segment
		(start 347.857318 -401.016216)
		(end 347.857318 -400.048984)
		(width 0.1016)
		(layer "F.Cu")
		(net "P5E_CPU0_P1_RX_BUF_DN<10>")
	)
	(segment
		(start 347.984318 -401.143216)
		(end 347.857318 -401.016216)
		(width 0.1016)
		(layer "F.Cu")
		(net "P5E_CPU0_P1_RX_BUF_DN<10>")
	)
	(segment
		(start 347.857318 -400.048984)
		(end 347.945456 -399.960846)
		(width 0.1016)
		(layer "F.Cu")
		(net "P5E_CPU0_P1_RX_BUF_DN<10>")
	)
	(segment
		(start 348.344236 -400.811238)
		(end 348.344236 -401.002246)
		(width 0.1016)
		(layer "F.Cu")
		(net "P5E_CPU0_P1_RX_BUF_DN<10>")
	)
	(segment
		(start 348.203266 -401.143216)
		(end 347.984318 -401.143216)
		(width 0.1016)
		(layer "F.Cu")
		(net "P5E_CPU0_P1_RX_BUF_DN<10>")
	)
	(segment
		(start 348.344236 -401.002246)
		(end 348.203266 -401.143216)
		(width 0.1016)
		(layer "F.Cu")
		(net "P5E_CPU0_P1_RX_BUF_DN<10>")
	)
	(segment
		(start 339.362288 -412.251652)
		(end 339.434424 -412.088838)
		(width 0.14224)
		(layer "In13.Cu")
		(net "P5E_CPU0_P1_RX_BUF_DN<10>")
	)
	(segment
		(start 335.522824 -434.030882)
		(end 335.006442 -434.030882)
		(width 0.14224)
		(layer "In13.Cu")
		(net "P5E_CPU0_P1_RX_BUF_DN<10>")
	)
	(segment
		(start 348.344236 -400.979386)
		(end 348.344236 -400.811238)
		(width 0.14224)
		(layer "In13.Cu")
		(net "P5E_CPU0_P1_RX_BUF_DN<10>")
	)
	(segment
		(start 334.688942 -433.713382)
		(end 334.688942 -424.945556)
		(width 0.14224)
		(layer "In13.Cu")
		(net "P5E_CPU0_P1_RX_BUF_DN<10>")
	)
	(segment
		(start 338.545678 -414.006538)
		(end 338.795614 -413.90316)
		(width 0.14224)
		(layer "In13.Cu")
		(net "P5E_CPU0_P1_RX_BUF_DN<10>")
	)
	(segment
		(start 343.028524 -409.344876)
		(end 345.465654 -406.907746)
		(width 0.14224)
		(layer "In13.Cu")
		(net "P5E_CPU0_P1_RX_BUF_DN<10>")
	)
	(segment
		(start 339.311996 -413.306514)
		(end 339.311996 -412.488634)
		(width 0.14224)
		(layer "In13.Cu")
		(net "P5E_CPU0_P1_RX_BUF_DN<10>")
	)
	(segment
		(start 340.337394 -411.233366)
		(end 340.636352 -410.988002)
		(width 0.14224)
		(layer "In13.Cu")
		(net "P5E_CPU0_P1_RX_BUF_DN<10>")
	)
	(segment
		(start 334.790542 -424.515788)
		(end 336.127852 -421.848788)
		(width 0.14224)
		(layer "In13.Cu")
		(net "P5E_CPU0_P1_RX_BUF_DN<10>")
	)
	(segment
		(start 337.780376 -419.079426)
		(end 337.780376 -415.020252)
		(width 0.14224)
		(layer "In13.Cu")
		(net "P5E_CPU0_P1_RX_BUF_DN<10>")
	)
	(segment
		(start 336.510376 -419.836346)
		(end 337.46313 -419.441376)
		(width 0.14224)
		(layer "In13.Cu")
		(net "P5E_CPU0_P1_RX_BUF_DN<10>")
	)
	(segment
		(start 347.910658 -401.117816)
		(end 348.205806 -401.117816)
		(width 0.14224)
		(layer "In13.Cu")
		(net "P5E_CPU0_P1_RX_BUF_DN<10>")
	)
	(segment
		(start 345.465654 -406.907746)
		(end 347.603318 -403.8727)
		(width 0.14224)
		(layer "In13.Cu")
		(net "P5E_CPU0_P1_RX_BUF_DN<10>")
	)
	(segment
		(start 338.795614 -413.90316)
		(end 339.064854 -413.723328)
		(width 0.14224)
		(layer "In13.Cu")
		(net "P5E_CPU0_P1_RX_BUF_DN<10>")
	)
	(segment
		(start 335.649824 -434.48986)
		(end 335.649824 -434.157882)
		(width 0.14224)
		(layer "In13.Cu")
		(net "P5E_CPU0_P1_RX_BUF_DN<10>")
	)
	(segment
		(start 336.127852 -421.848788)
		(end 336.132424 -421.829992)
		(width 0.14224)
		(layer "In13.Cu")
		(net "P5E_CPU0_P1_RX_BUF_DN<10>")
	)
	(segment
		(start 339.064854 -413.723328)
		(end 339.192108 -413.596074)
		(width 0.14224)
		(layer "In13.Cu")
		(net "P5E_CPU0_P1_RX_BUF_DN<10>")
	)
	(segment
		(start 336.132424 -421.829992)
		(end 336.244184 -421.421814)
		(width 0.14224)
		(layer "In13.Cu")
		(net "P5E_CPU0_P1_RX_BUF_DN<10>")
	)
	(segment
		(start 340.75751 -410.897324)
		(end 343.028524 -409.344876)
		(width 0.14224)
		(layer "In13.Cu")
		(net "P5E_CPU0_P1_RX_BUF_DN<10>")
	)
	(segment
		(start 347.603318 -401.425156)
		(end 347.910658 -401.117816)
		(width 0.14224)
		(layer "In13.Cu")
		(net "P5E_CPU0_P1_RX_BUF_DN<10>")
	)
	(segment
		(start 335.649824 -434.157882)
		(end 335.522824 -434.030882)
		(width 0.14224)
		(layer "In13.Cu")
		(net "P5E_CPU0_P1_RX_BUF_DN<10>")
	)
	(segment
		(start 335.006442 -434.030882)
		(end 334.688942 -433.713382)
		(width 0.14224)
		(layer "In13.Cu")
		(net "P5E_CPU0_P1_RX_BUF_DN<10>")
	)
	(segment
		(start 347.603318 -403.8727)
		(end 347.603318 -401.425156)
		(width 0.14224)
		(layer "In13.Cu")
		(net "P5E_CPU0_P1_RX_BUF_DN<10>")
	)
	(segment
		(start 337.566762 -419.370256)
		(end 337.734402 -419.194234)
		(width 0.14224)
		(layer "In13.Cu")
		(net "P5E_CPU0_P1_RX_BUF_DN<10>")
	)
	(segment
		(start 348.205806 -401.117816)
		(end 348.344236 -400.979386)
		(width 0.14224)
		(layer "In13.Cu")
		(net "P5E_CPU0_P1_RX_BUF_DN<10>")
	)
	(segment
		(start 336.248756 -421.388032)
		(end 336.248756 -420.228014)
		(width 0.14224)
		(layer "In13.Cu")
		(net "P5E_CPU0_P1_RX_BUF_DN<10>")
	)
	(arc
		(start 340.636352 -410.988002)
		(mid 340.69594 -410.941339)
		(end 340.75751 -410.897324)
		(width 0.14224)
		(layer "In13.Cu")
		(net "P5E_CPU0_P1_RX_BUF_DN<10>")
	)
	(arc
		(start 337.734402 -419.194234)
		(mid 337.768449 -419.14126)
		(end 337.780376 -419.079426)
		(width 0.14224)
		(layer "In13.Cu")
		(net "P5E_CPU0_P1_RX_BUF_DN<10>")
	)
	(arc
		(start 334.688942 -424.945556)
		(mid 334.714563 -424.724717)
		(end 334.790542 -424.515788)
		(width 0.14224)
		(layer "In13.Cu")
		(net "P5E_CPU0_P1_RX_BUF_DN<10>")
	)
	(arc
		(start 339.192108 -413.596074)
		(mid 339.280823 -413.463209)
		(end 339.311996 -413.306514)
		(width 0.14224)
		(layer "In13.Cu")
		(net "P5E_CPU0_P1_RX_BUF_DN<10>")
	)
	(arc
		(start 336.244184 -421.421814)
		(mid 336.24759 -421.405075)
		(end 336.248756 -421.388032)
		(width 0.14224)
		(layer "In13.Cu")
		(net "P5E_CPU0_P1_RX_BUF_DN<10>")
	)
	(arc
		(start 337.46313 -419.441376)
		(mid 337.518668 -419.41124)
		(end 337.566762 -419.370256)
		(width 0.14224)
		(layer "In13.Cu")
		(net "P5E_CPU0_P1_RX_BUF_DN<10>")
	)
	(arc
		(start 339.434424 -412.088838)
		(mid 339.495084 -411.983067)
		(end 339.576156 -411.891988)
		(width 0.14224)
		(layer "In13.Cu")
		(net "P5E_CPU0_P1_RX_BUF_DN<10>")
	)
	(arc
		(start 338.067904 -414.32607)
		(mid 338.291069 -414.142796)
		(end 338.545678 -414.006538)
		(width 0.14224)
		(layer "In13.Cu")
		(net "P5E_CPU0_P1_RX_BUF_DN<10>")
	)
	(arc
		(start 337.780376 -415.020252)
		(mid 337.855066 -414.644557)
		(end 338.067904 -414.32607)
		(width 0.14224)
		(layer "In13.Cu")
		(net "P5E_CPU0_P1_RX_BUF_DN<10>")
	)
	(arc
		(start 340.0171 -411.501844)
		(mid 340.176536 -411.366756)
		(end 340.337394 -411.233366)
		(width 0.14224)
		(layer "In13.Cu")
		(net "P5E_CPU0_P1_RX_BUF_DN<10>")
	)
	(arc
		(start 339.311996 -412.488634)
		(mid 339.324733 -412.367509)
		(end 339.362288 -412.251652)
		(width 0.14224)
		(layer "In13.Cu")
		(net "P5E_CPU0_P1_RX_BUF_DN<10>")
	)
	(arc
		(start 336.248756 -420.228014)
		(mid 336.320107 -419.992456)
		(end 336.510376 -419.836346)
		(width 0.14224)
		(layer "In13.Cu")
		(net "P5E_CPU0_P1_RX_BUF_DN<10>")
	)
	(arc
		(start 339.576156 -411.891988)
		(mid 339.795105 -411.695194)
		(end 340.0171 -411.501844)
		(width 0.14224)
		(layer "In13.Cu")
		(net "P5E_CPU0_P1_RX_BUF_DN<10>")
	)
	(segment
		(start 335.94548 -399.143474)
		(end 335.945988 -399.143982)
		(width 0.1016)
		(layer "F.Cu")
		(net "P5E_CPU0_P1_RX_BUF_DN<0>")
	)
	(segment
		(start 335.83499 -400.993864)
		(end 335.984342 -401.143216)
		(width 0.1016)
		(layer "F.Cu")
		(net "P5E_CPU0_P1_RX_BUF_DN<0>")
	)
	(segment
		(start 335.984342 -401.143216)
		(end 336.20329 -401.143216)
		(width 0.1016)
		(layer "F.Cu")
		(net "P5E_CPU0_P1_RX_BUF_DN<0>")
	)
	(segment
		(start 336.344006 -401.0025)
		(end 336.344006 -400.811238)
		(width 0.1016)
		(layer "F.Cu")
		(net "P5E_CPU0_P1_RX_BUF_DN<0>")
	)
	(segment
		(start 335.945988 -399.960338)
		(end 335.83499 -400.071336)
		(width 0.1016)
		(layer "F.Cu")
		(net "P5E_CPU0_P1_RX_BUF_DN<0>")
	)
	(segment
		(start 335.83499 -400.071336)
		(end 335.83499 -400.993864)
		(width 0.1016)
		(layer "F.Cu")
		(net "P5E_CPU0_P1_RX_BUF_DN<0>")
	)
	(segment
		(start 335.945988 -399.143982)
		(end 335.945988 -399.960338)
		(width 0.1016)
		(layer "F.Cu")
		(net "P5E_CPU0_P1_RX_BUF_DN<0>")
	)
	(segment
		(start 336.20329 -401.143216)
		(end 336.344006 -401.0025)
		(width 0.1016)
		(layer "F.Cu")
		(net "P5E_CPU0_P1_RX_BUF_DN<0>")
	)
	(segment
		(start 308.163214 -413.90316)
		(end 308.432454 -413.723328)
		(width 0.14224)
		(layer "In13.Cu")
		(net "P5E_CPU0_P1_RX_BUF_DN<0>")
	)
	(segment
		(start 333.680816 -402.013928)
		(end 334.321404 -401.627086)
		(width 0.14224)
		(layer "In13.Cu")
		(net "P5E_CPU0_P1_RX_BUF_DN<0>")
	)
	(segment
		(start 307.147976 -419.103302)
		(end 307.147976 -415.020252)
		(width 0.14224)
		(layer "In13.Cu")
		(net "P5E_CPU0_P1_RX_BUF_DN<0>")
	)
	(segment
		(start 336.053176 -401.102068)
		(end 336.344006 -400.811238)
		(width 0.14224)
		(layer "In13.Cu")
		(net "P5E_CPU0_P1_RX_BUF_DN<0>")
	)
	(segment
		(start 308.679596 -413.306514)
		(end 308.679596 -412.443676)
		(width 0.14224)
		(layer "In13.Cu")
		(net "P5E_CPU0_P1_RX_BUF_DN<0>")
	)
	(segment
		(start 313.831224 -433.865528)
		(end 305.737514 -422.95191)
		(width 0.14224)
		(layer "In13.Cu")
		(net "P5E_CPU0_P1_RX_BUF_DN<0>")
	)
	(segment
		(start 308.725824 -412.212536)
		(end 308.851046 -411.911038)
		(width 0.14224)
		(layer "In13.Cu")
		(net "P5E_CPU0_P1_RX_BUF_DN<0>")
	)
	(segment
		(start 309.573422 -411.256734)
		(end 316.465204 -408.141424)
		(width 0.14224)
		(layer "In13.Cu")
		(net "P5E_CPU0_P1_RX_BUF_DN<0>")
	)
	(segment
		(start 314.649612 -434.48986)
		(end 314.649612 -434.157882)
		(width 0.14224)
		(layer "In13.Cu")
		(net "P5E_CPU0_P1_RX_BUF_DN<0>")
	)
	(segment
		(start 307.913278 -414.006538)
		(end 308.163214 -413.90316)
		(width 0.14224)
		(layer "In13.Cu")
		(net "P5E_CPU0_P1_RX_BUF_DN<0>")
	)
	(segment
		(start 314.649612 -434.157882)
		(end 314.522612 -434.030882)
		(width 0.14224)
		(layer "In13.Cu")
		(net "P5E_CPU0_P1_RX_BUF_DN<0>")
	)
	(segment
		(start 329.06843 -403.681946)
		(end 333.680816 -402.013928)
		(width 0.14224)
		(layer "In13.Cu")
		(net "P5E_CPU0_P1_RX_BUF_DN<0>")
	)
	(segment
		(start 314.522612 -434.030882)
		(end 314.1599 -434.030882)
		(width 0.14224)
		(layer "In13.Cu")
		(net "P5E_CPU0_P1_RX_BUF_DN<0>")
	)
	(segment
		(start 308.432454 -413.723328)
		(end 308.559708 -413.596074)
		(width 0.14224)
		(layer "In13.Cu")
		(net "P5E_CPU0_P1_RX_BUF_DN<0>")
	)
	(segment
		(start 320.797428 -406.381966)
		(end 327.679558 -403.89302)
		(width 0.14224)
		(layer "In13.Cu")
		(net "P5E_CPU0_P1_RX_BUF_DN<0>")
	)
	(segment
		(start 309.002684 -411.703012)
		(end 309.3974 -411.367986)
		(width 0.14224)
		(layer "In13.Cu")
		(net "P5E_CPU0_P1_RX_BUF_DN<0>")
	)
	(segment
		(start 334.321404 -401.627086)
		(end 335.773014 -401.102068)
		(width 0.14224)
		(layer "In13.Cu")
		(net "P5E_CPU0_P1_RX_BUF_DN<0>")
	)
	(segment
		(start 335.773014 -401.102068)
		(end 336.053176 -401.102068)
		(width 0.14224)
		(layer "In13.Cu")
		(net "P5E_CPU0_P1_RX_BUF_DN<0>")
	)
	(segment
		(start 327.679558 -403.89302)
		(end 329.06843 -403.681946)
		(width 0.14224)
		(layer "In13.Cu")
		(net "P5E_CPU0_P1_RX_BUF_DN<0>")
	)
	(segment
		(start 306.41544 -419.607238)
		(end 306.962302 -419.38067)
		(width 0.14224)
		(layer "In13.Cu")
		(net "P5E_CPU0_P1_RX_BUF_DN<0>")
	)
	(segment
		(start 305.868578 -419.83406)
		(end 306.415694 -419.607238)
		(width 0.14224)
		(layer "In13.Cu")
		(net "P5E_CPU0_P1_RX_BUF_DN<0>")
	)
	(segment
		(start 305.616356 -422.585134)
		(end 305.616356 -420.21125)
		(width 0.14224)
		(layer "In13.Cu")
		(net "P5E_CPU0_P1_RX_BUF_DN<0>")
	)
	(segment
		(start 306.415694 -419.607238)
		(end 306.41544 -419.607238)
		(width 0.14224)
		(layer "In13.Cu")
		(net "P5E_CPU0_P1_RX_BUF_DN<0>")
	)
	(segment
		(start 320.797428 -406.381712)
		(end 320.797428 -406.381966)
		(width 0.14224)
		(layer "In13.Cu")
		(net "P5E_CPU0_P1_RX_BUF_DN<0>")
	)
	(arc
		(start 305.616356 -420.21125)
		(mid 305.685294 -419.984435)
		(end 305.868578 -419.83406)
		(width 0.14224)
		(layer "In13.Cu")
		(net "P5E_CPU0_P1_RX_BUF_DN<0>")
	)
	(arc
		(start 309.3974 -411.367986)
		(mid 309.481527 -411.306212)
		(end 309.573422 -411.256734)
		(width 0.14224)
		(layer "In13.Cu")
		(net "P5E_CPU0_P1_RX_BUF_DN<0>")
	)
	(arc
		(start 305.737514 -422.95191)
		(mid 305.64746 -422.778262)
		(end 305.616356 -422.585134)
		(width 0.14224)
		(layer "In13.Cu")
		(net "P5E_CPU0_P1_RX_BUF_DN<0>")
	)
	(arc
		(start 314.1599 -434.030882)
		(mid 313.975926 -433.987223)
		(end 313.831224 -433.865528)
		(width 0.14224)
		(layer "In13.Cu")
		(net "P5E_CPU0_P1_RX_BUF_DN<0>")
	)
	(arc
		(start 307.435504 -414.32607)
		(mid 307.658669 -414.142796)
		(end 307.913278 -414.006538)
		(width 0.14224)
		(layer "In13.Cu")
		(net "P5E_CPU0_P1_RX_BUF_DN<0>")
	)
	(arc
		(start 308.679596 -412.443676)
		(mid 308.691315 -412.325827)
		(end 308.725824 -412.212536)
		(width 0.14224)
		(layer "In13.Cu")
		(net "P5E_CPU0_P1_RX_BUF_DN<0>")
	)
	(arc
		(start 316.465204 -408.141424)
		(mid 318.614244 -407.219538)
		(end 320.797428 -406.381712)
		(width 0.14224)
		(layer "In13.Cu")
		(net "P5E_CPU0_P1_RX_BUF_DN<0>")
	)
	(arc
		(start 308.559708 -413.596074)
		(mid 308.648423 -413.463209)
		(end 308.679596 -413.306514)
		(width 0.14224)
		(layer "In13.Cu")
		(net "P5E_CPU0_P1_RX_BUF_DN<0>")
	)
	(arc
		(start 306.962302 -419.38067)
		(mid 307.097277 -419.270176)
		(end 307.147976 -419.103302)
		(width 0.14224)
		(layer "In13.Cu")
		(net "P5E_CPU0_P1_RX_BUF_DN<0>")
	)
	(arc
		(start 308.851046 -411.911038)
		(mid 308.914498 -411.798008)
		(end 309.002684 -411.703012)
		(width 0.14224)
		(layer "In13.Cu")
		(net "P5E_CPU0_P1_RX_BUF_DN<0>")
	)
	(arc
		(start 307.147976 -415.020252)
		(mid 307.222666 -414.644557)
		(end 307.435504 -414.32607)
		(width 0.14224)
		(layer "In13.Cu")
		(net "P5E_CPU0_P1_RX_BUF_DN<0>")
	)
	(segment
		(start 314.470288 -397.849344)
		(end 314.990988 -397.849344)
		(width 0.127)
		(layer "F.Cu")
		(net "P5E_CPU0_P0_TX_BUF_DP<9>")
	)
	(segment
		(start 331.956156 -416.336734)
		(end 331.956156 -413.11703)
		(width 0.12954)
		(layer "F.Cu")
		(net "P5E_CPU0_P0_TX_BUF_DP<9>")
	)
	(segment
		(start 331.956156 -413.11703)
		(end 332.226666 -412.84652)
		(width 0.12954)
		(layer "F.Cu")
		(net "P5E_CPU0_P0_TX_BUF_DP<9>")
	)
	(segment
		(start 332.252066 -416.632644)
		(end 331.956156 -416.336734)
		(width 0.12954)
		(layer "F.Cu")
		(net "P5E_CPU0_P0_TX_BUF_DP<9>")
	)
	(segment
		(start 319.958466 -407.243534)
		(end 322.095622 -407.778966)
		(width 0.14224)
		(layer "In4.Cu")
		(net "P5E_CPU0_P0_TX_BUF_DP<9>")
	)
	(segment
		(start 325.022718 -408.666696)
		(end 326.87387 -409.332684)
		(width 0.14224)
		(layer "In4.Cu")
		(net "P5E_CPU0_P0_TX_BUF_DP<9>")
	)
	(segment
		(start 314.87618 -397.734536)
		(end 314.696094 -397.734536)
		(width 0.14224)
		(layer "In4.Cu")
		(net "P5E_CPU0_P0_TX_BUF_DP<9>")
	)
	(segment
		(start 329.355196 -410.079698)
		(end 329.437746 -410.255466)
		(width 0.14224)
		(layer "In4.Cu")
		(net "P5E_CPU0_P0_TX_BUF_DP<9>")
	)
	(segment
		(start 314.97778 -399.1102)
		(end 315.25591 -399.781014)
		(width 0.14224)
		(layer "In4.Cu")
		(net "P5E_CPU0_P0_TX_BUF_DP<9>")
	)
	(segment
		(start 315.301884 -400.012154)
		(end 315.301884 -403.807676)
		(width 0.14224)
		(layer "In4.Cu")
		(net "P5E_CPU0_P0_TX_BUF_DP<9>")
	)
	(segment
		(start 330.521056 -410.771594)
		(end 330.71054 -410.731208)
		(width 0.14224)
		(layer "In4.Cu")
		(net "P5E_CPU0_P0_TX_BUF_DP<9>")
	)
	(segment
		(start 329.437746 -410.255466)
		(end 329.800966 -410.386022)
		(width 0.14224)
		(layer "In4.Cu")
		(net "P5E_CPU0_P0_TX_BUF_DP<9>")
	)
	(segment
		(start 314.990988 -397.849344)
		(end 314.87618 -397.734536)
		(width 0.14224)
		(layer "In4.Cu")
		(net "P5E_CPU0_P0_TX_BUF_DP<9>")
	)
	(segment
		(start 331.476858 -411.392116)
		(end 331.822298 -411.752288)
		(width 0.14224)
		(layer "In4.Cu")
		(net "P5E_CPU0_P0_TX_BUF_DP<9>")
	)
	(segment
		(start 327.495662 -409.556458)
		(end 328.816208 -410.031692)
		(width 0.14224)
		(layer "In4.Cu")
		(net "P5E_CPU0_P0_TX_BUF_DP<9>")
	)
	(segment
		(start 314.94349 -398.54886)
		(end 314.94349 -398.939004)
		(width 0.14224)
		(layer "In4.Cu")
		(net "P5E_CPU0_P0_TX_BUF_DP<9>")
	)
	(segment
		(start 318.6811 -406.989534)
		(end 319.958466 -407.243534)
		(width 0.14224)
		(layer "In4.Cu")
		(net "P5E_CPU0_P0_TX_BUF_DP<9>")
	)
	(segment
		(start 331.935836 -412.55569)
		(end 332.226666 -412.84652)
		(width 0.14224)
		(layer "In4.Cu")
		(net "P5E_CPU0_P0_TX_BUF_DP<9>")
	)
	(segment
		(start 331.07503 -411.131512)
		(end 331.075538 -411.131766)
		(width 0.14224)
		(layer "In4.Cu")
		(net "P5E_CPU0_P0_TX_BUF_DP<9>")
	)
	(segment
		(start 314.707778 -398.129252)
		(end 314.813696 -398.23517)
		(width 0.14224)
		(layer "In4.Cu")
		(net "P5E_CPU0_P0_TX_BUF_DP<9>")
	)
	(segment
		(start 331.034644 -410.94152)
		(end 331.07503 -411.131512)
		(width 0.14224)
		(layer "In4.Cu")
		(net "P5E_CPU0_P0_TX_BUF_DP<9>")
	)
	(segment
		(start 327.412858 -409.38069)
		(end 327.495662 -409.556458)
		(width 0.14224)
		(layer "In4.Cu")
		(net "P5E_CPU0_P0_TX_BUF_DP<9>")
	)
	(segment
		(start 330.71054 -410.731208)
		(end 331.034644 -410.94152)
		(width 0.14224)
		(layer "In4.Cu")
		(net "P5E_CPU0_P0_TX_BUF_DP<9>")
	)
	(segment
		(start 315.628528 -404.478236)
		(end 317.518542 -406.36825)
		(width 0.14224)
		(layer "In4.Cu")
		(net "P5E_CPU0_P0_TX_BUF_DP<9>")
	)
	(segment
		(start 314.606686 -397.823944)
		(end 314.606686 -397.885412)
		(width 0.14224)
		(layer "In4.Cu")
		(net "P5E_CPU0_P0_TX_BUF_DP<9>")
	)
	(segment
		(start 322.095622 -407.778966)
		(end 325.022718 -408.666696)
		(width 0.14224)
		(layer "In4.Cu")
		(net "P5E_CPU0_P0_TX_BUF_DP<9>")
	)
	(segment
		(start 314.696094 -397.734536)
		(end 314.606686 -397.823944)
		(width 0.14224)
		(layer "In4.Cu")
		(net "P5E_CPU0_P0_TX_BUF_DP<9>")
	)
	(segment
		(start 328.991722 -409.948888)
		(end 329.355196 -410.079698)
		(width 0.14224)
		(layer "In4.Cu")
		(net "P5E_CPU0_P0_TX_BUF_DP<9>")
	)
	(segment
		(start 328.816208 -410.031692)
		(end 328.991722 -409.948888)
		(width 0.14224)
		(layer "In4.Cu")
		(net "P5E_CPU0_P0_TX_BUF_DP<9>")
	)
	(segment
		(start 330.336398 -410.65196)
		(end 330.521056 -410.771594)
		(width 0.14224)
		(layer "In4.Cu")
		(net "P5E_CPU0_P0_TX_BUF_DP<9>")
	)
	(segment
		(start 326.87387 -409.332684)
		(end 327.049384 -409.250134)
		(width 0.14224)
		(layer "In4.Cu")
		(net "P5E_CPU0_P0_TX_BUF_DP<9>")
	)
	(segment
		(start 331.935836 -412.036006)
		(end 331.935836 -412.55569)
		(width 0.14224)
		(layer "In4.Cu")
		(net "P5E_CPU0_P0_TX_BUF_DP<9>")
	)
	(segment
		(start 327.049384 -409.250134)
		(end 327.412858 -409.38069)
		(width 0.14224)
		(layer "In4.Cu")
		(net "P5E_CPU0_P0_TX_BUF_DP<9>")
	)
	(segment
		(start 331.075538 -411.131766)
		(end 331.476858 -411.392116)
		(width 0.14224)
		(layer "In4.Cu")
		(net "P5E_CPU0_P0_TX_BUF_DP<9>")
	)
	(arc
		(start 314.813696 -398.23517)
		(mid 314.909832 -398.379093)
		(end 314.94349 -398.54886)
		(width 0.14224)
		(layer "In4.Cu")
		(net "P5E_CPU0_P0_TX_BUF_DP<9>")
	)
	(arc
		(start 331.822298 -411.752288)
		(mid 331.906516 -411.88316)
		(end 331.935836 -412.036006)
		(width 0.14224)
		(layer "In4.Cu")
		(net "P5E_CPU0_P0_TX_BUF_DP<9>")
	)
	(arc
		(start 317.518542 -406.36825)
		(mid 318.053726 -406.765154)
		(end 318.6811 -406.989534)
		(width 0.14224)
		(layer "In4.Cu")
		(net "P5E_CPU0_P0_TX_BUF_DP<9>")
	)
	(arc
		(start 314.606686 -397.885412)
		(mid 314.632957 -398.017398)
		(end 314.707778 -398.129252)
		(width 0.14224)
		(layer "In4.Cu")
		(net "P5E_CPU0_P0_TX_BUF_DP<9>")
	)
	(arc
		(start 315.301884 -403.807676)
		(mid 315.305809 -403.871035)
		(end 315.317632 -403.933406)
		(width 0.14224)
		(layer "In4.Cu")
		(net "P5E_CPU0_P0_TX_BUF_DP<9>")
	)
	(arc
		(start 314.94349 -398.939004)
		(mid 314.952187 -399.026296)
		(end 314.97778 -399.1102)
		(width 0.14224)
		(layer "In4.Cu")
		(net "P5E_CPU0_P0_TX_BUF_DP<9>")
	)
	(arc
		(start 329.800966 -410.386022)
		(mid 330.076366 -410.503521)
		(end 330.336398 -410.65196)
		(width 0.14224)
		(layer "In4.Cu")
		(net "P5E_CPU0_P0_TX_BUF_DP<9>")
	)
	(arc
		(start 315.25591 -399.781014)
		(mid 315.29028 -399.89432)
		(end 315.301884 -400.012154)
		(width 0.14224)
		(layer "In4.Cu")
		(net "P5E_CPU0_P0_TX_BUF_DP<9>")
	)
	(arc
		(start 315.317632 -403.933406)
		(mid 315.436457 -404.226721)
		(end 315.628528 -404.478236)
		(width 0.14224)
		(layer "In4.Cu")
		(net "P5E_CPU0_P0_TX_BUF_DP<9>")
	)
	(segment
		(start 313.270392 -397.849344)
		(end 313.791092 -397.849344)
		(width 0.127)
		(layer "F.Cu")
		(net "P5E_CPU0_P0_TX_BUF_DP<8>")
	)
	(segment
		(start 329.188826 -416.632644)
		(end 328.892916 -416.336734)
		(width 0.12954)
		(layer "F.Cu")
		(net "P5E_CPU0_P0_TX_BUF_DP<8>")
	)
	(segment
		(start 328.892916 -416.336734)
		(end 328.892916 -413.11703)
		(width 0.12954)
		(layer "F.Cu")
		(net "P5E_CPU0_P0_TX_BUF_DP<8>")
	)
	(segment
		(start 328.892916 -413.11703)
		(end 329.163426 -412.84652)
		(width 0.12954)
		(layer "F.Cu")
		(net "P5E_CPU0_P0_TX_BUF_DP<8>")
	)
	(segment
		(start 327.28027 -410.646118)
		(end 327.636886 -410.793692)
		(width 0.14224)
		(layer "In4.Cu")
		(net "P5E_CPU0_P0_TX_BUF_DP<8>")
	)
	(segment
		(start 318.39408 -407.885138)
		(end 319.621154 -408.128978)
		(width 0.14224)
		(layer "In4.Cu")
		(net "P5E_CPU0_P0_TX_BUF_DP<8>")
	)
	(segment
		(start 314.12942 -399.980404)
		(end 314.12942 -402.90496)
		(width 0.14224)
		(layer "In4.Cu")
		(net "P5E_CPU0_P0_TX_BUF_DP<8>")
	)
	(segment
		(start 327.636886 -410.793692)
		(end 327.81621 -410.719524)
		(width 0.14224)
		(layer "In4.Cu")
		(net "P5E_CPU0_P0_TX_BUF_DP<8>")
	)
	(segment
		(start 325.24573 -409.803346)
		(end 326.669908 -410.393134)
		(width 0.14224)
		(layer "In4.Cu")
		(net "P5E_CPU0_P0_TX_BUF_DP<8>")
	)
	(segment
		(start 328.247248 -411.046676)
		(end 328.603864 -411.19425)
		(width 0.14224)
		(layer "In4.Cu")
		(net "P5E_CPU0_P0_TX_BUF_DP<8>")
	)
	(segment
		(start 327.206102 -410.46654)
		(end 327.28027 -410.646118)
		(width 0.14224)
		(layer "In4.Cu")
		(net "P5E_CPU0_P0_TX_BUF_DP<8>")
	)
	(segment
		(start 314.26658 -403.46884)
		(end 314.12942 -403.606)
		(width 0.14224)
		(layer "In4.Cu")
		(net "P5E_CPU0_P0_TX_BUF_DP<8>")
	)
	(segment
		(start 322.399406 -408.858974)
		(end 323.7738 -409.276296)
		(width 0.14224)
		(layer "In4.Cu")
		(net "P5E_CPU0_P0_TX_BUF_DP<8>")
	)
	(segment
		(start 328.872596 -412.55569)
		(end 329.163426 -412.84652)
		(width 0.14224)
		(layer "In4.Cu")
		(net "P5E_CPU0_P0_TX_BUF_DP<8>")
	)
	(segment
		(start 314.12942 -403.606)
		(end 314.12942 -404.085298)
		(width 0.14224)
		(layer "In4.Cu")
		(net "P5E_CPU0_P0_TX_BUF_DP<8>")
	)
	(segment
		(start 313.40679 -397.823944)
		(end 313.40679 -397.920972)
		(width 0.14224)
		(layer "In4.Cu")
		(net "P5E_CPU0_P0_TX_BUF_DP<8>")
	)
	(segment
		(start 314.12942 -402.90496)
		(end 314.26658 -403.04212)
		(width 0.14224)
		(layer "In4.Cu")
		(net "P5E_CPU0_P0_TX_BUF_DP<8>")
	)
	(segment
		(start 313.791092 -397.849344)
		(end 313.676284 -397.734536)
		(width 0.14224)
		(layer "In4.Cu")
		(net "P5E_CPU0_P0_TX_BUF_DP<8>")
	)
	(segment
		(start 313.76747 -398.55775)
		(end 313.76747 -398.986502)
		(width 0.14224)
		(layer "In4.Cu")
		(net "P5E_CPU0_P0_TX_BUF_DP<8>")
	)
	(segment
		(start 313.676284 -397.734536)
		(end 313.496198 -397.734536)
		(width 0.14224)
		(layer "In4.Cu")
		(net "P5E_CPU0_P0_TX_BUF_DP<8>")
	)
	(segment
		(start 326.849232 -410.318966)
		(end 327.206102 -410.46654)
		(width 0.14224)
		(layer "In4.Cu")
		(net "P5E_CPU0_P0_TX_BUF_DP<8>")
	)
	(segment
		(start 327.81621 -410.719524)
		(end 328.17308 -410.867098)
		(width 0.14224)
		(layer "In4.Cu")
		(net "P5E_CPU0_P0_TX_BUF_DP<8>")
	)
	(segment
		(start 328.17308 -410.867098)
		(end 328.247248 -411.046676)
		(width 0.14224)
		(layer "In4.Cu")
		(net "P5E_CPU0_P0_TX_BUF_DP<8>")
	)
	(segment
		(start 328.872596 -411.648148)
		(end 328.872596 -412.55569)
		(width 0.14224)
		(layer "In4.Cu")
		(net "P5E_CPU0_P0_TX_BUF_DP<8>")
	)
	(segment
		(start 326.669908 -410.393134)
		(end 326.849232 -410.318966)
		(width 0.14224)
		(layer "In4.Cu")
		(net "P5E_CPU0_P0_TX_BUF_DP<8>")
	)
	(segment
		(start 314.26658 -403.04212)
		(end 314.26658 -403.46884)
		(width 0.14224)
		(layer "In4.Cu")
		(net "P5E_CPU0_P0_TX_BUF_DP<8>")
	)
	(segment
		(start 313.813444 -399.217388)
		(end 314.12942 -399.980404)
		(width 0.14224)
		(layer "In4.Cu")
		(net "P5E_CPU0_P0_TX_BUF_DP<8>")
	)
	(segment
		(start 313.482736 -398.104106)
		(end 313.647582 -398.268698)
		(width 0.14224)
		(layer "In4.Cu")
		(net "P5E_CPU0_P0_TX_BUF_DP<8>")
	)
	(segment
		(start 319.770252 -408.162506)
		(end 320.95821 -408.45994)
		(width 0.14224)
		(layer "In4.Cu")
		(net "P5E_CPU0_P0_TX_BUF_DP<8>")
	)
	(segment
		(start 314.285122 -404.461472)
		(end 316.921388 -407.097738)
		(width 0.14224)
		(layer "In4.Cu")
		(net "P5E_CPU0_P0_TX_BUF_DP<8>")
	)
	(segment
		(start 313.496198 -397.734536)
		(end 313.40679 -397.823944)
		(width 0.14224)
		(layer "In4.Cu")
		(net "P5E_CPU0_P0_TX_BUF_DP<8>")
	)
	(arc
		(start 319.621154 -408.128978)
		(mid 319.695909 -408.144826)
		(end 319.770252 -408.162506)
		(width 0.14224)
		(layer "In4.Cu")
		(net "P5E_CPU0_P0_TX_BUF_DP<8>")
	)
	(arc
		(start 313.40679 -397.920972)
		(mid 313.426526 -398.020103)
		(end 313.482736 -398.104106)
		(width 0.14224)
		(layer "In4.Cu")
		(net "P5E_CPU0_P0_TX_BUF_DP<8>")
	)
	(arc
		(start 313.647582 -398.268698)
		(mid 313.736278 -398.401301)
		(end 313.76747 -398.55775)
		(width 0.14224)
		(layer "In4.Cu")
		(net "P5E_CPU0_P0_TX_BUF_DP<8>")
	)
	(arc
		(start 323.7738 -409.276296)
		(mid 324.516217 -409.521802)
		(end 325.24573 -409.803346)
		(width 0.14224)
		(layer "In4.Cu")
		(net "P5E_CPU0_P0_TX_BUF_DP<8>")
	)
	(arc
		(start 320.95821 -408.45994)
		(mid 321.681274 -408.650549)
		(end 322.399406 -408.858974)
		(width 0.14224)
		(layer "In4.Cu")
		(net "P5E_CPU0_P0_TX_BUF_DP<8>")
	)
	(arc
		(start 314.12942 -404.085298)
		(mid 314.169824 -404.288892)
		(end 314.285122 -404.461472)
		(width 0.14224)
		(layer "In4.Cu")
		(net "P5E_CPU0_P0_TX_BUF_DP<8>")
	)
	(arc
		(start 328.603864 -411.19425)
		(mid 328.761486 -411.308138)
		(end 328.851514 -411.480508)
		(width 0.14224)
		(layer "In4.Cu")
		(net "P5E_CPU0_P0_TX_BUF_DP<8>")
	)
	(arc
		(start 316.921388 -407.097738)
		(mid 317.599345 -407.600646)
		(end 318.39408 -407.885138)
		(width 0.14224)
		(layer "In4.Cu")
		(net "P5E_CPU0_P0_TX_BUF_DP<8>")
	)
	(arc
		(start 328.851514 -411.480508)
		(mid 328.86731 -411.563668)
		(end 328.872596 -411.648148)
		(width 0.14224)
		(layer "In4.Cu")
		(net "P5E_CPU0_P0_TX_BUF_DP<8>")
	)
	(arc
		(start 313.76747 -398.986502)
		(mid 313.779091 -399.10421)
		(end 313.813444 -399.217388)
		(width 0.14224)
		(layer "In4.Cu")
		(net "P5E_CPU0_P0_TX_BUF_DP<8>")
	)
	(segment
		(start 325.829676 -416.336734)
		(end 325.829676 -413.11703)
		(width 0.12954)
		(layer "F.Cu")
		(net "P5E_CPU0_P0_TX_BUF_DP<7>")
	)
	(segment
		(start 326.125586 -416.632644)
		(end 325.829676 -416.336734)
		(width 0.12954)
		(layer "F.Cu")
		(net "P5E_CPU0_P0_TX_BUF_DP<7>")
	)
	(segment
		(start 325.829676 -413.11703)
		(end 326.100186 -412.84652)
		(width 0.12954)
		(layer "F.Cu")
		(net "P5E_CPU0_P0_TX_BUF_DP<7>")
	)
	(segment
		(start 312.070242 -397.849344)
		(end 312.590942 -397.849344)
		(width 0.127)
		(layer "F.Cu")
		(net "P5E_CPU0_P0_TX_BUF_DP<7>")
	)
	(segment
		(start 325.87184 -412.618174)
		(end 326.100186 -412.84652)
		(width 0.14224)
		(layer "In4.Cu")
		(net "P5E_CPU0_P0_TX_BUF_DP<7>")
	)
	(segment
		(start 312.264044 -398.05737)
		(end 312.415174 -398.2085)
		(width 0.14224)
		(layer "In4.Cu")
		(net "P5E_CPU0_P0_TX_BUF_DP<7>")
	)
	(segment
		(start 312.199782 -397.844264)
		(end 312.199782 -397.902176)
		(width 0.14224)
		(layer "In4.Cu")
		(net "P5E_CPU0_P0_TX_BUF_DP<7>")
	)
	(segment
		(start 325.824596 -411.621986)
		(end 325.824596 -412.504128)
		(width 0.14224)
		(layer "In4.Cu")
		(net "P5E_CPU0_P0_TX_BUF_DP<7>")
	)
	(segment
		(start 322.849748 -410.031692)
		(end 322.938902 -410.204412)
		(width 0.14224)
		(layer "In4.Cu")
		(net "P5E_CPU0_P0_TX_BUF_DP<7>")
	)
	(segment
		(start 312.30951 -397.734536)
		(end 312.199782 -397.844264)
		(width 0.14224)
		(layer "In4.Cu")
		(net "P5E_CPU0_P0_TX_BUF_DP<7>")
	)
	(segment
		(start 320.266314 -409.353766)
		(end 322.309236 -410.003752)
		(width 0.14224)
		(layer "In4.Cu")
		(net "P5E_CPU0_P0_TX_BUF_DP<7>")
	)
	(segment
		(start 312.953654 -402.886418)
		(end 313.090814 -403.023578)
		(width 0.14224)
		(layer "In4.Cu")
		(net "P5E_CPU0_P0_TX_BUF_DP<7>")
	)
	(segment
		(start 312.476134 -397.734536)
		(end 312.30951 -397.734536)
		(width 0.14224)
		(layer "In4.Cu")
		(net "P5E_CPU0_P0_TX_BUF_DP<7>")
	)
	(segment
		(start 313.090814 -403.023578)
		(end 313.090814 -403.450298)
		(width 0.14224)
		(layer "In4.Cu")
		(net "P5E_CPU0_P0_TX_BUF_DP<7>")
	)
	(segment
		(start 313.056778 -404.55723)
		(end 316.298072 -407.798524)
		(width 0.14224)
		(layer "In4.Cu")
		(net "P5E_CPU0_P0_TX_BUF_DP<7>")
	)
	(segment
		(start 313.090814 -403.450298)
		(end 312.953654 -403.587458)
		(width 0.14224)
		(layer "In4.Cu")
		(net "P5E_CPU0_P0_TX_BUF_DP<7>")
	)
	(segment
		(start 322.309236 -410.003752)
		(end 322.481702 -409.914598)
		(width 0.14224)
		(layer "In4.Cu")
		(net "P5E_CPU0_P0_TX_BUF_DP<7>")
	)
	(segment
		(start 318.147446 -408.787092)
		(end 320.266314 -409.353766)
		(width 0.14224)
		(layer "In4.Cu")
		(net "P5E_CPU0_P0_TX_BUF_DP<7>")
	)
	(segment
		(start 322.481702 -409.914598)
		(end 322.849748 -410.031692)
		(width 0.14224)
		(layer "In4.Cu")
		(net "P5E_CPU0_P0_TX_BUF_DP<7>")
	)
	(segment
		(start 322.938902 -410.204412)
		(end 323.306694 -410.321252)
		(width 0.14224)
		(layer "In4.Cu")
		(net "P5E_CPU0_P0_TX_BUF_DP<7>")
	)
	(segment
		(start 323.47916 -410.232098)
		(end 323.847206 -410.349192)
		(width 0.14224)
		(layer "In4.Cu")
		(net "P5E_CPU0_P0_TX_BUF_DP<7>")
	)
	(segment
		(start 323.847206 -410.349192)
		(end 323.93636 -410.521912)
		(width 0.14224)
		(layer "In4.Cu")
		(net "P5E_CPU0_P0_TX_BUF_DP<7>")
	)
	(segment
		(start 312.588656 -398.6276)
		(end 312.588656 -399.150586)
		(width 0.14224)
		(layer "In4.Cu")
		(net "P5E_CPU0_P0_TX_BUF_DP<7>")
	)
	(segment
		(start 312.590942 -397.849344)
		(end 312.476134 -397.734536)
		(width 0.14224)
		(layer "In4.Cu")
		(net "P5E_CPU0_P0_TX_BUF_DP<7>")
	)
	(segment
		(start 312.953654 -400.095974)
		(end 312.953654 -402.886418)
		(width 0.14224)
		(layer "In4.Cu")
		(net "P5E_CPU0_P0_TX_BUF_DP<7>")
	)
	(segment
		(start 323.306694 -410.321252)
		(end 323.47916 -410.232098)
		(width 0.14224)
		(layer "In4.Cu")
		(net "P5E_CPU0_P0_TX_BUF_DP<7>")
	)
	(segment
		(start 312.953654 -403.587458)
		(end 312.953654 -404.308564)
		(width 0.14224)
		(layer "In4.Cu")
		(net "P5E_CPU0_P0_TX_BUF_DP<7>")
	)
	(segment
		(start 325.466202 -411.056836)
		(end 325.678546 -411.26918)
		(width 0.14224)
		(layer "In4.Cu")
		(net "P5E_CPU0_P0_TX_BUF_DP<7>")
	)
	(segment
		(start 312.613294 -399.27403)
		(end 312.953654 -400.095974)
		(width 0.14224)
		(layer "In4.Cu")
		(net "P5E_CPU0_P0_TX_BUF_DP<7>")
	)
	(segment
		(start 323.93636 -410.521912)
		(end 325.301102 -410.956252)
		(width 0.14224)
		(layer "In4.Cu")
		(net "P5E_CPU0_P0_TX_BUF_DP<7>")
	)
	(arc
		(start 312.953654 -404.308564)
		(mid 312.980463 -404.44316)
		(end 313.056778 -404.55723)
		(width 0.14224)
		(layer "In4.Cu")
		(net "P5E_CPU0_P0_TX_BUF_DP<7>")
	)
	(arc
		(start 312.588656 -398.625314)
		(mid 312.588657 -398.626457)
		(end 312.588656 -398.6276)
		(width 0.14224)
		(layer "In4.Cu")
		(net "P5E_CPU0_P0_TX_BUF_DP<7>")
	)
	(arc
		(start 312.199782 -397.902176)
		(mid 312.216472 -397.986172)
		(end 312.264044 -398.05737)
		(width 0.14224)
		(layer "In4.Cu")
		(net "P5E_CPU0_P0_TX_BUF_DP<7>")
	)
	(arc
		(start 325.824596 -412.504128)
		(mid 325.836873 -412.565851)
		(end 325.87184 -412.618174)
		(width 0.14224)
		(layer "In4.Cu")
		(net "P5E_CPU0_P0_TX_BUF_DP<7>")
	)
	(arc
		(start 316.298072 -407.798524)
		(mid 317.149445 -408.429959)
		(end 318.147446 -408.787092)
		(width 0.14224)
		(layer "In4.Cu")
		(net "P5E_CPU0_P0_TX_BUF_DP<7>")
	)
	(arc
		(start 325.678546 -411.26918)
		(mid 325.78665 -411.431063)
		(end 325.824596 -411.621986)
		(width 0.14224)
		(layer "In4.Cu")
		(net "P5E_CPU0_P0_TX_BUF_DP<7>")
	)
	(arc
		(start 325.301102 -410.956252)
		(mid 325.389679 -410.996651)
		(end 325.466202 -411.056836)
		(width 0.14224)
		(layer "In4.Cu")
		(net "P5E_CPU0_P0_TX_BUF_DP<7>")
	)
	(arc
		(start 312.415174 -398.2085)
		(mid 312.543187 -398.39973)
		(end 312.588656 -398.625314)
		(width 0.14224)
		(layer "In4.Cu")
		(net "P5E_CPU0_P0_TX_BUF_DP<7>")
	)
	(arc
		(start 312.588656 -399.150586)
		(mid 312.59491 -399.213517)
		(end 312.613294 -399.27403)
		(width 0.14224)
		(layer "In4.Cu")
		(net "P5E_CPU0_P0_TX_BUF_DP<7>")
	)
	(segment
		(start 310.870346 -397.849344)
		(end 311.391046 -397.849344)
		(width 0.127)
		(layer "F.Cu")
		(net "P5E_CPU0_P0_TX_BUF_DP<6>")
	)
	(segment
		(start 322.766436 -416.336734)
		(end 322.766436 -413.11703)
		(width 0.12954)
		(layer "F.Cu")
		(net "P5E_CPU0_P0_TX_BUF_DP<6>")
	)
	(segment
		(start 323.062346 -416.632644)
		(end 322.766436 -416.336734)
		(width 0.12954)
		(layer "F.Cu")
		(net "P5E_CPU0_P0_TX_BUF_DP<6>")
	)
	(segment
		(start 322.766436 -413.11703)
		(end 323.036946 -412.84652)
		(width 0.12954)
		(layer "F.Cu")
		(net "P5E_CPU0_P0_TX_BUF_DP<6>")
	)
	(segment
		(start 318.822832 -409.965906)
		(end 319.891664 -410.393388)
		(width 0.14224)
		(layer "In4.Cu")
		(net "P5E_CPU0_P0_TX_BUF_DP<6>")
	)
	(segment
		(start 321.041776 -410.705808)
		(end 321.400424 -410.849318)
		(width 0.14224)
		(layer "In4.Cu")
		(net "P5E_CPU0_P0_TX_BUF_DP<6>")
	)
	(segment
		(start 311.377076 -399.221706)
		(end 311.753504 -400.130518)
		(width 0.14224)
		(layer "In4.Cu")
		(net "P5E_CPU0_P0_TX_BUF_DP<6>")
	)
	(segment
		(start 321.400424 -410.849318)
		(end 321.476878 -411.02788)
		(width 0.14224)
		(layer "In4.Cu")
		(net "P5E_CPU0_P0_TX_BUF_DP<6>")
	)
	(segment
		(start 311.890664 -403.476714)
		(end 311.753504 -403.613874)
		(width 0.14224)
		(layer "In4.Cu")
		(net "P5E_CPU0_P0_TX_BUF_DP<6>")
	)
	(segment
		(start 311.118758 -398.140428)
		(end 311.23763 -398.2593)
		(width 0.14224)
		(layer "In4.Cu")
		(net "P5E_CPU0_P0_TX_BUF_DP<6>")
	)
	(segment
		(start 312.027824 -404.937976)
		(end 315.421518 -408.33167)
		(width 0.14224)
		(layer "In4.Cu")
		(net "P5E_CPU0_P0_TX_BUF_DP<6>")
	)
	(segment
		(start 311.367424 -398.57299)
		(end 311.367424 -399.172938)
		(width 0.14224)
		(layer "In4.Cu")
		(net "P5E_CPU0_P0_TX_BUF_DP<6>")
	)
	(segment
		(start 321.476878 -411.02788)
		(end 322.411344 -411.401768)
		(width 0.14224)
		(layer "In4.Cu")
		(net "P5E_CPU0_P0_TX_BUF_DP<6>")
	)
	(segment
		(start 320.505074 -410.639006)
		(end 320.863468 -410.782262)
		(width 0.14224)
		(layer "In4.Cu")
		(net "P5E_CPU0_P0_TX_BUF_DP<6>")
	)
	(segment
		(start 311.753504 -400.130518)
		(end 311.753504 -402.912834)
		(width 0.14224)
		(layer "In4.Cu")
		(net "P5E_CPU0_P0_TX_BUF_DP<6>")
	)
	(segment
		(start 319.891664 -410.393388)
		(end 320.069972 -410.317188)
		(width 0.14224)
		(layer "In4.Cu")
		(net "P5E_CPU0_P0_TX_BUF_DP<6>")
	)
	(segment
		(start 320.863468 -410.782262)
		(end 321.041776 -410.705808)
		(width 0.14224)
		(layer "In4.Cu")
		(net "P5E_CPU0_P0_TX_BUF_DP<6>")
	)
	(segment
		(start 322.746116 -412.55569)
		(end 323.036946 -412.84652)
		(width 0.14224)
		(layer "In4.Cu")
		(net "P5E_CPU0_P0_TX_BUF_DP<6>")
	)
	(segment
		(start 311.096152 -397.734536)
		(end 311.006744 -397.823944)
		(width 0.14224)
		(layer "In4.Cu")
		(net "P5E_CPU0_P0_TX_BUF_DP<6>")
	)
	(segment
		(start 320.069972 -410.317188)
		(end 320.42862 -410.460444)
		(width 0.14224)
		(layer "In4.Cu")
		(net "P5E_CPU0_P0_TX_BUF_DP<6>")
	)
	(segment
		(start 311.276238 -397.734536)
		(end 311.096152 -397.734536)
		(width 0.14224)
		(layer "In4.Cu")
		(net "P5E_CPU0_P0_TX_BUF_DP<6>")
	)
	(segment
		(start 311.753504 -403.613874)
		(end 311.753504 -404.275798)
		(width 0.14224)
		(layer "In4.Cu")
		(net "P5E_CPU0_P0_TX_BUF_DP<6>")
	)
	(segment
		(start 317.895986 -409.733496)
		(end 318.822832 -409.965906)
		(width 0.14224)
		(layer "In4.Cu")
		(net "P5E_CPU0_P0_TX_BUF_DP<6>")
	)
	(segment
		(start 320.42862 -410.460444)
		(end 320.505074 -410.639006)
		(width 0.14224)
		(layer "In4.Cu")
		(net "P5E_CPU0_P0_TX_BUF_DP<6>")
	)
	(segment
		(start 311.006744 -397.823944)
		(end 311.006744 -397.870172)
		(width 0.14224)
		(layer "In4.Cu")
		(net "P5E_CPU0_P0_TX_BUF_DP<6>")
	)
	(segment
		(start 311.753504 -402.912834)
		(end 311.890664 -403.049994)
		(width 0.14224)
		(layer "In4.Cu")
		(net "P5E_CPU0_P0_TX_BUF_DP<6>")
	)
	(segment
		(start 311.890664 -403.049994)
		(end 311.890664 -403.476714)
		(width 0.14224)
		(layer "In4.Cu")
		(net "P5E_CPU0_P0_TX_BUF_DP<6>")
	)
	(segment
		(start 322.746116 -411.896052)
		(end 322.746116 -412.55569)
		(width 0.14224)
		(layer "In4.Cu")
		(net "P5E_CPU0_P0_TX_BUF_DP<6>")
	)
	(segment
		(start 311.391046 -397.849344)
		(end 311.276238 -397.734536)
		(width 0.14224)
		(layer "In4.Cu")
		(net "P5E_CPU0_P0_TX_BUF_DP<6>")
	)
	(arc
		(start 311.006744 -397.870172)
		(mid 311.035858 -398.016446)
		(end 311.118758 -398.140428)
		(width 0.14224)
		(layer "In4.Cu")
		(net "P5E_CPU0_P0_TX_BUF_DP<6>")
	)
	(arc
		(start 311.753504 -404.275798)
		(mid 311.824791 -404.63418)
		(end 312.027824 -404.937976)
		(width 0.14224)
		(layer "In4.Cu")
		(net "P5E_CPU0_P0_TX_BUF_DP<6>")
	)
	(arc
		(start 315.421518 -408.33167)
		(mid 316.56359 -409.200555)
		(end 317.895986 -409.733496)
		(width 0.14224)
		(layer "In4.Cu")
		(net "P5E_CPU0_P0_TX_BUF_DP<6>")
	)
	(arc
		(start 311.367424 -399.172938)
		(mid 311.36987 -399.197791)
		(end 311.377076 -399.221706)
		(width 0.14224)
		(layer "In4.Cu")
		(net "P5E_CPU0_P0_TX_BUF_DP<6>")
	)
	(arc
		(start 322.411344 -411.401768)
		(mid 322.654504 -411.597578)
		(end 322.746116 -411.896052)
		(width 0.14224)
		(layer "In4.Cu")
		(net "P5E_CPU0_P0_TX_BUF_DP<6>")
	)
	(arc
		(start 311.23763 -398.2593)
		(mid 311.333766 -398.403223)
		(end 311.367424 -398.57299)
		(width 0.14224)
		(layer "In4.Cu")
		(net "P5E_CPU0_P0_TX_BUF_DP<6>")
	)
	(segment
		(start 319.703196 -416.336734)
		(end 319.999106 -416.632644)
		(width 0.12954)
		(layer "F.Cu")
		(net "P5E_CPU0_P0_TX_BUF_DP<5>")
	)
	(segment
		(start 319.703196 -413.11703)
		(end 319.703196 -416.336734)
		(width 0.12954)
		(layer "F.Cu")
		(net "P5E_CPU0_P0_TX_BUF_DP<5>")
	)
	(segment
		(start 309.67045 -397.849344)
		(end 310.19115 -397.849344)
		(width 0.127)
		(layer "F.Cu")
		(net "P5E_CPU0_P0_TX_BUF_DP<5>")
	)
	(segment
		(start 319.973706 -412.84652)
		(end 319.703196 -413.11703)
		(width 0.12954)
		(layer "F.Cu")
		(net "P5E_CPU0_P0_TX_BUF_DP<5>")
	)
	(segment
		(start 309.806848 -397.823944)
		(end 309.806848 -397.82877)
		(width 0.14224)
		(layer "In4.Cu")
		(net "P5E_CPU0_P0_TX_BUF_DP<5>")
	)
	(segment
		(start 312.606944 -407.032206)
		(end 312.800746 -407.032206)
		(width 0.14224)
		(layer "In4.Cu")
		(net "P5E_CPU0_P0_TX_BUF_DP<5>")
	)
	(segment
		(start 310.553608 -400.084544)
		(end 310.553608 -403.187154)
		(width 0.14224)
		(layer "In4.Cu")
		(net "P5E_CPU0_P0_TX_BUF_DP<5>")
	)
	(segment
		(start 309.896256 -397.734536)
		(end 309.806848 -397.823944)
		(width 0.14224)
		(layer "In4.Cu")
		(net "P5E_CPU0_P0_TX_BUF_DP<5>")
	)
	(segment
		(start 309.947818 -398.16913)
		(end 310.04764 -398.268698)
		(width 0.14224)
		(layer "In4.Cu")
		(net "P5E_CPU0_P0_TX_BUF_DP<5>")
	)
	(segment
		(start 311.617614 -405.849074)
		(end 311.890918 -406.122378)
		(width 0.14224)
		(layer "In4.Cu")
		(net "P5E_CPU0_P0_TX_BUF_DP<5>")
	)
	(segment
		(start 311.890918 -406.31618)
		(end 312.606944 -407.032206)
		(width 0.14224)
		(layer "In4.Cu")
		(net "P5E_CPU0_P0_TX_BUF_DP<5>")
	)
	(segment
		(start 310.228996 -399.243804)
		(end 310.333898 -399.544794)
		(width 0.14224)
		(layer "In4.Cu")
		(net "P5E_CPU0_P0_TX_BUF_DP<5>")
	)
	(segment
		(start 310.553608 -403.888194)
		(end 310.553608 -404.42134)
		(width 0.14224)
		(layer "In4.Cu")
		(net "P5E_CPU0_P0_TX_BUF_DP<5>")
	)
	(segment
		(start 319.682876 -411.97149)
		(end 319.682876 -412.55569)
		(width 0.14224)
		(layer "In4.Cu")
		(net "P5E_CPU0_P0_TX_BUF_DP<5>")
	)
	(segment
		(start 311.423812 -405.849074)
		(end 311.617614 -405.849074)
		(width 0.14224)
		(layer "In4.Cu")
		(net "P5E_CPU0_P0_TX_BUF_DP<5>")
	)
	(segment
		(start 312.800746 -407.032206)
		(end 313.102752 -407.334212)
		(width 0.14224)
		(layer "In4.Cu")
		(net "P5E_CPU0_P0_TX_BUF_DP<5>")
	)
	(segment
		(start 310.167528 -398.55775)
		(end 310.167528 -398.801844)
		(width 0.14224)
		(layer "In4.Cu")
		(net "P5E_CPU0_P0_TX_BUF_DP<5>")
	)
	(segment
		(start 310.690768 -403.324314)
		(end 310.690768 -403.751034)
		(width 0.14224)
		(layer "In4.Cu")
		(net "P5E_CPU0_P0_TX_BUF_DP<5>")
	)
	(segment
		(start 313.102752 -407.528014)
		(end 315.114178 -409.53944)
		(width 0.14224)
		(layer "In4.Cu")
		(net "P5E_CPU0_P0_TX_BUF_DP<5>")
	)
	(segment
		(start 310.378856 -399.662904)
		(end 310.553608 -400.084544)
		(width 0.14224)
		(layer "In4.Cu")
		(net "P5E_CPU0_P0_TX_BUF_DP<5>")
	)
	(segment
		(start 311.890918 -406.122378)
		(end 311.890918 -406.31618)
		(width 0.14224)
		(layer "In4.Cu")
		(net "P5E_CPU0_P0_TX_BUF_DP<5>")
	)
	(segment
		(start 313.102752 -407.334212)
		(end 313.102752 -407.528014)
		(width 0.14224)
		(layer "In4.Cu")
		(net "P5E_CPU0_P0_TX_BUF_DP<5>")
	)
	(segment
		(start 310.553608 -403.187154)
		(end 310.690768 -403.324314)
		(width 0.14224)
		(layer "In4.Cu")
		(net "P5E_CPU0_P0_TX_BUF_DP<5>")
	)
	(segment
		(start 319.682876 -412.55569)
		(end 319.973706 -412.84652)
		(width 0.14224)
		(layer "In4.Cu")
		(net "P5E_CPU0_P0_TX_BUF_DP<5>")
	)
	(segment
		(start 316.16269 -410.239972)
		(end 319.4304 -411.593538)
		(width 0.14224)
		(layer "In4.Cu")
		(net "P5E_CPU0_P0_TX_BUF_DP<5>")
	)
	(segment
		(start 310.076342 -397.734536)
		(end 309.896256 -397.734536)
		(width 0.14224)
		(layer "In4.Cu")
		(net "P5E_CPU0_P0_TX_BUF_DP<5>")
	)
	(segment
		(start 310.19115 -397.849344)
		(end 310.076342 -397.734536)
		(width 0.14224)
		(layer "In4.Cu")
		(net "P5E_CPU0_P0_TX_BUF_DP<5>")
	)
	(segment
		(start 310.690768 -403.751034)
		(end 310.553608 -403.888194)
		(width 0.14224)
		(layer "In4.Cu")
		(net "P5E_CPU0_P0_TX_BUF_DP<5>")
	)
	(segment
		(start 310.947816 -405.373078)
		(end 311.423812 -405.849074)
		(width 0.14224)
		(layer "In4.Cu")
		(net "P5E_CPU0_P0_TX_BUF_DP<5>")
	)
	(arc
		(start 309.806848 -397.82877)
		(mid 309.843487 -398.012967)
		(end 309.947818 -398.16913)
		(width 0.14224)
		(layer "In4.Cu")
		(net "P5E_CPU0_P0_TX_BUF_DP<5>")
	)
	(arc
		(start 319.4304 -411.593538)
		(mid 319.613925 -411.744239)
		(end 319.682876 -411.97149)
		(width 0.14224)
		(layer "In4.Cu")
		(net "P5E_CPU0_P0_TX_BUF_DP<5>")
	)
	(arc
		(start 310.167528 -398.801844)
		(mid 310.174788 -398.962265)
		(end 310.196484 -399.121376)
		(width 0.14224)
		(layer "In4.Cu")
		(net "P5E_CPU0_P0_TX_BUF_DP<5>")
	)
	(arc
		(start 310.553608 -404.42134)
		(mid 310.656062 -404.936411)
		(end 310.947816 -405.373078)
		(width 0.14224)
		(layer "In4.Cu")
		(net "P5E_CPU0_P0_TX_BUF_DP<5>")
	)
	(arc
		(start 310.04764 -398.268698)
		(mid 310.136336 -398.401301)
		(end 310.167528 -398.55775)
		(width 0.14224)
		(layer "In4.Cu")
		(net "P5E_CPU0_P0_TX_BUF_DP<5>")
	)
	(arc
		(start 310.333898 -399.544794)
		(mid 310.355528 -399.604172)
		(end 310.378856 -399.662904)
		(width 0.14224)
		(layer "In4.Cu")
		(net "P5E_CPU0_P0_TX_BUF_DP<5>")
	)
	(arc
		(start 310.196484 -399.121376)
		(mid 310.210366 -399.183221)
		(end 310.228996 -399.243804)
		(width 0.14224)
		(layer "In4.Cu")
		(net "P5E_CPU0_P0_TX_BUF_DP<5>")
	)
	(arc
		(start 315.114178 -409.53944)
		(mid 315.603942 -409.941329)
		(end 316.16269 -410.239972)
		(width 0.14224)
		(layer "In4.Cu")
		(net "P5E_CPU0_P0_TX_BUF_DP<5>")
	)
	(segment
		(start 316.639956 -413.11703)
		(end 316.910466 -412.84652)
		(width 0.12954)
		(layer "F.Cu")
		(net "P5E_CPU0_P0_TX_BUF_DP<4>")
	)
	(segment
		(start 316.935866 -416.632644)
		(end 316.639956 -416.336734)
		(width 0.12954)
		(layer "F.Cu")
		(net "P5E_CPU0_P0_TX_BUF_DP<4>")
	)
	(segment
		(start 316.639956 -416.336734)
		(end 316.639956 -413.11703)
		(width 0.12954)
		(layer "F.Cu")
		(net "P5E_CPU0_P0_TX_BUF_DP<4>")
	)
	(segment
		(start 308.4703 -397.849344)
		(end 308.991 -397.849344)
		(width 0.127)
		(layer "F.Cu")
		(net "P5E_CPU0_P0_TX_BUF_DP<4>")
	)
	(segment
		(start 308.710838 -398.1323)
		(end 308.84749 -398.268698)
		(width 0.14224)
		(layer "In4.Cu")
		(net "P5E_CPU0_P0_TX_BUF_DP<4>")
	)
	(segment
		(start 308.967378 -398.55775)
		(end 308.967378 -398.914874)
		(width 0.14224)
		(layer "In4.Cu")
		(net "P5E_CPU0_P0_TX_BUF_DP<4>")
	)
	(segment
		(start 308.876192 -397.734536)
		(end 308.696106 -397.734536)
		(width 0.14224)
		(layer "In4.Cu")
		(net "P5E_CPU0_P0_TX_BUF_DP<4>")
	)
	(segment
		(start 309.713884 -405.654764)
		(end 310.195976 -406.136856)
		(width 0.14224)
		(layer "In4.Cu")
		(net "P5E_CPU0_P0_TX_BUF_DP<4>")
	)
	(segment
		(start 308.991 -397.849344)
		(end 308.876192 -397.734536)
		(width 0.14224)
		(layer "In4.Cu")
		(net "P5E_CPU0_P0_TX_BUF_DP<4>")
	)
	(segment
		(start 309.490618 -403.059138)
		(end 309.490618 -403.485858)
		(width 0.14224)
		(layer "In4.Cu")
		(net "P5E_CPU0_P0_TX_BUF_DP<4>")
	)
	(segment
		(start 309.353458 -403.623018)
		(end 309.353458 -404.78456)
		(width 0.14224)
		(layer "In4.Cu")
		(net "P5E_CPU0_P0_TX_BUF_DP<4>")
	)
	(segment
		(start 310.663336 -406.604216)
		(end 310.936132 -406.877012)
		(width 0.14224)
		(layer "In4.Cu")
		(net "P5E_CPU0_P0_TX_BUF_DP<4>")
	)
	(segment
		(start 308.606698 -397.823944)
		(end 308.606698 -397.88084)
		(width 0.14224)
		(layer "In4.Cu")
		(net "P5E_CPU0_P0_TX_BUF_DP<4>")
	)
	(segment
		(start 309.490618 -403.485858)
		(end 309.353458 -403.623018)
		(width 0.14224)
		(layer "In4.Cu")
		(net "P5E_CPU0_P0_TX_BUF_DP<4>")
	)
	(segment
		(start 310.390032 -406.136856)
		(end 310.663336 -406.41016)
		(width 0.14224)
		(layer "In4.Cu")
		(net "P5E_CPU0_P0_TX_BUF_DP<4>")
	)
	(segment
		(start 310.936132 -406.877012)
		(end 311.130188 -406.877012)
		(width 0.14224)
		(layer "In4.Cu")
		(net "P5E_CPU0_P0_TX_BUF_DP<4>")
	)
	(segment
		(start 316.619636 -412.093664)
		(end 316.619636 -412.55569)
		(width 0.14224)
		(layer "In4.Cu")
		(net "P5E_CPU0_P0_TX_BUF_DP<4>")
	)
	(segment
		(start 316.619636 -412.55569)
		(end 316.910466 -412.84652)
		(width 0.14224)
		(layer "In4.Cu")
		(net "P5E_CPU0_P0_TX_BUF_DP<4>")
	)
	(segment
		(start 311.403492 -407.150316)
		(end 311.403492 -407.344372)
		(width 0.14224)
		(layer "In4.Cu")
		(net "P5E_CPU0_P0_TX_BUF_DP<4>")
	)
	(segment
		(start 310.195976 -406.136856)
		(end 310.390032 -406.136856)
		(width 0.14224)
		(layer "In4.Cu")
		(net "P5E_CPU0_P0_TX_BUF_DP<4>")
	)
	(segment
		(start 309.353458 -402.921978)
		(end 309.490618 -403.059138)
		(width 0.14224)
		(layer "In4.Cu")
		(net "P5E_CPU0_P0_TX_BUF_DP<4>")
	)
	(segment
		(start 309.353458 -399.872454)
		(end 309.353458 -402.921978)
		(width 0.14224)
		(layer "In4.Cu")
		(net "P5E_CPU0_P0_TX_BUF_DP<4>")
	)
	(segment
		(start 311.130188 -406.877012)
		(end 311.403492 -407.150316)
		(width 0.14224)
		(layer "In4.Cu")
		(net "P5E_CPU0_P0_TX_BUF_DP<4>")
	)
	(segment
		(start 315.783722 -411.302962)
		(end 315.838078 -411.302962)
		(width 0.14224)
		(layer "In4.Cu")
		(net "P5E_CPU0_P0_TX_BUF_DP<4>")
	)
	(segment
		(start 308.696106 -397.734536)
		(end 308.606698 -397.823944)
		(width 0.14224)
		(layer "In4.Cu")
		(net "P5E_CPU0_P0_TX_BUF_DP<4>")
	)
	(segment
		(start 308.97703 -398.963642)
		(end 309.353458 -399.872454)
		(width 0.14224)
		(layer "In4.Cu")
		(net "P5E_CPU0_P0_TX_BUF_DP<4>")
	)
	(segment
		(start 311.403492 -407.344372)
		(end 315.063886 -411.004766)
		(width 0.14224)
		(layer "In4.Cu")
		(net "P5E_CPU0_P0_TX_BUF_DP<4>")
	)
	(segment
		(start 310.663336 -406.41016)
		(end 310.663336 -406.604216)
		(width 0.14224)
		(layer "In4.Cu")
		(net "P5E_CPU0_P0_TX_BUF_DP<4>")
	)
	(arc
		(start 316.308994 -411.498034)
		(mid 316.474833 -411.704232)
		(end 316.592458 -411.941264)
		(width 0.14224)
		(layer "In4.Cu")
		(net "P5E_CPU0_P0_TX_BUF_DP<4>")
	)
	(arc
		(start 308.606698 -397.88084)
		(mid 308.633766 -398.016922)
		(end 308.710838 -398.1323)
		(width 0.14224)
		(layer "In4.Cu")
		(net "P5E_CPU0_P0_TX_BUF_DP<4>")
	)
	(arc
		(start 308.84749 -398.268698)
		(mid 308.936186 -398.401301)
		(end 308.967378 -398.55775)
		(width 0.14224)
		(layer "In4.Cu")
		(net "P5E_CPU0_P0_TX_BUF_DP<4>")
	)
	(arc
		(start 315.063886 -411.004766)
		(mid 315.39415 -411.225441)
		(end 315.783722 -411.302962)
		(width 0.14224)
		(layer "In4.Cu")
		(net "P5E_CPU0_P0_TX_BUF_DP<4>")
	)
	(arc
		(start 316.592458 -411.941264)
		(mid 316.612779 -412.016266)
		(end 316.619636 -412.093664)
		(width 0.14224)
		(layer "In4.Cu")
		(net "P5E_CPU0_P0_TX_BUF_DP<4>")
	)
	(arc
		(start 315.838078 -411.302962)
		(mid 316.092941 -411.353657)
		(end 316.308994 -411.498034)
		(width 0.14224)
		(layer "In4.Cu")
		(net "P5E_CPU0_P0_TX_BUF_DP<4>")
	)
	(arc
		(start 309.353458 -404.78456)
		(mid 309.447134 -405.255502)
		(end 309.713884 -405.654764)
		(width 0.14224)
		(layer "In4.Cu")
		(net "P5E_CPU0_P0_TX_BUF_DP<4>")
	)
	(arc
		(start 308.967378 -398.914874)
		(mid 308.969824 -398.939727)
		(end 308.97703 -398.963642)
		(width 0.14224)
		(layer "In4.Cu")
		(net "P5E_CPU0_P0_TX_BUF_DP<4>")
	)
	(segment
		(start 313.576716 -416.336734)
		(end 313.576716 -413.11703)
		(width 0.12954)
		(layer "F.Cu")
		(net "P5E_CPU0_P0_TX_BUF_DP<3>")
	)
	(segment
		(start 313.872626 -416.632644)
		(end 313.576716 -416.336734)
		(width 0.12954)
		(layer "F.Cu")
		(net "P5E_CPU0_P0_TX_BUF_DP<3>")
	)
	(segment
		(start 313.576716 -413.11703)
		(end 313.847226 -412.84652)
		(width 0.12954)
		(layer "F.Cu")
		(net "P5E_CPU0_P0_TX_BUF_DP<3>")
	)
	(segment
		(start 307.270404 -397.849344)
		(end 307.791104 -397.849344)
		(width 0.127)
		(layer "F.Cu")
		(net "P5E_CPU0_P0_TX_BUF_DP<3>")
	)
	(segment
		(start 308.153562 -402.683472)
		(end 308.290722 -402.820632)
		(width 0.14224)
		(layer "In4.Cu")
		(net "P5E_CPU0_P0_TX_BUF_DP<3>")
	)
	(segment
		(start 307.767482 -398.558512)
		(end 307.767482 -398.994884)
		(width 0.14224)
		(layer "In4.Cu")
		(net "P5E_CPU0_P0_TX_BUF_DP<3>")
	)
	(segment
		(start 307.406802 -397.823944)
		(end 307.406802 -397.97355)
		(width 0.14224)
		(layer "In4.Cu")
		(net "P5E_CPU0_P0_TX_BUF_DP<3>")
	)
	(segment
		(start 308.153562 -404.512272)
		(end 308.153562 -405.065992)
		(width 0.14224)
		(layer "In4.Cu")
		(net "P5E_CPU0_P0_TX_BUF_DP<3>")
	)
	(segment
		(start 308.400958 -405.663146)
		(end 313.426602 -410.68879)
		(width 0.14224)
		(layer "In4.Cu")
		(net "P5E_CPU0_P0_TX_BUF_DP<3>")
	)
	(segment
		(start 307.49621 -397.734536)
		(end 307.406802 -397.823944)
		(width 0.14224)
		(layer "In4.Cu")
		(net "P5E_CPU0_P0_TX_BUF_DP<3>")
	)
	(segment
		(start 313.556396 -411.00248)
		(end 313.556396 -411.242256)
		(width 0.14224)
		(layer "In4.Cu")
		(net "P5E_CPU0_P0_TX_BUF_DP<3>")
	)
	(segment
		(start 308.290722 -402.820632)
		(end 308.290722 -403.247352)
		(width 0.14224)
		(layer "In4.Cu")
		(net "P5E_CPU0_P0_TX_BUF_DP<3>")
	)
	(segment
		(start 313.556396 -411.902656)
		(end 313.556396 -412.55569)
		(width 0.14224)
		(layer "In4.Cu")
		(net "P5E_CPU0_P0_TX_BUF_DP<3>")
	)
	(segment
		(start 308.153562 -403.384512)
		(end 308.153562 -403.811232)
		(width 0.14224)
		(layer "In4.Cu")
		(net "P5E_CPU0_P0_TX_BUF_DP<3>")
	)
	(segment
		(start 308.153562 -400.203162)
		(end 308.153562 -402.683472)
		(width 0.14224)
		(layer "In4.Cu")
		(net "P5E_CPU0_P0_TX_BUF_DP<3>")
	)
	(segment
		(start 313.693556 -411.765496)
		(end 313.556396 -411.902656)
		(width 0.14224)
		(layer "In4.Cu")
		(net "P5E_CPU0_P0_TX_BUF_DP<3>")
	)
	(segment
		(start 308.290722 -403.247352)
		(end 308.153562 -403.384512)
		(width 0.14224)
		(layer "In4.Cu")
		(net "P5E_CPU0_P0_TX_BUF_DP<3>")
	)
	(segment
		(start 313.556396 -411.242256)
		(end 313.693556 -411.379416)
		(width 0.14224)
		(layer "In4.Cu")
		(net "P5E_CPU0_P0_TX_BUF_DP<3>")
	)
	(segment
		(start 307.676296 -397.734536)
		(end 307.49621 -397.734536)
		(width 0.14224)
		(layer "In4.Cu")
		(net "P5E_CPU0_P0_TX_BUF_DP<3>")
	)
	(segment
		(start 307.786024 -399.119598)
		(end 308.13502 -399.96237)
		(width 0.14224)
		(layer "In4.Cu")
		(net "P5E_CPU0_P0_TX_BUF_DP<3>")
	)
	(segment
		(start 313.556396 -412.55569)
		(end 313.847226 -412.84652)
		(width 0.14224)
		(layer "In4.Cu")
		(net "P5E_CPU0_P0_TX_BUF_DP<3>")
	)
	(segment
		(start 308.153562 -403.811232)
		(end 308.290722 -403.948392)
		(width 0.14224)
		(layer "In4.Cu")
		(net "P5E_CPU0_P0_TX_BUF_DP<3>")
	)
	(segment
		(start 307.44414 -398.063466)
		(end 307.64607 -398.265396)
		(width 0.14224)
		(layer "In4.Cu")
		(net "P5E_CPU0_P0_TX_BUF_DP<3>")
	)
	(segment
		(start 308.13502 -399.96237)
		(end 308.13502 -400.042126)
		(width 0.14224)
		(layer "In4.Cu")
		(net "P5E_CPU0_P0_TX_BUF_DP<3>")
	)
	(segment
		(start 308.290722 -404.375112)
		(end 308.153562 -404.512272)
		(width 0.14224)
		(layer "In4.Cu")
		(net "P5E_CPU0_P0_TX_BUF_DP<3>")
	)
	(segment
		(start 307.791104 -397.849344)
		(end 307.676296 -397.734536)
		(width 0.14224)
		(layer "In4.Cu")
		(net "P5E_CPU0_P0_TX_BUF_DP<3>")
	)
	(segment
		(start 313.693556 -411.379416)
		(end 313.693556 -411.765496)
		(width 0.14224)
		(layer "In4.Cu")
		(net "P5E_CPU0_P0_TX_BUF_DP<3>")
	)
	(segment
		(start 308.290722 -403.948392)
		(end 308.290722 -404.375112)
		(width 0.14224)
		(layer "In4.Cu")
		(net "P5E_CPU0_P0_TX_BUF_DP<3>")
	)
	(arc
		(start 313.426602 -410.68879)
		(mid 313.522738 -410.832713)
		(end 313.556396 -411.00248)
		(width 0.14224)
		(layer "In4.Cu")
		(net "P5E_CPU0_P0_TX_BUF_DP<3>")
	)
	(arc
		(start 307.406802 -397.97355)
		(mid 307.416504 -398.022234)
		(end 307.44414 -398.063466)
		(width 0.14224)
		(layer "In4.Cu")
		(net "P5E_CPU0_P0_TX_BUF_DP<3>")
	)
	(arc
		(start 308.13502 -400.042126)
		(mid 308.148902 -400.122114)
		(end 308.153562 -400.203162)
		(width 0.14224)
		(layer "In4.Cu")
		(net "P5E_CPU0_P0_TX_BUF_DP<3>")
	)
	(arc
		(start 307.64607 -398.265396)
		(mid 307.735929 -398.399879)
		(end 307.767482 -398.558512)
		(width 0.14224)
		(layer "In4.Cu")
		(net "P5E_CPU0_P0_TX_BUF_DP<3>")
	)
	(arc
		(start 308.153562 -405.065992)
		(mid 308.217865 -405.389173)
		(end 308.400958 -405.663146)
		(width 0.14224)
		(layer "In4.Cu")
		(net "P5E_CPU0_P0_TX_BUF_DP<3>")
	)
	(arc
		(start 307.767482 -398.994884)
		(mid 307.772163 -399.057923)
		(end 307.786024 -399.119598)
		(width 0.14224)
		(layer "In4.Cu")
		(net "P5E_CPU0_P0_TX_BUF_DP<3>")
	)
	(segment
		(start 310.809386 -416.632644)
		(end 310.513476 -416.336734)
		(width 0.12954)
		(layer "F.Cu")
		(net "P5E_CPU0_P0_TX_BUF_DP<2>")
	)
	(segment
		(start 306.070254 -397.849344)
		(end 306.590954 -397.849344)
		(width 0.127)
		(layer "F.Cu")
		(net "P5E_CPU0_P0_TX_BUF_DP<2>")
	)
	(segment
		(start 310.513476 -413.11703)
		(end 310.783986 -412.84652)
		(width 0.12954)
		(layer "F.Cu")
		(net "P5E_CPU0_P0_TX_BUF_DP<2>")
	)
	(segment
		(start 310.513476 -416.336734)
		(end 310.513476 -413.11703)
		(width 0.12954)
		(layer "F.Cu")
		(net "P5E_CPU0_P0_TX_BUF_DP<2>")
	)
	(segment
		(start 310.630316 -411.654498)
		(end 310.493156 -411.791658)
		(width 0.14224)
		(layer "In4.Cu")
		(net "P5E_CPU0_P0_TX_BUF_DP<2>")
	)
	(segment
		(start 306.774596 -399.614136)
		(end 306.953666 -400.046698)
		(width 0.14224)
		(layer "In4.Cu")
		(net "P5E_CPU0_P0_TX_BUF_DP<2>")
	)
	(segment
		(start 307.090826 -402.847048)
		(end 307.090826 -403.273768)
		(width 0.14224)
		(layer "In4.Cu")
		(net "P5E_CPU0_P0_TX_BUF_DP<2>")
	)
	(segment
		(start 310.493156 -411.791658)
		(end 310.493156 -412.55569)
		(width 0.14224)
		(layer "In4.Cu")
		(net "P5E_CPU0_P0_TX_BUF_DP<2>")
	)
	(segment
		(start 306.320698 -397.734536)
		(end 306.206652 -397.848582)
		(width 0.14224)
		(layer "In4.Cu")
		(net "P5E_CPU0_P0_TX_BUF_DP<2>")
	)
	(segment
		(start 306.206652 -397.848582)
		(end 306.206652 -397.867378)
		(width 0.14224)
		(layer "In4.Cu")
		(net "P5E_CPU0_P0_TX_BUF_DP<2>")
	)
	(segment
		(start 307.090826 -403.273768)
		(end 306.953666 -403.410928)
		(width 0.14224)
		(layer "In4.Cu")
		(net "P5E_CPU0_P0_TX_BUF_DP<2>")
	)
	(segment
		(start 306.953666 -403.837648)
		(end 307.090826 -403.974808)
		(width 0.14224)
		(layer "In4.Cu")
		(net "P5E_CPU0_P0_TX_BUF_DP<2>")
	)
	(segment
		(start 306.953666 -403.410928)
		(end 306.953666 -403.837648)
		(width 0.14224)
		(layer "In4.Cu")
		(net "P5E_CPU0_P0_TX_BUF_DP<2>")
	)
	(segment
		(start 310.630316 -411.268418)
		(end 310.630316 -411.654498)
		(width 0.14224)
		(layer "In4.Cu")
		(net "P5E_CPU0_P0_TX_BUF_DP<2>")
	)
	(segment
		(start 306.600098 -398.651476)
		(end 306.600098 -398.99717)
		(width 0.14224)
		(layer "In4.Cu")
		(net "P5E_CPU0_P0_TX_BUF_DP<2>")
	)
	(segment
		(start 307.090826 -403.974808)
		(end 307.090826 -404.401528)
		(width 0.14224)
		(layer "In4.Cu")
		(net "P5E_CPU0_P0_TX_BUF_DP<2>")
	)
	(segment
		(start 307.153564 -405.637238)
		(end 310.160162 -409.300934)
		(width 0.14224)
		(layer "In4.Cu")
		(net "P5E_CPU0_P0_TX_BUF_DP<2>")
	)
	(segment
		(start 306.953666 -404.538688)
		(end 306.953666 -405.079454)
		(width 0.14224)
		(layer "In4.Cu")
		(net "P5E_CPU0_P0_TX_BUF_DP<2>")
	)
	(segment
		(start 307.090826 -404.401528)
		(end 306.953666 -404.538688)
		(width 0.14224)
		(layer "In4.Cu")
		(net "P5E_CPU0_P0_TX_BUF_DP<2>")
	)
	(segment
		(start 310.493156 -410.231844)
		(end 310.493156 -411.131258)
		(width 0.14224)
		(layer "In4.Cu")
		(net "P5E_CPU0_P0_TX_BUF_DP<2>")
	)
	(segment
		(start 306.590954 -397.849344)
		(end 306.476146 -397.734536)
		(width 0.14224)
		(layer "In4.Cu")
		(net "P5E_CPU0_P0_TX_BUF_DP<2>")
	)
	(segment
		(start 310.493156 -411.131258)
		(end 310.630316 -411.268418)
		(width 0.14224)
		(layer "In4.Cu")
		(net "P5E_CPU0_P0_TX_BUF_DP<2>")
	)
	(segment
		(start 306.953666 -402.709888)
		(end 307.090826 -402.847048)
		(width 0.14224)
		(layer "In4.Cu")
		(net "P5E_CPU0_P0_TX_BUF_DP<2>")
	)
	(segment
		(start 306.320698 -398.14246)
		(end 306.437538 -398.2593)
		(width 0.14224)
		(layer "In4.Cu")
		(net "P5E_CPU0_P0_TX_BUF_DP<2>")
	)
	(segment
		(start 306.476146 -397.734536)
		(end 306.320698 -397.734536)
		(width 0.14224)
		(layer "In4.Cu")
		(net "P5E_CPU0_P0_TX_BUF_DP<2>")
	)
	(segment
		(start 310.493156 -412.55569)
		(end 310.783986 -412.84652)
		(width 0.14224)
		(layer "In4.Cu")
		(net "P5E_CPU0_P0_TX_BUF_DP<2>")
	)
	(segment
		(start 306.953666 -400.046698)
		(end 306.953666 -402.709888)
		(width 0.14224)
		(layer "In4.Cu")
		(net "P5E_CPU0_P0_TX_BUF_DP<2>")
	)
	(segment
		(start 306.61864 -399.121884)
		(end 306.731924 -399.49501)
		(width 0.14224)
		(layer "In4.Cu")
		(net "P5E_CPU0_P0_TX_BUF_DP<2>")
	)
	(arc
		(start 306.953666 -405.079454)
		(mid 307.005243 -405.375677)
		(end 307.153564 -405.637238)
		(width 0.14224)
		(layer "In4.Cu")
		(net "P5E_CPU0_P0_TX_BUF_DP<2>")
	)
	(arc
		(start 306.731924 -399.49501)
		(mid 306.751807 -399.555093)
		(end 306.774596 -399.614136)
		(width 0.14224)
		(layer "In4.Cu")
		(net "P5E_CPU0_P0_TX_BUF_DP<2>")
	)
	(arc
		(start 306.206652 -397.867378)
		(mid 306.236288 -398.016277)
		(end 306.320698 -398.14246)
		(width 0.14224)
		(layer "In4.Cu")
		(net "P5E_CPU0_P0_TX_BUF_DP<2>")
	)
	(arc
		(start 306.437538 -398.2593)
		(mid 306.557794 -398.439231)
		(end 306.600098 -398.651476)
		(width 0.14224)
		(layer "In4.Cu")
		(net "P5E_CPU0_P0_TX_BUF_DP<2>")
	)
	(arc
		(start 306.600098 -398.99717)
		(mid 306.60475 -399.060215)
		(end 306.61864 -399.121884)
		(width 0.14224)
		(layer "In4.Cu")
		(net "P5E_CPU0_P0_TX_BUF_DP<2>")
	)
	(arc
		(start 310.160162 -409.300934)
		(mid 310.407419 -409.737503)
		(end 310.493156 -410.231844)
		(width 0.14224)
		(layer "In4.Cu")
		(net "P5E_CPU0_P0_TX_BUF_DP<2>")
	)
	(segment
		(start 307.746146 -416.632644)
		(end 307.450236 -416.336734)
		(width 0.12954)
		(layer "F.Cu")
		(net "P5E_CPU0_P0_TX_BUF_DP<1>")
	)
	(segment
		(start 307.450236 -413.11703)
		(end 307.720746 -412.84652)
		(width 0.12954)
		(layer "F.Cu")
		(net "P5E_CPU0_P0_TX_BUF_DP<1>")
	)
	(segment
		(start 307.450236 -416.336734)
		(end 307.450236 -413.11703)
		(width 0.12954)
		(layer "F.Cu")
		(net "P5E_CPU0_P0_TX_BUF_DP<1>")
	)
	(segment
		(start 304.870358 -397.849344)
		(end 305.391058 -397.849344)
		(width 0.127)
		(layer "F.Cu")
		(net "P5E_CPU0_P0_TX_BUF_DP<1>")
	)
	(segment
		(start 307.318664 -408.181048)
		(end 307.253386 -408.363674)
		(width 0.14224)
		(layer "In4.Cu")
		(net "P5E_CPU0_P0_TX_BUF_DP<1>")
	)
	(segment
		(start 307.429916 -412.55569)
		(end 307.720746 -412.84652)
		(width 0.14224)
		(layer "In4.Cu")
		(net "P5E_CPU0_P0_TX_BUF_DP<1>")
	)
	(segment
		(start 307.567076 -410.664152)
		(end 307.567076 -411.090872)
		(width 0.14224)
		(layer "In4.Cu")
		(net "P5E_CPU0_P0_TX_BUF_DP<1>")
	)
	(segment
		(start 306.471066 -406.710134)
		(end 306.653946 -406.775412)
		(width 0.14224)
		(layer "In4.Cu")
		(net "P5E_CPU0_P0_TX_BUF_DP<1>")
	)
	(segment
		(start 305.442874 -399.311876)
		(end 305.7398 -400.030696)
		(width 0.14224)
		(layer "In4.Cu")
		(net "P5E_CPU0_P0_TX_BUF_DP<1>")
	)
	(segment
		(start 307.429916 -408.829256)
		(end 307.429916 -410.526992)
		(width 0.14224)
		(layer "In4.Cu")
		(net "P5E_CPU0_P0_TX_BUF_DP<1>")
	)
	(segment
		(start 307.136292 -407.794968)
		(end 307.318664 -408.181048)
		(width 0.14224)
		(layer "In4.Cu")
		(net "P5E_CPU0_P0_TX_BUF_DP<1>")
	)
	(segment
		(start 307.429916 -410.526992)
		(end 307.567076 -410.664152)
		(width 0.14224)
		(layer "In4.Cu")
		(net "P5E_CPU0_P0_TX_BUF_DP<1>")
	)
	(segment
		(start 305.76012 -404.556214)
		(end 305.79187 -404.861522)
		(width 0.14224)
		(layer "In4.Cu")
		(net "P5E_CPU0_P0_TX_BUF_DP<1>")
	)
	(segment
		(start 305.006756 -397.823944)
		(end 305.006756 -397.88084)
		(width 0.14224)
		(layer "In4.Cu")
		(net "P5E_CPU0_P0_TX_BUF_DP<1>")
	)
	(segment
		(start 305.811936 -404.98649)
		(end 305.879246 -405.297894)
		(width 0.14224)
		(layer "In4.Cu")
		(net "P5E_CPU0_P0_TX_BUF_DP<1>")
	)
	(segment
		(start 305.096164 -397.734536)
		(end 305.006756 -397.823944)
		(width 0.14224)
		(layer "In4.Cu")
		(net "P5E_CPU0_P0_TX_BUF_DP<1>")
	)
	(segment
		(start 305.372516 -398.76476)
		(end 305.421792 -399.229072)
		(width 0.14224)
		(layer "In4.Cu")
		(net "P5E_CPU0_P0_TX_BUF_DP<1>")
	)
	(segment
		(start 305.391058 -397.849344)
		(end 305.27625 -397.734536)
		(width 0.14224)
		(layer "In4.Cu")
		(net "P5E_CPU0_P0_TX_BUF_DP<1>")
	)
	(segment
		(start 306.953412 -407.72969)
		(end 307.136292 -407.794968)
		(width 0.14224)
		(layer "In4.Cu")
		(net "P5E_CPU0_P0_TX_BUF_DP<1>")
	)
	(segment
		(start 306.836318 -407.161238)
		(end 306.77104 -407.344118)
		(width 0.14224)
		(layer "In4.Cu")
		(net "P5E_CPU0_P0_TX_BUF_DP<1>")
	)
	(segment
		(start 305.27625 -397.734536)
		(end 305.096164 -397.734536)
		(width 0.14224)
		(layer "In4.Cu")
		(net "P5E_CPU0_P0_TX_BUF_DP<1>")
	)
	(segment
		(start 305.753516 -400.158458)
		(end 305.753516 -404.429976)
		(width 0.14224)
		(layer "In4.Cu")
		(net "P5E_CPU0_P0_TX_BUF_DP<1>")
	)
	(segment
		(start 307.429916 -411.228032)
		(end 307.429916 -412.55569)
		(width 0.14224)
		(layer "In4.Cu")
		(net "P5E_CPU0_P0_TX_BUF_DP<1>")
	)
	(segment
		(start 306.77104 -407.344118)
		(end 306.953412 -407.72969)
		(width 0.14224)
		(layer "In4.Cu")
		(net "P5E_CPU0_P0_TX_BUF_DP<1>")
	)
	(segment
		(start 306.07254 -405.867362)
		(end 306.471066 -406.710134)
		(width 0.14224)
		(layer "In4.Cu")
		(net "P5E_CPU0_P0_TX_BUF_DP<1>")
	)
	(segment
		(start 305.367436 -398.55775)
		(end 305.367436 -398.668748)
		(width 0.14224)
		(layer "In4.Cu")
		(net "P5E_CPU0_P0_TX_BUF_DP<1>")
	)
	(segment
		(start 307.567076 -411.090872)
		(end 307.429916 -411.228032)
		(width 0.14224)
		(layer "In4.Cu")
		(net "P5E_CPU0_P0_TX_BUF_DP<1>")
	)
	(segment
		(start 305.110896 -398.1323)
		(end 305.247548 -398.268698)
		(width 0.14224)
		(layer "In4.Cu")
		(net "P5E_CPU0_P0_TX_BUF_DP<1>")
	)
	(segment
		(start 307.253386 -408.363674)
		(end 307.3908 -408.65425)
		(width 0.14224)
		(layer "In4.Cu")
		(net "P5E_CPU0_P0_TX_BUF_DP<1>")
	)
	(segment
		(start 306.653946 -406.775412)
		(end 306.836318 -407.161238)
		(width 0.14224)
		(layer "In4.Cu")
		(net "P5E_CPU0_P0_TX_BUF_DP<1>")
	)
	(arc
		(start 305.753516 -404.429976)
		(mid 305.755182 -404.493181)
		(end 305.76012 -404.556214)
		(width 0.14224)
		(layer "In4.Cu")
		(net "P5E_CPU0_P0_TX_BUF_DP<1>")
	)
	(arc
		(start 305.421792 -399.229072)
		(mid 305.429379 -399.271226)
		(end 305.442874 -399.311876)
		(width 0.14224)
		(layer "In4.Cu")
		(net "P5E_CPU0_P0_TX_BUF_DP<1>")
	)
	(arc
		(start 305.247548 -398.268698)
		(mid 305.336244 -398.401301)
		(end 305.367436 -398.55775)
		(width 0.14224)
		(layer "In4.Cu")
		(net "P5E_CPU0_P0_TX_BUF_DP<1>")
	)
	(arc
		(start 307.3908 -408.65425)
		(mid 307.420043 -408.739586)
		(end 307.429916 -408.829256)
		(width 0.14224)
		(layer "In4.Cu")
		(net "P5E_CPU0_P0_TX_BUF_DP<1>")
	)
	(arc
		(start 305.006756 -397.88084)
		(mid 305.033824 -398.016922)
		(end 305.110896 -398.1323)
		(width 0.14224)
		(layer "In4.Cu")
		(net "P5E_CPU0_P0_TX_BUF_DP<1>")
	)
	(arc
		(start 305.7398 -400.030696)
		(mid 305.750059 -400.094212)
		(end 305.753516 -400.158458)
		(width 0.14224)
		(layer "In4.Cu")
		(net "P5E_CPU0_P0_TX_BUF_DP<1>")
	)
	(arc
		(start 305.79187 -404.861522)
		(mid 305.800195 -404.92428)
		(end 305.811936 -404.98649)
		(width 0.14224)
		(layer "In4.Cu")
		(net "P5E_CPU0_P0_TX_BUF_DP<1>")
	)
	(arc
		(start 305.879246 -405.297894)
		(mid 305.959578 -405.588166)
		(end 306.07254 -405.867362)
		(width 0.14224)
		(layer "In4.Cu")
		(net "P5E_CPU0_P0_TX_BUF_DP<1>")
	)
	(arc
		(start 305.367436 -398.668748)
		(mid 305.368707 -398.716821)
		(end 305.372516 -398.76476)
		(width 0.14224)
		(layer "In4.Cu")
		(net "P5E_CPU0_P0_TX_BUF_DP<1>")
	)
	(segment
		(start 321.670426 -397.849344)
		(end 322.191126 -397.849344)
		(width 0.127)
		(layer "F.Cu")
		(net "P5E_CPU0_P0_TX_BUF_DP<15>")
	)
	(segment
		(start 350.335596 -416.336734)
		(end 350.335596 -413.11703)
		(width 0.12954)
		(layer "F.Cu")
		(net "P5E_CPU0_P0_TX_BUF_DP<15>")
	)
	(segment
		(start 350.335596 -413.11703)
		(end 350.606106 -412.84652)
		(width 0.12954)
		(layer "F.Cu")
		(net "P5E_CPU0_P0_TX_BUF_DP<15>")
	)
	(segment
		(start 350.631506 -416.632644)
		(end 350.335596 -416.336734)
		(width 0.12954)
		(layer "F.Cu")
		(net "P5E_CPU0_P0_TX_BUF_DP<15>")
	)
	(segment
		(start 322.535296 -399.479516)
		(end 322.608956 -399.65757)
		(width 0.14224)
		(layer "In4.Cu")
		(net "P5E_CPU0_P0_TX_BUF_DP<15>")
	)
	(segment
		(start 332.487016 -404.325074)
		(end 332.582774 -404.493984)
		(width 0.14224)
		(layer "In4.Cu")
		(net "P5E_CPU0_P0_TX_BUF_DP<15>")
	)
	(segment
		(start 321.896232 -397.734536)
		(end 321.806824 -397.823944)
		(width 0.14224)
		(layer "In4.Cu")
		(net "P5E_CPU0_P0_TX_BUF_DP<15>")
	)
	(segment
		(start 349.933514 -410.700982)
		(end 350.023684 -410.791152)
		(width 0.14224)
		(layer "In4.Cu")
		(net "P5E_CPU0_P0_TX_BUF_DP<15>")
	)
	(segment
		(start 322.661026 -399.84553)
		(end 322.761864 -400.520154)
		(width 0.14224)
		(layer "In4.Cu")
		(net "P5E_CPU0_P0_TX_BUF_DP<15>")
	)
	(segment
		(start 331.90688 -404.306786)
		(end 332.075536 -404.211028)
		(width 0.14224)
		(layer "In4.Cu")
		(net "P5E_CPU0_P0_TX_BUF_DP<15>")
	)
	(segment
		(start 322.280534 -398.640808)
		(end 322.492878 -399.36039)
		(width 0.14224)
		(layer "In4.Cu")
		(net "P5E_CPU0_P0_TX_BUF_DP<15>")
	)
	(segment
		(start 324.827138 -402.34743)
		(end 331.90688 -404.306786)
		(width 0.14224)
		(layer "In4.Cu")
		(net "P5E_CPU0_P0_TX_BUF_DP<15>")
	)
	(segment
		(start 335.658968 -405.345392)
		(end 337.7184 -405.915368)
		(width 0.14224)
		(layer "In4.Cu")
		(net "P5E_CPU0_P0_TX_BUF_DP<15>")
	)
	(segment
		(start 350.315276 -411.49524)
		(end 350.315276 -412.55569)
		(width 0.14224)
		(layer "In4.Cu")
		(net "P5E_CPU0_P0_TX_BUF_DP<15>")
	)
	(segment
		(start 339.958934 -406.535382)
		(end 349.800672 -410.612082)
		(width 0.14224)
		(layer "In4.Cu")
		(net "P5E_CPU0_P0_TX_BUF_DP<15>")
	)
	(segment
		(start 335.56321 -405.176228)
		(end 335.658714 -405.345392)
		(width 0.14224)
		(layer "In4.Cu")
		(net "P5E_CPU0_P0_TX_BUF_DP<15>")
	)
	(segment
		(start 335.151476 -405.062436)
		(end 335.56321 -405.176228)
		(width 0.14224)
		(layer "In4.Cu")
		(net "P5E_CPU0_P0_TX_BUF_DP<15>")
	)
	(segment
		(start 334.98282 -405.158194)
		(end 335.151476 -405.062436)
		(width 0.14224)
		(layer "In4.Cu")
		(net "P5E_CPU0_P0_TX_BUF_DP<15>")
	)
	(segment
		(start 332.582774 -404.493984)
		(end 334.98282 -405.158194)
		(width 0.14224)
		(layer "In4.Cu")
		(net "P5E_CPU0_P0_TX_BUF_DP<15>")
	)
	(segment
		(start 323.059044 -401.244054)
		(end 323.155056 -401.385278)
		(width 0.14224)
		(layer "In4.Cu")
		(net "P5E_CPU0_P0_TX_BUF_DP<15>")
	)
	(segment
		(start 335.658714 -405.345392)
		(end 335.658968 -405.345392)
		(width 0.14224)
		(layer "In4.Cu")
		(net "P5E_CPU0_P0_TX_BUF_DP<15>")
	)
	(segment
		(start 337.7184 -405.915368)
		(end 337.887056 -405.81961)
		(width 0.14224)
		(layer "In4.Cu")
		(net "P5E_CPU0_P0_TX_BUF_DP<15>")
	)
	(segment
		(start 322.191126 -397.849344)
		(end 322.076318 -397.734536)
		(width 0.14224)
		(layer "In4.Cu")
		(net "P5E_CPU0_P0_TX_BUF_DP<15>")
	)
	(segment
		(start 350.315276 -412.55569)
		(end 350.606106 -412.84652)
		(width 0.14224)
		(layer "In4.Cu")
		(net "P5E_CPU0_P0_TX_BUF_DP<15>")
	)
	(segment
		(start 338.298536 -405.933402)
		(end 338.394294 -406.102566)
		(width 0.14224)
		(layer "In4.Cu")
		(net "P5E_CPU0_P0_TX_BUF_DP<15>")
	)
	(segment
		(start 338.394294 -406.102566)
		(end 338.394294 -406.102312)
		(width 0.14224)
		(layer "In4.Cu")
		(net "P5E_CPU0_P0_TX_BUF_DP<15>")
	)
	(segment
		(start 332.075536 -404.211028)
		(end 332.487016 -404.325074)
		(width 0.14224)
		(layer "In4.Cu")
		(net "P5E_CPU0_P0_TX_BUF_DP<15>")
	)
	(segment
		(start 337.887056 -405.81961)
		(end 338.298536 -405.933402)
		(width 0.14224)
		(layer "In4.Cu")
		(net "P5E_CPU0_P0_TX_BUF_DP<15>")
	)
	(segment
		(start 322.795646 -400.64182)
		(end 322.9991 -401.132802)
		(width 0.14224)
		(layer "In4.Cu")
		(net "P5E_CPU0_P0_TX_BUF_DP<15>")
	)
	(segment
		(start 338.394294 -406.102312)
		(end 339.958934 -406.535382)
		(width 0.14224)
		(layer "In4.Cu")
		(net "P5E_CPU0_P0_TX_BUF_DP<15>")
	)
	(segment
		(start 322.076318 -397.734536)
		(end 321.896232 -397.734536)
		(width 0.14224)
		(layer "In4.Cu")
		(net "P5E_CPU0_P0_TX_BUF_DP<15>")
	)
	(segment
		(start 321.878706 -398.099788)
		(end 322.076572 -398.2974)
		(width 0.14224)
		(layer "In4.Cu")
		(net "P5E_CPU0_P0_TX_BUF_DP<15>")
	)
	(segment
		(start 321.806824 -397.823944)
		(end 321.806824 -397.926814)
		(width 0.14224)
		(layer "In4.Cu")
		(net "P5E_CPU0_P0_TX_BUF_DP<15>")
	)
	(arc
		(start 321.806824 -397.926814)
		(mid 321.825561 -398.020448)
		(end 321.878706 -398.099788)
		(width 0.14224)
		(layer "In4.Cu")
		(net "P5E_CPU0_P0_TX_BUF_DP<15>")
	)
	(arc
		(start 322.076572 -398.2974)
		(mid 322.200067 -398.456328)
		(end 322.280534 -398.640808)
		(width 0.14224)
		(layer "In4.Cu")
		(net "P5E_CPU0_P0_TX_BUF_DP<15>")
	)
	(arc
		(start 323.238368 -401.480782)
		(mid 323.982793 -402.005692)
		(end 324.827138 -402.34743)
		(width 0.14224)
		(layer "In4.Cu")
		(net "P5E_CPU0_P0_TX_BUF_DP<15>")
	)
	(arc
		(start 349.800672 -410.612082)
		(mid 349.871484 -410.649974)
		(end 349.933514 -410.700982)
		(width 0.14224)
		(layer "In4.Cu")
		(net "P5E_CPU0_P0_TX_BUF_DP<15>")
	)
	(arc
		(start 350.023684 -410.791152)
		(mid 350.239478 -411.114205)
		(end 350.315276 -411.49524)
		(width 0.14224)
		(layer "In4.Cu")
		(net "P5E_CPU0_P0_TX_BUF_DP<15>")
	)
	(arc
		(start 322.9991 -401.132802)
		(mid 323.026237 -401.189956)
		(end 323.059044 -401.244054)
		(width 0.14224)
		(layer "In4.Cu")
		(net "P5E_CPU0_P0_TX_BUF_DP<15>")
	)
	(arc
		(start 322.608956 -399.65757)
		(mid 322.640733 -399.74996)
		(end 322.661026 -399.84553)
		(width 0.14224)
		(layer "In4.Cu")
		(net "P5E_CPU0_P0_TX_BUF_DP<15>")
	)
	(arc
		(start 322.492878 -399.36039)
		(mid 322.512506 -399.420516)
		(end 322.535296 -399.479516)
		(width 0.14224)
		(layer "In4.Cu")
		(net "P5E_CPU0_P0_TX_BUF_DP<15>")
	)
	(arc
		(start 322.761864 -400.520154)
		(mid 322.775038 -400.582019)
		(end 322.795646 -400.64182)
		(width 0.14224)
		(layer "In4.Cu")
		(net "P5E_CPU0_P0_TX_BUF_DP<15>")
	)
	(arc
		(start 323.155056 -401.385278)
		(mid 323.193775 -401.435592)
		(end 323.238368 -401.480782)
		(width 0.14224)
		(layer "In4.Cu")
		(net "P5E_CPU0_P0_TX_BUF_DP<15>")
	)
	(segment
		(start 347.272356 -413.11703)
		(end 347.542866 -412.84652)
		(width 0.12954)
		(layer "F.Cu")
		(net "P5E_CPU0_P0_TX_BUF_DP<14>")
	)
	(segment
		(start 347.272356 -416.336734)
		(end 347.272356 -413.11703)
		(width 0.12954)
		(layer "F.Cu")
		(net "P5E_CPU0_P0_TX_BUF_DP<14>")
	)
	(segment
		(start 320.470276 -397.849344)
		(end 320.990976 -397.849344)
		(width 0.127)
		(layer "F.Cu")
		(net "P5E_CPU0_P0_TX_BUF_DP<14>")
	)
	(segment
		(start 347.568266 -416.632644)
		(end 347.272356 -416.336734)
		(width 0.12954)
		(layer "F.Cu")
		(net "P5E_CPU0_P0_TX_BUF_DP<14>")
	)
	(segment
		(start 322.972684 -402.988018)
		(end 323.347334 -403.081744)
		(width 0.14224)
		(layer "In4.Cu")
		(net "P5E_CPU0_P0_TX_BUF_DP<14>")
	)
	(segment
		(start 338.424012 -407.432256)
		(end 339.029548 -407.615898)
		(width 0.14224)
		(layer "In4.Cu")
		(net "P5E_CPU0_P0_TX_BUF_DP<14>")
	)
	(segment
		(start 325.981314 -403.741636)
		(end 326.081136 -403.90826)
		(width 0.14224)
		(layer "In4.Cu")
		(net "P5E_CPU0_P0_TX_BUF_DP<14>")
	)
	(segment
		(start 321.353688 -400.208242)
		(end 321.353688 -402.462238)
		(width 0.14224)
		(layer "In4.Cu")
		(net "P5E_CPU0_P0_TX_BUF_DP<14>")
	)
	(segment
		(start 325.44004 -403.747478)
		(end 325.60641 -403.64791)
		(width 0.14224)
		(layer "In4.Cu")
		(net "P5E_CPU0_P0_TX_BUF_DP<14>")
	)
	(segment
		(start 347.252036 -412.55569)
		(end 347.542866 -412.84652)
		(width 0.14224)
		(layer "In4.Cu")
		(net "P5E_CPU0_P0_TX_BUF_DP<14>")
	)
	(segment
		(start 323.447156 -403.248368)
		(end 325.44004 -403.747478)
		(width 0.14224)
		(layer "In4.Cu")
		(net "P5E_CPU0_P0_TX_BUF_DP<14>")
	)
	(segment
		(start 320.876168 -397.734536)
		(end 320.682112 -397.734536)
		(width 0.14224)
		(layer "In4.Cu")
		(net "P5E_CPU0_P0_TX_BUF_DP<14>")
	)
	(segment
		(start 320.990976 -397.849344)
		(end 320.876168 -397.734536)
		(width 0.14224)
		(layer "In4.Cu")
		(net "P5E_CPU0_P0_TX_BUF_DP<14>")
	)
	(segment
		(start 320.72326 -398.144746)
		(end 320.8401 -398.261586)
		(width 0.14224)
		(layer "In4.Cu")
		(net "P5E_CPU0_P0_TX_BUF_DP<14>")
	)
	(segment
		(start 343.033858 -409.15717)
		(end 343.444322 -409.327096)
		(width 0.14224)
		(layer "In4.Cu")
		(net "P5E_CPU0_P0_TX_BUF_DP<14>")
	)
	(segment
		(start 347.067886 -411.62478)
		(end 347.100398 -411.657292)
		(width 0.14224)
		(layer "In4.Cu")
		(net "P5E_CPU0_P0_TX_BUF_DP<14>")
	)
	(segment
		(start 321.391026 -402.552154)
		(end 321.607688 -402.768816)
		(width 0.14224)
		(layer "In4.Cu")
		(net "P5E_CPU0_P0_TX_BUF_DP<14>")
	)
	(segment
		(start 320.5988 -397.817848)
		(end 320.5988 -397.844264)
		(width 0.14224)
		(layer "In4.Cu")
		(net "P5E_CPU0_P0_TX_BUF_DP<14>")
	)
	(segment
		(start 339.029548 -407.615898)
		(end 342.892634 -409.21559)
		(width 0.14224)
		(layer "In4.Cu")
		(net "P5E_CPU0_P0_TX_BUF_DP<14>")
	)
	(segment
		(start 322.806314 -403.087586)
		(end 322.972684 -402.988018)
		(width 0.14224)
		(layer "In4.Cu")
		(net "P5E_CPU0_P0_TX_BUF_DP<14>")
	)
	(segment
		(start 323.347334 -403.081744)
		(end 323.447156 -403.248368)
		(width 0.14224)
		(layer "In4.Cu")
		(net "P5E_CPU0_P0_TX_BUF_DP<14>")
	)
	(segment
		(start 342.892634 -409.21559)
		(end 343.033858 -409.15717)
		(width 0.14224)
		(layer "In4.Cu")
		(net "P5E_CPU0_P0_TX_BUF_DP<14>")
	)
	(segment
		(start 320.682112 -397.734536)
		(end 320.5988 -397.817848)
		(width 0.14224)
		(layer "In4.Cu")
		(net "P5E_CPU0_P0_TX_BUF_DP<14>")
	)
	(segment
		(start 325.60641 -403.64791)
		(end 325.981314 -403.741636)
		(width 0.14224)
		(layer "In4.Cu")
		(net "P5E_CPU0_P0_TX_BUF_DP<14>")
	)
	(segment
		(start 337.917282 -407.17343)
		(end 338.356956 -407.30678)
		(width 0.14224)
		(layer "In4.Cu")
		(net "P5E_CPU0_P0_TX_BUF_DP<14>")
	)
	(segment
		(start 343.444322 -409.327096)
		(end 343.502996 -409.468574)
		(width 0.14224)
		(layer "In4.Cu")
		(net "P5E_CPU0_P0_TX_BUF_DP<14>")
	)
	(segment
		(start 321.037966 -398.908778)
		(end 321.279012 -399.704306)
		(width 0.14224)
		(layer "In4.Cu")
		(net "P5E_CPU0_P0_TX_BUF_DP<14>")
	)
	(segment
		(start 337.791806 -407.240486)
		(end 337.917282 -407.17343)
		(width 0.14224)
		(layer "In4.Cu")
		(net "P5E_CPU0_P0_TX_BUF_DP<14>")
	)
	(segment
		(start 338.356956 -407.30678)
		(end 338.424012 -407.432256)
		(width 0.14224)
		(layer "In4.Cu")
		(net "P5E_CPU0_P0_TX_BUF_DP<14>")
	)
	(segment
		(start 326.081136 -403.90826)
		(end 330.23556 -404.948898)
		(width 0.14224)
		(layer "In4.Cu")
		(net "P5E_CPU0_P0_TX_BUF_DP<14>")
	)
	(segment
		(start 347.252036 -412.023306)
		(end 347.252036 -412.55569)
		(width 0.14224)
		(layer "In4.Cu")
		(net "P5E_CPU0_P0_TX_BUF_DP<14>")
	)
	(segment
		(start 321.66687 -402.802344)
		(end 322.806314 -403.087586)
		(width 0.14224)
		(layer "In4.Cu")
		(net "P5E_CPU0_P0_TX_BUF_DP<14>")
	)
	(segment
		(start 330.23556 -404.948898)
		(end 337.791806 -407.240486)
		(width 0.14224)
		(layer "In4.Cu")
		(net "P5E_CPU0_P0_TX_BUF_DP<14>")
	)
	(segment
		(start 343.502996 -409.468574)
		(end 344.391742 -409.83662)
		(width 0.14224)
		(layer "In4.Cu")
		(net "P5E_CPU0_P0_TX_BUF_DP<14>")
	)
	(arc
		(start 320.5988 -397.844264)
		(mid 320.631147 -398.006882)
		(end 320.72326 -398.144746)
		(width 0.14224)
		(layer "In4.Cu")
		(net "P5E_CPU0_P0_TX_BUF_DP<14>")
	)
	(arc
		(start 321.353688 -402.462238)
		(mid 321.36339 -402.510922)
		(end 321.391026 -402.552154)
		(width 0.14224)
		(layer "In4.Cu")
		(net "P5E_CPU0_P0_TX_BUF_DP<14>")
	)
	(arc
		(start 320.8401 -398.261586)
		(mid 320.957582 -398.437177)
		(end 320.99885 -398.644364)
		(width 0.14224)
		(layer "In4.Cu")
		(net "P5E_CPU0_P0_TX_BUF_DP<14>")
	)
	(arc
		(start 344.391742 -409.83662)
		(mid 345.817886 -410.598891)
		(end 347.067886 -411.62478)
		(width 0.14224)
		(layer "In4.Cu")
		(net "P5E_CPU0_P0_TX_BUF_DP<14>")
	)
	(arc
		(start 321.279012 -399.704306)
		(mid 321.334908 -399.953523)
		(end 321.353688 -400.208242)
		(width 0.14224)
		(layer "In4.Cu")
		(net "P5E_CPU0_P0_TX_BUF_DP<14>")
	)
	(arc
		(start 347.100398 -411.657292)
		(mid 347.212604 -411.825221)
		(end 347.252036 -412.023306)
		(width 0.14224)
		(layer "In4.Cu")
		(net "P5E_CPU0_P0_TX_BUF_DP<14>")
	)
	(arc
		(start 320.99885 -398.644364)
		(mid 321.008645 -398.778015)
		(end 321.037966 -398.908778)
		(width 0.14224)
		(layer "In4.Cu")
		(net "P5E_CPU0_P0_TX_BUF_DP<14>")
	)
	(arc
		(start 321.607688 -402.768816)
		(mid 321.635002 -402.789598)
		(end 321.66687 -402.802344)
		(width 0.14224)
		(layer "In4.Cu")
		(net "P5E_CPU0_P0_TX_BUF_DP<14>")
	)
	(segment
		(start 344.209116 -413.11703)
		(end 344.479626 -412.84652)
		(width 0.12954)
		(layer "F.Cu")
		(net "P5E_CPU0_P0_TX_BUF_DP<13>")
	)
	(segment
		(start 344.209116 -416.336734)
		(end 344.209116 -413.11703)
		(width 0.12954)
		(layer "F.Cu")
		(net "P5E_CPU0_P0_TX_BUF_DP<13>")
	)
	(segment
		(start 344.505026 -416.632644)
		(end 344.209116 -416.336734)
		(width 0.12954)
		(layer "F.Cu")
		(net "P5E_CPU0_P0_TX_BUF_DP<13>")
	)
	(segment
		(start 319.27038 -397.849344)
		(end 319.79108 -397.849344)
		(width 0.127)
		(layer "F.Cu")
		(net "P5E_CPU0_P0_TX_BUF_DP<13>")
	)
	(segment
		(start 334.52943 -407.419556)
		(end 334.704944 -407.336752)
		(width 0.14224)
		(layer "In4.Cu")
		(net "P5E_CPU0_P0_TX_BUF_DP<13>")
	)
	(segment
		(start 334.704944 -407.336752)
		(end 335.106772 -407.480516)
		(width 0.14224)
		(layer "In4.Cu")
		(net "P5E_CPU0_P0_TX_BUF_DP<13>")
	)
	(segment
		(start 319.496186 -397.734536)
		(end 319.406778 -397.823944)
		(width 0.14224)
		(layer "In4.Cu")
		(net "P5E_CPU0_P0_TX_BUF_DP<13>")
	)
	(segment
		(start 339.267546 -409.115006)
		(end 339.71611 -409.275534)
		(width 0.14224)
		(layer "In4.Cu")
		(net "P5E_CPU0_P0_TX_BUF_DP<13>")
	)
	(segment
		(start 319.793112 -399.216372)
		(end 320.153538 -400.086576)
		(width 0.14224)
		(layer "In4.Cu")
		(net "P5E_CPU0_P0_TX_BUF_DP<13>")
	)
	(segment
		(start 335.18983 -407.65603)
		(end 338.607146 -408.878532)
		(width 0.14224)
		(layer "In4.Cu")
		(net "P5E_CPU0_P0_TX_BUF_DP<13>")
	)
	(segment
		(start 319.767458 -398.558512)
		(end 319.767458 -398.97939)
		(width 0.14224)
		(layer "In4.Cu")
		(net "P5E_CPU0_P0_TX_BUF_DP<13>")
	)
	(segment
		(start 338.607146 -408.878532)
		(end 338.782406 -408.795728)
		(width 0.14224)
		(layer "In4.Cu")
		(net "P5E_CPU0_P0_TX_BUF_DP<13>")
	)
	(segment
		(start 320.153538 -400.086576)
		(end 320.153538 -402.756878)
		(width 0.14224)
		(layer "In4.Cu")
		(net "P5E_CPU0_P0_TX_BUF_DP<13>")
	)
	(segment
		(start 321.194684 -403.647402)
		(end 326.362314 -404.94204)
		(width 0.14224)
		(layer "In4.Cu")
		(net "P5E_CPU0_P0_TX_BUF_DP<13>")
	)
	(segment
		(start 320.208656 -402.889974)
		(end 320.667634 -403.348952)
		(width 0.14224)
		(layer "In4.Cu")
		(net "P5E_CPU0_P0_TX_BUF_DP<13>")
	)
	(segment
		(start 341.283798 -409.836366)
		(end 343.380568 -410.704792)
		(width 0.14224)
		(layer "In4.Cu")
		(net "P5E_CPU0_P0_TX_BUF_DP<13>")
	)
	(segment
		(start 340.255352 -409.322524)
		(end 340.338156 -409.498038)
		(width 0.14224)
		(layer "In4.Cu")
		(net "P5E_CPU0_P0_TX_BUF_DP<13>")
	)
	(segment
		(start 339.71611 -409.275534)
		(end 339.891624 -409.192476)
		(width 0.14224)
		(layer "In4.Cu")
		(net "P5E_CPU0_P0_TX_BUF_DP<13>")
	)
	(segment
		(start 340.338156 -409.498038)
		(end 341.283798 -409.836366)
		(width 0.14224)
		(layer "In4.Cu")
		(net "P5E_CPU0_P0_TX_BUF_DP<13>")
	)
	(segment
		(start 319.79108 -397.849344)
		(end 319.676272 -397.734536)
		(width 0.14224)
		(layer "In4.Cu")
		(net "P5E_CPU0_P0_TX_BUF_DP<13>")
	)
	(segment
		(start 326.362314 -404.94204)
		(end 334.52943 -407.419556)
		(width 0.14224)
		(layer "In4.Cu")
		(net "P5E_CPU0_P0_TX_BUF_DP<13>")
	)
	(segment
		(start 344.188796 -412.55569)
		(end 344.479626 -412.84652)
		(width 0.14224)
		(layer "In4.Cu")
		(net "P5E_CPU0_P0_TX_BUF_DP<13>")
	)
	(segment
		(start 319.793112 -399.150586)
		(end 319.793112 -399.216372)
		(width 0.14224)
		(layer "In4.Cu")
		(net "P5E_CPU0_P0_TX_BUF_DP<13>")
	)
	(segment
		(start 335.106772 -407.480516)
		(end 335.18983 -407.65603)
		(width 0.14224)
		(layer "In4.Cu")
		(net "P5E_CPU0_P0_TX_BUF_DP<13>")
	)
	(segment
		(start 343.839546 -411.011624)
		(end 343.92743 -411.099508)
		(width 0.14224)
		(layer "In4.Cu")
		(net "P5E_CPU0_P0_TX_BUF_DP<13>")
	)
	(segment
		(start 319.406778 -397.823944)
		(end 319.406778 -397.912844)
		(width 0.14224)
		(layer "In4.Cu")
		(net "P5E_CPU0_P0_TX_BUF_DP<13>")
	)
	(segment
		(start 319.488312 -398.109694)
		(end 319.64757 -398.268952)
		(width 0.14224)
		(layer "In4.Cu")
		(net "P5E_CPU0_P0_TX_BUF_DP<13>")
	)
	(segment
		(start 319.676272 -397.734536)
		(end 319.496186 -397.734536)
		(width 0.14224)
		(layer "In4.Cu")
		(net "P5E_CPU0_P0_TX_BUF_DP<13>")
	)
	(segment
		(start 339.184488 -408.939492)
		(end 339.267546 -409.115006)
		(width 0.14224)
		(layer "In4.Cu")
		(net "P5E_CPU0_P0_TX_BUF_DP<13>")
	)
	(segment
		(start 339.891624 -409.192476)
		(end 340.255352 -409.322524)
		(width 0.14224)
		(layer "In4.Cu")
		(net "P5E_CPU0_P0_TX_BUF_DP<13>")
	)
	(segment
		(start 344.188796 -411.730444)
		(end 344.188796 -412.55569)
		(width 0.14224)
		(layer "In4.Cu")
		(net "P5E_CPU0_P0_TX_BUF_DP<13>")
	)
	(segment
		(start 338.782406 -408.795728)
		(end 339.184488 -408.939492)
		(width 0.14224)
		(layer "In4.Cu")
		(net "P5E_CPU0_P0_TX_BUF_DP<13>")
	)
	(arc
		(start 320.667634 -403.348952)
		(mid 320.910908 -403.533927)
		(end 321.194684 -403.647402)
		(width 0.14224)
		(layer "In4.Cu")
		(net "P5E_CPU0_P0_TX_BUF_DP<13>")
	)
	(arc
		(start 319.767458 -398.97939)
		(mid 319.773956 -399.065938)
		(end 319.793112 -399.150586)
		(width 0.14224)
		(layer "In4.Cu")
		(net "P5E_CPU0_P0_TX_BUF_DP<13>")
	)
	(arc
		(start 343.92743 -411.099508)
		(mid 344.120852 -411.388984)
		(end 344.188796 -411.730444)
		(width 0.14224)
		(layer "In4.Cu")
		(net "P5E_CPU0_P0_TX_BUF_DP<13>")
	)
	(arc
		(start 319.64757 -398.268952)
		(mid 319.736285 -398.401817)
		(end 319.767458 -398.558512)
		(width 0.14224)
		(layer "In4.Cu")
		(net "P5E_CPU0_P0_TX_BUF_DP<13>")
	)
	(arc
		(start 320.153538 -402.756878)
		(mid 320.167865 -402.828904)
		(end 320.208656 -402.889974)
		(width 0.14224)
		(layer "In4.Cu")
		(net "P5E_CPU0_P0_TX_BUF_DP<13>")
	)
	(arc
		(start 343.380568 -410.704792)
		(mid 343.625164 -410.835608)
		(end 343.839546 -411.011624)
		(width 0.14224)
		(layer "In4.Cu")
		(net "P5E_CPU0_P0_TX_BUF_DP<13>")
	)
	(arc
		(start 319.406778 -397.912844)
		(mid 319.427969 -398.019377)
		(end 319.488312 -398.109694)
		(width 0.14224)
		(layer "In4.Cu")
		(net "P5E_CPU0_P0_TX_BUF_DP<13>")
	)
	(segment
		(start 341.441786 -416.632644)
		(end 341.145876 -416.336734)
		(width 0.12954)
		(layer "F.Cu")
		(net "P5E_CPU0_P0_TX_BUF_DP<12>")
	)
	(segment
		(start 318.07023 -397.849344)
		(end 318.59093 -397.849344)
		(width 0.127)
		(layer "F.Cu")
		(net "P5E_CPU0_P0_TX_BUF_DP<12>")
	)
	(segment
		(start 341.145876 -413.11703)
		(end 341.416386 -412.84652)
		(width 0.12954)
		(layer "F.Cu")
		(net "P5E_CPU0_P0_TX_BUF_DP<12>")
	)
	(segment
		(start 341.145876 -416.336734)
		(end 341.145876 -413.11703)
		(width 0.12954)
		(layer "F.Cu")
		(net "P5E_CPU0_P0_TX_BUF_DP<12>")
	)
	(segment
		(start 325.86422 -405.82215)
		(end 335.222342 -408.661108)
		(width 0.14224)
		(layer "In4.Cu")
		(net "P5E_CPU0_P0_TX_BUF_DP<12>")
	)
	(segment
		(start 318.59093 -397.849344)
		(end 318.476122 -397.734536)
		(width 0.14224)
		(layer "In4.Cu")
		(net "P5E_CPU0_P0_TX_BUF_DP<12>")
	)
	(segment
		(start 318.591946 -398.968468)
		(end 318.907414 -399.730722)
		(width 0.14224)
		(layer "In4.Cu")
		(net "P5E_CPU0_P0_TX_BUF_DP<12>")
	)
	(segment
		(start 335.222342 -408.661108)
		(end 338.53882 -410.03474)
		(width 0.14224)
		(layer "In4.Cu")
		(net "P5E_CPU0_P0_TX_BUF_DP<12>")
	)
	(segment
		(start 341.125556 -411.481016)
		(end 341.125556 -412.55569)
		(width 0.14224)
		(layer "In4.Cu")
		(net "P5E_CPU0_P0_TX_BUF_DP<12>")
	)
	(segment
		(start 340.87562 -411.03677)
		(end 340.988142 -411.149292)
		(width 0.14224)
		(layer "In4.Cu")
		(net "P5E_CPU0_P0_TX_BUF_DP<12>")
	)
	(segment
		(start 318.567308 -398.558512)
		(end 318.567308 -398.845024)
		(width 0.14224)
		(layer "In4.Cu")
		(net "P5E_CPU0_P0_TX_BUF_DP<12>")
	)
	(segment
		(start 339.112352 -410.123894)
		(end 339.186774 -410.303472)
		(width 0.14224)
		(layer "In4.Cu")
		(net "P5E_CPU0_P0_TX_BUF_DP<12>")
	)
	(segment
		(start 318.24422 -398.06372)
		(end 318.445896 -398.265396)
		(width 0.14224)
		(layer "In4.Cu")
		(net "P5E_CPU0_P0_TX_BUF_DP<12>")
	)
	(segment
		(start 340.154514 -410.555694)
		(end 340.228682 -410.735272)
		(width 0.14224)
		(layer "In4.Cu")
		(net "P5E_CPU0_P0_TX_BUF_DP<12>")
	)
	(segment
		(start 341.125556 -412.55569)
		(end 341.416386 -412.84652)
		(width 0.14224)
		(layer "In4.Cu")
		(net "P5E_CPU0_P0_TX_BUF_DP<12>")
	)
	(segment
		(start 338.53882 -410.034994)
		(end 338.71789 -409.960572)
		(width 0.14224)
		(layer "In4.Cu")
		(net "P5E_CPU0_P0_TX_BUF_DP<12>")
	)
	(segment
		(start 319.750948 -404.029164)
		(end 319.94475 -404.222966)
		(width 0.14224)
		(layer "In4.Cu")
		(net "P5E_CPU0_P0_TX_BUF_DP<12>")
	)
	(segment
		(start 339.186774 -410.303472)
		(end 339.580982 -410.46654)
		(width 0.14224)
		(layer "In4.Cu")
		(net "P5E_CPU0_P0_TX_BUF_DP<12>")
	)
	(segment
		(start 320.311018 -404.430484)
		(end 325.86422 -405.82215)
		(width 0.14224)
		(layer "In4.Cu")
		(net "P5E_CPU0_P0_TX_BUF_DP<12>")
	)
	(segment
		(start 339.760052 -410.392372)
		(end 340.154514 -410.555694)
		(width 0.14224)
		(layer "In4.Cu")
		(net "P5E_CPU0_P0_TX_BUF_DP<12>")
	)
	(segment
		(start 319.049908 -403.328124)
		(end 319.254886 -403.533102)
		(width 0.14224)
		(layer "In4.Cu")
		(net "P5E_CPU0_P0_TX_BUF_DP<12>")
	)
	(segment
		(start 319.254886 -403.533102)
		(end 319.448942 -403.533102)
		(width 0.14224)
		(layer "In4.Cu")
		(net "P5E_CPU0_P0_TX_BUF_DP<12>")
	)
	(segment
		(start 338.71789 -409.960572)
		(end 339.112352 -410.123894)
		(width 0.14224)
		(layer "In4.Cu")
		(net "P5E_CPU0_P0_TX_BUF_DP<12>")
	)
	(segment
		(start 318.476122 -397.734536)
		(end 318.313054 -397.734536)
		(width 0.14224)
		(layer "In4.Cu")
		(net "P5E_CPU0_P0_TX_BUF_DP<12>")
	)
	(segment
		(start 318.206882 -397.840708)
		(end 318.206882 -397.973804)
		(width 0.14224)
		(layer "In4.Cu")
		(net "P5E_CPU0_P0_TX_BUF_DP<12>")
	)
	(segment
		(start 319.750948 -403.835108)
		(end 319.750948 -404.029164)
		(width 0.14224)
		(layer "In4.Cu")
		(net "P5E_CPU0_P0_TX_BUF_DP<12>")
	)
	(segment
		(start 318.953388 -399.961608)
		(end 318.953388 -403.095206)
		(width 0.14224)
		(layer "In4.Cu")
		(net "P5E_CPU0_P0_TX_BUF_DP<12>")
	)
	(segment
		(start 338.53882 -410.03474)
		(end 338.53882 -410.034994)
		(width 0.14224)
		(layer "In4.Cu")
		(net "P5E_CPU0_P0_TX_BUF_DP<12>")
	)
	(segment
		(start 340.228682 -410.734764)
		(end 340.742778 -410.94787)
		(width 0.14224)
		(layer "In4.Cu")
		(net "P5E_CPU0_P0_TX_BUF_DP<12>")
	)
	(segment
		(start 339.580982 -410.46654)
		(end 339.760052 -410.392372)
		(width 0.14224)
		(layer "In4.Cu")
		(net "P5E_CPU0_P0_TX_BUF_DP<12>")
	)
	(segment
		(start 340.228682 -410.735272)
		(end 340.228682 -410.734764)
		(width 0.14224)
		(layer "In4.Cu")
		(net "P5E_CPU0_P0_TX_BUF_DP<12>")
	)
	(segment
		(start 319.448942 -403.533102)
		(end 319.750948 -403.835108)
		(width 0.14224)
		(layer "In4.Cu")
		(net "P5E_CPU0_P0_TX_BUF_DP<12>")
	)
	(segment
		(start 318.313054 -397.734536)
		(end 318.206882 -397.840708)
		(width 0.14224)
		(layer "In4.Cu")
		(net "P5E_CPU0_P0_TX_BUF_DP<12>")
	)
	(arc
		(start 318.953388 -403.095206)
		(mid 318.97848 -403.221262)
		(end 319.049908 -403.328124)
		(width 0.14224)
		(layer "In4.Cu")
		(net "P5E_CPU0_P0_TX_BUF_DP<12>")
	)
	(arc
		(start 319.94475 -404.222966)
		(mid 320.113797 -404.351586)
		(end 320.311018 -404.430484)
		(width 0.14224)
		(layer "In4.Cu")
		(net "P5E_CPU0_P0_TX_BUF_DP<12>")
	)
	(arc
		(start 340.988142 -411.149292)
		(mid 341.089836 -411.301488)
		(end 341.125556 -411.481016)
		(width 0.14224)
		(layer "In4.Cu")
		(net "P5E_CPU0_P0_TX_BUF_DP<12>")
	)
	(arc
		(start 318.907414 -399.730722)
		(mid 318.941745 -399.843905)
		(end 318.953388 -399.961608)
		(width 0.14224)
		(layer "In4.Cu")
		(net "P5E_CPU0_P0_TX_BUF_DP<12>")
	)
	(arc
		(start 318.445896 -398.265396)
		(mid 318.535755 -398.399879)
		(end 318.567308 -398.558512)
		(width 0.14224)
		(layer "In4.Cu")
		(net "P5E_CPU0_P0_TX_BUF_DP<12>")
	)
	(arc
		(start 318.206882 -397.973804)
		(mid 318.216584 -398.022488)
		(end 318.24422 -398.06372)
		(width 0.14224)
		(layer "In4.Cu")
		(net "P5E_CPU0_P0_TX_BUF_DP<12>")
	)
	(arc
		(start 318.567308 -398.845024)
		(mid 318.573557 -398.907957)
		(end 318.591946 -398.968468)
		(width 0.14224)
		(layer "In4.Cu")
		(net "P5E_CPU0_P0_TX_BUF_DP<12>")
	)
	(arc
		(start 340.742778 -410.94787)
		(mid 340.81359 -410.985762)
		(end 340.87562 -411.03677)
		(width 0.14224)
		(layer "In4.Cu")
		(net "P5E_CPU0_P0_TX_BUF_DP<12>")
	)
	(segment
		(start 316.870334 -397.849344)
		(end 317.391034 -397.849344)
		(width 0.127)
		(layer "F.Cu")
		(net "P5E_CPU0_P0_TX_BUF_DP<11>")
	)
	(segment
		(start 338.082636 -416.336734)
		(end 338.082636 -413.11703)
		(width 0.12954)
		(layer "F.Cu")
		(net "P5E_CPU0_P0_TX_BUF_DP<11>")
	)
	(segment
		(start 338.082636 -413.11703)
		(end 338.353146 -412.84652)
		(width 0.12954)
		(layer "F.Cu")
		(net "P5E_CPU0_P0_TX_BUF_DP<11>")
	)
	(segment
		(start 338.378546 -416.632644)
		(end 338.082636 -416.336734)
		(width 0.12954)
		(layer "F.Cu")
		(net "P5E_CPU0_P0_TX_BUF_DP<11>")
	)
	(segment
		(start 317.9064 -403.961346)
		(end 318.082676 -404.137622)
		(width 0.14224)
		(layer "In4.Cu")
		(net "P5E_CPU0_P0_TX_BUF_DP<11>")
	)
	(segment
		(start 318.578738 -404.633684)
		(end 318.941704 -404.99665)
		(width 0.14224)
		(layer "In4.Cu")
		(net "P5E_CPU0_P0_TX_BUF_DP<11>")
	)
	(segment
		(start 317.391034 -397.849344)
		(end 317.276226 -397.734536)
		(width 0.14224)
		(layer "In4.Cu")
		(net "P5E_CPU0_P0_TX_BUF_DP<11>")
	)
	(segment
		(start 318.276732 -404.137622)
		(end 318.578738 -404.439628)
		(width 0.14224)
		(layer "In4.Cu")
		(net "P5E_CPU0_P0_TX_BUF_DP<11>")
	)
	(segment
		(start 317.006732 -397.823944)
		(end 317.006732 -397.889476)
		(width 0.14224)
		(layer "In4.Cu")
		(net "P5E_CPU0_P0_TX_BUF_DP<11>")
	)
	(segment
		(start 324.085458 -406.35047)
		(end 333.88046 -409.322016)
		(width 0.14224)
		(layer "In4.Cu")
		(net "P5E_CPU0_P0_TX_BUF_DP<11>")
	)
	(segment
		(start 317.373 -399.085054)
		(end 317.753492 -400.004026)
		(width 0.14224)
		(layer "In4.Cu")
		(net "P5E_CPU0_P0_TX_BUF_DP<11>")
	)
	(segment
		(start 334.98409 -409.779216)
		(end 335.76641 -410.10332)
		(width 0.14224)
		(layer "In4.Cu")
		(net "P5E_CPU0_P0_TX_BUF_DP<11>")
	)
	(segment
		(start 334.453738 -409.410916)
		(end 334.8482 -409.574238)
		(width 0.14224)
		(layer "In4.Cu")
		(net "P5E_CPU0_P0_TX_BUF_DP<11>")
	)
	(segment
		(start 318.082676 -404.137622)
		(end 318.276732 -404.137622)
		(width 0.14224)
		(layer "In4.Cu")
		(net "P5E_CPU0_P0_TX_BUF_DP<11>")
	)
	(segment
		(start 333.88046 -409.322016)
		(end 334.083914 -409.406344)
		(width 0.14224)
		(layer "In4.Cu")
		(net "P5E_CPU0_P0_TX_BUF_DP<11>")
	)
	(segment
		(start 338.062316 -412.55569)
		(end 338.353146 -412.84652)
		(width 0.14224)
		(layer "In4.Cu")
		(net "P5E_CPU0_P0_TX_BUF_DP<11>")
	)
	(segment
		(start 317.104776 -398.126204)
		(end 317.247524 -398.268952)
		(width 0.14224)
		(layer "In4.Cu")
		(net "P5E_CPU0_P0_TX_BUF_DP<11>")
	)
	(segment
		(start 317.753492 -400.004026)
		(end 317.753492 -403.592538)
		(width 0.14224)
		(layer "In4.Cu")
		(net "P5E_CPU0_P0_TX_BUF_DP<11>")
	)
	(segment
		(start 318.578738 -404.439628)
		(end 318.578738 -404.633684)
		(width 0.14224)
		(layer "In4.Cu")
		(net "P5E_CPU0_P0_TX_BUF_DP<11>")
	)
	(segment
		(start 317.09614 -397.734536)
		(end 317.006732 -397.823944)
		(width 0.14224)
		(layer "In4.Cu")
		(net "P5E_CPU0_P0_TX_BUF_DP<11>")
	)
	(segment
		(start 317.276226 -397.734536)
		(end 317.09614 -397.734536)
		(width 0.14224)
		(layer "In4.Cu")
		(net "P5E_CPU0_P0_TX_BUF_DP<11>")
	)
	(segment
		(start 334.8482 -409.574238)
		(end 334.896968 -409.692094)
		(width 0.14224)
		(layer "In4.Cu")
		(net "P5E_CPU0_P0_TX_BUF_DP<11>")
	)
	(segment
		(start 334.083914 -409.406344)
		(end 334.274668 -409.485084)
		(width 0.14224)
		(layer "In4.Cu")
		(net "P5E_CPU0_P0_TX_BUF_DP<11>")
	)
	(segment
		(start 336.377026 -410.35605)
		(end 337.711288 -410.908754)
		(width 0.14224)
		(layer "In4.Cu")
		(net "P5E_CPU0_P0_TX_BUF_DP<11>")
	)
	(segment
		(start 338.062316 -411.492192)
		(end 338.062316 -412.55569)
		(width 0.14224)
		(layer "In4.Cu")
		(net "P5E_CPU0_P0_TX_BUF_DP<11>")
	)
	(segment
		(start 334.274668 -409.485084)
		(end 334.453738 -409.410916)
		(width 0.14224)
		(layer "In4.Cu")
		(net "P5E_CPU0_P0_TX_BUF_DP<11>")
	)
	(segment
		(start 336.302604 -410.176726)
		(end 336.377026 -410.35605)
		(width 0.14224)
		(layer "In4.Cu")
		(net "P5E_CPU0_P0_TX_BUF_DP<11>")
	)
	(segment
		(start 319.150746 -405.115014)
		(end 324.085458 -406.35047)
		(width 0.14224)
		(layer "In4.Cu")
		(net "P5E_CPU0_P0_TX_BUF_DP<11>")
	)
	(segment
		(start 317.367412 -398.558512)
		(end 317.367412 -399.048224)
		(width 0.14224)
		(layer "In4.Cu")
		(net "P5E_CPU0_P0_TX_BUF_DP<11>")
	)
	(segment
		(start 335.945734 -410.028898)
		(end 336.302604 -410.176726)
		(width 0.14224)
		(layer "In4.Cu")
		(net "P5E_CPU0_P0_TX_BUF_DP<11>")
	)
	(segment
		(start 335.76641 -410.10332)
		(end 335.945734 -410.028898)
		(width 0.14224)
		(layer "In4.Cu")
		(net "P5E_CPU0_P0_TX_BUF_DP<11>")
	)
	(arc
		(start 317.753492 -403.592538)
		(mid 317.793235 -403.792162)
		(end 317.9064 -403.961346)
		(width 0.14224)
		(layer "In4.Cu")
		(net "P5E_CPU0_P0_TX_BUF_DP<11>")
	)
	(arc
		(start 334.896968 -409.692094)
		(mid 334.931854 -409.74433)
		(end 334.98409 -409.779216)
		(width 0.14224)
		(layer "In4.Cu")
		(net "P5E_CPU0_P0_TX_BUF_DP<11>")
	)
	(arc
		(start 337.934808 -411.089602)
		(mid 338.028319 -411.281469)
		(end 338.062316 -411.492192)
		(width 0.14224)
		(layer "In4.Cu")
		(net "P5E_CPU0_P0_TX_BUF_DP<11>")
	)
	(arc
		(start 317.006732 -397.889476)
		(mid 317.032215 -398.017588)
		(end 317.104776 -398.126204)
		(width 0.14224)
		(layer "In4.Cu")
		(net "P5E_CPU0_P0_TX_BUF_DP<11>")
	)
	(arc
		(start 318.941704 -404.99665)
		(mid 319.03818 -405.070041)
		(end 319.150746 -405.115014)
		(width 0.14224)
		(layer "In4.Cu")
		(net "P5E_CPU0_P0_TX_BUF_DP<11>")
	)
	(arc
		(start 337.711288 -410.908754)
		(mid 337.83618 -410.982941)
		(end 337.934808 -411.089602)
		(width 0.14224)
		(layer "In4.Cu")
		(net "P5E_CPU0_P0_TX_BUF_DP<11>")
	)
	(arc
		(start 317.247524 -398.268952)
		(mid 317.336239 -398.401817)
		(end 317.367412 -398.558512)
		(width 0.14224)
		(layer "In4.Cu")
		(net "P5E_CPU0_P0_TX_BUF_DP<11>")
	)
	(arc
		(start 317.367412 -399.048224)
		(mid 317.368857 -399.066843)
		(end 317.373 -399.085054)
		(width 0.14224)
		(layer "In4.Cu")
		(net "P5E_CPU0_P0_TX_BUF_DP<11>")
	)
	(segment
		(start 335.019396 -413.11703)
		(end 335.289906 -412.84652)
		(width 0.12954)
		(layer "F.Cu")
		(net "P5E_CPU0_P0_TX_BUF_DP<10>")
	)
	(segment
		(start 315.670438 -397.849344)
		(end 316.191138 -397.849344)
		(width 0.127)
		(layer "F.Cu")
		(net "P5E_CPU0_P0_TX_BUF_DP<10>")
	)
	(segment
		(start 335.019396 -416.336734)
		(end 335.019396 -413.11703)
		(width 0.12954)
		(layer "F.Cu")
		(net "P5E_CPU0_P0_TX_BUF_DP<10>")
	)
	(segment
		(start 335.315306 -416.632644)
		(end 335.019396 -416.336734)
		(width 0.12954)
		(layer "F.Cu")
		(net "P5E_CPU0_P0_TX_BUF_DP<10>")
	)
	(segment
		(start 334.82661 -411.4165)
		(end 334.82661 -411.610556)
		(width 0.14224)
		(layer "In4.Cu")
		(net "P5E_CPU0_P0_TX_BUF_DP<10>")
	)
	(segment
		(start 334.82661 -411.610556)
		(end 334.879188 -411.663134)
		(width 0.14224)
		(layer "In4.Cu")
		(net "P5E_CPU0_P0_TX_BUF_DP<10>")
	)
	(segment
		(start 315.896244 -397.734536)
		(end 315.806836 -397.823944)
		(width 0.14224)
		(layer "In4.Cu")
		(net "P5E_CPU0_P0_TX_BUF_DP<10>")
	)
	(segment
		(start 330.108052 -409.181808)
		(end 331.976984 -409.953714)
		(width 0.14224)
		(layer "In4.Cu")
		(net "P5E_CPU0_P0_TX_BUF_DP<10>")
	)
	(segment
		(start 334.35925 -411.143196)
		(end 334.553306 -411.143196)
		(width 0.14224)
		(layer "In4.Cu")
		(net "P5E_CPU0_P0_TX_BUF_DP<10>")
	)
	(segment
		(start 333.123286 -410.279088)
		(end 333.48041 -410.426662)
		(width 0.14224)
		(layer "In4.Cu")
		(net "P5E_CPU0_P0_TX_BUF_DP<10>")
	)
	(segment
		(start 332.5876 -410.20619)
		(end 332.944216 -410.35351)
		(width 0.14224)
		(layer "In4.Cu")
		(net "P5E_CPU0_P0_TX_BUF_DP<10>")
	)
	(segment
		(start 318.688974 -405.963628)
		(end 323.334126 -407.126948)
		(width 0.14224)
		(layer "In4.Cu")
		(net "P5E_CPU0_P0_TX_BUF_DP<10>")
	)
	(segment
		(start 323.334126 -407.126948)
		(end 330.108052 -409.181808)
		(width 0.14224)
		(layer "In4.Cu")
		(net "P5E_CPU0_P0_TX_BUF_DP<10>")
	)
	(segment
		(start 332.944216 -410.35351)
		(end 333.123286 -410.279088)
		(width 0.14224)
		(layer "In4.Cu")
		(net "P5E_CPU0_P0_TX_BUF_DP<10>")
	)
	(segment
		(start 316.07633 -397.734536)
		(end 315.896244 -397.734536)
		(width 0.14224)
		(layer "In4.Cu")
		(net "P5E_CPU0_P0_TX_BUF_DP<10>")
	)
	(segment
		(start 332.513178 -410.026866)
		(end 332.5876 -410.20619)
		(width 0.14224)
		(layer "In4.Cu")
		(net "P5E_CPU0_P0_TX_BUF_DP<10>")
	)
	(segment
		(start 316.19825 -399.2372)
		(end 316.515496 -400.003772)
		(width 0.14224)
		(layer "In4.Cu")
		(net "P5E_CPU0_P0_TX_BUF_DP<10>")
	)
	(segment
		(start 333.48041 -410.426662)
		(end 333.554832 -410.605986)
		(width 0.14224)
		(layer "In4.Cu")
		(net "P5E_CPU0_P0_TX_BUF_DP<10>")
	)
	(segment
		(start 331.976984 -409.953714)
		(end 332.156054 -409.879292)
		(width 0.14224)
		(layer "In4.Cu")
		(net "P5E_CPU0_P0_TX_BUF_DP<10>")
	)
	(segment
		(start 334.086454 -410.8704)
		(end 334.35925 -411.143196)
		(width 0.14224)
		(layer "In4.Cu")
		(net "P5E_CPU0_P0_TX_BUF_DP<10>")
	)
	(segment
		(start 316.515496 -400.003772)
		(end 316.515496 -403.572218)
		(width 0.14224)
		(layer "In4.Cu")
		(net "P5E_CPU0_P0_TX_BUF_DP<10>")
	)
	(segment
		(start 315.806836 -397.823944)
		(end 315.806836 -397.926814)
		(width 0.14224)
		(layer "In4.Cu")
		(net "P5E_CPU0_P0_TX_BUF_DP<10>")
	)
	(segment
		(start 316.808612 -404.279862)
		(end 318.235584 -405.706834)
		(width 0.14224)
		(layer "In4.Cu")
		(net "P5E_CPU0_P0_TX_BUF_DP<10>")
	)
	(segment
		(start 333.554832 -410.605986)
		(end 333.911448 -410.753306)
		(width 0.14224)
		(layer "In4.Cu")
		(net "P5E_CPU0_P0_TX_BUF_DP<10>")
	)
	(segment
		(start 316.191138 -397.849344)
		(end 316.07633 -397.734536)
		(width 0.14224)
		(layer "In4.Cu")
		(net "P5E_CPU0_P0_TX_BUF_DP<10>")
	)
	(segment
		(start 315.878718 -398.100042)
		(end 316.047628 -398.268698)
		(width 0.14224)
		(layer "In4.Cu")
		(net "P5E_CPU0_P0_TX_BUF_DP<10>")
	)
	(segment
		(start 334.999076 -412.55569)
		(end 335.289906 -412.84652)
		(width 0.14224)
		(layer "In4.Cu")
		(net "P5E_CPU0_P0_TX_BUF_DP<10>")
	)
	(segment
		(start 334.553306 -411.143196)
		(end 334.82661 -411.4165)
		(width 0.14224)
		(layer "In4.Cu")
		(net "P5E_CPU0_P0_TX_BUF_DP<10>")
	)
	(segment
		(start 332.156054 -409.879292)
		(end 332.513178 -410.026866)
		(width 0.14224)
		(layer "In4.Cu")
		(net "P5E_CPU0_P0_TX_BUF_DP<10>")
	)
	(segment
		(start 334.999076 -411.952694)
		(end 334.999076 -412.55569)
		(width 0.14224)
		(layer "In4.Cu")
		(net "P5E_CPU0_P0_TX_BUF_DP<10>")
	)
	(segment
		(start 316.167516 -398.558258)
		(end 316.167516 -399.083276)
		(width 0.14224)
		(layer "In4.Cu")
		(net "P5E_CPU0_P0_TX_BUF_DP<10>")
	)
	(arc
		(start 316.515496 -403.572218)
		(mid 316.591674 -403.955192)
		(end 316.808612 -404.279862)
		(width 0.14224)
		(layer "In4.Cu")
		(net "P5E_CPU0_P0_TX_BUF_DP<10>")
	)
	(arc
		(start 334.879188 -411.663134)
		(mid 334.967903 -411.795999)
		(end 334.999076 -411.952694)
		(width 0.14224)
		(layer "In4.Cu")
		(net "P5E_CPU0_P0_TX_BUF_DP<10>")
	)
	(arc
		(start 315.806836 -397.926814)
		(mid 315.825524 -398.020585)
		(end 315.878718 -398.100042)
		(width 0.14224)
		(layer "In4.Cu")
		(net "P5E_CPU0_P0_TX_BUF_DP<10>")
	)
	(arc
		(start 316.167516 -399.083276)
		(mid 316.17529 -399.161756)
		(end 316.19825 -399.2372)
		(width 0.14224)
		(layer "In4.Cu")
		(net "P5E_CPU0_P0_TX_BUF_DP<10>")
	)
	(arc
		(start 318.235584 -405.706834)
		(mid 318.444834 -405.866035)
		(end 318.688974 -405.963628)
		(width 0.14224)
		(layer "In4.Cu")
		(net "P5E_CPU0_P0_TX_BUF_DP<10>")
	)
	(arc
		(start 333.911448 -410.753306)
		(mid 334.004697 -410.803262)
		(end 334.086454 -410.8704)
		(width 0.14224)
		(layer "In4.Cu")
		(net "P5E_CPU0_P0_TX_BUF_DP<10>")
	)
	(arc
		(start 316.047628 -398.268698)
		(mid 316.136421 -398.401536)
		(end 316.167516 -398.558258)
		(width 0.14224)
		(layer "In4.Cu")
		(net "P5E_CPU0_P0_TX_BUF_DP<10>")
	)
	(segment
		(start 303.670462 -397.849344)
		(end 304.191162 -397.849344)
		(width 0.127)
		(layer "F.Cu")
		(net "P5E_CPU0_P0_TX_BUF_DP<0>")
	)
	(segment
		(start 304.386996 -413.11703)
		(end 304.657506 -412.84652)
		(width 0.12954)
		(layer "F.Cu")
		(net "P5E_CPU0_P0_TX_BUF_DP<0>")
	)
	(segment
		(start 304.386996 -416.336734)
		(end 304.386996 -413.11703)
		(width 0.12954)
		(layer "F.Cu")
		(net "P5E_CPU0_P0_TX_BUF_DP<0>")
	)
	(segment
		(start 304.682906 -416.632644)
		(end 304.386996 -416.336734)
		(width 0.12954)
		(layer "F.Cu")
		(net "P5E_CPU0_P0_TX_BUF_DP<0>")
	)
	(segment
		(start 304.69078 -407.947368)
		(end 304.55362 -408.084528)
		(width 0.14224)
		(layer "In4.Cu")
		(net "P5E_CPU0_P0_TX_BUF_DP<0>")
	)
	(segment
		(start 304.175414 -398.586706)
		(end 304.175414 -398.84223)
		(width 0.14224)
		(layer "In4.Cu")
		(net "P5E_CPU0_P0_TX_BUF_DP<0>")
	)
	(segment
		(start 304.55362 -400.091402)
		(end 304.55362 -402.74621)
		(width 0.14224)
		(layer "In4.Cu")
		(net "P5E_CPU0_P0_TX_BUF_DP<0>")
	)
	(segment
		(start 304.69078 -406.21077)
		(end 304.69078 -406.63749)
		(width 0.14224)
		(layer "In4.Cu")
		(net "P5E_CPU0_P0_TX_BUF_DP<0>")
	)
	(segment
		(start 304.55362 -406.77465)
		(end 304.55362 -407.383488)
		(width 0.14224)
		(layer "In4.Cu")
		(net "P5E_CPU0_P0_TX_BUF_DP<0>")
	)
	(segment
		(start 304.366676 -412.55569)
		(end 304.657506 -412.84652)
		(width 0.14224)
		(layer "In4.Cu")
		(net "P5E_CPU0_P0_TX_BUF_DP<0>")
	)
	(segment
		(start 304.55362 -407.383488)
		(end 304.69078 -407.520648)
		(width 0.14224)
		(layer "In4.Cu")
		(net "P5E_CPU0_P0_TX_BUF_DP<0>")
	)
	(segment
		(start 303.820576 -397.869156)
		(end 303.820576 -397.984472)
		(width 0.14224)
		(layer "In4.Cu")
		(net "P5E_CPU0_P0_TX_BUF_DP<0>")
	)
	(segment
		(start 304.69078 -406.63749)
		(end 304.55362 -406.77465)
		(width 0.14224)
		(layer "In4.Cu")
		(net "P5E_CPU0_P0_TX_BUF_DP<0>")
	)
	(segment
		(start 304.55362 -402.74621)
		(end 304.69078 -402.88337)
		(width 0.14224)
		(layer "In4.Cu")
		(net "P5E_CPU0_P0_TX_BUF_DP<0>")
	)
	(segment
		(start 304.55362 -406.07361)
		(end 304.69078 -406.21077)
		(width 0.14224)
		(layer "In4.Cu")
		(net "P5E_CPU0_P0_TX_BUF_DP<0>")
	)
	(segment
		(start 304.55362 -403.44725)
		(end 304.55362 -406.07361)
		(width 0.14224)
		(layer "In4.Cu")
		(net "P5E_CPU0_P0_TX_BUF_DP<0>")
	)
	(segment
		(start 304.69078 -407.520648)
		(end 304.69078 -407.947368)
		(width 0.14224)
		(layer "In4.Cu")
		(net "P5E_CPU0_P0_TX_BUF_DP<0>")
	)
	(segment
		(start 304.69078 -402.88337)
		(end 304.69078 -403.31009)
		(width 0.14224)
		(layer "In4.Cu")
		(net "P5E_CPU0_P0_TX_BUF_DP<0>")
	)
	(segment
		(start 304.366676 -411.568392)
		(end 304.366676 -412.55569)
		(width 0.14224)
		(layer "In4.Cu")
		(net "P5E_CPU0_P0_TX_BUF_DP<0>")
	)
	(segment
		(start 304.076354 -397.734536)
		(end 303.896268 -397.734536)
		(width 0.14224)
		(layer "In4.Cu")
		(net "P5E_CPU0_P0_TX_BUF_DP<0>")
	)
	(segment
		(start 304.55362 -411.117034)
		(end 304.366676 -411.568392)
		(width 0.14224)
		(layer "In4.Cu")
		(net "P5E_CPU0_P0_TX_BUF_DP<0>")
	)
	(segment
		(start 303.857914 -398.074642)
		(end 304.037746 -398.254474)
		(width 0.14224)
		(layer "In4.Cu")
		(net "P5E_CPU0_P0_TX_BUF_DP<0>")
	)
	(segment
		(start 304.69078 -403.31009)
		(end 304.55362 -403.44725)
		(width 0.14224)
		(layer "In4.Cu")
		(net "P5E_CPU0_P0_TX_BUF_DP<0>")
	)
	(segment
		(start 304.273458 -399.415508)
		(end 304.55362 -400.091402)
		(width 0.14224)
		(layer "In4.Cu")
		(net "P5E_CPU0_P0_TX_BUF_DP<0>")
	)
	(segment
		(start 304.55362 -408.084528)
		(end 304.55362 -411.117034)
		(width 0.14224)
		(layer "In4.Cu")
		(net "P5E_CPU0_P0_TX_BUF_DP<0>")
	)
	(segment
		(start 304.191162 -397.849344)
		(end 304.076354 -397.734536)
		(width 0.14224)
		(layer "In4.Cu")
		(net "P5E_CPU0_P0_TX_BUF_DP<0>")
	)
	(segment
		(start 303.896268 -397.734536)
		(end 303.862232 -397.768572)
		(width 0.14224)
		(layer "In4.Cu")
		(net "P5E_CPU0_P0_TX_BUF_DP<0>")
	)
	(arc
		(start 303.862232 -397.768572)
		(mid 303.831397 -397.81472)
		(end 303.820576 -397.869156)
		(width 0.14224)
		(layer "In4.Cu")
		(net "P5E_CPU0_P0_TX_BUF_DP<0>")
	)
	(arc
		(start 304.037746 -398.254474)
		(mid 304.139596 -398.406903)
		(end 304.175414 -398.586706)
		(width 0.14224)
		(layer "In4.Cu")
		(net "P5E_CPU0_P0_TX_BUF_DP<0>")
	)
	(arc
		(start 304.175414 -398.84223)
		(mid 304.177121 -398.905569)
		(end 304.182272 -398.968722)
		(width 0.14224)
		(layer "In4.Cu")
		(net "P5E_CPU0_P0_TX_BUF_DP<0>")
	)
	(arc
		(start 304.182272 -398.968722)
		(mid 304.217491 -399.194233)
		(end 304.273458 -399.415508)
		(width 0.14224)
		(layer "In4.Cu")
		(net "P5E_CPU0_P0_TX_BUF_DP<0>")
	)
	(arc
		(start 303.820576 -397.984472)
		(mid 303.830282 -398.033267)
		(end 303.857914 -398.074642)
		(width 0.14224)
		(layer "In4.Cu")
		(net "P5E_CPU0_P0_TX_BUF_DP<0>")
	)
	(segment
		(start 331.337666 -416.632644)
		(end 331.633576 -416.336734)
		(width 0.12954)
		(layer "F.Cu")
		(net "P5E_CPU0_P0_TX_BUF_DN<9>")
	)
	(segment
		(start 314.070238 -397.156432)
		(end 314.590938 -397.156432)
		(width 0.127)
		(layer "F.Cu")
		(net "P5E_CPU0_P0_TX_BUF_DN<9>")
	)
	(segment
		(start 331.633576 -416.336734)
		(end 331.633576 -413.11703)
		(width 0.12954)
		(layer "F.Cu")
		(net "P5E_CPU0_P0_TX_BUF_DN<9>")
	)
	(segment
		(start 331.633576 -413.11703)
		(end 331.363066 -412.84652)
		(width 0.12954)
		(layer "F.Cu")
		(net "P5E_CPU0_P0_TX_BUF_DN<9>")
	)
	(segment
		(start 331.295756 -411.611064)
		(end 331.61859 -411.947614)
		(width 0.14224)
		(layer "In4.Cu")
		(net "P5E_CPU0_P0_TX_BUF_DN<9>")
	)
	(segment
		(start 314.66155 -398.548606)
		(end 314.66155 -398.939004)
		(width 0.14224)
		(layer "In4.Cu")
		(net "P5E_CPU0_P0_TX_BUF_DN<9>")
	)
	(segment
		(start 330.182728 -410.888434)
		(end 330.92136 -411.367986)
		(width 0.14224)
		(layer "In4.Cu")
		(net "P5E_CPU0_P0_TX_BUF_DN<9>")
	)
	(segment
		(start 314.717176 -399.218404)
		(end 314.995306 -399.889218)
		(width 0.14224)
		(layer "In4.Cu")
		(net "P5E_CPU0_P0_TX_BUF_DN<9>")
	)
	(segment
		(start 319.896744 -407.51887)
		(end 322.020438 -408.051)
		(width 0.14224)
		(layer "In4.Cu")
		(net "P5E_CPU0_P0_TX_BUF_DN<9>")
	)
	(segment
		(start 330.92136 -411.367986)
		(end 330.921868 -411.36824)
		(width 0.14224)
		(layer "In4.Cu")
		(net "P5E_CPU0_P0_TX_BUF_DN<9>")
	)
	(segment
		(start 331.653896 -412.035752)
		(end 331.653896 -412.55569)
		(width 0.14224)
		(layer "In4.Cu")
		(net "P5E_CPU0_P0_TX_BUF_DN<9>")
	)
	(segment
		(start 315.019944 -400.012408)
		(end 315.019944 -403.807422)
		(width 0.14224)
		(layer "In4.Cu")
		(net "P5E_CPU0_P0_TX_BUF_DN<9>")
	)
	(segment
		(start 314.590938 -397.156432)
		(end 314.643262 -397.208756)
		(width 0.14224)
		(layer "In4.Cu")
		(net "P5E_CPU0_P0_TX_BUF_DN<9>")
	)
	(segment
		(start 331.653896 -412.55569)
		(end 331.363066 -412.84652)
		(width 0.14224)
		(layer "In4.Cu")
		(net "P5E_CPU0_P0_TX_BUF_DN<9>")
	)
	(segment
		(start 314.643262 -397.388588)
		(end 314.324746 -397.707104)
		(width 0.14224)
		(layer "In4.Cu")
		(net "P5E_CPU0_P0_TX_BUF_DN<9>")
	)
	(segment
		(start 330.921868 -411.36824)
		(end 331.295756 -411.611064)
		(width 0.14224)
		(layer "In4.Cu")
		(net "P5E_CPU0_P0_TX_BUF_DN<9>")
	)
	(segment
		(start 314.324746 -397.707104)
		(end 314.324746 -397.885412)
		(width 0.14224)
		(layer "In4.Cu")
		(net "P5E_CPU0_P0_TX_BUF_DN<9>")
	)
	(segment
		(start 324.933818 -408.934666)
		(end 329.705462 -410.651452)
		(width 0.14224)
		(layer "In4.Cu")
		(net "P5E_CPU0_P0_TX_BUF_DN<9>")
	)
	(segment
		(start 314.508388 -398.328642)
		(end 314.614306 -398.43456)
		(width 0.14224)
		(layer "In4.Cu")
		(net "P5E_CPU0_P0_TX_BUF_DN<9>")
	)
	(segment
		(start 318.625982 -407.26614)
		(end 319.896744 -407.51887)
		(width 0.14224)
		(layer "In4.Cu")
		(net "P5E_CPU0_P0_TX_BUF_DN<9>")
	)
	(segment
		(start 314.643262 -397.208756)
		(end 314.643262 -397.388588)
		(width 0.14224)
		(layer "In4.Cu")
		(net "P5E_CPU0_P0_TX_BUF_DN<9>")
	)
	(segment
		(start 322.020438 -408.051)
		(end 324.933818 -408.934666)
		(width 0.14224)
		(layer "In4.Cu")
		(net "P5E_CPU0_P0_TX_BUF_DN<9>")
	)
	(segment
		(start 315.429138 -404.677626)
		(end 317.319152 -406.56764)
		(width 0.14224)
		(layer "In4.Cu")
		(net "P5E_CPU0_P0_TX_BUF_DN<9>")
	)
	(arc
		(start 329.705462 -410.651452)
		(mid 329.950944 -410.756151)
		(end 330.182728 -410.888434)
		(width 0.14224)
		(layer "In4.Cu")
		(net "P5E_CPU0_P0_TX_BUF_DN<9>")
	)
	(arc
		(start 314.324746 -397.885412)
		(mid 314.372479 -398.125291)
		(end 314.508388 -398.328642)
		(width 0.14224)
		(layer "In4.Cu")
		(net "P5E_CPU0_P0_TX_BUF_DN<9>")
	)
	(arc
		(start 331.61859 -411.947614)
		(mid 331.644742 -411.988272)
		(end 331.653896 -412.035752)
		(width 0.14224)
		(layer "In4.Cu")
		(net "P5E_CPU0_P0_TX_BUF_DN<9>")
	)
	(arc
		(start 317.319152 -406.56764)
		(mid 317.920759 -407.013816)
		(end 318.625982 -407.26614)
		(width 0.14224)
		(layer "In4.Cu")
		(net "P5E_CPU0_P0_TX_BUF_DN<9>")
	)
	(arc
		(start 314.614306 -398.43456)
		(mid 314.649268 -398.486885)
		(end 314.66155 -398.548606)
		(width 0.14224)
		(layer "In4.Cu")
		(net "P5E_CPU0_P0_TX_BUF_DN<9>")
	)
	(arc
		(start 315.019944 -403.807422)
		(mid 315.024942 -403.897795)
		(end 315.040264 -403.987)
		(width 0.14224)
		(layer "In4.Cu")
		(net "P5E_CPU0_P0_TX_BUF_DN<9>")
	)
	(arc
		(start 314.66155 -398.939004)
		(mid 314.675592 -399.081446)
		(end 314.717176 -399.218404)
		(width 0.14224)
		(layer "In4.Cu")
		(net "P5E_CPU0_P0_TX_BUF_DN<9>")
	)
	(arc
		(start 314.995306 -399.889218)
		(mid 315.013685 -399.9496)
		(end 315.019944 -400.012408)
		(width 0.14224)
		(layer "In4.Cu")
		(net "P5E_CPU0_P0_TX_BUF_DN<9>")
	)
	(arc
		(start 315.040264 -403.987)
		(mid 315.187276 -404.359017)
		(end 315.429138 -404.677626)
		(width 0.14224)
		(layer "In4.Cu")
		(net "P5E_CPU0_P0_TX_BUF_DN<9>")
	)
	(segment
		(start 328.274426 -416.632644)
		(end 328.570336 -416.336734)
		(width 0.12954)
		(layer "F.Cu")
		(net "P5E_CPU0_P0_TX_BUF_DN<8>")
	)
	(segment
		(start 312.870342 -397.156432)
		(end 313.391042 -397.156432)
		(width 0.127)
		(layer "F.Cu")
		(net "P5E_CPU0_P0_TX_BUF_DN<8>")
	)
	(segment
		(start 328.570336 -413.11703)
		(end 328.299826 -412.84652)
		(width 0.12954)
		(layer "F.Cu")
		(net "P5E_CPU0_P0_TX_BUF_DN<8>")
	)
	(segment
		(start 328.570336 -416.336734)
		(end 328.570336 -413.11703)
		(width 0.12954)
		(layer "F.Cu")
		(net "P5E_CPU0_P0_TX_BUF_DN<8>")
	)
	(segment
		(start 328.590656 -412.55569)
		(end 328.299826 -412.84652)
		(width 0.14224)
		(layer "In4.Cu")
		(net "P5E_CPU0_P0_TX_BUF_DN<8>")
	)
	(segment
		(start 313.391042 -397.156432)
		(end 313.443366 -397.208756)
		(width 0.14224)
		(layer "In4.Cu")
		(net "P5E_CPU0_P0_TX_BUF_DN<8>")
	)
	(segment
		(start 313.283346 -398.303496)
		(end 313.448192 -398.468342)
		(width 0.14224)
		(layer "In4.Cu")
		(net "P5E_CPU0_P0_TX_BUF_DN<8>")
	)
	(segment
		(start 313.12485 -397.707104)
		(end 313.12485 -397.920972)
		(width 0.14224)
		(layer "In4.Cu")
		(net "P5E_CPU0_P0_TX_BUF_DN<8>")
	)
	(segment
		(start 322.317364 -409.128722)
		(end 323.691758 -409.546044)
		(width 0.14224)
		(layer "In4.Cu")
		(net "P5E_CPU0_P0_TX_BUF_DN<8>")
	)
	(segment
		(start 328.590656 -411.648402)
		(end 328.590656 -412.55569)
		(width 0.14224)
		(layer "In4.Cu")
		(net "P5E_CPU0_P0_TX_BUF_DN<8>")
	)
	(segment
		(start 313.443366 -397.388588)
		(end 313.12485 -397.707104)
		(width 0.14224)
		(layer "In4.Cu")
		(net "P5E_CPU0_P0_TX_BUF_DN<8>")
	)
	(segment
		(start 313.84748 -400.036538)
		(end 313.84748 -404.085552)
		(width 0.14224)
		(layer "In4.Cu")
		(net "P5E_CPU0_P0_TX_BUF_DN<8>")
	)
	(segment
		(start 325.13778 -410.06395)
		(end 328.49566 -411.454854)
		(width 0.14224)
		(layer "In4.Cu")
		(net "P5E_CPU0_P0_TX_BUF_DN<8>")
	)
	(segment
		(start 314.085732 -404.660862)
		(end 316.721998 -407.297128)
		(width 0.14224)
		(layer "In4.Cu")
		(net "P5E_CPU0_P0_TX_BUF_DN<8>")
	)
	(segment
		(start 318.339216 -408.161744)
		(end 319.56629 -408.405584)
		(width 0.14224)
		(layer "In4.Cu")
		(net "P5E_CPU0_P0_TX_BUF_DN<8>")
	)
	(segment
		(start 319.701926 -408.436064)
		(end 320.88963 -408.733498)
		(width 0.14224)
		(layer "In4.Cu")
		(net "P5E_CPU0_P0_TX_BUF_DN<8>")
	)
	(segment
		(start 313.48553 -398.558004)
		(end 313.48553 -398.986502)
		(width 0.14224)
		(layer "In4.Cu")
		(net "P5E_CPU0_P0_TX_BUF_DN<8>")
	)
	(segment
		(start 313.55284 -399.325338)
		(end 313.84748 -400.036538)
		(width 0.14224)
		(layer "In4.Cu")
		(net "P5E_CPU0_P0_TX_BUF_DN<8>")
	)
	(segment
		(start 313.443366 -397.208756)
		(end 313.443366 -397.388588)
		(width 0.14224)
		(layer "In4.Cu")
		(net "P5E_CPU0_P0_TX_BUF_DN<8>")
	)
	(arc
		(start 313.48553 -398.986502)
		(mid 313.502521 -399.15923)
		(end 313.55284 -399.325338)
		(width 0.14224)
		(layer "In4.Cu")
		(net "P5E_CPU0_P0_TX_BUF_DN<8>")
	)
	(arc
		(start 323.691758 -409.546044)
		(mid 324.421109 -409.787296)
		(end 325.13778 -410.06395)
		(width 0.14224)
		(layer "In4.Cu")
		(net "P5E_CPU0_P0_TX_BUF_DN<8>")
	)
	(arc
		(start 316.721998 -407.297128)
		(mid 317.466488 -407.849367)
		(end 318.339216 -408.161744)
		(width 0.14224)
		(layer "In4.Cu")
		(net "P5E_CPU0_P0_TX_BUF_DN<8>")
	)
	(arc
		(start 313.84748 -404.085552)
		(mid 313.909394 -404.396903)
		(end 314.085732 -404.660862)
		(width 0.14224)
		(layer "In4.Cu")
		(net "P5E_CPU0_P0_TX_BUF_DN<8>")
	)
	(arc
		(start 328.57821 -411.550104)
		(mid 328.58752 -411.598862)
		(end 328.590656 -411.648402)
		(width 0.14224)
		(layer "In4.Cu")
		(net "P5E_CPU0_P0_TX_BUF_DN<8>")
	)
	(arc
		(start 313.12485 -397.920972)
		(mid 313.166048 -398.127997)
		(end 313.283346 -398.303496)
		(width 0.14224)
		(layer "In4.Cu")
		(net "P5E_CPU0_P0_TX_BUF_DN<8>")
	)
	(arc
		(start 313.448192 -398.468342)
		(mid 313.475762 -398.509464)
		(end 313.48553 -398.558004)
		(width 0.14224)
		(layer "In4.Cu")
		(net "P5E_CPU0_P0_TX_BUF_DN<8>")
	)
	(arc
		(start 319.56629 -408.405584)
		(mid 319.634296 -408.419988)
		(end 319.701926 -408.436064)
		(width 0.14224)
		(layer "In4.Cu")
		(net "P5E_CPU0_P0_TX_BUF_DN<8>")
	)
	(arc
		(start 328.49566 -411.454854)
		(mid 328.548169 -411.492745)
		(end 328.57821 -411.550104)
		(width 0.14224)
		(layer "In4.Cu")
		(net "P5E_CPU0_P0_TX_BUF_DN<8>")
	)
	(arc
		(start 320.88963 -408.733498)
		(mid 321.60594 -408.922284)
		(end 322.317364 -409.128722)
		(width 0.14224)
		(layer "In4.Cu")
		(net "P5E_CPU0_P0_TX_BUF_DN<8>")
	)
	(segment
		(start 325.507096 -413.11703)
		(end 325.236586 -412.84652)
		(width 0.12954)
		(layer "F.Cu")
		(net "P5E_CPU0_P0_TX_BUF_DN<7>")
	)
	(segment
		(start 325.211186 -416.632644)
		(end 325.507096 -416.336734)
		(width 0.12954)
		(layer "F.Cu")
		(net "P5E_CPU0_P0_TX_BUF_DN<7>")
	)
	(segment
		(start 311.670446 -397.156432)
		(end 312.191146 -397.156432)
		(width 0.127)
		(layer "F.Cu")
		(net "P5E_CPU0_P0_TX_BUF_DN<7>")
	)
	(segment
		(start 325.507096 -416.336734)
		(end 325.507096 -413.11703)
		(width 0.12954)
		(layer "F.Cu")
		(net "P5E_CPU0_P0_TX_BUF_DN<7>")
	)
	(segment
		(start 312.35269 -399.38198)
		(end 312.671714 -400.152108)
		(width 0.14224)
		(layer "In4.Cu")
		(net "P5E_CPU0_P0_TX_BUF_DN<7>")
	)
	(segment
		(start 312.24347 -397.401796)
		(end 311.917842 -397.727424)
		(width 0.14224)
		(layer "In4.Cu")
		(net "P5E_CPU0_P0_TX_BUF_DN<7>")
	)
	(segment
		(start 312.306716 -398.627346)
		(end 312.306716 -399.15084)
		(width 0.14224)
		(layer "In4.Cu")
		(net "P5E_CPU0_P0_TX_BUF_DN<7>")
	)
	(segment
		(start 320.187066 -409.62453)
		(end 323.332348 -410.625544)
		(width 0.14224)
		(layer "In4.Cu")
		(net "P5E_CPU0_P0_TX_BUF_DN<7>")
	)
	(segment
		(start 312.671714 -400.152108)
		(end 312.671714 -404.308564)
		(width 0.14224)
		(layer "In4.Cu")
		(net "P5E_CPU0_P0_TX_BUF_DN<7>")
	)
	(segment
		(start 312.064654 -398.25676)
		(end 312.215784 -398.40789)
		(width 0.14224)
		(layer "In4.Cu")
		(net "P5E_CPU0_P0_TX_BUF_DN<7>")
	)
	(segment
		(start 323.850762 -410.79039)
		(end 323.851016 -410.790644)
		(width 0.14224)
		(layer "In4.Cu")
		(net "P5E_CPU0_P0_TX_BUF_DN<7>")
	)
	(segment
		(start 325.480172 -412.602934)
		(end 325.236586 -412.84652)
		(width 0.14224)
		(layer "In4.Cu")
		(net "P5E_CPU0_P0_TX_BUF_DN<7>")
	)
	(segment
		(start 312.857388 -404.75662)
		(end 316.098682 -407.997914)
		(width 0.14224)
		(layer "In4.Cu")
		(net "P5E_CPU0_P0_TX_BUF_DN<7>")
	)
	(segment
		(start 325.542656 -411.621986)
		(end 325.542656 -412.488888)
		(width 0.14224)
		(layer "In4.Cu")
		(net "P5E_CPU0_P0_TX_BUF_DN<7>")
	)
	(segment
		(start 323.332348 -410.625544)
		(end 323.332602 -410.625544)
		(width 0.14224)
		(layer "In4.Cu")
		(net "P5E_CPU0_P0_TX_BUF_DN<7>")
	)
	(segment
		(start 323.851016 -410.790644)
		(end 325.215504 -411.224984)
		(width 0.14224)
		(layer "In4.Cu")
		(net "P5E_CPU0_P0_TX_BUF_DN<7>")
	)
	(segment
		(start 318.083184 -409.06192)
		(end 320.187066 -409.62453)
		(width 0.14224)
		(layer "In4.Cu")
		(net "P5E_CPU0_P0_TX_BUF_DN<7>")
	)
	(segment
		(start 323.332602 -410.625544)
		(end 323.850762 -410.79039)
		(width 0.14224)
		(layer "In4.Cu")
		(net "P5E_CPU0_P0_TX_BUF_DN<7>")
	)
	(segment
		(start 325.266812 -411.256226)
		(end 325.479156 -411.46857)
		(width 0.14224)
		(layer "In4.Cu")
		(net "P5E_CPU0_P0_TX_BUF_DN<7>")
	)
	(segment
		(start 325.542656 -412.488888)
		(end 325.527416 -412.488888)
		(width 0.14224)
		(layer "In4.Cu")
		(net "P5E_CPU0_P0_TX_BUF_DN<7>")
	)
	(segment
		(start 312.24347 -397.208756)
		(end 312.24347 -397.401796)
		(width 0.14224)
		(layer "In4.Cu")
		(net "P5E_CPU0_P0_TX_BUF_DN<7>")
	)
	(segment
		(start 312.191146 -397.156432)
		(end 312.24347 -397.208756)
		(width 0.14224)
		(layer "In4.Cu")
		(net "P5E_CPU0_P0_TX_BUF_DN<7>")
	)
	(segment
		(start 311.917842 -397.727424)
		(end 311.917842 -397.90243)
		(width 0.14224)
		(layer "In4.Cu")
		(net "P5E_CPU0_P0_TX_BUF_DN<7>")
	)
	(arc
		(start 311.917842 -397.90243)
		(mid 311.956042 -398.094184)
		(end 312.064654 -398.25676)
		(width 0.14224)
		(layer "In4.Cu")
		(net "P5E_CPU0_P0_TX_BUF_DN<7>")
	)
	(arc
		(start 325.527416 -412.488888)
		(mid 325.515139 -412.550611)
		(end 325.480172 -412.602934)
		(width 0.14224)
		(layer "In4.Cu")
		(net "P5E_CPU0_P0_TX_BUF_DN<7>")
	)
	(arc
		(start 325.215504 -411.224984)
		(mid 325.243029 -411.237532)
		(end 325.266812 -411.256226)
		(width 0.14224)
		(layer "In4.Cu")
		(net "P5E_CPU0_P0_TX_BUF_DN<7>")
	)
	(arc
		(start 312.671714 -404.308564)
		(mid 312.719969 -404.551068)
		(end 312.857388 -404.75662)
		(width 0.14224)
		(layer "In4.Cu")
		(net "P5E_CPU0_P0_TX_BUF_DN<7>")
	)
	(arc
		(start 312.215784 -398.40789)
		(mid 312.283061 -398.508577)
		(end 312.306716 -398.627346)
		(width 0.14224)
		(layer "In4.Cu")
		(net "P5E_CPU0_P0_TX_BUF_DN<7>")
	)
	(arc
		(start 312.306716 -399.15084)
		(mid 312.318317 -399.268676)
		(end 312.35269 -399.38198)
		(width 0.14224)
		(layer "In4.Cu")
		(net "P5E_CPU0_P0_TX_BUF_DN<7>")
	)
	(arc
		(start 316.098682 -407.997914)
		(mid 317.012337 -408.676521)
		(end 318.083184 -409.06192)
		(width 0.14224)
		(layer "In4.Cu")
		(net "P5E_CPU0_P0_TX_BUF_DN<7>")
	)
	(arc
		(start 325.479156 -411.46857)
		(mid 325.526134 -411.538972)
		(end 325.542656 -411.621986)
		(width 0.14224)
		(layer "In4.Cu")
		(net "P5E_CPU0_P0_TX_BUF_DN<7>")
	)
	(segment
		(start 322.443856 -413.11703)
		(end 322.173346 -412.84652)
		(width 0.12954)
		(layer "F.Cu")
		(net "P5E_CPU0_P0_TX_BUF_DN<6>")
	)
	(segment
		(start 322.147946 -416.632644)
		(end 322.443856 -416.336734)
		(width 0.12954)
		(layer "F.Cu")
		(net "P5E_CPU0_P0_TX_BUF_DN<6>")
	)
	(segment
		(start 322.443856 -416.336734)
		(end 322.443856 -413.11703)
		(width 0.12954)
		(layer "F.Cu")
		(net "P5E_CPU0_P0_TX_BUF_DN<6>")
	)
	(segment
		(start 310.470296 -397.156432)
		(end 310.990996 -397.156432)
		(width 0.127)
		(layer "F.Cu")
		(net "P5E_CPU0_P0_TX_BUF_DN<6>")
	)
	(segment
		(start 311.085484 -398.572736)
		(end 311.085484 -399.172938)
		(width 0.14224)
		(layer "In4.Cu")
		(net "P5E_CPU0_P0_TX_BUF_DN<6>")
	)
	(segment
		(start 311.828434 -405.137366)
		(end 315.222128 -408.53106)
		(width 0.14224)
		(layer "In4.Cu")
		(net "P5E_CPU0_P0_TX_BUF_DN<6>")
	)
	(segment
		(start 322.464176 -412.55569)
		(end 322.173346 -412.84652)
		(width 0.14224)
		(layer "In4.Cu")
		(net "P5E_CPU0_P0_TX_BUF_DN<6>")
	)
	(segment
		(start 310.919368 -398.339818)
		(end 311.03824 -398.45869)
		(width 0.14224)
		(layer "In4.Cu")
		(net "P5E_CPU0_P0_TX_BUF_DN<6>")
	)
	(segment
		(start 311.04332 -397.388588)
		(end 310.724804 -397.707104)
		(width 0.14224)
		(layer "In4.Cu")
		(net "P5E_CPU0_P0_TX_BUF_DN<6>")
	)
	(segment
		(start 311.04332 -397.208756)
		(end 311.04332 -397.388588)
		(width 0.14224)
		(layer "In4.Cu")
		(net "P5E_CPU0_P0_TX_BUF_DN<6>")
	)
	(segment
		(start 317.827406 -410.007054)
		(end 318.73571 -410.234892)
		(width 0.14224)
		(layer "In4.Cu")
		(net "P5E_CPU0_P0_TX_BUF_DN<6>")
	)
	(segment
		(start 310.990996 -397.156432)
		(end 311.04332 -397.208756)
		(width 0.14224)
		(layer "In4.Cu")
		(net "P5E_CPU0_P0_TX_BUF_DN<6>")
	)
	(segment
		(start 311.471564 -400.186652)
		(end 311.471564 -404.275798)
		(width 0.14224)
		(layer "In4.Cu")
		(net "P5E_CPU0_P0_TX_BUF_DN<6>")
	)
	(segment
		(start 322.464176 -411.896052)
		(end 322.464176 -412.55569)
		(width 0.14224)
		(layer "In4.Cu")
		(net "P5E_CPU0_P0_TX_BUF_DN<6>")
	)
	(segment
		(start 318.73571 -410.234892)
		(end 322.306696 -411.663642)
		(width 0.14224)
		(layer "In4.Cu")
		(net "P5E_CPU0_P0_TX_BUF_DN<6>")
	)
	(segment
		(start 310.724804 -397.707104)
		(end 310.724804 -397.870172)
		(width 0.14224)
		(layer "In4.Cu")
		(net "P5E_CPU0_P0_TX_BUF_DN<6>")
	)
	(segment
		(start 311.116472 -399.329402)
		(end 311.471564 -400.186652)
		(width 0.14224)
		(layer "In4.Cu")
		(net "P5E_CPU0_P0_TX_BUF_DN<6>")
	)
	(arc
		(start 315.222128 -408.53106)
		(mid 316.424558 -409.44594)
		(end 317.827406 -410.007054)
		(width 0.14224)
		(layer "In4.Cu")
		(net "P5E_CPU0_P0_TX_BUF_DN<6>")
	)
	(arc
		(start 311.471564 -404.275798)
		(mid 311.564312 -404.742074)
		(end 311.828434 -405.137366)
		(width 0.14224)
		(layer "In4.Cu")
		(net "P5E_CPU0_P0_TX_BUF_DN<6>")
	)
	(arc
		(start 322.306696 -411.663642)
		(mid 322.421118 -411.755674)
		(end 322.464176 -411.896052)
		(width 0.14224)
		(layer "In4.Cu")
		(net "P5E_CPU0_P0_TX_BUF_DN<6>")
	)
	(arc
		(start 311.085484 -399.172938)
		(mid 311.093277 -399.252696)
		(end 311.116472 -399.329402)
		(width 0.14224)
		(layer "In4.Cu")
		(net "P5E_CPU0_P0_TX_BUF_DN<6>")
	)
	(arc
		(start 311.03824 -398.45869)
		(mid 311.073202 -398.511015)
		(end 311.085484 -398.572736)
		(width 0.14224)
		(layer "In4.Cu")
		(net "P5E_CPU0_P0_TX_BUF_DN<6>")
	)
	(arc
		(start 310.724804 -397.870172)
		(mid 310.775364 -398.124354)
		(end 310.919368 -398.339818)
		(width 0.14224)
		(layer "In4.Cu")
		(net "P5E_CPU0_P0_TX_BUF_DN<6>")
	)
	(segment
		(start 319.380616 -416.336734)
		(end 319.084706 -416.632644)
		(width 0.12954)
		(layer "F.Cu")
		(net "P5E_CPU0_P0_TX_BUF_DN<5>")
	)
	(segment
		(start 319.110106 -412.84652)
		(end 319.380616 -413.11703)
		(width 0.12954)
		(layer "F.Cu")
		(net "P5E_CPU0_P0_TX_BUF_DN<5>")
	)
	(segment
		(start 309.2704 -397.156432)
		(end 309.7911 -397.156432)
		(width 0.127)
		(layer "F.Cu")
		(net "P5E_CPU0_P0_TX_BUF_DN<5>")
	)
	(segment
		(start 319.380616 -413.11703)
		(end 319.380616 -416.336734)
		(width 0.12954)
		(layer "F.Cu")
		(net "P5E_CPU0_P0_TX_BUF_DN<5>")
	)
	(segment
		(start 309.524908 -397.707104)
		(end 309.524908 -397.82877)
		(width 0.14224)
		(layer "In4.Cu")
		(net "P5E_CPU0_P0_TX_BUF_DN<5>")
	)
	(segment
		(start 319.400936 -412.55569)
		(end 319.110106 -412.84652)
		(width 0.14224)
		(layer "In4.Cu")
		(net "P5E_CPU0_P0_TX_BUF_DN<5>")
	)
	(segment
		(start 309.748428 -398.36852)
		(end 309.84825 -398.468342)
		(width 0.14224)
		(layer "In4.Cu")
		(net "P5E_CPU0_P0_TX_BUF_DN<5>")
	)
	(segment
		(start 316.05474 -410.500576)
		(end 319.322196 -411.854142)
		(width 0.14224)
		(layer "In4.Cu")
		(net "P5E_CPU0_P0_TX_BUF_DN<5>")
	)
	(segment
		(start 309.7911 -397.156432)
		(end 309.843424 -397.208756)
		(width 0.14224)
		(layer "In4.Cu")
		(net "P5E_CPU0_P0_TX_BUF_DN<5>")
	)
	(segment
		(start 309.843424 -397.388588)
		(end 309.524908 -397.707104)
		(width 0.14224)
		(layer "In4.Cu")
		(net "P5E_CPU0_P0_TX_BUF_DN<5>")
	)
	(segment
		(start 309.843424 -397.208756)
		(end 309.843424 -397.388588)
		(width 0.14224)
		(layer "In4.Cu")
		(net "P5E_CPU0_P0_TX_BUF_DN<5>")
	)
	(segment
		(start 309.885588 -398.558004)
		(end 309.885588 -398.802098)
		(width 0.14224)
		(layer "In4.Cu")
		(net "P5E_CPU0_P0_TX_BUF_DN<5>")
	)
	(segment
		(start 310.748426 -405.572468)
		(end 314.914788 -409.73883)
		(width 0.14224)
		(layer "In4.Cu")
		(net "P5E_CPU0_P0_TX_BUF_DN<5>")
	)
	(segment
		(start 309.962804 -399.336768)
		(end 310.067452 -399.637758)
		(width 0.14224)
		(layer "In4.Cu")
		(net "P5E_CPU0_P0_TX_BUF_DN<5>")
	)
	(segment
		(start 310.118252 -399.770854)
		(end 310.271668 -400.140932)
		(width 0.14224)
		(layer "In4.Cu")
		(net "P5E_CPU0_P0_TX_BUF_DN<5>")
	)
	(segment
		(start 310.271668 -400.140932)
		(end 310.271668 -404.42134)
		(width 0.14224)
		(layer "In4.Cu")
		(net "P5E_CPU0_P0_TX_BUF_DN<5>")
	)
	(segment
		(start 319.400936 -411.97149)
		(end 319.400936 -412.55569)
		(width 0.14224)
		(layer "In4.Cu")
		(net "P5E_CPU0_P0_TX_BUF_DN<5>")
	)
	(arc
		(start 310.271668 -404.42134)
		(mid 310.395568 -405.044319)
		(end 310.748426 -405.572468)
		(width 0.14224)
		(layer "In4.Cu")
		(net "P5E_CPU0_P0_TX_BUF_DN<5>")
	)
	(arc
		(start 309.885588 -398.802098)
		(mid 309.894015 -398.987892)
		(end 309.919116 -399.172176)
		(width 0.14224)
		(layer "In4.Cu")
		(net "P5E_CPU0_P0_TX_BUF_DN<5>")
	)
	(arc
		(start 314.914788 -409.73883)
		(mid 315.447247 -410.175847)
		(end 316.05474 -410.500576)
		(width 0.14224)
		(layer "In4.Cu")
		(net "P5E_CPU0_P0_TX_BUF_DN<5>")
	)
	(arc
		(start 309.919116 -399.172176)
		(mid 309.937762 -399.255321)
		(end 309.962804 -399.336768)
		(width 0.14224)
		(layer "In4.Cu")
		(net "P5E_CPU0_P0_TX_BUF_DN<5>")
	)
	(arc
		(start 309.84825 -398.468342)
		(mid 309.87582 -398.509464)
		(end 309.885588 -398.558004)
		(width 0.14224)
		(layer "In4.Cu")
		(net "P5E_CPU0_P0_TX_BUF_DN<5>")
	)
	(arc
		(start 319.322196 -411.854142)
		(mid 319.379445 -411.900841)
		(end 319.400936 -411.97149)
		(width 0.14224)
		(layer "In4.Cu")
		(net "P5E_CPU0_P0_TX_BUF_DN<5>")
	)
	(arc
		(start 310.067452 -399.637758)
		(mid 310.091901 -399.704669)
		(end 310.118252 -399.770854)
		(width 0.14224)
		(layer "In4.Cu")
		(net "P5E_CPU0_P0_TX_BUF_DN<5>")
	)
	(arc
		(start 309.524908 -397.82877)
		(mid 309.582993 -398.120875)
		(end 309.748428 -398.36852)
		(width 0.14224)
		(layer "In4.Cu")
		(net "P5E_CPU0_P0_TX_BUF_DN<5>")
	)
	(segment
		(start 316.317376 -416.336734)
		(end 316.317376 -413.11703)
		(width 0.12954)
		(layer "F.Cu")
		(net "P5E_CPU0_P0_TX_BUF_DN<4>")
	)
	(segment
		(start 308.07025 -397.156432)
		(end 308.59095 -397.156432)
		(width 0.127)
		(layer "F.Cu")
		(net "P5E_CPU0_P0_TX_BUF_DN<4>")
	)
	(segment
		(start 316.021466 -416.632644)
		(end 316.317376 -416.336734)
		(width 0.12954)
		(layer "F.Cu")
		(net "P5E_CPU0_P0_TX_BUF_DN<4>")
	)
	(segment
		(start 316.317376 -413.11703)
		(end 316.046866 -412.84652)
		(width 0.12954)
		(layer "F.Cu")
		(net "P5E_CPU0_P0_TX_BUF_DN<4>")
	)
	(segment
		(start 316.337696 -412.55569)
		(end 316.046866 -412.84652)
		(width 0.14224)
		(layer "In4.Cu")
		(net "P5E_CPU0_P0_TX_BUF_DN<4>")
	)
	(segment
		(start 316.337696 -412.093918)
		(end 316.337696 -412.55569)
		(width 0.14224)
		(layer "In4.Cu")
		(net "P5E_CPU0_P0_TX_BUF_DN<4>")
	)
	(segment
		(start 308.716426 -399.071338)
		(end 309.071518 -399.928588)
		(width 0.14224)
		(layer "In4.Cu")
		(net "P5E_CPU0_P0_TX_BUF_DN<4>")
	)
	(segment
		(start 308.59095 -397.156432)
		(end 308.643274 -397.208756)
		(width 0.14224)
		(layer "In4.Cu")
		(net "P5E_CPU0_P0_TX_BUF_DN<4>")
	)
	(segment
		(start 308.685438 -398.558004)
		(end 308.685438 -398.914874)
		(width 0.14224)
		(layer "In4.Cu")
		(net "P5E_CPU0_P0_TX_BUF_DN<4>")
	)
	(segment
		(start 309.514494 -405.854154)
		(end 314.864496 -411.204156)
		(width 0.14224)
		(layer "In4.Cu")
		(net "P5E_CPU0_P0_TX_BUF_DN<4>")
	)
	(segment
		(start 308.643274 -397.388588)
		(end 308.324758 -397.707104)
		(width 0.14224)
		(layer "In4.Cu")
		(net "P5E_CPU0_P0_TX_BUF_DN<4>")
	)
	(segment
		(start 309.071518 -399.928588)
		(end 309.071518 -404.78456)
		(width 0.14224)
		(layer "In4.Cu")
		(net "P5E_CPU0_P0_TX_BUF_DN<4>")
	)
	(segment
		(start 308.511448 -398.33169)
		(end 308.6481 -398.468342)
		(width 0.14224)
		(layer "In4.Cu")
		(net "P5E_CPU0_P0_TX_BUF_DN<4>")
	)
	(segment
		(start 308.643274 -397.208756)
		(end 308.643274 -397.388588)
		(width 0.14224)
		(layer "In4.Cu")
		(net "P5E_CPU0_P0_TX_BUF_DN<4>")
	)
	(segment
		(start 308.324758 -397.707104)
		(end 308.324758 -397.88084)
		(width 0.14224)
		(layer "In4.Cu")
		(net "P5E_CPU0_P0_TX_BUF_DN<4>")
	)
	(segment
		(start 315.783722 -411.584902)
		(end 315.838078 -411.584902)
		(width 0.14224)
		(layer "In4.Cu")
		(net "P5E_CPU0_P0_TX_BUF_DN<4>")
	)
	(arc
		(start 309.071518 -404.78456)
		(mid 309.186641 -405.36341)
		(end 309.514494 -405.854154)
		(width 0.14224)
		(layer "In4.Cu")
		(net "P5E_CPU0_P0_TX_BUF_DN<4>")
	)
	(arc
		(start 308.6481 -398.468342)
		(mid 308.67567 -398.509464)
		(end 308.685438 -398.558004)
		(width 0.14224)
		(layer "In4.Cu")
		(net "P5E_CPU0_P0_TX_BUF_DN<4>")
	)
	(arc
		(start 314.864496 -411.204156)
		(mid 315.28624 -411.485957)
		(end 315.783722 -411.584902)
		(width 0.14224)
		(layer "In4.Cu")
		(net "P5E_CPU0_P0_TX_BUF_DN<4>")
	)
	(arc
		(start 316.32779 -412.038546)
		(mid 316.335182 -412.065796)
		(end 316.337696 -412.093918)
		(width 0.14224)
		(layer "In4.Cu")
		(net "P5E_CPU0_P0_TX_BUF_DN<4>")
	)
	(arc
		(start 316.109604 -411.697424)
		(mid 316.237254 -411.856116)
		(end 316.32779 -412.038546)
		(width 0.14224)
		(layer "In4.Cu")
		(net "P5E_CPU0_P0_TX_BUF_DN<4>")
	)
	(arc
		(start 308.324758 -397.88084)
		(mid 308.373273 -398.12483)
		(end 308.511448 -398.33169)
		(width 0.14224)
		(layer "In4.Cu")
		(net "P5E_CPU0_P0_TX_BUF_DN<4>")
	)
	(arc
		(start 315.838078 -411.584902)
		(mid 315.985033 -411.614151)
		(end 316.109604 -411.697424)
		(width 0.14224)
		(layer "In4.Cu")
		(net "P5E_CPU0_P0_TX_BUF_DN<4>")
	)
	(arc
		(start 308.685438 -398.914874)
		(mid 308.693231 -398.994632)
		(end 308.716426 -399.071338)
		(width 0.14224)
		(layer "In4.Cu")
		(net "P5E_CPU0_P0_TX_BUF_DN<4>")
	)
	(segment
		(start 313.254136 -413.11703)
		(end 312.983626 -412.84652)
		(width 0.12954)
		(layer "F.Cu")
		(net "P5E_CPU0_P0_TX_BUF_DN<3>")
	)
	(segment
		(start 306.870354 -397.156432)
		(end 307.391054 -397.156432)
		(width 0.127)
		(layer "F.Cu")
		(net "P5E_CPU0_P0_TX_BUF_DN<3>")
	)
	(segment
		(start 313.254136 -416.336734)
		(end 313.254136 -413.11703)
		(width 0.12954)
		(layer "F.Cu")
		(net "P5E_CPU0_P0_TX_BUF_DN<3>")
	)
	(segment
		(start 312.958226 -416.632644)
		(end 313.254136 -416.336734)
		(width 0.12954)
		(layer "F.Cu")
		(net "P5E_CPU0_P0_TX_BUF_DN<3>")
	)
	(segment
		(start 307.391054 -397.156432)
		(end 307.443378 -397.208756)
		(width 0.14224)
		(layer "In4.Cu")
		(net "P5E_CPU0_P0_TX_BUF_DN<3>")
	)
	(segment
		(start 307.871622 -400.203416)
		(end 307.871622 -405.065992)
		(width 0.14224)
		(layer "In4.Cu")
		(net "P5E_CPU0_P0_TX_BUF_DN<3>")
	)
	(segment
		(start 307.520848 -399.216372)
		(end 307.85308 -400.018504)
		(width 0.14224)
		(layer "In4.Cu")
		(net "P5E_CPU0_P0_TX_BUF_DN<3>")
	)
	(segment
		(start 307.443378 -397.388588)
		(end 307.124862 -397.707104)
		(width 0.14224)
		(layer "In4.Cu")
		(net "P5E_CPU0_P0_TX_BUF_DN<3>")
	)
	(segment
		(start 307.24475 -398.262856)
		(end 307.44668 -398.464786)
		(width 0.14224)
		(layer "In4.Cu")
		(net "P5E_CPU0_P0_TX_BUF_DN<3>")
	)
	(segment
		(start 307.443378 -397.208756)
		(end 307.443378 -397.388588)
		(width 0.14224)
		(layer "In4.Cu")
		(net "P5E_CPU0_P0_TX_BUF_DN<3>")
	)
	(segment
		(start 313.274456 -411.002226)
		(end 313.274456 -412.55569)
		(width 0.14224)
		(layer "In4.Cu")
		(net "P5E_CPU0_P0_TX_BUF_DN<3>")
	)
	(segment
		(start 307.85308 -400.018504)
		(end 307.85308 -400.074638)
		(width 0.14224)
		(layer "In4.Cu")
		(net "P5E_CPU0_P0_TX_BUF_DN<3>")
	)
	(segment
		(start 313.274456 -412.55569)
		(end 312.983626 -412.84652)
		(width 0.14224)
		(layer "In4.Cu")
		(net "P5E_CPU0_P0_TX_BUF_DN<3>")
	)
	(segment
		(start 307.124862 -397.707104)
		(end 307.124862 -397.97355)
		(width 0.14224)
		(layer "In4.Cu")
		(net "P5E_CPU0_P0_TX_BUF_DN<3>")
	)
	(segment
		(start 307.485542 -398.558512)
		(end 307.485542 -398.995138)
		(width 0.14224)
		(layer "In4.Cu")
		(net "P5E_CPU0_P0_TX_BUF_DN<3>")
	)
	(segment
		(start 308.201568 -405.862536)
		(end 313.227212 -410.88818)
		(width 0.14224)
		(layer "In4.Cu")
		(net "P5E_CPU0_P0_TX_BUF_DN<3>")
	)
	(segment
		(start 307.85308 -400.074638)
		(end 307.860192 -400.106134)
		(width 0.14224)
		(layer "In4.Cu")
		(net "P5E_CPU0_P0_TX_BUF_DN<3>")
	)
	(arc
		(start 307.485542 -398.995138)
		(mid 307.494446 -399.107151)
		(end 307.520848 -399.216372)
		(width 0.14224)
		(layer "In4.Cu")
		(net "P5E_CPU0_P0_TX_BUF_DN<3>")
	)
	(arc
		(start 307.124862 -397.97355)
		(mid 307.156025 -398.130128)
		(end 307.24475 -398.262856)
		(width 0.14224)
		(layer "In4.Cu")
		(net "P5E_CPU0_P0_TX_BUF_DN<3>")
	)
	(arc
		(start 307.44668 -398.464786)
		(mid 307.475467 -398.507774)
		(end 307.485542 -398.558512)
		(width 0.14224)
		(layer "In4.Cu")
		(net "P5E_CPU0_P0_TX_BUF_DN<3>")
	)
	(arc
		(start 313.227212 -410.88818)
		(mid 313.262174 -410.940505)
		(end 313.274456 -411.002226)
		(width 0.14224)
		(layer "In4.Cu")
		(net "P5E_CPU0_P0_TX_BUF_DN<3>")
	)
	(arc
		(start 307.860192 -400.106134)
		(mid 307.868692 -400.154448)
		(end 307.871622 -400.203416)
		(width 0.14224)
		(layer "In4.Cu")
		(net "P5E_CPU0_P0_TX_BUF_DN<3>")
	)
	(arc
		(start 307.871622 -405.065992)
		(mid 307.957371 -405.497081)
		(end 308.201568 -405.862536)
		(width 0.14224)
		(layer "In4.Cu")
		(net "P5E_CPU0_P0_TX_BUF_DN<3>")
	)
	(segment
		(start 310.190896 -413.11703)
		(end 309.920386 -412.84652)
		(width 0.12954)
		(layer "F.Cu")
		(net "P5E_CPU0_P0_TX_BUF_DN<2>")
	)
	(segment
		(start 309.894986 -416.632644)
		(end 310.190896 -416.336734)
		(width 0.12954)
		(layer "F.Cu")
		(net "P5E_CPU0_P0_TX_BUF_DN<2>")
	)
	(segment
		(start 310.190896 -416.336734)
		(end 310.190896 -413.11703)
		(width 0.12954)
		(layer "F.Cu")
		(net "P5E_CPU0_P0_TX_BUF_DN<2>")
	)
	(segment
		(start 305.670458 -397.156432)
		(end 306.191158 -397.156432)
		(width 0.127)
		(layer "F.Cu")
		(net "P5E_CPU0_P0_TX_BUF_DN<2>")
	)
	(segment
		(start 310.211216 -412.55569)
		(end 309.920386 -412.84652)
		(width 0.14224)
		(layer "In4.Cu")
		(net "P5E_CPU0_P0_TX_BUF_DN<2>")
	)
	(segment
		(start 306.318158 -398.65173)
		(end 306.318158 -398.997424)
		(width 0.14224)
		(layer "In4.Cu")
		(net "P5E_CPU0_P0_TX_BUF_DN<2>")
	)
	(segment
		(start 305.924712 -397.731742)
		(end 305.924712 -397.867378)
		(width 0.14224)
		(layer "In4.Cu")
		(net "P5E_CPU0_P0_TX_BUF_DN<2>")
	)
	(segment
		(start 306.121308 -398.34185)
		(end 306.238148 -398.45869)
		(width 0.14224)
		(layer "In4.Cu")
		(net "P5E_CPU0_P0_TX_BUF_DN<2>")
	)
	(segment
		(start 306.935378 -405.816308)
		(end 309.941976 -409.480004)
		(width 0.14224)
		(layer "In4.Cu")
		(net "P5E_CPU0_P0_TX_BUF_DN<2>")
	)
	(segment
		(start 306.191158 -397.156432)
		(end 306.243482 -397.208756)
		(width 0.14224)
		(layer "In4.Cu")
		(net "P5E_CPU0_P0_TX_BUF_DN<2>")
	)
	(segment
		(start 306.243482 -397.412972)
		(end 305.924712 -397.731742)
		(width 0.14224)
		(layer "In4.Cu")
		(net "P5E_CPU0_P0_TX_BUF_DN<2>")
	)
	(segment
		(start 306.348638 -399.203672)
		(end 306.462176 -399.577052)
		(width 0.14224)
		(layer "In4.Cu")
		(net "P5E_CPU0_P0_TX_BUF_DN<2>")
	)
	(segment
		(start 310.211216 -410.232098)
		(end 310.211216 -412.55569)
		(width 0.14224)
		(layer "In4.Cu")
		(net "P5E_CPU0_P0_TX_BUF_DN<2>")
	)
	(segment
		(start 306.513992 -399.722086)
		(end 306.671726 -400.102832)
		(width 0.14224)
		(layer "In4.Cu")
		(net "P5E_CPU0_P0_TX_BUF_DN<2>")
	)
	(segment
		(start 306.243482 -397.208756)
		(end 306.243482 -397.412972)
		(width 0.14224)
		(layer "In4.Cu")
		(net "P5E_CPU0_P0_TX_BUF_DN<2>")
	)
	(segment
		(start 306.671726 -400.102832)
		(end 306.671726 -405.079454)
		(width 0.14224)
		(layer "In4.Cu")
		(net "P5E_CPU0_P0_TX_BUF_DN<2>")
	)
	(arc
		(start 306.671726 -405.079454)
		(mid 306.739622 -405.470757)
		(end 306.935378 -405.816308)
		(width 0.14224)
		(layer "In4.Cu")
		(net "P5E_CPU0_P0_TX_BUF_DN<2>")
	)
	(arc
		(start 306.318158 -398.997424)
		(mid 306.325799 -399.101671)
		(end 306.348638 -399.203672)
		(width 0.14224)
		(layer "In4.Cu")
		(net "P5E_CPU0_P0_TX_BUF_DN<2>")
	)
	(arc
		(start 309.941976 -409.480004)
		(mid 310.141854 -409.832692)
		(end 310.211216 -410.232098)
		(width 0.14224)
		(layer "In4.Cu")
		(net "P5E_CPU0_P0_TX_BUF_DN<2>")
	)
	(arc
		(start 306.238148 -398.45869)
		(mid 306.297327 -398.547258)
		(end 306.318158 -398.65173)
		(width 0.14224)
		(layer "In4.Cu")
		(net "P5E_CPU0_P0_TX_BUF_DN<2>")
	)
	(arc
		(start 306.462176 -399.577052)
		(mid 306.486314 -399.650202)
		(end 306.513992 -399.722086)
		(width 0.14224)
		(layer "In4.Cu")
		(net "P5E_CPU0_P0_TX_BUF_DN<2>")
	)
	(arc
		(start 305.924712 -397.867378)
		(mid 305.975809 -398.12417)
		(end 306.121308 -398.34185)
		(width 0.14224)
		(layer "In4.Cu")
		(net "P5E_CPU0_P0_TX_BUF_DN<2>")
	)
	(segment
		(start 306.831746 -416.632644)
		(end 307.127656 -416.336734)
		(width 0.12954)
		(layer "F.Cu")
		(net "P5E_CPU0_P0_TX_BUF_DN<1>")
	)
	(segment
		(start 307.127656 -413.11703)
		(end 306.857146 -412.84652)
		(width 0.12954)
		(layer "F.Cu")
		(net "P5E_CPU0_P0_TX_BUF_DN<1>")
	)
	(segment
		(start 304.470308 -397.156432)
		(end 304.991008 -397.156432)
		(width 0.127)
		(layer "F.Cu")
		(net "P5E_CPU0_P0_TX_BUF_DN<1>")
	)
	(segment
		(start 307.127656 -416.336734)
		(end 307.127656 -413.11703)
		(width 0.12954)
		(layer "F.Cu")
		(net "P5E_CPU0_P0_TX_BUF_DN<1>")
	)
	(segment
		(start 304.991008 -397.156432)
		(end 305.043332 -397.208756)
		(width 0.14224)
		(layer "In4.Cu")
		(net "P5E_CPU0_P0_TX_BUF_DN<1>")
	)
	(segment
		(start 307.147976 -412.55569)
		(end 306.857146 -412.84652)
		(width 0.14224)
		(layer "In4.Cu")
		(net "P5E_CPU0_P0_TX_BUF_DN<1>")
	)
	(segment
		(start 304.724816 -397.707104)
		(end 304.724816 -397.88084)
		(width 0.14224)
		(layer "In4.Cu")
		(net "P5E_CPU0_P0_TX_BUF_DN<1>")
	)
	(segment
		(start 305.47945 -404.585424)
		(end 305.5112 -404.890732)
		(width 0.14224)
		(layer "In4.Cu")
		(net "P5E_CPU0_P0_TX_BUF_DN<1>")
	)
	(segment
		(start 305.043332 -397.208756)
		(end 305.043332 -397.388588)
		(width 0.14224)
		(layer "In4.Cu")
		(net "P5E_CPU0_P0_TX_BUF_DN<1>")
	)
	(segment
		(start 307.147976 -408.829002)
		(end 307.147976 -412.55569)
		(width 0.14224)
		(layer "In4.Cu")
		(net "P5E_CPU0_P0_TX_BUF_DN<1>")
	)
	(segment
		(start 305.0921 -398.794478)
		(end 305.141376 -399.25879)
		(width 0.14224)
		(layer "In4.Cu")
		(net "P5E_CPU0_P0_TX_BUF_DN<1>")
	)
	(segment
		(start 305.085496 -398.558004)
		(end 305.085496 -398.668748)
		(width 0.14224)
		(layer "In4.Cu")
		(net "P5E_CPU0_P0_TX_BUF_DN<1>")
	)
	(segment
		(start 305.471576 -400.158712)
		(end 305.471576 -404.43023)
		(width 0.14224)
		(layer "In4.Cu")
		(net "P5E_CPU0_P0_TX_BUF_DN<1>")
	)
	(segment
		(start 305.18227 -399.419572)
		(end 305.46802 -400.111468)
		(width 0.14224)
		(layer "In4.Cu")
		(net "P5E_CPU0_P0_TX_BUF_DN<1>")
	)
	(segment
		(start 305.817524 -405.988012)
		(end 307.135784 -408.7749)
		(width 0.14224)
		(layer "In4.Cu")
		(net "P5E_CPU0_P0_TX_BUF_DN<1>")
	)
	(segment
		(start 304.911506 -398.33169)
		(end 305.048158 -398.468342)
		(width 0.14224)
		(layer "In4.Cu")
		(net "P5E_CPU0_P0_TX_BUF_DN<1>")
	)
	(segment
		(start 307.135784 -408.7749)
		(end 307.135784 -408.774646)
		(width 0.14224)
		(layer "In4.Cu")
		(net "P5E_CPU0_P0_TX_BUF_DN<1>")
	)
	(segment
		(start 305.536346 -405.04618)
		(end 305.603656 -405.357584)
		(width 0.14224)
		(layer "In4.Cu")
		(net "P5E_CPU0_P0_TX_BUF_DN<1>")
	)
	(segment
		(start 305.043332 -397.388588)
		(end 304.724816 -397.707104)
		(width 0.14224)
		(layer "In4.Cu")
		(net "P5E_CPU0_P0_TX_BUF_DN<1>")
	)
	(arc
		(start 305.048158 -398.468342)
		(mid 305.075728 -398.509464)
		(end 305.085496 -398.558004)
		(width 0.14224)
		(layer "In4.Cu")
		(net "P5E_CPU0_P0_TX_BUF_DN<1>")
	)
	(arc
		(start 305.603656 -405.357584)
		(mid 305.692535 -405.678923)
		(end 305.817524 -405.988012)
		(width 0.14224)
		(layer "In4.Cu")
		(net "P5E_CPU0_P0_TX_BUF_DN<1>")
	)
	(arc
		(start 307.135784 -408.774646)
		(mid 307.144891 -408.801149)
		(end 307.147976 -408.829002)
		(width 0.14224)
		(layer "In4.Cu")
		(net "P5E_CPU0_P0_TX_BUF_DN<1>")
	)
	(arc
		(start 304.724816 -397.88084)
		(mid 304.773331 -398.12483)
		(end 304.911506 -398.33169)
		(width 0.14224)
		(layer "In4.Cu")
		(net "P5E_CPU0_P0_TX_BUF_DN<1>")
	)
	(arc
		(start 305.085496 -398.668748)
		(mid 305.087133 -398.731701)
		(end 305.0921 -398.794478)
		(width 0.14224)
		(layer "In4.Cu")
		(net "P5E_CPU0_P0_TX_BUF_DN<1>")
	)
	(arc
		(start 305.141376 -399.25879)
		(mid 305.156071 -399.340644)
		(end 305.18227 -399.419572)
		(width 0.14224)
		(layer "In4.Cu")
		(net "P5E_CPU0_P0_TX_BUF_DN<1>")
	)
	(arc
		(start 305.5112 -404.890732)
		(mid 305.521643 -404.968801)
		(end 305.536346 -405.04618)
		(width 0.14224)
		(layer "In4.Cu")
		(net "P5E_CPU0_P0_TX_BUF_DN<1>")
	)
	(arc
		(start 305.471576 -404.43023)
		(mid 305.47351 -404.507928)
		(end 305.47945 -404.585424)
		(width 0.14224)
		(layer "In4.Cu")
		(net "P5E_CPU0_P0_TX_BUF_DN<1>")
	)
	(arc
		(start 305.46802 -400.111468)
		(mid 305.470665 -400.135025)
		(end 305.471576 -400.158712)
		(width 0.14224)
		(layer "In4.Cu")
		(net "P5E_CPU0_P0_TX_BUF_DN<1>")
	)
	(segment
		(start 349.717106 -416.632644)
		(end 350.013016 -416.336734)
		(width 0.12954)
		(layer "F.Cu")
		(net "P5E_CPU0_P0_TX_BUF_DN<15>")
	)
	(segment
		(start 350.013016 -413.11703)
		(end 349.742506 -412.84652)
		(width 0.12954)
		(layer "F.Cu")
		(net "P5E_CPU0_P0_TX_BUF_DN<15>")
	)
	(segment
		(start 350.013016 -416.336734)
		(end 350.013016 -413.11703)
		(width 0.12954)
		(layer "F.Cu")
		(net "P5E_CPU0_P0_TX_BUF_DN<15>")
	)
	(segment
		(start 321.270376 -397.156432)
		(end 321.791076 -397.156432)
		(width 0.127)
		(layer "F.Cu")
		(net "P5E_CPU0_P0_TX_BUF_DN<15>")
	)
	(segment
		(start 321.679316 -398.299432)
		(end 321.877182 -398.497044)
		(width 0.14224)
		(layer "In4.Cu")
		(net "P5E_CPU0_P0_TX_BUF_DN<15>")
	)
	(segment
		(start 322.274692 -399.58772)
		(end 322.348352 -399.765266)
		(width 0.14224)
		(layer "In4.Cu")
		(net "P5E_CPU0_P0_TX_BUF_DN<15>")
	)
	(segment
		(start 321.8434 -397.388588)
		(end 321.524884 -397.707104)
		(width 0.14224)
		(layer "In4.Cu")
		(net "P5E_CPU0_P0_TX_BUF_DN<15>")
	)
	(segment
		(start 321.524884 -397.707104)
		(end 321.524884 -397.926814)
		(width 0.14224)
		(layer "In4.Cu")
		(net "P5E_CPU0_P0_TX_BUF_DN<15>")
	)
	(segment
		(start 324.751954 -402.61921)
		(end 339.866986 -406.80259)
		(width 0.14224)
		(layer "In4.Cu")
		(net "P5E_CPU0_P0_TX_BUF_DN<15>")
	)
	(segment
		(start 349.734124 -410.900372)
		(end 349.824294 -410.990542)
		(width 0.14224)
		(layer "In4.Cu")
		(net "P5E_CPU0_P0_TX_BUF_DN<15>")
	)
	(segment
		(start 322.825618 -401.40255)
		(end 322.92163 -401.54352)
		(width 0.14224)
		(layer "In4.Cu")
		(net "P5E_CPU0_P0_TX_BUF_DN<15>")
	)
	(segment
		(start 339.866986 -406.80259)
		(end 349.692722 -410.872686)
		(width 0.14224)
		(layer "In4.Cu")
		(net "P5E_CPU0_P0_TX_BUF_DN<15>")
	)
	(segment
		(start 350.033336 -412.55569)
		(end 349.742506 -412.84652)
		(width 0.14224)
		(layer "In4.Cu")
		(net "P5E_CPU0_P0_TX_BUF_DN<15>")
	)
	(segment
		(start 350.033336 -411.49524)
		(end 350.033336 -412.55569)
		(width 0.14224)
		(layer "In4.Cu")
		(net "P5E_CPU0_P0_TX_BUF_DN<15>")
	)
	(segment
		(start 321.791076 -397.156432)
		(end 321.8434 -397.208756)
		(width 0.14224)
		(layer "In4.Cu")
		(net "P5E_CPU0_P0_TX_BUF_DN<15>")
	)
	(segment
		(start 322.382134 -399.886932)
		(end 322.482972 -400.562826)
		(width 0.14224)
		(layer "In4.Cu")
		(net "P5E_CPU0_P0_TX_BUF_DN<15>")
	)
	(segment
		(start 322.010024 -398.720564)
		(end 322.222368 -399.440654)
		(width 0.14224)
		(layer "In4.Cu")
		(net "P5E_CPU0_P0_TX_BUF_DN<15>")
	)
	(segment
		(start 322.535042 -400.74977)
		(end 322.738496 -401.240752)
		(width 0.14224)
		(layer "In4.Cu")
		(net "P5E_CPU0_P0_TX_BUF_DN<15>")
	)
	(segment
		(start 321.8434 -397.208756)
		(end 321.8434 -397.388588)
		(width 0.14224)
		(layer "In4.Cu")
		(net "P5E_CPU0_P0_TX_BUF_DN<15>")
	)
	(arc
		(start 322.482972 -400.562826)
		(mid 322.503294 -400.657889)
		(end 322.535042 -400.74977)
		(width 0.14224)
		(layer "In4.Cu")
		(net "P5E_CPU0_P0_TX_BUF_DN<15>")
	)
	(arc
		(start 349.824294 -410.990542)
		(mid 349.979016 -411.222099)
		(end 350.033336 -411.49524)
		(width 0.14224)
		(layer "In4.Cu")
		(net "P5E_CPU0_P0_TX_BUF_DN<15>")
	)
	(arc
		(start 323.037962 -401.679918)
		(mid 323.04418 -401.685512)
		(end 323.050408 -401.691094)
		(width 0.14224)
		(layer "In4.Cu")
		(net "P5E_CPU0_P0_TX_BUF_DN<15>")
	)
	(arc
		(start 322.348352 -399.765266)
		(mid 322.36896 -399.825067)
		(end 322.382134 -399.886932)
		(width 0.14224)
		(layer "In4.Cu")
		(net "P5E_CPU0_P0_TX_BUF_DN<15>")
	)
	(arc
		(start 323.050408 -401.691094)
		(mid 323.847661 -402.253279)
		(end 324.751954 -402.61921)
		(width 0.14224)
		(layer "In4.Cu")
		(net "P5E_CPU0_P0_TX_BUF_DN<15>")
	)
	(arc
		(start 349.692722 -410.872686)
		(mid 349.714797 -410.884477)
		(end 349.734124 -410.900372)
		(width 0.14224)
		(layer "In4.Cu")
		(net "P5E_CPU0_P0_TX_BUF_DN<15>")
	)
	(arc
		(start 321.877182 -398.497044)
		(mid 321.957613 -398.600482)
		(end 322.010024 -398.720564)
		(width 0.14224)
		(layer "In4.Cu")
		(net "P5E_CPU0_P0_TX_BUF_DN<15>")
	)
	(arc
		(start 321.524884 -397.926814)
		(mid 321.565018 -398.128493)
		(end 321.679316 -398.299432)
		(width 0.14224)
		(layer "In4.Cu")
		(net "P5E_CPU0_P0_TX_BUF_DN<15>")
	)
	(arc
		(start 322.738496 -401.240752)
		(mid 322.777935 -401.323871)
		(end 322.825618 -401.40255)
		(width 0.14224)
		(layer "In4.Cu")
		(net "P5E_CPU0_P0_TX_BUF_DN<15>")
	)
	(arc
		(start 322.222368 -399.440654)
		(mid 322.246586 -399.514879)
		(end 322.274692 -399.58772)
		(width 0.14224)
		(layer "In4.Cu")
		(net "P5E_CPU0_P0_TX_BUF_DN<15>")
	)
	(arc
		(start 322.92163 -401.54352)
		(mid 322.97596 -401.614991)
		(end 323.037962 -401.679918)
		(width 0.14224)
		(layer "In4.Cu")
		(net "P5E_CPU0_P0_TX_BUF_DN<15>")
	)
	(segment
		(start 346.949776 -416.336734)
		(end 346.949776 -413.11703)
		(width 0.12954)
		(layer "F.Cu")
		(net "P5E_CPU0_P0_TX_BUF_DN<14>")
	)
	(segment
		(start 346.949776 -413.11703)
		(end 346.679266 -412.84652)
		(width 0.12954)
		(layer "F.Cu")
		(net "P5E_CPU0_P0_TX_BUF_DN<14>")
	)
	(segment
		(start 320.07048 -397.156432)
		(end 320.59118 -397.156432)
		(width 0.127)
		(layer "F.Cu")
		(net "P5E_CPU0_P0_TX_BUF_DN<14>")
	)
	(segment
		(start 346.653866 -416.632644)
		(end 346.949776 -416.336734)
		(width 0.12954)
		(layer "F.Cu")
		(net "P5E_CPU0_P0_TX_BUF_DN<14>")
	)
	(segment
		(start 346.970096 -412.55569)
		(end 346.679266 -412.84652)
		(width 0.14224)
		(layer "In4.Cu")
		(net "P5E_CPU0_P0_TX_BUF_DN<14>")
	)
	(segment
		(start 320.767964 -398.990566)
		(end 321.009264 -399.786348)
		(width 0.14224)
		(layer "In4.Cu")
		(net "P5E_CPU0_P0_TX_BUF_DN<14>")
	)
	(segment
		(start 320.59118 -397.156432)
		(end 320.636392 -397.201644)
		(width 0.14224)
		(layer "In4.Cu")
		(net "P5E_CPU0_P0_TX_BUF_DN<14>")
	)
	(segment
		(start 320.636392 -397.201644)
		(end 320.636392 -397.381476)
		(width 0.14224)
		(layer "In4.Cu")
		(net "P5E_CPU0_P0_TX_BUF_DN<14>")
	)
	(segment
		(start 338.934298 -407.881836)
		(end 344.283792 -410.097224)
		(width 0.14224)
		(layer "In4.Cu")
		(net "P5E_CPU0_P0_TX_BUF_DN<14>")
	)
	(segment
		(start 320.636392 -397.381476)
		(end 320.31686 -397.701008)
		(width 0.14224)
		(layer "In4.Cu")
		(net "P5E_CPU0_P0_TX_BUF_DN<14>")
	)
	(segment
		(start 321.59829 -403.075902)
		(end 330.160376 -405.220932)
		(width 0.14224)
		(layer "In4.Cu")
		(net "P5E_CPU0_P0_TX_BUF_DN<14>")
	)
	(segment
		(start 321.191636 -402.751798)
		(end 321.408298 -402.968206)
		(width 0.14224)
		(layer "In4.Cu")
		(net "P5E_CPU0_P0_TX_BUF_DN<14>")
	)
	(segment
		(start 330.160376 -405.220932)
		(end 338.934298 -407.881836)
		(width 0.14224)
		(layer "In4.Cu")
		(net "P5E_CPU0_P0_TX_BUF_DN<14>")
	)
	(segment
		(start 320.31686 -397.701008)
		(end 320.31686 -397.844264)
		(width 0.14224)
		(layer "In4.Cu")
		(net "P5E_CPU0_P0_TX_BUF_DN<14>")
	)
	(segment
		(start 321.071748 -400.207988)
		(end 321.071748 -402.462238)
		(width 0.14224)
		(layer "In4.Cu")
		(net "P5E_CPU0_P0_TX_BUF_DN<14>")
	)
	(segment
		(start 346.868496 -411.82417)
		(end 346.901008 -411.856682)
		(width 0.14224)
		(layer "In4.Cu")
		(net "P5E_CPU0_P0_TX_BUF_DN<14>")
	)
	(segment
		(start 346.970096 -412.023306)
		(end 346.970096 -412.55569)
		(width 0.14224)
		(layer "In4.Cu")
		(net "P5E_CPU0_P0_TX_BUF_DN<14>")
	)
	(segment
		(start 320.52387 -398.344136)
		(end 320.64071 -398.460976)
		(width 0.14224)
		(layer "In4.Cu")
		(net "P5E_CPU0_P0_TX_BUF_DN<14>")
	)
	(arc
		(start 321.408298 -402.968206)
		(mid 321.495991 -403.034932)
		(end 321.59829 -403.075902)
		(width 0.14224)
		(layer "In4.Cu")
		(net "P5E_CPU0_P0_TX_BUF_DN<14>")
	)
	(arc
		(start 320.31686 -397.844264)
		(mid 320.370653 -398.11479)
		(end 320.52387 -398.344136)
		(width 0.14224)
		(layer "In4.Cu")
		(net "P5E_CPU0_P0_TX_BUF_DN<14>")
	)
	(arc
		(start 346.901008 -411.856682)
		(mid 346.952142 -411.933115)
		(end 346.970096 -412.023306)
		(width 0.14224)
		(layer "In4.Cu")
		(net "P5E_CPU0_P0_TX_BUF_DN<14>")
	)
	(arc
		(start 320.716656 -398.644364)
		(mid 320.729536 -398.819358)
		(end 320.767964 -398.990566)
		(width 0.14224)
		(layer "In4.Cu")
		(net "P5E_CPU0_P0_TX_BUF_DN<14>")
	)
	(arc
		(start 344.283792 -410.097224)
		(mid 345.661214 -410.833376)
		(end 346.868496 -411.82417)
		(width 0.14224)
		(layer "In4.Cu")
		(net "P5E_CPU0_P0_TX_BUF_DN<14>")
	)
	(arc
		(start 321.009264 -399.786348)
		(mid 321.056045 -399.994866)
		(end 321.071748 -400.207988)
		(width 0.14224)
		(layer "In4.Cu")
		(net "P5E_CPU0_P0_TX_BUF_DN<14>")
	)
	(arc
		(start 320.64071 -398.460976)
		(mid 320.69693 -398.545115)
		(end 320.716656 -398.644364)
		(width 0.14224)
		(layer "In4.Cu")
		(net "P5E_CPU0_P0_TX_BUF_DN<14>")
	)
	(arc
		(start 321.071748 -402.462238)
		(mid 321.102862 -402.618952)
		(end 321.191636 -402.751798)
		(width 0.14224)
		(layer "In4.Cu")
		(net "P5E_CPU0_P0_TX_BUF_DN<14>")
	)
	(segment
		(start 343.886536 -413.11703)
		(end 343.616026 -412.84652)
		(width 0.12954)
		(layer "F.Cu")
		(net "P5E_CPU0_P0_TX_BUF_DN<13>")
	)
	(segment
		(start 343.886536 -416.336734)
		(end 343.886536 -413.11703)
		(width 0.12954)
		(layer "F.Cu")
		(net "P5E_CPU0_P0_TX_BUF_DN<13>")
	)
	(segment
		(start 343.590626 -416.632644)
		(end 343.886536 -416.336734)
		(width 0.12954)
		(layer "F.Cu")
		(net "P5E_CPU0_P0_TX_BUF_DN<13>")
	)
	(segment
		(start 318.87033 -397.156432)
		(end 319.39103 -397.156432)
		(width 0.127)
		(layer "F.Cu")
		(net "P5E_CPU0_P0_TX_BUF_DN<13>")
	)
	(segment
		(start 326.28713 -405.214074)
		(end 334.424782 -407.6827)
		(width 0.14224)
		(layer "In4.Cu")
		(net "P5E_CPU0_P0_TX_BUF_DN<13>")
	)
	(segment
		(start 319.124838 -397.707104)
		(end 319.124838 -397.912844)
		(width 0.14224)
		(layer "In4.Cu")
		(net "P5E_CPU0_P0_TX_BUF_DN<13>")
	)
	(segment
		(start 343.906856 -412.55569)
		(end 343.616026 -412.84652)
		(width 0.14224)
		(layer "In4.Cu")
		(net "P5E_CPU0_P0_TX_BUF_DN<13>")
	)
	(segment
		(start 319.443354 -397.388588)
		(end 319.124838 -397.707104)
		(width 0.14224)
		(layer "In4.Cu")
		(net "P5E_CPU0_P0_TX_BUF_DN<13>")
	)
	(segment
		(start 343.640156 -411.211014)
		(end 343.72804 -411.298898)
		(width 0.14224)
		(layer "In4.Cu")
		(net "P5E_CPU0_P0_TX_BUF_DN<13>")
	)
	(segment
		(start 319.288922 -398.309084)
		(end 319.44818 -398.468342)
		(width 0.14224)
		(layer "In4.Cu")
		(net "P5E_CPU0_P0_TX_BUF_DN<13>")
	)
	(segment
		(start 339.17255 -409.38069)
		(end 339.172804 -409.38069)
		(width 0.14224)
		(layer "In4.Cu")
		(net "P5E_CPU0_P0_TX_BUF_DN<13>")
	)
	(segment
		(start 319.511172 -399.272506)
		(end 319.871598 -400.14271)
		(width 0.14224)
		(layer "In4.Cu")
		(net "P5E_CPU0_P0_TX_BUF_DN<13>")
	)
	(segment
		(start 319.443354 -397.208756)
		(end 319.443354 -397.388588)
		(width 0.14224)
		(layer "In4.Cu")
		(net "P5E_CPU0_P0_TX_BUF_DN<13>")
	)
	(segment
		(start 320.009266 -403.089364)
		(end 320.468244 -403.548342)
		(width 0.14224)
		(layer "In4.Cu")
		(net "P5E_CPU0_P0_TX_BUF_DN<13>")
	)
	(segment
		(start 339.172804 -409.38069)
		(end 341.182198 -410.09951)
		(width 0.14224)
		(layer "In4.Cu")
		(net "P5E_CPU0_P0_TX_BUF_DN<13>")
	)
	(segment
		(start 319.39103 -397.156432)
		(end 319.443354 -397.208756)
		(width 0.14224)
		(layer "In4.Cu")
		(net "P5E_CPU0_P0_TX_BUF_DN<13>")
	)
	(segment
		(start 343.906856 -411.730444)
		(end 343.906856 -412.55569)
		(width 0.14224)
		(layer "In4.Cu")
		(net "P5E_CPU0_P0_TX_BUF_DN<13>")
	)
	(segment
		(start 319.511172 -399.189194)
		(end 319.511172 -399.272506)
		(width 0.14224)
		(layer "In4.Cu")
		(net "P5E_CPU0_P0_TX_BUF_DN<13>")
	)
	(segment
		(start 319.485518 -398.558512)
		(end 319.485518 -398.97939)
		(width 0.14224)
		(layer "In4.Cu")
		(net "P5E_CPU0_P0_TX_BUF_DN<13>")
	)
	(segment
		(start 341.182198 -410.09951)
		(end 343.272618 -410.965396)
		(width 0.14224)
		(layer "In4.Cu")
		(net "P5E_CPU0_P0_TX_BUF_DN<13>")
	)
	(segment
		(start 319.871598 -400.14271)
		(end 319.871598 -402.756878)
		(width 0.14224)
		(layer "In4.Cu")
		(net "P5E_CPU0_P0_TX_BUF_DN<13>")
	)
	(segment
		(start 334.424782 -407.6827)
		(end 339.17255 -409.38069)
		(width 0.14224)
		(layer "In4.Cu")
		(net "P5E_CPU0_P0_TX_BUF_DN<13>")
	)
	(segment
		(start 321.126104 -403.92096)
		(end 326.28713 -405.214074)
		(width 0.14224)
		(layer "In4.Cu")
		(net "P5E_CPU0_P0_TX_BUF_DN<13>")
	)
	(arc
		(start 319.124838 -397.912844)
		(mid 319.167475 -398.127285)
		(end 319.288922 -398.309084)
		(width 0.14224)
		(layer "In4.Cu")
		(net "P5E_CPU0_P0_TX_BUF_DN<13>")
	)
	(arc
		(start 343.272618 -410.965396)
		(mid 343.468492 -411.070094)
		(end 343.640156 -411.211014)
		(width 0.14224)
		(layer "In4.Cu")
		(net "P5E_CPU0_P0_TX_BUF_DN<13>")
	)
	(arc
		(start 343.72804 -411.298898)
		(mid 343.86039 -411.496879)
		(end 343.906856 -411.730444)
		(width 0.14224)
		(layer "In4.Cu")
		(net "P5E_CPU0_P0_TX_BUF_DN<13>")
	)
	(arc
		(start 319.871598 -402.756878)
		(mid 319.907371 -402.936812)
		(end 320.009266 -403.089364)
		(width 0.14224)
		(layer "In4.Cu")
		(net "P5E_CPU0_P0_TX_BUF_DN<13>")
	)
	(arc
		(start 319.44818 -398.468342)
		(mid 319.475823 -398.509712)
		(end 319.485518 -398.558512)
		(width 0.14224)
		(layer "In4.Cu")
		(net "P5E_CPU0_P0_TX_BUF_DN<13>")
	)
	(arc
		(start 320.468244 -403.548342)
		(mid 320.77186 -403.77935)
		(end 321.126104 -403.92096)
		(width 0.14224)
		(layer "In4.Cu")
		(net "P5E_CPU0_P0_TX_BUF_DN<13>")
	)
	(arc
		(start 319.485518 -398.97939)
		(mid 319.491948 -399.085075)
		(end 319.511172 -399.189194)
		(width 0.14224)
		(layer "In4.Cu")
		(net "P5E_CPU0_P0_TX_BUF_DN<13>")
	)
	(segment
		(start 340.823296 -416.336734)
		(end 340.823296 -413.11703)
		(width 0.12954)
		(layer "F.Cu")
		(net "P5E_CPU0_P0_TX_BUF_DN<12>")
	)
	(segment
		(start 340.527386 -416.632644)
		(end 340.823296 -416.336734)
		(width 0.12954)
		(layer "F.Cu")
		(net "P5E_CPU0_P0_TX_BUF_DN<12>")
	)
	(segment
		(start 317.670434 -397.156432)
		(end 318.191134 -397.156432)
		(width 0.127)
		(layer "F.Cu")
		(net "P5E_CPU0_P0_TX_BUF_DN<12>")
	)
	(segment
		(start 340.823296 -413.11703)
		(end 340.552786 -412.84652)
		(width 0.12954)
		(layer "F.Cu")
		(net "P5E_CPU0_P0_TX_BUF_DN<12>")
	)
	(segment
		(start 318.671448 -399.961862)
		(end 318.671448 -403.095206)
		(width 0.14224)
		(layer "In4.Cu")
		(net "P5E_CPU0_P0_TX_BUF_DN<12>")
	)
	(segment
		(start 318.243458 -397.208756)
		(end 318.243458 -397.405352)
		(width 0.14224)
		(layer "In4.Cu")
		(net "P5E_CPU0_P0_TX_BUF_DN<12>")
	)
	(segment
		(start 335.127092 -408.927046)
		(end 340.634828 -411.208474)
		(width 0.14224)
		(layer "In4.Cu")
		(net "P5E_CPU0_P0_TX_BUF_DN<12>")
	)
	(segment
		(start 318.330834 -399.076164)
		(end 318.64681 -399.838672)
		(width 0.14224)
		(layer "In4.Cu")
		(net "P5E_CPU0_P0_TX_BUF_DN<12>")
	)
	(segment
		(start 318.285368 -398.558512)
		(end 318.285368 -398.845278)
		(width 0.14224)
		(layer "In4.Cu")
		(net "P5E_CPU0_P0_TX_BUF_DN<12>")
	)
	(segment
		(start 318.191134 -397.156432)
		(end 318.243458 -397.208756)
		(width 0.14224)
		(layer "In4.Cu")
		(net "P5E_CPU0_P0_TX_BUF_DN<12>")
	)
	(segment
		(start 340.843616 -411.481016)
		(end 340.843616 -412.55569)
		(width 0.14224)
		(layer "In4.Cu")
		(net "P5E_CPU0_P0_TX_BUF_DN<12>")
	)
	(segment
		(start 320.242438 -404.704042)
		(end 325.789036 -406.094184)
		(width 0.14224)
		(layer "In4.Cu")
		(net "P5E_CPU0_P0_TX_BUF_DN<12>")
	)
	(segment
		(start 325.789036 -406.094184)
		(end 335.127092 -408.927046)
		(width 0.14224)
		(layer "In4.Cu")
		(net "P5E_CPU0_P0_TX_BUF_DN<12>")
	)
	(segment
		(start 317.924942 -397.723868)
		(end 317.924942 -397.973804)
		(width 0.14224)
		(layer "In4.Cu")
		(net "P5E_CPU0_P0_TX_BUF_DN<12>")
	)
	(segment
		(start 318.243458 -397.405352)
		(end 317.924942 -397.723868)
		(width 0.14224)
		(layer "In4.Cu")
		(net "P5E_CPU0_P0_TX_BUF_DN<12>")
	)
	(segment
		(start 318.331342 -399.076164)
		(end 318.330834 -399.076164)
		(width 0.14224)
		(layer "In4.Cu")
		(net "P5E_CPU0_P0_TX_BUF_DN<12>")
	)
	(segment
		(start 318.850518 -403.527514)
		(end 319.74536 -404.422356)
		(width 0.14224)
		(layer "In4.Cu")
		(net "P5E_CPU0_P0_TX_BUF_DN<12>")
	)
	(segment
		(start 340.67623 -411.23616)
		(end 340.788752 -411.348682)
		(width 0.14224)
		(layer "In4.Cu")
		(net "P5E_CPU0_P0_TX_BUF_DN<12>")
	)
	(segment
		(start 340.843616 -412.55569)
		(end 340.552786 -412.84652)
		(width 0.14224)
		(layer "In4.Cu")
		(net "P5E_CPU0_P0_TX_BUF_DN<12>")
	)
	(segment
		(start 318.04483 -398.26311)
		(end 318.246506 -398.464786)
		(width 0.14224)
		(layer "In4.Cu")
		(net "P5E_CPU0_P0_TX_BUF_DN<12>")
	)
	(arc
		(start 318.64681 -399.838672)
		(mid 318.665208 -399.899053)
		(end 318.671448 -399.961862)
		(width 0.14224)
		(layer "In4.Cu")
		(net "P5E_CPU0_P0_TX_BUF_DN<12>")
	)
	(arc
		(start 318.285368 -398.845278)
		(mid 318.296989 -398.962986)
		(end 318.331342 -399.076164)
		(width 0.14224)
		(layer "In4.Cu")
		(net "P5E_CPU0_P0_TX_BUF_DN<12>")
	)
	(arc
		(start 319.74536 -404.422356)
		(mid 319.974765 -404.59697)
		(end 320.242438 -404.704042)
		(width 0.14224)
		(layer "In4.Cu")
		(net "P5E_CPU0_P0_TX_BUF_DN<12>")
	)
	(arc
		(start 318.246506 -398.464786)
		(mid 318.275293 -398.507774)
		(end 318.285368 -398.558512)
		(width 0.14224)
		(layer "In4.Cu")
		(net "P5E_CPU0_P0_TX_BUF_DN<12>")
	)
	(arc
		(start 340.634828 -411.208474)
		(mid 340.65689 -411.220282)
		(end 340.67623 -411.23616)
		(width 0.14224)
		(layer "In4.Cu")
		(net "P5E_CPU0_P0_TX_BUF_DN<12>")
	)
	(arc
		(start 317.924942 -397.973804)
		(mid 317.956105 -398.130382)
		(end 318.04483 -398.26311)
		(width 0.14224)
		(layer "In4.Cu")
		(net "P5E_CPU0_P0_TX_BUF_DN<12>")
	)
	(arc
		(start 340.788752 -411.348682)
		(mid 340.829374 -411.409383)
		(end 340.843616 -411.481016)
		(width 0.14224)
		(layer "In4.Cu")
		(net "P5E_CPU0_P0_TX_BUF_DN<12>")
	)
	(arc
		(start 318.671448 -403.095206)
		(mid 318.717986 -403.32917)
		(end 318.850518 -403.527514)
		(width 0.14224)
		(layer "In4.Cu")
		(net "P5E_CPU0_P0_TX_BUF_DN<12>")
	)
	(segment
		(start 337.464146 -416.632644)
		(end 337.760056 -416.336734)
		(width 0.12954)
		(layer "F.Cu")
		(net "P5E_CPU0_P0_TX_BUF_DN<11>")
	)
	(segment
		(start 316.470284 -397.156432)
		(end 316.990984 -397.156432)
		(width 0.127)
		(layer "F.Cu")
		(net "P5E_CPU0_P0_TX_BUF_DN<11>")
	)
	(segment
		(start 337.760056 -416.336734)
		(end 337.760056 -413.11703)
		(width 0.12954)
		(layer "F.Cu")
		(net "P5E_CPU0_P0_TX_BUF_DN<11>")
	)
	(segment
		(start 337.760056 -413.11703)
		(end 337.489546 -412.84652)
		(width 0.12954)
		(layer "F.Cu")
		(net "P5E_CPU0_P0_TX_BUF_DN<11>")
	)
	(segment
		(start 317.10884 -399.184114)
		(end 317.471552 -400.06016)
		(width 0.14224)
		(layer "In4.Cu")
		(net "P5E_CPU0_P0_TX_BUF_DN<11>")
	)
	(segment
		(start 334.87614 -410.03982)
		(end 337.603592 -411.169358)
		(width 0.14224)
		(layer "In4.Cu")
		(net "P5E_CPU0_P0_TX_BUF_DN<11>")
	)
	(segment
		(start 316.724792 -397.707104)
		(end 316.724792 -397.889476)
		(width 0.14224)
		(layer "In4.Cu")
		(net "P5E_CPU0_P0_TX_BUF_DN<11>")
	)
	(segment
		(start 317.471552 -400.06016)
		(end 317.471552 -403.592538)
		(width 0.14224)
		(layer "In4.Cu")
		(net "P5E_CPU0_P0_TX_BUF_DN<11>")
	)
	(segment
		(start 333.78521 -409.587954)
		(end 334.87614 -410.03982)
		(width 0.14224)
		(layer "In4.Cu")
		(net "P5E_CPU0_P0_TX_BUF_DN<11>")
	)
	(segment
		(start 317.043308 -397.388588)
		(end 316.724792 -397.707104)
		(width 0.14224)
		(layer "In4.Cu")
		(net "P5E_CPU0_P0_TX_BUF_DN<11>")
	)
	(segment
		(start 337.780376 -411.494478)
		(end 337.780376 -412.55569)
		(width 0.14224)
		(layer "In4.Cu")
		(net "P5E_CPU0_P0_TX_BUF_DN<11>")
	)
	(segment
		(start 317.70701 -404.160736)
		(end 318.742314 -405.19604)
		(width 0.14224)
		(layer "In4.Cu")
		(net "P5E_CPU0_P0_TX_BUF_DN<11>")
	)
	(segment
		(start 319.082166 -405.388572)
		(end 324.010274 -406.622504)
		(width 0.14224)
		(layer "In4.Cu")
		(net "P5E_CPU0_P0_TX_BUF_DN<11>")
	)
	(segment
		(start 316.990984 -397.156432)
		(end 317.043308 -397.208756)
		(width 0.14224)
		(layer "In4.Cu")
		(net "P5E_CPU0_P0_TX_BUF_DN<11>")
	)
	(segment
		(start 337.780376 -412.55569)
		(end 337.489546 -412.84652)
		(width 0.14224)
		(layer "In4.Cu")
		(net "P5E_CPU0_P0_TX_BUF_DN<11>")
	)
	(segment
		(start 316.905386 -398.325594)
		(end 317.048134 -398.468342)
		(width 0.14224)
		(layer "In4.Cu")
		(net "P5E_CPU0_P0_TX_BUF_DN<11>")
	)
	(segment
		(start 324.010274 -406.622504)
		(end 333.78521 -409.587954)
		(width 0.14224)
		(layer "In4.Cu")
		(net "P5E_CPU0_P0_TX_BUF_DN<11>")
	)
	(segment
		(start 317.043308 -397.208756)
		(end 317.043308 -397.388588)
		(width 0.14224)
		(layer "In4.Cu")
		(net "P5E_CPU0_P0_TX_BUF_DN<11>")
	)
	(segment
		(start 317.085472 -398.558512)
		(end 317.085472 -399.048732)
		(width 0.14224)
		(layer "In4.Cu")
		(net "P5E_CPU0_P0_TX_BUF_DN<11>")
	)
	(arc
		(start 317.048134 -398.468342)
		(mid 317.075777 -398.509712)
		(end 317.085472 -398.558512)
		(width 0.14224)
		(layer "In4.Cu")
		(net "P5E_CPU0_P0_TX_BUF_DN<11>")
	)
	(arc
		(start 316.724792 -397.889476)
		(mid 316.771721 -398.125496)
		(end 316.905386 -398.325594)
		(width 0.14224)
		(layer "In4.Cu")
		(net "P5E_CPU0_P0_TX_BUF_DN<11>")
	)
	(arc
		(start 317.471552 -403.592538)
		(mid 317.532742 -403.90007)
		(end 317.70701 -404.160736)
		(width 0.14224)
		(layer "In4.Cu")
		(net "P5E_CPU0_P0_TX_BUF_DN<11>")
	)
	(arc
		(start 318.742314 -405.19604)
		(mid 318.899169 -405.315375)
		(end 319.082166 -405.388572)
		(width 0.14224)
		(layer "In4.Cu")
		(net "P5E_CPU0_P0_TX_BUF_DN<11>")
	)
	(arc
		(start 337.702144 -411.249114)
		(mid 337.759273 -411.366049)
		(end 337.780376 -411.494478)
		(width 0.14224)
		(layer "In4.Cu")
		(net "P5E_CPU0_P0_TX_BUF_DN<11>")
	)
	(arc
		(start 317.085472 -399.048732)
		(mid 317.091449 -399.117407)
		(end 317.10884 -399.184114)
		(width 0.14224)
		(layer "In4.Cu")
		(net "P5E_CPU0_P0_TX_BUF_DN<11>")
	)
	(arc
		(start 337.603592 -411.169358)
		(mid 337.658687 -411.202051)
		(end 337.702144 -411.249114)
		(width 0.14224)
		(layer "In4.Cu")
		(net "P5E_CPU0_P0_TX_BUF_DN<11>")
	)
	(segment
		(start 334.696816 -416.336734)
		(end 334.696816 -413.11703)
		(width 0.12954)
		(layer "F.Cu")
		(net "P5E_CPU0_P0_TX_BUF_DN<10>")
	)
	(segment
		(start 334.696816 -413.11703)
		(end 334.426306 -412.84652)
		(width 0.12954)
		(layer "F.Cu")
		(net "P5E_CPU0_P0_TX_BUF_DN<10>")
	)
	(segment
		(start 315.270388 -397.156432)
		(end 315.791088 -397.156432)
		(width 0.127)
		(layer "F.Cu")
		(net "P5E_CPU0_P0_TX_BUF_DN<10>")
	)
	(segment
		(start 334.400906 -416.632644)
		(end 334.696816 -416.336734)
		(width 0.12954)
		(layer "F.Cu")
		(net "P5E_CPU0_P0_TX_BUF_DN<10>")
	)
	(segment
		(start 316.609222 -404.479252)
		(end 318.036194 -405.906224)
		(width 0.14224)
		(layer "In4.Cu")
		(net "P5E_CPU0_P0_TX_BUF_DN<10>")
	)
	(segment
		(start 315.843412 -397.208756)
		(end 315.843412 -397.388588)
		(width 0.14224)
		(layer "In4.Cu")
		(net "P5E_CPU0_P0_TX_BUF_DN<10>")
	)
	(segment
		(start 315.885576 -398.558258)
		(end 315.885576 -399.083276)
		(width 0.14224)
		(layer "In4.Cu")
		(net "P5E_CPU0_P0_TX_BUF_DN<10>")
	)
	(segment
		(start 315.679328 -398.299432)
		(end 315.848238 -398.468342)
		(width 0.14224)
		(layer "In4.Cu")
		(net "P5E_CPU0_P0_TX_BUF_DN<10>")
	)
	(segment
		(start 334.717136 -412.55569)
		(end 334.426306 -412.84652)
		(width 0.14224)
		(layer "In4.Cu")
		(net "P5E_CPU0_P0_TX_BUF_DN<10>")
	)
	(segment
		(start 318.620394 -406.237186)
		(end 323.258942 -407.398982)
		(width 0.14224)
		(layer "In4.Cu")
		(net "P5E_CPU0_P0_TX_BUF_DN<10>")
	)
	(segment
		(start 315.524896 -397.707104)
		(end 315.524896 -397.926814)
		(width 0.14224)
		(layer "In4.Cu")
		(net "P5E_CPU0_P0_TX_BUF_DN<10>")
	)
	(segment
		(start 330.013056 -409.447746)
		(end 333.803498 -411.01391)
		(width 0.14224)
		(layer "In4.Cu")
		(net "P5E_CPU0_P0_TX_BUF_DN<10>")
	)
	(segment
		(start 316.233556 -400.059906)
		(end 316.233556 -403.572218)
		(width 0.14224)
		(layer "In4.Cu")
		(net "P5E_CPU0_P0_TX_BUF_DN<10>")
	)
	(segment
		(start 333.887064 -411.06979)
		(end 334.679798 -411.862524)
		(width 0.14224)
		(layer "In4.Cu")
		(net "P5E_CPU0_P0_TX_BUF_DN<10>")
	)
	(segment
		(start 323.258942 -407.398982)
		(end 330.013056 -409.447746)
		(width 0.14224)
		(layer "In4.Cu")
		(net "P5E_CPU0_P0_TX_BUF_DN<10>")
	)
	(segment
		(start 315.937646 -399.34515)
		(end 316.233556 -400.059906)
		(width 0.14224)
		(layer "In4.Cu")
		(net "P5E_CPU0_P0_TX_BUF_DN<10>")
	)
	(segment
		(start 334.717136 -411.952694)
		(end 334.717136 -412.55569)
		(width 0.14224)
		(layer "In4.Cu")
		(net "P5E_CPU0_P0_TX_BUF_DN<10>")
	)
	(segment
		(start 315.843412 -397.388588)
		(end 315.524896 -397.707104)
		(width 0.14224)
		(layer "In4.Cu")
		(net "P5E_CPU0_P0_TX_BUF_DN<10>")
	)
	(segment
		(start 315.791088 -397.156432)
		(end 315.843412 -397.208756)
		(width 0.14224)
		(layer "In4.Cu")
		(net "P5E_CPU0_P0_TX_BUF_DN<10>")
	)
	(arc
		(start 315.524896 -397.926814)
		(mid 315.56503 -398.128493)
		(end 315.679328 -398.299432)
		(width 0.14224)
		(layer "In4.Cu")
		(net "P5E_CPU0_P0_TX_BUF_DN<10>")
	)
	(arc
		(start 316.233556 -403.572218)
		(mid 316.331181 -404.0631)
		(end 316.609222 -404.479252)
		(width 0.14224)
		(layer "In4.Cu")
		(net "P5E_CPU0_P0_TX_BUF_DN<10>")
	)
	(arc
		(start 315.885576 -399.083276)
		(mid 315.89872 -399.216776)
		(end 315.937646 -399.34515)
		(width 0.14224)
		(layer "In4.Cu")
		(net "P5E_CPU0_P0_TX_BUF_DN<10>")
	)
	(arc
		(start 333.803498 -411.01391)
		(mid 333.84801 -411.037766)
		(end 333.887064 -411.06979)
		(width 0.14224)
		(layer "In4.Cu")
		(net "P5E_CPU0_P0_TX_BUF_DN<10>")
	)
	(arc
		(start 334.679798 -411.862524)
		(mid 334.707441 -411.903894)
		(end 334.717136 -411.952694)
		(width 0.14224)
		(layer "In4.Cu")
		(net "P5E_CPU0_P0_TX_BUF_DN<10>")
	)
	(arc
		(start 318.036194 -405.906224)
		(mid 318.305822 -406.111368)
		(end 318.620394 -406.237186)
		(width 0.14224)
		(layer "In4.Cu")
		(net "P5E_CPU0_P0_TX_BUF_DN<10>")
	)
	(arc
		(start 315.848238 -398.468342)
		(mid 315.875857 -398.509582)
		(end 315.885576 -398.558258)
		(width 0.14224)
		(layer "In4.Cu")
		(net "P5E_CPU0_P0_TX_BUF_DN<10>")
	)
	(segment
		(start 303.768506 -416.632644)
		(end 304.064416 -416.336734)
		(width 0.12954)
		(layer "F.Cu")
		(net "P5E_CPU0_P0_TX_BUF_DN<0>")
	)
	(segment
		(start 304.064416 -413.11703)
		(end 303.793906 -412.84652)
		(width 0.12954)
		(layer "F.Cu")
		(net "P5E_CPU0_P0_TX_BUF_DN<0>")
	)
	(segment
		(start 303.270412 -397.156432)
		(end 303.791112 -397.156432)
		(width 0.127)
		(layer "F.Cu")
		(net "P5E_CPU0_P0_TX_BUF_DN<0>")
	)
	(segment
		(start 304.064416 -416.336734)
		(end 304.064416 -413.11703)
		(width 0.12954)
		(layer "F.Cu")
		(net "P5E_CPU0_P0_TX_BUF_DN<0>")
	)
	(segment
		(start 304.012854 -399.523204)
		(end 304.012854 -399.523458)
		(width 0.14224)
		(layer "In4.Cu")
		(net "P5E_CPU0_P0_TX_BUF_DN<0>")
	)
	(segment
		(start 304.084736 -412.55569)
		(end 303.793906 -412.84652)
		(width 0.14224)
		(layer "In4.Cu")
		(net "P5E_CPU0_P0_TX_BUF_DN<0>")
	)
	(segment
		(start 304.27168 -411.0609)
		(end 304.084736 -411.512258)
		(width 0.14224)
		(layer "In4.Cu")
		(net "P5E_CPU0_P0_TX_BUF_DN<0>")
	)
	(segment
		(start 303.658524 -398.274032)
		(end 303.838356 -398.453864)
		(width 0.14224)
		(layer "In4.Cu")
		(net "P5E_CPU0_P0_TX_BUF_DN<0>")
	)
	(segment
		(start 304.012854 -399.523458)
		(end 304.27168 -400.147536)
		(width 0.14224)
		(layer "In4.Cu")
		(net "P5E_CPU0_P0_TX_BUF_DN<0>")
	)
	(segment
		(start 303.893474 -398.58696)
		(end 303.893474 -398.84223)
		(width 0.14224)
		(layer "In4.Cu")
		(net "P5E_CPU0_P0_TX_BUF_DN<0>")
	)
	(segment
		(start 303.538636 -397.86941)
		(end 303.538636 -397.984472)
		(width 0.14224)
		(layer "In4.Cu")
		(net "P5E_CPU0_P0_TX_BUF_DN<0>")
	)
	(segment
		(start 303.843436 -397.388588)
		(end 303.662842 -397.569182)
		(width 0.14224)
		(layer "In4.Cu")
		(net "P5E_CPU0_P0_TX_BUF_DN<0>")
	)
	(segment
		(start 303.843436 -397.208756)
		(end 303.843436 -397.388588)
		(width 0.14224)
		(layer "In4.Cu")
		(net "P5E_CPU0_P0_TX_BUF_DN<0>")
	)
	(segment
		(start 304.27168 -400.147536)
		(end 304.27168 -411.0609)
		(width 0.14224)
		(layer "In4.Cu")
		(net "P5E_CPU0_P0_TX_BUF_DN<0>")
	)
	(segment
		(start 304.007774 -399.511012)
		(end 304.012854 -399.523204)
		(width 0.14224)
		(layer "In4.Cu")
		(net "P5E_CPU0_P0_TX_BUF_DN<0>")
	)
	(segment
		(start 304.084736 -411.512258)
		(end 304.084736 -412.55569)
		(width 0.14224)
		(layer "In4.Cu")
		(net "P5E_CPU0_P0_TX_BUF_DN<0>")
	)
	(segment
		(start 303.791112 -397.156432)
		(end 303.843436 -397.208756)
		(width 0.14224)
		(layer "In4.Cu")
		(net "P5E_CPU0_P0_TX_BUF_DN<0>")
	)
	(arc
		(start 303.662842 -397.569182)
		(mid 303.570832 -397.706929)
		(end 303.538636 -397.86941)
		(width 0.14224)
		(layer "In4.Cu")
		(net "P5E_CPU0_P0_TX_BUF_DN<0>")
	)
	(arc
		(start 303.901856 -398.999202)
		(mid 303.941112 -399.250478)
		(end 304.003456 -399.497042)
		(width 0.14224)
		(layer "In4.Cu")
		(net "P5E_CPU0_P0_TX_BUF_DN<0>")
	)
	(arc
		(start 303.538636 -397.984472)
		(mid 303.569788 -398.141175)
		(end 303.658524 -398.274032)
		(width 0.14224)
		(layer "In4.Cu")
		(net "P5E_CPU0_P0_TX_BUF_DN<0>")
	)
	(arc
		(start 303.838356 -398.453864)
		(mid 303.879212 -398.514915)
		(end 303.893474 -398.58696)
		(width 0.14224)
		(layer "In4.Cu")
		(net "P5E_CPU0_P0_TX_BUF_DN<0>")
	)
	(arc
		(start 304.003456 -399.497042)
		(mid 304.005606 -399.50403)
		(end 304.007774 -399.511012)
		(width 0.14224)
		(layer "In4.Cu")
		(net "P5E_CPU0_P0_TX_BUF_DN<0>")
	)
	(arc
		(start 303.893474 -398.84223)
		(mid 303.895539 -398.920829)
		(end 303.901856 -398.999202)
		(width 0.14224)
		(layer "In4.Cu")
		(net "P5E_CPU0_P0_TX_BUF_DN<0>")
	)
	(segment
		(start 331.956156 -417.461954)
		(end 331.956156 -420.681658)
		(width 0.12954)
		(layer "F.Cu")
		(net "P5E_CPU0_P0_TX_BUF_C_DP<9>")
	)
	(segment
		(start 331.956156 -420.681658)
		(end 332.226666 -420.952168)
		(width 0.12954)
		(layer "F.Cu")
		(net "P5E_CPU0_P0_TX_BUF_C_DP<9>")
	)
	(segment
		(start 332.252066 -417.166044)
		(end 331.956156 -417.461954)
		(width 0.12954)
		(layer "F.Cu")
		(net "P5E_CPU0_P0_TX_BUF_C_DP<9>")
	)
	(segment
		(start 332.059534 -422.270936)
		(end 332.23073 -422.362376)
		(width 0.14224)
		(layer "In11.Cu")
		(net "P5E_CPU0_P0_TX_BUF_C_DP<9>")
	)
	(segment
		(start 332.261718 -422.944544)
		(end 332.3844 -423.349166)
		(width 0.14224)
		(layer "In11.Cu")
		(net "P5E_CPU0_P0_TX_BUF_C_DP<9>")
	)
	(segment
		(start 331.935836 -421.242998)
		(end 331.935836 -421.862758)
		(width 0.14224)
		(layer "In11.Cu")
		(net "P5E_CPU0_P0_TX_BUF_C_DP<9>")
	)
	(segment
		(start 333.507588 -431.148998)
		(end 333.649828 -431.006758)
		(width 0.14224)
		(layer "In11.Cu")
		(net "P5E_CPU0_P0_TX_BUF_C_DP<9>")
	)
	(segment
		(start 331.935836 -421.862758)
		(end 332.059534 -422.270936)
		(width 0.14224)
		(layer "In11.Cu")
		(net "P5E_CPU0_P0_TX_BUF_C_DP<9>")
	)
	(segment
		(start 333.076804 -431.052732)
		(end 333.135732 -431.11166)
		(width 0.14224)
		(layer "In11.Cu")
		(net "P5E_CPU0_P0_TX_BUF_C_DP<9>")
	)
	(segment
		(start 332.590394 -424.021758)
		(end 332.985872 -425.32681)
		(width 0.14224)
		(layer "In11.Cu")
		(net "P5E_CPU0_P0_TX_BUF_C_DP<9>")
	)
	(segment
		(start 332.681834 -423.850562)
		(end 332.590394 -424.021758)
		(width 0.14224)
		(layer "In11.Cu")
		(net "P5E_CPU0_P0_TX_BUF_C_DP<9>")
	)
	(segment
		(start 332.354682 -422.771062)
		(end 332.261718 -422.944544)
		(width 0.14224)
		(layer "In11.Cu")
		(net "P5E_CPU0_P0_TX_BUF_C_DP<9>")
	)
	(segment
		(start 333.225648 -431.148998)
		(end 333.507588 -431.148998)
		(width 0.14224)
		(layer "In11.Cu")
		(net "P5E_CPU0_P0_TX_BUF_C_DP<9>")
	)
	(segment
		(start 332.985872 -425.32681)
		(end 332.985872 -430.833276)
		(width 0.14224)
		(layer "In11.Cu")
		(net "P5E_CPU0_P0_TX_BUF_C_DP<9>")
	)
	(segment
		(start 332.226666 -420.952168)
		(end 331.935836 -421.242998)
		(width 0.14224)
		(layer "In11.Cu")
		(net "P5E_CPU0_P0_TX_BUF_C_DP<9>")
	)
	(segment
		(start 333.649828 -431.006758)
		(end 333.649828 -430.689766)
		(width 0.14224)
		(layer "In11.Cu")
		(net "P5E_CPU0_P0_TX_BUF_C_DP<9>")
	)
	(segment
		(start 332.3844 -423.349166)
		(end 332.557882 -423.441876)
		(width 0.14224)
		(layer "In11.Cu")
		(net "P5E_CPU0_P0_TX_BUF_C_DP<9>")
	)
	(segment
		(start 332.23073 -422.362376)
		(end 332.354682 -422.771062)
		(width 0.14224)
		(layer "In11.Cu")
		(net "P5E_CPU0_P0_TX_BUF_C_DP<9>")
	)
	(segment
		(start 332.557882 -423.441876)
		(end 332.681834 -423.850562)
		(width 0.14224)
		(layer "In11.Cu")
		(net "P5E_CPU0_P0_TX_BUF_C_DP<9>")
	)
	(arc
		(start 332.985872 -430.833276)
		(mid 333.009499 -430.952056)
		(end 333.076804 -431.052732)
		(width 0.14224)
		(layer "In11.Cu")
		(net "P5E_CPU0_P0_TX_BUF_C_DP<9>")
	)
	(arc
		(start 333.135732 -431.11166)
		(mid 333.176972 -431.139279)
		(end 333.225648 -431.148998)
		(width 0.14224)
		(layer "In11.Cu")
		(net "P5E_CPU0_P0_TX_BUF_C_DP<9>")
	)
	(segment
		(start 328.892916 -417.461954)
		(end 328.892916 -420.681658)
		(width 0.12954)
		(layer "F.Cu")
		(net "P5E_CPU0_P0_TX_BUF_C_DP<8>")
	)
	(segment
		(start 328.892916 -420.681658)
		(end 329.163426 -420.952168)
		(width 0.12954)
		(layer "F.Cu")
		(net "P5E_CPU0_P0_TX_BUF_C_DP<8>")
	)
	(segment
		(start 329.188826 -417.166044)
		(end 328.892916 -417.461954)
		(width 0.12954)
		(layer "F.Cu")
		(net "P5E_CPU0_P0_TX_BUF_C_DP<8>")
	)
	(segment
		(start 329.03668 -422.052242)
		(end 329.215242 -422.126156)
		(width 0.14224)
		(layer "In11.Cu")
		(net "P5E_CPU0_P0_TX_BUF_C_DP<8>")
	)
	(segment
		(start 330.599288 -425.826428)
		(end 330.825602 -426.372528)
		(width 0.14224)
		(layer "In11.Cu")
		(net "P5E_CPU0_P0_TX_BUF_C_DP<8>")
	)
	(segment
		(start 331.649832 -430.00676)
		(end 331.649832 -429.689768)
		(width 0.14224)
		(layer "In11.Cu")
		(net "P5E_CPU0_P0_TX_BUF_C_DP<8>")
	)
	(segment
		(start 330.510388 -425.252642)
		(end 330.67371 -425.647104)
		(width 0.14224)
		(layer "In11.Cu")
		(net "P5E_CPU0_P0_TX_BUF_C_DP<8>")
	)
	(segment
		(start 329.736958 -423.739818)
		(end 329.901296 -424.137328)
		(width 0.14224)
		(layer "In11.Cu")
		(net "P5E_CPU0_P0_TX_BUF_C_DP<8>")
	)
	(segment
		(start 329.647042 -423.168318)
		(end 329.810364 -423.56278)
		(width 0.14224)
		(layer "In11.Cu")
		(net "P5E_CPU0_P0_TX_BUF_C_DP<8>")
	)
	(segment
		(start 330.167742 -424.784266)
		(end 330.33081 -425.178474)
		(width 0.14224)
		(layer "In11.Cu")
		(net "P5E_CPU0_P0_TX_BUF_C_DP<8>")
	)
	(segment
		(start 330.825602 -426.372528)
		(end 330.825602 -429.60036)
		(width 0.14224)
		(layer "In11.Cu")
		(net "P5E_CPU0_P0_TX_BUF_C_DP<8>")
	)
	(segment
		(start 331.507592 -430.149)
		(end 331.649832 -430.00676)
		(width 0.14224)
		(layer "In11.Cu")
		(net "P5E_CPU0_P0_TX_BUF_C_DP<8>")
	)
	(segment
		(start 330.33081 -425.178474)
		(end 330.510388 -425.252642)
		(width 0.14224)
		(layer "In11.Cu")
		(net "P5E_CPU0_P0_TX_BUF_C_DP<8>")
	)
	(segment
		(start 329.467464 -423.09415)
		(end 329.647042 -423.168318)
		(width 0.14224)
		(layer "In11.Cu")
		(net "P5E_CPU0_P0_TX_BUF_C_DP<8>")
	)
	(segment
		(start 329.901296 -424.137328)
		(end 330.078588 -424.21048)
		(width 0.14224)
		(layer "In11.Cu")
		(net "P5E_CPU0_P0_TX_BUF_C_DP<8>")
	)
	(segment
		(start 329.215242 -422.126156)
		(end 329.378564 -422.520618)
		(width 0.14224)
		(layer "In11.Cu")
		(net "P5E_CPU0_P0_TX_BUF_C_DP<8>")
	)
	(segment
		(start 329.163426 -420.952168)
		(end 328.872596 -421.242998)
		(width 0.14224)
		(layer "In11.Cu")
		(net "P5E_CPU0_P0_TX_BUF_C_DP<8>")
	)
	(segment
		(start 330.078588 -424.21048)
		(end 330.24191 -424.604942)
		(width 0.14224)
		(layer "In11.Cu")
		(net "P5E_CPU0_P0_TX_BUF_C_DP<8>")
	)
	(segment
		(start 328.872596 -421.655494)
		(end 329.03668 -422.052242)
		(width 0.14224)
		(layer "In11.Cu")
		(net "P5E_CPU0_P0_TX_BUF_C_DP<8>")
	)
	(segment
		(start 328.872596 -421.242998)
		(end 328.872596 -421.655494)
		(width 0.14224)
		(layer "In11.Cu")
		(net "P5E_CPU0_P0_TX_BUF_C_DP<8>")
	)
	(segment
		(start 329.378564 -422.520618)
		(end 329.304396 -422.699942)
		(width 0.14224)
		(layer "In11.Cu")
		(net "P5E_CPU0_P0_TX_BUF_C_DP<8>")
	)
	(segment
		(start 331.358748 -430.149)
		(end 331.507592 -430.149)
		(width 0.14224)
		(layer "In11.Cu")
		(net "P5E_CPU0_P0_TX_BUF_C_DP<8>")
	)
	(segment
		(start 329.810364 -423.56278)
		(end 329.736958 -423.739818)
		(width 0.14224)
		(layer "In11.Cu")
		(net "P5E_CPU0_P0_TX_BUF_C_DP<8>")
	)
	(segment
		(start 330.24191 -424.604942)
		(end 330.167742 -424.784266)
		(width 0.14224)
		(layer "In11.Cu")
		(net "P5E_CPU0_P0_TX_BUF_C_DP<8>")
	)
	(segment
		(start 329.304396 -422.699942)
		(end 329.467464 -423.09415)
		(width 0.14224)
		(layer "In11.Cu")
		(net "P5E_CPU0_P0_TX_BUF_C_DP<8>")
	)
	(segment
		(start 330.67371 -425.647104)
		(end 330.599288 -425.826428)
		(width 0.14224)
		(layer "In11.Cu")
		(net "P5E_CPU0_P0_TX_BUF_C_DP<8>")
	)
	(segment
		(start 330.967842 -429.943768)
		(end 331.041756 -430.017682)
		(width 0.14224)
		(layer "In11.Cu")
		(net "P5E_CPU0_P0_TX_BUF_C_DP<8>")
	)
	(arc
		(start 330.825602 -429.60036)
		(mid 330.86257 -429.786209)
		(end 330.967842 -429.943768)
		(width 0.14224)
		(layer "In11.Cu")
		(net "P5E_CPU0_P0_TX_BUF_C_DP<8>")
	)
	(arc
		(start 331.041756 -430.017682)
		(mid 331.187193 -430.11486)
		(end 331.358748 -430.149)
		(width 0.14224)
		(layer "In11.Cu")
		(net "P5E_CPU0_P0_TX_BUF_C_DP<8>")
	)
	(segment
		(start 325.829676 -417.461954)
		(end 325.829676 -420.681658)
		(width 0.12954)
		(layer "F.Cu")
		(net "P5E_CPU0_P0_TX_BUF_C_DP<7>")
	)
	(segment
		(start 326.125586 -417.166044)
		(end 325.829676 -417.461954)
		(width 0.12954)
		(layer "F.Cu")
		(net "P5E_CPU0_P0_TX_BUF_C_DP<7>")
	)
	(segment
		(start 325.829676 -420.681658)
		(end 326.100186 -420.952168)
		(width 0.12954)
		(layer "F.Cu")
		(net "P5E_CPU0_P0_TX_BUF_C_DP<7>")
	)
	(segment
		(start 326.282812 -422.463976)
		(end 326.473058 -422.501822)
		(width 0.14224)
		(layer "In11.Cu")
		(net "P5E_CPU0_P0_TX_BUF_C_DP<7>")
	)
	(segment
		(start 326.100186 -420.952168)
		(end 325.819008 -421.233346)
		(width 0.14224)
		(layer "In11.Cu")
		(net "P5E_CPU0_P0_TX_BUF_C_DP<7>")
	)
	(segment
		(start 327.09993 -423.439336)
		(end 327.337166 -423.794428)
		(width 0.14224)
		(layer "In11.Cu")
		(net "P5E_CPU0_P0_TX_BUF_C_DP<7>")
	)
	(segment
		(start 327.969118 -424.987466)
		(end 327.969118 -430.94529)
		(width 0.14224)
		(layer "In11.Cu")
		(net "P5E_CPU0_P0_TX_BUF_C_DP<7>")
	)
	(segment
		(start 326.710548 -422.85666)
		(end 326.672702 -423.046906)
		(width 0.14224)
		(layer "In11.Cu")
		(net "P5E_CPU0_P0_TX_BUF_C_DP<7>")
	)
	(segment
		(start 327.337166 -423.794428)
		(end 327.29932 -423.984674)
		(width 0.14224)
		(layer "In11.Cu")
		(net "P5E_CPU0_P0_TX_BUF_C_DP<7>")
	)
	(segment
		(start 327.969118 -430.94529)
		(end 328.172826 -431.148998)
		(width 0.14224)
		(layer "In11.Cu")
		(net "P5E_CPU0_P0_TX_BUF_C_DP<7>")
	)
	(segment
		(start 327.29932 -423.984674)
		(end 327.969118 -424.987466)
		(width 0.14224)
		(layer "In11.Cu")
		(net "P5E_CPU0_P0_TX_BUF_C_DP<7>")
	)
	(segment
		(start 326.672702 -423.046906)
		(end 326.909684 -423.40149)
		(width 0.14224)
		(layer "In11.Cu")
		(net "P5E_CPU0_P0_TX_BUF_C_DP<7>")
	)
	(segment
		(start 326.909684 -423.40149)
		(end 327.09993 -423.439336)
		(width 0.14224)
		(layer "In11.Cu")
		(net "P5E_CPU0_P0_TX_BUF_C_DP<7>")
	)
	(segment
		(start 328.172826 -431.148998)
		(end 328.507344 -431.148998)
		(width 0.14224)
		(layer "In11.Cu")
		(net "P5E_CPU0_P0_TX_BUF_C_DP<7>")
	)
	(segment
		(start 325.819008 -421.76954)
		(end 326.282812 -422.463976)
		(width 0.14224)
		(layer "In11.Cu")
		(net "P5E_CPU0_P0_TX_BUF_C_DP<7>")
	)
	(segment
		(start 326.473058 -422.501822)
		(end 326.710548 -422.85666)
		(width 0.14224)
		(layer "In11.Cu")
		(net "P5E_CPU0_P0_TX_BUF_C_DP<7>")
	)
	(segment
		(start 325.819008 -421.233346)
		(end 325.819008 -421.76954)
		(width 0.14224)
		(layer "In11.Cu")
		(net "P5E_CPU0_P0_TX_BUF_C_DP<7>")
	)
	(segment
		(start 328.507344 -431.148998)
		(end 328.649584 -431.006758)
		(width 0.14224)
		(layer "In11.Cu")
		(net "P5E_CPU0_P0_TX_BUF_C_DP<7>")
	)
	(segment
		(start 328.649584 -431.006758)
		(end 328.649584 -430.689766)
		(width 0.14224)
		(layer "In11.Cu")
		(net "P5E_CPU0_P0_TX_BUF_C_DP<7>")
	)
	(segment
		(start 322.766436 -420.681658)
		(end 323.036946 -420.952168)
		(width 0.12954)
		(layer "F.Cu")
		(net "P5E_CPU0_P0_TX_BUF_C_DP<6>")
	)
	(segment
		(start 323.062346 -417.166044)
		(end 322.766436 -417.461954)
		(width 0.12954)
		(layer "F.Cu")
		(net "P5E_CPU0_P0_TX_BUF_C_DP<6>")
	)
	(segment
		(start 322.766436 -417.461954)
		(end 322.766436 -420.681658)
		(width 0.12954)
		(layer "F.Cu")
		(net "P5E_CPU0_P0_TX_BUF_C_DP<6>")
	)
	(segment
		(start 324.9676 -423.448226)
		(end 325.15429 -423.411142)
		(width 0.14224)
		(layer "In11.Cu")
		(net "P5E_CPU0_P0_TX_BUF_C_DP<6>")
	)
	(segment
		(start 324.03415 -422.824402)
		(end 324.22084 -422.787318)
		(width 0.14224)
		(layer "In11.Cu")
		(net "P5E_CPU0_P0_TX_BUF_C_DP<6>")
	)
	(segment
		(start 322.746116 -421.945054)
		(end 322.761864 -421.97401)
		(width 0.14224)
		(layer "In11.Cu")
		(net "P5E_CPU0_P0_TX_BUF_C_DP<6>")
	)
	(segment
		(start 326.649588 -430.006506)
		(end 326.649588 -429.689768)
		(width 0.14224)
		(layer "In11.Cu")
		(net "P5E_CPU0_P0_TX_BUF_C_DP<6>")
	)
	(segment
		(start 326.066912 -429.996092)
		(end 326.131174 -430.060354)
		(width 0.14224)
		(layer "In11.Cu")
		(net "P5E_CPU0_P0_TX_BUF_C_DP<6>")
	)
	(segment
		(start 322.746116 -421.242998)
		(end 322.746116 -421.945054)
		(width 0.14224)
		(layer "In11.Cu")
		(net "P5E_CPU0_P0_TX_BUF_C_DP<6>")
	)
	(segment
		(start 325.15429 -423.411142)
		(end 325.509382 -423.648378)
		(width 0.14224)
		(layer "In11.Cu")
		(net "P5E_CPU0_P0_TX_BUF_C_DP<6>")
	)
	(segment
		(start 325.980552 -424.28922)
		(end 325.980552 -429.787558)
		(width 0.14224)
		(layer "In11.Cu")
		(net "P5E_CPU0_P0_TX_BUF_C_DP<6>")
	)
	(segment
		(start 325.546466 -423.835068)
		(end 325.844154 -424.03395)
		(width 0.14224)
		(layer "In11.Cu")
		(net "P5E_CPU0_P0_TX_BUF_C_DP<6>")
	)
	(segment
		(start 323.642482 -422.40073)
		(end 323.679566 -422.58742)
		(width 0.14224)
		(layer "In11.Cu")
		(net "P5E_CPU0_P0_TX_BUF_C_DP<6>")
	)
	(segment
		(start 324.575932 -423.024554)
		(end 324.613016 -423.211244)
		(width 0.14224)
		(layer "In11.Cu")
		(net "P5E_CPU0_P0_TX_BUF_C_DP<6>")
	)
	(segment
		(start 323.679566 -422.58742)
		(end 324.03415 -422.824402)
		(width 0.14224)
		(layer "In11.Cu")
		(net "P5E_CPU0_P0_TX_BUF_C_DP<6>")
	)
	(segment
		(start 325.509382 -423.648378)
		(end 325.546466 -423.835068)
		(width 0.14224)
		(layer "In11.Cu")
		(net "P5E_CPU0_P0_TX_BUF_C_DP<6>")
	)
	(segment
		(start 323.28739 -422.163494)
		(end 323.642482 -422.40073)
		(width 0.14224)
		(layer "In11.Cu")
		(net "P5E_CPU0_P0_TX_BUF_C_DP<6>")
	)
	(segment
		(start 325.844154 -424.03395)
		(end 325.980552 -424.28922)
		(width 0.14224)
		(layer "In11.Cu")
		(net "P5E_CPU0_P0_TX_BUF_C_DP<6>")
	)
	(segment
		(start 324.613016 -423.211244)
		(end 324.9676 -423.448226)
		(width 0.14224)
		(layer "In11.Cu")
		(net "P5E_CPU0_P0_TX_BUF_C_DP<6>")
	)
	(segment
		(start 324.22084 -422.787318)
		(end 324.575932 -423.024554)
		(width 0.14224)
		(layer "In11.Cu")
		(net "P5E_CPU0_P0_TX_BUF_C_DP<6>")
	)
	(segment
		(start 326.493124 -430.16297)
		(end 326.649588 -430.006506)
		(width 0.14224)
		(layer "In11.Cu")
		(net "P5E_CPU0_P0_TX_BUF_C_DP<6>")
	)
	(segment
		(start 323.1007 -422.200578)
		(end 323.28739 -422.163494)
		(width 0.14224)
		(layer "In11.Cu")
		(net "P5E_CPU0_P0_TX_BUF_C_DP<6>")
	)
	(segment
		(start 323.036946 -420.952168)
		(end 322.746116 -421.242998)
		(width 0.14224)
		(layer "In11.Cu")
		(net "P5E_CPU0_P0_TX_BUF_C_DP<6>")
	)
	(segment
		(start 326.378824 -430.16297)
		(end 326.493124 -430.16297)
		(width 0.14224)
		(layer "In11.Cu")
		(net "P5E_CPU0_P0_TX_BUF_C_DP<6>")
	)
	(segment
		(start 322.761864 -421.97401)
		(end 323.1007 -422.200578)
		(width 0.14224)
		(layer "In11.Cu")
		(net "P5E_CPU0_P0_TX_BUF_C_DP<6>")
	)
	(arc
		(start 326.131174 -430.060354)
		(mid 326.244797 -430.136274)
		(end 326.378824 -430.16297)
		(width 0.14224)
		(layer "In11.Cu")
		(net "P5E_CPU0_P0_TX_BUF_C_DP<6>")
	)
	(arc
		(start 325.980552 -429.787558)
		(mid 326.002999 -429.900409)
		(end 326.066912 -429.996092)
		(width 0.14224)
		(layer "In11.Cu")
		(net "P5E_CPU0_P0_TX_BUF_C_DP<6>")
	)
	(segment
		(start 319.703196 -417.461954)
		(end 319.703196 -420.681658)
		(width 0.12954)
		(layer "F.Cu")
		(net "P5E_CPU0_P0_TX_BUF_C_DP<5>")
	)
	(segment
		(start 319.703196 -420.681658)
		(end 319.973706 -420.952168)
		(width 0.12954)
		(layer "F.Cu")
		(net "P5E_CPU0_P0_TX_BUF_C_DP<5>")
	)
	(segment
		(start 319.999106 -417.166044)
		(end 319.703196 -417.461954)
		(width 0.12954)
		(layer "F.Cu")
		(net "P5E_CPU0_P0_TX_BUF_C_DP<5>")
	)
	(segment
		(start 324.078092 -431.054256)
		(end 324.103492 -431.079656)
		(width 0.14224)
		(layer "In11.Cu")
		(net "P5E_CPU0_P0_TX_BUF_C_DP<5>")
	)
	(segment
		(start 319.682876 -421.242998)
		(end 319.682876 -421.71747)
		(width 0.14224)
		(layer "In11.Cu")
		(net "P5E_CPU0_P0_TX_BUF_C_DP<5>")
	)
	(segment
		(start 324.507352 -431.148998)
		(end 324.649592 -431.006758)
		(width 0.14224)
		(layer "In11.Cu")
		(net "P5E_CPU0_P0_TX_BUF_C_DP<5>")
	)
	(segment
		(start 324.270878 -431.148998)
		(end 324.507352 -431.148998)
		(width 0.14224)
		(layer "In11.Cu")
		(net "P5E_CPU0_P0_TX_BUF_C_DP<5>")
	)
	(segment
		(start 322.430648 -423.307764)
		(end 322.8467 -423.724324)
		(width 0.14224)
		(layer "In11.Cu")
		(net "P5E_CPU0_P0_TX_BUF_C_DP<5>")
	)
	(segment
		(start 322.430648 -423.113708)
		(end 322.430648 -423.307764)
		(width 0.14224)
		(layer "In11.Cu")
		(net "P5E_CPU0_P0_TX_BUF_C_DP<5>")
	)
	(segment
		(start 321.935094 -422.811448)
		(end 322.128896 -422.811448)
		(width 0.14224)
		(layer "In11.Cu")
		(net "P5E_CPU0_P0_TX_BUF_C_DP<5>")
	)
	(segment
		(start 323.342508 -424.22064)
		(end 323.866002 -424.744642)
		(width 0.14224)
		(layer "In11.Cu")
		(net "P5E_CPU0_P0_TX_BUF_C_DP<5>")
	)
	(segment
		(start 323.040756 -423.724324)
		(end 323.342508 -424.026584)
		(width 0.14224)
		(layer "In11.Cu")
		(net "P5E_CPU0_P0_TX_BUF_C_DP<5>")
	)
	(segment
		(start 323.985636 -424.864276)
		(end 323.985636 -430.831244)
		(width 0.14224)
		(layer "In11.Cu")
		(net "P5E_CPU0_P0_TX_BUF_C_DP<5>")
	)
	(segment
		(start 319.951862 -421.986202)
		(end 321.613784 -422.490138)
		(width 0.14224)
		(layer "In11.Cu")
		(net "P5E_CPU0_P0_TX_BUF_C_DP<5>")
	)
	(segment
		(start 319.682876 -421.71747)
		(end 319.951862 -421.986202)
		(width 0.14224)
		(layer "In11.Cu")
		(net "P5E_CPU0_P0_TX_BUF_C_DP<5>")
	)
	(segment
		(start 319.973706 -420.952168)
		(end 319.682876 -421.242998)
		(width 0.14224)
		(layer "In11.Cu")
		(net "P5E_CPU0_P0_TX_BUF_C_DP<5>")
	)
	(segment
		(start 323.342508 -424.026584)
		(end 323.342508 -424.22064)
		(width 0.14224)
		(layer "In11.Cu")
		(net "P5E_CPU0_P0_TX_BUF_C_DP<5>")
	)
	(segment
		(start 323.866002 -424.744642)
		(end 323.985636 -424.864276)
		(width 0.14224)
		(layer "In11.Cu")
		(net "P5E_CPU0_P0_TX_BUF_C_DP<5>")
	)
	(segment
		(start 324.649592 -431.006758)
		(end 324.649592 -430.689766)
		(width 0.14224)
		(layer "In11.Cu")
		(net "P5E_CPU0_P0_TX_BUF_C_DP<5>")
	)
	(segment
		(start 322.128896 -422.811448)
		(end 322.430648 -423.113708)
		(width 0.14224)
		(layer "In11.Cu")
		(net "P5E_CPU0_P0_TX_BUF_C_DP<5>")
	)
	(segment
		(start 322.8467 -423.724324)
		(end 323.040756 -423.724324)
		(width 0.14224)
		(layer "In11.Cu")
		(net "P5E_CPU0_P0_TX_BUF_C_DP<5>")
	)
	(segment
		(start 321.613784 -422.490138)
		(end 321.935094 -422.811448)
		(width 0.14224)
		(layer "In11.Cu")
		(net "P5E_CPU0_P0_TX_BUF_C_DP<5>")
	)
	(arc
		(start 324.103492 -431.079656)
		(mid 324.180289 -431.13097)
		(end 324.270878 -431.148998)
		(width 0.14224)
		(layer "In11.Cu")
		(net "P5E_CPU0_P0_TX_BUF_C_DP<5>")
	)
	(arc
		(start 323.985636 -430.831244)
		(mid 324.009665 -430.951954)
		(end 324.078092 -431.054256)
		(width 0.14224)
		(layer "In11.Cu")
		(net "P5E_CPU0_P0_TX_BUF_C_DP<5>")
	)
	(segment
		(start 316.935866 -417.166044)
		(end 316.639956 -417.461954)
		(width 0.12954)
		(layer "F.Cu")
		(net "P5E_CPU0_P0_TX_BUF_C_DP<4>")
	)
	(segment
		(start 316.639956 -417.461954)
		(end 316.639956 -420.681658)
		(width 0.12954)
		(layer "F.Cu")
		(net "P5E_CPU0_P0_TX_BUF_C_DP<4>")
	)
	(segment
		(start 316.639956 -420.681658)
		(end 316.910466 -420.952168)
		(width 0.12954)
		(layer "F.Cu")
		(net "P5E_CPU0_P0_TX_BUF_C_DP<4>")
	)
	(segment
		(start 316.625224 -421.595042)
		(end 316.717426 -421.767)
		(width 0.14224)
		(layer "In11.Cu")
		(net "P5E_CPU0_P0_TX_BUF_C_DP<4>")
	)
	(segment
		(start 320.32956 -423.393616)
		(end 320.684144 -423.630598)
		(width 0.14224)
		(layer "In11.Cu")
		(net "P5E_CPU0_P0_TX_BUF_C_DP<4>")
	)
	(segment
		(start 321.229482 -423.830242)
		(end 321.267328 -424.020488)
		(width 0.14224)
		(layer "In11.Cu")
		(net "P5E_CPU0_P0_TX_BUF_C_DP<4>")
	)
	(segment
		(start 318.025272 -421.827198)
		(end 318.162432 -421.964358)
		(width 0.14224)
		(layer "In11.Cu")
		(net "P5E_CPU0_P0_TX_BUF_C_DP<4>")
	)
	(segment
		(start 320.291714 -423.20337)
		(end 320.32956 -423.393616)
		(width 0.14224)
		(layer "In11.Cu")
		(net "P5E_CPU0_P0_TX_BUF_C_DP<4>")
	)
	(segment
		(start 317.461392 -421.964358)
		(end 317.598552 -421.827198)
		(width 0.14224)
		(layer "In11.Cu")
		(net "P5E_CPU0_P0_TX_BUF_C_DP<4>")
	)
	(segment
		(start 316.717426 -421.767)
		(end 317.01232 -421.964358)
		(width 0.14224)
		(layer "In11.Cu")
		(net "P5E_CPU0_P0_TX_BUF_C_DP<4>")
	)
	(segment
		(start 322.649596 -430.050702)
		(end 322.649596 -429.689768)
		(width 0.14224)
		(layer "In11.Cu")
		(net "P5E_CPU0_P0_TX_BUF_C_DP<4>")
	)
	(segment
		(start 317.01232 -421.964358)
		(end 317.461392 -421.964358)
		(width 0.14224)
		(layer "In11.Cu")
		(net "P5E_CPU0_P0_TX_BUF_C_DP<4>")
	)
	(segment
		(start 321.975988 -424.624246)
		(end 321.975988 -429.839628)
		(width 0.14224)
		(layer "In11.Cu")
		(net "P5E_CPU0_P0_TX_BUF_C_DP<4>")
	)
	(segment
		(start 316.625224 -421.23741)
		(end 316.625224 -421.595042)
		(width 0.14224)
		(layer "In11.Cu")
		(net "P5E_CPU0_P0_TX_BUF_C_DP<4>")
	)
	(segment
		(start 322.314316 -430.177956)
		(end 322.522342 -430.177956)
		(width 0.14224)
		(layer "In11.Cu")
		(net "P5E_CPU0_P0_TX_BUF_C_DP<4>")
	)
	(segment
		(start 319.936622 -422.966134)
		(end 320.291714 -423.20337)
		(width 0.14224)
		(layer "In11.Cu")
		(net "P5E_CPU0_P0_TX_BUF_C_DP<4>")
	)
	(segment
		(start 316.910466 -420.952168)
		(end 316.625224 -421.23741)
		(width 0.14224)
		(layer "In11.Cu")
		(net "P5E_CPU0_P0_TX_BUF_C_DP<4>")
	)
	(segment
		(start 320.684144 -423.630598)
		(end 320.87439 -423.592752)
		(width 0.14224)
		(layer "In11.Cu")
		(net "P5E_CPU0_P0_TX_BUF_C_DP<4>")
	)
	(segment
		(start 319.746376 -423.00398)
		(end 319.936622 -422.966134)
		(width 0.14224)
		(layer "In11.Cu")
		(net "P5E_CPU0_P0_TX_BUF_C_DP<4>")
	)
	(segment
		(start 321.267328 -424.020488)
		(end 321.86753 -424.421554)
		(width 0.14224)
		(layer "In11.Cu")
		(net "P5E_CPU0_P0_TX_BUF_C_DP<4>")
	)
	(segment
		(start 322.522342 -430.177956)
		(end 322.649596 -430.050702)
		(width 0.14224)
		(layer "In11.Cu")
		(net "P5E_CPU0_P0_TX_BUF_C_DP<4>")
	)
	(segment
		(start 319.391792 -422.766998)
		(end 319.746376 -423.00398)
		(width 0.14224)
		(layer "In11.Cu")
		(net "P5E_CPU0_P0_TX_BUF_C_DP<4>")
	)
	(segment
		(start 321.86753 -424.421554)
		(end 321.975988 -424.624246)
		(width 0.14224)
		(layer "In11.Cu")
		(net "P5E_CPU0_P0_TX_BUF_C_DP<4>")
	)
	(segment
		(start 318.162432 -421.964358)
		(end 318.589152 -421.964358)
		(width 0.14224)
		(layer "In11.Cu")
		(net "P5E_CPU0_P0_TX_BUF_C_DP<4>")
	)
	(segment
		(start 320.87439 -423.592752)
		(end 321.229482 -423.830242)
		(width 0.14224)
		(layer "In11.Cu")
		(net "P5E_CPU0_P0_TX_BUF_C_DP<4>")
	)
	(segment
		(start 317.598552 -421.827198)
		(end 318.025272 -421.827198)
		(width 0.14224)
		(layer "In11.Cu")
		(net "P5E_CPU0_P0_TX_BUF_C_DP<4>")
	)
	(segment
		(start 318.589152 -421.964358)
		(end 319.391792 -422.766998)
		(width 0.14224)
		(layer "In11.Cu")
		(net "P5E_CPU0_P0_TX_BUF_C_DP<4>")
	)
	(arc
		(start 321.975988 -429.839628)
		(mid 322.075082 -430.078862)
		(end 322.314316 -430.177956)
		(width 0.14224)
		(layer "In11.Cu")
		(net "P5E_CPU0_P0_TX_BUF_C_DP<4>")
	)
	(segment
		(start 313.872626 -417.166044)
		(end 313.576716 -417.461954)
		(width 0.12954)
		(layer "F.Cu")
		(net "P5E_CPU0_P0_TX_BUF_C_DP<3>")
	)
	(segment
		(start 313.576716 -417.461954)
		(end 313.576716 -420.681658)
		(width 0.12954)
		(layer "F.Cu")
		(net "P5E_CPU0_P0_TX_BUF_C_DP<3>")
	)
	(segment
		(start 313.576716 -420.681658)
		(end 313.847226 -420.952168)
		(width 0.12954)
		(layer "F.Cu")
		(net "P5E_CPU0_P0_TX_BUF_C_DP<3>")
	)
	(segment
		(start 319.985644 -430.9618)
		(end 320.172842 -431.148998)
		(width 0.14224)
		(layer "In11.Cu")
		(net "P5E_CPU0_P0_TX_BUF_C_DP<3>")
	)
	(segment
		(start 320.172842 -431.148998)
		(end 320.50736 -431.148998)
		(width 0.14224)
		(layer "In11.Cu")
		(net "P5E_CPU0_P0_TX_BUF_C_DP<3>")
	)
	(segment
		(start 313.847226 -420.952168)
		(end 313.556396 -421.242998)
		(width 0.14224)
		(layer "In11.Cu")
		(net "P5E_CPU0_P0_TX_BUF_C_DP<3>")
	)
	(segment
		(start 314.992766 -422.038272)
		(end 315.419486 -422.038272)
		(width 0.14224)
		(layer "In11.Cu")
		(net "P5E_CPU0_P0_TX_BUF_C_DP<3>")
	)
	(segment
		(start 319.489582 -424.212512)
		(end 319.489582 -424.406568)
		(width 0.14224)
		(layer "In11.Cu")
		(net "P5E_CPU0_P0_TX_BUF_C_DP<3>")
	)
	(segment
		(start 315.419486 -422.038272)
		(end 316.530228 -422.781476)
		(width 0.14224)
		(layer "In11.Cu")
		(net "P5E_CPU0_P0_TX_BUF_C_DP<3>")
	)
	(segment
		(start 316.91326 -422.897808)
		(end 317.980822 -422.897808)
		(width 0.14224)
		(layer "In11.Cu")
		(net "P5E_CPU0_P0_TX_BUF_C_DP<3>")
	)
	(segment
		(start 313.556396 -421.745664)
		(end 313.849004 -422.038272)
		(width 0.14224)
		(layer "In11.Cu")
		(net "P5E_CPU0_P0_TX_BUF_C_DP<3>")
	)
	(segment
		(start 318.99352 -423.910506)
		(end 319.187576 -423.910506)
		(width 0.14224)
		(layer "In11.Cu")
		(net "P5E_CPU0_P0_TX_BUF_C_DP<3>")
	)
	(segment
		(start 319.985644 -425.177712)
		(end 319.985644 -430.9618)
		(width 0.14224)
		(layer "In11.Cu")
		(net "P5E_CPU0_P0_TX_BUF_C_DP<3>")
	)
	(segment
		(start 313.556396 -421.242998)
		(end 313.556396 -421.745664)
		(width 0.14224)
		(layer "In11.Cu")
		(net "P5E_CPU0_P0_TX_BUF_C_DP<3>")
	)
	(segment
		(start 320.6496 -431.006758)
		(end 320.6496 -430.689766)
		(width 0.14224)
		(layer "In11.Cu")
		(net "P5E_CPU0_P0_TX_BUF_C_DP<3>")
	)
	(segment
		(start 317.980822 -422.897808)
		(end 318.99352 -423.910506)
		(width 0.14224)
		(layer "In11.Cu")
		(net "P5E_CPU0_P0_TX_BUF_C_DP<3>")
	)
	(segment
		(start 314.291726 -422.038272)
		(end 314.428886 -421.901112)
		(width 0.14224)
		(layer "In11.Cu")
		(net "P5E_CPU0_P0_TX_BUF_C_DP<3>")
	)
	(segment
		(start 314.428886 -421.901112)
		(end 314.855606 -421.901112)
		(width 0.14224)
		(layer "In11.Cu")
		(net "P5E_CPU0_P0_TX_BUF_C_DP<3>")
	)
	(segment
		(start 314.855606 -421.901112)
		(end 314.992766 -422.038272)
		(width 0.14224)
		(layer "In11.Cu")
		(net "P5E_CPU0_P0_TX_BUF_C_DP<3>")
	)
	(segment
		(start 319.489582 -424.406568)
		(end 319.79108 -424.708066)
		(width 0.14224)
		(layer "In11.Cu")
		(net "P5E_CPU0_P0_TX_BUF_C_DP<3>")
	)
	(segment
		(start 319.187576 -423.910506)
		(end 319.489582 -424.212512)
		(width 0.14224)
		(layer "In11.Cu")
		(net "P5E_CPU0_P0_TX_BUF_C_DP<3>")
	)
	(segment
		(start 320.50736 -431.148998)
		(end 320.6496 -431.006758)
		(width 0.14224)
		(layer "In11.Cu")
		(net "P5E_CPU0_P0_TX_BUF_C_DP<3>")
	)
	(segment
		(start 313.849004 -422.038272)
		(end 314.291726 -422.038272)
		(width 0.14224)
		(layer "In11.Cu")
		(net "P5E_CPU0_P0_TX_BUF_C_DP<3>")
	)
	(arc
		(start 316.530228 -422.781476)
		(mid 316.713108 -422.868071)
		(end 316.91326 -422.897808)
		(width 0.14224)
		(layer "In11.Cu")
		(net "P5E_CPU0_P0_TX_BUF_C_DP<3>")
	)
	(arc
		(start 319.79108 -424.708066)
		(mid 319.935056 -424.923541)
		(end 319.985644 -425.177712)
		(width 0.14224)
		(layer "In11.Cu")
		(net "P5E_CPU0_P0_TX_BUF_C_DP<3>")
	)
	(segment
		(start 310.513476 -420.681658)
		(end 310.783986 -420.952168)
		(width 0.12954)
		(layer "F.Cu")
		(net "P5E_CPU0_P0_TX_BUF_C_DP<2>")
	)
	(segment
		(start 310.809386 -417.166044)
		(end 310.513476 -417.461954)
		(width 0.12954)
		(layer "F.Cu")
		(net "P5E_CPU0_P0_TX_BUF_C_DP<2>")
	)
	(segment
		(start 310.513476 -417.461954)
		(end 310.513476 -420.681658)
		(width 0.12954)
		(layer "F.Cu")
		(net "P5E_CPU0_P0_TX_BUF_C_DP<2>")
	)
	(segment
		(start 310.493156 -421.242998)
		(end 310.493156 -421.742108)
		(width 0.14224)
		(layer "In11.Cu")
		(net "P5E_CPU0_P0_TX_BUF_C_DP<2>")
	)
	(segment
		(start 310.493156 -422.300908)
		(end 310.493156 -422.67251)
		(width 0.14224)
		(layer "In11.Cu")
		(net "P5E_CPU0_P0_TX_BUF_C_DP<2>")
	)
	(segment
		(start 310.493156 -421.742108)
		(end 310.630316 -421.879268)
		(width 0.14224)
		(layer "In11.Cu")
		(net "P5E_CPU0_P0_TX_BUF_C_DP<2>")
	)
	(segment
		(start 318.284606 -430.153826)
		(end 318.502284 -430.153826)
		(width 0.14224)
		(layer "In11.Cu")
		(net "P5E_CPU0_P0_TX_BUF_C_DP<2>")
	)
	(segment
		(start 317.980568 -425.74083)
		(end 317.980568 -429.753268)
		(width 0.14224)
		(layer "In11.Cu")
		(net "P5E_CPU0_P0_TX_BUF_C_DP<2>")
	)
	(segment
		(start 311.336944 -422.886632)
		(end 311.621424 -422.886632)
		(width 0.14224)
		(layer "In11.Cu")
		(net "P5E_CPU0_P0_TX_BUF_C_DP<2>")
	)
	(segment
		(start 312.043064 -423.023792)
		(end 312.180224 -422.886632)
		(width 0.14224)
		(layer "In11.Cu")
		(net "P5E_CPU0_P0_TX_BUF_C_DP<2>")
	)
	(segment
		(start 318.502284 -430.153826)
		(end 318.649604 -430.006506)
		(width 0.14224)
		(layer "In11.Cu")
		(net "P5E_CPU0_P0_TX_BUF_C_DP<2>")
	)
	(segment
		(start 312.180224 -422.886632)
		(end 312.464704 -422.886632)
		(width 0.14224)
		(layer "In11.Cu")
		(net "P5E_CPU0_P0_TX_BUF_C_DP<2>")
	)
	(segment
		(start 310.630316 -421.879268)
		(end 310.630316 -422.163748)
		(width 0.14224)
		(layer "In11.Cu")
		(net "P5E_CPU0_P0_TX_BUF_C_DP<2>")
	)
	(segment
		(start 312.886344 -423.023792)
		(end 313.023504 -422.886632)
		(width 0.14224)
		(layer "In11.Cu")
		(net "P5E_CPU0_P0_TX_BUF_C_DP<2>")
	)
	(segment
		(start 318.649604 -430.006506)
		(end 318.649604 -429.689768)
		(width 0.14224)
		(layer "In11.Cu")
		(net "P5E_CPU0_P0_TX_BUF_C_DP<2>")
	)
	(segment
		(start 311.199784 -423.023792)
		(end 311.336944 -422.886632)
		(width 0.14224)
		(layer "In11.Cu")
		(net "P5E_CPU0_P0_TX_BUF_C_DP<2>")
	)
	(segment
		(start 315.043566 -423.023792)
		(end 315.493654 -423.209974)
		(width 0.14224)
		(layer "In11.Cu")
		(net "P5E_CPU0_P0_TX_BUF_C_DP<2>")
	)
	(segment
		(start 313.307984 -422.886632)
		(end 313.445144 -423.023792)
		(width 0.14224)
		(layer "In11.Cu")
		(net "P5E_CPU0_P0_TX_BUF_C_DP<2>")
	)
	(segment
		(start 316.561724 -423.826432)
		(end 316.765178 -423.826432)
		(width 0.14224)
		(layer "In11.Cu")
		(net "P5E_CPU0_P0_TX_BUF_C_DP<2>")
	)
	(segment
		(start 312.464704 -422.886632)
		(end 312.601864 -423.023792)
		(width 0.14224)
		(layer "In11.Cu")
		(net "P5E_CPU0_P0_TX_BUF_C_DP<2>")
	)
	(segment
		(start 315.493654 -423.209974)
		(end 316.293754 -423.745152)
		(width 0.14224)
		(layer "In11.Cu")
		(net "P5E_CPU0_P0_TX_BUF_C_DP<2>")
	)
	(segment
		(start 313.023504 -422.886632)
		(end 313.307984 -422.886632)
		(width 0.14224)
		(layer "In11.Cu")
		(net "P5E_CPU0_P0_TX_BUF_C_DP<2>")
	)
	(segment
		(start 317.23965 -424.023028)
		(end 317.289688 -424.073066)
		(width 0.14224)
		(layer "In11.Cu")
		(net "P5E_CPU0_P0_TX_BUF_C_DP<2>")
	)
	(segment
		(start 312.601864 -423.023792)
		(end 312.886344 -423.023792)
		(width 0.14224)
		(layer "In11.Cu")
		(net "P5E_CPU0_P0_TX_BUF_C_DP<2>")
	)
	(segment
		(start 313.445144 -423.023792)
		(end 315.043566 -423.023792)
		(width 0.14224)
		(layer "In11.Cu")
		(net "P5E_CPU0_P0_TX_BUF_C_DP<2>")
	)
	(segment
		(start 310.783986 -420.952168)
		(end 310.493156 -421.242998)
		(width 0.14224)
		(layer "In11.Cu")
		(net "P5E_CPU0_P0_TX_BUF_C_DP<2>")
	)
	(segment
		(start 310.844438 -423.023792)
		(end 311.199784 -423.023792)
		(width 0.14224)
		(layer "In11.Cu")
		(net "P5E_CPU0_P0_TX_BUF_C_DP<2>")
	)
	(segment
		(start 311.758584 -423.023792)
		(end 312.043064 -423.023792)
		(width 0.14224)
		(layer "In11.Cu")
		(net "P5E_CPU0_P0_TX_BUF_C_DP<2>")
	)
	(segment
		(start 310.630316 -422.163748)
		(end 310.493156 -422.300908)
		(width 0.14224)
		(layer "In11.Cu")
		(net "P5E_CPU0_P0_TX_BUF_C_DP<2>")
	)
	(segment
		(start 311.621424 -422.886632)
		(end 311.758584 -423.023792)
		(width 0.14224)
		(layer "In11.Cu")
		(net "P5E_CPU0_P0_TX_BUF_C_DP<2>")
	)
	(arc
		(start 318.117982 -430.084738)
		(mid 318.194416 -430.135843)
		(end 318.284606 -430.153826)
		(width 0.14224)
		(layer "In11.Cu")
		(net "P5E_CPU0_P0_TX_BUF_C_DP<2>")
	)
	(arc
		(start 316.765178 -423.826432)
		(mid 317.02197 -423.877529)
		(end 317.23965 -424.023028)
		(width 0.14224)
		(layer "In11.Cu")
		(net "P5E_CPU0_P0_TX_BUF_C_DP<2>")
	)
	(arc
		(start 317.980568 -429.753268)
		(mid 318.01629 -429.932674)
		(end 318.117982 -430.084738)
		(width 0.14224)
		(layer "In11.Cu")
		(net "P5E_CPU0_P0_TX_BUF_C_DP<2>")
	)
	(arc
		(start 316.293754 -423.745152)
		(mid 316.421698 -423.805731)
		(end 316.561724 -423.826432)
		(width 0.14224)
		(layer "In11.Cu")
		(net "P5E_CPU0_P0_TX_BUF_C_DP<2>")
	)
	(arc
		(start 317.289688 -424.073066)
		(mid 317.801016 -424.838228)
		(end 317.980568 -425.74083)
		(width 0.14224)
		(layer "In11.Cu")
		(net "P5E_CPU0_P0_TX_BUF_C_DP<2>")
	)
	(arc
		(start 310.493156 -422.67251)
		(mid 310.596044 -422.920904)
		(end 310.844438 -423.023792)
		(width 0.14224)
		(layer "In11.Cu")
		(net "P5E_CPU0_P0_TX_BUF_C_DP<2>")
	)
	(segment
		(start 307.450236 -417.461954)
		(end 307.450236 -420.681658)
		(width 0.12954)
		(layer "F.Cu")
		(net "P5E_CPU0_P0_TX_BUF_C_DP<1>")
	)
	(segment
		(start 307.746146 -417.166044)
		(end 307.450236 -417.461954)
		(width 0.12954)
		(layer "F.Cu")
		(net "P5E_CPU0_P0_TX_BUF_C_DP<1>")
	)
	(segment
		(start 307.450236 -420.681658)
		(end 307.720746 -420.952168)
		(width 0.12954)
		(layer "F.Cu")
		(net "P5E_CPU0_P0_TX_BUF_C_DP<1>")
	)
	(segment
		(start 315.071252 -424.046904)
		(end 315.098176 -424.05808)
		(width 0.14224)
		(layer "In11.Cu")
		(net "P5E_CPU0_P0_TX_BUF_C_DP<1>")
	)
	(segment
		(start 309.265066 -423.600372)
		(end 309.58409 -423.919396)
		(width 0.14224)
		(layer "In11.Cu")
		(net "P5E_CPU0_P0_TX_BUF_C_DP<1>")
	)
	(segment
		(start 307.429916 -421.242998)
		(end 307.429916 -421.651176)
		(width 0.14224)
		(layer "In11.Cu")
		(net "P5E_CPU0_P0_TX_BUF_C_DP<1>")
	)
	(segment
		(start 307.510688 -421.845994)
		(end 307.88737 -422.222676)
		(width 0.14224)
		(layer "In11.Cu")
		(net "P5E_CPU0_P0_TX_BUF_C_DP<1>")
	)
	(segment
		(start 315.985652 -425.559982)
		(end 315.985652 -430.909222)
		(width 0.14224)
		(layer "In11.Cu")
		(net "P5E_CPU0_P0_TX_BUF_C_DP<1>")
	)
	(segment
		(start 316.507368 -431.148998)
		(end 316.649608 -431.006758)
		(width 0.14224)
		(layer "In11.Cu")
		(net "P5E_CPU0_P0_TX_BUF_C_DP<1>")
	)
	(segment
		(start 316.32525 -431.148998)
		(end 316.507368 -431.148998)
		(width 0.14224)
		(layer "In11.Cu")
		(net "P5E_CPU0_P0_TX_BUF_C_DP<1>")
	)
	(segment
		(start 308.383178 -422.718484)
		(end 308.769258 -423.104564)
		(width 0.14224)
		(layer "In11.Cu")
		(net "P5E_CPU0_P0_TX_BUF_C_DP<1>")
	)
	(segment
		(start 308.769258 -423.104564)
		(end 308.96306 -423.104564)
		(width 0.14224)
		(layer "In11.Cu")
		(net "P5E_CPU0_P0_TX_BUF_C_DP<1>")
	)
	(segment
		(start 308.96306 -423.104564)
		(end 309.265066 -423.40657)
		(width 0.14224)
		(layer "In11.Cu")
		(net "P5E_CPU0_P0_TX_BUF_C_DP<1>")
	)
	(segment
		(start 308.081172 -422.222676)
		(end 308.383178 -422.524682)
		(width 0.14224)
		(layer "In11.Cu")
		(net "P5E_CPU0_P0_TX_BUF_C_DP<1>")
	)
	(segment
		(start 308.383178 -422.524682)
		(end 308.383178 -422.718484)
		(width 0.14224)
		(layer "In11.Cu")
		(net "P5E_CPU0_P0_TX_BUF_C_DP<1>")
	)
	(segment
		(start 315.071252 -424.047158)
		(end 315.071252 -424.046904)
		(width 0.14224)
		(layer "In11.Cu")
		(net "P5E_CPU0_P0_TX_BUF_C_DP<1>")
	)
	(segment
		(start 316.649608 -431.006758)
		(end 316.649608 -430.689766)
		(width 0.14224)
		(layer "In11.Cu")
		(net "P5E_CPU0_P0_TX_BUF_C_DP<1>")
	)
	(segment
		(start 315.098176 -424.05808)
		(end 315.233558 -424.149266)
		(width 0.14224)
		(layer "In11.Cu")
		(net "P5E_CPU0_P0_TX_BUF_C_DP<1>")
	)
	(segment
		(start 314.852558 -423.956734)
		(end 315.071252 -424.047158)
		(width 0.14224)
		(layer "In11.Cu")
		(net "P5E_CPU0_P0_TX_BUF_C_DP<1>")
	)
	(segment
		(start 309.674006 -423.956734)
		(end 314.852558 -423.956734)
		(width 0.14224)
		(layer "In11.Cu")
		(net "P5E_CPU0_P0_TX_BUF_C_DP<1>")
	)
	(segment
		(start 307.88737 -422.222676)
		(end 308.081172 -422.222676)
		(width 0.14224)
		(layer "In11.Cu")
		(net "P5E_CPU0_P0_TX_BUF_C_DP<1>")
	)
	(segment
		(start 307.720746 -420.952168)
		(end 307.429916 -421.242998)
		(width 0.14224)
		(layer "In11.Cu")
		(net "P5E_CPU0_P0_TX_BUF_C_DP<1>")
	)
	(segment
		(start 309.265066 -423.40657)
		(end 309.265066 -423.600372)
		(width 0.14224)
		(layer "In11.Cu")
		(net "P5E_CPU0_P0_TX_BUF_C_DP<1>")
	)
	(segment
		(start 316.02299 -430.999138)
		(end 316.0649 -431.041048)
		(width 0.14224)
		(layer "In11.Cu")
		(net "P5E_CPU0_P0_TX_BUF_C_DP<1>")
	)
	(arc
		(start 316.0649 -431.041048)
		(mid 316.184335 -431.120915)
		(end 316.32525 -431.148998)
		(width 0.14224)
		(layer "In11.Cu")
		(net "P5E_CPU0_P0_TX_BUF_C_DP<1>")
	)
	(arc
		(start 309.58409 -423.919396)
		(mid 309.62533 -423.947015)
		(end 309.674006 -423.956734)
		(width 0.14224)
		(layer "In11.Cu")
		(net "P5E_CPU0_P0_TX_BUF_C_DP<1>")
	)
	(arc
		(start 315.985652 -430.909222)
		(mid 315.995354 -430.957906)
		(end 316.02299 -430.999138)
		(width 0.14224)
		(layer "In11.Cu")
		(net "P5E_CPU0_P0_TX_BUF_C_DP<1>")
	)
	(arc
		(start 307.429916 -421.651176)
		(mid 307.450909 -421.756625)
		(end 307.510688 -421.845994)
		(width 0.14224)
		(layer "In11.Cu")
		(net "P5E_CPU0_P0_TX_BUF_C_DP<1>")
	)
	(arc
		(start 315.233558 -424.149266)
		(mid 315.785914 -424.760634)
		(end 315.985652 -425.559982)
		(width 0.14224)
		(layer "In11.Cu")
		(net "P5E_CPU0_P0_TX_BUF_C_DP<1>")
	)
	(segment
		(start 350.335596 -417.461954)
		(end 350.335596 -420.681658)
		(width 0.12954)
		(layer "F.Cu")
		(net "P5E_CPU0_P0_TX_BUF_C_DP<15>")
	)
	(segment
		(start 350.335596 -420.681658)
		(end 350.606106 -420.952168)
		(width 0.12954)
		(layer "F.Cu")
		(net "P5E_CPU0_P0_TX_BUF_C_DP<15>")
	)
	(segment
		(start 350.631506 -417.166044)
		(end 350.335596 -417.461954)
		(width 0.12954)
		(layer "F.Cu")
		(net "P5E_CPU0_P0_TX_BUF_C_DP<15>")
	)
	(segment
		(start 345.649804 -431.006758)
		(end 345.649804 -430.689766)
		(width 0.14224)
		(layer "In11.Cu")
		(net "P5E_CPU0_P0_TX_BUF_C_DP<15>")
	)
	(segment
		(start 348.139766 -423.125392)
		(end 348.056708 -423.300906)
		(width 0.14224)
		(layer "In11.Cu")
		(net "P5E_CPU0_P0_TX_BUF_C_DP<15>")
	)
	(segment
		(start 348.716854 -423.064432)
		(end 348.54134 -422.981628)
		(width 0.14224)
		(layer "In11.Cu")
		(net "P5E_CPU0_P0_TX_BUF_C_DP<15>")
	)
	(segment
		(start 345.046808 -431.02276)
		(end 345.135708 -431.11166)
		(width 0.14224)
		(layer "In11.Cu")
		(net "P5E_CPU0_P0_TX_BUF_C_DP<15>")
	)
	(segment
		(start 349.603314 -422.60139)
		(end 349.20174 -422.745154)
		(width 0.14224)
		(layer "In11.Cu")
		(net "P5E_CPU0_P0_TX_BUF_C_DP<15>")
	)
	(segment
		(start 345.225624 -431.148998)
		(end 345.507564 -431.148998)
		(width 0.14224)
		(layer "In11.Cu")
		(net "P5E_CPU0_P0_TX_BUF_C_DP<15>")
	)
	(segment
		(start 349.118682 -422.920668)
		(end 348.716854 -423.064432)
		(width 0.14224)
		(layer "In11.Cu")
		(net "P5E_CPU0_P0_TX_BUF_C_DP<15>")
	)
	(segment
		(start 350.331786 -421.226488)
		(end 350.331786 -421.738806)
		(width 0.14224)
		(layer "In11.Cu")
		(net "P5E_CPU0_P0_TX_BUF_C_DP<15>")
	)
	(segment
		(start 350.606106 -420.952168)
		(end 350.331786 -421.226488)
		(width 0.14224)
		(layer "In11.Cu")
		(net "P5E_CPU0_P0_TX_BUF_C_DP<15>")
	)
	(segment
		(start 344.985848 -424.846242)
		(end 344.985848 -430.875694)
		(width 0.14224)
		(layer "In11.Cu")
		(net "P5E_CPU0_P0_TX_BUF_C_DP<15>")
	)
	(segment
		(start 344.986102 -424.846496)
		(end 344.985848 -424.846242)
		(width 0.14224)
		(layer "In11.Cu")
		(net "P5E_CPU0_P0_TX_BUF_C_DP<15>")
	)
	(segment
		(start 347.65488 -423.44467)
		(end 347.479366 -423.361866)
		(width 0.14224)
		(layer "In11.Cu")
		(net "P5E_CPU0_P0_TX_BUF_C_DP<15>")
	)
	(segment
		(start 348.54134 -422.981628)
		(end 348.139766 -423.125392)
		(width 0.14224)
		(layer "In11.Cu")
		(net "P5E_CPU0_P0_TX_BUF_C_DP<15>")
	)
	(segment
		(start 350.182688 -422.098724)
		(end 349.813372 -422.46804)
		(width 0.14224)
		(layer "In11.Cu")
		(net "P5E_CPU0_P0_TX_BUF_C_DP<15>")
	)
	(segment
		(start 348.056708 -423.300906)
		(end 347.65488 -423.44467)
		(width 0.14224)
		(layer "In11.Cu")
		(net "P5E_CPU0_P0_TX_BUF_C_DP<15>")
	)
	(segment
		(start 347.479366 -423.361866)
		(end 345.37269 -424.115738)
		(width 0.14224)
		(layer "In11.Cu")
		(net "P5E_CPU0_P0_TX_BUF_C_DP<15>")
	)
	(segment
		(start 345.507564 -431.148998)
		(end 345.649804 -431.006758)
		(width 0.14224)
		(layer "In11.Cu")
		(net "P5E_CPU0_P0_TX_BUF_C_DP<15>")
	)
	(segment
		(start 349.20174 -422.745154)
		(end 349.118682 -422.920668)
		(width 0.14224)
		(layer "In11.Cu")
		(net "P5E_CPU0_P0_TX_BUF_C_DP<15>")
	)
	(arc
		(start 350.331786 -421.738806)
		(mid 350.293039 -421.933598)
		(end 350.182688 -422.098724)
		(width 0.14224)
		(layer "In11.Cu")
		(net "P5E_CPU0_P0_TX_BUF_C_DP<15>")
	)
	(arc
		(start 349.730822 -422.536366)
		(mid 349.669119 -422.5729)
		(end 349.603314 -422.60139)
		(width 0.14224)
		(layer "In11.Cu")
		(net "P5E_CPU0_P0_TX_BUF_C_DP<15>")
	)
	(arc
		(start 345.135708 -431.11166)
		(mid 345.176948 -431.139279)
		(end 345.225624 -431.148998)
		(width 0.14224)
		(layer "In11.Cu")
		(net "P5E_CPU0_P0_TX_BUF_C_DP<15>")
	)
	(arc
		(start 345.37269 -424.115738)
		(mid 345.268272 -424.170942)
		(end 345.183714 -424.253406)
		(width 0.14224)
		(layer "In11.Cu")
		(net "P5E_CPU0_P0_TX_BUF_C_DP<15>")
	)
	(arc
		(start 345.183714 -424.253406)
		(mid 345.18155 -424.256196)
		(end 345.179396 -424.258994)
		(width 0.14224)
		(layer "In11.Cu")
		(net "P5E_CPU0_P0_TX_BUF_C_DP<15>")
	)
	(arc
		(start 344.985848 -430.875694)
		(mid 345.001698 -430.955288)
		(end 345.046808 -431.02276)
		(width 0.14224)
		(layer "In11.Cu")
		(net "P5E_CPU0_P0_TX_BUF_C_DP<15>")
	)
	(arc
		(start 349.813372 -422.46804)
		(mid 349.773709 -422.50415)
		(end 349.730822 -422.536366)
		(width 0.14224)
		(layer "In11.Cu")
		(net "P5E_CPU0_P0_TX_BUF_C_DP<15>")
	)
	(arc
		(start 345.179396 -424.258994)
		(mid 345.03557 -424.53722)
		(end 344.986102 -424.846496)
		(width 0.14224)
		(layer "In11.Cu")
		(net "P5E_CPU0_P0_TX_BUF_C_DP<15>")
	)
	(segment
		(start 347.272356 -417.461954)
		(end 347.272356 -420.681658)
		(width 0.12954)
		(layer "F.Cu")
		(net "P5E_CPU0_P0_TX_BUF_C_DP<14>")
	)
	(segment
		(start 347.272356 -420.681658)
		(end 347.542866 -420.952168)
		(width 0.12954)
		(layer "F.Cu")
		(net "P5E_CPU0_P0_TX_BUF_C_DP<14>")
	)
	(segment
		(start 347.568266 -417.166044)
		(end 347.272356 -417.461954)
		(width 0.12954)
		(layer "F.Cu")
		(net "P5E_CPU0_P0_TX_BUF_C_DP<14>")
	)
	(segment
		(start 343.507568 -430.148746)
		(end 343.649808 -430.006506)
		(width 0.14224)
		(layer "In11.Cu")
		(net "P5E_CPU0_P0_TX_BUF_C_DP<14>")
	)
	(segment
		(start 343.92616 -423.812716)
		(end 343.624154 -424.114722)
		(width 0.14224)
		(layer "In11.Cu")
		(net "P5E_CPU0_P0_TX_BUF_C_DP<14>")
	)
	(segment
		(start 343.649808 -430.006506)
		(end 343.649808 -429.689768)
		(width 0.14224)
		(layer "In11.Cu")
		(net "P5E_CPU0_P0_TX_BUF_C_DP<14>")
	)
	(segment
		(start 342.980772 -424.734736)
		(end 342.980772 -429.795686)
		(width 0.14224)
		(layer "In11.Cu")
		(net "P5E_CPU0_P0_TX_BUF_C_DP<14>")
	)
	(segment
		(start 344.227658 -423.317162)
		(end 343.92616 -423.61866)
		(width 0.14224)
		(layer "In11.Cu")
		(net "P5E_CPU0_P0_TX_BUF_C_DP<14>")
	)
	(segment
		(start 347.252036 -421.242998)
		(end 347.252036 -421.899334)
		(width 0.14224)
		(layer "In11.Cu")
		(net "P5E_CPU0_P0_TX_BUF_C_DP<14>")
	)
	(segment
		(start 347.252036 -421.899334)
		(end 346.969334 -422.182036)
		(width 0.14224)
		(layer "In11.Cu")
		(net "P5E_CPU0_P0_TX_BUF_C_DP<14>")
	)
	(segment
		(start 347.542866 -420.952168)
		(end 347.252036 -421.242998)
		(width 0.14224)
		(layer "In11.Cu")
		(net "P5E_CPU0_P0_TX_BUF_C_DP<14>")
	)
	(segment
		(start 346.969334 -422.182036)
		(end 346.575126 -422.345104)
		(width 0.14224)
		(layer "In11.Cu")
		(net "P5E_CPU0_P0_TX_BUF_C_DP<14>")
	)
	(segment
		(start 343.34196 -430.148746)
		(end 343.507568 -430.148746)
		(width 0.14224)
		(layer "In11.Cu")
		(net "P5E_CPU0_P0_TX_BUF_C_DP<14>")
	)
	(segment
		(start 345.064334 -423.119296)
		(end 344.88501 -423.045128)
		(width 0.14224)
		(layer "In11.Cu")
		(net "P5E_CPU0_P0_TX_BUF_C_DP<14>")
	)
	(segment
		(start 345.927172 -422.613582)
		(end 345.532964 -422.77665)
		(width 0.14224)
		(layer "In11.Cu")
		(net "P5E_CPU0_P0_TX_BUF_C_DP<14>")
	)
	(segment
		(start 343.430098 -424.114722)
		(end 343.101676 -424.443144)
		(width 0.14224)
		(layer "In11.Cu")
		(net "P5E_CPU0_P0_TX_BUF_C_DP<14>")
	)
	(segment
		(start 346.500958 -422.524682)
		(end 346.106496 -422.68775)
		(width 0.14224)
		(layer "In11.Cu")
		(net "P5E_CPU0_P0_TX_BUF_C_DP<14>")
	)
	(segment
		(start 345.458796 -422.956228)
		(end 345.064334 -423.119296)
		(width 0.14224)
		(layer "In11.Cu")
		(net "P5E_CPU0_P0_TX_BUF_C_DP<14>")
	)
	(segment
		(start 343.061544 -429.990504)
		(end 343.133426 -430.062386)
		(width 0.14224)
		(layer "In11.Cu")
		(net "P5E_CPU0_P0_TX_BUF_C_DP<14>")
	)
	(segment
		(start 346.106496 -422.68775)
		(end 345.927172 -422.613582)
		(width 0.14224)
		(layer "In11.Cu")
		(net "P5E_CPU0_P0_TX_BUF_C_DP<14>")
	)
	(segment
		(start 345.532964 -422.77665)
		(end 345.458796 -422.956228)
		(width 0.14224)
		(layer "In11.Cu")
		(net "P5E_CPU0_P0_TX_BUF_C_DP<14>")
	)
	(segment
		(start 343.92616 -423.61866)
		(end 343.92616 -423.812716)
		(width 0.14224)
		(layer "In11.Cu")
		(net "P5E_CPU0_P0_TX_BUF_C_DP<14>")
	)
	(segment
		(start 346.575126 -422.345104)
		(end 346.500958 -422.524682)
		(width 0.14224)
		(layer "In11.Cu")
		(net "P5E_CPU0_P0_TX_BUF_C_DP<14>")
	)
	(segment
		(start 344.88501 -423.045128)
		(end 344.227658 -423.317162)
		(width 0.14224)
		(layer "In11.Cu")
		(net "P5E_CPU0_P0_TX_BUF_C_DP<14>")
	)
	(segment
		(start 343.624154 -424.114722)
		(end 343.430098 -424.114722)
		(width 0.14224)
		(layer "In11.Cu")
		(net "P5E_CPU0_P0_TX_BUF_C_DP<14>")
	)
	(arc
		(start 343.133426 -430.062386)
		(mid 343.229102 -430.126315)
		(end 343.34196 -430.148746)
		(width 0.14224)
		(layer "In11.Cu")
		(net "P5E_CPU0_P0_TX_BUF_C_DP<14>")
	)
	(arc
		(start 343.101676 -424.443144)
		(mid 343.012177 -424.576899)
		(end 342.980772 -424.734736)
		(width 0.14224)
		(layer "In11.Cu")
		(net "P5E_CPU0_P0_TX_BUF_C_DP<14>")
	)
	(arc
		(start 342.980772 -429.795686)
		(mid 343.001765 -429.901135)
		(end 343.061544 -429.990504)
		(width 0.14224)
		(layer "In11.Cu")
		(net "P5E_CPU0_P0_TX_BUF_C_DP<14>")
	)
	(segment
		(start 344.209116 -420.681658)
		(end 344.479626 -420.952168)
		(width 0.12954)
		(layer "F.Cu")
		(net "P5E_CPU0_P0_TX_BUF_C_DP<13>")
	)
	(segment
		(start 344.505026 -417.166044)
		(end 344.209116 -417.461954)
		(width 0.12954)
		(layer "F.Cu")
		(net "P5E_CPU0_P0_TX_BUF_C_DP<13>")
	)
	(segment
		(start 344.209116 -417.461954)
		(end 344.209116 -420.681658)
		(width 0.12954)
		(layer "F.Cu")
		(net "P5E_CPU0_P0_TX_BUF_C_DP<13>")
	)
	(segment
		(start 341.992712 -423.724578)
		(end 341.637874 -423.961814)
		(width 0.14224)
		(layer "In11.Cu")
		(net "P5E_CPU0_P0_TX_BUF_C_DP<13>")
	)
	(segment
		(start 344.032078 -422.197022)
		(end 342.968326 -422.907714)
		(width 0.14224)
		(layer "In11.Cu")
		(net "P5E_CPU0_P0_TX_BUF_C_DP<13>")
	)
	(segment
		(start 341.637874 -423.961814)
		(end 341.447628 -423.923968)
		(width 0.14224)
		(layer "In11.Cu")
		(net "P5E_CPU0_P0_TX_BUF_C_DP<13>")
	)
	(segment
		(start 344.188796 -421.242998)
		(end 344.188796 -421.903906)
		(width 0.14224)
		(layer "In11.Cu")
		(net "P5E_CPU0_P0_TX_BUF_C_DP<13>")
	)
	(segment
		(start 341.247476 -431.164746)
		(end 341.491824 -431.164746)
		(width 0.14224)
		(layer "In11.Cu")
		(net "P5E_CPU0_P0_TX_BUF_C_DP<13>")
	)
	(segment
		(start 340.985856 -424.318938)
		(end 340.985856 -430.90338)
		(width 0.14224)
		(layer "In11.Cu")
		(net "P5E_CPU0_P0_TX_BUF_C_DP<13>")
	)
	(segment
		(start 344.479626 -420.952168)
		(end 344.188796 -421.242998)
		(width 0.14224)
		(layer "In11.Cu")
		(net "P5E_CPU0_P0_TX_BUF_C_DP<13>")
	)
	(segment
		(start 341.491824 -431.164746)
		(end 341.649812 -431.006758)
		(width 0.14224)
		(layer "In11.Cu")
		(net "P5E_CPU0_P0_TX_BUF_C_DP<13>")
	)
	(segment
		(start 341.447628 -423.923968)
		(end 341.057738 -424.184318)
		(width 0.14224)
		(layer "In11.Cu")
		(net "P5E_CPU0_P0_TX_BUF_C_DP<13>")
	)
	(segment
		(start 342.968326 -422.907714)
		(end 342.93048 -423.09796)
		(width 0.14224)
		(layer "In11.Cu")
		(net "P5E_CPU0_P0_TX_BUF_C_DP<13>")
	)
	(segment
		(start 342.575388 -423.335196)
		(end 342.385142 -423.29735)
		(width 0.14224)
		(layer "In11.Cu")
		(net "P5E_CPU0_P0_TX_BUF_C_DP<13>")
	)
	(segment
		(start 342.030558 -423.534332)
		(end 341.992712 -423.724578)
		(width 0.14224)
		(layer "In11.Cu")
		(net "P5E_CPU0_P0_TX_BUF_C_DP<13>")
	)
	(segment
		(start 344.188796 -421.903906)
		(end 344.032078 -422.197022)
		(width 0.14224)
		(layer "In11.Cu")
		(net "P5E_CPU0_P0_TX_BUF_C_DP<13>")
	)
	(segment
		(start 341.649812 -431.006758)
		(end 341.649812 -430.689766)
		(width 0.14224)
		(layer "In11.Cu")
		(net "P5E_CPU0_P0_TX_BUF_C_DP<13>")
	)
	(segment
		(start 342.93048 -423.09796)
		(end 342.575388 -423.335196)
		(width 0.14224)
		(layer "In11.Cu")
		(net "P5E_CPU0_P0_TX_BUF_C_DP<13>")
	)
	(segment
		(start 342.385142 -423.29735)
		(end 342.030558 -423.534332)
		(width 0.14224)
		(layer "In11.Cu")
		(net "P5E_CPU0_P0_TX_BUF_C_DP<13>")
	)
	(arc
		(start 341.057738 -424.184318)
		(mid 341.004969 -424.242639)
		(end 340.985856 -424.318938)
		(width 0.14224)
		(layer "In11.Cu")
		(net "P5E_CPU0_P0_TX_BUF_C_DP<13>")
	)
	(arc
		(start 340.985856 -430.90338)
		(mid 341.062498 -431.088283)
		(end 341.247476 -431.164746)
		(width 0.14224)
		(layer "In11.Cu")
		(net "P5E_CPU0_P0_TX_BUF_C_DP<13>")
	)
	(segment
		(start 341.145876 -420.681658)
		(end 341.416386 -420.952168)
		(width 0.12954)
		(layer "F.Cu")
		(net "P5E_CPU0_P0_TX_BUF_C_DP<12>")
	)
	(segment
		(start 341.441786 -417.166044)
		(end 341.145876 -417.461954)
		(width 0.12954)
		(layer "F.Cu")
		(net "P5E_CPU0_P0_TX_BUF_C_DP<12>")
	)
	(segment
		(start 341.145876 -417.461954)
		(end 341.145876 -420.681658)
		(width 0.12954)
		(layer "F.Cu")
		(net "P5E_CPU0_P0_TX_BUF_C_DP<12>")
	)
	(segment
		(start 339.293962 -430.170336)
		(end 339.485986 -430.170336)
		(width 0.14224)
		(layer "In11.Cu")
		(net "P5E_CPU0_P0_TX_BUF_C_DP<12>")
	)
	(segment
		(start 339.65007 -423.842942)
		(end 339.379052 -424.173142)
		(width 0.14224)
		(layer "In11.Cu")
		(net "P5E_CPU0_P0_TX_BUF_C_DP<12>")
	)
	(segment
		(start 340.063328 -423.357548)
		(end 339.869526 -423.376598)
		(width 0.14224)
		(layer "In11.Cu")
		(net "P5E_CPU0_P0_TX_BUF_C_DP<12>")
	)
	(segment
		(start 340.334346 -423.027348)
		(end 340.063328 -423.357548)
		(width 0.14224)
		(layer "In11.Cu")
		(net "P5E_CPU0_P0_TX_BUF_C_DP<12>")
	)
	(segment
		(start 339.649816 -430.006506)
		(end 339.649816 -429.689768)
		(width 0.14224)
		(layer "In11.Cu")
		(net "P5E_CPU0_P0_TX_BUF_C_DP<12>")
	)
	(segment
		(start 340.725506 -422.565068)
		(end 340.51875 -422.585642)
		(width 0.14224)
		(layer "In11.Cu")
		(net "P5E_CPU0_P0_TX_BUF_C_DP<12>")
	)
	(segment
		(start 339.485986 -430.170336)
		(end 339.649816 -430.006506)
		(width 0.14224)
		(layer "In11.Cu")
		(net "P5E_CPU0_P0_TX_BUF_C_DP<12>")
	)
	(segment
		(start 339.201506 -424.190668)
		(end 338.977478 -424.463718)
		(width 0.14224)
		(layer "In11.Cu")
		(net "P5E_CPU0_P0_TX_BUF_C_DP<12>")
	)
	(segment
		(start 341.416386 -420.952168)
		(end 341.125556 -421.242998)
		(width 0.14224)
		(layer "In11.Cu")
		(net "P5E_CPU0_P0_TX_BUF_C_DP<12>")
	)
	(segment
		(start 339.869526 -423.376598)
		(end 339.632544 -423.665396)
		(width 0.14224)
		(layer "In11.Cu")
		(net "P5E_CPU0_P0_TX_BUF_C_DP<12>")
	)
	(segment
		(start 341.125556 -421.852852)
		(end 340.928706 -422.092628)
		(width 0.14224)
		(layer "In11.Cu")
		(net "P5E_CPU0_P0_TX_BUF_C_DP<12>")
	)
	(segment
		(start 341.125556 -421.242998)
		(end 341.125556 -421.852852)
		(width 0.14224)
		(layer "In11.Cu")
		(net "P5E_CPU0_P0_TX_BUF_C_DP<12>")
	)
	(segment
		(start 340.948518 -422.293542)
		(end 340.725506 -422.565068)
		(width 0.14224)
		(layer "In11.Cu")
		(net "P5E_CPU0_P0_TX_BUF_C_DP<12>")
	)
	(segment
		(start 339.11413 -430.043082)
		(end 339.204046 -430.132998)
		(width 0.14224)
		(layer "In11.Cu")
		(net "P5E_CPU0_P0_TX_BUF_C_DP<12>")
	)
	(segment
		(start 338.977478 -424.463718)
		(end 338.977478 -429.71339)
		(width 0.14224)
		(layer "In11.Cu")
		(net "P5E_CPU0_P0_TX_BUF_C_DP<12>")
	)
	(segment
		(start 340.315296 -422.833546)
		(end 340.334346 -423.027348)
		(width 0.14224)
		(layer "In11.Cu")
		(net "P5E_CPU0_P0_TX_BUF_C_DP<12>")
	)
	(segment
		(start 339.632544 -423.665396)
		(end 339.65007 -423.842942)
		(width 0.14224)
		(layer "In11.Cu")
		(net "P5E_CPU0_P0_TX_BUF_C_DP<12>")
	)
	(segment
		(start 339.379052 -424.173142)
		(end 339.201506 -424.190668)
		(width 0.14224)
		(layer "In11.Cu")
		(net "P5E_CPU0_P0_TX_BUF_C_DP<12>")
	)
	(segment
		(start 340.51875 -422.585642)
		(end 340.315296 -422.833546)
		(width 0.14224)
		(layer "In11.Cu")
		(net "P5E_CPU0_P0_TX_BUF_C_DP<12>")
	)
	(segment
		(start 340.928706 -422.092628)
		(end 340.948518 -422.293542)
		(width 0.14224)
		(layer "In11.Cu")
		(net "P5E_CPU0_P0_TX_BUF_C_DP<12>")
	)
	(arc
		(start 339.204046 -430.132998)
		(mid 339.245286 -430.160617)
		(end 339.293962 -430.170336)
		(width 0.14224)
		(layer "In11.Cu")
		(net "P5E_CPU0_P0_TX_BUF_C_DP<12>")
	)
	(arc
		(start 338.977478 -429.71339)
		(mid 339.012991 -429.891838)
		(end 339.11413 -430.043082)
		(width 0.14224)
		(layer "In11.Cu")
		(net "P5E_CPU0_P0_TX_BUF_C_DP<12>")
	)
	(segment
		(start 338.082636 -420.681658)
		(end 338.353146 -420.952168)
		(width 0.12954)
		(layer "F.Cu")
		(net "P5E_CPU0_P0_TX_BUF_C_DP<11>")
	)
	(segment
		(start 338.378546 -417.166044)
		(end 338.082636 -417.461954)
		(width 0.12954)
		(layer "F.Cu")
		(net "P5E_CPU0_P0_TX_BUF_C_DP<11>")
	)
	(segment
		(start 338.082636 -417.461954)
		(end 338.082636 -420.681658)
		(width 0.12954)
		(layer "F.Cu")
		(net "P5E_CPU0_P0_TX_BUF_C_DP<11>")
	)
	(segment
		(start 337.810094 -422.6179)
		(end 337.630516 -422.692322)
		(width 0.14224)
		(layer "In11.Cu")
		(net "P5E_CPU0_P0_TX_BUF_C_DP<11>")
	)
	(segment
		(start 337.467448 -423.08653)
		(end 337.541616 -423.2656)
		(width 0.14224)
		(layer "In11.Cu")
		(net "P5E_CPU0_P0_TX_BUF_C_DP<11>")
	)
	(segment
		(start 337.64982 -431.006758)
		(end 337.64982 -430.689766)
		(width 0.14224)
		(layer "In11.Cu")
		(net "P5E_CPU0_P0_TX_BUF_C_DP<11>")
	)
	(segment
		(start 336.985864 -430.909476)
		(end 336.986118 -430.909476)
		(width 0.14224)
		(layer "In11.Cu")
		(net "P5E_CPU0_P0_TX_BUF_C_DP<11>")
	)
	(segment
		(start 336.985864 -424.248834)
		(end 336.985864 -430.909476)
		(width 0.14224)
		(layer "In11.Cu")
		(net "P5E_CPU0_P0_TX_BUF_C_DP<11>")
	)
	(segment
		(start 338.062316 -421.242998)
		(end 338.062316 -421.65016)
		(width 0.14224)
		(layer "In11.Cu")
		(net "P5E_CPU0_P0_TX_BUF_C_DP<11>")
	)
	(segment
		(start 337.973416 -422.223438)
		(end 337.810094 -422.6179)
		(width 0.14224)
		(layer "In11.Cu")
		(net "P5E_CPU0_P0_TX_BUF_C_DP<11>")
	)
	(segment
		(start 337.022948 -430.999138)
		(end 337.096354 -431.07229)
		(width 0.14224)
		(layer "In11.Cu")
		(net "P5E_CPU0_P0_TX_BUF_C_DP<11>")
	)
	(segment
		(start 337.541616 -423.2656)
		(end 337.378294 -423.660062)
		(width 0.14224)
		(layer "In11.Cu")
		(net "P5E_CPU0_P0_TX_BUF_C_DP<11>")
	)
	(segment
		(start 337.630516 -422.692322)
		(end 337.467448 -423.08653)
		(width 0.14224)
		(layer "In11.Cu")
		(net "P5E_CPU0_P0_TX_BUF_C_DP<11>")
	)
	(segment
		(start 337.19897 -423.734484)
		(end 336.985864 -424.248834)
		(width 0.14224)
		(layer "In11.Cu")
		(net "P5E_CPU0_P0_TX_BUF_C_DP<11>")
	)
	(segment
		(start 338.062316 -421.65016)
		(end 337.899248 -422.044368)
		(width 0.14224)
		(layer "In11.Cu")
		(net "P5E_CPU0_P0_TX_BUF_C_DP<11>")
	)
	(segment
		(start 338.353146 -420.952168)
		(end 338.062316 -421.242998)
		(width 0.14224)
		(layer "In11.Cu")
		(net "P5E_CPU0_P0_TX_BUF_C_DP<11>")
	)
	(segment
		(start 337.50758 -431.148998)
		(end 337.64982 -431.006758)
		(width 0.14224)
		(layer "In11.Cu")
		(net "P5E_CPU0_P0_TX_BUF_C_DP<11>")
	)
	(segment
		(start 337.378294 -423.660062)
		(end 337.19897 -423.734484)
		(width 0.14224)
		(layer "In11.Cu")
		(net "P5E_CPU0_P0_TX_BUF_C_DP<11>")
	)
	(segment
		(start 337.899248 -422.044368)
		(end 337.973416 -422.223438)
		(width 0.14224)
		(layer "In11.Cu")
		(net "P5E_CPU0_P0_TX_BUF_C_DP<11>")
	)
	(segment
		(start 337.281266 -431.148998)
		(end 337.50758 -431.148998)
		(width 0.14224)
		(layer "In11.Cu")
		(net "P5E_CPU0_P0_TX_BUF_C_DP<11>")
	)
	(arc
		(start 336.986118 -430.909476)
		(mid 336.995634 -430.957964)
		(end 337.022948 -430.999138)
		(width 0.14224)
		(layer "In11.Cu")
		(net "P5E_CPU0_P0_TX_BUF_C_DP<11>")
	)
	(arc
		(start 337.096354 -431.07229)
		(mid 337.181164 -431.129085)
		(end 337.281266 -431.148998)
		(width 0.14224)
		(layer "In11.Cu")
		(net "P5E_CPU0_P0_TX_BUF_C_DP<11>")
	)
	(segment
		(start 335.019396 -417.461954)
		(end 335.019396 -420.681658)
		(width 0.12954)
		(layer "F.Cu")
		(net "P5E_CPU0_P0_TX_BUF_C_DP<10>")
	)
	(segment
		(start 335.315306 -417.166044)
		(end 335.019396 -417.461954)
		(width 0.12954)
		(layer "F.Cu")
		(net "P5E_CPU0_P0_TX_BUF_C_DP<10>")
	)
	(segment
		(start 335.019396 -420.681658)
		(end 335.289906 -420.952168)
		(width 0.12954)
		(layer "F.Cu")
		(net "P5E_CPU0_P0_TX_BUF_C_DP<10>")
	)
	(segment
		(start 335.117948 -422.251886)
		(end 334.980788 -422.389046)
		(width 0.14224)
		(layer "In11.Cu")
		(net "P5E_CPU0_P0_TX_BUF_C_DP<10>")
	)
	(segment
		(start 334.980788 -422.389046)
		(end 334.980788 -422.815766)
		(width 0.14224)
		(layer "In11.Cu")
		(net "P5E_CPU0_P0_TX_BUF_C_DP<10>")
	)
	(segment
		(start 335.27238 -430.148746)
		(end 335.507584 -430.148746)
		(width 0.14224)
		(layer "In11.Cu")
		(net "P5E_CPU0_P0_TX_BUF_C_DP<10>")
	)
	(segment
		(start 335.117948 -421.825166)
		(end 335.117948 -422.251886)
		(width 0.14224)
		(layer "In11.Cu")
		(net "P5E_CPU0_P0_TX_BUF_C_DP<10>")
	)
	(segment
		(start 335.117948 -424.080686)
		(end 335.117948 -424.507406)
		(width 0.14224)
		(layer "In11.Cu")
		(net "P5E_CPU0_P0_TX_BUF_C_DP<10>")
	)
	(segment
		(start 335.649824 -430.006506)
		(end 335.649824 -429.689768)
		(width 0.14224)
		(layer "In11.Cu")
		(net "P5E_CPU0_P0_TX_BUF_C_DP<10>")
	)
	(segment
		(start 335.507584 -430.148746)
		(end 335.649824 -430.006506)
		(width 0.14224)
		(layer "In11.Cu")
		(net "P5E_CPU0_P0_TX_BUF_C_DP<10>")
	)
	(segment
		(start 335.117948 -423.379646)
		(end 334.980788 -423.516806)
		(width 0.14224)
		(layer "In11.Cu")
		(net "P5E_CPU0_P0_TX_BUF_C_DP<10>")
	)
	(segment
		(start 334.980788 -423.516806)
		(end 334.980788 -423.943526)
		(width 0.14224)
		(layer "In11.Cu")
		(net "P5E_CPU0_P0_TX_BUF_C_DP<10>")
	)
	(segment
		(start 334.980788 -421.688006)
		(end 335.117948 -421.825166)
		(width 0.14224)
		(layer "In11.Cu")
		(net "P5E_CPU0_P0_TX_BUF_C_DP<10>")
	)
	(segment
		(start 335.117948 -424.507406)
		(end 334.980788 -424.644566)
		(width 0.14224)
		(layer "In11.Cu")
		(net "P5E_CPU0_P0_TX_BUF_C_DP<10>")
	)
	(segment
		(start 334.980788 -423.943526)
		(end 335.117948 -424.080686)
		(width 0.14224)
		(layer "In11.Cu")
		(net "P5E_CPU0_P0_TX_BUF_C_DP<10>")
	)
	(segment
		(start 334.980788 -421.261286)
		(end 334.980788 -421.688006)
		(width 0.14224)
		(layer "In11.Cu")
		(net "P5E_CPU0_P0_TX_BUF_C_DP<10>")
	)
	(segment
		(start 335.289906 -420.952168)
		(end 334.980788 -421.261286)
		(width 0.14224)
		(layer "In11.Cu")
		(net "P5E_CPU0_P0_TX_BUF_C_DP<10>")
	)
	(segment
		(start 335.102454 -430.031398)
		(end 335.182464 -430.111408)
		(width 0.14224)
		(layer "In11.Cu")
		(net "P5E_CPU0_P0_TX_BUF_C_DP<10>")
	)
	(segment
		(start 334.980788 -422.815766)
		(end 335.117948 -422.952926)
		(width 0.14224)
		(layer "In11.Cu")
		(net "P5E_CPU0_P0_TX_BUF_C_DP<10>")
	)
	(segment
		(start 335.117948 -422.952926)
		(end 335.117948 -423.379646)
		(width 0.14224)
		(layer "In11.Cu")
		(net "P5E_CPU0_P0_TX_BUF_C_DP<10>")
	)
	(segment
		(start 334.980788 -424.644566)
		(end 334.980788 -429.737774)
		(width 0.14224)
		(layer "In11.Cu")
		(net "P5E_CPU0_P0_TX_BUF_C_DP<10>")
	)
	(arc
		(start 334.980788 -429.737774)
		(mid 335.012415 -429.896684)
		(end 335.102454 -430.031398)
		(width 0.14224)
		(layer "In11.Cu")
		(net "P5E_CPU0_P0_TX_BUF_C_DP<10>")
	)
	(arc
		(start 335.182464 -430.111408)
		(mid 335.223704 -430.139027)
		(end 335.27238 -430.148746)
		(width 0.14224)
		(layer "In11.Cu")
		(net "P5E_CPU0_P0_TX_BUF_C_DP<10>")
	)
	(segment
		(start 304.386996 -420.681658)
		(end 304.657506 -420.952168)
		(width 0.12954)
		(layer "F.Cu")
		(net "P5E_CPU0_P0_TX_BUF_C_DP<0>")
	)
	(segment
		(start 304.682906 -417.166044)
		(end 304.386996 -417.461954)
		(width 0.12954)
		(layer "F.Cu")
		(net "P5E_CPU0_P0_TX_BUF_C_DP<0>")
	)
	(segment
		(start 304.386996 -417.461954)
		(end 304.386996 -420.681658)
		(width 0.12954)
		(layer "F.Cu")
		(net "P5E_CPU0_P0_TX_BUF_C_DP<0>")
	)
	(segment
		(start 306.405788 -423.32148)
		(end 306.420012 -423.514774)
		(width 0.14224)
		(layer "In11.Cu")
		(net "P5E_CPU0_P0_TX_BUF_C_DP<0>")
	)
	(segment
		(start 308.443122 -425.258484)
		(end 308.76621 -425.536868)
		(width 0.14224)
		(layer "In11.Cu")
		(net "P5E_CPU0_P0_TX_BUF_C_DP<0>")
	)
	(segment
		(start 308.428644 -425.064936)
		(end 308.443122 -425.258484)
		(width 0.14224)
		(layer "In11.Cu")
		(net "P5E_CPU0_P0_TX_BUF_C_DP<0>")
	)
	(segment
		(start 308.105302 -424.786044)
		(end 308.428644 -425.064936)
		(width 0.14224)
		(layer "In11.Cu")
		(net "P5E_CPU0_P0_TX_BUF_C_DP<0>")
	)
	(segment
		(start 305.465734 -422.511474)
		(end 305.480212 -422.704768)
		(width 0.14224)
		(layer "In11.Cu")
		(net "P5E_CPU0_P0_TX_BUF_C_DP<0>")
	)
	(segment
		(start 304.410872 -421.783256)
		(end 304.948844 -422.246806)
		(width 0.14224)
		(layer "In11.Cu")
		(net "P5E_CPU0_P0_TX_BUF_C_DP<0>")
	)
	(segment
		(start 307.046122 -423.873168)
		(end 307.369464 -424.15206)
		(width 0.14224)
		(layer "In11.Cu")
		(net "P5E_CPU0_P0_TX_BUF_C_DP<0>")
	)
	(segment
		(start 307.369464 -424.15206)
		(end 307.383942 -424.345608)
		(width 0.14224)
		(layer "In11.Cu")
		(net "P5E_CPU0_P0_TX_BUF_C_DP<0>")
	)
	(segment
		(start 304.948844 -422.246806)
		(end 305.142392 -422.232582)
		(width 0.14224)
		(layer "In11.Cu")
		(net "P5E_CPU0_P0_TX_BUF_C_DP<0>")
	)
	(segment
		(start 314.507372 -430.148746)
		(end 314.649612 -430.006506)
		(width 0.14224)
		(layer "In11.Cu")
		(net "P5E_CPU0_P0_TX_BUF_C_DP<0>")
	)
	(segment
		(start 314.253626 -430.148746)
		(end 314.507372 -430.148746)
		(width 0.14224)
		(layer "In11.Cu")
		(net "P5E_CPU0_P0_TX_BUF_C_DP<0>")
	)
	(segment
		(start 307.383942 -424.345608)
		(end 307.911754 -424.800522)
		(width 0.14224)
		(layer "In11.Cu")
		(net "P5E_CPU0_P0_TX_BUF_C_DP<0>")
	)
	(segment
		(start 304.657506 -420.952168)
		(end 304.366676 -421.242998)
		(width 0.14224)
		(layer "In11.Cu")
		(net "P5E_CPU0_P0_TX_BUF_C_DP<0>")
	)
	(segment
		(start 306.082192 -423.042588)
		(end 306.405788 -423.32148)
		(width 0.14224)
		(layer "In11.Cu")
		(net "P5E_CPU0_P0_TX_BUF_C_DP<0>")
	)
	(segment
		(start 305.142392 -422.232582)
		(end 305.465734 -422.511474)
		(width 0.14224)
		(layer "In11.Cu")
		(net "P5E_CPU0_P0_TX_BUF_C_DP<0>")
	)
	(segment
		(start 307.911754 -424.800522)
		(end 308.105302 -424.786044)
		(width 0.14224)
		(layer "In11.Cu")
		(net "P5E_CPU0_P0_TX_BUF_C_DP<0>")
	)
	(segment
		(start 306.852574 -423.887646)
		(end 307.046122 -423.873168)
		(width 0.14224)
		(layer "In11.Cu")
		(net "P5E_CPU0_P0_TX_BUF_C_DP<0>")
	)
	(segment
		(start 311.493662 -428.079916)
		(end 313.271408 -429.612552)
		(width 0.14224)
		(layer "In11.Cu")
		(net "P5E_CPU0_P0_TX_BUF_C_DP<0>")
	)
	(segment
		(start 305.480212 -422.704768)
		(end 305.888644 -423.056812)
		(width 0.14224)
		(layer "In11.Cu")
		(net "P5E_CPU0_P0_TX_BUF_C_DP<0>")
	)
	(segment
		(start 306.420012 -423.514774)
		(end 306.852574 -423.887646)
		(width 0.14224)
		(layer "In11.Cu")
		(net "P5E_CPU0_P0_TX_BUF_C_DP<0>")
	)
	(segment
		(start 304.366676 -421.242998)
		(end 304.366676 -421.68699)
		(width 0.14224)
		(layer "In11.Cu")
		(net "P5E_CPU0_P0_TX_BUF_C_DP<0>")
	)
	(segment
		(start 305.888644 -423.056812)
		(end 306.082192 -423.042588)
		(width 0.14224)
		(layer "In11.Cu")
		(net "P5E_CPU0_P0_TX_BUF_C_DP<0>")
	)
	(segment
		(start 308.788562 -425.557696)
		(end 308.928262 -425.697396)
		(width 0.14224)
		(layer "In11.Cu")
		(net "P5E_CPU0_P0_TX_BUF_C_DP<0>")
	)
	(segment
		(start 314.649612 -430.006506)
		(end 314.649612 -429.689768)
		(width 0.14224)
		(layer "In11.Cu")
		(net "P5E_CPU0_P0_TX_BUF_C_DP<0>")
	)
	(arc
		(start 308.76621 -425.536868)
		(mid 308.777578 -425.547076)
		(end 308.788562 -425.557696)
		(width 0.14224)
		(layer "In11.Cu")
		(net "P5E_CPU0_P0_TX_BUF_C_DP<0>")
	)
	(arc
		(start 304.366676 -421.68699)
		(mid 304.378249 -421.739958)
		(end 304.410872 -421.783256)
		(width 0.14224)
		(layer "In11.Cu")
		(net "P5E_CPU0_P0_TX_BUF_C_DP<0>")
	)
	(arc
		(start 308.928262 -425.697396)
		(mid 310.188969 -426.912338)
		(end 311.493662 -428.079916)
		(width 0.14224)
		(layer "In11.Cu")
		(net "P5E_CPU0_P0_TX_BUF_C_DP<0>")
	)
	(arc
		(start 313.271408 -429.612552)
		(mid 313.649146 -429.891223)
		(end 314.06465 -430.10963)
		(width 0.14224)
		(layer "In11.Cu")
		(net "P5E_CPU0_P0_TX_BUF_C_DP<0>")
	)
	(arc
		(start 314.06465 -430.10963)
		(mid 314.157133 -430.138883)
		(end 314.253626 -430.148746)
		(width 0.14224)
		(layer "In11.Cu")
		(net "P5E_CPU0_P0_TX_BUF_C_DP<0>")
	)
	(segment
		(start 331.633576 -417.461954)
		(end 331.633576 -420.681658)
		(width 0.12954)
		(layer "F.Cu")
		(net "P5E_CPU0_P0_TX_BUF_C_DN<9>")
	)
	(segment
		(start 331.633576 -420.681658)
		(end 331.363066 -420.952168)
		(width 0.12954)
		(layer "F.Cu")
		(net "P5E_CPU0_P0_TX_BUF_C_DN<9>")
	)
	(segment
		(start 331.337666 -417.166044)
		(end 331.633576 -417.461954)
		(width 0.12954)
		(layer "F.Cu")
		(net "P5E_CPU0_P0_TX_BUF_C_DN<9>")
	)
	(segment
		(start 333.649828 -431.573178)
		(end 333.649828 -431.889916)
		(width 0.14224)
		(layer "In11.Cu")
		(net "P5E_CPU0_P0_TX_BUF_C_DN<9>")
	)
	(segment
		(start 333.507588 -431.430938)
		(end 333.649828 -431.573178)
		(width 0.14224)
		(layer "In11.Cu")
		(net "P5E_CPU0_P0_TX_BUF_C_DN<9>")
	)
	(segment
		(start 331.653896 -421.242998)
		(end 331.653896 -421.904668)
		(width 0.14224)
		(layer "In11.Cu")
		(net "P5E_CPU0_P0_TX_BUF_C_DN<9>")
	)
	(segment
		(start 331.95895 -422.911524)
		(end 331.95768 -422.914318)
		(width 0.14224)
		(layer "In11.Cu")
		(net "P5E_CPU0_P0_TX_BUF_C_DN<9>")
	)
	(segment
		(start 332.703932 -425.36872)
		(end 332.703932 -430.833276)
		(width 0.14224)
		(layer "In11.Cu")
		(net "P5E_CPU0_P0_TX_BUF_C_DN<9>")
	)
	(segment
		(start 332.14818 -423.542968)
		(end 332.150974 -423.544492)
		(width 0.14224)
		(layer "In11.Cu")
		(net "P5E_CPU0_P0_TX_BUF_C_DN<9>")
	)
	(segment
		(start 333.225648 -431.430938)
		(end 333.507588 -431.430938)
		(width 0.14224)
		(layer "In11.Cu")
		(net "P5E_CPU0_P0_TX_BUF_C_DN<9>")
	)
	(segment
		(start 332.877414 -431.252122)
		(end 332.936342 -431.31105)
		(width 0.14224)
		(layer "In11.Cu")
		(net "P5E_CPU0_P0_TX_BUF_C_DN<9>")
	)
	(segment
		(start 332.150974 -423.544492)
		(end 332.703932 -425.36872)
		(width 0.14224)
		(layer "In11.Cu")
		(net "P5E_CPU0_P0_TX_BUF_C_DN<9>")
	)
	(segment
		(start 331.95768 -422.914318)
		(end 332.14818 -423.542968)
		(width 0.14224)
		(layer "In11.Cu")
		(net "P5E_CPU0_P0_TX_BUF_C_DN<9>")
	)
	(segment
		(start 331.363066 -420.952168)
		(end 331.653896 -421.242998)
		(width 0.14224)
		(layer "In11.Cu")
		(net "P5E_CPU0_P0_TX_BUF_C_DN<9>")
	)
	(segment
		(start 331.653896 -421.904668)
		(end 331.95895 -422.911524)
		(width 0.14224)
		(layer "In11.Cu")
		(net "P5E_CPU0_P0_TX_BUF_C_DN<9>")
	)
	(arc
		(start 332.936342 -431.31105)
		(mid 333.069062 -431.399794)
		(end 333.225648 -431.430938)
		(width 0.14224)
		(layer "In11.Cu")
		(net "P5E_CPU0_P0_TX_BUF_C_DN<9>")
	)
	(arc
		(start 332.703932 -430.833276)
		(mid 332.74902 -431.05995)
		(end 332.877414 -431.252122)
		(width 0.14224)
		(layer "In11.Cu")
		(net "P5E_CPU0_P0_TX_BUF_C_DN<9>")
	)
	(segment
		(start 328.274426 -417.166044)
		(end 328.570336 -417.461954)
		(width 0.12954)
		(layer "F.Cu")
		(net "P5E_CPU0_P0_TX_BUF_C_DN<8>")
	)
	(segment
		(start 328.570336 -420.681658)
		(end 328.299826 -420.952168)
		(width 0.12954)
		(layer "F.Cu")
		(net "P5E_CPU0_P0_TX_BUF_C_DN<8>")
	)
	(segment
		(start 328.570336 -417.461954)
		(end 328.570336 -420.681658)
		(width 0.12954)
		(layer "F.Cu")
		(net "P5E_CPU0_P0_TX_BUF_C_DN<8>")
	)
	(segment
		(start 329.475084 -423.849038)
		(end 329.477116 -423.8498)
		(width 0.14224)
		(layer "In11.Cu")
		(net "P5E_CPU0_P0_TX_BUF_C_DN<8>")
	)
	(segment
		(start 328.590656 -421.711628)
		(end 328.82078 -422.268142)
		(width 0.14224)
		(layer "In11.Cu")
		(net "P5E_CPU0_P0_TX_BUF_C_DN<8>")
	)
	(segment
		(start 331.506576 -430.43094)
		(end 331.649832 -430.574196)
		(width 0.14224)
		(layer "In11.Cu")
		(net "P5E_CPU0_P0_TX_BUF_C_DN<8>")
	)
	(segment
		(start 328.590656 -421.242998)
		(end 328.590656 -421.711628)
		(width 0.14224)
		(layer "In11.Cu")
		(net "P5E_CPU0_P0_TX_BUF_C_DN<8>")
	)
	(segment
		(start 331.358748 -430.43094)
		(end 331.506576 -430.43094)
		(width 0.14224)
		(layer "In11.Cu")
		(net "P5E_CPU0_P0_TX_BUF_C_DN<8>")
	)
	(segment
		(start 328.821796 -422.26865)
		(end 328.82078 -422.270174)
		(width 0.14224)
		(layer "In11.Cu")
		(net "P5E_CPU0_P0_TX_BUF_C_DN<8>")
	)
	(segment
		(start 329.477116 -423.8498)
		(end 329.685396 -424.353482)
		(width 0.14224)
		(layer "In11.Cu")
		(net "P5E_CPU0_P0_TX_BUF_C_DN<8>")
	)
	(segment
		(start 329.68438 -424.355006)
		(end 330.543662 -426.428916)
		(width 0.14224)
		(layer "In11.Cu")
		(net "P5E_CPU0_P0_TX_BUF_C_DN<8>")
	)
	(segment
		(start 330.768452 -430.143158)
		(end 330.842366 -430.217072)
		(width 0.14224)
		(layer "In11.Cu")
		(net "P5E_CPU0_P0_TX_BUF_C_DN<8>")
	)
	(segment
		(start 328.82078 -422.268142)
		(end 328.821796 -422.26865)
		(width 0.14224)
		(layer "In11.Cu")
		(net "P5E_CPU0_P0_TX_BUF_C_DN<8>")
	)
	(segment
		(start 331.649832 -430.574196)
		(end 331.649832 -430.889918)
		(width 0.14224)
		(layer "In11.Cu")
		(net "P5E_CPU0_P0_TX_BUF_C_DN<8>")
	)
	(segment
		(start 328.299826 -420.952168)
		(end 328.590656 -421.242998)
		(width 0.14224)
		(layer "In11.Cu")
		(net "P5E_CPU0_P0_TX_BUF_C_DN<8>")
	)
	(segment
		(start 329.685396 -424.353482)
		(end 329.68438 -424.355006)
		(width 0.14224)
		(layer "In11.Cu")
		(net "P5E_CPU0_P0_TX_BUF_C_DN<8>")
	)
	(segment
		(start 330.543662 -426.428916)
		(end 330.543662 -429.60036)
		(width 0.14224)
		(layer "In11.Cu")
		(net "P5E_CPU0_P0_TX_BUF_C_DN<8>")
	)
	(segment
		(start 328.82078 -422.270174)
		(end 329.475084 -423.849038)
		(width 0.14224)
		(layer "In11.Cu")
		(net "P5E_CPU0_P0_TX_BUF_C_DN<8>")
	)
	(arc
		(start 330.842366 -430.217072)
		(mid 331.079284 -430.375376)
		(end 331.358748 -430.43094)
		(width 0.14224)
		(layer "In11.Cu")
		(net "P5E_CPU0_P0_TX_BUF_C_DN<8>")
	)
	(arc
		(start 330.543662 -429.60036)
		(mid 330.602076 -429.894117)
		(end 330.768452 -430.143158)
		(width 0.14224)
		(layer "In11.Cu")
		(net "P5E_CPU0_P0_TX_BUF_C_DN<8>")
	)
	(segment
		(start 325.211186 -417.166044)
		(end 325.507096 -417.461954)
		(width 0.12954)
		(layer "F.Cu")
		(net "P5E_CPU0_P0_TX_BUF_C_DN<7>")
	)
	(segment
		(start 325.507096 -420.681658)
		(end 325.236586 -420.952168)
		(width 0.12954)
		(layer "F.Cu")
		(net "P5E_CPU0_P0_TX_BUF_C_DN<7>")
	)
	(segment
		(start 325.507096 -417.461954)
		(end 325.507096 -420.681658)
		(width 0.12954)
		(layer "F.Cu")
		(net "P5E_CPU0_P0_TX_BUF_C_DN<7>")
	)
	(segment
		(start 328.649584 -431.573178)
		(end 328.649584 -431.889916)
		(width 0.14224)
		(layer "In11.Cu")
		(net "P5E_CPU0_P0_TX_BUF_C_DN<7>")
	)
	(segment
		(start 328.055986 -431.430938)
		(end 328.507344 -431.430938)
		(width 0.14224)
		(layer "In11.Cu")
		(net "P5E_CPU0_P0_TX_BUF_C_DN<7>")
	)
	(segment
		(start 326.11314 -422.717722)
		(end 326.113394 -422.717722)
		(width 0.14224)
		(layer "In11.Cu")
		(net "P5E_CPU0_P0_TX_BUF_C_DN<7>")
	)
	(segment
		(start 325.537068 -421.25265)
		(end 325.537068 -421.855138)
		(width 0.14224)
		(layer "In11.Cu")
		(net "P5E_CPU0_P0_TX_BUF_C_DN<7>")
	)
	(segment
		(start 325.537068 -421.855138)
		(end 326.11314 -422.717722)
		(width 0.14224)
		(layer "In11.Cu")
		(net "P5E_CPU0_P0_TX_BUF_C_DN<7>")
	)
	(segment
		(start 327.687178 -425.073064)
		(end 327.687178 -431.06213)
		(width 0.14224)
		(layer "In11.Cu")
		(net "P5E_CPU0_P0_TX_BUF_C_DN<7>")
	)
	(segment
		(start 328.507344 -431.430938)
		(end 328.649584 -431.573178)
		(width 0.14224)
		(layer "In11.Cu")
		(net "P5E_CPU0_P0_TX_BUF_C_DN<7>")
	)
	(segment
		(start 325.236586 -420.952168)
		(end 325.537068 -421.25265)
		(width 0.14224)
		(layer "In11.Cu")
		(net "P5E_CPU0_P0_TX_BUF_C_DN<7>")
	)
	(segment
		(start 326.113394 -422.717722)
		(end 327.687178 -425.073064)
		(width 0.14224)
		(layer "In11.Cu")
		(net "P5E_CPU0_P0_TX_BUF_C_DN<7>")
	)
	(segment
		(start 327.687178 -431.06213)
		(end 328.055986 -431.430938)
		(width 0.14224)
		(layer "In11.Cu")
		(net "P5E_CPU0_P0_TX_BUF_C_DN<7>")
	)
	(segment
		(start 322.443856 -420.681658)
		(end 322.173346 -420.952168)
		(width 0.12954)
		(layer "F.Cu")
		(net "P5E_CPU0_P0_TX_BUF_C_DN<6>")
	)
	(segment
		(start 322.147946 -417.166044)
		(end 322.443856 -417.461954)
		(width 0.12954)
		(layer "F.Cu")
		(net "P5E_CPU0_P0_TX_BUF_C_DN<6>")
	)
	(segment
		(start 322.443856 -417.461954)
		(end 322.443856 -420.681658)
		(width 0.12954)
		(layer "F.Cu")
		(net "P5E_CPU0_P0_TX_BUF_C_DN<6>")
	)
	(segment
		(start 322.173346 -420.952168)
		(end 322.464176 -421.242998)
		(width 0.14224)
		(layer "In11.Cu")
		(net "P5E_CPU0_P0_TX_BUF_C_DN<6>")
	)
	(segment
		(start 326.37857 -430.44491)
		(end 326.50684 -430.44491)
		(width 0.14224)
		(layer "In11.Cu")
		(net "P5E_CPU0_P0_TX_BUF_C_DN<6>")
	)
	(segment
		(start 322.464176 -422.01592)
		(end 322.546218 -422.169336)
		(width 0.14224)
		(layer "In11.Cu")
		(net "P5E_CPU0_P0_TX_BUF_C_DN<6>")
	)
	(segment
		(start 322.464176 -421.242998)
		(end 322.464176 -422.01592)
		(width 0.14224)
		(layer "In11.Cu")
		(net "P5E_CPU0_P0_TX_BUF_C_DN<6>")
	)
	(segment
		(start 325.628508 -424.229276)
		(end 325.698612 -424.359832)
		(width 0.14224)
		(layer "In11.Cu")
		(net "P5E_CPU0_P0_TX_BUF_C_DN<6>")
	)
	(segment
		(start 322.546218 -422.169336)
		(end 325.628508 -424.229276)
		(width 0.14224)
		(layer "In11.Cu")
		(net "P5E_CPU0_P0_TX_BUF_C_DN<6>")
	)
	(segment
		(start 326.649588 -430.587658)
		(end 326.649588 -430.889918)
		(width 0.14224)
		(layer "In11.Cu")
		(net "P5E_CPU0_P0_TX_BUF_C_DN<6>")
	)
	(segment
		(start 326.50684 -430.44491)
		(end 326.649588 -430.587658)
		(width 0.14224)
		(layer "In11.Cu")
		(net "P5E_CPU0_P0_TX_BUF_C_DN<6>")
	)
	(segment
		(start 325.867522 -430.195482)
		(end 325.931784 -430.259744)
		(width 0.14224)
		(layer "In11.Cu")
		(net "P5E_CPU0_P0_TX_BUF_C_DN<6>")
	)
	(segment
		(start 325.698612 -424.359832)
		(end 325.698612 -429.787558)
		(width 0.14224)
		(layer "In11.Cu")
		(net "P5E_CPU0_P0_TX_BUF_C_DN<6>")
	)
	(arc
		(start 325.698612 -429.787558)
		(mid 325.742506 -430.008317)
		(end 325.867522 -430.195482)
		(width 0.14224)
		(layer "In11.Cu")
		(net "P5E_CPU0_P0_TX_BUF_C_DN<6>")
	)
	(arc
		(start 325.931784 -430.259744)
		(mid 326.13677 -430.396741)
		(end 326.37857 -430.44491)
		(width 0.14224)
		(layer "In11.Cu")
		(net "P5E_CPU0_P0_TX_BUF_C_DN<6>")
	)
	(segment
		(start 319.380616 -420.681658)
		(end 319.110106 -420.952168)
		(width 0.12954)
		(layer "F.Cu")
		(net "P5E_CPU0_P0_TX_BUF_C_DN<5>")
	)
	(segment
		(start 319.380616 -417.461954)
		(end 319.380616 -420.681658)
		(width 0.12954)
		(layer "F.Cu")
		(net "P5E_CPU0_P0_TX_BUF_C_DN<5>")
	)
	(segment
		(start 319.084706 -417.166044)
		(end 319.380616 -417.461954)
		(width 0.12954)
		(layer "F.Cu")
		(net "P5E_CPU0_P0_TX_BUF_C_DN<5>")
	)
	(segment
		(start 323.878702 -431.253646)
		(end 323.904102 -431.279046)
		(width 0.14224)
		(layer "In11.Cu")
		(net "P5E_CPU0_P0_TX_BUF_C_DN<5>")
	)
	(segment
		(start 324.270878 -431.430938)
		(end 324.507352 -431.430938)
		(width 0.14224)
		(layer "In11.Cu")
		(net "P5E_CPU0_P0_TX_BUF_C_DN<5>")
	)
	(segment
		(start 323.703696 -424.981116)
		(end 323.703696 -430.831244)
		(width 0.14224)
		(layer "In11.Cu")
		(net "P5E_CPU0_P0_TX_BUF_C_DN<5>")
	)
	(segment
		(start 321.735196 -423.010838)
		(end 323.666358 -424.944032)
		(width 0.14224)
		(layer "In11.Cu")
		(net "P5E_CPU0_P0_TX_BUF_C_DN<5>")
	)
	(segment
		(start 324.649592 -431.573178)
		(end 324.649592 -431.889916)
		(width 0.14224)
		(layer "In11.Cu")
		(net "P5E_CPU0_P0_TX_BUF_C_DN<5>")
	)
	(segment
		(start 319.400936 -421.83431)
		(end 319.80251 -422.23563)
		(width 0.14224)
		(layer "In11.Cu")
		(net "P5E_CPU0_P0_TX_BUF_C_DN<5>")
	)
	(segment
		(start 321.464178 -422.739566)
		(end 321.735196 -423.010584)
		(width 0.14224)
		(layer "In11.Cu")
		(net "P5E_CPU0_P0_TX_BUF_C_DN<5>")
	)
	(segment
		(start 319.110106 -420.952168)
		(end 319.400936 -421.242998)
		(width 0.14224)
		(layer "In11.Cu")
		(net "P5E_CPU0_P0_TX_BUF_C_DN<5>")
	)
	(segment
		(start 319.400936 -421.242998)
		(end 319.400936 -421.83431)
		(width 0.14224)
		(layer "In11.Cu")
		(net "P5E_CPU0_P0_TX_BUF_C_DN<5>")
	)
	(segment
		(start 321.735196 -423.010584)
		(end 321.735196 -423.010838)
		(width 0.14224)
		(layer "In11.Cu")
		(net "P5E_CPU0_P0_TX_BUF_C_DN<5>")
	)
	(segment
		(start 319.80251 -422.23563)
		(end 321.464178 -422.739566)
		(width 0.14224)
		(layer "In11.Cu")
		(net "P5E_CPU0_P0_TX_BUF_C_DN<5>")
	)
	(segment
		(start 324.507352 -431.430938)
		(end 324.649592 -431.573178)
		(width 0.14224)
		(layer "In11.Cu")
		(net "P5E_CPU0_P0_TX_BUF_C_DN<5>")
	)
	(segment
		(start 323.666358 -424.944032)
		(end 323.703696 -424.981116)
		(width 0.14224)
		(layer "In11.Cu")
		(net "P5E_CPU0_P0_TX_BUF_C_DN<5>")
	)
	(arc
		(start 323.703696 -430.831244)
		(mid 323.749186 -431.059848)
		(end 323.878702 -431.253646)
		(width 0.14224)
		(layer "In11.Cu")
		(net "P5E_CPU0_P0_TX_BUF_C_DN<5>")
	)
	(arc
		(start 323.904102 -431.279046)
		(mid 324.07238 -431.391486)
		(end 324.270878 -431.430938)
		(width 0.14224)
		(layer "In11.Cu")
		(net "P5E_CPU0_P0_TX_BUF_C_DN<5>")
	)
	(segment
		(start 316.317376 -417.461954)
		(end 316.317376 -420.681658)
		(width 0.12954)
		(layer "F.Cu")
		(net "P5E_CPU0_P0_TX_BUF_C_DN<4>")
	)
	(segment
		(start 316.317376 -420.681658)
		(end 316.046866 -420.952168)
		(width 0.12954)
		(layer "F.Cu")
		(net "P5E_CPU0_P0_TX_BUF_C_DN<4>")
	)
	(segment
		(start 316.021466 -417.166044)
		(end 316.317376 -417.461954)
		(width 0.12954)
		(layer "F.Cu")
		(net "P5E_CPU0_P0_TX_BUF_C_DN<4>")
	)
	(segment
		(start 318.472312 -422.246298)
		(end 319.21196 -422.985946)
		(width 0.14224)
		(layer "In11.Cu")
		(net "P5E_CPU0_P0_TX_BUF_C_DN<4>")
	)
	(segment
		(start 321.652138 -424.61688)
		(end 321.694048 -424.695112)
		(width 0.14224)
		(layer "In11.Cu")
		(net "P5E_CPU0_P0_TX_BUF_C_DN<4>")
	)
	(segment
		(start 316.50178 -421.962326)
		(end 316.926722 -422.246298)
		(width 0.14224)
		(layer "In11.Cu")
		(net "P5E_CPU0_P0_TX_BUF_C_DN<4>")
	)
	(segment
		(start 322.649596 -430.586896)
		(end 322.649596 -430.889918)
		(width 0.14224)
		(layer "In11.Cu")
		(net "P5E_CPU0_P0_TX_BUF_C_DN<4>")
	)
	(segment
		(start 321.694048 -424.695112)
		(end 321.694048 -429.839628)
		(width 0.14224)
		(layer "In11.Cu")
		(net "P5E_CPU0_P0_TX_BUF_C_DN<4>")
	)
	(segment
		(start 319.21196 -422.985946)
		(end 321.652138 -424.61688)
		(width 0.14224)
		(layer "In11.Cu")
		(net "P5E_CPU0_P0_TX_BUF_C_DN<4>")
	)
	(segment
		(start 316.343284 -421.248586)
		(end 316.343284 -421.665654)
		(width 0.14224)
		(layer "In11.Cu")
		(net "P5E_CPU0_P0_TX_BUF_C_DN<4>")
	)
	(segment
		(start 322.522596 -430.459896)
		(end 322.649596 -430.586896)
		(width 0.14224)
		(layer "In11.Cu")
		(net "P5E_CPU0_P0_TX_BUF_C_DN<4>")
	)
	(segment
		(start 316.926722 -422.246298)
		(end 318.472312 -422.246298)
		(width 0.14224)
		(layer "In11.Cu")
		(net "P5E_CPU0_P0_TX_BUF_C_DN<4>")
	)
	(segment
		(start 322.314316 -430.459896)
		(end 322.522596 -430.459896)
		(width 0.14224)
		(layer "In11.Cu")
		(net "P5E_CPU0_P0_TX_BUF_C_DN<4>")
	)
	(segment
		(start 316.343284 -421.665654)
		(end 316.50178 -421.962326)
		(width 0.14224)
		(layer "In11.Cu")
		(net "P5E_CPU0_P0_TX_BUF_C_DN<4>")
	)
	(segment
		(start 316.046866 -420.952168)
		(end 316.343284 -421.248586)
		(width 0.14224)
		(layer "In11.Cu")
		(net "P5E_CPU0_P0_TX_BUF_C_DN<4>")
	)
	(arc
		(start 321.694048 -429.839628)
		(mid 321.87572 -430.278224)
		(end 322.314316 -430.459896)
		(width 0.14224)
		(layer "In11.Cu")
		(net "P5E_CPU0_P0_TX_BUF_C_DN<4>")
	)
	(segment
		(start 313.254136 -420.681658)
		(end 312.983626 -420.952168)
		(width 0.12954)
		(layer "F.Cu")
		(net "P5E_CPU0_P0_TX_BUF_C_DN<3>")
	)
	(segment
		(start 312.958226 -417.166044)
		(end 313.254136 -417.461954)
		(width 0.12954)
		(layer "F.Cu")
		(net "P5E_CPU0_P0_TX_BUF_C_DN<3>")
	)
	(segment
		(start 313.254136 -417.461954)
		(end 313.254136 -420.681658)
		(width 0.12954)
		(layer "F.Cu")
		(net "P5E_CPU0_P0_TX_BUF_C_DN<3>")
	)
	(segment
		(start 317.863982 -423.179748)
		(end 319.59169 -424.907456)
		(width 0.14224)
		(layer "In11.Cu")
		(net "P5E_CPU0_P0_TX_BUF_C_DN<3>")
	)
	(segment
		(start 320.056002 -431.430938)
		(end 320.50736 -431.430938)
		(width 0.14224)
		(layer "In11.Cu")
		(net "P5E_CPU0_P0_TX_BUF_C_DN<3>")
	)
	(segment
		(start 320.6496 -431.573178)
		(end 320.6496 -431.889916)
		(width 0.14224)
		(layer "In11.Cu")
		(net "P5E_CPU0_P0_TX_BUF_C_DN<3>")
	)
	(segment
		(start 312.983626 -420.952168)
		(end 313.274456 -421.242998)
		(width 0.14224)
		(layer "In11.Cu")
		(net "P5E_CPU0_P0_TX_BUF_C_DN<3>")
	)
	(segment
		(start 316.91326 -423.179748)
		(end 317.863982 -423.179748)
		(width 0.14224)
		(layer "In11.Cu")
		(net "P5E_CPU0_P0_TX_BUF_C_DN<3>")
	)
	(segment
		(start 320.50736 -431.430938)
		(end 320.6496 -431.573178)
		(width 0.14224)
		(layer "In11.Cu")
		(net "P5E_CPU0_P0_TX_BUF_C_DN<3>")
	)
	(segment
		(start 313.732164 -422.320212)
		(end 315.333634 -422.320212)
		(width 0.14224)
		(layer "In11.Cu")
		(net "P5E_CPU0_P0_TX_BUF_C_DN<3>")
	)
	(segment
		(start 319.703704 -425.177712)
		(end 319.703704 -431.07864)
		(width 0.14224)
		(layer "In11.Cu")
		(net "P5E_CPU0_P0_TX_BUF_C_DN<3>")
	)
	(segment
		(start 315.333634 -422.320212)
		(end 316.37351 -423.015918)
		(width 0.14224)
		(layer "In11.Cu")
		(net "P5E_CPU0_P0_TX_BUF_C_DN<3>")
	)
	(segment
		(start 313.274456 -421.242998)
		(end 313.274456 -421.862504)
		(width 0.14224)
		(layer "In11.Cu")
		(net "P5E_CPU0_P0_TX_BUF_C_DN<3>")
	)
	(segment
		(start 319.703704 -431.07864)
		(end 320.056002 -431.430938)
		(width 0.14224)
		(layer "In11.Cu")
		(net "P5E_CPU0_P0_TX_BUF_C_DN<3>")
	)
	(segment
		(start 313.274456 -421.862504)
		(end 313.732164 -422.320212)
		(width 0.14224)
		(layer "In11.Cu")
		(net "P5E_CPU0_P0_TX_BUF_C_DN<3>")
	)
	(arc
		(start 316.37351 -423.015918)
		(mid 316.631227 -423.137888)
		(end 316.91326 -423.179748)
		(width 0.14224)
		(layer "In11.Cu")
		(net "P5E_CPU0_P0_TX_BUF_C_DN<3>")
	)
	(arc
		(start 319.59169 -424.907456)
		(mid 319.674594 -425.031436)
		(end 319.703704 -425.177712)
		(width 0.14224)
		(layer "In11.Cu")
		(net "P5E_CPU0_P0_TX_BUF_C_DN<3>")
	)
	(segment
		(start 310.190896 -420.681658)
		(end 309.920386 -420.952168)
		(width 0.12954)
		(layer "F.Cu")
		(net "P5E_CPU0_P0_TX_BUF_C_DN<2>")
	)
	(segment
		(start 310.190896 -417.461954)
		(end 310.190896 -420.681658)
		(width 0.12954)
		(layer "F.Cu")
		(net "P5E_CPU0_P0_TX_BUF_C_DN<2>")
	)
	(segment
		(start 309.894986 -417.166044)
		(end 310.190896 -417.461954)
		(width 0.12954)
		(layer "F.Cu")
		(net "P5E_CPU0_P0_TX_BUF_C_DN<2>")
	)
	(segment
		(start 317.04026 -424.222418)
		(end 317.090298 -424.272456)
		(width 0.14224)
		(layer "In11.Cu")
		(net "P5E_CPU0_P0_TX_BUF_C_DN<2>")
	)
	(segment
		(start 318.512444 -430.435766)
		(end 318.649604 -430.572926)
		(width 0.14224)
		(layer "In11.Cu")
		(net "P5E_CPU0_P0_TX_BUF_C_DN<2>")
	)
	(segment
		(start 318.284352 -430.435766)
		(end 318.512444 -430.435766)
		(width 0.14224)
		(layer "In11.Cu")
		(net "P5E_CPU0_P0_TX_BUF_C_DN<2>")
	)
	(segment
		(start 317.698628 -425.74083)
		(end 317.698628 -429.753268)
		(width 0.14224)
		(layer "In11.Cu")
		(net "P5E_CPU0_P0_TX_BUF_C_DN<2>")
	)
	(segment
		(start 315.36005 -423.45991)
		(end 316.137036 -423.979594)
		(width 0.14224)
		(layer "In11.Cu")
		(net "P5E_CPU0_P0_TX_BUF_C_DN<2>")
	)
	(segment
		(start 310.211216 -421.242998)
		(end 310.211216 -422.67251)
		(width 0.14224)
		(layer "In11.Cu")
		(net "P5E_CPU0_P0_TX_BUF_C_DN<2>")
	)
	(segment
		(start 310.844438 -423.305732)
		(end 314.987432 -423.305732)
		(width 0.14224)
		(layer "In11.Cu")
		(net "P5E_CPU0_P0_TX_BUF_C_DN<2>")
	)
	(segment
		(start 316.561978 -424.108372)
		(end 316.765178 -424.108372)
		(width 0.14224)
		(layer "In11.Cu")
		(net "P5E_CPU0_P0_TX_BUF_C_DN<2>")
	)
	(segment
		(start 318.649604 -430.572926)
		(end 318.649604 -430.889918)
		(width 0.14224)
		(layer "In11.Cu")
		(net "P5E_CPU0_P0_TX_BUF_C_DN<2>")
	)
	(segment
		(start 309.920386 -420.952168)
		(end 310.211216 -421.242998)
		(width 0.14224)
		(layer "In11.Cu")
		(net "P5E_CPU0_P0_TX_BUF_C_DN<2>")
	)
	(segment
		(start 314.987432 -423.305732)
		(end 315.36005 -423.45991)
		(width 0.14224)
		(layer "In11.Cu")
		(net "P5E_CPU0_P0_TX_BUF_C_DN<2>")
	)
	(arc
		(start 317.698628 -429.753268)
		(mid 317.755796 -430.040582)
		(end 317.918592 -430.284128)
		(width 0.14224)
		(layer "In11.Cu")
		(net "P5E_CPU0_P0_TX_BUF_C_DN<2>")
	)
	(arc
		(start 317.090298 -424.272456)
		(mid 317.540501 -424.946137)
		(end 317.698628 -425.74083)
		(width 0.14224)
		(layer "In11.Cu")
		(net "P5E_CPU0_P0_TX_BUF_C_DN<2>")
	)
	(arc
		(start 316.137036 -423.979594)
		(mid 316.339948 -424.075517)
		(end 316.561978 -424.108372)
		(width 0.14224)
		(layer "In11.Cu")
		(net "P5E_CPU0_P0_TX_BUF_C_DN<2>")
	)
	(arc
		(start 310.211216 -422.67251)
		(mid 310.396682 -423.120266)
		(end 310.844438 -423.305732)
		(width 0.14224)
		(layer "In11.Cu")
		(net "P5E_CPU0_P0_TX_BUF_C_DN<2>")
	)
	(arc
		(start 316.765178 -424.108372)
		(mid 316.914077 -424.138008)
		(end 317.04026 -424.222418)
		(width 0.14224)
		(layer "In11.Cu")
		(net "P5E_CPU0_P0_TX_BUF_C_DN<2>")
	)
	(arc
		(start 317.918592 -430.284128)
		(mid 318.08639 -430.39631)
		(end 318.284352 -430.435766)
		(width 0.14224)
		(layer "In11.Cu")
		(net "P5E_CPU0_P0_TX_BUF_C_DN<2>")
	)
	(segment
		(start 306.831746 -417.166044)
		(end 307.127656 -417.461954)
		(width 0.12954)
		(layer "F.Cu")
		(net "P5E_CPU0_P0_TX_BUF_C_DN<1>")
	)
	(segment
		(start 307.127656 -420.681658)
		(end 306.857146 -420.952168)
		(width 0.12954)
		(layer "F.Cu")
		(net "P5E_CPU0_P0_TX_BUF_C_DN<1>")
	)
	(segment
		(start 307.127656 -417.461954)
		(end 307.127656 -420.681658)
		(width 0.12954)
		(layer "F.Cu")
		(net "P5E_CPU0_P0_TX_BUF_C_DN<1>")
	)
	(segment
		(start 314.796424 -424.238674)
		(end 314.964064 -424.308016)
		(width 0.14224)
		(layer "In11.Cu")
		(net "P5E_CPU0_P0_TX_BUF_C_DN<1>")
	)
	(segment
		(start 316.507368 -431.430938)
		(end 316.649608 -431.573178)
		(width 0.14224)
		(layer "In11.Cu")
		(net "P5E_CPU0_P0_TX_BUF_C_DN<1>")
	)
	(segment
		(start 314.964064 -424.308016)
		(end 315.076332 -424.383454)
		(width 0.14224)
		(layer "In11.Cu")
		(net "P5E_CPU0_P0_TX_BUF_C_DN<1>")
	)
	(segment
		(start 315.8236 -431.198528)
		(end 315.86551 -431.240438)
		(width 0.14224)
		(layer "In11.Cu")
		(net "P5E_CPU0_P0_TX_BUF_C_DN<1>")
	)
	(segment
		(start 316.649608 -431.573178)
		(end 316.649608 -431.889916)
		(width 0.14224)
		(layer "In11.Cu")
		(net "P5E_CPU0_P0_TX_BUF_C_DN<1>")
	)
	(segment
		(start 306.857146 -420.952168)
		(end 307.147976 -421.242998)
		(width 0.14224)
		(layer "In11.Cu")
		(net "P5E_CPU0_P0_TX_BUF_C_DN<1>")
	)
	(segment
		(start 307.311298 -422.045384)
		(end 309.3847 -424.118786)
		(width 0.14224)
		(layer "In11.Cu")
		(net "P5E_CPU0_P0_TX_BUF_C_DN<1>")
	)
	(segment
		(start 315.703712 -425.559982)
		(end 315.703712 -430.909222)
		(width 0.14224)
		(layer "In11.Cu")
		(net "P5E_CPU0_P0_TX_BUF_C_DN<1>")
	)
	(segment
		(start 307.147976 -421.242998)
		(end 307.147976 -421.651176)
		(width 0.14224)
		(layer "In11.Cu")
		(net "P5E_CPU0_P0_TX_BUF_C_DN<1>")
	)
	(segment
		(start 309.674006 -424.238674)
		(end 314.796424 -424.238674)
		(width 0.14224)
		(layer "In11.Cu")
		(net "P5E_CPU0_P0_TX_BUF_C_DN<1>")
	)
	(segment
		(start 316.32525 -431.430938)
		(end 316.507368 -431.430938)
		(width 0.14224)
		(layer "In11.Cu")
		(net "P5E_CPU0_P0_TX_BUF_C_DN<1>")
	)
	(arc
		(start 307.147976 -421.651176)
		(mid 307.190415 -421.864533)
		(end 307.311298 -422.045384)
		(width 0.14224)
		(layer "In11.Cu")
		(net "P5E_CPU0_P0_TX_BUF_C_DN<1>")
	)
	(arc
		(start 315.86551 -431.240438)
		(mid 316.076426 -431.381431)
		(end 316.32525 -431.430938)
		(width 0.14224)
		(layer "In11.Cu")
		(net "P5E_CPU0_P0_TX_BUF_C_DN<1>")
	)
	(arc
		(start 315.703712 -430.909222)
		(mid 315.734875 -431.0658)
		(end 315.8236 -431.198528)
		(width 0.14224)
		(layer "In11.Cu")
		(net "P5E_CPU0_P0_TX_BUF_C_DN<1>")
	)
	(arc
		(start 315.076332 -424.383454)
		(mid 315.537083 -424.893301)
		(end 315.703712 -425.559982)
		(width 0.14224)
		(layer "In11.Cu")
		(net "P5E_CPU0_P0_TX_BUF_C_DN<1>")
	)
	(arc
		(start 309.3847 -424.118786)
		(mid 309.51742 -424.20753)
		(end 309.674006 -424.238674)
		(width 0.14224)
		(layer "In11.Cu")
		(net "P5E_CPU0_P0_TX_BUF_C_DN<1>")
	)
	(segment
		(start 350.013016 -420.681658)
		(end 349.742506 -420.952168)
		(width 0.12954)
		(layer "F.Cu")
		(net "P5E_CPU0_P0_TX_BUF_C_DN<15>")
	)
	(segment
		(start 349.717106 -417.166044)
		(end 350.013016 -417.461954)
		(width 0.12954)
		(layer "F.Cu")
		(net "P5E_CPU0_P0_TX_BUF_C_DN<15>")
	)
	(segment
		(start 350.013016 -417.461954)
		(end 350.013016 -420.681658)
		(width 0.12954)
		(layer "F.Cu")
		(net "P5E_CPU0_P0_TX_BUF_C_DN<15>")
	)
	(segment
		(start 347.384116 -423.096182)
		(end 347.384116 -423.096436)
		(width 0.14224)
		(layer "In11.Cu")
		(net "P5E_CPU0_P0_TX_BUF_C_DN<15>")
	)
	(segment
		(start 349.508064 -422.335706)
		(end 347.384116 -423.096182)
		(width 0.14224)
		(layer "In11.Cu")
		(net "P5E_CPU0_P0_TX_BUF_C_DN<15>")
	)
	(segment
		(start 345.507564 -431.430938)
		(end 345.649804 -431.573178)
		(width 0.14224)
		(layer "In11.Cu")
		(net "P5E_CPU0_P0_TX_BUF_C_DN<15>")
	)
	(segment
		(start 344.703908 -424.846496)
		(end 344.703908 -430.875694)
		(width 0.14224)
		(layer "In11.Cu")
		(net "P5E_CPU0_P0_TX_BUF_C_DN<15>")
	)
	(segment
		(start 345.225624 -431.430938)
		(end 345.507564 -431.430938)
		(width 0.14224)
		(layer "In11.Cu")
		(net "P5E_CPU0_P0_TX_BUF_C_DN<15>")
	)
	(segment
		(start 347.384116 -423.096436)
		(end 345.277694 -423.850054)
		(width 0.14224)
		(layer "In11.Cu")
		(net "P5E_CPU0_P0_TX_BUF_C_DN<15>")
	)
	(segment
		(start 344.847418 -431.22215)
		(end 344.936318 -431.31105)
		(width 0.14224)
		(layer "In11.Cu")
		(net "P5E_CPU0_P0_TX_BUF_C_DN<15>")
	)
	(segment
		(start 350.049846 -421.259508)
		(end 350.049846 -421.738552)
		(width 0.14224)
		(layer "In11.Cu")
		(net "P5E_CPU0_P0_TX_BUF_C_DN<15>")
	)
	(segment
		(start 345.649804 -431.573178)
		(end 345.649804 -431.889916)
		(width 0.14224)
		(layer "In11.Cu")
		(net "P5E_CPU0_P0_TX_BUF_C_DN<15>")
	)
	(segment
		(start 349.983298 -421.899334)
		(end 349.613982 -422.26865)
		(width 0.14224)
		(layer "In11.Cu")
		(net "P5E_CPU0_P0_TX_BUF_C_DN<15>")
	)
	(segment
		(start 349.613982 -422.26865)
		(end 349.613728 -422.26865)
		(width 0.14224)
		(layer "In11.Cu")
		(net "P5E_CPU0_P0_TX_BUF_C_DN<15>")
	)
	(segment
		(start 349.742506 -420.952168)
		(end 350.049846 -421.259508)
		(width 0.14224)
		(layer "In11.Cu")
		(net "P5E_CPU0_P0_TX_BUF_C_DN<15>")
	)
	(arc
		(start 345.277694 -423.850054)
		(mid 345.097184 -423.946523)
		(end 344.952574 -424.091354)
		(width 0.14224)
		(layer "In11.Cu")
		(net "P5E_CPU0_P0_TX_BUF_C_DN<15>")
	)
	(arc
		(start 350.049846 -421.738552)
		(mid 350.03261 -421.825587)
		(end 349.983298 -421.899334)
		(width 0.14224)
		(layer "In11.Cu")
		(net "P5E_CPU0_P0_TX_BUF_C_DN<15>")
	)
	(arc
		(start 344.952574 -424.091354)
		(mid 344.767612 -424.448958)
		(end 344.703908 -424.846496)
		(width 0.14224)
		(layer "In11.Cu")
		(net "P5E_CPU0_P0_TX_BUF_C_DN<15>")
	)
	(arc
		(start 349.613728 -422.26865)
		(mid 349.593713 -422.286903)
		(end 349.572072 -422.303194)
		(width 0.14224)
		(layer "In11.Cu")
		(net "P5E_CPU0_P0_TX_BUF_C_DN<15>")
	)
	(arc
		(start 344.703908 -430.875694)
		(mid 344.741204 -431.063196)
		(end 344.847418 -431.22215)
		(width 0.14224)
		(layer "In11.Cu")
		(net "P5E_CPU0_P0_TX_BUF_C_DN<15>")
	)
	(arc
		(start 349.572072 -422.303194)
		(mid 349.541091 -422.321464)
		(end 349.508064 -422.335706)
		(width 0.14224)
		(layer "In11.Cu")
		(net "P5E_CPU0_P0_TX_BUF_C_DN<15>")
	)
	(arc
		(start 344.936318 -431.31105)
		(mid 345.069038 -431.399794)
		(end 345.225624 -431.430938)
		(width 0.14224)
		(layer "In11.Cu")
		(net "P5E_CPU0_P0_TX_BUF_C_DN<15>")
	)
	(segment
		(start 346.653866 -417.166044)
		(end 346.949776 -417.461954)
		(width 0.12954)
		(layer "F.Cu")
		(net "P5E_CPU0_P0_TX_BUF_C_DN<14>")
	)
	(segment
		(start 346.949776 -417.461954)
		(end 346.949776 -420.681658)
		(width 0.12954)
		(layer "F.Cu")
		(net "P5E_CPU0_P0_TX_BUF_C_DN<14>")
	)
	(segment
		(start 346.949776 -420.681658)
		(end 346.679266 -420.952168)
		(width 0.12954)
		(layer "F.Cu")
		(net "P5E_CPU0_P0_TX_BUF_C_DN<14>")
	)
	(segment
		(start 343.507568 -430.430686)
		(end 343.649808 -430.572926)
		(width 0.14224)
		(layer "In11.Cu")
		(net "P5E_CPU0_P0_TX_BUF_C_DN<14>")
	)
	(segment
		(start 346.809568 -421.943022)
		(end 344.777314 -422.78427)
		(width 0.14224)
		(layer "In11.Cu")
		(net "P5E_CPU0_P0_TX_BUF_C_DN<14>")
	)
	(segment
		(start 344.067892 -423.078148)
		(end 342.902286 -424.243754)
		(width 0.14224)
		(layer "In11.Cu")
		(net "P5E_CPU0_P0_TX_BUF_C_DN<14>")
	)
	(segment
		(start 342.698832 -424.734736)
		(end 342.698832 -429.795686)
		(width 0.14224)
		(layer "In11.Cu")
		(net "P5E_CPU0_P0_TX_BUF_C_DN<14>")
	)
	(segment
		(start 344.777314 -422.784524)
		(end 344.067892 -423.078148)
		(width 0.14224)
		(layer "In11.Cu")
		(net "P5E_CPU0_P0_TX_BUF_C_DN<14>")
	)
	(segment
		(start 343.34196 -430.430686)
		(end 343.507568 -430.430686)
		(width 0.14224)
		(layer "In11.Cu")
		(net "P5E_CPU0_P0_TX_BUF_C_DN<14>")
	)
	(segment
		(start 346.970096 -421.782494)
		(end 346.809568 -421.943022)
		(width 0.14224)
		(layer "In11.Cu")
		(net "P5E_CPU0_P0_TX_BUF_C_DN<14>")
	)
	(segment
		(start 346.970096 -421.242998)
		(end 346.970096 -421.782494)
		(width 0.14224)
		(layer "In11.Cu")
		(net "P5E_CPU0_P0_TX_BUF_C_DN<14>")
	)
	(segment
		(start 346.679266 -420.952168)
		(end 346.970096 -421.242998)
		(width 0.14224)
		(layer "In11.Cu")
		(net "P5E_CPU0_P0_TX_BUF_C_DN<14>")
	)
	(segment
		(start 344.777314 -422.78427)
		(end 344.777314 -422.784524)
		(width 0.14224)
		(layer "In11.Cu")
		(net "P5E_CPU0_P0_TX_BUF_C_DN<14>")
	)
	(segment
		(start 342.862154 -430.189894)
		(end 342.934036 -430.261776)
		(width 0.14224)
		(layer "In11.Cu")
		(net "P5E_CPU0_P0_TX_BUF_C_DN<14>")
	)
	(segment
		(start 343.649808 -430.572926)
		(end 343.649808 -430.889918)
		(width 0.14224)
		(layer "In11.Cu")
		(net "P5E_CPU0_P0_TX_BUF_C_DN<14>")
	)
	(arc
		(start 342.934036 -430.261776)
		(mid 343.121207 -430.386777)
		(end 343.34196 -430.430686)
		(width 0.14224)
		(layer "In11.Cu")
		(net "P5E_CPU0_P0_TX_BUF_C_DN<14>")
	)
	(arc
		(start 342.902286 -424.243754)
		(mid 342.751715 -424.469004)
		(end 342.698832 -424.734736)
		(width 0.14224)
		(layer "In11.Cu")
		(net "P5E_CPU0_P0_TX_BUF_C_DN<14>")
	)
	(arc
		(start 342.698832 -429.795686)
		(mid 342.741271 -430.009043)
		(end 342.862154 -430.189894)
		(width 0.14224)
		(layer "In11.Cu")
		(net "P5E_CPU0_P0_TX_BUF_C_DN<14>")
	)
	(segment
		(start 343.886536 -420.681658)
		(end 343.616026 -420.952168)
		(width 0.12954)
		(layer "F.Cu")
		(net "P5E_CPU0_P0_TX_BUF_C_DN<13>")
	)
	(segment
		(start 343.886536 -417.461954)
		(end 343.886536 -420.681658)
		(width 0.12954)
		(layer "F.Cu")
		(net "P5E_CPU0_P0_TX_BUF_C_DN<13>")
	)
	(segment
		(start 343.590626 -417.166044)
		(end 343.886536 -417.461954)
		(width 0.12954)
		(layer "F.Cu")
		(net "P5E_CPU0_P0_TX_BUF_C_DN<13>")
	)
	(segment
		(start 341.649812 -431.573686)
		(end 341.649812 -431.889916)
		(width 0.14224)
		(layer "In11.Cu")
		(net "P5E_CPU0_P0_TX_BUF_C_DN<13>")
	)
	(segment
		(start 343.906856 -421.83304)
		(end 343.816686 -422.001696)
		(width 0.14224)
		(layer "In11.Cu")
		(net "P5E_CPU0_P0_TX_BUF_C_DN<13>")
	)
	(segment
		(start 340.703916 -424.318938)
		(end 340.703916 -430.903634)
		(width 0.14224)
		(layer "In11.Cu")
		(net "P5E_CPU0_P0_TX_BUF_C_DN<13>")
	)
	(segment
		(start 343.906856 -421.242998)
		(end 343.906856 -421.83304)
		(width 0.14224)
		(layer "In11.Cu")
		(net "P5E_CPU0_P0_TX_BUF_C_DN<13>")
	)
	(segment
		(start 343.616026 -420.952168)
		(end 343.906856 -421.242998)
		(width 0.14224)
		(layer "In11.Cu")
		(net "P5E_CPU0_P0_TX_BUF_C_DN<13>")
	)
	(segment
		(start 343.816686 -422.001696)
		(end 340.90102 -423.949876)
		(width 0.14224)
		(layer "In11.Cu")
		(net "P5E_CPU0_P0_TX_BUF_C_DN<13>")
	)
	(segment
		(start 341.24773 -431.446686)
		(end 341.522812 -431.446686)
		(width 0.14224)
		(layer "In11.Cu")
		(net "P5E_CPU0_P0_TX_BUF_C_DN<13>")
	)
	(segment
		(start 341.522812 -431.446686)
		(end 341.649812 -431.573686)
		(width 0.14224)
		(layer "In11.Cu")
		(net "P5E_CPU0_P0_TX_BUF_C_DN<13>")
	)
	(arc
		(start 340.90102 -423.949876)
		(mid 340.756254 -424.109731)
		(end 340.703916 -424.318938)
		(width 0.14224)
		(layer "In11.Cu")
		(net "P5E_CPU0_P0_TX_BUF_C_DN<13>")
	)
	(arc
		(start 340.703916 -430.903634)
		(mid 340.863316 -431.287825)
		(end 341.24773 -431.446686)
		(width 0.14224)
		(layer "In11.Cu")
		(net "P5E_CPU0_P0_TX_BUF_C_DN<13>")
	)
	(segment
		(start 340.527386 -417.166044)
		(end 340.823296 -417.461954)
		(width 0.12954)
		(layer "F.Cu")
		(net "P5E_CPU0_P0_TX_BUF_C_DN<12>")
	)
	(segment
		(start 340.823296 -417.461954)
		(end 340.823296 -420.681658)
		(width 0.12954)
		(layer "F.Cu")
		(net "P5E_CPU0_P0_TX_BUF_C_DN<12>")
	)
	(segment
		(start 340.823296 -420.681658)
		(end 340.552786 -420.952168)
		(width 0.12954)
		(layer "F.Cu")
		(net "P5E_CPU0_P0_TX_BUF_C_DN<12>")
	)
	(segment
		(start 339.452712 -430.452276)
		(end 339.649816 -430.64938)
		(width 0.14224)
		(layer "In11.Cu")
		(net "P5E_CPU0_P0_TX_BUF_C_DN<12>")
	)
	(segment
		(start 339.649816 -430.64938)
		(end 339.649816 -430.889918)
		(width 0.14224)
		(layer "In11.Cu")
		(net "P5E_CPU0_P0_TX_BUF_C_DN<12>")
	)
	(segment
		(start 340.674198 -421.951404)
		(end 338.695538 -424.36288)
		(width 0.14224)
		(layer "In11.Cu")
		(net "P5E_CPU0_P0_TX_BUF_C_DN<12>")
	)
	(segment
		(start 338.695538 -424.36288)
		(end 338.695538 -429.71339)
		(width 0.14224)
		(layer "In11.Cu")
		(net "P5E_CPU0_P0_TX_BUF_C_DN<12>")
	)
	(segment
		(start 339.293962 -430.452276)
		(end 339.452712 -430.452276)
		(width 0.14224)
		(layer "In11.Cu")
		(net "P5E_CPU0_P0_TX_BUF_C_DN<12>")
	)
	(segment
		(start 340.843616 -421.242998)
		(end 340.843616 -421.74414)
		(width 0.14224)
		(layer "In11.Cu")
		(net "P5E_CPU0_P0_TX_BUF_C_DN<12>")
	)
	(segment
		(start 340.552786 -420.952168)
		(end 340.843616 -421.242998)
		(width 0.14224)
		(layer "In11.Cu")
		(net "P5E_CPU0_P0_TX_BUF_C_DN<12>")
	)
	(segment
		(start 340.843616 -421.74414)
		(end 340.674198 -421.950642)
		(width 0.14224)
		(layer "In11.Cu")
		(net "P5E_CPU0_P0_TX_BUF_C_DN<12>")
	)
	(segment
		(start 338.91474 -430.242472)
		(end 339.004656 -430.332388)
		(width 0.14224)
		(layer "In11.Cu")
		(net "P5E_CPU0_P0_TX_BUF_C_DN<12>")
	)
	(segment
		(start 340.674198 -421.950642)
		(end 340.674198 -421.951404)
		(width 0.14224)
		(layer "In11.Cu")
		(net "P5E_CPU0_P0_TX_BUF_C_DN<12>")
	)
	(arc
		(start 338.695538 -429.71339)
		(mid 338.752513 -429.999732)
		(end 338.91474 -430.242472)
		(width 0.14224)
		(layer "In11.Cu")
		(net "P5E_CPU0_P0_TX_BUF_C_DN<12>")
	)
	(arc
		(start 339.004656 -430.332388)
		(mid 339.137376 -430.421132)
		(end 339.293962 -430.452276)
		(width 0.14224)
		(layer "In11.Cu")
		(net "P5E_CPU0_P0_TX_BUF_C_DN<12>")
	)
	(segment
		(start 337.464146 -417.166044)
		(end 337.760056 -417.461954)
		(width 0.12954)
		(layer "F.Cu")
		(net "P5E_CPU0_P0_TX_BUF_C_DN<11>")
	)
	(segment
		(start 337.760056 -420.681658)
		(end 337.489546 -420.952168)
		(width 0.12954)
		(layer "F.Cu")
		(net "P5E_CPU0_P0_TX_BUF_C_DN<11>")
	)
	(segment
		(start 337.760056 -417.461954)
		(end 337.760056 -420.681658)
		(width 0.12954)
		(layer "F.Cu")
		(net "P5E_CPU0_P0_TX_BUF_C_DN<11>")
	)
	(segment
		(start 337.50758 -431.430938)
		(end 337.64982 -431.573178)
		(width 0.14224)
		(layer "In11.Cu")
		(net "P5E_CPU0_P0_TX_BUF_C_DN<11>")
	)
	(segment
		(start 337.281266 -431.430938)
		(end 337.50758 -431.430938)
		(width 0.14224)
		(layer "In11.Cu")
		(net "P5E_CPU0_P0_TX_BUF_C_DN<11>")
	)
	(segment
		(start 337.64982 -431.573178)
		(end 337.64982 -431.889916)
		(width 0.14224)
		(layer "In11.Cu")
		(net "P5E_CPU0_P0_TX_BUF_C_DN<11>")
	)
	(segment
		(start 337.489546 -420.952168)
		(end 337.780376 -421.242998)
		(width 0.14224)
		(layer "In11.Cu")
		(net "P5E_CPU0_P0_TX_BUF_C_DN<11>")
	)
	(segment
		(start 336.823812 -431.198782)
		(end 336.896964 -431.27168)
		(width 0.14224)
		(layer "In11.Cu")
		(net "P5E_CPU0_P0_TX_BUF_C_DN<11>")
	)
	(segment
		(start 337.780376 -421.594026)
		(end 336.703924 -424.1927)
		(width 0.14224)
		(layer "In11.Cu")
		(net "P5E_CPU0_P0_TX_BUF_C_DN<11>")
	)
	(segment
		(start 336.703924 -424.1927)
		(end 336.703924 -430.909222)
		(width 0.14224)
		(layer "In11.Cu")
		(net "P5E_CPU0_P0_TX_BUF_C_DN<11>")
	)
	(segment
		(start 337.780376 -421.242998)
		(end 337.780376 -421.594026)
		(width 0.14224)
		(layer "In11.Cu")
		(net "P5E_CPU0_P0_TX_BUF_C_DN<11>")
	)
	(arc
		(start 336.703924 -430.909222)
		(mid 336.735038 -431.065936)
		(end 336.823812 -431.198782)
		(width 0.14224)
		(layer "In11.Cu")
		(net "P5E_CPU0_P0_TX_BUF_C_DN<11>")
	)
	(arc
		(start 336.896964 -431.27168)
		(mid 337.073269 -431.389546)
		(end 337.281266 -431.430938)
		(width 0.14224)
		(layer "In11.Cu")
		(net "P5E_CPU0_P0_TX_BUF_C_DN<11>")
	)
	(segment
		(start 334.696816 -420.681658)
		(end 334.426306 -420.952168)
		(width 0.12954)
		(layer "F.Cu")
		(net "P5E_CPU0_P0_TX_BUF_C_DN<10>")
	)
	(segment
		(start 334.400906 -417.166044)
		(end 334.696816 -417.461954)
		(width 0.12954)
		(layer "F.Cu")
		(net "P5E_CPU0_P0_TX_BUF_C_DN<10>")
	)
	(segment
		(start 334.696816 -417.461954)
		(end 334.696816 -420.681658)
		(width 0.12954)
		(layer "F.Cu")
		(net "P5E_CPU0_P0_TX_BUF_C_DN<10>")
	)
	(segment
		(start 335.649824 -430.59731)
		(end 335.649824 -430.889918)
		(width 0.14224)
		(layer "In11.Cu")
		(net "P5E_CPU0_P0_TX_BUF_C_DN<10>")
	)
	(segment
		(start 335.27238 -430.430686)
		(end 335.4832 -430.430686)
		(width 0.14224)
		(layer "In11.Cu")
		(net "P5E_CPU0_P0_TX_BUF_C_DN<10>")
	)
	(segment
		(start 334.426306 -420.952168)
		(end 334.698848 -421.22471)
		(width 0.14224)
		(layer "In11.Cu")
		(net "P5E_CPU0_P0_TX_BUF_C_DN<10>")
	)
	(segment
		(start 335.4832 -430.430686)
		(end 335.649824 -430.59731)
		(width 0.14224)
		(layer "In11.Cu")
		(net "P5E_CPU0_P0_TX_BUF_C_DN<10>")
	)
	(segment
		(start 334.698848 -421.22471)
		(end 334.698848 -429.737774)
		(width 0.14224)
		(layer "In11.Cu")
		(net "P5E_CPU0_P0_TX_BUF_C_DN<10>")
	)
	(segment
		(start 334.903064 -430.230788)
		(end 334.983074 -430.310798)
		(width 0.14224)
		(layer "In11.Cu")
		(net "P5E_CPU0_P0_TX_BUF_C_DN<10>")
	)
	(arc
		(start 334.698848 -429.737774)
		(mid 334.751921 -430.004592)
		(end 334.903064 -430.230788)
		(width 0.14224)
		(layer "In11.Cu")
		(net "P5E_CPU0_P0_TX_BUF_C_DN<10>")
	)
	(arc
		(start 334.983074 -430.310798)
		(mid 335.115794 -430.399542)
		(end 335.27238 -430.430686)
		(width 0.14224)
		(layer "In11.Cu")
		(net "P5E_CPU0_P0_TX_BUF_C_DN<10>")
	)
	(segment
		(start 303.768506 -417.166044)
		(end 304.064416 -417.461954)
		(width 0.12954)
		(layer "F.Cu")
		(net "P5E_CPU0_P0_TX_BUF_C_DN<0>")
	)
	(segment
		(start 304.064416 -417.461954)
		(end 304.064416 -420.681658)
		(width 0.12954)
		(layer "F.Cu")
		(net "P5E_CPU0_P0_TX_BUF_C_DN<0>")
	)
	(segment
		(start 304.064416 -420.681658)
		(end 303.793906 -420.952168)
		(width 0.12954)
		(layer "F.Cu")
		(net "P5E_CPU0_P0_TX_BUF_C_DN<0>")
	)
	(segment
		(start 303.793906 -420.952168)
		(end 304.084736 -421.242998)
		(width 0.14224)
		(layer "In11.Cu")
		(net "P5E_CPU0_P0_TX_BUF_C_DN<0>")
	)
	(segment
		(start 311.309512 -428.29353)
		(end 313.087258 -429.826166)
		(width 0.14224)
		(layer "In11.Cu")
		(net "P5E_CPU0_P0_TX_BUF_C_DN<0>")
	)
	(segment
		(start 314.25388 -430.430686)
		(end 314.507372 -430.430686)
		(width 0.14224)
		(layer "In11.Cu")
		(net "P5E_CPU0_P0_TX_BUF_C_DN<0>")
	)
	(segment
		(start 308.589172 -425.757086)
		(end 308.728872 -425.896786)
		(width 0.14224)
		(layer "In11.Cu")
		(net "P5E_CPU0_P0_TX_BUF_C_DN<0>")
	)
	(segment
		(start 314.649612 -430.572926)
		(end 314.649612 -430.889918)
		(width 0.14224)
		(layer "In11.Cu")
		(net "P5E_CPU0_P0_TX_BUF_C_DN<0>")
	)
	(segment
		(start 304.226722 -421.99687)
		(end 308.58206 -425.750482)
		(width 0.14224)
		(layer "In11.Cu")
		(net "P5E_CPU0_P0_TX_BUF_C_DN<0>")
	)
	(segment
		(start 314.507372 -430.430686)
		(end 314.649612 -430.572926)
		(width 0.14224)
		(layer "In11.Cu")
		(net "P5E_CPU0_P0_TX_BUF_C_DN<0>")
	)
	(segment
		(start 304.084736 -421.242998)
		(end 304.084736 -421.68699)
		(width 0.14224)
		(layer "In11.Cu")
		(net "P5E_CPU0_P0_TX_BUF_C_DN<0>")
	)
	(arc
		(start 308.58206 -425.750482)
		(mid 308.585677 -425.753718)
		(end 308.589172 -425.757086)
		(width 0.14224)
		(layer "In11.Cu")
		(net "P5E_CPU0_P0_TX_BUF_C_DN<0>")
	)
	(arc
		(start 313.952636 -430.368456)
		(mid 314.100066 -430.415024)
		(end 314.25388 -430.430686)
		(width 0.14224)
		(layer "In11.Cu")
		(net "P5E_CPU0_P0_TX_BUF_C_DN<0>")
	)
	(arc
		(start 308.728872 -425.896786)
		(mid 309.997067 -427.118981)
		(end 311.309512 -428.29353)
		(width 0.14224)
		(layer "In11.Cu")
		(net "P5E_CPU0_P0_TX_BUF_C_DN<0>")
	)
	(arc
		(start 313.087258 -429.826166)
		(mid 313.499347 -430.130184)
		(end 313.952636 -430.368456)
		(width 0.14224)
		(layer "In11.Cu")
		(net "P5E_CPU0_P0_TX_BUF_C_DN<0>")
	)
	(arc
		(start 304.084736 -421.68699)
		(mid 304.121919 -421.857424)
		(end 304.226722 -421.99687)
		(width 0.14224)
		(layer "In11.Cu")
		(net "P5E_CPU0_P0_TX_BUF_C_DN<0>")
	)
	(segment
		(start 313.9313 -399.941796)
		(end 313.9313 -401.105878)
		(width 0.1016)
		(layer "F.Cu")
		(net "P5E_CPU0_P0_RX_BUF_DP<9>")
	)
	(segment
		(start 314.184538 -401.359116)
		(end 314.477654 -401.359116)
		(width 0.1016)
		(layer "F.Cu")
		(net "P5E_CPU0_P0_RX_BUF_DP<9>")
	)
	(segment
		(start 314.616338 -401.4978)
		(end 314.616338 -401.674838)
		(width 0.1016)
		(layer "F.Cu")
		(net "P5E_CPU0_P0_RX_BUF_DP<9>")
	)
	(segment
		(start 313.917838 -399.663158)
		(end 314.00242 -399.74774)
		(width 0.1016)
		(layer "F.Cu")
		(net "P5E_CPU0_P0_RX_BUF_DP<9>")
	)
	(segment
		(start 314.477654 -401.359116)
		(end 314.616338 -401.4978)
		(width 0.1016)
		(layer "F.Cu")
		(net "P5E_CPU0_P0_RX_BUF_DP<9>")
	)
	(segment
		(start 313.9313 -401.105878)
		(end 314.184538 -401.359116)
		(width 0.1016)
		(layer "F.Cu")
		(net "P5E_CPU0_P0_RX_BUF_DP<9>")
	)
	(segment
		(start 314.00242 -399.870676)
		(end 313.9313 -399.941796)
		(width 0.1016)
		(layer "F.Cu")
		(net "P5E_CPU0_P0_RX_BUF_DP<9>")
	)
	(segment
		(start 314.00242 -399.74774)
		(end 314.00242 -399.870676)
		(width 0.1016)
		(layer "F.Cu")
		(net "P5E_CPU0_P0_RX_BUF_DP<9>")
	)
	(segment
		(start 315.75248 -406.258268)
		(end 315.75248 -406.075388)
		(width 0.14224)
		(layer "In15.Cu")
		(net "P5E_CPU0_P0_RX_BUF_DP<9>")
	)
	(segment
		(start 332.860142 -419.62197)
		(end 332.463394 -419.457378)
		(width 0.14224)
		(layer "In15.Cu")
		(net "P5E_CPU0_P0_RX_BUF_DP<9>")
	)
	(segment
		(start 314.15736 -404.183596)
		(end 314.29452 -404.046436)
		(width 0.14224)
		(layer "In15.Cu")
		(net "P5E_CPU0_P0_RX_BUF_DP<9>")
	)
	(segment
		(start 314.15736 -401.520406)
		(end 314.28436 -401.393406)
		(width 0.14224)
		(layer "In15.Cu")
		(net "P5E_CPU0_P0_RX_BUF_DP<9>")
	)
	(segment
		(start 333.410306 -422.92651)
		(end 333.473044 -422.504108)
		(width 0.14224)
		(layer "In15.Cu")
		(net "P5E_CPU0_P0_RX_BUF_DP<9>")
	)
	(segment
		(start 326.300084 -410.464)
		(end 325.891906 -410.340302)
		(width 0.14224)
		(layer "In15.Cu")
		(net "P5E_CPU0_P0_RX_BUF_DP<9>")
	)
	(segment
		(start 327.84669 -410.826966)
		(end 327.438004 -410.703014)
		(width 0.14224)
		(layer "In15.Cu")
		(net "P5E_CPU0_P0_RX_BUF_DP<9>")
	)
	(segment
		(start 333.177388 -423.578782)
		(end 333.257144 -423.040048)
		(width 0.14224)
		(layer "In15.Cu")
		(net "P5E_CPU0_P0_RX_BUF_DP<9>")
	)
	(segment
		(start 329.675744 -411.489144)
		(end 327.914508 -410.954728)
		(width 0.14224)
		(layer "In15.Cu")
		(net "P5E_CPU0_P0_RX_BUF_DP<9>")
	)
	(segment
		(start 314.29452 -404.046436)
		(end 314.29452 -403.619716)
		(width 0.14224)
		(layer "In15.Cu")
		(net "P5E_CPU0_P0_RX_BUF_DP<9>")
	)
	(segment
		(start 327.914254 -410.953966)
		(end 327.84669 -410.826966)
		(width 0.14224)
		(layer "In15.Cu")
		(net "P5E_CPU0_P0_RX_BUF_DP<9>")
	)
	(segment
		(start 332.072996 -415.91738)
		(end 331.935836 -415.78022)
		(width 0.14224)
		(layer "In15.Cu")
		(net "P5E_CPU0_P0_RX_BUF_DP<9>")
	)
	(segment
		(start 330.404216 -413.502856)
		(end 330.404216 -412.337504)
		(width 0.14224)
		(layer "In15.Cu")
		(net "P5E_CPU0_P0_RX_BUF_DP<9>")
	)
	(segment
		(start 314.458858 -404.964646)
		(end 314.194698 -404.700486)
		(width 0.14224)
		(layer "In15.Cu")
		(net "P5E_CPU0_P0_RX_BUF_DP<9>")
	)
	(segment
		(start 314.28436 -401.393406)
		(end 314.489338 -401.393406)
		(width 0.14224)
		(layer "In15.Cu")
		(net "P5E_CPU0_P0_RX_BUF_DP<9>")
	)
	(segment
		(start 314.15736 -403.482556)
		(end 314.15736 -401.520406)
		(width 0.14224)
		(layer "In15.Cu")
		(net "P5E_CPU0_P0_RX_BUF_DP<9>")
	)
	(segment
		(start 326.90308 -410.647134)
		(end 326.835516 -410.520134)
		(width 0.14224)
		(layer "In15.Cu")
		(net "P5E_CPU0_P0_RX_BUF_DP<9>")
	)
	(segment
		(start 314.616338 -401.520406)
		(end 314.616338 -401.674838)
		(width 0.14224)
		(layer "In15.Cu")
		(net "P5E_CPU0_P0_RX_BUF_DP<9>")
	)
	(segment
		(start 332.970886 -424.616118)
		(end 333.041244 -424.261788)
		(width 0.14224)
		(layer "In15.Cu")
		(net "P5E_CPU0_P0_RX_BUF_DP<9>")
	)
	(segment
		(start 324.815708 -410.013912)
		(end 324.290944 -409.583128)
		(width 0.14224)
		(layer "In15.Cu")
		(net "P5E_CPU0_P0_RX_BUF_DP<9>")
	)
	(segment
		(start 332.072996 -417.47186)
		(end 332.072996 -417.04514)
		(width 0.14224)
		(layer "In15.Cu")
		(net "P5E_CPU0_P0_RX_BUF_DP<9>")
	)
	(segment
		(start 333.359506 -422.3512)
		(end 333.42199 -421.929306)
		(width 0.14224)
		(layer "In15.Cu")
		(net "P5E_CPU0_P0_RX_BUF_DP<9>")
	)
	(segment
		(start 333.283052 -423.737278)
		(end 333.177388 -423.578782)
		(width 0.14224)
		(layer "In15.Cu")
		(net "P5E_CPU0_P0_RX_BUF_DP<9>")
	)
	(segment
		(start 331.73035 -414.31083)
		(end 331.468984 -414.049464)
		(width 0.14224)
		(layer "In15.Cu")
		(net "P5E_CPU0_P0_RX_BUF_DP<9>")
	)
	(segment
		(start 330.274422 -412.023814)
		(end 329.83551 -411.584902)
		(width 0.14224)
		(layer "In15.Cu")
		(net "P5E_CPU0_P0_RX_BUF_DP<9>")
	)
	(segment
		(start 333.42199 -421.929306)
		(end 333.467456 -421.468296)
		(width 0.14224)
		(layer "In15.Cu")
		(net "P5E_CPU0_P0_RX_BUF_DP<9>")
	)
	(segment
		(start 325.415656 -410.089604)
		(end 325.28891 -410.157422)
		(width 0.14224)
		(layer "In15.Cu")
		(net "P5E_CPU0_P0_RX_BUF_DP<9>")
	)
	(segment
		(start 332.109826 -419.104064)
		(end 331.935836 -418.684964)
		(width 0.14224)
		(layer "In15.Cu")
		(net "P5E_CPU0_P0_RX_BUF_DP<9>")
	)
	(segment
		(start 333.347568 -420.109396)
		(end 332.860142 -419.62197)
		(width 0.14224)
		(layer "In15.Cu")
		(net "P5E_CPU0_P0_RX_BUF_DP<9>")
	)
	(segment
		(start 314.15736 -404.610316)
		(end 314.15736 -404.183596)
		(width 0.14224)
		(layer "In15.Cu")
		(net "P5E_CPU0_P0_RX_BUF_DP<9>")
	)
	(segment
		(start 331.468984 -414.049464)
		(end 331.24521 -413.956754)
		(width 0.14224)
		(layer "In15.Cu")
		(net "P5E_CPU0_P0_RX_BUF_DP<9>")
	)
	(segment
		(start 331.935836 -416.90798)
		(end 331.935836 -416.48126)
		(width 0.14224)
		(layer "In15.Cu")
		(net "P5E_CPU0_P0_RX_BUF_DP<9>")
	)
	(segment
		(start 332.072996 -416.3441)
		(end 332.072996 -415.91738)
		(width 0.14224)
		(layer "In15.Cu")
		(net "P5E_CPU0_P0_RX_BUF_DP<9>")
	)
	(segment
		(start 314.95492 -405.266652)
		(end 314.652914 -404.964646)
		(width 0.14224)
		(layer "In15.Cu")
		(net "P5E_CPU0_P0_RX_BUF_DP<9>")
	)
	(segment
		(start 314.652914 -404.964646)
		(end 314.458858 -404.964646)
		(width 0.14224)
		(layer "In15.Cu")
		(net "P5E_CPU0_P0_RX_BUF_DP<9>")
	)
	(segment
		(start 331.935836 -417.60902)
		(end 332.072996 -417.47186)
		(width 0.14224)
		(layer "In15.Cu")
		(net "P5E_CPU0_P0_RX_BUF_DP<9>")
	)
	(segment
		(start 314.95492 -405.460708)
		(end 314.95492 -405.266652)
		(width 0.14224)
		(layer "In15.Cu")
		(net "P5E_CPU0_P0_RX_BUF_DP<9>")
	)
	(segment
		(start 333.499714 -438.341262)
		(end 333.1083 -438.341262)
		(width 0.14224)
		(layer "In15.Cu")
		(net "P5E_CPU0_P0_RX_BUF_DP<9>")
	)
	(segment
		(start 327.311258 -410.770832)
		(end 326.90308 -410.647134)
		(width 0.14224)
		(layer "In15.Cu")
		(net "P5E_CPU0_P0_RX_BUF_DP<9>")
	)
	(segment
		(start 333.467456 -421.468296)
		(end 333.467456 -420.398702)
		(width 0.14224)
		(layer "In15.Cu")
		(net "P5E_CPU0_P0_RX_BUF_DP<9>")
	)
	(segment
		(start 333.649828 -437.889904)
		(end 333.649828 -438.191148)
		(width 0.14224)
		(layer "In15.Cu")
		(net "P5E_CPU0_P0_RX_BUF_DP<9>")
	)
	(segment
		(start 333.473044 -422.504108)
		(end 333.359506 -422.3512)
		(width 0.14224)
		(layer "In15.Cu")
		(net "P5E_CPU0_P0_RX_BUF_DP<9>")
	)
	(segment
		(start 314.489338 -401.393406)
		(end 314.616338 -401.520406)
		(width 0.14224)
		(layer "In15.Cu")
		(net "P5E_CPU0_P0_RX_BUF_DP<9>")
	)
	(segment
		(start 331.935836 -418.684964)
		(end 331.935836 -417.60902)
		(width 0.14224)
		(layer "In15.Cu")
		(net "P5E_CPU0_P0_RX_BUF_DP<9>")
	)
	(segment
		(start 330.634086 -413.899604)
		(end 330.522326 -413.787844)
		(width 0.14224)
		(layer "In15.Cu")
		(net "P5E_CPU0_P0_RX_BUF_DP<9>")
	)
	(segment
		(start 333.041244 -424.261788)
		(end 333.19974 -424.15587)
		(width 0.14224)
		(layer "In15.Cu")
		(net "P5E_CPU0_P0_RX_BUF_DP<9>")
	)
	(segment
		(start 333.257144 -423.040048)
		(end 333.410306 -422.92651)
		(width 0.14224)
		(layer "In15.Cu")
		(net "P5E_CPU0_P0_RX_BUF_DP<9>")
	)
	(segment
		(start 316.507114 -407.012902)
		(end 315.75248 -406.258268)
		(width 0.14224)
		(layer "In15.Cu")
		(net "P5E_CPU0_P0_RX_BUF_DP<9>")
	)
	(segment
		(start 331.935836 -415.78022)
		(end 331.935836 -414.806892)
		(width 0.14224)
		(layer "In15.Cu")
		(net "P5E_CPU0_P0_RX_BUF_DP<9>")
	)
	(segment
		(start 333.19974 -424.15587)
		(end 333.283052 -423.737278)
		(width 0.14224)
		(layer "In15.Cu")
		(net "P5E_CPU0_P0_RX_BUF_DP<9>")
	)
	(segment
		(start 325.891906 -410.340302)
		(end 325.824088 -410.213556)
		(width 0.14224)
		(layer "In15.Cu")
		(net "P5E_CPU0_P0_RX_BUF_DP<9>")
	)
	(segment
		(start 333.649828 -438.191148)
		(end 333.499714 -438.341262)
		(width 0.14224)
		(layer "In15.Cu")
		(net "P5E_CPU0_P0_RX_BUF_DP<9>")
	)
	(segment
		(start 326.42683 -410.396182)
		(end 326.300084 -410.464)
		(width 0.14224)
		(layer "In15.Cu")
		(net "P5E_CPU0_P0_RX_BUF_DP<9>")
	)
	(segment
		(start 331.935836 -416.48126)
		(end 332.072996 -416.3441)
		(width 0.14224)
		(layer "In15.Cu")
		(net "P5E_CPU0_P0_RX_BUF_DP<9>")
	)
	(segment
		(start 331.24521 -413.956754)
		(end 330.772008 -413.956754)
		(width 0.14224)
		(layer "In15.Cu")
		(net "P5E_CPU0_P0_RX_BUF_DP<9>")
	)
	(segment
		(start 315.256418 -405.762206)
		(end 314.95492 -405.460708)
		(width 0.14224)
		(layer "In15.Cu")
		(net "P5E_CPU0_P0_RX_BUF_DP<9>")
	)
	(segment
		(start 332.072996 -417.04514)
		(end 331.935836 -416.90798)
		(width 0.14224)
		(layer "In15.Cu")
		(net "P5E_CPU0_P0_RX_BUF_DP<9>")
	)
	(segment
		(start 315.75248 -406.075388)
		(end 315.439298 -405.762206)
		(width 0.14224)
		(layer "In15.Cu")
		(net "P5E_CPU0_P0_RX_BUF_DP<9>")
	)
	(segment
		(start 314.29452 -403.619716)
		(end 314.15736 -403.482556)
		(width 0.14224)
		(layer "In15.Cu")
		(net "P5E_CPU0_P0_RX_BUF_DP<9>")
	)
	(segment
		(start 325.824088 -410.213556)
		(end 325.415656 -410.089604)
		(width 0.14224)
		(layer "In15.Cu")
		(net "P5E_CPU0_P0_RX_BUF_DP<9>")
	)
	(segment
		(start 332.970886 -438.203848)
		(end 332.970886 -424.616118)
		(width 0.14224)
		(layer "In15.Cu")
		(net "P5E_CPU0_P0_RX_BUF_DP<9>")
	)
	(segment
		(start 327.914508 -410.954728)
		(end 327.914254 -410.953966)
		(width 0.14224)
		(layer "In15.Cu")
		(net "P5E_CPU0_P0_RX_BUF_DP<9>")
	)
	(segment
		(start 331.935836 -414.806892)
		(end 331.73035 -414.31083)
		(width 0.14224)
		(layer "In15.Cu")
		(net "P5E_CPU0_P0_RX_BUF_DP<9>")
	)
	(segment
		(start 327.438004 -410.703014)
		(end 327.311258 -410.770832)
		(width 0.14224)
		(layer "In15.Cu")
		(net "P5E_CPU0_P0_RX_BUF_DP<9>")
	)
	(segment
		(start 324.290944 -409.583128)
		(end 317.211964 -407.435304)
		(width 0.14224)
		(layer "In15.Cu")
		(net "P5E_CPU0_P0_RX_BUF_DP<9>")
	)
	(segment
		(start 326.835516 -410.520134)
		(end 326.42683 -410.396182)
		(width 0.14224)
		(layer "In15.Cu")
		(net "P5E_CPU0_P0_RX_BUF_DP<9>")
	)
	(segment
		(start 315.439298 -405.762206)
		(end 315.256418 -405.762206)
		(width 0.14224)
		(layer "In15.Cu")
		(net "P5E_CPU0_P0_RX_BUF_DP<9>")
	)
	(segment
		(start 325.28891 -410.157422)
		(end 324.815708 -410.013912)
		(width 0.14224)
		(layer "In15.Cu")
		(net "P5E_CPU0_P0_RX_BUF_DP<9>")
	)
	(segment
		(start 333.1083 -438.341262)
		(end 332.970886 -438.203848)
		(width 0.14224)
		(layer "In15.Cu")
		(net "P5E_CPU0_P0_RX_BUF_DP<9>")
	)
	(arc
		(start 332.463394 -419.457378)
		(mid 332.251474 -419.315876)
		(end 332.109826 -419.104064)
		(width 0.14224)
		(layer "In15.Cu")
		(net "P5E_CPU0_P0_RX_BUF_DP<9>")
	)
	(arc
		(start 330.522326 -413.787844)
		(mid 330.434906 -413.657105)
		(end 330.404216 -413.502856)
		(width 0.14224)
		(layer "In15.Cu")
		(net "P5E_CPU0_P0_RX_BUF_DP<9>")
	)
	(arc
		(start 329.83551 -411.584902)
		(mid 329.761516 -411.527205)
		(end 329.675744 -411.489144)
		(width 0.14224)
		(layer "In15.Cu")
		(net "P5E_CPU0_P0_RX_BUF_DP<9>")
	)
	(arc
		(start 333.467456 -420.398702)
		(mid 333.436293 -420.242124)
		(end 333.347568 -420.109396)
		(width 0.14224)
		(layer "In15.Cu")
		(net "P5E_CPU0_P0_RX_BUF_DP<9>")
	)
	(arc
		(start 330.772008 -413.956754)
		(mid 330.697357 -413.941905)
		(end 330.634086 -413.899604)
		(width 0.14224)
		(layer "In15.Cu")
		(net "P5E_CPU0_P0_RX_BUF_DP<9>")
	)
	(arc
		(start 314.194698 -404.700486)
		(mid 314.167055 -404.659116)
		(end 314.15736 -404.610316)
		(width 0.14224)
		(layer "In15.Cu")
		(net "P5E_CPU0_P0_RX_BUF_DP<9>")
	)
	(arc
		(start 317.211964 -407.435304)
		(mid 316.833484 -407.267578)
		(end 316.507114 -407.012902)
		(width 0.14224)
		(layer "In15.Cu")
		(net "P5E_CPU0_P0_RX_BUF_DP<9>")
	)
	(arc
		(start 330.404216 -412.337504)
		(mid 330.370526 -412.167751)
		(end 330.274422 -412.023814)
		(width 0.14224)
		(layer "In15.Cu")
		(net "P5E_CPU0_P0_RX_BUF_DP<9>")
	)
	(segment
		(start 312.713624 -401.105878)
		(end 312.966862 -401.359116)
		(width 0.1016)
		(layer "F.Cu")
		(net "P5E_CPU0_P0_RX_BUF_DP<8>")
	)
	(segment
		(start 312.713624 -399.959322)
		(end 312.713624 -401.105878)
		(width 0.1016)
		(layer "F.Cu")
		(net "P5E_CPU0_P0_RX_BUF_DP<8>")
	)
	(segment
		(start 313.416442 -401.498054)
		(end 313.416442 -401.674838)
		(width 0.1016)
		(layer "F.Cu")
		(net "P5E_CPU0_P0_RX_BUF_DP<8>")
	)
	(segment
		(start 312.717688 -399.663158)
		(end 312.80227 -399.74774)
		(width 0.1016)
		(layer "F.Cu")
		(net "P5E_CPU0_P0_RX_BUF_DP<8>")
	)
	(segment
		(start 312.966862 -401.359116)
		(end 313.277504 -401.359116)
		(width 0.1016)
		(layer "F.Cu")
		(net "P5E_CPU0_P0_RX_BUF_DP<8>")
	)
	(segment
		(start 312.80227 -399.870676)
		(end 312.713624 -399.959322)
		(width 0.1016)
		(layer "F.Cu")
		(net "P5E_CPU0_P0_RX_BUF_DP<8>")
	)
	(segment
		(start 313.277504 -401.359116)
		(end 313.416442 -401.498054)
		(width 0.1016)
		(layer "F.Cu")
		(net "P5E_CPU0_P0_RX_BUF_DP<8>")
	)
	(segment
		(start 312.80227 -399.74774)
		(end 312.80227 -399.870676)
		(width 0.1016)
		(layer "F.Cu")
		(net "P5E_CPU0_P0_RX_BUF_DP<8>")
	)
	(segment
		(start 326.706484 -411.565344)
		(end 324.36689 -410.855922)
		(width 0.14224)
		(layer "In15.Cu")
		(net "P5E_CPU0_P0_RX_BUF_DP<8>")
	)
	(segment
		(start 315.350144 -407.50109)
		(end 315.350144 -407.307288)
		(width 0.14224)
		(layer "In15.Cu")
		(net "P5E_CPU0_P0_RX_BUF_DP<8>")
	)
	(segment
		(start 330.5302 -421.872918)
		(end 330.5302 -421.446198)
		(width 0.14224)
		(layer "In15.Cu")
		(net "P5E_CPU0_P0_RX_BUF_DP<8>")
	)
	(segment
		(start 330.5302 -421.446198)
		(end 330.404216 -421.320214)
		(width 0.14224)
		(layer "In15.Cu")
		(net "P5E_CPU0_P0_RX_BUF_DP<8>")
	)
	(segment
		(start 313.416442 -401.511008)
		(end 313.416442 -401.674838)
		(width 0.14224)
		(layer "In15.Cu")
		(net "P5E_CPU0_P0_RX_BUF_DP<8>")
	)
	(segment
		(start 330.487274 -422.772586)
		(end 330.404216 -422.354248)
		(width 0.14224)
		(layer "In15.Cu")
		(net "P5E_CPU0_P0_RX_BUF_DP<8>")
	)
	(segment
		(start 313.094624 -403.417024)
		(end 313.094624 -402.990304)
		(width 0.14224)
		(layer "In15.Cu")
		(net "P5E_CPU0_P0_RX_BUF_DP<8>")
	)
	(segment
		(start 312.957464 -401.511008)
		(end 313.09691 -401.371562)
		(width 0.14224)
		(layer "In15.Cu")
		(net "P5E_CPU0_P0_RX_BUF_DP<8>")
	)
	(segment
		(start 330.404216 -421.320214)
		(end 330.404216 -420.408354)
		(width 0.14224)
		(layer "In15.Cu")
		(net "P5E_CPU0_P0_RX_BUF_DP<8>")
	)
	(segment
		(start 313.858148 -406.009348)
		(end 312.994802 -405.146002)
		(width 0.14224)
		(layer "In15.Cu")
		(net "P5E_CPU0_P0_RX_BUF_DP<8>")
	)
	(segment
		(start 330.707492 -423.878756)
		(end 330.624434 -423.460418)
		(width 0.14224)
		(layer "In15.Cu")
		(net "P5E_CPU0_P0_RX_BUF_DP<8>")
	)
	(segment
		(start 331.649832 -437.19115)
		(end 331.503782 -437.3372)
		(width 0.14224)
		(layer "In15.Cu")
		(net "P5E_CPU0_P0_RX_BUF_DP<8>")
	)
	(segment
		(start 330.869036 -423.986706)
		(end 330.707492 -423.878756)
		(width 0.14224)
		(layer "In15.Cu")
		(net "P5E_CPU0_P0_RX_BUF_DP<8>")
	)
	(segment
		(start 329.07478 -419.151054)
		(end 328.872596 -418.663882)
		(width 0.14224)
		(layer "In15.Cu")
		(net "P5E_CPU0_P0_RX_BUF_DP<8>")
	)
	(segment
		(start 313.094624 -404.544784)
		(end 313.094624 -404.118064)
		(width 0.14224)
		(layer "In15.Cu")
		(net "P5E_CPU0_P0_RX_BUF_DP<8>")
	)
	(segment
		(start 327.41362 -413.742378)
		(end 327.340976 -413.567118)
		(width 0.14224)
		(layer "In15.Cu")
		(net "P5E_CPU0_P0_RX_BUF_DP<8>")
	)
	(segment
		(start 313.094624 -404.118064)
		(end 312.957464 -403.980904)
		(width 0.14224)
		(layer "In15.Cu")
		(net "P5E_CPU0_P0_RX_BUF_DP<8>")
	)
	(segment
		(start 330.983082 -437.2102)
		(end 330.983082 -425.264072)
		(width 0.14224)
		(layer "In15.Cu")
		(net "P5E_CPU0_P0_RX_BUF_DP<8>")
	)
	(segment
		(start 313.094624 -402.990304)
		(end 312.957464 -402.853144)
		(width 0.14224)
		(layer "In15.Cu")
		(net "P5E_CPU0_P0_RX_BUF_DP<8>")
	)
	(segment
		(start 315.350144 -407.307288)
		(end 315.048138 -407.005282)
		(width 0.14224)
		(layer "In15.Cu")
		(net "P5E_CPU0_P0_RX_BUF_DP<8>")
	)
	(segment
		(start 328.182224 -413.956754)
		(end 327.669906 -413.956754)
		(width 0.14224)
		(layer "In15.Cu")
		(net "P5E_CPU0_P0_RX_BUF_DP<8>")
	)
	(segment
		(start 328.354436 -414.028128)
		(end 328.182224 -413.956754)
		(width 0.14224)
		(layer "In15.Cu")
		(net "P5E_CPU0_P0_RX_BUF_DP<8>")
	)
	(segment
		(start 313.276996 -401.371562)
		(end 313.416442 -401.511008)
		(width 0.14224)
		(layer "In15.Cu")
		(net "P5E_CPU0_P0_RX_BUF_DP<8>")
	)
	(segment
		(start 330.983082 -425.264072)
		(end 330.844398 -424.566588)
		(width 0.14224)
		(layer "In15.Cu")
		(net "P5E_CPU0_P0_RX_BUF_DP<8>")
	)
	(segment
		(start 315.048138 -407.005282)
		(end 314.854082 -407.005282)
		(width 0.14224)
		(layer "In15.Cu")
		(net "P5E_CPU0_P0_RX_BUF_DP<8>")
	)
	(segment
		(start 315.970158 -408.050238)
		(end 315.793628 -407.944574)
		(width 0.14224)
		(layer "In15.Cu")
		(net "P5E_CPU0_P0_RX_BUF_DP<8>")
	)
	(segment
		(start 331.503782 -437.3372)
		(end 331.110082 -437.3372)
		(width 0.14224)
		(layer "In15.Cu")
		(net "P5E_CPU0_P0_RX_BUF_DP<8>")
	)
	(segment
		(start 328.872596 -416.154616)
		(end 328.872596 -414.806892)
		(width 0.14224)
		(layer "In15.Cu")
		(net "P5E_CPU0_P0_RX_BUF_DP<8>")
	)
	(segment
		(start 323.86778 -410.44622)
		(end 315.970158 -408.050238)
		(width 0.14224)
		(layer "In15.Cu")
		(net "P5E_CPU0_P0_RX_BUF_DP<8>")
	)
	(segment
		(start 328.872596 -418.663882)
		(end 328.872596 -417.983416)
		(width 0.14224)
		(layer "In15.Cu")
		(net "P5E_CPU0_P0_RX_BUF_DP<8>")
	)
	(segment
		(start 330.404216 -421.998902)
		(end 330.5302 -421.872918)
		(width 0.14224)
		(layer "In15.Cu")
		(net "P5E_CPU0_P0_RX_BUF_DP<8>")
	)
	(segment
		(start 312.957464 -403.980904)
		(end 312.957464 -403.554184)
		(width 0.14224)
		(layer "In15.Cu")
		(net "P5E_CPU0_P0_RX_BUF_DP<8>")
	)
	(segment
		(start 328.872596 -417.282376)
		(end 328.872596 -416.855656)
		(width 0.14224)
		(layer "In15.Cu")
		(net "P5E_CPU0_P0_RX_BUF_DP<8>")
	)
	(segment
		(start 312.957464 -403.554184)
		(end 313.094624 -403.417024)
		(width 0.14224)
		(layer "In15.Cu")
		(net "P5E_CPU0_P0_RX_BUF_DP<8>")
	)
	(segment
		(start 312.957464 -405.055832)
		(end 312.957464 -404.681944)
		(width 0.14224)
		(layer "In15.Cu")
		(net "P5E_CPU0_P0_RX_BUF_DP<8>")
	)
	(segment
		(start 314.353956 -406.311354)
		(end 314.05195 -406.009348)
		(width 0.14224)
		(layer "In15.Cu")
		(net "P5E_CPU0_P0_RX_BUF_DP<8>")
	)
	(segment
		(start 331.649832 -436.889906)
		(end 331.649832 -437.19115)
		(width 0.14224)
		(layer "In15.Cu")
		(net "P5E_CPU0_P0_RX_BUF_DP<8>")
	)
	(segment
		(start 329.009756 -416.291776)
		(end 328.872596 -416.154616)
		(width 0.14224)
		(layer "In15.Cu")
		(net "P5E_CPU0_P0_RX_BUF_DP<8>")
	)
	(segment
		(start 327.598278 -413.927036)
		(end 327.41362 -413.742378)
		(width 0.14224)
		(layer "In15.Cu")
		(net "P5E_CPU0_P0_RX_BUF_DP<8>")
	)
	(segment
		(start 328.688192 -414.361884)
		(end 328.354436 -414.028128)
		(width 0.14224)
		(layer "In15.Cu")
		(net "P5E_CPU0_P0_RX_BUF_DP<8>")
	)
	(segment
		(start 327.221088 -412.00324)
		(end 326.898254 -411.680406)
		(width 0.14224)
		(layer "In15.Cu")
		(net "P5E_CPU0_P0_RX_BUF_DP<8>")
	)
	(segment
		(start 329.009756 -416.718496)
		(end 329.009756 -416.291776)
		(width 0.14224)
		(layer "In15.Cu")
		(net "P5E_CPU0_P0_RX_BUF_DP<8>")
	)
	(segment
		(start 315.793628 -407.944574)
		(end 315.350144 -407.50109)
		(width 0.14224)
		(layer "In15.Cu")
		(net "P5E_CPU0_P0_RX_BUF_DP<8>")
	)
	(segment
		(start 329.009756 -417.846256)
		(end 329.009756 -417.419536)
		(width 0.14224)
		(layer "In15.Cu")
		(net "P5E_CPU0_P0_RX_BUF_DP<8>")
	)
	(segment
		(start 330.73213 -423.299128)
		(end 330.648818 -422.880282)
		(width 0.14224)
		(layer "In15.Cu")
		(net "P5E_CPU0_P0_RX_BUF_DP<8>")
	)
	(segment
		(start 328.872596 -417.983416)
		(end 329.009756 -417.846256)
		(width 0.14224)
		(layer "In15.Cu")
		(net "P5E_CPU0_P0_RX_BUF_DP<8>")
	)
	(segment
		(start 327.340976 -413.567118)
		(end 327.340976 -412.292546)
		(width 0.14224)
		(layer "In15.Cu")
		(net "P5E_CPU0_P0_RX_BUF_DP<8>")
	)
	(segment
		(start 330.404216 -422.354248)
		(end 330.404216 -421.998902)
		(width 0.14224)
		(layer "In15.Cu")
		(net "P5E_CPU0_P0_RX_BUF_DP<8>")
	)
	(segment
		(start 330.624434 -423.460418)
		(end 330.73213 -423.299128)
		(width 0.14224)
		(layer "In15.Cu")
		(net "P5E_CPU0_P0_RX_BUF_DP<8>")
	)
	(segment
		(start 328.872596 -414.806892)
		(end 328.688192 -414.361884)
		(width 0.14224)
		(layer "In15.Cu")
		(net "P5E_CPU0_P0_RX_BUF_DP<8>")
	)
	(segment
		(start 326.898254 -411.680406)
		(end 326.706484 -411.565344)
		(width 0.14224)
		(layer "In15.Cu")
		(net "P5E_CPU0_P0_RX_BUF_DP<8>")
	)
	(segment
		(start 314.05195 -406.009348)
		(end 313.858148 -406.009348)
		(width 0.14224)
		(layer "In15.Cu")
		(net "P5E_CPU0_P0_RX_BUF_DP<8>")
	)
	(segment
		(start 330.648818 -422.880282)
		(end 330.487274 -422.772586)
		(width 0.14224)
		(layer "In15.Cu")
		(net "P5E_CPU0_P0_RX_BUF_DP<8>")
	)
	(segment
		(start 312.957464 -402.853144)
		(end 312.957464 -401.511008)
		(width 0.14224)
		(layer "In15.Cu")
		(net "P5E_CPU0_P0_RX_BUF_DP<8>")
	)
	(segment
		(start 330.284328 -420.119048)
		(end 329.780392 -419.615112)
		(width 0.14224)
		(layer "In15.Cu")
		(net "P5E_CPU0_P0_RX_BUF_DP<8>")
	)
	(segment
		(start 330.952348 -424.405298)
		(end 330.869036 -423.986706)
		(width 0.14224)
		(layer "In15.Cu")
		(net "P5E_CPU0_P0_RX_BUF_DP<8>")
	)
	(segment
		(start 313.09691 -401.371562)
		(end 313.276996 -401.371562)
		(width 0.14224)
		(layer "In15.Cu")
		(net "P5E_CPU0_P0_RX_BUF_DP<8>")
	)
	(segment
		(start 329.780392 -419.615112)
		(end 329.367896 -419.44417)
		(width 0.14224)
		(layer "In15.Cu")
		(net "P5E_CPU0_P0_RX_BUF_DP<8>")
	)
	(segment
		(start 312.957464 -404.681944)
		(end 313.094624 -404.544784)
		(width 0.14224)
		(layer "In15.Cu")
		(net "P5E_CPU0_P0_RX_BUF_DP<8>")
	)
	(segment
		(start 329.009756 -417.419536)
		(end 328.872596 -417.282376)
		(width 0.14224)
		(layer "In15.Cu")
		(net "P5E_CPU0_P0_RX_BUF_DP<8>")
	)
	(segment
		(start 328.872596 -416.855656)
		(end 329.009756 -416.718496)
		(width 0.14224)
		(layer "In15.Cu")
		(net "P5E_CPU0_P0_RX_BUF_DP<8>")
	)
	(segment
		(start 330.844398 -424.566588)
		(end 330.952348 -424.405298)
		(width 0.14224)
		(layer "In15.Cu")
		(net "P5E_CPU0_P0_RX_BUF_DP<8>")
	)
	(segment
		(start 314.854082 -407.005282)
		(end 314.353956 -406.505156)
		(width 0.14224)
		(layer "In15.Cu")
		(net "P5E_CPU0_P0_RX_BUF_DP<8>")
	)
	(segment
		(start 331.110082 -437.3372)
		(end 330.983082 -437.2102)
		(width 0.14224)
		(layer "In15.Cu")
		(net "P5E_CPU0_P0_RX_BUF_DP<8>")
	)
	(segment
		(start 314.353956 -406.505156)
		(end 314.353956 -406.311354)
		(width 0.14224)
		(layer "In15.Cu")
		(net "P5E_CPU0_P0_RX_BUF_DP<8>")
	)
	(segment
		(start 327.669906 -413.956754)
		(end 327.598278 -413.927036)
		(width 0.14224)
		(layer "In15.Cu")
		(net "P5E_CPU0_P0_RX_BUF_DP<8>")
	)
	(segment
		(start 324.36689 -410.855922)
		(end 323.86778 -410.44622)
		(width 0.14224)
		(layer "In15.Cu")
		(net "P5E_CPU0_P0_RX_BUF_DP<8>")
	)
	(arc
		(start 329.367896 -419.44417)
		(mid 329.192205 -419.326745)
		(end 329.07478 -419.151054)
		(width 0.14224)
		(layer "In15.Cu")
		(net "P5E_CPU0_P0_RX_BUF_DP<8>")
	)
	(arc
		(start 312.994802 -405.146002)
		(mid 312.967159 -405.104632)
		(end 312.957464 -405.055832)
		(width 0.14224)
		(layer "In15.Cu")
		(net "P5E_CPU0_P0_RX_BUF_DP<8>")
	)
	(arc
		(start 330.404216 -420.408354)
		(mid 330.373053 -420.251776)
		(end 330.284328 -420.119048)
		(width 0.14224)
		(layer "In15.Cu")
		(net "P5E_CPU0_P0_RX_BUF_DP<8>")
	)
	(arc
		(start 327.340976 -412.292546)
		(mid 327.309813 -412.135968)
		(end 327.221088 -412.00324)
		(width 0.14224)
		(layer "In15.Cu")
		(net "P5E_CPU0_P0_RX_BUF_DP<8>")
	)
	(segment
		(start 311.513728 -399.959322)
		(end 311.513728 -401.105878)
		(width 0.1016)
		(layer "F.Cu")
		(net "P5E_CPU0_P0_RX_BUF_DP<7>")
	)
	(segment
		(start 311.602374 -399.870676)
		(end 311.513728 -399.959322)
		(width 0.1016)
		(layer "F.Cu")
		(net "P5E_CPU0_P0_RX_BUF_DP<7>")
	)
	(segment
		(start 312.077608 -401.359116)
		(end 312.216292 -401.4978)
		(width 0.1016)
		(layer "F.Cu")
		(net "P5E_CPU0_P0_RX_BUF_DP<7>")
	)
	(segment
		(start 312.216292 -401.4978)
		(end 312.216292 -401.674838)
		(width 0.1016)
		(layer "F.Cu")
		(net "P5E_CPU0_P0_RX_BUF_DP<7>")
	)
	(segment
		(start 311.602374 -399.74774)
		(end 311.602374 -399.870676)
		(width 0.1016)
		(layer "F.Cu")
		(net "P5E_CPU0_P0_RX_BUF_DP<7>")
	)
	(segment
		(start 311.517792 -399.663158)
		(end 311.602374 -399.74774)
		(width 0.1016)
		(layer "F.Cu")
		(net "P5E_CPU0_P0_RX_BUF_DP<7>")
	)
	(segment
		(start 311.766966 -401.359116)
		(end 312.077608 -401.359116)
		(width 0.1016)
		(layer "F.Cu")
		(net "P5E_CPU0_P0_RX_BUF_DP<7>")
	)
	(segment
		(start 311.513728 -401.105878)
		(end 311.766966 -401.359116)
		(width 0.1016)
		(layer "F.Cu")
		(net "P5E_CPU0_P0_RX_BUF_DP<7>")
	)
	(segment
		(start 322.503546 -411.22727)
		(end 322.503546 -411.227016)
		(width 0.14224)
		(layer "In15.Cu")
		(net "P5E_CPU0_P0_RX_BUF_DP<7>")
	)
	(segment
		(start 322.503546 -411.227016)
		(end 322.897754 -411.390338)
		(width 0.14224)
		(layer "In15.Cu")
		(net "P5E_CPU0_P0_RX_BUF_DP<7>")
	)
	(segment
		(start 325.809356 -414.806892)
		(end 325.809356 -416.029902)
		(width 0.14224)
		(layer "In15.Cu")
		(net "P5E_CPU0_P0_RX_BUF_DP<7>")
	)
	(segment
		(start 325.809356 -417.858702)
		(end 325.809356 -418.545772)
		(width 0.14224)
		(layer "In15.Cu")
		(net "P5E_CPU0_P0_RX_BUF_DP<7>")
	)
	(segment
		(start 325.291196 -414.028128)
		(end 325.624952 -414.361884)
		(width 0.14224)
		(layer "In15.Cu")
		(net "P5E_CPU0_P0_RX_BUF_DP<7>")
	)
	(segment
		(start 311.89676 -401.371562)
		(end 311.757314 -401.511008)
		(width 0.14224)
		(layer "In15.Cu")
		(net "P5E_CPU0_P0_RX_BUF_DP<7>")
	)
	(segment
		(start 314.230004 -407.941272)
		(end 314.842652 -408.55392)
		(width 0.14224)
		(layer "In15.Cu")
		(net "P5E_CPU0_P0_RX_BUF_DP<7>")
	)
	(segment
		(start 311.757314 -401.511008)
		(end 311.757314 -402.832824)
		(width 0.14224)
		(layer "In15.Cu")
		(net "P5E_CPU0_P0_RX_BUF_DP<7>")
	)
	(segment
		(start 324.207886 -412.154878)
		(end 324.277736 -412.38424)
		(width 0.14224)
		(layer "In15.Cu")
		(net "P5E_CPU0_P0_RX_BUF_DP<7>")
	)
	(segment
		(start 314.230004 -407.74747)
		(end 314.230004 -407.941272)
		(width 0.14224)
		(layer "In15.Cu")
		(net "P5E_CPU0_P0_RX_BUF_DP<7>")
	)
	(segment
		(start 327.710546 -423.151046)
		(end 327.604882 -423.309542)
		(width 0.14224)
		(layer "In15.Cu")
		(net "P5E_CPU0_P0_RX_BUF_DP<7>")
	)
	(segment
		(start 312.856626 -406.56764)
		(end 313.050428 -406.56764)
		(width 0.14224)
		(layer "In15.Cu")
		(net "P5E_CPU0_P0_RX_BUF_DP<7>")
	)
	(segment
		(start 325.821548 -418.607494)
		(end 326.01281 -419.06825)
		(width 0.14224)
		(layer "In15.Cu")
		(net "P5E_CPU0_P0_RX_BUF_DP<7>")
	)
	(segment
		(start 311.894474 -404.097744)
		(end 311.894474 -404.524464)
		(width 0.14224)
		(layer "In15.Cu")
		(net "P5E_CPU0_P0_RX_BUF_DP<7>")
	)
	(segment
		(start 312.216292 -401.511008)
		(end 312.076846 -401.371562)
		(width 0.14224)
		(layer "In15.Cu")
		(net "P5E_CPU0_P0_RX_BUF_DP<7>")
	)
	(segment
		(start 315.307726 -408.832558)
		(end 320.590164 -410.435298)
		(width 0.14224)
		(layer "In15.Cu")
		(net "P5E_CPU0_P0_RX_BUF_DP<7>")
	)
	(segment
		(start 325.946516 -417.721542)
		(end 325.809356 -417.858702)
		(width 0.14224)
		(layer "In15.Cu")
		(net "P5E_CPU0_P0_RX_BUF_DP<7>")
	)
	(segment
		(start 322.429378 -411.047946)
		(end 322.503546 -411.22727)
		(width 0.14224)
		(layer "In15.Cu")
		(net "P5E_CPU0_P0_RX_BUF_DP<7>")
	)
	(segment
		(start 324.606666 -413.956754)
		(end 325.118984 -413.956754)
		(width 0.14224)
		(layer "In15.Cu")
		(net "P5E_CPU0_P0_RX_BUF_DP<7>")
	)
	(segment
		(start 323.93636 -411.748732)
		(end 324.207886 -412.154878)
		(width 0.14224)
		(layer "In15.Cu")
		(net "P5E_CPU0_P0_RX_BUF_DP<7>")
	)
	(segment
		(start 326.429624 -419.495986)
		(end 326.561704 -419.550596)
		(width 0.14224)
		(layer "In15.Cu")
		(net "P5E_CPU0_P0_RX_BUF_DP<7>")
	)
	(segment
		(start 324.35038 -413.742378)
		(end 324.535038 -413.927036)
		(width 0.14224)
		(layer "In15.Cu")
		(net "P5E_CPU0_P0_RX_BUF_DP<7>")
	)
	(segment
		(start 327.340976 -420.433754)
		(end 327.340976 -421.983154)
		(width 0.14224)
		(layer "In15.Cu")
		(net "P5E_CPU0_P0_RX_BUF_DP<7>")
	)
	(segment
		(start 311.757314 -404.661624)
		(end 311.757314 -405.41575)
		(width 0.14224)
		(layer "In15.Cu")
		(net "P5E_CPU0_P0_RX_BUF_DP<7>")
	)
	(segment
		(start 311.894474 -403.396704)
		(end 311.757314 -403.533864)
		(width 0.14224)
		(layer "In15.Cu")
		(net "P5E_CPU0_P0_RX_BUF_DP<7>")
	)
	(segment
		(start 324.535038 -413.927036)
		(end 324.606666 -413.956754)
		(width 0.14224)
		(layer "In15.Cu")
		(net "P5E_CPU0_P0_RX_BUF_DP<7>")
	)
	(segment
		(start 313.352434 -406.869646)
		(end 313.352434 -407.063702)
		(width 0.14224)
		(layer "In15.Cu")
		(net "P5E_CPU0_P0_RX_BUF_DP<7>")
	)
	(segment
		(start 325.809356 -416.029902)
		(end 325.946516 -416.167062)
		(width 0.14224)
		(layer "In15.Cu")
		(net "P5E_CPU0_P0_RX_BUF_DP<7>")
	)
	(segment
		(start 327.970896 -425.151042)
		(end 327.970896 -438.195212)
		(width 0.14224)
		(layer "In15.Cu")
		(net "P5E_CPU0_P0_RX_BUF_DP<7>")
	)
	(segment
		(start 325.809356 -416.730942)
		(end 325.809356 -417.157662)
		(width 0.14224)
		(layer "In15.Cu")
		(net "P5E_CPU0_P0_RX_BUF_DP<7>")
	)
	(segment
		(start 327.970896 -438.195212)
		(end 328.113136 -438.337452)
		(width 0.14224)
		(layer "In15.Cu")
		(net "P5E_CPU0_P0_RX_BUF_DP<7>")
	)
	(segment
		(start 311.894474 -404.524464)
		(end 311.757314 -404.661624)
		(width 0.14224)
		(layer "In15.Cu")
		(net "P5E_CPU0_P0_RX_BUF_DP<7>")
	)
	(segment
		(start 327.340976 -421.983154)
		(end 327.468992 -422.62679)
		(width 0.14224)
		(layer "In15.Cu")
		(net "P5E_CPU0_P0_RX_BUF_DP<7>")
	)
	(segment
		(start 311.757314 -403.533864)
		(end 311.757314 -403.960584)
		(width 0.14224)
		(layer "In15.Cu")
		(net "P5E_CPU0_P0_RX_BUF_DP<7>")
	)
	(segment
		(start 326.7583 -419.68166)
		(end 327.221088 -420.144448)
		(width 0.14224)
		(layer "In15.Cu")
		(net "P5E_CPU0_P0_RX_BUF_DP<7>")
	)
	(segment
		(start 325.946516 -417.294822)
		(end 325.946516 -417.721542)
		(width 0.14224)
		(layer "In15.Cu")
		(net "P5E_CPU0_P0_RX_BUF_DP<7>")
	)
	(segment
		(start 327.627488 -422.732454)
		(end 327.710546 -423.151046)
		(width 0.14224)
		(layer "In15.Cu")
		(net "P5E_CPU0_P0_RX_BUF_DP<7>")
	)
	(segment
		(start 321.855592 -410.959046)
		(end 322.034662 -410.884624)
		(width 0.14224)
		(layer "In15.Cu")
		(net "P5E_CPU0_P0_RX_BUF_DP<7>")
	)
	(segment
		(start 311.757314 -402.832824)
		(end 311.894474 -402.969984)
		(width 0.14224)
		(layer "In15.Cu")
		(net "P5E_CPU0_P0_RX_BUF_DP<7>")
	)
	(segment
		(start 311.894474 -402.969984)
		(end 311.894474 -403.396704)
		(width 0.14224)
		(layer "In15.Cu")
		(net "P5E_CPU0_P0_RX_BUF_DP<7>")
	)
	(segment
		(start 322.034662 -410.884624)
		(end 322.429378 -411.047946)
		(width 0.14224)
		(layer "In15.Cu")
		(net "P5E_CPU0_P0_RX_BUF_DP<7>")
	)
	(segment
		(start 312.554874 -406.072086)
		(end 312.554874 -406.266142)
		(width 0.14224)
		(layer "In15.Cu")
		(net "P5E_CPU0_P0_RX_BUF_DP<7>")
	)
	(segment
		(start 323.221096 -411.390338)
		(end 323.782436 -411.622494)
		(width 0.14224)
		(layer "In15.Cu")
		(net "P5E_CPU0_P0_RX_BUF_DP<7>")
	)
	(segment
		(start 313.734196 -407.445464)
		(end 313.927998 -407.445464)
		(width 0.14224)
		(layer "In15.Cu")
		(net "P5E_CPU0_P0_RX_BUF_DP<7>")
	)
	(segment
		(start 312.252868 -405.77008)
		(end 312.554874 -406.072086)
		(width 0.14224)
		(layer "In15.Cu")
		(net "P5E_CPU0_P0_RX_BUF_DP<7>")
	)
	(segment
		(start 312.554874 -406.266142)
		(end 312.856626 -406.56764)
		(width 0.14224)
		(layer "In15.Cu")
		(net "P5E_CPU0_P0_RX_BUF_DP<7>")
	)
	(segment
		(start 324.277736 -413.567118)
		(end 324.35038 -413.742378)
		(width 0.14224)
		(layer "In15.Cu")
		(net "P5E_CPU0_P0_RX_BUF_DP<7>")
	)
	(segment
		(start 327.604882 -423.309542)
		(end 327.970896 -425.151042)
		(width 0.14224)
		(layer "In15.Cu")
		(net "P5E_CPU0_P0_RX_BUF_DP<7>")
	)
	(segment
		(start 323.782436 -411.622494)
		(end 323.93636 -411.748732)
		(width 0.14224)
		(layer "In15.Cu")
		(net "P5E_CPU0_P0_RX_BUF_DP<7>")
	)
	(segment
		(start 312.076846 -401.371562)
		(end 311.89676 -401.371562)
		(width 0.14224)
		(layer "In15.Cu")
		(net "P5E_CPU0_P0_RX_BUF_DP<7>")
	)
	(segment
		(start 312.216292 -401.674838)
		(end 312.216292 -401.511008)
		(width 0.14224)
		(layer "In15.Cu")
		(net "P5E_CPU0_P0_RX_BUF_DP<7>")
	)
	(segment
		(start 320.590164 -410.435298)
		(end 321.855592 -410.959046)
		(width 0.14224)
		(layer "In15.Cu")
		(net "P5E_CPU0_P0_RX_BUF_DP<7>")
	)
	(segment
		(start 328.50328 -438.337452)
		(end 328.649584 -438.191148)
		(width 0.14224)
		(layer "In15.Cu")
		(net "P5E_CPU0_P0_RX_BUF_DP<7>")
	)
	(segment
		(start 322.897754 -411.390338)
		(end 323.221096 -411.390338)
		(width 0.14224)
		(layer "In15.Cu")
		(net "P5E_CPU0_P0_RX_BUF_DP<7>")
	)
	(segment
		(start 328.113136 -438.337452)
		(end 328.50328 -438.337452)
		(width 0.14224)
		(layer "In15.Cu")
		(net "P5E_CPU0_P0_RX_BUF_DP<7>")
	)
	(segment
		(start 325.118984 -413.956754)
		(end 325.291196 -414.028128)
		(width 0.14224)
		(layer "In15.Cu")
		(net "P5E_CPU0_P0_RX_BUF_DP<7>")
	)
	(segment
		(start 325.809356 -417.157662)
		(end 325.946516 -417.294822)
		(width 0.14224)
		(layer "In15.Cu")
		(net "P5E_CPU0_P0_RX_BUF_DP<7>")
	)
	(segment
		(start 325.946516 -416.593782)
		(end 325.809356 -416.730942)
		(width 0.14224)
		(layer "In15.Cu")
		(net "P5E_CPU0_P0_RX_BUF_DP<7>")
	)
	(segment
		(start 328.649584 -438.191148)
		(end 328.649584 -437.889904)
		(width 0.14224)
		(layer "In15.Cu")
		(net "P5E_CPU0_P0_RX_BUF_DP<7>")
	)
	(segment
		(start 324.277736 -412.38424)
		(end 324.277736 -413.567118)
		(width 0.14224)
		(layer "In15.Cu")
		(net "P5E_CPU0_P0_RX_BUF_DP<7>")
	)
	(segment
		(start 313.927998 -407.445464)
		(end 314.230004 -407.74747)
		(width 0.14224)
		(layer "In15.Cu")
		(net "P5E_CPU0_P0_RX_BUF_DP<7>")
	)
	(segment
		(start 325.946516 -416.167062)
		(end 325.946516 -416.593782)
		(width 0.14224)
		(layer "In15.Cu")
		(net "P5E_CPU0_P0_RX_BUF_DP<7>")
	)
	(segment
		(start 325.624952 -414.361884)
		(end 325.809356 -414.806892)
		(width 0.14224)
		(layer "In15.Cu")
		(net "P5E_CPU0_P0_RX_BUF_DP<7>")
	)
	(segment
		(start 327.468992 -422.62679)
		(end 327.627488 -422.732454)
		(width 0.14224)
		(layer "In15.Cu")
		(net "P5E_CPU0_P0_RX_BUF_DP<7>")
	)
	(segment
		(start 311.757314 -403.960584)
		(end 311.894474 -404.097744)
		(width 0.14224)
		(layer "In15.Cu")
		(net "P5E_CPU0_P0_RX_BUF_DP<7>")
	)
	(segment
		(start 311.794652 -405.50592)
		(end 312.058812 -405.77008)
		(width 0.14224)
		(layer "In15.Cu")
		(net "P5E_CPU0_P0_RX_BUF_DP<7>")
	)
	(segment
		(start 313.352434 -407.063702)
		(end 313.734196 -407.445464)
		(width 0.14224)
		(layer "In15.Cu")
		(net "P5E_CPU0_P0_RX_BUF_DP<7>")
	)
	(segment
		(start 313.050428 -406.56764)
		(end 313.352434 -406.869646)
		(width 0.14224)
		(layer "In15.Cu")
		(net "P5E_CPU0_P0_RX_BUF_DP<7>")
	)
	(segment
		(start 312.058812 -405.77008)
		(end 312.252868 -405.77008)
		(width 0.14224)
		(layer "In15.Cu")
		(net "P5E_CPU0_P0_RX_BUF_DP<7>")
	)
	(arc
		(start 311.757314 -405.41575)
		(mid 311.76702 -405.464545)
		(end 311.794652 -405.50592)
		(width 0.14224)
		(layer "In15.Cu")
		(net "P5E_CPU0_P0_RX_BUF_DP<7>")
	)
	(arc
		(start 314.842652 -408.55392)
		(mid 315.058017 -408.721898)
		(end 315.307726 -408.832558)
		(width 0.14224)
		(layer "In15.Cu")
		(net "P5E_CPU0_P0_RX_BUF_DP<7>")
	)
	(arc
		(start 326.072246 -419.18001)
		(mid 326.183684 -419.318756)
		(end 326.318626 -419.434772)
		(width 0.14224)
		(layer "In15.Cu")
		(net "P5E_CPU0_P0_RX_BUF_DP<7>")
	)
	(arc
		(start 325.809356 -418.545772)
		(mid 325.812409 -418.577234)
		(end 325.821548 -418.607494)
		(width 0.14224)
		(layer "In15.Cu")
		(net "P5E_CPU0_P0_RX_BUF_DP<7>")
	)
	(arc
		(start 326.318626 -419.434772)
		(mid 326.372393 -419.46852)
		(end 326.429624 -419.495986)
		(width 0.14224)
		(layer "In15.Cu")
		(net "P5E_CPU0_P0_RX_BUF_DP<7>")
	)
	(arc
		(start 327.221088 -420.144448)
		(mid 327.309832 -420.277168)
		(end 327.340976 -420.433754)
		(width 0.14224)
		(layer "In15.Cu")
		(net "P5E_CPU0_P0_RX_BUF_DP<7>")
	)
	(arc
		(start 326.561704 -419.550596)
		(mid 326.666484 -419.606408)
		(end 326.7583 -419.68166)
		(width 0.14224)
		(layer "In15.Cu")
		(net "P5E_CPU0_P0_RX_BUF_DP<7>")
	)
	(arc
		(start 326.01281 -419.06825)
		(mid 326.039845 -419.125558)
		(end 326.072246 -419.18001)
		(width 0.14224)
		(layer "In15.Cu")
		(net "P5E_CPU0_P0_RX_BUF_DP<7>")
	)
	(segment
		(start 311.016396 -401.498054)
		(end 311.016396 -401.674838)
		(width 0.1016)
		(layer "F.Cu")
		(net "P5E_CPU0_P0_RX_BUF_DP<6>")
	)
	(segment
		(start 310.317642 -399.663158)
		(end 310.402224 -399.74774)
		(width 0.1016)
		(layer "F.Cu")
		(net "P5E_CPU0_P0_RX_BUF_DP<6>")
	)
	(segment
		(start 310.322468 -401.105878)
		(end 310.575706 -401.359116)
		(width 0.1016)
		(layer "F.Cu")
		(net "P5E_CPU0_P0_RX_BUF_DP<6>")
	)
	(segment
		(start 310.322468 -399.950432)
		(end 310.322468 -401.105878)
		(width 0.1016)
		(layer "F.Cu")
		(net "P5E_CPU0_P0_RX_BUF_DP<6>")
	)
	(segment
		(start 310.402224 -399.74774)
		(end 310.402224 -399.870676)
		(width 0.1016)
		(layer "F.Cu")
		(net "P5E_CPU0_P0_RX_BUF_DP<6>")
	)
	(segment
		(start 310.402224 -399.870676)
		(end 310.322468 -399.950432)
		(width 0.1016)
		(layer "F.Cu")
		(net "P5E_CPU0_P0_RX_BUF_DP<6>")
	)
	(segment
		(start 310.575706 -401.359116)
		(end 310.877458 -401.359116)
		(width 0.1016)
		(layer "F.Cu")
		(net "P5E_CPU0_P0_RX_BUF_DP<6>")
	)
	(segment
		(start 310.877458 -401.359116)
		(end 311.016396 -401.498054)
		(width 0.1016)
		(layer "F.Cu")
		(net "P5E_CPU0_P0_RX_BUF_DP<6>")
	)
	(segment
		(start 310.557418 -404.708614)
		(end 310.557418 -405.648922)
		(width 0.14224)
		(layer "In15.Cu")
		(net "P5E_CPU0_P0_RX_BUF_DP<6>")
	)
	(segment
		(start 325.044308 -422.716706)
		(end 325.226934 -423.102786)
		(width 0.14224)
		(layer "In15.Cu")
		(net "P5E_CPU0_P0_RX_BUF_DP<6>")
	)
	(segment
		(start 326.174862 -437.341264)
		(end 326.499474 -437.341264)
		(width 0.14224)
		(layer "In15.Cu")
		(net "P5E_CPU0_P0_RX_BUF_DP<6>")
	)
	(segment
		(start 322.746116 -417.05276)
		(end 322.883276 -417.18992)
		(width 0.14224)
		(layer "In15.Cu")
		(net "P5E_CPU0_P0_RX_BUF_DP<6>")
	)
	(segment
		(start 310.696864 -401.371562)
		(end 310.557418 -401.511008)
		(width 0.14224)
		(layer "In15.Cu")
		(net "P5E_CPU0_P0_RX_BUF_DP<6>")
	)
	(segment
		(start 325.9709 -425.092622)
		(end 325.9709 -437.137302)
		(width 0.14224)
		(layer "In15.Cu")
		(net "P5E_CPU0_P0_RX_BUF_DP<6>")
	)
	(segment
		(start 310.694578 -403.016974)
		(end 310.694578 -403.443694)
		(width 0.14224)
		(layer "In15.Cu")
		(net "P5E_CPU0_P0_RX_BUF_DP<6>")
	)
	(segment
		(start 310.87695 -401.371562)
		(end 310.696864 -401.371562)
		(width 0.14224)
		(layer "In15.Cu")
		(net "P5E_CPU0_P0_RX_BUF_DP<6>")
	)
	(segment
		(start 311.354978 -406.463754)
		(end 311.354978 -406.65781)
		(width 0.14224)
		(layer "In15.Cu")
		(net "P5E_CPU0_P0_RX_BUF_DP<6>")
	)
	(segment
		(start 322.746116 -416.62604)
		(end 322.746116 -417.05276)
		(width 0.14224)
		(layer "In15.Cu")
		(net "P5E_CPU0_P0_RX_BUF_DP<6>")
	)
	(segment
		(start 325.162672 -423.28211)
		(end 325.345044 -423.667682)
		(width 0.14224)
		(layer "In15.Cu")
		(net "P5E_CPU0_P0_RX_BUF_DP<6>")
	)
	(segment
		(start 326.649588 -437.19115)
		(end 326.649588 -436.889906)
		(width 0.14224)
		(layer "In15.Cu")
		(net "P5E_CPU0_P0_RX_BUF_DP<6>")
	)
	(segment
		(start 325.9709 -437.137302)
		(end 326.174862 -437.341264)
		(width 0.14224)
		(layer "In15.Cu")
		(net "P5E_CPU0_P0_RX_BUF_DP<6>")
	)
	(segment
		(start 321.0179 -411.795722)
		(end 321.161664 -412.07309)
		(width 0.14224)
		(layer "In15.Cu")
		(net "P5E_CPU0_P0_RX_BUF_DP<6>")
	)
	(segment
		(start 323.721984 -419.75913)
		(end 324.147942 -420.185088)
		(width 0.14224)
		(layer "In15.Cu")
		(net "P5E_CPU0_P0_RX_BUF_DP<6>")
	)
	(segment
		(start 322.227956 -414.028128)
		(end 322.561712 -414.361884)
		(width 0.14224)
		(layer "In15.Cu")
		(net "P5E_CPU0_P0_RX_BUF_DP<6>")
	)
	(segment
		(start 321.471798 -413.927036)
		(end 321.543426 -413.956754)
		(width 0.14224)
		(layer "In15.Cu")
		(net "P5E_CPU0_P0_RX_BUF_DP<6>")
	)
	(segment
		(start 322.746116 -417.7538)
		(end 322.746116 -418.512498)
		(width 0.14224)
		(layer "In15.Cu")
		(net "P5E_CPU0_P0_RX_BUF_DP<6>")
	)
	(segment
		(start 325.524622 -423.731944)
		(end 325.706994 -424.11777)
		(width 0.14224)
		(layer "In15.Cu")
		(net "P5E_CPU0_P0_RX_BUF_DP<6>")
	)
	(segment
		(start 312.454036 -407.756868)
		(end 312.648092 -407.756868)
		(width 0.14224)
		(layer "In15.Cu")
		(net "P5E_CPU0_P0_RX_BUF_DP<6>")
	)
	(segment
		(start 322.055744 -413.956754)
		(end 322.227956 -414.028128)
		(width 0.14224)
		(layer "In15.Cu")
		(net "P5E_CPU0_P0_RX_BUF_DP<6>")
	)
	(segment
		(start 310.694578 -403.443694)
		(end 310.557418 -403.580854)
		(width 0.14224)
		(layer "In15.Cu")
		(net "P5E_CPU0_P0_RX_BUF_DP<6>")
	)
	(segment
		(start 310.858916 -406.161748)
		(end 311.052972 -406.161748)
		(width 0.14224)
		(layer "In15.Cu")
		(net "P5E_CPU0_P0_RX_BUF_DP<6>")
	)
	(segment
		(start 311.850532 -406.959308)
		(end 312.152538 -407.261314)
		(width 0.14224)
		(layer "In15.Cu")
		(net "P5E_CPU0_P0_RX_BUF_DP<6>")
	)
	(segment
		(start 310.557418 -403.580854)
		(end 310.557418 -404.007574)
		(width 0.14224)
		(layer "In15.Cu")
		(net "P5E_CPU0_P0_RX_BUF_DP<6>")
	)
	(segment
		(start 322.883276 -416.06216)
		(end 322.883276 -416.48888)
		(width 0.14224)
		(layer "In15.Cu")
		(net "P5E_CPU0_P0_RX_BUF_DP<6>")
	)
	(segment
		(start 311.656476 -406.959308)
		(end 311.850532 -406.959308)
		(width 0.14224)
		(layer "In15.Cu")
		(net "P5E_CPU0_P0_RX_BUF_DP<6>")
	)
	(segment
		(start 310.557418 -404.007574)
		(end 310.694578 -404.144734)
		(width 0.14224)
		(layer "In15.Cu")
		(net "P5E_CPU0_P0_RX_BUF_DP<6>")
	)
	(segment
		(start 321.327272 -413.78251)
		(end 321.471798 -413.927036)
		(width 0.14224)
		(layer "In15.Cu")
		(net "P5E_CPU0_P0_RX_BUF_DP<6>")
	)
	(segment
		(start 321.543426 -413.956754)
		(end 322.055744 -413.956754)
		(width 0.14224)
		(layer "In15.Cu")
		(net "P5E_CPU0_P0_RX_BUF_DP<6>")
	)
	(segment
		(start 322.883276 -416.48888)
		(end 322.746116 -416.62604)
		(width 0.14224)
		(layer "In15.Cu")
		(net "P5E_CPU0_P0_RX_BUF_DP<6>")
	)
	(segment
		(start 325.226934 -423.102786)
		(end 325.162672 -423.28211)
		(width 0.14224)
		(layer "In15.Cu")
		(net "P5E_CPU0_P0_RX_BUF_DP<6>")
	)
	(segment
		(start 310.557418 -402.879814)
		(end 310.694578 -403.016974)
		(width 0.14224)
		(layer "In15.Cu")
		(net "P5E_CPU0_P0_RX_BUF_DP<6>")
	)
	(segment
		(start 324.32625 -421.513762)
		(end 324.864984 -422.652698)
		(width 0.14224)
		(layer "In15.Cu")
		(net "P5E_CPU0_P0_RX_BUF_DP<6>")
	)
	(segment
		(start 325.642732 -424.297094)
		(end 325.7804 -424.588178)
		(width 0.14224)
		(layer "In15.Cu")
		(net "P5E_CPU0_P0_RX_BUF_DP<6>")
	)
	(segment
		(start 311.354978 -406.65781)
		(end 311.656476 -406.959308)
		(width 0.14224)
		(layer "In15.Cu")
		(net "P5E_CPU0_P0_RX_BUF_DP<6>")
	)
	(segment
		(start 324.277736 -420.498524)
		(end 324.277736 -421.298624)
		(width 0.14224)
		(layer "In15.Cu")
		(net "P5E_CPU0_P0_RX_BUF_DP<6>")
	)
	(segment
		(start 311.016396 -401.674838)
		(end 311.016396 -401.511008)
		(width 0.14224)
		(layer "In15.Cu")
		(net "P5E_CPU0_P0_RX_BUF_DP<6>")
	)
	(segment
		(start 326.499474 -437.341264)
		(end 326.649588 -437.19115)
		(width 0.14224)
		(layer "In15.Cu")
		(net "P5E_CPU0_P0_RX_BUF_DP<6>")
	)
	(segment
		(start 311.016396 -401.511008)
		(end 310.87695 -401.371562)
		(width 0.14224)
		(layer "In15.Cu")
		(net "P5E_CPU0_P0_RX_BUF_DP<6>")
	)
	(segment
		(start 312.648092 -407.756868)
		(end 312.950098 -408.058874)
		(width 0.14224)
		(layer "In15.Cu")
		(net "P5E_CPU0_P0_RX_BUF_DP<6>")
	)
	(segment
		(start 321.214496 -413.509968)
		(end 321.327272 -413.78251)
		(width 0.14224)
		(layer "In15.Cu")
		(net "P5E_CPU0_P0_RX_BUF_DP<6>")
	)
	(segment
		(start 325.706994 -424.11777)
		(end 325.642732 -424.297094)
		(width 0.14224)
		(layer "In15.Cu")
		(net "P5E_CPU0_P0_RX_BUF_DP<6>")
	)
	(segment
		(start 322.883276 -417.61664)
		(end 322.746116 -417.7538)
		(width 0.14224)
		(layer "In15.Cu")
		(net "P5E_CPU0_P0_RX_BUF_DP<6>")
	)
	(segment
		(start 312.950098 -408.25293)
		(end 314.122562 -409.425394)
		(width 0.14224)
		(layer "In15.Cu")
		(net "P5E_CPU0_P0_RX_BUF_DP<6>")
	)
	(segment
		(start 322.883276 -417.18992)
		(end 322.883276 -417.61664)
		(width 0.14224)
		(layer "In15.Cu")
		(net "P5E_CPU0_P0_RX_BUF_DP<6>")
	)
	(segment
		(start 321.214496 -412.289498)
		(end 321.214496 -413.509968)
		(width 0.14224)
		(layer "In15.Cu")
		(net "P5E_CPU0_P0_RX_BUF_DP<6>")
	)
	(segment
		(start 310.694578 -404.144734)
		(end 310.694578 -404.571454)
		(width 0.14224)
		(layer "In15.Cu")
		(net "P5E_CPU0_P0_RX_BUF_DP<6>")
	)
	(segment
		(start 325.345044 -423.667682)
		(end 325.524622 -423.731944)
		(width 0.14224)
		(layer "In15.Cu")
		(net "P5E_CPU0_P0_RX_BUF_DP<6>")
	)
	(segment
		(start 310.707024 -406.009856)
		(end 310.858916 -406.161748)
		(width 0.14224)
		(layer "In15.Cu")
		(net "P5E_CPU0_P0_RX_BUF_DP<6>")
	)
	(segment
		(start 310.694578 -404.571454)
		(end 310.557418 -404.708614)
		(width 0.14224)
		(layer "In15.Cu")
		(net "P5E_CPU0_P0_RX_BUF_DP<6>")
	)
	(segment
		(start 325.7804 -424.588178)
		(end 325.918068 -424.879516)
		(width 0.14224)
		(layer "In15.Cu")
		(net "P5E_CPU0_P0_RX_BUF_DP<6>")
	)
	(segment
		(start 324.864984 -422.652698)
		(end 325.044308 -422.716706)
		(width 0.14224)
		(layer "In15.Cu")
		(net "P5E_CPU0_P0_RX_BUF_DP<6>")
	)
	(segment
		(start 312.152538 -407.261314)
		(end 312.152538 -407.45537)
		(width 0.14224)
		(layer "In15.Cu")
		(net "P5E_CPU0_P0_RX_BUF_DP<6>")
	)
	(segment
		(start 314.29706 -409.530042)
		(end 320.452496 -411.39745)
		(width 0.14224)
		(layer "In15.Cu")
		(net "P5E_CPU0_P0_RX_BUF_DP<6>")
	)
	(segment
		(start 311.052972 -406.161748)
		(end 311.354978 -406.463754)
		(width 0.14224)
		(layer "In15.Cu")
		(net "P5E_CPU0_P0_RX_BUF_DP<6>")
	)
	(segment
		(start 320.452496 -411.39745)
		(end 321.0179 -411.795722)
		(width 0.14224)
		(layer "In15.Cu")
		(net "P5E_CPU0_P0_RX_BUF_DP<6>")
	)
	(segment
		(start 322.746116 -414.806892)
		(end 322.746116 -415.925)
		(width 0.14224)
		(layer "In15.Cu")
		(net "P5E_CPU0_P0_RX_BUF_DP<6>")
	)
	(segment
		(start 322.770754 -418.635942)
		(end 322.94195 -419.0492)
		(width 0.14224)
		(layer "In15.Cu")
		(net "P5E_CPU0_P0_RX_BUF_DP<6>")
	)
	(segment
		(start 312.950098 -408.058874)
		(end 312.950098 -408.25293)
		(width 0.14224)
		(layer "In15.Cu")
		(net "P5E_CPU0_P0_RX_BUF_DP<6>")
	)
	(segment
		(start 312.152538 -407.45537)
		(end 312.454036 -407.756868)
		(width 0.14224)
		(layer "In15.Cu")
		(net "P5E_CPU0_P0_RX_BUF_DP<6>")
	)
	(segment
		(start 310.557418 -401.511008)
		(end 310.557418 -402.879814)
		(width 0.14224)
		(layer "In15.Cu")
		(net "P5E_CPU0_P0_RX_BUF_DP<6>")
	)
	(segment
		(start 322.561712 -414.361884)
		(end 322.746116 -414.806892)
		(width 0.14224)
		(layer "In15.Cu")
		(net "P5E_CPU0_P0_RX_BUF_DP<6>")
	)
	(segment
		(start 322.746116 -415.925)
		(end 322.883276 -416.06216)
		(width 0.14224)
		(layer "In15.Cu")
		(net "P5E_CPU0_P0_RX_BUF_DP<6>")
	)
	(arc
		(start 323.342 -419.482778)
		(mid 323.542798 -419.606097)
		(end 323.721984 -419.75913)
		(width 0.14224)
		(layer "In15.Cu")
		(net "P5E_CPU0_P0_RX_BUF_DP<6>")
	)
	(arc
		(start 322.746116 -418.512498)
		(mid 322.75237 -418.575429)
		(end 322.770754 -418.635942)
		(width 0.14224)
		(layer "In15.Cu")
		(net "P5E_CPU0_P0_RX_BUF_DP<6>")
	)
	(arc
		(start 324.277736 -421.298624)
		(mid 324.290072 -421.408881)
		(end 324.32625 -421.513762)
		(width 0.14224)
		(layer "In15.Cu")
		(net "P5E_CPU0_P0_RX_BUF_DP<6>")
	)
	(arc
		(start 310.557418 -405.648922)
		(mid 310.596296 -405.844283)
		(end 310.707024 -406.009856)
		(width 0.14224)
		(layer "In15.Cu")
		(net "P5E_CPU0_P0_RX_BUF_DP<6>")
	)
	(arc
		(start 314.122562 -409.425394)
		(mid 314.20335 -409.488495)
		(end 314.29706 -409.530042)
		(width 0.14224)
		(layer "In15.Cu")
		(net "P5E_CPU0_P0_RX_BUF_DP<6>")
	)
	(arc
		(start 324.147942 -420.185088)
		(mid 324.24403 -420.328894)
		(end 324.277736 -420.498524)
		(width 0.14224)
		(layer "In15.Cu")
		(net "P5E_CPU0_P0_RX_BUF_DP<6>")
	)
	(arc
		(start 325.918068 -424.879516)
		(mid 325.955193 -424.983413)
		(end 325.9709 -425.092622)
		(width 0.14224)
		(layer "In15.Cu")
		(net "P5E_CPU0_P0_RX_BUF_DP<6>")
	)
	(arc
		(start 321.161664 -412.07309)
		(mid 321.201075 -412.17812)
		(end 321.214496 -412.289498)
		(width 0.14224)
		(layer "In15.Cu")
		(net "P5E_CPU0_P0_RX_BUF_DP<6>")
	)
	(arc
		(start 322.94195 -419.0492)
		(mid 323.103306 -419.301679)
		(end 323.342 -419.482778)
		(width 0.14224)
		(layer "In15.Cu")
		(net "P5E_CPU0_P0_RX_BUF_DP<6>")
	)
	(segment
		(start 309.677562 -401.359116)
		(end 309.816246 -401.4978)
		(width 0.1016)
		(layer "F.Cu")
		(net "P5E_CPU0_P0_RX_BUF_DP<5>")
	)
	(segment
		(start 309.202328 -399.870676)
		(end 309.113682 -399.959322)
		(width 0.1016)
		(layer "F.Cu")
		(net "P5E_CPU0_P0_RX_BUF_DP<5>")
	)
	(segment
		(start 309.113682 -401.105878)
		(end 309.36692 -401.359116)
		(width 0.1016)
		(layer "F.Cu")
		(net "P5E_CPU0_P0_RX_BUF_DP<5>")
	)
	(segment
		(start 309.117746 -399.663158)
		(end 309.202328 -399.74774)
		(width 0.1016)
		(layer "F.Cu")
		(net "P5E_CPU0_P0_RX_BUF_DP<5>")
	)
	(segment
		(start 309.816246 -401.4978)
		(end 309.816246 -401.674838)
		(width 0.1016)
		(layer "F.Cu")
		(net "P5E_CPU0_P0_RX_BUF_DP<5>")
	)
	(segment
		(start 309.36692 -401.359116)
		(end 309.677562 -401.359116)
		(width 0.1016)
		(layer "F.Cu")
		(net "P5E_CPU0_P0_RX_BUF_DP<5>")
	)
	(segment
		(start 309.202328 -399.74774)
		(end 309.202328 -399.870676)
		(width 0.1016)
		(layer "F.Cu")
		(net "P5E_CPU0_P0_RX_BUF_DP<5>")
	)
	(segment
		(start 309.113682 -399.959322)
		(end 309.113682 -401.105878)
		(width 0.1016)
		(layer "F.Cu")
		(net "P5E_CPU0_P0_RX_BUF_DP<5>")
	)
	(segment
		(start 309.658766 -406.655778)
		(end 309.852822 -406.655778)
		(width 0.14224)
		(layer "In15.Cu")
		(net "P5E_CPU0_P0_RX_BUF_DP<5>")
	)
	(segment
		(start 324.649592 -438.191148)
		(end 324.649592 -437.889904)
		(width 0.14224)
		(layer "In15.Cu")
		(net "P5E_CPU0_P0_RX_BUF_DP<5>")
	)
	(segment
		(start 312.069734 -409.066746)
		(end 312.26379 -409.066746)
		(width 0.14224)
		(layer "In15.Cu")
		(net "P5E_CPU0_P0_RX_BUF_DP<5>")
	)
	(segment
		(start 309.816246 -401.674838)
		(end 309.816246 -401.511008)
		(width 0.14224)
		(layer "In15.Cu")
		(net "P5E_CPU0_P0_RX_BUF_DP<5>")
	)
	(segment
		(start 311.253886 -408.250898)
		(end 311.447942 -408.250898)
		(width 0.14224)
		(layer "In15.Cu")
		(net "P5E_CPU0_P0_RX_BUF_DP<5>")
	)
	(segment
		(start 318.151256 -412.180532)
		(end 318.151256 -413.49168)
		(width 0.14224)
		(layer "In15.Cu")
		(net "P5E_CPU0_P0_RX_BUF_DP<5>")
	)
	(segment
		(start 311.749948 -408.74696)
		(end 312.069734 -409.066746)
		(width 0.14224)
		(layer "In15.Cu")
		(net "P5E_CPU0_P0_RX_BUF_DP<5>")
	)
	(segment
		(start 321.214496 -421.27805)
		(end 321.242436 -421.362632)
		(width 0.14224)
		(layer "In15.Cu")
		(net "P5E_CPU0_P0_RX_BUF_DP<5>")
	)
	(segment
		(start 309.852822 -406.655778)
		(end 310.154828 -406.957784)
		(width 0.14224)
		(layer "In15.Cu")
		(net "P5E_CPU0_P0_RX_BUF_DP<5>")
	)
	(segment
		(start 310.154828 -406.957784)
		(end 310.154828 -407.15184)
		(width 0.14224)
		(layer "In15.Cu")
		(net "P5E_CPU0_P0_RX_BUF_DP<5>")
	)
	(segment
		(start 318.408558 -413.927036)
		(end 318.480186 -413.956754)
		(width 0.14224)
		(layer "In15.Cu")
		(net "P5E_CPU0_P0_RX_BUF_DP<5>")
	)
	(segment
		(start 319.820036 -418.038026)
		(end 319.682876 -418.175186)
		(width 0.14224)
		(layer "In15.Cu")
		(net "P5E_CPU0_P0_RX_BUF_DP<5>")
	)
	(segment
		(start 322.301108 -422.563798)
		(end 322.555616 -422.906698)
		(width 0.14224)
		(layer "In15.Cu")
		(net "P5E_CPU0_P0_RX_BUF_DP<5>")
	)
	(segment
		(start 319.682876 -417.474146)
		(end 319.820036 -417.611306)
		(width 0.14224)
		(layer "In15.Cu")
		(net "P5E_CPU0_P0_RX_BUF_DP<5>")
	)
	(segment
		(start 309.357268 -403.869398)
		(end 309.357268 -404.370032)
		(width 0.14224)
		(layer "In15.Cu")
		(net "P5E_CPU0_P0_RX_BUF_DP<5>")
	)
	(segment
		(start 313.556904 -410.304742)
		(end 317.462662 -411.488636)
		(width 0.14224)
		(layer "In15.Cu")
		(net "P5E_CPU0_P0_RX_BUF_DP<5>")
	)
	(segment
		(start 319.682876 -417.047426)
		(end 319.682876 -417.474146)
		(width 0.14224)
		(layer "In15.Cu")
		(net "P5E_CPU0_P0_RX_BUF_DP<5>")
	)
	(segment
		(start 320.24701 -419.472618)
		(end 320.361564 -419.519862)
		(width 0.14224)
		(layer "In15.Cu")
		(net "P5E_CPU0_P0_RX_BUF_DP<5>")
	)
	(segment
		(start 322.555616 -422.906698)
		(end 322.527676 -423.094912)
		(width 0.14224)
		(layer "In15.Cu")
		(net "P5E_CPU0_P0_RX_BUF_DP<5>")
	)
	(segment
		(start 319.820036 -417.611306)
		(end 319.820036 -418.038026)
		(width 0.14224)
		(layer "In15.Cu")
		(net "P5E_CPU0_P0_RX_BUF_DP<5>")
	)
	(segment
		(start 309.6768 -401.371562)
		(end 309.496714 -401.371562)
		(width 0.14224)
		(layer "In15.Cu")
		(net "P5E_CPU0_P0_RX_BUF_DP<5>")
	)
	(segment
		(start 323.982588 -438.148984)
		(end 324.174866 -438.341262)
		(width 0.14224)
		(layer "In15.Cu")
		(net "P5E_CPU0_P0_RX_BUF_DP<5>")
	)
	(segment
		(start 309.494428 -404.507192)
		(end 309.494428 -404.933912)
		(width 0.14224)
		(layer "In15.Cu")
		(net "P5E_CPU0_P0_RX_BUF_DP<5>")
	)
	(segment
		(start 310.952388 -407.9494)
		(end 311.253886 -408.250898)
		(width 0.14224)
		(layer "In15.Cu")
		(net "P5E_CPU0_P0_RX_BUF_DP<5>")
	)
	(segment
		(start 317.462662 -411.488636)
		(end 317.913766 -411.760416)
		(width 0.14224)
		(layer "In15.Cu")
		(net "P5E_CPU0_P0_RX_BUF_DP<5>")
	)
	(segment
		(start 324.174866 -438.341262)
		(end 324.499478 -438.341262)
		(width 0.14224)
		(layer "In15.Cu")
		(net "P5E_CPU0_P0_RX_BUF_DP<5>")
	)
	(segment
		(start 309.494428 -403.305518)
		(end 309.494428 -403.732238)
		(width 0.14224)
		(layer "In15.Cu")
		(net "P5E_CPU0_P0_RX_BUF_DP<5>")
	)
	(segment
		(start 319.682876 -414.806892)
		(end 319.682876 -416.346386)
		(width 0.14224)
		(layer "In15.Cu")
		(net "P5E_CPU0_P0_RX_BUF_DP<5>")
	)
	(segment
		(start 323.450966 -424.339258)
		(end 323.742812 -424.7769)
		(width 0.14224)
		(layer "In15.Cu")
		(net "P5E_CPU0_P0_RX_BUF_DP<5>")
	)
	(segment
		(start 318.480186 -413.956754)
		(end 318.992504 -413.956754)
		(width 0.14224)
		(layer "In15.Cu")
		(net "P5E_CPU0_P0_RX_BUF_DP<5>")
	)
	(segment
		(start 319.682876 -418.175186)
		(end 319.682876 -418.764974)
		(width 0.14224)
		(layer "In15.Cu")
		(net "P5E_CPU0_P0_RX_BUF_DP<5>")
	)
	(segment
		(start 319.682876 -416.346386)
		(end 319.820036 -416.483546)
		(width 0.14224)
		(layer "In15.Cu")
		(net "P5E_CPU0_P0_RX_BUF_DP<5>")
	)
	(segment
		(start 319.820036 -416.910266)
		(end 319.682876 -417.047426)
		(width 0.14224)
		(layer "In15.Cu")
		(net "P5E_CPU0_P0_RX_BUF_DP<5>")
	)
	(segment
		(start 309.496714 -401.371562)
		(end 309.357268 -401.511008)
		(width 0.14224)
		(layer "In15.Cu")
		(net "P5E_CPU0_P0_RX_BUF_DP<5>")
	)
	(segment
		(start 309.494428 -404.933912)
		(end 309.357268 -405.071072)
		(width 0.14224)
		(layer "In15.Cu")
		(net "P5E_CPU0_P0_RX_BUF_DP<5>")
	)
	(segment
		(start 322.112894 -422.535858)
		(end 322.301108 -422.563798)
		(width 0.14224)
		(layer "In15.Cu")
		(net "P5E_CPU0_P0_RX_BUF_DP<5>")
	)
	(segment
		(start 311.447942 -408.250898)
		(end 311.749948 -408.552904)
		(width 0.14224)
		(layer "In15.Cu")
		(net "P5E_CPU0_P0_RX_BUF_DP<5>")
	)
	(segment
		(start 323.982588 -425.539662)
		(end 323.982588 -438.148984)
		(width 0.14224)
		(layer "In15.Cu")
		(net "P5E_CPU0_P0_RX_BUF_DP<5>")
	)
	(segment
		(start 311.749948 -408.552904)
		(end 311.749948 -408.74696)
		(width 0.14224)
		(layer "In15.Cu")
		(net "P5E_CPU0_P0_RX_BUF_DP<5>")
	)
	(segment
		(start 310.154828 -407.15184)
		(end 310.456326 -407.453338)
		(width 0.14224)
		(layer "In15.Cu")
		(net "P5E_CPU0_P0_RX_BUF_DP<5>")
	)
	(segment
		(start 319.682876 -418.764974)
		(end 319.784984 -419.0111)
		(width 0.14224)
		(layer "In15.Cu")
		(net "P5E_CPU0_P0_RX_BUF_DP<5>")
	)
	(segment
		(start 309.494428 -403.732238)
		(end 309.357268 -403.869398)
		(width 0.14224)
		(layer "In15.Cu")
		(net "P5E_CPU0_P0_RX_BUF_DP<5>")
	)
	(segment
		(start 318.992504 -413.956754)
		(end 319.164716 -414.028128)
		(width 0.14224)
		(layer "In15.Cu")
		(net "P5E_CPU0_P0_RX_BUF_DP<5>")
	)
	(segment
		(start 310.650382 -407.453338)
		(end 310.952388 -407.755344)
		(width 0.14224)
		(layer "In15.Cu")
		(net "P5E_CPU0_P0_RX_BUF_DP<5>")
	)
	(segment
		(start 312.565796 -409.368752)
		(end 312.565796 -409.562808)
		(width 0.14224)
		(layer "In15.Cu")
		(net "P5E_CPU0_P0_RX_BUF_DP<5>")
	)
	(segment
		(start 309.357268 -403.168358)
		(end 309.494428 -403.305518)
		(width 0.14224)
		(layer "In15.Cu")
		(net "P5E_CPU0_P0_RX_BUF_DP<5>")
	)
	(segment
		(start 319.820036 -416.483546)
		(end 319.820036 -416.910266)
		(width 0.14224)
		(layer "In15.Cu")
		(net "P5E_CPU0_P0_RX_BUF_DP<5>")
	)
	(segment
		(start 312.26379 -409.066746)
		(end 312.565796 -409.368752)
		(width 0.14224)
		(layer "In15.Cu")
		(net "P5E_CPU0_P0_RX_BUF_DP<5>")
	)
	(segment
		(start 320.629026 -419.698424)
		(end 321.094608 -420.164006)
		(width 0.14224)
		(layer "In15.Cu")
		(net "P5E_CPU0_P0_RX_BUF_DP<5>")
	)
	(segment
		(start 323.742812 -424.7769)
		(end 323.911976 -425.185586)
		(width 0.14224)
		(layer "In15.Cu")
		(net "P5E_CPU0_P0_RX_BUF_DP<5>")
	)
	(segment
		(start 309.357268 -401.511008)
		(end 309.357268 -403.168358)
		(width 0.14224)
		(layer "In15.Cu")
		(net "P5E_CPU0_P0_RX_BUF_DP<5>")
	)
	(segment
		(start 319.164716 -414.028128)
		(end 319.498472 -414.361884)
		(width 0.14224)
		(layer "In15.Cu")
		(net "P5E_CPU0_P0_RX_BUF_DP<5>")
	)
	(segment
		(start 310.952388 -407.755344)
		(end 310.952388 -407.9494)
		(width 0.14224)
		(layer "In15.Cu")
		(net "P5E_CPU0_P0_RX_BUF_DP<5>")
	)
	(segment
		(start 318.27724 -413.795718)
		(end 318.408558 -413.927036)
		(width 0.14224)
		(layer "In15.Cu")
		(net "P5E_CPU0_P0_RX_BUF_DP<5>")
	)
	(segment
		(start 309.816246 -401.511008)
		(end 309.6768 -401.371562)
		(width 0.14224)
		(layer "In15.Cu")
		(net "P5E_CPU0_P0_RX_BUF_DP<5>")
	)
	(segment
		(start 310.456326 -407.453338)
		(end 310.650382 -407.453338)
		(width 0.14224)
		(layer "In15.Cu")
		(net "P5E_CPU0_P0_RX_BUF_DP<5>")
	)
	(segment
		(start 321.214496 -420.453312)
		(end 321.214496 -421.27805)
		(width 0.14224)
		(layer "In15.Cu")
		(net "P5E_CPU0_P0_RX_BUF_DP<5>")
	)
	(segment
		(start 318.151256 -413.49168)
		(end 318.27724 -413.795718)
		(width 0.14224)
		(layer "In15.Cu")
		(net "P5E_CPU0_P0_RX_BUF_DP<5>")
	)
	(segment
		(start 324.499478 -438.341262)
		(end 324.649592 -438.191148)
		(width 0.14224)
		(layer "In15.Cu")
		(net "P5E_CPU0_P0_RX_BUF_DP<5>")
	)
	(segment
		(start 309.357268 -404.370032)
		(end 309.494428 -404.507192)
		(width 0.14224)
		(layer "In15.Cu")
		(net "P5E_CPU0_P0_RX_BUF_DP<5>")
	)
	(segment
		(start 312.565796 -409.562808)
		(end 312.935112 -409.932124)
		(width 0.14224)
		(layer "In15.Cu")
		(net "P5E_CPU0_P0_RX_BUF_DP<5>")
	)
	(segment
		(start 309.394606 -406.391618)
		(end 309.658766 -406.655778)
		(width 0.14224)
		(layer "In15.Cu")
		(net "P5E_CPU0_P0_RX_BUF_DP<5>")
	)
	(segment
		(start 319.498472 -414.361884)
		(end 319.682876 -414.806892)
		(width 0.14224)
		(layer "In15.Cu")
		(net "P5E_CPU0_P0_RX_BUF_DP<5>")
	)
	(segment
		(start 322.527676 -423.094912)
		(end 323.450966 -424.339258)
		(width 0.14224)
		(layer "In15.Cu")
		(net "P5E_CPU0_P0_RX_BUF_DP<5>")
	)
	(segment
		(start 321.242436 -421.362632)
		(end 322.112894 -422.535858)
		(width 0.14224)
		(layer "In15.Cu")
		(net "P5E_CPU0_P0_RX_BUF_DP<5>")
	)
	(segment
		(start 309.357268 -405.071072)
		(end 309.357268 -406.301448)
		(width 0.14224)
		(layer "In15.Cu")
		(net "P5E_CPU0_P0_RX_BUF_DP<5>")
	)
	(arc
		(start 317.913766 -411.760416)
		(mid 318.087649 -411.93929)
		(end 318.151256 -412.180532)
		(width 0.14224)
		(layer "In15.Cu")
		(net "P5E_CPU0_P0_RX_BUF_DP<5>")
	)
	(arc
		(start 312.935112 -409.932124)
		(mid 313.223022 -410.156789)
		(end 313.556904 -410.304742)
		(width 0.14224)
		(layer "In15.Cu")
		(net "P5E_CPU0_P0_RX_BUF_DP<5>")
	)
	(arc
		(start 309.357268 -406.301448)
		(mid 309.366974 -406.350243)
		(end 309.394606 -406.391618)
		(width 0.14224)
		(layer "In15.Cu")
		(net "P5E_CPU0_P0_RX_BUF_DP<5>")
	)
	(arc
		(start 320.361564 -419.519862)
		(mid 320.504116 -419.59593)
		(end 320.629026 -419.698424)
		(width 0.14224)
		(layer "In15.Cu")
		(net "P5E_CPU0_P0_RX_BUF_DP<5>")
	)
	(arc
		(start 321.094608 -420.164006)
		(mid 321.183352 -420.296726)
		(end 321.214496 -420.453312)
		(width 0.14224)
		(layer "In15.Cu")
		(net "P5E_CPU0_P0_RX_BUF_DP<5>")
	)
	(arc
		(start 319.784984 -419.0111)
		(mid 319.970118 -419.287796)
		(end 320.24701 -419.472618)
		(width 0.14224)
		(layer "In15.Cu")
		(net "P5E_CPU0_P0_RX_BUF_DP<5>")
	)
	(arc
		(start 323.911976 -425.185586)
		(mid 323.964763 -425.359138)
		(end 323.982588 -425.539662)
		(width 0.14224)
		(layer "In15.Cu")
		(net "P5E_CPU0_P0_RX_BUF_DP<5>")
	)
	(segment
		(start 307.913786 -401.105878)
		(end 308.167024 -401.359116)
		(width 0.1016)
		(layer "F.Cu")
		(net "P5E_CPU0_P0_RX_BUF_DP<4>")
	)
	(segment
		(start 308.167024 -401.359116)
		(end 308.477666 -401.359116)
		(width 0.1016)
		(layer "F.Cu")
		(net "P5E_CPU0_P0_RX_BUF_DP<4>")
	)
	(segment
		(start 307.91785 -399.663158)
		(end 308.002432 -399.74774)
		(width 0.1016)
		(layer "F.Cu")
		(net "P5E_CPU0_P0_RX_BUF_DP<4>")
	)
	(segment
		(start 308.61635 -401.4978)
		(end 308.61635 -401.674838)
		(width 0.1016)
		(layer "F.Cu")
		(net "P5E_CPU0_P0_RX_BUF_DP<4>")
	)
	(segment
		(start 308.002432 -399.74774)
		(end 308.002432 -399.870676)
		(width 0.1016)
		(layer "F.Cu")
		(net "P5E_CPU0_P0_RX_BUF_DP<4>")
	)
	(segment
		(start 307.913786 -399.959322)
		(end 307.913786 -401.105878)
		(width 0.1016)
		(layer "F.Cu")
		(net "P5E_CPU0_P0_RX_BUF_DP<4>")
	)
	(segment
		(start 308.477666 -401.359116)
		(end 308.61635 -401.4978)
		(width 0.1016)
		(layer "F.Cu")
		(net "P5E_CPU0_P0_RX_BUF_DP<4>")
	)
	(segment
		(start 308.002432 -399.870676)
		(end 307.913786 -399.959322)
		(width 0.1016)
		(layer "F.Cu")
		(net "P5E_CPU0_P0_RX_BUF_DP<4>")
	)
	(segment
		(start 315.345318 -413.927036)
		(end 315.416946 -413.956754)
		(width 0.14224)
		(layer "In15.Cu")
		(net "P5E_CPU0_P0_RX_BUF_DP<4>")
	)
	(segment
		(start 318.585596 -422.197784)
		(end 319.249552 -422.640252)
		(width 0.14224)
		(layer "In15.Cu")
		(net "P5E_CPU0_P0_RX_BUF_DP<4>")
	)
	(segment
		(start 319.82918 -423.026586)
		(end 321.38239 -424.064176)
		(width 0.14224)
		(layer "In15.Cu")
		(net "P5E_CPU0_P0_RX_BUF_DP<4>")
	)
	(segment
		(start 315.088016 -412.376874)
		(end 315.088016 -413.566864)
		(width 0.14224)
		(layer "In15.Cu")
		(net "P5E_CPU0_P0_RX_BUF_DP<4>")
	)
	(segment
		(start 317.581788 -419.671246)
		(end 318.031114 -420.119556)
		(width 0.14224)
		(layer "In15.Cu")
		(net "P5E_CPU0_P0_RX_BUF_DP<4>")
	)
	(segment
		(start 308.954932 -407.387806)
		(end 308.954932 -407.581862)
		(width 0.14224)
		(layer "In15.Cu")
		(net "P5E_CPU0_P0_RX_BUF_DP<4>")
	)
	(segment
		(start 315.16066 -413.742378)
		(end 315.345318 -413.927036)
		(width 0.14224)
		(layer "In15.Cu")
		(net "P5E_CPU0_P0_RX_BUF_DP<4>")
	)
	(segment
		(start 321.970908 -425.13504)
		(end 321.970908 -437.137302)
		(width 0.14224)
		(layer "In15.Cu")
		(net "P5E_CPU0_P0_RX_BUF_DP<4>")
	)
	(segment
		(start 308.206902 -406.833832)
		(end 308.45887 -407.0858)
		(width 0.14224)
		(layer "In15.Cu")
		(net "P5E_CPU0_P0_RX_BUF_DP<4>")
	)
	(segment
		(start 321.970908 -437.137302)
		(end 322.17487 -437.341264)
		(width 0.14224)
		(layer "In15.Cu")
		(net "P5E_CPU0_P0_RX_BUF_DP<4>")
	)
	(segment
		(start 308.294532 -403.988524)
		(end 308.294532 -404.415244)
		(width 0.14224)
		(layer "In15.Cu")
		(net "P5E_CPU0_P0_RX_BUF_DP<4>")
	)
	(segment
		(start 322.17487 -437.341264)
		(end 322.499482 -437.341264)
		(width 0.14224)
		(layer "In15.Cu")
		(net "P5E_CPU0_P0_RX_BUF_DP<4>")
	)
	(segment
		(start 321.38239 -424.064176)
		(end 321.624198 -424.305984)
		(width 0.14224)
		(layer "In15.Cu")
		(net "P5E_CPU0_P0_RX_BUF_DP<4>")
	)
	(segment
		(start 308.476904 -401.371562)
		(end 308.296818 -401.371562)
		(width 0.14224)
		(layer "In15.Cu")
		(net "P5E_CPU0_P0_RX_BUF_DP<4>")
	)
	(segment
		(start 315.416946 -413.956754)
		(end 315.891164 -413.956754)
		(width 0.14224)
		(layer "In15.Cu")
		(net "P5E_CPU0_P0_RX_BUF_DP<4>")
	)
	(segment
		(start 309.450486 -407.88336)
		(end 309.752492 -408.185366)
		(width 0.14224)
		(layer "In15.Cu")
		(net "P5E_CPU0_P0_RX_BUF_DP<4>")
	)
	(segment
		(start 308.294532 -404.415244)
		(end 308.157372 -404.552404)
		(width 0.14224)
		(layer "In15.Cu")
		(net "P5E_CPU0_P0_RX_BUF_DP<4>")
	)
	(segment
		(start 308.294532 -403.287484)
		(end 308.157372 -403.424644)
		(width 0.14224)
		(layer "In15.Cu")
		(net "P5E_CPU0_P0_RX_BUF_DP<4>")
	)
	(segment
		(start 319.436242 -422.602914)
		(end 319.791588 -422.839896)
		(width 0.14224)
		(layer "In15.Cu")
		(net "P5E_CPU0_P0_RX_BUF_DP<4>")
	)
	(segment
		(start 316.756796 -417.159694)
		(end 316.619636 -417.296854)
		(width 0.14224)
		(layer "In15.Cu")
		(net "P5E_CPU0_P0_RX_BUF_DP<4>")
	)
	(segment
		(start 316.756796 -416.732974)
		(end 316.756796 -417.159694)
		(width 0.14224)
		(layer "In15.Cu")
		(net "P5E_CPU0_P0_RX_BUF_DP<4>")
	)
	(segment
		(start 316.619636 -416.595814)
		(end 316.756796 -416.732974)
		(width 0.14224)
		(layer "In15.Cu")
		(net "P5E_CPU0_P0_RX_BUF_DP<4>")
	)
	(segment
		(start 317.11519 -419.425628)
		(end 317.374016 -419.532816)
		(width 0.14224)
		(layer "In15.Cu")
		(net "P5E_CPU0_P0_RX_BUF_DP<4>")
	)
	(segment
		(start 309.25643 -407.88336)
		(end 309.450486 -407.88336)
		(width 0.14224)
		(layer "In15.Cu")
		(net "P5E_CPU0_P0_RX_BUF_DP<4>")
	)
	(segment
		(start 311.370218 -409.997148)
		(end 312.507376 -411.134306)
		(width 0.14224)
		(layer "In15.Cu")
		(net "P5E_CPU0_P0_RX_BUF_DP<4>")
	)
	(segment
		(start 308.157372 -405.680164)
		(end 308.157372 -406.714198)
		(width 0.14224)
		(layer "In15.Cu")
		(net "P5E_CPU0_P0_RX_BUF_DP<4>")
	)
	(segment
		(start 308.61635 -401.674838)
		(end 308.61635 -401.511008)
		(width 0.14224)
		(layer "In15.Cu")
		(net "P5E_CPU0_P0_RX_BUF_DP<4>")
	)
	(segment
		(start 315.891164 -413.956754)
		(end 316.1284 -414.055052)
		(width 0.14224)
		(layer "In15.Cu")
		(net "P5E_CPU0_P0_RX_BUF_DP<4>")
	)
	(segment
		(start 310.550052 -408.982926)
		(end 310.550052 -409.176982)
		(width 0.14224)
		(layer "In15.Cu")
		(net "P5E_CPU0_P0_RX_BUF_DP<4>")
	)
	(segment
		(start 308.652926 -407.0858)
		(end 308.954932 -407.387806)
		(width 0.14224)
		(layer "In15.Cu")
		(net "P5E_CPU0_P0_RX_BUF_DP<4>")
	)
	(segment
		(start 322.499482 -437.341264)
		(end 322.649596 -437.19115)
		(width 0.14224)
		(layer "In15.Cu")
		(net "P5E_CPU0_P0_RX_BUF_DP<4>")
	)
	(segment
		(start 322.649596 -437.19115)
		(end 322.649596 -436.889906)
		(width 0.14224)
		(layer "In15.Cu")
		(net "P5E_CPU0_P0_RX_BUF_DP<4>")
	)
	(segment
		(start 311.370218 -409.803092)
		(end 311.370218 -409.997148)
		(width 0.14224)
		(layer "In15.Cu")
		(net "P5E_CPU0_P0_RX_BUF_DP<4>")
	)
	(segment
		(start 308.45887 -407.0858)
		(end 308.652926 -407.0858)
		(width 0.14224)
		(layer "In15.Cu")
		(net "P5E_CPU0_P0_RX_BUF_DP<4>")
	)
	(segment
		(start 310.550052 -409.176982)
		(end 310.874156 -409.501086)
		(width 0.14224)
		(layer "In15.Cu")
		(net "P5E_CPU0_P0_RX_BUF_DP<4>")
	)
	(segment
		(start 311.068212 -409.501086)
		(end 311.370218 -409.803092)
		(width 0.14224)
		(layer "In15.Cu")
		(net "P5E_CPU0_P0_RX_BUF_DP<4>")
	)
	(segment
		(start 316.1284 -414.055052)
		(end 316.435232 -414.361884)
		(width 0.14224)
		(layer "In15.Cu")
		(net "P5E_CPU0_P0_RX_BUF_DP<4>")
	)
	(segment
		(start 309.752492 -408.185366)
		(end 309.752492 -408.379422)
		(width 0.14224)
		(layer "In15.Cu")
		(net "P5E_CPU0_P0_RX_BUF_DP<4>")
	)
	(segment
		(start 319.249552 -422.640252)
		(end 319.436242 -422.602914)
		(width 0.14224)
		(layer "In15.Cu")
		(net "P5E_CPU0_P0_RX_BUF_DP<4>")
	)
	(segment
		(start 316.619636 -414.806892)
		(end 316.619636 -416.595814)
		(width 0.14224)
		(layer "In15.Cu")
		(net "P5E_CPU0_P0_RX_BUF_DP<4>")
	)
	(segment
		(start 308.296818 -401.371562)
		(end 308.157372 -401.511008)
		(width 0.14224)
		(layer "In15.Cu")
		(net "P5E_CPU0_P0_RX_BUF_DP<4>")
	)
	(segment
		(start 308.157372 -404.979124)
		(end 308.294532 -405.116284)
		(width 0.14224)
		(layer "In15.Cu")
		(net "P5E_CPU0_P0_RX_BUF_DP<4>")
	)
	(segment
		(start 319.791588 -422.839896)
		(end 319.82918 -423.026586)
		(width 0.14224)
		(layer "In15.Cu")
		(net "P5E_CPU0_P0_RX_BUF_DP<4>")
	)
	(segment
		(start 318.151256 -420.409116)
		(end 318.151256 -421.322246)
		(width 0.14224)
		(layer "In15.Cu")
		(net "P5E_CPU0_P0_RX_BUF_DP<4>")
	)
	(segment
		(start 308.294532 -405.543004)
		(end 308.157372 -405.680164)
		(width 0.14224)
		(layer "In15.Cu")
		(net "P5E_CPU0_P0_RX_BUF_DP<4>")
	)
	(segment
		(start 308.294532 -405.116284)
		(end 308.294532 -405.543004)
		(width 0.14224)
		(layer "In15.Cu")
		(net "P5E_CPU0_P0_RX_BUF_DP<4>")
	)
	(segment
		(start 321.93484 -424.85564)
		(end 321.93484 -424.856148)
		(width 0.14224)
		(layer "In15.Cu")
		(net "P5E_CPU0_P0_RX_BUF_DP<4>")
	)
	(segment
		(start 316.435232 -414.361884)
		(end 316.619636 -414.806892)
		(width 0.14224)
		(layer "In15.Cu")
		(net "P5E_CPU0_P0_RX_BUF_DP<4>")
	)
	(segment
		(start 315.088016 -413.566864)
		(end 315.16066 -413.742378)
		(width 0.14224)
		(layer "In15.Cu")
		(net "P5E_CPU0_P0_RX_BUF_DP<4>")
	)
	(segment
		(start 318.169544 -421.44696)
		(end 318.252094 -421.720264)
		(width 0.14224)
		(layer "In15.Cu")
		(net "P5E_CPU0_P0_RX_BUF_DP<4>")
	)
	(segment
		(start 310.248046 -408.68092)
		(end 310.550052 -408.982926)
		(width 0.14224)
		(layer "In15.Cu")
		(net "P5E_CPU0_P0_RX_BUF_DP<4>")
	)
	(segment
		(start 316.619636 -417.296854)
		(end 316.619636 -418.62756)
		(width 0.14224)
		(layer "In15.Cu")
		(net "P5E_CPU0_P0_RX_BUF_DP<4>")
	)
	(segment
		(start 308.61635 -401.511008)
		(end 308.476904 -401.371562)
		(width 0.14224)
		(layer "In15.Cu")
		(net "P5E_CPU0_P0_RX_BUF_DP<4>")
	)
	(segment
		(start 308.157372 -403.851364)
		(end 308.294532 -403.988524)
		(width 0.14224)
		(layer "In15.Cu")
		(net "P5E_CPU0_P0_RX_BUF_DP<4>")
	)
	(segment
		(start 310.874156 -409.501086)
		(end 311.068212 -409.501086)
		(width 0.14224)
		(layer "In15.Cu")
		(net "P5E_CPU0_P0_RX_BUF_DP<4>")
	)
	(segment
		(start 308.157372 -401.511008)
		(end 308.157372 -402.723604)
		(width 0.14224)
		(layer "In15.Cu")
		(net "P5E_CPU0_P0_RX_BUF_DP<4>")
	)
	(segment
		(start 314.638944 -411.645862)
		(end 314.888626 -411.895544)
		(width 0.14224)
		(layer "In15.Cu")
		(net "P5E_CPU0_P0_RX_BUF_DP<4>")
	)
	(segment
		(start 308.294532 -402.860764)
		(end 308.294532 -403.287484)
		(width 0.14224)
		(layer "In15.Cu")
		(net "P5E_CPU0_P0_RX_BUF_DP<4>")
	)
	(segment
		(start 308.157372 -404.552404)
		(end 308.157372 -404.979124)
		(width 0.14224)
		(layer "In15.Cu")
		(net "P5E_CPU0_P0_RX_BUF_DP<4>")
	)
	(segment
		(start 308.157372 -402.723604)
		(end 308.294532 -402.860764)
		(width 0.14224)
		(layer "In15.Cu")
		(net "P5E_CPU0_P0_RX_BUF_DP<4>")
	)
	(segment
		(start 312.5724 -411.169104)
		(end 314.335668 -411.520132)
		(width 0.14224)
		(layer "In15.Cu")
		(net "P5E_CPU0_P0_RX_BUF_DP<4>")
	)
	(segment
		(start 316.619636 -418.62756)
		(end 316.808866 -419.083998)
		(width 0.14224)
		(layer "In15.Cu")
		(net "P5E_CPU0_P0_RX_BUF_DP<4>")
	)
	(segment
		(start 308.954932 -407.581862)
		(end 309.25643 -407.88336)
		(width 0.14224)
		(layer "In15.Cu")
		(net "P5E_CPU0_P0_RX_BUF_DP<4>")
	)
	(segment
		(start 309.752492 -408.379422)
		(end 310.05399 -408.68092)
		(width 0.14224)
		(layer "In15.Cu")
		(net "P5E_CPU0_P0_RX_BUF_DP<4>")
	)
	(segment
		(start 314.335668 -411.520132)
		(end 314.638944 -411.645862)
		(width 0.14224)
		(layer "In15.Cu")
		(net "P5E_CPU0_P0_RX_BUF_DP<4>")
	)
	(segment
		(start 310.05399 -408.68092)
		(end 310.248046 -408.68092)
		(width 0.14224)
		(layer "In15.Cu")
		(net "P5E_CPU0_P0_RX_BUF_DP<4>")
	)
	(segment
		(start 308.157372 -403.424644)
		(end 308.157372 -403.851364)
		(width 0.14224)
		(layer "In15.Cu")
		(net "P5E_CPU0_P0_RX_BUF_DP<4>")
	)
	(arc
		(start 318.151256 -421.322246)
		(mid 318.155837 -421.385272)
		(end 318.169544 -421.44696)
		(width 0.14224)
		(layer "In15.Cu")
		(net "P5E_CPU0_P0_RX_BUF_DP<4>")
	)
	(arc
		(start 318.252094 -421.720264)
		(mid 318.380853 -421.985553)
		(end 318.585596 -422.197784)
		(width 0.14224)
		(layer "In15.Cu")
		(net "P5E_CPU0_P0_RX_BUF_DP<4>")
	)
	(arc
		(start 317.374016 -419.532816)
		(mid 317.484688 -419.591842)
		(end 317.581788 -419.671246)
		(width 0.14224)
		(layer "In15.Cu")
		(net "P5E_CPU0_P0_RX_BUF_DP<4>")
	)
	(arc
		(start 318.031114 -420.119556)
		(mid 318.120044 -420.252364)
		(end 318.151256 -420.409116)
		(width 0.14224)
		(layer "In15.Cu")
		(net "P5E_CPU0_P0_RX_BUF_DP<4>")
	)
	(arc
		(start 312.507376 -411.134306)
		(mid 312.537312 -411.156516)
		(end 312.5724 -411.169104)
		(width 0.14224)
		(layer "In15.Cu")
		(net "P5E_CPU0_P0_RX_BUF_DP<4>")
	)
	(arc
		(start 314.888626 -411.895544)
		(mid 315.036184 -412.11638)
		(end 315.088016 -412.376874)
		(width 0.14224)
		(layer "In15.Cu")
		(net "P5E_CPU0_P0_RX_BUF_DP<4>")
	)
	(arc
		(start 316.808866 -419.083998)
		(mid 316.892051 -419.233081)
		(end 317.00724 -419.35908)
		(width 0.14224)
		(layer "In15.Cu")
		(net "P5E_CPU0_P0_RX_BUF_DP<4>")
	)
	(arc
		(start 317.00724 -419.35908)
		(mid 317.058531 -419.396706)
		(end 317.11519 -419.425628)
		(width 0.14224)
		(layer "In15.Cu")
		(net "P5E_CPU0_P0_RX_BUF_DP<4>")
	)
	(arc
		(start 321.624198 -424.305984)
		(mid 321.817024 -424.559614)
		(end 321.93484 -424.85564)
		(width 0.14224)
		(layer "In15.Cu")
		(net "P5E_CPU0_P0_RX_BUF_DP<4>")
	)
	(arc
		(start 321.956938 -424.963082)
		(mid 321.967446 -425.048775)
		(end 321.970908 -425.13504)
		(width 0.14224)
		(layer "In15.Cu")
		(net "P5E_CPU0_P0_RX_BUF_DP<4>")
	)
	(arc
		(start 308.157372 -406.714198)
		(mid 308.170249 -406.778934)
		(end 308.206902 -406.833832)
		(width 0.14224)
		(layer "In15.Cu")
		(net "P5E_CPU0_P0_RX_BUF_DP<4>")
	)
	(arc
		(start 321.93484 -424.856148)
		(mid 321.946934 -424.909399)
		(end 321.956938 -424.963082)
		(width 0.14224)
		(layer "In15.Cu")
		(net "P5E_CPU0_P0_RX_BUF_DP<4>")
	)
	(segment
		(start 306.726844 -399.946114)
		(end 306.726844 -401.105878)
		(width 0.1016)
		(layer "F.Cu")
		(net "P5E_CPU0_P0_RX_BUF_DP<3>")
	)
	(segment
		(start 306.7177 -399.663158)
		(end 306.802282 -399.74774)
		(width 0.1016)
		(layer "F.Cu")
		(net "P5E_CPU0_P0_RX_BUF_DP<3>")
	)
	(segment
		(start 306.980082 -401.359116)
		(end 307.277516 -401.359116)
		(width 0.1016)
		(layer "F.Cu")
		(net "P5E_CPU0_P0_RX_BUF_DP<3>")
	)
	(segment
		(start 307.277516 -401.359116)
		(end 307.4162 -401.4978)
		(width 0.1016)
		(layer "F.Cu")
		(net "P5E_CPU0_P0_RX_BUF_DP<3>")
	)
	(segment
		(start 306.726844 -401.105878)
		(end 306.980082 -401.359116)
		(width 0.1016)
		(layer "F.Cu")
		(net "P5E_CPU0_P0_RX_BUF_DP<3>")
	)
	(segment
		(start 307.4162 -401.4978)
		(end 307.4162 -401.674838)
		(width 0.1016)
		(layer "F.Cu")
		(net "P5E_CPU0_P0_RX_BUF_DP<3>")
	)
	(segment
		(start 306.802282 -399.74774)
		(end 306.802282 -399.870676)
		(width 0.1016)
		(layer "F.Cu")
		(net "P5E_CPU0_P0_RX_BUF_DP<3>")
	)
	(segment
		(start 306.802282 -399.870676)
		(end 306.726844 -399.946114)
		(width 0.1016)
		(layer "F.Cu")
		(net "P5E_CPU0_P0_RX_BUF_DP<3>")
	)
	(segment
		(start 320.499486 -438.341262)
		(end 320.6496 -438.191148)
		(width 0.14224)
		(layer "In15.Cu")
		(net "P5E_CPU0_P0_RX_BUF_DP<3>")
	)
	(segment
		(start 313.038236 -414.028128)
		(end 313.371992 -414.361884)
		(width 0.14224)
		(layer "In15.Cu")
		(net "P5E_CPU0_P0_RX_BUF_DP<3>")
	)
	(segment
		(start 314.230258 -419.518338)
		(end 314.45454 -419.610794)
		(width 0.14224)
		(layer "In15.Cu")
		(net "P5E_CPU0_P0_RX_BUF_DP<3>")
	)
	(segment
		(start 309.845456 -409.807918)
		(end 310.147462 -410.109924)
		(width 0.14224)
		(layer "In15.Cu")
		(net "P5E_CPU0_P0_RX_BUF_DP<3>")
	)
	(segment
		(start 308.250336 -408.212798)
		(end 308.552342 -408.514804)
		(width 0.14224)
		(layer "In15.Cu")
		(net "P5E_CPU0_P0_RX_BUF_DP<3>")
	)
	(segment
		(start 315.264292 -421.66921)
		(end 315.529214 -421.934132)
		(width 0.14224)
		(layer "In15.Cu")
		(net "P5E_CPU0_P0_RX_BUF_DP<3>")
	)
	(segment
		(start 314.45454 -419.610794)
		(end 314.968128 -420.124636)
		(width 0.14224)
		(layer "In15.Cu")
		(net "P5E_CPU0_P0_RX_BUF_DP<3>")
	)
	(segment
		(start 312.09742 -413.742378)
		(end 312.282078 -413.927036)
		(width 0.14224)
		(layer "In15.Cu")
		(net "P5E_CPU0_P0_RX_BUF_DP<3>")
	)
	(segment
		(start 306.957222 -405.711406)
		(end 306.957222 -407.060908)
		(width 0.14224)
		(layer "In15.Cu")
		(net "P5E_CPU0_P0_RX_BUF_DP<3>")
	)
	(segment
		(start 307.096668 -401.371562)
		(end 306.957222 -401.511008)
		(width 0.14224)
		(layer "In15.Cu")
		(net "P5E_CPU0_P0_RX_BUF_DP<3>")
	)
	(segment
		(start 313.556396 -418.744908)
		(end 313.626754 -418.91458)
		(width 0.14224)
		(layer "In15.Cu")
		(net "P5E_CPU0_P0_RX_BUF_DP<3>")
	)
	(segment
		(start 313.371992 -414.361884)
		(end 313.556396 -414.806892)
		(width 0.14224)
		(layer "In15.Cu")
		(net "P5E_CPU0_P0_RX_BUF_DP<3>")
	)
	(segment
		(start 319.240662 -424.070526)
		(end 319.699386 -424.630088)
		(width 0.14224)
		(layer "In15.Cu")
		(net "P5E_CPU0_P0_RX_BUF_DP<3>")
	)
	(segment
		(start 315.088016 -420.413942)
		(end 315.088016 -421.24376)
		(width 0.14224)
		(layer "In15.Cu")
		(net "P5E_CPU0_P0_RX_BUF_DP<3>")
	)
	(segment
		(start 319.970912 -438.204102)
		(end 320.108072 -438.341262)
		(width 0.14224)
		(layer "In15.Cu")
		(net "P5E_CPU0_P0_RX_BUF_DP<3>")
	)
	(segment
		(start 307.094382 -404.019766)
		(end 307.094382 -404.446486)
		(width 0.14224)
		(layer "In15.Cu")
		(net "P5E_CPU0_P0_RX_BUF_DP<3>")
	)
	(segment
		(start 310.147462 -410.109924)
		(end 310.147462 -410.30398)
		(width 0.14224)
		(layer "In15.Cu")
		(net "P5E_CPU0_P0_RX_BUF_DP<3>")
	)
	(segment
		(start 313.693556 -417.345622)
		(end 313.693556 -417.772342)
		(width 0.14224)
		(layer "In15.Cu")
		(net "P5E_CPU0_P0_RX_BUF_DP<3>")
	)
	(segment
		(start 318.28105 -423.42943)
		(end 319.240662 -424.070526)
		(width 0.14224)
		(layer "In15.Cu")
		(net "P5E_CPU0_P0_RX_BUF_DP<3>")
	)
	(segment
		(start 313.556396 -416.781742)
		(end 313.556396 -417.208462)
		(width 0.14224)
		(layer "In15.Cu")
		(net "P5E_CPU0_P0_RX_BUF_DP<3>")
	)
	(segment
		(start 319.699386 -424.630088)
		(end 319.81013 -424.814492)
		(width 0.14224)
		(layer "In15.Cu")
		(net "P5E_CPU0_P0_RX_BUF_DP<3>")
	)
	(segment
		(start 307.754782 -407.717244)
		(end 307.754782 -407.9113)
		(width 0.14224)
		(layer "In15.Cu")
		(net "P5E_CPU0_P0_RX_BUF_DP<3>")
	)
	(segment
		(start 313.556396 -417.909502)
		(end 313.556396 -418.744908)
		(width 0.14224)
		(layer "In15.Cu")
		(net "P5E_CPU0_P0_RX_BUF_DP<3>")
	)
	(segment
		(start 308.552342 -408.70886)
		(end 308.85384 -409.010358)
		(width 0.14224)
		(layer "In15.Cu")
		(net "P5E_CPU0_P0_RX_BUF_DP<3>")
	)
	(segment
		(start 309.349902 -409.312364)
		(end 309.349902 -409.50642)
		(width 0.14224)
		(layer "In15.Cu")
		(net "P5E_CPU0_P0_RX_BUF_DP<3>")
	)
	(segment
		(start 306.957222 -403.455886)
		(end 306.957222 -403.882606)
		(width 0.14224)
		(layer "In15.Cu")
		(net "P5E_CPU0_P0_RX_BUF_DP<3>")
	)
	(segment
		(start 308.85384 -409.010358)
		(end 309.047896 -409.010358)
		(width 0.14224)
		(layer "In15.Cu")
		(net "P5E_CPU0_P0_RX_BUF_DP<3>")
	)
	(segment
		(start 306.957222 -405.010366)
		(end 307.094382 -405.147526)
		(width 0.14224)
		(layer "In15.Cu")
		(net "P5E_CPU0_P0_RX_BUF_DP<3>")
	)
	(segment
		(start 307.094382 -403.318726)
		(end 306.957222 -403.455886)
		(width 0.14224)
		(layer "In15.Cu")
		(net "P5E_CPU0_P0_RX_BUF_DP<3>")
	)
	(segment
		(start 308.05628 -408.212798)
		(end 308.250336 -408.212798)
		(width 0.14224)
		(layer "In15.Cu")
		(net "P5E_CPU0_P0_RX_BUF_DP<3>")
	)
	(segment
		(start 307.094382 -405.147526)
		(end 307.094382 -405.574246)
		(width 0.14224)
		(layer "In15.Cu")
		(net "P5E_CPU0_P0_RX_BUF_DP<3>")
	)
	(segment
		(start 317.329058 -422.920668)
		(end 318.28105 -423.42943)
		(width 0.14224)
		(layer "In15.Cu")
		(net "P5E_CPU0_P0_RX_BUF_DP<3>")
	)
	(segment
		(start 310.147462 -410.30398)
		(end 311.84596 -412.002478)
		(width 0.14224)
		(layer "In15.Cu")
		(net "P5E_CPU0_P0_RX_BUF_DP<3>")
	)
	(segment
		(start 319.970912 -425.355258)
		(end 319.970912 -438.204102)
		(width 0.14224)
		(layer "In15.Cu")
		(net "P5E_CPU0_P0_RX_BUF_DP<3>")
	)
	(segment
		(start 312.024776 -413.567118)
		(end 312.09742 -413.742378)
		(width 0.14224)
		(layer "In15.Cu")
		(net "P5E_CPU0_P0_RX_BUF_DP<3>")
	)
	(segment
		(start 307.094382 -402.892006)
		(end 307.094382 -403.318726)
		(width 0.14224)
		(layer "In15.Cu")
		(net "P5E_CPU0_P0_RX_BUF_DP<3>")
	)
	(segment
		(start 320.6496 -438.191148)
		(end 320.6496 -437.889904)
		(width 0.14224)
		(layer "In15.Cu")
		(net "P5E_CPU0_P0_RX_BUF_DP<3>")
	)
	(segment
		(start 313.556396 -416.080702)
		(end 313.693556 -416.217862)
		(width 0.14224)
		(layer "In15.Cu")
		(net "P5E_CPU0_P0_RX_BUF_DP<3>")
	)
	(segment
		(start 312.353706 -413.956754)
		(end 312.866024 -413.956754)
		(width 0.14224)
		(layer "In15.Cu")
		(net "P5E_CPU0_P0_RX_BUF_DP<3>")
	)
	(segment
		(start 307.754782 -407.9113)
		(end 308.05628 -408.212798)
		(width 0.14224)
		(layer "In15.Cu")
		(net "P5E_CPU0_P0_RX_BUF_DP<3>")
	)
	(segment
		(start 306.957222 -401.511008)
		(end 306.957222 -402.754846)
		(width 0.14224)
		(layer "In15.Cu")
		(net "P5E_CPU0_P0_RX_BUF_DP<3>")
	)
	(segment
		(start 316.454536 -422.506902)
		(end 317.329058 -422.920668)
		(width 0.14224)
		(layer "In15.Cu")
		(net "P5E_CPU0_P0_RX_BUF_DP<3>")
	)
	(segment
		(start 312.024776 -412.434024)
		(end 312.024776 -413.567118)
		(width 0.14224)
		(layer "In15.Cu")
		(net "P5E_CPU0_P0_RX_BUF_DP<3>")
	)
	(segment
		(start 306.957222 -402.754846)
		(end 307.094382 -402.892006)
		(width 0.14224)
		(layer "In15.Cu")
		(net "P5E_CPU0_P0_RX_BUF_DP<3>")
	)
	(segment
		(start 307.276754 -401.371562)
		(end 307.096668 -401.371562)
		(width 0.14224)
		(layer "In15.Cu")
		(net "P5E_CPU0_P0_RX_BUF_DP<3>")
	)
	(segment
		(start 307.25872 -407.415238)
		(end 307.452776 -407.415238)
		(width 0.14224)
		(layer "In15.Cu")
		(net "P5E_CPU0_P0_RX_BUF_DP<3>")
	)
	(segment
		(start 320.108072 -438.341262)
		(end 320.499486 -438.341262)
		(width 0.14224)
		(layer "In15.Cu")
		(net "P5E_CPU0_P0_RX_BUF_DP<3>")
	)
	(segment
		(start 309.6514 -409.807918)
		(end 309.845456 -409.807918)
		(width 0.14224)
		(layer "In15.Cu")
		(net "P5E_CPU0_P0_RX_BUF_DP<3>")
	)
	(segment
		(start 313.693556 -416.644582)
		(end 313.556396 -416.781742)
		(width 0.14224)
		(layer "In15.Cu")
		(net "P5E_CPU0_P0_RX_BUF_DP<3>")
	)
	(segment
		(start 309.047896 -409.010358)
		(end 309.349902 -409.312364)
		(width 0.14224)
		(layer "In15.Cu")
		(net "P5E_CPU0_P0_RX_BUF_DP<3>")
	)
	(segment
		(start 307.094382 -404.446486)
		(end 306.957222 -404.583646)
		(width 0.14224)
		(layer "In15.Cu")
		(net "P5E_CPU0_P0_RX_BUF_DP<3>")
	)
	(segment
		(start 307.452776 -407.415238)
		(end 307.754782 -407.717244)
		(width 0.14224)
		(layer "In15.Cu")
		(net "P5E_CPU0_P0_RX_BUF_DP<3>")
	)
	(segment
		(start 313.693556 -416.217862)
		(end 313.693556 -416.644582)
		(width 0.14224)
		(layer "In15.Cu")
		(net "P5E_CPU0_P0_RX_BUF_DP<3>")
	)
	(segment
		(start 306.957222 -404.583646)
		(end 306.957222 -405.010366)
		(width 0.14224)
		(layer "In15.Cu")
		(net "P5E_CPU0_P0_RX_BUF_DP<3>")
	)
	(segment
		(start 307.4162 -401.511008)
		(end 307.276754 -401.371562)
		(width 0.14224)
		(layer "In15.Cu")
		(net "P5E_CPU0_P0_RX_BUF_DP<3>")
	)
	(segment
		(start 312.282078 -413.927036)
		(end 312.353706 -413.956754)
		(width 0.14224)
		(layer "In15.Cu")
		(net "P5E_CPU0_P0_RX_BUF_DP<3>")
	)
	(segment
		(start 306.99456 -407.151078)
		(end 307.25872 -407.415238)
		(width 0.14224)
		(layer "In15.Cu")
		(net "P5E_CPU0_P0_RX_BUF_DP<3>")
	)
	(segment
		(start 309.349902 -409.50642)
		(end 309.6514 -409.807918)
		(width 0.14224)
		(layer "In15.Cu")
		(net "P5E_CPU0_P0_RX_BUF_DP<3>")
	)
	(segment
		(start 313.693556 -417.772342)
		(end 313.556396 -417.909502)
		(width 0.14224)
		(layer "In15.Cu")
		(net "P5E_CPU0_P0_RX_BUF_DP<3>")
	)
	(segment
		(start 308.552342 -408.514804)
		(end 308.552342 -408.70886)
		(width 0.14224)
		(layer "In15.Cu")
		(net "P5E_CPU0_P0_RX_BUF_DP<3>")
	)
	(segment
		(start 306.957222 -403.882606)
		(end 307.094382 -404.019766)
		(width 0.14224)
		(layer "In15.Cu")
		(net "P5E_CPU0_P0_RX_BUF_DP<3>")
	)
	(segment
		(start 307.094382 -405.574246)
		(end 306.957222 -405.711406)
		(width 0.14224)
		(layer "In15.Cu")
		(net "P5E_CPU0_P0_RX_BUF_DP<3>")
	)
	(segment
		(start 316.11443 -422.325038)
		(end 316.454536 -422.506902)
		(width 0.14224)
		(layer "In15.Cu")
		(net "P5E_CPU0_P0_RX_BUF_DP<3>")
	)
	(segment
		(start 307.4162 -401.674838)
		(end 307.4162 -401.511008)
		(width 0.14224)
		(layer "In15.Cu")
		(net "P5E_CPU0_P0_RX_BUF_DP<3>")
	)
	(segment
		(start 315.529214 -421.934132)
		(end 316.11443 -422.325038)
		(width 0.14224)
		(layer "In15.Cu")
		(net "P5E_CPU0_P0_RX_BUF_DP<3>")
	)
	(segment
		(start 313.556396 -417.208462)
		(end 313.693556 -417.345622)
		(width 0.14224)
		(layer "In15.Cu")
		(net "P5E_CPU0_P0_RX_BUF_DP<3>")
	)
	(segment
		(start 312.866024 -413.956754)
		(end 313.038236 -414.028128)
		(width 0.14224)
		(layer "In15.Cu")
		(net "P5E_CPU0_P0_RX_BUF_DP<3>")
	)
	(segment
		(start 319.81013 -424.814492)
		(end 319.911984 -425.06011)
		(width 0.14224)
		(layer "In15.Cu")
		(net "P5E_CPU0_P0_RX_BUF_DP<3>")
	)
	(segment
		(start 313.556396 -414.806892)
		(end 313.556396 -416.080702)
		(width 0.14224)
		(layer "In15.Cu")
		(net "P5E_CPU0_P0_RX_BUF_DP<3>")
	)
	(arc
		(start 315.088016 -421.24376)
		(mid 315.133835 -421.474016)
		(end 315.264292 -421.66921)
		(width 0.14224)
		(layer "In15.Cu")
		(net "P5E_CPU0_P0_RX_BUF_DP<3>")
	)
	(arc
		(start 306.957222 -407.060908)
		(mid 306.966928 -407.109703)
		(end 306.99456 -407.151078)
		(width 0.14224)
		(layer "In15.Cu")
		(net "P5E_CPU0_P0_RX_BUF_DP<3>")
	)
	(arc
		(start 313.626754 -418.91458)
		(mid 313.868477 -419.276468)
		(end 314.230258 -419.518338)
		(width 0.14224)
		(layer "In15.Cu")
		(net "P5E_CPU0_P0_RX_BUF_DP<3>")
	)
	(arc
		(start 311.84596 -412.002478)
		(mid 311.97831 -412.200459)
		(end 312.024776 -412.434024)
		(width 0.14224)
		(layer "In15.Cu")
		(net "P5E_CPU0_P0_RX_BUF_DP<3>")
	)
	(arc
		(start 319.911984 -425.06011)
		(mid 319.955997 -425.204778)
		(end 319.970912 -425.355258)
		(width 0.14224)
		(layer "In15.Cu")
		(net "P5E_CPU0_P0_RX_BUF_DP<3>")
	)
	(arc
		(start 314.968128 -420.124636)
		(mid 315.056872 -420.257356)
		(end 315.088016 -420.413942)
		(width 0.14224)
		(layer "In15.Cu")
		(net "P5E_CPU0_P0_RX_BUF_DP<3>")
	)
	(segment
		(start 305.51374 -399.959322)
		(end 305.51374 -401.105878)
		(width 0.1016)
		(layer "F.Cu")
		(net "P5E_CPU0_P0_RX_BUF_DP<2>")
	)
	(segment
		(start 306.07762 -401.359116)
		(end 306.216304 -401.4978)
		(width 0.1016)
		(layer "F.Cu")
		(net "P5E_CPU0_P0_RX_BUF_DP<2>")
	)
	(segment
		(start 306.216304 -401.4978)
		(end 306.216304 -401.674838)
		(width 0.1016)
		(layer "F.Cu")
		(net "P5E_CPU0_P0_RX_BUF_DP<2>")
	)
	(segment
		(start 305.517804 -399.663158)
		(end 305.602386 -399.74774)
		(width 0.1016)
		(layer "F.Cu")
		(net "P5E_CPU0_P0_RX_BUF_DP<2>")
	)
	(segment
		(start 305.766978 -401.359116)
		(end 306.07762 -401.359116)
		(width 0.1016)
		(layer "F.Cu")
		(net "P5E_CPU0_P0_RX_BUF_DP<2>")
	)
	(segment
		(start 305.602386 -399.74774)
		(end 305.602386 -399.870676)
		(width 0.1016)
		(layer "F.Cu")
		(net "P5E_CPU0_P0_RX_BUF_DP<2>")
	)
	(segment
		(start 305.602386 -399.870676)
		(end 305.51374 -399.959322)
		(width 0.1016)
		(layer "F.Cu")
		(net "P5E_CPU0_P0_RX_BUF_DP<2>")
	)
	(segment
		(start 305.51374 -401.105878)
		(end 305.766978 -401.359116)
		(width 0.1016)
		(layer "F.Cu")
		(net "P5E_CPU0_P0_RX_BUF_DP<2>")
	)
	(segment
		(start 310.493156 -414.806892)
		(end 310.493156 -416.139122)
		(width 0.14224)
		(layer "In15.Cu")
		(net "P5E_CPU0_P0_RX_BUF_DP<2>")
	)
	(segment
		(start 317.970916 -437.137302)
		(end 318.174878 -437.341264)
		(width 0.14224)
		(layer "In15.Cu")
		(net "P5E_CPU0_P0_RX_BUF_DP<2>")
	)
	(segment
		(start 312.196734 -421.576754)
		(end 312.343038 -421.795702)
		(width 0.14224)
		(layer "In15.Cu")
		(net "P5E_CPU0_P0_RX_BUF_DP<2>")
	)
	(segment
		(start 305.757326 -407.01087)
		(end 305.757326 -407.860754)
		(width 0.14224)
		(layer "In15.Cu")
		(net "P5E_CPU0_P0_RX_BUF_DP<2>")
	)
	(segment
		(start 309.974996 -414.028128)
		(end 310.308752 -414.361884)
		(width 0.14224)
		(layer "In15.Cu")
		(net "P5E_CPU0_P0_RX_BUF_DP<2>")
	)
	(segment
		(start 310.630316 -417.404042)
		(end 310.630316 -417.830762)
		(width 0.14224)
		(layer "In15.Cu")
		(net "P5E_CPU0_P0_RX_BUF_DP<2>")
	)
	(segment
		(start 308.961536 -413.567118)
		(end 309.03418 -413.742378)
		(width 0.14224)
		(layer "In15.Cu")
		(net "P5E_CPU0_P0_RX_BUF_DP<2>")
	)
	(segment
		(start 307.211984 -409.742132)
		(end 308.780942 -411.653482)
		(width 0.14224)
		(layer "In15.Cu")
		(net "P5E_CPU0_P0_RX_BUF_DP<2>")
	)
	(segment
		(start 310.493156 -417.266882)
		(end 310.630316 -417.404042)
		(width 0.14224)
		(layer "In15.Cu")
		(net "P5E_CPU0_P0_RX_BUF_DP<2>")
	)
	(segment
		(start 305.894486 -403.06371)
		(end 305.894486 -403.49043)
		(width 0.14224)
		(layer "In15.Cu")
		(net "P5E_CPU0_P0_RX_BUF_DP<2>")
	)
	(segment
		(start 310.493156 -416.840162)
		(end 310.493156 -417.266882)
		(width 0.14224)
		(layer "In15.Cu")
		(net "P5E_CPU0_P0_RX_BUF_DP<2>")
	)
	(segment
		(start 313.474354 -422.390824)
		(end 313.645296 -422.299384)
		(width 0.14224)
		(layer "In15.Cu")
		(net "P5E_CPU0_P0_RX_BUF_DP<2>")
	)
	(segment
		(start 305.894486 -404.61819)
		(end 305.757326 -404.75535)
		(width 0.14224)
		(layer "In15.Cu")
		(net "P5E_CPU0_P0_RX_BUF_DP<2>")
	)
	(segment
		(start 310.493156 -416.139122)
		(end 310.630316 -416.276282)
		(width 0.14224)
		(layer "In15.Cu")
		(net "P5E_CPU0_P0_RX_BUF_DP<2>")
	)
	(segment
		(start 305.82616 -408.053032)
		(end 306.051712 -408.328114)
		(width 0.14224)
		(layer "In15.Cu")
		(net "P5E_CPU0_P0_RX_BUF_DP<2>")
	)
	(segment
		(start 311.394094 -419.612064)
		(end 311.904888 -420.123112)
		(width 0.14224)
		(layer "In15.Cu")
		(net "P5E_CPU0_P0_RX_BUF_DP<2>")
	)
	(segment
		(start 310.630316 -416.703002)
		(end 310.493156 -416.840162)
		(width 0.14224)
		(layer "In15.Cu")
		(net "P5E_CPU0_P0_RX_BUF_DP<2>")
	)
	(segment
		(start 310.493156 -418.729922)
		(end 310.651398 -419.111684)
		(width 0.14224)
		(layer "In15.Cu")
		(net "P5E_CPU0_P0_RX_BUF_DP<2>")
	)
	(segment
		(start 318.174878 -437.341264)
		(end 318.49949 -437.341264)
		(width 0.14224)
		(layer "In15.Cu")
		(net "P5E_CPU0_P0_RX_BUF_DP<2>")
	)
	(segment
		(start 309.03418 -413.742378)
		(end 309.218838 -413.927036)
		(width 0.14224)
		(layer "In15.Cu")
		(net "P5E_CPU0_P0_RX_BUF_DP<2>")
	)
	(segment
		(start 314.553854 -422.717722)
		(end 317.233046 -423.985436)
		(width 0.14224)
		(layer "In15.Cu")
		(net "P5E_CPU0_P0_RX_BUF_DP<2>")
	)
	(segment
		(start 307.231034 -409.549092)
		(end 307.211984 -409.742132)
		(width 0.14224)
		(layer "In15.Cu")
		(net "P5E_CPU0_P0_RX_BUF_DP<2>")
	)
	(segment
		(start 305.757326 -405.88311)
		(end 305.757326 -406.30983)
		(width 0.14224)
		(layer "In15.Cu")
		(net "P5E_CPU0_P0_RX_BUF_DP<2>")
	)
	(segment
		(start 305.757326 -405.18207)
		(end 305.894486 -405.31923)
		(width 0.14224)
		(layer "In15.Cu")
		(net "P5E_CPU0_P0_RX_BUF_DP<2>")
	)
	(segment
		(start 306.960016 -409.218892)
		(end 307.231034 -409.549092)
		(width 0.14224)
		(layer "In15.Cu")
		(net "P5E_CPU0_P0_RX_BUF_DP<2>")
	)
	(segment
		(start 312.024776 -421.161972)
		(end 312.196734 -421.576754)
		(width 0.14224)
		(layer "In15.Cu")
		(net "P5E_CPU0_P0_RX_BUF_DP<2>")
	)
	(segment
		(start 314.053982 -422.423082)
		(end 314.145676 -422.594278)
		(width 0.14224)
		(layer "In15.Cu")
		(net "P5E_CPU0_P0_RX_BUF_DP<2>")
	)
	(segment
		(start 305.757326 -403.62759)
		(end 305.757326 -404.05431)
		(width 0.14224)
		(layer "In15.Cu")
		(net "P5E_CPU0_P0_RX_BUF_DP<2>")
	)
	(segment
		(start 305.894486 -405.74595)
		(end 305.757326 -405.88311)
		(width 0.14224)
		(layer "In15.Cu")
		(net "P5E_CPU0_P0_RX_BUF_DP<2>")
	)
	(segment
		(start 309.218838 -413.927036)
		(end 309.290466 -413.956754)
		(width 0.14224)
		(layer "In15.Cu")
		(net "P5E_CPU0_P0_RX_BUF_DP<2>")
	)
	(segment
		(start 310.630316 -416.276282)
		(end 310.630316 -416.703002)
		(width 0.14224)
		(layer "In15.Cu")
		(net "P5E_CPU0_P0_RX_BUF_DP<2>")
	)
	(segment
		(start 306.244752 -408.347164)
		(end 306.515516 -408.67711)
		(width 0.14224)
		(layer "In15.Cu")
		(net "P5E_CPU0_P0_RX_BUF_DP<2>")
	)
	(segment
		(start 306.496466 -408.87015)
		(end 306.766976 -409.199842)
		(width 0.14224)
		(layer "In15.Cu")
		(net "P5E_CPU0_P0_RX_BUF_DP<2>")
	)
	(segment
		(start 317.970916 -424.871642)
		(end 317.970916 -437.137302)
		(width 0.14224)
		(layer "In15.Cu")
		(net "P5E_CPU0_P0_RX_BUF_DP<2>")
	)
	(segment
		(start 317.233046 -423.985436)
		(end 317.412624 -424.105578)
		(width 0.14224)
		(layer "In15.Cu")
		(net "P5E_CPU0_P0_RX_BUF_DP<2>")
	)
	(segment
		(start 310.630316 -417.830762)
		(end 310.493156 -417.967922)
		(width 0.14224)
		(layer "In15.Cu")
		(net "P5E_CPU0_P0_RX_BUF_DP<2>")
	)
	(segment
		(start 306.515516 -408.67711)
		(end 306.496466 -408.87015)
		(width 0.14224)
		(layer "In15.Cu")
		(net "P5E_CPU0_P0_RX_BUF_DP<2>")
	)
	(segment
		(start 305.894486 -406.44699)
		(end 305.894486 -406.87371)
		(width 0.14224)
		(layer "In15.Cu")
		(net "P5E_CPU0_P0_RX_BUF_DP<2>")
	)
	(segment
		(start 310.493156 -417.967922)
		(end 310.493156 -418.729922)
		(width 0.14224)
		(layer "In15.Cu")
		(net "P5E_CPU0_P0_RX_BUF_DP<2>")
	)
	(segment
		(start 310.981344 -419.441376)
		(end 311.394094 -419.612064)
		(width 0.14224)
		(layer "In15.Cu")
		(net "P5E_CPU0_P0_RX_BUF_DP<2>")
	)
	(segment
		(start 312.537856 -421.990774)
		(end 312.931556 -422.22674)
		(width 0.14224)
		(layer "In15.Cu")
		(net "P5E_CPU0_P0_RX_BUF_DP<2>")
	)
	(segment
		(start 306.051712 -408.328114)
		(end 306.244752 -408.347164)
		(width 0.14224)
		(layer "In15.Cu")
		(net "P5E_CPU0_P0_RX_BUF_DP<2>")
	)
	(segment
		(start 305.894486 -403.49043)
		(end 305.757326 -403.62759)
		(width 0.14224)
		(layer "In15.Cu")
		(net "P5E_CPU0_P0_RX_BUF_DP<2>")
	)
	(segment
		(start 313.645296 -422.299384)
		(end 314.053982 -422.423082)
		(width 0.14224)
		(layer "In15.Cu")
		(net "P5E_CPU0_P0_RX_BUF_DP<2>")
	)
	(segment
		(start 306.766976 -409.199842)
		(end 306.960016 -409.218892)
		(width 0.14224)
		(layer "In15.Cu")
		(net "P5E_CPU0_P0_RX_BUF_DP<2>")
	)
	(segment
		(start 305.757326 -401.511008)
		(end 305.757326 -402.92655)
		(width 0.14224)
		(layer "In15.Cu")
		(net "P5E_CPU0_P0_RX_BUF_DP<2>")
	)
	(segment
		(start 309.802784 -413.956754)
		(end 309.974996 -414.028128)
		(width 0.14224)
		(layer "In15.Cu")
		(net "P5E_CPU0_P0_RX_BUF_DP<2>")
	)
	(segment
		(start 317.412624 -424.105578)
		(end 317.824104 -424.517058)
		(width 0.14224)
		(layer "In15.Cu")
		(net "P5E_CPU0_P0_RX_BUF_DP<2>")
	)
	(segment
		(start 305.896772 -401.371562)
		(end 305.757326 -401.511008)
		(width 0.14224)
		(layer "In15.Cu")
		(net "P5E_CPU0_P0_RX_BUF_DP<2>")
	)
	(segment
		(start 305.894486 -406.87371)
		(end 305.757326 -407.01087)
		(width 0.14224)
		(layer "In15.Cu")
		(net "P5E_CPU0_P0_RX_BUF_DP<2>")
	)
	(segment
		(start 314.145676 -422.594278)
		(end 314.553854 -422.717722)
		(width 0.14224)
		(layer "In15.Cu")
		(net "P5E_CPU0_P0_RX_BUF_DP<2>")
	)
	(segment
		(start 306.216304 -401.511008)
		(end 306.076858 -401.371562)
		(width 0.14224)
		(layer "In15.Cu")
		(net "P5E_CPU0_P0_RX_BUF_DP<2>")
	)
	(segment
		(start 305.757326 -404.75535)
		(end 305.757326 -405.18207)
		(width 0.14224)
		(layer "In15.Cu")
		(net "P5E_CPU0_P0_RX_BUF_DP<2>")
	)
	(segment
		(start 308.961536 -412.15945)
		(end 308.961536 -413.567118)
		(width 0.14224)
		(layer "In15.Cu")
		(net "P5E_CPU0_P0_RX_BUF_DP<2>")
	)
	(segment
		(start 305.894486 -405.31923)
		(end 305.894486 -405.74595)
		(width 0.14224)
		(layer "In15.Cu")
		(net "P5E_CPU0_P0_RX_BUF_DP<2>")
	)
	(segment
		(start 318.49949 -437.341264)
		(end 318.649604 -437.19115)
		(width 0.14224)
		(layer "In15.Cu")
		(net "P5E_CPU0_P0_RX_BUF_DP<2>")
	)
	(segment
		(start 305.757326 -404.05431)
		(end 305.894486 -404.19147)
		(width 0.14224)
		(layer "In15.Cu")
		(net "P5E_CPU0_P0_RX_BUF_DP<2>")
	)
	(segment
		(start 306.216304 -401.674838)
		(end 306.216304 -401.511008)
		(width 0.14224)
		(layer "In15.Cu")
		(net "P5E_CPU0_P0_RX_BUF_DP<2>")
	)
	(segment
		(start 306.076858 -401.371562)
		(end 305.896772 -401.371562)
		(width 0.14224)
		(layer "In15.Cu")
		(net "P5E_CPU0_P0_RX_BUF_DP<2>")
	)
	(segment
		(start 310.308752 -414.361884)
		(end 310.493156 -414.806892)
		(width 0.14224)
		(layer "In15.Cu")
		(net "P5E_CPU0_P0_RX_BUF_DP<2>")
	)
	(segment
		(start 305.757326 -402.92655)
		(end 305.894486 -403.06371)
		(width 0.14224)
		(layer "In15.Cu")
		(net "P5E_CPU0_P0_RX_BUF_DP<2>")
	)
	(segment
		(start 305.757326 -406.30983)
		(end 305.894486 -406.44699)
		(width 0.14224)
		(layer "In15.Cu")
		(net "P5E_CPU0_P0_RX_BUF_DP<2>")
	)
	(segment
		(start 312.343038 -421.795702)
		(end 312.537856 -421.990774)
		(width 0.14224)
		(layer "In15.Cu")
		(net "P5E_CPU0_P0_RX_BUF_DP<2>")
	)
	(segment
		(start 312.931556 -422.22674)
		(end 313.474354 -422.390824)
		(width 0.14224)
		(layer "In15.Cu")
		(net "P5E_CPU0_P0_RX_BUF_DP<2>")
	)
	(segment
		(start 309.290466 -413.956754)
		(end 309.802784 -413.956754)
		(width 0.14224)
		(layer "In15.Cu")
		(net "P5E_CPU0_P0_RX_BUF_DP<2>")
	)
	(segment
		(start 305.894486 -404.19147)
		(end 305.894486 -404.61819)
		(width 0.14224)
		(layer "In15.Cu")
		(net "P5E_CPU0_P0_RX_BUF_DP<2>")
	)
	(segment
		(start 312.024776 -420.412418)
		(end 312.024776 -421.161972)
		(width 0.14224)
		(layer "In15.Cu")
		(net "P5E_CPU0_P0_RX_BUF_DP<2>")
	)
	(segment
		(start 318.649604 -437.19115)
		(end 318.649604 -436.889906)
		(width 0.14224)
		(layer "In15.Cu")
		(net "P5E_CPU0_P0_RX_BUF_DP<2>")
	)
	(arc
		(start 317.824104 -424.517058)
		(mid 317.932806 -424.679743)
		(end 317.970916 -424.871642)
		(width 0.14224)
		(layer "In15.Cu")
		(net "P5E_CPU0_P0_RX_BUF_DP<2>")
	)
	(arc
		(start 305.757326 -407.860754)
		(mid 305.77505 -407.96287)
		(end 305.82616 -408.053032)
		(width 0.14224)
		(layer "In15.Cu")
		(net "P5E_CPU0_P0_RX_BUF_DP<2>")
	)
	(arc
		(start 310.651398 -419.111684)
		(mid 310.783589 -419.309332)
		(end 310.981344 -419.441376)
		(width 0.14224)
		(layer "In15.Cu")
		(net "P5E_CPU0_P0_RX_BUF_DP<2>")
	)
	(arc
		(start 311.904888 -420.123112)
		(mid 311.993632 -420.255832)
		(end 312.024776 -420.412418)
		(width 0.14224)
		(layer "In15.Cu")
		(net "P5E_CPU0_P0_RX_BUF_DP<2>")
	)
	(arc
		(start 308.780942 -411.653482)
		(mid 308.915175 -411.890791)
		(end 308.961536 -412.15945)
		(width 0.14224)
		(layer "In15.Cu")
		(net "P5E_CPU0_P0_RX_BUF_DP<2>")
	)
	(segment
		(start 304.317654 -399.663158)
		(end 304.402236 -399.74774)
		(width 0.1016)
		(layer "F.Cu")
		(net "P5E_CPU0_P0_RX_BUF_DP<1>")
	)
	(segment
		(start 304.566828 -401.359116)
		(end 304.87747 -401.359116)
		(width 0.1016)
		(layer "F.Cu")
		(net "P5E_CPU0_P0_RX_BUF_DP<1>")
	)
	(segment
		(start 304.31359 -401.105878)
		(end 304.566828 -401.359116)
		(width 0.1016)
		(layer "F.Cu")
		(net "P5E_CPU0_P0_RX_BUF_DP<1>")
	)
	(segment
		(start 304.31359 -399.959322)
		(end 304.31359 -401.105878)
		(width 0.1016)
		(layer "F.Cu")
		(net "P5E_CPU0_P0_RX_BUF_DP<1>")
	)
	(segment
		(start 304.402236 -399.74774)
		(end 304.402236 -399.870676)
		(width 0.1016)
		(layer "F.Cu")
		(net "P5E_CPU0_P0_RX_BUF_DP<1>")
	)
	(segment
		(start 304.87747 -401.359116)
		(end 305.016154 -401.4978)
		(width 0.1016)
		(layer "F.Cu")
		(net "P5E_CPU0_P0_RX_BUF_DP<1>")
	)
	(segment
		(start 305.016154 -401.4978)
		(end 305.016154 -401.674838)
		(width 0.1016)
		(layer "F.Cu")
		(net "P5E_CPU0_P0_RX_BUF_DP<1>")
	)
	(segment
		(start 304.402236 -399.870676)
		(end 304.31359 -399.959322)
		(width 0.1016)
		(layer "F.Cu")
		(net "P5E_CPU0_P0_RX_BUF_DP<1>")
	)
	(segment
		(start 305.420522 -410.804106)
		(end 305.494944 -410.624782)
		(width 0.14224)
		(layer "In15.Cu")
		(net "P5E_CPU0_P0_RX_BUF_DP<1>")
	)
	(segment
		(start 304.694336 -406.65527)
		(end 304.694336 -406.22855)
		(width 0.14224)
		(layer "In15.Cu")
		(net "P5E_CPU0_P0_RX_BUF_DP<1>")
	)
	(segment
		(start 305.97094 -413.742378)
		(end 305.898296 -413.567118)
		(width 0.14224)
		(layer "In15.Cu")
		(net "P5E_CPU0_P0_RX_BUF_DP<1>")
	)
	(segment
		(start 307.245512 -414.361884)
		(end 306.97043 -414.086802)
		(width 0.14224)
		(layer "In15.Cu")
		(net "P5E_CPU0_P0_RX_BUF_DP<1>")
	)
	(segment
		(start 309.647844 -422.10355)
		(end 309.525924 -422.017444)
		(width 0.14224)
		(layer "In15.Cu")
		(net "P5E_CPU0_P0_RX_BUF_DP<1>")
	)
	(segment
		(start 316.649608 -438.191148)
		(end 316.503558 -438.337198)
		(width 0.14224)
		(layer "In15.Cu")
		(net "P5E_CPU0_P0_RX_BUF_DP<1>")
	)
	(segment
		(start 304.557176 -403.40915)
		(end 304.694336 -403.27199)
		(width 0.14224)
		(layer "In15.Cu")
		(net "P5E_CPU0_P0_RX_BUF_DP<1>")
	)
	(segment
		(start 304.694336 -407.35631)
		(end 304.557176 -407.21915)
		(width 0.14224)
		(layer "In15.Cu")
		(net "P5E_CPU0_P0_RX_BUF_DP<1>")
	)
	(segment
		(start 310.933338 -422.711372)
		(end 309.647844 -422.10355)
		(width 0.14224)
		(layer "In15.Cu")
		(net "P5E_CPU0_P0_RX_BUF_DP<1>")
	)
	(segment
		(start 304.694336 -405.10079)
		(end 304.557176 -404.96363)
		(width 0.14224)
		(layer "In15.Cu")
		(net "P5E_CPU0_P0_RX_BUF_DP<1>")
	)
	(segment
		(start 308.365652 -419.626542)
		(end 308.0893 -419.511988)
		(width 0.14224)
		(layer "In15.Cu")
		(net "P5E_CPU0_P0_RX_BUF_DP<1>")
	)
	(segment
		(start 304.876708 -401.371562)
		(end 305.016154 -401.511008)
		(width 0.14224)
		(layer "In15.Cu")
		(net "P5E_CPU0_P0_RX_BUF_DP<1>")
	)
	(segment
		(start 304.694336 -405.52751)
		(end 304.694336 -405.10079)
		(width 0.14224)
		(layer "In15.Cu")
		(net "P5E_CPU0_P0_RX_BUF_DP<1>")
	)
	(segment
		(start 304.557176 -403.83587)
		(end 304.557176 -403.40915)
		(width 0.14224)
		(layer "In15.Cu")
		(net "P5E_CPU0_P0_RX_BUF_DP<1>")
	)
	(segment
		(start 307.595524 -419.018466)
		(end 307.429916 -418.619686)
		(width 0.14224)
		(layer "In15.Cu")
		(net "P5E_CPU0_P0_RX_BUF_DP<1>")
	)
	(segment
		(start 306.155598 -413.927036)
		(end 305.97094 -413.742378)
		(width 0.14224)
		(layer "In15.Cu")
		(net "P5E_CPU0_P0_RX_BUF_DP<1>")
	)
	(segment
		(start 307.429916 -417.095178)
		(end 307.429916 -416.579304)
		(width 0.14224)
		(layer "In15.Cu")
		(net "P5E_CPU0_P0_RX_BUF_DP<1>")
	)
	(segment
		(start 305.898296 -413.567118)
		(end 305.898296 -412.039562)
		(width 0.14224)
		(layer "In15.Cu")
		(net "P5E_CPU0_P0_RX_BUF_DP<1>")
	)
	(segment
		(start 305.331622 -410.23032)
		(end 305.152044 -410.156152)
		(width 0.14224)
		(layer "In15.Cu")
		(net "P5E_CPU0_P0_RX_BUF_DP<1>")
	)
	(segment
		(start 304.557176 -406.79243)
		(end 304.694336 -406.65527)
		(width 0.14224)
		(layer "In15.Cu")
		(net "P5E_CPU0_P0_RX_BUF_DP<1>")
	)
	(segment
		(start 305.063144 -409.58262)
		(end 304.899822 -409.188158)
		(width 0.14224)
		(layer "In15.Cu")
		(net "P5E_CPU0_P0_RX_BUF_DP<1>")
	)
	(segment
		(start 305.494944 -410.624782)
		(end 305.331622 -410.23032)
		(width 0.14224)
		(layer "In15.Cu")
		(net "P5E_CPU0_P0_RX_BUF_DP<1>")
	)
	(segment
		(start 304.720244 -409.11399)
		(end 304.566828 -408.74315)
		(width 0.14224)
		(layer "In15.Cu")
		(net "P5E_CPU0_P0_RX_BUF_DP<1>")
	)
	(segment
		(start 304.694336 -403.27199)
		(end 304.694336 -402.84527)
		(width 0.14224)
		(layer "In15.Cu")
		(net "P5E_CPU0_P0_RX_BUF_DP<1>")
	)
	(segment
		(start 304.557176 -405.66467)
		(end 304.694336 -405.52751)
		(width 0.14224)
		(layer "In15.Cu")
		(net "P5E_CPU0_P0_RX_BUF_DP<1>")
	)
	(segment
		(start 307.567076 -416.442144)
		(end 307.567076 -416.015424)
		(width 0.14224)
		(layer "In15.Cu")
		(net "P5E_CPU0_P0_RX_BUF_DP<1>")
	)
	(segment
		(start 304.694336 -406.22855)
		(end 304.557176 -406.09139)
		(width 0.14224)
		(layer "In15.Cu")
		(net "P5E_CPU0_P0_RX_BUF_DP<1>")
	)
	(segment
		(start 306.97043 -414.086802)
		(end 306.656486 -413.956754)
		(width 0.14224)
		(layer "In15.Cu")
		(net "P5E_CPU0_P0_RX_BUF_DP<1>")
	)
	(segment
		(start 305.016154 -401.511008)
		(end 305.016154 -401.674838)
		(width 0.14224)
		(layer "In15.Cu")
		(net "P5E_CPU0_P0_RX_BUF_DP<1>")
	)
	(segment
		(start 316.649608 -437.889904)
		(end 316.649608 -438.191148)
		(width 0.14224)
		(layer "In15.Cu")
		(net "P5E_CPU0_P0_RX_BUF_DP<1>")
	)
	(segment
		(start 307.429916 -417.796218)
		(end 307.567076 -417.659058)
		(width 0.14224)
		(layer "In15.Cu")
		(net "P5E_CPU0_P0_RX_BUF_DP<1>")
	)
	(segment
		(start 304.694336 -404.39975)
		(end 304.694336 -403.97303)
		(width 0.14224)
		(layer "In15.Cu")
		(net "P5E_CPU0_P0_RX_BUF_DP<1>")
	)
	(segment
		(start 314.561474 -423.812208)
		(end 310.933338 -422.711372)
		(width 0.14224)
		(layer "In15.Cu")
		(net "P5E_CPU0_P0_RX_BUF_DP<1>")
	)
	(segment
		(start 308.841648 -420.101522)
		(end 308.365652 -419.626542)
		(width 0.14224)
		(layer "In15.Cu")
		(net "P5E_CPU0_P0_RX_BUF_DP<1>")
	)
	(segment
		(start 304.557176 -404.53691)
		(end 304.694336 -404.39975)
		(width 0.14224)
		(layer "In15.Cu")
		(net "P5E_CPU0_P0_RX_BUF_DP<1>")
	)
	(segment
		(start 306.227226 -413.956754)
		(end 306.155598 -413.927036)
		(width 0.14224)
		(layer "In15.Cu")
		(net "P5E_CPU0_P0_RX_BUF_DP<1>")
	)
	(segment
		(start 304.557176 -401.511008)
		(end 304.696622 -401.371562)
		(width 0.14224)
		(layer "In15.Cu")
		(net "P5E_CPU0_P0_RX_BUF_DP<1>")
	)
	(segment
		(start 304.557176 -402.70811)
		(end 304.557176 -401.511008)
		(width 0.14224)
		(layer "In15.Cu")
		(net "P5E_CPU0_P0_RX_BUF_DP<1>")
	)
	(segment
		(start 304.557176 -407.92019)
		(end 304.694336 -407.78303)
		(width 0.14224)
		(layer "In15.Cu")
		(net "P5E_CPU0_P0_RX_BUF_DP<1>")
	)
	(segment
		(start 304.557176 -406.09139)
		(end 304.557176 -405.66467)
		(width 0.14224)
		(layer "In15.Cu")
		(net "P5E_CPU0_P0_RX_BUF_DP<1>")
	)
	(segment
		(start 304.694336 -402.84527)
		(end 304.557176 -402.70811)
		(width 0.14224)
		(layer "In15.Cu")
		(net "P5E_CPU0_P0_RX_BUF_DP<1>")
	)
	(segment
		(start 307.567076 -416.015424)
		(end 307.429916 -415.878264)
		(width 0.14224)
		(layer "In15.Cu")
		(net "P5E_CPU0_P0_RX_BUF_DP<1>")
	)
	(segment
		(start 316.09919 -438.337198)
		(end 315.95822 -438.196228)
		(width 0.14224)
		(layer "In15.Cu")
		(net "P5E_CPU0_P0_RX_BUF_DP<1>")
	)
	(segment
		(start 307.567076 -417.232338)
		(end 307.429916 -417.095178)
		(width 0.14224)
		(layer "In15.Cu")
		(net "P5E_CPU0_P0_RX_BUF_DP<1>")
	)
	(segment
		(start 304.988976 -409.761944)
		(end 305.063144 -409.58262)
		(width 0.14224)
		(layer "In15.Cu")
		(net "P5E_CPU0_P0_RX_BUF_DP<1>")
	)
	(segment
		(start 307.567076 -417.659058)
		(end 307.567076 -417.232338)
		(width 0.14224)
		(layer "In15.Cu")
		(net "P5E_CPU0_P0_RX_BUF_DP<1>")
	)
	(segment
		(start 305.152044 -410.156152)
		(end 304.988976 -409.761944)
		(width 0.14224)
		(layer "In15.Cu")
		(net "P5E_CPU0_P0_RX_BUF_DP<1>")
	)
	(segment
		(start 304.899822 -409.188158)
		(end 304.720244 -409.11399)
		(width 0.14224)
		(layer "In15.Cu")
		(net "P5E_CPU0_P0_RX_BUF_DP<1>")
	)
	(segment
		(start 307.429916 -414.806892)
		(end 307.245512 -414.361884)
		(width 0.14224)
		(layer "In15.Cu")
		(net "P5E_CPU0_P0_RX_BUF_DP<1>")
	)
	(segment
		(start 306.656486 -413.956754)
		(end 306.227226 -413.956754)
		(width 0.14224)
		(layer "In15.Cu")
		(net "P5E_CPU0_P0_RX_BUF_DP<1>")
	)
	(segment
		(start 304.557176 -407.21915)
		(end 304.557176 -406.79243)
		(width 0.14224)
		(layer "In15.Cu")
		(net "P5E_CPU0_P0_RX_BUF_DP<1>")
	)
	(segment
		(start 315.679328 -424.274234)
		(end 314.561474 -423.812208)
		(width 0.14224)
		(layer "In15.Cu")
		(net "P5E_CPU0_P0_RX_BUF_DP<1>")
	)
	(segment
		(start 316.503558 -438.337198)
		(end 316.09919 -438.337198)
		(width 0.14224)
		(layer "In15.Cu")
		(net "P5E_CPU0_P0_RX_BUF_DP<1>")
	)
	(segment
		(start 307.429916 -415.878264)
		(end 307.429916 -414.806892)
		(width 0.14224)
		(layer "In15.Cu")
		(net "P5E_CPU0_P0_RX_BUF_DP<1>")
	)
	(segment
		(start 304.694336 -403.97303)
		(end 304.557176 -403.83587)
		(width 0.14224)
		(layer "In15.Cu")
		(net "P5E_CPU0_P0_RX_BUF_DP<1>")
	)
	(segment
		(start 308.961536 -421.37584)
		(end 308.961536 -420.391336)
		(width 0.14224)
		(layer "In15.Cu")
		(net "P5E_CPU0_P0_RX_BUF_DP<1>")
	)
	(segment
		(start 304.557176 -408.694382)
		(end 304.557176 -407.92019)
		(width 0.14224)
		(layer "In15.Cu")
		(net "P5E_CPU0_P0_RX_BUF_DP<1>")
	)
	(segment
		(start 309.525924 -422.017444)
		(end 309.089552 -421.650414)
		(width 0.14224)
		(layer "In15.Cu")
		(net "P5E_CPU0_P0_RX_BUF_DP<1>")
	)
	(segment
		(start 304.694336 -407.78303)
		(end 304.694336 -407.35631)
		(width 0.14224)
		(layer "In15.Cu")
		(net "P5E_CPU0_P0_RX_BUF_DP<1>")
	)
	(segment
		(start 307.429916 -418.619686)
		(end 307.429916 -417.796218)
		(width 0.14224)
		(layer "In15.Cu")
		(net "P5E_CPU0_P0_RX_BUF_DP<1>")
	)
	(segment
		(start 315.95822 -438.196228)
		(end 315.95822 -424.691048)
		(width 0.14224)
		(layer "In15.Cu")
		(net "P5E_CPU0_P0_RX_BUF_DP<1>")
	)
	(segment
		(start 304.696622 -401.371562)
		(end 304.876708 -401.371562)
		(width 0.14224)
		(layer "In15.Cu")
		(net "P5E_CPU0_P0_RX_BUF_DP<1>")
	)
	(segment
		(start 307.429916 -416.579304)
		(end 307.567076 -416.442144)
		(width 0.14224)
		(layer "In15.Cu")
		(net "P5E_CPU0_P0_RX_BUF_DP<1>")
	)
	(segment
		(start 305.867308 -411.882844)
		(end 305.420522 -410.804106)
		(width 0.14224)
		(layer "In15.Cu")
		(net "P5E_CPU0_P0_RX_BUF_DP<1>")
	)
	(segment
		(start 304.557176 -404.96363)
		(end 304.557176 -404.53691)
		(width 0.14224)
		(layer "In15.Cu")
		(net "P5E_CPU0_P0_RX_BUF_DP<1>")
	)
	(arc
		(start 315.95822 -424.691048)
		(mid 315.882008 -424.440324)
		(end 315.679328 -424.274234)
		(width 0.14224)
		(layer "In15.Cu")
		(net "P5E_CPU0_P0_RX_BUF_DP<1>")
	)
	(arc
		(start 307.90642 -419.410134)
		(mid 307.723617 -419.236012)
		(end 307.595524 -419.018466)
		(width 0.14224)
		(layer "In15.Cu")
		(net "P5E_CPU0_P0_RX_BUF_DP<1>")
	)
	(arc
		(start 308.961536 -420.391336)
		(mid 308.930432 -420.234496)
		(end 308.841648 -420.101522)
		(width 0.14224)
		(layer "In15.Cu")
		(net "P5E_CPU0_P0_RX_BUF_DP<1>")
	)
	(arc
		(start 309.089552 -421.650414)
		(mid 308.995135 -421.5273)
		(end 308.961536 -421.37584)
		(width 0.14224)
		(layer "In15.Cu")
		(net "P5E_CPU0_P0_RX_BUF_DP<1>")
	)
	(arc
		(start 304.566828 -408.74315)
		(mid 304.559583 -408.719243)
		(end 304.557176 -408.694382)
		(width 0.14224)
		(layer "In15.Cu")
		(net "P5E_CPU0_P0_RX_BUF_DP<1>")
	)
	(arc
		(start 305.898296 -412.039562)
		(mid 305.890533 -411.959673)
		(end 305.867308 -411.882844)
		(width 0.14224)
		(layer "In15.Cu")
		(net "P5E_CPU0_P0_RX_BUF_DP<1>")
	)
	(arc
		(start 308.0893 -419.511988)
		(mid 307.994933 -419.466318)
		(end 307.90642 -419.410134)
		(width 0.14224)
		(layer "In15.Cu")
		(net "P5E_CPU0_P0_RX_BUF_DP<1>")
	)
	(segment
		(start 321.117722 -399.663158)
		(end 321.202304 -399.74774)
		(width 0.1016)
		(layer "F.Cu")
		(net "P5E_CPU0_P0_RX_BUF_DP<15>")
	)
	(segment
		(start 321.366896 -401.359116)
		(end 321.661028 -401.359116)
		(width 0.1016)
		(layer "F.Cu")
		(net "P5E_CPU0_P0_RX_BUF_DP<15>")
	)
	(segment
		(start 321.113658 -399.959322)
		(end 321.113658 -401.105878)
		(width 0.1016)
		(layer "F.Cu")
		(net "P5E_CPU0_P0_RX_BUF_DP<15>")
	)
	(segment
		(start 321.202304 -399.870676)
		(end 321.113658 -399.959322)
		(width 0.1016)
		(layer "F.Cu")
		(net "P5E_CPU0_P0_RX_BUF_DP<15>")
	)
	(segment
		(start 321.202304 -399.74774)
		(end 321.202304 -399.870676)
		(width 0.1016)
		(layer "F.Cu")
		(net "P5E_CPU0_P0_RX_BUF_DP<15>")
	)
	(segment
		(start 321.113658 -401.105878)
		(end 321.366896 -401.359116)
		(width 0.1016)
		(layer "F.Cu")
		(net "P5E_CPU0_P0_RX_BUF_DP<15>")
	)
	(segment
		(start 321.816222 -401.51431)
		(end 321.816222 -401.674838)
		(width 0.1016)
		(layer "F.Cu")
		(net "P5E_CPU0_P0_RX_BUF_DP<15>")
	)
	(segment
		(start 321.661028 -401.359116)
		(end 321.816222 -401.51431)
		(width 0.1016)
		(layer "F.Cu")
		(net "P5E_CPU0_P0_RX_BUF_DP<15>")
	)
	(segment
		(start 345.49969 -438.341262)
		(end 345.108276 -438.341262)
		(width 0.14224)
		(layer "In15.Cu")
		(net "P5E_CPU0_P0_RX_BUF_DP<15>")
	)
	(segment
		(start 350.452436 -416.406584)
		(end 350.452436 -415.979864)
		(width 0.14224)
		(layer "In15.Cu")
		(net "P5E_CPU0_P0_RX_BUF_DP<15>")
	)
	(segment
		(start 348.40926 -423.434764)
		(end 348.5007 -423.263568)
		(width 0.14224)
		(layer "In15.Cu")
		(net "P5E_CPU0_P0_RX_BUF_DP<15>")
	)
	(segment
		(start 330.808838 -403.874478)
		(end 330.658978 -403.997414)
		(width 0.14224)
		(layer "In15.Cu")
		(net "P5E_CPU0_P0_RX_BUF_DP<15>")
	)
	(segment
		(start 350.130872 -414.361884)
		(end 349.797116 -414.028128)
		(width 0.14224)
		(layer "In15.Cu")
		(net "P5E_CPU0_P0_RX_BUF_DP<15>")
	)
	(segment
		(start 321.49669 -401.371562)
		(end 321.676776 -401.371562)
		(width 0.14224)
		(layer "In15.Cu")
		(net "P5E_CPU0_P0_RX_BUF_DP<15>")
	)
	(segment
		(start 336.829908 -404.994872)
		(end 335.52257 -404.598378)
		(width 0.14224)
		(layer "In15.Cu")
		(net "P5E_CPU0_P0_RX_BUF_DP<15>")
	)
	(segment
		(start 350.452436 -415.979864)
		(end 350.315276 -415.842704)
		(width 0.14224)
		(layer "In15.Cu")
		(net "P5E_CPU0_P0_RX_BUF_DP<15>")
	)
	(segment
		(start 321.816222 -401.511008)
		(end 321.816222 -401.674838)
		(width 0.14224)
		(layer "In15.Cu")
		(net "P5E_CPU0_P0_RX_BUF_DP<15>")
	)
	(segment
		(start 321.357244 -402.554694)
		(end 321.357244 -401.511008)
		(width 0.14224)
		(layer "In15.Cu")
		(net "P5E_CPU0_P0_RX_BUF_DP<15>")
	)
	(segment
		(start 348.784672 -413.506158)
		(end 348.783402 -412.356554)
		(width 0.14224)
		(layer "In15.Cu")
		(net "P5E_CPU0_P0_RX_BUF_DP<15>")
	)
	(segment
		(start 328.883518 -403.68474)
		(end 328.458576 -403.64283)
		(width 0.14224)
		(layer "In15.Cu")
		(net "P5E_CPU0_P0_RX_BUF_DP<15>")
	)
	(segment
		(start 351.17024 -419.593268)
		(end 350.729804 -419.410642)
		(width 0.14224)
		(layer "In15.Cu")
		(net "P5E_CPU0_P0_RX_BUF_DP<15>")
	)
	(segment
		(start 349.488506 -423.107612)
		(end 349.579946 -422.936162)
		(width 0.14224)
		(layer "In15.Cu")
		(net "P5E_CPU0_P0_RX_BUF_DP<15>")
	)
	(segment
		(start 346.342208 -423.91838)
		(end 346.750386 -423.794682)
		(width 0.14224)
		(layer "In15.Cu")
		(net "P5E_CPU0_P0_RX_BUF_DP<15>")
	)
	(segment
		(start 331.23378 -403.916388)
		(end 330.808838 -403.874478)
		(width 0.14224)
		(layer "In15.Cu")
		(net "P5E_CPU0_P0_RX_BUF_DP<15>")
	)
	(segment
		(start 346.921582 -423.886122)
		(end 347.330014 -423.76217)
		(width 0.14224)
		(layer "In15.Cu")
		(net "P5E_CPU0_P0_RX_BUF_DP<15>")
	)
	(segment
		(start 348.4245 -411.695646)
		(end 340.949788 -406.701498)
		(width 0.14224)
		(layer "In15.Cu")
		(net "P5E_CPU0_P0_RX_BUF_DP<15>")
	)
	(segment
		(start 328.458576 -403.64283)
		(end 328.308716 -403.76602)
		(width 0.14224)
		(layer "In15.Cu")
		(net "P5E_CPU0_P0_RX_BUF_DP<15>")
	)
	(segment
		(start 349.579946 -422.936162)
		(end 350.129856 -422.769538)
		(width 0.14224)
		(layer "In15.Cu")
		(net "P5E_CPU0_P0_RX_BUF_DP<15>")
	)
	(segment
		(start 350.315276 -418.662104)
		(end 350.315276 -417.671504)
		(width 0.14224)
		(layer "In15.Cu")
		(net "P5E_CPU0_P0_RX_BUF_DP<15>")
	)
	(segment
		(start 349.797116 -414.028128)
		(end 349.624904 -413.956754)
		(width 0.14224)
		(layer "In15.Cu")
		(net "P5E_CPU0_P0_RX_BUF_DP<15>")
	)
	(segment
		(start 350.922336 -422.44137)
		(end 351.069656 -422.36263)
		(width 0.14224)
		(layer "In15.Cu")
		(net "P5E_CPU0_P0_RX_BUF_DP<15>")
	)
	(segment
		(start 345.649804 -437.889904)
		(end 345.649804 -438.191148)
		(width 0.14224)
		(layer "In15.Cu")
		(net "P5E_CPU0_P0_RX_BUF_DP<15>")
	)
	(segment
		(start 335.52257 -404.598378)
		(end 334.31353 -404.35784)
		(width 0.14224)
		(layer "In15.Cu")
		(net "P5E_CPU0_P0_RX_BUF_DP<15>")
	)
	(segment
		(start 330.129134 -403.945344)
		(end 330.005944 -403.79523)
		(width 0.14224)
		(layer "In15.Cu")
		(net "P5E_CPU0_P0_RX_BUF_DP<15>")
	)
	(segment
		(start 349.040958 -413.927036)
		(end 348.901512 -413.78759)
		(width 0.14224)
		(layer "In15.Cu")
		(net "P5E_CPU0_P0_RX_BUF_DP<15>")
	)
	(segment
		(start 331.35697 -404.066502)
		(end 331.23378 -403.916388)
		(width 0.14224)
		(layer "In15.Cu")
		(net "P5E_CPU0_P0_RX_BUF_DP<15>")
	)
	(segment
		(start 349.080074 -423.23131)
		(end 349.488506 -423.107612)
		(width 0.14224)
		(layer "In15.Cu")
		(net "P5E_CPU0_P0_RX_BUF_DP<15>")
	)
	(segment
		(start 321.4497 -402.679154)
		(end 321.357244 -402.554694)
		(width 0.14224)
		(layer "In15.Cu")
		(net "P5E_CPU0_P0_RX_BUF_DP<15>")
	)
	(segment
		(start 328.308716 -403.76602)
		(end 323.272404 -403.270212)
		(width 0.14224)
		(layer "In15.Cu")
		(net "P5E_CPU0_P0_RX_BUF_DP<15>")
	)
	(segment
		(start 330.005944 -403.79523)
		(end 329.581002 -403.75332)
		(width 0.14224)
		(layer "In15.Cu")
		(net "P5E_CPU0_P0_RX_BUF_DP<15>")
	)
	(segment
		(start 348.000828 -423.558716)
		(end 348.40926 -423.434764)
		(width 0.14224)
		(layer "In15.Cu")
		(net "P5E_CPU0_P0_RX_BUF_DP<15>")
	)
	(segment
		(start 351.486724 -422.053258)
		(end 351.7519 -421.713406)
		(width 0.14224)
		(layer "In15.Cu")
		(net "P5E_CPU0_P0_RX_BUF_DP<15>")
	)
	(segment
		(start 350.315276 -416.543744)
		(end 350.452436 -416.406584)
		(width 0.14224)
		(layer "In15.Cu")
		(net "P5E_CPU0_P0_RX_BUF_DP<15>")
	)
	(segment
		(start 351.881948 -421.292782)
		(end 351.881948 -420.474394)
		(width 0.14224)
		(layer "In15.Cu")
		(net "P5E_CPU0_P0_RX_BUF_DP<15>")
	)
	(segment
		(start 351.069656 -422.36263)
		(end 351.486724 -422.053258)
		(width 0.14224)
		(layer "In15.Cu")
		(net "P5E_CPU0_P0_RX_BUF_DP<15>")
	)
	(segment
		(start 329.581002 -403.75332)
		(end 329.431142 -403.87651)
		(width 0.14224)
		(layer "In15.Cu")
		(net "P5E_CPU0_P0_RX_BUF_DP<15>")
	)
	(segment
		(start 349.624904 -413.956754)
		(end 349.112586 -413.956754)
		(width 0.14224)
		(layer "In15.Cu")
		(net "P5E_CPU0_P0_RX_BUF_DP<15>")
	)
	(segment
		(start 321.357244 -401.511008)
		(end 321.49669 -401.371562)
		(width 0.14224)
		(layer "In15.Cu")
		(net "P5E_CPU0_P0_RX_BUF_DP<15>")
	)
	(segment
		(start 329.006708 -403.834854)
		(end 328.883518 -403.68474)
		(width 0.14224)
		(layer "In15.Cu")
		(net "P5E_CPU0_P0_RX_BUF_DP<15>")
	)
	(segment
		(start 347.421454 -423.590974)
		(end 347.829632 -423.467276)
		(width 0.14224)
		(layer "In15.Cu")
		(net "P5E_CPU0_P0_RX_BUF_DP<15>")
	)
	(segment
		(start 347.330014 -423.76217)
		(end 347.421454 -423.590974)
		(width 0.14224)
		(layer "In15.Cu")
		(net "P5E_CPU0_P0_RX_BUF_DP<15>")
	)
	(segment
		(start 345.108276 -438.341262)
		(end 345.018106 -438.251092)
		(width 0.14224)
		(layer "In15.Cu")
		(net "P5E_CPU0_P0_RX_BUF_DP<15>")
	)
	(segment
		(start 350.452436 -417.107624)
		(end 350.315276 -416.970464)
		(width 0.14224)
		(layer "In15.Cu")
		(net "P5E_CPU0_P0_RX_BUF_DP<15>")
	)
	(segment
		(start 345.027504 -424.471084)
		(end 345.252802 -424.234102)
		(width 0.14224)
		(layer "In15.Cu")
		(net "P5E_CPU0_P0_RX_BUF_DP<15>")
	)
	(segment
		(start 350.129856 -422.769538)
		(end 350.922336 -422.44137)
		(width 0.14224)
		(layer "In15.Cu")
		(net "P5E_CPU0_P0_RX_BUF_DP<15>")
	)
	(segment
		(start 346.750386 -423.794682)
		(end 346.921582 -423.886122)
		(width 0.14224)
		(layer "In15.Cu")
		(net "P5E_CPU0_P0_RX_BUF_DP<15>")
	)
	(segment
		(start 331.357224 -404.066756)
		(end 331.35697 -404.066502)
		(width 0.14224)
		(layer "In15.Cu")
		(net "P5E_CPU0_P0_RX_BUF_DP<15>")
	)
	(segment
		(start 330.658978 -403.997414)
		(end 330.129134 -403.945344)
		(width 0.14224)
		(layer "In15.Cu")
		(net "P5E_CPU0_P0_RX_BUF_DP<15>")
	)
	(segment
		(start 344.970862 -438.137046)
		(end 344.970862 -424.612816)
		(width 0.14224)
		(layer "In15.Cu")
		(net "P5E_CPU0_P0_RX_BUF_DP<15>")
	)
	(segment
		(start 350.315276 -416.970464)
		(end 350.315276 -416.543744)
		(width 0.14224)
		(layer "In15.Cu")
		(net "P5E_CPU0_P0_RX_BUF_DP<15>")
	)
	(segment
		(start 351.7519 -421.713406)
		(end 351.841308 -421.497506)
		(width 0.14224)
		(layer "In15.Cu")
		(net "P5E_CPU0_P0_RX_BUF_DP<15>")
	)
	(segment
		(start 350.552258 -419.233096)
		(end 350.315276 -418.662104)
		(width 0.14224)
		(layer "In15.Cu")
		(net "P5E_CPU0_P0_RX_BUF_DP<15>")
	)
	(segment
		(start 322.430394 -403.102572)
		(end 321.764152 -402.900896)
		(width 0.14224)
		(layer "In15.Cu")
		(net "P5E_CPU0_P0_RX_BUF_DP<15>")
	)
	(segment
		(start 334.31353 -404.35784)
		(end 331.357224 -404.066756)
		(width 0.14224)
		(layer "In15.Cu")
		(net "P5E_CPU0_P0_RX_BUF_DP<15>")
	)
	(segment
		(start 321.676776 -401.371562)
		(end 321.816222 -401.511008)
		(width 0.14224)
		(layer "In15.Cu")
		(net "P5E_CPU0_P0_RX_BUF_DP<15>")
	)
	(segment
		(start 348.5007 -423.263568)
		(end 348.908878 -423.13987)
		(width 0.14224)
		(layer "In15.Cu")
		(net "P5E_CPU0_P0_RX_BUF_DP<15>")
	)
	(segment
		(start 329.431142 -403.87651)
		(end 329.006708 -403.834854)
		(width 0.14224)
		(layer "In15.Cu")
		(net "P5E_CPU0_P0_RX_BUF_DP<15>")
	)
	(segment
		(start 350.315276 -414.806892)
		(end 350.130872 -414.361884)
		(width 0.14224)
		(layer "In15.Cu")
		(net "P5E_CPU0_P0_RX_BUF_DP<15>")
	)
	(segment
		(start 350.315276 -417.671504)
		(end 350.452436 -417.534344)
		(width 0.14224)
		(layer "In15.Cu")
		(net "P5E_CPU0_P0_RX_BUF_DP<15>")
	)
	(segment
		(start 350.452436 -417.534344)
		(end 350.452436 -417.107624)
		(width 0.14224)
		(layer "In15.Cu")
		(net "P5E_CPU0_P0_RX_BUF_DP<15>")
	)
	(segment
		(start 345.355672 -424.162982)
		(end 345.501722 -424.101768)
		(width 0.14224)
		(layer "In15.Cu")
		(net "P5E_CPU0_P0_RX_BUF_DP<15>")
	)
	(segment
		(start 348.908878 -423.13987)
		(end 349.080074 -423.23131)
		(width 0.14224)
		(layer "In15.Cu")
		(net "P5E_CPU0_P0_RX_BUF_DP<15>")
	)
	(segment
		(start 351.76206 -420.185088)
		(end 351.17024 -419.593268)
		(width 0.14224)
		(layer "In15.Cu")
		(net "P5E_CPU0_P0_RX_BUF_DP<15>")
	)
	(segment
		(start 351.841308 -421.497506)
		(end 351.881948 -421.292782)
		(width 0.14224)
		(layer "In15.Cu")
		(net "P5E_CPU0_P0_RX_BUF_DP<15>")
	)
	(segment
		(start 350.315276 -415.842704)
		(end 350.315276 -414.806892)
		(width 0.14224)
		(layer "In15.Cu")
		(net "P5E_CPU0_P0_RX_BUF_DP<15>")
	)
	(segment
		(start 349.112586 -413.956754)
		(end 349.040958 -413.927036)
		(width 0.14224)
		(layer "In15.Cu")
		(net "P5E_CPU0_P0_RX_BUF_DP<15>")
	)
	(segment
		(start 340.949788 -406.701498)
		(end 336.829908 -404.994872)
		(width 0.14224)
		(layer "In15.Cu")
		(net "P5E_CPU0_P0_RX_BUF_DP<15>")
	)
	(segment
		(start 345.651836 -424.055794)
		(end 346.342208 -423.91838)
		(width 0.14224)
		(layer "In15.Cu")
		(net "P5E_CPU0_P0_RX_BUF_DP<15>")
	)
	(segment
		(start 345.649804 -438.191148)
		(end 345.49969 -438.341262)
		(width 0.14224)
		(layer "In15.Cu")
		(net "P5E_CPU0_P0_RX_BUF_DP<15>")
	)
	(segment
		(start 347.829632 -423.467276)
		(end 348.000828 -423.558716)
		(width 0.14224)
		(layer "In15.Cu")
		(net "P5E_CPU0_P0_RX_BUF_DP<15>")
	)
	(segment
		(start 323.272404 -403.270212)
		(end 322.430394 -403.102572)
		(width 0.14224)
		(layer "In15.Cu")
		(net "P5E_CPU0_P0_RX_BUF_DP<15>")
	)
	(arc
		(start 351.881948 -420.474394)
		(mid 351.850785 -420.317816)
		(end 351.76206 -420.185088)
		(width 0.14224)
		(layer "In15.Cu")
		(net "P5E_CPU0_P0_RX_BUF_DP<15>")
	)
	(arc
		(start 345.252802 -424.234102)
		(mid 345.300563 -424.193224)
		(end 345.355672 -424.162982)
		(width 0.14224)
		(layer "In15.Cu")
		(net "P5E_CPU0_P0_RX_BUF_DP<15>")
	)
	(arc
		(start 348.664784 -411.95625)
		(mid 348.560154 -411.811649)
		(end 348.4245 -411.695646)
		(width 0.14224)
		(layer "In15.Cu")
		(net "P5E_CPU0_P0_RX_BUF_DP<15>")
	)
	(arc
		(start 348.783402 -412.356554)
		(mid 348.773315 -412.241944)
		(end 348.743778 -412.130748)
		(width 0.14224)
		(layer "In15.Cu")
		(net "P5E_CPU0_P0_RX_BUF_DP<15>")
	)
	(arc
		(start 348.901512 -413.78759)
		(mid 348.815177 -413.658469)
		(end 348.784672 -413.506158)
		(width 0.14224)
		(layer "In15.Cu")
		(net "P5E_CPU0_P0_RX_BUF_DP<15>")
	)
	(arc
		(start 348.743778 -412.130748)
		(mid 348.707856 -412.04188)
		(end 348.664784 -411.95625)
		(width 0.14224)
		(layer "In15.Cu")
		(net "P5E_CPU0_P0_RX_BUF_DP<15>")
	)
	(arc
		(start 345.018106 -438.251092)
		(mid 344.983144 -438.198767)
		(end 344.970862 -438.137046)
		(width 0.14224)
		(layer "In15.Cu")
		(net "P5E_CPU0_P0_RX_BUF_DP<15>")
	)
	(arc
		(start 344.970862 -424.612816)
		(mid 344.985541 -424.536496)
		(end 345.027504 -424.471084)
		(width 0.14224)
		(layer "In15.Cu")
		(net "P5E_CPU0_P0_RX_BUF_DP<15>")
	)
	(arc
		(start 321.764152 -402.900896)
		(mid 321.589102 -402.815305)
		(end 321.4497 -402.679154)
		(width 0.14224)
		(layer "In15.Cu")
		(net "P5E_CPU0_P0_RX_BUF_DP<15>")
	)
	(arc
		(start 345.501722 -424.101768)
		(mid 345.575625 -424.075015)
		(end 345.651836 -424.055794)
		(width 0.14224)
		(layer "In15.Cu")
		(net "P5E_CPU0_P0_RX_BUF_DP<15>")
	)
	(arc
		(start 350.729804 -419.410642)
		(mid 350.623387 -419.339513)
		(end 350.552258 -419.233096)
		(width 0.14224)
		(layer "In15.Cu")
		(net "P5E_CPU0_P0_RX_BUF_DP<15>")
	)
	(segment
		(start 320.167 -401.359116)
		(end 320.459608 -401.359116)
		(width 0.1016)
		(layer "F.Cu")
		(net "P5E_CPU0_P0_RX_BUF_DP<14>")
	)
	(segment
		(start 319.913762 -399.959322)
		(end 319.913762 -401.105878)
		(width 0.1016)
		(layer "F.Cu")
		(net "P5E_CPU0_P0_RX_BUF_DP<14>")
	)
	(segment
		(start 320.002408 -399.870676)
		(end 319.913762 -399.959322)
		(width 0.1016)
		(layer "F.Cu")
		(net "P5E_CPU0_P0_RX_BUF_DP<14>")
	)
	(segment
		(start 320.002408 -399.74774)
		(end 320.002408 -399.870676)
		(width 0.1016)
		(layer "F.Cu")
		(net "P5E_CPU0_P0_RX_BUF_DP<14>")
	)
	(segment
		(start 320.459608 -401.359116)
		(end 320.616326 -401.515834)
		(width 0.1016)
		(layer "F.Cu")
		(net "P5E_CPU0_P0_RX_BUF_DP<14>")
	)
	(segment
		(start 319.917826 -399.663158)
		(end 320.002408 -399.74774)
		(width 0.1016)
		(layer "F.Cu")
		(net "P5E_CPU0_P0_RX_BUF_DP<14>")
	)
	(segment
		(start 320.616326 -401.515834)
		(end 320.616326 -401.674838)
		(width 0.1016)
		(layer "F.Cu")
		(net "P5E_CPU0_P0_RX_BUF_DP<14>")
	)
	(segment
		(start 319.913762 -401.105878)
		(end 320.167 -401.359116)
		(width 0.1016)
		(layer "F.Cu")
		(net "P5E_CPU0_P0_RX_BUF_DP<14>")
	)
	(segment
		(start 342.691212 -409.197302)
		(end 342.740488 -409.385008)
		(width 0.14224)
		(layer "In15.Cu")
		(net "P5E_CPU0_P0_RX_BUF_DP<14>")
	)
	(segment
		(start 347.252036 -415.936176)
		(end 347.389196 -416.073336)
		(width 0.14224)
		(layer "In15.Cu")
		(net "P5E_CPU0_P0_RX_BUF_DP<14>")
	)
	(segment
		(start 347.389196 -417.201096)
		(end 347.389196 -417.627816)
		(width 0.14224)
		(layer "In15.Cu")
		(net "P5E_CPU0_P0_RX_BUF_DP<14>")
	)
	(segment
		(start 331.433932 -405.36749)
		(end 331.856334 -405.430228)
		(width 0.14224)
		(layer "In15.Cu")
		(net "P5E_CPU0_P0_RX_BUF_DP<14>")
	)
	(segment
		(start 343.10828 -437.341264)
		(end 343.499694 -437.341264)
		(width 0.14224)
		(layer "In15.Cu")
		(net "P5E_CPU0_P0_RX_BUF_DP<14>")
	)
	(segment
		(start 339.172042 -407.304748)
		(end 341.160354 -408.46375)
		(width 0.14224)
		(layer "In15.Cu")
		(net "P5E_CPU0_P0_RX_BUF_DP<14>")
	)
	(segment
		(start 320.39179 -403.33422)
		(end 320.534284 -403.476714)
		(width 0.14224)
		(layer "In15.Cu")
		(net "P5E_CPU0_P0_RX_BUF_DP<14>")
	)
	(segment
		(start 343.01811 -437.251094)
		(end 343.10828 -437.341264)
		(width 0.14224)
		(layer "In15.Cu")
		(net "P5E_CPU0_P0_RX_BUF_DP<14>")
	)
	(segment
		(start 342.32215 -408.982418)
		(end 342.691212 -409.197302)
		(width 0.14224)
		(layer "In15.Cu")
		(net "P5E_CPU0_P0_RX_BUF_DP<14>")
	)
	(segment
		(start 329.619102 -405.091138)
		(end 329.740514 -405.254968)
		(width 0.14224)
		(layer "In15.Cu")
		(net "P5E_CPU0_P0_RX_BUF_DP<14>")
	)
	(segment
		(start 336.79003 -406.301448)
		(end 339.172042 -407.304748)
		(width 0.14224)
		(layer "In15.Cu")
		(net "P5E_CPU0_P0_RX_BUF_DP<14>")
	)
	(segment
		(start 320.157348 -401.511008)
		(end 320.157348 -402.768308)
		(width 0.14224)
		(layer "In15.Cu")
		(net "P5E_CPU0_P0_RX_BUF_DP<14>")
	)
	(segment
		(start 345.61018 -411.981396)
		(end 345.720416 -412.247588)
		(width 0.14224)
		(layer "In15.Cu")
		(net "P5E_CPU0_P0_RX_BUF_DP<14>")
	)
	(segment
		(start 344.82786 -423.361866)
		(end 344.100658 -423.700448)
		(width 0.14224)
		(layer "In15.Cu")
		(net "P5E_CPU0_P0_RX_BUF_DP<14>")
	)
	(segment
		(start 347.067632 -414.361884)
		(end 347.252036 -414.806892)
		(width 0.14224)
		(layer "In15.Cu")
		(net "P5E_CPU0_P0_RX_BUF_DP<14>")
	)
	(segment
		(start 347.101414 -422.57853)
		(end 346.696792 -422.713404)
		(width 0.14224)
		(layer "In15.Cu")
		(net "P5E_CPU0_P0_RX_BUF_DP<14>")
	)
	(segment
		(start 348.101666 -419.590982)
		(end 348.663768 -420.153084)
		(width 0.14224)
		(layer "In15.Cu")
		(net "P5E_CPU0_P0_RX_BUF_DP<14>")
	)
	(segment
		(start 323.708014 -404.359618)
		(end 326.047862 -404.706836)
		(width 0.14224)
		(layer "In15.Cu")
		(net "P5E_CPU0_P0_RX_BUF_DP<14>")
	)
	(segment
		(start 347.252036 -417.063936)
		(end 347.389196 -417.201096)
		(width 0.14224)
		(layer "In15.Cu")
		(net "P5E_CPU0_P0_RX_BUF_DP<14>")
	)
	(segment
		(start 347.389196 -417.627816)
		(end 347.252036 -417.764976)
		(width 0.14224)
		(layer "In15.Cu")
		(net "P5E_CPU0_P0_RX_BUF_DP<14>")
	)
	(segment
		(start 320.296794 -401.371562)
		(end 320.157348 -401.511008)
		(width 0.14224)
		(layer "In15.Cu")
		(net "P5E_CPU0_P0_RX_BUF_DP<14>")
	)
	(segment
		(start 346.098876 -422.912794)
		(end 345.259406 -423.192448)
		(width 0.14224)
		(layer "In15.Cu")
		(net "P5E_CPU0_P0_RX_BUF_DP<14>")
	)
	(segment
		(start 341.766144 -408.81681)
		(end 342.134698 -409.031694)
		(width 0.14224)
		(layer "In15.Cu")
		(net "P5E_CPU0_P0_RX_BUF_DP<14>")
	)
	(segment
		(start 331.97165 -405.586184)
		(end 336.79003 -406.301448)
		(width 0.14224)
		(layer "In15.Cu")
		(net "P5E_CPU0_P0_RX_BUF_DP<14>")
	)
	(segment
		(start 345.79306 -413.742378)
		(end 345.977718 -413.927036)
		(width 0.14224)
		(layer "In15.Cu")
		(net "P5E_CPU0_P0_RX_BUF_DP<14>")
	)
	(segment
		(start 330.856082 -405.420576)
		(end 331.277976 -405.48306)
		(width 0.14224)
		(layer "In15.Cu")
		(net "P5E_CPU0_P0_RX_BUF_DP<14>")
	)
	(segment
		(start 346.561664 -413.956754)
		(end 346.733876 -414.028128)
		(width 0.14224)
		(layer "In15.Cu")
		(net "P5E_CPU0_P0_RX_BUF_DP<14>")
	)
	(segment
		(start 320.731642 -403.595078)
		(end 322.38061 -404.095458)
		(width 0.14224)
		(layer "In15.Cu")
		(net "P5E_CPU0_P0_RX_BUF_DP<14>")
	)
	(segment
		(start 343.499694 -437.341264)
		(end 343.649808 -437.19115)
		(width 0.14224)
		(layer "In15.Cu")
		(net "P5E_CPU0_P0_RX_BUF_DP<14>")
	)
	(segment
		(start 329.740514 -405.254968)
		(end 330.162408 -405.317452)
		(width 0.14224)
		(layer "In15.Cu")
		(net "P5E_CPU0_P0_RX_BUF_DP<14>")
	)
	(segment
		(start 330.318364 -405.201882)
		(end 330.740766 -405.26462)
		(width 0.14224)
		(layer "In15.Cu")
		(net "P5E_CPU0_P0_RX_BUF_DP<14>")
	)
	(segment
		(start 346.696792 -422.713404)
		(end 346.63253 -422.842182)
		(width 0.14224)
		(layer "In15.Cu")
		(net "P5E_CPU0_P0_RX_BUF_DP<14>")
	)
	(segment
		(start 330.740766 -405.26462)
		(end 330.856082 -405.420576)
		(width 0.14224)
		(layer "In15.Cu")
		(net "P5E_CPU0_P0_RX_BUF_DP<14>")
	)
	(segment
		(start 344.629994 -410.772102)
		(end 345.23299 -411.417008)
		(width 0.14224)
		(layer "In15.Cu")
		(net "P5E_CPU0_P0_RX_BUF_DP<14>")
	)
	(segment
		(start 345.720416 -413.567118)
		(end 345.79306 -413.742378)
		(width 0.14224)
		(layer "In15.Cu")
		(net "P5E_CPU0_P0_RX_BUF_DP<14>")
	)
	(segment
		(start 345.977718 -413.927036)
		(end 346.049346 -413.956754)
		(width 0.14224)
		(layer "In15.Cu")
		(net "P5E_CPU0_P0_RX_BUF_DP<14>")
	)
	(segment
		(start 346.2274 -422.977056)
		(end 346.098876 -422.912794)
		(width 0.14224)
		(layer "In15.Cu")
		(net "P5E_CPU0_P0_RX_BUF_DP<14>")
	)
	(segment
		(start 345.720416 -412.247588)
		(end 345.720416 -413.567118)
		(width 0.14224)
		(layer "In15.Cu")
		(net "P5E_CPU0_P0_RX_BUF_DP<14>")
	)
	(segment
		(start 330.162408 -405.317452)
		(end 330.318364 -405.201882)
		(width 0.14224)
		(layer "In15.Cu")
		(net "P5E_CPU0_P0_RX_BUF_DP<14>")
	)
	(segment
		(start 326.047862 -404.706836)
		(end 329.04684 -405.151844)
		(width 0.14224)
		(layer "In15.Cu")
		(net "P5E_CPU0_P0_RX_BUF_DP<14>")
	)
	(segment
		(start 346.733876 -414.028128)
		(end 347.067632 -414.361884)
		(width 0.14224)
		(layer "In15.Cu")
		(net "P5E_CPU0_P0_RX_BUF_DP<14>")
	)
	(segment
		(start 342.970866 -424.58386)
		(end 342.970866 -437.137048)
		(width 0.14224)
		(layer "In15.Cu")
		(net "P5E_CPU0_P0_RX_BUF_DP<14>")
	)
	(segment
		(start 347.229938 -422.642792)
		(end 347.101414 -422.57853)
		(width 0.14224)
		(layer "In15.Cu")
		(net "P5E_CPU0_P0_RX_BUF_DP<14>")
	)
	(segment
		(start 341.716614 -408.629104)
		(end 341.766144 -408.81681)
		(width 0.14224)
		(layer "In15.Cu")
		(net "P5E_CPU0_P0_RX_BUF_DP<14>")
	)
	(segment
		(start 331.856334 -405.430228)
		(end 331.97165 -405.586184)
		(width 0.14224)
		(layer "In15.Cu")
		(net "P5E_CPU0_P0_RX_BUF_DP<14>")
	)
	(segment
		(start 343.109042 -409.599892)
		(end 344.629994 -410.772102)
		(width 0.14224)
		(layer "In15.Cu")
		(net "P5E_CPU0_P0_RX_BUF_DP<14>")
	)
	(segment
		(start 348.783656 -420.44239)
		(end 348.783656 -421.350186)
		(width 0.14224)
		(layer "In15.Cu")
		(net "P5E_CPU0_P0_RX_BUF_DP<14>")
	)
	(segment
		(start 345.23299 -411.417008)
		(end 345.61018 -411.981396)
		(width 0.14224)
		(layer "In15.Cu")
		(net "P5E_CPU0_P0_RX_BUF_DP<14>")
	)
	(segment
		(start 347.753178 -419.446456)
		(end 348.101666 -419.590982)
		(width 0.14224)
		(layer "In15.Cu")
		(net "P5E_CPU0_P0_RX_BUF_DP<14>")
	)
	(segment
		(start 320.47688 -401.371562)
		(end 320.296794 -401.371562)
		(width 0.14224)
		(layer "In15.Cu")
		(net "P5E_CPU0_P0_RX_BUF_DP<14>")
	)
	(segment
		(start 342.134698 -409.031694)
		(end 342.32215 -408.982418)
		(width 0.14224)
		(layer "In15.Cu")
		(net "P5E_CPU0_P0_RX_BUF_DP<14>")
	)
	(segment
		(start 346.63253 -422.842182)
		(end 346.2274 -422.977056)
		(width 0.14224)
		(layer "In15.Cu")
		(net "P5E_CPU0_P0_RX_BUF_DP<14>")
	)
	(segment
		(start 329.04684 -405.151844)
		(end 329.210416 -405.030432)
		(width 0.14224)
		(layer "In15.Cu")
		(net "P5E_CPU0_P0_RX_BUF_DP<14>")
	)
	(segment
		(start 348.150434 -422.228772)
		(end 347.69933 -422.37914)
		(width 0.14224)
		(layer "In15.Cu")
		(net "P5E_CPU0_P0_RX_BUF_DP<14>")
	)
	(segment
		(start 341.347806 -408.41422)
		(end 341.716614 -408.629104)
		(width 0.14224)
		(layer "In15.Cu")
		(net "P5E_CPU0_P0_RX_BUF_DP<14>")
	)
	(segment
		(start 342.740488 -409.385008)
		(end 343.109042 -409.599892)
		(width 0.14224)
		(layer "In15.Cu")
		(net "P5E_CPU0_P0_RX_BUF_DP<14>")
	)
	(segment
		(start 331.277976 -405.48306)
		(end 331.433932 -405.36749)
		(width 0.14224)
		(layer "In15.Cu")
		(net "P5E_CPU0_P0_RX_BUF_DP<14>")
	)
	(segment
		(start 347.69933 -422.37914)
		(end 347.635068 -422.507918)
		(width 0.14224)
		(layer "In15.Cu")
		(net "P5E_CPU0_P0_RX_BUF_DP<14>")
	)
	(segment
		(start 320.616326 -401.674838)
		(end 320.616326 -401.511008)
		(width 0.14224)
		(layer "In15.Cu")
		(net "P5E_CPU0_P0_RX_BUF_DP<14>")
	)
	(segment
		(start 341.160354 -408.46375)
		(end 341.347806 -408.41422)
		(width 0.14224)
		(layer "In15.Cu")
		(net "P5E_CPU0_P0_RX_BUF_DP<14>")
	)
	(segment
		(start 347.635068 -422.507918)
		(end 347.229938 -422.642792)
		(width 0.14224)
		(layer "In15.Cu")
		(net "P5E_CPU0_P0_RX_BUF_DP<14>")
	)
	(segment
		(start 347.252036 -414.806892)
		(end 347.252036 -415.936176)
		(width 0.14224)
		(layer "In15.Cu")
		(net "P5E_CPU0_P0_RX_BUF_DP<14>")
	)
	(segment
		(start 347.252036 -418.627306)
		(end 347.477842 -419.17112)
		(width 0.14224)
		(layer "In15.Cu")
		(net "P5E_CPU0_P0_RX_BUF_DP<14>")
	)
	(segment
		(start 347.252036 -416.637216)
		(end 347.252036 -417.063936)
		(width 0.14224)
		(layer "In15.Cu")
		(net "P5E_CPU0_P0_RX_BUF_DP<14>")
	)
	(segment
		(start 347.389196 -416.500056)
		(end 347.252036 -416.637216)
		(width 0.14224)
		(layer "In15.Cu")
		(net "P5E_CPU0_P0_RX_BUF_DP<14>")
	)
	(segment
		(start 343.823036 -423.85107)
		(end 343.140792 -424.277028)
		(width 0.14224)
		(layer "In15.Cu")
		(net "P5E_CPU0_P0_RX_BUF_DP<14>")
	)
	(segment
		(start 343.649808 -437.19115)
		(end 343.649808 -436.889906)
		(width 0.14224)
		(layer "In15.Cu")
		(net "P5E_CPU0_P0_RX_BUF_DP<14>")
	)
	(segment
		(start 347.389196 -416.073336)
		(end 347.389196 -416.500056)
		(width 0.14224)
		(layer "In15.Cu")
		(net "P5E_CPU0_P0_RX_BUF_DP<14>")
	)
	(segment
		(start 329.210416 -405.030432)
		(end 329.619102 -405.091138)
		(width 0.14224)
		(layer "In15.Cu")
		(net "P5E_CPU0_P0_RX_BUF_DP<14>")
	)
	(segment
		(start 346.049346 -413.956754)
		(end 346.561664 -413.956754)
		(width 0.14224)
		(layer "In15.Cu")
		(net "P5E_CPU0_P0_RX_BUF_DP<14>")
	)
	(segment
		(start 320.616326 -401.511008)
		(end 320.47688 -401.371562)
		(width 0.14224)
		(layer "In15.Cu")
		(net "P5E_CPU0_P0_RX_BUF_DP<14>")
	)
	(segment
		(start 347.252036 -417.764976)
		(end 347.252036 -418.627306)
		(width 0.14224)
		(layer "In15.Cu")
		(net "P5E_CPU0_P0_RX_BUF_DP<14>")
	)
	(segment
		(start 322.38061 -404.095458)
		(end 323.708014 -404.359618)
		(width 0.14224)
		(layer "In15.Cu")
		(net "P5E_CPU0_P0_RX_BUF_DP<14>")
	)
	(arc
		(start 345.259406 -423.192448)
		(mid 345.041397 -423.271461)
		(end 344.82786 -423.361866)
		(width 0.14224)
		(layer "In15.Cu")
		(net "P5E_CPU0_P0_RX_BUF_DP<14>")
	)
	(arc
		(start 347.477842 -419.17112)
		(mid 347.588136 -419.336162)
		(end 347.753178 -419.446456)
		(width 0.14224)
		(layer "In15.Cu")
		(net "P5E_CPU0_P0_RX_BUF_DP<14>")
	)
	(arc
		(start 342.970866 -437.137048)
		(mid 342.983143 -437.198771)
		(end 343.01811 -437.251094)
		(width 0.14224)
		(layer "In15.Cu")
		(net "P5E_CPU0_P0_RX_BUF_DP<14>")
	)
	(arc
		(start 320.157348 -402.768308)
		(mid 320.218271 -403.07459)
		(end 320.39179 -403.33422)
		(width 0.14224)
		(layer "In15.Cu")
		(net "P5E_CPU0_P0_RX_BUF_DP<14>")
	)
	(arc
		(start 320.534284 -403.476714)
		(mid 320.625658 -403.54808)
		(end 320.731642 -403.595078)
		(width 0.14224)
		(layer "In15.Cu")
		(net "P5E_CPU0_P0_RX_BUF_DP<14>")
	)
	(arc
		(start 344.100658 -423.700448)
		(mid 343.959538 -423.771503)
		(end 343.823036 -423.85107)
		(width 0.14224)
		(layer "In15.Cu")
		(net "P5E_CPU0_P0_RX_BUF_DP<14>")
	)
	(arc
		(start 348.783656 -421.350186)
		(mid 348.60885 -421.891677)
		(end 348.150434 -422.228772)
		(width 0.14224)
		(layer "In15.Cu")
		(net "P5E_CPU0_P0_RX_BUF_DP<14>")
	)
	(arc
		(start 348.663768 -420.153084)
		(mid 348.752512 -420.285804)
		(end 348.783656 -420.44239)
		(width 0.14224)
		(layer "In15.Cu")
		(net "P5E_CPU0_P0_RX_BUF_DP<14>")
	)
	(arc
		(start 343.140792 -424.277028)
		(mid 343.01611 -424.408439)
		(end 342.970866 -424.58386)
		(width 0.14224)
		(layer "In15.Cu")
		(net "P5E_CPU0_P0_RX_BUF_DP<14>")
	)
	(segment
		(start 318.722248 -399.950686)
		(end 318.722248 -401.105878)
		(width 0.1016)
		(layer "F.Cu")
		(net "P5E_CPU0_P0_RX_BUF_DP<13>")
	)
	(segment
		(start 319.416176 -401.4978)
		(end 319.416176 -401.674838)
		(width 0.1016)
		(layer "F.Cu")
		(net "P5E_CPU0_P0_RX_BUF_DP<13>")
	)
	(segment
		(start 319.277492 -401.359116)
		(end 319.416176 -401.4978)
		(width 0.1016)
		(layer "F.Cu")
		(net "P5E_CPU0_P0_RX_BUF_DP<13>")
	)
	(segment
		(start 318.802258 -399.870676)
		(end 318.722248 -399.950686)
		(width 0.1016)
		(layer "F.Cu")
		(net "P5E_CPU0_P0_RX_BUF_DP<13>")
	)
	(segment
		(start 318.802258 -399.74774)
		(end 318.802258 -399.870676)
		(width 0.1016)
		(layer "F.Cu")
		(net "P5E_CPU0_P0_RX_BUF_DP<13>")
	)
	(segment
		(start 318.722248 -401.105878)
		(end 318.975486 -401.359116)
		(width 0.1016)
		(layer "F.Cu")
		(net "P5E_CPU0_P0_RX_BUF_DP<13>")
	)
	(segment
		(start 318.975486 -401.359116)
		(end 319.277492 -401.359116)
		(width 0.1016)
		(layer "F.Cu")
		(net "P5E_CPU0_P0_RX_BUF_DP<13>")
	)
	(segment
		(start 318.717676 -399.663158)
		(end 318.802258 -399.74774)
		(width 0.1016)
		(layer "F.Cu")
		(net "P5E_CPU0_P0_RX_BUF_DP<13>")
	)
	(segment
		(start 318.957198 -401.511008)
		(end 318.957198 -403.040342)
		(width 0.14224)
		(layer "In15.Cu")
		(net "P5E_CPU0_P0_RX_BUF_DP<13>")
	)
	(segment
		(start 329.211686 -406.535128)
		(end 329.634088 -406.597612)
		(width 0.14224)
		(layer "In15.Cu")
		(net "P5E_CPU0_P0_RX_BUF_DP<13>")
	)
	(segment
		(start 337.984846 -408.685492)
		(end 338.05241 -408.86761)
		(width 0.14224)
		(layer "In15.Cu")
		(net "P5E_CPU0_P0_RX_BUF_DP<13>")
	)
	(segment
		(start 340.97087 -424.626786)
		(end 340.97087 -438.13222)
		(width 0.14224)
		(layer "In15.Cu")
		(net "P5E_CPU0_P0_RX_BUF_DP<13>")
	)
	(segment
		(start 319.289176 -401.371562)
		(end 319.096644 -401.371562)
		(width 0.14224)
		(layer "In15.Cu")
		(net "P5E_CPU0_P0_RX_BUF_DP<13>")
	)
	(segment
		(start 340.465664 -410.398976)
		(end 340.65591 -410.36113)
		(width 0.14224)
		(layer "In15.Cu")
		(net "P5E_CPU0_P0_RX_BUF_DP<13>")
	)
	(segment
		(start 341.593678 -410.988002)
		(end 341.94877 -411.225492)
		(width 0.14224)
		(layer "In15.Cu")
		(net "P5E_CPU0_P0_RX_BUF_DP<13>")
	)
	(segment
		(start 331.28712 -406.98166)
		(end 331.442822 -406.86609)
		(width 0.14224)
		(layer "In15.Cu")
		(net "P5E_CPU0_P0_RX_BUF_DP<13>")
	)
	(segment
		(start 344.200988 -418.625528)
		(end 344.378026 -419.052248)
		(width 0.14224)
		(layer "In15.Cu")
		(net "P5E_CPU0_P0_RX_BUF_DP<13>")
	)
	(segment
		(start 319.416176 -401.498562)
		(end 319.289176 -401.371562)
		(width 0.14224)
		(layer "In15.Cu")
		(net "P5E_CPU0_P0_RX_BUF_DP<13>")
	)
	(segment
		(start 342.657176 -412.210758)
		(end 342.657176 -413.566864)
		(width 0.14224)
		(layer "In15.Cu")
		(net "P5E_CPU0_P0_RX_BUF_DP<13>")
	)
	(segment
		(start 341.993982 -423.52849)
		(end 341.382604 -423.936668)
		(width 0.14224)
		(layer "In15.Cu")
		(net "P5E_CPU0_P0_RX_BUF_DP<13>")
	)
	(segment
		(start 337.596734 -408.507692)
		(end 337.984846 -408.685492)
		(width 0.14224)
		(layer "In15.Cu")
		(net "P5E_CPU0_P0_RX_BUF_DP<13>")
	)
	(segment
		(start 341.011002 -410.59862)
		(end 341.048848 -410.788866)
		(width 0.14224)
		(layer "In15.Cu")
		(net "P5E_CPU0_P0_RX_BUF_DP<13>")
	)
	(segment
		(start 342.72982 -413.742378)
		(end 342.914478 -413.927036)
		(width 0.14224)
		(layer "In15.Cu")
		(net "P5E_CPU0_P0_RX_BUF_DP<13>")
	)
	(segment
		(start 319.096644 -401.371562)
		(end 318.957198 -401.511008)
		(width 0.14224)
		(layer "In15.Cu")
		(net "P5E_CPU0_P0_RX_BUF_DP<13>")
	)
	(segment
		(start 341.499698 -438.341262)
		(end 341.649812 -438.191148)
		(width 0.14224)
		(layer "In15.Cu")
		(net "P5E_CPU0_P0_RX_BUF_DP<13>")
	)
	(segment
		(start 342.657176 -413.566864)
		(end 342.72982 -413.742378)
		(width 0.14224)
		(layer "In15.Cu")
		(net "P5E_CPU0_P0_RX_BUF_DP<13>")
	)
	(segment
		(start 336.361532 -407.942034)
		(end 336.749898 -408.119834)
		(width 0.14224)
		(layer "In15.Cu")
		(net "P5E_CPU0_P0_RX_BUF_DP<13>")
	)
	(segment
		(start 319.416176 -401.674838)
		(end 319.416176 -401.498562)
		(width 0.14224)
		(layer "In15.Cu")
		(net "P5E_CPU0_P0_RX_BUF_DP<13>")
	)
	(segment
		(start 341.11311 -438.341262)
		(end 341.499698 -438.341262)
		(width 0.14224)
		(layer "In15.Cu")
		(net "P5E_CPU0_P0_RX_BUF_DP<13>")
	)
	(segment
		(start 345.105736 -419.697916)
		(end 345.590622 -420.182548)
		(width 0.14224)
		(layer "In15.Cu")
		(net "P5E_CPU0_P0_RX_BUF_DP<13>")
	)
	(segment
		(start 345.054936 -422.235376)
		(end 344.903298 -422.311576)
		(width 0.14224)
		(layer "In15.Cu")
		(net "P5E_CPU0_P0_RX_BUF_DP<13>")
	)
	(segment
		(start 342.088724 -423.47769)
		(end 341.993982 -423.52849)
		(width 0.14224)
		(layer "In15.Cu")
		(net "P5E_CPU0_P0_RX_BUF_DP<13>")
	)
	(segment
		(start 336.179922 -408.009852)
		(end 336.361532 -407.942034)
		(width 0.14224)
		(layer "In15.Cu")
		(net "P5E_CPU0_P0_RX_BUF_DP<13>")
	)
	(segment
		(start 344.725498 -419.456362)
		(end 344.870278 -419.528498)
		(width 0.14224)
		(layer "In15.Cu")
		(net "P5E_CPU0_P0_RX_BUF_DP<13>")
	)
	(segment
		(start 339.527896 -409.772104)
		(end 339.718142 -409.734258)
		(width 0.14224)
		(layer "In15.Cu")
		(net "P5E_CPU0_P0_RX_BUF_DP<13>")
	)
	(segment
		(start 341.018114 -438.246266)
		(end 341.11311 -438.341262)
		(width 0.14224)
		(layer "In15.Cu")
		(net "P5E_CPU0_P0_RX_BUF_DP<13>")
	)
	(segment
		(start 338.05241 -408.86761)
		(end 338.440268 -409.045156)
		(width 0.14224)
		(layer "In15.Cu")
		(net "P5E_CPU0_P0_RX_BUF_DP<13>")
	)
	(segment
		(start 341.94877 -411.225492)
		(end 341.986616 -411.415738)
		(width 0.14224)
		(layer "In15.Cu")
		(net "P5E_CPU0_P0_RX_BUF_DP<13>")
	)
	(segment
		(start 340.65591 -410.36113)
		(end 341.011002 -410.59862)
		(width 0.14224)
		(layer "In15.Cu")
		(net "P5E_CPU0_P0_RX_BUF_DP<13>")
	)
	(segment
		(start 330.171552 -406.816052)
		(end 330.327254 -406.700482)
		(width 0.14224)
		(layer "In15.Cu")
		(net "P5E_CPU0_P0_RX_BUF_DP<13>")
	)
	(segment
		(start 331.442822 -406.86609)
		(end 331.865224 -406.928828)
		(width 0.14224)
		(layer "In15.Cu")
		(net "P5E_CPU0_P0_RX_BUF_DP<13>")
	)
	(segment
		(start 331.865224 -406.928828)
		(end 331.980794 -407.084784)
		(width 0.14224)
		(layer "In15.Cu")
		(net "P5E_CPU0_P0_RX_BUF_DP<13>")
	)
	(segment
		(start 340.11108 -410.161994)
		(end 340.465664 -410.398976)
		(width 0.14224)
		(layer "In15.Cu")
		(net "P5E_CPU0_P0_RX_BUF_DP<13>")
	)
	(segment
		(start 336.817462 -408.301952)
		(end 337.41487 -408.57551)
		(width 0.14224)
		(layer "In15.Cu")
		(net "P5E_CPU0_P0_RX_BUF_DP<13>")
	)
	(segment
		(start 344.903298 -422.311576)
		(end 342.088724 -423.47769)
		(width 0.14224)
		(layer "In15.Cu")
		(net "P5E_CPU0_P0_RX_BUF_DP<13>")
	)
	(segment
		(start 342.986106 -413.956754)
		(end 343.375234 -413.956754)
		(width 0.14224)
		(layer "In15.Cu")
		(net "P5E_CPU0_P0_RX_BUF_DP<13>")
	)
	(segment
		(start 341.048848 -410.788866)
		(end 341.403432 -411.025848)
		(width 0.14224)
		(layer "In15.Cu")
		(net "P5E_CPU0_P0_RX_BUF_DP<13>")
	)
	(segment
		(start 330.749656 -406.76322)
		(end 330.865226 -406.919176)
		(width 0.14224)
		(layer "In15.Cu")
		(net "P5E_CPU0_P0_RX_BUF_DP<13>")
	)
	(segment
		(start 319.142872 -403.488398)
		(end 319.799208 -404.144734)
		(width 0.14224)
		(layer "In15.Cu")
		(net "P5E_CPU0_P0_RX_BUF_DP<13>")
	)
	(segment
		(start 337.41487 -408.57551)
		(end 337.596734 -408.507692)
		(width 0.14224)
		(layer "In15.Cu")
		(net "P5E_CPU0_P0_RX_BUF_DP<13>")
	)
	(segment
		(start 341.403432 -411.025848)
		(end 341.593678 -410.988002)
		(width 0.14224)
		(layer "In15.Cu")
		(net "P5E_CPU0_P0_RX_BUF_DP<13>")
	)
	(segment
		(start 330.865226 -406.919176)
		(end 331.28712 -406.98166)
		(width 0.14224)
		(layer "In15.Cu")
		(net "P5E_CPU0_P0_RX_BUF_DP<13>")
	)
	(segment
		(start 329.749658 -406.753568)
		(end 330.171552 -406.816052)
		(width 0.14224)
		(layer "In15.Cu")
		(net "P5E_CPU0_P0_RX_BUF_DP<13>")
	)
	(segment
		(start 326.137524 -406.218136)
		(end 329.05573 -406.650698)
		(width 0.14224)
		(layer "In15.Cu")
		(net "P5E_CPU0_P0_RX_BUF_DP<13>")
	)
	(segment
		(start 343.70645 -414.093914)
		(end 344.025982 -414.4137)
		(width 0.14224)
		(layer "In15.Cu")
		(net "P5E_CPU0_P0_RX_BUF_DP<13>")
	)
	(segment
		(start 320.308732 -404.450042)
		(end 326.137524 -406.218136)
		(width 0.14224)
		(layer "In15.Cu")
		(net "P5E_CPU0_P0_RX_BUF_DP<13>")
	)
	(segment
		(start 338.440268 -409.045156)
		(end 339.527896 -409.772104)
		(width 0.14224)
		(layer "In15.Cu")
		(net "P5E_CPU0_P0_RX_BUF_DP<13>")
	)
	(segment
		(start 341.986616 -411.415738)
		(end 342.3412 -411.65272)
		(width 0.14224)
		(layer "In15.Cu")
		(net "P5E_CPU0_P0_RX_BUF_DP<13>")
	)
	(segment
		(start 342.48598 -411.7975)
		(end 342.657176 -412.210758)
		(width 0.14224)
		(layer "In15.Cu")
		(net "P5E_CPU0_P0_RX_BUF_DP<13>")
	)
	(segment
		(start 339.718142 -409.734258)
		(end 340.073234 -409.971748)
		(width 0.14224)
		(layer "In15.Cu")
		(net "P5E_CPU0_P0_RX_BUF_DP<13>")
	)
	(segment
		(start 342.3412 -411.65272)
		(end 342.48598 -411.7975)
		(width 0.14224)
		(layer "In15.Cu")
		(net "P5E_CPU0_P0_RX_BUF_DP<13>")
	)
	(segment
		(start 335.20507 -407.56332)
		(end 336.179922 -408.009852)
		(width 0.14224)
		(layer "In15.Cu")
		(net "P5E_CPU0_P0_RX_BUF_DP<13>")
	)
	(segment
		(start 342.914478 -413.927036)
		(end 342.986106 -413.956754)
		(width 0.14224)
		(layer "In15.Cu")
		(net "P5E_CPU0_P0_RX_BUF_DP<13>")
	)
	(segment
		(start 341.649812 -438.191148)
		(end 341.649812 -437.889904)
		(width 0.14224)
		(layer "In15.Cu")
		(net "P5E_CPU0_P0_RX_BUF_DP<13>")
	)
	(segment
		(start 344.025982 -414.4137)
		(end 344.145108 -414.700974)
		(width 0.14224)
		(layer "In15.Cu")
		(net "P5E_CPU0_P0_RX_BUF_DP<13>")
	)
	(segment
		(start 329.634088 -406.597612)
		(end 329.749658 -406.753568)
		(width 0.14224)
		(layer "In15.Cu")
		(net "P5E_CPU0_P0_RX_BUF_DP<13>")
	)
	(segment
		(start 340.073234 -409.971748)
		(end 340.11108 -410.161994)
		(width 0.14224)
		(layer "In15.Cu")
		(net "P5E_CPU0_P0_RX_BUF_DP<13>")
	)
	(segment
		(start 329.05573 -406.650698)
		(end 329.211686 -406.535128)
		(width 0.14224)
		(layer "In15.Cu")
		(net "P5E_CPU0_P0_RX_BUF_DP<13>")
	)
	(segment
		(start 330.327254 -406.700482)
		(end 330.749656 -406.76322)
		(width 0.14224)
		(layer "In15.Cu")
		(net "P5E_CPU0_P0_RX_BUF_DP<13>")
	)
	(segment
		(start 331.980794 -407.084784)
		(end 335.20507 -407.56332)
		(width 0.14224)
		(layer "In15.Cu")
		(net "P5E_CPU0_P0_RX_BUF_DP<13>")
	)
	(segment
		(start 345.720416 -420.495984)
		(end 345.720416 -421.154606)
		(width 0.14224)
		(layer "In15.Cu")
		(net "P5E_CPU0_P0_RX_BUF_DP<13>")
	)
	(segment
		(start 336.749898 -408.119834)
		(end 336.817462 -408.301952)
		(width 0.14224)
		(layer "In15.Cu")
		(net "P5E_CPU0_P0_RX_BUF_DP<13>")
	)
	(segment
		(start 344.188796 -414.921192)
		(end 344.188796 -418.563806)
		(width 0.14224)
		(layer "In15.Cu")
		(net "P5E_CPU0_P0_RX_BUF_DP<13>")
	)
	(arc
		(start 344.870278 -419.528498)
		(mid 344.99488 -419.603656)
		(end 345.105736 -419.697916)
		(width 0.14224)
		(layer "In15.Cu")
		(net "P5E_CPU0_P0_RX_BUF_DP<13>")
	)
	(arc
		(start 318.957198 -403.040342)
		(mid 319.005453 -403.282846)
		(end 319.142872 -403.488398)
		(width 0.14224)
		(layer "In15.Cu")
		(net "P5E_CPU0_P0_RX_BUF_DP<13>")
	)
	(arc
		(start 340.986364 -424.501056)
		(mid 340.974794 -424.56345)
		(end 340.97087 -424.626786)
		(width 0.14224)
		(layer "In15.Cu")
		(net "P5E_CPU0_P0_RX_BUF_DP<13>")
	)
	(arc
		(start 344.145108 -414.700974)
		(mid 344.177823 -414.808928)
		(end 344.188796 -414.921192)
		(width 0.14224)
		(layer "In15.Cu")
		(net "P5E_CPU0_P0_RX_BUF_DP<13>")
	)
	(arc
		(start 344.378026 -419.052248)
		(mid 344.479292 -419.233471)
		(end 344.619834 -419.386258)
		(width 0.14224)
		(layer "In15.Cu")
		(net "P5E_CPU0_P0_RX_BUF_DP<13>")
	)
	(arc
		(start 345.720416 -421.154606)
		(mid 345.540648 -421.789188)
		(end 345.054936 -422.235376)
		(width 0.14224)
		(layer "In15.Cu")
		(net "P5E_CPU0_P0_RX_BUF_DP<13>")
	)
	(arc
		(start 345.590622 -420.182548)
		(mid 345.686764 -420.326339)
		(end 345.720416 -420.495984)
		(width 0.14224)
		(layer "In15.Cu")
		(net "P5E_CPU0_P0_RX_BUF_DP<13>")
	)
	(arc
		(start 319.799208 -404.144734)
		(mid 320.035145 -404.328802)
		(end 320.308732 -404.450042)
		(width 0.14224)
		(layer "In15.Cu")
		(net "P5E_CPU0_P0_RX_BUF_DP<13>")
	)
	(arc
		(start 341.382604 -423.936668)
		(mid 341.131767 -424.181852)
		(end 340.986364 -424.501056)
		(width 0.14224)
		(layer "In15.Cu")
		(net "P5E_CPU0_P0_RX_BUF_DP<13>")
	)
	(arc
		(start 343.375234 -413.956754)
		(mid 343.554499 -413.992354)
		(end 343.70645 -414.093914)
		(width 0.14224)
		(layer "In15.Cu")
		(net "P5E_CPU0_P0_RX_BUF_DP<13>")
	)
	(arc
		(start 340.97087 -438.13222)
		(mid 340.983147 -438.193943)
		(end 341.018114 -438.246266)
		(width 0.14224)
		(layer "In15.Cu")
		(net "P5E_CPU0_P0_RX_BUF_DP<13>")
	)
	(arc
		(start 344.619834 -419.386258)
		(mid 344.670499 -419.424577)
		(end 344.725498 -419.456362)
		(width 0.14224)
		(layer "In15.Cu")
		(net "P5E_CPU0_P0_RX_BUF_DP<13>")
	)
	(arc
		(start 344.188796 -418.563806)
		(mid 344.191844 -418.59527)
		(end 344.200988 -418.625528)
		(width 0.14224)
		(layer "In15.Cu")
		(net "P5E_CPU0_P0_RX_BUF_DP<13>")
	)
	(segment
		(start 317.513716 -399.959322)
		(end 317.513716 -401.105878)
		(width 0.1016)
		(layer "F.Cu")
		(net "P5E_CPU0_P0_RX_BUF_DP<12>")
	)
	(segment
		(start 317.602362 -399.74774)
		(end 317.602362 -399.870676)
		(width 0.1016)
		(layer "F.Cu")
		(net "P5E_CPU0_P0_RX_BUF_DP<12>")
	)
	(segment
		(start 318.074294 -401.359116)
		(end 318.21628 -401.501102)
		(width 0.1016)
		(layer "F.Cu")
		(net "P5E_CPU0_P0_RX_BUF_DP<12>")
	)
	(segment
		(start 317.51778 -399.663158)
		(end 317.602362 -399.74774)
		(width 0.1016)
		(layer "F.Cu")
		(net "P5E_CPU0_P0_RX_BUF_DP<12>")
	)
	(segment
		(start 317.602362 -399.870676)
		(end 317.513716 -399.959322)
		(width 0.1016)
		(layer "F.Cu")
		(net "P5E_CPU0_P0_RX_BUF_DP<12>")
	)
	(segment
		(start 317.513716 -401.105878)
		(end 317.766954 -401.359116)
		(width 0.1016)
		(layer "F.Cu")
		(net "P5E_CPU0_P0_RX_BUF_DP<12>")
	)
	(segment
		(start 317.766954 -401.359116)
		(end 318.074294 -401.359116)
		(width 0.1016)
		(layer "F.Cu")
		(net "P5E_CPU0_P0_RX_BUF_DP<12>")
	)
	(segment
		(start 318.21628 -401.501102)
		(end 318.21628 -401.674838)
		(width 0.1016)
		(layer "F.Cu")
		(net "P5E_CPU0_P0_RX_BUF_DP<12>")
	)
	(segment
		(start 318.076834 -401.371562)
		(end 317.896748 -401.371562)
		(width 0.14224)
		(layer "In15.Cu")
		(net "P5E_CPU0_P0_RX_BUF_DP<12>")
	)
	(segment
		(start 339.851238 -413.927036)
		(end 339.922866 -413.956754)
		(width 0.14224)
		(layer "In15.Cu")
		(net "P5E_CPU0_P0_RX_BUF_DP<12>")
	)
	(segment
		(start 341.125556 -417.858702)
		(end 341.125556 -418.595048)
		(width 0.14224)
		(layer "In15.Cu")
		(net "P5E_CPU0_P0_RX_BUF_DP<12>")
	)
	(segment
		(start 327.291446 -407.497534)
		(end 327.454768 -407.392632)
		(width 0.14224)
		(layer "In15.Cu")
		(net "P5E_CPU0_P0_RX_BUF_DP<12>")
	)
	(segment
		(start 341.262716 -416.593782)
		(end 341.125556 -416.730942)
		(width 0.14224)
		(layer "In15.Cu")
		(net "P5E_CPU0_P0_RX_BUF_DP<12>")
	)
	(segment
		(start 339.607398 -423.90441)
		(end 339.46211 -424.049698)
		(width 0.14224)
		(layer "In15.Cu")
		(net "P5E_CPU0_P0_RX_BUF_DP<12>")
	)
	(segment
		(start 317.868046 -403.219666)
		(end 317.757302 -403.33041)
		(width 0.14224)
		(layer "In15.Cu")
		(net "P5E_CPU0_P0_RX_BUF_DP<12>")
	)
	(segment
		(start 339.018118 -437.251094)
		(end 339.108288 -437.341264)
		(width 0.14224)
		(layer "In15.Cu")
		(net "P5E_CPU0_P0_RX_BUF_DP<12>")
	)
	(segment
		(start 318.21628 -401.674838)
		(end 318.21628 -401.511008)
		(width 0.14224)
		(layer "In15.Cu")
		(net "P5E_CPU0_P0_RX_BUF_DP<12>")
	)
	(segment
		(start 337.982052 -410.655008)
		(end 338.46897 -410.980382)
		(width 0.14224)
		(layer "In15.Cu")
		(net "P5E_CPU0_P0_RX_BUF_DP<12>")
	)
	(segment
		(start 342.02624 -419.612064)
		(end 342.537034 -420.121842)
		(width 0.14224)
		(layer "In15.Cu")
		(net "P5E_CPU0_P0_RX_BUF_DP<12>")
	)
	(segment
		(start 339.649816 -437.19115)
		(end 339.649816 -436.889906)
		(width 0.14224)
		(layer "In15.Cu")
		(net "P5E_CPU0_P0_RX_BUF_DP<12>")
	)
	(segment
		(start 337.589114 -410.227526)
		(end 337.944206 -410.464762)
		(width 0.14224)
		(layer "In15.Cu")
		(net "P5E_CPU0_P0_RX_BUF_DP<12>")
	)
	(segment
		(start 342.475312 -421.936672)
		(end 342.324182 -422.087802)
		(width 0.14224)
		(layer "In15.Cu")
		(net "P5E_CPU0_P0_RX_BUF_DP<12>")
	)
	(segment
		(start 334.514444 -409.009088)
		(end 334.675734 -408.901138)
		(width 0.14224)
		(layer "In15.Cu")
		(net "P5E_CPU0_P0_RX_BUF_DP<12>")
	)
	(segment
		(start 338.56676 -411.060646)
		(end 339.474048 -411.967934)
		(width 0.14224)
		(layer "In15.Cu")
		(net "P5E_CPU0_P0_RX_BUF_DP<12>")
	)
	(segment
		(start 317.827406 -403.777196)
		(end 319.275714 -405.091392)
		(width 0.14224)
		(layer "In15.Cu")
		(net "P5E_CPU0_P0_RX_BUF_DP<12>")
	)
	(segment
		(start 341.125556 -414.806892)
		(end 341.125556 -416.029902)
		(width 0.14224)
		(layer "In15.Cu")
		(net "P5E_CPU0_P0_RX_BUF_DP<12>")
	)
	(segment
		(start 327.871836 -407.48331)
		(end 327.976992 -407.646632)
		(width 0.14224)
		(layer "In15.Cu")
		(net "P5E_CPU0_P0_RX_BUF_DP<12>")
	)
	(segment
		(start 339.040724 -424.60164)
		(end 338.989162 -424.773852)
		(width 0.14224)
		(layer "In15.Cu")
		(net "P5E_CPU0_P0_RX_BUF_DP<12>")
	)
	(segment
		(start 328.413618 -407.741374)
		(end 328.576686 -407.636472)
		(width 0.14224)
		(layer "In15.Cu")
		(net "P5E_CPU0_P0_RX_BUF_DP<12>")
	)
	(segment
		(start 317.757302 -403.33041)
		(end 317.757302 -403.448012)
		(width 0.14224)
		(layer "In15.Cu")
		(net "P5E_CPU0_P0_RX_BUF_DP<12>")
	)
	(segment
		(start 339.593936 -412.25724)
		(end 339.593936 -413.566102)
		(width 0.14224)
		(layer "In15.Cu")
		(net "P5E_CPU0_P0_RX_BUF_DP<12>")
	)
	(segment
		(start 341.125556 -418.595048)
		(end 341.351616 -419.140386)
		(width 0.14224)
		(layer "In15.Cu")
		(net "P5E_CPU0_P0_RX_BUF_DP<12>")
	)
	(segment
		(start 339.46211 -424.049698)
		(end 339.099906 -424.490642)
		(width 0.14224)
		(layer "In15.Cu")
		(net "P5E_CPU0_P0_RX_BUF_DP<12>")
	)
	(segment
		(start 341.125556 -416.730942)
		(end 341.125556 -417.157662)
		(width 0.14224)
		(layer "In15.Cu")
		(net "P5E_CPU0_P0_RX_BUF_DP<12>")
	)
	(segment
		(start 339.499702 -437.341264)
		(end 339.649816 -437.19115)
		(width 0.14224)
		(layer "In15.Cu")
		(net "P5E_CPU0_P0_RX_BUF_DP<12>")
	)
	(segment
		(start 342.657176 -420.411402)
		(end 342.657176 -421.497506)
		(width 0.14224)
		(layer "In15.Cu")
		(net "P5E_CPU0_P0_RX_BUF_DP<12>")
	)
	(segment
		(start 317.757302 -401.511008)
		(end 317.757302 -402.682202)
		(width 0.14224)
		(layer "In15.Cu")
		(net "P5E_CPU0_P0_RX_BUF_DP<12>")
	)
	(segment
		(start 339.66658 -413.742378)
		(end 339.851238 -413.927036)
		(width 0.14224)
		(layer "In15.Cu")
		(net "P5E_CPU0_P0_RX_BUF_DP<12>")
	)
	(segment
		(start 330.370688 -408.026108)
		(end 330.78801 -408.116786)
		(width 0.14224)
		(layer "In15.Cu")
		(net "P5E_CPU0_P0_RX_BUF_DP<12>")
	)
	(segment
		(start 330.78801 -408.116786)
		(end 330.892912 -408.280108)
		(width 0.14224)
		(layer "In15.Cu")
		(net "P5E_CPU0_P0_RX_BUF_DP<12>")
	)
	(segment
		(start 318.21628 -401.511008)
		(end 318.076834 -401.371562)
		(width 0.14224)
		(layer "In15.Cu")
		(net "P5E_CPU0_P0_RX_BUF_DP<12>")
	)
	(segment
		(start 319.384934 -405.153114)
		(end 326.656446 -407.359866)
		(width 0.14224)
		(layer "In15.Cu")
		(net "P5E_CPU0_P0_RX_BUF_DP<12>")
	)
	(segment
		(start 330.892912 -408.280108)
		(end 331.364336 -408.38247)
		(width 0.14224)
		(layer "In15.Cu")
		(net "P5E_CPU0_P0_RX_BUF_DP<12>")
	)
	(segment
		(start 328.576686 -407.636472)
		(end 328.994008 -407.72715)
		(width 0.14224)
		(layer "In15.Cu")
		(net "P5E_CPU0_P0_RX_BUF_DP<12>")
	)
	(segment
		(start 335.202276 -409.145994)
		(end 335.773268 -409.259532)
		(width 0.14224)
		(layer "In15.Cu")
		(net "P5E_CPU0_P0_RX_BUF_DP<12>")
	)
	(segment
		(start 328.994008 -407.72715)
		(end 329.09891 -407.890472)
		(width 0.14224)
		(layer "In15.Cu")
		(net "P5E_CPU0_P0_RX_BUF_DP<12>")
	)
	(segment
		(start 340.941152 -414.361884)
		(end 341.125556 -414.806892)
		(width 0.14224)
		(layer "In15.Cu")
		(net "P5E_CPU0_P0_RX_BUF_DP<12>")
	)
	(segment
		(start 341.262716 -416.167062)
		(end 341.262716 -416.593782)
		(width 0.14224)
		(layer "In15.Cu")
		(net "P5E_CPU0_P0_RX_BUF_DP<12>")
	)
	(segment
		(start 334.675734 -408.901138)
		(end 335.09458 -408.98445)
		(width 0.14224)
		(layer "In15.Cu")
		(net "P5E_CPU0_P0_RX_BUF_DP<12>")
	)
	(segment
		(start 341.125556 -416.029902)
		(end 341.262716 -416.167062)
		(width 0.14224)
		(layer "In15.Cu")
		(net "P5E_CPU0_P0_RX_BUF_DP<12>")
	)
	(segment
		(start 336.651346 -409.600908)
		(end 337.006438 -409.838144)
		(width 0.14224)
		(layer "In15.Cu")
		(net "P5E_CPU0_P0_RX_BUF_DP<12>")
	)
	(segment
		(start 341.680038 -419.468808)
		(end 342.02624 -419.612064)
		(width 0.14224)
		(layer "In15.Cu")
		(net "P5E_CPU0_P0_RX_BUF_DP<12>")
	)
	(segment
		(start 339.922866 -413.956754)
		(end 340.435184 -413.956754)
		(width 0.14224)
		(layer "In15.Cu")
		(net "P5E_CPU0_P0_RX_BUF_DP<12>")
	)
	(segment
		(start 317.757302 -402.682202)
		(end 317.868046 -402.792946)
		(width 0.14224)
		(layer "In15.Cu")
		(net "P5E_CPU0_P0_RX_BUF_DP<12>")
	)
	(segment
		(start 317.896748 -401.371562)
		(end 317.757302 -401.511008)
		(width 0.14224)
		(layer "In15.Cu")
		(net "P5E_CPU0_P0_RX_BUF_DP<12>")
	)
	(segment
		(start 327.976992 -407.646632)
		(end 328.413618 -407.741374)
		(width 0.14224)
		(layer "In15.Cu")
		(net "P5E_CPU0_P0_RX_BUF_DP<12>")
	)
	(segment
		(start 337.044284 -410.02839)
		(end 337.398868 -410.265372)
		(width 0.14224)
		(layer "In15.Cu")
		(net "P5E_CPU0_P0_RX_BUF_DP<12>")
	)
	(segment
		(start 335.09458 -408.98445)
		(end 335.202276 -409.145994)
		(width 0.14224)
		(layer "In15.Cu")
		(net "P5E_CPU0_P0_RX_BUF_DP<12>")
	)
	(segment
		(start 331.364336 -408.38247)
		(end 334.514444 -409.009088)
		(width 0.14224)
		(layer "In15.Cu")
		(net "P5E_CPU0_P0_RX_BUF_DP<12>")
	)
	(segment
		(start 326.656446 -407.359866)
		(end 327.291446 -407.497534)
		(width 0.14224)
		(layer "In15.Cu")
		(net "P5E_CPU0_P0_RX_BUF_DP<12>")
	)
	(segment
		(start 330.207366 -408.13101)
		(end 330.370688 -408.026108)
		(width 0.14224)
		(layer "In15.Cu")
		(net "P5E_CPU0_P0_RX_BUF_DP<12>")
	)
	(segment
		(start 339.108288 -437.341264)
		(end 339.499702 -437.341264)
		(width 0.14224)
		(layer "In15.Cu")
		(net "P5E_CPU0_P0_RX_BUF_DP<12>")
	)
	(segment
		(start 341.125556 -417.157662)
		(end 341.262716 -417.294822)
		(width 0.14224)
		(layer "In15.Cu")
		(net "P5E_CPU0_P0_RX_BUF_DP<12>")
	)
	(segment
		(start 336.4611 -409.638754)
		(end 336.651346 -409.600908)
		(width 0.14224)
		(layer "In15.Cu")
		(net "P5E_CPU0_P0_RX_BUF_DP<12>")
	)
	(segment
		(start 329.09891 -407.890472)
		(end 330.207366 -408.13101)
		(width 0.14224)
		(layer "In15.Cu")
		(net "P5E_CPU0_P0_RX_BUF_DP<12>")
	)
	(segment
		(start 337.398868 -410.265372)
		(end 337.589114 -410.227526)
		(width 0.14224)
		(layer "In15.Cu")
		(net "P5E_CPU0_P0_RX_BUF_DP<12>")
	)
	(segment
		(start 337.944206 -410.464762)
		(end 337.982052 -410.655008)
		(width 0.14224)
		(layer "In15.Cu")
		(net "P5E_CPU0_P0_RX_BUF_DP<12>")
	)
	(segment
		(start 327.454768 -407.392632)
		(end 327.871836 -407.48331)
		(width 0.14224)
		(layer "In15.Cu")
		(net "P5E_CPU0_P0_RX_BUF_DP<12>")
	)
	(segment
		(start 341.262716 -417.294822)
		(end 341.262716 -417.721542)
		(width 0.14224)
		(layer "In15.Cu")
		(net "P5E_CPU0_P0_RX_BUF_DP<12>")
	)
	(segment
		(start 338.970874 -424.898566)
		(end 338.970874 -437.137048)
		(width 0.14224)
		(layer "In15.Cu")
		(net "P5E_CPU0_P0_RX_BUF_DP<12>")
	)
	(segment
		(start 340.435184 -413.956754)
		(end 340.607396 -414.028128)
		(width 0.14224)
		(layer "In15.Cu")
		(net "P5E_CPU0_P0_RX_BUF_DP<12>")
	)
	(segment
		(start 317.868046 -402.792946)
		(end 317.868046 -403.219666)
		(width 0.14224)
		(layer "In15.Cu")
		(net "P5E_CPU0_P0_RX_BUF_DP<12>")
	)
	(segment
		(start 341.262716 -417.721542)
		(end 341.125556 -417.858702)
		(width 0.14224)
		(layer "In15.Cu")
		(net "P5E_CPU0_P0_RX_BUF_DP<12>")
	)
	(segment
		(start 336.089752 -409.390596)
		(end 336.4611 -409.638754)
		(width 0.14224)
		(layer "In15.Cu")
		(net "P5E_CPU0_P0_RX_BUF_DP<12>")
	)
	(segment
		(start 342.324182 -422.087802)
		(end 339.607398 -423.90441)
		(width 0.14224)
		(layer "In15.Cu")
		(net "P5E_CPU0_P0_RX_BUF_DP<12>")
	)
	(segment
		(start 339.593936 -413.566102)
		(end 339.66658 -413.742378)
		(width 0.14224)
		(layer "In15.Cu")
		(net "P5E_CPU0_P0_RX_BUF_DP<12>")
	)
	(segment
		(start 337.006438 -409.838144)
		(end 337.044284 -410.02839)
		(width 0.14224)
		(layer "In15.Cu")
		(net "P5E_CPU0_P0_RX_BUF_DP<12>")
	)
	(segment
		(start 340.607396 -414.028128)
		(end 340.941152 -414.361884)
		(width 0.14224)
		(layer "In15.Cu")
		(net "P5E_CPU0_P0_RX_BUF_DP<12>")
	)
	(arc
		(start 319.275714 -405.091392)
		(mid 319.326904 -405.128305)
		(end 319.384934 -405.153114)
		(width 0.14224)
		(layer "In15.Cu")
		(net "P5E_CPU0_P0_RX_BUF_DP<12>")
	)
	(arc
		(start 342.537034 -420.121842)
		(mid 342.625964 -420.25465)
		(end 342.657176 -420.411402)
		(width 0.14224)
		(layer "In15.Cu")
		(net "P5E_CPU0_P0_RX_BUF_DP<12>")
	)
	(arc
		(start 339.099906 -424.490642)
		(mid 339.064795 -424.543198)
		(end 339.040724 -424.60164)
		(width 0.14224)
		(layer "In15.Cu")
		(net "P5E_CPU0_P0_RX_BUF_DP<12>")
	)
	(arc
		(start 342.657176 -421.497506)
		(mid 342.609918 -421.735178)
		(end 342.475312 -421.936672)
		(width 0.14224)
		(layer "In15.Cu")
		(net "P5E_CPU0_P0_RX_BUF_DP<12>")
	)
	(arc
		(start 339.474048 -411.967934)
		(mid 339.562792 -412.100654)
		(end 339.593936 -412.25724)
		(width 0.14224)
		(layer "In15.Cu")
		(net "P5E_CPU0_P0_RX_BUF_DP<12>")
	)
	(arc
		(start 341.351616 -419.140386)
		(mid 341.483196 -419.337228)
		(end 341.680038 -419.468808)
		(width 0.14224)
		(layer "In15.Cu")
		(net "P5E_CPU0_P0_RX_BUF_DP<12>")
	)
	(arc
		(start 338.46897 -410.980382)
		(mid 338.519845 -411.018103)
		(end 338.56676 -411.060646)
		(width 0.14224)
		(layer "In15.Cu")
		(net "P5E_CPU0_P0_RX_BUF_DP<12>")
	)
	(arc
		(start 338.989162 -424.773852)
		(mid 338.975493 -424.835544)
		(end 338.970874 -424.898566)
		(width 0.14224)
		(layer "In15.Cu")
		(net "P5E_CPU0_P0_RX_BUF_DP<12>")
	)
	(arc
		(start 335.773268 -409.259532)
		(mid 335.937965 -409.309477)
		(end 336.089752 -409.390596)
		(width 0.14224)
		(layer "In15.Cu")
		(net "P5E_CPU0_P0_RX_BUF_DP<12>")
	)
	(arc
		(start 317.769748 -403.66442)
		(mid 317.788324 -403.72604)
		(end 317.827406 -403.777196)
		(width 0.14224)
		(layer "In15.Cu")
		(net "P5E_CPU0_P0_RX_BUF_DP<12>")
	)
	(arc
		(start 338.970874 -437.137048)
		(mid 338.983151 -437.198771)
		(end 339.018118 -437.251094)
		(width 0.14224)
		(layer "In15.Cu")
		(net "P5E_CPU0_P0_RX_BUF_DP<12>")
	)
	(arc
		(start 317.757302 -403.448012)
		(mid 317.760468 -403.556392)
		(end 317.769748 -403.66442)
		(width 0.14224)
		(layer "In15.Cu")
		(net "P5E_CPU0_P0_RX_BUF_DP<12>")
	)
	(segment
		(start 316.313566 -399.959322)
		(end 316.313566 -401.105878)
		(width 0.1016)
		(layer "F.Cu")
		(net "P5E_CPU0_P0_RX_BUF_DP<11>")
	)
	(segment
		(start 316.402212 -399.870676)
		(end 316.313566 -399.959322)
		(width 0.1016)
		(layer "F.Cu")
		(net "P5E_CPU0_P0_RX_BUF_DP<11>")
	)
	(segment
		(start 316.402212 -399.74774)
		(end 316.402212 -399.870676)
		(width 0.1016)
		(layer "F.Cu")
		(net "P5E_CPU0_P0_RX_BUF_DP<11>")
	)
	(segment
		(start 316.877446 -401.359116)
		(end 317.016384 -401.498054)
		(width 0.1016)
		(layer "F.Cu")
		(net "P5E_CPU0_P0_RX_BUF_DP<11>")
	)
	(segment
		(start 316.31763 -399.663158)
		(end 316.402212 -399.74774)
		(width 0.1016)
		(layer "F.Cu")
		(net "P5E_CPU0_P0_RX_BUF_DP<11>")
	)
	(segment
		(start 316.566804 -401.359116)
		(end 316.877446 -401.359116)
		(width 0.1016)
		(layer "F.Cu")
		(net "P5E_CPU0_P0_RX_BUF_DP<11>")
	)
	(segment
		(start 316.313566 -401.105878)
		(end 316.566804 -401.359116)
		(width 0.1016)
		(layer "F.Cu")
		(net "P5E_CPU0_P0_RX_BUF_DP<11>")
	)
	(segment
		(start 317.016384 -401.498054)
		(end 317.016384 -401.674838)
		(width 0.1016)
		(layer "F.Cu")
		(net "P5E_CPU0_P0_RX_BUF_DP<11>")
	)
	(segment
		(start 337.108292 -438.341262)
		(end 337.499706 -438.341262)
		(width 0.14224)
		(layer "In15.Cu")
		(net "P5E_CPU0_P0_RX_BUF_DP<11>")
	)
	(segment
		(start 338.91855 -419.593776)
		(end 339.473794 -420.147496)
		(width 0.14224)
		(layer "In15.Cu")
		(net "P5E_CPU0_P0_RX_BUF_DP<11>")
	)
	(segment
		(start 316.694566 -403.018244)
		(end 316.694566 -403.444964)
		(width 0.14224)
		(layer "In15.Cu")
		(net "P5E_CPU0_P0_RX_BUF_DP<11>")
	)
	(segment
		(start 336.787998 -413.927036)
		(end 336.859626 -413.956754)
		(width 0.14224)
		(layer "In15.Cu")
		(net "P5E_CPU0_P0_RX_BUF_DP<11>")
	)
	(segment
		(start 336.530696 -413.566864)
		(end 336.60334 -413.742378)
		(width 0.14224)
		(layer "In15.Cu")
		(net "P5E_CPU0_P0_RX_BUF_DP<11>")
	)
	(segment
		(start 316.557406 -403.582124)
		(end 316.557406 -403.970998)
		(width 0.14224)
		(layer "In15.Cu")
		(net "P5E_CPU0_P0_RX_BUF_DP<11>")
	)
	(segment
		(start 338.861654 -422.549828)
		(end 338.667598 -422.549828)
		(width 0.14224)
		(layer "In15.Cu")
		(net "P5E_CPU0_P0_RX_BUF_DP<11>")
	)
	(segment
		(start 337.018122 -438.251092)
		(end 337.108292 -438.341262)
		(width 0.14224)
		(layer "In15.Cu")
		(net "P5E_CPU0_P0_RX_BUF_DP<11>")
	)
	(segment
		(start 338.199476 -416.500056)
		(end 338.062316 -416.637216)
		(width 0.14224)
		(layer "In15.Cu")
		(net "P5E_CPU0_P0_RX_BUF_DP<11>")
	)
	(segment
		(start 338.3661 -422.851326)
		(end 338.3661 -423.045382)
		(width 0.14224)
		(layer "In15.Cu")
		(net "P5E_CPU0_P0_RX_BUF_DP<11>")
	)
	(segment
		(start 316.557406 -402.881084)
		(end 316.694566 -403.018244)
		(width 0.14224)
		(layer "In15.Cu")
		(net "P5E_CPU0_P0_RX_BUF_DP<11>")
	)
	(segment
		(start 336.530696 -412.405576)
		(end 336.530696 -413.566864)
		(width 0.14224)
		(layer "In15.Cu")
		(net "P5E_CPU0_P0_RX_BUF_DP<11>")
	)
	(segment
		(start 337.557364 -423.660062)
		(end 337.077812 -424.377612)
		(width 0.14224)
		(layer "In15.Cu")
		(net "P5E_CPU0_P0_RX_BUF_DP<11>")
	)
	(segment
		(start 316.694566 -403.444964)
		(end 316.557406 -403.582124)
		(width 0.14224)
		(layer "In15.Cu")
		(net "P5E_CPU0_P0_RX_BUF_DP<11>")
	)
	(segment
		(start 317.401448 -404.921974)
		(end 317.59525 -404.912322)
		(width 0.14224)
		(layer "In15.Cu")
		(net "P5E_CPU0_P0_RX_BUF_DP<11>")
	)
	(segment
		(start 317.016384 -401.511008)
		(end 316.876938 -401.371562)
		(width 0.14224)
		(layer "In15.Cu")
		(net "P5E_CPU0_P0_RX_BUF_DP<11>")
	)
	(segment
		(start 338.064094 -423.347388)
		(end 337.870038 -423.347388)
		(width 0.14224)
		(layer "In15.Cu")
		(net "P5E_CPU0_P0_RX_BUF_DP<11>")
	)
	(segment
		(start 339.16366 -422.053766)
		(end 339.16366 -422.247822)
		(width 0.14224)
		(layer "In15.Cu")
		(net "P5E_CPU0_P0_RX_BUF_DP<11>")
	)
	(segment
		(start 317.911988 -405.199088)
		(end 317.92164 -405.392636)
		(width 0.14224)
		(layer "In15.Cu")
		(net "P5E_CPU0_P0_RX_BUF_DP<11>")
	)
	(segment
		(start 332.528672 -409.74899)
		(end 332.52918 -409.749752)
		(width 0.14224)
		(layer "In15.Cu")
		(net "P5E_CPU0_P0_RX_BUF_DP<11>")
	)
	(segment
		(start 336.60334 -413.742378)
		(end 336.787998 -413.927036)
		(width 0.14224)
		(layer "In15.Cu")
		(net "P5E_CPU0_P0_RX_BUF_DP<11>")
	)
	(segment
		(start 332.52918 -409.749752)
		(end 333.564992 -409.982416)
		(width 0.14224)
		(layer "In15.Cu")
		(net "P5E_CPU0_P0_RX_BUF_DP<11>")
	)
	(segment
		(start 338.062316 -415.936176)
		(end 338.199476 -416.073336)
		(width 0.14224)
		(layer "In15.Cu")
		(net "P5E_CPU0_P0_RX_BUF_DP<11>")
	)
	(segment
		(start 338.062316 -416.637216)
		(end 338.062316 -417.063936)
		(width 0.14224)
		(layer "In15.Cu")
		(net "P5E_CPU0_P0_RX_BUF_DP<11>")
	)
	(segment
		(start 338.3661 -423.045382)
		(end 338.064094 -423.347388)
		(width 0.14224)
		(layer "In15.Cu")
		(net "P5E_CPU0_P0_RX_BUF_DP<11>")
	)
	(segment
		(start 331.844396 -409.59532)
		(end 332.008226 -409.491434)
		(width 0.14224)
		(layer "In15.Cu")
		(net "P5E_CPU0_P0_RX_BUF_DP<11>")
	)
	(segment
		(start 336.859626 -413.956754)
		(end 337.371944 -413.956754)
		(width 0.14224)
		(layer "In15.Cu")
		(net "P5E_CPU0_P0_RX_BUF_DP<11>")
	)
	(segment
		(start 332.008226 -409.491434)
		(end 332.424786 -409.584906)
		(width 0.14224)
		(layer "In15.Cu")
		(net "P5E_CPU0_P0_RX_BUF_DP<11>")
	)
	(segment
		(start 339.474048 -421.743378)
		(end 339.16366 -422.053766)
		(width 0.14224)
		(layer "In15.Cu")
		(net "P5E_CPU0_P0_RX_BUF_DP<11>")
	)
	(segment
		(start 339.16366 -422.247822)
		(end 338.861654 -422.549828)
		(width 0.14224)
		(layer "In15.Cu")
		(net "P5E_CPU0_P0_RX_BUF_DP<11>")
	)
	(segment
		(start 337.870038 -423.347388)
		(end 337.557364 -423.660062)
		(width 0.14224)
		(layer "In15.Cu")
		(net "P5E_CPU0_P0_RX_BUF_DP<11>")
	)
	(segment
		(start 337.499706 -438.341262)
		(end 337.64982 -438.191148)
		(width 0.14224)
		(layer "In15.Cu")
		(net "P5E_CPU0_P0_RX_BUF_DP<11>")
	)
	(segment
		(start 330.743814 -409.347924)
		(end 330.903326 -409.246832)
		(width 0.14224)
		(layer "In15.Cu")
		(net "P5E_CPU0_P0_RX_BUF_DP<11>")
	)
	(segment
		(start 316.557406 -401.511008)
		(end 316.557406 -402.881084)
		(width 0.14224)
		(layer "In15.Cu")
		(net "P5E_CPU0_P0_RX_BUF_DP<11>")
	)
	(segment
		(start 338.062316 -417.063936)
		(end 338.199476 -417.201096)
		(width 0.14224)
		(layer "In15.Cu")
		(net "P5E_CPU0_P0_RX_BUF_DP<11>")
	)
	(segment
		(start 338.062316 -414.806892)
		(end 338.062316 -415.936176)
		(width 0.14224)
		(layer "In15.Cu")
		(net "P5E_CPU0_P0_RX_BUF_DP<11>")
	)
	(segment
		(start 335.923382 -411.526736)
		(end 336.338672 -411.942026)
		(width 0.14224)
		(layer "In15.Cu")
		(net "P5E_CPU0_P0_RX_BUF_DP<11>")
	)
	(segment
		(start 316.696852 -401.371562)
		(end 316.557406 -401.511008)
		(width 0.14224)
		(layer "In15.Cu")
		(net "P5E_CPU0_P0_RX_BUF_DP<11>")
	)
	(segment
		(start 333.864712 -410.113226)
		(end 335.923382 -411.526736)
		(width 0.14224)
		(layer "In15.Cu")
		(net "P5E_CPU0_P0_RX_BUF_DP<11>")
	)
	(segment
		(start 337.371944 -413.956754)
		(end 337.544156 -414.028128)
		(width 0.14224)
		(layer "In15.Cu")
		(net "P5E_CPU0_P0_RX_BUF_DP<11>")
	)
	(segment
		(start 338.199476 -416.073336)
		(end 338.199476 -416.500056)
		(width 0.14224)
		(layer "In15.Cu")
		(net "P5E_CPU0_P0_RX_BUF_DP<11>")
	)
	(segment
		(start 330.903326 -409.246832)
		(end 331.326998 -409.341828)
		(width 0.14224)
		(layer "In15.Cu")
		(net "P5E_CPU0_P0_RX_BUF_DP<11>")
	)
	(segment
		(start 337.877912 -414.361884)
		(end 338.062316 -414.806892)
		(width 0.14224)
		(layer "In15.Cu")
		(net "P5E_CPU0_P0_RX_BUF_DP<11>")
	)
	(segment
		(start 337.544156 -414.028128)
		(end 337.877912 -414.361884)
		(width 0.14224)
		(layer "In15.Cu")
		(net "P5E_CPU0_P0_RX_BUF_DP<11>")
	)
	(segment
		(start 338.062316 -417.764976)
		(end 338.062316 -418.665914)
		(width 0.14224)
		(layer "In15.Cu")
		(net "P5E_CPU0_P0_RX_BUF_DP<11>")
	)
	(segment
		(start 338.199476 -417.201096)
		(end 338.199476 -417.627816)
		(width 0.14224)
		(layer "In15.Cu")
		(net "P5E_CPU0_P0_RX_BUF_DP<11>")
	)
	(segment
		(start 331.42809 -409.501848)
		(end 331.844396 -409.59532)
		(width 0.14224)
		(layer "In15.Cu")
		(net "P5E_CPU0_P0_RX_BUF_DP<11>")
	)
	(segment
		(start 316.666626 -404.257002)
		(end 317.401448 -404.921974)
		(width 0.14224)
		(layer "In15.Cu")
		(net "P5E_CPU0_P0_RX_BUF_DP<11>")
	)
	(segment
		(start 327.683368 -408.660346)
		(end 330.743814 -409.347924)
		(width 0.14224)
		(layer "In15.Cu")
		(net "P5E_CPU0_P0_RX_BUF_DP<11>")
	)
	(segment
		(start 338.54136 -419.437312)
		(end 338.91855 -419.593776)
		(width 0.14224)
		(layer "In15.Cu")
		(net "P5E_CPU0_P0_RX_BUF_DP<11>")
	)
	(segment
		(start 317.92164 -405.392636)
		(end 318.23787 -405.678894)
		(width 0.14224)
		(layer "In15.Cu")
		(net "P5E_CPU0_P0_RX_BUF_DP<11>")
	)
	(segment
		(start 338.667598 -422.549828)
		(end 338.3661 -422.851326)
		(width 0.14224)
		(layer "In15.Cu")
		(net "P5E_CPU0_P0_RX_BUF_DP<11>")
	)
	(segment
		(start 338.199476 -417.627816)
		(end 338.062316 -417.764976)
		(width 0.14224)
		(layer "In15.Cu")
		(net "P5E_CPU0_P0_RX_BUF_DP<11>")
	)
	(segment
		(start 336.970878 -424.687746)
		(end 336.970878 -438.137046)
		(width 0.14224)
		(layer "In15.Cu")
		(net "P5E_CPU0_P0_RX_BUF_DP<11>")
	)
	(segment
		(start 318.678052 -405.927814)
		(end 327.683368 -408.660346)
		(width 0.14224)
		(layer "In15.Cu")
		(net "P5E_CPU0_P0_RX_BUF_DP<11>")
	)
	(segment
		(start 316.876938 -401.371562)
		(end 316.696852 -401.371562)
		(width 0.14224)
		(layer "In15.Cu")
		(net "P5E_CPU0_P0_RX_BUF_DP<11>")
	)
	(segment
		(start 317.59525 -404.912322)
		(end 317.911988 -405.199088)
		(width 0.14224)
		(layer "In15.Cu")
		(net "P5E_CPU0_P0_RX_BUF_DP<11>")
	)
	(segment
		(start 338.062316 -418.665914)
		(end 338.269834 -419.165786)
		(width 0.14224)
		(layer "In15.Cu")
		(net "P5E_CPU0_P0_RX_BUF_DP<11>")
	)
	(segment
		(start 337.64982 -438.191148)
		(end 337.64982 -437.889904)
		(width 0.14224)
		(layer "In15.Cu")
		(net "P5E_CPU0_P0_RX_BUF_DP<11>")
	)
	(segment
		(start 332.424786 -409.584906)
		(end 332.528672 -409.74899)
		(width 0.14224)
		(layer "In15.Cu")
		(net "P5E_CPU0_P0_RX_BUF_DP<11>")
	)
	(segment
		(start 339.593936 -420.437056)
		(end 339.593936 -421.453818)
		(width 0.14224)
		(layer "In15.Cu")
		(net "P5E_CPU0_P0_RX_BUF_DP<11>")
	)
	(segment
		(start 317.016384 -401.674838)
		(end 317.016384 -401.511008)
		(width 0.14224)
		(layer "In15.Cu")
		(net "P5E_CPU0_P0_RX_BUF_DP<11>")
	)
	(segment
		(start 331.326998 -409.341828)
		(end 331.42809 -409.501848)
		(width 0.14224)
		(layer "In15.Cu")
		(net "P5E_CPU0_P0_RX_BUF_DP<11>")
	)
	(arc
		(start 339.473794 -420.147496)
		(mid 339.562724 -420.280304)
		(end 339.593936 -420.437056)
		(width 0.14224)
		(layer "In15.Cu")
		(net "P5E_CPU0_P0_RX_BUF_DP<11>")
	)
	(arc
		(start 336.970878 -438.137046)
		(mid 336.983155 -438.198769)
		(end 337.018122 -438.251092)
		(width 0.14224)
		(layer "In15.Cu")
		(net "P5E_CPU0_P0_RX_BUF_DP<11>")
	)
	(arc
		(start 333.564992 -409.982416)
		(mid 333.721094 -410.03352)
		(end 333.864712 -410.113226)
		(width 0.14224)
		(layer "In15.Cu")
		(net "P5E_CPU0_P0_RX_BUF_DP<11>")
	)
	(arc
		(start 339.593936 -421.453818)
		(mid 339.562784 -421.610521)
		(end 339.474048 -421.743378)
		(width 0.14224)
		(layer "In15.Cu")
		(net "P5E_CPU0_P0_RX_BUF_DP<11>")
	)
	(arc
		(start 318.23787 -405.678894)
		(mid 318.444192 -405.827699)
		(end 318.678052 -405.927814)
		(width 0.14224)
		(layer "In15.Cu")
		(net "P5E_CPU0_P0_RX_BUF_DP<11>")
	)
	(arc
		(start 338.269834 -419.165786)
		(mid 338.378613 -419.328533)
		(end 338.54136 -419.437312)
		(width 0.14224)
		(layer "In15.Cu")
		(net "P5E_CPU0_P0_RX_BUF_DP<11>")
	)
	(arc
		(start 316.557406 -403.970998)
		(mid 316.56659 -404.063974)
		(end 316.593728 -404.15337)
		(width 0.14224)
		(layer "In15.Cu")
		(net "P5E_CPU0_P0_RX_BUF_DP<11>")
	)
	(arc
		(start 337.077812 -424.377612)
		(mid 337.027011 -424.466991)
		(end 336.989674 -424.562778)
		(width 0.14224)
		(layer "In15.Cu")
		(net "P5E_CPU0_P0_RX_BUF_DP<11>")
	)
	(arc
		(start 316.593728 -404.15337)
		(mid 316.624379 -404.209268)
		(end 316.666626 -404.257002)
		(width 0.14224)
		(layer "In15.Cu")
		(net "P5E_CPU0_P0_RX_BUF_DP<11>")
	)
	(arc
		(start 336.989674 -424.562778)
		(mid 336.97561 -424.624559)
		(end 336.970878 -424.687746)
		(width 0.14224)
		(layer "In15.Cu")
		(net "P5E_CPU0_P0_RX_BUF_DP<11>")
	)
	(arc
		(start 336.338672 -411.942026)
		(mid 336.480779 -412.154705)
		(end 336.530696 -412.405576)
		(width 0.14224)
		(layer "In15.Cu")
		(net "P5E_CPU0_P0_RX_BUF_DP<11>")
	)
	(segment
		(start 315.11367 -399.959322)
		(end 315.201808 -399.871184)
		(width 0.1016)
		(layer "F.Cu")
		(net "P5E_CPU0_P0_RX_BUF_DP<10>")
	)
	(segment
		(start 315.67755 -401.359116)
		(end 315.366908 -401.359116)
		(width 0.1016)
		(layer "F.Cu")
		(net "P5E_CPU0_P0_RX_BUF_DP<10>")
	)
	(segment
		(start 315.816488 -401.498054)
		(end 315.67755 -401.359116)
		(width 0.1016)
		(layer "F.Cu")
		(net "P5E_CPU0_P0_RX_BUF_DP<10>")
	)
	(segment
		(start 315.816488 -401.674838)
		(end 315.816488 -401.498054)
		(width 0.1016)
		(layer "F.Cu")
		(net "P5E_CPU0_P0_RX_BUF_DP<10>")
	)
	(segment
		(start 315.11367 -401.105878)
		(end 315.11367 -399.959322)
		(width 0.1016)
		(layer "F.Cu")
		(net "P5E_CPU0_P0_RX_BUF_DP<10>")
	)
	(segment
		(start 315.201808 -399.747232)
		(end 315.117734 -399.663158)
		(width 0.1016)
		(layer "F.Cu")
		(net "P5E_CPU0_P0_RX_BUF_DP<10>")
	)
	(segment
		(start 315.201808 -399.871184)
		(end 315.201808 -399.747232)
		(width 0.1016)
		(layer "F.Cu")
		(net "P5E_CPU0_P0_RX_BUF_DP<10>")
	)
	(segment
		(start 315.366908 -401.359116)
		(end 315.11367 -401.105878)
		(width 0.1016)
		(layer "F.Cu")
		(net "P5E_CPU0_P0_RX_BUF_DP<10>")
	)
	(segment
		(start 335.649824 -437.19115)
		(end 335.649824 -436.889906)
		(width 0.14224)
		(layer "In15.Cu")
		(net "P5E_CPU0_P0_RX_BUF_DP<10>")
	)
	(segment
		(start 333.724758 -413.927036)
		(end 333.796386 -413.956754)
		(width 0.14224)
		(layer "In15.Cu")
		(net "P5E_CPU0_P0_RX_BUF_DP<10>")
	)
	(segment
		(start 333.467456 -413.566864)
		(end 333.5401 -413.742378)
		(width 0.14224)
		(layer "In15.Cu")
		(net "P5E_CPU0_P0_RX_BUF_DP<10>")
	)
	(segment
		(start 334.999076 -417.783264)
		(end 334.999076 -418.704522)
		(width 0.14224)
		(layer "In15.Cu")
		(net "P5E_CPU0_P0_RX_BUF_DP<10>")
	)
	(segment
		(start 328.823066 -410.146754)
		(end 328.994262 -410.055314)
		(width 0.14224)
		(layer "In15.Cu")
		(net "P5E_CPU0_P0_RX_BUF_DP<10>")
	)
	(segment
		(start 328.994262 -410.055314)
		(end 329.402694 -410.179266)
		(width 0.14224)
		(layer "In15.Cu")
		(net "P5E_CPU0_P0_RX_BUF_DP<10>")
	)
	(segment
		(start 335.667096 -423.437812)
		(end 335.704942 -423.628058)
		(width 0.14224)
		(layer "In15.Cu")
		(net "P5E_CPU0_P0_RX_BUF_DP<10>")
	)
	(segment
		(start 329.494134 -410.350462)
		(end 329.902312 -410.47416)
		(width 0.14224)
		(layer "In15.Cu")
		(net "P5E_CPU0_P0_RX_BUF_DP<10>")
	)
	(segment
		(start 328.323448 -409.85186)
		(end 328.414888 -410.023056)
		(width 0.14224)
		(layer "In15.Cu")
		(net "P5E_CPU0_P0_RX_BUF_DP<10>")
	)
	(segment
		(start 335.65084 -419.509448)
		(end 335.809336 -419.574726)
		(width 0.14224)
		(layer "In15.Cu")
		(net "P5E_CPU0_P0_RX_BUF_DP<10>")
	)
	(segment
		(start 335.704942 -423.628058)
		(end 335.467706 -423.98315)
		(width 0.14224)
		(layer "In15.Cu")
		(net "P5E_CPU0_P0_RX_BUF_DP<10>")
	)
	(segment
		(start 315.677042 -401.371562)
		(end 315.496956 -401.371562)
		(width 0.14224)
		(layer "In15.Cu")
		(net "P5E_CPU0_P0_RX_BUF_DP<10>")
	)
	(segment
		(start 335.49971 -437.341264)
		(end 335.649824 -437.19115)
		(width 0.14224)
		(layer "In15.Cu")
		(net "P5E_CPU0_P0_RX_BUF_DP<10>")
	)
	(segment
		(start 334.480916 -414.028128)
		(end 334.814672 -414.361884)
		(width 0.14224)
		(layer "In15.Cu")
		(net "P5E_CPU0_P0_RX_BUF_DP<10>")
	)
	(segment
		(start 334.970882 -437.199024)
		(end 335.113122 -437.341264)
		(width 0.14224)
		(layer "In15.Cu")
		(net "P5E_CPU0_P0_RX_BUF_DP<10>")
	)
	(segment
		(start 315.816488 -401.511008)
		(end 315.677042 -401.371562)
		(width 0.14224)
		(layer "In15.Cu")
		(net "P5E_CPU0_P0_RX_BUF_DP<10>")
	)
	(segment
		(start 329.902312 -410.47416)
		(end 330.073508 -410.38272)
		(width 0.14224)
		(layer "In15.Cu")
		(net "P5E_CPU0_P0_RX_BUF_DP<10>")
	)
	(segment
		(start 330.48194 -410.506672)
		(end 330.57338 -410.677868)
		(width 0.14224)
		(layer "In15.Cu")
		(net "P5E_CPU0_P0_RX_BUF_DP<10>")
	)
	(segment
		(start 335.136236 -416.091624)
		(end 335.136236 -416.518344)
		(width 0.14224)
		(layer "In15.Cu")
		(net "P5E_CPU0_P0_RX_BUF_DP<10>")
	)
	(segment
		(start 334.999076 -417.082224)
		(end 335.136236 -417.219384)
		(width 0.14224)
		(layer "In15.Cu")
		(net "P5E_CPU0_P0_RX_BUF_DP<10>")
	)
	(segment
		(start 315.35751 -403.020022)
		(end 315.49467 -403.157182)
		(width 0.14224)
		(layer "In15.Cu")
		(net "P5E_CPU0_P0_RX_BUF_DP<10>")
	)
	(segment
		(start 336.33156 -422.69029)
		(end 336.094324 -423.045382)
		(width 0.14224)
		(layer "In15.Cu")
		(net "P5E_CPU0_P0_RX_BUF_DP<10>")
	)
	(segment
		(start 335.27746 -424.020996)
		(end 334.970882 -424.47972)
		(width 0.14224)
		(layer "In15.Cu")
		(net "P5E_CPU0_P0_RX_BUF_DP<10>")
	)
	(segment
		(start 330.073508 -410.38272)
		(end 330.48194 -410.506672)
		(width 0.14224)
		(layer "In15.Cu")
		(net "P5E_CPU0_P0_RX_BUF_DP<10>")
	)
	(segment
		(start 333.467456 -412.4579)
		(end 333.467456 -413.566864)
		(width 0.14224)
		(layer "In15.Cu")
		(net "P5E_CPU0_P0_RX_BUF_DP<10>")
	)
	(segment
		(start 317.295022 -406.224994)
		(end 317.58509 -406.451308)
		(width 0.14224)
		(layer "In15.Cu")
		(net "P5E_CPU0_P0_RX_BUF_DP<10>")
	)
	(segment
		(start 336.094324 -423.045382)
		(end 335.904078 -423.083228)
		(width 0.14224)
		(layer "In15.Cu")
		(net "P5E_CPU0_P0_RX_BUF_DP<10>")
	)
	(segment
		(start 329.402694 -410.179266)
		(end 329.494134 -410.350462)
		(width 0.14224)
		(layer "In15.Cu")
		(net "P5E_CPU0_P0_RX_BUF_DP<10>")
	)
	(segment
		(start 328.414888 -410.023056)
		(end 328.823066 -410.146754)
		(width 0.14224)
		(layer "In15.Cu")
		(net "P5E_CPU0_P0_RX_BUF_DP<10>")
	)
	(segment
		(start 335.809336 -419.574726)
		(end 336.410808 -420.176198)
		(width 0.14224)
		(layer "In15.Cu")
		(net "P5E_CPU0_P0_RX_BUF_DP<10>")
	)
	(segment
		(start 315.496956 -401.371562)
		(end 315.35751 -401.511008)
		(width 0.14224)
		(layer "In15.Cu")
		(net "P5E_CPU0_P0_RX_BUF_DP<10>")
	)
	(segment
		(start 324.859142 -408.77998)
		(end 325.17715 -409.040838)
		(width 0.14224)
		(layer "In15.Cu")
		(net "P5E_CPU0_P0_RX_BUF_DP<10>")
	)
	(segment
		(start 333.5401 -413.742378)
		(end 333.724758 -413.927036)
		(width 0.14224)
		(layer "In15.Cu")
		(net "P5E_CPU0_P0_RX_BUF_DP<10>")
	)
	(segment
		(start 325.756524 -409.073096)
		(end 326.16521 -409.197048)
		(width 0.14224)
		(layer "In15.Cu")
		(net "P5E_CPU0_P0_RX_BUF_DP<10>")
	)
	(segment
		(start 325.585328 -409.164536)
		(end 325.756524 -409.073096)
		(width 0.14224)
		(layer "In15.Cu")
		(net "P5E_CPU0_P0_RX_BUF_DP<10>")
	)
	(segment
		(start 334.308704 -413.956754)
		(end 334.480916 -414.028128)
		(width 0.14224)
		(layer "In15.Cu")
		(net "P5E_CPU0_P0_RX_BUF_DP<10>")
	)
	(segment
		(start 334.970882 -424.47972)
		(end 334.970882 -437.199024)
		(width 0.14224)
		(layer "In15.Cu")
		(net "P5E_CPU0_P0_RX_BUF_DP<10>")
	)
	(segment
		(start 315.816488 -401.674838)
		(end 315.816488 -401.511008)
		(width 0.14224)
		(layer "In15.Cu")
		(net "P5E_CPU0_P0_RX_BUF_DP<10>")
	)
	(segment
		(start 334.999076 -418.704522)
		(end 335.10728 -418.96538)
		(width 0.14224)
		(layer "In15.Cu")
		(net "P5E_CPU0_P0_RX_BUF_DP<10>")
	)
	(segment
		(start 315.49467 -403.583902)
		(end 315.35751 -403.721062)
		(width 0.14224)
		(layer "In15.Cu")
		(net "P5E_CPU0_P0_RX_BUF_DP<10>")
	)
	(segment
		(start 334.999076 -415.954464)
		(end 335.136236 -416.091624)
		(width 0.14224)
		(layer "In15.Cu")
		(net "P5E_CPU0_P0_RX_BUF_DP<10>")
	)
	(segment
		(start 315.44641 -404.376382)
		(end 317.295022 -406.224994)
		(width 0.14224)
		(layer "In15.Cu")
		(net "P5E_CPU0_P0_RX_BUF_DP<10>")
	)
	(segment
		(start 336.530696 -420.465504)
		(end 336.530696 -422.021508)
		(width 0.14224)
		(layer "In15.Cu")
		(net "P5E_CPU0_P0_RX_BUF_DP<10>")
	)
	(segment
		(start 334.999076 -414.806892)
		(end 334.999076 -415.954464)
		(width 0.14224)
		(layer "In15.Cu")
		(net "P5E_CPU0_P0_RX_BUF_DP<10>")
	)
	(segment
		(start 335.113122 -437.341264)
		(end 335.49971 -437.341264)
		(width 0.14224)
		(layer "In15.Cu")
		(net "P5E_CPU0_P0_RX_BUF_DP<10>")
	)
	(segment
		(start 335.904078 -423.083228)
		(end 335.667096 -423.437812)
		(width 0.14224)
		(layer "In15.Cu")
		(net "P5E_CPU0_P0_RX_BUF_DP<10>")
	)
	(segment
		(start 315.35751 -401.511008)
		(end 315.35751 -403.020022)
		(width 0.14224)
		(layer "In15.Cu")
		(net "P5E_CPU0_P0_RX_BUF_DP<10>")
	)
	(segment
		(start 327.915016 -409.727908)
		(end 328.323448 -409.85186)
		(width 0.14224)
		(layer "In15.Cu")
		(net "P5E_CPU0_P0_RX_BUF_DP<10>")
	)
	(segment
		(start 326.16521 -409.197048)
		(end 326.25665 -409.368244)
		(width 0.14224)
		(layer "In15.Cu")
		(net "P5E_CPU0_P0_RX_BUF_DP<10>")
	)
	(segment
		(start 330.57338 -410.677868)
		(end 332.431644 -411.24124)
		(width 0.14224)
		(layer "In15.Cu")
		(net "P5E_CPU0_P0_RX_BUF_DP<10>")
	)
	(segment
		(start 325.17715 -409.040838)
		(end 325.585328 -409.164536)
		(width 0.14224)
		(layer "In15.Cu")
		(net "P5E_CPU0_P0_RX_BUF_DP<10>")
	)
	(segment
		(start 318.154304 -406.746456)
		(end 324.859142 -408.77998)
		(width 0.14224)
		(layer "In15.Cu")
		(net "P5E_CPU0_P0_RX_BUF_DP<10>")
	)
	(segment
		(start 335.467706 -423.98315)
		(end 335.27746 -424.020996)
		(width 0.14224)
		(layer "In15.Cu")
		(net "P5E_CPU0_P0_RX_BUF_DP<10>")
	)
	(segment
		(start 335.136236 -416.518344)
		(end 334.999076 -416.655504)
		(width 0.14224)
		(layer "In15.Cu")
		(net "P5E_CPU0_P0_RX_BUF_DP<10>")
	)
	(segment
		(start 336.293714 -422.500044)
		(end 336.33156 -422.69029)
		(width 0.14224)
		(layer "In15.Cu")
		(net "P5E_CPU0_P0_RX_BUF_DP<10>")
	)
	(segment
		(start 334.999076 -416.655504)
		(end 334.999076 -417.082224)
		(width 0.14224)
		(layer "In15.Cu")
		(net "P5E_CPU0_P0_RX_BUF_DP<10>")
	)
	(segment
		(start 315.35751 -403.721062)
		(end 315.35751 -404.162006)
		(width 0.14224)
		(layer "In15.Cu")
		(net "P5E_CPU0_P0_RX_BUF_DP<10>")
	)
	(segment
		(start 334.814672 -414.361884)
		(end 334.999076 -414.806892)
		(width 0.14224)
		(layer "In15.Cu")
		(net "P5E_CPU0_P0_RX_BUF_DP<10>")
	)
	(segment
		(start 333.065882 -411.718252)
		(end 333.401416 -412.235142)
		(width 0.14224)
		(layer "In15.Cu")
		(net "P5E_CPU0_P0_RX_BUF_DP<10>")
	)
	(segment
		(start 336.461608 -422.248838)
		(end 336.293714 -422.500044)
		(width 0.14224)
		(layer "In15.Cu")
		(net "P5E_CPU0_P0_RX_BUF_DP<10>")
	)
	(segment
		(start 335.136236 -417.219384)
		(end 335.136236 -417.646104)
		(width 0.14224)
		(layer "In15.Cu")
		(net "P5E_CPU0_P0_RX_BUF_DP<10>")
	)
	(segment
		(start 335.136236 -417.646104)
		(end 334.999076 -417.783264)
		(width 0.14224)
		(layer "In15.Cu")
		(net "P5E_CPU0_P0_RX_BUF_DP<10>")
	)
	(segment
		(start 326.25665 -409.368244)
		(end 327.74382 -409.819348)
		(width 0.14224)
		(layer "In15.Cu")
		(net "P5E_CPU0_P0_RX_BUF_DP<10>")
	)
	(segment
		(start 333.796386 -413.956754)
		(end 334.308704 -413.956754)
		(width 0.14224)
		(layer "In15.Cu")
		(net "P5E_CPU0_P0_RX_BUF_DP<10>")
	)
	(segment
		(start 315.49467 -403.157182)
		(end 315.49467 -403.583902)
		(width 0.14224)
		(layer "In15.Cu")
		(net "P5E_CPU0_P0_RX_BUF_DP<10>")
	)
	(segment
		(start 327.74382 -409.819348)
		(end 327.915016 -409.727908)
		(width 0.14224)
		(layer "In15.Cu")
		(net "P5E_CPU0_P0_RX_BUF_DP<10>")
	)
	(arc
		(start 336.530696 -422.021508)
		(mid 336.51299 -422.140284)
		(end 336.461608 -422.248838)
		(width 0.14224)
		(layer "In15.Cu")
		(net "P5E_CPU0_P0_RX_BUF_DP<10>")
	)
	(arc
		(start 336.410808 -420.176198)
		(mid 336.499552 -420.308918)
		(end 336.530696 -420.465504)
		(width 0.14224)
		(layer "In15.Cu")
		(net "P5E_CPU0_P0_RX_BUF_DP<10>")
	)
	(arc
		(start 333.401416 -412.235142)
		(mid 333.450601 -412.341729)
		(end 333.467456 -412.4579)
		(width 0.14224)
		(layer "In15.Cu")
		(net "P5E_CPU0_P0_RX_BUF_DP<10>")
	)
	(arc
		(start 317.58509 -406.451308)
		(mid 317.85605 -406.625204)
		(end 318.154304 -406.746456)
		(width 0.14224)
		(layer "In15.Cu")
		(net "P5E_CPU0_P0_RX_BUF_DP<10>")
	)
	(arc
		(start 332.431644 -411.24124)
		(mid 332.790996 -411.423602)
		(end 333.065882 -411.718252)
		(width 0.14224)
		(layer "In15.Cu")
		(net "P5E_CPU0_P0_RX_BUF_DP<10>")
	)
	(arc
		(start 315.35751 -404.162006)
		(mid 315.380611 -404.27805)
		(end 315.44641 -404.376382)
		(width 0.14224)
		(layer "In15.Cu")
		(net "P5E_CPU0_P0_RX_BUF_DP<10>")
	)
	(arc
		(start 335.10728 -418.96538)
		(mid 335.324928 -419.291507)
		(end 335.65084 -419.509448)
		(width 0.14224)
		(layer "In15.Cu")
		(net "P5E_CPU0_P0_RX_BUF_DP<10>")
	)
	(segment
		(start 303.20234 -399.870676)
		(end 303.091342 -399.981674)
		(width 0.1016)
		(layer "F.Cu")
		(net "P5E_CPU0_P0_RX_BUF_DP<0>")
	)
	(segment
		(start 303.816258 -401.4978)
		(end 303.816258 -401.674838)
		(width 0.1016)
		(layer "F.Cu")
		(net "P5E_CPU0_P0_RX_BUF_DP<0>")
	)
	(segment
		(start 303.091342 -399.981674)
		(end 303.091342 -401.083526)
		(width 0.1016)
		(layer "F.Cu")
		(net "P5E_CPU0_P0_RX_BUF_DP<0>")
	)
	(segment
		(start 303.117758 -399.663158)
		(end 303.20234 -399.74774)
		(width 0.1016)
		(layer "F.Cu")
		(net "P5E_CPU0_P0_RX_BUF_DP<0>")
	)
	(segment
		(start 303.366932 -401.359116)
		(end 303.677574 -401.359116)
		(width 0.1016)
		(layer "F.Cu")
		(net "P5E_CPU0_P0_RX_BUF_DP<0>")
	)
	(segment
		(start 303.091342 -401.083526)
		(end 303.366932 -401.359116)
		(width 0.1016)
		(layer "F.Cu")
		(net "P5E_CPU0_P0_RX_BUF_DP<0>")
	)
	(segment
		(start 303.20234 -399.74774)
		(end 303.20234 -399.870676)
		(width 0.1016)
		(layer "F.Cu")
		(net "P5E_CPU0_P0_RX_BUF_DP<0>")
	)
	(segment
		(start 303.677574 -401.359116)
		(end 303.816258 -401.4978)
		(width 0.1016)
		(layer "F.Cu")
		(net "P5E_CPU0_P0_RX_BUF_DP<0>")
	)
	(segment
		(start 304.366676 -417.636452)
		(end 304.503836 -417.499292)
		(width 0.14224)
		(layer "In15.Cu")
		(net "P5E_CPU0_P0_RX_BUF_DP<0>")
	)
	(segment
		(start 303.35728 -406.68448)
		(end 303.35728 -406.25776)
		(width 0.14224)
		(layer "In15.Cu")
		(net "P5E_CPU0_P0_RX_BUF_DP<0>")
	)
	(segment
		(start 306.634388 -422.096692)
		(end 306.236878 -421.931846)
		(width 0.14224)
		(layer "In15.Cu")
		(net "P5E_CPU0_P0_RX_BUF_DP<0>")
	)
	(segment
		(start 303.49444 -407.9494)
		(end 303.35728 -407.81224)
		(width 0.14224)
		(layer "In15.Cu")
		(net "P5E_CPU0_P0_RX_BUF_DP<0>")
	)
	(segment
		(start 303.502822 -413.956754)
		(end 303.163986 -413.956754)
		(width 0.14224)
		(layer "In15.Cu")
		(net "P5E_CPU0_P0_RX_BUF_DP<0>")
	)
	(segment
		(start 303.35728 -407.81224)
		(end 303.35728 -407.38552)
		(width 0.14224)
		(layer "In15.Cu")
		(net "P5E_CPU0_P0_RX_BUF_DP<0>")
	)
	(segment
		(start 314.649612 -437.19115)
		(end 314.503562 -437.3372)
		(width 0.14224)
		(layer "In15.Cu")
		(net "P5E_CPU0_P0_RX_BUF_DP<0>")
	)
	(segment
		(start 303.35728 -407.38552)
		(end 303.49444 -407.24836)
		(width 0.14224)
		(layer "In15.Cu")
		(net "P5E_CPU0_P0_RX_BUF_DP<0>")
	)
	(segment
		(start 305.718464 -420.060882)
		(end 305.272948 -419.61435)
		(width 0.14224)
		(layer "In15.Cu")
		(net "P5E_CPU0_P0_RX_BUF_DP<0>")
	)
	(segment
		(start 303.35728 -403.3012)
		(end 303.35728 -401.511008)
		(width 0.14224)
		(layer "In15.Cu")
		(net "P5E_CPU0_P0_RX_BUF_DP<0>")
	)
	(segment
		(start 304.503836 -417.499292)
		(end 304.503836 -417.072572)
		(width 0.14224)
		(layer "In15.Cu")
		(net "P5E_CPU0_P0_RX_BUF_DP<0>")
	)
	(segment
		(start 304.366676 -415.807652)
		(end 304.366676 -414.806892)
		(width 0.14224)
		(layer "In15.Cu")
		(net "P5E_CPU0_P0_RX_BUF_DP<0>")
	)
	(segment
		(start 303.49444 -404.56612)
		(end 303.35728 -404.42896)
		(width 0.14224)
		(layer "In15.Cu")
		(net "P5E_CPU0_P0_RX_BUF_DP<0>")
	)
	(segment
		(start 307.27777 -422.363392)
		(end 307.204872 -422.18737)
		(width 0.14224)
		(layer "In15.Cu")
		(net "P5E_CPU0_P0_RX_BUF_DP<0>")
	)
	(segment
		(start 303.215802 -410.862526)
		(end 303.35728 -410.296868)
		(width 0.14224)
		(layer "In15.Cu")
		(net "P5E_CPU0_P0_RX_BUF_DP<0>")
	)
	(segment
		(start 313.489848 -436.899304)
		(end 313.489848 -425.131738)
		(width 0.14224)
		(layer "In15.Cu")
		(net "P5E_CPU0_P0_RX_BUF_DP<0>")
	)
	(segment
		(start 304.503836 -416.371532)
		(end 304.503836 -415.944812)
		(width 0.14224)
		(layer "In15.Cu")
		(net "P5E_CPU0_P0_RX_BUF_DP<0>")
	)
	(segment
		(start 305.898296 -421.520874)
		(end 305.898296 -420.49573)
		(width 0.14224)
		(layer "In15.Cu")
		(net "P5E_CPU0_P0_RX_BUF_DP<0>")
	)
	(segment
		(start 306.81041 -422.023794)
		(end 306.634388 -422.096692)
		(width 0.14224)
		(layer "In15.Cu")
		(net "P5E_CPU0_P0_RX_BUF_DP<0>")
	)
	(segment
		(start 302.9077 -413.742378)
		(end 302.833532 -413.563562)
		(width 0.14224)
		(layer "In15.Cu")
		(net "P5E_CPU0_P0_RX_BUF_DP<0>")
	)
	(segment
		(start 303.163986 -413.956754)
		(end 303.092358 -413.927036)
		(width 0.14224)
		(layer "In15.Cu")
		(net "P5E_CPU0_P0_RX_BUF_DP<0>")
	)
	(segment
		(start 303.35728 -401.511008)
		(end 303.496726 -401.371562)
		(width 0.14224)
		(layer "In15.Cu")
		(net "P5E_CPU0_P0_RX_BUF_DP<0>")
	)
	(segment
		(start 303.49444 -409.07716)
		(end 303.35728 -408.94)
		(width 0.14224)
		(layer "In15.Cu")
		(net "P5E_CPU0_P0_RX_BUF_DP<0>")
	)
	(segment
		(start 303.49444 -404.99284)
		(end 303.49444 -404.56612)
		(width 0.14224)
		(layer "In15.Cu")
		(net "P5E_CPU0_P0_RX_BUF_DP<0>")
	)
	(segment
		(start 304.366676 -416.935412)
		(end 304.366676 -416.508692)
		(width 0.14224)
		(layer "In15.Cu")
		(net "P5E_CPU0_P0_RX_BUF_DP<0>")
	)
	(segment
		(start 303.816258 -401.511008)
		(end 303.816258 -401.674838)
		(width 0.14224)
		(layer "In15.Cu")
		(net "P5E_CPU0_P0_RX_BUF_DP<0>")
	)
	(segment
		(start 303.35728 -406.25776)
		(end 303.49444 -406.1206)
		(width 0.14224)
		(layer "In15.Cu")
		(net "P5E_CPU0_P0_RX_BUF_DP<0>")
	)
	(segment
		(start 304.366676 -418.606732)
		(end 304.366676 -417.636452)
		(width 0.14224)
		(layer "In15.Cu")
		(net "P5E_CPU0_P0_RX_BUF_DP<0>")
	)
	(segment
		(start 303.49444 -406.82164)
		(end 303.35728 -406.68448)
		(width 0.14224)
		(layer "In15.Cu")
		(net "P5E_CPU0_P0_RX_BUF_DP<0>")
	)
	(segment
		(start 303.49444 -405.69388)
		(end 303.35728 -405.55672)
		(width 0.14224)
		(layer "In15.Cu")
		(net "P5E_CPU0_P0_RX_BUF_DP<0>")
	)
	(segment
		(start 303.215294 -410.86278)
		(end 303.215802 -410.862526)
		(width 0.14224)
		(layer "In15.Cu")
		(net "P5E_CPU0_P0_RX_BUF_DP<0>")
	)
	(segment
		(start 305.997102 -421.734996)
		(end 305.935634 -421.643302)
		(width 0.14224)
		(layer "In15.Cu")
		(net "P5E_CPU0_P0_RX_BUF_DP<0>")
	)
	(segment
		(start 303.676812 -401.371562)
		(end 303.816258 -401.511008)
		(width 0.14224)
		(layer "In15.Cu")
		(net "P5E_CPU0_P0_RX_BUF_DP<0>")
	)
	(segment
		(start 314.503562 -437.3372)
		(end 313.927744 -437.3372)
		(width 0.14224)
		(layer "In15.Cu")
		(net "P5E_CPU0_P0_RX_BUF_DP<0>")
	)
	(segment
		(start 303.49444 -403.43836)
		(end 303.35728 -403.3012)
		(width 0.14224)
		(layer "In15.Cu")
		(net "P5E_CPU0_P0_RX_BUF_DP<0>")
	)
	(segment
		(start 302.833532 -412.420562)
		(end 302.865536 -412.260034)
		(width 0.14224)
		(layer "In15.Cu")
		(net "P5E_CPU0_P0_RX_BUF_DP<0>")
	)
	(segment
		(start 304.503836 -415.944812)
		(end 304.366676 -415.807652)
		(width 0.14224)
		(layer "In15.Cu")
		(net "P5E_CPU0_P0_RX_BUF_DP<0>")
	)
	(segment
		(start 305.272948 -419.61435)
		(end 304.990754 -419.497764)
		(width 0.14224)
		(layer "In15.Cu")
		(net "P5E_CPU0_P0_RX_BUF_DP<0>")
	)
	(segment
		(start 303.49444 -409.50388)
		(end 303.49444 -409.07716)
		(width 0.14224)
		(layer "In15.Cu")
		(net "P5E_CPU0_P0_RX_BUF_DP<0>")
	)
	(segment
		(start 303.49444 -406.1206)
		(end 303.49444 -405.69388)
		(width 0.14224)
		(layer "In15.Cu")
		(net "P5E_CPU0_P0_RX_BUF_DP<0>")
	)
	(segment
		(start 303.496726 -401.371562)
		(end 303.676812 -401.371562)
		(width 0.14224)
		(layer "In15.Cu")
		(net "P5E_CPU0_P0_RX_BUF_DP<0>")
	)
	(segment
		(start 307.671724 -422.526714)
		(end 307.27777 -422.363392)
		(width 0.14224)
		(layer "In15.Cu")
		(net "P5E_CPU0_P0_RX_BUF_DP<0>")
	)
	(segment
		(start 302.865536 -412.260034)
		(end 303.215294 -410.86278)
		(width 0.14224)
		(layer "In15.Cu")
		(net "P5E_CPU0_P0_RX_BUF_DP<0>")
	)
	(segment
		(start 313.237372 -424.754548)
		(end 308.374288 -422.73982)
		(width 0.14224)
		(layer "In15.Cu")
		(net "P5E_CPU0_P0_RX_BUF_DP<0>")
	)
	(segment
		(start 303.35728 -404.00224)
		(end 303.49444 -403.86508)
		(width 0.14224)
		(layer "In15.Cu")
		(net "P5E_CPU0_P0_RX_BUF_DP<0>")
	)
	(segment
		(start 308.374288 -422.73982)
		(end 307.671724 -422.526714)
		(width 0.14224)
		(layer "In15.Cu")
		(net "P5E_CPU0_P0_RX_BUF_DP<0>")
	)
	(segment
		(start 303.35728 -405.13)
		(end 303.49444 -404.99284)
		(width 0.14224)
		(layer "In15.Cu")
		(net "P5E_CPU0_P0_RX_BUF_DP<0>")
	)
	(segment
		(start 303.35728 -409.64104)
		(end 303.49444 -409.50388)
		(width 0.14224)
		(layer "In15.Cu")
		(net "P5E_CPU0_P0_RX_BUF_DP<0>")
	)
	(segment
		(start 303.35728 -408.51328)
		(end 303.49444 -408.37612)
		(width 0.14224)
		(layer "In15.Cu")
		(net "P5E_CPU0_P0_RX_BUF_DP<0>")
	)
	(segment
		(start 304.503836 -417.072572)
		(end 304.366676 -416.935412)
		(width 0.14224)
		(layer "In15.Cu")
		(net "P5E_CPU0_P0_RX_BUF_DP<0>")
	)
	(segment
		(start 307.204872 -422.18737)
		(end 306.81041 -422.023794)
		(width 0.14224)
		(layer "In15.Cu")
		(net "P5E_CPU0_P0_RX_BUF_DP<0>")
	)
	(segment
		(start 302.833532 -413.563562)
		(end 302.833532 -412.420562)
		(width 0.14224)
		(layer "In15.Cu")
		(net "P5E_CPU0_P0_RX_BUF_DP<0>")
	)
	(segment
		(start 303.092358 -413.927036)
		(end 302.9077 -413.742378)
		(width 0.14224)
		(layer "In15.Cu")
		(net "P5E_CPU0_P0_RX_BUF_DP<0>")
	)
	(segment
		(start 304.366676 -414.806892)
		(end 304.25644 -414.5407)
		(width 0.14224)
		(layer "In15.Cu")
		(net "P5E_CPU0_P0_RX_BUF_DP<0>")
	)
	(segment
		(start 303.49444 -403.86508)
		(end 303.49444 -403.43836)
		(width 0.14224)
		(layer "In15.Cu")
		(net "P5E_CPU0_P0_RX_BUF_DP<0>")
	)
	(segment
		(start 306.236878 -421.931846)
		(end 305.997102 -421.734996)
		(width 0.14224)
		(layer "In15.Cu")
		(net "P5E_CPU0_P0_RX_BUF_DP<0>")
	)
	(segment
		(start 303.35728 -405.55672)
		(end 303.35728 -405.13)
		(width 0.14224)
		(layer "In15.Cu")
		(net "P5E_CPU0_P0_RX_BUF_DP<0>")
	)
	(segment
		(start 303.35728 -404.42896)
		(end 303.35728 -404.00224)
		(width 0.14224)
		(layer "In15.Cu")
		(net "P5E_CPU0_P0_RX_BUF_DP<0>")
	)
	(segment
		(start 313.927744 -437.3372)
		(end 313.489848 -436.899304)
		(width 0.14224)
		(layer "In15.Cu")
		(net "P5E_CPU0_P0_RX_BUF_DP<0>")
	)
	(segment
		(start 303.49444 -408.37612)
		(end 303.49444 -407.9494)
		(width 0.14224)
		(layer "In15.Cu")
		(net "P5E_CPU0_P0_RX_BUF_DP<0>")
	)
	(segment
		(start 304.366676 -416.508692)
		(end 304.503836 -416.371532)
		(width 0.14224)
		(layer "In15.Cu")
		(net "P5E_CPU0_P0_RX_BUF_DP<0>")
	)
	(segment
		(start 304.25644 -414.5407)
		(end 303.792382 -414.076642)
		(width 0.14224)
		(layer "In15.Cu")
		(net "P5E_CPU0_P0_RX_BUF_DP<0>")
	)
	(segment
		(start 314.649612 -436.889906)
		(end 314.649612 -437.19115)
		(width 0.14224)
		(layer "In15.Cu")
		(net "P5E_CPU0_P0_RX_BUF_DP<0>")
	)
	(segment
		(start 303.35728 -408.94)
		(end 303.35728 -408.51328)
		(width 0.14224)
		(layer "In15.Cu")
		(net "P5E_CPU0_P0_RX_BUF_DP<0>")
	)
	(segment
		(start 304.555906 -419.062916)
		(end 304.366676 -418.606732)
		(width 0.14224)
		(layer "In15.Cu")
		(net "P5E_CPU0_P0_RX_BUF_DP<0>")
	)
	(segment
		(start 303.35728 -410.296868)
		(end 303.35728 -409.64104)
		(width 0.14224)
		(layer "In15.Cu")
		(net "P5E_CPU0_P0_RX_BUF_DP<0>")
	)
	(segment
		(start 303.49444 -407.24836)
		(end 303.49444 -406.82164)
		(width 0.14224)
		(layer "In15.Cu")
		(net "P5E_CPU0_P0_RX_BUF_DP<0>")
	)
	(arc
		(start 303.792382 -414.076642)
		(mid 303.659517 -413.987927)
		(end 303.502822 -413.956754)
		(width 0.14224)
		(layer "In15.Cu")
		(net "P5E_CPU0_P0_RX_BUF_DP<0>")
	)
	(arc
		(start 313.489848 -425.131738)
		(mid 313.420845 -424.904825)
		(end 313.237372 -424.754548)
		(width 0.14224)
		(layer "In15.Cu")
		(net "P5E_CPU0_P0_RX_BUF_DP<0>")
	)
	(arc
		(start 305.898296 -420.49573)
		(mid 305.851566 -420.260445)
		(end 305.718464 -420.060882)
		(width 0.14224)
		(layer "In15.Cu")
		(net "P5E_CPU0_P0_RX_BUF_DP<0>")
	)
	(arc
		(start 305.935634 -421.643302)
		(mid 305.907874 -421.584861)
		(end 305.898296 -421.520874)
		(width 0.14224)
		(layer "In15.Cu")
		(net "P5E_CPU0_P0_RX_BUF_DP<0>")
	)
	(arc
		(start 304.990754 -419.497764)
		(mid 304.730129 -419.323541)
		(end 304.555906 -419.062916)
		(width 0.14224)
		(layer "In15.Cu")
		(net "P5E_CPU0_P0_RX_BUF_DP<0>")
	)
	(segment
		(start 314.21832 -399.960338)
		(end 314.1472 -400.031458)
		(width 0.1016)
		(layer "F.Cu")
		(net "P5E_CPU0_P0_RX_BUF_DN<9>")
	)
	(segment
		(start 314.21832 -399.143982)
		(end 314.21832 -399.960338)
		(width 0.1016)
		(layer "F.Cu")
		(net "P5E_CPU0_P0_RX_BUF_DN<9>")
	)
	(segment
		(start 314.1472 -401.016216)
		(end 314.2742 -401.143216)
		(width 0.1016)
		(layer "F.Cu")
		(net "P5E_CPU0_P0_RX_BUF_DN<9>")
	)
	(segment
		(start 314.475622 -401.143216)
		(end 314.616338 -401.0025)
		(width 0.1016)
		(layer "F.Cu")
		(net "P5E_CPU0_P0_RX_BUF_DN<9>")
	)
	(segment
		(start 314.217812 -399.143474)
		(end 314.21832 -399.143982)
		(width 0.1016)
		(layer "F.Cu")
		(net "P5E_CPU0_P0_RX_BUF_DN<9>")
	)
	(segment
		(start 314.2742 -401.143216)
		(end 314.475622 -401.143216)
		(width 0.1016)
		(layer "F.Cu")
		(net "P5E_CPU0_P0_RX_BUF_DN<9>")
	)
	(segment
		(start 314.616338 -401.0025)
		(end 314.616338 -400.811238)
		(width 0.1016)
		(layer "F.Cu")
		(net "P5E_CPU0_P0_RX_BUF_DN<9>")
	)
	(segment
		(start 314.1472 -400.031458)
		(end 314.1472 -401.016216)
		(width 0.1016)
		(layer "F.Cu")
		(net "P5E_CPU0_P0_RX_BUF_DN<9>")
	)
	(segment
		(start 331.309218 -414.288478)
		(end 331.189076 -414.238694)
		(width 0.14224)
		(layer "In15.Cu")
		(net "P5E_CPU0_P0_RX_BUF_DN<9>")
	)
	(segment
		(start 314.616338 -400.962622)
		(end 314.616338 -400.811238)
		(width 0.14224)
		(layer "In15.Cu")
		(net "P5E_CPU0_P0_RX_BUF_DN<9>")
	)
	(segment
		(start 314.467494 -401.111466)
		(end 314.616338 -400.962622)
		(width 0.14224)
		(layer "In15.Cu")
		(net "P5E_CPU0_P0_RX_BUF_DN<9>")
	)
	(segment
		(start 333.185516 -421.454326)
		(end 333.185516 -420.398702)
		(width 0.14224)
		(layer "In15.Cu")
		(net "P5E_CPU0_P0_RX_BUF_DN<9>")
	)
	(segment
		(start 333.649828 -438.76976)
		(end 333.50327 -438.623202)
		(width 0.14224)
		(layer "In15.Cu")
		(net "P5E_CPU0_P0_RX_BUF_DN<9>")
	)
	(segment
		(start 315.470286 -406.375108)
		(end 313.995308 -404.899876)
		(width 0.14224)
		(layer "In15.Cu")
		(net "P5E_CPU0_P0_RX_BUF_DN<9>")
	)
	(segment
		(start 333.649828 -439.0898)
		(end 333.649828 -438.76976)
		(width 0.14224)
		(layer "In15.Cu")
		(net "P5E_CPU0_P0_RX_BUF_DN<9>")
	)
	(segment
		(start 333.148178 -420.308786)
		(end 332.700376 -419.860984)
		(width 0.14224)
		(layer "In15.Cu")
		(net "P5E_CPU0_P0_RX_BUF_DN<9>")
	)
	(segment
		(start 331.491336 -414.470596)
		(end 331.309218 -414.288478)
		(width 0.14224)
		(layer "In15.Cu")
		(net "P5E_CPU0_P0_RX_BUF_DN<9>")
	)
	(segment
		(start 316.307724 -407.212292)
		(end 315.47054 -406.375108)
		(width 0.14224)
		(layer "In15.Cu")
		(net "P5E_CPU0_P0_RX_BUF_DN<9>")
	)
	(segment
		(start 313.87542 -404.610316)
		(end 313.87542 -401.403566)
		(width 0.14224)
		(layer "In15.Cu")
		(net "P5E_CPU0_P0_RX_BUF_DN<9>")
	)
	(segment
		(start 331.653896 -414.863026)
		(end 331.491336 -414.470596)
		(width 0.14224)
		(layer "In15.Cu")
		(net "P5E_CPU0_P0_RX_BUF_DN<9>")
	)
	(segment
		(start 330.122276 -413.502856)
		(end 330.122276 -412.33725)
		(width 0.14224)
		(layer "In15.Cu")
		(net "P5E_CPU0_P0_RX_BUF_DN<9>")
	)
	(segment
		(start 324.155308 -409.83662)
		(end 317.129922 -407.705306)
		(width 0.14224)
		(layer "In15.Cu")
		(net "P5E_CPU0_P0_RX_BUF_DN<9>")
	)
	(segment
		(start 330.434696 -414.098994)
		(end 330.322936 -413.987234)
		(width 0.14224)
		(layer "In15.Cu")
		(net "P5E_CPU0_P0_RX_BUF_DN<9>")
	)
	(segment
		(start 332.688946 -424.588178)
		(end 332.787244 -424.092116)
		(width 0.14224)
		(layer "In15.Cu")
		(net "P5E_CPU0_P0_RX_BUF_DN<9>")
	)
	(segment
		(start 330.075032 -412.223204)
		(end 329.63612 -411.784292)
		(width 0.14224)
		(layer "In15.Cu")
		(net "P5E_CPU0_P0_RX_BUF_DN<9>")
	)
	(segment
		(start 332.99146 -438.623202)
		(end 332.688946 -438.320688)
		(width 0.14224)
		(layer "In15.Cu")
		(net "P5E_CPU0_P0_RX_BUF_DN<9>")
	)
	(segment
		(start 324.681596 -410.268674)
		(end 324.155308 -409.83662)
		(width 0.14224)
		(layer "In15.Cu")
		(net "P5E_CPU0_P0_RX_BUF_DN<9>")
	)
	(segment
		(start 332.700376 -419.860984)
		(end 332.35519 -419.717982)
		(width 0.14224)
		(layer "In15.Cu")
		(net "P5E_CPU0_P0_RX_BUF_DN<9>")
	)
	(segment
		(start 333.142082 -421.894762)
		(end 333.185516 -421.454326)
		(width 0.14224)
		(layer "In15.Cu")
		(net "P5E_CPU0_P0_RX_BUF_DN<9>")
	)
	(segment
		(start 331.849222 -419.212268)
		(end 331.653896 -418.741098)
		(width 0.14224)
		(layer "In15.Cu")
		(net "P5E_CPU0_P0_RX_BUF_DN<9>")
	)
	(segment
		(start 331.189076 -414.238694)
		(end 330.772008 -414.238694)
		(width 0.14224)
		(layer "In15.Cu")
		(net "P5E_CPU0_P0_RX_BUF_DN<9>")
	)
	(segment
		(start 314.16752 -401.111466)
		(end 314.467494 -401.111466)
		(width 0.14224)
		(layer "In15.Cu")
		(net "P5E_CPU0_P0_RX_BUF_DN<9>")
	)
	(segment
		(start 313.87542 -401.403566)
		(end 314.16752 -401.111466)
		(width 0.14224)
		(layer "In15.Cu")
		(net "P5E_CPU0_P0_RX_BUF_DN<9>")
	)
	(segment
		(start 331.653896 -418.741098)
		(end 331.653896 -414.863026)
		(width 0.14224)
		(layer "In15.Cu")
		(net "P5E_CPU0_P0_RX_BUF_DN<9>")
	)
	(segment
		(start 332.899766 -423.526966)
		(end 333.142082 -421.894762)
		(width 0.14224)
		(layer "In15.Cu")
		(net "P5E_CPU0_P0_RX_BUF_DN<9>")
	)
	(segment
		(start 332.787498 -424.091862)
		(end 332.899766 -423.526966)
		(width 0.14224)
		(layer "In15.Cu")
		(net "P5E_CPU0_P0_RX_BUF_DN<9>")
	)
	(segment
		(start 333.50327 -438.623202)
		(end 332.99146 -438.623202)
		(width 0.14224)
		(layer "In15.Cu")
		(net "P5E_CPU0_P0_RX_BUF_DN<9>")
	)
	(segment
		(start 329.593702 -411.758892)
		(end 324.681596 -410.268674)
		(width 0.14224)
		(layer "In15.Cu")
		(net "P5E_CPU0_P0_RX_BUF_DN<9>")
	)
	(segment
		(start 332.787244 -424.092116)
		(end 332.787498 -424.091862)
		(width 0.14224)
		(layer "In15.Cu")
		(net "P5E_CPU0_P0_RX_BUF_DN<9>")
	)
	(segment
		(start 332.688946 -438.320688)
		(end 332.688946 -424.588178)
		(width 0.14224)
		(layer "In15.Cu")
		(net "P5E_CPU0_P0_RX_BUF_DN<9>")
	)
	(segment
		(start 315.47054 -406.375108)
		(end 315.470286 -406.375108)
		(width 0.14224)
		(layer "In15.Cu")
		(net "P5E_CPU0_P0_RX_BUF_DN<9>")
	)
	(arc
		(start 313.995308 -404.899876)
		(mid 313.906593 -404.767011)
		(end 313.87542 -404.610316)
		(width 0.14224)
		(layer "In15.Cu")
		(net "P5E_CPU0_P0_RX_BUF_DN<9>")
	)
	(arc
		(start 333.185516 -420.398702)
		(mid 333.175814 -420.350018)
		(end 333.148178 -420.308786)
		(width 0.14224)
		(layer "In15.Cu")
		(net "P5E_CPU0_P0_RX_BUF_DN<9>")
	)
	(arc
		(start 317.129922 -407.705306)
		(mid 316.688438 -407.509477)
		(end 316.307724 -407.212292)
		(width 0.14224)
		(layer "In15.Cu")
		(net "P5E_CPU0_P0_RX_BUF_DN<9>")
	)
	(arc
		(start 330.322936 -413.987234)
		(mid 330.174444 -413.764999)
		(end 330.122276 -413.502856)
		(width 0.14224)
		(layer "In15.Cu")
		(net "P5E_CPU0_P0_RX_BUF_DN<9>")
	)
	(arc
		(start 332.35519 -419.717982)
		(mid 332.051947 -419.515404)
		(end 331.849222 -419.212268)
		(width 0.14224)
		(layer "In15.Cu")
		(net "P5E_CPU0_P0_RX_BUF_DN<9>")
	)
	(arc
		(start 330.772008 -414.238694)
		(mid 330.589463 -414.202384)
		(end 330.434696 -414.098994)
		(width 0.14224)
		(layer "In15.Cu")
		(net "P5E_CPU0_P0_RX_BUF_DN<9>")
	)
	(arc
		(start 329.63612 -411.784292)
		(mid 329.616497 -411.768934)
		(end 329.593702 -411.758892)
		(width 0.14224)
		(layer "In15.Cu")
		(net "P5E_CPU0_P0_RX_BUF_DN<9>")
	)
	(arc
		(start 330.122276 -412.33725)
		(mid 330.109999 -412.275527)
		(end 330.075032 -412.223204)
		(width 0.14224)
		(layer "In15.Cu")
		(net "P5E_CPU0_P0_RX_BUF_DN<9>")
	)
	(segment
		(start 312.929524 -401.016216)
		(end 312.929524 -400.048984)
		(width 0.1016)
		(layer "F.Cu")
		(net "P5E_CPU0_P0_RX_BUF_DN<8>")
	)
	(segment
		(start 313.01817 -399.143982)
		(end 313.017662 -399.143474)
		(width 0.1016)
		(layer "F.Cu")
		(net "P5E_CPU0_P0_RX_BUF_DN<8>")
	)
	(segment
		(start 313.275472 -401.143216)
		(end 313.056524 -401.143216)
		(width 0.1016)
		(layer "F.Cu")
		(net "P5E_CPU0_P0_RX_BUF_DN<8>")
	)
	(segment
		(start 312.929524 -400.048984)
		(end 313.01817 -399.960338)
		(width 0.1016)
		(layer "F.Cu")
		(net "P5E_CPU0_P0_RX_BUF_DN<8>")
	)
	(segment
		(start 313.416442 -401.002246)
		(end 313.275472 -401.143216)
		(width 0.1016)
		(layer "F.Cu")
		(net "P5E_CPU0_P0_RX_BUF_DN<8>")
	)
	(segment
		(start 313.056524 -401.143216)
		(end 312.929524 -401.016216)
		(width 0.1016)
		(layer "F.Cu")
		(net "P5E_CPU0_P0_RX_BUF_DN<8>")
	)
	(segment
		(start 313.416442 -400.811238)
		(end 313.416442 -401.002246)
		(width 0.1016)
		(layer "F.Cu")
		(net "P5E_CPU0_P0_RX_BUF_DN<8>")
	)
	(segment
		(start 313.01817 -399.960338)
		(end 313.01817 -399.143982)
		(width 0.1016)
		(layer "F.Cu")
		(net "P5E_CPU0_P0_RX_BUF_DN<8>")
	)
	(segment
		(start 312.98007 -401.089622)
		(end 313.289442 -401.089622)
		(width 0.14224)
		(layer "In15.Cu")
		(net "P5E_CPU0_P0_RX_BUF_DN<8>")
	)
	(segment
		(start 315.618876 -408.168602)
		(end 315.068204 -407.61793)
		(width 0.14224)
		(layer "In15.Cu")
		(net "P5E_CPU0_P0_RX_BUF_DN<8>")
	)
	(segment
		(start 327.613518 -414.238694)
		(end 327.438512 -414.16605)
		(width 0.14224)
		(layer "In15.Cu")
		(net "P5E_CPU0_P0_RX_BUF_DN<8>")
	)
	(segment
		(start 312.675524 -405.055832)
		(end 312.675524 -401.394168)
		(width 0.14224)
		(layer "In15.Cu")
		(net "P5E_CPU0_P0_RX_BUF_DN<8>")
	)
	(segment
		(start 327.174606 -413.902144)
		(end 327.059036 -413.623252)
		(width 0.14224)
		(layer "In15.Cu")
		(net "P5E_CPU0_P0_RX_BUF_DN<8>")
	)
	(segment
		(start 313.416442 -400.962622)
		(end 313.416442 -400.811238)
		(width 0.14224)
		(layer "In15.Cu")
		(net "P5E_CPU0_P0_RX_BUF_DN<8>")
	)
	(segment
		(start 315.06795 -407.61793)
		(end 312.795412 -405.345392)
		(width 0.14224)
		(layer "In15.Cu")
		(net "P5E_CPU0_P0_RX_BUF_DN<8>")
	)
	(segment
		(start 330.084938 -420.318438)
		(end 329.620626 -419.854126)
		(width 0.14224)
		(layer "In15.Cu")
		(net "P5E_CPU0_P0_RX_BUF_DN<8>")
	)
	(segment
		(start 323.732144 -410.699712)
		(end 315.855096 -408.31008)
		(width 0.14224)
		(layer "In15.Cu")
		(net "P5E_CPU0_P0_RX_BUF_DN<8>")
	)
	(segment
		(start 330.701142 -437.32704)
		(end 330.701142 -425.292012)
		(width 0.14224)
		(layer "In15.Cu")
		(net "P5E_CPU0_P0_RX_BUF_DN<8>")
	)
	(segment
		(start 324.231254 -411.109414)
		(end 323.732144 -410.699712)
		(width 0.14224)
		(layer "In15.Cu")
		(net "P5E_CPU0_P0_RX_BUF_DN<8>")
	)
	(segment
		(start 327.059036 -413.623252)
		(end 327.059036 -412.292546)
		(width 0.14224)
		(layer "In15.Cu")
		(net "P5E_CPU0_P0_RX_BUF_DN<8>")
	)
	(segment
		(start 328.590656 -414.863026)
		(end 328.449178 -414.52165)
		(width 0.14224)
		(layer "In15.Cu")
		(net "P5E_CPU0_P0_RX_BUF_DN<8>")
	)
	(segment
		(start 331.49921 -437.61914)
		(end 330.993242 -437.61914)
		(width 0.14224)
		(layer "In15.Cu")
		(net "P5E_CPU0_P0_RX_BUF_DN<8>")
	)
	(segment
		(start 327.021698 -412.20263)
		(end 326.723502 -411.904434)
		(width 0.14224)
		(layer "In15.Cu")
		(net "P5E_CPU0_P0_RX_BUF_DN<8>")
	)
	(segment
		(start 328.19467 -414.267142)
		(end 328.12609 -414.238694)
		(width 0.14224)
		(layer "In15.Cu")
		(net "P5E_CPU0_P0_RX_BUF_DN<8>")
	)
	(segment
		(start 327.438512 -414.16605)
		(end 327.174606 -413.902144)
		(width 0.14224)
		(layer "In15.Cu")
		(net "P5E_CPU0_P0_RX_BUF_DN<8>")
	)
	(segment
		(start 330.701142 -425.292012)
		(end 330.63434 -424.956732)
		(width 0.14224)
		(layer "In15.Cu")
		(net "P5E_CPU0_P0_RX_BUF_DN<8>")
	)
	(segment
		(start 328.12609 -414.238694)
		(end 327.613518 -414.238694)
		(width 0.14224)
		(layer "In15.Cu")
		(net "P5E_CPU0_P0_RX_BUF_DN<8>")
	)
	(segment
		(start 331.649832 -437.769762)
		(end 331.49921 -437.61914)
		(width 0.14224)
		(layer "In15.Cu")
		(net "P5E_CPU0_P0_RX_BUF_DN<8>")
	)
	(segment
		(start 328.449178 -414.52165)
		(end 328.19467 -414.267142)
		(width 0.14224)
		(layer "In15.Cu")
		(net "P5E_CPU0_P0_RX_BUF_DN<8>")
	)
	(segment
		(start 330.634086 -424.956732)
		(end 330.122276 -422.383458)
		(width 0.14224)
		(layer "In15.Cu")
		(net "P5E_CPU0_P0_RX_BUF_DN<8>")
	)
	(segment
		(start 330.993242 -437.61914)
		(end 330.701142 -437.32704)
		(width 0.14224)
		(layer "In15.Cu")
		(net "P5E_CPU0_P0_RX_BUF_DN<8>")
	)
	(segment
		(start 330.63434 -424.956732)
		(end 330.634086 -424.956732)
		(width 0.14224)
		(layer "In15.Cu")
		(net "P5E_CPU0_P0_RX_BUF_DN<8>")
	)
	(segment
		(start 312.675524 -401.394168)
		(end 312.98007 -401.089622)
		(width 0.14224)
		(layer "In15.Cu")
		(net "P5E_CPU0_P0_RX_BUF_DN<8>")
	)
	(segment
		(start 330.122276 -422.383458)
		(end 330.122276 -420.408354)
		(width 0.14224)
		(layer "In15.Cu")
		(net "P5E_CPU0_P0_RX_BUF_DN<8>")
	)
	(segment
		(start 315.068204 -407.61793)
		(end 315.06795 -407.61793)
		(width 0.14224)
		(layer "In15.Cu")
		(net "P5E_CPU0_P0_RX_BUF_DN<8>")
	)
	(segment
		(start 331.649832 -438.089802)
		(end 331.649832 -437.769762)
		(width 0.14224)
		(layer "In15.Cu")
		(net "P5E_CPU0_P0_RX_BUF_DN<8>")
	)
	(segment
		(start 326.723502 -411.904434)
		(end 326.591168 -411.825186)
		(width 0.14224)
		(layer "In15.Cu")
		(net "P5E_CPU0_P0_RX_BUF_DN<8>")
	)
	(segment
		(start 315.855096 -408.31008)
		(end 315.618876 -408.168602)
		(width 0.14224)
		(layer "In15.Cu")
		(net "P5E_CPU0_P0_RX_BUF_DN<8>")
	)
	(segment
		(start 328.814176 -419.259258)
		(end 328.590656 -418.72027)
		(width 0.14224)
		(layer "In15.Cu")
		(net "P5E_CPU0_P0_RX_BUF_DN<8>")
	)
	(segment
		(start 329.620626 -419.854126)
		(end 329.259692 -419.704774)
		(width 0.14224)
		(layer "In15.Cu")
		(net "P5E_CPU0_P0_RX_BUF_DN<8>")
	)
	(segment
		(start 313.289442 -401.089622)
		(end 313.416442 -400.962622)
		(width 0.14224)
		(layer "In15.Cu")
		(net "P5E_CPU0_P0_RX_BUF_DN<8>")
	)
	(segment
		(start 326.591168 -411.825186)
		(end 324.231254 -411.109414)
		(width 0.14224)
		(layer "In15.Cu")
		(net "P5E_CPU0_P0_RX_BUF_DN<8>")
	)
	(segment
		(start 328.590656 -418.72027)
		(end 328.590656 -414.863026)
		(width 0.14224)
		(layer "In15.Cu")
		(net "P5E_CPU0_P0_RX_BUF_DN<8>")
	)
	(arc
		(start 327.059036 -412.292546)
		(mid 327.049334 -412.243862)
		(end 327.021698 -412.20263)
		(width 0.14224)
		(layer "In15.Cu")
		(net "P5E_CPU0_P0_RX_BUF_DN<8>")
	)
	(arc
		(start 329.259692 -419.704774)
		(mid 328.992658 -419.526292)
		(end 328.814176 -419.259258)
		(width 0.14224)
		(layer "In15.Cu")
		(net "P5E_CPU0_P0_RX_BUF_DN<8>")
	)
	(arc
		(start 312.795412 -405.345392)
		(mid 312.706697 -405.212527)
		(end 312.675524 -405.055832)
		(width 0.14224)
		(layer "In15.Cu")
		(net "P5E_CPU0_P0_RX_BUF_DN<8>")
	)
	(arc
		(start 330.122276 -420.408354)
		(mid 330.112574 -420.35967)
		(end 330.084938 -420.318438)
		(width 0.14224)
		(layer "In15.Cu")
		(net "P5E_CPU0_P0_RX_BUF_DN<8>")
	)
	(segment
		(start 312.075576 -401.143216)
		(end 312.216292 -401.0025)
		(width 0.1016)
		(layer "F.Cu")
		(net "P5E_CPU0_P0_RX_BUF_DN<7>")
	)
	(segment
		(start 312.216292 -401.0025)
		(end 312.216292 -400.811238)
		(width 0.1016)
		(layer "F.Cu")
		(net "P5E_CPU0_P0_RX_BUF_DN<7>")
	)
	(segment
		(start 311.818274 -399.960338)
		(end 311.729628 -400.048984)
		(width 0.1016)
		(layer "F.Cu")
		(net "P5E_CPU0_P0_RX_BUF_DN<7>")
	)
	(segment
		(start 311.729628 -400.048984)
		(end 311.729628 -401.016216)
		(width 0.1016)
		(layer "F.Cu")
		(net "P5E_CPU0_P0_RX_BUF_DN<7>")
	)
	(segment
		(start 311.856628 -401.143216)
		(end 312.075576 -401.143216)
		(width 0.1016)
		(layer "F.Cu")
		(net "P5E_CPU0_P0_RX_BUF_DN<7>")
	)
	(segment
		(start 311.817766 -399.143474)
		(end 311.818274 -399.143982)
		(width 0.1016)
		(layer "F.Cu")
		(net "P5E_CPU0_P0_RX_BUF_DN<7>")
	)
	(segment
		(start 311.818274 -399.143982)
		(end 311.818274 -399.960338)
		(width 0.1016)
		(layer "F.Cu")
		(net "P5E_CPU0_P0_RX_BUF_DN<7>")
	)
	(segment
		(start 311.729628 -401.016216)
		(end 311.856628 -401.143216)
		(width 0.1016)
		(layer "F.Cu")
		(net "P5E_CPU0_P0_RX_BUF_DN<7>")
	)
	(segment
		(start 327.059036 -420.433754)
		(end 327.059036 -422.011094)
		(width 0.14224)
		(layer "In15.Cu")
		(net "P5E_CPU0_P0_RX_BUF_DN<7>")
	)
	(segment
		(start 324.111366 -413.902144)
		(end 324.375272 -414.16605)
		(width 0.14224)
		(layer "In15.Cu")
		(net "P5E_CPU0_P0_RX_BUF_DN<7>")
	)
	(segment
		(start 327.059036 -422.011094)
		(end 327.688956 -425.178982)
		(width 0.14224)
		(layer "In15.Cu")
		(net "P5E_CPU0_P0_RX_BUF_DN<7>")
	)
	(segment
		(start 327.688956 -438.312052)
		(end 327.996296 -438.619392)
		(width 0.14224)
		(layer "In15.Cu")
		(net "P5E_CPU0_P0_RX_BUF_DN<7>")
	)
	(segment
		(start 325.560944 -418.715444)
		(end 325.752206 -419.176454)
		(width 0.14224)
		(layer "In15.Cu")
		(net "P5E_CPU0_P0_RX_BUF_DN<7>")
	)
	(segment
		(start 326.321928 -419.75659)
		(end 326.454008 -419.8112)
		(width 0.14224)
		(layer "In15.Cu")
		(net "P5E_CPU0_P0_RX_BUF_DN<7>")
	)
	(segment
		(start 312.216292 -400.811238)
		(end 312.216292 -400.962622)
		(width 0.14224)
		(layer "In15.Cu")
		(net "P5E_CPU0_P0_RX_BUF_DN<7>")
	)
	(segment
		(start 323.725032 -411.940248)
		(end 323.95033 -412.277052)
		(width 0.14224)
		(layer "In15.Cu")
		(net "P5E_CPU0_P0_RX_BUF_DN<7>")
	)
	(segment
		(start 325.06285 -414.238694)
		(end 325.13143 -414.267142)
		(width 0.14224)
		(layer "In15.Cu")
		(net "P5E_CPU0_P0_RX_BUF_DN<7>")
	)
	(segment
		(start 326.55891 -419.88105)
		(end 327.021698 -420.343838)
		(width 0.14224)
		(layer "In15.Cu")
		(net "P5E_CPU0_P0_RX_BUF_DN<7>")
	)
	(segment
		(start 328.499216 -438.619392)
		(end 328.649584 -438.76976)
		(width 0.14224)
		(layer "In15.Cu")
		(net "P5E_CPU0_P0_RX_BUF_DN<7>")
	)
	(segment
		(start 325.13143 -414.267142)
		(end 325.385938 -414.52165)
		(width 0.14224)
		(layer "In15.Cu")
		(net "P5E_CPU0_P0_RX_BUF_DN<7>")
	)
	(segment
		(start 311.475374 -401.394168)
		(end 311.475374 -405.41575)
		(width 0.14224)
		(layer "In15.Cu")
		(net "P5E_CPU0_P0_RX_BUF_DN<7>")
	)
	(segment
		(start 323.995796 -413.623252)
		(end 324.111366 -413.902144)
		(width 0.14224)
		(layer "In15.Cu")
		(net "P5E_CPU0_P0_RX_BUF_DN<7>")
	)
	(segment
		(start 320.494914 -410.701236)
		(end 321.747896 -411.21965)
		(width 0.14224)
		(layer "In15.Cu")
		(net "P5E_CPU0_P0_RX_BUF_DN<7>")
	)
	(segment
		(start 324.375272 -414.16605)
		(end 324.550278 -414.238694)
		(width 0.14224)
		(layer "In15.Cu")
		(net "P5E_CPU0_P0_RX_BUF_DN<7>")
	)
	(segment
		(start 327.996296 -438.619392)
		(end 328.499216 -438.619392)
		(width 0.14224)
		(layer "In15.Cu")
		(net "P5E_CPU0_P0_RX_BUF_DN<7>")
	)
	(segment
		(start 315.225684 -409.10256)
		(end 320.494914 -410.701236)
		(width 0.14224)
		(layer "In15.Cu")
		(net "P5E_CPU0_P0_RX_BUF_DN<7>")
	)
	(segment
		(start 323.995796 -412.426404)
		(end 323.995796 -413.623252)
		(width 0.14224)
		(layer "In15.Cu")
		(net "P5E_CPU0_P0_RX_BUF_DN<7>")
	)
	(segment
		(start 312.216292 -400.962622)
		(end 312.089292 -401.089622)
		(width 0.14224)
		(layer "In15.Cu")
		(net "P5E_CPU0_P0_RX_BUF_DN<7>")
	)
	(segment
		(start 325.527416 -414.863026)
		(end 325.527416 -418.545518)
		(width 0.14224)
		(layer "In15.Cu")
		(net "P5E_CPU0_P0_RX_BUF_DN<7>")
	)
	(segment
		(start 311.77992 -401.089622)
		(end 311.475374 -401.394168)
		(width 0.14224)
		(layer "In15.Cu")
		(net "P5E_CPU0_P0_RX_BUF_DN<7>")
	)
	(segment
		(start 325.385938 -414.52165)
		(end 325.527416 -414.863026)
		(width 0.14224)
		(layer "In15.Cu")
		(net "P5E_CPU0_P0_RX_BUF_DN<7>")
	)
	(segment
		(start 312.089292 -401.089622)
		(end 311.77992 -401.089622)
		(width 0.14224)
		(layer "In15.Cu")
		(net "P5E_CPU0_P0_RX_BUF_DN<7>")
	)
	(segment
		(start 323.164962 -411.672278)
		(end 323.635878 -411.867096)
		(width 0.14224)
		(layer "In15.Cu")
		(net "P5E_CPU0_P0_RX_BUF_DN<7>")
	)
	(segment
		(start 328.649584 -438.76976)
		(end 328.649584 -439.0898)
		(width 0.14224)
		(layer "In15.Cu")
		(net "P5E_CPU0_P0_RX_BUF_DN<7>")
	)
	(segment
		(start 322.841366 -411.672278)
		(end 323.164962 -411.672278)
		(width 0.14224)
		(layer "In15.Cu")
		(net "P5E_CPU0_P0_RX_BUF_DN<7>")
	)
	(segment
		(start 321.747896 -411.21965)
		(end 321.747642 -411.21965)
		(width 0.14224)
		(layer "In15.Cu")
		(net "P5E_CPU0_P0_RX_BUF_DN<7>")
	)
	(segment
		(start 323.635878 -411.867096)
		(end 323.725032 -411.940248)
		(width 0.14224)
		(layer "In15.Cu")
		(net "P5E_CPU0_P0_RX_BUF_DN<7>")
	)
	(segment
		(start 324.550278 -414.238694)
		(end 325.06285 -414.238694)
		(width 0.14224)
		(layer "In15.Cu")
		(net "P5E_CPU0_P0_RX_BUF_DN<7>")
	)
	(segment
		(start 311.595262 -405.70531)
		(end 314.643262 -408.75331)
		(width 0.14224)
		(layer "In15.Cu")
		(net "P5E_CPU0_P0_RX_BUF_DN<7>")
	)
	(segment
		(start 323.95033 -412.277052)
		(end 323.995796 -412.426404)
		(width 0.14224)
		(layer "In15.Cu")
		(net "P5E_CPU0_P0_RX_BUF_DN<7>")
	)
	(segment
		(start 327.688956 -425.178982)
		(end 327.688956 -438.312052)
		(width 0.14224)
		(layer "In15.Cu")
		(net "P5E_CPU0_P0_RX_BUF_DN<7>")
	)
	(segment
		(start 321.747642 -411.21965)
		(end 322.841366 -411.672278)
		(width 0.14224)
		(layer "In15.Cu")
		(net "P5E_CPU0_P0_RX_BUF_DN<7>")
	)
	(arc
		(start 325.527416 -418.545518)
		(mid 325.535814 -418.63213)
		(end 325.560944 -418.715444)
		(width 0.14224)
		(layer "In15.Cu")
		(net "P5E_CPU0_P0_RX_BUF_DN<7>")
	)
	(arc
		(start 314.643262 -408.75331)
		(mid 314.912938 -408.963852)
		(end 315.225684 -409.10256)
		(width 0.14224)
		(layer "In15.Cu")
		(net "P5E_CPU0_P0_RX_BUF_DN<7>")
	)
	(arc
		(start 326.454008 -419.8112)
		(mid 326.50992 -419.84093)
		(end 326.55891 -419.88105)
		(width 0.14224)
		(layer "In15.Cu")
		(net "P5E_CPU0_P0_RX_BUF_DN<7>")
	)
	(arc
		(start 311.475374 -405.41575)
		(mid 311.506526 -405.572453)
		(end 311.595262 -405.70531)
		(width 0.14224)
		(layer "In15.Cu")
		(net "P5E_CPU0_P0_RX_BUF_DN<7>")
	)
	(arc
		(start 327.021698 -420.343838)
		(mid 327.049317 -420.385078)
		(end 327.059036 -420.433754)
		(width 0.14224)
		(layer "In15.Cu")
		(net "P5E_CPU0_P0_RX_BUF_DN<7>")
	)
	(arc
		(start 325.752206 -419.176454)
		(mid 325.790807 -419.258117)
		(end 325.837042 -419.335712)
		(width 0.14224)
		(layer "In15.Cu")
		(net "P5E_CPU0_P0_RX_BUF_DN<7>")
	)
	(arc
		(start 326.155304 -419.664642)
		(mid 326.236026 -419.715309)
		(end 326.321928 -419.75659)
		(width 0.14224)
		(layer "In15.Cu")
		(net "P5E_CPU0_P0_RX_BUF_DN<7>")
	)
	(arc
		(start 325.837042 -419.335712)
		(mid 325.980987 -419.514872)
		(end 326.155304 -419.664642)
		(width 0.14224)
		(layer "In15.Cu")
		(net "P5E_CPU0_P0_RX_BUF_DN<7>")
	)
	(segment
		(start 310.538368 -400.040094)
		(end 310.538368 -401.016216)
		(width 0.1016)
		(layer "F.Cu")
		(net "P5E_CPU0_P0_RX_BUF_DN<6>")
	)
	(segment
		(start 311.016396 -401.0025)
		(end 311.016396 -400.811238)
		(width 0.1016)
		(layer "F.Cu")
		(net "P5E_CPU0_P0_RX_BUF_DN<6>")
	)
	(segment
		(start 310.618124 -399.960338)
		(end 310.538368 -400.040094)
		(width 0.1016)
		(layer "F.Cu")
		(net "P5E_CPU0_P0_RX_BUF_DN<6>")
	)
	(segment
		(start 310.618378 -399.143982)
		(end 310.618378 -399.747486)
		(width 0.1016)
		(layer "F.Cu")
		(net "P5E_CPU0_P0_RX_BUF_DN<6>")
	)
	(segment
		(start 310.665368 -401.143216)
		(end 310.87568 -401.143216)
		(width 0.1016)
		(layer "F.Cu")
		(net "P5E_CPU0_P0_RX_BUF_DN<6>")
	)
	(segment
		(start 310.618378 -399.747486)
		(end 310.618124 -399.74774)
		(width 0.1016)
		(layer "F.Cu")
		(net "P5E_CPU0_P0_RX_BUF_DN<6>")
	)
	(segment
		(start 310.87568 -401.143216)
		(end 311.016396 -401.0025)
		(width 0.1016)
		(layer "F.Cu")
		(net "P5E_CPU0_P0_RX_BUF_DN<6>")
	)
	(segment
		(start 310.61787 -399.143474)
		(end 310.618378 -399.143982)
		(width 0.1016)
		(layer "F.Cu")
		(net "P5E_CPU0_P0_RX_BUF_DN<6>")
	)
	(segment
		(start 310.618124 -399.74774)
		(end 310.618124 -399.960338)
		(width 0.1016)
		(layer "F.Cu")
		(net "P5E_CPU0_P0_RX_BUF_DN<6>")
	)
	(segment
		(start 310.538368 -401.016216)
		(end 310.665368 -401.143216)
		(width 0.1016)
		(layer "F.Cu")
		(net "P5E_CPU0_P0_RX_BUF_DN<6>")
	)
	(segment
		(start 326.058022 -437.623204)
		(end 326.50303 -437.623204)
		(width 0.14224)
		(layer "In15.Cu")
		(net "P5E_CPU0_P0_RX_BUF_DN<6>")
	)
	(segment
		(start 321.088004 -413.942276)
		(end 321.312032 -414.16605)
		(width 0.14224)
		(layer "In15.Cu")
		(net "P5E_CPU0_P0_RX_BUF_DN<6>")
	)
	(segment
		(start 311.953148 -407.65476)
		(end 313.923172 -409.624784)
		(width 0.14224)
		(layer "In15.Cu")
		(net "P5E_CPU0_P0_RX_BUF_DN<6>")
	)
	(segment
		(start 322.06819 -414.267142)
		(end 322.322698 -414.52165)
		(width 0.14224)
		(layer "In15.Cu")
		(net "P5E_CPU0_P0_RX_BUF_DN<6>")
	)
	(segment
		(start 326.649588 -437.769762)
		(end 326.649588 -438.089802)
		(width 0.14224)
		(layer "In15.Cu")
		(net "P5E_CPU0_P0_RX_BUF_DN<6>")
	)
	(segment
		(start 320.932556 -413.566102)
		(end 321.088004 -413.942276)
		(width 0.14224)
		(layer "In15.Cu")
		(net "P5E_CPU0_P0_RX_BUF_DN<6>")
	)
	(segment
		(start 311.016396 -400.811238)
		(end 311.016396 -400.962622)
		(width 0.14224)
		(layer "In15.Cu")
		(net "P5E_CPU0_P0_RX_BUF_DN<6>")
	)
	(segment
		(start 322.322698 -414.52165)
		(end 322.464176 -414.863026)
		(width 0.14224)
		(layer "In15.Cu")
		(net "P5E_CPU0_P0_RX_BUF_DN<6>")
	)
	(segment
		(start 320.798952 -411.98673)
		(end 320.91122 -412.203138)
		(width 0.14224)
		(layer "In15.Cu")
		(net "P5E_CPU0_P0_RX_BUF_DN<6>")
	)
	(segment
		(start 323.522594 -419.95852)
		(end 323.948552 -420.384478)
		(width 0.14224)
		(layer "In15.Cu")
		(net "P5E_CPU0_P0_RX_BUF_DN<6>")
	)
	(segment
		(start 323.995796 -420.498524)
		(end 323.995796 -421.298878)
		(width 0.14224)
		(layer "In15.Cu")
		(net "P5E_CPU0_P0_RX_BUF_DN<6>")
	)
	(segment
		(start 321.312032 -414.16605)
		(end 321.487038 -414.238694)
		(width 0.14224)
		(layer "In15.Cu")
		(net "P5E_CPU0_P0_RX_BUF_DN<6>")
	)
	(segment
		(start 311.016396 -400.962622)
		(end 310.889396 -401.089622)
		(width 0.14224)
		(layer "In15.Cu")
		(net "P5E_CPU0_P0_RX_BUF_DN<6>")
	)
	(segment
		(start 314.215018 -409.800044)
		(end 320.32702 -411.654244)
		(width 0.14224)
		(layer "In15.Cu")
		(net "P5E_CPU0_P0_RX_BUF_DN<6>")
	)
	(segment
		(start 310.889396 -401.089622)
		(end 310.580024 -401.089622)
		(width 0.14224)
		(layer "In15.Cu")
		(net "P5E_CPU0_P0_RX_BUF_DN<6>")
	)
	(segment
		(start 321.99961 -414.238694)
		(end 322.06819 -414.267142)
		(width 0.14224)
		(layer "In15.Cu")
		(net "P5E_CPU0_P0_RX_BUF_DN<6>")
	)
	(segment
		(start 322.464176 -414.863026)
		(end 322.464176 -418.512752)
		(width 0.14224)
		(layer "In15.Cu")
		(net "P5E_CPU0_P0_RX_BUF_DN<6>")
	)
	(segment
		(start 326.50303 -437.623204)
		(end 326.649588 -437.769762)
		(width 0.14224)
		(layer "In15.Cu")
		(net "P5E_CPU0_P0_RX_BUF_DN<6>")
	)
	(segment
		(start 310.275478 -401.394168)
		(end 310.275478 -405.648922)
		(width 0.14224)
		(layer "In15.Cu")
		(net "P5E_CPU0_P0_RX_BUF_DN<6>")
	)
	(segment
		(start 310.507634 -406.209246)
		(end 311.953148 -407.655014)
		(width 0.14224)
		(layer "In15.Cu")
		(net "P5E_CPU0_P0_RX_BUF_DN<6>")
	)
	(segment
		(start 321.487038 -414.238694)
		(end 321.99961 -414.238694)
		(width 0.14224)
		(layer "In15.Cu")
		(net "P5E_CPU0_P0_RX_BUF_DN<6>")
	)
	(segment
		(start 325.68896 -437.254142)
		(end 326.058022 -437.623204)
		(width 0.14224)
		(layer "In15.Cu")
		(net "P5E_CPU0_P0_RX_BUF_DN<6>")
	)
	(segment
		(start 320.932556 -412.289752)
		(end 320.932556 -413.566102)
		(width 0.14224)
		(layer "In15.Cu")
		(net "P5E_CPU0_P0_RX_BUF_DN<6>")
	)
	(segment
		(start 320.32702 -411.654244)
		(end 320.798952 -411.98673)
		(width 0.14224)
		(layer "In15.Cu")
		(net "P5E_CPU0_P0_RX_BUF_DN<6>")
	)
	(segment
		(start 324.071234 -421.634412)
		(end 325.663306 -425.00042)
		(width 0.14224)
		(layer "In15.Cu")
		(net "P5E_CPU0_P0_RX_BUF_DN<6>")
	)
	(segment
		(start 311.953148 -407.655014)
		(end 311.953148 -407.65476)
		(width 0.14224)
		(layer "In15.Cu")
		(net "P5E_CPU0_P0_RX_BUF_DN<6>")
	)
	(segment
		(start 310.580024 -401.089622)
		(end 310.275478 -401.394168)
		(width 0.14224)
		(layer "In15.Cu")
		(net "P5E_CPU0_P0_RX_BUF_DN<6>")
	)
	(segment
		(start 322.680838 -419.156896)
		(end 322.681346 -419.156896)
		(width 0.14224)
		(layer "In15.Cu")
		(net "P5E_CPU0_P0_RX_BUF_DN<6>")
	)
	(segment
		(start 325.68896 -425.099734)
		(end 325.68896 -437.254142)
		(width 0.14224)
		(layer "In15.Cu")
		(net "P5E_CPU0_P0_RX_BUF_DN<6>")
	)
	(segment
		(start 322.51015 -418.743892)
		(end 322.680838 -419.156896)
		(width 0.14224)
		(layer "In15.Cu")
		(net "P5E_CPU0_P0_RX_BUF_DN<6>")
	)
	(arc
		(start 310.275478 -405.648922)
		(mid 310.335817 -405.952177)
		(end 310.507634 -406.209246)
		(width 0.14224)
		(layer "In15.Cu")
		(net "P5E_CPU0_P0_RX_BUF_DN<6>")
	)
	(arc
		(start 322.681346 -419.156896)
		(mid 322.896012 -419.492728)
		(end 323.213476 -419.73373)
		(width 0.14224)
		(layer "In15.Cu")
		(net "P5E_CPU0_P0_RX_BUF_DN<6>")
	)
	(arc
		(start 322.464176 -418.512752)
		(mid 322.475772 -418.63059)
		(end 322.51015 -418.743892)
		(width 0.14224)
		(layer "In15.Cu")
		(net "P5E_CPU0_P0_RX_BUF_DN<6>")
	)
	(arc
		(start 323.948552 -420.384478)
		(mid 323.983514 -420.436803)
		(end 323.995796 -420.498524)
		(width 0.14224)
		(layer "In15.Cu")
		(net "P5E_CPU0_P0_RX_BUF_DN<6>")
	)
	(arc
		(start 325.663306 -425.00042)
		(mid 325.680918 -425.048842)
		(end 325.68896 -425.099734)
		(width 0.14224)
		(layer "In15.Cu")
		(net "P5E_CPU0_P0_RX_BUF_DN<6>")
	)
	(arc
		(start 323.995796 -421.298878)
		(mid 324.014902 -421.470833)
		(end 324.071234 -421.634412)
		(width 0.14224)
		(layer "In15.Cu")
		(net "P5E_CPU0_P0_RX_BUF_DN<6>")
	)
	(arc
		(start 313.923172 -409.624784)
		(mid 314.058291 -409.730404)
		(end 314.215018 -409.800044)
		(width 0.14224)
		(layer "In15.Cu")
		(net "P5E_CPU0_P0_RX_BUF_DN<6>")
	)
	(arc
		(start 320.91122 -412.203138)
		(mid 320.927076 -412.245164)
		(end 320.932556 -412.289752)
		(width 0.14224)
		(layer "In15.Cu")
		(net "P5E_CPU0_P0_RX_BUF_DN<6>")
	)
	(arc
		(start 323.213476 -419.73373)
		(mid 323.376813 -419.834052)
		(end 323.522594 -419.95852)
		(width 0.14224)
		(layer "In15.Cu")
		(net "P5E_CPU0_P0_RX_BUF_DN<6>")
	)
	(segment
		(start 309.456582 -401.143216)
		(end 309.67553 -401.143216)
		(width 0.1016)
		(layer "F.Cu")
		(net "P5E_CPU0_P0_RX_BUF_DN<5>")
	)
	(segment
		(start 309.816246 -401.0025)
		(end 309.816246 -400.811238)
		(width 0.1016)
		(layer "F.Cu")
		(net "P5E_CPU0_P0_RX_BUF_DN<5>")
	)
	(segment
		(start 309.418228 -399.143982)
		(end 309.418228 -399.960338)
		(width 0.1016)
		(layer "F.Cu")
		(net "P5E_CPU0_P0_RX_BUF_DN<5>")
	)
	(segment
		(start 309.67553 -401.143216)
		(end 309.816246 -401.0025)
		(width 0.1016)
		(layer "F.Cu")
		(net "P5E_CPU0_P0_RX_BUF_DN<5>")
	)
	(segment
		(start 309.329582 -400.048984)
		(end 309.329582 -401.016216)
		(width 0.1016)
		(layer "F.Cu")
		(net "P5E_CPU0_P0_RX_BUF_DN<5>")
	)
	(segment
		(start 309.41772 -399.143474)
		(end 309.418228 -399.143982)
		(width 0.1016)
		(layer "F.Cu")
		(net "P5E_CPU0_P0_RX_BUF_DN<5>")
	)
	(segment
		(start 309.329582 -401.016216)
		(end 309.456582 -401.143216)
		(width 0.1016)
		(layer "F.Cu")
		(net "P5E_CPU0_P0_RX_BUF_DN<5>")
	)
	(segment
		(start 309.418228 -399.960338)
		(end 309.329582 -400.048984)
		(width 0.1016)
		(layer "F.Cu")
		(net "P5E_CPU0_P0_RX_BUF_DN<5>")
	)
	(segment
		(start 318.038226 -413.955484)
		(end 318.248792 -414.16605)
		(width 0.14224)
		(layer "In15.Cu")
		(net "P5E_CPU0_P0_RX_BUF_DN<5>")
	)
	(segment
		(start 317.347092 -411.748478)
		(end 317.768224 -412.00197)
		(width 0.14224)
		(layer "In15.Cu")
		(net "P5E_CPU0_P0_RX_BUF_DN<5>")
	)
	(segment
		(start 318.248792 -414.16605)
		(end 318.423798 -414.238694)
		(width 0.14224)
		(layer "In15.Cu")
		(net "P5E_CPU0_P0_RX_BUF_DN<5>")
	)
	(segment
		(start 309.195216 -406.591008)
		(end 312.735722 -410.131514)
		(width 0.14224)
		(layer "In15.Cu")
		(net "P5E_CPU0_P0_RX_BUF_DN<5>")
	)
	(segment
		(start 319.259458 -414.52165)
		(end 319.400936 -414.863026)
		(width 0.14224)
		(layer "In15.Cu")
		(net "P5E_CPU0_P0_RX_BUF_DN<5>")
	)
	(segment
		(start 324.649592 -438.76976)
		(end 324.649592 -439.0898)
		(width 0.14224)
		(layer "In15.Cu")
		(net "P5E_CPU0_P0_RX_BUF_DN<5>")
	)
	(segment
		(start 309.379874 -401.089622)
		(end 309.075328 -401.394168)
		(width 0.14224)
		(layer "In15.Cu")
		(net "P5E_CPU0_P0_RX_BUF_DN<5>")
	)
	(segment
		(start 317.869316 -413.547814)
		(end 318.038226 -413.955484)
		(width 0.14224)
		(layer "In15.Cu")
		(net "P5E_CPU0_P0_RX_BUF_DN<5>")
	)
	(segment
		(start 320.960496 -421.408352)
		(end 320.960496 -421.40886)
		(width 0.14224)
		(layer "In15.Cu")
		(net "P5E_CPU0_P0_RX_BUF_DN<5>")
	)
	(segment
		(start 323.700648 -425.539662)
		(end 323.700648 -438.265824)
		(width 0.14224)
		(layer "In15.Cu")
		(net "P5E_CPU0_P0_RX_BUF_DN<5>")
	)
	(segment
		(start 324.058026 -438.623202)
		(end 324.503034 -438.623202)
		(width 0.14224)
		(layer "In15.Cu")
		(net "P5E_CPU0_P0_RX_BUF_DN<5>")
	)
	(segment
		(start 309.816246 -400.962622)
		(end 309.689246 -401.089622)
		(width 0.14224)
		(layer "In15.Cu")
		(net "P5E_CPU0_P0_RX_BUF_DN<5>")
	)
	(segment
		(start 319.00495 -414.267142)
		(end 319.259458 -414.52165)
		(width 0.14224)
		(layer "In15.Cu")
		(net "P5E_CPU0_P0_RX_BUF_DN<5>")
	)
	(segment
		(start 319.400936 -418.821362)
		(end 319.52438 -419.119304)
		(width 0.14224)
		(layer "In15.Cu")
		(net "P5E_CPU0_P0_RX_BUF_DN<5>")
	)
	(segment
		(start 323.700648 -438.265824)
		(end 324.058026 -438.623202)
		(width 0.14224)
		(layer "In15.Cu")
		(net "P5E_CPU0_P0_RX_BUF_DN<5>")
	)
	(segment
		(start 319.400936 -414.863026)
		(end 319.400936 -418.821362)
		(width 0.14224)
		(layer "In15.Cu")
		(net "P5E_CPU0_P0_RX_BUF_DN<5>")
	)
	(segment
		(start 320.988944 -421.494712)
		(end 323.22008 -424.501818)
		(width 0.14224)
		(layer "In15.Cu")
		(net "P5E_CPU0_P0_RX_BUF_DN<5>")
	)
	(segment
		(start 309.689246 -401.089622)
		(end 309.379874 -401.089622)
		(width 0.14224)
		(layer "In15.Cu")
		(net "P5E_CPU0_P0_RX_BUF_DN<5>")
	)
	(segment
		(start 324.503034 -438.623202)
		(end 324.649592 -438.76976)
		(width 0.14224)
		(layer "In15.Cu")
		(net "P5E_CPU0_P0_RX_BUF_DN<5>")
	)
	(segment
		(start 313.475116 -410.574744)
		(end 317.347092 -411.748478)
		(width 0.14224)
		(layer "In15.Cu")
		(net "P5E_CPU0_P0_RX_BUF_DN<5>")
	)
	(segment
		(start 320.932556 -420.453312)
		(end 320.932556 -421.323516)
		(width 0.14224)
		(layer "In15.Cu")
		(net "P5E_CPU0_P0_RX_BUF_DN<5>")
	)
	(segment
		(start 323.22008 -424.501818)
		(end 323.492622 -424.910504)
		(width 0.14224)
		(layer "In15.Cu")
		(net "P5E_CPU0_P0_RX_BUF_DN<5>")
	)
	(segment
		(start 309.816246 -400.811238)
		(end 309.816246 -400.962622)
		(width 0.14224)
		(layer "In15.Cu")
		(net "P5E_CPU0_P0_RX_BUF_DN<5>")
	)
	(segment
		(start 320.932556 -421.323516)
		(end 320.960496 -421.408352)
		(width 0.14224)
		(layer "In15.Cu")
		(net "P5E_CPU0_P0_RX_BUF_DN<5>")
	)
	(segment
		(start 320.960496 -421.40886)
		(end 320.988944 -421.494712)
		(width 0.14224)
		(layer "In15.Cu")
		(net "P5E_CPU0_P0_RX_BUF_DN<5>")
	)
	(segment
		(start 318.93637 -414.238694)
		(end 319.00495 -414.267142)
		(width 0.14224)
		(layer "In15.Cu")
		(net "P5E_CPU0_P0_RX_BUF_DN<5>")
	)
	(segment
		(start 318.423798 -414.238694)
		(end 318.93637 -414.238694)
		(width 0.14224)
		(layer "In15.Cu")
		(net "P5E_CPU0_P0_RX_BUF_DN<5>")
	)
	(segment
		(start 309.075328 -401.394168)
		(end 309.075328 -406.301448)
		(width 0.14224)
		(layer "In15.Cu")
		(net "P5E_CPU0_P0_RX_BUF_DN<5>")
	)
	(segment
		(start 323.492622 -424.910504)
		(end 323.651626 -425.29379)
		(width 0.14224)
		(layer "In15.Cu")
		(net "P5E_CPU0_P0_RX_BUF_DN<5>")
	)
	(segment
		(start 317.869316 -412.180786)
		(end 317.869316 -413.547814)
		(width 0.14224)
		(layer "In15.Cu")
		(net "P5E_CPU0_P0_RX_BUF_DN<5>")
	)
	(segment
		(start 320.429636 -419.897814)
		(end 320.895218 -420.363396)
		(width 0.14224)
		(layer "In15.Cu")
		(net "P5E_CPU0_P0_RX_BUF_DN<5>")
	)
	(segment
		(start 320.139314 -419.733222)
		(end 320.253868 -419.780466)
		(width 0.14224)
		(layer "In15.Cu")
		(net "P5E_CPU0_P0_RX_BUF_DN<5>")
	)
	(arc
		(start 323.651626 -425.29379)
		(mid 323.688273 -425.414306)
		(end 323.700648 -425.539662)
		(width 0.14224)
		(layer "In15.Cu")
		(net "P5E_CPU0_P0_RX_BUF_DN<5>")
	)
	(arc
		(start 317.768224 -412.00197)
		(mid 317.842262 -412.07809)
		(end 317.869316 -412.180786)
		(width 0.14224)
		(layer "In15.Cu")
		(net "P5E_CPU0_P0_RX_BUF_DN<5>")
	)
	(arc
		(start 309.075328 -406.301448)
		(mid 309.10648 -406.458151)
		(end 309.195216 -406.591008)
		(width 0.14224)
		(layer "In15.Cu")
		(net "P5E_CPU0_P0_RX_BUF_DN<5>")
	)
	(arc
		(start 312.735722 -410.131514)
		(mid 313.078067 -410.39876)
		(end 313.475116 -410.574744)
		(width 0.14224)
		(layer "In15.Cu")
		(net "P5E_CPU0_P0_RX_BUF_DN<5>")
	)
	(arc
		(start 320.253868 -419.780466)
		(mid 320.347552 -419.830452)
		(end 320.429636 -419.897814)
		(width 0.14224)
		(layer "In15.Cu")
		(net "P5E_CPU0_P0_RX_BUF_DN<5>")
	)
	(arc
		(start 320.895218 -420.363396)
		(mid 320.922837 -420.404636)
		(end 320.932556 -420.453312)
		(width 0.14224)
		(layer "In15.Cu")
		(net "P5E_CPU0_P0_RX_BUF_DN<5>")
	)
	(arc
		(start 319.52438 -419.119304)
		(mid 319.770834 -419.487373)
		(end 320.139314 -419.733222)
		(width 0.14224)
		(layer "In15.Cu")
		(net "P5E_CPU0_P0_RX_BUF_DN<5>")
	)
	(segment
		(start 308.218332 -399.143982)
		(end 308.218332 -399.960338)
		(width 0.1016)
		(layer "F.Cu")
		(net "P5E_CPU0_P0_RX_BUF_DN<4>")
	)
	(segment
		(start 308.129686 -400.048984)
		(end 308.129686 -401.016216)
		(width 0.1016)
		(layer "F.Cu")
		(net "P5E_CPU0_P0_RX_BUF_DN<4>")
	)
	(segment
		(start 308.129686 -401.016216)
		(end 308.256686 -401.143216)
		(width 0.1016)
		(layer "F.Cu")
		(net "P5E_CPU0_P0_RX_BUF_DN<4>")
	)
	(segment
		(start 308.256686 -401.143216)
		(end 308.475634 -401.143216)
		(width 0.1016)
		(layer "F.Cu")
		(net "P5E_CPU0_P0_RX_BUF_DN<4>")
	)
	(segment
		(start 308.217824 -399.143474)
		(end 308.218332 -399.143982)
		(width 0.1016)
		(layer "F.Cu")
		(net "P5E_CPU0_P0_RX_BUF_DN<4>")
	)
	(segment
		(start 308.61635 -401.0025)
		(end 308.61635 -400.811238)
		(width 0.1016)
		(layer "F.Cu")
		(net "P5E_CPU0_P0_RX_BUF_DN<4>")
	)
	(segment
		(start 308.218332 -399.960338)
		(end 308.129686 -400.048984)
		(width 0.1016)
		(layer "F.Cu")
		(net "P5E_CPU0_P0_RX_BUF_DN<4>")
	)
	(segment
		(start 308.475634 -401.143216)
		(end 308.61635 -401.0025)
		(width 0.1016)
		(layer "F.Cu")
		(net "P5E_CPU0_P0_RX_BUF_DN<4>")
	)
	(segment
		(start 316.337696 -414.863026)
		(end 316.337696 -418.683694)
		(width 0.14224)
		(layer "In15.Cu")
		(net "P5E_CPU0_P0_RX_BUF_DN<4>")
	)
	(segment
		(start 308.179978 -401.089622)
		(end 307.875432 -401.394168)
		(width 0.14224)
		(layer "In15.Cu")
		(net "P5E_CPU0_P0_RX_BUF_DN<4>")
	)
	(segment
		(start 321.688968 -425.135294)
		(end 321.688968 -437.254142)
		(width 0.14224)
		(layer "In15.Cu")
		(net "P5E_CPU0_P0_RX_BUF_DN<4>")
	)
	(segment
		(start 308.007512 -407.033222)
		(end 312.307986 -411.333696)
		(width 0.14224)
		(layer "In15.Cu")
		(net "P5E_CPU0_P0_RX_BUF_DN<4>")
	)
	(segment
		(start 314.806076 -412.376874)
		(end 314.806076 -413.622998)
		(width 0.14224)
		(layer "In15.Cu")
		(net "P5E_CPU0_P0_RX_BUF_DN<4>")
	)
	(segment
		(start 307.875432 -401.394168)
		(end 307.875432 -406.714198)
		(width 0.14224)
		(layer "In15.Cu")
		(net "P5E_CPU0_P0_RX_BUF_DN<4>")
	)
	(segment
		(start 321.202558 -424.283124)
		(end 321.424808 -424.505374)
		(width 0.14224)
		(layer "In15.Cu")
		(net "P5E_CPU0_P0_RX_BUF_DN<4>")
	)
	(segment
		(start 308.61635 -400.811238)
		(end 308.61635 -400.962622)
		(width 0.14224)
		(layer "In15.Cu")
		(net "P5E_CPU0_P0_RX_BUF_DN<4>")
	)
	(segment
		(start 312.517282 -411.44571)
		(end 314.253372 -411.791404)
		(width 0.14224)
		(layer "In15.Cu")
		(net "P5E_CPU0_P0_RX_BUF_DN<4>")
	)
	(segment
		(start 318.422782 -422.428162)
		(end 321.202558 -424.283124)
		(width 0.14224)
		(layer "In15.Cu")
		(net "P5E_CPU0_P0_RX_BUF_DN<4>")
	)
	(segment
		(start 314.921646 -413.902144)
		(end 315.185552 -414.16605)
		(width 0.14224)
		(layer "In15.Cu")
		(net "P5E_CPU0_P0_RX_BUF_DN<4>")
	)
	(segment
		(start 321.688968 -437.254142)
		(end 322.05803 -437.623204)
		(width 0.14224)
		(layer "In15.Cu")
		(net "P5E_CPU0_P0_RX_BUF_DN<4>")
	)
	(segment
		(start 322.503038 -437.623204)
		(end 322.649596 -437.769762)
		(width 0.14224)
		(layer "In15.Cu")
		(net "P5E_CPU0_P0_RX_BUF_DN<4>")
	)
	(segment
		(start 322.05803 -437.623204)
		(end 322.503038 -437.623204)
		(width 0.14224)
		(layer "In15.Cu")
		(net "P5E_CPU0_P0_RX_BUF_DN<4>")
	)
	(segment
		(start 314.806076 -413.622998)
		(end 314.921646 -413.902144)
		(width 0.14224)
		(layer "In15.Cu")
		(net "P5E_CPU0_P0_RX_BUF_DN<4>")
	)
	(segment
		(start 314.253372 -411.791404)
		(end 314.479178 -411.884876)
		(width 0.14224)
		(layer "In15.Cu")
		(net "P5E_CPU0_P0_RX_BUF_DN<4>")
	)
	(segment
		(start 315.83503 -414.238694)
		(end 315.968634 -414.294066)
		(width 0.14224)
		(layer "In15.Cu")
		(net "P5E_CPU0_P0_RX_BUF_DN<4>")
	)
	(segment
		(start 316.196218 -414.52165)
		(end 316.337696 -414.863026)
		(width 0.14224)
		(layer "In15.Cu")
		(net "P5E_CPU0_P0_RX_BUF_DN<4>")
	)
	(segment
		(start 316.337696 -418.683694)
		(end 316.548262 -419.192202)
		(width 0.14224)
		(layer "In15.Cu")
		(net "P5E_CPU0_P0_RX_BUF_DN<4>")
	)
	(segment
		(start 315.968634 -414.294066)
		(end 316.196218 -414.52165)
		(width 0.14224)
		(layer "In15.Cu")
		(net "P5E_CPU0_P0_RX_BUF_DN<4>")
	)
	(segment
		(start 315.360558 -414.238694)
		(end 315.83503 -414.238694)
		(width 0.14224)
		(layer "In15.Cu")
		(net "P5E_CPU0_P0_RX_BUF_DN<4>")
	)
	(segment
		(start 308.61635 -400.962622)
		(end 308.48935 -401.089622)
		(width 0.14224)
		(layer "In15.Cu")
		(net "P5E_CPU0_P0_RX_BUF_DN<4>")
	)
	(segment
		(start 314.479178 -411.884876)
		(end 314.689236 -412.094934)
		(width 0.14224)
		(layer "In15.Cu")
		(net "P5E_CPU0_P0_RX_BUF_DN<4>")
	)
	(segment
		(start 317.382652 -419.87089)
		(end 317.831978 -420.3192)
		(width 0.14224)
		(layer "In15.Cu")
		(net "P5E_CPU0_P0_RX_BUF_DN<4>")
	)
	(segment
		(start 317.007494 -419.686232)
		(end 317.26632 -419.79342)
		(width 0.14224)
		(layer "In15.Cu")
		(net "P5E_CPU0_P0_RX_BUF_DN<4>")
	)
	(segment
		(start 317.869316 -420.409116)
		(end 317.869316 -421.321992)
		(width 0.14224)
		(layer "In15.Cu")
		(net "P5E_CPU0_P0_RX_BUF_DN<4>")
	)
	(segment
		(start 308.48935 -401.089622)
		(end 308.179978 -401.089622)
		(width 0.14224)
		(layer "In15.Cu")
		(net "P5E_CPU0_P0_RX_BUF_DN<4>")
	)
	(segment
		(start 315.185552 -414.16605)
		(end 315.360558 -414.238694)
		(width 0.14224)
		(layer "In15.Cu")
		(net "P5E_CPU0_P0_RX_BUF_DN<4>")
	)
	(segment
		(start 322.649596 -437.769762)
		(end 322.649596 -438.089802)
		(width 0.14224)
		(layer "In15.Cu")
		(net "P5E_CPU0_P0_RX_BUF_DN<4>")
	)
	(segment
		(start 317.899542 -421.52824)
		(end 317.982092 -421.801798)
		(width 0.14224)
		(layer "In15.Cu")
		(net "P5E_CPU0_P0_RX_BUF_DN<4>")
	)
	(arc
		(start 321.661028 -424.923458)
		(mid 321.670633 -424.966085)
		(end 321.678554 -425.009056)
		(width 0.14224)
		(layer "In15.Cu")
		(net "P5E_CPU0_P0_RX_BUF_DN<4>")
	)
	(arc
		(start 317.982092 -421.801798)
		(mid 318.152011 -422.150457)
		(end 318.422782 -422.428162)
		(width 0.14224)
		(layer "In15.Cu")
		(net "P5E_CPU0_P0_RX_BUF_DN<4>")
	)
	(arc
		(start 307.875432 -406.714198)
		(mid 307.909755 -406.886842)
		(end 308.007512 -407.033222)
		(width 0.14224)
		(layer "In15.Cu")
		(net "P5E_CPU0_P0_RX_BUF_DN<4>")
	)
	(arc
		(start 314.689236 -412.094934)
		(mid 314.775722 -412.224275)
		(end 314.806076 -412.376874)
		(width 0.14224)
		(layer "In15.Cu")
		(net "P5E_CPU0_P0_RX_BUF_DN<4>")
	)
	(arc
		(start 316.548262 -419.192202)
		(mid 316.663305 -419.398165)
		(end 316.822582 -419.572186)
		(width 0.14224)
		(layer "In15.Cu")
		(net "P5E_CPU0_P0_RX_BUF_DN<4>")
	)
	(arc
		(start 321.678554 -425.009056)
		(mid 321.68635 -425.071961)
		(end 321.688968 -425.135294)
		(width 0.14224)
		(layer "In15.Cu")
		(net "P5E_CPU0_P0_RX_BUF_DN<4>")
	)
	(arc
		(start 317.831978 -420.3192)
		(mid 317.859597 -420.36044)
		(end 317.869316 -420.409116)
		(width 0.14224)
		(layer "In15.Cu")
		(net "P5E_CPU0_P0_RX_BUF_DN<4>")
	)
	(arc
		(start 321.424808 -424.505374)
		(mid 321.571455 -424.698294)
		(end 321.661028 -424.923458)
		(width 0.14224)
		(layer "In15.Cu")
		(net "P5E_CPU0_P0_RX_BUF_DN<4>")
	)
	(arc
		(start 317.26632 -419.79342)
		(mid 317.328288 -419.826446)
		(end 317.382652 -419.87089)
		(width 0.14224)
		(layer "In15.Cu")
		(net "P5E_CPU0_P0_RX_BUF_DN<4>")
	)
	(arc
		(start 317.869316 -421.321992)
		(mid 317.87685 -421.426228)
		(end 317.899542 -421.52824)
		(width 0.14224)
		(layer "In15.Cu")
		(net "P5E_CPU0_P0_RX_BUF_DN<4>")
	)
	(arc
		(start 312.307986 -411.333696)
		(mid 312.404329 -411.405219)
		(end 312.517282 -411.44571)
		(width 0.14224)
		(layer "In15.Cu")
		(net "P5E_CPU0_P0_RX_BUF_DN<4>")
	)
	(arc
		(start 316.822582 -419.572186)
		(mid 316.910437 -419.636667)
		(end 317.007494 -419.686232)
		(width 0.14224)
		(layer "In15.Cu")
		(net "P5E_CPU0_P0_RX_BUF_DN<4>")
	)
	(segment
		(start 306.942744 -400.035776)
		(end 306.942744 -401.016216)
		(width 0.1016)
		(layer "F.Cu")
		(net "P5E_CPU0_P0_RX_BUF_DN<3>")
	)
	(segment
		(start 307.018182 -399.143982)
		(end 307.018182 -399.960338)
		(width 0.1016)
		(layer "F.Cu")
		(net "P5E_CPU0_P0_RX_BUF_DN<3>")
	)
	(segment
		(start 306.942744 -401.016216)
		(end 307.069744 -401.143216)
		(width 0.1016)
		(layer "F.Cu")
		(net "P5E_CPU0_P0_RX_BUF_DN<3>")
	)
	(segment
		(start 307.069744 -401.143216)
		(end 307.275484 -401.143216)
		(width 0.1016)
		(layer "F.Cu")
		(net "P5E_CPU0_P0_RX_BUF_DN<3>")
	)
	(segment
		(start 307.017674 -399.143474)
		(end 307.018182 -399.143982)
		(width 0.1016)
		(layer "F.Cu")
		(net "P5E_CPU0_P0_RX_BUF_DN<3>")
	)
	(segment
		(start 307.018182 -399.960338)
		(end 306.942744 -400.035776)
		(width 0.1016)
		(layer "F.Cu")
		(net "P5E_CPU0_P0_RX_BUF_DN<3>")
	)
	(segment
		(start 307.4162 -401.0025)
		(end 307.4162 -400.811238)
		(width 0.1016)
		(layer "F.Cu")
		(net "P5E_CPU0_P0_RX_BUF_DN<3>")
	)
	(segment
		(start 307.275484 -401.143216)
		(end 307.4162 -401.0025)
		(width 0.1016)
		(layer "F.Cu")
		(net "P5E_CPU0_P0_RX_BUF_DN<3>")
	)
	(segment
		(start 319.049146 -424.281854)
		(end 319.468246 -424.792902)
		(width 0.14224)
		(layer "In15.Cu")
		(net "P5E_CPU0_P0_RX_BUF_DN<3>")
	)
	(segment
		(start 313.132978 -414.52165)
		(end 313.274456 -414.863026)
		(width 0.14224)
		(layer "In15.Cu")
		(net "P5E_CPU0_P0_RX_BUF_DN<3>")
	)
	(segment
		(start 307.2892 -401.089622)
		(end 306.979828 -401.089622)
		(width 0.14224)
		(layer "In15.Cu")
		(net "P5E_CPU0_P0_RX_BUF_DN<3>")
	)
	(segment
		(start 307.4162 -400.962622)
		(end 307.2892 -401.089622)
		(width 0.14224)
		(layer "In15.Cu")
		(net "P5E_CPU0_P0_RX_BUF_DN<3>")
	)
	(segment
		(start 312.87847 -414.267142)
		(end 313.132978 -414.52165)
		(width 0.14224)
		(layer "In15.Cu")
		(net "P5E_CPU0_P0_RX_BUF_DN<3>")
	)
	(segment
		(start 317.202312 -423.172636)
		(end 318.135762 -423.671746)
		(width 0.14224)
		(layer "In15.Cu")
		(net "P5E_CPU0_P0_RX_BUF_DN<3>")
	)
	(segment
		(start 306.979828 -401.089622)
		(end 306.675282 -401.394168)
		(width 0.14224)
		(layer "In15.Cu")
		(net "P5E_CPU0_P0_RX_BUF_DN<3>")
	)
	(segment
		(start 318.135762 -423.671746)
		(end 319.049146 -424.281854)
		(width 0.14224)
		(layer "In15.Cu")
		(net "P5E_CPU0_P0_RX_BUF_DN<3>")
	)
	(segment
		(start 320.503042 -438.623202)
		(end 320.6496 -438.76976)
		(width 0.14224)
		(layer "In15.Cu")
		(net "P5E_CPU0_P0_RX_BUF_DN<3>")
	)
	(segment
		(start 311.742836 -413.623252)
		(end 311.858406 -413.902144)
		(width 0.14224)
		(layer "In15.Cu")
		(net "P5E_CPU0_P0_RX_BUF_DN<3>")
	)
	(segment
		(start 313.274456 -418.801296)
		(end 313.36615 -419.02253)
		(width 0.14224)
		(layer "In15.Cu")
		(net "P5E_CPU0_P0_RX_BUF_DN<3>")
	)
	(segment
		(start 315.064902 -421.8686)
		(end 315.349382 -422.15308)
		(width 0.14224)
		(layer "In15.Cu")
		(net "P5E_CPU0_P0_RX_BUF_DN<3>")
	)
	(segment
		(start 319.991232 -438.623202)
		(end 320.503042 -438.623202)
		(width 0.14224)
		(layer "In15.Cu")
		(net "P5E_CPU0_P0_RX_BUF_DN<3>")
	)
	(segment
		(start 315.349382 -422.15308)
		(end 315.969142 -422.567354)
		(width 0.14224)
		(layer "In15.Cu")
		(net "P5E_CPU0_P0_RX_BUF_DN<3>")
	)
	(segment
		(start 319.557654 -424.941746)
		(end 319.651634 -425.168314)
		(width 0.14224)
		(layer "In15.Cu")
		(net "P5E_CPU0_P0_RX_BUF_DN<3>")
	)
	(segment
		(start 314.295028 -419.850062)
		(end 314.768738 -420.324026)
		(width 0.14224)
		(layer "In15.Cu")
		(net "P5E_CPU0_P0_RX_BUF_DN<3>")
	)
	(segment
		(start 314.122562 -419.778942)
		(end 314.295028 -419.850062)
		(width 0.14224)
		(layer "In15.Cu")
		(net "P5E_CPU0_P0_RX_BUF_DN<3>")
	)
	(segment
		(start 314.806076 -420.413942)
		(end 314.806076 -421.24376)
		(width 0.14224)
		(layer "In15.Cu")
		(net "P5E_CPU0_P0_RX_BUF_DN<3>")
	)
	(segment
		(start 307.4162 -400.811238)
		(end 307.4162 -400.962622)
		(width 0.14224)
		(layer "In15.Cu")
		(net "P5E_CPU0_P0_RX_BUF_DN<3>")
	)
	(segment
		(start 306.79517 -407.350468)
		(end 311.64657 -412.201868)
		(width 0.14224)
		(layer "In15.Cu")
		(net "P5E_CPU0_P0_RX_BUF_DN<3>")
	)
	(segment
		(start 311.742836 -412.434024)
		(end 311.742836 -413.623252)
		(width 0.14224)
		(layer "In15.Cu")
		(net "P5E_CPU0_P0_RX_BUF_DN<3>")
	)
	(segment
		(start 319.688972 -438.320942)
		(end 319.991232 -438.623202)
		(width 0.14224)
		(layer "In15.Cu")
		(net "P5E_CPU0_P0_RX_BUF_DN<3>")
	)
	(segment
		(start 312.297318 -414.238694)
		(end 312.80989 -414.238694)
		(width 0.14224)
		(layer "In15.Cu")
		(net "P5E_CPU0_P0_RX_BUF_DN<3>")
	)
	(segment
		(start 312.122312 -414.16605)
		(end 312.297318 -414.238694)
		(width 0.14224)
		(layer "In15.Cu")
		(net "P5E_CPU0_P0_RX_BUF_DN<3>")
	)
	(segment
		(start 311.858406 -413.902144)
		(end 312.122312 -414.16605)
		(width 0.14224)
		(layer "In15.Cu")
		(net "P5E_CPU0_P0_RX_BUF_DN<3>")
	)
	(segment
		(start 306.675282 -401.394168)
		(end 306.675282 -407.060908)
		(width 0.14224)
		(layer "In15.Cu")
		(net "P5E_CPU0_P0_RX_BUF_DN<3>")
	)
	(segment
		(start 313.274456 -414.863026)
		(end 313.274456 -418.801296)
		(width 0.14224)
		(layer "In15.Cu")
		(net "P5E_CPU0_P0_RX_BUF_DN<3>")
	)
	(segment
		(start 316.32779 -422.75887)
		(end 317.202312 -423.172636)
		(width 0.14224)
		(layer "In15.Cu")
		(net "P5E_CPU0_P0_RX_BUF_DN<3>")
	)
	(segment
		(start 319.688972 -425.355512)
		(end 319.688972 -438.320942)
		(width 0.14224)
		(layer "In15.Cu")
		(net "P5E_CPU0_P0_RX_BUF_DN<3>")
	)
	(segment
		(start 320.6496 -438.76976)
		(end 320.6496 -439.0898)
		(width 0.14224)
		(layer "In15.Cu")
		(net "P5E_CPU0_P0_RX_BUF_DN<3>")
	)
	(segment
		(start 312.80989 -414.238694)
		(end 312.87847 -414.267142)
		(width 0.14224)
		(layer "In15.Cu")
		(net "P5E_CPU0_P0_RX_BUF_DN<3>")
	)
	(segment
		(start 319.468246 -424.792902)
		(end 319.557654 -424.941746)
		(width 0.14224)
		(layer "In15.Cu")
		(net "P5E_CPU0_P0_RX_BUF_DN<3>")
	)
	(segment
		(start 315.969142 -422.567354)
		(end 316.32779 -422.75887)
		(width 0.14224)
		(layer "In15.Cu")
		(net "P5E_CPU0_P0_RX_BUF_DN<3>")
	)
	(arc
		(start 311.64657 -412.201868)
		(mid 311.717794 -412.308368)
		(end 311.742836 -412.434024)
		(width 0.14224)
		(layer "In15.Cu")
		(net "P5E_CPU0_P0_RX_BUF_DN<3>")
	)
	(arc
		(start 314.768738 -420.324026)
		(mid 314.796357 -420.365266)
		(end 314.806076 -420.413942)
		(width 0.14224)
		(layer "In15.Cu")
		(net "P5E_CPU0_P0_RX_BUF_DN<3>")
	)
	(arc
		(start 306.675282 -407.060908)
		(mid 306.706434 -407.217611)
		(end 306.79517 -407.350468)
		(width 0.14224)
		(layer "In15.Cu")
		(net "P5E_CPU0_P0_RX_BUF_DN<3>")
	)
	(arc
		(start 314.806076 -421.24376)
		(mid 314.873341 -421.581924)
		(end 315.064902 -421.8686)
		(width 0.14224)
		(layer "In15.Cu")
		(net "P5E_CPU0_P0_RX_BUF_DN<3>")
	)
	(arc
		(start 313.36615 -419.02253)
		(mid 313.669131 -419.475961)
		(end 314.122562 -419.778942)
		(width 0.14224)
		(layer "In15.Cu")
		(net "P5E_CPU0_P0_RX_BUF_DN<3>")
	)
	(arc
		(start 319.651634 -425.168314)
		(mid 319.679532 -425.260071)
		(end 319.688972 -425.355512)
		(width 0.14224)
		(layer "In15.Cu")
		(net "P5E_CPU0_P0_RX_BUF_DN<3>")
	)
	(segment
		(start 305.818286 -399.960338)
		(end 305.72964 -400.048984)
		(width 0.1016)
		(layer "F.Cu")
		(net "P5E_CPU0_P0_RX_BUF_DN<2>")
	)
	(segment
		(start 305.818286 -399.143982)
		(end 305.818286 -399.960338)
		(width 0.1016)
		(layer "F.Cu")
		(net "P5E_CPU0_P0_RX_BUF_DN<2>")
	)
	(segment
		(start 306.216304 -401.0025)
		(end 306.216304 -400.811238)
		(width 0.1016)
		(layer "F.Cu")
		(net "P5E_CPU0_P0_RX_BUF_DN<2>")
	)
	(segment
		(start 305.85664 -401.143216)
		(end 306.075588 -401.143216)
		(width 0.1016)
		(layer "F.Cu")
		(net "P5E_CPU0_P0_RX_BUF_DN<2>")
	)
	(segment
		(start 306.075588 -401.143216)
		(end 306.216304 -401.0025)
		(width 0.1016)
		(layer "F.Cu")
		(net "P5E_CPU0_P0_RX_BUF_DN<2>")
	)
	(segment
		(start 305.817778 -399.143474)
		(end 305.818286 -399.143982)
		(width 0.1016)
		(layer "F.Cu")
		(net "P5E_CPU0_P0_RX_BUF_DN<2>")
	)
	(segment
		(start 305.72964 -400.048984)
		(end 305.72964 -401.016216)
		(width 0.1016)
		(layer "F.Cu")
		(net "P5E_CPU0_P0_RX_BUF_DN<2>")
	)
	(segment
		(start 305.72964 -401.016216)
		(end 305.85664 -401.143216)
		(width 0.1016)
		(layer "F.Cu")
		(net "P5E_CPU0_P0_RX_BUF_DN<2>")
	)
	(segment
		(start 306.089304 -401.089622)
		(end 305.779932 -401.089622)
		(width 0.14224)
		(layer "In15.Cu")
		(net "P5E_CPU0_P0_RX_BUF_DN<2>")
	)
	(segment
		(start 318.058038 -437.623204)
		(end 318.503046 -437.623204)
		(width 0.14224)
		(layer "In15.Cu")
		(net "P5E_CPU0_P0_RX_BUF_DN<2>")
	)
	(segment
		(start 312.816494 -422.486582)
		(end 314.452254 -422.981628)
		(width 0.14224)
		(layer "In15.Cu")
		(net "P5E_CPU0_P0_RX_BUF_DN<2>")
	)
	(segment
		(start 308.795166 -413.902144)
		(end 309.059072 -414.16605)
		(width 0.14224)
		(layer "In15.Cu")
		(net "P5E_CPU0_P0_RX_BUF_DN<2>")
	)
	(segment
		(start 317.232792 -424.324526)
		(end 317.624714 -424.716448)
		(width 0.14224)
		(layer "In15.Cu")
		(net "P5E_CPU0_P0_RX_BUF_DN<2>")
	)
	(segment
		(start 305.607974 -408.232102)
		(end 306.994052 -409.920948)
		(width 0.14224)
		(layer "In15.Cu")
		(net "P5E_CPU0_P0_RX_BUF_DN<2>")
	)
	(segment
		(start 306.216304 -400.811238)
		(end 306.216304 -400.962622)
		(width 0.14224)
		(layer "In15.Cu")
		(net "P5E_CPU0_P0_RX_BUF_DN<2>")
	)
	(segment
		(start 317.688976 -437.254142)
		(end 318.058038 -437.623204)
		(width 0.14224)
		(layer "In15.Cu")
		(net "P5E_CPU0_P0_RX_BUF_DN<2>")
	)
	(segment
		(start 310.211216 -414.863026)
		(end 310.211216 -418.786056)
		(width 0.14224)
		(layer "In15.Cu")
		(net "P5E_CPU0_P0_RX_BUF_DN<2>")
	)
	(segment
		(start 310.069738 -414.52165)
		(end 310.211216 -414.863026)
		(width 0.14224)
		(layer "In15.Cu")
		(net "P5E_CPU0_P0_RX_BUF_DN<2>")
	)
	(segment
		(start 317.688976 -424.871642)
		(end 317.688976 -437.254142)
		(width 0.14224)
		(layer "In15.Cu")
		(net "P5E_CPU0_P0_RX_BUF_DN<2>")
	)
	(segment
		(start 318.503046 -437.623204)
		(end 318.649604 -437.769762)
		(width 0.14224)
		(layer "In15.Cu")
		(net "P5E_CPU0_P0_RX_BUF_DN<2>")
	)
	(segment
		(start 309.059072 -414.16605)
		(end 309.234078 -414.238694)
		(width 0.14224)
		(layer "In15.Cu")
		(net "P5E_CPU0_P0_RX_BUF_DN<2>")
	)
	(segment
		(start 314.452254 -422.981628)
		(end 317.0936 -424.231562)
		(width 0.14224)
		(layer "In15.Cu")
		(net "P5E_CPU0_P0_RX_BUF_DN<2>")
	)
	(segment
		(start 305.475386 -401.394168)
		(end 305.475386 -407.860754)
		(width 0.14224)
		(layer "In15.Cu")
		(net "P5E_CPU0_P0_RX_BUF_DN<2>")
	)
	(segment
		(start 306.994052 -409.920948)
		(end 306.994052 -409.921202)
		(width 0.14224)
		(layer "In15.Cu")
		(net "P5E_CPU0_P0_RX_BUF_DN<2>")
	)
	(segment
		(start 306.994052 -409.921202)
		(end 306.993798 -409.921202)
		(width 0.14224)
		(layer "In15.Cu")
		(net "P5E_CPU0_P0_RX_BUF_DN<2>")
	)
	(segment
		(start 310.873394 -419.70198)
		(end 311.234328 -419.851332)
		(width 0.14224)
		(layer "In15.Cu")
		(net "P5E_CPU0_P0_RX_BUF_DN<2>")
	)
	(segment
		(start 305.779932 -401.089622)
		(end 305.475386 -401.394168)
		(width 0.14224)
		(layer "In15.Cu")
		(net "P5E_CPU0_P0_RX_BUF_DN<2>")
	)
	(segment
		(start 306.216304 -400.962622)
		(end 306.089304 -401.089622)
		(width 0.14224)
		(layer "In15.Cu")
		(net "P5E_CPU0_P0_RX_BUF_DN<2>")
	)
	(segment
		(start 311.234328 -419.851332)
		(end 311.705498 -420.322502)
		(width 0.14224)
		(layer "In15.Cu")
		(net "P5E_CPU0_P0_RX_BUF_DN<2>")
	)
	(segment
		(start 308.679596 -413.623252)
		(end 308.795166 -413.902144)
		(width 0.14224)
		(layer "In15.Cu")
		(net "P5E_CPU0_P0_RX_BUF_DN<2>")
	)
	(segment
		(start 311.742836 -420.412418)
		(end 311.742836 -421.218106)
		(width 0.14224)
		(layer "In15.Cu")
		(net "P5E_CPU0_P0_RX_BUF_DN<2>")
	)
	(segment
		(start 310.211216 -418.786056)
		(end 310.390794 -419.219634)
		(width 0.14224)
		(layer "In15.Cu")
		(net "P5E_CPU0_P0_RX_BUF_DN<2>")
	)
	(segment
		(start 308.679342 -412.159196)
		(end 308.679596 -412.159196)
		(width 0.14224)
		(layer "In15.Cu")
		(net "P5E_CPU0_P0_RX_BUF_DN<2>")
	)
	(segment
		(start 311.946798 -421.710358)
		(end 312.123836 -421.975534)
		(width 0.14224)
		(layer "In15.Cu")
		(net "P5E_CPU0_P0_RX_BUF_DN<2>")
	)
	(segment
		(start 312.123836 -421.975534)
		(end 312.363104 -422.214802)
		(width 0.14224)
		(layer "In15.Cu")
		(net "P5E_CPU0_P0_RX_BUF_DN<2>")
	)
	(segment
		(start 309.74665 -414.238694)
		(end 309.81523 -414.267142)
		(width 0.14224)
		(layer "In15.Cu")
		(net "P5E_CPU0_P0_RX_BUF_DN<2>")
	)
	(segment
		(start 311.742836 -421.218106)
		(end 311.946798 -421.710358)
		(width 0.14224)
		(layer "In15.Cu")
		(net "P5E_CPU0_P0_RX_BUF_DN<2>")
	)
	(segment
		(start 318.649604 -437.769762)
		(end 318.649604 -438.089802)
		(width 0.14224)
		(layer "In15.Cu")
		(net "P5E_CPU0_P0_RX_BUF_DN<2>")
	)
	(segment
		(start 317.0936 -424.231562)
		(end 317.232792 -424.324526)
		(width 0.14224)
		(layer "In15.Cu")
		(net "P5E_CPU0_P0_RX_BUF_DN<2>")
	)
	(segment
		(start 309.234078 -414.238694)
		(end 309.74665 -414.238694)
		(width 0.14224)
		(layer "In15.Cu")
		(net "P5E_CPU0_P0_RX_BUF_DN<2>")
	)
	(segment
		(start 309.81523 -414.267142)
		(end 310.069738 -414.52165)
		(width 0.14224)
		(layer "In15.Cu")
		(net "P5E_CPU0_P0_RX_BUF_DN<2>")
	)
	(segment
		(start 308.679596 -412.159196)
		(end 308.679596 -413.623252)
		(width 0.14224)
		(layer "In15.Cu")
		(net "P5E_CPU0_P0_RX_BUF_DN<2>")
	)
	(segment
		(start 312.363104 -422.214802)
		(end 312.816494 -422.486582)
		(width 0.14224)
		(layer "In15.Cu")
		(net "P5E_CPU0_P0_RX_BUF_DN<2>")
	)
	(segment
		(start 306.993798 -409.921202)
		(end 308.562756 -411.832298)
		(width 0.14224)
		(layer "In15.Cu")
		(net "P5E_CPU0_P0_RX_BUF_DN<2>")
	)
	(arc
		(start 317.624714 -424.716448)
		(mid 317.672291 -424.787652)
		(end 317.688976 -424.871642)
		(width 0.14224)
		(layer "In15.Cu")
		(net "P5E_CPU0_P0_RX_BUF_DN<2>")
	)
	(arc
		(start 310.390794 -419.219634)
		(mid 310.58413 -419.50879)
		(end 310.873394 -419.70198)
		(width 0.14224)
		(layer "In15.Cu")
		(net "P5E_CPU0_P0_RX_BUF_DN<2>")
	)
	(arc
		(start 311.705498 -420.322502)
		(mid 311.733117 -420.363742)
		(end 311.742836 -420.412418)
		(width 0.14224)
		(layer "In15.Cu")
		(net "P5E_CPU0_P0_RX_BUF_DN<2>")
	)
	(arc
		(start 305.475386 -407.860754)
		(mid 305.509441 -408.05794)
		(end 305.607974 -408.232102)
		(width 0.14224)
		(layer "In15.Cu")
		(net "P5E_CPU0_P0_RX_BUF_DN<2>")
	)
	(arc
		(start 308.562756 -411.832298)
		(mid 308.649373 -411.985641)
		(end 308.679342 -412.159196)
		(width 0.14224)
		(layer "In15.Cu")
		(net "P5E_CPU0_P0_RX_BUF_DN<2>")
	)
	(segment
		(start 304.52949 -401.016216)
		(end 304.65649 -401.143216)
		(width 0.1016)
		(layer "F.Cu")
		(net "P5E_CPU0_P0_RX_BUF_DN<1>")
	)
	(segment
		(start 304.875438 -401.143216)
		(end 305.016154 -401.0025)
		(width 0.1016)
		(layer "F.Cu")
		(net "P5E_CPU0_P0_RX_BUF_DN<1>")
	)
	(segment
		(start 304.618136 -399.960338)
		(end 304.52949 -400.048984)
		(width 0.1016)
		(layer "F.Cu")
		(net "P5E_CPU0_P0_RX_BUF_DN<1>")
	)
	(segment
		(start 304.617628 -399.143474)
		(end 304.618136 -399.143982)
		(width 0.1016)
		(layer "F.Cu")
		(net "P5E_CPU0_P0_RX_BUF_DN<1>")
	)
	(segment
		(start 304.52949 -400.048984)
		(end 304.52949 -401.016216)
		(width 0.1016)
		(layer "F.Cu")
		(net "P5E_CPU0_P0_RX_BUF_DN<1>")
	)
	(segment
		(start 304.65649 -401.143216)
		(end 304.875438 -401.143216)
		(width 0.1016)
		(layer "F.Cu")
		(net "P5E_CPU0_P0_RX_BUF_DN<1>")
	)
	(segment
		(start 305.016154 -401.0025)
		(end 305.016154 -400.811238)
		(width 0.1016)
		(layer "F.Cu")
		(net "P5E_CPU0_P0_RX_BUF_DN<1>")
	)
	(segment
		(start 304.618136 -399.143982)
		(end 304.618136 -399.960338)
		(width 0.1016)
		(layer "F.Cu")
		(net "P5E_CPU0_P0_RX_BUF_DN<1>")
	)
	(segment
		(start 306.600352 -414.238694)
		(end 306.170838 -414.238694)
		(width 0.14224)
		(layer "In15.Cu")
		(net "P5E_CPU0_P0_RX_BUF_DN<1>")
	)
	(segment
		(start 304.275236 -401.394168)
		(end 304.579782 -401.089622)
		(width 0.14224)
		(layer "In15.Cu")
		(net "P5E_CPU0_P0_RX_BUF_DN<1>")
	)
	(segment
		(start 307.33492 -419.12667)
		(end 307.147976 -418.676074)
		(width 0.14224)
		(layer "In15.Cu")
		(net "P5E_CPU0_P0_RX_BUF_DN<1>")
	)
	(segment
		(start 307.147976 -414.863026)
		(end 307.006498 -414.52165)
		(width 0.14224)
		(layer "In15.Cu")
		(net "P5E_CPU0_P0_RX_BUF_DN<1>")
	)
	(segment
		(start 309.353458 -422.241218)
		(end 308.907942 -421.866314)
		(width 0.14224)
		(layer "In15.Cu")
		(net "P5E_CPU0_P0_RX_BUF_DN<1>")
	)
	(segment
		(start 309.50535 -422.348152)
		(end 309.353458 -422.241218)
		(width 0.14224)
		(layer "In15.Cu")
		(net "P5E_CPU0_P0_RX_BUF_DN<1>")
	)
	(segment
		(start 307.147976 -418.676074)
		(end 307.147976 -414.863026)
		(width 0.14224)
		(layer "In15.Cu")
		(net "P5E_CPU0_P0_RX_BUF_DN<1>")
	)
	(segment
		(start 308.679596 -421.37584)
		(end 308.679596 -420.391336)
		(width 0.14224)
		(layer "In15.Cu")
		(net "P5E_CPU0_P0_RX_BUF_DN<1>")
	)
	(segment
		(start 306.170838 -414.238694)
		(end 305.995832 -414.16605)
		(width 0.14224)
		(layer "In15.Cu")
		(net "P5E_CPU0_P0_RX_BUF_DN<1>")
	)
	(segment
		(start 305.731926 -413.902144)
		(end 305.616356 -413.623252)
		(width 0.14224)
		(layer "In15.Cu")
		(net "P5E_CPU0_P0_RX_BUF_DN<1>")
	)
	(segment
		(start 304.275236 -408.694128)
		(end 304.275236 -401.394168)
		(width 0.14224)
		(layer "In15.Cu")
		(net "P5E_CPU0_P0_RX_BUF_DN<1>")
	)
	(segment
		(start 308.642258 -420.301166)
		(end 308.205886 -419.86581)
		(width 0.14224)
		(layer "In15.Cu")
		(net "P5E_CPU0_P0_RX_BUF_DN<1>")
	)
	(segment
		(start 316.498986 -438.619138)
		(end 315.98235 -438.619138)
		(width 0.14224)
		(layer "In15.Cu")
		(net "P5E_CPU0_P0_RX_BUF_DN<1>")
	)
	(segment
		(start 304.579782 -401.089622)
		(end 304.889154 -401.089622)
		(width 0.14224)
		(layer "In15.Cu")
		(net "P5E_CPU0_P0_RX_BUF_DN<1>")
	)
	(segment
		(start 305.606704 -411.99054)
		(end 304.459894 -409.221686)
		(width 0.14224)
		(layer "In15.Cu")
		(net "P5E_CPU0_P0_RX_BUF_DN<1>")
	)
	(segment
		(start 304.45964 -409.221686)
		(end 304.306224 -408.850846)
		(width 0.14224)
		(layer "In15.Cu")
		(net "P5E_CPU0_P0_RX_BUF_DN<1>")
	)
	(segment
		(start 306.810664 -414.325816)
		(end 306.600352 -414.238694)
		(width 0.14224)
		(layer "In15.Cu")
		(net "P5E_CPU0_P0_RX_BUF_DN<1>")
	)
	(segment
		(start 315.98235 -438.619138)
		(end 315.67628 -438.313068)
		(width 0.14224)
		(layer "In15.Cu")
		(net "P5E_CPU0_P0_RX_BUF_DN<1>")
	)
	(segment
		(start 305.995832 -414.16605)
		(end 305.731926 -413.902144)
		(width 0.14224)
		(layer "In15.Cu")
		(net "P5E_CPU0_P0_RX_BUF_DN<1>")
	)
	(segment
		(start 307.006498 -414.52165)
		(end 306.810664 -414.325816)
		(width 0.14224)
		(layer "In15.Cu")
		(net "P5E_CPU0_P0_RX_BUF_DN<1>")
	)
	(segment
		(start 308.205886 -419.86581)
		(end 307.981096 -419.772592)
		(width 0.14224)
		(layer "In15.Cu")
		(net "P5E_CPU0_P0_RX_BUF_DN<1>")
	)
	(segment
		(start 316.649608 -439.0898)
		(end 316.649608 -438.76976)
		(width 0.14224)
		(layer "In15.Cu")
		(net "P5E_CPU0_P0_RX_BUF_DN<1>")
	)
	(segment
		(start 316.649608 -438.76976)
		(end 316.498986 -438.619138)
		(width 0.14224)
		(layer "In15.Cu")
		(net "P5E_CPU0_P0_RX_BUF_DN<1>")
	)
	(segment
		(start 314.466478 -424.078146)
		(end 310.831484 -422.975278)
		(width 0.14224)
		(layer "In15.Cu")
		(net "P5E_CPU0_P0_RX_BUF_DN<1>")
	)
	(segment
		(start 305.616356 -413.623252)
		(end 305.616356 -412.039308)
		(width 0.14224)
		(layer "In15.Cu")
		(net "P5E_CPU0_P0_RX_BUF_DN<1>")
	)
	(segment
		(start 305.016154 -400.962622)
		(end 305.016154 -400.811238)
		(width 0.14224)
		(layer "In15.Cu")
		(net "P5E_CPU0_P0_RX_BUF_DN<1>")
	)
	(segment
		(start 304.889154 -401.089622)
		(end 305.016154 -400.962622)
		(width 0.14224)
		(layer "In15.Cu")
		(net "P5E_CPU0_P0_RX_BUF_DN<1>")
	)
	(segment
		(start 315.67628 -438.313068)
		(end 315.67628 -424.691302)
		(width 0.14224)
		(layer "In15.Cu")
		(net "P5E_CPU0_P0_RX_BUF_DN<1>")
	)
	(segment
		(start 315.571632 -424.534838)
		(end 314.466478 -424.078146)
		(width 0.14224)
		(layer "In15.Cu")
		(net "P5E_CPU0_P0_RX_BUF_DN<1>")
	)
	(segment
		(start 310.831484 -422.975278)
		(end 309.50535 -422.348152)
		(width 0.14224)
		(layer "In15.Cu")
		(net "P5E_CPU0_P0_RX_BUF_DN<1>")
	)
	(segment
		(start 304.459894 -409.221686)
		(end 304.45964 -409.221686)
		(width 0.14224)
		(layer "In15.Cu")
		(net "P5E_CPU0_P0_RX_BUF_DN<1>")
	)
	(arc
		(start 315.67628 -424.691302)
		(mid 315.647718 -424.597163)
		(end 315.571632 -424.534838)
		(width 0.14224)
		(layer "In15.Cu")
		(net "P5E_CPU0_P0_RX_BUF_DN<1>")
	)
	(arc
		(start 307.981096 -419.772592)
		(mid 307.593817 -419.513841)
		(end 307.33492 -419.12667)
		(width 0.14224)
		(layer "In15.Cu")
		(net "P5E_CPU0_P0_RX_BUF_DN<1>")
	)
	(arc
		(start 304.306224 -408.850846)
		(mid 304.283021 -408.774012)
		(end 304.275236 -408.694128)
		(width 0.14224)
		(layer "In15.Cu")
		(net "P5E_CPU0_P0_RX_BUF_DN<1>")
	)
	(arc
		(start 308.907942 -421.866314)
		(mid 308.739458 -421.646358)
		(end 308.679596 -421.37584)
		(width 0.14224)
		(layer "In15.Cu")
		(net "P5E_CPU0_P0_RX_BUF_DN<1>")
	)
	(arc
		(start 308.679596 -420.391336)
		(mid 308.66989 -420.342541)
		(end 308.642258 -420.301166)
		(width 0.14224)
		(layer "In15.Cu")
		(net "P5E_CPU0_P0_RX_BUF_DN<1>")
	)
	(arc
		(start 305.616356 -412.039308)
		(mid 305.61391 -412.014455)
		(end 305.606704 -411.99054)
		(width 0.14224)
		(layer "In15.Cu")
		(net "P5E_CPU0_P0_RX_BUF_DN<1>")
	)
	(segment
		(start 321.816222 -400.981926)
		(end 321.654932 -401.143216)
		(width 0.1016)
		(layer "F.Cu")
		(net "P5E_CPU0_P0_RX_BUF_DN<15>")
	)
	(segment
		(start 321.418204 -399.143982)
		(end 321.417696 -399.143474)
		(width 0.1016)
		(layer "F.Cu")
		(net "P5E_CPU0_P0_RX_BUF_DN<15>")
	)
	(segment
		(start 321.816222 -400.811238)
		(end 321.816222 -400.981926)
		(width 0.1016)
		(layer "F.Cu")
		(net "P5E_CPU0_P0_RX_BUF_DN<15>")
	)
	(segment
		(start 321.654932 -401.143216)
		(end 321.456558 -401.143216)
		(width 0.1016)
		(layer "F.Cu")
		(net "P5E_CPU0_P0_RX_BUF_DN<15>")
	)
	(segment
		(start 321.418204 -399.960338)
		(end 321.418204 -399.143982)
		(width 0.1016)
		(layer "F.Cu")
		(net "P5E_CPU0_P0_RX_BUF_DN<15>")
	)
	(segment
		(start 321.329558 -401.016216)
		(end 321.329558 -400.048984)
		(width 0.1016)
		(layer "F.Cu")
		(net "P5E_CPU0_P0_RX_BUF_DN<15>")
	)
	(segment
		(start 321.329558 -400.048984)
		(end 321.418204 -399.960338)
		(width 0.1016)
		(layer "F.Cu")
		(net "P5E_CPU0_P0_RX_BUF_DN<15>")
	)
	(segment
		(start 321.456558 -401.143216)
		(end 321.329558 -401.016216)
		(width 0.1016)
		(layer "F.Cu")
		(net "P5E_CPU0_P0_RX_BUF_DN<15>")
	)
	(segment
		(start 321.075304 -401.394168)
		(end 321.37985 -401.089622)
		(width 0.14224)
		(layer "In15.Cu")
		(net "P5E_CPU0_P0_RX_BUF_DN<15>")
	)
	(segment
		(start 349.63735 -414.267142)
		(end 349.56877 -414.238694)
		(width 0.14224)
		(layer "In15.Cu")
		(net "P5E_CPU0_P0_RX_BUF_DN<15>")
	)
	(segment
		(start 321.075304 -402.648166)
		(end 321.075304 -401.394168)
		(width 0.14224)
		(layer "In15.Cu")
		(net "P5E_CPU0_P0_RX_BUF_DN<15>")
	)
	(segment
		(start 349.056198 -414.238694)
		(end 348.881446 -414.166304)
		(width 0.14224)
		(layer "In15.Cu")
		(net "P5E_CPU0_P0_RX_BUF_DN<15>")
	)
	(segment
		(start 349.56877 -414.238694)
		(end 349.056198 -414.238694)
		(width 0.14224)
		(layer "In15.Cu")
		(net "P5E_CPU0_P0_RX_BUF_DN<15>")
	)
	(segment
		(start 344.688922 -438.136792)
		(end 344.688922 -424.612562)
		(width 0.14224)
		(layer "In15.Cu")
		(net "P5E_CPU0_P0_RX_BUF_DN<15>")
	)
	(segment
		(start 336.734658 -405.26081)
		(end 335.45399 -404.872444)
		(width 0.14224)
		(layer "In15.Cu")
		(net "P5E_CPU0_P0_RX_BUF_DN<15>")
	)
	(segment
		(start 344.991436 -438.623202)
		(end 344.818716 -438.450482)
		(width 0.14224)
		(layer "In15.Cu")
		(net "P5E_CPU0_P0_RX_BUF_DN<15>")
	)
	(segment
		(start 345.649804 -438.76976)
		(end 345.503246 -438.623202)
		(width 0.14224)
		(layer "In15.Cu")
		(net "P5E_CPU0_P0_RX_BUF_DN<15>")
	)
	(segment
		(start 349.891858 -414.52165)
		(end 349.63735 -414.267142)
		(width 0.14224)
		(layer "In15.Cu")
		(net "P5E_CPU0_P0_RX_BUF_DN<15>")
	)
	(segment
		(start 345.503246 -438.623202)
		(end 344.991436 -438.623202)
		(width 0.14224)
		(layer "In15.Cu")
		(net "P5E_CPU0_P0_RX_BUF_DN<15>")
	)
	(segment
		(start 334.272128 -404.63724)
		(end 323.231002 -403.549612)
		(width 0.14224)
		(layer "In15.Cu")
		(net "P5E_CPU0_P0_RX_BUF_DN<15>")
	)
	(segment
		(start 348.267782 -411.930088)
		(end 340.816184 -406.951434)
		(width 0.14224)
		(layer "In15.Cu")
		(net "P5E_CPU0_P0_RX_BUF_DN<15>")
	)
	(segment
		(start 335.45399 -404.872444)
		(end 334.272128 -404.63724)
		(width 0.14224)
		(layer "In15.Cu")
		(net "P5E_CPU0_P0_RX_BUF_DN<15>")
	)
	(segment
		(start 345.246198 -423.902886)
		(end 345.392756 -423.841672)
		(width 0.14224)
		(layer "In15.Cu")
		(net "P5E_CPU0_P0_RX_BUF_DN<15>")
	)
	(segment
		(start 323.231002 -403.549612)
		(end 322.361814 -403.376638)
		(width 0.14224)
		(layer "In15.Cu")
		(net "P5E_CPU0_P0_RX_BUF_DN<15>")
	)
	(segment
		(start 350.034606 -422.5036)
		(end 350.801686 -422.1861)
		(width 0.14224)
		(layer "In15.Cu")
		(net "P5E_CPU0_P0_RX_BUF_DN<15>")
	)
	(segment
		(start 344.823034 -424.276774)
		(end 345.048332 -424.039538)
		(width 0.14224)
		(layer "In15.Cu")
		(net "P5E_CPU0_P0_RX_BUF_DN<15>")
	)
	(segment
		(start 351.600008 -421.264842)
		(end 351.600008 -420.474394)
		(width 0.14224)
		(layer "In15.Cu")
		(net "P5E_CPU0_P0_RX_BUF_DN<15>")
	)
	(segment
		(start 321.816222 -400.962622)
		(end 321.816222 -400.811238)
		(width 0.14224)
		(layer "In15.Cu")
		(net "P5E_CPU0_P0_RX_BUF_DN<15>")
	)
	(segment
		(start 350.918272 -422.123616)
		(end 351.287842 -421.84955)
		(width 0.14224)
		(layer "In15.Cu")
		(net "P5E_CPU0_P0_RX_BUF_DN<15>")
	)
	(segment
		(start 321.37985 -401.089622)
		(end 321.689222 -401.089622)
		(width 0.14224)
		(layer "In15.Cu")
		(net "P5E_CPU0_P0_RX_BUF_DN<15>")
	)
	(segment
		(start 345.649804 -439.0898)
		(end 345.649804 -438.76976)
		(width 0.14224)
		(layer "In15.Cu")
		(net "P5E_CPU0_P0_RX_BUF_DN<15>")
	)
	(segment
		(start 350.033336 -414.863026)
		(end 349.891858 -414.52165)
		(width 0.14224)
		(layer "In15.Cu")
		(net "P5E_CPU0_P0_RX_BUF_DN<15>")
	)
	(segment
		(start 350.033336 -418.718492)
		(end 350.033336 -414.863026)
		(width 0.14224)
		(layer "In15.Cu")
		(net "P5E_CPU0_P0_RX_BUF_DN<15>")
	)
	(segment
		(start 351.570036 -421.41521)
		(end 351.600008 -421.264842)
		(width 0.14224)
		(layer "In15.Cu")
		(net "P5E_CPU0_P0_RX_BUF_DN<15>")
	)
	(segment
		(start 351.010474 -419.832282)
		(end 350.6216 -419.671246)
		(width 0.14224)
		(layer "In15.Cu")
		(net "P5E_CPU0_P0_RX_BUF_DN<15>")
	)
	(segment
		(start 340.816184 -406.951434)
		(end 336.734658 -405.26081)
		(width 0.14224)
		(layer "In15.Cu")
		(net "P5E_CPU0_P0_RX_BUF_DN<15>")
	)
	(segment
		(start 351.506028 -421.57015)
		(end 351.570036 -421.41521)
		(width 0.14224)
		(layer "In15.Cu")
		(net "P5E_CPU0_P0_RX_BUF_DN<15>")
	)
	(segment
		(start 345.596718 -423.779188)
		(end 346.273628 -423.644314)
		(width 0.14224)
		(layer "In15.Cu")
		(net "P5E_CPU0_P0_RX_BUF_DN<15>")
	)
	(segment
		(start 348.881446 -414.166304)
		(end 348.702122 -413.98698)
		(width 0.14224)
		(layer "In15.Cu")
		(net "P5E_CPU0_P0_RX_BUF_DN<15>")
	)
	(segment
		(start 351.287842 -421.84955)
		(end 351.506028 -421.57015)
		(width 0.14224)
		(layer "In15.Cu")
		(net "P5E_CPU0_P0_RX_BUF_DN<15>")
	)
	(segment
		(start 350.801686 -422.1861)
		(end 350.918272 -422.123616)
		(width 0.14224)
		(layer "In15.Cu")
		(net "P5E_CPU0_P0_RX_BUF_DN<15>")
	)
	(segment
		(start 346.273628 -423.644314)
		(end 350.034606 -422.5036)
		(width 0.14224)
		(layer "In15.Cu")
		(net "P5E_CPU0_P0_RX_BUF_DN<15>")
	)
	(segment
		(start 321.223386 -402.847302)
		(end 321.075304 -402.648166)
		(width 0.14224)
		(layer "In15.Cu")
		(net "P5E_CPU0_P0_RX_BUF_DN<15>")
	)
	(segment
		(start 321.689222 -401.089622)
		(end 321.816222 -400.962622)
		(width 0.14224)
		(layer "In15.Cu")
		(net "P5E_CPU0_P0_RX_BUF_DN<15>")
	)
	(segment
		(start 350.291654 -419.341046)
		(end 350.033336 -418.718492)
		(width 0.14224)
		(layer "In15.Cu")
		(net "P5E_CPU0_P0_RX_BUF_DN<15>")
	)
	(segment
		(start 348.502732 -413.506412)
		(end 348.501208 -412.356808)
		(width 0.14224)
		(layer "In15.Cu")
		(net "P5E_CPU0_P0_RX_BUF_DN<15>")
	)
	(segment
		(start 322.361814 -403.376638)
		(end 321.68211 -403.170644)
		(width 0.14224)
		(layer "In15.Cu")
		(net "P5E_CPU0_P0_RX_BUF_DN<15>")
	)
	(segment
		(start 351.56267 -420.384478)
		(end 351.010474 -419.832282)
		(width 0.14224)
		(layer "In15.Cu")
		(net "P5E_CPU0_P0_RX_BUF_DN<15>")
	)
	(arc
		(start 348.702122 -413.98698)
		(mid 348.55471 -413.766496)
		(end 348.502732 -413.506412)
		(width 0.14224)
		(layer "In15.Cu")
		(net "P5E_CPU0_P0_RX_BUF_DN<15>")
	)
	(arc
		(start 350.6216 -419.671246)
		(mid 350.423825 -419.538928)
		(end 350.291654 -419.341046)
		(width 0.14224)
		(layer "In15.Cu")
		(net "P5E_CPU0_P0_RX_BUF_DN<15>")
	)
	(arc
		(start 321.68211 -403.170644)
		(mid 321.426769 -403.045832)
		(end 321.223386 -402.847302)
		(width 0.14224)
		(layer "In15.Cu")
		(net "P5E_CPU0_P0_RX_BUF_DN<15>")
	)
	(arc
		(start 351.600008 -420.474394)
		(mid 351.590306 -420.42571)
		(end 351.56267 -420.384478)
		(width 0.14224)
		(layer "In15.Cu")
		(net "P5E_CPU0_P0_RX_BUF_DN<15>")
	)
	(arc
		(start 348.478348 -412.225998)
		(mid 348.450962 -412.158472)
		(end 348.41815 -412.09341)
		(width 0.14224)
		(layer "In15.Cu")
		(net "P5E_CPU0_P0_RX_BUF_DN<15>")
	)
	(arc
		(start 345.392756 -423.841672)
		(mid 345.493167 -423.805306)
		(end 345.596718 -423.779188)
		(width 0.14224)
		(layer "In15.Cu")
		(net "P5E_CPU0_P0_RX_BUF_DN<15>")
	)
	(arc
		(start 344.818716 -438.450482)
		(mid 344.72258 -438.306559)
		(end 344.688922 -438.136792)
		(width 0.14224)
		(layer "In15.Cu")
		(net "P5E_CPU0_P0_RX_BUF_DN<15>")
	)
	(arc
		(start 345.048332 -424.039538)
		(mid 345.140212 -423.960999)
		(end 345.246198 -423.902886)
		(width 0.14224)
		(layer "In15.Cu")
		(net "P5E_CPU0_P0_RX_BUF_DN<15>")
	)
	(arc
		(start 348.501208 -412.356808)
		(mid 348.495404 -412.29042)
		(end 348.478348 -412.225998)
		(width 0.14224)
		(layer "In15.Cu")
		(net "P5E_CPU0_P0_RX_BUF_DN<15>")
	)
	(arc
		(start 344.688922 -424.612562)
		(mid 344.723757 -424.43181)
		(end 344.823034 -424.276774)
		(width 0.14224)
		(layer "In15.Cu")
		(net "P5E_CPU0_P0_RX_BUF_DN<15>")
	)
	(arc
		(start 348.41815 -412.09341)
		(mid 348.352696 -412.002791)
		(end 348.267782 -411.930088)
		(width 0.14224)
		(layer "In15.Cu")
		(net "P5E_CPU0_P0_RX_BUF_DN<15>")
	)
	(segment
		(start 320.256662 -401.143216)
		(end 320.129662 -401.016216)
		(width 0.1016)
		(layer "F.Cu")
		(net "P5E_CPU0_P0_RX_BUF_DN<14>")
	)
	(segment
		(start 320.129662 -400.048984)
		(end 320.218308 -399.960338)
		(width 0.1016)
		(layer "F.Cu")
		(net "P5E_CPU0_P0_RX_BUF_DN<14>")
	)
	(segment
		(start 320.129662 -401.016216)
		(end 320.129662 -400.048984)
		(width 0.1016)
		(layer "F.Cu")
		(net "P5E_CPU0_P0_RX_BUF_DN<14>")
	)
	(segment
		(start 320.218308 -399.143982)
		(end 320.2178 -399.143474)
		(width 0.1016)
		(layer "F.Cu")
		(net "P5E_CPU0_P0_RX_BUF_DN<14>")
	)
	(segment
		(start 320.616326 -400.811238)
		(end 320.616326 -400.97583)
		(width 0.1016)
		(layer "F.Cu")
		(net "P5E_CPU0_P0_RX_BUF_DN<14>")
	)
	(segment
		(start 320.44894 -401.143216)
		(end 320.256662 -401.143216)
		(width 0.1016)
		(layer "F.Cu")
		(net "P5E_CPU0_P0_RX_BUF_DN<14>")
	)
	(segment
		(start 320.616326 -400.97583)
		(end 320.44894 -401.143216)
		(width 0.1016)
		(layer "F.Cu")
		(net "P5E_CPU0_P0_RX_BUF_DN<14>")
	)
	(segment
		(start 320.218308 -399.960338)
		(end 320.218308 -399.143982)
		(width 0.1016)
		(layer "F.Cu")
		(net "P5E_CPU0_P0_RX_BUF_DN<14>")
	)
	(segment
		(start 347.9419 -419.829996)
		(end 348.464378 -420.352474)
		(width 0.14224)
		(layer "In15.Cu")
		(net "P5E_CPU0_P0_RX_BUF_DN<14>")
	)
	(segment
		(start 343.50325 -437.623204)
		(end 343.649808 -437.769762)
		(width 0.14224)
		(layer "In15.Cu")
		(net "P5E_CPU0_P0_RX_BUF_DN<14>")
	)
	(segment
		(start 320.616326 -400.811238)
		(end 320.616326 -400.962622)
		(width 0.14224)
		(layer "In15.Cu")
		(net "P5E_CPU0_P0_RX_BUF_DN<14>")
	)
	(segment
		(start 346.828618 -414.52165)
		(end 346.970096 -414.863026)
		(width 0.14224)
		(layer "In15.Cu")
		(net "P5E_CPU0_P0_RX_BUF_DN<14>")
	)
	(segment
		(start 329.005438 -405.430736)
		(end 329.005438 -405.43099)
		(width 0.14224)
		(layer "In15.Cu")
		(net "P5E_CPU0_P0_RX_BUF_DN<14>")
	)
	(segment
		(start 322.31203 -404.369524)
		(end 323.659754 -404.637494)
		(width 0.14224)
		(layer "In15.Cu")
		(net "P5E_CPU0_P0_RX_BUF_DN<14>")
	)
	(segment
		(start 345.554046 -413.902144)
		(end 345.817952 -414.16605)
		(width 0.14224)
		(layer "In15.Cu")
		(net "P5E_CPU0_P0_RX_BUF_DN<14>")
	)
	(segment
		(start 348.061026 -421.961056)
		(end 345.170252 -422.924732)
		(width 0.14224)
		(layer "In15.Cu")
		(net "P5E_CPU0_P0_RX_BUF_DN<14>")
	)
	(segment
		(start 339.045804 -407.557732)
		(end 341.018368 -408.707336)
		(width 0.14224)
		(layer "In15.Cu")
		(net "P5E_CPU0_P0_RX_BUF_DN<14>")
	)
	(segment
		(start 345.011248 -411.592776)
		(end 345.360244 -412.115)
		(width 0.14224)
		(layer "In15.Cu")
		(net "P5E_CPU0_P0_RX_BUF_DN<14>")
	)
	(segment
		(start 345.438476 -412.303722)
		(end 345.438476 -413.623252)
		(width 0.14224)
		(layer "In15.Cu")
		(net "P5E_CPU0_P0_RX_BUF_DN<14>")
	)
	(segment
		(start 342.99144 -437.623204)
		(end 343.50325 -437.623204)
		(width 0.14224)
		(layer "In15.Cu")
		(net "P5E_CPU0_P0_RX_BUF_DN<14>")
	)
	(segment
		(start 342.688926 -424.584114)
		(end 342.688926 -437.136794)
		(width 0.14224)
		(layer "In15.Cu")
		(net "P5E_CPU0_P0_RX_BUF_DN<14>")
	)
	(segment
		(start 329.005438 -405.43099)
		(end 336.71383 -406.575514)
		(width 0.14224)
		(layer "In15.Cu")
		(net "P5E_CPU0_P0_RX_BUF_DN<14>")
	)
	(segment
		(start 344.70975 -423.10558)
		(end 343.981532 -423.44467)
		(width 0.14224)
		(layer "In15.Cu")
		(net "P5E_CPU0_P0_RX_BUF_DN<14>")
	)
	(segment
		(start 342.951308 -409.834334)
		(end 344.439494 -410.981652)
		(width 0.14224)
		(layer "In15.Cu")
		(net "P5E_CPU0_P0_RX_BUF_DN<14>")
	)
	(segment
		(start 320.6496 -403.86508)
		(end 322.31203 -404.369524)
		(width 0.14224)
		(layer "In15.Cu")
		(net "P5E_CPU0_P0_RX_BUF_DN<14>")
	)
	(segment
		(start 341.018368 -408.707336)
		(end 341.018368 -408.70759)
		(width 0.14224)
		(layer "In15.Cu")
		(net "P5E_CPU0_P0_RX_BUF_DN<14>")
	)
	(segment
		(start 320.179954 -401.089622)
		(end 319.875408 -401.394168)
		(width 0.14224)
		(layer "In15.Cu")
		(net "P5E_CPU0_P0_RX_BUF_DN<14>")
	)
	(segment
		(start 323.659754 -404.637494)
		(end 329.005438 -405.430736)
		(width 0.14224)
		(layer "In15.Cu")
		(net "P5E_CPU0_P0_RX_BUF_DN<14>")
	)
	(segment
		(start 341.018368 -408.70759)
		(end 342.951308 -409.834334)
		(width 0.14224)
		(layer "In15.Cu")
		(net "P5E_CPU0_P0_RX_BUF_DN<14>")
	)
	(segment
		(start 345.438476 -413.623252)
		(end 345.554046 -413.902144)
		(width 0.14224)
		(layer "In15.Cu")
		(net "P5E_CPU0_P0_RX_BUF_DN<14>")
	)
	(segment
		(start 343.649808 -437.769762)
		(end 343.649808 -438.089802)
		(width 0.14224)
		(layer "In15.Cu")
		(net "P5E_CPU0_P0_RX_BUF_DN<14>")
	)
	(segment
		(start 347.644974 -419.70706)
		(end 347.9419 -419.829996)
		(width 0.14224)
		(layer "In15.Cu")
		(net "P5E_CPU0_P0_RX_BUF_DN<14>")
	)
	(segment
		(start 345.992958 -414.238694)
		(end 346.50553 -414.238694)
		(width 0.14224)
		(layer "In15.Cu")
		(net "P5E_CPU0_P0_RX_BUF_DN<14>")
	)
	(segment
		(start 346.970096 -418.683694)
		(end 347.217238 -419.279324)
		(width 0.14224)
		(layer "In15.Cu")
		(net "P5E_CPU0_P0_RX_BUF_DN<14>")
	)
	(segment
		(start 348.501716 -420.44239)
		(end 348.501716 -421.350186)
		(width 0.14224)
		(layer "In15.Cu")
		(net "P5E_CPU0_P0_RX_BUF_DN<14>")
	)
	(segment
		(start 344.439494 -410.981652)
		(end 345.011248 -411.592776)
		(width 0.14224)
		(layer "In15.Cu")
		(net "P5E_CPU0_P0_RX_BUF_DN<14>")
	)
	(segment
		(start 320.489326 -401.089622)
		(end 320.179954 -401.089622)
		(width 0.14224)
		(layer "In15.Cu")
		(net "P5E_CPU0_P0_RX_BUF_DN<14>")
	)
	(segment
		(start 336.71383 -406.575514)
		(end 339.045804 -407.557732)
		(width 0.14224)
		(layer "In15.Cu")
		(net "P5E_CPU0_P0_RX_BUF_DN<14>")
	)
	(segment
		(start 346.57411 -414.267142)
		(end 346.828618 -414.52165)
		(width 0.14224)
		(layer "In15.Cu")
		(net "P5E_CPU0_P0_RX_BUF_DN<14>")
	)
	(segment
		(start 320.1924 -403.53361)
		(end 320.334894 -403.676104)
		(width 0.14224)
		(layer "In15.Cu")
		(net "P5E_CPU0_P0_RX_BUF_DN<14>")
	)
	(segment
		(start 345.817952 -414.16605)
		(end 345.992958 -414.238694)
		(width 0.14224)
		(layer "In15.Cu")
		(net "P5E_CPU0_P0_RX_BUF_DN<14>")
	)
	(segment
		(start 320.616326 -400.962622)
		(end 320.489326 -401.089622)
		(width 0.14224)
		(layer "In15.Cu")
		(net "P5E_CPU0_P0_RX_BUF_DN<14>")
	)
	(segment
		(start 346.970096 -414.863026)
		(end 346.970096 -418.683694)
		(width 0.14224)
		(layer "In15.Cu")
		(net "P5E_CPU0_P0_RX_BUF_DN<14>")
	)
	(segment
		(start 342.81872 -437.450484)
		(end 342.99144 -437.623204)
		(width 0.14224)
		(layer "In15.Cu")
		(net "P5E_CPU0_P0_RX_BUF_DN<14>")
	)
	(segment
		(start 346.50553 -414.238694)
		(end 346.57411 -414.267142)
		(width 0.14224)
		(layer "In15.Cu")
		(net "P5E_CPU0_P0_RX_BUF_DN<14>")
	)
	(segment
		(start 319.875408 -401.394168)
		(end 319.875408 -402.768308)
		(width 0.14224)
		(layer "In15.Cu")
		(net "P5E_CPU0_P0_RX_BUF_DN<14>")
	)
	(segment
		(start 343.67343 -423.611802)
		(end 342.99144 -424.03776)
		(width 0.14224)
		(layer "In15.Cu")
		(net "P5E_CPU0_P0_RX_BUF_DN<14>")
	)
	(segment
		(start 345.360244 -412.115)
		(end 345.438476 -412.303722)
		(width 0.14224)
		(layer "In15.Cu")
		(net "P5E_CPU0_P0_RX_BUF_DN<14>")
	)
	(arc
		(start 345.170252 -422.924732)
		(mid 344.937606 -423.009057)
		(end 344.70975 -423.10558)
		(width 0.14224)
		(layer "In15.Cu")
		(net "P5E_CPU0_P0_RX_BUF_DN<14>")
	)
	(arc
		(start 319.875408 -402.768308)
		(mid 319.957793 -403.182484)
		(end 320.1924 -403.53361)
		(width 0.14224)
		(layer "In15.Cu")
		(net "P5E_CPU0_P0_RX_BUF_DN<14>")
	)
	(arc
		(start 348.501716 -421.350186)
		(mid 348.379984 -421.72677)
		(end 348.061026 -421.961056)
		(width 0.14224)
		(layer "In15.Cu")
		(net "P5E_CPU0_P0_RX_BUF_DN<14>")
	)
	(arc
		(start 342.99144 -424.03776)
		(mid 342.76939 -424.271748)
		(end 342.688926 -424.584114)
		(width 0.14224)
		(layer "In15.Cu")
		(net "P5E_CPU0_P0_RX_BUF_DN<14>")
	)
	(arc
		(start 347.217238 -419.279324)
		(mid 347.388589 -419.535709)
		(end 347.644974 -419.70706)
		(width 0.14224)
		(layer "In15.Cu")
		(net "P5E_CPU0_P0_RX_BUF_DN<14>")
	)
	(arc
		(start 348.464378 -420.352474)
		(mid 348.491997 -420.393714)
		(end 348.501716 -420.44239)
		(width 0.14224)
		(layer "In15.Cu")
		(net "P5E_CPU0_P0_RX_BUF_DN<14>")
	)
	(arc
		(start 343.981532 -423.44467)
		(mid 343.824919 -423.523513)
		(end 343.67343 -423.611802)
		(width 0.14224)
		(layer "In15.Cu")
		(net "P5E_CPU0_P0_RX_BUF_DN<14>")
	)
	(arc
		(start 320.334894 -403.676104)
		(mid 320.480599 -403.789989)
		(end 320.6496 -403.86508)
		(width 0.14224)
		(layer "In15.Cu")
		(net "P5E_CPU0_P0_RX_BUF_DN<14>")
	)
	(arc
		(start 342.688926 -437.136794)
		(mid 342.722616 -437.306547)
		(end 342.81872 -437.450484)
		(width 0.14224)
		(layer "In15.Cu")
		(net "P5E_CPU0_P0_RX_BUF_DN<14>")
	)
	(segment
		(start 319.27546 -401.143216)
		(end 319.416176 -401.0025)
		(width 0.1016)
		(layer "F.Cu")
		(net "P5E_CPU0_P0_RX_BUF_DN<13>")
	)
	(segment
		(start 319.065148 -401.143216)
		(end 319.27546 -401.143216)
		(width 0.1016)
		(layer "F.Cu")
		(net "P5E_CPU0_P0_RX_BUF_DN<13>")
	)
	(segment
		(start 319.018158 -399.143982)
		(end 319.018158 -399.960338)
		(width 0.1016)
		(layer "F.Cu")
		(net "P5E_CPU0_P0_RX_BUF_DN<13>")
	)
	(segment
		(start 318.938148 -400.040348)
		(end 318.938148 -401.016216)
		(width 0.1016)
		(layer "F.Cu")
		(net "P5E_CPU0_P0_RX_BUF_DN<13>")
	)
	(segment
		(start 319.01765 -399.143474)
		(end 319.018158 -399.143982)
		(width 0.1016)
		(layer "F.Cu")
		(net "P5E_CPU0_P0_RX_BUF_DN<13>")
	)
	(segment
		(start 318.938148 -401.016216)
		(end 319.065148 -401.143216)
		(width 0.1016)
		(layer "F.Cu")
		(net "P5E_CPU0_P0_RX_BUF_DN<13>")
	)
	(segment
		(start 319.018158 -399.960338)
		(end 318.938148 -400.040348)
		(width 0.1016)
		(layer "F.Cu")
		(net "P5E_CPU0_P0_RX_BUF_DN<13>")
	)
	(segment
		(start 319.416176 -401.0025)
		(end 319.416176 -400.811238)
		(width 0.1016)
		(layer "F.Cu")
		(net "P5E_CPU0_P0_RX_BUF_DN<13>")
	)
	(segment
		(start 343.94013 -418.733224)
		(end 343.940384 -418.733478)
		(width 0.14224)
		(layer "In15.Cu")
		(net "P5E_CPU0_P0_RX_BUF_DN<13>")
	)
	(segment
		(start 344.785696 -422.055036)
		(end 341.967566 -423.22242)
		(width 0.14224)
		(layer "In15.Cu")
		(net "P5E_CPU0_P0_RX_BUF_DN<13>")
	)
	(segment
		(start 344.906346 -419.897306)
		(end 345.391232 -420.381938)
		(width 0.14224)
		(layer "In15.Cu")
		(net "P5E_CPU0_P0_RX_BUF_DN<13>")
	)
	(segment
		(start 341.503254 -438.623202)
		(end 341.649812 -438.76976)
		(width 0.14224)
		(layer "In15.Cu")
		(net "P5E_CPU0_P0_RX_BUF_DN<13>")
	)
	(segment
		(start 341.848694 -423.286428)
		(end 341.225886 -423.702226)
		(width 0.14224)
		(layer "In15.Cu")
		(net "P5E_CPU0_P0_RX_BUF_DN<13>")
	)
	(segment
		(start 343.906856 -414.921192)
		(end 343.906856 -418.563552)
		(width 0.14224)
		(layer "In15.Cu")
		(net "P5E_CPU0_P0_RX_BUF_DN<13>")
	)
	(segment
		(start 344.92819 -421.983408)
		(end 344.785696 -422.055036)
		(width 0.14224)
		(layer "In15.Cu")
		(net "P5E_CPU0_P0_RX_BUF_DN<13>")
	)
	(segment
		(start 336.06232 -408.266138)
		(end 336.06232 -408.266392)
		(width 0.14224)
		(layer "In15.Cu")
		(net "P5E_CPU0_P0_RX_BUF_DN<13>")
	)
	(segment
		(start 319.289176 -401.089622)
		(end 318.979804 -401.089622)
		(width 0.14224)
		(layer "In15.Cu")
		(net "P5E_CPU0_P0_RX_BUF_DN<13>")
	)
	(segment
		(start 338.302346 -409.292298)
		(end 342.161368 -411.871668)
		(width 0.14224)
		(layer "In15.Cu")
		(net "P5E_CPU0_P0_RX_BUF_DN<13>")
	)
	(segment
		(start 342.161368 -411.871668)
		(end 342.246966 -411.957266)
		(width 0.14224)
		(layer "In15.Cu")
		(net "P5E_CPU0_P0_RX_BUF_DN<13>")
	)
	(segment
		(start 342.375236 -413.622998)
		(end 342.490806 -413.902144)
		(width 0.14224)
		(layer "In15.Cu")
		(net "P5E_CPU0_P0_RX_BUF_DN<13>")
	)
	(segment
		(start 318.979804 -401.089622)
		(end 318.675258 -401.394168)
		(width 0.14224)
		(layer "In15.Cu")
		(net "P5E_CPU0_P0_RX_BUF_DN<13>")
	)
	(segment
		(start 340.99627 -438.623202)
		(end 341.503254 -438.623202)
		(width 0.14224)
		(layer "In15.Cu")
		(net "P5E_CPU0_P0_RX_BUF_DN<13>")
	)
	(segment
		(start 341.649812 -438.76976)
		(end 341.649812 -439.0898)
		(width 0.14224)
		(layer "In15.Cu")
		(net "P5E_CPU0_P0_RX_BUF_DN<13>")
	)
	(segment
		(start 326.075548 -406.49398)
		(end 335.124044 -407.83637)
		(width 0.14224)
		(layer "In15.Cu")
		(net "P5E_CPU0_P0_RX_BUF_DN<13>")
	)
	(segment
		(start 340.68893 -424.626532)
		(end 340.68893 -438.131966)
		(width 0.14224)
		(layer "In15.Cu")
		(net "P5E_CPU0_P0_RX_BUF_DN<13>")
	)
	(segment
		(start 342.490806 -413.902144)
		(end 342.754712 -414.16605)
		(width 0.14224)
		(layer "In15.Cu")
		(net "P5E_CPU0_P0_RX_BUF_DN<13>")
	)
	(segment
		(start 318.943482 -403.687788)
		(end 319.599818 -404.344124)
		(width 0.14224)
		(layer "In15.Cu")
		(net "P5E_CPU0_P0_RX_BUF_DN<13>")
	)
	(segment
		(start 319.416176 -400.811238)
		(end 319.416176 -400.962622)
		(width 0.14224)
		(layer "In15.Cu")
		(net "P5E_CPU0_P0_RX_BUF_DN<13>")
	)
	(segment
		(start 342.375236 -412.266892)
		(end 342.375236 -413.622998)
		(width 0.14224)
		(layer "In15.Cu")
		(net "P5E_CPU0_P0_RX_BUF_DN<13>")
	)
	(segment
		(start 343.940384 -418.733478)
		(end 344.117422 -419.160452)
		(width 0.14224)
		(layer "In15.Cu")
		(net "P5E_CPU0_P0_RX_BUF_DN<13>")
	)
	(segment
		(start 340.818724 -438.445656)
		(end 340.99627 -438.623202)
		(width 0.14224)
		(layer "In15.Cu")
		(net "P5E_CPU0_P0_RX_BUF_DN<13>")
	)
	(segment
		(start 343.940384 -418.733224)
		(end 343.94013 -418.733224)
		(width 0.14224)
		(layer "In15.Cu")
		(net "P5E_CPU0_P0_RX_BUF_DN<13>")
	)
	(segment
		(start 319.416176 -400.962622)
		(end 319.289176 -401.089622)
		(width 0.14224)
		(layer "In15.Cu")
		(net "P5E_CPU0_P0_RX_BUF_DN<13>")
	)
	(segment
		(start 341.967566 -423.22242)
		(end 341.848694 -423.286428)
		(width 0.14224)
		(layer "In15.Cu")
		(net "P5E_CPU0_P0_RX_BUF_DN<13>")
	)
	(segment
		(start 335.124044 -407.83637)
		(end 336.06232 -408.266138)
		(width 0.14224)
		(layer "In15.Cu")
		(net "P5E_CPU0_P0_RX_BUF_DN<13>")
	)
	(segment
		(start 344.599768 -419.708838)
		(end 344.744548 -419.780974)
		(width 0.14224)
		(layer "In15.Cu")
		(net "P5E_CPU0_P0_RX_BUF_DN<13>")
	)
	(segment
		(start 336.06232 -408.266392)
		(end 338.302346 -409.292298)
		(width 0.14224)
		(layer "In15.Cu")
		(net "P5E_CPU0_P0_RX_BUF_DN<13>")
	)
	(segment
		(start 342.929464 -414.238694)
		(end 343.375234 -414.238694)
		(width 0.14224)
		(layer "In15.Cu")
		(net "P5E_CPU0_P0_RX_BUF_DN<13>")
	)
	(segment
		(start 320.22669 -404.720044)
		(end 326.075548 -406.49398)
		(width 0.14224)
		(layer "In15.Cu")
		(net "P5E_CPU0_P0_RX_BUF_DN<13>")
	)
	(segment
		(start 343.786968 -414.573466)
		(end 343.884504 -414.808924)
		(width 0.14224)
		(layer "In15.Cu")
		(net "P5E_CPU0_P0_RX_BUF_DN<13>")
	)
	(segment
		(start 342.246966 -411.957266)
		(end 342.375236 -412.266892)
		(width 0.14224)
		(layer "In15.Cu")
		(net "P5E_CPU0_P0_RX_BUF_DN<13>")
	)
	(segment
		(start 342.754712 -414.16605)
		(end 342.929464 -414.238694)
		(width 0.14224)
		(layer "In15.Cu")
		(net "P5E_CPU0_P0_RX_BUF_DN<13>")
	)
	(segment
		(start 318.675258 -401.394168)
		(end 318.675258 -403.040342)
		(width 0.14224)
		(layer "In15.Cu")
		(net "P5E_CPU0_P0_RX_BUF_DN<13>")
	)
	(segment
		(start 345.438476 -420.495984)
		(end 345.438476 -421.154352)
		(width 0.14224)
		(layer "In15.Cu")
		(net "P5E_CPU0_P0_RX_BUF_DN<13>")
	)
	(segment
		(start 343.506806 -414.293304)
		(end 343.786968 -414.573466)
		(width 0.14224)
		(layer "In15.Cu")
		(net "P5E_CPU0_P0_RX_BUF_DN<13>")
	)
	(arc
		(start 343.375234 -414.238694)
		(mid 343.446469 -414.252881)
		(end 343.506806 -414.293304)
		(width 0.14224)
		(layer "In15.Cu")
		(net "P5E_CPU0_P0_RX_BUF_DN<13>")
	)
	(arc
		(start 318.675258 -403.040342)
		(mid 318.744974 -403.390739)
		(end 318.943482 -403.687788)
		(width 0.14224)
		(layer "In15.Cu")
		(net "P5E_CPU0_P0_RX_BUF_DN<13>")
	)
	(arc
		(start 345.438476 -421.154352)
		(mid 345.300703 -421.641145)
		(end 344.92819 -421.983408)
		(width 0.14224)
		(layer "In15.Cu")
		(net "P5E_CPU0_P0_RX_BUF_DN<13>")
	)
	(arc
		(start 343.906856 -418.563552)
		(mid 343.915274 -418.650036)
		(end 343.940384 -418.733224)
		(width 0.14224)
		(layer "In15.Cu")
		(net "P5E_CPU0_P0_RX_BUF_DN<13>")
	)
	(arc
		(start 344.117422 -419.160452)
		(mid 344.25085 -419.399113)
		(end 344.435938 -419.60038)
		(width 0.14224)
		(layer "In15.Cu")
		(net "P5E_CPU0_P0_RX_BUF_DN<13>")
	)
	(arc
		(start 340.68893 -438.131966)
		(mid 340.72262 -438.301719)
		(end 340.818724 -438.445656)
		(width 0.14224)
		(layer "In15.Cu")
		(net "P5E_CPU0_P0_RX_BUF_DN<13>")
	)
	(arc
		(start 345.391232 -420.381938)
		(mid 345.426248 -420.434248)
		(end 345.438476 -420.495984)
		(width 0.14224)
		(layer "In15.Cu")
		(net "P5E_CPU0_P0_RX_BUF_DN<13>")
	)
	(arc
		(start 344.744548 -419.780974)
		(mid 344.830169 -419.832573)
		(end 344.906346 -419.897306)
		(width 0.14224)
		(layer "In15.Cu")
		(net "P5E_CPU0_P0_RX_BUF_DN<13>")
	)
	(arc
		(start 341.225886 -423.702226)
		(mid 340.900988 -424.019671)
		(end 340.712552 -424.432984)
		(width 0.14224)
		(layer "In15.Cu")
		(net "P5E_CPU0_P0_RX_BUF_DN<13>")
	)
	(arc
		(start 319.599818 -404.344124)
		(mid 319.890066 -404.570756)
		(end 320.22669 -404.720044)
		(width 0.14224)
		(layer "In15.Cu")
		(net "P5E_CPU0_P0_RX_BUF_DN<13>")
	)
	(arc
		(start 344.435938 -419.60038)
		(mid 344.514494 -419.659684)
		(end 344.599768 -419.708838)
		(width 0.14224)
		(layer "In15.Cu")
		(net "P5E_CPU0_P0_RX_BUF_DN<13>")
	)
	(arc
		(start 343.884504 -414.808924)
		(mid 343.901214 -414.863956)
		(end 343.906856 -414.921192)
		(width 0.14224)
		(layer "In15.Cu")
		(net "P5E_CPU0_P0_RX_BUF_DN<13>")
	)
	(arc
		(start 340.712552 -424.432984)
		(mid 340.694845 -424.529039)
		(end 340.68893 -424.626532)
		(width 0.14224)
		(layer "In15.Cu")
		(net "P5E_CPU0_P0_RX_BUF_DN<13>")
	)
	(segment
		(start 317.818262 -399.960338)
		(end 317.818262 -399.143982)
		(width 0.1016)
		(layer "F.Cu")
		(net "P5E_CPU0_P0_RX_BUF_DN<12>")
	)
	(segment
		(start 317.818262 -399.143982)
		(end 317.817754 -399.143474)
		(width 0.1016)
		(layer "F.Cu")
		(net "P5E_CPU0_P0_RX_BUF_DN<12>")
	)
	(segment
		(start 318.21628 -400.977862)
		(end 318.050926 -401.143216)
		(width 0.1016)
		(layer "F.Cu")
		(net "P5E_CPU0_P0_RX_BUF_DN<12>")
	)
	(segment
		(start 317.729616 -401.016216)
		(end 317.729616 -400.048984)
		(width 0.1016)
		(layer "F.Cu")
		(net "P5E_CPU0_P0_RX_BUF_DN<12>")
	)
	(segment
		(start 317.729616 -400.048984)
		(end 317.818262 -399.960338)
		(width 0.1016)
		(layer "F.Cu")
		(net "P5E_CPU0_P0_RX_BUF_DN<12>")
	)
	(segment
		(start 318.21628 -400.811238)
		(end 318.21628 -400.977862)
		(width 0.1016)
		(layer "F.Cu")
		(net "P5E_CPU0_P0_RX_BUF_DN<12>")
	)
	(segment
		(start 318.050926 -401.143216)
		(end 317.856616 -401.143216)
		(width 0.1016)
		(layer "F.Cu")
		(net "P5E_CPU0_P0_RX_BUF_DN<12>")
	)
	(segment
		(start 317.856616 -401.143216)
		(end 317.729616 -401.016216)
		(width 0.1016)
		(layer "F.Cu")
		(net "P5E_CPU0_P0_RX_BUF_DN<12>")
	)
	(segment
		(start 339.427566 -423.685462)
		(end 339.253068 -423.85996)
		(width 0.14224)
		(layer "In15.Cu")
		(net "P5E_CPU0_P0_RX_BUF_DN<12>")
	)
	(segment
		(start 340.37905 -414.238694)
		(end 340.44763 -414.267142)
		(width 0.14224)
		(layer "In15.Cu")
		(net "P5E_CPU0_P0_RX_BUF_DN<12>")
	)
	(segment
		(start 340.702138 -414.52165)
		(end 340.843616 -414.863026)
		(width 0.14224)
		(layer "In15.Cu")
		(net "P5E_CPU0_P0_RX_BUF_DN<12>")
	)
	(segment
		(start 341.572088 -419.729412)
		(end 341.866474 -419.851332)
		(width 0.14224)
		(layer "In15.Cu")
		(net "P5E_CPU0_P0_RX_BUF_DN<12>")
	)
	(segment
		(start 319.303146 -405.423116)
		(end 326.585326 -407.63317)
		(width 0.14224)
		(layer "In15.Cu")
		(net "P5E_CPU0_P0_RX_BUF_DN<12>")
	)
	(segment
		(start 340.843616 -414.863026)
		(end 340.843616 -418.651182)
		(width 0.14224)
		(layer "In15.Cu")
		(net "P5E_CPU0_P0_RX_BUF_DN<12>")
	)
	(segment
		(start 339.253068 -423.85996)
		(end 338.881974 -424.311572)
		(width 0.14224)
		(layer "In15.Cu")
		(net "P5E_CPU0_P0_RX_BUF_DN<12>")
	)
	(segment
		(start 342.275922 -421.737282)
		(end 342.14435 -421.868854)
		(width 0.14224)
		(layer "In15.Cu")
		(net "P5E_CPU0_P0_RX_BUF_DN<12>")
	)
	(segment
		(start 338.770468 -424.520868)
		(end 338.718906 -424.692826)
		(width 0.14224)
		(layer "In15.Cu")
		(net "P5E_CPU0_P0_RX_BUF_DN<12>")
	)
	(segment
		(start 317.475362 -401.394168)
		(end 317.475362 -403.447758)
		(width 0.14224)
		(layer "In15.Cu")
		(net "P5E_CPU0_P0_RX_BUF_DN<12>")
	)
	(segment
		(start 339.311996 -412.25724)
		(end 339.311996 -413.621982)
		(width 0.14224)
		(layer "In15.Cu")
		(net "P5E_CPU0_P0_RX_BUF_DN<12>")
	)
	(segment
		(start 338.36737 -411.260036)
		(end 339.274658 -412.167324)
		(width 0.14224)
		(layer "In15.Cu")
		(net "P5E_CPU0_P0_RX_BUF_DN<12>")
	)
	(segment
		(start 342.14435 -421.868854)
		(end 339.427566 -423.685462)
		(width 0.14224)
		(layer "In15.Cu")
		(net "P5E_CPU0_P0_RX_BUF_DN<12>")
	)
	(segment
		(start 318.21628 -400.962622)
		(end 318.08928 -401.089622)
		(width 0.14224)
		(layer "In15.Cu")
		(net "P5E_CPU0_P0_RX_BUF_DN<12>")
	)
	(segment
		(start 342.375236 -420.411402)
		(end 342.375236 -421.497506)
		(width 0.14224)
		(layer "In15.Cu")
		(net "P5E_CPU0_P0_RX_BUF_DN<12>")
	)
	(segment
		(start 340.44763 -414.267142)
		(end 340.702138 -414.52165)
		(width 0.14224)
		(layer "In15.Cu")
		(net "P5E_CPU0_P0_RX_BUF_DN<12>")
	)
	(segment
		(start 340.843616 -418.651182)
		(end 341.091012 -419.248336)
		(width 0.14224)
		(layer "In15.Cu")
		(net "P5E_CPU0_P0_RX_BUF_DN<12>")
	)
	(segment
		(start 339.503258 -437.623204)
		(end 339.649816 -437.769762)
		(width 0.14224)
		(layer "In15.Cu")
		(net "P5E_CPU0_P0_RX_BUF_DN<12>")
	)
	(segment
		(start 341.866474 -419.851332)
		(end 342.337898 -420.321486)
		(width 0.14224)
		(layer "In15.Cu")
		(net "P5E_CPU0_P0_RX_BUF_DN<12>")
	)
	(segment
		(start 338.818728 -437.450484)
		(end 338.991448 -437.623204)
		(width 0.14224)
		(layer "In15.Cu")
		(net "P5E_CPU0_P0_RX_BUF_DN<12>")
	)
	(segment
		(start 318.08928 -401.089622)
		(end 317.779908 -401.089622)
		(width 0.14224)
		(layer "In15.Cu")
		(net "P5E_CPU0_P0_RX_BUF_DN<12>")
	)
	(segment
		(start 339.649816 -437.769762)
		(end 339.649816 -438.089802)
		(width 0.14224)
		(layer "In15.Cu")
		(net "P5E_CPU0_P0_RX_BUF_DN<12>")
	)
	(segment
		(start 317.637922 -403.985984)
		(end 319.086484 -405.300434)
		(width 0.14224)
		(layer "In15.Cu")
		(net "P5E_CPU0_P0_RX_BUF_DN<12>")
	)
	(segment
		(start 331.306932 -408.658568)
		(end 335.71815 -409.536138)
		(width 0.14224)
		(layer "In15.Cu")
		(net "P5E_CPU0_P0_RX_BUF_DN<12>")
	)
	(segment
		(start 335.933034 -409.625038)
		(end 338.312252 -411.214824)
		(width 0.14224)
		(layer "In15.Cu")
		(net "P5E_CPU0_P0_RX_BUF_DN<12>")
	)
	(segment
		(start 339.427312 -413.90189)
		(end 339.691726 -414.166304)
		(width 0.14224)
		(layer "In15.Cu")
		(net "P5E_CPU0_P0_RX_BUF_DN<12>")
	)
	(segment
		(start 317.779908 -401.089622)
		(end 317.475362 -401.394168)
		(width 0.14224)
		(layer "In15.Cu")
		(net "P5E_CPU0_P0_RX_BUF_DN<12>")
	)
	(segment
		(start 339.311996 -413.621982)
		(end 339.427312 -413.90189)
		(width 0.14224)
		(layer "In15.Cu")
		(net "P5E_CPU0_P0_RX_BUF_DN<12>")
	)
	(segment
		(start 338.770468 -424.520614)
		(end 338.770468 -424.520868)
		(width 0.14224)
		(layer "In15.Cu")
		(net "P5E_CPU0_P0_RX_BUF_DN<12>")
	)
	(segment
		(start 318.21628 -400.811238)
		(end 318.21628 -400.962622)
		(width 0.14224)
		(layer "In15.Cu")
		(net "P5E_CPU0_P0_RX_BUF_DN<12>")
	)
	(segment
		(start 326.585326 -407.63317)
		(end 331.306932 -408.658568)
		(width 0.14224)
		(layer "In15.Cu")
		(net "P5E_CPU0_P0_RX_BUF_DN<12>")
	)
	(segment
		(start 338.688934 -424.898312)
		(end 338.688934 -437.136794)
		(width 0.14224)
		(layer "In15.Cu")
		(net "P5E_CPU0_P0_RX_BUF_DN<12>")
	)
	(segment
		(start 339.866478 -414.238694)
		(end 340.37905 -414.238694)
		(width 0.14224)
		(layer "In15.Cu")
		(net "P5E_CPU0_P0_RX_BUF_DN<12>")
	)
	(segment
		(start 339.691726 -414.166304)
		(end 339.866478 -414.238694)
		(width 0.14224)
		(layer "In15.Cu")
		(net "P5E_CPU0_P0_RX_BUF_DN<12>")
	)
	(segment
		(start 338.991448 -437.623204)
		(end 339.503258 -437.623204)
		(width 0.14224)
		(layer "In15.Cu")
		(net "P5E_CPU0_P0_RX_BUF_DN<12>")
	)
	(arc
		(start 317.475362 -403.447758)
		(mid 317.475362 -403.448012)
		(end 317.475362 -403.448266)
		(width 0.14224)
		(layer "In15.Cu")
		(net "P5E_CPU0_P0_RX_BUF_DN<12>")
	)
	(arc
		(start 342.337898 -420.321486)
		(mid 342.365517 -420.362726)
		(end 342.375236 -420.411402)
		(width 0.14224)
		(layer "In15.Cu")
		(net "P5E_CPU0_P0_RX_BUF_DN<12>")
	)
	(arc
		(start 335.71815 -409.536138)
		(mid 335.829968 -409.57001)
		(end 335.933034 -409.625038)
		(width 0.14224)
		(layer "In15.Cu")
		(net "P5E_CPU0_P0_RX_BUF_DN<12>")
	)
	(arc
		(start 317.475362 -403.448266)
		(mid 317.478969 -403.572419)
		(end 317.489586 -403.69617)
		(width 0.14224)
		(layer "In15.Cu")
		(net "P5E_CPU0_P0_RX_BUF_DN<12>")
	)
	(arc
		(start 341.091012 -419.248336)
		(mid 341.283738 -419.536686)
		(end 341.572088 -419.729412)
		(width 0.14224)
		(layer "In15.Cu")
		(net "P5E_CPU0_P0_RX_BUF_DN<12>")
	)
	(arc
		(start 339.274658 -412.167324)
		(mid 339.302277 -412.208564)
		(end 339.311996 -412.25724)
		(width 0.14224)
		(layer "In15.Cu")
		(net "P5E_CPU0_P0_RX_BUF_DN<12>")
	)
	(arc
		(start 338.688934 -437.136794)
		(mid 338.722624 -437.306547)
		(end 338.818728 -437.450484)
		(width 0.14224)
		(layer "In15.Cu")
		(net "P5E_CPU0_P0_RX_BUF_DN<12>")
	)
	(arc
		(start 338.881974 -424.311572)
		(mid 338.815835 -424.410552)
		(end 338.770468 -424.520614)
		(width 0.14224)
		(layer "In15.Cu")
		(net "P5E_CPU0_P0_RX_BUF_DN<12>")
	)
	(arc
		(start 317.489586 -403.69617)
		(mid 317.537369 -403.854572)
		(end 317.637922 -403.985984)
		(width 0.14224)
		(layer "In15.Cu")
		(net "P5E_CPU0_P0_RX_BUF_DN<12>")
	)
	(arc
		(start 338.312252 -411.214824)
		(mid 338.340924 -411.236073)
		(end 338.36737 -411.260036)
		(width 0.14224)
		(layer "In15.Cu")
		(net "P5E_CPU0_P0_RX_BUF_DN<12>")
	)
	(arc
		(start 319.086484 -405.300434)
		(mid 319.188014 -405.373785)
		(end 319.303146 -405.423116)
		(width 0.14224)
		(layer "In15.Cu")
		(net "P5E_CPU0_P0_RX_BUF_DN<12>")
	)
	(arc
		(start 338.718906 -424.692826)
		(mid 338.696429 -424.794477)
		(end 338.688934 -424.898312)
		(width 0.14224)
		(layer "In15.Cu")
		(net "P5E_CPU0_P0_RX_BUF_DN<12>")
	)
	(arc
		(start 342.375236 -421.497506)
		(mid 342.349424 -421.62727)
		(end 342.275922 -421.737282)
		(width 0.14224)
		(layer "In15.Cu")
		(net "P5E_CPU0_P0_RX_BUF_DN<12>")
	)
	(segment
		(start 316.618112 -399.960338)
		(end 316.618112 -399.143728)
		(width 0.1016)
		(layer "F.Cu")
		(net "P5E_CPU0_P0_RX_BUF_DN<11>")
	)
	(segment
		(start 316.529466 -401.016216)
		(end 316.529466 -400.048984)
		(width 0.1016)
		(layer "F.Cu")
		(net "P5E_CPU0_P0_RX_BUF_DN<11>")
	)
	(segment
		(start 316.875414 -401.143216)
		(end 316.656466 -401.143216)
		(width 0.1016)
		(layer "F.Cu")
		(net "P5E_CPU0_P0_RX_BUF_DN<11>")
	)
	(segment
		(start 317.016384 -400.811238)
		(end 317.016384 -401.002246)
		(width 0.1016)
		(layer "F.Cu")
		(net "P5E_CPU0_P0_RX_BUF_DN<11>")
	)
	(segment
		(start 316.529466 -400.048984)
		(end 316.618112 -399.960338)
		(width 0.1016)
		(layer "F.Cu")
		(net "P5E_CPU0_P0_RX_BUF_DN<11>")
	)
	(segment
		(start 316.618112 -399.143728)
		(end 316.617858 -399.143474)
		(width 0.1016)
		(layer "F.Cu")
		(net "P5E_CPU0_P0_RX_BUF_DN<11>")
	)
	(segment
		(start 316.656466 -401.143216)
		(end 316.529466 -401.016216)
		(width 0.1016)
		(layer "F.Cu")
		(net "P5E_CPU0_P0_RX_BUF_DN<11>")
	)
	(segment
		(start 317.016384 -401.002246)
		(end 316.875414 -401.143216)
		(width 0.1016)
		(layer "F.Cu")
		(net "P5E_CPU0_P0_RX_BUF_DN<11>")
	)
	(segment
		(start 318.59601 -406.197816)
		(end 327.611486 -408.933396)
		(width 0.14224)
		(layer "In15.Cu")
		(net "P5E_CPU0_P0_RX_BUF_DN<11>")
	)
	(segment
		(start 316.580012 -401.089622)
		(end 316.275466 -401.394168)
		(width 0.14224)
		(layer "In15.Cu")
		(net "P5E_CPU0_P0_RX_BUF_DN<11>")
	)
	(segment
		(start 337.31581 -414.238694)
		(end 337.38439 -414.267142)
		(width 0.14224)
		(layer "In15.Cu")
		(net "P5E_CPU0_P0_RX_BUF_DN<11>")
	)
	(segment
		(start 330.681838 -409.623006)
		(end 330.682092 -409.623514)
		(width 0.14224)
		(layer "In15.Cu")
		(net "P5E_CPU0_P0_RX_BUF_DN<11>")
	)
	(segment
		(start 337.780376 -414.863026)
		(end 337.780376 -418.722302)
		(width 0.14224)
		(layer "In15.Cu")
		(net "P5E_CPU0_P0_RX_BUF_DN<11>")
	)
	(segment
		(start 327.611486 -408.933396)
		(end 330.681838 -409.623006)
		(width 0.14224)
		(layer "In15.Cu")
		(net "P5E_CPU0_P0_RX_BUF_DN<11>")
	)
	(segment
		(start 336.364326 -413.902144)
		(end 336.628232 -414.16605)
		(width 0.14224)
		(layer "In15.Cu")
		(net "P5E_CPU0_P0_RX_BUF_DN<11>")
	)
	(segment
		(start 317.016384 -400.962622)
		(end 316.889384 -401.089622)
		(width 0.14224)
		(layer "In15.Cu")
		(net "P5E_CPU0_P0_RX_BUF_DN<11>")
	)
	(segment
		(start 336.248756 -413.622998)
		(end 336.364326 -413.902144)
		(width 0.14224)
		(layer "In15.Cu")
		(net "P5E_CPU0_P0_RX_BUF_DN<11>")
	)
	(segment
		(start 337.503262 -438.623202)
		(end 337.64982 -438.76976)
		(width 0.14224)
		(layer "In15.Cu")
		(net "P5E_CPU0_P0_RX_BUF_DN<11>")
	)
	(segment
		(start 333.704946 -410.34589)
		(end 335.74228 -411.744414)
		(width 0.14224)
		(layer "In15.Cu")
		(net "P5E_CPU0_P0_RX_BUF_DN<11>")
	)
	(segment
		(start 316.477396 -404.466044)
		(end 318.04864 -405.887936)
		(width 0.14224)
		(layer "In15.Cu")
		(net "P5E_CPU0_P0_RX_BUF_DN<11>")
	)
	(segment
		(start 317.016384 -400.811238)
		(end 317.016384 -400.962622)
		(width 0.14224)
		(layer "In15.Cu")
		(net "P5E_CPU0_P0_RX_BUF_DN<11>")
	)
	(segment
		(start 330.681838 -409.624022)
		(end 333.503016 -410.257752)
		(width 0.14224)
		(layer "In15.Cu")
		(net "P5E_CPU0_P0_RX_BUF_DN<11>")
	)
	(segment
		(start 337.338416 -423.48023)
		(end 336.84337 -424.220894)
		(width 0.14224)
		(layer "In15.Cu")
		(net "P5E_CPU0_P0_RX_BUF_DN<11>")
	)
	(segment
		(start 330.682092 -409.623514)
		(end 330.681838 -409.624022)
		(width 0.14224)
		(layer "In15.Cu")
		(net "P5E_CPU0_P0_RX_BUF_DN<11>")
	)
	(segment
		(start 339.311996 -420.437056)
		(end 339.311996 -421.453818)
		(width 0.14224)
		(layer "In15.Cu")
		(net "P5E_CPU0_P0_RX_BUF_DN<11>")
	)
	(segment
		(start 336.818732 -438.450482)
		(end 336.991452 -438.623202)
		(width 0.14224)
		(layer "In15.Cu")
		(net "P5E_CPU0_P0_RX_BUF_DN<11>")
	)
	(segment
		(start 336.628232 -414.16605)
		(end 336.803238 -414.238694)
		(width 0.14224)
		(layer "In15.Cu")
		(net "P5E_CPU0_P0_RX_BUF_DN<11>")
	)
	(segment
		(start 338.433156 -419.697916)
		(end 338.758784 -419.833044)
		(width 0.14224)
		(layer "In15.Cu")
		(net "P5E_CPU0_P0_RX_BUF_DN<11>")
	)
	(segment
		(start 337.64982 -438.76976)
		(end 337.64982 -439.0898)
		(width 0.14224)
		(layer "In15.Cu")
		(net "P5E_CPU0_P0_RX_BUF_DN<11>")
	)
	(segment
		(start 337.38439 -414.267142)
		(end 337.638898 -414.52165)
		(width 0.14224)
		(layer "In15.Cu")
		(net "P5E_CPU0_P0_RX_BUF_DN<11>")
	)
	(segment
		(start 338.758784 -419.833044)
		(end 339.274658 -420.34714)
		(width 0.14224)
		(layer "In15.Cu")
		(net "P5E_CPU0_P0_RX_BUF_DN<11>")
	)
	(segment
		(start 336.803238 -414.238694)
		(end 337.31581 -414.238694)
		(width 0.14224)
		(layer "In15.Cu")
		(net "P5E_CPU0_P0_RX_BUF_DN<11>")
	)
	(segment
		(start 336.248756 -412.405576)
		(end 336.248756 -413.622998)
		(width 0.14224)
		(layer "In15.Cu")
		(net "P5E_CPU0_P0_RX_BUF_DN<11>")
	)
	(segment
		(start 316.889384 -401.089622)
		(end 316.580012 -401.089622)
		(width 0.14224)
		(layer "In15.Cu")
		(net "P5E_CPU0_P0_RX_BUF_DN<11>")
	)
	(segment
		(start 337.780376 -418.722302)
		(end 338.009484 -419.27399)
		(width 0.14224)
		(layer "In15.Cu")
		(net "P5E_CPU0_P0_RX_BUF_DN<11>")
	)
	(segment
		(start 337.638898 -414.52165)
		(end 337.780376 -414.863026)
		(width 0.14224)
		(layer "In15.Cu")
		(net "P5E_CPU0_P0_RX_BUF_DN<11>")
	)
	(segment
		(start 339.274658 -421.543988)
		(end 337.338416 -423.48023)
		(width 0.14224)
		(layer "In15.Cu")
		(net "P5E_CPU0_P0_RX_BUF_DN<11>")
	)
	(segment
		(start 335.74228 -411.744414)
		(end 336.139282 -412.141416)
		(width 0.14224)
		(layer "In15.Cu")
		(net "P5E_CPU0_P0_RX_BUF_DN<11>")
	)
	(segment
		(start 336.991452 -438.623202)
		(end 337.503262 -438.623202)
		(width 0.14224)
		(layer "In15.Cu")
		(net "P5E_CPU0_P0_RX_BUF_DN<11>")
	)
	(segment
		(start 316.275466 -401.394168)
		(end 316.275466 -403.971252)
		(width 0.14224)
		(layer "In15.Cu")
		(net "P5E_CPU0_P0_RX_BUF_DN<11>")
	)
	(segment
		(start 336.688938 -424.687746)
		(end 336.688938 -438.136792)
		(width 0.14224)
		(layer "In15.Cu")
		(net "P5E_CPU0_P0_RX_BUF_DN<11>")
	)
	(arc
		(start 336.72018 -424.47972)
		(mid 336.696752 -424.582562)
		(end 336.688938 -424.687746)
		(width 0.14224)
		(layer "In15.Cu")
		(net "P5E_CPU0_P0_RX_BUF_DN<11>")
	)
	(arc
		(start 336.688938 -438.136792)
		(mid 336.722628 -438.306545)
		(end 336.818732 -438.450482)
		(width 0.14224)
		(layer "In15.Cu")
		(net "P5E_CPU0_P0_RX_BUF_DN<11>")
	)
	(arc
		(start 318.04864 -405.887936)
		(mid 318.30518 -406.073162)
		(end 318.59601 -406.197816)
		(width 0.14224)
		(layer "In15.Cu")
		(net "P5E_CPU0_P0_RX_BUF_DN<11>")
	)
	(arc
		(start 339.274658 -420.34714)
		(mid 339.302277 -420.38838)
		(end 339.311996 -420.437056)
		(width 0.14224)
		(layer "In15.Cu")
		(net "P5E_CPU0_P0_RX_BUF_DN<11>")
	)
	(arc
		(start 333.503016 -410.257752)
		(mid 333.608191 -410.292178)
		(end 333.704946 -410.34589)
		(width 0.14224)
		(layer "In15.Cu")
		(net "P5E_CPU0_P0_RX_BUF_DN<11>")
	)
	(arc
		(start 336.84337 -424.220894)
		(mid 336.772367 -424.345829)
		(end 336.72018 -424.47972)
		(width 0.14224)
		(layer "In15.Cu")
		(net "P5E_CPU0_P0_RX_BUF_DN<11>")
	)
	(arc
		(start 336.139282 -412.141416)
		(mid 336.220317 -412.262599)
		(end 336.248756 -412.405576)
		(width 0.14224)
		(layer "In15.Cu")
		(net "P5E_CPU0_P0_RX_BUF_DN<11>")
	)
	(arc
		(start 339.311996 -421.453818)
		(mid 339.30229 -421.502613)
		(end 339.274658 -421.543988)
		(width 0.14224)
		(layer "In15.Cu")
		(net "P5E_CPU0_P0_RX_BUF_DN<11>")
	)
	(arc
		(start 316.333124 -404.261066)
		(mid 316.39384 -404.371592)
		(end 316.477396 -404.466044)
		(width 0.14224)
		(layer "In15.Cu")
		(net "P5E_CPU0_P0_RX_BUF_DN<11>")
	)
	(arc
		(start 316.275466 -403.971252)
		(mid 316.29007 -404.118989)
		(end 316.333124 -404.261066)
		(width 0.14224)
		(layer "In15.Cu")
		(net "P5E_CPU0_P0_RX_BUF_DN<11>")
	)
	(arc
		(start 338.009484 -419.27399)
		(mid 338.179208 -419.528045)
		(end 338.433156 -419.697916)
		(width 0.14224)
		(layer "In15.Cu")
		(net "P5E_CPU0_P0_RX_BUF_DN<11>")
	)
	(segment
		(start 315.675518 -401.143216)
		(end 315.45657 -401.143216)
		(width 0.1016)
		(layer "F.Cu")
		(net "P5E_CPU0_P0_RX_BUF_DN<10>")
	)
	(segment
		(start 315.32957 -401.016216)
		(end 315.32957 -400.048984)
		(width 0.1016)
		(layer "F.Cu")
		(net "P5E_CPU0_P0_RX_BUF_DN<10>")
	)
	(segment
		(start 315.45657 -401.143216)
		(end 315.32957 -401.016216)
		(width 0.1016)
		(layer "F.Cu")
		(net "P5E_CPU0_P0_RX_BUF_DN<10>")
	)
	(segment
		(start 315.32957 -400.048984)
		(end 315.417708 -399.960846)
		(width 0.1016)
		(layer "F.Cu")
		(net "P5E_CPU0_P0_RX_BUF_DN<10>")
	)
	(segment
		(start 315.417708 -399.960846)
		(end 315.417708 -399.143474)
		(width 0.1016)
		(layer "F.Cu")
		(net "P5E_CPU0_P0_RX_BUF_DN<10>")
	)
	(segment
		(start 315.816488 -400.811238)
		(end 315.816488 -401.002246)
		(width 0.1016)
		(layer "F.Cu")
		(net "P5E_CPU0_P0_RX_BUF_DN<10>")
	)
	(segment
		(start 315.816488 -401.002246)
		(end 315.675518 -401.143216)
		(width 0.1016)
		(layer "F.Cu")
		(net "P5E_CPU0_P0_RX_BUF_DN<10>")
	)
	(segment
		(start 334.575658 -414.52165)
		(end 334.717136 -414.863026)
		(width 0.14224)
		(layer "In15.Cu")
		(net "P5E_CPU0_P0_RX_BUF_DN<10>")
	)
	(segment
		(start 333.739998 -414.238694)
		(end 334.25257 -414.238694)
		(width 0.14224)
		(layer "In15.Cu")
		(net "P5E_CPU0_P0_RX_BUF_DN<10>")
	)
	(segment
		(start 333.185516 -412.4579)
		(end 333.185516 -413.622998)
		(width 0.14224)
		(layer "In15.Cu")
		(net "P5E_CPU0_P0_RX_BUF_DN<10>")
	)
	(segment
		(start 335.649824 -437.769762)
		(end 335.649824 -438.089802)
		(width 0.14224)
		(layer "In15.Cu")
		(net "P5E_CPU0_P0_RX_BUF_DN<10>")
	)
	(segment
		(start 333.564992 -414.16605)
		(end 333.739998 -414.238694)
		(width 0.14224)
		(layer "In15.Cu")
		(net "P5E_CPU0_P0_RX_BUF_DN<10>")
	)
	(segment
		(start 333.185516 -413.622998)
		(end 333.301086 -413.902144)
		(width 0.14224)
		(layer "In15.Cu")
		(net "P5E_CPU0_P0_RX_BUF_DN<10>")
	)
	(segment
		(start 334.717136 -414.863026)
		(end 334.717136 -418.760656)
		(width 0.14224)
		(layer "In15.Cu")
		(net "P5E_CPU0_P0_RX_BUF_DN<10>")
	)
	(segment
		(start 334.688942 -437.315864)
		(end 334.996282 -437.623204)
		(width 0.14224)
		(layer "In15.Cu")
		(net "P5E_CPU0_P0_RX_BUF_DN<10>")
	)
	(segment
		(start 330.379324 -410.913834)
		(end 330.379578 -410.914088)
		(width 0.14224)
		(layer "In15.Cu")
		(net "P5E_CPU0_P0_RX_BUF_DN<10>")
	)
	(segment
		(start 330.379578 -410.914088)
		(end 332.349856 -411.511242)
		(width 0.14224)
		(layer "In15.Cu")
		(net "P5E_CPU0_P0_RX_BUF_DN<10>")
	)
	(segment
		(start 336.248756 -420.465504)
		(end 336.248756 -422.021254)
		(width 0.14224)
		(layer "In15.Cu")
		(net "P5E_CPU0_P0_RX_BUF_DN<10>")
	)
	(segment
		(start 327.661778 -410.089604)
		(end 330.379324 -410.913834)
		(width 0.14224)
		(layer "In15.Cu")
		(net "P5E_CPU0_P0_RX_BUF_DN<10>")
	)
	(segment
		(start 315.816488 -400.962622)
		(end 315.689488 -401.089622)
		(width 0.14224)
		(layer "In15.Cu")
		(net "P5E_CPU0_P0_RX_BUF_DN<10>")
	)
	(segment
		(start 336.227166 -422.09212)
		(end 334.688942 -424.394122)
		(width 0.14224)
		(layer "In15.Cu")
		(net "P5E_CPU0_P0_RX_BUF_DN<10>")
	)
	(segment
		(start 334.996282 -437.623204)
		(end 335.503266 -437.623204)
		(width 0.14224)
		(layer "In15.Cu")
		(net "P5E_CPU0_P0_RX_BUF_DN<10>")
	)
	(segment
		(start 333.301086 -413.902144)
		(end 333.564992 -414.16605)
		(width 0.14224)
		(layer "In15.Cu")
		(net "P5E_CPU0_P0_RX_BUF_DN<10>")
	)
	(segment
		(start 335.649824 -419.813994)
		(end 336.211418 -420.375588)
		(width 0.14224)
		(layer "In15.Cu")
		(net "P5E_CPU0_P0_RX_BUF_DN<10>")
	)
	(segment
		(start 315.24702 -404.575772)
		(end 317.107824 -406.436576)
		(width 0.14224)
		(layer "In15.Cu")
		(net "P5E_CPU0_P0_RX_BUF_DN<10>")
	)
	(segment
		(start 325.041514 -409.294584)
		(end 327.661778 -410.089096)
		(width 0.14224)
		(layer "In15.Cu")
		(net "P5E_CPU0_P0_RX_BUF_DN<10>")
	)
	(segment
		(start 315.816488 -400.811238)
		(end 315.816488 -400.962622)
		(width 0.14224)
		(layer "In15.Cu")
		(net "P5E_CPU0_P0_RX_BUF_DN<10>")
	)
	(segment
		(start 332.829154 -411.871922)
		(end 333.164942 -412.388812)
		(width 0.14224)
		(layer "In15.Cu")
		(net "P5E_CPU0_P0_RX_BUF_DN<10>")
	)
	(segment
		(start 327.661778 -410.089096)
		(end 327.661778 -410.089604)
		(width 0.14224)
		(layer "In15.Cu")
		(net "P5E_CPU0_P0_RX_BUF_DN<10>")
	)
	(segment
		(start 324.723506 -409.033726)
		(end 325.041514 -409.294584)
		(width 0.14224)
		(layer "In15.Cu")
		(net "P5E_CPU0_P0_RX_BUF_DN<10>")
	)
	(segment
		(start 315.689488 -401.089622)
		(end 315.380116 -401.089622)
		(width 0.14224)
		(layer "In15.Cu")
		(net "P5E_CPU0_P0_RX_BUF_DN<10>")
	)
	(segment
		(start 334.688942 -424.394122)
		(end 334.688942 -437.315864)
		(width 0.14224)
		(layer "In15.Cu")
		(net "P5E_CPU0_P0_RX_BUF_DN<10>")
	)
	(segment
		(start 334.32115 -414.267142)
		(end 334.575658 -414.52165)
		(width 0.14224)
		(layer "In15.Cu")
		(net "P5E_CPU0_P0_RX_BUF_DN<10>")
	)
	(segment
		(start 335.503266 -437.623204)
		(end 335.649824 -437.769762)
		(width 0.14224)
		(layer "In15.Cu")
		(net "P5E_CPU0_P0_RX_BUF_DN<10>")
	)
	(segment
		(start 318.072262 -407.016458)
		(end 324.723506 -409.033726)
		(width 0.14224)
		(layer "In15.Cu")
		(net "P5E_CPU0_P0_RX_BUF_DN<10>")
	)
	(segment
		(start 317.107824 -406.436576)
		(end 317.411608 -406.673558)
		(width 0.14224)
		(layer "In15.Cu")
		(net "P5E_CPU0_P0_RX_BUF_DN<10>")
	)
	(segment
		(start 315.07557 -401.394168)
		(end 315.07557 -404.162006)
		(width 0.14224)
		(layer "In15.Cu")
		(net "P5E_CPU0_P0_RX_BUF_DN<10>")
	)
	(segment
		(start 315.380116 -401.089622)
		(end 315.07557 -401.394168)
		(width 0.14224)
		(layer "In15.Cu")
		(net "P5E_CPU0_P0_RX_BUF_DN<10>")
	)
	(segment
		(start 334.25257 -414.238694)
		(end 334.32115 -414.267142)
		(width 0.14224)
		(layer "In15.Cu")
		(net "P5E_CPU0_P0_RX_BUF_DN<10>")
	)
	(segment
		(start 335.543144 -419.770052)
		(end 335.649824 -419.813994)
		(width 0.14224)
		(layer "In15.Cu")
		(net "P5E_CPU0_P0_RX_BUF_DN<10>")
	)
	(segment
		(start 334.717136 -418.760656)
		(end 334.846676 -419.07333)
		(width 0.14224)
		(layer "In15.Cu")
		(net "P5E_CPU0_P0_RX_BUF_DN<10>")
	)
	(arc
		(start 334.846676 -419.07333)
		(mid 335.12563 -419.490932)
		(end 335.543144 -419.770052)
		(width 0.14224)
		(layer "In15.Cu")
		(net "P5E_CPU0_P0_RX_BUF_DN<10>")
	)
	(arc
		(start 336.211418 -420.375588)
		(mid 336.239037 -420.416828)
		(end 336.248756 -420.465504)
		(width 0.14224)
		(layer "In15.Cu")
		(net "P5E_CPU0_P0_RX_BUF_DN<10>")
	)
	(arc
		(start 336.248756 -422.021254)
		(mid 336.243235 -422.058292)
		(end 336.227166 -422.09212)
		(width 0.14224)
		(layer "In15.Cu")
		(net "P5E_CPU0_P0_RX_BUF_DN<10>")
	)
	(arc
		(start 315.07557 -404.162006)
		(mid 315.120132 -404.385944)
		(end 315.24702 -404.575772)
		(width 0.14224)
		(layer "In15.Cu")
		(net "P5E_CPU0_P0_RX_BUF_DN<10>")
	)
	(arc
		(start 332.349856 -411.511242)
		(mid 332.621394 -411.649196)
		(end 332.829154 -411.871922)
		(width 0.14224)
		(layer "In15.Cu")
		(net "P5E_CPU0_P0_RX_BUF_DN<10>")
	)
	(arc
		(start 317.411608 -406.673558)
		(mid 317.726094 -406.875526)
		(end 318.072262 -407.016458)
		(width 0.14224)
		(layer "In15.Cu")
		(net "P5E_CPU0_P0_RX_BUF_DN<10>")
	)
	(arc
		(start 333.164942 -412.388812)
		(mid 333.180275 -412.421858)
		(end 333.185516 -412.4579)
		(width 0.14224)
		(layer "In15.Cu")
		(net "P5E_CPU0_P0_RX_BUF_DN<10>")
	)
	(segment
		(start 303.307242 -400.071336)
		(end 303.307242 -400.993864)
		(width 0.1016)
		(layer "F.Cu")
		(net "P5E_CPU0_P0_RX_BUF_DN<0>")
	)
	(segment
		(start 303.456594 -401.143216)
		(end 303.675542 -401.143216)
		(width 0.1016)
		(layer "F.Cu")
		(net "P5E_CPU0_P0_RX_BUF_DN<0>")
	)
	(segment
		(start 303.41824 -399.143982)
		(end 303.41824 -399.960338)
		(width 0.1016)
		(layer "F.Cu")
		(net "P5E_CPU0_P0_RX_BUF_DN<0>")
	)
	(segment
		(start 303.675542 -401.143216)
		(end 303.816258 -401.0025)
		(width 0.1016)
		(layer "F.Cu")
		(net "P5E_CPU0_P0_RX_BUF_DN<0>")
	)
	(segment
		(start 303.307242 -400.993864)
		(end 303.456594 -401.143216)
		(width 0.1016)
		(layer "F.Cu")
		(net "P5E_CPU0_P0_RX_BUF_DN<0>")
	)
	(segment
		(start 303.417732 -399.143474)
		(end 303.41824 -399.143982)
		(width 0.1016)
		(layer "F.Cu")
		(net "P5E_CPU0_P0_RX_BUF_DN<0>")
	)
	(segment
		(start 303.816258 -401.0025)
		(end 303.816258 -400.811238)
		(width 0.1016)
		(layer "F.Cu")
		(net "P5E_CPU0_P0_RX_BUF_DN<0>")
	)
	(segment
		(start 303.41824 -399.960338)
		(end 303.307242 -400.071336)
		(width 0.1016)
		(layer "F.Cu")
		(net "P5E_CPU0_P0_RX_BUF_DN<0>")
	)
	(segment
		(start 303.502822 -414.238694)
		(end 303.107598 -414.238694)
		(width 0.14224)
		(layer "In15.Cu")
		(net "P5E_CPU0_P0_RX_BUF_DN<0>")
	)
	(segment
		(start 303.379886 -401.089622)
		(end 303.689258 -401.089622)
		(width 0.14224)
		(layer "In15.Cu")
		(net "P5E_CPU0_P0_RX_BUF_DN<0>")
	)
	(segment
		(start 305.616356 -421.521128)
		(end 305.616356 -420.49573)
		(width 0.14224)
		(layer "In15.Cu")
		(net "P5E_CPU0_P0_RX_BUF_DN<0>")
	)
	(segment
		(start 313.810904 -437.61914)
		(end 313.207908 -437.016144)
		(width 0.14224)
		(layer "In15.Cu")
		(net "P5E_CPU0_P0_RX_BUF_DN<0>")
	)
	(segment
		(start 305.785774 -421.926512)
		(end 305.701446 -421.800528)
		(width 0.14224)
		(layer "In15.Cu")
		(net "P5E_CPU0_P0_RX_BUF_DN<0>")
	)
	(segment
		(start 305.112928 -419.853618)
		(end 304.882804 -419.758368)
		(width 0.14224)
		(layer "In15.Cu")
		(net "P5E_CPU0_P0_RX_BUF_DN<0>")
	)
	(segment
		(start 313.207908 -437.016144)
		(end 313.207908 -425.131992)
		(width 0.14224)
		(layer "In15.Cu")
		(net "P5E_CPU0_P0_RX_BUF_DN<0>")
	)
	(segment
		(start 304.084736 -418.662866)
		(end 304.084736 -414.863026)
		(width 0.14224)
		(layer "In15.Cu")
		(net "P5E_CPU0_P0_RX_BUF_DN<0>")
	)
	(segment
		(start 304.084736 -414.863026)
		(end 304.017426 -414.700466)
		(width 0.14224)
		(layer "In15.Cu")
		(net "P5E_CPU0_P0_RX_BUF_DN<0>")
	)
	(segment
		(start 303.07534 -410.26207)
		(end 303.07534 -401.394168)
		(width 0.14224)
		(layer "In15.Cu")
		(net "P5E_CPU0_P0_RX_BUF_DN<0>")
	)
	(segment
		(start 303.07534 -401.394168)
		(end 303.379886 -401.089622)
		(width 0.14224)
		(layer "In15.Cu")
		(net "P5E_CPU0_P0_RX_BUF_DN<0>")
	)
	(segment
		(start 302.932592 -414.16605)
		(end 302.668686 -413.902144)
		(width 0.14224)
		(layer "In15.Cu")
		(net "P5E_CPU0_P0_RX_BUF_DN<0>")
	)
	(segment
		(start 306.090066 -422.176448)
		(end 305.785774 -421.926512)
		(width 0.14224)
		(layer "In15.Cu")
		(net "P5E_CPU0_P0_RX_BUF_DN<0>")
	)
	(segment
		(start 302.668686 -413.902144)
		(end 302.551592 -413.61995)
		(width 0.14224)
		(layer "In15.Cu")
		(net "P5E_CPU0_P0_RX_BUF_DN<0>")
	)
	(segment
		(start 314.649612 -438.089802)
		(end 314.649612 -437.769762)
		(width 0.14224)
		(layer "In15.Cu")
		(net "P5E_CPU0_P0_RX_BUF_DN<0>")
	)
	(segment
		(start 304.295302 -419.170866)
		(end 304.084736 -418.662866)
		(width 0.14224)
		(layer "In15.Cu")
		(net "P5E_CPU0_P0_RX_BUF_DN<0>")
	)
	(segment
		(start 302.551592 -412.392622)
		(end 302.5902 -412.198058)
		(width 0.14224)
		(layer "In15.Cu")
		(net "P5E_CPU0_P0_RX_BUF_DN<0>")
	)
	(segment
		(start 314.649612 -437.769762)
		(end 314.49899 -437.61914)
		(width 0.14224)
		(layer "In15.Cu")
		(net "P5E_CPU0_P0_RX_BUF_DN<0>")
	)
	(segment
		(start 303.107598 -414.238694)
		(end 302.932592 -414.16605)
		(width 0.14224)
		(layer "In15.Cu")
		(net "P5E_CPU0_P0_RX_BUF_DN<0>")
	)
	(segment
		(start 304.017426 -414.700466)
		(end 303.592992 -414.276032)
		(width 0.14224)
		(layer "In15.Cu")
		(net "P5E_CPU0_P0_RX_BUF_DN<0>")
	)
	(segment
		(start 302.5902 -412.198058)
		(end 302.957484 -410.731208)
		(width 0.14224)
		(layer "In15.Cu")
		(net "P5E_CPU0_P0_RX_BUF_DN<0>")
	)
	(segment
		(start 305.51882 -420.260018)
		(end 305.112928 -419.853618)
		(width 0.14224)
		(layer "In15.Cu")
		(net "P5E_CPU0_P0_RX_BUF_DN<0>")
	)
	(segment
		(start 303.689258 -401.089622)
		(end 303.816258 -400.962622)
		(width 0.14224)
		(layer "In15.Cu")
		(net "P5E_CPU0_P0_RX_BUF_DN<0>")
	)
	(segment
		(start 303.816258 -400.962622)
		(end 303.816258 -400.811238)
		(width 0.14224)
		(layer "In15.Cu")
		(net "P5E_CPU0_P0_RX_BUF_DN<0>")
	)
	(segment
		(start 313.129676 -425.015152)
		(end 308.279038 -423.005758)
		(width 0.14224)
		(layer "In15.Cu")
		(net "P5E_CPU0_P0_RX_BUF_DN<0>")
	)
	(segment
		(start 307.576474 -422.792652)
		(end 306.090066 -422.176448)
		(width 0.14224)
		(layer "In15.Cu")
		(net "P5E_CPU0_P0_RX_BUF_DN<0>")
	)
	(segment
		(start 308.279038 -423.005758)
		(end 307.576474 -422.792652)
		(width 0.14224)
		(layer "In15.Cu")
		(net "P5E_CPU0_P0_RX_BUF_DN<0>")
	)
	(segment
		(start 302.957484 -410.731208)
		(end 302.957992 -410.731208)
		(width 0.14224)
		(layer "In15.Cu")
		(net "P5E_CPU0_P0_RX_BUF_DN<0>")
	)
	(segment
		(start 302.957992 -410.731208)
		(end 303.07534 -410.26207)
		(width 0.14224)
		(layer "In15.Cu")
		(net "P5E_CPU0_P0_RX_BUF_DN<0>")
	)
	(segment
		(start 314.49899 -437.61914)
		(end 313.810904 -437.61914)
		(width 0.14224)
		(layer "In15.Cu")
		(net "P5E_CPU0_P0_RX_BUF_DN<0>")
	)
	(segment
		(start 302.551592 -413.61995)
		(end 302.551592 -412.392622)
		(width 0.14224)
		(layer "In15.Cu")
		(net "P5E_CPU0_P0_RX_BUF_DN<0>")
	)
	(arc
		(start 304.882804 -419.758368)
		(mid 304.53067 -419.523)
		(end 304.295302 -419.170866)
		(width 0.14224)
		(layer "In15.Cu")
		(net "P5E_CPU0_P0_RX_BUF_DN<0>")
	)
	(arc
		(start 305.616356 -420.49573)
		(mid 305.591004 -420.368187)
		(end 305.51882 -420.260018)
		(width 0.14224)
		(layer "In15.Cu")
		(net "P5E_CPU0_P0_RX_BUF_DN<0>")
	)
	(arc
		(start 303.592992 -414.276032)
		(mid 303.551622 -414.248389)
		(end 303.502822 -414.238694)
		(width 0.14224)
		(layer "In15.Cu")
		(net "P5E_CPU0_P0_RX_BUF_DN<0>")
	)
	(arc
		(start 313.207908 -425.131992)
		(mid 313.186555 -425.061664)
		(end 313.129676 -425.015152)
		(width 0.14224)
		(layer "In15.Cu")
		(net "P5E_CPU0_P0_RX_BUF_DN<0>")
	)
	(arc
		(start 305.701446 -421.800528)
		(mid 305.638144 -421.66715)
		(end 305.616356 -421.521128)
		(width 0.14224)
		(layer "In15.Cu")
		(net "P5E_CPU0_P0_RX_BUF_DN<0>")
	)
	(segment
		(start 336.517996 -260.860032)
		(end 336.051144 -261.12597)
		(width 0.12954)
		(layer "F.Cu")
		(net "Net_1795")
	)
	(via
		(at 336.051144 -261.12597)
		(size 0.4064)
		(drill 0.2032)
		(layers "F.Cu" "B.Cu")
		(net "Net_1795")
	)
	(segment
		(start 336.047842 -261.670038)
		(end 335.58099 -261.935976)
		(width 0.12954)
		(layer "F.Cu")
		(net "Net_1796")
	)
	(via
		(at 335.58099 -261.935976)
		(size 0.4064)
		(drill 0.2032)
		(layers "F.Cu" "B.Cu")
		(net "Net_1796")
	)
	(segment
		(start 335.747868 -251.23013)
		(end 335.281016 -250.964192)
		(width 0.10668)
		(layer "F.Cu")
		(net "Net_1797")
	)
	(via
		(at 335.281016 -250.964192)
		(size 0.4064)
		(drill 0.2032)
		(layers "F.Cu" "B.Cu")
		(net "Net_1797")
	)
	(segment
		(start 337.158076 -252.040136)
		(end 336.691224 -251.774198)
		(width 0.10668)
		(layer "F.Cu")
		(net "Net_1798")
	)
	(via
		(at 336.691224 -251.774198)
		(size 0.4064)
		(drill 0.2032)
		(layers "F.Cu" "B.Cu")
		(net "Net_1798")
	)
	(segment
		(start 337.45805 -267.34008)
		(end 336.991198 -267.606018)
		(width 0.12954)
		(layer "F.Cu")
		(net "Net_1799")
	)
	(via
		(at 336.991198 -267.606018)
		(size 0.4064)
		(drill 0.2032)
		(layers "F.Cu" "B.Cu")
		(net "Net_1799")
	)
	(segment
		(start 337.92795 -264.910062)
		(end 337.461098 -265.176)
		(width 0.12954)
		(layer "F.Cu")
		(net "Net_1800")
	)
	(via
		(at 337.461098 -265.176)
		(size 0.4064)
		(drill 0.2032)
		(layers "F.Cu" "B.Cu")
		(net "Net_1800")
	)
	(segment
		(start 336.517996 -265.720068)
		(end 336.051144 -265.986006)
		(width 0.12954)
		(layer "F.Cu")
		(net "Net_1801")
	)
	(via
		(at 336.051144 -265.986006)
		(size 0.4064)
		(drill 0.2032)
		(layers "F.Cu" "B.Cu")
		(net "Net_1801")
	)
	(segment
		(start 336.047842 -268.150086)
		(end 335.58099 -268.416024)
		(width 0.12954)
		(layer "F.Cu")
		(net "Net_1802")
	)
	(via
		(at 335.58099 -268.416024)
		(size 0.4064)
		(drill 0.2032)
		(layers "F.Cu" "B.Cu")
		(net "Net_1802")
	)
	(segment
		(start 343.097866 -260.860032)
		(end 342.631014 -261.12597)
		(width 0.10668)
		(layer "F.Cu")
		(net "Net_1803")
	)
	(via
		(at 342.631014 -261.12597)
		(size 0.4064)
		(drill 0.2032)
		(layers "F.Cu" "B.Cu")
		(net "Net_1803")
	)
	(segment
		(start 342.627966 -261.670038)
		(end 342.161114 -261.935976)
		(width 0.10668)
		(layer "F.Cu")
		(net "Net_1804")
	)
	(via
		(at 342.161114 -261.935976)
		(size 0.4064)
		(drill 0.2032)
		(layers "F.Cu" "B.Cu")
		(net "Net_1804")
	)
	(segment
		(start 342.327992 -251.23013)
		(end 341.86114 -250.964192)
		(width 0.10668)
		(layer "F.Cu")
		(net "Net_1805")
	)
	(via
		(at 341.86114 -250.964192)
		(size 0.4064)
		(drill 0.2032)
		(layers "F.Cu" "B.Cu")
		(net "Net_1805")
	)
	(segment
		(start 343.737946 -252.040136)
		(end 343.271094 -251.774198)
		(width 0.10668)
		(layer "F.Cu")
		(net "Net_1806")
	)
	(via
		(at 343.271094 -251.774198)
		(size 0.4064)
		(drill 0.2032)
		(layers "F.Cu" "B.Cu")
		(net "Net_1806")
	)
	(segment
		(start 344.03792 -267.34008)
		(end 343.571068 -267.606018)
		(width 0.12954)
		(layer "F.Cu")
		(net "Net_1807")
	)
	(via
		(at 343.571068 -267.606018)
		(size 0.4064)
		(drill 0.2032)
		(layers "F.Cu" "B.Cu")
		(net "Net_1807")
	)
	(segment
		(start 344.508074 -264.910062)
		(end 344.041222 -265.176)
		(width 0.12954)
		(layer "F.Cu")
		(net "Net_1808")
	)
	(via
		(at 344.041222 -265.176)
		(size 0.4064)
		(drill 0.2032)
		(layers "F.Cu" "B.Cu")
		(net "Net_1808")
	)
	(segment
		(start 343.097866 -265.720068)
		(end 342.631014 -265.986006)
		(width 0.12954)
		(layer "F.Cu")
		(net "Net_1809")
	)
	(via
		(at 342.631014 -265.986006)
		(size 0.4064)
		(drill 0.2032)
		(layers "F.Cu" "B.Cu")
		(net "Net_1809")
	)
	(segment
		(start 342.627966 -268.150086)
		(end 342.161114 -268.416024)
		(width 0.12954)
		(layer "F.Cu")
		(net "Net_1810")
	)
	(via
		(at 342.161114 -268.416024)
		(size 0.4064)
		(drill 0.2032)
		(layers "F.Cu" "B.Cu")
		(net "Net_1810")
	)
	(segment
		(start 339.337904 -260.860032)
		(end 338.871052 -261.12597)
		(width 0.10668)
		(layer "F.Cu")
		(net "Net_1811")
	)
	(via
		(at 338.871052 -261.12597)
		(size 0.4064)
		(drill 0.2032)
		(layers "F.Cu" "B.Cu")
		(net "Net_1811")
	)
	(segment
		(start 339.808058 -261.670038)
		(end 339.341206 -261.935976)
		(width 0.10668)
		(layer "F.Cu")
		(net "Net_1812")
	)
	(via
		(at 339.341206 -261.935976)
		(size 0.4064)
		(drill 0.2032)
		(layers "F.Cu" "B.Cu")
		(net "Net_1812")
	)
	(segment
		(start 339.508084 -251.23013)
		(end 339.041232 -250.964192)
		(width 0.10668)
		(layer "F.Cu")
		(net "Net_1813")
	)
	(via
		(at 339.041232 -250.964192)
		(size 0.4064)
		(drill 0.2032)
		(layers "F.Cu" "B.Cu")
		(net "Net_1813")
	)
	(segment
		(start 340.918038 -252.040136)
		(end 340.451186 -251.774198)
		(width 0.10668)
		(layer "F.Cu")
		(net "Net_1814")
	)
	(via
		(at 340.451186 -251.774198)
		(size 0.4064)
		(drill 0.2032)
		(layers "F.Cu" "B.Cu")
		(net "Net_1814")
	)
	(segment
		(start 341.218012 -267.34008)
		(end 340.75116 -267.606018)
		(width 0.12954)
		(layer "F.Cu")
		(net "Net_1815")
	)
	(via
		(at 340.75116 -267.606018)
		(size 0.4064)
		(drill 0.2032)
		(layers "F.Cu" "B.Cu")
		(net "Net_1815")
	)
	(segment
		(start 340.747858 -264.910062)
		(end 340.281006 -265.176)
		(width 0.12954)
		(layer "F.Cu")
		(net "Net_1816")
	)
	(via
		(at 340.281006 -265.176)
		(size 0.4064)
		(drill 0.2032)
		(layers "F.Cu" "B.Cu")
		(net "Net_1816")
	)
	(segment
		(start 339.337904 -265.720068)
		(end 338.871052 -265.986006)
		(width 0.12954)
		(layer "F.Cu")
		(net "Net_1817")
	)
	(via
		(at 338.871052 -265.986006)
		(size 0.4064)
		(drill 0.2032)
		(layers "F.Cu" "B.Cu")
		(net "Net_1817")
	)
	(segment
		(start 339.808058 -268.150086)
		(end 339.341206 -268.416024)
		(width 0.12954)
		(layer "F.Cu")
		(net "Net_1818")
	)
	(via
		(at 339.341206 -268.416024)
		(size 0.4064)
		(drill 0.2032)
		(layers "F.Cu" "B.Cu")
		(net "Net_1818")
	)
	(segment
		(start 329.937872 -260.860032)
		(end 329.47102 -261.12597)
		(width 0.12954)
		(layer "F.Cu")
		(net "Net_1819")
	)
	(via
		(at 329.47102 -261.12597)
		(size 0.4064)
		(drill 0.2032)
		(layers "F.Cu" "B.Cu")
		(net "Net_1819")
	)
	(segment
		(start 329.467972 -261.670038)
		(end 329.00112 -261.935976)
		(width 0.12954)
		(layer "F.Cu")
		(net "Net_1820")
	)
	(via
		(at 329.00112 -261.935976)
		(size 0.4064)
		(drill 0.2032)
		(layers "F.Cu" "B.Cu")
		(net "Net_1820")
	)
	(segment
		(start 329.167998 -251.23013)
		(end 328.701146 -250.964192)
		(width 0.10668)
		(layer "F.Cu")
		(net "Net_1821")
	)
	(via
		(at 328.701146 -250.964192)
		(size 0.4064)
		(drill 0.2032)
		(layers "F.Cu" "B.Cu")
		(net "Net_1821")
	)
	(segment
		(start 330.577952 -252.040136)
		(end 330.1111 -251.774198)
		(width 0.10668)
		(layer "F.Cu")
		(net "Net_1822")
	)
	(via
		(at 330.1111 -251.774198)
		(size 0.4064)
		(drill 0.2032)
		(layers "F.Cu" "B.Cu")
		(net "Net_1822")
	)
	(segment
		(start 330.877926 -267.34008)
		(end 330.411074 -267.606018)
		(width 0.12954)
		(layer "F.Cu")
		(net "Net_1823")
	)
	(via
		(at 330.411074 -267.606018)
		(size 0.4064)
		(drill 0.2032)
		(layers "F.Cu" "B.Cu")
		(net "Net_1823")
	)
	(segment
		(start 331.34808 -264.910062)
		(end 330.881228 -265.176)
		(width 0.12954)
		(layer "F.Cu")
		(net "Net_1824")
	)
	(via
		(at 330.881228 -265.176)
		(size 0.4064)
		(drill 0.2032)
		(layers "F.Cu" "B.Cu")
		(net "Net_1824")
	)
	(segment
		(start 329.937872 -265.720068)
		(end 329.47102 -265.986006)
		(width 0.12954)
		(layer "F.Cu")
		(net "Net_1825")
	)
	(via
		(at 329.47102 -265.986006)
		(size 0.4064)
		(drill 0.2032)
		(layers "F.Cu" "B.Cu")
		(net "Net_1825")
	)
	(segment
		(start 329.467972 -268.150086)
		(end 329.00112 -268.416024)
		(width 0.12954)
		(layer "F.Cu")
		(net "Net_1826")
	)
	(via
		(at 329.00112 -268.416024)
		(size 0.4064)
		(drill 0.2032)
		(layers "F.Cu" "B.Cu")
		(net "Net_1826")
	)
	(segment
		(start 332.758034 -260.860032)
		(end 332.291182 -261.12597)
		(width 0.12954)
		(layer "F.Cu")
		(net "Net_1827")
	)
	(via
		(at 332.291182 -261.12597)
		(size 0.4064)
		(drill 0.2032)
		(layers "F.Cu" "B.Cu")
		(net "Net_1827")
	)
	(segment
		(start 333.227934 -261.670038)
		(end 332.761082 -261.935976)
		(width 0.12954)
		(layer "F.Cu")
		(net "Net_1828")
	)
	(via
		(at 332.761082 -261.935976)
		(size 0.4064)
		(drill 0.2032)
		(layers "F.Cu" "B.Cu")
		(net "Net_1828")
	)
	(segment
		(start 332.92796 -251.23013)
		(end 332.461108 -250.964192)
		(width 0.10668)
		(layer "F.Cu")
		(net "Net_1829")
	)
	(via
		(at 332.461108 -250.964192)
		(size 0.4064)
		(drill 0.2032)
		(layers "F.Cu" "B.Cu")
		(net "Net_1829")
	)
	(segment
		(start 334.337914 -252.040136)
		(end 333.871062 -251.774198)
		(width 0.10668)
		(layer "F.Cu")
		(net "Net_1830")
	)
	(via
		(at 333.871062 -251.774198)
		(size 0.4064)
		(drill 0.2032)
		(layers "F.Cu" "B.Cu")
		(net "Net_1830")
	)
	(segment
		(start 334.637888 -267.34008)
		(end 334.171036 -267.606018)
		(width 0.12954)
		(layer "F.Cu")
		(net "Net_1831")
	)
	(via
		(at 334.171036 -267.606018)
		(size 0.4064)
		(drill 0.2032)
		(layers "F.Cu" "B.Cu")
		(net "Net_1831")
	)
	(segment
		(start 334.167988 -264.910062)
		(end 333.701136 -265.176)
		(width 0.12954)
		(layer "F.Cu")
		(net "Net_1832")
	)
	(via
		(at 333.701136 -265.176)
		(size 0.4064)
		(drill 0.2032)
		(layers "F.Cu" "B.Cu")
		(net "Net_1832")
	)
	(segment
		(start 332.758034 -265.720068)
		(end 332.291182 -265.986006)
		(width 0.12954)
		(layer "F.Cu")
		(net "Net_1833")
	)
	(via
		(at 332.291182 -265.986006)
		(size 0.4064)
		(drill 0.2032)
		(layers "F.Cu" "B.Cu")
		(net "Net_1833")
	)
	(segment
		(start 333.227934 -268.150086)
		(end 332.761082 -268.416024)
		(width 0.12954)
		(layer "F.Cu")
		(net "Net_1834")
	)
	(via
		(at 332.761082 -268.416024)
		(size 0.4064)
		(drill 0.2032)
		(layers "F.Cu" "B.Cu")
		(net "Net_1834")
	)
	(segment
		(start 383.517902 -260.860032)
		(end 383.984754 -261.12597)
		(width 0.10668)
		(layer "F.Cu")
		(net "Net_1843")
	)
	(via
		(at 383.984754 -261.12597)
		(size 0.4064)
		(drill 0.2032)
		(layers "F.Cu" "B.Cu")
		(net "Net_1843")
	)
	(segment
		(start 383.988056 -261.670038)
		(end 384.454908 -261.935976)
		(width 0.10668)
		(layer "F.Cu")
		(net "Net_1844")
	)
	(via
		(at 384.454908 -261.935976)
		(size 0.4064)
		(drill 0.2032)
		(layers "F.Cu" "B.Cu")
		(net "Net_1844")
	)
	(segment
		(start 383.217928 -252.040136)
		(end 383.68478 -251.774198)
		(width 0.10668)
		(layer "F.Cu")
		(net "Net_1845")
	)
	(via
		(at 383.68478 -251.774198)
		(size 0.4064)
		(drill 0.2032)
		(layers "F.Cu" "B.Cu")
		(net "Net_1845")
	)
	(segment
		(start 381.807974 -252.850142)
		(end 382.274826 -252.584204)
		(width 0.10668)
		(layer "F.Cu")
		(net "Net_1846")
	)
	(via
		(at 382.274826 -252.584204)
		(size 0.4064)
		(drill 0.2032)
		(layers "F.Cu" "B.Cu")
		(net "Net_1846")
	)
	(segment
		(start 382.577848 -267.34008)
		(end 383.0447 -267.606018)
		(width 0.10668)
		(layer "F.Cu")
		(net "Net_1847")
	)
	(via
		(at 383.0447 -267.606018)
		(size 0.4064)
		(drill 0.2032)
		(layers "F.Cu" "B.Cu")
		(net "Net_1847")
	)
	(segment
		(start 383.988056 -264.910062)
		(end 384.454908 -265.176)
		(width 0.10668)
		(layer "F.Cu")
		(net "Net_1848")
	)
	(via
		(at 384.454908 -265.176)
		(size 0.4064)
		(drill 0.2032)
		(layers "F.Cu" "B.Cu")
		(net "Net_1848")
	)
	(segment
		(start 383.517902 -265.720068)
		(end 383.984754 -265.986006)
		(width 0.10668)
		(layer "F.Cu")
		(net "Net_1849")
	)
	(via
		(at 383.984754 -265.986006)
		(size 0.4064)
		(drill 0.2032)
		(layers "F.Cu" "B.Cu")
		(net "Net_1849")
	)
	(segment
		(start 383.988056 -268.150086)
		(end 384.454908 -268.416024)
		(width 0.10668)
		(layer "F.Cu")
		(net "Net_1850")
	)
	(via
		(at 384.454908 -268.416024)
		(size 0.4064)
		(drill 0.2032)
		(layers "F.Cu" "B.Cu")
		(net "Net_1850")
	)
	(segment
		(start 376.938032 -260.860032)
		(end 377.404884 -261.12597)
		(width 0.10668)
		(layer "F.Cu")
		(net "Net_1851")
	)
	(via
		(at 377.404884 -261.12597)
		(size 0.4064)
		(drill 0.2032)
		(layers "F.Cu" "B.Cu")
		(net "Net_1851")
	)
	(segment
		(start 377.407932 -261.670038)
		(end 377.874784 -261.935976)
		(width 0.10668)
		(layer "F.Cu")
		(net "Net_1852")
	)
	(via
		(at 377.874784 -261.935976)
		(size 0.4064)
		(drill 0.2032)
		(layers "F.Cu" "B.Cu")
		(net "Net_1852")
	)
	(segment
		(start 376.638058 -252.040136)
		(end 377.10491 -251.774198)
		(width 0.10668)
		(layer "F.Cu")
		(net "Net_1853")
	)
	(via
		(at 377.10491 -251.774198)
		(size 0.4064)
		(drill 0.2032)
		(layers "F.Cu" "B.Cu")
		(net "Net_1853")
	)
	(segment
		(start 375.22785 -252.850142)
		(end 375.694702 -252.584204)
		(width 0.10668)
		(layer "F.Cu")
		(net "Net_1854")
	)
	(via
		(at 375.694702 -252.584204)
		(size 0.4064)
		(drill 0.2032)
		(layers "F.Cu" "B.Cu")
		(net "Net_1854")
	)
	(segment
		(start 375.997978 -267.34008)
		(end 376.46483 -267.606018)
		(width 0.10668)
		(layer "F.Cu")
		(net "Net_1855")
	)
	(via
		(at 376.46483 -267.606018)
		(size 0.4064)
		(drill 0.2032)
		(layers "F.Cu" "B.Cu")
		(net "Net_1855")
	)
	(segment
		(start 377.407932 -264.910062)
		(end 377.874784 -265.176)
		(width 0.10668)
		(layer "F.Cu")
		(net "Net_1856")
	)
	(via
		(at 377.874784 -265.176)
		(size 0.4064)
		(drill 0.2032)
		(layers "F.Cu" "B.Cu")
		(net "Net_1856")
	)
	(segment
		(start 376.938032 -265.720068)
		(end 377.404884 -265.986006)
		(width 0.10668)
		(layer "F.Cu")
		(net "Net_1857")
	)
	(via
		(at 377.404884 -265.986006)
		(size 0.4064)
		(drill 0.2032)
		(layers "F.Cu" "B.Cu")
		(net "Net_1857")
	)
	(segment
		(start 377.407932 -268.150086)
		(end 377.874784 -268.416024)
		(width 0.10668)
		(layer "F.Cu")
		(net "Net_1858")
	)
	(via
		(at 377.874784 -268.416024)
		(size 0.4064)
		(drill 0.2032)
		(layers "F.Cu" "B.Cu")
		(net "Net_1858")
	)
	(segment
		(start 380.697994 -260.860032)
		(end 381.164846 -261.12597)
		(width 0.10668)
		(layer "F.Cu")
		(net "Net_1859")
	)
	(via
		(at 381.164846 -261.12597)
		(size 0.4064)
		(drill 0.2032)
		(layers "F.Cu" "B.Cu")
		(net "Net_1859")
	)
	(segment
		(start 380.22784 -261.670038)
		(end 380.694692 -261.935976)
		(width 0.10668)
		(layer "F.Cu")
		(net "Net_1860")
	)
	(via
		(at 380.694692 -261.935976)
		(size 0.4064)
		(drill 0.2032)
		(layers "F.Cu" "B.Cu")
		(net "Net_1860")
	)
	(segment
		(start 380.39802 -252.040136)
		(end 380.864872 -251.774198)
		(width 0.10668)
		(layer "F.Cu")
		(net "Net_1861")
	)
	(via
		(at 380.864872 -251.774198)
		(size 0.4064)
		(drill 0.2032)
		(layers "F.Cu" "B.Cu")
		(net "Net_1861")
	)
	(segment
		(start 378.988066 -252.850142)
		(end 379.454918 -252.584204)
		(width 0.10668)
		(layer "F.Cu")
		(net "Net_1862")
	)
	(via
		(at 379.454918 -252.584204)
		(size 0.4064)
		(drill 0.2032)
		(layers "F.Cu" "B.Cu")
		(net "Net_1862")
	)
	(segment
		(start 378.817886 -267.34008)
		(end 379.284738 -267.606018)
		(width 0.10668)
		(layer "F.Cu")
		(net "Net_1863")
	)
	(via
		(at 379.284738 -267.606018)
		(size 0.4064)
		(drill 0.2032)
		(layers "F.Cu" "B.Cu")
		(net "Net_1863")
	)
	(segment
		(start 380.22784 -264.910062)
		(end 380.694692 -265.176)
		(width 0.10668)
		(layer "F.Cu")
		(net "Net_1864")
	)
	(via
		(at 380.694692 -265.176)
		(size 0.4064)
		(drill 0.2032)
		(layers "F.Cu" "B.Cu")
		(net "Net_1864")
	)
	(segment
		(start 380.697994 -265.720068)
		(end 381.164846 -265.986006)
		(width 0.10668)
		(layer "F.Cu")
		(net "Net_1865")
	)
	(via
		(at 381.164846 -265.986006)
		(size 0.4064)
		(drill 0.2032)
		(layers "F.Cu" "B.Cu")
		(net "Net_1865")
	)
	(segment
		(start 380.22784 -268.150086)
		(end 380.694692 -268.416024)
		(width 0.10668)
		(layer "F.Cu")
		(net "Net_1866")
	)
	(via
		(at 380.694692 -268.416024)
		(size 0.4064)
		(drill 0.2032)
		(layers "F.Cu" "B.Cu")
		(net "Net_1866")
	)
	(segment
		(start 357.36784 -225.310192)
		(end 356.901242 -225.044254)
		(width 0.12954)
		(layer "F.Cu")
		(net "Net_1867")
	)
	(via
		(at 356.901242 -225.044254)
		(size 0.4064)
		(drill 0.2032)
		(layers "F.Cu" "B.Cu")
		(net "Net_1867")
	)
	(segment
		(start 358.307894 -225.310192)
		(end 357.841296 -225.044254)
		(width 0.12954)
		(layer "F.Cu")
		(net "Net_1868")
	)
	(via
		(at 357.841296 -225.044254)
		(size 0.4064)
		(drill 0.2032)
		(layers "F.Cu" "B.Cu")
		(net "Net_1868")
	)
	(segment
		(start 356.42804 -223.69018)
		(end 355.961442 -223.424242)
		(width 0.12954)
		(layer "F.Cu")
		(net "Net_1869")
	)
	(via
		(at 355.961442 -223.424242)
		(size 0.4064)
		(drill 0.2032)
		(layers "F.Cu" "B.Cu")
		(net "Net_1869")
	)
	(segment
		(start 357.36784 -223.69018)
		(end 356.901242 -223.424242)
		(width 0.12954)
		(layer "F.Cu")
		(net "Net_1870")
	)
	(via
		(at 356.901242 -223.424242)
		(size 0.4064)
		(drill 0.2032)
		(layers "F.Cu" "B.Cu")
		(net "Net_1870")
	)
	(segment
		(start 372.874794 -225.044254)
		(end 372.407942 -225.310192)
		(width 0.1524)
		(layer "F.Cu")
		(net "Net_1883")
	)
	(via
		(at 372.874794 -225.044254)
		(size 0.4064)
		(drill 0.2032)
		(layers "F.Cu" "B.Cu")
		(net "Net_1883")
	)
	(segment
		(start 358.607868 -294.070024)
		(end 358.141016 -294.335962)
		(width 0.10668)
		(layer "F.Cu")
		(net "Net_1888")
	)
	(via
		(at 358.141016 -294.335962)
		(size 0.4064)
		(drill 0.2032)
		(layers "F.Cu" "B.Cu")
		(net "Net_1888")
	)
	(segment
		(start 334.637888 -294.88003)
		(end 334.171036 -295.145968)
		(width 0.12954)
		(layer "F.Cu")
		(net "Net_1889")
	)
	(via
		(at 334.171036 -295.145968)
		(size 0.4064)
		(drill 0.2032)
		(layers "F.Cu" "B.Cu")
		(net "Net_1889")
	)
	(segment
		(start 335.108042 -295.690036)
		(end 334.64119 -295.955974)
		(width 0.12954)
		(layer "F.Cu")
		(net "Net_1890")
	)
	(via
		(at 334.64119 -295.955974)
		(size 0.4064)
		(drill 0.2032)
		(layers "F.Cu" "B.Cu")
		(net "Net_1890")
	)
	(segment
		(start 331.34808 -295.690036)
		(end 330.881228 -295.955974)
		(width 0.12954)
		(layer "F.Cu")
		(net "Net_1891")
	)
	(via
		(at 330.881228 -295.955974)
		(size 0.4064)
		(drill 0.2032)
		(layers "F.Cu" "B.Cu")
		(net "Net_1891")
	)
	(segment
		(start 330.877926 -294.88003)
		(end 330.411074 -295.145968)
		(width 0.12954)
		(layer "F.Cu")
		(net "Net_1892")
	)
	(via
		(at 330.411074 -295.145968)
		(size 0.4064)
		(drill 0.2032)
		(layers "F.Cu" "B.Cu")
		(net "Net_1892")
	)
	(segment
		(start 341.218012 -294.88003)
		(end 340.75116 -295.145968)
		(width 0.12954)
		(layer "F.Cu")
		(net "Net_1896")
	)
	(via
		(at 340.75116 -295.145968)
		(size 0.4064)
		(drill 0.2032)
		(layers "F.Cu" "B.Cu")
		(net "Net_1896")
	)
	(segment
		(start 341.687912 -294.070024)
		(end 341.22106 -294.335962)
		(width 0.12954)
		(layer "F.Cu")
		(net "Net_1897")
	)
	(via
		(at 341.22106 -294.335962)
		(size 0.4064)
		(drill 0.2032)
		(layers "F.Cu" "B.Cu")
		(net "Net_1897")
	)
	(segment
		(start 385.098036 -256.900172)
		(end 385.564888 -256.634234)
		(width 0.10668)
		(layer "F.Cu")
		(net "Net_1913")
	)
	(via
		(at 385.564888 -256.634234)
		(size 0.4064)
		(drill 0.2032)
		(layers "F.Cu" "B.Cu")
		(net "Net_1913")
	)
	(segment
		(start 382.277874 -256.900172)
		(end 382.744726 -256.634234)
		(width 0.10668)
		(layer "F.Cu")
		(net "Net_1914")
	)
	(via
		(at 382.744726 -256.634234)
		(size 0.4064)
		(drill 0.2032)
		(layers "F.Cu" "B.Cu")
		(net "Net_1914")
	)
	(segment
		(start 378.517912 -256.900172)
		(end 378.984764 -256.634234)
		(width 0.10668)
		(layer "F.Cu")
		(net "Net_1915")
	)
	(via
		(at 378.984764 -256.634234)
		(size 0.4064)
		(drill 0.2032)
		(layers "F.Cu" "B.Cu")
		(net "Net_1915")
	)
	(segment
		(start 375.698004 -256.900172)
		(end 376.164856 -256.634234)
		(width 0.10668)
		(layer "F.Cu")
		(net "Net_1916")
	)
	(via
		(at 376.164856 -256.634234)
		(size 0.4064)
		(drill 0.2032)
		(layers "F.Cu" "B.Cu")
		(net "Net_1916")
	)
	(segment
		(start 391.677906 -256.900172)
		(end 392.144758 -256.634234)
		(width 0.10668)
		(layer "F.Cu")
		(net "Net_1917")
	)
	(via
		(at 392.144758 -256.634234)
		(size 0.4064)
		(drill 0.2032)
		(layers "F.Cu" "B.Cu")
		(net "Net_1917")
	)
	(segment
		(start 343.737946 -256.900172)
		(end 343.271094 -256.634234)
		(width 0.14732)
		(layer "F.Cu")
		(net "Net_1918")
	)
	(via
		(at 343.271094 -256.634234)
		(size 0.4064)
		(drill 0.2032)
		(layers "F.Cu" "B.Cu")
		(net "Net_1918")
	)
	(segment
		(start 340.918038 -256.900172)
		(end 340.451186 -256.634234)
		(width 0.14732)
		(layer "F.Cu")
		(net "Net_1919")
	)
	(via
		(at 340.451186 -256.634234)
		(size 0.4064)
		(drill 0.2032)
		(layers "F.Cu" "B.Cu")
		(net "Net_1919")
	)
	(segment
		(start 337.158076 -256.900172)
		(end 336.691224 -256.634234)
		(width 0.14732)
		(layer "F.Cu")
		(net "Net_1920")
	)
	(via
		(at 336.691224 -256.634234)
		(size 0.4064)
		(drill 0.2032)
		(layers "F.Cu" "B.Cu")
		(net "Net_1920")
	)
	(segment
		(start 334.337914 -256.900172)
		(end 333.871062 -256.634234)
		(width 0.14732)
		(layer "F.Cu")
		(net "Net_1921")
	)
	(via
		(at 333.871062 -256.634234)
		(size 0.4064)
		(drill 0.2032)
		(layers "F.Cu" "B.Cu")
		(net "Net_1921")
	)
	(segment
		(start 330.577952 -256.900172)
		(end 330.1111 -256.634234)
		(width 0.14732)
		(layer "F.Cu")
		(net "Net_1922")
	)
	(via
		(at 330.1111 -256.634234)
		(size 0.4064)
		(drill 0.2032)
		(layers "F.Cu" "B.Cu")
		(net "Net_1922")
	)
	(segment
		(start 388.857998 -256.900172)
		(end 389.32485 -256.634234)
		(width 0.10668)
		(layer "F.Cu")
		(net "Net_1923")
	)
	(via
		(at 389.32485 -256.634234)
		(size 0.4064)
		(drill 0.2032)
		(layers "F.Cu" "B.Cu")
		(net "Net_1923")
	)
	(segment
		(start 327.758044 -256.900172)
		(end 327.291192 -256.634234)
		(width 0.14732)
		(layer "F.Cu")
		(net "Net_1924")
	)
	(via
		(at 327.291192 -256.634234)
		(size 0.4064)
		(drill 0.2032)
		(layers "F.Cu" "B.Cu")
		(net "Net_1924")
	)
	(segment
		(start 387.277864 -260.860032)
		(end 387.744716 -261.12597)
		(width 0.10668)
		(layer "F.Cu")
		(net "Net_1956")
	)
	(via
		(at 387.744716 -261.12597)
		(size 0.4064)
		(drill 0.2032)
		(layers "F.Cu" "B.Cu")
		(net "Net_1956")
	)
	(segment
		(start 386.807964 -261.670038)
		(end 387.274816 -261.935976)
		(width 0.10668)
		(layer "F.Cu")
		(net "Net_1957")
	)
	(via
		(at 387.274816 -261.935976)
		(size 0.4064)
		(drill 0.2032)
		(layers "F.Cu" "B.Cu")
		(net "Net_1957")
	)
	(segment
		(start 386.97789 -252.040136)
		(end 387.444742 -251.774198)
		(width 0.10668)
		(layer "F.Cu")
		(net "Net_1958")
	)
	(via
		(at 387.444742 -251.774198)
		(size 0.4064)
		(drill 0.2032)
		(layers "F.Cu" "B.Cu")
		(net "Net_1958")
	)
	(segment
		(start 385.567936 -252.850142)
		(end 386.034788 -252.584204)
		(width 0.10668)
		(layer "F.Cu")
		(net "Net_1959")
	)
	(via
		(at 386.034788 -252.584204)
		(size 0.4064)
		(drill 0.2032)
		(layers "F.Cu" "B.Cu")
		(net "Net_1959")
	)
	(segment
		(start 385.39801 -267.34008)
		(end 385.864862 -267.606018)
		(width 0.10668)
		(layer "F.Cu")
		(net "Net_1960")
	)
	(via
		(at 385.864862 -267.606018)
		(size 0.4064)
		(drill 0.2032)
		(layers "F.Cu" "B.Cu")
		(net "Net_1960")
	)
	(segment
		(start 386.807964 -264.910062)
		(end 387.274816 -265.176)
		(width 0.10668)
		(layer "F.Cu")
		(net "Net_1961")
	)
	(via
		(at 387.274816 -265.176)
		(size 0.4064)
		(drill 0.2032)
		(layers "F.Cu" "B.Cu")
		(net "Net_1961")
	)
	(segment
		(start 387.277864 -265.720068)
		(end 387.744716 -265.986006)
		(width 0.10668)
		(layer "F.Cu")
		(net "Net_1962")
	)
	(via
		(at 387.744716 -265.986006)
		(size 0.4064)
		(drill 0.2032)
		(layers "F.Cu" "B.Cu")
		(net "Net_1962")
	)
	(segment
		(start 386.807964 -268.150086)
		(end 387.274816 -268.416024)
		(width 0.10668)
		(layer "F.Cu")
		(net "Net_1963")
	)
	(via
		(at 387.274816 -268.416024)
		(size 0.4064)
		(drill 0.2032)
		(layers "F.Cu" "B.Cu")
		(net "Net_1963")
	)
	(segment
		(start 390.098026 -260.860032)
		(end 390.564878 -261.12597)
		(width 0.10668)
		(layer "F.Cu")
		(net "Net_1964")
	)
	(via
		(at 390.564878 -261.12597)
		(size 0.4064)
		(drill 0.2032)
		(layers "F.Cu" "B.Cu")
		(net "Net_1964")
	)
	(segment
		(start 390.567926 -261.670038)
		(end 391.034778 -261.935976)
		(width 0.10668)
		(layer "F.Cu")
		(net "Net_1965")
	)
	(via
		(at 391.034778 -261.935976)
		(size 0.4064)
		(drill 0.2032)
		(layers "F.Cu" "B.Cu")
		(net "Net_1965")
	)
	(segment
		(start 389.798052 -252.040136)
		(end 390.264904 -251.774198)
		(width 0.10668)
		(layer "F.Cu")
		(net "Net_1966")
	)
	(via
		(at 390.264904 -251.774198)
		(size 0.4064)
		(drill 0.2032)
		(layers "F.Cu" "B.Cu")
		(net "Net_1966")
	)
	(segment
		(start 388.387844 -252.850142)
		(end 388.854696 -252.584204)
		(width 0.10668)
		(layer "F.Cu")
		(net "Net_1967")
	)
	(via
		(at 388.854696 -252.584204)
		(size 0.4064)
		(drill 0.2032)
		(layers "F.Cu" "B.Cu")
		(net "Net_1967")
	)
	(segment
		(start 389.157972 -267.34008)
		(end 389.624824 -267.606018)
		(width 0.10668)
		(layer "F.Cu")
		(net "Net_1968")
	)
	(via
		(at 389.624824 -267.606018)
		(size 0.4064)
		(drill 0.2032)
		(layers "F.Cu" "B.Cu")
		(net "Net_1968")
	)
	(segment
		(start 390.567926 -264.910062)
		(end 391.034778 -265.176)
		(width 0.10668)
		(layer "F.Cu")
		(net "Net_1969")
	)
	(via
		(at 391.034778 -265.176)
		(size 0.4064)
		(drill 0.2032)
		(layers "F.Cu" "B.Cu")
		(net "Net_1969")
	)
	(segment
		(start 390.098026 -265.720068)
		(end 390.564878 -265.986006)
		(width 0.10668)
		(layer "F.Cu")
		(net "Net_1970")
	)
	(via
		(at 390.564878 -265.986006)
		(size 0.4064)
		(drill 0.2032)
		(layers "F.Cu" "B.Cu")
		(net "Net_1970")
	)
	(segment
		(start 390.567926 -268.150086)
		(end 391.034778 -268.416024)
		(width 0.10668)
		(layer "F.Cu")
		(net "Net_1971")
	)
	(via
		(at 391.034778 -268.416024)
		(size 0.4064)
		(drill 0.2032)
		(layers "F.Cu" "B.Cu")
		(net "Net_1971")
	)
	(segment
		(start 88.577928 -260.860286)
		(end 88.111076 -261.126224)
		(width 0.10668)
		(layer "F.Cu")
		(net "Net_1998")
	)
	(via
		(at 88.111076 -261.126224)
		(size 0.4064)
		(drill 0.2032)
		(layers "F.Cu" "B.Cu")
		(net "Net_1998")
	)
	(segment
		(start 88.107774 -261.670292)
		(end 87.640922 -261.93623)
		(width 0.10668)
		(layer "F.Cu")
		(net "Net_1999")
	)
	(via
		(at 87.640922 -261.93623)
		(size 0.4064)
		(drill 0.2032)
		(layers "F.Cu" "B.Cu")
		(net "Net_1999")
	)
	(segment
		(start 87.8078 -251.230384)
		(end 87.340948 -250.964446)
		(width 0.10668)
		(layer "F.Cu")
		(net "Net_2000")
	)
	(via
		(at 87.340948 -250.964446)
		(size 0.4064)
		(drill 0.2032)
		(layers "F.Cu" "B.Cu")
		(net "Net_2000")
	)
	(segment
		(start 89.218008 -252.04039)
		(end 88.751156 -251.774452)
		(width 0.10668)
		(layer "F.Cu")
		(net "Net_2001")
	)
	(via
		(at 88.751156 -251.774452)
		(size 0.4064)
		(drill 0.2032)
		(layers "F.Cu" "B.Cu")
		(net "Net_2001")
	)
	(segment
		(start 89.517982 -267.340334)
		(end 89.05113 -267.606272)
		(width 0.10668)
		(layer "F.Cu")
		(net "Net_2002")
	)
	(via
		(at 89.05113 -267.606272)
		(size 0.4064)
		(drill 0.2032)
		(layers "F.Cu" "B.Cu")
		(net "Net_2002")
	)
	(segment
		(start 89.987882 -264.910316)
		(end 89.52103 -265.176254)
		(width 0.10668)
		(layer "F.Cu")
		(net "Net_2003")
	)
	(via
		(at 89.52103 -265.176254)
		(size 0.4064)
		(drill 0.2032)
		(layers "F.Cu" "B.Cu")
		(net "Net_2003")
	)
	(segment
		(start 88.577928 -265.720322)
		(end 88.111076 -265.98626)
		(width 0.10668)
		(layer "F.Cu")
		(net "Net_2004")
	)
	(via
		(at 88.111076 -265.98626)
		(size 0.4064)
		(drill 0.2032)
		(layers "F.Cu" "B.Cu")
		(net "Net_2004")
	)
	(segment
		(start 88.107774 -268.15034)
		(end 87.640922 -268.416278)
		(width 0.10668)
		(layer "F.Cu")
		(net "Net_2005")
	)
	(via
		(at 87.640922 -268.416278)
		(size 0.4064)
		(drill 0.2032)
		(layers "F.Cu" "B.Cu")
		(net "Net_2005")
	)
	(segment
		(start 95.157798 -260.860286)
		(end 94.690946 -261.126224)
		(width 0.10668)
		(layer "F.Cu")
		(net "Net_2006")
	)
	(via
		(at 94.690946 -261.126224)
		(size 0.4064)
		(drill 0.2032)
		(layers "F.Cu" "B.Cu")
		(net "Net_2006")
	)
	(segment
		(start 94.687898 -261.670292)
		(end 94.221046 -261.93623)
		(width 0.10668)
		(layer "F.Cu")
		(net "Net_2007")
	)
	(via
		(at 94.221046 -261.93623)
		(size 0.4064)
		(drill 0.2032)
		(layers "F.Cu" "B.Cu")
		(net "Net_2007")
	)
	(segment
		(start 94.387924 -251.230384)
		(end 93.921072 -250.964446)
		(width 0.10668)
		(layer "F.Cu")
		(net "Net_2008")
	)
	(via
		(at 93.921072 -250.964446)
		(size 0.4064)
		(drill 0.2032)
		(layers "F.Cu" "B.Cu")
		(net "Net_2008")
	)
	(segment
		(start 95.797878 -252.04039)
		(end 95.331026 -251.774452)
		(width 0.10668)
		(layer "F.Cu")
		(net "Net_2009")
	)
	(via
		(at 95.331026 -251.774452)
		(size 0.4064)
		(drill 0.2032)
		(layers "F.Cu" "B.Cu")
		(net "Net_2009")
	)
	(segment
		(start 96.097852 -267.340334)
		(end 95.631 -267.606272)
		(width 0.10668)
		(layer "F.Cu")
		(net "Net_2010")
	)
	(via
		(at 95.631 -267.606272)
		(size 0.4064)
		(drill 0.2032)
		(layers "F.Cu" "B.Cu")
		(net "Net_2010")
	)
	(segment
		(start 96.568006 -264.910316)
		(end 96.101154 -265.176254)
		(width 0.10668)
		(layer "F.Cu")
		(net "Net_2011")
	)
	(via
		(at 96.101154 -265.176254)
		(size 0.4064)
		(drill 0.2032)
		(layers "F.Cu" "B.Cu")
		(net "Net_2011")
	)
	(segment
		(start 95.157798 -265.720322)
		(end 94.690946 -265.98626)
		(width 0.10668)
		(layer "F.Cu")
		(net "Net_2012")
	)
	(via
		(at 94.690946 -265.98626)
		(size 0.4064)
		(drill 0.2032)
		(layers "F.Cu" "B.Cu")
		(net "Net_2012")
	)
	(segment
		(start 94.687898 -268.15034)
		(end 94.221046 -268.416278)
		(width 0.10668)
		(layer "F.Cu")
		(net "Net_2013")
	)
	(via
		(at 94.221046 -268.416278)
		(size 0.4064)
		(drill 0.2032)
		(layers "F.Cu" "B.Cu")
		(net "Net_2013")
	)
	(segment
		(start 91.397836 -260.860286)
		(end 90.930984 -261.126224)
		(width 0.10668)
		(layer "F.Cu")
		(net "Net_2014")
	)
	(via
		(at 90.930984 -261.126224)
		(size 0.4064)
		(drill 0.2032)
		(layers "F.Cu" "B.Cu")
		(net "Net_2014")
	)
	(segment
		(start 91.86799 -261.670292)
		(end 91.401138 -261.93623)
		(width 0.10668)
		(layer "F.Cu")
		(net "Net_2015")
	)
	(via
		(at 91.401138 -261.93623)
		(size 0.4064)
		(drill 0.2032)
		(layers "F.Cu" "B.Cu")
		(net "Net_2015")
	)
	(segment
		(start 91.568016 -251.230384)
		(end 91.101164 -250.964446)
		(width 0.10668)
		(layer "F.Cu")
		(net "Net_2016")
	)
	(via
		(at 91.101164 -250.964446)
		(size 0.4064)
		(drill 0.2032)
		(layers "F.Cu" "B.Cu")
		(net "Net_2016")
	)
	(segment
		(start 92.97797 -252.04039)
		(end 92.511118 -251.774452)
		(width 0.10668)
		(layer "F.Cu")
		(net "Net_2017")
	)
	(via
		(at 92.511118 -251.774452)
		(size 0.4064)
		(drill 0.2032)
		(layers "F.Cu" "B.Cu")
		(net "Net_2017")
	)
	(segment
		(start 93.277944 -267.340334)
		(end 92.811092 -267.606272)
		(width 0.10668)
		(layer "F.Cu")
		(net "Net_2018")
	)
	(via
		(at 92.811092 -267.606272)
		(size 0.4064)
		(drill 0.2032)
		(layers "F.Cu" "B.Cu")
		(net "Net_2018")
	)
	(segment
		(start 92.80779 -264.910316)
		(end 92.340938 -265.176254)
		(width 0.10668)
		(layer "F.Cu")
		(net "Net_2019")
	)
	(via
		(at 92.340938 -265.176254)
		(size 0.4064)
		(drill 0.2032)
		(layers "F.Cu" "B.Cu")
		(net "Net_2019")
	)
	(segment
		(start 91.397836 -265.720322)
		(end 90.930984 -265.98626)
		(width 0.10668)
		(layer "F.Cu")
		(net "Net_2020")
	)
	(via
		(at 90.930984 -265.98626)
		(size 0.4064)
		(drill 0.2032)
		(layers "F.Cu" "B.Cu")
		(net "Net_2020")
	)
	(segment
		(start 91.86799 -268.15034)
		(end 91.401138 -268.416278)
		(width 0.10668)
		(layer "F.Cu")
		(net "Net_2021")
	)
	(via
		(at 91.401138 -268.416278)
		(size 0.4064)
		(drill 0.2032)
		(layers "F.Cu" "B.Cu")
		(net "Net_2021")
	)
	(segment
		(start 81.997804 -260.860286)
		(end 81.530952 -261.126224)
		(width 0.10668)
		(layer "F.Cu")
		(net "Net_2022")
	)
	(via
		(at 81.530952 -261.126224)
		(size 0.4064)
		(drill 0.2032)
		(layers "F.Cu" "B.Cu")
		(net "Net_2022")
	)
	(segment
		(start 81.527904 -261.670292)
		(end 81.061052 -261.93623)
		(width 0.10668)
		(layer "F.Cu")
		(net "Net_2023")
	)
	(via
		(at 81.061052 -261.93623)
		(size 0.4064)
		(drill 0.2032)
		(layers "F.Cu" "B.Cu")
		(net "Net_2023")
	)
	(segment
		(start 81.22793 -251.230384)
		(end 80.761078 -250.964446)
		(width 0.10668)
		(layer "F.Cu")
		(net "Net_2024")
	)
	(via
		(at 80.761078 -250.964446)
		(size 0.4064)
		(drill 0.2032)
		(layers "F.Cu" "B.Cu")
		(net "Net_2024")
	)
	(segment
		(start 82.637884 -252.04039)
		(end 82.171032 -251.774452)
		(width 0.10668)
		(layer "F.Cu")
		(net "Net_2025")
	)
	(via
		(at 82.171032 -251.774452)
		(size 0.4064)
		(drill 0.2032)
		(layers "F.Cu" "B.Cu")
		(net "Net_2025")
	)
	(segment
		(start 82.937858 -267.340334)
		(end 82.471006 -267.606272)
		(width 0.10668)
		(layer "F.Cu")
		(net "Net_2026")
	)
	(via
		(at 82.471006 -267.606272)
		(size 0.4064)
		(drill 0.2032)
		(layers "F.Cu" "B.Cu")
		(net "Net_2026")
	)
	(segment
		(start 83.408012 -264.910316)
		(end 82.94116 -265.176254)
		(width 0.10668)
		(layer "F.Cu")
		(net "Net_2027")
	)
	(via
		(at 82.94116 -265.176254)
		(size 0.4064)
		(drill 0.2032)
		(layers "F.Cu" "B.Cu")
		(net "Net_2027")
	)
	(segment
		(start 81.997804 -265.720322)
		(end 81.530952 -265.98626)
		(width 0.10668)
		(layer "F.Cu")
		(net "Net_2028")
	)
	(via
		(at 81.530952 -265.98626)
		(size 0.4064)
		(drill 0.2032)
		(layers "F.Cu" "B.Cu")
		(net "Net_2028")
	)
	(segment
		(start 81.527904 -268.15034)
		(end 81.061052 -268.416278)
		(width 0.10668)
		(layer "F.Cu")
		(net "Net_2029")
	)
	(via
		(at 81.061052 -268.416278)
		(size 0.4064)
		(drill 0.2032)
		(layers "F.Cu" "B.Cu")
		(net "Net_2029")
	)
	(segment
		(start 84.817966 -260.860286)
		(end 84.351114 -261.126224)
		(width 0.10668)
		(layer "F.Cu")
		(net "Net_2030")
	)
	(via
		(at 84.351114 -261.126224)
		(size 0.4064)
		(drill 0.2032)
		(layers "F.Cu" "B.Cu")
		(net "Net_2030")
	)
	(segment
		(start 85.287866 -261.670292)
		(end 84.821014 -261.93623)
		(width 0.10668)
		(layer "F.Cu")
		(net "Net_2031")
	)
	(via
		(at 84.821014 -261.93623)
		(size 0.4064)
		(drill 0.2032)
		(layers "F.Cu" "B.Cu")
		(net "Net_2031")
	)
	(segment
		(start 84.987892 -251.230384)
		(end 84.52104 -250.964446)
		(width 0.10668)
		(layer "F.Cu")
		(net "Net_2032")
	)
	(via
		(at 84.52104 -250.964446)
		(size 0.4064)
		(drill 0.2032)
		(layers "F.Cu" "B.Cu")
		(net "Net_2032")
	)
	(segment
		(start 86.397846 -252.04039)
		(end 85.930994 -251.774452)
		(width 0.10668)
		(layer "F.Cu")
		(net "Net_2033")
	)
	(via
		(at 85.930994 -251.774452)
		(size 0.4064)
		(drill 0.2032)
		(layers "F.Cu" "B.Cu")
		(net "Net_2033")
	)
	(segment
		(start 86.69782 -267.340334)
		(end 86.230968 -267.606272)
		(width 0.10668)
		(layer "F.Cu")
		(net "Net_2034")
	)
	(via
		(at 86.230968 -267.606272)
		(size 0.4064)
		(drill 0.2032)
		(layers "F.Cu" "B.Cu")
		(net "Net_2034")
	)
	(segment
		(start 86.22792 -264.910316)
		(end 85.761068 -265.176254)
		(width 0.10668)
		(layer "F.Cu")
		(net "Net_2035")
	)
	(via
		(at 85.761068 -265.176254)
		(size 0.4064)
		(drill 0.2032)
		(layers "F.Cu" "B.Cu")
		(net "Net_2035")
	)
	(segment
		(start 84.817966 -265.720322)
		(end 84.351114 -265.98626)
		(width 0.10668)
		(layer "F.Cu")
		(net "Net_2036")
	)
	(via
		(at 84.351114 -265.98626)
		(size 0.4064)
		(drill 0.2032)
		(layers "F.Cu" "B.Cu")
		(net "Net_2036")
	)
	(segment
		(start 85.287866 -268.15034)
		(end 84.821014 -268.416278)
		(width 0.10668)
		(layer "F.Cu")
		(net "Net_2037")
	)
	(via
		(at 84.821014 -268.416278)
		(size 0.4064)
		(drill 0.2032)
		(layers "F.Cu" "B.Cu")
		(net "Net_2037")
	)
	(segment
		(start 135.577834 -260.860286)
		(end 136.044686 -261.126224)
		(width 0.10668)
		(layer "F.Cu")
		(net "Net_2046")
	)
	(via
		(at 136.044686 -261.126224)
		(size 0.4064)
		(drill 0.2032)
		(layers "F.Cu" "B.Cu")
		(net "Net_2046")
	)
	(segment
		(start 136.047988 -261.670292)
		(end 136.51484 -261.93623)
		(width 0.10668)
		(layer "F.Cu")
		(net "Net_2047")
	)
	(via
		(at 136.51484 -261.93623)
		(size 0.4064)
		(drill 0.2032)
		(layers "F.Cu" "B.Cu")
		(net "Net_2047")
	)
	(segment
		(start 135.27786 -252.04039)
		(end 135.744712 -251.774452)
		(width 0.10668)
		(layer "F.Cu")
		(net "Net_2048")
	)
	(via
		(at 135.744712 -251.774452)
		(size 0.4064)
		(drill 0.2032)
		(layers "F.Cu" "B.Cu")
		(net "Net_2048")
	)
	(segment
		(start 133.867906 -252.850396)
		(end 134.334758 -252.584458)
		(width 0.10668)
		(layer "F.Cu")
		(net "Net_2049")
	)
	(via
		(at 134.334758 -252.584458)
		(size 0.4064)
		(drill 0.2032)
		(layers "F.Cu" "B.Cu")
		(net "Net_2049")
	)
	(segment
		(start 134.63778 -267.340334)
		(end 135.104632 -267.606272)
		(width 0.10668)
		(layer "F.Cu")
		(net "Net_2050")
	)
	(via
		(at 135.104632 -267.606272)
		(size 0.4064)
		(drill 0.2032)
		(layers "F.Cu" "B.Cu")
		(net "Net_2050")
	)
	(segment
		(start 136.047988 -264.910316)
		(end 136.51484 -265.176254)
		(width 0.10668)
		(layer "F.Cu")
		(net "Net_2051")
	)
	(via
		(at 136.51484 -265.176254)
		(size 0.4064)
		(drill 0.2032)
		(layers "F.Cu" "B.Cu")
		(net "Net_2051")
	)
	(segment
		(start 135.577834 -265.720322)
		(end 136.044686 -265.98626)
		(width 0.10668)
		(layer "F.Cu")
		(net "Net_2052")
	)
	(via
		(at 136.044686 -265.98626)
		(size 0.4064)
		(drill 0.2032)
		(layers "F.Cu" "B.Cu")
		(net "Net_2052")
	)
	(segment
		(start 136.047988 -268.15034)
		(end 136.51484 -268.416278)
		(width 0.10668)
		(layer "F.Cu")
		(net "Net_2053")
	)
	(via
		(at 136.51484 -268.416278)
		(size 0.4064)
		(drill 0.2032)
		(layers "F.Cu" "B.Cu")
		(net "Net_2053")
	)
	(segment
		(start 128.997964 -260.860286)
		(end 129.464816 -261.126224)
		(width 0.10668)
		(layer "F.Cu")
		(net "Net_2054")
	)
	(via
		(at 129.464816 -261.126224)
		(size 0.4064)
		(drill 0.2032)
		(layers "F.Cu" "B.Cu")
		(net "Net_2054")
	)
	(segment
		(start 129.467864 -261.670292)
		(end 129.934716 -261.93623)
		(width 0.10668)
		(layer "F.Cu")
		(net "Net_2055")
	)
	(via
		(at 129.934716 -261.93623)
		(size 0.4064)
		(drill 0.2032)
		(layers "F.Cu" "B.Cu")
		(net "Net_2055")
	)
	(segment
		(start 128.69799 -252.04039)
		(end 129.164842 -251.774452)
		(width 0.10668)
		(layer "F.Cu")
		(net "Net_2056")
	)
	(via
		(at 129.164842 -251.774452)
		(size 0.4064)
		(drill 0.2032)
		(layers "F.Cu" "B.Cu")
		(net "Net_2056")
	)
	(segment
		(start 127.287782 -252.850396)
		(end 127.754634 -252.584458)
		(width 0.10668)
		(layer "F.Cu")
		(net "Net_2057")
	)
	(via
		(at 127.754634 -252.584458)
		(size 0.4064)
		(drill 0.2032)
		(layers "F.Cu" "B.Cu")
		(net "Net_2057")
	)
	(segment
		(start 128.05791 -267.340334)
		(end 128.524762 -267.606272)
		(width 0.10668)
		(layer "F.Cu")
		(net "Net_2058")
	)
	(via
		(at 128.524762 -267.606272)
		(size 0.4064)
		(drill 0.2032)
		(layers "F.Cu" "B.Cu")
		(net "Net_2058")
	)
	(segment
		(start 129.467864 -264.910316)
		(end 129.934716 -265.176254)
		(width 0.10668)
		(layer "F.Cu")
		(net "Net_2059")
	)
	(via
		(at 129.934716 -265.176254)
		(size 0.4064)
		(drill 0.2032)
		(layers "F.Cu" "B.Cu")
		(net "Net_2059")
	)
	(segment
		(start 128.997964 -265.720322)
		(end 129.464816 -265.98626)
		(width 0.10668)
		(layer "F.Cu")
		(net "Net_2060")
	)
	(via
		(at 129.464816 -265.98626)
		(size 0.4064)
		(drill 0.2032)
		(layers "F.Cu" "B.Cu")
		(net "Net_2060")
	)
	(segment
		(start 129.467864 -268.15034)
		(end 129.934716 -268.416278)
		(width 0.10668)
		(layer "F.Cu")
		(net "Net_2061")
	)
	(via
		(at 129.934716 -268.416278)
		(size 0.4064)
		(drill 0.2032)
		(layers "F.Cu" "B.Cu")
		(net "Net_2061")
	)
	(segment
		(start 132.757926 -260.860286)
		(end 133.224778 -261.126224)
		(width 0.10668)
		(layer "F.Cu")
		(net "Net_2062")
	)
	(via
		(at 133.224778 -261.126224)
		(size 0.4064)
		(drill 0.2032)
		(layers "F.Cu" "B.Cu")
		(net "Net_2062")
	)
	(segment
		(start 132.287772 -261.670292)
		(end 132.754624 -261.93623)
		(width 0.10668)
		(layer "F.Cu")
		(net "Net_2063")
	)
	(via
		(at 132.754624 -261.93623)
		(size 0.4064)
		(drill 0.2032)
		(layers "F.Cu" "B.Cu")
		(net "Net_2063")
	)
	(segment
		(start 132.457952 -252.04039)
		(end 132.924804 -251.774452)
		(width 0.10668)
		(layer "F.Cu")
		(net "Net_2064")
	)
	(via
		(at 132.924804 -251.774452)
		(size 0.4064)
		(drill 0.2032)
		(layers "F.Cu" "B.Cu")
		(net "Net_2064")
	)
	(segment
		(start 131.047998 -252.850396)
		(end 131.51485 -252.584458)
		(width 0.10668)
		(layer "F.Cu")
		(net "Net_2065")
	)
	(via
		(at 131.51485 -252.584458)
		(size 0.4064)
		(drill 0.2032)
		(layers "F.Cu" "B.Cu")
		(net "Net_2065")
	)
	(segment
		(start 130.877818 -267.340334)
		(end 131.34467 -267.606272)
		(width 0.10668)
		(layer "F.Cu")
		(net "Net_2066")
	)
	(via
		(at 131.34467 -267.606272)
		(size 0.4064)
		(drill 0.2032)
		(layers "F.Cu" "B.Cu")
		(net "Net_2066")
	)
	(segment
		(start 132.287772 -264.910316)
		(end 132.754624 -265.176254)
		(width 0.10668)
		(layer "F.Cu")
		(net "Net_2067")
	)
	(via
		(at 132.754624 -265.176254)
		(size 0.4064)
		(drill 0.2032)
		(layers "F.Cu" "B.Cu")
		(net "Net_2067")
	)
	(segment
		(start 132.757926 -265.720322)
		(end 133.224778 -265.98626)
		(width 0.10668)
		(layer "F.Cu")
		(net "Net_2068")
	)
	(via
		(at 133.224778 -265.98626)
		(size 0.4064)
		(drill 0.2032)
		(layers "F.Cu" "B.Cu")
		(net "Net_2068")
	)
	(segment
		(start 132.287772 -268.15034)
		(end 132.754624 -268.416278)
		(width 0.10668)
		(layer "F.Cu")
		(net "Net_2069")
	)
	(via
		(at 132.754624 -268.416278)
		(size 0.4064)
		(drill 0.2032)
		(layers "F.Cu" "B.Cu")
		(net "Net_2069")
	)
	(segment
		(start 100.967794 -225.310446)
		(end 100.500942 -225.044508)
		(width 0.10668)
		(layer "F.Cu")
		(net "Net_2070")
	)
	(via
		(at 100.500942 -225.044508)
		(size 0.4064)
		(drill 0.2032)
		(layers "F.Cu" "B.Cu")
		(net "Net_2070")
	)
	(segment
		(start 101.907848 -225.310446)
		(end 101.440996 -225.044508)
		(width 0.10668)
		(layer "F.Cu")
		(net "Net_2071")
	)
	(via
		(at 101.440996 -225.044508)
		(size 0.4064)
		(drill 0.2032)
		(layers "F.Cu" "B.Cu")
		(net "Net_2071")
	)
	(segment
		(start 100.027994 -223.690434)
		(end 99.561142 -223.424496)
		(width 0.10668)
		(layer "F.Cu")
		(net "Net_2072")
	)
	(via
		(at 99.561142 -223.424496)
		(size 0.4064)
		(drill 0.2032)
		(layers "F.Cu" "B.Cu")
		(net "Net_2072")
	)
	(segment
		(start 100.967794 -223.690434)
		(end 100.500942 -223.424496)
		(width 0.10668)
		(layer "F.Cu")
		(net "Net_2073")
	)
	(via
		(at 100.500942 -223.424496)
		(size 0.4064)
		(drill 0.2032)
		(layers "F.Cu" "B.Cu")
		(net "Net_2073")
	)
	(segment
		(start 117.247924 -295.69029)
		(end 117.714776 -295.956228)
		(width 0.10668)
		(layer "F.Cu")
		(net "Net_2074")
	)
	(via
		(at 117.714776 -295.956228)
		(size 0.4064)
		(drill 0.2032)
		(layers "F.Cu" "B.Cu")
		(net "Net_2074")
	)
	(segment
		(start 119.597932 -294.880284)
		(end 120.064784 -295.146222)
		(width 0.10668)
		(layer "F.Cu")
		(net "Net_2075")
	)
	(via
		(at 120.064784 -295.146222)
		(size 0.4064)
		(drill 0.2032)
		(layers "F.Cu" "B.Cu")
		(net "Net_2075")
	)
	(segment
		(start 119.127778 -292.450266)
		(end 119.59463 -292.716204)
		(width 0.10668)
		(layer "F.Cu")
		(net "Net_2076")
	)
	(via
		(at 119.59463 -292.716204)
		(size 0.4064)
		(drill 0.2032)
		(layers "F.Cu" "B.Cu")
		(net "Net_2076")
	)
	(segment
		(start 118.657878 -293.260272)
		(end 119.12473 -293.52621)
		(width 0.10668)
		(layer "F.Cu")
		(net "Net_2077")
	)
	(via
		(at 119.12473 -293.52621)
		(size 0.4064)
		(drill 0.2032)
		(layers "F.Cu" "B.Cu")
		(net "Net_2077")
	)
	(segment
		(start 118.187978 -294.070278)
		(end 118.65483 -294.336216)
		(width 0.10668)
		(layer "F.Cu")
		(net "Net_2078")
	)
	(via
		(at 118.65483 -294.336216)
		(size 0.4064)
		(drill 0.2032)
		(layers "F.Cu" "B.Cu")
		(net "Net_2078")
	)
	(segment
		(start 117.247924 -294.070278)
		(end 117.714776 -294.336216)
		(width 0.10668)
		(layer "F.Cu")
		(net "Net_2079")
	)
	(via
		(at 117.714776 -294.336216)
		(size 0.4064)
		(drill 0.2032)
		(layers "F.Cu" "B.Cu")
		(net "Net_2079")
	)
	(segment
		(start 133.867906 -223.690434)
		(end 134.334758 -223.424496)
		(width 0.10668)
		(layer "F.Cu")
		(net "Net_2081")
	)
	(via
		(at 134.334758 -223.424496)
		(size 0.4064)
		(drill 0.2032)
		(layers "F.Cu" "B.Cu")
		(net "Net_2081")
	)
	(segment
		(start 134.80796 -222.070422)
		(end 135.274812 -221.804484)
		(width 0.10668)
		(layer "F.Cu")
		(net "Net_2082")
	)
	(via
		(at 135.274812 -221.804484)
		(size 0.4064)
		(drill 0.2032)
		(layers "F.Cu" "B.Cu")
		(net "Net_2082")
	)
	(segment
		(start 113.957862 -293.260272)
		(end 114.424714 -293.52621)
		(width 0.10668)
		(layer "F.Cu")
		(net "Net_2084")
	)
	(via
		(at 114.424714 -293.52621)
		(size 0.4064)
		(drill 0.2032)
		(layers "F.Cu" "B.Cu")
		(net "Net_2084")
	)
	(segment
		(start 144.037812 -294.880284)
		(end 144.504664 -295.146222)
		(width 0.10668)
		(layer "F.Cu")
		(net "Net_2085")
	)
	(via
		(at 144.504664 -295.146222)
		(size 0.4064)
		(drill 0.2032)
		(layers "F.Cu" "B.Cu")
		(net "Net_2085")
	)
	(segment
		(start 136.987788 -294.070278)
		(end 137.45464 -294.336216)
		(width 0.10668)
		(layer "F.Cu")
		(net "Net_2086")
	)
	(via
		(at 137.45464 -294.336216)
		(size 0.4064)
		(drill 0.2032)
		(layers "F.Cu" "B.Cu")
		(net "Net_2086")
	)
	(segment
		(start 120.067832 -295.69029)
		(end 120.534684 -295.956228)
		(width 0.10668)
		(layer "F.Cu")
		(net "Net_2087")
	)
	(via
		(at 120.534684 -295.956228)
		(size 0.4064)
		(drill 0.2032)
		(layers "F.Cu" "B.Cu")
		(net "Net_2087")
	)
	(segment
		(start 136.047988 -294.070278)
		(end 136.51484 -294.336216)
		(width 0.10668)
		(layer "F.Cu")
		(net "Net_2092")
	)
	(via
		(at 136.51484 -294.336216)
		(size 0.4064)
		(drill 0.2032)
		(layers "F.Cu" "B.Cu")
		(net "Net_2092")
	)
	(segment
		(start 136.517888 -294.880284)
		(end 136.98474 -295.146222)
		(width 0.10668)
		(layer "F.Cu")
		(net "Net_2093")
	)
	(via
		(at 136.98474 -295.146222)
		(size 0.4064)
		(drill 0.2032)
		(layers "F.Cu" "B.Cu")
		(net "Net_2093")
	)
	(segment
		(start 127.58801 -295.69029)
		(end 128.054862 -295.956228)
		(width 0.10668)
		(layer "F.Cu")
		(net "Net_2094")
	)
	(via
		(at 128.054862 -295.956228)
		(size 0.4064)
		(drill 0.2032)
		(layers "F.Cu" "B.Cu")
		(net "Net_2094")
	)
	(segment
		(start 128.52781 -295.69029)
		(end 128.994662 -295.956228)
		(width 0.10668)
		(layer "F.Cu")
		(net "Net_2095")
	)
	(via
		(at 128.994662 -295.956228)
		(size 0.4064)
		(drill 0.2032)
		(layers "F.Cu" "B.Cu")
		(net "Net_2095")
	)
	(segment
		(start 133.398006 -224.50044)
		(end 133.864858 -224.234502)
		(width 0.10668)
		(layer "F.Cu")
		(net "Net_2100")
	)
	(via
		(at 133.864858 -224.234502)
		(size 0.4064)
		(drill 0.2032)
		(layers "F.Cu" "B.Cu")
		(net "Net_2100")
	)
	(segment
		(start 133.398006 -222.880428)
		(end 133.864858 -222.61449)
		(width 0.10668)
		(layer "F.Cu")
		(net "Net_2101")
	)
	(via
		(at 133.864858 -222.61449)
		(size 0.4064)
		(drill 0.2032)
		(layers "F.Cu" "B.Cu")
		(net "Net_2101")
	)
	(segment
		(start 123.827794 -295.69029)
		(end 124.294646 -295.956228)
		(width 0.10668)
		(layer "F.Cu")
		(net "Net_2102")
	)
	(via
		(at 124.294646 -295.956228)
		(size 0.4064)
		(drill 0.2032)
		(layers "F.Cu" "B.Cu")
		(net "Net_2102")
	)
	(segment
		(start 126.647956 -295.69029)
		(end 127.114808 -295.956228)
		(width 0.10668)
		(layer "F.Cu")
		(net "Net_2103")
	)
	(via
		(at 127.114808 -295.956228)
		(size 0.4064)
		(drill 0.2032)
		(layers "F.Cu" "B.Cu")
		(net "Net_2103")
	)
	(segment
		(start 121.477786 -293.260272)
		(end 121.944638 -293.52621)
		(width 0.10668)
		(layer "F.Cu")
		(net "Net_2104")
	)
	(via
		(at 121.944638 -293.52621)
		(size 0.4064)
		(drill 0.2032)
		(layers "F.Cu" "B.Cu")
		(net "Net_2104")
	)
	(segment
		(start 126.647956 -294.070278)
		(end 127.114808 -294.336216)
		(width 0.10668)
		(layer "F.Cu")
		(net "Net_2105")
	)
	(via
		(at 127.114808 -294.336216)
		(size 0.4064)
		(drill 0.2032)
		(layers "F.Cu" "B.Cu")
		(net "Net_2105")
	)
	(segment
		(start 121.007886 -295.69029)
		(end 121.474738 -295.956228)
		(width 0.10668)
		(layer "F.Cu")
		(net "Net_2106")
	)
	(via
		(at 121.474738 -295.956228)
		(size 0.4064)
		(drill 0.2032)
		(layers "F.Cu" "B.Cu")
		(net "Net_2106")
	)
	(segment
		(start 120.067832 -294.070278)
		(end 120.534684 -294.336216)
		(width 0.10668)
		(layer "F.Cu")
		(net "Net_2107")
	)
	(via
		(at 120.534684 -294.336216)
		(size 0.4064)
		(drill 0.2032)
		(layers "F.Cu" "B.Cu")
		(net "Net_2107")
	)
	(segment
		(start 125.238002 -293.260272)
		(end 125.704854 -293.52621)
		(width 0.10668)
		(layer "F.Cu")
		(net "Net_2108")
	)
	(via
		(at 125.704854 -293.52621)
		(size 0.4064)
		(drill 0.2032)
		(layers "F.Cu" "B.Cu")
		(net "Net_2108")
	)
	(segment
		(start 125.238002 -294.880284)
		(end 125.704854 -295.146222)
		(width 0.10668)
		(layer "F.Cu")
		(net "Net_2109")
	)
	(via
		(at 125.704854 -295.146222)
		(size 0.4064)
		(drill 0.2032)
		(layers "F.Cu" "B.Cu")
		(net "Net_2109")
	)
	(segment
		(start 124.767848 -292.450266)
		(end 125.2347 -292.716204)
		(width 0.10668)
		(layer "F.Cu")
		(net "Net_2110")
	)
	(via
		(at 125.2347 -292.716204)
		(size 0.4064)
		(drill 0.2032)
		(layers "F.Cu" "B.Cu")
		(net "Net_2110")
	)
	(segment
		(start 124.297948 -293.260272)
		(end 124.7648 -293.52621)
		(width 0.10668)
		(layer "F.Cu")
		(net "Net_2111")
	)
	(via
		(at 124.7648 -293.52621)
		(size 0.4064)
		(drill 0.2032)
		(layers "F.Cu" "B.Cu")
		(net "Net_2111")
	)
	(segment
		(start 123.827794 -294.070278)
		(end 124.294646 -294.336216)
		(width 0.10668)
		(layer "F.Cu")
		(net "Net_2112")
	)
	(via
		(at 124.294646 -294.336216)
		(size 0.4064)
		(drill 0.2032)
		(layers "F.Cu" "B.Cu")
		(net "Net_2112")
	)
	(segment
		(start 125.707902 -294.070278)
		(end 126.174754 -294.336216)
		(width 0.10668)
		(layer "F.Cu")
		(net "Net_2113")
	)
	(via
		(at 126.174754 -294.336216)
		(size 0.4064)
		(drill 0.2032)
		(layers "F.Cu" "B.Cu")
		(net "Net_2113")
	)
	(segment
		(start 121.007886 -294.070278)
		(end 121.474738 -294.336216)
		(width 0.10668)
		(layer "F.Cu")
		(net "Net_2114")
	)
	(via
		(at 121.474738 -294.336216)
		(size 0.4064)
		(drill 0.2032)
		(layers "F.Cu" "B.Cu")
		(net "Net_2114")
	)
	(segment
		(start 125.707902 -295.69029)
		(end 126.174754 -295.956228)
		(width 0.10668)
		(layer "F.Cu")
		(net "Net_2115")
	)
	(via
		(at 126.174754 -295.956228)
		(size 0.4064)
		(drill 0.2032)
		(layers "F.Cu" "B.Cu")
		(net "Net_2115")
	)
	(segment
		(start 122.887994 -295.69029)
		(end 123.354846 -295.956228)
		(width 0.10668)
		(layer "F.Cu")
		(net "Net_2116")
	)
	(via
		(at 123.354846 -295.956228)
		(size 0.4064)
		(drill 0.2032)
		(layers "F.Cu" "B.Cu")
		(net "Net_2116")
	)
	(segment
		(start 121.94794 -292.450266)
		(end 122.414792 -292.716204)
		(width 0.10668)
		(layer "F.Cu")
		(net "Net_2117")
	)
	(via
		(at 122.414792 -292.716204)
		(size 0.4064)
		(drill 0.2032)
		(layers "F.Cu" "B.Cu")
		(net "Net_2117")
	)
	(segment
		(start 119.597932 -293.260272)
		(end 120.064784 -293.52621)
		(width 0.10668)
		(layer "F.Cu")
		(net "Net_2118")
	)
	(via
		(at 120.064784 -293.52621)
		(size 0.4064)
		(drill 0.2032)
		(layers "F.Cu" "B.Cu")
		(net "Net_2118")
	)
	(segment
		(start 122.887994 -294.070278)
		(end 123.354846 -294.336216)
		(width 0.10668)
		(layer "F.Cu")
		(net "Net_2119")
	)
	(via
		(at 123.354846 -294.336216)
		(size 0.4064)
		(drill 0.2032)
		(layers "F.Cu" "B.Cu")
		(net "Net_2119")
	)
	(segment
		(start 122.41784 -294.880284)
		(end 122.884692 -295.146222)
		(width 0.10668)
		(layer "F.Cu")
		(net "Net_2120")
	)
	(via
		(at 122.884692 -295.146222)
		(size 0.4064)
		(drill 0.2032)
		(layers "F.Cu" "B.Cu")
		(net "Net_2120")
	)
	(segment
		(start 117.888004 -222.070422)
		(end 118.354856 -221.804484)
		(width 0.10668)
		(layer "F.Cu")
		(net "Net_2121")
	)
	(via
		(at 118.354856 -221.804484)
		(size 0.4064)
		(drill 0.2032)
		(layers "F.Cu" "B.Cu")
		(net "Net_2121")
	)
	(segment
		(start 114.127788 -222.070422)
		(end 114.59464 -221.804484)
		(width 0.10668)
		(layer "F.Cu")
		(net "Net_2122")
	)
	(via
		(at 114.59464 -221.804484)
		(size 0.4064)
		(drill 0.2032)
		(layers "F.Cu" "B.Cu")
		(net "Net_2122")
	)
	(segment
		(start 105.66781 -222.070422)
		(end 105.200958 -221.804484)
		(width 0.10668)
		(layer "F.Cu")
		(net "Net_2125")
	)
	(via
		(at 105.200958 -221.804484)
		(size 0.4064)
		(drill 0.2032)
		(layers "F.Cu" "B.Cu")
		(net "Net_2125")
	)
	(segment
		(start 102.847902 -222.070422)
		(end 102.38105 -221.804484)
		(width 0.10668)
		(layer "F.Cu")
		(net "Net_2126")
	)
	(via
		(at 102.38105 -221.804484)
		(size 0.4064)
		(drill 0.2032)
		(layers "F.Cu" "B.Cu")
		(net "Net_2126")
	)
	(segment
		(start 100.967794 -222.070422)
		(end 100.500942 -221.804484)
		(width 0.10668)
		(layer "F.Cu")
		(net "Net_2127")
	)
	(via
		(at 100.500942 -221.804484)
		(size 0.4064)
		(drill 0.2032)
		(layers "F.Cu" "B.Cu")
		(net "Net_2127")
	)
	(segment
		(start 100.027994 -222.070422)
		(end 99.561142 -221.804484)
		(width 0.10668)
		(layer "F.Cu")
		(net "Net_2128")
	)
	(via
		(at 99.561142 -221.804484)
		(size 0.4064)
		(drill 0.2032)
		(layers "F.Cu" "B.Cu")
		(net "Net_2128")
	)
	(segment
		(start 97.207832 -222.070422)
		(end 96.74098 -221.804484)
		(width 0.10668)
		(layer "F.Cu")
		(net "Net_2129")
	)
	(via
		(at 96.74098 -221.804484)
		(size 0.4064)
		(drill 0.2032)
		(layers "F.Cu" "B.Cu")
		(net "Net_2129")
	)
	(segment
		(start 96.267778 -222.070422)
		(end 95.800926 -221.804484)
		(width 0.10668)
		(layer "F.Cu")
		(net "Net_2130")
	)
	(via
		(at 95.800926 -221.804484)
		(size 0.4064)
		(drill 0.2032)
		(layers "F.Cu" "B.Cu")
		(net "Net_2130")
	)
	(segment
		(start 95.327978 -222.070422)
		(end 94.861126 -221.804484)
		(width 0.10668)
		(layer "F.Cu")
		(net "Net_2131")
	)
	(via
		(at 94.861126 -221.804484)
		(size 0.4064)
		(drill 0.2032)
		(layers "F.Cu" "B.Cu")
		(net "Net_2131")
	)
	(segment
		(start 94.387924 -222.070422)
		(end 93.921072 -221.804484)
		(width 0.10668)
		(layer "F.Cu")
		(net "Net_2132")
	)
	(via
		(at 93.921072 -221.804484)
		(size 0.4064)
		(drill 0.2032)
		(layers "F.Cu" "B.Cu")
		(net "Net_2132")
	)
	(segment
		(start 137.157968 -256.900426)
		(end 137.62482 -256.634488)
		(width 0.10668)
		(layer "F.Cu")
		(net "Net_2136")
	)
	(via
		(at 137.62482 -256.634488)
		(size 0.4064)
		(drill 0.2032)
		(layers "F.Cu" "B.Cu")
		(net "Net_2136")
	)
	(segment
		(start 134.337806 -256.900426)
		(end 134.804658 -256.634488)
		(width 0.10668)
		(layer "F.Cu")
		(net "Net_2137")
	)
	(via
		(at 134.804658 -256.634488)
		(size 0.4064)
		(drill 0.2032)
		(layers "F.Cu" "B.Cu")
		(net "Net_2137")
	)
	(segment
		(start 130.577844 -256.900426)
		(end 131.044696 -256.634488)
		(width 0.10668)
		(layer "F.Cu")
		(net "Net_2138")
	)
	(via
		(at 131.044696 -256.634488)
		(size 0.4064)
		(drill 0.2032)
		(layers "F.Cu" "B.Cu")
		(net "Net_2138")
	)
	(segment
		(start 127.757936 -256.900426)
		(end 128.224788 -256.634488)
		(width 0.10668)
		(layer "F.Cu")
		(net "Net_2139")
	)
	(via
		(at 128.224788 -256.634488)
		(size 0.4064)
		(drill 0.2032)
		(layers "F.Cu" "B.Cu")
		(net "Net_2139")
	)
	(segment
		(start 143.737838 -256.900426)
		(end 144.20469 -256.634488)
		(width 0.10668)
		(layer "F.Cu")
		(net "Net_2140")
	)
	(via
		(at 144.20469 -256.634488)
		(size 0.4064)
		(drill 0.2032)
		(layers "F.Cu" "B.Cu")
		(net "Net_2140")
	)
	(segment
		(start 95.797878 -256.900426)
		(end 95.331026 -256.634488)
		(width 0.10668)
		(layer "F.Cu")
		(net "Net_2141")
	)
	(via
		(at 95.331026 -256.634488)
		(size 0.4064)
		(drill 0.2032)
		(layers "F.Cu" "B.Cu")
		(net "Net_2141")
	)
	(segment
		(start 92.97797 -256.900426)
		(end 92.511118 -256.634488)
		(width 0.10668)
		(layer "F.Cu")
		(net "Net_2142")
	)
	(via
		(at 92.511118 -256.634488)
		(size 0.4064)
		(drill 0.2032)
		(layers "F.Cu" "B.Cu")
		(net "Net_2142")
	)
	(segment
		(start 89.218008 -256.900426)
		(end 88.751156 -256.634488)
		(width 0.10668)
		(layer "F.Cu")
		(net "Net_2143")
	)
	(via
		(at 88.751156 -256.634488)
		(size 0.4064)
		(drill 0.2032)
		(layers "F.Cu" "B.Cu")
		(net "Net_2143")
	)
	(segment
		(start 86.397846 -256.900426)
		(end 85.930994 -256.634488)
		(width 0.10668)
		(layer "F.Cu")
		(net "Net_2144")
	)
	(via
		(at 85.930994 -256.634488)
		(size 0.4064)
		(drill 0.2032)
		(layers "F.Cu" "B.Cu")
		(net "Net_2144")
	)
	(segment
		(start 82.637884 -256.900426)
		(end 82.171032 -256.634488)
		(width 0.10668)
		(layer "F.Cu")
		(net "Net_2145")
	)
	(via
		(at 82.171032 -256.634488)
		(size 0.4064)
		(drill 0.2032)
		(layers "F.Cu" "B.Cu")
		(net "Net_2145")
	)
	(segment
		(start 140.91793 -256.900426)
		(end 141.384782 -256.634488)
		(width 0.10668)
		(layer "F.Cu")
		(net "Net_2146")
	)
	(via
		(at 141.384782 -256.634488)
		(size 0.4064)
		(drill 0.2032)
		(layers "F.Cu" "B.Cu")
		(net "Net_2146")
	)
	(segment
		(start 117.888004 -223.690434)
		(end 118.354856 -223.424496)
		(width 0.10668)
		(layer "F.Cu")
		(net "Net_2148")
	)
	(via
		(at 118.354856 -223.424496)
		(size 0.4064)
		(drill 0.2032)
		(layers "F.Cu" "B.Cu")
		(net "Net_2148")
	)
	(segment
		(start 115.067842 -223.690434)
		(end 115.534694 -223.424496)
		(width 0.10668)
		(layer "F.Cu")
		(net "Net_2149")
	)
	(via
		(at 115.534694 -223.424496)
		(size 0.4064)
		(drill 0.2032)
		(layers "F.Cu" "B.Cu")
		(net "Net_2149")
	)
	(segment
		(start 114.127788 -223.690434)
		(end 114.59464 -223.424496)
		(width 0.10668)
		(layer "F.Cu")
		(net "Net_2150")
	)
	(via
		(at 114.59464 -223.424496)
		(size 0.4064)
		(drill 0.2032)
		(layers "F.Cu" "B.Cu")
		(net "Net_2150")
	)
	(segment
		(start 98.147886 -223.690434)
		(end 97.681034 -223.424496)
		(width 0.10668)
		(layer "F.Cu")
		(net "Net_2151")
	)
	(via
		(at 97.681034 -223.424496)
		(size 0.4064)
		(drill 0.2032)
		(layers "F.Cu" "B.Cu")
		(net "Net_2151")
	)
	(segment
		(start 97.207832 -223.690434)
		(end 96.74098 -223.424496)
		(width 0.10668)
		(layer "F.Cu")
		(net "Net_2152")
	)
	(via
		(at 96.74098 -223.424496)
		(size 0.4064)
		(drill 0.2032)
		(layers "F.Cu" "B.Cu")
		(net "Net_2152")
	)
	(segment
		(start 137.157968 -224.50044)
		(end 137.62482 -224.234502)
		(width 0.10668)
		(layer "F.Cu")
		(net "Net_2153")
	)
	(via
		(at 137.62482 -224.234502)
		(size 0.4064)
		(drill 0.2032)
		(layers "F.Cu" "B.Cu")
		(net "Net_2153")
	)
	(segment
		(start 126.817882 -224.50044)
		(end 127.284734 -224.234502)
		(width 0.10668)
		(layer "F.Cu")
		(net "Net_2154")
	)
	(via
		(at 127.284734 -224.234502)
		(size 0.4064)
		(drill 0.2032)
		(layers "F.Cu" "B.Cu")
		(net "Net_2154")
	)
	(segment
		(start 115.537996 -224.50044)
		(end 116.004848 -224.234502)
		(width 0.10668)
		(layer "F.Cu")
		(net "Net_2155")
	)
	(via
		(at 116.004848 -224.234502)
		(size 0.4064)
		(drill 0.2032)
		(layers "F.Cu" "B.Cu")
		(net "Net_2155")
	)
	(segment
		(start 113.657888 -224.50044)
		(end 114.12474 -224.234502)
		(width 0.10668)
		(layer "F.Cu")
		(net "Net_2156")
	)
	(via
		(at 114.12474 -224.234502)
		(size 0.4064)
		(drill 0.2032)
		(layers "F.Cu" "B.Cu")
		(net "Net_2156")
	)
	(segment
		(start 143.737838 -224.50044)
		(end 144.20469 -224.234502)
		(width 0.10668)
		(layer "F.Cu")
		(net "Net_2157")
	)
	(via
		(at 144.20469 -224.234502)
		(size 0.4064)
		(drill 0.2032)
		(layers "F.Cu" "B.Cu")
		(net "Net_2157")
	)
	(segment
		(start 139.977876 -224.50044)
		(end 140.444728 -224.234502)
		(width 0.10668)
		(layer "F.Cu")
		(net "Net_2162")
	)
	(via
		(at 140.444728 -224.234502)
		(size 0.4064)
		(drill 0.2032)
		(layers "F.Cu" "B.Cu")
		(net "Net_2162")
	)
	(segment
		(start 131.347972 -294.070278)
		(end 131.814824 -294.336216)
		(width 0.10668)
		(layer "F.Cu")
		(net "Net_2163")
	)
	(via
		(at 131.814824 -294.336216)
		(size 0.4064)
		(drill 0.2032)
		(layers "F.Cu" "B.Cu")
		(net "Net_2163")
	)
	(segment
		(start 131.817872 -294.880284)
		(end 132.284724 -295.146222)
		(width 0.10668)
		(layer "F.Cu")
		(net "Net_2164")
	)
	(via
		(at 132.284724 -295.146222)
		(size 0.4064)
		(drill 0.2032)
		(layers "F.Cu" "B.Cu")
		(net "Net_2164")
	)
	(segment
		(start 128.05791 -294.880284)
		(end 128.524762 -295.146222)
		(width 0.10668)
		(layer "F.Cu")
		(net "Net_2165")
	)
	(via
		(at 128.524762 -295.146222)
		(size 0.4064)
		(drill 0.2032)
		(layers "F.Cu" "B.Cu")
		(net "Net_2165")
	)
	(segment
		(start 143.567912 -295.69029)
		(end 144.034764 -295.956228)
		(width 0.10668)
		(layer "F.Cu")
		(net "Net_2166")
	)
	(via
		(at 144.034764 -295.956228)
		(size 0.4064)
		(drill 0.2032)
		(layers "F.Cu" "B.Cu")
		(net "Net_2166")
	)
	(segment
		(start 116.007896 -225.310446)
		(end 116.474748 -225.044508)
		(width 0.10668)
		(layer "F.Cu")
		(net "Net_2167")
	)
	(via
		(at 116.474748 -225.044508)
		(size 0.4064)
		(drill 0.2032)
		(layers "F.Cu" "B.Cu")
		(net "Net_2167")
	)
	(segment
		(start 113.187988 -225.310446)
		(end 113.65484 -225.044508)
		(width 0.10668)
		(layer "F.Cu")
		(net "Net_2168")
	)
	(via
		(at 113.65484 -225.044508)
		(size 0.4064)
		(drill 0.2032)
		(layers "F.Cu" "B.Cu")
		(net "Net_2168")
	)
	(segment
		(start 135.577834 -294.880284)
		(end 136.044686 -295.146222)
		(width 0.10668)
		(layer "F.Cu")
		(net "Net_2170")
	)
	(via
		(at 136.044686 -295.146222)
		(size 0.4064)
		(drill 0.2032)
		(layers "F.Cu" "B.Cu")
		(net "Net_2170")
	)
	(segment
		(start 109.257846 -293.260272)
		(end 108.790994 -293.52621)
		(width 0.10668)
		(layer "F.Cu")
		(net "Net_2171")
	)
	(via
		(at 108.790994 -293.52621)
		(size 0.4064)
		(drill 0.2032)
		(layers "F.Cu" "B.Cu")
		(net "Net_2171")
	)
	(segment
		(start 125.407928 -223.690434)
		(end 125.87478 -223.424496)
		(width 0.10668)
		(layer "F.Cu")
		(net "Net_2172")
	)
	(via
		(at 125.87478 -223.424496)
		(size 0.4064)
		(drill 0.2032)
		(layers "F.Cu" "B.Cu")
		(net "Net_2172")
	)
	(segment
		(start 134.63778 -294.880284)
		(end 135.104632 -295.146222)
		(width 0.10668)
		(layer "F.Cu")
		(net "Net_2174")
	)
	(via
		(at 135.104632 -295.146222)
		(size 0.4064)
		(drill 0.2032)
		(layers "F.Cu" "B.Cu")
		(net "Net_2174")
	)
	(segment
		(start 108.787946 -294.070278)
		(end 108.321094 -294.336216)
		(width 0.10668)
		(layer "F.Cu")
		(net "Net_2175")
	)
	(via
		(at 108.321094 -294.336216)
		(size 0.4064)
		(drill 0.2032)
		(layers "F.Cu" "B.Cu")
		(net "Net_2175")
	)
	(segment
		(start 125.877828 -224.50044)
		(end 126.34468 -224.234502)
		(width 0.10668)
		(layer "F.Cu")
		(net "Net_2176")
	)
	(via
		(at 126.34468 -224.234502)
		(size 0.4064)
		(drill 0.2032)
		(layers "F.Cu" "B.Cu")
		(net "Net_2176")
	)
	(segment
		(start 113.657888 -222.880428)
		(end 114.12474 -222.61449)
		(width 0.10668)
		(layer "F.Cu")
		(net "Net_2177")
	)
	(via
		(at 114.12474 -222.61449)
		(size 0.4064)
		(drill 0.2032)
		(layers "F.Cu" "B.Cu")
		(net "Net_2177")
	)
	(segment
		(start 139.337796 -260.860286)
		(end 139.804648 -261.126224)
		(width 0.10668)
		(layer "F.Cu")
		(net "Net_2179")
	)
	(via
		(at 139.804648 -261.126224)
		(size 0.4064)
		(drill 0.2032)
		(layers "F.Cu" "B.Cu")
		(net "Net_2179")
	)
	(segment
		(start 138.867896 -261.670292)
		(end 139.334748 -261.93623)
		(width 0.10668)
		(layer "F.Cu")
		(net "Net_2180")
	)
	(via
		(at 139.334748 -261.93623)
		(size 0.4064)
		(drill 0.2032)
		(layers "F.Cu" "B.Cu")
		(net "Net_2180")
	)
	(segment
		(start 139.037822 -252.04039)
		(end 139.504674 -251.774452)
		(width 0.10668)
		(layer "F.Cu")
		(net "Net_2181")
	)
	(via
		(at 139.504674 -251.774452)
		(size 0.4064)
		(drill 0.2032)
		(layers "F.Cu" "B.Cu")
		(net "Net_2181")
	)
	(segment
		(start 137.627868 -252.850396)
		(end 138.09472 -252.584458)
		(width 0.10668)
		(layer "F.Cu")
		(net "Net_2182")
	)
	(via
		(at 138.09472 -252.584458)
		(size 0.4064)
		(drill 0.2032)
		(layers "F.Cu" "B.Cu")
		(net "Net_2182")
	)
	(segment
		(start 137.457942 -267.340334)
		(end 137.924794 -267.606272)
		(width 0.10668)
		(layer "F.Cu")
		(net "Net_2183")
	)
	(via
		(at 137.924794 -267.606272)
		(size 0.4064)
		(drill 0.2032)
		(layers "F.Cu" "B.Cu")
		(net "Net_2183")
	)
	(segment
		(start 138.867896 -264.910316)
		(end 139.334748 -265.176254)
		(width 0.10668)
		(layer "F.Cu")
		(net "Net_2184")
	)
	(via
		(at 139.334748 -265.176254)
		(size 0.4064)
		(drill 0.2032)
		(layers "F.Cu" "B.Cu")
		(net "Net_2184")
	)
	(segment
		(start 139.337796 -265.720322)
		(end 139.804648 -265.98626)
		(width 0.10668)
		(layer "F.Cu")
		(net "Net_2185")
	)
	(via
		(at 139.804648 -265.98626)
		(size 0.4064)
		(drill 0.2032)
		(layers "F.Cu" "B.Cu")
		(net "Net_2185")
	)
	(segment
		(start 138.867896 -268.15034)
		(end 139.334748 -268.416278)
		(width 0.10668)
		(layer "F.Cu")
		(net "Net_2186")
	)
	(via
		(at 139.334748 -268.416278)
		(size 0.4064)
		(drill 0.2032)
		(layers "F.Cu" "B.Cu")
		(net "Net_2186")
	)
	(segment
		(start 142.157958 -260.860286)
		(end 142.62481 -261.126224)
		(width 0.10668)
		(layer "F.Cu")
		(net "Net_2187")
	)
	(via
		(at 142.62481 -261.126224)
		(size 0.4064)
		(drill 0.2032)
		(layers "F.Cu" "B.Cu")
		(net "Net_2187")
	)
	(segment
		(start 142.627858 -261.670292)
		(end 143.09471 -261.93623)
		(width 0.10668)
		(layer "F.Cu")
		(net "Net_2188")
	)
	(via
		(at 143.09471 -261.93623)
		(size 0.4064)
		(drill 0.2032)
		(layers "F.Cu" "B.Cu")
		(net "Net_2188")
	)
	(segment
		(start 141.857984 -252.04039)
		(end 142.324836 -251.774452)
		(width 0.10668)
		(layer "F.Cu")
		(net "Net_2189")
	)
	(via
		(at 142.324836 -251.774452)
		(size 0.4064)
		(drill 0.2032)
		(layers "F.Cu" "B.Cu")
		(net "Net_2189")
	)
	(segment
		(start 140.447776 -252.850396)
		(end 140.914628 -252.584458)
		(width 0.10668)
		(layer "F.Cu")
		(net "Net_2190")
	)
	(via
		(at 140.914628 -252.584458)
		(size 0.4064)
		(drill 0.2032)
		(layers "F.Cu" "B.Cu")
		(net "Net_2190")
	)
	(segment
		(start 141.217904 -267.340334)
		(end 141.684756 -267.606272)
		(width 0.10668)
		(layer "F.Cu")
		(net "Net_2191")
	)
	(via
		(at 141.684756 -267.606272)
		(size 0.4064)
		(drill 0.2032)
		(layers "F.Cu" "B.Cu")
		(net "Net_2191")
	)
	(segment
		(start 142.627858 -264.910316)
		(end 143.09471 -265.176254)
		(width 0.10668)
		(layer "F.Cu")
		(net "Net_2192")
	)
	(via
		(at 143.09471 -265.176254)
		(size 0.4064)
		(drill 0.2032)
		(layers "F.Cu" "B.Cu")
		(net "Net_2192")
	)
	(segment
		(start 142.157958 -265.720322)
		(end 142.62481 -265.98626)
		(width 0.10668)
		(layer "F.Cu")
		(net "Net_2193")
	)
	(via
		(at 142.62481 -265.98626)
		(size 0.4064)
		(drill 0.2032)
		(layers "F.Cu" "B.Cu")
		(net "Net_2193")
	)
	(segment
		(start 142.627858 -268.15034)
		(end 143.09471 -268.416278)
		(width 0.10668)
		(layer "F.Cu")
		(net "Net_2194")
	)
	(via
		(at 143.09471 -268.416278)
		(size 0.4064)
		(drill 0.2032)
		(layers "F.Cu" "B.Cu")
		(net "Net_2194")
	)
	(segment
		(start 166.02456 -123.683014)
		(end 166.854886 -123.683014)
		(width 0.10668)
		(layer "F.Cu")
		(net "RST_SRST_PLD_BMC_R_N")
	)
	(segment
		(start 178.72202 -119.452898)
		(end 178.33213 -119.842788)
		(width 0.10668)
		(layer "F.Cu")
		(net "RST_SRST_PLD_BMC_R_N")
	)
	(segment
		(start 166.854886 -123.683014)
		(end 167.01008 -123.52782)
		(width 0.10668)
		(layer "F.Cu")
		(net "RST_SRST_PLD_BMC_R_N")
	)
	(via
		(at 176.845468 -120.625616)
		(size 0.6604)
		(drill 0.3302)
		(layers "F.Cu" "B.Cu")
		(net "RST_SRST_PLD_BMC_R_N")
	)
	(via
		(at 167.01008 -123.52782)
		(size 0.508)
		(drill 0.254)
		(layers "F.Cu" "B.Cu")
		(net "RST_SRST_PLD_BMC_R_N")
	)
	(via
		(at 178.33213 -119.842788)
		(size 0.4572)
		(drill 0.254)
		(layers "F.Cu" "B.Cu")
		(net "RST_SRST_PLD_BMC_R_N")
	)
	(segment
		(start 174.752 -121.84634)
		(end 175.972724 -120.625616)
		(width 0.10668)
		(layer "B.Cu")
		(net "RST_SRST_PLD_BMC_R_N")
	)
	(segment
		(start 175.972724 -120.625616)
		(end 176.845468 -120.625616)
		(width 0.10668)
		(layer "B.Cu")
		(net "RST_SRST_PLD_BMC_R_N")
	)
	(segment
		(start 176.845468 -120.625616)
		(end 177.320702 -120.625616)
		(width 0.10668)
		(layer "B.Cu")
		(net "RST_SRST_PLD_BMC_R_N")
	)
	(segment
		(start 167.01008 -123.52782)
		(end 167.01008 -123.708668)
		(width 0.10668)
		(layer "B.Cu")
		(net "RST_SRST_PLD_BMC_R_N")
	)
	(segment
		(start 167.01008 -123.708668)
		(end 167.356028 -124.054616)
		(width 0.10668)
		(layer "B.Cu")
		(net "RST_SRST_PLD_BMC_R_N")
	)
	(segment
		(start 172.51426 -122.01398)
		(end 172.6819 -121.84634)
		(width 0.10668)
		(layer "B.Cu")
		(net "RST_SRST_PLD_BMC_R_N")
	)
	(segment
		(start 172.00118 -122.01398)
		(end 172.51426 -122.01398)
		(width 0.10668)
		(layer "B.Cu")
		(net "RST_SRST_PLD_BMC_R_N")
	)
	(segment
		(start 178.10353 -119.842788)
		(end 178.33213 -119.842788)
		(width 0.10668)
		(layer "B.Cu")
		(net "RST_SRST_PLD_BMC_R_N")
	)
	(segment
		(start 177.320702 -120.625616)
		(end 178.10353 -119.842788)
		(width 0.10668)
		(layer "B.Cu")
		(net "RST_SRST_PLD_BMC_R_N")
	)
	(segment
		(start 167.356028 -124.054616)
		(end 169.960544 -124.054616)
		(width 0.10668)
		(layer "B.Cu")
		(net "RST_SRST_PLD_BMC_R_N")
	)
	(segment
		(start 169.960544 -124.054616)
		(end 172.00118 -122.01398)
		(width 0.10668)
		(layer "B.Cu")
		(net "RST_SRST_PLD_BMC_R_N")
	)
	(segment
		(start 172.6819 -121.84634)
		(end 174.752 -121.84634)
		(width 0.10668)
		(layer "B.Cu")
		(net "RST_SRST_PLD_BMC_R_N")
	)
	(segment
		(start 185.062114 -18.242026)
		(end 184.7088 -18.59534)
		(width 0.10668)
		(layer "F.Cu")
		(net "RST_SRST_PLD_BMC_N")
	)
	(segment
		(start 165.22446 -123.683014)
		(end 165.22446 -123.00712)
		(width 0.10668)
		(layer "F.Cu")
		(net "RST_SRST_PLD_BMC_N")
	)
	(segment
		(start 185.062114 -16.549878)
		(end 185.062114 -18.242026)
		(width 0.10668)
		(layer "F.Cu")
		(net "RST_SRST_PLD_BMC_N")
	)
	(segment
		(start 165.22446 -123.00712)
		(end 165.70452 -122.52706)
		(width 0.10668)
		(layer "F.Cu")
		(net "RST_SRST_PLD_BMC_N")
	)
	(via
		(at 165.5953 -25.37206)
		(size 0.508)
		(drill 0.254)
		(layers "F.Cu" "B.Cu")
		(net "RST_SRST_PLD_BMC_N")
	)
	(via
		(at 165.70452 -122.52706)
		(size 0.508)
		(drill 0.254)
		(layers "F.Cu" "B.Cu")
		(net "RST_SRST_PLD_BMC_N")
	)
	(via
		(at 169.44086 -97.8281)
		(size 0.508)
		(drill 0.254)
		(layers "F.Cu" "B.Cu")
		(net "RST_SRST_PLD_BMC_N")
	)
	(via
		(at 184.7088 -18.59534)
		(size 0.508)
		(drill 0.254)
		(layers "F.Cu" "B.Cu")
		(net "RST_SRST_PLD_BMC_N")
	)
	(segment
		(start 176.200816 -18.90776)
		(end 175.96866 -19.139916)
		(width 0.11684)
		(layer "In6.Cu")
		(net "RST_SRST_PLD_BMC_N")
	)
	(segment
		(start 175.96866 -19.139916)
		(end 173.328076 -19.139916)
		(width 0.11684)
		(layer "In6.Cu")
		(net "RST_SRST_PLD_BMC_N")
	)
	(segment
		(start 184.033414 -18.598642)
		(end 183.554624 -18.119852)
		(width 0.11684)
		(layer "In6.Cu")
		(net "RST_SRST_PLD_BMC_N")
	)
	(segment
		(start 183.554624 -18.119852)
		(end 181.180486 -18.119852)
		(width 0.11684)
		(layer "In6.Cu")
		(net "RST_SRST_PLD_BMC_N")
	)
	(segment
		(start 178.332384 -18.90776)
		(end 176.200816 -18.90776)
		(width 0.11684)
		(layer "In6.Cu")
		(net "RST_SRST_PLD_BMC_N")
	)
	(segment
		(start 184.705498 -18.598642)
		(end 184.033414 -18.598642)
		(width 0.11684)
		(layer "In6.Cu")
		(net "RST_SRST_PLD_BMC_N")
	)
	(segment
		(start 166.259764 -25.37206)
		(end 165.5953 -25.37206)
		(width 0.11684)
		(layer "In6.Cu")
		(net "RST_SRST_PLD_BMC_N")
	)
	(segment
		(start 168.008554 -21.010372)
		(end 168.008554 -23.62327)
		(width 0.11684)
		(layer "In6.Cu")
		(net "RST_SRST_PLD_BMC_N")
	)
	(segment
		(start 173.328076 -19.139916)
		(end 172.40504 -18.21688)
		(width 0.11684)
		(layer "In6.Cu")
		(net "RST_SRST_PLD_BMC_N")
	)
	(segment
		(start 170.802046 -18.21688)
		(end 168.008554 -21.010372)
		(width 0.11684)
		(layer "In6.Cu")
		(net "RST_SRST_PLD_BMC_N")
	)
	(segment
		(start 172.40504 -18.21688)
		(end 170.802046 -18.21688)
		(width 0.11684)
		(layer "In6.Cu")
		(net "RST_SRST_PLD_BMC_N")
	)
	(segment
		(start 168.008554 -23.62327)
		(end 166.259764 -25.37206)
		(width 0.11684)
		(layer "In6.Cu")
		(net "RST_SRST_PLD_BMC_N")
	)
	(segment
		(start 181.180486 -18.119852)
		(end 180.160422 -19.139916)
		(width 0.11684)
		(layer "In6.Cu")
		(net "RST_SRST_PLD_BMC_N")
	)
	(segment
		(start 178.56454 -19.139916)
		(end 178.332384 -18.90776)
		(width 0.11684)
		(layer "In6.Cu")
		(net "RST_SRST_PLD_BMC_N")
	)
	(segment
		(start 184.7088 -18.59534)
		(end 184.705498 -18.598642)
		(width 0.11684)
		(layer "In6.Cu")
		(net "RST_SRST_PLD_BMC_N")
	)
	(segment
		(start 180.160422 -19.139916)
		(end 178.56454 -19.139916)
		(width 0.11684)
		(layer "In6.Cu")
		(net "RST_SRST_PLD_BMC_N")
	)
	(segment
		(start 172.963332 -88.449658)
		(end 171.544488 -89.868502)
		(width 0.11684)
		(layer "In11.Cu")
		(net "RST_SRST_PLD_BMC_N")
	)
	(segment
		(start 166.803324 -56.210708)
		(end 166.803324 -79.223616)
		(width 0.11684)
		(layer "In11.Cu")
		(net "RST_SRST_PLD_BMC_N")
	)
	(segment
		(start 169.992548 -92.213938)
		(end 169.992548 -97.276412)
		(width 0.11684)
		(layer "In11.Cu")
		(net "RST_SRST_PLD_BMC_N")
	)
	(segment
		(start 171.544488 -89.868502)
		(end 171.544488 -90.661998)
		(width 0.11684)
		(layer "In11.Cu")
		(net "RST_SRST_PLD_BMC_N")
	)
	(segment
		(start 165.5953 -39.597584)
		(end 168.150032 -42.152316)
		(width 0.11684)
		(layer "In11.Cu")
		(net "RST_SRST_PLD_BMC_N")
	)
	(segment
		(start 165.379146 -54.78653)
		(end 166.803324 -56.210708)
		(width 0.11684)
		(layer "In11.Cu")
		(net "RST_SRST_PLD_BMC_N")
	)
	(segment
		(start 165.5953 -25.37206)
		(end 165.5953 -39.597584)
		(width 0.11684)
		(layer "In11.Cu")
		(net "RST_SRST_PLD_BMC_N")
	)
	(segment
		(start 171.544488 -90.661998)
		(end 169.992548 -92.213938)
		(width 0.11684)
		(layer "In11.Cu")
		(net "RST_SRST_PLD_BMC_N")
	)
	(segment
		(start 168.150032 -45.744384)
		(end 165.379146 -48.51527)
		(width 0.11684)
		(layer "In11.Cu")
		(net "RST_SRST_PLD_BMC_N")
	)
	(segment
		(start 165.379146 -48.51527)
		(end 165.379146 -54.78653)
		(width 0.11684)
		(layer "In11.Cu")
		(net "RST_SRST_PLD_BMC_N")
	)
	(segment
		(start 166.803324 -79.223616)
		(end 172.963332 -85.383624)
		(width 0.11684)
		(layer "In11.Cu")
		(net "RST_SRST_PLD_BMC_N")
	)
	(segment
		(start 168.150032 -42.152316)
		(end 168.150032 -45.744384)
		(width 0.11684)
		(layer "In11.Cu")
		(net "RST_SRST_PLD_BMC_N")
	)
	(segment
		(start 172.963332 -85.383624)
		(end 172.963332 -88.449658)
		(width 0.11684)
		(layer "In11.Cu")
		(net "RST_SRST_PLD_BMC_N")
	)
	(segment
		(start 169.992548 -97.276412)
		(end 169.44086 -97.8281)
		(width 0.11684)
		(layer "In11.Cu")
		(net "RST_SRST_PLD_BMC_N")
	)
	(segment
		(start 166.289228 -104.817672)
		(end 169.44086 -101.66604)
		(width 0.11684)
		(layer "In15.Cu")
		(net "RST_SRST_PLD_BMC_N")
	)
	(segment
		(start 165.090602 -105.51287)
		(end 165.7858 -104.817672)
		(width 0.11684)
		(layer "In15.Cu")
		(net "RST_SRST_PLD_BMC_N")
	)
	(segment
		(start 164.25418 -109.550708)
		(end 165.090602 -108.714286)
		(width 0.11684)
		(layer "In15.Cu")
		(net "RST_SRST_PLD_BMC_N")
	)
	(segment
		(start 165.7858 -104.817672)
		(end 166.289228 -104.817672)
		(width 0.11684)
		(layer "In15.Cu")
		(net "RST_SRST_PLD_BMC_N")
	)
	(segment
		(start 165.2651 -122.52706)
		(end 164.25418 -121.51614)
		(width 0.11684)
		(layer "In15.Cu")
		(net "RST_SRST_PLD_BMC_N")
	)
	(segment
		(start 169.44086 -101.66604)
		(end 169.44086 -97.8281)
		(width 0.11684)
		(layer "In15.Cu")
		(net "RST_SRST_PLD_BMC_N")
	)
	(segment
		(start 165.090602 -108.714286)
		(end 165.090602 -105.51287)
		(width 0.11684)
		(layer "In15.Cu")
		(net "RST_SRST_PLD_BMC_N")
	)
	(segment
		(start 165.70452 -122.52706)
		(end 165.2651 -122.52706)
		(width 0.11684)
		(layer "In15.Cu")
		(net "RST_SRST_PLD_BMC_N")
	)
	(segment
		(start 164.25418 -121.51614)
		(end 164.25418 -109.550708)
		(width 0.11684)
		(layer "In15.Cu")
		(net "RST_SRST_PLD_BMC_N")
	)
	(segment
		(start 184.322212 -109.052868)
		(end 183.932322 -108.662978)
		(width 0.10668)
		(layer "F.Cu")
		(net "P12V_HSC_T_CRIT_R_N")
	)
	(segment
		(start 283.216858 -404.666704)
		(end 283.21127 -404.661116)
		(width 0.10668)
		(layer "F.Cu")
		(net "P12V_HSC_T_CRIT_R_N")
	)
	(segment
		(start 283.21127 -401.987004)
		(end 283.21127 -403.335744)
		(width 0.10668)
		(layer "F.Cu")
		(net "P12V_HSC_T_CRIT_R_N")
	)
	(segment
		(start 284.342586 -395.311122)
		(end 282.586684 -397.067024)
		(width 0.10668)
		(layer "F.Cu")
		(net "P12V_HSC_T_CRIT_R_N")
	)
	(segment
		(start 283.21127 -404.661116)
		(end 283.21127 -403.335744)
		(width 0.10668)
		(layer "F.Cu")
		(net "P12V_HSC_T_CRIT_R_N")
	)
	(segment
		(start 282.812744 -401.987004)
		(end 283.21127 -401.987004)
		(width 0.10668)
		(layer "F.Cu")
		(net "P12V_HSC_T_CRIT_R_N")
	)
	(segment
		(start 282.586684 -401.760944)
		(end 282.812744 -401.987004)
		(width 0.10668)
		(layer "F.Cu")
		(net "P12V_HSC_T_CRIT_R_N")
	)
	(segment
		(start 282.586684 -397.067024)
		(end 282.586684 -401.760944)
		(width 0.10668)
		(layer "F.Cu")
		(net "P12V_HSC_T_CRIT_R_N")
	)
	(via
		(at 449.834 -324.62724)
		(size 0.508)
		(drill 0.254)
		(layers "F.Cu" "B.Cu")
		(net "P12V_HSC_T_CRIT_R_N")
	)
	(via
		(at 290.33724 -131.184904)
		(size 0.508)
		(drill 0.254)
		(layers "F.Cu" "B.Cu")
		(net "P12V_HSC_T_CRIT_R_N")
	)
	(via
		(at 183.932322 -108.662978)
		(size 0.4572)
		(drill 0.254)
		(layers "F.Cu" "B.Cu")
		(net "P12V_HSC_T_CRIT_R_N")
	)
	(via
		(at 283.21127 -403.335744)
		(size 0.762)
		(drill 0.381)
		(layers "F.Cu" "B.Cu")
		(net "P12V_HSC_T_CRIT_R_N")
	)
	(via
		(at 255.33858 -158.93034)
		(size 0.508)
		(drill 0.254)
		(layers "F.Cu" "B.Cu")
		(net "P12V_HSC_T_CRIT_R_N")
	)
	(via
		(at 284.342586 -395.311122)
		(size 0.508)
		(drill 0.254)
		(layers "F.Cu" "B.Cu")
		(net "P12V_HSC_T_CRIT_R_N")
	)
	(via
		(at 187.078112 -146.42592)
		(size 0.508)
		(drill 0.254)
		(layers "F.Cu" "B.Cu")
		(net "P12V_HSC_T_CRIT_R_N")
	)
	(via
		(at 272.619978 -368.790474)
		(size 0.508)
		(drill 0.254)
		(layers "F.Cu" "B.Cu")
		(net "P12V_HSC_T_CRIT_R_N")
	)
	(via
		(at 432.142392 -372.505478)
		(size 0.508)
		(drill 0.254)
		(layers "F.Cu" "B.Cu")
		(net "P12V_HSC_T_CRIT_R_N")
	)
	(segment
		(start 431.641758 -373.006112)
		(end 430.4792 -373.006112)
		(width 0.10668)
		(layer "B.Cu")
		(net "P12V_HSC_T_CRIT_R_N")
	)
	(segment
		(start 292.179756 -374.715024)
		(end 288.642806 -371.178074)
		(width 0.10668)
		(layer "B.Cu")
		(net "P12V_HSC_T_CRIT_R_N")
	)
	(segment
		(start 294.922448 -374.715024)
		(end 292.179756 -374.715024)
		(width 0.10668)
		(layer "B.Cu")
		(net "P12V_HSC_T_CRIT_R_N")
	)
	(segment
		(start 273.003772 -369.174268)
		(end 272.619978 -368.790474)
		(width 0.10668)
		(layer "B.Cu")
		(net "P12V_HSC_T_CRIT_R_N")
	)
	(segment
		(start 432.142392 -372.505478)
		(end 431.641758 -373.006112)
		(width 0.10668)
		(layer "B.Cu")
		(net "P12V_HSC_T_CRIT_R_N")
	)
	(segment
		(start 288.642806 -371.178074)
		(end 286.404812 -371.178074)
		(width 0.10668)
		(layer "B.Cu")
		(net "P12V_HSC_T_CRIT_R_N")
	)
	(segment
		(start 428.245016 -370.771928)
		(end 298.865544 -370.771928)
		(width 0.10668)
		(layer "B.Cu")
		(net "P12V_HSC_T_CRIT_R_N")
	)
	(segment
		(start 284.401006 -369.174268)
		(end 273.003772 -369.174268)
		(width 0.10668)
		(layer "B.Cu")
		(net "P12V_HSC_T_CRIT_R_N")
	)
	(segment
		(start 298.865544 -370.771928)
		(end 294.922448 -374.715024)
		(width 0.10668)
		(layer "B.Cu")
		(net "P12V_HSC_T_CRIT_R_N")
	)
	(segment
		(start 430.4792 -373.006112)
		(end 428.245016 -370.771928)
		(width 0.10668)
		(layer "B.Cu")
		(net "P12V_HSC_T_CRIT_R_N")
	)
	(segment
		(start 286.404812 -371.178074)
		(end 284.401006 -369.174268)
		(width 0.10668)
		(layer "B.Cu")
		(net "P12V_HSC_T_CRIT_R_N")
	)
	(segment
		(start 283.628338 -387.029198)
		(end 283.628338 -390.12749)
		(width 0.11684)
		(layer "In4.Cu")
		(net "P12V_HSC_T_CRIT_R_N")
	)
	(segment
		(start 284.755844 -391.254996)
		(end 284.755844 -394.897864)
		(width 0.11684)
		(layer "In4.Cu")
		(net "P12V_HSC_T_CRIT_R_N")
	)
	(segment
		(start 283.329634 -371.556534)
		(end 284.480254 -372.707154)
		(width 0.11684)
		(layer "In4.Cu")
		(net "P12V_HSC_T_CRIT_R_N")
	)
	(segment
		(start 185.72734 -119.7229)
		(end 185.72734 -127.4445)
		(width 0.11684)
		(layer "In4.Cu")
		(net "P12V_HSC_T_CRIT_R_N")
	)
	(segment
		(start 183.932322 -108.871258)
		(end 183.520842 -109.282738)
		(width 0.11684)
		(layer "In4.Cu")
		(net "P12V_HSC_T_CRIT_R_N")
	)
	(segment
		(start 284.480254 -374.696736)
		(end 282.39085 -376.78614)
		(width 0.11684)
		(layer "In4.Cu")
		(net "P12V_HSC_T_CRIT_R_N")
	)
	(segment
		(start 186.283346 -132.673598)
		(end 186.60618 -132.996432)
		(width 0.11684)
		(layer "In4.Cu")
		(net "P12V_HSC_T_CRIT_R_N")
	)
	(segment
		(start 275.932392 -371.556534)
		(end 283.329634 -371.556534)
		(width 0.11684)
		(layer "In4.Cu")
		(net "P12V_HSC_T_CRIT_R_N")
	)
	(segment
		(start 187.64758 -139.24026)
		(end 187.0075 -139.88034)
		(width 0.11684)
		(layer "In4.Cu")
		(net "P12V_HSC_T_CRIT_R_N")
	)
	(segment
		(start 187.466732 -144.461484)
		(end 187.466732 -146.0373)
		(width 0.11684)
		(layer "In4.Cu")
		(net "P12V_HSC_T_CRIT_R_N")
	)
	(segment
		(start 272.97253 -369.143026)
		(end 273.518884 -369.143026)
		(width 0.11684)
		(layer "In4.Cu")
		(net "P12V_HSC_T_CRIT_R_N")
	)
	(segment
		(start 283.628338 -390.12749)
		(end 284.755844 -391.254996)
		(width 0.11684)
		(layer "In4.Cu")
		(net "P12V_HSC_T_CRIT_R_N")
	)
	(segment
		(start 186.60618 -137.417302)
		(end 187.64758 -138.458702)
		(width 0.11684)
		(layer "In4.Cu")
		(net "P12V_HSC_T_CRIT_R_N")
	)
	(segment
		(start 185.46064 -115.58016)
		(end 185.46064 -119.4562)
		(width 0.11684)
		(layer "In4.Cu")
		(net "P12V_HSC_T_CRIT_R_N")
	)
	(segment
		(start 282.39085 -376.78614)
		(end 282.39085 -385.79171)
		(width 0.11684)
		(layer "In4.Cu")
		(net "P12V_HSC_T_CRIT_R_N")
	)
	(segment
		(start 185.72734 -127.4445)
		(end 187.005468 -128.722628)
		(width 0.11684)
		(layer "In4.Cu")
		(net "P12V_HSC_T_CRIT_R_N")
	)
	(segment
		(start 284.480254 -372.707154)
		(end 284.480254 -374.696736)
		(width 0.11684)
		(layer "In4.Cu")
		(net "P12V_HSC_T_CRIT_R_N")
	)
	(segment
		(start 282.39085 -385.79171)
		(end 283.628338 -387.029198)
		(width 0.11684)
		(layer "In4.Cu")
		(net "P12V_HSC_T_CRIT_R_N")
	)
	(segment
		(start 273.518884 -369.143026)
		(end 275.932392 -371.556534)
		(width 0.11684)
		(layer "In4.Cu")
		(net "P12V_HSC_T_CRIT_R_N")
	)
	(segment
		(start 183.520842 -114.465862)
		(end 184.14746 -115.09248)
		(width 0.11684)
		(layer "In4.Cu")
		(net "P12V_HSC_T_CRIT_R_N")
	)
	(segment
		(start 262.591804 -158.93034)
		(end 290.33724 -131.184904)
		(width 0.11684)
		(layer "In4.Cu")
		(net "P12V_HSC_T_CRIT_R_N")
	)
	(segment
		(start 187.0075 -139.88034)
		(end 187.0075 -144.002252)
		(width 0.11684)
		(layer "In4.Cu")
		(net "P12V_HSC_T_CRIT_R_N")
	)
	(segment
		(start 272.619978 -368.790474)
		(end 272.97253 -369.143026)
		(width 0.11684)
		(layer "In4.Cu")
		(net "P12V_HSC_T_CRIT_R_N")
	)
	(segment
		(start 187.005468 -130.61442)
		(end 186.283346 -131.336542)
		(width 0.11684)
		(layer "In4.Cu")
		(net "P12V_HSC_T_CRIT_R_N")
	)
	(segment
		(start 184.14746 -115.09248)
		(end 184.97296 -115.09248)
		(width 0.11684)
		(layer "In4.Cu")
		(net "P12V_HSC_T_CRIT_R_N")
	)
	(segment
		(start 255.33858 -158.93034)
		(end 262.591804 -158.93034)
		(width 0.11684)
		(layer "In4.Cu")
		(net "P12V_HSC_T_CRIT_R_N")
	)
	(segment
		(start 183.520842 -109.282738)
		(end 183.520842 -114.465862)
		(width 0.11684)
		(layer "In4.Cu")
		(net "P12V_HSC_T_CRIT_R_N")
	)
	(segment
		(start 183.932322 -108.662978)
		(end 183.932322 -108.871258)
		(width 0.11684)
		(layer "In4.Cu")
		(net "P12V_HSC_T_CRIT_R_N")
	)
	(segment
		(start 187.0075 -144.002252)
		(end 187.466732 -144.461484)
		(width 0.11684)
		(layer "In4.Cu")
		(net "P12V_HSC_T_CRIT_R_N")
	)
	(segment
		(start 187.005468 -128.722628)
		(end 187.005468 -130.61442)
		(width 0.11684)
		(layer "In4.Cu")
		(net "P12V_HSC_T_CRIT_R_N")
	)
	(segment
		(start 187.466732 -146.0373)
		(end 187.078112 -146.42592)
		(width 0.11684)
		(layer "In4.Cu")
		(net "P12V_HSC_T_CRIT_R_N")
	)
	(segment
		(start 184.97296 -115.09248)
		(end 185.46064 -115.58016)
		(width 0.11684)
		(layer "In4.Cu")
		(net "P12V_HSC_T_CRIT_R_N")
	)
	(segment
		(start 185.46064 -119.4562)
		(end 185.72734 -119.7229)
		(width 0.11684)
		(layer "In4.Cu")
		(net "P12V_HSC_T_CRIT_R_N")
	)
	(segment
		(start 187.64758 -138.458702)
		(end 187.64758 -139.24026)
		(width 0.11684)
		(layer "In4.Cu")
		(net "P12V_HSC_T_CRIT_R_N")
	)
	(segment
		(start 186.60618 -132.996432)
		(end 186.60618 -137.417302)
		(width 0.11684)
		(layer "In4.Cu")
		(net "P12V_HSC_T_CRIT_R_N")
	)
	(segment
		(start 284.755844 -394.897864)
		(end 284.342586 -395.311122)
		(width 0.11684)
		(layer "In4.Cu")
		(net "P12V_HSC_T_CRIT_R_N")
	)
	(segment
		(start 186.283346 -131.336542)
		(end 186.283346 -132.673598)
		(width 0.11684)
		(layer "In4.Cu")
		(net "P12V_HSC_T_CRIT_R_N")
	)
	(segment
		(start 188.38926 -145.756884)
		(end 194.14871 -145.756884)
		(width 0.11684)
		(layer "In6.Cu")
		(net "P12V_HSC_T_CRIT_R_N")
	)
	(segment
		(start 202.28687 -149.127718)
		(end 226.130358 -149.127718)
		(width 0.11684)
		(layer "In6.Cu")
		(net "P12V_HSC_T_CRIT_R_N")
	)
	(segment
		(start 235.97108 -151.75484)
		(end 238.91494 -154.6987)
		(width 0.11684)
		(layer "In6.Cu")
		(net "P12V_HSC_T_CRIT_R_N")
	)
	(segment
		(start 246.23776 -154.6987)
		(end 249.2375 -157.69844)
		(width 0.11684)
		(layer "In6.Cu")
		(net "P12V_HSC_T_CRIT_R_N")
	)
	(segment
		(start 194.14871 -145.756884)
		(end 202.28687 -149.127718)
		(width 0.11684)
		(layer "In6.Cu")
		(net "P12V_HSC_T_CRIT_R_N")
	)
	(segment
		(start 255.33858 -158.9024)
		(end 255.33858 -158.93034)
		(width 0.11684)
		(layer "In6.Cu")
		(net "P12V_HSC_T_CRIT_R_N")
	)
	(segment
		(start 254.13462 -157.69844)
		(end 255.33858 -158.9024)
		(width 0.11684)
		(layer "In6.Cu")
		(net "P12V_HSC_T_CRIT_R_N")
	)
	(segment
		(start 238.91494 -154.6987)
		(end 246.23776 -154.6987)
		(width 0.11684)
		(layer "In6.Cu")
		(net "P12V_HSC_T_CRIT_R_N")
	)
	(segment
		(start 226.130358 -149.127718)
		(end 228.75748 -151.75484)
		(width 0.11684)
		(layer "In6.Cu")
		(net "P12V_HSC_T_CRIT_R_N")
	)
	(segment
		(start 187.720224 -146.42592)
		(end 188.38926 -145.756884)
		(width 0.11684)
		(layer "In6.Cu")
		(net "P12V_HSC_T_CRIT_R_N")
	)
	(segment
		(start 249.2375 -157.69844)
		(end 254.13462 -157.69844)
		(width 0.11684)
		(layer "In6.Cu")
		(net "P12V_HSC_T_CRIT_R_N")
	)
	(segment
		(start 228.75748 -151.75484)
		(end 235.97108 -151.75484)
		(width 0.11684)
		(layer "In6.Cu")
		(net "P12V_HSC_T_CRIT_R_N")
	)
	(segment
		(start 187.078112 -146.42592)
		(end 187.720224 -146.42592)
		(width 0.11684)
		(layer "In6.Cu")
		(net "P12V_HSC_T_CRIT_R_N")
	)
	(segment
		(start 444.913512 -368.63528)
		(end 451.08114 -362.467652)
		(width 0.11684)
		(layer "In11.Cu")
		(net "P12V_HSC_T_CRIT_R_N")
	)
	(segment
		(start 450.14642 -341.51062)
		(end 450.14642 -325.13778)
		(width 0.11684)
		(layer "In11.Cu")
		(net "P12V_HSC_T_CRIT_R_N")
	)
	(segment
		(start 437.66994 -368.63528)
		(end 444.913512 -368.63528)
		(width 0.11684)
		(layer "In11.Cu")
		(net "P12V_HSC_T_CRIT_R_N")
	)
	(segment
		(start 433.611274 -372.693946)
		(end 437.66994 -368.63528)
		(width 0.11684)
		(layer "In11.Cu")
		(net "P12V_HSC_T_CRIT_R_N")
	)
	(segment
		(start 432.142392 -372.505478)
		(end 432.33086 -372.693946)
		(width 0.11684)
		(layer "In11.Cu")
		(net "P12V_HSC_T_CRIT_R_N")
	)
	(segment
		(start 449.834 -324.82536)
		(end 449.834 -324.62724)
		(width 0.11684)
		(layer "In11.Cu")
		(net "P12V_HSC_T_CRIT_R_N")
	)
	(segment
		(start 432.33086 -372.693946)
		(end 433.611274 -372.693946)
		(width 0.11684)
		(layer "In11.Cu")
		(net "P12V_HSC_T_CRIT_R_N")
	)
	(segment
		(start 451.08114 -362.467652)
		(end 451.08114 -342.44534)
		(width 0.11684)
		(layer "In11.Cu")
		(net "P12V_HSC_T_CRIT_R_N")
	)
	(segment
		(start 451.08114 -342.44534)
		(end 450.14642 -341.51062)
		(width 0.11684)
		(layer "In11.Cu")
		(net "P12V_HSC_T_CRIT_R_N")
	)
	(segment
		(start 450.14642 -325.13778)
		(end 449.834 -324.82536)
		(width 0.11684)
		(layer "In11.Cu")
		(net "P12V_HSC_T_CRIT_R_N")
	)
	(segment
		(start 454.658222 -325.756016)
		(end 450.962776 -325.756016)
		(width 0.11684)
		(layer "In15.Cu")
		(net "P12V_HSC_T_CRIT_R_N")
	)
	(segment
		(start 373.593868 -129.480056)
		(end 445.249554 -129.480056)
		(width 0.11684)
		(layer "In15.Cu")
		(net "P12V_HSC_T_CRIT_R_N")
	)
	(segment
		(start 293.996618 -130.946398)
		(end 298.575476 -126.36754)
		(width 0.11684)
		(layer "In15.Cu")
		(net "P12V_HSC_T_CRIT_R_N")
	)
	(segment
		(start 454.854818 -139.08532)
		(end 454.854818 -150.842726)
		(width 0.11684)
		(layer "In15.Cu")
		(net "P12V_HSC_T_CRIT_R_N")
	)
	(segment
		(start 453.981058 -166.829486)
		(end 461.322928 -174.171356)
		(width 0.11684)
		(layer "In15.Cu")
		(net "P12V_HSC_T_CRIT_R_N")
	)
	(segment
		(start 454.854818 -150.842726)
		(end 453.981058 -151.716486)
		(width 0.11684)
		(layer "In15.Cu")
		(net "P12V_HSC_T_CRIT_R_N")
	)
	(segment
		(start 290.575746 -130.946398)
		(end 293.996618 -130.946398)
		(width 0.11684)
		(layer "In15.Cu")
		(net "P12V_HSC_T_CRIT_R_N")
	)
	(segment
		(start 461.322928 -174.171356)
		(end 461.322928 -319.09131)
		(width 0.11684)
		(layer "In15.Cu")
		(net "P12V_HSC_T_CRIT_R_N")
	)
	(segment
		(start 453.981058 -151.716486)
		(end 453.981058 -166.829486)
		(width 0.11684)
		(layer "In15.Cu")
		(net "P12V_HSC_T_CRIT_R_N")
	)
	(segment
		(start 461.322928 -319.09131)
		(end 454.658222 -325.756016)
		(width 0.11684)
		(layer "In15.Cu")
		(net "P12V_HSC_T_CRIT_R_N")
	)
	(segment
		(start 450.962776 -325.756016)
		(end 449.834 -324.62724)
		(width 0.11684)
		(layer "In15.Cu")
		(net "P12V_HSC_T_CRIT_R_N")
	)
	(segment
		(start 298.575476 -126.36754)
		(end 370.481352 -126.36754)
		(width 0.11684)
		(layer "In15.Cu")
		(net "P12V_HSC_T_CRIT_R_N")
	)
	(segment
		(start 445.249554 -129.480056)
		(end 454.854818 -139.08532)
		(width 0.11684)
		(layer "In15.Cu")
		(net "P12V_HSC_T_CRIT_R_N")
	)
	(segment
		(start 370.481352 -126.36754)
		(end 373.593868 -129.480056)
		(width 0.11684)
		(layer "In15.Cu")
		(net "P12V_HSC_T_CRIT_R_N")
	)
	(segment
		(start 290.33724 -131.184904)
		(end 290.575746 -130.946398)
		(width 0.11684)
		(layer "In15.Cu")
		(net "P12V_HSC_T_CRIT_R_N")
	)
	(segment
		(start 283.21127 -399.629884)
		(end 283.21127 -399.147538)
		(width 0.10668)
		(layer "F.Cu")
		(net "P12V_HSC_T_CRIT_N")
	)
	(segment
		(start 284.243018 -398.11579)
		(end 284.243018 -397.570198)
		(width 0.10668)
		(layer "F.Cu")
		(net "P12V_HSC_T_CRIT_N")
	)
	(segment
		(start 283.21127 -401.186904)
		(end 283.21127 -399.629884)
		(width 0.10668)
		(layer "F.Cu")
		(net "P12V_HSC_T_CRIT_N")
	)
	(segment
		(start 283.21127 -399.147538)
		(end 284.243018 -398.11579)
		(width 0.10668)
		(layer "F.Cu")
		(net "P12V_HSC_T_CRIT_N")
	)
	(via
		(at 283.21127 -399.629884)
		(size 0.762)
		(drill 0.381)
		(layers "F.Cu" "B.Cu")
		(net "P12V_HSC_T_CRIT_N")
	)
	(segment
		(start 281.818588 -393.115038)
		(end 281.827732 -393.105894)
		(width 0.10668)
		(layer "F.Cu")
		(net "P12V_HSC_TEMP_ALERT_R_N")
	)
	(segment
		(start 186.722004 -111.452914)
		(end 187.111894 -111.063024)
		(width 0.10668)
		(layer "F.Cu")
		(net "P12V_HSC_TEMP_ALERT_R_N")
	)
	(segment
		(start 281.827732 -393.105894)
		(end 282.582366 -393.105894)
		(width 0.10668)
		(layer "F.Cu")
		(net "P12V_HSC_TEMP_ALERT_R_N")
	)
	(segment
		(start 281.818588 -394.044932)
		(end 281.818588 -393.115038)
		(width 0.10668)
		(layer "F.Cu")
		(net "P12V_HSC_TEMP_ALERT_R_N")
	)
	(via
		(at 194.320414 -143.730218)
		(size 0.508)
		(drill 0.254)
		(layers "F.Cu" "B.Cu")
		(net "P12V_HSC_TEMP_ALERT_R_N")
	)
	(via
		(at 433.132484 -372.19255)
		(size 0.508)
		(drill 0.254)
		(layers "F.Cu" "B.Cu")
		(net "P12V_HSC_TEMP_ALERT_R_N")
	)
	(via
		(at 449.4911 -325.1708)
		(size 0.508)
		(drill 0.254)
		(layers "F.Cu" "B.Cu")
		(net "P12V_HSC_TEMP_ALERT_R_N")
	)
	(via
		(at 261.24916 -157.734)
		(size 0.508)
		(drill 0.254)
		(layers "F.Cu" "B.Cu")
		(net "P12V_HSC_TEMP_ALERT_R_N")
	)
	(via
		(at 289.39744 -131.071874)
		(size 0.508)
		(drill 0.254)
		(layers "F.Cu" "B.Cu")
		(net "P12V_HSC_TEMP_ALERT_R_N")
	)
	(via
		(at 282.582366 -393.105894)
		(size 0.508)
		(drill 0.254)
		(layers "F.Cu" "B.Cu")
		(net "P12V_HSC_TEMP_ALERT_R_N")
	)
	(via
		(at 187.111894 -111.063024)
		(size 0.4572)
		(drill 0.254)
		(layers "F.Cu" "B.Cu")
		(net "P12V_HSC_TEMP_ALERT_R_N")
	)
	(via
		(at 271.859248 -368.815112)
		(size 0.508)
		(drill 0.254)
		(layers "F.Cu" "B.Cu")
		(net "P12V_HSC_TEMP_ALERT_R_N")
	)
	(segment
		(start 284.281118 -369.52682)
		(end 272.570956 -369.52682)
		(width 0.10668)
		(layer "B.Cu")
		(net "P12V_HSC_TEMP_ALERT_R_N")
	)
	(segment
		(start 295.015412 -374.938544)
		(end 291.919152 -374.938544)
		(width 0.10668)
		(layer "B.Cu")
		(net "P12V_HSC_TEMP_ALERT_R_N")
	)
	(segment
		(start 428.162212 -371.005608)
		(end 298.948348 -371.005608)
		(width 0.10668)
		(layer "B.Cu")
		(net "P12V_HSC_TEMP_ALERT_R_N")
	)
	(segment
		(start 291.919152 -374.938544)
		(end 288.492692 -371.512084)
		(width 0.10668)
		(layer "B.Cu")
		(net "P12V_HSC_TEMP_ALERT_R_N")
	)
	(segment
		(start 430.49571 -373.339106)
		(end 428.162212 -371.005608)
		(width 0.10668)
		(layer "B.Cu")
		(net "P12V_HSC_TEMP_ALERT_R_N")
	)
	(segment
		(start 288.492692 -371.512084)
		(end 286.266382 -371.512084)
		(width 0.10668)
		(layer "B.Cu")
		(net "P12V_HSC_TEMP_ALERT_R_N")
	)
	(segment
		(start 433.132484 -372.19255)
		(end 431.985928 -373.339106)
		(width 0.10668)
		(layer "B.Cu")
		(net "P12V_HSC_TEMP_ALERT_R_N")
	)
	(segment
		(start 286.266382 -371.512084)
		(end 284.281118 -369.52682)
		(width 0.10668)
		(layer "B.Cu")
		(net "P12V_HSC_TEMP_ALERT_R_N")
	)
	(segment
		(start 431.985928 -373.339106)
		(end 430.49571 -373.339106)
		(width 0.10668)
		(layer "B.Cu")
		(net "P12V_HSC_TEMP_ALERT_R_N")
	)
	(segment
		(start 272.570956 -369.52682)
		(end 271.859248 -368.815112)
		(width 0.10668)
		(layer "B.Cu")
		(net "P12V_HSC_TEMP_ALERT_R_N")
	)
	(segment
		(start 298.948348 -371.005608)
		(end 295.015412 -374.938544)
		(width 0.10668)
		(layer "B.Cu")
		(net "P12V_HSC_TEMP_ALERT_R_N")
	)
	(segment
		(start 193.70802 -142.441422)
		(end 194.077082 -143.333978)
		(width 0.11684)
		(layer "In4.Cu")
		(net "P12V_HSC_TEMP_ALERT_R_N")
	)
	(segment
		(start 279.217628 -378.906024)
		(end 279.217628 -380.064518)
		(width 0.11684)
		(layer "In4.Cu")
		(net "P12V_HSC_TEMP_ALERT_R_N")
	)
	(segment
		(start 192.856866 -130.161792)
		(end 192.856866 -131.77266)
		(width 0.11684)
		(layer "In4.Cu")
		(net "P12V_HSC_TEMP_ALERT_R_N")
	)
	(segment
		(start 274.520152 -372.186708)
		(end 276.774402 -372.186708)
		(width 0.11684)
		(layer "In4.Cu")
		(net "P12V_HSC_TEMP_ALERT_R_N")
	)
	(segment
		(start 188.75502 -126.389384)
		(end 191.348106 -128.98247)
		(width 0.11684)
		(layer "In4.Cu")
		(net "P12V_HSC_TEMP_ALERT_R_N")
	)
	(segment
		(start 271.859248 -368.815112)
		(end 271.859248 -369.525804)
		(width 0.11684)
		(layer "In4.Cu")
		(net "P12V_HSC_TEMP_ALERT_R_N")
	)
	(segment
		(start 279.975818 -380.822708)
		(end 279.975818 -390.499346)
		(width 0.11684)
		(layer "In4.Cu")
		(net "P12V_HSC_TEMP_ALERT_R_N")
	)
	(segment
		(start 191.677544 -128.98247)
		(end 192.856866 -130.161792)
		(width 0.11684)
		(layer "In4.Cu")
		(net "P12V_HSC_TEMP_ALERT_R_N")
	)
	(segment
		(start 289.39744 -131.55676)
		(end 289.39744 -131.071874)
		(width 0.11684)
		(layer "In4.Cu")
		(net "P12V_HSC_TEMP_ALERT_R_N")
	)
	(segment
		(start 271.859248 -369.525804)
		(end 274.520152 -372.186708)
		(width 0.11684)
		(layer "In4.Cu")
		(net "P12V_HSC_TEMP_ALERT_R_N")
	)
	(segment
		(start 188.310774 -111.59871)
		(end 188.310774 -124.953014)
		(width 0.11684)
		(layer "In4.Cu")
		(net "P12V_HSC_TEMP_ALERT_R_N")
	)
	(segment
		(start 279.975818 -390.499346)
		(end 282.582366 -393.105894)
		(width 0.11684)
		(layer "In4.Cu")
		(net "P12V_HSC_TEMP_ALERT_R_N")
	)
	(segment
		(start 193.70802 -134.12724)
		(end 193.70802 -142.441422)
		(width 0.11684)
		(layer "In4.Cu")
		(net "P12V_HSC_TEMP_ALERT_R_N")
	)
	(segment
		(start 194.077082 -143.333978)
		(end 194.21221 -143.469106)
		(width 0.11684)
		(layer "In4.Cu")
		(net "P12V_HSC_TEMP_ALERT_R_N")
	)
	(segment
		(start 279.89149 -375.303796)
		(end 279.89149 -378.232162)
		(width 0.11684)
		(layer "In4.Cu")
		(net "P12V_HSC_TEMP_ALERT_R_N")
	)
	(segment
		(start 194.21221 -143.469106)
		(end 194.320414 -143.730218)
		(width 0.11684)
		(layer "In4.Cu")
		(net "P12V_HSC_TEMP_ALERT_R_N")
	)
	(segment
		(start 187.111894 -111.063024)
		(end 187.52058 -111.47171)
		(width 0.11684)
		(layer "In4.Cu")
		(net "P12V_HSC_TEMP_ALERT_R_N")
	)
	(segment
		(start 187.52058 -111.47171)
		(end 188.183774 -111.47171)
		(width 0.11684)
		(layer "In4.Cu")
		(net "P12V_HSC_TEMP_ALERT_R_N")
	)
	(segment
		(start 188.75502 -125.39726)
		(end 188.75502 -126.389384)
		(width 0.11684)
		(layer "In4.Cu")
		(net "P12V_HSC_TEMP_ALERT_R_N")
	)
	(segment
		(start 263.2202 -157.734)
		(end 289.39744 -131.55676)
		(width 0.11684)
		(layer "In4.Cu")
		(net "P12V_HSC_TEMP_ALERT_R_N")
	)
	(segment
		(start 188.310774 -124.953014)
		(end 188.75502 -125.39726)
		(width 0.11684)
		(layer "In4.Cu")
		(net "P12V_HSC_TEMP_ALERT_R_N")
	)
	(segment
		(start 279.217628 -380.064518)
		(end 279.975818 -380.822708)
		(width 0.11684)
		(layer "In4.Cu")
		(net "P12V_HSC_TEMP_ALERT_R_N")
	)
	(segment
		(start 188.183774 -111.47171)
		(end 188.310774 -111.59871)
		(width 0.11684)
		(layer "In4.Cu")
		(net "P12V_HSC_TEMP_ALERT_R_N")
	)
	(segment
		(start 192.856866 -131.77266)
		(end 192.568068 -132.061458)
		(width 0.11684)
		(layer "In4.Cu")
		(net "P12V_HSC_TEMP_ALERT_R_N")
	)
	(segment
		(start 192.568068 -132.061458)
		(end 192.568068 -132.987288)
		(width 0.11684)
		(layer "In4.Cu")
		(net "P12V_HSC_TEMP_ALERT_R_N")
	)
	(segment
		(start 261.24916 -157.734)
		(end 263.2202 -157.734)
		(width 0.11684)
		(layer "In4.Cu")
		(net "P12V_HSC_TEMP_ALERT_R_N")
	)
	(segment
		(start 191.348106 -128.98247)
		(end 191.677544 -128.98247)
		(width 0.11684)
		(layer "In4.Cu")
		(net "P12V_HSC_TEMP_ALERT_R_N")
	)
	(segment
		(start 276.774402 -372.186708)
		(end 279.89149 -375.303796)
		(width 0.11684)
		(layer "In4.Cu")
		(net "P12V_HSC_TEMP_ALERT_R_N")
	)
	(segment
		(start 192.568068 -132.987288)
		(end 193.70802 -134.12724)
		(width 0.11684)
		(layer "In4.Cu")
		(net "P12V_HSC_TEMP_ALERT_R_N")
	)
	(segment
		(start 279.89149 -378.232162)
		(end 279.217628 -378.906024)
		(width 0.11684)
		(layer "In4.Cu")
		(net "P12V_HSC_TEMP_ALERT_R_N")
	)
	(segment
		(start 199.636126 -144.873218)
		(end 200.180956 -145.418048)
		(width 0.11684)
		(layer "In6.Cu")
		(net "P12V_HSC_TEMP_ALERT_R_N")
	)
	(segment
		(start 194.471036 -143.88084)
		(end 196.865748 -144.873218)
		(width 0.11684)
		(layer "In6.Cu")
		(net "P12V_HSC_TEMP_ALERT_R_N")
	)
	(segment
		(start 248.69013 -156.379164)
		(end 248.69013 -156.51353)
		(width 0.11684)
		(layer "In6.Cu")
		(net "P12V_HSC_TEMP_ALERT_R_N")
	)
	(segment
		(start 218.501468 -145.418048)
		(end 219.85224 -146.76882)
		(width 0.11684)
		(layer "In6.Cu")
		(net "P12V_HSC_TEMP_ALERT_R_N")
	)
	(segment
		(start 231.26446 -149.27834)
		(end 234.53852 -149.27834)
		(width 0.11684)
		(layer "In6.Cu")
		(net "P12V_HSC_TEMP_ALERT_R_N")
	)
	(segment
		(start 249.430794 -157.254194)
		(end 260.769354 -157.254194)
		(width 0.11684)
		(layer "In6.Cu")
		(net "P12V_HSC_TEMP_ALERT_R_N")
	)
	(segment
		(start 228.75494 -146.76882)
		(end 231.26446 -149.27834)
		(width 0.11684)
		(layer "In6.Cu")
		(net "P12V_HSC_TEMP_ALERT_R_N")
	)
	(segment
		(start 219.85224 -146.76882)
		(end 228.75494 -146.76882)
		(width 0.11684)
		(layer "In6.Cu")
		(net "P12V_HSC_TEMP_ALERT_R_N")
	)
	(segment
		(start 200.180956 -145.418048)
		(end 218.501468 -145.418048)
		(width 0.11684)
		(layer "In6.Cu")
		(net "P12V_HSC_TEMP_ALERT_R_N")
	)
	(segment
		(start 194.320414 -143.730218)
		(end 194.471036 -143.88084)
		(width 0.11684)
		(layer "In6.Cu")
		(net "P12V_HSC_TEMP_ALERT_R_N")
	)
	(segment
		(start 260.769354 -157.254194)
		(end 261.24916 -157.734)
		(width 0.11684)
		(layer "In6.Cu")
		(net "P12V_HSC_TEMP_ALERT_R_N")
	)
	(segment
		(start 234.53852 -149.27834)
		(end 239.460532 -154.200352)
		(width 0.11684)
		(layer "In6.Cu")
		(net "P12V_HSC_TEMP_ALERT_R_N")
	)
	(segment
		(start 248.69013 -156.51353)
		(end 249.430794 -157.254194)
		(width 0.11684)
		(layer "In6.Cu")
		(net "P12V_HSC_TEMP_ALERT_R_N")
	)
	(segment
		(start 239.460532 -154.200352)
		(end 246.511318 -154.200352)
		(width 0.11684)
		(layer "In6.Cu")
		(net "P12V_HSC_TEMP_ALERT_R_N")
	)
	(segment
		(start 246.511318 -154.200352)
		(end 248.69013 -156.379164)
		(width 0.11684)
		(layer "In6.Cu")
		(net "P12V_HSC_TEMP_ALERT_R_N")
	)
	(segment
		(start 196.865748 -144.873218)
		(end 199.636126 -144.873218)
		(width 0.11684)
		(layer "In6.Cu")
		(net "P12V_HSC_TEMP_ALERT_R_N")
	)
	(segment
		(start 444.633096 -368.03584)
		(end 437.55564 -368.03584)
		(width 0.11684)
		(layer "In11.Cu")
		(net "P12V_HSC_TEMP_ALERT_R_N")
	)
	(segment
		(start 437.55564 -368.03584)
		(end 433.39893 -372.19255)
		(width 0.11684)
		(layer "In11.Cu")
		(net "P12V_HSC_TEMP_ALERT_R_N")
	)
	(segment
		(start 449.4911 -325.1708)
		(end 449.4911 -341.79002)
		(width 0.11684)
		(layer "In11.Cu")
		(net "P12V_HSC_TEMP_ALERT_R_N")
	)
	(segment
		(start 450.41312 -342.71204)
		(end 450.41312 -362.255816)
		(width 0.11684)
		(layer "In11.Cu")
		(net "P12V_HSC_TEMP_ALERT_R_N")
	)
	(segment
		(start 449.4911 -341.79002)
		(end 450.41312 -342.71204)
		(width 0.11684)
		(layer "In11.Cu")
		(net "P12V_HSC_TEMP_ALERT_R_N")
	)
	(segment
		(start 450.41312 -362.255816)
		(end 444.633096 -368.03584)
		(width 0.11684)
		(layer "In11.Cu")
		(net "P12V_HSC_TEMP_ALERT_R_N")
	)
	(segment
		(start 433.39893 -372.19255)
		(end 433.132484 -372.19255)
		(width 0.11684)
		(layer "In11.Cu")
		(net "P12V_HSC_TEMP_ALERT_R_N")
	)
	(segment
		(start 454.699878 -326.166988)
		(end 450.487288 -326.166988)
		(width 0.11684)
		(layer "In15.Cu")
		(net "P12V_HSC_TEMP_ALERT_R_N")
	)
	(segment
		(start 371.059964 -126.0475)
		(end 374.153176 -129.140712)
		(width 0.11684)
		(layer "In15.Cu")
		(net "P12V_HSC_TEMP_ALERT_R_N")
	)
	(segment
		(start 455.174858 -151.194516)
		(end 454.301098 -152.068276)
		(width 0.11684)
		(layer "In15.Cu")
		(net "P12V_HSC_TEMP_ALERT_R_N")
	)
	(segment
		(start 298.442888 -126.0475)
		(end 371.059964 -126.0475)
		(width 0.11684)
		(layer "In15.Cu")
		(net "P12V_HSC_TEMP_ALERT_R_N")
	)
	(segment
		(start 374.153176 -129.140712)
		(end 445.362838 -129.140712)
		(width 0.11684)
		(layer "In15.Cu")
		(net "P12V_HSC_TEMP_ALERT_R_N")
	)
	(segment
		(start 461.642968 -319.223898)
		(end 454.699878 -326.166988)
		(width 0.11684)
		(layer "In15.Cu")
		(net "P12V_HSC_TEMP_ALERT_R_N")
	)
	(segment
		(start 445.362838 -129.140712)
		(end 455.174858 -138.952732)
		(width 0.11684)
		(layer "In15.Cu")
		(net "P12V_HSC_TEMP_ALERT_R_N")
	)
	(segment
		(start 455.174858 -138.952732)
		(end 455.174858 -151.194516)
		(width 0.11684)
		(layer "In15.Cu")
		(net "P12V_HSC_TEMP_ALERT_R_N")
	)
	(segment
		(start 454.301098 -152.068276)
		(end 454.301098 -166.547546)
		(width 0.11684)
		(layer "In15.Cu")
		(net "P12V_HSC_TEMP_ALERT_R_N")
	)
	(segment
		(start 461.642968 -173.889416)
		(end 461.642968 -319.223898)
		(width 0.11684)
		(layer "In15.Cu")
		(net "P12V_HSC_TEMP_ALERT_R_N")
	)
	(segment
		(start 289.842956 -130.626358)
		(end 293.86403 -130.626358)
		(width 0.11684)
		(layer "In15.Cu")
		(net "P12V_HSC_TEMP_ALERT_R_N")
	)
	(segment
		(start 293.86403 -130.626358)
		(end 298.442888 -126.0475)
		(width 0.11684)
		(layer "In15.Cu")
		(net "P12V_HSC_TEMP_ALERT_R_N")
	)
	(segment
		(start 289.39744 -131.071874)
		(end 289.842956 -130.626358)
		(width 0.11684)
		(layer "In15.Cu")
		(net "P12V_HSC_TEMP_ALERT_R_N")
	)
	(segment
		(start 450.487288 -326.166988)
		(end 449.4911 -325.1708)
		(width 0.11684)
		(layer "In15.Cu")
		(net "P12V_HSC_TEMP_ALERT_R_N")
	)
	(segment
		(start 454.301098 -166.547546)
		(end 461.642968 -173.889416)
		(width 0.11684)
		(layer "In15.Cu")
		(net "P12V_HSC_TEMP_ALERT_R_N")
	)
	(segment
		(start 284.893004 -392.870182)
		(end 284.893004 -394.087096)
		(width 0.10668)
		(layer "F.Cu")
		(net "P12V_HSC_TEMP_ALERT_N")
	)
	(segment
		(start 284.135068 -394.845032)
		(end 282.744418 -394.845032)
		(width 0.10668)
		(layer "F.Cu")
		(net "P12V_HSC_TEMP_ALERT_N")
	)
	(segment
		(start 282.744418 -394.845032)
		(end 281.818588 -394.845032)
		(width 0.10668)
		(layer "F.Cu")
		(net "P12V_HSC_TEMP_ALERT_N")
	)
	(segment
		(start 284.893004 -394.087096)
		(end 284.135068 -394.845032)
		(width 0.10668)
		(layer "F.Cu")
		(net "P12V_HSC_TEMP_ALERT_N")
	)
	(via
		(at 282.744418 -394.845032)
		(size 0.762)
		(drill 0.381)
		(layers "F.Cu" "B.Cu")
		(net "P12V_HSC_TEMP_ALERT_N")
	)
	(segment
		(start 180.32222 -116.252752)
		(end 179.93233 -116.642642)
		(width 0.10668)
		(layer "F.Cu")
		(net "HP_LVC3_OCP_V3_2_P12V_PWRGD_R")
	)
	(via
		(at 179.93233 -116.642642)
		(size 0.4572)
		(drill 0.254)
		(layers "F.Cu" "B.Cu")
		(net "HP_LVC3_OCP_V3_2_P12V_PWRGD_R")
	)
	(via
		(at 174.358808 -116.73459)
		(size 0.6604)
		(drill 0.3302)
		(layers "F.Cu" "B.Cu")
		(net "HP_LVC3_OCP_V3_2_P12V_PWRGD_R")
	)
	(segment
		(start 168.6306 -117.8687)
		(end 168.48582 -117.72392)
		(width 0.10668)
		(layer "B.Cu")
		(net "HP_LVC3_OCP_V3_2_P12V_PWRGD_R")
	)
	(segment
		(start 164.53993 -117.72392)
		(end 164.14623 -117.33022)
		(width 0.10668)
		(layer "B.Cu")
		(net "HP_LVC3_OCP_V3_2_P12V_PWRGD_R")
	)
	(segment
		(start 170.029632 -117.566948)
		(end 169.72788 -117.8687)
		(width 0.10668)
		(layer "B.Cu")
		(net "HP_LVC3_OCP_V3_2_P12V_PWRGD_R")
	)
	(segment
		(start 168.48582 -117.72392)
		(end 164.53993 -117.72392)
		(width 0.10668)
		(layer "B.Cu")
		(net "HP_LVC3_OCP_V3_2_P12V_PWRGD_R")
	)
	(segment
		(start 169.72788 -117.8687)
		(end 168.6306 -117.8687)
		(width 0.10668)
		(layer "B.Cu")
		(net "HP_LVC3_OCP_V3_2_P12V_PWRGD_R")
	)
	(segment
		(start 179.296568 -116.241576)
		(end 174.851822 -116.241576)
		(width 0.10668)
		(layer "B.Cu")
		(net "HP_LVC3_OCP_V3_2_P12V_PWRGD_R")
	)
	(segment
		(start 173.52645 -117.566948)
		(end 170.029632 -117.566948)
		(width 0.10668)
		(layer "B.Cu")
		(net "HP_LVC3_OCP_V3_2_P12V_PWRGD_R")
	)
	(segment
		(start 179.697634 -116.642642)
		(end 179.296568 -116.241576)
		(width 0.10668)
		(layer "B.Cu")
		(net "HP_LVC3_OCP_V3_2_P12V_PWRGD_R")
	)
	(segment
		(start 174.358808 -116.73459)
		(end 173.52645 -117.566948)
		(width 0.10668)
		(layer "B.Cu")
		(net "HP_LVC3_OCP_V3_2_P12V_PWRGD_R")
	)
	(segment
		(start 179.93233 -116.642642)
		(end 179.697634 -116.642642)
		(width 0.10668)
		(layer "B.Cu")
		(net "HP_LVC3_OCP_V3_2_P12V_PWRGD_R")
	)
	(segment
		(start 174.851822 -116.241576)
		(end 174.358808 -116.73459)
		(width 0.10668)
		(layer "B.Cu")
		(net "HP_LVC3_OCP_V3_2_P12V_PWRGD_R")
	)
	(via
		(at 295.724072 -270.43507)
		(size 0.4826)
		(drill 0.254)
		(layers "F.Cu" "B.Cu")
		(net "Net_2268")
	)
	(via
		(at 295.724072 -271.284954)
		(size 0.4826)
		(drill 0.254)
		(layers "F.Cu" "B.Cu")
		(net "Net_2269")
	)
	(via
		(at 47.784004 -270.435324)
		(size 0.4826)
		(drill 0.254)
		(layers "F.Cu" "B.Cu")
		(net "Net_2275")
	)
	(via
		(at 47.784004 -271.285208)
		(size 0.4826)
		(drill 0.254)
		(layers "F.Cu" "B.Cu")
		(net "Net_2276")
	)
	(via
		(at 288.180018 -270.43507)
		(size 0.4826)
		(drill 0.254)
		(layers "F.Cu" "B.Cu")
		(net "Net_2282")
	)
	(via
		(at 288.180018 -271.284954)
		(size 0.4826)
		(drill 0.254)
		(layers "F.Cu" "B.Cu")
		(net "Net_2283")
	)
	(via
		(at 40.23995 -270.435324)
		(size 0.4826)
		(drill 0.254)
		(layers "F.Cu" "B.Cu")
		(net "Net_2289")
	)
	(via
		(at 40.23995 -271.285208)
		(size 0.4826)
		(drill 0.254)
		(layers "F.Cu" "B.Cu")
		(net "Net_2290")
	)
	(via
		(at 280.635964 -270.43507)
		(size 0.4826)
		(drill 0.254)
		(layers "F.Cu" "B.Cu")
		(net "Net_2296")
	)
	(via
		(at 280.635964 -271.284954)
		(size 0.4826)
		(drill 0.254)
		(layers "F.Cu" "B.Cu")
		(net "Net_2297")
	)
	(via
		(at 32.695896 -270.435324)
		(size 0.4826)
		(drill 0.254)
		(layers "F.Cu" "B.Cu")
		(net "Net_2303")
	)
	(via
		(at 32.695896 -271.285208)
		(size 0.4826)
		(drill 0.254)
		(layers "F.Cu" "B.Cu")
		(net "Net_2304")
	)
	(via
		(at 273.092164 -270.43507)
		(size 0.4826)
		(drill 0.254)
		(layers "F.Cu" "B.Cu")
		(net "Net_2310")
	)
	(via
		(at 273.092164 -271.284954)
		(size 0.4826)
		(drill 0.254)
		(layers "F.Cu" "B.Cu")
		(net "Net_2311")
	)
	(via
		(at 25.152096 -270.435324)
		(size 0.4826)
		(drill 0.254)
		(layers "F.Cu" "B.Cu")
		(net "Net_2317")
	)
	(via
		(at 25.152096 -271.285208)
		(size 0.4826)
		(drill 0.254)
		(layers "F.Cu" "B.Cu")
		(net "Net_2318")
	)
	(via
		(at 265.54811 -270.43507)
		(size 0.4826)
		(drill 0.254)
		(layers "F.Cu" "B.Cu")
		(net "Net_2324")
	)
	(via
		(at 265.54811 -271.284954)
		(size 0.4826)
		(drill 0.254)
		(layers "F.Cu" "B.Cu")
		(net "Net_2325")
	)
	(via
		(at 17.608042 -270.435324)
		(size 0.4826)
		(drill 0.254)
		(layers "F.Cu" "B.Cu")
		(net "Net_2331")
	)
	(via
		(at 17.608042 -271.285208)
		(size 0.4826)
		(drill 0.254)
		(layers "F.Cu" "B.Cu")
		(net "Net_2332")
	)
	(via
		(at 419.912038 -270.43507)
		(size 0.4826)
		(drill 0.254)
		(layers "F.Cu" "B.Cu")
		(net "Net_2352")
	)
	(via
		(at 419.912038 -271.284954)
		(size 0.4826)
		(drill 0.254)
		(layers "F.Cu" "B.Cu")
		(net "Net_2353")
	)
	(via
		(at 171.97197 -270.435324)
		(size 0.4826)
		(drill 0.254)
		(layers "F.Cu" "B.Cu")
		(net "Net_2359")
	)
	(via
		(at 171.97197 -271.285208)
		(size 0.4826)
		(drill 0.254)
		(layers "F.Cu" "B.Cu")
		(net "Net_2360")
	)
	(via
		(at 427.456092 -270.43507)
		(size 0.4826)
		(drill 0.254)
		(layers "F.Cu" "B.Cu")
		(net "Net_2366")
	)
	(via
		(at 427.456092 -271.284954)
		(size 0.4826)
		(drill 0.254)
		(layers "F.Cu" "B.Cu")
		(net "Net_2367")
	)
	(via
		(at 179.516024 -270.435324)
		(size 0.4826)
		(drill 0.254)
		(layers "F.Cu" "B.Cu")
		(net "Net_2373")
	)
	(via
		(at 179.516024 -271.285208)
		(size 0.4826)
		(drill 0.254)
		(layers "F.Cu" "B.Cu")
		(net "Net_2374")
	)
	(via
		(at 435.000146 -270.43507)
		(size 0.4826)
		(drill 0.254)
		(layers "F.Cu" "B.Cu")
		(net "Net_2380")
	)
	(via
		(at 435.000146 -271.284954)
		(size 0.4826)
		(drill 0.254)
		(layers "F.Cu" "B.Cu")
		(net "Net_2381")
	)
	(via
		(at 187.060078 -270.435324)
		(size 0.4826)
		(drill 0.254)
		(layers "F.Cu" "B.Cu")
		(net "Net_2387")
	)
	(via
		(at 187.060078 -271.285208)
		(size 0.4826)
		(drill 0.254)
		(layers "F.Cu" "B.Cu")
		(net "Net_2388")
	)
	(via
		(at 442.5442 -270.43507)
		(size 0.4826)
		(drill 0.254)
		(layers "F.Cu" "B.Cu")
		(net "Net_2394")
	)
	(via
		(at 442.5442 -271.284954)
		(size 0.4826)
		(drill 0.254)
		(layers "F.Cu" "B.Cu")
		(net "Net_2395")
	)
	(via
		(at 194.604132 -270.435324)
		(size 0.4826)
		(drill 0.254)
		(layers "F.Cu" "B.Cu")
		(net "Net_2401")
	)
	(via
		(at 194.604132 -271.285208)
		(size 0.4826)
		(drill 0.254)
		(layers "F.Cu" "B.Cu")
		(net "Net_2402")
	)
	(via
		(at 450.088 -270.43507)
		(size 0.4826)
		(drill 0.254)
		(layers "F.Cu" "B.Cu")
		(net "Net_2408")
	)
	(via
		(at 450.088 -271.284954)
		(size 0.4826)
		(drill 0.254)
		(layers "F.Cu" "B.Cu")
		(net "Net_2409")
	)
	(via
		(at 202.147932 -270.435324)
		(size 0.4826)
		(drill 0.254)
		(layers "F.Cu" "B.Cu")
		(net "Net_2415")
	)
	(via
		(at 202.147932 -271.285208)
		(size 0.4826)
		(drill 0.254)
		(layers "F.Cu" "B.Cu")
		(net "Net_2416")
	)
	(segment
		(start 305.707542 -24.972264)
		(end 305.580542 -24.845264)
		(width 0.10668)
		(layer "F.Cu")
		(net "U9_NR")
	)
	(segment
		(start 305.580542 -24.341074)
		(end 305.830732 -24.090884)
		(width 0.10668)
		(layer "F.Cu")
		(net "U9_NR")
	)
	(segment
		(start 305.830732 -24.090884)
		(end 306.47132 -24.090884)
		(width 0.10668)
		(layer "F.Cu")
		(net "U9_NR")
	)
	(segment
		(start 306.031646 -24.972264)
		(end 305.707542 -24.972264)
		(width 0.10668)
		(layer "F.Cu")
		(net "U9_NR")
	)
	(segment
		(start 306.47132 -24.090884)
		(end 307.341524 -24.090884)
		(width 0.10668)
		(layer "F.Cu")
		(net "U9_NR")
	)
	(segment
		(start 305.580542 -24.845264)
		(end 305.580542 -24.341074)
		(width 0.10668)
		(layer "F.Cu")
		(net "U9_NR")
	)
	(via
		(at 306.47132 -24.090884)
		(size 0.508)
		(drill 0.254)
		(layers "F.Cu" "B.Cu")
		(net "U9_NR")
	)
	(segment
		(start 179.835302 -410.630624)
		(end 180.15204 -410.947362)
		(width 0.10668)
		(layer "F.Cu")
		(net "SMB_SML1_PMBUS_HSC_R1_SDA")
	)
	(segment
		(start 192.546224 -385.660646)
		(end 193.779902 -385.660646)
		(width 0.10668)
		(layer "F.Cu")
		(net "SMB_SML1_PMBUS_HSC_R1_SDA")
	)
	(segment
		(start 179.251864 -410.630624)
		(end 179.835302 -410.630624)
		(width 0.10668)
		(layer "F.Cu")
		(net "SMB_SML1_PMBUS_HSC_R1_SDA")
	)
	(via
		(at 180.15204 -410.947362)
		(size 0.508)
		(drill 0.254)
		(layers "F.Cu" "B.Cu")
		(net "SMB_SML1_PMBUS_HSC_R1_SDA")
	)
	(via
		(at 192.546224 -385.660646)
		(size 0.508)
		(drill 0.254)
		(layers "F.Cu" "B.Cu")
		(net "SMB_SML1_PMBUS_HSC_R1_SDA")
	)
	(segment
		(start 183.68137 -385.660646)
		(end 179.728368 -389.613648)
		(width 0.11684)
		(layer "In4.Cu")
		(net "SMB_SML1_PMBUS_HSC_R1_SDA")
	)
	(segment
		(start 179.490878 -389.613648)
		(end 176.223168 -392.881358)
		(width 0.11684)
		(layer "In4.Cu")
		(net "SMB_SML1_PMBUS_HSC_R1_SDA")
	)
	(segment
		(start 178.925982 -410.15158)
		(end 179.415186 -410.640784)
		(width 0.11684)
		(layer "In4.Cu")
		(net "SMB_SML1_PMBUS_HSC_R1_SDA")
	)
	(segment
		(start 179.845462 -410.640784)
		(end 180.15204 -410.947362)
		(width 0.11684)
		(layer "In4.Cu")
		(net "SMB_SML1_PMBUS_HSC_R1_SDA")
	)
	(segment
		(start 175.79848 -408.90063)
		(end 177.04943 -410.15158)
		(width 0.11684)
		(layer "In4.Cu")
		(net "SMB_SML1_PMBUS_HSC_R1_SDA")
	)
	(segment
		(start 176.223168 -392.881358)
		(end 176.223168 -407.247598)
		(width 0.11684)
		(layer "In4.Cu")
		(net "SMB_SML1_PMBUS_HSC_R1_SDA")
	)
	(segment
		(start 192.546224 -385.660646)
		(end 183.68137 -385.660646)
		(width 0.11684)
		(layer "In4.Cu")
		(net "SMB_SML1_PMBUS_HSC_R1_SDA")
	)
	(segment
		(start 179.415186 -410.640784)
		(end 179.845462 -410.640784)
		(width 0.11684)
		(layer "In4.Cu")
		(net "SMB_SML1_PMBUS_HSC_R1_SDA")
	)
	(segment
		(start 179.728368 -389.613648)
		(end 179.490878 -389.613648)
		(width 0.11684)
		(layer "In4.Cu")
		(net "SMB_SML1_PMBUS_HSC_R1_SDA")
	)
	(segment
		(start 176.223168 -407.247598)
		(end 175.79848 -407.672286)
		(width 0.11684)
		(layer "In4.Cu")
		(net "SMB_SML1_PMBUS_HSC_R1_SDA")
	)
	(segment
		(start 177.04943 -410.15158)
		(end 178.925982 -410.15158)
		(width 0.11684)
		(layer "In4.Cu")
		(net "SMB_SML1_PMBUS_HSC_R1_SDA")
	)
	(segment
		(start 175.79848 -407.672286)
		(end 175.79848 -408.90063)
		(width 0.11684)
		(layer "In4.Cu")
		(net "SMB_SML1_PMBUS_HSC_R1_SDA")
	)
	(segment
		(start 183.412384 -425.969938)
		(end 179.788566 -422.34612)
		(width 0.11684)
		(layer "In6.Cu")
		(net "SMB_SML1_PMBUS_HSC_R1_SDA")
	)
	(segment
		(start 185.529982 -428.808642)
		(end 185.402982 -428.681642)
		(width 0.11684)
		(layer "In6.Cu")
		(net "SMB_SML1_PMBUS_HSC_R1_SDA")
	)
	(segment
		(start 185.529982 -431.036476)
		(end 185.529982 -428.808642)
		(width 0.11684)
		(layer "In6.Cu")
		(net "SMB_SML1_PMBUS_HSC_R1_SDA")
	)
	(segment
		(start 180.15204 -417.363402)
		(end 180.15204 -410.947362)
		(width 0.11684)
		(layer "In6.Cu")
		(net "SMB_SML1_PMBUS_HSC_R1_SDA")
	)
	(segment
		(start 185.402982 -428.681642)
		(end 184.79135 -428.681642)
		(width 0.11684)
		(layer "In6.Cu")
		(net "SMB_SML1_PMBUS_HSC_R1_SDA")
	)
	(segment
		(start 192.324736 -435.044088)
		(end 189.537594 -435.044088)
		(width 0.11684)
		(layer "In6.Cu")
		(net "SMB_SML1_PMBUS_HSC_R1_SDA")
	)
	(segment
		(start 184.79135 -428.681642)
		(end 183.412384 -427.302676)
		(width 0.11684)
		(layer "In6.Cu")
		(net "SMB_SML1_PMBUS_HSC_R1_SDA")
	)
	(segment
		(start 179.788566 -422.34612)
		(end 179.788566 -417.726876)
		(width 0.11684)
		(layer "In6.Cu")
		(net "SMB_SML1_PMBUS_HSC_R1_SDA")
	)
	(segment
		(start 179.788566 -417.726876)
		(end 180.15204 -417.363402)
		(width 0.11684)
		(layer "In6.Cu")
		(net "SMB_SML1_PMBUS_HSC_R1_SDA")
	)
	(segment
		(start 189.537594 -435.044088)
		(end 185.529982 -431.036476)
		(width 0.11684)
		(layer "In6.Cu")
		(net "SMB_SML1_PMBUS_HSC_R1_SDA")
	)
	(segment
		(start 183.412384 -427.302676)
		(end 183.412384 -425.969938)
		(width 0.11684)
		(layer "In6.Cu")
		(net "SMB_SML1_PMBUS_HSC_R1_SDA")
	)
	(segment
		(start 192.487804 -384.660648)
		(end 193.779902 -384.660648)
		(width 0.10668)
		(layer "F.Cu")
		(net "SMB_SML1_PMBUS_HSC_R1_SCL")
	)
	(segment
		(start 176.868074 -412.257748)
		(end 176.766982 -412.35884)
		(width 0.10668)
		(layer "F.Cu")
		(net "SMB_SML1_PMBUS_HSC_R1_SCL")
	)
	(segment
		(start 177.584862 -412.257748)
		(end 176.868074 -412.257748)
		(width 0.10668)
		(layer "F.Cu")
		(net "SMB_SML1_PMBUS_HSC_R1_SCL")
	)
	(via
		(at 192.487804 -384.660648)
		(size 0.508)
		(drill 0.254)
		(layers "F.Cu" "B.Cu")
		(net "SMB_SML1_PMBUS_HSC_R1_SCL")
	)
	(via
		(at 176.766982 -412.35884)
		(size 0.508)
		(drill 0.254)
		(layers "F.Cu" "B.Cu")
		(net "SMB_SML1_PMBUS_HSC_R1_SCL")
	)
	(segment
		(start 182.652416 -384.660648)
		(end 175.321214 -391.99185)
		(width 0.11684)
		(layer "In4.Cu")
		(net "SMB_SML1_PMBUS_HSC_R1_SCL")
	)
	(segment
		(start 175.321214 -391.99185)
		(end 175.321214 -406.63622)
		(width 0.11684)
		(layer "In4.Cu")
		(net "SMB_SML1_PMBUS_HSC_R1_SCL")
	)
	(segment
		(start 192.487804 -384.660648)
		(end 182.652416 -384.660648)
		(width 0.11684)
		(layer "In4.Cu")
		(net "SMB_SML1_PMBUS_HSC_R1_SCL")
	)
	(segment
		(start 175.321214 -406.63622)
		(end 174.762414 -407.19502)
		(width 0.11684)
		(layer "In4.Cu")
		(net "SMB_SML1_PMBUS_HSC_R1_SCL")
	)
	(segment
		(start 177.216308 -411.630622)
		(end 177.216308 -411.909514)
		(width 0.11684)
		(layer "In4.Cu")
		(net "SMB_SML1_PMBUS_HSC_R1_SCL")
	)
	(segment
		(start 174.762414 -409.176728)
		(end 177.216308 -411.630622)
		(width 0.11684)
		(layer "In4.Cu")
		(net "SMB_SML1_PMBUS_HSC_R1_SCL")
	)
	(segment
		(start 177.216308 -411.909514)
		(end 176.766982 -412.35884)
		(width 0.11684)
		(layer "In4.Cu")
		(net "SMB_SML1_PMBUS_HSC_R1_SCL")
	)
	(segment
		(start 174.762414 -407.19502)
		(end 174.762414 -409.176728)
		(width 0.11684)
		(layer "In4.Cu")
		(net "SMB_SML1_PMBUS_HSC_R1_SCL")
	)
	(segment
		(start 190.444374 -435.703726)
		(end 189.303914 -435.703726)
		(width 0.11684)
		(layer "In6.Cu")
		(net "SMB_SML1_PMBUS_HSC_R1_SCL")
	)
	(segment
		(start 182.982108 -429.38192)
		(end 182.982108 -428.597568)
		(width 0.11684)
		(layer "In6.Cu")
		(net "SMB_SML1_PMBUS_HSC_R1_SCL")
	)
	(segment
		(start 192.324736 -437.584088)
		(end 190.444374 -435.703726)
		(width 0.11684)
		(layer "In6.Cu")
		(net "SMB_SML1_PMBUS_HSC_R1_SCL")
	)
	(segment
		(start 176.801526 -412.832804)
		(end 176.766982 -412.79826)
		(width 0.11684)
		(layer "In6.Cu")
		(net "SMB_SML1_PMBUS_HSC_R1_SCL")
	)
	(segment
		(start 176.583848 -422.199308)
		(end 176.583848 -420.676832)
		(width 0.11684)
		(layer "In6.Cu")
		(net "SMB_SML1_PMBUS_HSC_R1_SCL")
	)
	(segment
		(start 189.303914 -435.703726)
		(end 182.982108 -429.38192)
		(width 0.11684)
		(layer "In6.Cu")
		(net "SMB_SML1_PMBUS_HSC_R1_SCL")
	)
	(segment
		(start 182.982108 -428.597568)
		(end 176.583848 -422.199308)
		(width 0.11684)
		(layer "In6.Cu")
		(net "SMB_SML1_PMBUS_HSC_R1_SCL")
	)
	(segment
		(start 176.801526 -420.459154)
		(end 176.801526 -412.832804)
		(width 0.11684)
		(layer "In6.Cu")
		(net "SMB_SML1_PMBUS_HSC_R1_SCL")
	)
	(segment
		(start 176.766982 -412.79826)
		(end 176.766982 -412.35884)
		(width 0.11684)
		(layer "In6.Cu")
		(net "SMB_SML1_PMBUS_HSC_R1_SCL")
	)
	(segment
		(start 176.583848 -420.676832)
		(end 176.801526 -420.459154)
		(width 0.11684)
		(layer "In6.Cu")
		(net "SMB_SML1_PMBUS_HSC_R1_SCL")
	)
	(segment
		(start 418.94252 -367.465102)
		(end 419.037008 -367.370614)
		(width 0.10668)
		(layer "F.Cu")
		(net "SMB_SCM_2_R6_SDA")
	)
	(segment
		(start 326.30745 -363.22)
		(end 326.644 -363.22)
		(width 0.10668)
		(layer "F.Cu")
		(net "SMB_SCM_2_R6_SDA")
	)
	(segment
		(start 421.104568 -368.44859)
		(end 420.12108 -367.465102)
		(width 0.10668)
		(layer "F.Cu")
		(net "SMB_SCM_2_R6_SDA")
	)
	(segment
		(start 421.104568 -368.88039)
		(end 421.104568 -368.44859)
		(width 0.10668)
		(layer "F.Cu")
		(net "SMB_SCM_2_R6_SDA")
	)
	(segment
		(start 419.037008 -367.370614)
		(end 419.037008 -365.883952)
		(width 0.10668)
		(layer "F.Cu")
		(net "SMB_SCM_2_R6_SDA")
	)
	(segment
		(start 420.12108 -367.465102)
		(end 418.94252 -367.465102)
		(width 0.10668)
		(layer "F.Cu")
		(net "SMB_SCM_2_R6_SDA")
	)
	(segment
		(start 326.644 -363.22)
		(end 327.0758 -363.6518)
		(width 0.10668)
		(layer "F.Cu")
		(net "SMB_SCM_2_R6_SDA")
	)
	(via
		(at 418.94252 -367.465102)
		(size 0.508)
		(drill 0.254)
		(layers "F.Cu" "B.Cu")
		(net "SMB_SCM_2_R6_SDA")
	)
	(via
		(at 327.0758 -363.6518)
		(size 0.508)
		(drill 0.254)
		(layers "F.Cu" "B.Cu")
		(net "SMB_SCM_2_R6_SDA")
	)
	(segment
		(start 403.174454 -360.211878)
		(end 407.207212 -360.211878)
		(width 0.10668)
		(layer "B.Cu")
		(net "SMB_SCM_2_R6_SDA")
	)
	(segment
		(start 411.254448 -364.259114)
		(end 411.254448 -367.027206)
		(width 0.10668)
		(layer "B.Cu")
		(net "SMB_SCM_2_R6_SDA")
	)
	(segment
		(start 411.254448 -367.027206)
		(end 413.315404 -369.088162)
		(width 0.10668)
		(layer "B.Cu")
		(net "SMB_SCM_2_R6_SDA")
	)
	(segment
		(start 398.073118 -365.313214)
		(end 403.174454 -360.211878)
		(width 0.10668)
		(layer "B.Cu")
		(net "SMB_SCM_2_R6_SDA")
	)
	(segment
		(start 413.315404 -369.088162)
		(end 417.31946 -369.088162)
		(width 0.10668)
		(layer "B.Cu")
		(net "SMB_SCM_2_R6_SDA")
	)
	(segment
		(start 417.31946 -369.088162)
		(end 418.94252 -367.465102)
		(width 0.10668)
		(layer "B.Cu")
		(net "SMB_SCM_2_R6_SDA")
	)
	(segment
		(start 407.207212 -360.211878)
		(end 411.254448 -364.259114)
		(width 0.10668)
		(layer "B.Cu")
		(net "SMB_SCM_2_R6_SDA")
	)
	(segment
		(start 328.737214 -365.313214)
		(end 398.073118 -365.313214)
		(width 0.10668)
		(layer "B.Cu")
		(net "SMB_SCM_2_R6_SDA")
	)
	(segment
		(start 327.0758 -363.6518)
		(end 328.737214 -365.313214)
		(width 0.10668)
		(layer "B.Cu")
		(net "SMB_SCM_2_R6_SDA")
	)
	(segment
		(start 327.5076 -364.236)
		(end 328.0918 -363.6518)
		(width 0.10668)
		(layer "F.Cu")
		(net "SMB_SCM_2_R6_SCL")
	)
	(segment
		(start 417.5506 -368.167666)
		(end 416.856418 -367.473484)
		(width 0.10668)
		(layer "F.Cu")
		(net "SMB_SCM_2_R6_SCL")
	)
	(segment
		(start 416.479736 -366.34928)
		(end 416.479736 -366.756188)
		(width 0.10668)
		(layer "F.Cu")
		(net "SMB_SCM_2_R6_SCL")
	)
	(segment
		(start 326.30745 -364.236)
		(end 327.5076 -364.236)
		(width 0.10668)
		(layer "F.Cu")
		(net "SMB_SCM_2_R6_SCL")
	)
	(segment
		(start 416.456368 -366.325912)
		(end 416.479736 -366.34928)
		(width 0.10668)
		(layer "F.Cu")
		(net "SMB_SCM_2_R6_SCL")
	)
	(segment
		(start 420.017956 -368.351562)
		(end 419.83406 -368.167666)
		(width 0.10668)
		(layer "F.Cu")
		(net "SMB_SCM_2_R6_SCL")
	)
	(segment
		(start 416.479736 -366.756188)
		(end 416.456368 -366.779556)
		(width 0.10668)
		(layer "F.Cu")
		(net "SMB_SCM_2_R6_SCL")
	)
	(segment
		(start 419.83406 -368.167666)
		(end 417.5506 -368.167666)
		(width 0.10668)
		(layer "F.Cu")
		(net "SMB_SCM_2_R6_SCL")
	)
	(segment
		(start 416.456368 -366.779556)
		(end 416.456368 -367.073434)
		(width 0.10668)
		(layer "F.Cu")
		(net "SMB_SCM_2_R6_SCL")
	)
	(segment
		(start 416.456368 -367.073434)
		(end 416.856418 -367.473484)
		(width 0.10668)
		(layer "F.Cu")
		(net "SMB_SCM_2_R6_SCL")
	)
	(segment
		(start 420.017956 -368.875056)
		(end 420.017956 -368.351562)
		(width 0.10668)
		(layer "F.Cu")
		(net "SMB_SCM_2_R6_SCL")
	)
	(via
		(at 416.856418 -367.473484)
		(size 0.508)
		(drill 0.254)
		(layers "F.Cu" "B.Cu")
		(net "SMB_SCM_2_R6_SCL")
	)
	(via
		(at 328.0918 -363.6518)
		(size 0.508)
		(drill 0.254)
		(layers "F.Cu" "B.Cu")
		(net "SMB_SCM_2_R6_SCL")
	)
	(segment
		(start 413.082486 -368.27587)
		(end 415.583116 -368.27587)
		(width 0.10668)
		(layer "B.Cu")
		(net "SMB_SCM_2_R6_SCL")
	)
	(segment
		(start 415.583116 -368.27587)
		(end 416.385502 -367.473484)
		(width 0.10668)
		(layer "B.Cu")
		(net "SMB_SCM_2_R6_SCL")
	)
	(segment
		(start 402.63953 -359.844086)
		(end 407.542238 -359.844086)
		(width 0.10668)
		(layer "B.Cu")
		(net "SMB_SCM_2_R6_SCL")
	)
	(segment
		(start 407.542238 -359.844086)
		(end 411.689296 -363.991144)
		(width 0.10668)
		(layer "B.Cu")
		(net "SMB_SCM_2_R6_SCL")
	)
	(segment
		(start 329.412854 -364.972854)
		(end 397.510762 -364.972854)
		(width 0.10668)
		(layer "B.Cu")
		(net "SMB_SCM_2_R6_SCL")
	)
	(segment
		(start 328.0918 -363.6518)
		(end 329.412854 -364.972854)
		(width 0.10668)
		(layer "B.Cu")
		(net "SMB_SCM_2_R6_SCL")
	)
	(segment
		(start 416.385502 -367.473484)
		(end 416.856418 -367.473484)
		(width 0.10668)
		(layer "B.Cu")
		(net "SMB_SCM_2_R6_SCL")
	)
	(segment
		(start 411.689296 -363.991144)
		(end 411.689296 -366.88268)
		(width 0.10668)
		(layer "B.Cu")
		(net "SMB_SCM_2_R6_SCL")
	)
	(segment
		(start 397.510762 -364.972854)
		(end 402.63953 -359.844086)
		(width 0.10668)
		(layer "B.Cu")
		(net "SMB_SCM_2_R6_SCL")
	)
	(segment
		(start 411.689296 -366.88268)
		(end 413.082486 -368.27587)
		(width 0.10668)
		(layer "B.Cu")
		(net "SMB_SCM_2_R6_SCL")
	)
	(segment
		(start 174.410878 -367.272824)
		(end 175.13681 -367.998756)
		(width 0.10668)
		(layer "F.Cu")
		(net "SMB_SCM_2_R5_SDA")
	)
	(segment
		(start 187.461398 -370.859304)
		(end 197.226174 -370.859304)
		(width 0.10668)
		(layer "F.Cu")
		(net "SMB_SCM_2_R5_SDA")
	)
	(segment
		(start 281.683206 -368.169444)
		(end 284.905958 -371.392196)
		(width 0.10668)
		(layer "F.Cu")
		(net "SMB_SCM_2_R5_SDA")
	)
	(segment
		(start 290.632388 -371.392196)
		(end 291.536628 -370.487956)
		(width 0.10668)
		(layer "F.Cu")
		(net "SMB_SCM_2_R5_SDA")
	)
	(segment
		(start 270.708882 -369.19789)
		(end 271.737328 -368.169444)
		(width 0.10668)
		(layer "F.Cu")
		(net "SMB_SCM_2_R5_SDA")
	)
	(segment
		(start 180.577744 -370.178584)
		(end 186.780678 -370.178584)
		(width 0.10668)
		(layer "F.Cu")
		(net "SMB_SCM_2_R5_SDA")
	)
	(segment
		(start 253.553722 -369.19789)
		(end 270.708882 -369.19789)
		(width 0.10668)
		(layer "F.Cu")
		(net "SMB_SCM_2_R5_SDA")
	)
	(segment
		(start 291.536628 -370.487956)
		(end 296.064178 -370.487956)
		(width 0.10668)
		(layer "F.Cu")
		(net "SMB_SCM_2_R5_SDA")
	)
	(segment
		(start 296.956734 -369.5954)
		(end 299.2628 -369.5954)
		(width 0.10668)
		(layer "F.Cu")
		(net "SMB_SCM_2_R5_SDA")
	)
	(segment
		(start 249.122946 -364.767114)
		(end 253.553722 -369.19789)
		(width 0.10668)
		(layer "F.Cu")
		(net "SMB_SCM_2_R5_SDA")
	)
	(segment
		(start 186.780678 -370.178584)
		(end 187.461398 -370.859304)
		(width 0.10668)
		(layer "F.Cu")
		(net "SMB_SCM_2_R5_SDA")
	)
	(segment
		(start 296.064178 -370.487956)
		(end 296.956734 -369.5954)
		(width 0.10668)
		(layer "F.Cu")
		(net "SMB_SCM_2_R5_SDA")
	)
	(segment
		(start 197.226174 -370.859304)
		(end 197.87489 -370.210588)
		(width 0.10668)
		(layer "F.Cu")
		(net "SMB_SCM_2_R5_SDA")
	)
	(segment
		(start 174.410878 -365.058198)
		(end 174.410878 -367.272824)
		(width 0.10668)
		(layer "F.Cu")
		(net "SMB_SCM_2_R5_SDA")
	)
	(segment
		(start 200.921112 -371.352064)
		(end 218.685364 -371.352064)
		(width 0.10668)
		(layer "F.Cu")
		(net "SMB_SCM_2_R5_SDA")
	)
	(segment
		(start 284.905958 -371.392196)
		(end 290.632388 -371.392196)
		(width 0.10668)
		(layer "F.Cu")
		(net "SMB_SCM_2_R5_SDA")
	)
	(segment
		(start 178.397916 -367.998756)
		(end 180.577744 -370.178584)
		(width 0.10668)
		(layer "F.Cu")
		(net "SMB_SCM_2_R5_SDA")
	)
	(segment
		(start 299.2628 -369.5954)
		(end 299.7708 -370.1034)
		(width 0.10668)
		(layer "F.Cu")
		(net "SMB_SCM_2_R5_SDA")
	)
	(segment
		(start 218.685364 -371.352064)
		(end 220.542358 -369.49507)
		(width 0.10668)
		(layer "F.Cu")
		(net "SMB_SCM_2_R5_SDA")
	)
	(segment
		(start 304.01895 -367.665)
		(end 303.276 -367.665)
		(width 0.10668)
		(layer "F.Cu")
		(net "SMB_SCM_2_R5_SDA")
	)
	(segment
		(start 197.87489 -370.210588)
		(end 199.779636 -370.210588)
		(width 0.10668)
		(layer "F.Cu")
		(net "SMB_SCM_2_R5_SDA")
	)
	(segment
		(start 161.29 -356.76205)
		(end 166.11473 -356.76205)
		(width 0.10668)
		(layer "F.Cu")
		(net "SMB_SCM_2_R5_SDA")
	)
	(segment
		(start 199.779636 -370.210588)
		(end 200.921112 -371.352064)
		(width 0.10668)
		(layer "F.Cu")
		(net "SMB_SCM_2_R5_SDA")
	)
	(segment
		(start 271.737328 -368.169444)
		(end 281.683206 -368.169444)
		(width 0.10668)
		(layer "F.Cu")
		(net "SMB_SCM_2_R5_SDA")
	)
	(segment
		(start 225.901758 -369.49507)
		(end 230.629714 -364.767114)
		(width 0.10668)
		(layer "F.Cu")
		(net "SMB_SCM_2_R5_SDA")
	)
	(segment
		(start 220.542358 -369.49507)
		(end 225.901758 -369.49507)
		(width 0.10668)
		(layer "F.Cu")
		(net "SMB_SCM_2_R5_SDA")
	)
	(segment
		(start 230.629714 -364.767114)
		(end 249.122946 -364.767114)
		(width 0.10668)
		(layer "F.Cu")
		(net "SMB_SCM_2_R5_SDA")
	)
	(segment
		(start 166.11473 -356.76205)
		(end 174.410878 -365.058198)
		(width 0.10668)
		(layer "F.Cu")
		(net "SMB_SCM_2_R5_SDA")
	)
	(segment
		(start 175.13681 -367.998756)
		(end 178.397916 -367.998756)
		(width 0.10668)
		(layer "F.Cu")
		(net "SMB_SCM_2_R5_SDA")
	)
	(segment
		(start 325.50735 -363.22)
		(end 324.99935 -363.728)
		(width 0.10668)
		(layer "F.Cu")
		(net "SMB_SCM_2_R5_SDA")
	)
	(via
		(at 324.99935 -363.728)
		(size 0.508)
		(drill 0.254)
		(layers "F.Cu" "B.Cu")
		(net "SMB_SCM_2_R5_SDA")
	)
	(via
		(at 299.7708 -370.1034)
		(size 0.508)
		(drill 0.254)
		(layers "F.Cu" "B.Cu")
		(net "SMB_SCM_2_R5_SDA")
	)
	(via
		(at 303.276 -367.665)
		(size 0.508)
		(drill 0.254)
		(layers "F.Cu" "B.Cu")
		(net "SMB_SCM_2_R5_SDA")
	)
	(segment
		(start 303.276 -367.665)
		(end 302.8442 -367.2332)
		(width 0.11684)
		(layer "In11.Cu")
		(net "SMB_SCM_2_R5_SDA")
	)
	(segment
		(start 302.3108 -367.2332)
		(end 299.7708 -369.7732)
		(width 0.11684)
		(layer "In11.Cu")
		(net "SMB_SCM_2_R5_SDA")
	)
	(segment
		(start 299.7708 -369.7732)
		(end 299.7708 -370.1034)
		(width 0.11684)
		(layer "In11.Cu")
		(net "SMB_SCM_2_R5_SDA")
	)
	(segment
		(start 302.8442 -367.2332)
		(end 302.3108 -367.2332)
		(width 0.11684)
		(layer "In11.Cu")
		(net "SMB_SCM_2_R5_SDA")
	)
	(segment
		(start 312.683144 -367.48593)
		(end 311.743852 -368.425222)
		(width 0.11684)
		(layer "In13.Cu")
		(net "SMB_SCM_2_R5_SDA")
	)
	(segment
		(start 321.97802 -366.74933)
		(end 315.932058 -366.74933)
		(width 0.11684)
		(layer "In13.Cu")
		(net "SMB_SCM_2_R5_SDA")
	)
	(segment
		(start 324.99935 -363.728)
		(end 321.97802 -366.74933)
		(width 0.11684)
		(layer "In13.Cu")
		(net "SMB_SCM_2_R5_SDA")
	)
	(segment
		(start 310.103012 -369.104926)
		(end 304.715926 -369.104926)
		(width 0.11684)
		(layer "In13.Cu")
		(net "SMB_SCM_2_R5_SDA")
	)
	(segment
		(start 311.743852 -368.425222)
		(end 310.103012 -369.104926)
		(width 0.11684)
		(layer "In13.Cu")
		(net "SMB_SCM_2_R5_SDA")
	)
	(segment
		(start 315.195458 -367.48593)
		(end 312.683144 -367.48593)
		(width 0.11684)
		(layer "In13.Cu")
		(net "SMB_SCM_2_R5_SDA")
	)
	(segment
		(start 315.932058 -366.74933)
		(end 315.195458 -367.48593)
		(width 0.11684)
		(layer "In13.Cu")
		(net "SMB_SCM_2_R5_SDA")
	)
	(segment
		(start 304.715926 -369.104926)
		(end 303.276 -367.665)
		(width 0.11684)
		(layer "In13.Cu")
		(net "SMB_SCM_2_R5_SDA")
	)
	(segment
		(start 249.07621 -365.211106)
		(end 253.403354 -369.53825)
		(width 0.10668)
		(layer "F.Cu")
		(net "SMB_SCM_2_R5_SCL")
	)
	(segment
		(start 174.05604 -367.440718)
		(end 175.044608 -368.429286)
		(width 0.10668)
		(layer "F.Cu")
		(net "SMB_SCM_2_R5_SCL")
	)
	(segment
		(start 199.50938 -370.709952)
		(end 200.528174 -371.728746)
		(width 0.10668)
		(layer "F.Cu")
		(net "SMB_SCM_2_R5_SCL")
	)
	(segment
		(start 200.528174 -371.728746)
		(end 218.997276 -371.728746)
		(width 0.10668)
		(layer "F.Cu")
		(net "SMB_SCM_2_R5_SCL")
	)
	(segment
		(start 253.403354 -369.53825)
		(end 282.400756 -369.53825)
		(width 0.10668)
		(layer "F.Cu")
		(net "SMB_SCM_2_R5_SCL")
	)
	(segment
		(start 296.196004 -370.847874)
		(end 296.947844 -370.096034)
		(width 0.10668)
		(layer "F.Cu")
		(net "SMB_SCM_2_R5_SCL")
	)
	(segment
		(start 166.101014 -357.23449)
		(end 174.05604 -365.189516)
		(width 0.10668)
		(layer "F.Cu")
		(net "SMB_SCM_2_R5_SCL")
	)
	(segment
		(start 160.49244 -357.23449)
		(end 166.101014 -357.23449)
		(width 0.10668)
		(layer "F.Cu")
		(net "SMB_SCM_2_R5_SCL")
	)
	(segment
		(start 198.153528 -370.709952)
		(end 199.50938 -370.709952)
		(width 0.10668)
		(layer "F.Cu")
		(net "SMB_SCM_2_R5_SCL")
	)
	(segment
		(start 225.997516 -370.050568)
		(end 230.836978 -365.211106)
		(width 0.10668)
		(layer "F.Cu")
		(net "SMB_SCM_2_R5_SCL")
	)
	(segment
		(start 175.044608 -368.429286)
		(end 178.163728 -368.429286)
		(width 0.10668)
		(layer "F.Cu")
		(net "SMB_SCM_2_R5_SCL")
	)
	(segment
		(start 185.712862 -370.525802)
		(end 186.491372 -371.304312)
		(width 0.10668)
		(layer "F.Cu")
		(net "SMB_SCM_2_R5_SCL")
	)
	(segment
		(start 160.02 -356.76205)
		(end 160.49244 -357.23449)
		(width 0.10668)
		(layer "F.Cu")
		(net "SMB_SCM_2_R5_SCL")
	)
	(segment
		(start 178.163728 -368.429286)
		(end 180.260244 -370.525802)
		(width 0.10668)
		(layer "F.Cu")
		(net "SMB_SCM_2_R5_SCL")
	)
	(segment
		(start 174.05604 -365.189516)
		(end 174.05604 -367.440718)
		(width 0.10668)
		(layer "F.Cu")
		(net "SMB_SCM_2_R5_SCL")
	)
	(segment
		(start 324.231 -363.728)
		(end 324.739 -364.236)
		(width 0.10668)
		(layer "F.Cu")
		(net "SMB_SCM_2_R5_SCL")
	)
	(segment
		(start 218.997276 -371.728746)
		(end 220.675454 -370.050568)
		(width 0.10668)
		(layer "F.Cu")
		(net "SMB_SCM_2_R5_SCL")
	)
	(segment
		(start 282.400756 -369.53825)
		(end 284.637734 -371.775228)
		(width 0.10668)
		(layer "F.Cu")
		(net "SMB_SCM_2_R5_SCL")
	)
	(segment
		(start 324.739 -364.236)
		(end 325.50735 -364.236)
		(width 0.10668)
		(layer "F.Cu")
		(net "SMB_SCM_2_R5_SCL")
	)
	(segment
		(start 197.559168 -371.304312)
		(end 198.153528 -370.709952)
		(width 0.10668)
		(layer "F.Cu")
		(net "SMB_SCM_2_R5_SCL")
	)
	(segment
		(start 291.837872 -370.847874)
		(end 296.196004 -370.847874)
		(width 0.10668)
		(layer "F.Cu")
		(net "SMB_SCM_2_R5_SCL")
	)
	(segment
		(start 284.637734 -371.775228)
		(end 290.910518 -371.775228)
		(width 0.10668)
		(layer "F.Cu")
		(net "SMB_SCM_2_R5_SCL")
	)
	(segment
		(start 304.01895 -366.395)
		(end 303.276 -366.395)
		(width 0.10668)
		(layer "F.Cu")
		(net "SMB_SCM_2_R5_SCL")
	)
	(segment
		(start 230.836978 -365.211106)
		(end 249.07621 -365.211106)
		(width 0.10668)
		(layer "F.Cu")
		(net "SMB_SCM_2_R5_SCL")
	)
	(segment
		(start 220.675454 -370.050568)
		(end 225.997516 -370.050568)
		(width 0.10668)
		(layer "F.Cu")
		(net "SMB_SCM_2_R5_SCL")
	)
	(segment
		(start 186.491372 -371.304312)
		(end 197.559168 -371.304312)
		(width 0.10668)
		(layer "F.Cu")
		(net "SMB_SCM_2_R5_SCL")
	)
	(segment
		(start 180.260244 -370.525802)
		(end 185.712862 -370.525802)
		(width 0.10668)
		(layer "F.Cu")
		(net "SMB_SCM_2_R5_SCL")
	)
	(segment
		(start 296.947844 -370.096034)
		(end 298.831 -370.096034)
		(width 0.10668)
		(layer "F.Cu")
		(net "SMB_SCM_2_R5_SCL")
	)
	(segment
		(start 290.910518 -371.775228)
		(end 291.837872 -370.847874)
		(width 0.10668)
		(layer "F.Cu")
		(net "SMB_SCM_2_R5_SCL")
	)
	(via
		(at 298.831 -370.096034)
		(size 0.508)
		(drill 0.254)
		(layers "F.Cu" "B.Cu")
		(net "SMB_SCM_2_R5_SCL")
	)
	(via
		(at 324.231 -363.728)
		(size 0.508)
		(drill 0.254)
		(layers "F.Cu" "B.Cu")
		(net "SMB_SCM_2_R5_SCL")
	)
	(via
		(at 303.276 -366.395)
		(size 0.508)
		(drill 0.254)
		(layers "F.Cu" "B.Cu")
		(net "SMB_SCM_2_R5_SCL")
	)
	(segment
		(start 303.276 -366.395)
		(end 302.895 -366.776)
		(width 0.11684)
		(layer "In11.Cu")
		(net "SMB_SCM_2_R5_SCL")
	)
	(segment
		(start 302.151034 -366.776)
		(end 298.831 -370.096034)
		(width 0.11684)
		(layer "In11.Cu")
		(net "SMB_SCM_2_R5_SCL")
	)
	(segment
		(start 302.895 -366.776)
		(end 302.151034 -366.776)
		(width 0.11684)
		(layer "In11.Cu")
		(net "SMB_SCM_2_R5_SCL")
	)
	(segment
		(start 312.364374 -367.03127)
		(end 311.211976 -368.183668)
		(width 0.11684)
		(layer "In13.Cu")
		(net "SMB_SCM_2_R5_SCL")
	)
	(segment
		(start 310.071262 -368.656108)
		(end 305.537108 -368.656108)
		(width 0.11684)
		(layer "In13.Cu")
		(net "SMB_SCM_2_R5_SCL")
	)
	(segment
		(start 315.752226 -366.319054)
		(end 315.04001 -367.03127)
		(width 0.11684)
		(layer "In13.Cu")
		(net "SMB_SCM_2_R5_SCL")
	)
	(segment
		(start 324.231 -363.728)
		(end 321.639946 -366.319054)
		(width 0.11684)
		(layer "In13.Cu")
		(net "SMB_SCM_2_R5_SCL")
	)
	(segment
		(start 305.537108 -368.656108)
		(end 303.276 -366.395)
		(width 0.11684)
		(layer "In13.Cu")
		(net "SMB_SCM_2_R5_SCL")
	)
	(segment
		(start 315.04001 -367.03127)
		(end 312.364374 -367.03127)
		(width 0.11684)
		(layer "In13.Cu")
		(net "SMB_SCM_2_R5_SCL")
	)
	(segment
		(start 311.211976 -368.183668)
		(end 310.071262 -368.656108)
		(width 0.11684)
		(layer "In13.Cu")
		(net "SMB_SCM_2_R5_SCL")
	)
	(segment
		(start 321.639946 -366.319054)
		(end 315.752226 -366.319054)
		(width 0.11684)
		(layer "In13.Cu")
		(net "SMB_SCM_2_R5_SCL")
	)
	(segment
		(start 316.277498 -115.108228)
		(end 317.496698 -115.108228)
		(width 0.10668)
		(layer "F.Cu")
		(net "SMB_FRU_3V3AUX_R1_SDA")
	)
	(segment
		(start 314.537852 -115.665504)
		(end 315.720222 -115.665504)
		(width 0.10668)
		(layer "F.Cu")
		(net "SMB_FRU_3V3AUX_R1_SDA")
	)
	(segment
		(start 317.6524 -114.468656)
		(end 319.532 -114.468656)
		(width 0.10668)
		(layer "F.Cu")
		(net "SMB_FRU_3V3AUX_R1_SDA")
	)
	(segment
		(start 317.496698 -115.108228)
		(end 317.496698 -114.624358)
		(width 0.10668)
		(layer "F.Cu")
		(net "SMB_FRU_3V3AUX_R1_SDA")
	)
	(segment
		(start 315.720222 -115.665504)
		(end 316.277498 -115.108228)
		(width 0.10668)
		(layer "F.Cu")
		(net "SMB_FRU_3V3AUX_R1_SDA")
	)
	(segment
		(start 317.496698 -114.624358)
		(end 317.6524 -114.468656)
		(width 0.10668)
		(layer "F.Cu")
		(net "SMB_FRU_3V3AUX_R1_SDA")
	)
	(segment
		(start 319.771268 -114.707924)
		(end 319.771268 -115.410488)
		(width 0.10668)
		(layer "F.Cu")
		(net "SMB_FRU_3V3AUX_R1_SDA")
	)
	(segment
		(start 319.532 -114.468656)
		(end 319.771268 -114.707924)
		(width 0.10668)
		(layer "F.Cu")
		(net "SMB_FRU_3V3AUX_R1_SDA")
	)
	(via
		(at 316.277498 -115.108228)
		(size 0.762)
		(drill 0.381)
		(layers "F.Cu" "B.Cu")
		(net "SMB_FRU_3V3AUX_R1_SDA")
	)
	(segment
		(start 315.720222 -116.935504)
		(end 316.277498 -116.378228)
		(width 0.10668)
		(layer "F.Cu")
		(net "SMB_FRU_3V3AUX_R1_SCL")
	)
	(segment
		(start 316.277498 -116.378228)
		(end 317.496698 -116.378228)
		(width 0.10668)
		(layer "F.Cu")
		(net "SMB_FRU_3V3AUX_R1_SCL")
	)
	(segment
		(start 314.537852 -116.935504)
		(end 315.720222 -116.935504)
		(width 0.10668)
		(layer "F.Cu")
		(net "SMB_FRU_3V3AUX_R1_SCL")
	)
	(segment
		(start 317.496698 -116.378228)
		(end 317.496698 -116.862098)
		(width 0.10668)
		(layer "F.Cu")
		(net "SMB_FRU_3V3AUX_R1_SCL")
	)
	(segment
		(start 319.753488 -117.024912)
		(end 319.753488 -116.632228)
		(width 0.10668)
		(layer "F.Cu")
		(net "SMB_FRU_3V3AUX_R1_SCL")
	)
	(segment
		(start 317.881 -117.2464)
		(end 319.532 -117.2464)
		(width 0.10668)
		(layer "F.Cu")
		(net "SMB_FRU_3V3AUX_R1_SCL")
	)
	(segment
		(start 317.496698 -116.862098)
		(end 317.881 -117.2464)
		(width 0.10668)
		(layer "F.Cu")
		(net "SMB_FRU_3V3AUX_R1_SCL")
	)
	(segment
		(start 319.532 -117.2464)
		(end 319.753488 -117.024912)
		(width 0.10668)
		(layer "F.Cu")
		(net "SMB_FRU_3V3AUX_R1_SCL")
	)
	(via
		(at 316.277498 -116.378228)
		(size 0.762)
		(drill 0.381)
		(layers "F.Cu" "B.Cu")
		(net "SMB_FRU_3V3AUX_R1_SCL")
	)
	(segment
		(start 314.167266 -108.52277)
		(end 314.167266 -109.53877)
		(width 0.10668)
		(layer "F.Cu")
		(net "SMB_CPU_FRU_3V3AUX_SDA")
	)
	(segment
		(start 313.124596 -109.53877)
		(end 312.967116 -109.69625)
		(width 0.10668)
		(layer "F.Cu")
		(net "SMB_CPU_FRU_3V3AUX_SDA")
	)
	(segment
		(start 311.316116 -109.69625)
		(end 312.967116 -109.69625)
		(width 0.10668)
		(layer "F.Cu")
		(net "SMB_CPU_FRU_3V3AUX_SDA")
	)
	(segment
		(start 314.167266 -109.53877)
		(end 313.124596 -109.53877)
		(width 0.10668)
		(layer "F.Cu")
		(net "SMB_CPU_FRU_3V3AUX_SDA")
	)
	(via
		(at 312.967116 -109.69625)
		(size 0.762)
		(drill 0.381)
		(layers "F.Cu" "B.Cu")
		(net "SMB_CPU_FRU_3V3AUX_SDA")
	)
	(segment
		(start 314.167266 -110.55477)
		(end 313.378596 -110.55477)
		(width 0.10668)
		(layer "F.Cu")
		(net "SMB_CPU_FRU_3V3AUX_SCL")
	)
	(segment
		(start 314.167266 -111.57077)
		(end 314.167266 -110.55477)
		(width 0.10668)
		(layer "F.Cu")
		(net "SMB_CPU_FRU_3V3AUX_SCL")
	)
	(segment
		(start 311.316116 -110.96625)
		(end 312.967116 -110.96625)
		(width 0.10668)
		(layer "F.Cu")
		(net "SMB_CPU_FRU_3V3AUX_SCL")
	)
	(segment
		(start 313.378596 -110.55477)
		(end 312.967116 -110.96625)
		(width 0.10668)
		(layer "F.Cu")
		(net "SMB_CPU_FRU_3V3AUX_SCL")
	)
	(via
		(at 312.967116 -110.96625)
		(size 0.762)
		(drill 0.381)
		(layers "F.Cu" "B.Cu")
		(net "SMB_CPU_FRU_3V3AUX_SCL")
	)
	(via
		(at 230.505 -244.680486)
		(size 0.508)
		(drill 0.254)
		(layers "F.Cu" "B.Cu")
		(net "SMB_CPU0_CPU1_APML_MUX2_SDA")
	)
	(via
		(at 230.886 -248.282714)
		(size 0.508)
		(drill 0.254)
		(layers "F.Cu" "B.Cu")
		(net "SMB_CPU0_CPU1_APML_MUX2_SDA")
	)
	(segment
		(start 230.505 -243.64315)
		(end 230.505 -244.680486)
		(width 0.10668)
		(layer "B.Cu")
		(net "SMB_CPU0_CPU1_APML_MUX2_SDA")
	)
	(segment
		(start 232.217722 -248.282714)
		(end 230.886 -248.282714)
		(width 0.10668)
		(layer "B.Cu")
		(net "SMB_CPU0_CPU1_APML_MUX2_SDA")
	)
	(segment
		(start 230.22941 -247.693434)
		(end 230.81869 -248.282714)
		(width 0.11684)
		(layer "In4.Cu")
		(net "SMB_CPU0_CPU1_APML_MUX2_SDA")
	)
	(segment
		(start 230.22941 -244.956076)
		(end 230.22941 -247.693434)
		(width 0.11684)
		(layer "In4.Cu")
		(net "SMB_CPU0_CPU1_APML_MUX2_SDA")
	)
	(segment
		(start 230.81869 -248.282714)
		(end 230.886 -248.282714)
		(width 0.11684)
		(layer "In4.Cu")
		(net "SMB_CPU0_CPU1_APML_MUX2_SDA")
	)
	(segment
		(start 230.505 -244.680486)
		(end 230.22941 -244.956076)
		(width 0.11684)
		(layer "In4.Cu")
		(net "SMB_CPU0_CPU1_APML_MUX2_SDA")
	)
	(via
		(at 231.775 -244.680486)
		(size 0.508)
		(drill 0.254)
		(layers "F.Cu" "B.Cu")
		(net "SMB_CPU0_CPU1_APML_MUX2_SCL")
	)
	(via
		(at 231.404414 -248.782586)
		(size 0.508)
		(drill 0.254)
		(layers "F.Cu" "B.Cu")
		(net "SMB_CPU0_CPU1_APML_MUX2_SCL")
	)
	(segment
		(start 231.775 -243.64315)
		(end 231.775 -244.680486)
		(width 0.10668)
		(layer "B.Cu")
		(net "SMB_CPU0_CPU1_APML_MUX2_SCL")
	)
	(segment
		(start 232.217722 -248.782586)
		(end 231.404414 -248.782586)
		(width 0.10668)
		(layer "B.Cu")
		(net "SMB_CPU0_CPU1_APML_MUX2_SCL")
	)
	(segment
		(start 231.775 -244.680486)
		(end 231.775 -248.412)
		(width 0.11684)
		(layer "In4.Cu")
		(net "SMB_CPU0_CPU1_APML_MUX2_SCL")
	)
	(segment
		(start 231.775 -248.412)
		(end 231.404414 -248.782586)
		(width 0.11684)
		(layer "In4.Cu")
		(net "SMB_CPU0_CPU1_APML_MUX2_SCL")
	)
	(via
		(at 230.378 -239.141)
		(size 0.6604)
		(drill 0.3302)
		(layers "F.Cu" "B.Cu")
		(net "SMB_CPU0_CPU1_APML_MUX1_SDA")
	)
	(via
		(at 230.39705 -240.919)
		(size 0.508)
		(drill 0.254)
		(layers "F.Cu" "B.Cu")
		(net "SMB_CPU0_CPU1_APML_MUX1_SDA")
	)
	(via
		(at 228.854 -230.886)
		(size 0.508)
		(drill 0.254)
		(layers "F.Cu" "B.Cu")
		(net "SMB_CPU0_CPU1_APML_MUX1_SDA")
	)
	(segment
		(start 228.854 -231.75595)
		(end 228.854 -230.886)
		(width 0.10668)
		(layer "B.Cu")
		(net "SMB_CPU0_CPU1_APML_MUX1_SDA")
	)
	(segment
		(start 230.378 -239.62995)
		(end 230.378 -239.141)
		(width 0.10668)
		(layer "B.Cu")
		(net "SMB_CPU0_CPU1_APML_MUX1_SDA")
	)
	(segment
		(start 230.39705 -239.649)
		(end 230.378 -239.62995)
		(width 0.10668)
		(layer "B.Cu")
		(net "SMB_CPU0_CPU1_APML_MUX1_SDA")
	)
	(segment
		(start 230.39705 -240.03)
		(end 230.39705 -239.649)
		(width 0.10668)
		(layer "B.Cu")
		(net "SMB_CPU0_CPU1_APML_MUX1_SDA")
	)
	(segment
		(start 230.88854 -238.63046)
		(end 230.378 -239.141)
		(width 0.10668)
		(layer "B.Cu")
		(net "SMB_CPU0_CPU1_APML_MUX1_SDA")
	)
	(segment
		(start 230.505 -241.02695)
		(end 230.39705 -240.919)
		(width 0.10668)
		(layer "B.Cu")
		(net "SMB_CPU0_CPU1_APML_MUX1_SDA")
	)
	(segment
		(start 230.88854 -237.449106)
		(end 230.88854 -238.63046)
		(width 0.10668)
		(layer "B.Cu")
		(net "SMB_CPU0_CPU1_APML_MUX1_SDA")
	)
	(segment
		(start 230.505 -242.04295)
		(end 230.505 -241.02695)
		(width 0.10668)
		(layer "B.Cu")
		(net "SMB_CPU0_CPU1_APML_MUX1_SDA")
	)
	(segment
		(start 230.39705 -240.03)
		(end 230.39705 -240.919)
		(width 0.10668)
		(layer "B.Cu")
		(net "SMB_CPU0_CPU1_APML_MUX1_SDA")
	)
	(segment
		(start 228.854 -230.886)
		(end 228.854 -234.951778)
		(width 0.11684)
		(layer "In4.Cu")
		(net "SMB_CPU0_CPU1_APML_MUX1_SDA")
	)
	(segment
		(start 228.854 -234.951778)
		(end 230.39705 -236.494828)
		(width 0.11684)
		(layer "In4.Cu")
		(net "SMB_CPU0_CPU1_APML_MUX1_SDA")
	)
	(segment
		(start 230.39705 -236.494828)
		(end 230.39705 -240.919)
		(width 0.11684)
		(layer "In4.Cu")
		(net "SMB_CPU0_CPU1_APML_MUX1_SDA")
	)
	(via
		(at 231.75595 -239.141)
		(size 0.6604)
		(drill 0.3302)
		(layers "F.Cu" "B.Cu")
		(net "SMB_CPU0_CPU1_APML_MUX1_SCL")
	)
	(via
		(at 231.75595 -240.919)
		(size 0.508)
		(drill 0.254)
		(layers "F.Cu" "B.Cu")
		(net "SMB_CPU0_CPU1_APML_MUX1_SCL")
	)
	(via
		(at 232.918 -230.886)
		(size 0.508)
		(drill 0.254)
		(layers "F.Cu" "B.Cu")
		(net "SMB_CPU0_CPU1_APML_MUX1_SCL")
	)
	(segment
		(start 231.775 -240.93805)
		(end 231.75595 -240.919)
		(width 0.10668)
		(layer "B.Cu")
		(net "SMB_CPU0_CPU1_APML_MUX1_SCL")
	)
	(segment
		(start 231.75595 -239.141)
		(end 231.75595 -240.03)
		(width 0.10668)
		(layer "B.Cu")
		(net "SMB_CPU0_CPU1_APML_MUX1_SCL")
	)
	(segment
		(start 231.775 -242.04295)
		(end 231.775 -240.93805)
		(width 0.10668)
		(layer "B.Cu")
		(net "SMB_CPU0_CPU1_APML_MUX1_SCL")
	)
	(segment
		(start 232.918 -231.75595)
		(end 232.918 -230.886)
		(width 0.10668)
		(layer "B.Cu")
		(net "SMB_CPU0_CPU1_APML_MUX1_SCL")
	)
	(segment
		(start 231.388412 -237.449106)
		(end 231.388412 -238.773462)
		(width 0.10668)
		(layer "B.Cu")
		(net "SMB_CPU0_CPU1_APML_MUX1_SCL")
	)
	(segment
		(start 231.75595 -240.03)
		(end 231.75595 -240.919)
		(width 0.10668)
		(layer "B.Cu")
		(net "SMB_CPU0_CPU1_APML_MUX1_SCL")
	)
	(segment
		(start 231.388412 -238.773462)
		(end 231.75595 -239.141)
		(width 0.10668)
		(layer "B.Cu")
		(net "SMB_CPU0_CPU1_APML_MUX1_SCL")
	)
	(segment
		(start 232.21315 -231.59085)
		(end 232.21315 -238.418116)
		(width 0.11684)
		(layer "In4.Cu")
		(net "SMB_CPU0_CPU1_APML_MUX1_SCL")
	)
	(segment
		(start 231.891332 -238.739934)
		(end 231.891332 -240.783618)
		(width 0.11684)
		(layer "In4.Cu")
		(net "SMB_CPU0_CPU1_APML_MUX1_SCL")
	)
	(segment
		(start 231.891332 -240.783618)
		(end 231.75595 -240.919)
		(width 0.11684)
		(layer "In4.Cu")
		(net "SMB_CPU0_CPU1_APML_MUX1_SCL")
	)
	(segment
		(start 232.21315 -238.418116)
		(end 231.891332 -238.739934)
		(width 0.11684)
		(layer "In4.Cu")
		(net "SMB_CPU0_CPU1_APML_MUX1_SCL")
	)
	(segment
		(start 232.918 -230.886)
		(end 232.21315 -231.59085)
		(width 0.11684)
		(layer "In4.Cu")
		(net "SMB_CPU0_CPU1_APML_MUX1_SCL")
	)
	(via
		(at 230.380794 -215.787224)
		(size 0.6604)
		(drill 0.3302)
		(layers "F.Cu" "B.Cu")
		(net "SMB_CPU0_CPU1_APML_BUF2_SDA_R2")
	)
	(segment
		(start 230.380794 -215.787224)
		(end 230.01605 -216.151968)
		(width 0.10668)
		(layer "B.Cu")
		(net "SMB_CPU0_CPU1_APML_BUF2_SDA_R2")
	)
	(segment
		(start 233.886248 -213.258654)
		(end 233.400854 -213.744048)
		(width 0.10668)
		(layer "B.Cu")
		(net "SMB_CPU0_CPU1_APML_BUF2_SDA_R2")
	)
	(segment
		(start 233.400854 -213.744048)
		(end 232.42397 -213.744048)
		(width 0.10668)
		(layer "B.Cu")
		(net "SMB_CPU0_CPU1_APML_BUF2_SDA_R2")
	)
	(segment
		(start 229.997 -217.65895)
		(end 229.997 -216.68105)
		(width 0.10668)
		(layer "B.Cu")
		(net "SMB_CPU0_CPU1_APML_BUF2_SDA_R2")
	)
	(segment
		(start 232.42397 -213.744048)
		(end 230.380794 -215.787224)
		(width 0.10668)
		(layer "B.Cu")
		(net "SMB_CPU0_CPU1_APML_BUF2_SDA_R2")
	)
	(segment
		(start 230.01605 -216.151968)
		(end 230.01605 -216.662)
		(width 0.10668)
		(layer "B.Cu")
		(net "SMB_CPU0_CPU1_APML_BUF2_SDA_R2")
	)
	(segment
		(start 229.997 -216.68105)
		(end 230.01605 -216.662)
		(width 0.10668)
		(layer "B.Cu")
		(net "SMB_CPU0_CPU1_APML_BUF2_SDA_R2")
	)
	(via
		(at 229.997 -219.329)
		(size 0.6604)
		(drill 0.3302)
		(layers "F.Cu" "B.Cu")
		(net "SMB_CPU0_CPU1_APML_BUF2_SDA_R1")
	)
	(segment
		(start 229.997 -219.329)
		(end 229.997 -218.45905)
		(width 0.10668)
		(layer "B.Cu")
		(net "SMB_CPU0_CPU1_APML_BUF2_SDA_R1")
	)
	(segment
		(start 230.32593 -219.65793)
		(end 229.997 -219.329)
		(width 0.10668)
		(layer "B.Cu")
		(net "SMB_CPU0_CPU1_APML_BUF2_SDA_R1")
	)
	(segment
		(start 230.32593 -220.86697)
		(end 230.32593 -219.65793)
		(width 0.10668)
		(layer "B.Cu")
		(net "SMB_CPU0_CPU1_APML_BUF2_SDA_R1")
	)
	(via
		(at 232.41 -228.092)
		(size 0.6604)
		(drill 0.3302)
		(layers "F.Cu" "B.Cu")
		(net "SMB_CPU0_CPU1_APML_BUF2_SDA")
	)
	(segment
		(start 230.32593 -226.00793)
		(end 232.41 -228.092)
		(width 0.10668)
		(layer "B.Cu")
		(net "SMB_CPU0_CPU1_APML_BUF2_SDA")
	)
	(segment
		(start 232.41 -228.092)
		(end 233.27995 -228.092)
		(width 0.10668)
		(layer "B.Cu")
		(net "SMB_CPU0_CPU1_APML_BUF2_SDA")
	)
	(segment
		(start 230.32593 -225.216974)
		(end 230.32593 -226.00793)
		(width 0.10668)
		(layer "B.Cu")
		(net "SMB_CPU0_CPU1_APML_BUF2_SDA")
	)
	(via
		(at 232.11663 -215.050624)
		(size 0.6604)
		(drill 0.3302)
		(layers "F.Cu" "B.Cu")
		(net "SMB_CPU0_CPU1_APML_BUF2_SCL_R2")
	)
	(segment
		(start 232.352342 -214.814912)
		(end 232.11663 -215.050624)
		(width 0.10668)
		(layer "B.Cu")
		(net "SMB_CPU0_CPU1_APML_BUF2_SCL_R2")
	)
	(segment
		(start 233.91495 -215.186514)
		(end 233.543348 -214.814912)
		(width 0.10668)
		(layer "B.Cu")
		(net "SMB_CPU0_CPU1_APML_BUF2_SCL_R2")
	)
	(segment
		(start 231.267 -216.76995)
		(end 231.37495 -216.662)
		(width 0.10668)
		(layer "B.Cu")
		(net "SMB_CPU0_CPU1_APML_BUF2_SCL_R2")
	)
	(segment
		(start 231.37495 -215.792304)
		(end 231.37495 -216.662)
		(width 0.10668)
		(layer "B.Cu")
		(net "SMB_CPU0_CPU1_APML_BUF2_SCL_R2")
	)
	(segment
		(start 232.11663 -215.050624)
		(end 231.37495 -215.792304)
		(width 0.10668)
		(layer "B.Cu")
		(net "SMB_CPU0_CPU1_APML_BUF2_SCL_R2")
	)
	(segment
		(start 233.543348 -214.814912)
		(end 232.352342 -214.814912)
		(width 0.10668)
		(layer "B.Cu")
		(net "SMB_CPU0_CPU1_APML_BUF2_SCL_R2")
	)
	(segment
		(start 231.267 -217.65895)
		(end 231.267 -216.76995)
		(width 0.10668)
		(layer "B.Cu")
		(net "SMB_CPU0_CPU1_APML_BUF2_SCL_R2")
	)
	(via
		(at 231.267 -219.329)
		(size 0.6604)
		(drill 0.3302)
		(layers "F.Cu" "B.Cu")
		(net "SMB_CPU0_CPU1_APML_BUF2_SCL_R1")
	)
	(segment
		(start 231.267 -219.329)
		(end 231.267 -218.45905)
		(width 0.10668)
		(layer "B.Cu")
		(net "SMB_CPU0_CPU1_APML_BUF2_SCL_R1")
	)
	(segment
		(start 230.97617 -219.61983)
		(end 231.267 -219.329)
		(width 0.10668)
		(layer "B.Cu")
		(net "SMB_CPU0_CPU1_APML_BUF2_SCL_R1")
	)
	(segment
		(start 230.97617 -220.86697)
		(end 230.97617 -219.61983)
		(width 0.10668)
		(layer "B.Cu")
		(net "SMB_CPU0_CPU1_APML_BUF2_SCL_R1")
	)
	(via
		(at 232.41 -226.822)
		(size 0.6604)
		(drill 0.3302)
		(layers "F.Cu" "B.Cu")
		(net "SMB_CPU0_CPU1_APML_BUF2_SCL")
	)
	(segment
		(start 233.27995 -226.822)
		(end 232.41 -226.822)
		(width 0.10668)
		(layer "B.Cu")
		(net "SMB_CPU0_CPU1_APML_BUF2_SCL")
	)
	(segment
		(start 232.41 -226.822)
		(end 231.775 -226.822)
		(width 0.10668)
		(layer "B.Cu")
		(net "SMB_CPU0_CPU1_APML_BUF2_SCL")
	)
	(segment
		(start 231.775 -226.822)
		(end 230.97617 -226.02317)
		(width 0.10668)
		(layer "B.Cu")
		(net "SMB_CPU0_CPU1_APML_BUF2_SCL")
	)
	(segment
		(start 230.97617 -226.02317)
		(end 230.97617 -225.216974)
		(width 0.10668)
		(layer "B.Cu")
		(net "SMB_CPU0_CPU1_APML_BUF2_SCL")
	)
	(via
		(at 239.022382 -215.038432)
		(size 0.6604)
		(drill 0.3302)
		(layers "F.Cu" "B.Cu")
		(net "SMB_CPU0_CPU1_APML_BUF1_SDA_R2")
	)
	(segment
		(start 239.50295 -216.027)
		(end 239.50295 -216.38895)
		(width 0.10668)
		(layer "B.Cu")
		(net "SMB_CPU0_CPU1_APML_BUF1_SDA_R2")
	)
	(segment
		(start 237.906052 -213.922102)
		(end 239.022382 -215.038432)
		(width 0.10668)
		(layer "B.Cu")
		(net "SMB_CPU0_CPU1_APML_BUF1_SDA_R2")
	)
	(segment
		(start 239.50295 -215.519)
		(end 239.50295 -216.027)
		(width 0.10668)
		(layer "B.Cu")
		(net "SMB_CPU0_CPU1_APML_BUF1_SDA_R2")
	)
	(segment
		(start 236.149896 -213.922102)
		(end 237.906052 -213.922102)
		(width 0.10668)
		(layer "B.Cu")
		(net "SMB_CPU0_CPU1_APML_BUF1_SDA_R2")
	)
	(segment
		(start 239.50295 -216.38895)
		(end 239.522 -216.408)
		(width 0.10668)
		(layer "B.Cu")
		(net "SMB_CPU0_CPU1_APML_BUF1_SDA_R2")
	)
	(segment
		(start 235.486448 -213.258654)
		(end 236.149896 -213.922102)
		(width 0.10668)
		(layer "B.Cu")
		(net "SMB_CPU0_CPU1_APML_BUF1_SDA_R2")
	)
	(segment
		(start 239.022382 -215.038432)
		(end 239.50295 -215.519)
		(width 0.10668)
		(layer "B.Cu")
		(net "SMB_CPU0_CPU1_APML_BUF1_SDA_R2")
	)
	(segment
		(start 239.522 -216.408)
		(end 239.522 -217.27795)
		(width 0.10668)
		(layer "B.Cu")
		(net "SMB_CPU0_CPU1_APML_BUF1_SDA_R2")
	)
	(via
		(at 235.712 -228.092)
		(size 0.6604)
		(drill 0.3302)
		(layers "F.Cu" "B.Cu")
		(net "SMB_CPU0_CPU1_APML_BUF1_SDA")
	)
	(segment
		(start 239.24895 -227.203)
		(end 238.35995 -228.092)
		(width 0.10668)
		(layer "B.Cu")
		(net "SMB_CPU0_CPU1_APML_BUF1_SDA")
	)
	(segment
		(start 235.712 -228.092)
		(end 234.88015 -228.092)
		(width 0.10668)
		(layer "B.Cu")
		(net "SMB_CPU0_CPU1_APML_BUF1_SDA")
	)
	(segment
		(start 238.35995 -228.092)
		(end 235.712 -228.092)
		(width 0.10668)
		(layer "B.Cu")
		(net "SMB_CPU0_CPU1_APML_BUF1_SDA")
	)
	(segment
		(start 239.065562 -227.019612)
		(end 239.24895 -227.203)
		(width 0.10668)
		(layer "B.Cu")
		(net "SMB_CPU0_CPU1_APML_BUF1_SDA")
	)
	(segment
		(start 239.065562 -225.277172)
		(end 239.065562 -227.019612)
		(width 0.10668)
		(layer "B.Cu")
		(net "SMB_CPU0_CPU1_APML_BUF1_SDA")
	)
	(via
		(at 237.268766 -214.503)
		(size 0.6604)
		(drill 0.3302)
		(layers "F.Cu" "B.Cu")
		(net "SMB_CPU0_CPU1_APML_BUF1_SCL_R2")
	)
	(segment
		(start 238.27105 -216.027)
		(end 238.27105 -216.38895)
		(width 0.10668)
		(layer "B.Cu")
		(net "SMB_CPU0_CPU1_APML_BUF1_SCL_R2")
	)
	(segment
		(start 236.198664 -214.503)
		(end 237.268766 -214.503)
		(width 0.10668)
		(layer "B.Cu")
		(net "SMB_CPU0_CPU1_APML_BUF1_SCL_R2")
	)
	(segment
		(start 237.268766 -214.503)
		(end 237.870746 -214.503)
		(width 0.10668)
		(layer "B.Cu")
		(net "SMB_CPU0_CPU1_APML_BUF1_SCL_R2")
	)
	(segment
		(start 238.27105 -214.903304)
		(end 238.27105 -216.027)
		(width 0.10668)
		(layer "B.Cu")
		(net "SMB_CPU0_CPU1_APML_BUF1_SCL_R2")
	)
	(segment
		(start 237.870746 -214.503)
		(end 238.27105 -214.903304)
		(width 0.10668)
		(layer "B.Cu")
		(net "SMB_CPU0_CPU1_APML_BUF1_SCL_R2")
	)
	(segment
		(start 238.252 -216.408)
		(end 238.252 -217.27795)
		(width 0.10668)
		(layer "B.Cu")
		(net "SMB_CPU0_CPU1_APML_BUF1_SCL_R2")
	)
	(segment
		(start 238.27105 -216.38895)
		(end 238.252 -216.408)
		(width 0.10668)
		(layer "B.Cu")
		(net "SMB_CPU0_CPU1_APML_BUF1_SCL_R2")
	)
	(segment
		(start 235.51515 -215.186514)
		(end 236.198664 -214.503)
		(width 0.10668)
		(layer "B.Cu")
		(net "SMB_CPU0_CPU1_APML_BUF1_SCL_R2")
	)
	(via
		(at 235.712 -226.822)
		(size 0.6604)
		(drill 0.3302)
		(layers "F.Cu" "B.Cu")
		(net "SMB_CPU0_CPU1_APML_BUF1_SCL")
	)
	(segment
		(start 234.88015 -226.822)
		(end 235.712 -226.822)
		(width 0.10668)
		(layer "B.Cu")
		(net "SMB_CPU0_CPU1_APML_BUF1_SCL")
	)
	(segment
		(start 238.27105 -227.584)
		(end 238.27105 -227.203)
		(width 0.10668)
		(layer "B.Cu")
		(net "SMB_CPU0_CPU1_APML_BUF1_SCL")
	)
	(segment
		(start 236.601 -227.711)
		(end 238.14405 -227.711)
		(width 0.10668)
		(layer "B.Cu")
		(net "SMB_CPU0_CPU1_APML_BUF1_SCL")
	)
	(segment
		(start 238.14405 -227.711)
		(end 238.27105 -227.584)
		(width 0.10668)
		(layer "B.Cu")
		(net "SMB_CPU0_CPU1_APML_BUF1_SCL")
	)
	(segment
		(start 235.712 -226.822)
		(end 236.601 -227.711)
		(width 0.10668)
		(layer "B.Cu")
		(net "SMB_CPU0_CPU1_APML_BUF1_SCL")
	)
	(segment
		(start 238.415322 -225.277172)
		(end 238.415322 -227.058728)
		(width 0.10668)
		(layer "B.Cu")
		(net "SMB_CPU0_CPU1_APML_BUF1_SCL")
	)
	(segment
		(start 238.415322 -227.058728)
		(end 238.27105 -227.203)
		(width 0.10668)
		(layer "B.Cu")
		(net "SMB_CPU0_CPU1_APML_BUF1_SCL")
	)
	(via
		(at 234.569 -242.901216)
		(size 0.6604)
		(drill 0.3302)
		(layers "F.Cu" "B.Cu")
		(net "SMB_APML_CPU1_MUX2_SDA")
	)
	(segment
		(start 234.569 -242.901216)
		(end 234.569 -247.269)
		(width 0.10668)
		(layer "B.Cu")
		(net "SMB_APML_CPU1_MUX2_SDA")
	)
	(segment
		(start 234.569 -241.61115)
		(end 234.569 -242.901216)
		(width 0.10668)
		(layer "B.Cu")
		(net "SMB_APML_CPU1_MUX2_SDA")
	)
	(segment
		(start 234.055412 -247.782588)
		(end 233.497882 -247.782588)
		(width 0.10668)
		(layer "B.Cu")
		(net "SMB_APML_CPU1_MUX2_SDA")
	)
	(segment
		(start 234.569 -247.269)
		(end 234.055412 -247.782588)
		(width 0.10668)
		(layer "B.Cu")
		(net "SMB_APML_CPU1_MUX2_SDA")
	)
	(via
		(at 235.839 -242.910106)
		(size 0.6604)
		(drill 0.3302)
		(layers "F.Cu" "B.Cu")
		(net "SMB_APML_CPU1_MUX2_SCL")
	)
	(segment
		(start 235.839 -241.61115)
		(end 235.839 -242.910106)
		(width 0.10668)
		(layer "B.Cu")
		(net "SMB_APML_CPU1_MUX2_SCL")
	)
	(segment
		(start 234.317032 -248.282714)
		(end 233.497882 -248.282714)
		(width 0.10668)
		(layer "B.Cu")
		(net "SMB_APML_CPU1_MUX2_SCL")
	)
	(segment
		(start 235.839 -246.760746)
		(end 234.317032 -248.282714)
		(width 0.10668)
		(layer "B.Cu")
		(net "SMB_APML_CPU1_MUX2_SCL")
	)
	(segment
		(start 235.839 -242.910106)
		(end 235.839 -246.760746)
		(width 0.10668)
		(layer "B.Cu")
		(net "SMB_APML_CPU1_MUX2_SCL")
	)
	(via
		(at 235.458 -248.285)
		(size 0.6604)
		(drill 0.3302)
		(layers "F.Cu" "B.Cu")
		(net "SMB_APML_CPU0_MUX2_SDA")
	)
	(segment
		(start 234.960414 -248.782586)
		(end 235.458 -248.285)
		(width 0.10668)
		(layer "B.Cu")
		(net "SMB_APML_CPU0_MUX2_SDA")
	)
	(segment
		(start 233.497882 -248.782586)
		(end 234.960414 -248.782586)
		(width 0.10668)
		(layer "B.Cu")
		(net "SMB_APML_CPU0_MUX2_SDA")
	)
	(segment
		(start 236.41685 -248.285)
		(end 235.458 -248.285)
		(width 0.10668)
		(layer "B.Cu")
		(net "SMB_APML_CPU0_MUX2_SDA")
	)
	(via
		(at 235.458 -249.555)
		(size 0.6604)
		(drill 0.3302)
		(layers "F.Cu" "B.Cu")
		(net "SMB_APML_CPU0_MUX2_SCL")
	)
	(segment
		(start 236.41685 -249.555)
		(end 235.458 -249.555)
		(width 0.10668)
		(layer "B.Cu")
		(net "SMB_APML_CPU0_MUX2_SCL")
	)
	(segment
		(start 234.042966 -249.282712)
		(end 233.497882 -249.282712)
		(width 0.10668)
		(layer "B.Cu")
		(net "SMB_APML_CPU0_MUX2_SCL")
	)
	(segment
		(start 235.458 -249.555)
		(end 234.315254 -249.555)
		(width 0.10668)
		(layer "B.Cu")
		(net "SMB_APML_CPU0_MUX2_SCL")
	)
	(segment
		(start 234.315254 -249.555)
		(end 234.042966 -249.282712)
		(width 0.10668)
		(layer "B.Cu")
		(net "SMB_APML_CPU0_MUX2_SCL")
	)
	(segment
		(start 50.48504 -434.960014)
		(end 49.977802 -434.452776)
		(width 0.10668)
		(layer "F.Cu")
		(net "RST_PERST_CPU1_SWB_1_R_N")
	)
	(via
		(at 213.78164 -141.7828)
		(size 0.508)
		(drill 0.254)
		(layers "F.Cu" "B.Cu")
		(net "RST_PERST_CPU1_SWB_1_R_N")
	)
	(via
		(at 49.977802 -434.452776)
		(size 0.508)
		(drill 0.254)
		(layers "F.Cu" "B.Cu")
		(net "RST_PERST_CPU1_SWB_1_R_N")
	)
	(via
		(at 214.07755 -114.995706)
		(size 0.508)
		(drill 0.254)
		(layers "F.Cu" "B.Cu")
		(net "RST_PERST_CPU1_SWB_1_R_N")
	)
	(segment
		(start 203.3016 -114.8842)
		(end 208.3562 -114.8842)
		(width 0.10668)
		(layer "B.Cu")
		(net "RST_PERST_CPU1_SWB_1_R_N")
	)
	(segment
		(start 209.82686 -113.41354)
		(end 211.33054 -113.41354)
		(width 0.10668)
		(layer "B.Cu")
		(net "RST_PERST_CPU1_SWB_1_R_N")
	)
	(segment
		(start 201.5236 -115.955572)
		(end 201.5236 -115.5446)
		(width 0.10668)
		(layer "B.Cu")
		(net "RST_PERST_CPU1_SWB_1_R_N")
	)
	(segment
		(start 208.3562 -114.8842)
		(end 209.82686 -113.41354)
		(width 0.10668)
		(layer "B.Cu")
		(net "RST_PERST_CPU1_SWB_1_R_N")
	)
	(segment
		(start 212.912706 -114.995706)
		(end 214.07755 -114.995706)
		(width 0.10668)
		(layer "B.Cu")
		(net "RST_PERST_CPU1_SWB_1_R_N")
	)
	(segment
		(start 201.8792 -115.189)
		(end 202.9968 -115.189)
		(width 0.10668)
		(layer "B.Cu")
		(net "RST_PERST_CPU1_SWB_1_R_N")
	)
	(segment
		(start 202.9968 -115.189)
		(end 203.3016 -114.8842)
		(width 0.10668)
		(layer "B.Cu")
		(net "RST_PERST_CPU1_SWB_1_R_N")
	)
	(segment
		(start 211.33054 -113.41354)
		(end 212.912706 -114.995706)
		(width 0.10668)
		(layer "B.Cu")
		(net "RST_PERST_CPU1_SWB_1_R_N")
	)
	(segment
		(start 201.5236 -115.5446)
		(end 201.8792 -115.189)
		(width 0.10668)
		(layer "B.Cu")
		(net "RST_PERST_CPU1_SWB_1_R_N")
	)
	(segment
		(start 214.321898 -127.88265)
		(end 214.321898 -120.445022)
		(width 0.11684)
		(layer "In4.Cu")
		(net "RST_PERST_CPU1_SWB_1_R_N")
	)
	(segment
		(start 213.78164 -141.7828)
		(end 213.78164 -140.38072)
		(width 0.11684)
		(layer "In4.Cu")
		(net "RST_PERST_CPU1_SWB_1_R_N")
	)
	(segment
		(start 216.32926 -137.8331)
		(end 216.32926 -129.890012)
		(width 0.11684)
		(layer "In4.Cu")
		(net "RST_PERST_CPU1_SWB_1_R_N")
	)
	(segment
		(start 216.32926 -129.890012)
		(end 214.321898 -127.88265)
		(width 0.11684)
		(layer "In4.Cu")
		(net "RST_PERST_CPU1_SWB_1_R_N")
	)
	(segment
		(start 214.321898 -120.445022)
		(end 214.07755 -120.200674)
		(width 0.11684)
		(layer "In4.Cu")
		(net "RST_PERST_CPU1_SWB_1_R_N")
	)
	(segment
		(start 213.78164 -140.38072)
		(end 216.32926 -137.8331)
		(width 0.11684)
		(layer "In4.Cu")
		(net "RST_PERST_CPU1_SWB_1_R_N")
	)
	(segment
		(start 214.07755 -120.200674)
		(end 214.07755 -114.995706)
		(width 0.11684)
		(layer "In4.Cu")
		(net "RST_PERST_CPU1_SWB_1_R_N")
	)
	(segment
		(start 24.89073 -370.407438)
		(end 29.797502 -375.31421)
		(width 0.11684)
		(layer "In13.Cu")
		(net "RST_PERST_CPU1_SWB_1_R_N")
	)
	(segment
		(start 50.879248 -433.55133)
		(end 50.374042 -433.55133)
		(width 0.11684)
		(layer "In13.Cu")
		(net "RST_PERST_CPU1_SWB_1_R_N")
	)
	(segment
		(start 43.710606 -422.629838)
		(end 45.844714 -424.763946)
		(width 0.11684)
		(layer "In13.Cu")
		(net "RST_PERST_CPU1_SWB_1_R_N")
	)
	(segment
		(start 157.345634 -143.97355)
		(end 150.453344 -137.08126)
		(width 0.11684)
		(layer "In13.Cu")
		(net "RST_PERST_CPU1_SWB_1_R_N")
	)
	(segment
		(start 6.86308 -336.03438)
		(end 16.114522 -345.285822)
		(width 0.11684)
		(layer "In13.Cu")
		(net "RST_PERST_CPU1_SWB_1_R_N")
	)
	(segment
		(start 17.671288 -356.15245)
		(end 17.671288 -367.974372)
		(width 0.11684)
		(layer "In13.Cu")
		(net "RST_PERST_CPU1_SWB_1_R_N")
	)
	(segment
		(start 16.114522 -345.285822)
		(end 16.114522 -354.595684)
		(width 0.11684)
		(layer "In13.Cu")
		(net "RST_PERST_CPU1_SWB_1_R_N")
	)
	(segment
		(start 188.60135 -144.576038)
		(end 176.769014 -144.576038)
		(width 0.11684)
		(layer "In13.Cu")
		(net "RST_PERST_CPU1_SWB_1_R_N")
	)
	(segment
		(start 29.797502 -375.31421)
		(end 29.797502 -379.621796)
		(width 0.11684)
		(layer "In13.Cu")
		(net "RST_PERST_CPU1_SWB_1_R_N")
	)
	(segment
		(start 38.264338 -388.088632)
		(end 38.264338 -392.22553)
		(width 0.11684)
		(layer "In13.Cu")
		(net "RST_PERST_CPU1_SWB_1_R_N")
	)
	(segment
		(start 33.900364 -413.87776)
		(end 35.064446 -415.041842)
		(width 0.11684)
		(layer "In13.Cu")
		(net "RST_PERST_CPU1_SWB_1_R_N")
	)
	(segment
		(start 93.184218 -136.70026)
		(end 79.400146 -136.70026)
		(width 0.11684)
		(layer "In13.Cu")
		(net "RST_PERST_CPU1_SWB_1_R_N")
	)
	(segment
		(start 51.452526 -432.978052)
		(end 50.879248 -433.55133)
		(width 0.11684)
		(layer "In13.Cu")
		(net "RST_PERST_CPU1_SWB_1_R_N")
	)
	(segment
		(start 17.671288 -367.974372)
		(end 20.104354 -370.407438)
		(width 0.11684)
		(layer "In13.Cu")
		(net "RST_PERST_CPU1_SWB_1_R_N")
	)
	(segment
		(start 49.977802 -433.94757)
		(end 49.977802 -434.452776)
		(width 0.11684)
		(layer "In13.Cu")
		(net "RST_PERST_CPU1_SWB_1_R_N")
	)
	(segment
		(start 29.797502 -379.621796)
		(end 38.264338 -388.088632)
		(width 0.11684)
		(layer "In13.Cu")
		(net "RST_PERST_CPU1_SWB_1_R_N")
	)
	(segment
		(start 49.022 -426.927264)
		(end 49.022 -428.879)
		(width 0.11684)
		(layer "In13.Cu")
		(net "RST_PERST_CPU1_SWB_1_R_N")
	)
	(segment
		(start 20.104354 -370.407438)
		(end 24.89073 -370.407438)
		(width 0.11684)
		(layer "In13.Cu")
		(net "RST_PERST_CPU1_SWB_1_R_N")
	)
	(segment
		(start 16.114522 -354.595684)
		(end 17.671288 -356.15245)
		(width 0.11684)
		(layer "In13.Cu")
		(net "RST_PERST_CPU1_SWB_1_R_N")
	)
	(segment
		(start 176.166526 -143.97355)
		(end 157.345634 -143.97355)
		(width 0.11684)
		(layer "In13.Cu")
		(net "RST_PERST_CPU1_SWB_1_R_N")
	)
	(segment
		(start 51.452526 -431.309526)
		(end 51.452526 -432.978052)
		(width 0.11684)
		(layer "In13.Cu")
		(net "RST_PERST_CPU1_SWB_1_R_N")
	)
	(segment
		(start 38.264338 -392.22553)
		(end 36.763706 -393.726162)
		(width 0.11684)
		(layer "In13.Cu")
		(net "RST_PERST_CPU1_SWB_1_R_N")
	)
	(segment
		(start 197.068186 -142.426436)
		(end 193.947288 -142.426436)
		(width 0.11684)
		(layer "In13.Cu")
		(net "RST_PERST_CPU1_SWB_1_R_N")
	)
	(segment
		(start 192.573402 -143.800322)
		(end 189.377066 -143.800322)
		(width 0.11684)
		(layer "In13.Cu")
		(net "RST_PERST_CPU1_SWB_1_R_N")
	)
	(segment
		(start 36.97224 -415.041842)
		(end 43.710606 -421.780208)
		(width 0.11684)
		(layer "In13.Cu")
		(net "RST_PERST_CPU1_SWB_1_R_N")
	)
	(segment
		(start 35.44951 -397.45793)
		(end 35.44951 -408.347672)
		(width 0.11684)
		(layer "In13.Cu")
		(net "RST_PERST_CPU1_SWB_1_R_N")
	)
	(segment
		(start 189.377066 -143.800322)
		(end 188.60135 -144.576038)
		(width 0.11684)
		(layer "In13.Cu")
		(net "RST_PERST_CPU1_SWB_1_R_N")
	)
	(segment
		(start 93.565218 -137.08126)
		(end 93.184218 -136.70026)
		(width 0.11684)
		(layer "In13.Cu")
		(net "RST_PERST_CPU1_SWB_1_R_N")
	)
	(segment
		(start 213.78164 -141.7828)
		(end 211.473288 -144.091152)
		(width 0.11684)
		(layer "In13.Cu")
		(net "RST_PERST_CPU1_SWB_1_R_N")
	)
	(segment
		(start 198.732902 -144.091152)
		(end 197.068186 -142.426436)
		(width 0.11684)
		(layer "In13.Cu")
		(net "RST_PERST_CPU1_SWB_1_R_N")
	)
	(segment
		(start 35.064446 -415.041842)
		(end 36.97224 -415.041842)
		(width 0.11684)
		(layer "In13.Cu")
		(net "RST_PERST_CPU1_SWB_1_R_N")
	)
	(segment
		(start 77.77861 -138.321796)
		(end 30.750764 -138.321796)
		(width 0.11684)
		(layer "In13.Cu")
		(net "RST_PERST_CPU1_SWB_1_R_N")
	)
	(segment
		(start 30.750764 -138.321796)
		(end 18.682716 -150.389844)
		(width 0.11684)
		(layer "In13.Cu")
		(net "RST_PERST_CPU1_SWB_1_R_N")
	)
	(segment
		(start 6.86308 -186.222132)
		(end 6.86308 -336.03438)
		(width 0.11684)
		(layer "In13.Cu")
		(net "RST_PERST_CPU1_SWB_1_R_N")
	)
	(segment
		(start 18.682716 -150.389844)
		(end 18.682716 -174.402496)
		(width 0.11684)
		(layer "In13.Cu")
		(net "RST_PERST_CPU1_SWB_1_R_N")
	)
	(segment
		(start 211.473288 -144.091152)
		(end 198.732902 -144.091152)
		(width 0.11684)
		(layer "In13.Cu")
		(net "RST_PERST_CPU1_SWB_1_R_N")
	)
	(segment
		(start 35.44951 -408.347672)
		(end 33.900364 -409.896818)
		(width 0.11684)
		(layer "In13.Cu")
		(net "RST_PERST_CPU1_SWB_1_R_N")
	)
	(segment
		(start 43.710606 -421.780208)
		(end 43.710606 -422.629838)
		(width 0.11684)
		(layer "In13.Cu")
		(net "RST_PERST_CPU1_SWB_1_R_N")
	)
	(segment
		(start 176.769014 -144.576038)
		(end 176.166526 -143.97355)
		(width 0.11684)
		(layer "In13.Cu")
		(net "RST_PERST_CPU1_SWB_1_R_N")
	)
	(segment
		(start 36.763706 -393.726162)
		(end 36.763706 -396.143734)
		(width 0.11684)
		(layer "In13.Cu")
		(net "RST_PERST_CPU1_SWB_1_R_N")
	)
	(segment
		(start 36.763706 -396.143734)
		(end 35.44951 -397.45793)
		(width 0.11684)
		(layer "In13.Cu")
		(net "RST_PERST_CPU1_SWB_1_R_N")
	)
	(segment
		(start 50.374042 -433.55133)
		(end 49.977802 -433.94757)
		(width 0.11684)
		(layer "In13.Cu")
		(net "RST_PERST_CPU1_SWB_1_R_N")
	)
	(segment
		(start 79.400146 -136.70026)
		(end 77.77861 -138.321796)
		(width 0.11684)
		(layer "In13.Cu")
		(net "RST_PERST_CPU1_SWB_1_R_N")
	)
	(segment
		(start 46.858682 -424.763946)
		(end 49.022 -426.927264)
		(width 0.11684)
		(layer "In13.Cu")
		(net "RST_PERST_CPU1_SWB_1_R_N")
	)
	(segment
		(start 49.022 -428.879)
		(end 51.452526 -431.309526)
		(width 0.11684)
		(layer "In13.Cu")
		(net "RST_PERST_CPU1_SWB_1_R_N")
	)
	(segment
		(start 45.844714 -424.763946)
		(end 46.858682 -424.763946)
		(width 0.11684)
		(layer "In13.Cu")
		(net "RST_PERST_CPU1_SWB_1_R_N")
	)
	(segment
		(start 193.947288 -142.426436)
		(end 192.573402 -143.800322)
		(width 0.11684)
		(layer "In13.Cu")
		(net "RST_PERST_CPU1_SWB_1_R_N")
	)
	(segment
		(start 150.453344 -137.08126)
		(end 93.565218 -137.08126)
		(width 0.11684)
		(layer "In13.Cu")
		(net "RST_PERST_CPU1_SWB_1_R_N")
	)
	(segment
		(start 33.900364 -409.896818)
		(end 33.900364 -413.87776)
		(width 0.11684)
		(layer "In13.Cu")
		(net "RST_PERST_CPU1_SWB_1_R_N")
	)
	(segment
		(start 18.682716 -174.402496)
		(end 6.86308 -186.222132)
		(width 0.11684)
		(layer "In13.Cu")
		(net "RST_PERST_CPU1_SWB_1_R_N")
	)
	(segment
		(start 190.721996 -114.652806)
		(end 191.111886 -114.262916)
		(width 0.10668)
		(layer "F.Cu")
		(net "RST_PERST_CPU1_SWB_1_N")
	)
	(via
		(at 191.111886 -114.262916)
		(size 0.4572)
		(drill 0.254)
		(layers "F.Cu" "B.Cu")
		(net "RST_PERST_CPU1_SWB_1_N")
	)
	(via
		(at 194.578478 -114.649758)
		(size 0.6604)
		(drill 0.3302)
		(layers "F.Cu" "B.Cu")
		(net "RST_PERST_CPU1_SWB_1_N")
	)
	(segment
		(start 191.120268 -114.262916)
		(end 191.111886 -114.262916)
		(width 0.10668)
		(layer "B.Cu")
		(net "RST_PERST_CPU1_SWB_1_N")
	)
	(segment
		(start 196.153024 -114.15014)
		(end 195.653406 -114.649758)
		(width 0.10668)
		(layer "B.Cu")
		(net "RST_PERST_CPU1_SWB_1_N")
	)
	(segment
		(start 195.653406 -114.649758)
		(end 194.578478 -114.649758)
		(width 0.10668)
		(layer "B.Cu")
		(net "RST_PERST_CPU1_SWB_1_N")
	)
	(segment
		(start 194.540632 -114.687604)
		(end 191.544956 -114.687604)
		(width 0.10668)
		(layer "B.Cu")
		(net "RST_PERST_CPU1_SWB_1_N")
	)
	(segment
		(start 200.7235 -114.3889)
		(end 200.440036 -114.105436)
		(width 0.10668)
		(layer "B.Cu")
		(net "RST_PERST_CPU1_SWB_1_N")
	)
	(segment
		(start 199.647048 -114.105436)
		(end 199.602344 -114.15014)
		(width 0.10668)
		(layer "B.Cu")
		(net "RST_PERST_CPU1_SWB_1_N")
	)
	(segment
		(start 200.7235 -116.971572)
		(end 200.7235 -115.955572)
		(width 0.10668)
		(layer "B.Cu")
		(net "RST_PERST_CPU1_SWB_1_N")
	)
	(segment
		(start 200.7235 -115.955572)
		(end 200.7235 -114.3889)
		(width 0.10668)
		(layer "B.Cu")
		(net "RST_PERST_CPU1_SWB_1_N")
	)
	(segment
		(start 191.544956 -114.687604)
		(end 191.120268 -114.262916)
		(width 0.10668)
		(layer "B.Cu")
		(net "RST_PERST_CPU1_SWB_1_N")
	)
	(segment
		(start 194.578478 -114.649758)
		(end 194.540632 -114.687604)
		(width 0.10668)
		(layer "B.Cu")
		(net "RST_PERST_CPU1_SWB_1_N")
	)
	(segment
		(start 200.440036 -114.105436)
		(end 199.647048 -114.105436)
		(width 0.10668)
		(layer "B.Cu")
		(net "RST_PERST_CPU1_SWB_1_N")
	)
	(segment
		(start 199.602344 -114.15014)
		(end 196.153024 -114.15014)
		(width 0.10668)
		(layer "B.Cu")
		(net "RST_PERST_CPU1_SWB_1_N")
	)
	(via
		(at 229.601014 -226.822)
		(size 0.6604)
		(drill 0.3302)
		(layers "F.Cu" "B.Cu")
		(net "PU_U2_EN")
	)
	(segment
		(start 229.601014 -226.822)
		(end 229.601014 -225.216974)
		(width 0.10668)
		(layer "B.Cu")
		(net "PU_U2_EN")
	)
	(segment
		(start 229.576122 -226.846892)
		(end 229.601014 -226.822)
		(width 0.10668)
		(layer "B.Cu")
		(net "PU_U2_EN")
	)
	(segment
		(start 229.576122 -227.743258)
		(end 229.576122 -226.846892)
		(width 0.10668)
		(layer "B.Cu")
		(net "PU_U2_EN")
	)
	(segment
		(start 314.167266 -112.58677)
		(end 313.317636 -112.58677)
		(width 0.10668)
		(layer "F.Cu")
		(net "PD_CPU_FRU_WP")
	)
	(segment
		(start 313.317636 -112.58677)
		(end 312.967116 -112.23625)
		(width 0.10668)
		(layer "F.Cu")
		(net "PD_CPU_FRU_WP")
	)
	(segment
		(start 311.316116 -112.23625)
		(end 312.967116 -112.23625)
		(width 0.10668)
		(layer "F.Cu")
		(net "PD_CPU_FRU_WP")
	)
	(via
		(at 312.967116 -112.23625)
		(size 0.762)
		(drill 0.381)
		(layers "F.Cu" "B.Cu")
		(net "PD_CPU_FRU_WP")
	)
	(segment
		(start 187.522104 -109.852968)
		(end 187.911994 -109.463078)
		(width 0.10668)
		(layer "F.Cu")
		(net "FM_APML_MUX2_SEL_R")
	)
	(segment
		(start 212.593682 -117.748812)
		(end 211.772754 -117.748812)
		(width 0.10668)
		(layer "F.Cu")
		(net "FM_APML_MUX2_SEL_R")
	)
	(via
		(at 211.772754 -117.748812)
		(size 0.508)
		(drill 0.254)
		(layers "F.Cu" "B.Cu")
		(net "FM_APML_MUX2_SEL_R")
	)
	(via
		(at 187.911994 -109.463078)
		(size 0.4572)
		(drill 0.254)
		(layers "F.Cu" "B.Cu")
		(net "FM_APML_MUX2_SEL_R")
	)
	(segment
		(start 193.60896 -112.26292)
		(end 187.71362 -112.26292)
		(width 0.11684)
		(layer "In2.Cu")
		(net "FM_APML_MUX2_SEL_R")
	)
	(segment
		(start 211.217002 -117.19306)
		(end 209.84972 -117.19306)
		(width 0.11684)
		(layer "In2.Cu")
		(net "FM_APML_MUX2_SEL_R")
	)
	(segment
		(start 209.01406 -115.44046)
		(end 208.33842 -114.76482)
		(width 0.11684)
		(layer "In2.Cu")
		(net "FM_APML_MUX2_SEL_R")
	)
	(segment
		(start 203.5937 -114.76482)
		(end 202.93076 -114.10188)
		(width 0.11684)
		(layer "In2.Cu")
		(net "FM_APML_MUX2_SEL_R")
	)
	(segment
		(start 209.01406 -116.3574)
		(end 209.01406 -115.44046)
		(width 0.11684)
		(layer "In2.Cu")
		(net "FM_APML_MUX2_SEL_R")
	)
	(segment
		(start 202.93076 -114.10188)
		(end 201.69632 -114.10188)
		(width 0.11684)
		(layer "In2.Cu")
		(net "FM_APML_MUX2_SEL_R")
	)
	(segment
		(start 208.33842 -114.76482)
		(end 203.5937 -114.76482)
		(width 0.11684)
		(layer "In2.Cu")
		(net "FM_APML_MUX2_SEL_R")
	)
	(segment
		(start 187.511944 -112.061244)
		(end 187.511944 -109.863128)
		(width 0.11684)
		(layer "In2.Cu")
		(net "FM_APML_MUX2_SEL_R")
	)
	(segment
		(start 195.182236 -113.074196)
		(end 194.59194 -112.4839)
		(width 0.11684)
		(layer "In2.Cu")
		(net "FM_APML_MUX2_SEL_R")
	)
	(segment
		(start 209.84972 -117.19306)
		(end 209.01406 -116.3574)
		(width 0.11684)
		(layer "In2.Cu")
		(net "FM_APML_MUX2_SEL_R")
	)
	(segment
		(start 201.69632 -114.10188)
		(end 200.668636 -113.074196)
		(width 0.11684)
		(layer "In2.Cu")
		(net "FM_APML_MUX2_SEL_R")
	)
	(segment
		(start 187.511944 -109.863128)
		(end 187.911994 -109.463078)
		(width 0.11684)
		(layer "In2.Cu")
		(net "FM_APML_MUX2_SEL_R")
	)
	(segment
		(start 194.59194 -112.4839)
		(end 193.82994 -112.4839)
		(width 0.11684)
		(layer "In2.Cu")
		(net "FM_APML_MUX2_SEL_R")
	)
	(segment
		(start 193.82994 -112.4839)
		(end 193.60896 -112.26292)
		(width 0.11684)
		(layer "In2.Cu")
		(net "FM_APML_MUX2_SEL_R")
	)
	(segment
		(start 211.772754 -117.748812)
		(end 211.217002 -117.19306)
		(width 0.11684)
		(layer "In2.Cu")
		(net "FM_APML_MUX2_SEL_R")
	)
	(segment
		(start 200.668636 -113.074196)
		(end 195.182236 -113.074196)
		(width 0.11684)
		(layer "In2.Cu")
		(net "FM_APML_MUX2_SEL_R")
	)
	(segment
		(start 187.71362 -112.26292)
		(end 187.511944 -112.061244)
		(width 0.11684)
		(layer "In2.Cu")
		(net "FM_APML_MUX2_SEL_R")
	)
	(segment
		(start 213.393782 -117.748812)
		(end 213.393782 -118.609618)
		(width 0.10668)
		(layer "F.Cu")
		(net "FM_APML_MUX2_SEL")
	)
	(segment
		(start 230.430578 -169.582084)
		(end 230.430578 -183.983376)
		(width 0.10668)
		(layer "F.Cu")
		(net "FM_APML_MUX2_SEL")
	)
	(segment
		(start 213.393782 -118.609618)
		(end 213.1568 -118.8466)
		(width 0.10668)
		(layer "F.Cu")
		(net "FM_APML_MUX2_SEL")
	)
	(segment
		(start 213.393782 -116.732812)
		(end 213.393782 -115.716812)
		(width 0.10668)
		(layer "F.Cu")
		(net "FM_APML_MUX2_SEL")
	)
	(segment
		(start 213.393782 -116.732812)
		(end 213.393782 -117.748812)
		(width 0.10668)
		(layer "F.Cu")
		(net "FM_APML_MUX2_SEL")
	)
	(segment
		(start 229.75189 -184.662064)
		(end 229.75189 -189.138306)
		(width 0.10668)
		(layer "F.Cu")
		(net "FM_APML_MUX2_SEL")
	)
	(segment
		(start 230.430578 -183.983376)
		(end 229.75189 -184.662064)
		(width 0.10668)
		(layer "F.Cu")
		(net "FM_APML_MUX2_SEL")
	)
	(via
		(at 230.430578 -169.582084)
		(size 0.508)
		(drill 0.254)
		(layers "F.Cu" "B.Cu")
		(net "FM_APML_MUX2_SEL")
	)
	(via
		(at 230.886 -249.428)
		(size 0.508)
		(drill 0.254)
		(layers "F.Cu" "B.Cu")
		(net "FM_APML_MUX2_SEL")
	)
	(via
		(at 213.1568 -118.8466)
		(size 0.508)
		(drill 0.254)
		(layers "F.Cu" "B.Cu")
		(net "FM_APML_MUX2_SEL")
	)
	(via
		(at 229.75189 -189.138306)
		(size 0.508)
		(drill 0.254)
		(layers "F.Cu" "B.Cu")
		(net "FM_APML_MUX2_SEL")
	)
	(segment
		(start 232.217722 -249.282712)
		(end 231.850692 -249.282712)
		(width 0.10668)
		(layer "B.Cu")
		(net "FM_APML_MUX2_SEL")
	)
	(segment
		(start 231.705404 -249.428)
		(end 230.886 -249.428)
		(width 0.10668)
		(layer "B.Cu")
		(net "FM_APML_MUX2_SEL")
	)
	(segment
		(start 231.850692 -249.282712)
		(end 231.705404 -249.428)
		(width 0.10668)
		(layer "B.Cu")
		(net "FM_APML_MUX2_SEL")
	)
	(segment
		(start 230.467408 -190.59906)
		(end 230.47452 -190.59906)
		(width 0.11684)
		(layer "In2.Cu")
		(net "FM_APML_MUX2_SEL")
	)
	(segment
		(start 230.147622 -248.223278)
		(end 230.147622 -248.689622)
		(width 0.11684)
		(layer "In2.Cu")
		(net "FM_APML_MUX2_SEL")
	)
	(segment
		(start 230.47452 -190.59906)
		(end 230.59136 -190.7159)
		(width 0.11684)
		(layer "In2.Cu")
		(net "FM_APML_MUX2_SEL")
	)
	(segment
		(start 229.75189 -189.883542)
		(end 230.467408 -190.59906)
		(width 0.11684)
		(layer "In2.Cu")
		(net "FM_APML_MUX2_SEL")
	)
	(segment
		(start 231.7496 -209.004408)
		(end 224.604326 -216.149682)
		(width 0.11684)
		(layer "In2.Cu")
		(net "FM_APML_MUX2_SEL")
	)
	(segment
		(start 230.147622 -248.689622)
		(end 230.886 -249.428)
		(width 0.11684)
		(layer "In2.Cu")
		(net "FM_APML_MUX2_SEL")
	)
	(segment
		(start 224.604326 -242.679982)
		(end 230.147622 -248.223278)
		(width 0.11684)
		(layer "In2.Cu")
		(net "FM_APML_MUX2_SEL")
	)
	(segment
		(start 230.59136 -204.53858)
		(end 231.7496 -205.69682)
		(width 0.11684)
		(layer "In2.Cu")
		(net "FM_APML_MUX2_SEL")
	)
	(segment
		(start 231.7496 -205.69682)
		(end 231.7496 -209.004408)
		(width 0.11684)
		(layer "In2.Cu")
		(net "FM_APML_MUX2_SEL")
	)
	(segment
		(start 230.59136 -190.7159)
		(end 230.59136 -204.53858)
		(width 0.11684)
		(layer "In2.Cu")
		(net "FM_APML_MUX2_SEL")
	)
	(segment
		(start 229.75189 -189.138306)
		(end 229.75189 -189.883542)
		(width 0.11684)
		(layer "In2.Cu")
		(net "FM_APML_MUX2_SEL")
	)
	(segment
		(start 224.604326 -216.149682)
		(end 224.604326 -242.679982)
		(width 0.11684)
		(layer "In2.Cu")
		(net "FM_APML_MUX2_SEL")
	)
	(segment
		(start 217.623136 -168.63822)
		(end 209.66938 -160.684464)
		(width 0.11684)
		(layer "In11.Cu")
		(net "FM_APML_MUX2_SEL")
	)
	(segment
		(start 230.430578 -169.582084)
		(end 229.486714 -168.63822)
		(width 0.11684)
		(layer "In11.Cu")
		(net "FM_APML_MUX2_SEL")
	)
	(segment
		(start 209.66938 -160.684464)
		(end 209.66938 -155.67152)
		(width 0.11684)
		(layer "In11.Cu")
		(net "FM_APML_MUX2_SEL")
	)
	(segment
		(start 211.515452 -125.300994)
		(end 211.515452 -120.487948)
		(width 0.11684)
		(layer "In11.Cu")
		(net "FM_APML_MUX2_SEL")
	)
	(segment
		(start 208.482692 -128.333754)
		(end 211.515452 -125.300994)
		(width 0.11684)
		(layer "In11.Cu")
		(net "FM_APML_MUX2_SEL")
	)
	(segment
		(start 211.515452 -120.487948)
		(end 213.1568 -118.8466)
		(width 0.11684)
		(layer "In11.Cu")
		(net "FM_APML_MUX2_SEL")
	)
	(segment
		(start 229.486714 -168.63822)
		(end 217.623136 -168.63822)
		(width 0.11684)
		(layer "In11.Cu")
		(net "FM_APML_MUX2_SEL")
	)
	(segment
		(start 208.482692 -131.899406)
		(end 208.482692 -128.333754)
		(width 0.11684)
		(layer "In11.Cu")
		(net "FM_APML_MUX2_SEL")
	)
	(segment
		(start 207.76692 -132.615178)
		(end 208.482692 -131.899406)
		(width 0.11684)
		(layer "In11.Cu")
		(net "FM_APML_MUX2_SEL")
	)
	(segment
		(start 203.634848 -140.35786)
		(end 207.76692 -136.225788)
		(width 0.11684)
		(layer "In11.Cu")
		(net "FM_APML_MUX2_SEL")
	)
	(segment
		(start 203.634848 -149.636988)
		(end 203.634848 -140.35786)
		(width 0.11684)
		(layer "In11.Cu")
		(net "FM_APML_MUX2_SEL")
	)
	(segment
		(start 207.76692 -136.225788)
		(end 207.76692 -132.615178)
		(width 0.11684)
		(layer "In11.Cu")
		(net "FM_APML_MUX2_SEL")
	)
	(segment
		(start 209.66938 -155.67152)
		(end 203.634848 -149.636988)
		(width 0.11684)
		(layer "In11.Cu")
		(net "FM_APML_MUX2_SEL")
	)
	(segment
		(start 212.593682 -112.662208)
		(end 212.076792 -112.662208)
		(width 0.10668)
		(layer "F.Cu")
		(net "FM_APML_MUX2_OE_R_N")
	)
	(segment
		(start 187.522104 -110.652814)
		(end 187.911994 -110.262924)
		(width 0.10668)
		(layer "F.Cu")
		(net "FM_APML_MUX2_OE_R_N")
	)
	(segment
		(start 212.076792 -112.662208)
		(end 211.7852 -112.9538)
		(width 0.10668)
		(layer "F.Cu")
		(net "FM_APML_MUX2_OE_R_N")
	)
	(via
		(at 187.911994 -110.262924)
		(size 0.4572)
		(drill 0.254)
		(layers "F.Cu" "B.Cu")
		(net "FM_APML_MUX2_OE_R_N")
	)
	(via
		(at 211.7852 -112.9538)
		(size 0.508)
		(drill 0.254)
		(layers "F.Cu" "B.Cu")
		(net "FM_APML_MUX2_OE_R_N")
	)
	(segment
		(start 201.336148 -112.101376)
		(end 200.732136 -111.497364)
		(width 0.11684)
		(layer "In2.Cu")
		(net "FM_APML_MUX2_OE_R_N")
	)
	(segment
		(start 193.373248 -110.674404)
		(end 188.323474 -110.674404)
		(width 0.11684)
		(layer "In2.Cu")
		(net "FM_APML_MUX2_OE_R_N")
	)
	(segment
		(start 197.521576 -111.497364)
		(end 197.11543 -111.90351)
		(width 0.11684)
		(layer "In2.Cu")
		(net "FM_APML_MUX2_OE_R_N")
	)
	(segment
		(start 200.732136 -111.497364)
		(end 197.521576 -111.497364)
		(width 0.11684)
		(layer "In2.Cu")
		(net "FM_APML_MUX2_OE_R_N")
	)
	(segment
		(start 207.83296 -113.12906)
		(end 203.679552 -113.12906)
		(width 0.11684)
		(layer "In2.Cu")
		(net "FM_APML_MUX2_OE_R_N")
	)
	(segment
		(start 208.82864 -112.13338)
		(end 207.83296 -113.12906)
		(width 0.11684)
		(layer "In2.Cu")
		(net "FM_APML_MUX2_OE_R_N")
	)
	(segment
		(start 203.679552 -113.12906)
		(end 202.651868 -112.101376)
		(width 0.11684)
		(layer "In2.Cu")
		(net "FM_APML_MUX2_OE_R_N")
	)
	(segment
		(start 194.602354 -111.90351)
		(end 193.373248 -110.674404)
		(width 0.11684)
		(layer "In2.Cu")
		(net "FM_APML_MUX2_OE_R_N")
	)
	(segment
		(start 202.651868 -112.101376)
		(end 201.336148 -112.101376)
		(width 0.11684)
		(layer "In2.Cu")
		(net "FM_APML_MUX2_OE_R_N")
	)
	(segment
		(start 210.96478 -112.13338)
		(end 208.82864 -112.13338)
		(width 0.11684)
		(layer "In2.Cu")
		(net "FM_APML_MUX2_OE_R_N")
	)
	(segment
		(start 211.7852 -112.9538)
		(end 210.96478 -112.13338)
		(width 0.11684)
		(layer "In2.Cu")
		(net "FM_APML_MUX2_OE_R_N")
	)
	(segment
		(start 197.11543 -111.90351)
		(end 194.602354 -111.90351)
		(width 0.11684)
		(layer "In2.Cu")
		(net "FM_APML_MUX2_OE_R_N")
	)
	(segment
		(start 188.323474 -110.674404)
		(end 187.911994 -110.262924)
		(width 0.11684)
		(layer "In2.Cu")
		(net "FM_APML_MUX2_OE_R_N")
	)
	(segment
		(start 213.393782 -111.646208)
		(end 213.393782 -110.630208)
		(width 0.10668)
		(layer "F.Cu")
		(net "FM_APML_MUX2_OE_N")
	)
	(segment
		(start 213.393782 -111.646208)
		(end 213.393782 -112.662208)
		(width 0.10668)
		(layer "F.Cu")
		(net "FM_APML_MUX2_OE_N")
	)
	(segment
		(start 230.96728 -183.882538)
		(end 230.21163 -184.638188)
		(width 0.10668)
		(layer "F.Cu")
		(net "FM_APML_MUX2_OE_N")
	)
	(segment
		(start 213.393782 -112.662208)
		(end 213.778592 -112.662208)
		(width 0.10668)
		(layer "F.Cu")
		(net "FM_APML_MUX2_OE_N")
	)
	(segment
		(start 230.96728 -168.63822)
		(end 230.96728 -183.882538)
		(width 0.10668)
		(layer "F.Cu")
		(net "FM_APML_MUX2_OE_N")
	)
	(segment
		(start 230.21163 -184.638188)
		(end 230.21163 -188.573156)
		(width 0.10668)
		(layer "F.Cu")
		(net "FM_APML_MUX2_OE_N")
	)
	(segment
		(start 213.778592 -112.662208)
		(end 214.6554 -111.7854)
		(width 0.10668)
		(layer "F.Cu")
		(net "FM_APML_MUX2_OE_N")
	)
	(via
		(at 230.96728 -168.63822)
		(size 0.508)
		(drill 0.254)
		(layers "F.Cu" "B.Cu")
		(net "FM_APML_MUX2_OE_N")
	)
	(via
		(at 230.886 -247.396)
		(size 0.508)
		(drill 0.254)
		(layers "F.Cu" "B.Cu")
		(net "FM_APML_MUX2_OE_N")
	)
	(via
		(at 214.6554 -111.7854)
		(size 0.508)
		(drill 0.254)
		(layers "F.Cu" "B.Cu")
		(net "FM_APML_MUX2_OE_N")
	)
	(via
		(at 230.21163 -188.573156)
		(size 0.508)
		(drill 0.254)
		(layers "F.Cu" "B.Cu")
		(net "FM_APML_MUX2_OE_N")
	)
	(segment
		(start 232.217722 -247.782588)
		(end 231.780588 -247.782588)
		(width 0.10668)
		(layer "B.Cu")
		(net "FM_APML_MUX2_OE_N")
	)
	(segment
		(start 231.394 -247.396)
		(end 230.886 -247.396)
		(width 0.10668)
		(layer "B.Cu")
		(net "FM_APML_MUX2_OE_N")
	)
	(segment
		(start 231.780588 -247.782588)
		(end 231.394 -247.396)
		(width 0.10668)
		(layer "B.Cu")
		(net "FM_APML_MUX2_OE_N")
	)
	(segment
		(start 230.759 -247.269)
		(end 229.645972 -247.269)
		(width 0.11684)
		(layer "In2.Cu")
		(net "FM_APML_MUX2_OE_N")
	)
	(segment
		(start 224.924366 -216.28227)
		(end 232.06964 -209.136996)
		(width 0.11684)
		(layer "In2.Cu")
		(net "FM_APML_MUX2_OE_N")
	)
	(segment
		(start 232.06964 -205.564232)
		(end 230.9114 -204.405992)
		(width 0.11684)
		(layer "In2.Cu")
		(net "FM_APML_MUX2_OE_N")
	)
	(segment
		(start 230.9114 -189.769242)
		(end 230.21163 -189.069472)
		(width 0.11684)
		(layer "In2.Cu")
		(net "FM_APML_MUX2_OE_N")
	)
	(segment
		(start 229.645972 -247.269)
		(end 224.924366 -242.547394)
		(width 0.11684)
		(layer "In2.Cu")
		(net "FM_APML_MUX2_OE_N")
	)
	(segment
		(start 232.06964 -209.136996)
		(end 232.06964 -205.564232)
		(width 0.11684)
		(layer "In2.Cu")
		(net "FM_APML_MUX2_OE_N")
	)
	(segment
		(start 230.886 -247.396)
		(end 230.759 -247.269)
		(width 0.11684)
		(layer "In2.Cu")
		(net "FM_APML_MUX2_OE_N")
	)
	(segment
		(start 230.21163 -189.069472)
		(end 230.21163 -188.573156)
		(width 0.11684)
		(layer "In2.Cu")
		(net "FM_APML_MUX2_OE_N")
	)
	(segment
		(start 230.9114 -204.405992)
		(end 230.9114 -189.769242)
		(width 0.11684)
		(layer "In2.Cu")
		(net "FM_APML_MUX2_OE_N")
	)
	(segment
		(start 224.924366 -242.547394)
		(end 224.924366 -216.28227)
		(width 0.11684)
		(layer "In2.Cu")
		(net "FM_APML_MUX2_OE_N")
	)
	(segment
		(start 203.954888 -140.490448)
		(end 208.08696 -136.358376)
		(width 0.11684)
		(layer "In11.Cu")
		(net "FM_APML_MUX2_OE_N")
	)
	(segment
		(start 230.50246 -168.1734)
		(end 217.615008 -168.1734)
		(width 0.11684)
		(layer "In11.Cu")
		(net "FM_APML_MUX2_OE_N")
	)
	(segment
		(start 217.615008 -168.1734)
		(end 209.98942 -160.547812)
		(width 0.11684)
		(layer "In11.Cu")
		(net "FM_APML_MUX2_OE_N")
	)
	(segment
		(start 203.954888 -149.5044)
		(end 203.954888 -140.490448)
		(width 0.11684)
		(layer "In11.Cu")
		(net "FM_APML_MUX2_OE_N")
	)
	(segment
		(start 230.96728 -168.63822)
		(end 230.50246 -168.1734)
		(width 0.11684)
		(layer "In11.Cu")
		(net "FM_APML_MUX2_OE_N")
	)
	(segment
		(start 212.134704 -125.993144)
		(end 213.6521 -124.475748)
		(width 0.11684)
		(layer "In11.Cu")
		(net "FM_APML_MUX2_OE_N")
	)
	(segment
		(start 213.6521 -124.475748)
		(end 213.6521 -118.324122)
		(width 0.11684)
		(layer "In11.Cu")
		(net "FM_APML_MUX2_OE_N")
	)
	(segment
		(start 208.887568 -132.007356)
		(end 208.887568 -130.530092)
		(width 0.11684)
		(layer "In11.Cu")
		(net "FM_APML_MUX2_OE_N")
	)
	(segment
		(start 210.431634 -128.986026)
		(end 211.256626 -128.986026)
		(width 0.11684)
		(layer "In11.Cu")
		(net "FM_APML_MUX2_OE_N")
	)
	(segment
		(start 213.6521 -118.324122)
		(end 212.76945 -117.441472)
		(width 0.11684)
		(layer "In11.Cu")
		(net "FM_APML_MUX2_OE_N")
	)
	(segment
		(start 212.76945 -117.441472)
		(end 212.76945 -113.67135)
		(width 0.11684)
		(layer "In11.Cu")
		(net "FM_APML_MUX2_OE_N")
	)
	(segment
		(start 208.887568 -130.530092)
		(end 210.431634 -128.986026)
		(width 0.11684)
		(layer "In11.Cu")
		(net "FM_APML_MUX2_OE_N")
	)
	(segment
		(start 208.08696 -132.807964)
		(end 208.887568 -132.007356)
		(width 0.11684)
		(layer "In11.Cu")
		(net "FM_APML_MUX2_OE_N")
	)
	(segment
		(start 212.134704 -128.107948)
		(end 212.134704 -125.993144)
		(width 0.11684)
		(layer "In11.Cu")
		(net "FM_APML_MUX2_OE_N")
	)
	(segment
		(start 208.08696 -136.358376)
		(end 208.08696 -132.807964)
		(width 0.11684)
		(layer "In11.Cu")
		(net "FM_APML_MUX2_OE_N")
	)
	(segment
		(start 211.256626 -128.986026)
		(end 212.134704 -128.107948)
		(width 0.11684)
		(layer "In11.Cu")
		(net "FM_APML_MUX2_OE_N")
	)
	(segment
		(start 212.76945 -113.67135)
		(end 214.6554 -111.7854)
		(width 0.11684)
		(layer "In11.Cu")
		(net "FM_APML_MUX2_OE_N")
	)
	(segment
		(start 209.98942 -160.547812)
		(end 209.98942 -155.538932)
		(width 0.11684)
		(layer "In11.Cu")
		(net "FM_APML_MUX2_OE_N")
	)
	(segment
		(start 209.98942 -155.538932)
		(end 203.954888 -149.5044)
		(width 0.11684)
		(layer "In11.Cu")
		(net "FM_APML_MUX2_OE_N")
	)
	(segment
		(start 302.641508 -109.779308)
		(end 303.841658 -109.779308)
		(width 0.10668)
		(layer "F.Cu")
		(net "CPU_FRU_ADDR2")
	)
	(segment
		(start 302.641508 -110.795308)
		(end 302.641508 -109.779308)
		(width 0.10668)
		(layer "F.Cu")
		(net "CPU_FRU_ADDR2")
	)
	(segment
		(start 306.116228 -110.96625)
		(end 305.0286 -110.96625)
		(width 0.10668)
		(layer "F.Cu")
		(net "CPU_FRU_ADDR2")
	)
	(segment
		(start 305.0286 -110.96625)
		(end 303.841658 -109.779308)
		(width 0.10668)
		(layer "F.Cu")
		(net "CPU_FRU_ADDR2")
	)
	(via
		(at 303.841658 -109.779308)
		(size 0.762)
		(drill 0.381)
		(layers "F.Cu" "B.Cu")
		(net "CPU_FRU_ADDR2")
	)
	(segment
		(start 302.641508 -111.811308)
		(end 302.641508 -112.827308)
		(width 0.10668)
		(layer "F.Cu")
		(net "CPU_FRU_ADDR1")
	)
	(segment
		(start 303.841658 -111.811308)
		(end 302.641508 -111.811308)
		(width 0.10668)
		(layer "F.Cu")
		(net "CPU_FRU_ADDR1")
	)
	(segment
		(start 306.116228 -112.23625)
		(end 304.2666 -112.23625)
		(width 0.10668)
		(layer "F.Cu")
		(net "CPU_FRU_ADDR1")
	)
	(segment
		(start 304.2666 -112.23625)
		(end 303.841658 -111.811308)
		(width 0.10668)
		(layer "F.Cu")
		(net "CPU_FRU_ADDR1")
	)
	(via
		(at 303.841658 -111.811308)
		(size 0.762)
		(drill 0.381)
		(layers "F.Cu" "B.Cu")
		(net "CPU_FRU_ADDR1")
	)
	(segment
		(start 302.641508 -113.843308)
		(end 302.641508 -114.859308)
		(width 0.10668)
		(layer "F.Cu")
		(net "CPU_FRU_ADDR0")
	)
	(segment
		(start 303.841658 -113.843308)
		(end 302.641508 -113.843308)
		(width 0.10668)
		(layer "F.Cu")
		(net "CPU_FRU_ADDR0")
	)
	(segment
		(start 306.116228 -113.50625)
		(end 304.178716 -113.50625)
		(width 0.10668)
		(layer "F.Cu")
		(net "CPU_FRU_ADDR0")
	)
	(segment
		(start 304.178716 -113.50625)
		(end 303.841658 -113.843308)
		(width 0.10668)
		(layer "F.Cu")
		(net "CPU_FRU_ADDR0")
	)
	(via
		(at 303.841658 -113.843308)
		(size 0.762)
		(drill 0.381)
		(layers "F.Cu" "B.Cu")
		(net "CPU_FRU_ADDR0")
	)
	(segment
		(start 105.734104 -25.183592)
		(end 105.734104 -26.351992)
		(width 0.10668)
		(layer "F.Cu")
		(net "XTAL_USB_CPU0_HUB2_XOUT")
	)
	(segment
		(start 106.863642 -28.935172)
		(end 105.835704 -26.453592)
		(width 0.10668)
		(layer "F.Cu")
		(net "XTAL_USB_CPU0_HUB2_XOUT")
	)
	(segment
		(start 104.535224 -24.261064)
		(end 104.81564 -24.54148)
		(width 0.10668)
		(layer "F.Cu")
		(net "XTAL_USB_CPU0_HUB2_XOUT")
	)
	(segment
		(start 105.58272 -24.54148)
		(end 105.734104 -24.692864)
		(width 0.10668)
		(layer "F.Cu")
		(net "XTAL_USB_CPU0_HUB2_XOUT")
	)
	(segment
		(start 107.176316 -29.247846)
		(end 106.863642 -28.935172)
		(width 0.10668)
		(layer "F.Cu")
		(net "XTAL_USB_CPU0_HUB2_XOUT")
	)
	(segment
		(start 104.641904 -23.371556)
		(end 104.535224 -23.478236)
		(width 0.10668)
		(layer "F.Cu")
		(net "XTAL_USB_CPU0_HUB2_XOUT")
	)
	(segment
		(start 105.1814 -24.54148)
		(end 105.58272 -24.54148)
		(width 0.10668)
		(layer "F.Cu")
		(net "XTAL_USB_CPU0_HUB2_XOUT")
	)
	(segment
		(start 105.734104 -24.692864)
		(end 105.734104 -25.183592)
		(width 0.10668)
		(layer "F.Cu")
		(net "XTAL_USB_CPU0_HUB2_XOUT")
	)
	(segment
		(start 104.535224 -23.478236)
		(end 104.535224 -24.261064)
		(width 0.10668)
		(layer "F.Cu")
		(net "XTAL_USB_CPU0_HUB2_XOUT")
	)
	(segment
		(start 105.734104 -26.351992)
		(end 105.835704 -26.453592)
		(width 0.10668)
		(layer "F.Cu")
		(net "XTAL_USB_CPU0_HUB2_XOUT")
	)
	(segment
		(start 108.398818 -29.247846)
		(end 107.176316 -29.247846)
		(width 0.10668)
		(layer "F.Cu")
		(net "XTAL_USB_CPU0_HUB2_XOUT")
	)
	(segment
		(start 104.81564 -24.54148)
		(end 105.1814 -24.54148)
		(width 0.10668)
		(layer "F.Cu")
		(net "XTAL_USB_CPU0_HUB2_XOUT")
	)
	(segment
		(start 105.400602 -23.371556)
		(end 104.641904 -23.371556)
		(width 0.10668)
		(layer "F.Cu")
		(net "XTAL_USB_CPU0_HUB2_XOUT")
	)
	(via
		(at 105.1814 -24.54148)
		(size 0.508)
		(drill 0.254)
		(layers "F.Cu" "B.Cu")
		(net "XTAL_USB_CPU0_HUB2_XOUT")
	)
	(segment
		(start 106.6546 -24.54148)
		(end 106.737404 -24.624284)
		(width 0.10668)
		(layer "F.Cu")
		(net "XTAL_USB_CPU0_HUB2_XIN")
	)
	(segment
		(start 106.635804 -25.285192)
		(end 106.635804 -26.453592)
		(width 0.10668)
		(layer "F.Cu")
		(net "XTAL_USB_CPU0_HUB2_XIN")
	)
	(segment
		(start 106.737404 -25.183592)
		(end 106.635804 -25.285192)
		(width 0.10668)
		(layer "F.Cu")
		(net "XTAL_USB_CPU0_HUB2_XIN")
	)
	(segment
		(start 108.398818 -28.74772)
		(end 107.57662 -28.74772)
		(width 0.10668)
		(layer "F.Cu")
		(net "XTAL_USB_CPU0_HUB2_XIN")
	)
	(segment
		(start 107.336844 -28.507944)
		(end 106.635804 -26.815542)
		(width 0.10668)
		(layer "F.Cu")
		(net "XTAL_USB_CPU0_HUB2_XIN")
	)
	(segment
		(start 106.737404 -24.624284)
		(end 106.737404 -25.183592)
		(width 0.10668)
		(layer "F.Cu")
		(net "XTAL_USB_CPU0_HUB2_XIN")
	)
	(segment
		(start 107.10037 -21.171408)
		(end 106.250486 -22.021292)
		(width 0.10668)
		(layer "F.Cu")
		(net "XTAL_USB_CPU0_HUB2_XIN")
	)
	(segment
		(start 106.635804 -26.815542)
		(end 106.635804 -26.453592)
		(width 0.10668)
		(layer "F.Cu")
		(net "XTAL_USB_CPU0_HUB2_XIN")
	)
	(segment
		(start 106.250486 -22.021292)
		(end 106.250486 -24.137366)
		(width 0.10668)
		(layer "F.Cu")
		(net "XTAL_USB_CPU0_HUB2_XIN")
	)
	(segment
		(start 106.250486 -24.137366)
		(end 106.6546 -24.54148)
		(width 0.10668)
		(layer "F.Cu")
		(net "XTAL_USB_CPU0_HUB2_XIN")
	)
	(segment
		(start 107.57662 -28.74772)
		(end 107.336844 -28.507944)
		(width 0.10668)
		(layer "F.Cu")
		(net "XTAL_USB_CPU0_HUB2_XIN")
	)
	(via
		(at 106.6546 -24.54148)
		(size 0.508)
		(drill 0.254)
		(layers "F.Cu" "B.Cu")
		(net "XTAL_USB_CPU0_HUB2_XIN")
	)
	(segment
		(start 117.653816 -33.247838)
		(end 118.218458 -32.683196)
		(width 0.10668)
		(layer "F.Cu")
		(net "USB_HUB2_TI_VDD_MRP_USB3DN_TXDP4")
	)
	(segment
		(start 117.198902 -33.247838)
		(end 117.653816 -33.247838)
		(width 0.10668)
		(layer "F.Cu")
		(net "USB_HUB2_TI_VDD_MRP_USB3DN_TXDP4")
	)
	(segment
		(start 118.518686 -31.560262)
		(end 118.53672 -31.560262)
		(width 0.10668)
		(layer "F.Cu")
		(net "USB_HUB2_TI_VDD_MRP_USB3DN_TXDP4")
	)
	(segment
		(start 118.218458 -32.683196)
		(end 118.218458 -31.86049)
		(width 0.10668)
		(layer "F.Cu")
		(net "USB_HUB2_TI_VDD_MRP_USB3DN_TXDP4")
	)
	(segment
		(start 118.218458 -31.86049)
		(end 118.518686 -31.560262)
		(width 0.10668)
		(layer "F.Cu")
		(net "USB_HUB2_TI_VDD_MRP_USB3DN_TXDP4")
	)
	(segment
		(start 120.29821 -29.46019)
		(end 118.53672 -31.22168)
		(width 0.10668)
		(layer "F.Cu")
		(net "USB_HUB2_TI_VDD_MRP_USB3DN_TXDP4")
	)
	(segment
		(start 120.29821 -29.373576)
		(end 120.29821 -29.46019)
		(width 0.10668)
		(layer "F.Cu")
		(net "USB_HUB2_TI_VDD_MRP_USB3DN_TXDP4")
	)
	(segment
		(start 118.53672 -31.22168)
		(end 118.53672 -31.560262)
		(width 0.10668)
		(layer "F.Cu")
		(net "USB_HUB2_TI_VDD_MRP_USB3DN_TXDP4")
	)
	(via
		(at 118.53672 -31.560262)
		(size 0.762)
		(drill 0.381)
		(layers "F.Cu" "B.Cu")
		(net "USB_HUB2_TI_VDD_MRP_USB3DN_TXDP4")
	)
	(segment
		(start 120.2817 -26.815796)
		(end 120.2817 -27.129486)
		(width 0.10668)
		(layer "F.Cu")
		(net "USB_HUB2_TI_VDD_MRP_USB3DN_TXDP3")
	)
	(segment
		(start 120.2817 -27.129486)
		(end 118.960392 -28.450794)
		(width 0.10668)
		(layer "F.Cu")
		(net "USB_HUB2_TI_VDD_MRP_USB3DN_TXDP3")
	)
	(segment
		(start 117.198902 -29.747718)
		(end 117.470682 -29.747718)
		(width 0.10668)
		(layer "F.Cu")
		(net "USB_HUB2_TI_VDD_MRP_USB3DN_TXDP3")
	)
	(segment
		(start 117.470682 -29.747718)
		(end 118.767606 -28.450794)
		(width 0.10668)
		(layer "F.Cu")
		(net "USB_HUB2_TI_VDD_MRP_USB3DN_TXDP3")
	)
	(segment
		(start 118.767606 -28.450794)
		(end 118.960392 -28.450794)
		(width 0.10668)
		(layer "F.Cu")
		(net "USB_HUB2_TI_VDD_MRP_USB3DN_TXDP3")
	)
	(via
		(at 118.960392 -28.450794)
		(size 0.762)
		(drill 0.381)
		(layers "F.Cu" "B.Cu")
		(net "USB_HUB2_TI_VDD_MRP_USB3DN_TXDP3")
	)
	(segment
		(start 110.89894 -22.540214)
		(end 110.785148 -22.426422)
		(width 0.10668)
		(layer "F.Cu")
		(net "USB_HUB2_TI_VDD_MRP_USB3DN_TXDM1")
	)
	(segment
		(start 111.0488 -27.097736)
		(end 111.0488 -26.677874)
		(width 0.10668)
		(layer "F.Cu")
		(net "USB_HUB2_TI_VDD_MRP_USB3DN_TXDM1")
	)
	(segment
		(start 110.89894 -24.885142)
		(end 110.89894 -22.540214)
		(width 0.10668)
		(layer "F.Cu")
		(net "USB_HUB2_TI_VDD_MRP_USB3DN_TXDM1")
	)
	(segment
		(start 110.785148 -22.426422)
		(end 110.785148 -21.027644)
		(width 0.10668)
		(layer "F.Cu")
		(net "USB_HUB2_TI_VDD_MRP_USB3DN_TXDM1")
	)
	(segment
		(start 110.785148 -21.027644)
		(end 111.422942 -20.38985)
		(width 0.10668)
		(layer "F.Cu")
		(net "USB_HUB2_TI_VDD_MRP_USB3DN_TXDM1")
	)
	(segment
		(start 111.0488 -26.677874)
		(end 110.866428 -26.495502)
		(width 0.10668)
		(layer "F.Cu")
		(net "USB_HUB2_TI_VDD_MRP_USB3DN_TXDM1")
	)
	(segment
		(start 110.866428 -26.495502)
		(end 110.866428 -24.935688)
		(width 0.10668)
		(layer "F.Cu")
		(net "USB_HUB2_TI_VDD_MRP_USB3DN_TXDM1")
	)
	(segment
		(start 110.866428 -24.935688)
		(end 110.866428 -24.917654)
		(width 0.10668)
		(layer "F.Cu")
		(net "USB_HUB2_TI_VDD_MRP_USB3DN_TXDM1")
	)
	(segment
		(start 110.866428 -24.917654)
		(end 110.89894 -24.885142)
		(width 0.10668)
		(layer "F.Cu")
		(net "USB_HUB2_TI_VDD_MRP_USB3DN_TXDM1")
	)
	(via
		(at 110.866428 -24.935688)
		(size 0.762)
		(drill 0.381)
		(layers "F.Cu" "B.Cu")
		(net "USB_HUB2_TI_VDD_MRP_USB3DN_TXDM1")
	)
	(segment
		(start 120.053862 -31.405576)
		(end 119.13108 -32.328358)
		(width 0.10668)
		(layer "F.Cu")
		(net "USB_HUB2_TI_VDD_MRP_USB3DN_RXDP4")
	)
	(segment
		(start 120.29821 -31.405576)
		(end 120.053862 -31.405576)
		(width 0.10668)
		(layer "F.Cu")
		(net "USB_HUB2_TI_VDD_MRP_USB3DN_RXDP4")
	)
	(segment
		(start 119.13108 -32.328358)
		(end 119.13108 -34.43732)
		(width 0.10668)
		(layer "F.Cu")
		(net "USB_HUB2_TI_VDD_MRP_USB3DN_RXDP4")
	)
	(segment
		(start 118.212108 -34.747708)
		(end 118.5164 -35.052)
		(width 0.10668)
		(layer "F.Cu")
		(net "USB_HUB2_TI_VDD_MRP_USB3DN_RXDP4")
	)
	(segment
		(start 119.13108 -34.43732)
		(end 118.5164 -35.052)
		(width 0.10668)
		(layer "F.Cu")
		(net "USB_HUB2_TI_VDD_MRP_USB3DN_RXDP4")
	)
	(segment
		(start 117.198902 -34.747708)
		(end 118.212108 -34.747708)
		(width 0.10668)
		(layer "F.Cu")
		(net "USB_HUB2_TI_VDD_MRP_USB3DN_RXDP4")
	)
	(via
		(at 118.5164 -35.052)
		(size 0.762)
		(drill 0.381)
		(layers "F.Cu" "B.Cu")
		(net "USB_HUB2_TI_VDD_MRP_USB3DN_RXDP4")
	)
	(segment
		(start 111.807244 -23.81885)
		(end 111.807244 -23.720044)
		(width 0.10668)
		(layer "F.Cu")
		(net "USB_HUB2_TI_VDD_MRP_USB3DN_RXDM1")
	)
	(segment
		(start 112.438942 -22.16785)
		(end 111.807244 -22.799548)
		(width 0.10668)
		(layer "F.Cu")
		(net "USB_HUB2_TI_VDD_MRP_USB3DN_RXDM1")
	)
	(segment
		(start 112.548924 -26.417016)
		(end 112.885474 -26.080466)
		(width 0.10668)
		(layer "F.Cu")
		(net "USB_HUB2_TI_VDD_MRP_USB3DN_RXDM1")
	)
	(segment
		(start 112.885474 -26.080466)
		(end 112.885474 -24.89708)
		(width 0.10668)
		(layer "F.Cu")
		(net "USB_HUB2_TI_VDD_MRP_USB3DN_RXDM1")
	)
	(segment
		(start 112.885474 -24.89708)
		(end 111.807244 -23.81885)
		(width 0.10668)
		(layer "F.Cu")
		(net "USB_HUB2_TI_VDD_MRP_USB3DN_RXDM1")
	)
	(segment
		(start 112.548924 -27.097736)
		(end 112.548924 -26.417016)
		(width 0.10668)
		(layer "F.Cu")
		(net "USB_HUB2_TI_VDD_MRP_USB3DN_RXDM1")
	)
	(segment
		(start 111.807244 -22.799548)
		(end 111.807244 -23.720044)
		(width 0.10668)
		(layer "F.Cu")
		(net "USB_HUB2_TI_VDD_MRP_USB3DN_RXDM1")
	)
	(via
		(at 111.807244 -23.720044)
		(size 0.762)
		(drill 0.381)
		(layers "F.Cu" "B.Cu")
		(net "USB_HUB2_TI_VDD_MRP_USB3DN_RXDM1")
	)
	(segment
		(start 117.246908 -37.714936)
		(end 120.780302 -37.714936)
		(width 0.10668)
		(layer "F.Cu")
		(net "USB_HUB2_TI_VDD33_MRP_PRT_CTL4_GANGPWR")
	)
	(segment
		(start 124.459238 -40.7797)
		(end 123.443238 -40.7797)
		(width 0.10668)
		(layer "F.Cu")
		(net "USB_HUB2_TI_VDD33_MRP_PRT_CTL4_GANGPWR")
	)
	(segment
		(start 120.780302 -37.714936)
		(end 122.625866 -39.5605)
		(width 0.10668)
		(layer "F.Cu")
		(net "USB_HUB2_TI_VDD33_MRP_PRT_CTL4_GANGPWR")
	)
	(segment
		(start 116.04879 -36.516818)
		(end 117.246908 -37.714936)
		(width 0.10668)
		(layer "F.Cu")
		(net "USB_HUB2_TI_VDD33_MRP_PRT_CTL4_GANGPWR")
	)
	(segment
		(start 123.443238 -40.7797)
		(end 123.443238 -39.5605)
		(width 0.10668)
		(layer "F.Cu")
		(net "USB_HUB2_TI_VDD33_MRP_PRT_CTL4_GANGPWR")
	)
	(segment
		(start 122.625866 -39.5605)
		(end 123.443238 -39.5605)
		(width 0.10668)
		(layer "F.Cu")
		(net "USB_HUB2_TI_VDD33_MRP_PRT_CTL4_GANGPWR")
	)
	(segment
		(start 116.04879 -35.89782)
		(end 116.04879 -36.516818)
		(width 0.10668)
		(layer "F.Cu")
		(net "USB_HUB2_TI_VDD33_MRP_PRT_CTL4_GANGPWR")
	)
	(via
		(at 123.443238 -39.5605)
		(size 0.762)
		(drill 0.381)
		(layers "F.Cu" "B.Cu")
		(net "USB_HUB2_TI_VDD33_MRP_PRT_CTL4_GANGPWR")
	)
	(segment
		(start 119.927624 -23.005796)
		(end 119.6848 -23.24862)
		(width 0.10668)
		(layer "F.Cu")
		(net "USB_HUB2_TI_VDD33_MRP_PROG_FUNC7")
	)
	(segment
		(start 119.6848 -23.7236)
		(end 119.049546 -24.358854)
		(width 0.10668)
		(layer "F.Cu")
		(net "USB_HUB2_TI_VDD33_MRP_PROG_FUNC7")
	)
	(segment
		(start 119.049546 -24.358854)
		(end 118.464584 -24.358854)
		(width 0.10668)
		(layer "F.Cu")
		(net "USB_HUB2_TI_VDD33_MRP_PROG_FUNC7")
	)
	(segment
		(start 119.6848 -23.24862)
		(end 119.6848 -23.7236)
		(width 0.10668)
		(layer "F.Cu")
		(net "USB_HUB2_TI_VDD33_MRP_PROG_FUNC7")
	)
	(segment
		(start 116.548916 -26.795476)
		(end 118.223792 -25.1206)
		(width 0.10668)
		(layer "F.Cu")
		(net "USB_HUB2_TI_VDD33_MRP_PROG_FUNC7")
	)
	(segment
		(start 116.548916 -27.097736)
		(end 116.548916 -26.795476)
		(width 0.10668)
		(layer "F.Cu")
		(net "USB_HUB2_TI_VDD33_MRP_PROG_FUNC7")
	)
	(segment
		(start 120.2817 -23.005796)
		(end 119.927624 -23.005796)
		(width 0.10668)
		(layer "F.Cu")
		(net "USB_HUB2_TI_VDD33_MRP_PROG_FUNC7")
	)
	(segment
		(start 118.223792 -24.599646)
		(end 118.464584 -24.358854)
		(width 0.10668)
		(layer "F.Cu")
		(net "USB_HUB2_TI_VDD33_MRP_PROG_FUNC7")
	)
	(segment
		(start 118.223792 -25.1206)
		(end 118.223792 -24.599646)
		(width 0.10668)
		(layer "F.Cu")
		(net "USB_HUB2_TI_VDD33_MRP_PROG_FUNC7")
	)
	(via
		(at 118.464584 -24.358854)
		(size 0.762)
		(drill 0.381)
		(layers "F.Cu" "B.Cu")
		(net "USB_HUB2_TI_VDD33_MRP_PROG_FUNC7")
	)
	(segment
		(start 103.453946 -48.29937)
		(end 103.453946 -51.181)
		(width 0.10668)
		(layer "F.Cu")
		(net "USB_HUB2_TI_USB_VBUS_MRP_RESET_N")
	)
	(segment
		(start 109.048804 -36.198556)
		(end 106.278426 -38.968934)
		(width 0.10668)
		(layer "F.Cu")
		(net "USB_HUB2_TI_USB_VBUS_MRP_RESET_N")
	)
	(segment
		(start 109.048804 -35.89782)
		(end 109.048804 -36.198556)
		(width 0.10668)
		(layer "F.Cu")
		(net "USB_HUB2_TI_USB_VBUS_MRP_RESET_N")
	)
	(segment
		(start 106.278426 -38.968934)
		(end 106.278426 -45.47489)
		(width 0.10668)
		(layer "F.Cu")
		(net "USB_HUB2_TI_USB_VBUS_MRP_RESET_N")
	)
	(segment
		(start 103.453946 -51.181)
		(end 103.453946 -52.46243)
		(width 0.10668)
		(layer "F.Cu")
		(net "USB_HUB2_TI_USB_VBUS_MRP_RESET_N")
	)
	(segment
		(start 106.278426 -45.47489)
		(end 103.453946 -48.29937)
		(width 0.10668)
		(layer "F.Cu")
		(net "USB_HUB2_TI_USB_VBUS_MRP_RESET_N")
	)
	(segment
		(start 103.453946 -52.46243)
		(end 102.437946 -52.46243)
		(width 0.10668)
		(layer "F.Cu")
		(net "USB_HUB2_TI_USB_VBUS_MRP_RESET_N")
	)
	(via
		(at 103.453946 -51.181)
		(size 0.762)
		(drill 0.381)
		(layers "F.Cu" "B.Cu")
		(net "USB_HUB2_TI_USB_VBUS_MRP_RESET_N")
	)
	(segment
		(start 104.469946 -53.26253)
		(end 103.453946 -53.26253)
		(width 0.10668)
		(layer "F.Cu")
		(net "USB_HUB2_TI_USB_VBUS")
	)
	(segment
		(start 104.469946 -54.481984)
		(end 104.469946 -53.872384)
		(width 0.10668)
		(layer "F.Cu")
		(net "USB_HUB2_TI_USB_VBUS")
	)
	(segment
		(start 104.469946 -53.872384)
		(end 104.469946 -53.26253)
		(width 0.10668)
		(layer "F.Cu")
		(net "USB_HUB2_TI_USB_VBUS")
	)
	(via
		(at 104.469946 -53.872384)
		(size 0.508)
		(drill 0.254)
		(layers "F.Cu" "B.Cu")
		(net "USB_HUB2_TI_USB_VBUS")
	)
	(segment
		(start 112.324134 -25.82164)
		(end 112.324134 -25.636982)
		(width 0.10668)
		(layer "F.Cu")
		(net "USB_HUB2_TI_USB_SSRXP_DN1_MRP_VDD12")
	)
	(segment
		(start 112.324134 -25.636982)
		(end 112.324134 -25.167336)
		(width 0.10668)
		(layer "F.Cu")
		(net "USB_HUB2_TI_USB_SSRXP_DN1_MRP_VDD12")
	)
	(segment
		(start 111.548926 -26.596848)
		(end 112.324134 -25.82164)
		(width 0.10668)
		(layer "F.Cu")
		(net "USB_HUB2_TI_USB_SSRXP_DN1_MRP_VDD12")
	)
	(segment
		(start 111.14151 -22.449282)
		(end 111.422942 -22.16785)
		(width 0.10668)
		(layer "F.Cu")
		(net "USB_HUB2_TI_USB_SSRXP_DN1_MRP_VDD12")
	)
	(segment
		(start 111.548926 -27.097736)
		(end 111.548926 -26.596848)
		(width 0.10668)
		(layer "F.Cu")
		(net "USB_HUB2_TI_USB_SSRXP_DN1_MRP_VDD12")
	)
	(segment
		(start 112.324134 -25.167336)
		(end 111.14151 -23.984712)
		(width 0.10668)
		(layer "F.Cu")
		(net "USB_HUB2_TI_USB_SSRXP_DN1_MRP_VDD12")
	)
	(segment
		(start 111.14151 -23.984712)
		(end 111.14151 -22.449282)
		(width 0.10668)
		(layer "F.Cu")
		(net "USB_HUB2_TI_USB_SSRXP_DN1_MRP_VDD12")
	)
	(via
		(at 112.324134 -25.636982)
		(size 0.762)
		(drill 0.381)
		(layers "F.Cu" "B.Cu")
		(net "USB_HUB2_TI_USB_SSRXP_DN1_MRP_VDD12")
	)
	(segment
		(start 118.6561 -33.6423)
		(end 118.5164 -33.782)
		(width 0.10668)
		(layer "F.Cu")
		(net "USB_HUB2_TI_USB_SSRXM_DN4_MRP_VDD12")
	)
	(segment
		(start 120.29821 -30.389576)
		(end 120.29821 -30.691328)
		(width 0.10668)
		(layer "F.Cu")
		(net "USB_HUB2_TI_USB_SSRXM_DN4_MRP_VDD12")
	)
	(segment
		(start 120.29821 -30.691328)
		(end 118.6561 -32.333438)
		(width 0.10668)
		(layer "F.Cu")
		(net "USB_HUB2_TI_USB_SSRXM_DN4_MRP_VDD12")
	)
	(segment
		(start 117.198902 -34.247836)
		(end 118.050564 -34.247836)
		(width 0.10668)
		(layer "F.Cu")
		(net "USB_HUB2_TI_USB_SSRXM_DN4_MRP_VDD12")
	)
	(segment
		(start 118.050564 -34.247836)
		(end 118.5164 -33.782)
		(width 0.10668)
		(layer "F.Cu")
		(net "USB_HUB2_TI_USB_SSRXM_DN4_MRP_VDD12")
	)
	(segment
		(start 118.6561 -32.333438)
		(end 118.6561 -33.6423)
		(width 0.10668)
		(layer "F.Cu")
		(net "USB_HUB2_TI_USB_SSRXM_DN4_MRP_VDD12")
	)
	(via
		(at 118.5164 -33.782)
		(size 0.762)
		(drill 0.381)
		(layers "F.Cu" "B.Cu")
		(net "USB_HUB2_TI_USB_SSRXM_DN4_MRP_VDD12")
	)
	(segment
		(start 117.740684 -30.747716)
		(end 118.5164 -29.972)
		(width 0.10668)
		(layer "F.Cu")
		(net "USB_HUB2_TI_USB_SSRXM_DN3_MRP_VDD12")
	)
	(segment
		(start 120.2817 -28.085796)
		(end 119.793004 -28.085796)
		(width 0.10668)
		(layer "F.Cu")
		(net "USB_HUB2_TI_USB_SSRXM_DN3_MRP_VDD12")
	)
	(segment
		(start 119.618506 -28.869894)
		(end 118.5164 -29.972)
		(width 0.10668)
		(layer "F.Cu")
		(net "USB_HUB2_TI_USB_SSRXM_DN3_MRP_VDD12")
	)
	(segment
		(start 119.793004 -28.085796)
		(end 119.618506 -28.260294)
		(width 0.10668)
		(layer "F.Cu")
		(net "USB_HUB2_TI_USB_SSRXM_DN3_MRP_VDD12")
	)
	(segment
		(start 119.618506 -28.260294)
		(end 119.618506 -28.869894)
		(width 0.10668)
		(layer "F.Cu")
		(net "USB_HUB2_TI_USB_SSRXM_DN3_MRP_VDD12")
	)
	(segment
		(start 117.198902 -30.747716)
		(end 117.740684 -30.747716)
		(width 0.10668)
		(layer "F.Cu")
		(net "USB_HUB2_TI_USB_SSRXM_DN3_MRP_VDD12")
	)
	(via
		(at 118.5164 -29.972)
		(size 0.762)
		(drill 0.381)
		(layers "F.Cu" "B.Cu")
		(net "USB_HUB2_TI_USB_SSRXM_DN3_MRP_VDD12")
	)
	(segment
		(start 108.09732 -25.74036)
		(end 108.72089 -25.11679)
		(width 0.10668)
		(layer "F.Cu")
		(net "USB_HUB2_TI_USB_R1_MRP_RBIAS")
	)
	(segment
		(start 108.263436 -27.747722)
		(end 108.09732 -27.581606)
		(width 0.10668)
		(layer "F.Cu")
		(net "USB_HUB2_TI_USB_R1_MRP_RBIAS")
	)
	(segment
		(start 108.73359 -25.11679)
		(end 108.73359 -25.10409)
		(width 0.10668)
		(layer "F.Cu")
		(net "USB_HUB2_TI_USB_R1_MRP_RBIAS")
	)
	(segment
		(start 108.09732 -27.581606)
		(end 108.09732 -25.74036)
		(width 0.10668)
		(layer "F.Cu")
		(net "USB_HUB2_TI_USB_R1_MRP_RBIAS")
	)
	(segment
		(start 110.15599 -23.934928)
		(end 109.13999 -23.934928)
		(width 0.10668)
		(layer "F.Cu")
		(net "USB_HUB2_TI_USB_R1_MRP_RBIAS")
	)
	(segment
		(start 108.73359 -25.10409)
		(end 109.13999 -24.69769)
		(width 0.10668)
		(layer "F.Cu")
		(net "USB_HUB2_TI_USB_R1_MRP_RBIAS")
	)
	(segment
		(start 109.13999 -24.69769)
		(end 109.13999 -23.934928)
		(width 0.10668)
		(layer "F.Cu")
		(net "USB_HUB2_TI_USB_R1_MRP_RBIAS")
	)
	(segment
		(start 108.398818 -27.747722)
		(end 108.263436 -27.747722)
		(width 0.10668)
		(layer "F.Cu")
		(net "USB_HUB2_TI_USB_R1_MRP_RBIAS")
	)
	(segment
		(start 108.72089 -25.11679)
		(end 108.73359 -25.11679)
		(width 0.10668)
		(layer "F.Cu")
		(net "USB_HUB2_TI_USB_R1_MRP_RBIAS")
	)
	(via
		(at 108.73359 -25.11679)
		(size 0.762)
		(drill 0.381)
		(layers "F.Cu" "B.Cu")
		(net "USB_HUB2_TI_USB_R1_MRP_RBIAS")
	)
	(segment
		(start 118.74373 -25.620726)
		(end 119.347996 -25.620726)
		(width 0.10668)
		(layer "F.Cu")
		(net "USB_HUB2_TI_USB_DP_DN3_MRP_VDD12")
	)
	(segment
		(start 117.536468 -27.553412)
		(end 117.536468 -26.827988)
		(width 0.10668)
		(layer "F.Cu")
		(net "USB_HUB2_TI_USB_DP_DN3_MRP_VDD12")
	)
	(segment
		(start 117.342158 -27.747722)
		(end 117.536468 -27.553412)
		(width 0.10668)
		(layer "F.Cu")
		(net "USB_HUB2_TI_USB_DP_DN3_MRP_VDD12")
	)
	(segment
		(start 119.934482 -24.275796)
		(end 119.762524 -24.447754)
		(width 0.10668)
		(layer "F.Cu")
		(net "USB_HUB2_TI_USB_DP_DN3_MRP_VDD12")
	)
	(segment
		(start 117.198902 -27.747722)
		(end 117.342158 -27.747722)
		(width 0.10668)
		(layer "F.Cu")
		(net "USB_HUB2_TI_USB_DP_DN3_MRP_VDD12")
	)
	(segment
		(start 119.762524 -24.447754)
		(end 119.762524 -25.206198)
		(width 0.10668)
		(layer "F.Cu")
		(net "USB_HUB2_TI_USB_DP_DN3_MRP_VDD12")
	)
	(segment
		(start 119.762524 -25.206198)
		(end 119.347996 -25.620726)
		(width 0.10668)
		(layer "F.Cu")
		(net "USB_HUB2_TI_USB_DP_DN3_MRP_VDD12")
	)
	(segment
		(start 120.2817 -24.275796)
		(end 119.934482 -24.275796)
		(width 0.10668)
		(layer "F.Cu")
		(net "USB_HUB2_TI_USB_DP_DN3_MRP_VDD12")
	)
	(segment
		(start 117.536468 -26.827988)
		(end 118.74373 -25.620726)
		(width 0.10668)
		(layer "F.Cu")
		(net "USB_HUB2_TI_USB_DP_DN3_MRP_VDD12")
	)
	(via
		(at 119.347996 -25.620726)
		(size 0.762)
		(drill 0.381)
		(layers "F.Cu" "B.Cu")
		(net "USB_HUB2_TI_USB_DP_DN3_MRP_VDD12")
	)
	(segment
		(start 109.048804 -26.587196)
		(end 109.7788 -25.8572)
		(width 0.10668)
		(layer "F.Cu")
		(net "USB_HUB2_TI_USB_DP_DN1_MRP_CFG_STRAP")
	)
	(segment
		(start 109.048804 -27.097736)
		(end 109.048804 -26.587196)
		(width 0.10668)
		(layer "F.Cu")
		(net "USB_HUB2_TI_USB_DP_DN1_MRP_CFG_STRAP")
	)
	(segment
		(start 110.67542 -22.690328)
		(end 110.152942 -22.16785)
		(width 0.10668)
		(layer "F.Cu")
		(net "USB_HUB2_TI_USB_DP_DN1_MRP_CFG_STRAP")
	)
	(segment
		(start 109.7788 -25.032208)
		(end 110.67542 -24.135588)
		(width 0.10668)
		(layer "F.Cu")
		(net "USB_HUB2_TI_USB_DP_DN1_MRP_CFG_STRAP")
	)
	(segment
		(start 109.7788 -25.8572)
		(end 109.7788 -25.032208)
		(width 0.10668)
		(layer "F.Cu")
		(net "USB_HUB2_TI_USB_DP_DN1_MRP_CFG_STRAP")
	)
	(segment
		(start 110.67542 -24.135588)
		(end 110.67542 -22.690328)
		(width 0.10668)
		(layer "F.Cu")
		(net "USB_HUB2_TI_USB_DP_DN1_MRP_CFG_STRAP")
	)
	(via
		(at 109.7788 -25.8572)
		(size 0.762)
		(drill 0.381)
		(layers "F.Cu" "B.Cu")
		(net "USB_HUB2_TI_USB_DP_DN1_MRP_CFG_STRAP")
	)
	(segment
		(start 119.780558 -26.046938)
		(end 120.2817 -25.545796)
		(width 0.10668)
		(layer "F.Cu")
		(net "USB_HUB2_TI_USB_DM_DN3_MRP_VDD33")
	)
	(segment
		(start 118.022878 -27.925522)
		(end 118.022878 -27.171396)
		(width 0.10668)
		(layer "F.Cu")
		(net "USB_HUB2_TI_USB_DM_DN3_MRP_VDD33")
	)
	(segment
		(start 117.198902 -28.247848)
		(end 117.700552 -28.247848)
		(width 0.10668)
		(layer "F.Cu")
		(net "USB_HUB2_TI_USB_DM_DN3_MRP_VDD33")
	)
	(segment
		(start 118.284498 -26.909776)
		(end 119.038624 -26.909776)
		(width 0.10668)
		(layer "F.Cu")
		(net "USB_HUB2_TI_USB_DM_DN3_MRP_VDD33")
	)
	(segment
		(start 117.700552 -28.247848)
		(end 118.022878 -27.925522)
		(width 0.10668)
		(layer "F.Cu")
		(net "USB_HUB2_TI_USB_DM_DN3_MRP_VDD33")
	)
	(segment
		(start 119.780558 -26.167842)
		(end 119.780558 -26.046938)
		(width 0.10668)
		(layer "F.Cu")
		(net "USB_HUB2_TI_USB_DM_DN3_MRP_VDD33")
	)
	(segment
		(start 118.022878 -27.171396)
		(end 118.284498 -26.909776)
		(width 0.10668)
		(layer "F.Cu")
		(net "USB_HUB2_TI_USB_DM_DN3_MRP_VDD33")
	)
	(segment
		(start 119.038624 -26.909776)
		(end 119.780558 -26.167842)
		(width 0.10668)
		(layer "F.Cu")
		(net "USB_HUB2_TI_USB_DM_DN3_MRP_VDD33")
	)
	(via
		(at 118.284498 -26.909776)
		(size 0.762)
		(drill 0.381)
		(layers "F.Cu" "B.Cu")
		(net "USB_HUB2_TI_USB_DM_DN3_MRP_VDD33")
	)
	(segment
		(start 105.591864 -37.6682)
		(end 105.591864 -36.6522)
		(width 0.10668)
		(layer "F.Cu")
		(net "USB_HUB2_TI_TEST_MRP_PROG_FUNC6")
	)
	(segment
		(start 108.398818 -35.247834)
		(end 108.20146 -35.247834)
		(width 0.10668)
		(layer "F.Cu")
		(net "USB_HUB2_TI_TEST_MRP_PROG_FUNC6")
	)
	(segment
		(start 106.811064 -36.63823)
		(end 106.813858 -36.635436)
		(width 0.10668)
		(layer "F.Cu")
		(net "USB_HUB2_TI_TEST_MRP_PROG_FUNC6")
	)
	(segment
		(start 106.811064 -36.6522)
		(end 106.811064 -36.63823)
		(width 0.10668)
		(layer "F.Cu")
		(net "USB_HUB2_TI_TEST_MRP_PROG_FUNC6")
	)
	(segment
		(start 105.591864 -36.6522)
		(end 106.811064 -36.6522)
		(width 0.10668)
		(layer "F.Cu")
		(net "USB_HUB2_TI_TEST_MRP_PROG_FUNC6")
	)
	(segment
		(start 108.20146 -35.247834)
		(end 106.813858 -36.635436)
		(width 0.10668)
		(layer "F.Cu")
		(net "USB_HUB2_TI_TEST_MRP_PROG_FUNC6")
	)
	(via
		(at 106.813858 -36.635436)
		(size 0.762)
		(drill 0.381)
		(layers "F.Cu" "B.Cu")
		(net "USB_HUB2_TI_TEST_MRP_PROG_FUNC6")
	)
	(segment
		(start 117.347238 -40.7797)
		(end 118.363238 -40.7797)
		(width 0.10668)
		(layer "F.Cu")
		(net "USB_HUB2_TI_SMBUSZ_MRP_PROG_FUNC2")
	)
	(segment
		(start 113.548922 -35.89782)
		(end 113.548922 -36.414202)
		(width 0.10668)
		(layer "F.Cu")
		(net "USB_HUB2_TI_SMBUSZ_MRP_PROG_FUNC2")
	)
	(segment
		(start 116.3066 -39.17188)
		(end 116.958618 -39.17188)
		(width 0.10668)
		(layer "F.Cu")
		(net "USB_HUB2_TI_SMBUSZ_MRP_PROG_FUNC2")
	)
	(segment
		(start 113.548922 -36.414202)
		(end 116.3066 -39.17188)
		(width 0.10668)
		(layer "F.Cu")
		(net "USB_HUB2_TI_SMBUSZ_MRP_PROG_FUNC2")
	)
	(segment
		(start 117.347238 -40.7797)
		(end 117.347238 -39.5605)
		(width 0.10668)
		(layer "F.Cu")
		(net "USB_HUB2_TI_SMBUSZ_MRP_PROG_FUNC2")
	)
	(segment
		(start 116.958618 -39.17188)
		(end 117.347238 -39.5605)
		(width 0.10668)
		(layer "F.Cu")
		(net "USB_HUB2_TI_SMBUSZ_MRP_PROG_FUNC2")
	)
	(via
		(at 117.347238 -39.5605)
		(size 0.762)
		(drill 0.381)
		(layers "F.Cu" "B.Cu")
		(net "USB_HUB2_TI_SMBUSZ_MRP_PROG_FUNC2")
	)
	(segment
		(start 114.54892 -35.89782)
		(end 114.54892 -36.219384)
		(width 0.10668)
		(layer "F.Cu")
		(net "SMB_USB_HUB2_TI_SDA_MRP_PRT_CTL2")
	)
	(segment
		(start 119.275606 -38.440868)
		(end 120.395238 -39.5605)
		(width 0.10668)
		(layer "F.Cu")
		(net "SMB_USB_HUB2_TI_SDA_MRP_PRT_CTL2")
	)
	(segment
		(start 120.395238 -40.7797)
		(end 120.395238 -39.5605)
		(width 0.10668)
		(layer "F.Cu")
		(net "SMB_USB_HUB2_TI_SDA_MRP_PRT_CTL2")
	)
	(segment
		(start 114.54892 -36.219384)
		(end 116.770404 -38.440868)
		(width 0.10668)
		(layer "F.Cu")
		(net "SMB_USB_HUB2_TI_SDA_MRP_PRT_CTL2")
	)
	(segment
		(start 116.770404 -38.440868)
		(end 119.275606 -38.440868)
		(width 0.10668)
		(layer "F.Cu")
		(net "SMB_USB_HUB2_TI_SDA_MRP_PRT_CTL2")
	)
	(via
		(at 120.395238 -39.5605)
		(size 0.762)
		(drill 0.381)
		(layers "F.Cu" "B.Cu")
		(net "SMB_USB_HUB2_TI_SDA_MRP_PRT_CTL2")
	)
	(segment
		(start 119.379238 -40.7797)
		(end 119.379238 -39.8145)
		(width 0.10668)
		(layer "F.Cu")
		(net "SMB_USB_HUB2_TI_SCL_MRP_PRT_CTL1")
	)
	(segment
		(start 119.379238 -39.8145)
		(end 119.125238 -39.5605)
		(width 0.10668)
		(layer "F.Cu")
		(net "SMB_USB_HUB2_TI_SCL_MRP_PRT_CTL1")
	)
	(segment
		(start 114.048794 -36.265866)
		(end 116.576348 -38.79342)
		(width 0.10668)
		(layer "F.Cu")
		(net "SMB_USB_HUB2_TI_SCL_MRP_PRT_CTL1")
	)
	(segment
		(start 116.576348 -38.79342)
		(end 118.358158 -38.79342)
		(width 0.10668)
		(layer "F.Cu")
		(net "SMB_USB_HUB2_TI_SCL_MRP_PRT_CTL1")
	)
	(segment
		(start 118.358158 -38.79342)
		(end 119.125238 -39.5605)
		(width 0.10668)
		(layer "F.Cu")
		(net "SMB_USB_HUB2_TI_SCL_MRP_PRT_CTL1")
	)
	(segment
		(start 114.048794 -35.89782)
		(end 114.048794 -36.265866)
		(width 0.10668)
		(layer "F.Cu")
		(net "SMB_USB_HUB2_TI_SCL_MRP_PRT_CTL1")
	)
	(via
		(at 119.125238 -39.5605)
		(size 0.762)
		(drill 0.381)
		(layers "F.Cu" "B.Cu")
		(net "SMB_USB_HUB2_TI_SCL_MRP_PRT_CTL1")
	)
	(segment
		(start 113.283238 -39.0017)
		(end 113.283238 -38.482016)
		(width 0.10668)
		(layer "F.Cu")
		(net "USB_HUB2_TI_PWRCTL_POL_MRP_VBUS_DET")
	)
	(segment
		(start 112.548924 -35.89782)
		(end 112.548924 -36.602924)
		(width 0.10668)
		(layer "F.Cu")
		(net "USB_HUB2_TI_PWRCTL_POL_MRP_VBUS_DET")
	)
	(segment
		(start 112.548924 -36.602924)
		(end 113.486438 -37.540438)
		(width 0.10668)
		(layer "F.Cu")
		(net "USB_HUB2_TI_PWRCTL_POL_MRP_VBUS_DET")
	)
	(segment
		(start 113.486438 -37.540438)
		(end 113.486438 -37.719)
		(width 0.10668)
		(layer "F.Cu")
		(net "USB_HUB2_TI_PWRCTL_POL_MRP_VBUS_DET")
	)
	(segment
		(start 113.486438 -38.278816)
		(end 113.486438 -37.719)
		(width 0.10668)
		(layer "F.Cu")
		(net "USB_HUB2_TI_PWRCTL_POL_MRP_VBUS_DET")
	)
	(segment
		(start 113.283238 -38.482016)
		(end 113.486438 -38.278816)
		(width 0.10668)
		(layer "F.Cu")
		(net "USB_HUB2_TI_PWRCTL_POL_MRP_VBUS_DET")
	)
	(segment
		(start 113.283238 -39.0017)
		(end 114.299238 -39.0017)
		(width 0.10668)
		(layer "F.Cu")
		(net "USB_HUB2_TI_PWRCTL_POL_MRP_VBUS_DET")
	)
	(via
		(at 113.486438 -37.719)
		(size 0.762)
		(drill 0.381)
		(layers "F.Cu" "B.Cu")
		(net "USB_HUB2_TI_PWRCTL_POL_MRP_VBUS_DET")
	)
	(segment
		(start 112.07496 -37.928042)
		(end 112.201198 -37.928042)
		(width 0.10668)
		(layer "F.Cu")
		(net "USB_HUB2_TI_PWRCTL_POL")
	)
	(segment
		(start 112.267238 -39.059612)
		(end 112.07496 -38.867334)
		(width 0.10668)
		(layer "F.Cu")
		(net "USB_HUB2_TI_PWRCTL_POL")
	)
	(segment
		(start 112.88268 -39.8018)
		(end 113.283238 -39.8018)
		(width 0.10668)
		(layer "F.Cu")
		(net "USB_HUB2_TI_PWRCTL_POL")
	)
	(segment
		(start 112.267238 -40.7797)
		(end 112.267238 -39.059612)
		(width 0.10668)
		(layer "F.Cu")
		(net "USB_HUB2_TI_PWRCTL_POL")
	)
	(segment
		(start 112.267238 -40.7797)
		(end 113.283238 -40.7797)
		(width 0.10668)
		(layer "F.Cu")
		(net "USB_HUB2_TI_PWRCTL_POL")
	)
	(segment
		(start 112.6744 -39.59352)
		(end 112.88268 -39.8018)
		(width 0.10668)
		(layer "F.Cu")
		(net "USB_HUB2_TI_PWRCTL_POL")
	)
	(segment
		(start 112.6744 -38.401244)
		(end 112.6744 -39.59352)
		(width 0.10668)
		(layer "F.Cu")
		(net "USB_HUB2_TI_PWRCTL_POL")
	)
	(segment
		(start 112.201198 -37.928042)
		(end 112.6744 -38.401244)
		(width 0.10668)
		(layer "F.Cu")
		(net "USB_HUB2_TI_PWRCTL_POL")
	)
	(segment
		(start 112.07496 -38.867334)
		(end 112.07496 -37.928042)
		(width 0.10668)
		(layer "F.Cu")
		(net "USB_HUB2_TI_PWRCTL_POL")
	)
	(via
		(at 112.07496 -37.928042)
		(size 0.762)
		(drill 0.381)
		(layers "F.Cu" "B.Cu")
		(net "USB_HUB2_TI_PWRCTL_POL")
	)
	(segment
		(start 118.46052 -37.12718)
		(end 118.5164 -37.0713)
		(width 0.10668)
		(layer "F.Cu")
		(net "USB_HUB2_TI_PWRCTL3_MRP_VDD33")
	)
	(segment
		(start 116.548916 -35.89782)
		(end 116.548916 -36.270184)
		(width 0.10668)
		(layer "F.Cu")
		(net "USB_HUB2_TI_PWRCTL3_MRP_VDD33")
	)
	(segment
		(start 117.509798 -37.12718)
		(end 118.46052 -37.12718)
		(width 0.10668)
		(layer "F.Cu")
		(net "USB_HUB2_TI_PWRCTL3_MRP_VDD33")
	)
	(segment
		(start 116.548916 -36.270184)
		(end 117.405912 -37.12718)
		(width 0.10668)
		(layer "F.Cu")
		(net "USB_HUB2_TI_PWRCTL3_MRP_VDD33")
	)
	(segment
		(start 117.405912 -37.12718)
		(end 117.509798 -37.12718)
		(width 0.10668)
		(layer "F.Cu")
		(net "USB_HUB2_TI_PWRCTL3_MRP_VDD33")
	)
	(via
		(at 117.509798 -37.12718)
		(size 0.762)
		(drill 0.381)
		(layers "F.Cu" "B.Cu")
		(net "USB_HUB2_TI_PWRCTL3_MRP_VDD33")
	)
	(segment
		(start 121.411238 -39.8145)
		(end 121.665238 -39.5605)
		(width 0.10668)
		(layer "F.Cu")
		(net "USB_HUB2_TI_PWRCTL2_MRP_VDD12")
	)
	(segment
		(start 120.172226 -38.067488)
		(end 121.665238 -39.5605)
		(width 0.10668)
		(layer "F.Cu")
		(net "USB_HUB2_TI_PWRCTL2_MRP_VDD12")
	)
	(segment
		(start 115.548918 -35.89782)
		(end 115.548918 -36.500562)
		(width 0.10668)
		(layer "F.Cu")
		(net "USB_HUB2_TI_PWRCTL2_MRP_VDD12")
	)
	(segment
		(start 121.411238 -40.7797)
		(end 122.427238 -40.7797)
		(width 0.10668)
		(layer "F.Cu")
		(net "USB_HUB2_TI_PWRCTL2_MRP_VDD12")
	)
	(segment
		(start 121.411238 -40.7797)
		(end 121.411238 -39.8145)
		(width 0.10668)
		(layer "F.Cu")
		(net "USB_HUB2_TI_PWRCTL2_MRP_VDD12")
	)
	(segment
		(start 117.115844 -38.067488)
		(end 120.172226 -38.067488)
		(width 0.10668)
		(layer "F.Cu")
		(net "USB_HUB2_TI_PWRCTL2_MRP_VDD12")
	)
	(segment
		(start 115.548918 -36.500562)
		(end 117.115844 -38.067488)
		(width 0.10668)
		(layer "F.Cu")
		(net "USB_HUB2_TI_PWRCTL2_MRP_VDD12")
	)
	(via
		(at 121.665238 -39.5605)
		(size 0.762)
		(drill 0.381)
		(layers "F.Cu" "B.Cu")
		(net "USB_HUB2_TI_PWRCTL2_MRP_VDD12")
	)
	(segment
		(start 111.548926 -35.89782)
		(end 111.548926 -36.218114)
		(width 0.10668)
		(layer "F.Cu")
		(net "USB_HUB2_TI_OVERCUR4_MRP_I2C_SLV_CFG1")
	)
	(segment
		(start 107.396026 -40.371014)
		(end 107.396026 -47.440596)
		(width 0.10668)
		(layer "F.Cu")
		(net "USB_HUB2_TI_OVERCUR4_MRP_I2C_SLV_CFG1")
	)
	(segment
		(start 111.548926 -36.218114)
		(end 107.396026 -40.371014)
		(width 0.10668)
		(layer "F.Cu")
		(net "USB_HUB2_TI_OVERCUR4_MRP_I2C_SLV_CFG1")
	)
	(segment
		(start 114.610896 -53.49748)
		(end 114.610896 -52.48148)
		(width 0.10668)
		(layer "F.Cu")
		(net "USB_HUB2_TI_OVERCUR4_MRP_I2C_SLV_CFG1")
	)
	(segment
		(start 111.872776 -48.52416)
		(end 114.610896 -51.26228)
		(width 0.10668)
		(layer "F.Cu")
		(net "USB_HUB2_TI_OVERCUR4_MRP_I2C_SLV_CFG1")
	)
	(segment
		(start 114.610896 -52.48148)
		(end 114.610896 -51.26228)
		(width 0.10668)
		(layer "F.Cu")
		(net "USB_HUB2_TI_OVERCUR4_MRP_I2C_SLV_CFG1")
	)
	(segment
		(start 108.47959 -48.52416)
		(end 111.872776 -48.52416)
		(width 0.10668)
		(layer "F.Cu")
		(net "USB_HUB2_TI_OVERCUR4_MRP_I2C_SLV_CFG1")
	)
	(segment
		(start 107.396026 -47.440596)
		(end 108.47959 -48.52416)
		(width 0.10668)
		(layer "F.Cu")
		(net "USB_HUB2_TI_OVERCUR4_MRP_I2C_SLV_CFG1")
	)
	(via
		(at 114.610896 -51.26228)
		(size 0.762)
		(drill 0.381)
		(layers "F.Cu" "B.Cu")
		(net "USB_HUB2_TI_OVERCUR4_MRP_I2C_SLV_CFG1")
	)
	(segment
		(start 111.0488 -35.89782)
		(end 111.0488 -36.356798)
		(width 0.10668)
		(layer "F.Cu")
		(net "USB_HUB2_TI_OVERCUR3_MRP_CFG_BC_EN")
	)
	(segment
		(start 107.172506 -40.233092)
		(end 107.172506 -47.533306)
		(width 0.10668)
		(layer "F.Cu")
		(net "USB_HUB2_TI_OVERCUR3_MRP_CFG_BC_EN")
	)
	(segment
		(start 112.597946 -52.46243)
		(end 112.597946 -51.24323)
		(width 0.10668)
		(layer "F.Cu")
		(net "USB_HUB2_TI_OVERCUR3_MRP_CFG_BC_EN")
	)
	(segment
		(start 110.348776 -48.99406)
		(end 112.597946 -51.24323)
		(width 0.10668)
		(layer "F.Cu")
		(net "USB_HUB2_TI_OVERCUR3_MRP_CFG_BC_EN")
	)
	(segment
		(start 111.0488 -36.356798)
		(end 107.172506 -40.233092)
		(width 0.10668)
		(layer "F.Cu")
		(net "USB_HUB2_TI_OVERCUR3_MRP_CFG_BC_EN")
	)
	(segment
		(start 108.63326 -48.99406)
		(end 110.348776 -48.99406)
		(width 0.10668)
		(layer "F.Cu")
		(net "USB_HUB2_TI_OVERCUR3_MRP_CFG_BC_EN")
	)
	(segment
		(start 113.613946 -52.46243)
		(end 112.597946 -52.46243)
		(width 0.10668)
		(layer "F.Cu")
		(net "USB_HUB2_TI_OVERCUR3_MRP_CFG_BC_EN")
	)
	(segment
		(start 107.172506 -47.533306)
		(end 108.63326 -48.99406)
		(width 0.10668)
		(layer "F.Cu")
		(net "USB_HUB2_TI_OVERCUR3_MRP_CFG_BC_EN")
	)
	(via
		(at 112.597946 -51.24323)
		(size 0.762)
		(drill 0.381)
		(layers "F.Cu" "B.Cu")
		(net "USB_HUB2_TI_OVERCUR3_MRP_CFG_BC_EN")
	)
	(segment
		(start 112.597946 -54.481984)
		(end 112.597946 -53.87213)
		(width 0.10668)
		(layer "F.Cu")
		(net "USB_HUB2_TI_OVERCUR3")
	)
	(segment
		(start 112.597946 -53.87213)
		(end 112.597946 -53.26253)
		(width 0.10668)
		(layer "F.Cu")
		(net "USB_HUB2_TI_OVERCUR3")
	)
	(via
		(at 112.597946 -53.87213)
		(size 0.508)
		(drill 0.254)
		(layers "F.Cu" "B.Cu")
		(net "USB_HUB2_TI_OVERCUR3")
	)
	(segment
		(start 109.54893 -35.89782)
		(end 109.54893 -36.26231)
		(width 0.10668)
		(layer "F.Cu")
		(net "USB_HUB2_TI_OVERCUR2_MRP_PROG_FUNC5")
	)
	(segment
		(start 106.501946 -39.309294)
		(end 106.501946 -51.054)
		(width 0.10668)
		(layer "F.Cu")
		(net "USB_HUB2_TI_OVERCUR2_MRP_PROG_FUNC5")
	)
	(segment
		(start 106.501946 -51.054)
		(end 106.501946 -52.46243)
		(width 0.10668)
		(layer "F.Cu")
		(net "USB_HUB2_TI_OVERCUR2_MRP_PROG_FUNC5")
	)
	(segment
		(start 105.485946 -52.46243)
		(end 106.501946 -52.46243)
		(width 0.10668)
		(layer "F.Cu")
		(net "USB_HUB2_TI_OVERCUR2_MRP_PROG_FUNC5")
	)
	(segment
		(start 109.54893 -36.26231)
		(end 106.501946 -39.309294)
		(width 0.10668)
		(layer "F.Cu")
		(net "USB_HUB2_TI_OVERCUR2_MRP_PROG_FUNC5")
	)
	(via
		(at 106.501946 -51.054)
		(size 0.762)
		(drill 0.381)
		(layers "F.Cu" "B.Cu")
		(net "USB_HUB2_TI_OVERCUR2_MRP_PROG_FUNC5")
	)
	(segment
		(start 105.9688 -53.41366)
		(end 105.9688 -54.315614)
		(width 0.10668)
		(layer "F.Cu")
		(net "USB_HUB2_TI_OVERCUR2")
	)
	(segment
		(start 105.9942 -55.78094)
		(end 105.9942 -54.990238)
		(width 0.10668)
		(layer "F.Cu")
		(net "USB_HUB2_TI_OVERCUR2")
	)
	(segment
		(start 106.68 -55.026814)
		(end 106.68 -55.86476)
		(width 0.10668)
		(layer "F.Cu")
		(net "USB_HUB2_TI_OVERCUR2")
	)
	(segment
		(start 105.9688 -54.315614)
		(end 106.68 -55.026814)
		(width 0.10668)
		(layer "F.Cu")
		(net "USB_HUB2_TI_OVERCUR2")
	)
	(segment
		(start 106.68 -55.86476)
		(end 106.07802 -55.86476)
		(width 0.10668)
		(layer "F.Cu")
		(net "USB_HUB2_TI_OVERCUR2")
	)
	(segment
		(start 105.81767 -53.26253)
		(end 105.9688 -53.41366)
		(width 0.10668)
		(layer "F.Cu")
		(net "USB_HUB2_TI_OVERCUR2")
	)
	(segment
		(start 105.9942 -54.990238)
		(end 105.485946 -54.481984)
		(width 0.10668)
		(layer "F.Cu")
		(net "USB_HUB2_TI_OVERCUR2")
	)
	(segment
		(start 106.07802 -55.86476)
		(end 105.9942 -55.78094)
		(width 0.10668)
		(layer "F.Cu")
		(net "USB_HUB2_TI_OVERCUR2")
	)
	(segment
		(start 105.485946 -53.26253)
		(end 105.81767 -53.26253)
		(width 0.10668)
		(layer "F.Cu")
		(net "USB_HUB2_TI_OVERCUR2")
	)
	(via
		(at 106.68 -55.86476)
		(size 0.762)
		(drill 0.381)
		(layers "F.Cu" "B.Cu")
		(net "USB_HUB2_TI_OVERCUR2")
	)
	(segment
		(start 108.533946 -52.46243)
		(end 107.517946 -52.46243)
		(width 0.10668)
		(layer "F.Cu")
		(net "USB_HUB2_TI_OVERCUR1_MRP_PROG_FUNC4")
	)
	(segment
		(start 108.533946 -49.715166)
		(end 108.533946 -50.673)
		(width 0.10668)
		(layer "F.Cu")
		(net "USB_HUB2_TI_OVERCUR1_MRP_PROG_FUNC4")
	)
	(segment
		(start 106.725466 -39.63416)
		(end 106.725466 -47.906686)
		(width 0.10668)
		(layer "F.Cu")
		(net "USB_HUB2_TI_OVERCUR1_MRP_PROG_FUNC4")
	)
	(segment
		(start 110.048802 -36.310824)
		(end 106.725466 -39.63416)
		(width 0.10668)
		(layer "F.Cu")
		(net "USB_HUB2_TI_OVERCUR1_MRP_PROG_FUNC4")
	)
	(segment
		(start 108.533946 -50.673)
		(end 108.533946 -52.46243)
		(width 0.10668)
		(layer "F.Cu")
		(net "USB_HUB2_TI_OVERCUR1_MRP_PROG_FUNC4")
	)
	(segment
		(start 106.725466 -47.906686)
		(end 108.533946 -49.715166)
		(width 0.10668)
		(layer "F.Cu")
		(net "USB_HUB2_TI_OVERCUR1_MRP_PROG_FUNC4")
	)
	(segment
		(start 110.048802 -35.89782)
		(end 110.048802 -36.310824)
		(width 0.10668)
		(layer "F.Cu")
		(net "USB_HUB2_TI_OVERCUR1_MRP_PROG_FUNC4")
	)
	(via
		(at 108.533946 -50.673)
		(size 0.762)
		(drill 0.381)
		(layers "F.Cu" "B.Cu")
		(net "USB_HUB2_TI_OVERCUR1_MRP_PROG_FUNC4")
	)
	(segment
		(start 107.93476 -54.35092)
		(end 108.533946 -53.751734)
		(width 0.10668)
		(layer "F.Cu")
		(net "USB_HUB2_TI_OVERCUR1")
	)
	(segment
		(start 107.264708 -54.4576)
		(end 107.371388 -54.35092)
		(width 0.10668)
		(layer "F.Cu")
		(net "USB_HUB2_TI_OVERCUR1")
	)
	(segment
		(start 108.533946 -53.751734)
		(end 108.533946 -53.26253)
		(width 0.10668)
		(layer "F.Cu")
		(net "USB_HUB2_TI_OVERCUR1")
	)
	(segment
		(start 107.264708 -54.591204)
		(end 107.264708 -54.4576)
		(width 0.10668)
		(layer "F.Cu")
		(net "USB_HUB2_TI_OVERCUR1")
	)
	(segment
		(start 107.371388 -54.35092)
		(end 107.93476 -54.35092)
		(width 0.10668)
		(layer "F.Cu")
		(net "USB_HUB2_TI_OVERCUR1")
	)
	(segment
		(start 107.264708 -54.591204)
		(end 108.424726 -54.591204)
		(width 0.10668)
		(layer "F.Cu")
		(net "USB_HUB2_TI_OVERCUR1")
	)
	(segment
		(start 108.424726 -54.591204)
		(end 108.533946 -54.481984)
		(width 0.10668)
		(layer "F.Cu")
		(net "USB_HUB2_TI_OVERCUR1")
	)
	(via
		(at 107.264708 -54.591204)
		(size 0.762)
		(drill 0.381)
		(layers "F.Cu" "B.Cu")
		(net "USB_HUB2_TI_OVERCUR1")
	)
	(segment
		(start 115.918996 -51.97348)
		(end 115.410996 -52.48148)
		(width 0.10668)
		(layer "F.Cu")
		(net "USB_HUB2_TI_OVERCCUR4")
	)
	(segment
		(start 118.217696 -52.48148)
		(end 117.709696 -51.97348)
		(width 0.10668)
		(layer "F.Cu")
		(net "USB_HUB2_TI_OVERCCUR4")
	)
	(segment
		(start 117.709696 -51.97348)
		(end 116.630196 -51.97348)
		(width 0.10668)
		(layer "F.Cu")
		(net "USB_HUB2_TI_OVERCCUR4")
	)
	(segment
		(start 116.630196 -51.97348)
		(end 115.918996 -51.97348)
		(width 0.10668)
		(layer "F.Cu")
		(net "USB_HUB2_TI_OVERCCUR4")
	)
	(via
		(at 116.630196 -51.97348)
		(size 0.762)
		(drill 0.381)
		(layers "F.Cu" "B.Cu")
		(net "USB_HUB2_TI_OVERCCUR4")
	)
	(segment
		(start 106.869738 -29.747718)
		(end 105.2576 -28.13558)
		(width 0.10668)
		(layer "F.Cu")
		(net "USB_HUB2_TI_NC_MRP_ATEST")
	)
	(segment
		(start 105.2576 -28.13558)
		(end 104.96042 -27.8384)
		(width 0.10668)
		(layer "F.Cu")
		(net "USB_HUB2_TI_NC_MRP_ATEST")
	)
	(segment
		(start 108.398818 -29.747718)
		(end 106.869738 -29.747718)
		(width 0.10668)
		(layer "F.Cu")
		(net "USB_HUB2_TI_NC_MRP_ATEST")
	)
	(segment
		(start 103.185722 -26.992326)
		(end 103.185722 -26.835354)
		(width 0.10668)
		(layer "F.Cu")
		(net "USB_HUB2_TI_NC_MRP_ATEST")
	)
	(segment
		(start 104.96042 -27.8384)
		(end 104.031796 -27.8384)
		(width 0.10668)
		(layer "F.Cu")
		(net "USB_HUB2_TI_NC_MRP_ATEST")
	)
	(segment
		(start 104.031796 -27.8384)
		(end 103.185722 -26.992326)
		(width 0.10668)
		(layer "F.Cu")
		(net "USB_HUB2_TI_NC_MRP_ATEST")
	)
	(via
		(at 105.2576 -28.13558)
		(size 0.762)
		(drill 0.381)
		(layers "F.Cu" "B.Cu")
		(net "USB_HUB2_TI_NC_MRP_ATEST")
	)
	(segment
		(start 106.948986 -39.916354)
		(end 106.948986 -47.62627)
		(width 0.10668)
		(layer "F.Cu")
		(net "USB_HUB2_TI_HS_SUSPEND_MRP_CFG_NON_REM")
	)
	(segment
		(start 106.948986 -47.62627)
		(end 110.565946 -51.24323)
		(width 0.10668)
		(layer "F.Cu")
		(net "USB_HUB2_TI_HS_SUSPEND_MRP_CFG_NON_REM")
	)
	(segment
		(start 110.565946 -52.46243)
		(end 110.565946 -51.24323)
		(width 0.10668)
		(layer "F.Cu")
		(net "USB_HUB2_TI_HS_SUSPEND_MRP_CFG_NON_REM")
	)
	(segment
		(start 110.548928 -36.316412)
		(end 106.948986 -39.916354)
		(width 0.10668)
		(layer "F.Cu")
		(net "USB_HUB2_TI_HS_SUSPEND_MRP_CFG_NON_REM")
	)
	(segment
		(start 111.581946 -52.46243)
		(end 110.565946 -52.46243)
		(width 0.10668)
		(layer "F.Cu")
		(net "USB_HUB2_TI_HS_SUSPEND_MRP_CFG_NON_REM")
	)
	(segment
		(start 110.548928 -35.89782)
		(end 110.548928 -36.316412)
		(width 0.10668)
		(layer "F.Cu")
		(net "USB_HUB2_TI_HS_SUSPEND_MRP_CFG_NON_REM")
	)
	(via
		(at 110.565946 -51.24323)
		(size 0.762)
		(drill 0.381)
		(layers "F.Cu" "B.Cu")
		(net "USB_HUB2_TI_HS_SUSPEND_MRP_CFG_NON_REM")
	)
	(segment
		(start 110.565946 -53.26253)
		(end 109.549946 -53.26253)
		(width 0.10668)
		(layer "F.Cu")
		(net "USB_HUB2_TI_HS_SUSPEND")
	)
	(segment
		(start 109.549946 -53.87213)
		(end 109.549946 -53.26253)
		(width 0.10668)
		(layer "F.Cu")
		(net "USB_HUB2_TI_HS_SUSPEND")
	)
	(segment
		(start 109.549946 -54.481984)
		(end 109.549946 -53.87213)
		(width 0.10668)
		(layer "F.Cu")
		(net "USB_HUB2_TI_HS_SUSPEND")
	)
	(via
		(at 109.549946 -53.87213)
		(size 0.508)
		(drill 0.254)
		(layers "F.Cu" "B.Cu")
		(net "USB_HUB2_TI_HS_SUSPEND")
	)
	(segment
		(start 100.342192 -32.195262)
		(end 100.350828 -32.186626)
		(width 0.10668)
		(layer "F.Cu")
		(net "USB_HUB2_TI_GRSTZ_MRP_PROG_FUNC1")
	)
	(segment
		(start 101.413056 -32.858202)
		(end 101.413056 -32.186626)
		(width 0.10668)
		(layer "F.Cu")
		(net "USB_HUB2_TI_GRSTZ_MRP_PROG_FUNC1")
	)
	(segment
		(start 99.278186 -32.247586)
		(end 99.33051 -32.195262)
		(width 0.10668)
		(layer "F.Cu")
		(net "USB_HUB2_TI_GRSTZ_MRP_PROG_FUNC1")
	)
	(segment
		(start 108.183172 -34.747708)
		(end 107.25658 -35.6743)
		(width 0.10668)
		(layer "F.Cu")
		(net "USB_HUB2_TI_GRSTZ_MRP_PROG_FUNC1")
	)
	(segment
		(start 100.350828 -32.186626)
		(end 101.413056 -32.186626)
		(width 0.10668)
		(layer "F.Cu")
		(net "USB_HUB2_TI_GRSTZ_MRP_PROG_FUNC1")
	)
	(segment
		(start 107.25658 -35.6743)
		(end 104.229154 -35.6743)
		(width 0.10668)
		(layer "F.Cu")
		(net "USB_HUB2_TI_GRSTZ_MRP_PROG_FUNC1")
	)
	(segment
		(start 108.398818 -34.747708)
		(end 108.183172 -34.747708)
		(width 0.10668)
		(layer "F.Cu")
		(net "USB_HUB2_TI_GRSTZ_MRP_PROG_FUNC1")
	)
	(segment
		(start 98.222562 -32.235648)
		(end 98.2345 -32.247586)
		(width 0.10668)
		(layer "F.Cu")
		(net "USB_HUB2_TI_GRSTZ_MRP_PROG_FUNC1")
	)
	(segment
		(start 104.229154 -35.6743)
		(end 102.585774 -34.03092)
		(width 0.10668)
		(layer "F.Cu")
		(net "USB_HUB2_TI_GRSTZ_MRP_PROG_FUNC1")
	)
	(segment
		(start 99.33051 -32.195262)
		(end 100.342192 -32.195262)
		(width 0.10668)
		(layer "F.Cu")
		(net "USB_HUB2_TI_GRSTZ_MRP_PROG_FUNC1")
	)
	(segment
		(start 98.2345 -32.247586)
		(end 99.278186 -32.247586)
		(width 0.10668)
		(layer "F.Cu")
		(net "USB_HUB2_TI_GRSTZ_MRP_PROG_FUNC1")
	)
	(segment
		(start 102.585774 -34.03092)
		(end 101.413056 -32.858202)
		(width 0.10668)
		(layer "F.Cu")
		(net "USB_HUB2_TI_GRSTZ_MRP_PROG_FUNC1")
	)
	(via
		(at 102.585774 -34.03092)
		(size 0.762)
		(drill 0.381)
		(layers "F.Cu" "B.Cu")
		(net "USB_HUB2_TI_GRSTZ_MRP_PROG_FUNC1")
	)
	(segment
		(start 111.251238 -38.726872)
		(end 111.251238 -39.0017)
		(width 0.10668)
		(layer "F.Cu")
		(net "USB_HUB2_TI_GANGED_MRP_I2C_SLV_CFG0")
	)
	(segment
		(start 110.587282 -38.062916)
		(end 111.251238 -38.726872)
		(width 0.10668)
		(layer "F.Cu")
		(net "USB_HUB2_TI_GANGED_MRP_I2C_SLV_CFG0")
	)
	(segment
		(start 111.251238 -39.0017)
		(end 110.235238 -39.0017)
		(width 0.10668)
		(layer "F.Cu")
		(net "USB_HUB2_TI_GANGED_MRP_I2C_SLV_CFG0")
	)
	(segment
		(start 110.587282 -37.851588)
		(end 110.587282 -38.062916)
		(width 0.10668)
		(layer "F.Cu")
		(net "USB_HUB2_TI_GANGED_MRP_I2C_SLV_CFG0")
	)
	(segment
		(start 112.048798 -35.89782)
		(end 112.048798 -36.390072)
		(width 0.10668)
		(layer "F.Cu")
		(net "USB_HUB2_TI_GANGED_MRP_I2C_SLV_CFG0")
	)
	(segment
		(start 112.048798 -36.390072)
		(end 110.587282 -37.851588)
		(width 0.10668)
		(layer "F.Cu")
		(net "USB_HUB2_TI_GANGED_MRP_I2C_SLV_CFG0")
	)
	(via
		(at 110.587282 -38.062916)
		(size 0.762)
		(drill 0.381)
		(layers "F.Cu" "B.Cu")
		(net "USB_HUB2_TI_GANGED_MRP_I2C_SLV_CFG0")
	)
	(segment
		(start 109.0168 -39.59606)
		(end 109.0168 -40.577262)
		(width 0.10668)
		(layer "F.Cu")
		(net "USB_HUB2_TI_GANGED")
	)
	(segment
		(start 110.029498 -39.59606)
		(end 110.235238 -39.8018)
		(width 0.10668)
		(layer "F.Cu")
		(net "USB_HUB2_TI_GANGED")
	)
	(segment
		(start 109.219238 -40.7797)
		(end 110.235238 -40.7797)
		(width 0.10668)
		(layer "F.Cu")
		(net "USB_HUB2_TI_GANGED")
	)
	(segment
		(start 109.0168 -40.577262)
		(end 109.219238 -40.7797)
		(width 0.10668)
		(layer "F.Cu")
		(net "USB_HUB2_TI_GANGED")
	)
	(segment
		(start 109.0168 -39.59606)
		(end 110.029498 -39.59606)
		(width 0.10668)
		(layer "F.Cu")
		(net "USB_HUB2_TI_GANGED")
	)
	(via
		(at 109.0168 -39.59606)
		(size 0.762)
		(drill 0.381)
		(layers "F.Cu" "B.Cu")
		(net "USB_HUB2_TI_GANGED")
	)
	(segment
		(start 115.315238 -40.7797)
		(end 116.331238 -40.7797)
		(width 0.10668)
		(layer "F.Cu")
		(net "USB_HUB2_TI_FULLPWRMGMTZ_MRP_PROG_FUNC3")
	)
	(segment
		(start 116.331238 -40.7797)
		(end 116.331238 -40.3225)
		(width 0.10668)
		(layer "F.Cu")
		(net "USB_HUB2_TI_FULLPWRMGMTZ_MRP_PROG_FUNC3")
	)
	(segment
		(start 115.569238 -38.947598)
		(end 115.569238 -39.5605)
		(width 0.10668)
		(layer "F.Cu")
		(net "USB_HUB2_TI_FULLPWRMGMTZ_MRP_PROG_FUNC3")
	)
	(segment
		(start 113.048796 -35.89782)
		(end 113.048796 -36.427156)
		(width 0.10668)
		(layer "F.Cu")
		(net "USB_HUB2_TI_FULLPWRMGMTZ_MRP_PROG_FUNC3")
	)
	(segment
		(start 113.048796 -36.427156)
		(end 115.569238 -38.947598)
		(width 0.10668)
		(layer "F.Cu")
		(net "USB_HUB2_TI_FULLPWRMGMTZ_MRP_PROG_FUNC3")
	)
	(segment
		(start 116.331238 -40.3225)
		(end 115.569238 -39.5605)
		(width 0.10668)
		(layer "F.Cu")
		(net "USB_HUB2_TI_FULLPWRMGMTZ_MRP_PROG_FUNC3")
	)
	(via
		(at 115.569238 -39.5605)
		(size 0.762)
		(drill 0.381)
		(layers "F.Cu" "B.Cu")
		(net "USB_HUB2_TI_FULLPWRMGMTZ_MRP_PROG_FUNC3")
	)
	(segment
		(start 113.801652 -40.299386)
		(end 114.299238 -39.8018)
		(width 0.10668)
		(layer "F.Cu")
		(net "USB_HUB2_MRP_VBUS_DET")
	)
	(segment
		(start 114.299238 -40.7797)
		(end 114.281966 -40.7797)
		(width 0.10668)
		(layer "F.Cu")
		(net "USB_HUB2_MRP_VBUS_DET")
	)
	(segment
		(start 114.281966 -40.7797)
		(end 113.801652 -40.299386)
		(width 0.10668)
		(layer "F.Cu")
		(net "USB_HUB2_MRP_VBUS_DET")
	)
	(via
		(at 113.801652 -40.299386)
		(size 0.508)
		(drill 0.254)
		(layers "F.Cu" "B.Cu")
		(net "USB_HUB2_MRP_VBUS_DET")
	)
	(segment
		(start 102.437946 -54.481984)
		(end 101.421946 -54.481984)
		(width 0.10668)
		(layer "F.Cu")
		(net "USB_HUB2_MRP_RESET_N")
	)
	(segment
		(start 101.244146 -53.26253)
		(end 99.606862 -53.26253)
		(width 0.10668)
		(layer "F.Cu")
		(net "USB_HUB2_MRP_RESET_N")
	)
	(segment
		(start 102.437946 -53.26253)
		(end 101.244146 -53.26253)
		(width 0.10668)
		(layer "F.Cu")
		(net "USB_HUB2_MRP_RESET_N")
	)
	(segment
		(start 103.453946 -54.481984)
		(end 102.437946 -54.481984)
		(width 0.10668)
		(layer "F.Cu")
		(net "USB_HUB2_MRP_RESET_N")
	)
	(segment
		(start 102.437946 -54.481984)
		(end 102.437946 -53.26253)
		(width 0.10668)
		(layer "F.Cu")
		(net "USB_HUB2_MRP_RESET_N")
	)
	(via
		(at 101.244146 -53.26253)
		(size 0.762)
		(drill 0.381)
		(layers "F.Cu" "B.Cu")
		(net "USB_HUB2_MRP_RESET_N")
	)
	(segment
		(start 123.25604 -42.77106)
		(end 123.830334 -42.77106)
		(width 0.10668)
		(layer "F.Cu")
		(net "USB_HUB2_MRP_PRT_CTL4_GANGPWR")
	)
	(segment
		(start 123.830334 -42.77106)
		(end 124.024644 -42.57675)
		(width 0.10668)
		(layer "F.Cu")
		(net "USB_HUB2_MRP_PRT_CTL4_GANGPWR")
	)
	(segment
		(start 123.443238 -41.5798)
		(end 123.25604 -41.766998)
		(width 0.10668)
		(layer "F.Cu")
		(net "USB_HUB2_MRP_PRT_CTL4_GANGPWR")
	)
	(segment
		(start 124.024644 -42.57675)
		(end 124.440188 -42.57675)
		(width 0.10668)
		(layer "F.Cu")
		(net "USB_HUB2_MRP_PRT_CTL4_GANGPWR")
	)
	(segment
		(start 123.25604 -41.766998)
		(end 123.25604 -42.77106)
		(width 0.10668)
		(layer "F.Cu")
		(net "USB_HUB2_MRP_PRT_CTL4_GANGPWR")
	)
	(segment
		(start 124.440188 -42.57675)
		(end 124.440188 -43.59275)
		(width 0.10668)
		(layer "F.Cu")
		(net "USB_HUB2_MRP_PRT_CTL4_GANGPWR")
	)
	(via
		(at 123.25604 -42.77106)
		(size 0.762)
		(drill 0.381)
		(layers "F.Cu" "B.Cu")
		(net "USB_HUB2_MRP_PRT_CTL4_GANGPWR")
	)
	(segment
		(start 103.813864 -37.966904)
		(end 104.74706 -38.9001)
		(width 0.10668)
		(layer "F.Cu")
		(net "USB_HUB2_MRP_PROG_FUNC6")
	)
	(segment
		(start 105.007664 -37.8841)
		(end 104.791764 -37.6682)
		(width 0.10668)
		(layer "F.Cu")
		(net "USB_HUB2_MRP_PROG_FUNC6")
	)
	(segment
		(start 103.813864 -37.6682)
		(end 103.813864 -36.6522)
		(width 0.10668)
		(layer "F.Cu")
		(net "USB_HUB2_MRP_PROG_FUNC6")
	)
	(segment
		(start 104.74706 -38.9001)
		(end 105.007664 -38.9001)
		(width 0.10668)
		(layer "F.Cu")
		(net "USB_HUB2_MRP_PROG_FUNC6")
	)
	(segment
		(start 103.813864 -37.6682)
		(end 103.813864 -37.966904)
		(width 0.10668)
		(layer "F.Cu")
		(net "USB_HUB2_MRP_PROG_FUNC6")
	)
	(segment
		(start 105.007664 -38.9001)
		(end 105.007664 -37.8841)
		(width 0.10668)
		(layer "F.Cu")
		(net "USB_HUB2_MRP_PROG_FUNC6")
	)
	(via
		(at 105.007664 -38.9001)
		(size 0.762)
		(drill 0.381)
		(layers "F.Cu" "B.Cu")
		(net "USB_HUB2_MRP_PROG_FUNC6")
	)
	(segment
		(start 115.410996 -53.49748)
		(end 115.664996 -53.24348)
		(width 0.10668)
		(layer "F.Cu")
		(net "USB_HUB2_MRP_I2C_SLV_CFG1")
	)
	(segment
		(start 117.963696 -53.24348)
		(end 118.217696 -53.49748)
		(width 0.10668)
		(layer "F.Cu")
		(net "USB_HUB2_MRP_I2C_SLV_CFG1")
	)
	(segment
		(start 115.664996 -53.24348)
		(end 116.630196 -53.24348)
		(width 0.10668)
		(layer "F.Cu")
		(net "USB_HUB2_MRP_I2C_SLV_CFG1")
	)
	(segment
		(start 116.630196 -53.24348)
		(end 117.963696 -53.24348)
		(width 0.10668)
		(layer "F.Cu")
		(net "USB_HUB2_MRP_I2C_SLV_CFG1")
	)
	(via
		(at 116.630196 -53.24348)
		(size 0.762)
		(drill 0.381)
		(layers "F.Cu" "B.Cu")
		(net "USB_HUB2_MRP_I2C_SLV_CFG1")
	)
	(segment
		(start 111.251238 -40.7797)
		(end 111.251238 -40.763952)
		(width 0.10668)
		(layer "F.Cu")
		(net "USB_HUB2_MRP_I2C_SLV_CFG0")
	)
	(segment
		(start 111.251238 -40.763952)
		(end 110.770162 -40.282876)
		(width 0.10668)
		(layer "F.Cu")
		(net "USB_HUB2_MRP_I2C_SLV_CFG0")
	)
	(segment
		(start 110.770162 -40.282876)
		(end 111.251238 -39.8018)
		(width 0.10668)
		(layer "F.Cu")
		(net "USB_HUB2_MRP_I2C_SLV_CFG0")
	)
	(via
		(at 110.770162 -40.282876)
		(size 0.508)
		(drill 0.254)
		(layers "F.Cu" "B.Cu")
		(net "USB_HUB2_MRP_I2C_SLV_CFG0")
	)
	(segment
		(start 109.565186 -21.26107)
		(end 109.565186 -20.977606)
		(width 0.10668)
		(layer "F.Cu")
		(net "USB_HUB2_MRP_CFG_STRAP")
	)
	(segment
		(start 109.565186 -20.977606)
		(end 109.663992 -20.8788)
		(width 0.10668)
		(layer "F.Cu")
		(net "USB_HUB2_MRP_CFG_STRAP")
	)
	(segment
		(start 110.152942 -20.38985)
		(end 109.136942 -20.38985)
		(width 0.10668)
		(layer "F.Cu")
		(net "USB_HUB2_MRP_CFG_STRAP")
	)
	(segment
		(start 109.663992 -20.8788)
		(end 110.046262 -20.8788)
		(width 0.10668)
		(layer "F.Cu")
		(net "USB_HUB2_MRP_CFG_STRAP")
	)
	(segment
		(start 110.152942 -21.36775)
		(end 109.671866 -21.36775)
		(width 0.10668)
		(layer "F.Cu")
		(net "USB_HUB2_MRP_CFG_STRAP")
	)
	(segment
		(start 110.152942 -20.77212)
		(end 110.152942 -20.38985)
		(width 0.10668)
		(layer "F.Cu")
		(net "USB_HUB2_MRP_CFG_STRAP")
	)
	(segment
		(start 110.046262 -20.8788)
		(end 110.152942 -20.77212)
		(width 0.10668)
		(layer "F.Cu")
		(net "USB_HUB2_MRP_CFG_STRAP")
	)
	(segment
		(start 109.671866 -21.36775)
		(end 109.565186 -21.26107)
		(width 0.10668)
		(layer "F.Cu")
		(net "USB_HUB2_MRP_CFG_STRAP")
	)
	(via
		(at 109.565186 -20.977606)
		(size 0.508)
		(drill 0.254)
		(layers "F.Cu" "B.Cu")
		(net "USB_HUB2_MRP_CFG_STRAP")
	)
	(segment
		(start 111.3028 -53.872384)
		(end 111.581946 -54.15153)
		(width 0.10668)
		(layer "F.Cu")
		(net "USB_HUB2_MRP_CFG_NON_REM")
	)
	(segment
		(start 111.3028 -53.84546)
		(end 111.3028 -53.872384)
		(width 0.10668)
		(layer "F.Cu")
		(net "USB_HUB2_MRP_CFG_NON_REM")
	)
	(segment
		(start 111.581946 -53.26253)
		(end 111.581946 -53.566314)
		(width 0.10668)
		(layer "F.Cu")
		(net "USB_HUB2_MRP_CFG_NON_REM")
	)
	(segment
		(start 111.581946 -54.15153)
		(end 111.581946 -54.481984)
		(width 0.10668)
		(layer "F.Cu")
		(net "USB_HUB2_MRP_CFG_NON_REM")
	)
	(segment
		(start 111.581946 -53.566314)
		(end 111.3028 -53.84546)
		(width 0.10668)
		(layer "F.Cu")
		(net "USB_HUB2_MRP_CFG_NON_REM")
	)
	(segment
		(start 111.581946 -54.481984)
		(end 110.565946 -54.481984)
		(width 0.10668)
		(layer "F.Cu")
		(net "USB_HUB2_MRP_CFG_NON_REM")
	)
	(via
		(at 111.3028 -53.872384)
		(size 0.508)
		(drill 0.254)
		(layers "F.Cu" "B.Cu")
		(net "USB_HUB2_MRP_CFG_NON_REM")
	)
	(segment
		(start 114.629946 -54.481984)
		(end 113.613946 -54.481984)
		(width 0.10668)
		(layer "F.Cu")
		(net "USB_HUB2_MRP_CFG_BC_EN")
	)
	(segment
		(start 113.918746 -53.857144)
		(end 113.613946 -53.552344)
		(width 0.10668)
		(layer "F.Cu")
		(net "USB_HUB2_MRP_CFG_BC_EN")
	)
	(segment
		(start 113.613946 -54.161944)
		(end 113.918746 -53.857144)
		(width 0.10668)
		(layer "F.Cu")
		(net "USB_HUB2_MRP_CFG_BC_EN")
	)
	(segment
		(start 113.613946 -53.552344)
		(end 113.613946 -53.26253)
		(width 0.10668)
		(layer "F.Cu")
		(net "USB_HUB2_MRP_CFG_BC_EN")
	)
	(segment
		(start 113.613946 -54.481984)
		(end 113.613946 -54.161944)
		(width 0.10668)
		(layer "F.Cu")
		(net "USB_HUB2_MRP_CFG_BC_EN")
	)
	(via
		(at 113.918746 -53.857144)
		(size 0.508)
		(drill 0.254)
		(layers "F.Cu" "B.Cu")
		(net "USB_HUB2_MRP_CFG_BC_EN")
	)
	(segment
		(start 430.780698 -422.630092)
		(end 430.780698 -424.590972)
		(width 0.10668)
		(layer "F.Cu")
		(net "SMB_HSC_TYPE_ADC_SDA")
	)
	(segment
		(start 430.780698 -425.603162)
		(end 430.674018 -425.709842)
		(width 0.10668)
		(layer "F.Cu")
		(net "SMB_HSC_TYPE_ADC_SDA")
	)
	(segment
		(start 365.887 -410.21)
		(end 366.014 -410.083)
		(width 0.10668)
		(layer "F.Cu")
		(net "SMB_HSC_TYPE_ADC_SDA")
	)
	(segment
		(start 365.887 -410.82595)
		(end 365.887 -410.21)
		(width 0.10668)
		(layer "F.Cu")
		(net "SMB_HSC_TYPE_ADC_SDA")
	)
	(segment
		(start 430.026064 -421.875458)
		(end 430.780698 -422.630092)
		(width 0.10668)
		(layer "F.Cu")
		(net "SMB_HSC_TYPE_ADC_SDA")
	)
	(segment
		(start 430.081182 -425.709842)
		(end 429.774604 -426.01642)
		(width 0.10668)
		(layer "F.Cu")
		(net "SMB_HSC_TYPE_ADC_SDA")
	)
	(segment
		(start 429.774604 -426.01642)
		(end 429.774604 -426.906182)
		(width 0.10668)
		(layer "F.Cu")
		(net "SMB_HSC_TYPE_ADC_SDA")
	)
	(segment
		(start 427.739048 -423.206164)
		(end 427.739048 -422.932098)
		(width 0.10668)
		(layer "F.Cu")
		(net "SMB_HSC_TYPE_ADC_SDA")
	)
	(segment
		(start 430.674018 -425.709842)
		(end 430.081182 -425.709842)
		(width 0.10668)
		(layer "F.Cu")
		(net "SMB_HSC_TYPE_ADC_SDA")
	)
	(segment
		(start 428.117 -422.554146)
		(end 428.795688 -421.875458)
		(width 0.10668)
		(layer "F.Cu")
		(net "SMB_HSC_TYPE_ADC_SDA")
	)
	(segment
		(start 427.739048 -422.932098)
		(end 428.117 -422.554146)
		(width 0.10668)
		(layer "F.Cu")
		(net "SMB_HSC_TYPE_ADC_SDA")
	)
	(segment
		(start 430.780698 -424.590972)
		(end 430.780698 -425.603162)
		(width 0.10668)
		(layer "F.Cu")
		(net "SMB_HSC_TYPE_ADC_SDA")
	)
	(segment
		(start 428.795688 -421.875458)
		(end 430.026064 -421.875458)
		(width 0.10668)
		(layer "F.Cu")
		(net "SMB_HSC_TYPE_ADC_SDA")
	)
	(via
		(at 366.014 -410.083)
		(size 0.508)
		(drill 0.254)
		(layers "F.Cu" "B.Cu")
		(net "SMB_HSC_TYPE_ADC_SDA")
	)
	(via
		(at 430.780698 -424.590972)
		(size 0.508)
		(drill 0.254)
		(layers "F.Cu" "B.Cu")
		(net "SMB_HSC_TYPE_ADC_SDA")
	)
	(via
		(at 428.117 -422.554146)
		(size 0.508)
		(drill 0.254)
		(layers "F.Cu" "B.Cu")
		(net "SMB_HSC_TYPE_ADC_SDA")
	)
	(segment
		(start 366.014 -410.083)
		(end 366.014 -409.575)
		(width 0.11684)
		(layer "In2.Cu")
		(net "SMB_HSC_TYPE_ADC_SDA")
	)
	(segment
		(start 366.714532 -408.874468)
		(end 367.478056 -408.874468)
		(width 0.11684)
		(layer "In2.Cu")
		(net "SMB_HSC_TYPE_ADC_SDA")
	)
	(segment
		(start 419.659308 -409.049474)
		(end 422.469818 -411.859984)
		(width 0.11684)
		(layer "In2.Cu")
		(net "SMB_HSC_TYPE_ADC_SDA")
	)
	(segment
		(start 367.653062 -409.049474)
		(end 419.659308 -409.049474)
		(width 0.11684)
		(layer "In2.Cu")
		(net "SMB_HSC_TYPE_ADC_SDA")
	)
	(segment
		(start 428.117 -421.896794)
		(end 428.117 -422.554146)
		(width 0.11684)
		(layer "In2.Cu")
		(net "SMB_HSC_TYPE_ADC_SDA")
	)
	(segment
		(start 427.671738 -421.451532)
		(end 428.117 -421.896794)
		(width 0.11684)
		(layer "In2.Cu")
		(net "SMB_HSC_TYPE_ADC_SDA")
	)
	(segment
		(start 367.478056 -408.874468)
		(end 367.653062 -409.049474)
		(width 0.11684)
		(layer "In2.Cu")
		(net "SMB_HSC_TYPE_ADC_SDA")
	)
	(segment
		(start 366.014 -409.575)
		(end 366.714532 -408.874468)
		(width 0.11684)
		(layer "In2.Cu")
		(net "SMB_HSC_TYPE_ADC_SDA")
	)
	(segment
		(start 422.469818 -419.836346)
		(end 424.085004 -421.451532)
		(width 0.11684)
		(layer "In2.Cu")
		(net "SMB_HSC_TYPE_ADC_SDA")
	)
	(segment
		(start 422.469818 -411.859984)
		(end 422.469818 -419.836346)
		(width 0.11684)
		(layer "In2.Cu")
		(net "SMB_HSC_TYPE_ADC_SDA")
	)
	(segment
		(start 424.085004 -421.451532)
		(end 427.671738 -421.451532)
		(width 0.11684)
		(layer "In2.Cu")
		(net "SMB_HSC_TYPE_ADC_SDA")
	)
	(segment
		(start 432.303936 -424.590972)
		(end 432.303936 -426.052234)
		(width 0.10668)
		(layer "F.Cu")
		(net "SMB_HSC_TYPE_ADC_SCL")
	)
	(segment
		(start 432.303936 -426.052234)
		(end 430.800002 -427.556168)
		(width 0.10668)
		(layer "F.Cu")
		(net "SMB_HSC_TYPE_ADC_SCL")
	)
	(segment
		(start 430.800002 -427.556168)
		(end 430.42459 -427.556168)
		(width 0.10668)
		(layer "F.Cu")
		(net "SMB_HSC_TYPE_ADC_SCL")
	)
	(segment
		(start 367.157 -410.82595)
		(end 367.157 -410.083)
		(width 0.10668)
		(layer "F.Cu")
		(net "SMB_HSC_TYPE_ADC_SCL")
	)
	(via
		(at 367.157 -410.083)
		(size 0.508)
		(drill 0.254)
		(layers "F.Cu" "B.Cu")
		(net "SMB_HSC_TYPE_ADC_SCL")
	)
	(via
		(at 432.303936 -424.590972)
		(size 0.508)
		(drill 0.254)
		(layers "F.Cu" "B.Cu")
		(net "SMB_HSC_TYPE_ADC_SCL")
	)
	(segment
		(start 427.644306 -422.861994)
		(end 428.16018 -423.377868)
		(width 0.11684)
		(layer "In2.Cu")
		(net "SMB_HSC_TYPE_ADC_SCL")
	)
	(segment
		(start 422.024048 -419.986968)
		(end 424.009058 -421.971978)
		(width 0.11684)
		(layer "In2.Cu")
		(net "SMB_HSC_TYPE_ADC_SCL")
	)
	(segment
		(start 427.644306 -422.300654)
		(end 427.644306 -422.861994)
		(width 0.11684)
		(layer "In2.Cu")
		(net "SMB_HSC_TYPE_ADC_SCL")
	)
	(segment
		(start 419.550596 -409.537154)
		(end 422.024048 -412.010606)
		(width 0.11684)
		(layer "In2.Cu")
		(net "SMB_HSC_TYPE_ADC_SCL")
	)
	(segment
		(start 427.31563 -421.971978)
		(end 427.644306 -422.300654)
		(width 0.11684)
		(layer "In2.Cu")
		(net "SMB_HSC_TYPE_ADC_SCL")
	)
	(segment
		(start 424.009058 -421.971978)
		(end 427.31563 -421.971978)
		(width 0.11684)
		(layer "In2.Cu")
		(net "SMB_HSC_TYPE_ADC_SCL")
	)
	(segment
		(start 422.024048 -412.010606)
		(end 422.024048 -419.986968)
		(width 0.11684)
		(layer "In2.Cu")
		(net "SMB_HSC_TYPE_ADC_SCL")
	)
	(segment
		(start 368.177318 -409.537154)
		(end 419.550596 -409.537154)
		(width 0.11684)
		(layer "In2.Cu")
		(net "SMB_HSC_TYPE_ADC_SCL")
	)
	(segment
		(start 367.157 -410.083)
		(end 367.631472 -410.083)
		(width 0.11684)
		(layer "In2.Cu")
		(net "SMB_HSC_TYPE_ADC_SCL")
	)
	(segment
		(start 367.631472 -410.083)
		(end 368.177318 -409.537154)
		(width 0.11684)
		(layer "In2.Cu")
		(net "SMB_HSC_TYPE_ADC_SCL")
	)
	(segment
		(start 431.090832 -423.377868)
		(end 432.303936 -424.590972)
		(width 0.11684)
		(layer "In2.Cu")
		(net "SMB_HSC_TYPE_ADC_SCL")
	)
	(segment
		(start 428.16018 -423.377868)
		(end 431.090832 -423.377868)
		(width 0.11684)
		(layer "In2.Cu")
		(net "SMB_HSC_TYPE_ADC_SCL")
	)
	(segment
		(start 125.14199 -40.89273)
		(end 125.030484 -41.16197)
		(width 0.381)
		(layer "F.Cu")
		(net "P3V3_AUX_CPU0_USB2_AVDD33")
	)
	(segment
		(start 125.14199 -40.892476)
		(end 125.14199 -40.89273)
		(width 0.381)
		(layer "F.Cu")
		(net "P3V3_AUX_CPU0_USB2_AVDD33")
	)
	(segment
		(start 124.612654 -41.5798)
		(end 124.459238 -41.5798)
		(width 0.381)
		(layer "F.Cu")
		(net "P3V3_AUX_CPU0_USB2_AVDD33")
	)
	(segment
		(start 107.819444 -33.74771)
		(end 107.717844 -33.84931)
		(width 0.1778)
		(layer "F.Cu")
		(net "P3V3_AUX_CPU0_USB2_AVDD33")
	)
	(segment
		(start 121.3104 -25.545796)
		(end 121.7676 -25.088596)
		(width 0.4572)
		(layer "F.Cu")
		(net "P3V3_AUX_CPU0_USB2_AVDD33")
	)
	(segment
		(start 108.398818 -28.247848)
		(end 107.812078 -28.247848)
		(width 0.254)
		(layer "F.Cu")
		(net "P3V3_AUX_CPU0_USB2_AVDD33")
	)
	(segment
		(start 118.94312 -36.2712)
		(end 119.38254 -35.83178)
		(width 0.4572)
		(layer "F.Cu")
		(net "P3V3_AUX_CPU0_USB2_AVDD33")
	)
	(segment
		(start 107.812078 -28.247848)
		(end 107.717336 -28.153106)
		(width 0.254)
		(layer "F.Cu")
		(net "P3V3_AUX_CPU0_USB2_AVDD33")
	)
	(segment
		(start 118.5164 -36.2712)
		(end 118.94312 -36.2712)
		(width 0.4572)
		(layer "F.Cu")
		(net "P3V3_AUX_CPU0_USB2_AVDD33")
	)
	(segment
		(start 121.0818 -23.005796)
		(end 121.7676 -23.005796)
		(width 0.4572)
		(layer "F.Cu")
		(net "P3V3_AUX_CPU0_USB2_AVDD33")
	)
	(segment
		(start 121.0818 -25.545796)
		(end 121.3104 -25.545796)
		(width 0.4572)
		(layer "F.Cu")
		(net "P3V3_AUX_CPU0_USB2_AVDD33")
	)
	(segment
		(start 125.030484 -41.16197)
		(end 124.612654 -41.5798)
		(width 0.381)
		(layer "F.Cu")
		(net "P3V3_AUX_CPU0_USB2_AVDD33")
	)
	(segment
		(start 108.398818 -33.74771)
		(end 107.819444 -33.74771)
		(width 0.1778)
		(layer "F.Cu")
		(net "P3V3_AUX_CPU0_USB2_AVDD33")
	)
	(segment
		(start 121.7676 -25.088596)
		(end 121.7676 -24.783796)
		(width 0.4572)
		(layer "F.Cu")
		(net "P3V3_AUX_CPU0_USB2_AVDD33")
	)
	(via
		(at 121.7676 -24.783796)
		(size 0.508)
		(drill 0.254)
		(layers "F.Cu" "B.Cu")
		(net "P3V3_AUX_CPU0_USB2_AVDD33")
	)
	(via
		(at 107.717844 -33.84931)
		(size 0.508)
		(drill 0.254)
		(layers "F.Cu" "B.Cu")
		(net "P3V3_AUX_CPU0_USB2_AVDD33")
	)
	(via
		(at 107.717336 -28.153106)
		(size 0.508)
		(drill 0.254)
		(layers "F.Cu" "B.Cu")
		(net "P3V3_AUX_CPU0_USB2_AVDD33")
	)
	(via
		(at 121.7676 -23.005796)
		(size 0.508)
		(drill 0.254)
		(layers "F.Cu" "B.Cu")
		(net "P3V3_AUX_CPU0_USB2_AVDD33")
	)
	(via
		(at 125.14199 -40.892476)
		(size 0.508)
		(drill 0.254)
		(layers "F.Cu" "B.Cu")
		(net "P3V3_AUX_CPU0_USB2_AVDD33")
	)
	(via
		(at 119.38254 -35.83178)
		(size 0.508)
		(drill 0.254)
		(layers "F.Cu" "B.Cu")
		(net "P3V3_AUX_CPU0_USB2_AVDD33")
	)
	(segment
		(start 121.334276 -40.892476)
		(end 125.14199 -40.892476)
		(width 0.4572)
		(layer "In4.Cu")
		(net "P3V3_AUX_CPU0_USB2_AVDD33")
	)
	(segment
		(start 119.38254 -35.83178)
		(end 119.1006 -36.11372)
		(width 0.4572)
		(layer "In4.Cu")
		(net "P3V3_AUX_CPU0_USB2_AVDD33")
	)
	(segment
		(start 119.1006 -36.11372)
		(end 119.1006 -38.6588)
		(width 0.4572)
		(layer "In4.Cu")
		(net "P3V3_AUX_CPU0_USB2_AVDD33")
	)
	(segment
		(start 119.1006 -38.6588)
		(end 121.334276 -40.892476)
		(width 0.4572)
		(layer "In4.Cu")
		(net "P3V3_AUX_CPU0_USB2_AVDD33")
	)
	(segment
		(start 112.438942 -21.36775)
		(end 111.422942 -21.36775)
		(width 0.381)
		(layer "F.Cu")
		(net "P1V2_CPU0_USB2_DVDD12")
	)
	(segment
		(start 108.398818 -34.247836)
		(end 108.340398 -34.247836)
		(width 0.1778)
		(layer "F.Cu")
		(net "P1V2_CPU0_USB2_DVDD12")
	)
	(segment
		(start 121.00052 -45.31868)
		(end 122.427238 -43.891962)
		(width 0.381)
		(layer "F.Cu")
		(net "P1V2_CPU0_USB2_DVDD12")
	)
	(segment
		(start 107.459272 -34.61258)
		(end 107.41406 -34.7218)
		(width 0.1778)
		(layer "F.Cu")
		(net "P1V2_CPU0_USB2_DVDD12")
	)
	(segment
		(start 121.09831 -31.405576)
		(end 121.78411 -31.405576)
		(width 0.4572)
		(layer "F.Cu")
		(net "P1V2_CPU0_USB2_DVDD12")
	)
	(segment
		(start 121.09831 -30.389576)
		(end 121.78411 -30.389576)
		(width 0.4572)
		(layer "F.Cu")
		(net "P1V2_CPU0_USB2_DVDD12")
	)
	(segment
		(start 121.677176 -28.085796)
		(end 121.7676 -28.17622)
		(width 0.4572)
		(layer "F.Cu")
		(net "P1V2_CPU0_USB2_DVDD12")
	)
	(segment
		(start 110.235238 -43.358054)
		(end 110.235238 -43.974258)
		(width 0.381)
		(layer "F.Cu")
		(net "P1V2_CPU0_USB2_DVDD12")
	)
	(segment
		(start 111.422942 -19.58975)
		(end 112.060228 -19.58975)
		(width 0.381)
		(layer "F.Cu")
		(net "P1V2_CPU0_USB2_DVDD12")
	)
	(segment
		(start 115.048792 -26.416762)
		(end 115.048792 -27.097736)
		(width 0.1778)
		(layer "F.Cu")
		(net "P1V2_CPU0_USB2_DVDD12")
	)
	(segment
		(start 121.0818 -28.085796)
		(end 121.677176 -28.085796)
		(width 0.4572)
		(layer "F.Cu")
		(net "P1V2_CPU0_USB2_DVDD12")
	)
	(segment
		(start 112.589564 -21.36775)
		(end 112.438942 -21.36775)
		(width 0.381)
		(layer "F.Cu")
		(net "P1V2_CPU0_USB2_DVDD12")
	)
	(segment
		(start 113.097818 -20.859496)
		(end 112.589564 -21.36775)
		(width 0.381)
		(layer "F.Cu")
		(net "P1V2_CPU0_USB2_DVDD12")
	)
	(segment
		(start 108.340398 -34.247836)
		(end 107.459272 -34.61258)
		(width 0.1778)
		(layer "F.Cu")
		(net "P1V2_CPU0_USB2_DVDD12")
	)
	(segment
		(start 111.57966 -45.31868)
		(end 121.00052 -45.31868)
		(width 0.381)
		(layer "F.Cu")
		(net "P1V2_CPU0_USB2_DVDD12")
	)
	(segment
		(start 122.427238 -43.891962)
		(end 122.427238 -41.5798)
		(width 0.381)
		(layer "F.Cu")
		(net "P1V2_CPU0_USB2_DVDD12")
	)
	(segment
		(start 121.09831 -29.373576)
		(end 121.78411 -29.373576)
		(width 0.4572)
		(layer "F.Cu")
		(net "P1V2_CPU0_USB2_DVDD12")
	)
	(segment
		(start 110.235238 -43.974258)
		(end 111.57966 -45.31868)
		(width 0.381)
		(layer "F.Cu")
		(net "P1V2_CPU0_USB2_DVDD12")
	)
	(segment
		(start 107.717844 -31.247842)
		(end 108.398818 -31.247842)
		(width 0.1778)
		(layer "F.Cu")
		(net "P1V2_CPU0_USB2_DVDD12")
	)
	(segment
		(start 121.0818 -24.275796)
		(end 121.3358 -24.021796)
		(width 0.4572)
		(layer "F.Cu")
		(net "P1V2_CPU0_USB2_DVDD12")
	)
	(segment
		(start 121.0818 -26.815796)
		(end 121.0818 -28.085796)
		(width 0.381)
		(layer "F.Cu")
		(net "P1V2_CPU0_USB2_DVDD12")
	)
	(segment
		(start 121.3358 -24.021796)
		(end 121.7676 -24.021796)
		(width 0.4572)
		(layer "F.Cu")
		(net "P1V2_CPU0_USB2_DVDD12")
	)
	(via
		(at 121.78411 -30.389576)
		(size 0.508)
		(drill 0.254)
		(layers "F.Cu" "B.Cu")
		(net "P1V2_CPU0_USB2_DVDD12")
	)
	(via
		(at 113.097818 -20.859496)
		(size 0.508)
		(drill 0.254)
		(layers "F.Cu" "B.Cu")
		(net "P1V2_CPU0_USB2_DVDD12")
	)
	(via
		(at 107.41406 -34.7218)
		(size 0.508)
		(drill 0.254)
		(layers "F.Cu" "B.Cu")
		(net "P1V2_CPU0_USB2_DVDD12")
	)
	(via
		(at 112.060228 -19.58975)
		(size 0.508)
		(drill 0.254)
		(layers "F.Cu" "B.Cu")
		(net "P1V2_CPU0_USB2_DVDD12")
	)
	(via
		(at 115.048792 -26.416762)
		(size 0.508)
		(drill 0.254)
		(layers "F.Cu" "B.Cu")
		(net "P1V2_CPU0_USB2_DVDD12")
	)
	(via
		(at 121.7676 -28.17622)
		(size 0.508)
		(drill 0.254)
		(layers "F.Cu" "B.Cu")
		(net "P1V2_CPU0_USB2_DVDD12")
	)
	(via
		(at 121.78411 -31.405576)
		(size 0.508)
		(drill 0.254)
		(layers "F.Cu" "B.Cu")
		(net "P1V2_CPU0_USB2_DVDD12")
	)
	(via
		(at 121.78411 -29.373576)
		(size 0.508)
		(drill 0.254)
		(layers "F.Cu" "B.Cu")
		(net "P1V2_CPU0_USB2_DVDD12")
	)
	(via
		(at 110.235238 -43.358054)
		(size 0.508)
		(drill 0.254)
		(layers "F.Cu" "B.Cu")
		(net "P1V2_CPU0_USB2_DVDD12")
	)
	(via
		(at 121.7676 -24.021796)
		(size 0.508)
		(drill 0.254)
		(layers "F.Cu" "B.Cu")
		(net "P1V2_CPU0_USB2_DVDD12")
	)
	(via
		(at 107.717844 -31.247842)
		(size 0.508)
		(drill 0.254)
		(layers "F.Cu" "B.Cu")
		(net "P1V2_CPU0_USB2_DVDD12")
	)
	(segment
		(start 110.235238 -43.358054)
		(end 108.559854 -43.358054)
		(width 0.4572)
		(layer "In4.Cu")
		(net "P1V2_CPU0_USB2_DVDD12")
	)
	(segment
		(start 107.726988 -42.525188)
		(end 107.726988 -35.034728)
		(width 0.4572)
		(layer "In4.Cu")
		(net "P1V2_CPU0_USB2_DVDD12")
	)
	(segment
		(start 108.559854 -43.358054)
		(end 107.726988 -42.525188)
		(width 0.4572)
		(layer "In4.Cu")
		(net "P1V2_CPU0_USB2_DVDD12")
	)
	(segment
		(start 107.726988 -35.034728)
		(end 107.41406 -34.7218)
		(width 0.4572)
		(layer "In4.Cu")
		(net "P1V2_CPU0_USB2_DVDD12")
	)
	(segment
		(start 427.232318 -429.056292)
		(end 425.804838 -430.483772)
		(width 0.10668)
		(layer "F.Cu")
		(net "NC_HSC_TYPE_VINP")
	)
	(segment
		(start 427.624494 -429.056292)
		(end 427.232318 -429.056292)
		(width 0.10668)
		(layer "F.Cu")
		(net "NC_HSC_TYPE_VINP")
	)
	(via
		(at 425.804838 -430.483772)
		(size 0.762)
		(drill 0.381)
		(layers "F.Cu" "B.Cu")
		(net "NC_HSC_TYPE_VINP")
	)
	(segment
		(start 428.27448 -430.05121)
		(end 427.968918 -430.356772)
		(width 0.10668)
		(layer "F.Cu")
		(net "NC_HSC_TYPE_VINM")
	)
	(segment
		(start 428.27448 -429.706278)
		(end 428.27448 -430.05121)
		(width 0.10668)
		(layer "F.Cu")
		(net "NC_HSC_TYPE_VINM")
	)
	(segment
		(start 427.968918 -430.356772)
		(end 427.201838 -430.356772)
		(width 0.10668)
		(layer "F.Cu")
		(net "NC_HSC_TYPE_VINM")
	)
	(segment
		(start 427.201838 -430.356772)
		(end 425.804838 -431.753772)
		(width 0.10668)
		(layer "F.Cu")
		(net "NC_HSC_TYPE_VINM")
	)
	(via
		(at 425.804838 -431.753772)
		(size 0.762)
		(drill 0.381)
		(layers "F.Cu" "B.Cu")
		(net "NC_HSC_TYPE_VINM")
	)
	(segment
		(start 427.5328 -427.556168)
		(end 427.624494 -427.556168)
		(width 0.10668)
		(layer "F.Cu")
		(net "NC_HSC_TYPE_NC5")
	)
	(segment
		(start 427.4058 -427.429168)
		(end 427.5328 -427.556168)
		(width 0.10668)
		(layer "F.Cu")
		(net "NC_HSC_TYPE_NC5")
	)
	(segment
		(start 427.4058 -426.409612)
		(end 427.4058 -427.429168)
		(width 0.10668)
		(layer "F.Cu")
		(net "NC_HSC_TYPE_NC5")
	)
	(segment
		(start 426.19422 -426.54347)
		(end 426.5041 -426.23359)
		(width 0.10668)
		(layer "F.Cu")
		(net "NC_HSC_TYPE_NC5")
	)
	(segment
		(start 426.5041 -426.23359)
		(end 427.229778 -426.23359)
		(width 0.10668)
		(layer "F.Cu")
		(net "NC_HSC_TYPE_NC5")
	)
	(segment
		(start 427.229778 -426.23359)
		(end 427.4058 -426.409612)
		(width 0.10668)
		(layer "F.Cu")
		(net "NC_HSC_TYPE_NC5")
	)
	(via
		(at 426.19422 -426.54347)
		(size 0.762)
		(drill 0.381)
		(layers "F.Cu" "B.Cu")
		(net "NC_HSC_TYPE_NC5")
	)
	(segment
		(start 425.96816 -428.107094)
		(end 425.804838 -427.943772)
		(width 0.10668)
		(layer "F.Cu")
		(net "NC_HSC_TYPE_NC4")
	)
	(segment
		(start 427.001686 -428.107094)
		(end 425.96816 -428.107094)
		(width 0.10668)
		(layer "F.Cu")
		(net "NC_HSC_TYPE_NC4")
	)
	(segment
		(start 427.624494 -428.056294)
		(end 427.052486 -428.056294)
		(width 0.10668)
		(layer "F.Cu")
		(net "NC_HSC_TYPE_NC4")
	)
	(segment
		(start 427.052486 -428.056294)
		(end 427.001686 -428.107094)
		(width 0.10668)
		(layer "F.Cu")
		(net "NC_HSC_TYPE_NC4")
	)
	(via
		(at 425.804838 -427.943772)
		(size 0.762)
		(drill 0.381)
		(layers "F.Cu" "B.Cu")
		(net "NC_HSC_TYPE_NC4")
	)
	(segment
		(start 427.624494 -428.556166)
		(end 427.2915 -428.556166)
		(width 0.10668)
		(layer "F.Cu")
		(net "NC_HSC_TYPE_NC3")
	)
	(segment
		(start 426.633894 -429.213772)
		(end 425.804838 -429.213772)
		(width 0.10668)
		(layer "F.Cu")
		(net "NC_HSC_TYPE_NC3")
	)
	(segment
		(start 427.2915 -428.556166)
		(end 426.633894 -429.213772)
		(width 0.10668)
		(layer "F.Cu")
		(net "NC_HSC_TYPE_NC3")
	)
	(via
		(at 425.804838 -429.213772)
		(size 0.762)
		(drill 0.381)
		(layers "F.Cu" "B.Cu")
		(net "NC_HSC_TYPE_NC3")
	)
	(segment
		(start 431.056034 -429.056292)
		(end 431.956718 -429.956976)
		(width 0.10668)
		(layer "F.Cu")
		(net "NC_HSC_TYPE_NC2")
	)
	(segment
		(start 430.42459 -429.056292)
		(end 431.056034 -429.056292)
		(width 0.10668)
		(layer "F.Cu")
		(net "NC_HSC_TYPE_NC2")
	)
	(via
		(at 431.956718 -429.956976)
		(size 0.762)
		(drill 0.381)
		(layers "F.Cu" "B.Cu")
		(net "NC_HSC_TYPE_NC2")
	)
	(segment
		(start 430.42459 -428.556166)
		(end 431.164238 -428.556166)
		(width 0.10668)
		(layer "F.Cu")
		(net "NC_HSC_TYPE_NC1")
	)
	(segment
		(start 431.164238 -428.556166)
		(end 431.295048 -428.686976)
		(width 0.10668)
		(layer "F.Cu")
		(net "NC_HSC_TYPE_NC1")
	)
	(segment
		(start 431.295048 -428.686976)
		(end 431.956718 -428.686976)
		(width 0.10668)
		(layer "F.Cu")
		(net "NC_HSC_TYPE_NC1")
	)
	(via
		(at 431.956718 -428.686976)
		(size 0.762)
		(drill 0.381)
		(layers "F.Cu" "B.Cu")
		(net "NC_HSC_TYPE_NC1")
	)
	(segment
		(start 429.274478 -425.337986)
		(end 429.274478 -426.906182)
		(width 0.10668)
		(layer "F.Cu")
		(net "HSC_TYPE_ADC_ALERT")
	)
	(segment
		(start 429.87341 -424.00601)
		(end 429.87341 -424.616626)
		(width 0.10668)
		(layer "F.Cu")
		(net "HSC_TYPE_ADC_ALERT")
	)
	(segment
		(start 429.213264 -425.276772)
		(end 429.274478 -425.337986)
		(width 0.10668)
		(layer "F.Cu")
		(net "HSC_TYPE_ADC_ALERT")
	)
	(segment
		(start 429.87341 -424.616626)
		(end 429.213264 -425.276772)
		(width 0.10668)
		(layer "F.Cu")
		(net "HSC_TYPE_ADC_ALERT")
	)
	(via
		(at 429.213264 -425.276772)
		(size 0.762)
		(drill 0.381)
		(layers "F.Cu" "B.Cu")
		(net "HSC_TYPE_ADC_ALERT")
	)
	(segment
		(start 426.673264 -425.276772)
		(end 427.079664 -425.683172)
		(width 0.10668)
		(layer "F.Cu")
		(net "HSC_TYPE_ADC_A1")
	)
	(segment
		(start 428.27448 -426.512228)
		(end 428.27448 -426.906182)
		(width 0.10668)
		(layer "F.Cu")
		(net "HSC_TYPE_ADC_A1")
	)
	(segment
		(start 427.445424 -425.683172)
		(end 428.27448 -426.512228)
		(width 0.10668)
		(layer "F.Cu")
		(net "HSC_TYPE_ADC_A1")
	)
	(segment
		(start 427.079664 -425.683172)
		(end 427.445424 -425.683172)
		(width 0.10668)
		(layer "F.Cu")
		(net "HSC_TYPE_ADC_A1")
	)
	(segment
		(start 426.673264 -424.022012)
		(end 426.673264 -425.276772)
		(width 0.10668)
		(layer "F.Cu")
		(net "HSC_TYPE_ADC_A1")
	)
	(via
		(at 426.673264 -425.276772)
		(size 0.762)
		(drill 0.381)
		(layers "F.Cu" "B.Cu")
		(net "HSC_TYPE_ADC_A1")
	)
	(segment
		(start 428.813722 -424.021758)
		(end 428.813722 -424.406314)
		(width 0.10668)
		(layer "F.Cu")
		(net "HSC_TYPE_ADC_A0")
	)
	(segment
		(start 428.813722 -424.021758)
		(end 427.754542 -424.021758)
		(width 0.10668)
		(layer "F.Cu")
		(net "HSC_TYPE_ADC_A0")
	)
	(segment
		(start 427.943264 -425.276772)
		(end 428.774606 -426.108114)
		(width 0.10668)
		(layer "F.Cu")
		(net "HSC_TYPE_ADC_A0")
	)
	(segment
		(start 428.774606 -426.108114)
		(end 428.774606 -426.906182)
		(width 0.10668)
		(layer "F.Cu")
		(net "HSC_TYPE_ADC_A0")
	)
	(segment
		(start 428.813722 -424.406314)
		(end 427.943264 -425.276772)
		(width 0.10668)
		(layer "F.Cu")
		(net "HSC_TYPE_ADC_A0")
	)
	(segment
		(start 427.754542 -424.021758)
		(end 427.739048 -424.006264)
		(width 0.10668)
		(layer "F.Cu")
		(net "HSC_TYPE_ADC_A0")
	)
	(via
		(at 427.943264 -425.276772)
		(size 0.762)
		(drill 0.381)
		(layers "F.Cu" "B.Cu")
		(net "HSC_TYPE_ADC_A0")
	)
	(segment
		(start 130.294126 -33.023556)
		(end 130.294126 -31.880556)
		(width 0.10668)
		(layer "F.Cu")
		(net "XTAL_USB_CPU0_HUB1_XOUT")
	)
	(segment
		(start 127.943864 -29.530294)
		(end 127.171196 -29.530294)
		(width 0.10668)
		(layer "F.Cu")
		(net "XTAL_USB_CPU0_HUB1_XOUT")
	)
	(segment
		(start 126.571756 -29.297122)
		(end 126.938024 -29.297122)
		(width 0.10668)
		(layer "F.Cu")
		(net "XTAL_USB_CPU0_HUB1_XOUT")
	)
	(segment
		(start 126.938024 -29.297122)
		(end 127.171196 -29.530294)
		(width 0.10668)
		(layer "F.Cu")
		(net "XTAL_USB_CPU0_HUB1_XOUT")
	)
	(segment
		(start 126.571756 -29.297122)
		(end 126.366016 -29.091382)
		(width 0.10668)
		(layer "F.Cu")
		(net "XTAL_USB_CPU0_HUB1_XOUT")
	)
	(segment
		(start 130.294126 -31.880556)
		(end 127.943864 -29.530294)
		(width 0.10668)
		(layer "F.Cu")
		(net "XTAL_USB_CPU0_HUB1_XOUT")
	)
	(segment
		(start 124.373386 -29.091382)
		(end 123.685046 -29.779722)
		(width 0.10668)
		(layer "F.Cu")
		(net "XTAL_USB_CPU0_HUB1_XOUT")
	)
	(segment
		(start 126.366016 -29.091382)
		(end 124.373386 -29.091382)
		(width 0.10668)
		(layer "F.Cu")
		(net "XTAL_USB_CPU0_HUB1_XOUT")
	)
	(via
		(at 127.171196 -29.530294)
		(size 0.508)
		(drill 0.254)
		(layers "F.Cu" "B.Cu")
		(net "XTAL_USB_CPU0_HUB1_XOUT")
	)
	(segment
		(start 127.6985 -28.264104)
		(end 127.697992 -28.263596)
		(width 0.10668)
		(layer "F.Cu")
		(net "XTAL_USB_CPU0_HUB1_XIN")
	)
	(segment
		(start 124.884434 -28.617926)
		(end 126.028196 -28.617926)
		(width 0.10668)
		(layer "F.Cu")
		(net "XTAL_USB_CPU0_HUB1_XIN")
	)
	(segment
		(start 130.694176 -33.023556)
		(end 130.694176 -31.779972)
		(width 0.10668)
		(layer "F.Cu")
		(net "XTAL_USB_CPU0_HUB1_XIN")
	)
	(segment
		(start 126.382526 -28.263596)
		(end 126.58979 -28.263596)
		(width 0.10668)
		(layer "F.Cu")
		(net "XTAL_USB_CPU0_HUB1_XIN")
	)
	(segment
		(start 124.918978 -27.929586)
		(end 124.777754 -28.07081)
		(width 0.10668)
		(layer "F.Cu")
		(net "XTAL_USB_CPU0_HUB1_XIN")
	)
	(segment
		(start 126.028196 -28.617926)
		(end 126.382526 -28.263596)
		(width 0.10668)
		(layer "F.Cu")
		(net "XTAL_USB_CPU0_HUB1_XIN")
	)
	(segment
		(start 129.375154 -30.46095)
		(end 129.375154 -29.502354)
		(width 0.10668)
		(layer "F.Cu")
		(net "XTAL_USB_CPU0_HUB1_XIN")
	)
	(segment
		(start 124.777754 -28.07081)
		(end 124.777754 -28.511246)
		(width 0.10668)
		(layer "F.Cu")
		(net "XTAL_USB_CPU0_HUB1_XIN")
	)
	(segment
		(start 124.777754 -28.511246)
		(end 124.884434 -28.617926)
		(width 0.10668)
		(layer "F.Cu")
		(net "XTAL_USB_CPU0_HUB1_XIN")
	)
	(segment
		(start 125.234954 -27.929586)
		(end 124.918978 -27.929586)
		(width 0.10668)
		(layer "F.Cu")
		(net "XTAL_USB_CPU0_HUB1_XIN")
	)
	(segment
		(start 130.694176 -31.779972)
		(end 129.375154 -30.46095)
		(width 0.10668)
		(layer "F.Cu")
		(net "XTAL_USB_CPU0_HUB1_XIN")
	)
	(segment
		(start 129.375154 -29.502354)
		(end 128.136904 -28.264104)
		(width 0.10668)
		(layer "F.Cu")
		(net "XTAL_USB_CPU0_HUB1_XIN")
	)
	(segment
		(start 127.697992 -28.263596)
		(end 126.58979 -28.263596)
		(width 0.10668)
		(layer "F.Cu")
		(net "XTAL_USB_CPU0_HUB1_XIN")
	)
	(segment
		(start 128.136904 -28.264104)
		(end 127.6985 -28.264104)
		(width 0.10668)
		(layer "F.Cu")
		(net "XTAL_USB_CPU0_HUB1_XIN")
	)
	(via
		(at 127.6985 -28.264104)
		(size 0.508)
		(drill 0.254)
		(layers "F.Cu" "B.Cu")
		(net "XTAL_USB_CPU0_HUB1_XIN")
	)
	(segment
		(start 138.801094 -39.793418)
		(end 140.020294 -39.793418)
		(width 0.10668)
		(layer "F.Cu")
		(net "USB_CPU0_HUB1_VBUS_US")
	)
	(segment
		(start 137.106406 -40.073326)
		(end 137.42924 -40.39616)
		(width 0.10668)
		(layer "F.Cu")
		(net "USB_CPU0_HUB1_VBUS_US")
	)
	(segment
		(start 137.42924 -40.39616)
		(end 138.198352 -40.39616)
		(width 0.10668)
		(layer "F.Cu")
		(net "USB_CPU0_HUB1_VBUS_US")
	)
	(segment
		(start 136.694164 -40.073326)
		(end 137.106406 -40.073326)
		(width 0.10668)
		(layer "F.Cu")
		(net "USB_CPU0_HUB1_VBUS_US")
	)
	(segment
		(start 138.198352 -40.39616)
		(end 138.801094 -39.793418)
		(width 0.10668)
		(layer "F.Cu")
		(net "USB_CPU0_HUB1_VBUS_US")
	)
	(segment
		(start 140.020294 -39.793418)
		(end 140.020294 -38.796468)
		(width 0.10668)
		(layer "F.Cu")
		(net "USB_CPU0_HUB1_VBUS_US")
	)
	(via
		(at 138.801094 -39.793418)
		(size 0.762)
		(drill 0.381)
		(layers "F.Cu" "B.Cu")
		(net "USB_CPU0_HUB1_VBUS_US")
	)
	(segment
		(start 136.30148 -44.363894)
		(end 137.62736 -45.689774)
		(width 0.10668)
		(layer "F.Cu")
		(net "USB_CPU0_HUB1_VBUS_DS")
	)
	(segment
		(start 140.765784 -46.908974)
		(end 140.765784 -45.689774)
		(width 0.10668)
		(layer "F.Cu")
		(net "USB_CPU0_HUB1_VBUS_DS")
	)
	(segment
		(start 137.62736 -45.689774)
		(end 140.765784 -45.689774)
		(width 0.10668)
		(layer "F.Cu")
		(net "USB_CPU0_HUB1_VBUS_DS")
	)
	(segment
		(start 136.30148 -41.90111)
		(end 136.30148 -44.363894)
		(width 0.10668)
		(layer "F.Cu")
		(net "USB_CPU0_HUB1_VBUS_DS")
	)
	(segment
		(start 135.894064 -40.873426)
		(end 135.894064 -41.493694)
		(width 0.10668)
		(layer "F.Cu")
		(net "USB_CPU0_HUB1_VBUS_DS")
	)
	(segment
		(start 135.894064 -41.493694)
		(end 136.30148 -41.90111)
		(width 0.10668)
		(layer "F.Cu")
		(net "USB_CPU0_HUB1_VBUS_DS")
	)
	(via
		(at 140.765784 -45.689774)
		(size 0.762)
		(drill 0.381)
		(layers "F.Cu" "B.Cu")
		(net "USB_CPU0_HUB1_VBUS_DS")
	)
	(segment
		(start 136.54405 -34.073338)
		(end 137.242296 -34.073338)
		(width 0.10668)
		(layer "F.Cu")
		(net "USB_CPU0_HUB1_RREF_USB2")
	)
	(segment
		(start 138.3284 -33.1216)
		(end 138.3284 -33.28924)
		(width 0.10668)
		(layer "F.Cu")
		(net "USB_CPU0_HUB1_RREF_USB2")
	)
	(segment
		(start 138.026394 -33.28924)
		(end 138.3284 -33.28924)
		(width 0.10668)
		(layer "F.Cu")
		(net "USB_CPU0_HUB1_RREF_USB2")
	)
	(segment
		(start 137.955274 -32.748474)
		(end 138.3284 -33.1216)
		(width 0.10668)
		(layer "F.Cu")
		(net "USB_CPU0_HUB1_RREF_USB2")
	)
	(segment
		(start 137.242296 -34.073338)
		(end 138.026394 -33.28924)
		(width 0.10668)
		(layer "F.Cu")
		(net "USB_CPU0_HUB1_RREF_USB2")
	)
	(segment
		(start 137.955274 -32.10687)
		(end 137.955274 -32.748474)
		(width 0.10668)
		(layer "F.Cu")
		(net "USB_CPU0_HUB1_RREF_USB2")
	)
	(via
		(at 138.3284 -33.28924)
		(size 0.762)
		(drill 0.381)
		(layers "F.Cu" "B.Cu")
		(net "USB_CPU0_HUB1_RREF_USB2")
	)
	(segment
		(start 132.950712 -44.646088)
		(end 129.256536 -48.340264)
		(width 0.10668)
		(layer "F.Cu")
		(net "USB_CPU0_HUB1_RREF_SS")
	)
	(segment
		(start 132.694172 -40.723312)
		(end 132.694172 -41.357296)
		(width 0.10668)
		(layer "F.Cu")
		(net "USB_CPU0_HUB1_RREF_SS")
	)
	(segment
		(start 127.204978 -48.137064)
		(end 128.438148 -48.137064)
		(width 0.10668)
		(layer "F.Cu")
		(net "USB_CPU0_HUB1_RREF_SS")
	)
	(segment
		(start 128.438148 -48.137064)
		(end 128.641348 -48.340264)
		(width 0.10668)
		(layer "F.Cu")
		(net "USB_CPU0_HUB1_RREF_SS")
	)
	(segment
		(start 132.694172 -41.357296)
		(end 132.950712 -41.613836)
		(width 0.10668)
		(layer "F.Cu")
		(net "USB_CPU0_HUB1_RREF_SS")
	)
	(segment
		(start 132.950712 -41.613836)
		(end 132.950712 -44.646088)
		(width 0.10668)
		(layer "F.Cu")
		(net "USB_CPU0_HUB1_RREF_SS")
	)
	(segment
		(start 129.256536 -48.340264)
		(end 128.641348 -48.340264)
		(width 0.10668)
		(layer "F.Cu")
		(net "USB_CPU0_HUB1_RREF_SS")
	)
	(via
		(at 128.641348 -48.340264)
		(size 0.762)
		(drill 0.381)
		(layers "F.Cu" "B.Cu")
		(net "USB_CPU0_HUB1_RREF_SS")
	)
	(segment
		(start 133.494272 -44.75734)
		(end 130.050286 -48.201326)
		(width 0.10668)
		(layer "F.Cu")
		(net "USB_CPU0_HUB1_MODE_SEL1")
	)
	(segment
		(start 133.494272 -40.723312)
		(end 133.494272 -44.75734)
		(width 0.10668)
		(layer "F.Cu")
		(net "USB_CPU0_HUB1_MODE_SEL1")
	)
	(segment
		(start 130.050286 -49.073054)
		(end 129.739644 -49.383696)
		(width 0.10668)
		(layer "F.Cu")
		(net "USB_CPU0_HUB1_MODE_SEL1")
	)
	(segment
		(start 127.204978 -49.153064)
		(end 128.184148 -49.153064)
		(width 0.10668)
		(layer "F.Cu")
		(net "USB_CPU0_HUB1_MODE_SEL1")
	)
	(segment
		(start 127.204978 -50.169064)
		(end 127.204978 -49.153064)
		(width 0.10668)
		(layer "F.Cu")
		(net "USB_CPU0_HUB1_MODE_SEL1")
	)
	(segment
		(start 128.184148 -49.153064)
		(end 128.41478 -49.383696)
		(width 0.10668)
		(layer "F.Cu")
		(net "USB_CPU0_HUB1_MODE_SEL1")
	)
	(segment
		(start 130.050286 -48.201326)
		(end 130.050286 -49.073054)
		(width 0.10668)
		(layer "F.Cu")
		(net "USB_CPU0_HUB1_MODE_SEL1")
	)
	(segment
		(start 128.41478 -49.383696)
		(end 129.739644 -49.383696)
		(width 0.10668)
		(layer "F.Cu")
		(net "USB_CPU0_HUB1_MODE_SEL1")
	)
	(via
		(at 129.739644 -49.383696)
		(size 0.762)
		(drill 0.381)
		(layers "F.Cu" "B.Cu")
		(net "USB_CPU0_HUB1_MODE_SEL1")
	)
	(segment
		(start 133.894068 -40.723312)
		(end 133.894068 -47.136558)
		(width 0.10668)
		(layer "F.Cu")
		(net "USB_CPU0_HUB1_MODE_SEL0")
	)
	(segment
		(start 137.571734 -50.611024)
		(end 137.571734 -49.595024)
		(width 0.10668)
		(layer "F.Cu")
		(net "USB_CPU0_HUB1_MODE_SEL0")
	)
	(segment
		(start 137.571734 -49.595024)
		(end 136.352534 -49.595024)
		(width 0.10668)
		(layer "F.Cu")
		(net "USB_CPU0_HUB1_MODE_SEL0")
	)
	(segment
		(start 133.894068 -47.136558)
		(end 136.352534 -49.595024)
		(width 0.10668)
		(layer "F.Cu")
		(net "USB_CPU0_HUB1_MODE_SEL0")
	)
	(via
		(at 136.352534 -49.595024)
		(size 0.762)
		(drill 0.381)
		(layers "F.Cu" "B.Cu")
		(net "USB_CPU0_HUB1_MODE_SEL0")
	)
	(segment
		(start 107.75188 -64.457072)
		(end 107.651042 -64.55791)
		(width 0.10668)
		(layer "F.Cu")
		(net "USB_CPU0_ADD_A2")
	)
	(segment
		(start 106.24566 -63.54191)
		(end 106.24566 -64.55791)
		(width 0.10668)
		(layer "F.Cu")
		(net "USB_CPU0_ADD_A2")
	)
	(segment
		(start 109.35208 -64.457072)
		(end 107.75188 -64.457072)
		(width 0.10668)
		(layer "F.Cu")
		(net "USB_CPU0_ADD_A2")
	)
	(segment
		(start 107.651042 -64.55791)
		(end 106.24566 -64.55791)
		(width 0.10668)
		(layer "F.Cu")
		(net "USB_CPU0_ADD_A2")
	)
	(via
		(at 107.75188 -64.457072)
		(size 0.762)
		(drill 0.381)
		(layers "F.Cu" "B.Cu")
		(net "USB_CPU0_ADD_A2")
	)
	(segment
		(start 106.24566 -66.58991)
		(end 106.24566 -65.57391)
		(width 0.10668)
		(layer "F.Cu")
		(net "USB_CPU0_ADD_A1")
	)
	(segment
		(start 107.75188 -65.727072)
		(end 107.598718 -65.57391)
		(width 0.10668)
		(layer "F.Cu")
		(net "USB_CPU0_ADD_A1")
	)
	(segment
		(start 109.35208 -65.727072)
		(end 107.75188 -65.727072)
		(width 0.10668)
		(layer "F.Cu")
		(net "USB_CPU0_ADD_A1")
	)
	(segment
		(start 107.598718 -65.57391)
		(end 106.24566 -65.57391)
		(width 0.10668)
		(layer "F.Cu")
		(net "USB_CPU0_ADD_A1")
	)
	(via
		(at 107.75188 -65.727072)
		(size 0.762)
		(drill 0.381)
		(layers "F.Cu" "B.Cu")
		(net "USB_CPU0_ADD_A1")
	)
	(segment
		(start 107.75188 -66.997072)
		(end 109.35208 -66.997072)
		(width 0.10668)
		(layer "F.Cu")
		(net "USB_CPU0_ADD_A0")
	)
	(segment
		(start 106.854498 -66.997072)
		(end 107.75188 -66.997072)
		(width 0.10668)
		(layer "F.Cu")
		(net "USB_CPU0_ADD_A0")
	)
	(segment
		(start 106.24566 -67.60591)
		(end 106.854498 -66.997072)
		(width 0.10668)
		(layer "F.Cu")
		(net "USB_CPU0_ADD_A0")
	)
	(segment
		(start 106.24566 -68.62191)
		(end 106.24566 -67.60591)
		(width 0.10668)
		(layer "F.Cu")
		(net "USB_CPU0_ADD_A0")
	)
	(via
		(at 107.75188 -66.997072)
		(size 0.762)
		(drill 0.381)
		(layers "F.Cu" "B.Cu")
		(net "USB_CPU0_ADD_A0")
	)
	(segment
		(start 108.398818 -30.747716)
		(end 108.152692 -30.747716)
		(width 0.12954)
		(layer "F.Cu")
		(net "USB3_CPU0_BMC_TX_C2_DP")
	)
	(segment
		(start 145.63344 -30.38729)
		(end 145.63344 -29.920184)
		(width 0.12954)
		(layer "F.Cu")
		(net "USB3_CPU0_BMC_TX_C2_DP")
	)
	(segment
		(start 103.185722 -29.553154)
		(end 102.906576 -29.274008)
		(width 0.12954)
		(layer "F.Cu")
		(net "USB3_CPU0_BMC_TX_C2_DP")
	)
	(segment
		(start 102.906576 -29.274008)
		(end 101.952806 -29.274008)
		(width 0.12954)
		(layer "F.Cu")
		(net "USB3_CPU0_BMC_TX_C2_DP")
	)
	(segment
		(start 103.456232 -29.282644)
		(end 103.185722 -29.553154)
		(width 0.12954)
		(layer "F.Cu")
		(net "USB3_CPU0_BMC_TX_C2_DP")
	)
	(segment
		(start 108.064046 -30.65907)
		(end 105.633012 -30.65907)
		(width 0.12954)
		(layer "F.Cu")
		(net "USB3_CPU0_BMC_TX_C2_DP")
	)
	(segment
		(start 145.153126 -26.5938)
		(end 144.720564 -26.161238)
		(width 0.12954)
		(layer "F.Cu")
		(net "USB3_CPU0_BMC_TX_C2_DP")
	)
	(segment
		(start 105.633012 -30.65907)
		(end 104.256586 -29.282644)
		(width 0.12954)
		(layer "F.Cu")
		(net "USB3_CPU0_BMC_TX_C2_DP")
	)
	(segment
		(start 145.63344 -29.920184)
		(end 145.153126 -29.43987)
		(width 0.12954)
		(layer "F.Cu")
		(net "USB3_CPU0_BMC_TX_C2_DP")
	)
	(segment
		(start 142.257526 -26.161238)
		(end 142.003526 -25.90419)
		(width 0.12954)
		(layer "F.Cu")
		(net "USB3_CPU0_BMC_TX_C2_DP")
	)
	(segment
		(start 144.720564 -26.161238)
		(end 142.257526 -26.161238)
		(width 0.12954)
		(layer "F.Cu")
		(net "USB3_CPU0_BMC_TX_C2_DP")
	)
	(segment
		(start 104.256586 -29.282644)
		(end 103.456232 -29.282644)
		(width 0.12954)
		(layer "F.Cu")
		(net "USB3_CPU0_BMC_TX_C2_DP")
	)
	(segment
		(start 145.153126 -29.43987)
		(end 145.153126 -26.5938)
		(width 0.12954)
		(layer "F.Cu")
		(net "USB3_CPU0_BMC_TX_C2_DP")
	)
	(segment
		(start 108.152692 -30.747716)
		(end 108.064046 -30.65907)
		(width 0.12954)
		(layer "F.Cu")
		(net "USB3_CPU0_BMC_TX_C2_DP")
	)
	(segment
		(start 101.952806 -29.274008)
		(end 101.708204 -29.51861)
		(width 0.12954)
		(layer "F.Cu")
		(net "USB3_CPU0_BMC_TX_C2_DP")
	)
	(segment
		(start 127.19431 -20.96516)
		(end 133.005068 -20.96516)
		(width 0.14224)
		(layer "In6.Cu")
		(net "USB3_CPU0_BMC_TX_C2_DP")
	)
	(segment
		(start 113.841784 -21.895816)
		(end 114.77244 -20.96516)
		(width 0.14224)
		(layer "In6.Cu")
		(net "USB3_CPU0_BMC_TX_C2_DP")
	)
	(segment
		(start 125.93447 -21.10232)
		(end 126.07163 -20.96516)
		(width 0.14224)
		(layer "In6.Cu")
		(net "USB3_CPU0_BMC_TX_C2_DP")
	)
	(segment
		(start 110.4773 -27.2542)
		(end 110.4773 -24.09952)
		(width 0.14224)
		(layer "In6.Cu")
		(net "USB3_CPU0_BMC_TX_C2_DP")
	)
	(segment
		(start 111.860584 -22.716236)
		(end 113.841784 -21.895816)
		(width 0.14224)
		(layer "In6.Cu")
		(net "USB3_CPU0_BMC_TX_C2_DP")
	)
	(segment
		(start 105.4354 -29.6672)
		(end 108.0643 -29.6672)
		(width 0.14224)
		(layer "In6.Cu")
		(net "USB3_CPU0_BMC_TX_C2_DP")
	)
	(segment
		(start 143.053308 -25.148794)
		(end 143.053308 -25.948386)
		(width 0.14224)
		(layer "In6.Cu")
		(net "USB3_CPU0_BMC_TX_C2_DP")
	)
	(segment
		(start 140.22959 -24.511)
		(end 140.65377 -24.511)
		(width 0.14224)
		(layer "In6.Cu")
		(net "USB3_CPU0_BMC_TX_C2_DP")
	)
	(segment
		(start 142.806674 -26.19502)
		(end 142.294356 -26.19502)
		(width 0.14224)
		(layer "In6.Cu")
		(net "USB3_CPU0_BMC_TX_C2_DP")
	)
	(segment
		(start 139.53109 -24.511)
		(end 139.66825 -24.64816)
		(width 0.14224)
		(layer "In6.Cu")
		(net "USB3_CPU0_BMC_TX_C2_DP")
	)
	(segment
		(start 138.96975 -24.64816)
		(end 139.10691 -24.511)
		(width 0.14224)
		(layer "In6.Cu")
		(net "USB3_CPU0_BMC_TX_C2_DP")
	)
	(segment
		(start 140.09243 -24.64816)
		(end 140.22959 -24.511)
		(width 0.14224)
		(layer "In6.Cu")
		(net "USB3_CPU0_BMC_TX_C2_DP")
	)
	(segment
		(start 142.415514 -24.511)
		(end 143.053308 -25.148794)
		(width 0.14224)
		(layer "In6.Cu")
		(net "USB3_CPU0_BMC_TX_C2_DP")
	)
	(segment
		(start 124.94895 -20.96516)
		(end 125.37313 -20.96516)
		(width 0.14224)
		(layer "In6.Cu")
		(net "USB3_CPU0_BMC_TX_C2_DP")
	)
	(segment
		(start 126.63297 -21.10232)
		(end 127.05715 -21.10232)
		(width 0.14224)
		(layer "In6.Cu")
		(net "USB3_CPU0_BMC_TX_C2_DP")
	)
	(segment
		(start 139.10691 -24.511)
		(end 139.53109 -24.511)
		(width 0.14224)
		(layer "In6.Cu")
		(net "USB3_CPU0_BMC_TX_C2_DP")
	)
	(segment
		(start 138.40841 -24.511)
		(end 138.54557 -24.64816)
		(width 0.14224)
		(layer "In6.Cu")
		(net "USB3_CPU0_BMC_TX_C2_DP")
	)
	(segment
		(start 138.54557 -24.64816)
		(end 138.96975 -24.64816)
		(width 0.14224)
		(layer "In6.Cu")
		(net "USB3_CPU0_BMC_TX_C2_DP")
	)
	(segment
		(start 123.26493 -21.10232)
		(end 123.68911 -21.10232)
		(width 0.14224)
		(layer "In6.Cu")
		(net "USB3_CPU0_BMC_TX_C2_DP")
	)
	(segment
		(start 141.35227 -24.511)
		(end 142.415514 -24.511)
		(width 0.14224)
		(layer "In6.Cu")
		(net "USB3_CPU0_BMC_TX_C2_DP")
	)
	(segment
		(start 104.99598 -29.22778)
		(end 105.4354 -29.6672)
		(width 0.14224)
		(layer "In6.Cu")
		(net "USB3_CPU0_BMC_TX_C2_DP")
	)
	(segment
		(start 123.68911 -21.10232)
		(end 123.82627 -20.96516)
		(width 0.14224)
		(layer "In6.Cu")
		(net "USB3_CPU0_BMC_TX_C2_DP")
	)
	(segment
		(start 142.294356 -26.19502)
		(end 142.003526 -25.90419)
		(width 0.14224)
		(layer "In6.Cu")
		(net "USB3_CPU0_BMC_TX_C2_DP")
	)
	(segment
		(start 141.21511 -24.64816)
		(end 141.35227 -24.511)
		(width 0.14224)
		(layer "In6.Cu")
		(net "USB3_CPU0_BMC_TX_C2_DP")
	)
	(segment
		(start 140.65377 -24.511)
		(end 140.79093 -24.64816)
		(width 0.14224)
		(layer "In6.Cu")
		(net "USB3_CPU0_BMC_TX_C2_DP")
	)
	(segment
		(start 125.51029 -21.10232)
		(end 125.93447 -21.10232)
		(width 0.14224)
		(layer "In6.Cu")
		(net "USB3_CPU0_BMC_TX_C2_DP")
	)
	(segment
		(start 139.66825 -24.64816)
		(end 140.09243 -24.64816)
		(width 0.14224)
		(layer "In6.Cu")
		(net "USB3_CPU0_BMC_TX_C2_DP")
	)
	(segment
		(start 108.0643 -29.6672)
		(end 110.4773 -27.2542)
		(width 0.14224)
		(layer "In6.Cu")
		(net "USB3_CPU0_BMC_TX_C2_DP")
	)
	(segment
		(start 110.4773 -24.09952)
		(end 111.860584 -22.716236)
		(width 0.14224)
		(layer "In6.Cu")
		(net "USB3_CPU0_BMC_TX_C2_DP")
	)
	(segment
		(start 137.84707 -24.64816)
		(end 137.98423 -24.511)
		(width 0.14224)
		(layer "In6.Cu")
		(net "USB3_CPU0_BMC_TX_C2_DP")
	)
	(segment
		(start 140.79093 -24.64816)
		(end 141.21511 -24.64816)
		(width 0.14224)
		(layer "In6.Cu")
		(net "USB3_CPU0_BMC_TX_C2_DP")
	)
	(segment
		(start 143.053308 -25.948386)
		(end 142.806674 -26.19502)
		(width 0.14224)
		(layer "In6.Cu")
		(net "USB3_CPU0_BMC_TX_C2_DP")
	)
	(segment
		(start 101.999034 -29.22778)
		(end 104.99598 -29.22778)
		(width 0.14224)
		(layer "In6.Cu")
		(net "USB3_CPU0_BMC_TX_C2_DP")
	)
	(segment
		(start 137.98423 -24.511)
		(end 138.40841 -24.511)
		(width 0.14224)
		(layer "In6.Cu")
		(net "USB3_CPU0_BMC_TX_C2_DP")
	)
	(segment
		(start 126.07163 -20.96516)
		(end 126.49581 -20.96516)
		(width 0.14224)
		(layer "In6.Cu")
		(net "USB3_CPU0_BMC_TX_C2_DP")
	)
	(segment
		(start 125.37313 -20.96516)
		(end 125.51029 -21.10232)
		(width 0.14224)
		(layer "In6.Cu")
		(net "USB3_CPU0_BMC_TX_C2_DP")
	)
	(segment
		(start 123.82627 -20.96516)
		(end 124.25045 -20.96516)
		(width 0.14224)
		(layer "In6.Cu")
		(net "USB3_CPU0_BMC_TX_C2_DP")
	)
	(segment
		(start 124.81179 -21.10232)
		(end 124.94895 -20.96516)
		(width 0.14224)
		(layer "In6.Cu")
		(net "USB3_CPU0_BMC_TX_C2_DP")
	)
	(segment
		(start 101.708204 -29.51861)
		(end 101.999034 -29.22778)
		(width 0.14224)
		(layer "In6.Cu")
		(net "USB3_CPU0_BMC_TX_C2_DP")
	)
	(segment
		(start 114.77244 -20.96516)
		(end 123.12777 -20.96516)
		(width 0.14224)
		(layer "In6.Cu")
		(net "USB3_CPU0_BMC_TX_C2_DP")
	)
	(segment
		(start 123.12777 -20.96516)
		(end 123.26493 -21.10232)
		(width 0.14224)
		(layer "In6.Cu")
		(net "USB3_CPU0_BMC_TX_C2_DP")
	)
	(segment
		(start 124.25045 -20.96516)
		(end 124.38761 -21.10232)
		(width 0.14224)
		(layer "In6.Cu")
		(net "USB3_CPU0_BMC_TX_C2_DP")
	)
	(segment
		(start 127.05715 -21.10232)
		(end 127.19431 -20.96516)
		(width 0.14224)
		(layer "In6.Cu")
		(net "USB3_CPU0_BMC_TX_C2_DP")
	)
	(segment
		(start 133.005068 -20.96516)
		(end 136.550908 -24.511)
		(width 0.14224)
		(layer "In6.Cu")
		(net "USB3_CPU0_BMC_TX_C2_DP")
	)
	(segment
		(start 124.38761 -21.10232)
		(end 124.81179 -21.10232)
		(width 0.14224)
		(layer "In6.Cu")
		(net "USB3_CPU0_BMC_TX_C2_DP")
	)
	(segment
		(start 137.28573 -24.511)
		(end 137.42289 -24.64816)
		(width 0.14224)
		(layer "In6.Cu")
		(net "USB3_CPU0_BMC_TX_C2_DP")
	)
	(segment
		(start 136.550908 -24.511)
		(end 137.28573 -24.511)
		(width 0.14224)
		(layer "In6.Cu")
		(net "USB3_CPU0_BMC_TX_C2_DP")
	)
	(segment
		(start 126.49581 -20.96516)
		(end 126.63297 -21.10232)
		(width 0.14224)
		(layer "In6.Cu")
		(net "USB3_CPU0_BMC_TX_C2_DP")
	)
	(segment
		(start 137.42289 -24.64816)
		(end 137.84707 -24.64816)
		(width 0.14224)
		(layer "In6.Cu")
		(net "USB3_CPU0_BMC_TX_C2_DP")
	)
	(segment
		(start 108.066586 -30.33649)
		(end 105.76687 -30.33649)
		(width 0.12954)
		(layer "F.Cu")
		(net "USB3_CPU0_BMC_TX_C2_DN")
	)
	(segment
		(start 144.15135 -26.483818)
		(end 144.007078 -26.62809)
		(width 0.12954)
		(layer "F.Cu")
		(net "USB3_CPU0_BMC_TX_C2_DN")
	)
	(segment
		(start 144.640046 -27.173174)
		(end 144.830546 -26.982674)
		(width 0.12954)
		(layer "F.Cu")
		(net "USB3_CPU0_BMC_TX_C2_DN")
	)
	(segment
		(start 144.640046 -28.397454)
		(end 144.830546 -28.206954)
		(width 0.12954)
		(layer "F.Cu")
		(net "USB3_CPU0_BMC_TX_C2_DN")
	)
	(segment
		(start 144.640046 -28.783534)
		(end 144.640046 -28.397454)
		(width 0.12954)
		(layer "F.Cu")
		(net "USB3_CPU0_BMC_TX_C2_DN")
	)
	(segment
		(start 144.640046 -27.559254)
		(end 144.640046 -27.173174)
		(width 0.12954)
		(layer "F.Cu")
		(net "USB3_CPU0_BMC_TX_C2_DN")
	)
	(segment
		(start 108.155232 -30.247844)
		(end 108.066586 -30.33649)
		(width 0.12954)
		(layer "F.Cu")
		(net "USB3_CPU0_BMC_TX_C2_DN")
	)
	(segment
		(start 144.830546 -29.437076)
		(end 144.830546 -28.974034)
		(width 0.12954)
		(layer "F.Cu")
		(net "USB3_CPU0_BMC_TX_C2_DN")
	)
	(segment
		(start 144.830546 -27.749754)
		(end 144.640046 -27.559254)
		(width 0.12954)
		(layer "F.Cu")
		(net "USB3_CPU0_BMC_TX_C2_DN")
	)
	(segment
		(start 144.830546 -26.982674)
		(end 144.830546 -26.727658)
		(width 0.12954)
		(layer "F.Cu")
		(net "USB3_CPU0_BMC_TX_C2_DN")
	)
	(segment
		(start 103.456232 -28.960064)
		(end 103.185722 -28.689554)
		(width 0.12954)
		(layer "F.Cu")
		(net "USB3_CPU0_BMC_TX_C2_DN")
	)
	(segment
		(start 144.830546 -26.727658)
		(end 144.586706 -26.483818)
		(width 0.12954)
		(layer "F.Cu")
		(net "USB3_CPU0_BMC_TX_C2_DN")
	)
	(segment
		(start 144.830546 -28.974034)
		(end 144.640046 -28.783534)
		(width 0.12954)
		(layer "F.Cu")
		(net "USB3_CPU0_BMC_TX_C2_DN")
	)
	(segment
		(start 144.007078 -26.62809)
		(end 143.618458 -26.62809)
		(width 0.12954)
		(layer "F.Cu")
		(net "USB3_CPU0_BMC_TX_C2_DN")
	)
	(segment
		(start 144.586706 -26.483818)
		(end 144.15135 -26.483818)
		(width 0.12954)
		(layer "F.Cu")
		(net "USB3_CPU0_BMC_TX_C2_DN")
	)
	(segment
		(start 108.398818 -30.247844)
		(end 108.155232 -30.247844)
		(width 0.12954)
		(layer "F.Cu")
		(net "USB3_CPU0_BMC_TX_C2_DN")
	)
	(segment
		(start 102.923848 -28.951428)
		(end 102.004622 -28.951428)
		(width 0.12954)
		(layer "F.Cu")
		(net "USB3_CPU0_BMC_TX_C2_DN")
	)
	(segment
		(start 143.474186 -26.483818)
		(end 142.287498 -26.483818)
		(width 0.12954)
		(layer "F.Cu")
		(net "USB3_CPU0_BMC_TX_C2_DN")
	)
	(segment
		(start 142.287498 -26.483818)
		(end 142.003526 -26.76779)
		(width 0.12954)
		(layer "F.Cu")
		(net "USB3_CPU0_BMC_TX_C2_DN")
	)
	(segment
		(start 143.618458 -26.62809)
		(end 143.474186 -26.483818)
		(width 0.12954)
		(layer "F.Cu")
		(net "USB3_CPU0_BMC_TX_C2_DN")
	)
	(segment
		(start 103.185722 -28.689554)
		(end 102.923848 -28.951428)
		(width 0.12954)
		(layer "F.Cu")
		(net "USB3_CPU0_BMC_TX_C2_DN")
	)
	(segment
		(start 105.76687 -30.33649)
		(end 104.390444 -28.960064)
		(width 0.12954)
		(layer "F.Cu")
		(net "USB3_CPU0_BMC_TX_C2_DN")
	)
	(segment
		(start 102.004622 -28.951428)
		(end 101.708204 -28.65501)
		(width 0.12954)
		(layer "F.Cu")
		(net "USB3_CPU0_BMC_TX_C2_DN")
	)
	(segment
		(start 144.36344 -29.904182)
		(end 144.830546 -29.437076)
		(width 0.12954)
		(layer "F.Cu")
		(net "USB3_CPU0_BMC_TX_C2_DN")
	)
	(segment
		(start 144.36344 -30.38729)
		(end 144.36344 -29.904182)
		(width 0.12954)
		(layer "F.Cu")
		(net "USB3_CPU0_BMC_TX_C2_DN")
	)
	(segment
		(start 144.830546 -28.206954)
		(end 144.830546 -27.749754)
		(width 0.12954)
		(layer "F.Cu")
		(net "USB3_CPU0_BMC_TX_C2_DN")
	)
	(segment
		(start 104.390444 -28.960064)
		(end 103.456232 -28.960064)
		(width 0.12954)
		(layer "F.Cu")
		(net "USB3_CPU0_BMC_TX_C2_DN")
	)
	(segment
		(start 110.19536 -23.98268)
		(end 111.700818 -22.477222)
		(width 0.14224)
		(layer "In6.Cu")
		(net "USB3_CPU0_BMC_TX_C2_DN")
	)
	(segment
		(start 114.6556 -20.68322)
		(end 133.121908 -20.68322)
		(width 0.14224)
		(layer "In6.Cu")
		(net "USB3_CPU0_BMC_TX_C2_DN")
	)
	(segment
		(start 133.121908 -20.68322)
		(end 136.667748 -24.22906)
		(width 0.14224)
		(layer "In6.Cu")
		(net "USB3_CPU0_BMC_TX_C2_DN")
	)
	(segment
		(start 111.700818 -22.477222)
		(end 113.682018 -21.656802)
		(width 0.14224)
		(layer "In6.Cu")
		(net "USB3_CPU0_BMC_TX_C2_DN")
	)
	(segment
		(start 143.335248 -25.031954)
		(end 143.335248 -26.065226)
		(width 0.14224)
		(layer "In6.Cu")
		(net "USB3_CPU0_BMC_TX_C2_DN")
	)
	(segment
		(start 105.55224 -29.38526)
		(end 107.94746 -29.38526)
		(width 0.14224)
		(layer "In6.Cu")
		(net "USB3_CPU0_BMC_TX_C2_DN")
	)
	(segment
		(start 142.294356 -26.47696)
		(end 142.003526 -26.76779)
		(width 0.14224)
		(layer "In6.Cu")
		(net "USB3_CPU0_BMC_TX_C2_DN")
	)
	(segment
		(start 110.19536 -27.13736)
		(end 110.19536 -23.98268)
		(width 0.14224)
		(layer "In6.Cu")
		(net "USB3_CPU0_BMC_TX_C2_DN")
	)
	(segment
		(start 107.94746 -29.38526)
		(end 110.19536 -27.13736)
		(width 0.14224)
		(layer "In6.Cu")
		(net "USB3_CPU0_BMC_TX_C2_DN")
	)
	(segment
		(start 101.999034 -28.94584)
		(end 105.11282 -28.94584)
		(width 0.14224)
		(layer "In6.Cu")
		(net "USB3_CPU0_BMC_TX_C2_DN")
	)
	(segment
		(start 101.708204 -28.65501)
		(end 101.999034 -28.94584)
		(width 0.14224)
		(layer "In6.Cu")
		(net "USB3_CPU0_BMC_TX_C2_DN")
	)
	(segment
		(start 143.335248 -26.065226)
		(end 142.923514 -26.47696)
		(width 0.14224)
		(layer "In6.Cu")
		(net "USB3_CPU0_BMC_TX_C2_DN")
	)
	(segment
		(start 136.667748 -24.22906)
		(end 142.532354 -24.22906)
		(width 0.14224)
		(layer "In6.Cu")
		(net "USB3_CPU0_BMC_TX_C2_DN")
	)
	(segment
		(start 113.682018 -21.656802)
		(end 114.6556 -20.68322)
		(width 0.14224)
		(layer "In6.Cu")
		(net "USB3_CPU0_BMC_TX_C2_DN")
	)
	(segment
		(start 105.11282 -28.94584)
		(end 105.55224 -29.38526)
		(width 0.14224)
		(layer "In6.Cu")
		(net "USB3_CPU0_BMC_TX_C2_DN")
	)
	(segment
		(start 142.532354 -24.22906)
		(end 143.335248 -25.031954)
		(width 0.14224)
		(layer "In6.Cu")
		(net "USB3_CPU0_BMC_TX_C2_DN")
	)
	(segment
		(start 142.923514 -26.47696)
		(end 142.294356 -26.47696)
		(width 0.14224)
		(layer "In6.Cu")
		(net "USB3_CPU0_BMC_TX_C2_DN")
	)
	(segment
		(start 145.20545 -32.963358)
		(end 145.20545 -33.762188)
		(width 0.12954)
		(layer "F.Cu")
		(net "USB3_CPU0_BMC_TX_C1_DP")
	)
	(segment
		(start 137.213848 -36.841684)
		(end 137.182098 -36.873434)
		(width 0.12954)
		(layer "F.Cu")
		(net "USB3_CPU0_BMC_TX_C1_DP")
	)
	(segment
		(start 145.20545 -33.762188)
		(end 142.125954 -36.841684)
		(width 0.12954)
		(layer "F.Cu")
		(net "USB3_CPU0_BMC_TX_C1_DP")
	)
	(segment
		(start 137.182098 -36.873434)
		(end 136.54405 -36.873434)
		(width 0.12954)
		(layer "F.Cu")
		(net "USB3_CPU0_BMC_TX_C1_DP")
	)
	(segment
		(start 142.125954 -36.841684)
		(end 137.213848 -36.841684)
		(width 0.12954)
		(layer "F.Cu")
		(net "USB3_CPU0_BMC_TX_C1_DP")
	)
	(segment
		(start 145.63344 -32.535368)
		(end 145.20545 -32.963358)
		(width 0.12954)
		(layer "F.Cu")
		(net "USB3_CPU0_BMC_TX_C1_DP")
	)
	(segment
		(start 145.63344 -31.98749)
		(end 145.63344 -32.535368)
		(width 0.12954)
		(layer "F.Cu")
		(net "USB3_CPU0_BMC_TX_C1_DP")
	)
	(segment
		(start 141.992096 -36.519104)
		(end 140.84046 -36.519104)
		(width 0.12954)
		(layer "F.Cu")
		(net "USB3_CPU0_BMC_TX_C1_DN")
	)
	(segment
		(start 144.88287 -33.62833)
		(end 143.623284 -34.887916)
		(width 0.12954)
		(layer "F.Cu")
		(net "USB3_CPU0_BMC_TX_C1_DN")
	)
	(segment
		(start 144.36344 -32.487362)
		(end 144.88287 -33.006792)
		(width 0.12954)
		(layer "F.Cu")
		(net "USB3_CPU0_BMC_TX_C1_DN")
	)
	(segment
		(start 143.080486 -35.16122)
		(end 143.080486 -35.430714)
		(width 0.12954)
		(layer "F.Cu")
		(net "USB3_CPU0_BMC_TX_C1_DN")
	)
	(segment
		(start 137.228072 -36.519104)
		(end 137.182352 -36.473384)
		(width 0.12954)
		(layer "F.Cu")
		(net "USB3_CPU0_BMC_TX_C1_DN")
	)
	(segment
		(start 140.26388 -36.328604)
		(end 140.07338 -36.519104)
		(width 0.12954)
		(layer "F.Cu")
		(net "USB3_CPU0_BMC_TX_C1_DN")
	)
	(segment
		(start 143.35379 -34.887916)
		(end 143.080486 -35.16122)
		(width 0.12954)
		(layer "F.Cu")
		(net "USB3_CPU0_BMC_TX_C1_DN")
	)
	(segment
		(start 142.264892 -35.976814)
		(end 142.264892 -36.246308)
		(width 0.12954)
		(layer "F.Cu")
		(net "USB3_CPU0_BMC_TX_C1_DN")
	)
	(segment
		(start 140.07338 -36.519104)
		(end 137.228072 -36.519104)
		(width 0.12954)
		(layer "F.Cu")
		(net "USB3_CPU0_BMC_TX_C1_DN")
	)
	(segment
		(start 142.264892 -36.246308)
		(end 141.992096 -36.519104)
		(width 0.12954)
		(layer "F.Cu")
		(net "USB3_CPU0_BMC_TX_C1_DN")
	)
	(segment
		(start 140.64996 -36.328604)
		(end 140.26388 -36.328604)
		(width 0.12954)
		(layer "F.Cu")
		(net "USB3_CPU0_BMC_TX_C1_DN")
	)
	(segment
		(start 144.88287 -33.006792)
		(end 144.88287 -33.62833)
		(width 0.12954)
		(layer "F.Cu")
		(net "USB3_CPU0_BMC_TX_C1_DN")
	)
	(segment
		(start 143.080486 -35.430714)
		(end 142.80769 -35.70351)
		(width 0.12954)
		(layer "F.Cu")
		(net "USB3_CPU0_BMC_TX_C1_DN")
	)
	(segment
		(start 142.80769 -35.70351)
		(end 142.538196 -35.70351)
		(width 0.12954)
		(layer "F.Cu")
		(net "USB3_CPU0_BMC_TX_C1_DN")
	)
	(segment
		(start 137.182352 -36.473384)
		(end 136.54405 -36.473384)
		(width 0.12954)
		(layer "F.Cu")
		(net "USB3_CPU0_BMC_TX_C1_DN")
	)
	(segment
		(start 144.36344 -31.98749)
		(end 144.36344 -32.487362)
		(width 0.12954)
		(layer "F.Cu")
		(net "USB3_CPU0_BMC_TX_C1_DN")
	)
	(segment
		(start 143.623284 -34.887916)
		(end 143.35379 -34.887916)
		(width 0.12954)
		(layer "F.Cu")
		(net "USB3_CPU0_BMC_TX_C1_DN")
	)
	(segment
		(start 140.84046 -36.519104)
		(end 140.64996 -36.328604)
		(width 0.12954)
		(layer "F.Cu")
		(net "USB3_CPU0_BMC_TX_C1_DN")
	)
	(segment
		(start 142.538196 -35.70351)
		(end 142.264892 -35.976814)
		(width 0.12954)
		(layer "F.Cu")
		(net "USB3_CPU0_BMC_TX_C1_DN")
	)
	(segment
		(start 141.29512 -31.22676)
		(end 141.09192 -31.22676)
		(width 0.12954)
		(layer "F.Cu")
		(net "USB3_CPU0_BMC_RX_HUB_C_DP")
	)
	(segment
		(start 369.588034 -225.310192)
		(end 370.054886 -225.044254)
		(width 0.12954)
		(layer "F.Cu")
		(net "USB3_CPU0_BMC_RX_HUB_C_DP")
	)
	(segment
		(start 141.09192 -31.22676)
		(end 140.66012 -30.79496)
		(width 0.12954)
		(layer "F.Cu")
		(net "USB3_CPU0_BMC_RX_HUB_C_DP")
	)
	(segment
		(start 191.939164 -170.657774)
		(end 182.47868 -170.64228)
		(width 0.14224)
		(layer "In15.Cu")
		(net "USB3_CPU0_BMC_RX_HUB_C_DP")
	)
	(segment
		(start 135.579104 -37.728906)
		(end 135.579104 -33.75152)
		(width 0.14224)
		(layer "In15.Cu")
		(net "USB3_CPU0_BMC_RX_HUB_C_DP")
	)
	(segment
		(start 139.800838 -31.08579)
		(end 140.36929 -31.08579)
		(width 0.14224)
		(layer "In15.Cu")
		(net "USB3_CPU0_BMC_RX_HUB_C_DP")
	)
	(segment
		(start 200.59015 -171.883324)
		(end 191.939164 -170.657774)
		(width 0.14224)
		(layer "In15.Cu")
		(net "USB3_CPU0_BMC_RX_HUB_C_DP")
	)
	(segment
		(start 136.59358 -31.894272)
		(end 137.84326 -31.477712)
		(width 0.14224)
		(layer "In15.Cu")
		(net "USB3_CPU0_BMC_RX_HUB_C_DP")
	)
	(segment
		(start 369.333018 -223.119442)
		(end 369.30203 -223.101662)
		(width 0.1143)
		(layer "In15.Cu")
		(net "USB3_CPU0_BMC_RX_HUB_C_DP")
	)
	(segment
		(start 135.469376 -32.663384)
		(end 135.987282 -32.145478)
		(width 0.14224)
		(layer "In15.Cu")
		(net "USB3_CPU0_BMC_RX_HUB_C_DP")
	)
	(segment
		(start 367.885726 -222.288354)
		(end 367.88598 -222.2881)
		(width 0.1143)
		(layer "In15.Cu")
		(net "USB3_CPU0_BMC_RX_HUB_C_DP")
	)
	(segment
		(start 137.860278 -31.47187)
		(end 137.875264 -31.468822)
		(width 0.14224)
		(layer "In15.Cu")
		(net "USB3_CPU0_BMC_RX_HUB_C_DP")
	)
	(segment
		(start 182.47868 -170.64228)
		(end 172.18025 -169.9768)
		(width 0.14224)
		(layer "In15.Cu")
		(net "USB3_CPU0_BMC_RX_HUB_C_DP")
	)
	(segment
		(start 137.87755 -31.468314)
		(end 139.800838 -31.08579)
		(width 0.14224)
		(layer "In15.Cu")
		(net "USB3_CPU0_BMC_RX_HUB_C_DP")
	)
	(segment
		(start 368.372898 -223.107758)
		(end 368.362738 -223.10217)
		(width 0.1143)
		(layer "In15.Cu")
		(net "USB3_CPU0_BMC_RX_HUB_C_DP")
	)
	(segment
		(start 370.271548 -224.738946)
		(end 370.203476 -224.699322)
		(width 0.1143)
		(layer "In15.Cu")
		(net "USB3_CPU0_BMC_RX_HUB_C_DP")
	)
	(segment
		(start 369.80241 -223.929448)
		(end 369.771168 -223.911414)
		(width 0.1143)
		(layer "In15.Cu")
		(net "USB3_CPU0_BMC_RX_HUB_C_DP")
	)
	(segment
		(start 367.563908 -220.200982)
		(end 327.003156 -179.64023)
		(width 0.14224)
		(layer "In15.Cu")
		(net "USB3_CPU0_BMC_RX_HUB_C_DP")
	)
	(segment
		(start 135.35914 -32.929322)
		(end 135.469376 -32.663384)
		(width 0.14224)
		(layer "In15.Cu")
		(net "USB3_CPU0_BMC_RX_HUB_C_DP")
	)
	(segment
		(start 367.563908 -221.420436)
		(end 367.563908 -221.391988)
		(width 0.1143)
		(layer "In15.Cu")
		(net "USB3_CPU0_BMC_RX_HUB_C_DP")
	)
	(segment
		(start 135.987282 -32.145478)
		(end 136.59358 -31.894272)
		(width 0.14224)
		(layer "In15.Cu")
		(net "USB3_CPU0_BMC_RX_HUB_C_DP")
	)
	(segment
		(start 370.054886 -225.044254)
		(end 370.352828 -225.044254)
		(width 0.1143)
		(layer "In15.Cu")
		(net "USB3_CPU0_BMC_RX_HUB_C_DP")
	)
	(segment
		(start 137.84326 -31.477712)
		(end 137.84326 -31.477458)
		(width 0.14224)
		(layer "In15.Cu")
		(net "USB3_CPU0_BMC_RX_HUB_C_DP")
	)
	(segment
		(start 128.343152 -107.40136)
		(end 133.93674 -75.6793)
		(width 0.14224)
		(layer "In15.Cu")
		(net "USB3_CPU0_BMC_RX_HUB_C_DP")
	)
	(segment
		(start 133.322822 -49.32299)
		(end 133.906768 -42.649394)
		(width 0.14224)
		(layer "In15.Cu")
		(net "USB3_CPU0_BMC_RX_HUB_C_DP")
	)
	(segment
		(start 369.771168 -223.911414)
		(end 369.734338 -223.889824)
		(width 0.1143)
		(layer "In15.Cu")
		(net "USB3_CPU0_BMC_RX_HUB_C_DP")
	)
	(segment
		(start 159.043624 -164.535612)
		(end 144.320514 -154.227022)
		(width 0.14224)
		(layer "In15.Cu")
		(net "USB3_CPU0_BMC_RX_HUB_C_DP")
	)
	(segment
		(start 133.93674 -72.176132)
		(end 131.614926 -59.00801)
		(width 0.14224)
		(layer "In15.Cu")
		(net "USB3_CPU0_BMC_RX_HUB_C_DP")
	)
	(segment
		(start 367.609628 -221.909386)
		(end 367.609628 -221.466156)
		(width 0.1143)
		(layer "In15.Cu")
		(net "USB3_CPU0_BMC_RX_HUB_C_DP")
	)
	(segment
		(start 140.36929 -31.08579)
		(end 140.66012 -30.79496)
		(width 0.14224)
		(layer "In15.Cu")
		(net "USB3_CPU0_BMC_RX_HUB_C_DP")
	)
	(segment
		(start 144.320514 -154.227022)
		(end 134.001256 -139.48918)
		(width 0.14224)
		(layer "In15.Cu")
		(net "USB3_CPU0_BMC_RX_HUB_C_DP")
	)
	(segment
		(start 134.001256 -139.48918)
		(end 128.343152 -107.40136)
		(width 0.14224)
		(layer "In15.Cu")
		(net "USB3_CPU0_BMC_RX_HUB_C_DP")
	)
	(segment
		(start 368.359436 -223.100392)
		(end 368.35842 -223.099884)
		(width 0.1143)
		(layer "In15.Cu")
		(net "USB3_CPU0_BMC_RX_HUB_C_DP")
	)
	(segment
		(start 133.906768 -42.649394)
		(end 134.216648 -41.38295)
		(width 0.14224)
		(layer "In15.Cu")
		(net "USB3_CPU0_BMC_RX_HUB_C_DP")
	)
	(segment
		(start 137.876788 -31.468568)
		(end 137.87755 -31.468314)
		(width 0.14224)
		(layer "In15.Cu")
		(net "USB3_CPU0_BMC_RX_HUB_C_DP")
	)
	(segment
		(start 367.898934 -222.29572)
		(end 367.891822 -222.292164)
		(width 0.1143)
		(layer "In15.Cu")
		(net "USB3_CPU0_BMC_RX_HUB_C_DP")
	)
	(segment
		(start 327.003156 -179.64023)
		(end 311.005728 -173.013878)
		(width 0.14224)
		(layer "In15.Cu")
		(net "USB3_CPU0_BMC_RX_HUB_C_DP")
	)
	(segment
		(start 307.1495 -173.013878)
		(end 200.59015 -171.883324)
		(width 0.14224)
		(layer "In15.Cu")
		(net "USB3_CPU0_BMC_RX_HUB_C_DP")
	)
	(segment
		(start 367.563908 -221.391988)
		(end 367.563908 -220.200982)
		(width 0.14224)
		(layer "In15.Cu")
		(net "USB3_CPU0_BMC_RX_HUB_C_DP")
	)
	(segment
		(start 367.923572 -222.310198)
		(end 367.898934 -222.29572)
		(width 0.1143)
		(layer "In15.Cu")
		(net "USB3_CPU0_BMC_RX_HUB_C_DP")
	)
	(segment
		(start 367.888266 -222.289624)
		(end 367.885726 -222.288354)
		(width 0.1143)
		(layer "In15.Cu")
		(net "USB3_CPU0_BMC_RX_HUB_C_DP")
	)
	(segment
		(start 367.609628 -221.466156)
		(end 367.563908 -221.420436)
		(width 0.1143)
		(layer "In15.Cu")
		(net "USB3_CPU0_BMC_RX_HUB_C_DP")
	)
	(segment
		(start 135.35914 -33.220406)
		(end 135.35914 -32.929322)
		(width 0.14224)
		(layer "In15.Cu")
		(net "USB3_CPU0_BMC_RX_HUB_C_DP")
	)
	(segment
		(start 368.362738 -223.10217)
		(end 368.361722 -223.101662)
		(width 0.1143)
		(layer "In15.Cu")
		(net "USB3_CPU0_BMC_RX_HUB_C_DP")
	)
	(segment
		(start 368.361722 -223.101662)
		(end 368.359436 -223.100392)
		(width 0.1143)
		(layer "In15.Cu")
		(net "USB3_CPU0_BMC_RX_HUB_C_DP")
	)
	(segment
		(start 137.84326 -31.477458)
		(end 137.843514 -31.477458)
		(width 0.14224)
		(layer "In15.Cu")
		(net "USB3_CPU0_BMC_RX_HUB_C_DP")
	)
	(segment
		(start 172.18025 -169.9768)
		(end 159.043624 -164.535612)
		(width 0.14224)
		(layer "In15.Cu")
		(net "USB3_CPU0_BMC_RX_HUB_C_DP")
	)
	(segment
		(start 369.30203 -223.101662)
		(end 369.293394 -223.096582)
		(width 0.1143)
		(layer "In15.Cu")
		(net "USB3_CPU0_BMC_RX_HUB_C_DP")
	)
	(segment
		(start 368.35842 -223.099884)
		(end 368.323622 -223.07931)
		(width 0.1143)
		(layer "In15.Cu")
		(net "USB3_CPU0_BMC_RX_HUB_C_DP")
	)
	(segment
		(start 367.88598 -222.2881)
		(end 367.853214 -222.269304)
		(width 0.1143)
		(layer "In15.Cu")
		(net "USB3_CPU0_BMC_RX_HUB_C_DP")
	)
	(segment
		(start 134.216648 -41.38295)
		(end 135.43915 -38.432232)
		(width 0.14224)
		(layer "In15.Cu")
		(net "USB3_CPU0_BMC_RX_HUB_C_DP")
	)
	(segment
		(start 135.43915 -38.432232)
		(end 135.579104 -37.728906)
		(width 0.14224)
		(layer "In15.Cu")
		(net "USB3_CPU0_BMC_RX_HUB_C_DP")
	)
	(segment
		(start 311.005728 -173.013878)
		(end 307.1495 -173.013878)
		(width 0.14224)
		(layer "In15.Cu")
		(net "USB3_CPU0_BMC_RX_HUB_C_DP")
	)
	(segment
		(start 131.614926 -59.00801)
		(end 133.322822 -49.32299)
		(width 0.14224)
		(layer "In15.Cu")
		(net "USB3_CPU0_BMC_RX_HUB_C_DP")
	)
	(segment
		(start 137.843514 -31.477458)
		(end 137.860278 -31.47187)
		(width 0.14224)
		(layer "In15.Cu")
		(net "USB3_CPU0_BMC_RX_HUB_C_DP")
	)
	(segment
		(start 137.875264 -31.468822)
		(end 137.876788 -31.468568)
		(width 0.14224)
		(layer "In15.Cu")
		(net "USB3_CPU0_BMC_RX_HUB_C_DP")
	)
	(segment
		(start 133.93674 -75.6793)
		(end 133.93674 -72.176132)
		(width 0.14224)
		(layer "In15.Cu")
		(net "USB3_CPU0_BMC_RX_HUB_C_DP")
	)
	(segment
		(start 367.891822 -222.292164)
		(end 367.888266 -222.289624)
		(width 0.1143)
		(layer "In15.Cu")
		(net "USB3_CPU0_BMC_RX_HUB_C_DP")
	)
	(segment
		(start 135.579104 -33.75152)
		(end 135.35914 -33.220406)
		(width 0.14224)
		(layer "In15.Cu")
		(net "USB3_CPU0_BMC_RX_HUB_C_DP")
	)
	(segment
		(start 369.804188 -223.930718)
		(end 369.80241 -223.929448)
		(width 0.1143)
		(layer "In15.Cu")
		(net "USB3_CPU0_BMC_RX_HUB_C_DP")
	)
	(segment
		(start 370.352828 -225.044254)
		(end 370.422678 -225.07321)
		(width 0.1143)
		(layer "In15.Cu")
		(net "USB3_CPU0_BMC_RX_HUB_C_DP")
	)
	(arc
		(start 367.853214 -222.269304)
		(mid 367.782565 -222.211497)
		(end 367.72215 -222.143066)
		(width 0.1143)
		(layer "In15.Cu")
		(net "USB3_CPU0_BMC_RX_HUB_C_DP")
	)
	(arc
		(start 369.293394 -223.096582)
		(mid 369.109966 -223.051243)
		(end 368.927888 -223.101662)
		(width 0.1143)
		(layer "In15.Cu")
		(net "USB3_CPU0_BMC_RX_HUB_C_DP")
	)
	(arc
		(start 368.323622 -223.07931)
		(mid 368.144429 -222.8768)
		(end 368.079782 -222.614236)
		(width 0.1143)
		(layer "In15.Cu")
		(net "USB3_CPU0_BMC_RX_HUB_C_DP")
	)
	(arc
		(start 370.422678 -225.07321)
		(mid 370.391256 -224.886112)
		(end 370.271548 -224.738946)
		(width 0.1143)
		(layer "In15.Cu")
		(net "USB3_CPU0_BMC_RX_HUB_C_DP")
	)
	(arc
		(start 368.079782 -222.614236)
		(mid 368.038384 -222.443362)
		(end 367.923572 -222.310198)
		(width 0.1143)
		(layer "In15.Cu")
		(net "USB3_CPU0_BMC_RX_HUB_C_DP")
	)
	(arc
		(start 369.489736 -223.424242)
		(mid 369.448253 -223.252888)
		(end 369.333018 -223.119442)
		(width 0.1143)
		(layer "In15.Cu")
		(net "USB3_CPU0_BMC_RX_HUB_C_DP")
	)
	(arc
		(start 370.203476 -224.699322)
		(mid 370.024283 -224.496812)
		(end 369.959636 -224.234248)
		(width 0.1143)
		(layer "In15.Cu")
		(net "USB3_CPU0_BMC_RX_HUB_C_DP")
	)
	(arc
		(start 369.959636 -224.234248)
		(mid 369.918447 -224.063781)
		(end 369.804188 -223.930718)
		(width 0.1143)
		(layer "In15.Cu")
		(net "USB3_CPU0_BMC_RX_HUB_C_DP")
	)
	(arc
		(start 367.72215 -222.143066)
		(mid 367.652401 -222.03272)
		(end 367.609628 -221.909386)
		(width 0.1143)
		(layer "In15.Cu")
		(net "USB3_CPU0_BMC_RX_HUB_C_DP")
	)
	(arc
		(start 368.927888 -223.101662)
		(mid 368.651186 -223.177804)
		(end 368.372898 -223.107758)
		(width 0.1143)
		(layer "In15.Cu")
		(net "USB3_CPU0_BMC_RX_HUB_C_DP")
	)
	(arc
		(start 369.734338 -223.889824)
		(mid 369.554546 -223.687236)
		(end 369.489736 -223.424242)
		(width 0.1143)
		(layer "In15.Cu")
		(net "USB3_CPU0_BMC_RX_HUB_C_DP")
	)
	(segment
		(start 140.02512 -31.22676)
		(end 140.22832 -31.22676)
		(width 0.12954)
		(layer "F.Cu")
		(net "USB3_CPU0_BMC_RX_HUB_C_DN")
	)
	(segment
		(start 370.527834 -225.310192)
		(end 370.994686 -225.044254)
		(width 0.12954)
		(layer "F.Cu")
		(net "USB3_CPU0_BMC_RX_HUB_C_DN")
	)
	(segment
		(start 140.22832 -31.22676)
		(end 140.66012 -31.65856)
		(width 0.12954)
		(layer "F.Cu")
		(net "USB3_CPU0_BMC_RX_HUB_C_DN")
	)
	(segment
		(start 135.861044 -37.07384)
		(end 135.998204 -36.93668)
		(width 0.14224)
		(layer "In15.Cu")
		(net "USB3_CPU0_BMC_RX_HUB_C_DN")
	)
	(segment
		(start 367.984278 -222.124778)
		(end 367.983516 -222.12427)
		(width 0.1143)
		(layer "In15.Cu")
		(net "USB3_CPU0_BMC_RX_HUB_C_DN")
	)
	(segment
		(start 135.861044 -36.37534)
		(end 135.861044 -35.95116)
		(width 0.14224)
		(layer "In15.Cu")
		(net "USB3_CPU0_BMC_RX_HUB_C_DN")
	)
	(segment
		(start 369.906804 -223.769682)
		(end 369.837208 -223.729042)
		(width 0.1143)
		(layer "In15.Cu")
		(net "USB3_CPU0_BMC_RX_HUB_C_DN")
	)
	(segment
		(start 138.847068 -31.70047)
		(end 139.246102 -31.621222)
		(width 0.14224)
		(layer "In15.Cu")
		(net "USB3_CPU0_BMC_RX_HUB_C_DN")
	)
	(segment
		(start 134.26821 -139.37869)
		(end 128.629664 -107.40136)
		(width 0.14224)
		(layer "In15.Cu")
		(net "USB3_CPU0_BMC_RX_HUB_C_DN")
	)
	(segment
		(start 137.932668 -31.745174)
		(end 138.688826 -31.594806)
		(width 0.14224)
		(layer "In15.Cu")
		(net "USB3_CPU0_BMC_RX_HUB_C_DN")
	)
	(segment
		(start 135.998204 -35.814)
		(end 135.998204 -35.38982)
		(width 0.14224)
		(layer "In15.Cu")
		(net "USB3_CPU0_BMC_RX_HUB_C_DN")
	)
	(segment
		(start 367.845848 -221.391988)
		(end 367.845848 -220.084142)
		(width 0.14224)
		(layer "In15.Cu")
		(net "USB3_CPU0_BMC_RX_HUB_C_DN")
	)
	(segment
		(start 367.800128 -221.886018)
		(end 367.800128 -221.466156)
		(width 0.1143)
		(layer "In15.Cu")
		(net "USB3_CPU0_BMC_RX_HUB_C_DN")
	)
	(segment
		(start 139.351766 -31.462726)
		(end 139.828778 -31.367984)
		(width 0.14224)
		(layer "In15.Cu")
		(net "USB3_CPU0_BMC_RX_HUB_C_DN")
	)
	(segment
		(start 135.995664 -34.28746)
		(end 135.861044 -34.15284)
		(width 0.14224)
		(layer "In15.Cu")
		(net "USB3_CPU0_BMC_RX_HUB_C_DN")
	)
	(segment
		(start 139.351766 -31.462472)
		(end 139.351766 -31.462726)
		(width 0.14224)
		(layer "In15.Cu")
		(net "USB3_CPU0_BMC_RX_HUB_C_DN")
	)
	(segment
		(start 139.829032 -31.36773)
		(end 140.36929 -31.36773)
		(width 0.14224)
		(layer "In15.Cu")
		(net "USB3_CPU0_BMC_RX_HUB_C_DN")
	)
	(segment
		(start 311.061862 -172.731938)
		(end 307.151024 -172.731938)
		(width 0.14224)
		(layer "In15.Cu")
		(net "USB3_CPU0_BMC_RX_HUB_C_DN")
	)
	(segment
		(start 136.692386 -32.158686)
		(end 137.932668 -31.745174)
		(width 0.14224)
		(layer "In15.Cu")
		(net "USB3_CPU0_BMC_RX_HUB_C_DN")
	)
	(segment
		(start 135.861044 -37.756846)
		(end 135.861044 -37.07384)
		(width 0.14224)
		(layer "In15.Cu")
		(net "USB3_CPU0_BMC_RX_HUB_C_DN")
	)
	(segment
		(start 370.374164 -224.57791)
		(end 370.337842 -224.556828)
		(width 0.1143)
		(layer "In15.Cu")
		(net "USB3_CPU0_BMC_RX_HUB_C_DN")
	)
	(segment
		(start 307.151024 -172.731938)
		(end 200.611486 -171.601384)
		(width 0.14224)
		(layer "In15.Cu")
		(net "USB3_CPU0_BMC_RX_HUB_C_DN")
	)
	(segment
		(start 135.805418 -38.037008)
		(end 135.861044 -37.756846)
		(width 0.14224)
		(layer "In15.Cu")
		(net "USB3_CPU0_BMC_RX_HUB_C_DN")
	)
	(segment
		(start 370.337842 -224.556828)
		(end 370.306092 -224.53854)
		(width 0.1143)
		(layer "In15.Cu")
		(net "USB3_CPU0_BMC_RX_HUB_C_DN")
	)
	(segment
		(start 367.987834 -222.12681)
		(end 367.987072 -222.126302)
		(width 0.1143)
		(layer "In15.Cu")
		(net "USB3_CPU0_BMC_RX_HUB_C_DN")
	)
	(segment
		(start 131.901438 -59.00801)
		(end 133.60273 -49.35982)
		(width 0.14224)
		(layer "In15.Cu")
		(net "USB3_CPU0_BMC_RX_HUB_C_DN")
	)
	(segment
		(start 135.998204 -35.38982)
		(end 135.861044 -35.25266)
		(width 0.14224)
		(layer "In15.Cu")
		(net "USB3_CPU0_BMC_RX_HUB_C_DN")
	)
	(segment
		(start 135.995664 -34.69386)
		(end 135.995664 -34.28746)
		(width 0.14224)
		(layer "In15.Cu")
		(net "USB3_CPU0_BMC_RX_HUB_C_DN")
	)
	(segment
		(start 128.629664 -107.40136)
		(end 134.21868 -75.704192)
		(width 0.14224)
		(layer "In15.Cu")
		(net "USB3_CPU0_BMC_RX_HUB_C_DN")
	)
	(segment
		(start 135.710422 -38.514528)
		(end 135.805418 -38.037262)
		(width 0.14224)
		(layer "In15.Cu")
		(net "USB3_CPU0_BMC_RX_HUB_C_DN")
	)
	(segment
		(start 134.21868 -72.15124)
		(end 131.901438 -59.00801)
		(width 0.14224)
		(layer "In15.Cu")
		(net "USB3_CPU0_BMC_RX_HUB_C_DN")
	)
	(segment
		(start 139.246102 -31.621222)
		(end 139.351766 -31.462472)
		(width 0.14224)
		(layer "In15.Cu")
		(net "USB3_CPU0_BMC_RX_HUB_C_DN")
	)
	(segment
		(start 133.60273 -49.35982)
		(end 134.185914 -42.695622)
		(width 0.14224)
		(layer "In15.Cu")
		(net "USB3_CPU0_BMC_RX_HUB_C_DN")
	)
	(segment
		(start 144.523206 -154.02433)
		(end 134.26821 -139.37869)
		(width 0.14224)
		(layer "In15.Cu")
		(net "USB3_CPU0_BMC_RX_HUB_C_DN")
	)
	(segment
		(start 368.46637 -222.941642)
		(end 368.457988 -222.936816)
		(width 0.1143)
		(layer "In15.Cu")
		(net "USB3_CPU0_BMC_RX_HUB_C_DN")
	)
	(segment
		(start 369.397788 -222.936816)
		(end 369.387374 -222.93072)
		(width 0.1143)
		(layer "In15.Cu")
		(net "USB3_CPU0_BMC_RX_HUB_C_DN")
	)
	(segment
		(start 135.805418 -38.037262)
		(end 135.805418 -38.037008)
		(width 0.14224)
		(layer "In15.Cu")
		(net "USB3_CPU0_BMC_RX_HUB_C_DN")
	)
	(segment
		(start 136.147048 -32.384492)
		(end 136.692386 -32.158686)
		(width 0.14224)
		(layer "In15.Cu")
		(net "USB3_CPU0_BMC_RX_HUB_C_DN")
	)
	(segment
		(start 367.983516 -222.12427)
		(end 367.981484 -222.123254)
		(width 0.1143)
		(layer "In15.Cu")
		(net "USB3_CPU0_BMC_RX_HUB_C_DN")
	)
	(segment
		(start 135.998204 -36.93668)
		(end 135.998204 -36.5125)
		(width 0.14224)
		(layer "In15.Cu")
		(net "USB3_CPU0_BMC_RX_HUB_C_DN")
	)
	(segment
		(start 139.828778 -31.367984)
		(end 139.829032 -31.36773)
		(width 0.14224)
		(layer "In15.Cu")
		(net "USB3_CPU0_BMC_RX_HUB_C_DN")
	)
	(segment
		(start 135.64108 -32.985456)
		(end 135.70839 -32.82315)
		(width 0.14224)
		(layer "In15.Cu")
		(net "USB3_CPU0_BMC_RX_HUB_C_DN")
	)
	(segment
		(start 135.70839 -32.82315)
		(end 136.147048 -32.384492)
		(width 0.14224)
		(layer "In15.Cu")
		(net "USB3_CPU0_BMC_RX_HUB_C_DN")
	)
	(segment
		(start 369.435634 -222.95866)
		(end 369.397788 -222.936816)
		(width 0.1143)
		(layer "In15.Cu")
		(net "USB3_CPU0_BMC_RX_HUB_C_DN")
	)
	(segment
		(start 182.488078 -170.36034)
		(end 172.24502 -169.698416)
		(width 0.14224)
		(layer "In15.Cu")
		(net "USB3_CPU0_BMC_RX_HUB_C_DN")
	)
	(segment
		(start 135.64108 -33.164272)
		(end 135.64108 -32.985456)
		(width 0.14224)
		(layer "In15.Cu")
		(net "USB3_CPU0_BMC_RX_HUB_C_DN")
	)
	(segment
		(start 370.994686 -225.044254)
		(end 370.696744 -225.044254)
		(width 0.1143)
		(layer "In15.Cu")
		(net "USB3_CPU0_BMC_RX_HUB_C_DN")
	)
	(segment
		(start 172.24502 -169.698416)
		(end 159.180276 -164.286692)
		(width 0.14224)
		(layer "In15.Cu")
		(net "USB3_CPU0_BMC_RX_HUB_C_DN")
	)
	(segment
		(start 135.861044 -34.82848)
		(end 135.995664 -34.69386)
		(width 0.14224)
		(layer "In15.Cu")
		(net "USB3_CPU0_BMC_RX_HUB_C_DN")
	)
	(segment
		(start 367.845848 -221.420436)
		(end 367.845848 -221.391988)
		(width 0.1143)
		(layer "In15.Cu")
		(net "USB3_CPU0_BMC_RX_HUB_C_DN")
	)
	(segment
		(start 134.185914 -42.695622)
		(end 134.485634 -41.471088)
		(width 0.14224)
		(layer "In15.Cu")
		(net "USB3_CPU0_BMC_RX_HUB_C_DN")
	)
	(segment
		(start 368.457988 -222.936816)
		(end 368.455956 -222.9358)
		(width 0.1143)
		(layer "In15.Cu")
		(net "USB3_CPU0_BMC_RX_HUB_C_DN")
	)
	(segment
		(start 367.98885 -222.127318)
		(end 367.987834 -222.12681)
		(width 0.1143)
		(layer "In15.Cu")
		(net "USB3_CPU0_BMC_RX_HUB_C_DN")
	)
	(segment
		(start 134.21868 -75.704192)
		(end 134.21868 -72.15124)
		(width 0.14224)
		(layer "In15.Cu")
		(net "USB3_CPU0_BMC_RX_HUB_C_DN")
	)
	(segment
		(start 370.696744 -225.044254)
		(end 370.61394 -224.96145)
		(width 0.1143)
		(layer "In15.Cu")
		(net "USB3_CPU0_BMC_RX_HUB_C_DN")
	)
	(segment
		(start 191.95923 -170.375834)
		(end 182.488078 -170.36034)
		(width 0.14224)
		(layer "In15.Cu")
		(net "USB3_CPU0_BMC_RX_HUB_C_DN")
	)
	(segment
		(start 368.02695 -222.14967)
		(end 367.98885 -222.127318)
		(width 0.1143)
		(layer "In15.Cu")
		(net "USB3_CPU0_BMC_RX_HUB_C_DN")
	)
	(segment
		(start 367.987072 -222.126302)
		(end 367.984278 -222.124778)
		(width 0.1143)
		(layer "In15.Cu")
		(net "USB3_CPU0_BMC_RX_HUB_C_DN")
	)
	(segment
		(start 134.485634 -41.471088)
		(end 135.710422 -38.514528)
		(width 0.14224)
		(layer "In15.Cu")
		(net "USB3_CPU0_BMC_RX_HUB_C_DN")
	)
	(segment
		(start 368.455956 -222.9358)
		(end 368.426238 -222.918528)
		(width 0.1143)
		(layer "In15.Cu")
		(net "USB3_CPU0_BMC_RX_HUB_C_DN")
	)
	(segment
		(start 135.998204 -36.5125)
		(end 135.861044 -36.37534)
		(width 0.14224)
		(layer "In15.Cu")
		(net "USB3_CPU0_BMC_RX_HUB_C_DN")
	)
	(segment
		(start 367.981484 -222.123254)
		(end 367.956084 -222.108522)
		(width 0.1143)
		(layer "In15.Cu")
		(net "USB3_CPU0_BMC_RX_HUB_C_DN")
	)
	(segment
		(start 327.162922 -179.401216)
		(end 311.061862 -172.731938)
		(width 0.14224)
		(layer "In15.Cu")
		(net "USB3_CPU0_BMC_RX_HUB_C_DN")
	)
	(segment
		(start 140.36929 -31.36773)
		(end 140.66012 -31.65856)
		(width 0.14224)
		(layer "In15.Cu")
		(net "USB3_CPU0_BMC_RX_HUB_C_DN")
	)
	(segment
		(start 135.861044 -33.695386)
		(end 135.64108 -33.164272)
		(width 0.14224)
		(layer "In15.Cu")
		(net "USB3_CPU0_BMC_RX_HUB_C_DN")
	)
	(segment
		(start 159.180276 -164.286692)
		(end 144.523206 -154.02433)
		(width 0.14224)
		(layer "In15.Cu")
		(net "USB3_CPU0_BMC_RX_HUB_C_DN")
	)
	(segment
		(start 200.611486 -171.601384)
		(end 191.95923 -170.375834)
		(width 0.14224)
		(layer "In15.Cu")
		(net "USB3_CPU0_BMC_RX_HUB_C_DN")
	)
	(segment
		(start 135.861044 -35.95116)
		(end 135.998204 -35.814)
		(width 0.14224)
		(layer "In15.Cu")
		(net "USB3_CPU0_BMC_RX_HUB_C_DN")
	)
	(segment
		(start 135.861044 -35.25266)
		(end 135.861044 -34.82848)
		(width 0.14224)
		(layer "In15.Cu")
		(net "USB3_CPU0_BMC_RX_HUB_C_DN")
	)
	(segment
		(start 367.845848 -220.084142)
		(end 327.162922 -179.401216)
		(width 0.14224)
		(layer "In15.Cu")
		(net "USB3_CPU0_BMC_RX_HUB_C_DN")
	)
	(segment
		(start 138.688826 -31.594806)
		(end 138.847068 -31.70047)
		(width 0.14224)
		(layer "In15.Cu")
		(net "USB3_CPU0_BMC_RX_HUB_C_DN")
	)
	(segment
		(start 367.800128 -221.466156)
		(end 367.845848 -221.420436)
		(width 0.1143)
		(layer "In15.Cu")
		(net "USB3_CPU0_BMC_RX_HUB_C_DN")
	)
	(segment
		(start 135.861044 -34.15284)
		(end 135.861044 -33.695386)
		(width 0.14224)
		(layer "In15.Cu")
		(net "USB3_CPU0_BMC_RX_HUB_C_DN")
	)
	(arc
		(start 369.837208 -223.729042)
		(mid 369.721781 -223.595666)
		(end 369.680236 -223.424242)
		(width 0.1143)
		(layer "In15.Cu")
		(net "USB3_CPU0_BMC_RX_HUB_C_DN")
	)
	(arc
		(start 370.306092 -224.53854)
		(mid 370.191416 -224.405206)
		(end 370.150136 -224.234248)
		(width 0.1143)
		(layer "In15.Cu")
		(net "USB3_CPU0_BMC_RX_HUB_C_DN")
	)
	(arc
		(start 370.61394 -224.96145)
		(mid 370.53409 -224.744652)
		(end 370.374164 -224.57791)
		(width 0.1143)
		(layer "In15.Cu")
		(net "USB3_CPU0_BMC_RX_HUB_C_DN")
	)
	(arc
		(start 368.270282 -222.614236)
		(mid 368.205767 -222.352017)
		(end 368.02695 -222.14967)
		(width 0.1143)
		(layer "In15.Cu")
		(net "USB3_CPU0_BMC_RX_HUB_C_DN")
	)
	(arc
		(start 368.426238 -222.918528)
		(mid 368.311562 -222.785194)
		(end 368.270282 -222.614236)
		(width 0.1143)
		(layer "In15.Cu")
		(net "USB3_CPU0_BMC_RX_HUB_C_DN")
	)
	(arc
		(start 370.150136 -224.234248)
		(mid 370.085621 -223.972029)
		(end 369.906804 -223.769682)
		(width 0.1143)
		(layer "In15.Cu")
		(net "USB3_CPU0_BMC_RX_HUB_C_DN")
	)
	(arc
		(start 369.387374 -222.93072)
		(mid 369.108942 -222.860622)
		(end 368.83213 -222.936816)
		(width 0.1143)
		(layer "In15.Cu")
		(net "USB3_CPU0_BMC_RX_HUB_C_DN")
	)
	(arc
		(start 369.680236 -223.424242)
		(mid 369.615364 -223.161279)
		(end 369.435634 -222.95866)
		(width 0.1143)
		(layer "In15.Cu")
		(net "USB3_CPU0_BMC_RX_HUB_C_DN")
	)
	(arc
		(start 367.956084 -222.108522)
		(mid 367.911179 -222.070526)
		(end 367.872772 -222.025972)
		(width 0.1143)
		(layer "In15.Cu")
		(net "USB3_CPU0_BMC_RX_HUB_C_DN")
	)
	(arc
		(start 367.872772 -222.025972)
		(mid 367.82909 -221.959816)
		(end 367.800128 -221.886018)
		(width 0.1143)
		(layer "In15.Cu")
		(net "USB3_CPU0_BMC_RX_HUB_C_DN")
	)
	(arc
		(start 368.83213 -222.936816)
		(mid 368.649879 -222.987166)
		(end 368.46637 -222.941642)
		(width 0.1143)
		(layer "In15.Cu")
		(net "USB3_CPU0_BMC_RX_HUB_C_DN")
	)
	(segment
		(start 141.29512 -30.113986)
		(end 140.82268 -29.641546)
		(width 0.12954)
		(layer "F.Cu")
		(net "USB3_CPU0_BMC_RX_HUB2_DP")
	)
	(segment
		(start 140.82268 -28.775152)
		(end 141.09827 -28.499562)
		(width 0.12954)
		(layer "F.Cu")
		(net "USB3_CPU0_BMC_RX_HUB2_DP")
	)
	(segment
		(start 108.071666 -32.15894)
		(end 106.28757 -32.15894)
		(width 0.12954)
		(layer "F.Cu")
		(net "USB3_CPU0_BMC_RX_HUB2_DP")
	)
	(segment
		(start 140.82268 -29.641546)
		(end 140.82268 -28.775152)
		(width 0.12954)
		(layer "F.Cu")
		(net "USB3_CPU0_BMC_RX_HUB2_DP")
	)
	(segment
		(start 108.160566 -32.24784)
		(end 108.071666 -32.15894)
		(width 0.12954)
		(layer "F.Cu")
		(net "USB3_CPU0_BMC_RX_HUB2_DP")
	)
	(segment
		(start 108.398818 -32.24784)
		(end 108.160566 -32.24784)
		(width 0.12954)
		(layer "F.Cu")
		(net "USB3_CPU0_BMC_RX_HUB2_DP")
	)
	(segment
		(start 106.28757 -32.15894)
		(end 106.041444 -32.405066)
		(width 0.12954)
		(layer "F.Cu")
		(net "USB3_CPU0_BMC_RX_HUB2_DP")
	)
	(segment
		(start 141.29512 -30.42666)
		(end 141.29512 -30.113986)
		(width 0.12954)
		(layer "F.Cu")
		(net "USB3_CPU0_BMC_RX_HUB2_DP")
	)
	(segment
		(start 140.22578 -29.915612)
		(end 140.830808 -29.310584)
		(width 0.14224)
		(layer "In11.Cu")
		(net "USB3_CPU0_BMC_RX_HUB2_DP")
	)
	(segment
		(start 119.45874 -38.27526)
		(end 122.9868 -38.27526)
		(width 0.14224)
		(layer "In11.Cu")
		(net "USB3_CPU0_BMC_RX_HUB2_DP")
	)
	(segment
		(start 140.830808 -28.767024)
		(end 141.09827 -28.499562)
		(width 0.14224)
		(layer "In11.Cu")
		(net "USB3_CPU0_BMC_RX_HUB2_DP")
	)
	(segment
		(start 106.463338 -32.114236)
		(end 107.977432 -32.741616)
		(width 0.14224)
		(layer "In11.Cu")
		(net "USB3_CPU0_BMC_RX_HUB2_DP")
	)
	(segment
		(start 130.45186 -33.39084)
		(end 132.820664 -31.022036)
		(width 0.14224)
		(layer "In11.Cu")
		(net "USB3_CPU0_BMC_RX_HUB2_DP")
	)
	(segment
		(start 107.977432 -32.741616)
		(end 109.305598 -34.069782)
		(width 0.14224)
		(layer "In11.Cu")
		(net "USB3_CPU0_BMC_RX_HUB2_DP")
	)
	(segment
		(start 140.830808 -29.310584)
		(end 140.830808 -28.767024)
		(width 0.14224)
		(layer "In11.Cu")
		(net "USB3_CPU0_BMC_RX_HUB2_DP")
	)
	(segment
		(start 124.772166 -36.489894)
		(end 125.20676 -35.440874)
		(width 0.14224)
		(layer "In11.Cu")
		(net "USB3_CPU0_BMC_RX_HUB2_DP")
	)
	(segment
		(start 122.9868 -38.27526)
		(end 124.772166 -36.489894)
		(width 0.14224)
		(layer "In11.Cu")
		(net "USB3_CPU0_BMC_RX_HUB2_DP")
	)
	(segment
		(start 106.332274 -32.114236)
		(end 106.463338 -32.114236)
		(width 0.14224)
		(layer "In11.Cu")
		(net "USB3_CPU0_BMC_RX_HUB2_DP")
	)
	(segment
		(start 109.305598 -34.069782)
		(end 119.45874 -38.27526)
		(width 0.14224)
		(layer "In11.Cu")
		(net "USB3_CPU0_BMC_RX_HUB2_DP")
	)
	(segment
		(start 136.300464 -31.022036)
		(end 137.406888 -29.915612)
		(width 0.14224)
		(layer "In11.Cu")
		(net "USB3_CPU0_BMC_RX_HUB2_DP")
	)
	(segment
		(start 125.20676 -35.440874)
		(end 125.20676 -35.44062)
		(width 0.14224)
		(layer "In11.Cu")
		(net "USB3_CPU0_BMC_RX_HUB2_DP")
	)
	(segment
		(start 106.041444 -32.405066)
		(end 106.332274 -32.114236)
		(width 0.14224)
		(layer "In11.Cu")
		(net "USB3_CPU0_BMC_RX_HUB2_DP")
	)
	(segment
		(start 132.820664 -31.022036)
		(end 136.300464 -31.022036)
		(width 0.14224)
		(layer "In11.Cu")
		(net "USB3_CPU0_BMC_RX_HUB2_DP")
	)
	(segment
		(start 137.406888 -29.915612)
		(end 140.22578 -29.915612)
		(width 0.14224)
		(layer "In11.Cu")
		(net "USB3_CPU0_BMC_RX_HUB2_DP")
	)
	(segment
		(start 127.25654 -33.39084)
		(end 130.45186 -33.39084)
		(width 0.14224)
		(layer "In11.Cu")
		(net "USB3_CPU0_BMC_RX_HUB2_DP")
	)
	(segment
		(start 125.20676 -35.44062)
		(end 127.25654 -33.39084)
		(width 0.14224)
		(layer "In11.Cu")
		(net "USB3_CPU0_BMC_RX_HUB2_DP")
	)
	(segment
		(start 140.02512 -30.11424)
		(end 140.5001 -29.63926)
		(width 0.12954)
		(layer "F.Cu")
		(net "USB3_CPU0_BMC_RX_HUB2_DN")
	)
	(segment
		(start 108.074206 -31.83636)
		(end 106.336338 -31.83636)
		(width 0.12954)
		(layer "F.Cu")
		(net "USB3_CPU0_BMC_RX_HUB2_DN")
	)
	(segment
		(start 108.162852 -31.747714)
		(end 108.074206 -31.83636)
		(width 0.12954)
		(layer "F.Cu")
		(net "USB3_CPU0_BMC_RX_HUB2_DN")
	)
	(segment
		(start 108.398818 -31.747714)
		(end 108.162852 -31.747714)
		(width 0.12954)
		(layer "F.Cu")
		(net "USB3_CPU0_BMC_RX_HUB2_DN")
	)
	(segment
		(start 140.02512 -30.42666)
		(end 140.02512 -30.11424)
		(width 0.12954)
		(layer "F.Cu")
		(net "USB3_CPU0_BMC_RX_HUB2_DN")
	)
	(segment
		(start 106.336338 -31.83636)
		(end 106.041444 -31.541466)
		(width 0.12954)
		(layer "F.Cu")
		(net "USB3_CPU0_BMC_RX_HUB2_DN")
	)
	(segment
		(start 140.5001 -28.764992)
		(end 140.23467 -28.499562)
		(width 0.12954)
		(layer "F.Cu")
		(net "USB3_CPU0_BMC_RX_HUB2_DN")
	)
	(segment
		(start 140.5001 -29.63926)
		(end 140.5001 -28.764992)
		(width 0.12954)
		(layer "F.Cu")
		(net "USB3_CPU0_BMC_RX_HUB2_DN")
	)
	(segment
		(start 130.33502 -33.1089)
		(end 131.90982 -31.5341)
		(width 0.14224)
		(layer "In11.Cu")
		(net "USB3_CPU0_BMC_RX_HUB2_DN")
	)
	(segment
		(start 131.90982 -31.5341)
		(end 131.90982 -31.340044)
		(width 0.14224)
		(layer "In11.Cu")
		(net "USB3_CPU0_BMC_RX_HUB2_DN")
	)
	(segment
		(start 106.041444 -31.541466)
		(end 106.332274 -31.832296)
		(width 0.14224)
		(layer "In11.Cu")
		(net "USB3_CPU0_BMC_RX_HUB2_DN")
	)
	(segment
		(start 127.1397 -33.1089)
		(end 130.33502 -33.1089)
		(width 0.14224)
		(layer "In11.Cu")
		(net "USB3_CPU0_BMC_RX_HUB2_DN")
	)
	(segment
		(start 133.63575 -30.602936)
		(end 134.05993 -30.602936)
		(width 0.14224)
		(layer "In11.Cu")
		(net "USB3_CPU0_BMC_RX_HUB2_DN")
	)
	(segment
		(start 138.618722 -29.633672)
		(end 140.10894 -29.633672)
		(width 0.14224)
		(layer "In11.Cu")
		(net "USB3_CPU0_BMC_RX_HUB2_DN")
	)
	(segment
		(start 137.917682 -29.633672)
		(end 138.054842 -29.496512)
		(width 0.14224)
		(layer "In11.Cu")
		(net "USB3_CPU0_BMC_RX_HUB2_DN")
	)
	(segment
		(start 136.183624 -30.740096)
		(end 137.290048 -29.633672)
		(width 0.14224)
		(layer "In11.Cu")
		(net "USB3_CPU0_BMC_RX_HUB2_DN")
	)
	(segment
		(start 132.703824 -30.740096)
		(end 133.49859 -30.740096)
		(width 0.14224)
		(layer "In11.Cu")
		(net "USB3_CPU0_BMC_RX_HUB2_DN")
	)
	(segment
		(start 138.481562 -29.496512)
		(end 138.618722 -29.633672)
		(width 0.14224)
		(layer "In11.Cu")
		(net "USB3_CPU0_BMC_RX_HUB2_DN")
	)
	(segment
		(start 109.465364 -33.830768)
		(end 119.514874 -37.99332)
		(width 0.14224)
		(layer "In11.Cu")
		(net "USB3_CPU0_BMC_RX_HUB2_DN")
	)
	(segment
		(start 135.18261 -30.602936)
		(end 135.31977 -30.740096)
		(width 0.14224)
		(layer "In11.Cu")
		(net "USB3_CPU0_BMC_RX_HUB2_DN")
	)
	(segment
		(start 124.533152 -36.330128)
		(end 124.967746 -35.280854)
		(width 0.14224)
		(layer "In11.Cu")
		(net "USB3_CPU0_BMC_RX_HUB2_DN")
	)
	(segment
		(start 133.49859 -30.740096)
		(end 133.63575 -30.602936)
		(width 0.14224)
		(layer "In11.Cu")
		(net "USB3_CPU0_BMC_RX_HUB2_DN")
	)
	(segment
		(start 122.86996 -37.99332)
		(end 124.533152 -36.330128)
		(width 0.14224)
		(layer "In11.Cu")
		(net "USB3_CPU0_BMC_RX_HUB2_DN")
	)
	(segment
		(start 134.75843 -30.602936)
		(end 135.18261 -30.602936)
		(width 0.14224)
		(layer "In11.Cu")
		(net "USB3_CPU0_BMC_RX_HUB2_DN")
	)
	(segment
		(start 134.62127 -30.740096)
		(end 134.75843 -30.602936)
		(width 0.14224)
		(layer "In11.Cu")
		(net "USB3_CPU0_BMC_RX_HUB2_DN")
	)
	(segment
		(start 124.967746 -35.280854)
		(end 127.1397 -33.1089)
		(width 0.14224)
		(layer "In11.Cu")
		(net "USB3_CPU0_BMC_RX_HUB2_DN")
	)
	(segment
		(start 135.31977 -30.740096)
		(end 136.183624 -30.740096)
		(width 0.14224)
		(layer "In11.Cu")
		(net "USB3_CPU0_BMC_RX_HUB2_DN")
	)
	(segment
		(start 119.514874 -37.99332)
		(end 122.86996 -37.99332)
		(width 0.14224)
		(layer "In11.Cu")
		(net "USB3_CPU0_BMC_RX_HUB2_DN")
	)
	(segment
		(start 138.054842 -29.496512)
		(end 138.481562 -29.496512)
		(width 0.14224)
		(layer "In11.Cu")
		(net "USB3_CPU0_BMC_RX_HUB2_DN")
	)
	(segment
		(start 131.90982 -31.340044)
		(end 132.210048 -31.039816)
		(width 0.14224)
		(layer "In11.Cu")
		(net "USB3_CPU0_BMC_RX_HUB2_DN")
	)
	(segment
		(start 134.19709 -30.740096)
		(end 134.62127 -30.740096)
		(width 0.14224)
		(layer "In11.Cu")
		(net "USB3_CPU0_BMC_RX_HUB2_DN")
	)
	(segment
		(start 132.404104 -31.039816)
		(end 132.703824 -30.740096)
		(width 0.14224)
		(layer "In11.Cu")
		(net "USB3_CPU0_BMC_RX_HUB2_DN")
	)
	(segment
		(start 132.210048 -31.039816)
		(end 132.404104 -31.039816)
		(width 0.14224)
		(layer "In11.Cu")
		(net "USB3_CPU0_BMC_RX_HUB2_DN")
	)
	(segment
		(start 140.10894 -29.633672)
		(end 140.548868 -29.193744)
		(width 0.14224)
		(layer "In11.Cu")
		(net "USB3_CPU0_BMC_RX_HUB2_DN")
	)
	(segment
		(start 108.137198 -32.502602)
		(end 109.465364 -33.830768)
		(width 0.14224)
		(layer "In11.Cu")
		(net "USB3_CPU0_BMC_RX_HUB2_DN")
	)
	(segment
		(start 137.290048 -29.633672)
		(end 137.917682 -29.633672)
		(width 0.14224)
		(layer "In11.Cu")
		(net "USB3_CPU0_BMC_RX_HUB2_DN")
	)
	(segment
		(start 140.548868 -29.193744)
		(end 140.548868 -28.81376)
		(width 0.14224)
		(layer "In11.Cu")
		(net "USB3_CPU0_BMC_RX_HUB2_DN")
	)
	(segment
		(start 140.548868 -28.81376)
		(end 140.23467 -28.499562)
		(width 0.14224)
		(layer "In11.Cu")
		(net "USB3_CPU0_BMC_RX_HUB2_DN")
	)
	(segment
		(start 134.05993 -30.602936)
		(end 134.19709 -30.740096)
		(width 0.14224)
		(layer "In11.Cu")
		(net "USB3_CPU0_BMC_RX_HUB2_DN")
	)
	(segment
		(start 106.519472 -31.832296)
		(end 108.137198 -32.502602)
		(width 0.14224)
		(layer "In11.Cu")
		(net "USB3_CPU0_BMC_RX_HUB2_DN")
	)
	(segment
		(start 106.332274 -31.832296)
		(end 106.519472 -31.832296)
		(width 0.14224)
		(layer "In11.Cu")
		(net "USB3_CPU0_BMC_RX_HUB2_DN")
	)
	(segment
		(start 139.53871 -35.627564)
		(end 140.84173 -34.324544)
		(width 0.12954)
		(layer "F.Cu")
		(net "USB3_CPU0_BMC_RX_HUB1_DP")
	)
	(segment
		(start 141.29512 -32.3977)
		(end 141.29512 -32.02686)
		(width 0.12954)
		(layer "F.Cu")
		(net "USB3_CPU0_BMC_RX_HUB1_DP")
	)
	(segment
		(start 137.182098 -35.673538)
		(end 137.228072 -35.627564)
		(width 0.12954)
		(layer "F.Cu")
		(net "USB3_CPU0_BMC_RX_HUB1_DP")
	)
	(segment
		(start 137.228072 -35.627564)
		(end 139.53871 -35.627564)
		(width 0.12954)
		(layer "F.Cu")
		(net "USB3_CPU0_BMC_RX_HUB1_DP")
	)
	(segment
		(start 136.54405 -35.673538)
		(end 137.182098 -35.673538)
		(width 0.12954)
		(layer "F.Cu")
		(net "USB3_CPU0_BMC_RX_HUB1_DP")
	)
	(segment
		(start 140.84173 -32.85109)
		(end 141.29512 -32.3977)
		(width 0.12954)
		(layer "F.Cu")
		(net "USB3_CPU0_BMC_RX_HUB1_DP")
	)
	(segment
		(start 140.84173 -34.324544)
		(end 140.84173 -32.85109)
		(width 0.12954)
		(layer "F.Cu")
		(net "USB3_CPU0_BMC_RX_HUB1_DP")
	)
	(segment
		(start 137.182352 -35.273488)
		(end 137.213848 -35.304984)
		(width 0.12954)
		(layer "F.Cu")
		(net "USB3_CPU0_BMC_RX_HUB1_DN")
	)
	(segment
		(start 140.32865 -33.253426)
		(end 140.51915 -33.062926)
		(width 0.12954)
		(layer "F.Cu")
		(net "USB3_CPU0_BMC_RX_HUB1_DN")
	)
	(segment
		(start 140.51915 -33.830006)
		(end 140.32865 -33.639506)
		(width 0.12954)
		(layer "F.Cu")
		(net "USB3_CPU0_BMC_RX_HUB1_DN")
	)
	(segment
		(start 139.677648 -35.032188)
		(end 139.677648 -34.762694)
		(width 0.12954)
		(layer "F.Cu")
		(net "USB3_CPU0_BMC_RX_HUB1_DN")
	)
	(segment
		(start 138.442192 -35.114484)
		(end 138.828272 -35.114484)
		(width 0.12954)
		(layer "F.Cu")
		(net "USB3_CPU0_BMC_RX_HUB1_DN")
	)
	(segment
		(start 140.51915 -33.062926)
		(end 140.51915 -32.848804)
		(width 0.12954)
		(layer "F.Cu")
		(net "USB3_CPU0_BMC_RX_HUB1_DN")
	)
	(segment
		(start 138.828272 -35.114484)
		(end 139.018772 -35.304984)
		(width 0.12954)
		(layer "F.Cu")
		(net "USB3_CPU0_BMC_RX_HUB1_DN")
	)
	(segment
		(start 139.018772 -35.304984)
		(end 139.404852 -35.304984)
		(width 0.12954)
		(layer "F.Cu")
		(net "USB3_CPU0_BMC_RX_HUB1_DN")
	)
	(segment
		(start 140.02512 -32.354774)
		(end 140.02512 -32.02686)
		(width 0.12954)
		(layer "F.Cu")
		(net "USB3_CPU0_BMC_RX_HUB1_DN")
	)
	(segment
		(start 137.213848 -35.304984)
		(end 138.251692 -35.304984)
		(width 0.12954)
		(layer "F.Cu")
		(net "USB3_CPU0_BMC_RX_HUB1_DN")
	)
	(segment
		(start 138.251692 -35.304984)
		(end 138.442192 -35.114484)
		(width 0.12954)
		(layer "F.Cu")
		(net "USB3_CPU0_BMC_RX_HUB1_DN")
	)
	(segment
		(start 140.51915 -34.190686)
		(end 140.51915 -33.830006)
		(width 0.12954)
		(layer "F.Cu")
		(net "USB3_CPU0_BMC_RX_HUB1_DN")
	)
	(segment
		(start 136.54405 -35.273488)
		(end 137.182352 -35.273488)
		(width 0.12954)
		(layer "F.Cu")
		(net "USB3_CPU0_BMC_RX_HUB1_DN")
	)
	(segment
		(start 139.677648 -34.762694)
		(end 139.950952 -34.48939)
		(width 0.12954)
		(layer "F.Cu")
		(net "USB3_CPU0_BMC_RX_HUB1_DN")
	)
	(segment
		(start 140.32865 -33.639506)
		(end 140.32865 -33.253426)
		(width 0.12954)
		(layer "F.Cu")
		(net "USB3_CPU0_BMC_RX_HUB1_DN")
	)
	(segment
		(start 140.51915 -32.848804)
		(end 140.02512 -32.354774)
		(width 0.12954)
		(layer "F.Cu")
		(net "USB3_CPU0_BMC_RX_HUB1_DN")
	)
	(segment
		(start 139.950952 -34.48939)
		(end 140.220446 -34.48939)
		(width 0.12954)
		(layer "F.Cu")
		(net "USB3_CPU0_BMC_RX_HUB1_DN")
	)
	(segment
		(start 139.404852 -35.304984)
		(end 139.677648 -35.032188)
		(width 0.12954)
		(layer "F.Cu")
		(net "USB3_CPU0_BMC_RX_HUB1_DN")
	)
	(segment
		(start 140.220446 -34.48939)
		(end 140.51915 -34.190686)
		(width 0.12954)
		(layer "F.Cu")
		(net "USB3_CPU0_BMC_RX_HUB1_DN")
	)
	(segment
		(start 122.49277 -32.974788)
		(end 122.76328 -33.245298)
		(width 0.12954)
		(layer "F.Cu")
		(net "USB3_CPU0_BMC_RX_C2_DP")
	)
	(segment
		(start 115.548918 -27.097736)
		(end 115.548918 -26.883614)
		(width 0.12954)
		(layer "F.Cu")
		(net "USB3_CPU0_BMC_RX_C2_DP")
	)
	(segment
		(start 116.86159 -24.781256)
		(end 116.86159 -24.41702)
		(width 0.12954)
		(layer "F.Cu")
		(net "USB3_CPU0_BMC_RX_C2_DP")
	)
	(segment
		(start 122.76328 -33.245298)
		(end 123.29922 -33.245298)
		(width 0.12954)
		(layer "F.Cu")
		(net "USB3_CPU0_BMC_RX_C2_DP")
	)
	(segment
		(start 123.79325 -32.751268)
		(end 124.18822 -32.751268)
		(width 0.12954)
		(layer "F.Cu")
		(net "USB3_CPU0_BMC_RX_C2_DP")
	)
	(segment
		(start 116.86159 -24.41702)
		(end 116.600224 -24.155654)
		(width 0.12954)
		(layer "F.Cu")
		(net "USB3_CPU0_BMC_RX_C2_DP")
	)
	(segment
		(start 123.29922 -33.245298)
		(end 123.79325 -32.751268)
		(width 0.12954)
		(layer "F.Cu")
		(net "USB3_CPU0_BMC_RX_C2_DP")
	)
	(segment
		(start 115.548918 -26.883614)
		(end 115.637564 -26.794968)
		(width 0.12954)
		(layer "F.Cu")
		(net "USB3_CPU0_BMC_RX_C2_DP")
	)
	(segment
		(start 115.637564 -26.794968)
		(end 115.637564 -26.005282)
		(width 0.12954)
		(layer "F.Cu")
		(net "USB3_CPU0_BMC_RX_C2_DP")
	)
	(segment
		(start 115.637564 -26.005282)
		(end 116.86159 -24.781256)
		(width 0.12954)
		(layer "F.Cu")
		(net "USB3_CPU0_BMC_RX_C2_DP")
	)
	(segment
		(start 116.891054 -23.864824)
		(end 116.891054 -22.781006)
		(width 0.14224)
		(layer "In11.Cu")
		(net "USB3_CPU0_BMC_RX_C2_DP")
	)
	(segment
		(start 121.216674 -34.14522)
		(end 121.990104 -33.37179)
		(width 0.14224)
		(layer "In11.Cu")
		(net "USB3_CPU0_BMC_RX_C2_DP")
	)
	(segment
		(start 116.600224 -24.155654)
		(end 116.891054 -23.864824)
		(width 0.14224)
		(layer "In11.Cu")
		(net "USB3_CPU0_BMC_RX_C2_DP")
	)
	(segment
		(start 119.41302 -31.47314)
		(end 118.95328 -31.93288)
		(width 0.14224)
		(layer "In11.Cu")
		(net "USB3_CPU0_BMC_RX_C2_DP")
	)
	(segment
		(start 119.41302 -22.81174)
		(end 119.41302 -31.47314)
		(width 0.14224)
		(layer "In11.Cu")
		(net "USB3_CPU0_BMC_RX_C2_DP")
	)
	(segment
		(start 118.95328 -33.35782)
		(end 119.74068 -34.14522)
		(width 0.14224)
		(layer "In11.Cu")
		(net "USB3_CPU0_BMC_RX_C2_DP")
	)
	(segment
		(start 116.891054 -22.781006)
		(end 117.61724 -22.05482)
		(width 0.14224)
		(layer "In11.Cu")
		(net "USB3_CPU0_BMC_RX_C2_DP")
	)
	(segment
		(start 118.95328 -31.93288)
		(end 118.95328 -33.35782)
		(width 0.14224)
		(layer "In11.Cu")
		(net "USB3_CPU0_BMC_RX_C2_DP")
	)
	(segment
		(start 118.6561 -22.05482)
		(end 119.41302 -22.81174)
		(width 0.14224)
		(layer "In11.Cu")
		(net "USB3_CPU0_BMC_RX_C2_DP")
	)
	(segment
		(start 122.49277 -33.229296)
		(end 122.49277 -32.974788)
		(width 0.14224)
		(layer "In11.Cu")
		(net "USB3_CPU0_BMC_RX_C2_DP")
	)
	(segment
		(start 119.74068 -34.14522)
		(end 121.216674 -34.14522)
		(width 0.14224)
		(layer "In11.Cu")
		(net "USB3_CPU0_BMC_RX_C2_DP")
	)
	(segment
		(start 122.350276 -33.37179)
		(end 122.49277 -33.229296)
		(width 0.14224)
		(layer "In11.Cu")
		(net "USB3_CPU0_BMC_RX_C2_DP")
	)
	(segment
		(start 121.990104 -33.37179)
		(end 122.350276 -33.37179)
		(width 0.14224)
		(layer "In11.Cu")
		(net "USB3_CPU0_BMC_RX_C2_DP")
	)
	(segment
		(start 117.61724 -22.05482)
		(end 118.6561 -22.05482)
		(width 0.14224)
		(layer "In11.Cu")
		(net "USB3_CPU0_BMC_RX_C2_DP")
	)
	(segment
		(start 122.49277 -33.838388)
		(end 122.76328 -33.567878)
		(width 0.12954)
		(layer "F.Cu")
		(net "USB3_CPU0_BMC_RX_C2_DN")
	)
	(segment
		(start 115.960144 -26.79954)
		(end 115.960144 -26.13914)
		(width 0.12954)
		(layer "F.Cu")
		(net "USB3_CPU0_BMC_RX_C2_DN")
	)
	(segment
		(start 123.74118 -34.021268)
		(end 124.18822 -34.021268)
		(width 0.12954)
		(layer "F.Cu")
		(net "USB3_CPU0_BMC_RX_C2_DN")
	)
	(segment
		(start 122.76328 -33.567878)
		(end 123.28779 -33.567878)
		(width 0.12954)
		(layer "F.Cu")
		(net "USB3_CPU0_BMC_RX_C2_DN")
	)
	(segment
		(start 116.04879 -26.888186)
		(end 115.960144 -26.79954)
		(width 0.12954)
		(layer "F.Cu")
		(net "USB3_CPU0_BMC_RX_C2_DN")
	)
	(segment
		(start 123.28779 -33.567878)
		(end 123.74118 -34.021268)
		(width 0.12954)
		(layer "F.Cu")
		(net "USB3_CPU0_BMC_RX_C2_DN")
	)
	(segment
		(start 116.04879 -27.097736)
		(end 116.04879 -26.888186)
		(width 0.12954)
		(layer "F.Cu")
		(net "USB3_CPU0_BMC_RX_C2_DN")
	)
	(segment
		(start 117.18417 -24.435308)
		(end 117.463824 -24.155654)
		(width 0.12954)
		(layer "F.Cu")
		(net "USB3_CPU0_BMC_RX_C2_DN")
	)
	(segment
		(start 115.960144 -26.13914)
		(end 117.18417 -24.915114)
		(width 0.12954)
		(layer "F.Cu")
		(net "USB3_CPU0_BMC_RX_C2_DN")
	)
	(segment
		(start 117.18417 -24.915114)
		(end 117.18417 -24.435308)
		(width 0.12954)
		(layer "F.Cu")
		(net "USB3_CPU0_BMC_RX_C2_DN")
	)
	(segment
		(start 118.99392 -29.84119)
		(end 119.13108 -29.70403)
		(width 0.14224)
		(layer "In11.Cu")
		(net "USB3_CPU0_BMC_RX_C2_DN")
	)
	(segment
		(start 118.99392 -28.02001)
		(end 118.99392 -27.59583)
		(width 0.14224)
		(layer "In11.Cu")
		(net "USB3_CPU0_BMC_RX_C2_DN")
	)
	(segment
		(start 119.13108 -29.70403)
		(end 119.13108 -29.27985)
		(width 0.14224)
		(layer "In11.Cu")
		(net "USB3_CPU0_BMC_RX_C2_DN")
	)
	(segment
		(start 119.13108 -27.03449)
		(end 118.99392 -26.89733)
		(width 0.14224)
		(layer "In11.Cu")
		(net "USB3_CPU0_BMC_RX_C2_DN")
	)
	(segment
		(start 119.13108 -31.3563)
		(end 119.13108 -30.40253)
		(width 0.14224)
		(layer "In11.Cu")
		(net "USB3_CPU0_BMC_RX_C2_DN")
	)
	(segment
		(start 122.106944 -33.65373)
		(end 121.333514 -34.42716)
		(width 0.14224)
		(layer "In11.Cu")
		(net "USB3_CPU0_BMC_RX_C2_DN")
	)
	(segment
		(start 119.13108 -25.21331)
		(end 119.13108 -24.78913)
		(width 0.14224)
		(layer "In11.Cu")
		(net "USB3_CPU0_BMC_RX_C2_DN")
	)
	(segment
		(start 119.13108 -22.92858)
		(end 118.53926 -22.33676)
		(width 0.14224)
		(layer "In11.Cu")
		(net "USB3_CPU0_BMC_RX_C2_DN")
	)
	(segment
		(start 119.13108 -30.40253)
		(end 118.99392 -30.26537)
		(width 0.14224)
		(layer "In11.Cu")
		(net "USB3_CPU0_BMC_RX_C2_DN")
	)
	(segment
		(start 118.99392 -27.59583)
		(end 119.13108 -27.45867)
		(width 0.14224)
		(layer "In11.Cu")
		(net "USB3_CPU0_BMC_RX_C2_DN")
	)
	(segment
		(start 119.13108 -28.58135)
		(end 119.13108 -28.15717)
		(width 0.14224)
		(layer "In11.Cu")
		(net "USB3_CPU0_BMC_RX_C2_DN")
	)
	(segment
		(start 118.99392 -28.71851)
		(end 119.13108 -28.58135)
		(width 0.14224)
		(layer "In11.Cu")
		(net "USB3_CPU0_BMC_RX_C2_DN")
	)
	(segment
		(start 119.13108 -24.09063)
		(end 119.13108 -22.92858)
		(width 0.14224)
		(layer "In11.Cu")
		(net "USB3_CPU0_BMC_RX_C2_DN")
	)
	(segment
		(start 118.67134 -31.81604)
		(end 119.13108 -31.3563)
		(width 0.14224)
		(layer "In11.Cu")
		(net "USB3_CPU0_BMC_RX_C2_DN")
	)
	(segment
		(start 122.308112 -33.65373)
		(end 122.106944 -33.65373)
		(width 0.14224)
		(layer "In11.Cu")
		(net "USB3_CPU0_BMC_RX_C2_DN")
	)
	(segment
		(start 117.172994 -22.897846)
		(end 117.172994 -23.864824)
		(width 0.14224)
		(layer "In11.Cu")
		(net "USB3_CPU0_BMC_RX_C2_DN")
	)
	(segment
		(start 118.99392 -24.22779)
		(end 119.13108 -24.09063)
		(width 0.14224)
		(layer "In11.Cu")
		(net "USB3_CPU0_BMC_RX_C2_DN")
	)
	(segment
		(start 118.99392 -25.77465)
		(end 118.99392 -25.35047)
		(width 0.14224)
		(layer "In11.Cu")
		(net "USB3_CPU0_BMC_RX_C2_DN")
	)
	(segment
		(start 118.99392 -29.14269)
		(end 118.99392 -28.71851)
		(width 0.14224)
		(layer "In11.Cu")
		(net "USB3_CPU0_BMC_RX_C2_DN")
	)
	(segment
		(start 117.73408 -22.33676)
		(end 117.172994 -22.897846)
		(width 0.14224)
		(layer "In11.Cu")
		(net "USB3_CPU0_BMC_RX_C2_DN")
	)
	(segment
		(start 119.13108 -27.45867)
		(end 119.13108 -27.03449)
		(width 0.14224)
		(layer "In11.Cu")
		(net "USB3_CPU0_BMC_RX_C2_DN")
	)
	(segment
		(start 118.99392 -30.26537)
		(end 118.99392 -29.84119)
		(width 0.14224)
		(layer "In11.Cu")
		(net "USB3_CPU0_BMC_RX_C2_DN")
	)
	(segment
		(start 119.13108 -29.27985)
		(end 118.99392 -29.14269)
		(width 0.14224)
		(layer "In11.Cu")
		(net "USB3_CPU0_BMC_RX_C2_DN")
	)
	(segment
		(start 119.13108 -26.33599)
		(end 119.13108 -25.91181)
		(width 0.14224)
		(layer "In11.Cu")
		(net "USB3_CPU0_BMC_RX_C2_DN")
	)
	(segment
		(start 118.99392 -25.35047)
		(end 119.13108 -25.21331)
		(width 0.14224)
		(layer "In11.Cu")
		(net "USB3_CPU0_BMC_RX_C2_DN")
	)
	(segment
		(start 119.62384 -34.42716)
		(end 118.67134 -33.47466)
		(width 0.14224)
		(layer "In11.Cu")
		(net "USB3_CPU0_BMC_RX_C2_DN")
	)
	(segment
		(start 121.333514 -34.42716)
		(end 119.62384 -34.42716)
		(width 0.14224)
		(layer "In11.Cu")
		(net "USB3_CPU0_BMC_RX_C2_DN")
	)
	(segment
		(start 118.99392 -24.65197)
		(end 118.99392 -24.22779)
		(width 0.14224)
		(layer "In11.Cu")
		(net "USB3_CPU0_BMC_RX_C2_DN")
	)
	(segment
		(start 122.49277 -33.838388)
		(end 122.308112 -33.65373)
		(width 0.14224)
		(layer "In11.Cu")
		(net "USB3_CPU0_BMC_RX_C2_DN")
	)
	(segment
		(start 117.172994 -23.864824)
		(end 117.463824 -24.155654)
		(width 0.14224)
		(layer "In11.Cu")
		(net "USB3_CPU0_BMC_RX_C2_DN")
	)
	(segment
		(start 119.13108 -25.91181)
		(end 118.99392 -25.77465)
		(width 0.14224)
		(layer "In11.Cu")
		(net "USB3_CPU0_BMC_RX_C2_DN")
	)
	(segment
		(start 118.67134 -33.47466)
		(end 118.67134 -31.81604)
		(width 0.14224)
		(layer "In11.Cu")
		(net "USB3_CPU0_BMC_RX_C2_DN")
	)
	(segment
		(start 118.99392 -26.89733)
		(end 118.99392 -26.47315)
		(width 0.14224)
		(layer "In11.Cu")
		(net "USB3_CPU0_BMC_RX_C2_DN")
	)
	(segment
		(start 119.13108 -28.15717)
		(end 118.99392 -28.02001)
		(width 0.14224)
		(layer "In11.Cu")
		(net "USB3_CPU0_BMC_RX_C2_DN")
	)
	(segment
		(start 118.99392 -26.47315)
		(end 119.13108 -26.33599)
		(width 0.14224)
		(layer "In11.Cu")
		(net "USB3_CPU0_BMC_RX_C2_DN")
	)
	(segment
		(start 119.13108 -24.78913)
		(end 118.99392 -24.65197)
		(width 0.14224)
		(layer "In11.Cu")
		(net "USB3_CPU0_BMC_RX_C2_DN")
	)
	(segment
		(start 118.53926 -22.33676)
		(end 117.73408 -22.33676)
		(width 0.14224)
		(layer "In11.Cu")
		(net "USB3_CPU0_BMC_RX_C2_DN")
	)
	(segment
		(start 128.503934 -33.673542)
		(end 128.50368 -33.673288)
		(width 0.12954)
		(layer "F.Cu")
		(net "USB3_CPU0_BMC_RX_C1_DP")
	)
	(segment
		(start 127.961136 -33.676082)
		(end 127.489458 -33.204658)
		(width 0.12954)
		(layer "F.Cu")
		(net "USB3_CPU0_BMC_RX_C1_DP")
	)
	(segment
		(start 127.489458 -33.204658)
		(end 126.68885 -33.204658)
		(width 0.12954)
		(layer "F.Cu")
		(net "USB3_CPU0_BMC_RX_C1_DP")
	)
	(segment
		(start 126.68885 -33.204658)
		(end 126.110492 -32.6263)
		(width 0.12954)
		(layer "F.Cu")
		(net "USB3_CPU0_BMC_RX_C1_DP")
	)
	(segment
		(start 126.110492 -32.6263)
		(end 125.913388 -32.6263)
		(width 0.12954)
		(layer "F.Cu")
		(net "USB3_CPU0_BMC_RX_C1_DP")
	)
	(segment
		(start 125.913388 -32.6263)
		(end 125.78842 -32.751268)
		(width 0.12954)
		(layer "F.Cu")
		(net "USB3_CPU0_BMC_RX_C1_DP")
	)
	(segment
		(start 128.031494 -33.705546)
		(end 127.961136 -33.676082)
		(width 0.12954)
		(layer "F.Cu")
		(net "USB3_CPU0_BMC_RX_C1_DP")
	)
	(segment
		(start 128.206246 -33.673288)
		(end 128.173988 -33.705546)
		(width 0.12954)
		(layer "F.Cu")
		(net "USB3_CPU0_BMC_RX_C1_DP")
	)
	(segment
		(start 128.69418 -33.673542)
		(end 128.503934 -33.673542)
		(width 0.12954)
		(layer "F.Cu")
		(net "USB3_CPU0_BMC_RX_C1_DP")
	)
	(segment
		(start 128.173988 -33.705546)
		(end 128.031494 -33.705546)
		(width 0.12954)
		(layer "F.Cu")
		(net "USB3_CPU0_BMC_RX_C1_DP")
	)
	(segment
		(start 128.50368 -33.673288)
		(end 128.206246 -33.673288)
		(width 0.12954)
		(layer "F.Cu")
		(net "USB3_CPU0_BMC_RX_C1_DP")
	)
	(segment
		(start 127.3556 -33.527238)
		(end 126.67742 -33.527238)
		(width 0.12954)
		(layer "F.Cu")
		(net "USB3_CPU0_BMC_RX_C1_DN")
	)
	(segment
		(start 126.67742 -33.527238)
		(end 126.18339 -34.021268)
		(width 0.12954)
		(layer "F.Cu")
		(net "USB3_CPU0_BMC_RX_C1_DN")
	)
	(segment
		(start 126.18339 -34.021268)
		(end 125.78842 -34.021268)
		(width 0.12954)
		(layer "F.Cu")
		(net "USB3_CPU0_BMC_RX_C1_DN")
	)
	(segment
		(start 128.205992 -34.073338)
		(end 128.16078 -34.028126)
		(width 0.12954)
		(layer "F.Cu")
		(net "USB3_CPU0_BMC_RX_C1_DN")
	)
	(segment
		(start 127.967232 -34.028126)
		(end 127.778256 -33.949894)
		(width 0.12954)
		(layer "F.Cu")
		(net "USB3_CPU0_BMC_RX_C1_DN")
	)
	(segment
		(start 128.16078 -34.028126)
		(end 127.967232 -34.028126)
		(width 0.12954)
		(layer "F.Cu")
		(net "USB3_CPU0_BMC_RX_C1_DN")
	)
	(segment
		(start 128.844294 -34.073338)
		(end 128.205992 -34.073338)
		(width 0.12954)
		(layer "F.Cu")
		(net "USB3_CPU0_BMC_RX_C1_DN")
	)
	(segment
		(start 127.778256 -33.949894)
		(end 127.3556 -33.527238)
		(width 0.12954)
		(layer "F.Cu")
		(net "USB3_CPU0_BMC_RX_C1_DN")
	)
	(segment
		(start 120.26138 -33.17113)
		(end 120.11533 -33.02508)
		(width 0.12954)
		(layer "F.Cu")
		(net "USB3_CPU0_BMC_HUB2_TX_DP")
	)
	(segment
		(start 120.26138 -35.8013)
		(end 120.26138 -33.17113)
		(width 0.12954)
		(layer "F.Cu")
		(net "USB3_CPU0_BMC_HUB2_TX_DP")
	)
	(segment
		(start 114.137694 -26.78176)
		(end 114.137694 -25.493726)
		(width 0.12954)
		(layer "F.Cu")
		(net "USB3_CPU0_BMC_HUB2_TX_DP")
	)
	(segment
		(start 115.095274 -24.536146)
		(end 115.095274 -22.79396)
		(width 0.12954)
		(layer "F.Cu")
		(net "USB3_CPU0_BMC_HUB2_TX_DP")
	)
	(segment
		(start 120.70334 -36.24326)
		(end 120.26138 -35.8013)
		(width 0.12954)
		(layer "F.Cu")
		(net "USB3_CPU0_BMC_HUB2_TX_DP")
	)
	(segment
		(start 121.694448 -36.675568)
		(end 121.26214 -36.24326)
		(width 0.12954)
		(layer "F.Cu")
		(net "USB3_CPU0_BMC_HUB2_TX_DP")
	)
	(segment
		(start 114.048794 -26.87066)
		(end 114.137694 -26.78176)
		(width 0.12954)
		(layer "F.Cu")
		(net "USB3_CPU0_BMC_HUB2_TX_DP")
	)
	(segment
		(start 114.048794 -27.097736)
		(end 114.048794 -26.87066)
		(width 0.12954)
		(layer "F.Cu")
		(net "USB3_CPU0_BMC_HUB2_TX_DP")
	)
	(segment
		(start 114.137694 -25.493726)
		(end 115.095274 -24.536146)
		(width 0.12954)
		(layer "F.Cu")
		(net "USB3_CPU0_BMC_HUB2_TX_DP")
	)
	(segment
		(start 122.15622 -36.675568)
		(end 121.694448 -36.675568)
		(width 0.12954)
		(layer "F.Cu")
		(net "USB3_CPU0_BMC_HUB2_TX_DP")
	)
	(segment
		(start 121.26214 -36.24326)
		(end 120.70334 -36.24326)
		(width 0.12954)
		(layer "F.Cu")
		(net "USB3_CPU0_BMC_HUB2_TX_DP")
	)
	(segment
		(start 115.095274 -22.79396)
		(end 114.833908 -22.532594)
		(width 0.12954)
		(layer "F.Cu")
		(net "USB3_CPU0_BMC_HUB2_TX_DP")
	)
	(segment
		(start 115.51285 -25.09774)
		(end 115.124738 -23.876)
		(width 0.14224)
		(layer "In2.Cu")
		(net "USB3_CPU0_BMC_HUB2_TX_DP")
	)
	(segment
		(start 115.124738 -23.876)
		(end 115.124738 -22.823424)
		(width 0.14224)
		(layer "In2.Cu")
		(net "USB3_CPU0_BMC_HUB2_TX_DP")
	)
	(segment
		(start 115.124738 -22.823424)
		(end 114.833908 -22.532594)
		(width 0.14224)
		(layer "In2.Cu")
		(net "USB3_CPU0_BMC_HUB2_TX_DP")
	)
	(segment
		(start 120.40616 -32.73425)
		(end 120.40616 -32.024574)
		(width 0.14224)
		(layer "In2.Cu")
		(net "USB3_CPU0_BMC_HUB2_TX_DP")
	)
	(segment
		(start 120.40616 -32.024574)
		(end 115.51285 -25.09774)
		(width 0.14224)
		(layer "In2.Cu")
		(net "USB3_CPU0_BMC_HUB2_TX_DP")
	)
	(segment
		(start 120.11533 -33.02508)
		(end 120.40616 -32.73425)
		(width 0.14224)
		(layer "In2.Cu")
		(net "USB3_CPU0_BMC_HUB2_TX_DP")
	)
	(segment
		(start 120.58396 -33.238186)
		(end 120.797066 -33.02508)
		(width 0.12954)
		(layer "F.Cu")
		(net "USB3_CPU0_BMC_HUB2_TX_DN")
	)
	(segment
		(start 114.54892 -27.097736)
		(end 114.54892 -26.867866)
		(width 0.12954)
		(layer "F.Cu")
		(net "USB3_CPU0_BMC_HUB2_TX_DN")
	)
	(segment
		(start 120.58396 -33.619186)
		(end 120.58396 -33.238186)
		(width 0.12954)
		(layer "F.Cu")
		(net "USB3_CPU0_BMC_HUB2_TX_DN")
	)
	(segment
		(start 114.460274 -25.627584)
		(end 115.417854 -24.670004)
		(width 0.12954)
		(layer "F.Cu")
		(net "USB3_CPU0_BMC_HUB2_TX_DN")
	)
	(segment
		(start 115.417854 -22.812248)
		(end 115.697508 -22.532594)
		(width 0.12954)
		(layer "F.Cu")
		(net "USB3_CPU0_BMC_HUB2_TX_DN")
	)
	(segment
		(start 120.797066 -33.02508)
		(end 120.97893 -33.02508)
		(width 0.12954)
		(layer "F.Cu")
		(net "USB3_CPU0_BMC_HUB2_TX_DN")
	)
	(segment
		(start 120.76938 -34.86023)
		(end 120.58396 -34.67481)
		(width 0.12954)
		(layer "F.Cu")
		(net "USB3_CPU0_BMC_HUB2_TX_DN")
	)
	(segment
		(start 114.460274 -26.77922)
		(end 114.460274 -25.627584)
		(width 0.12954)
		(layer "F.Cu")
		(net "USB3_CPU0_BMC_HUB2_TX_DN")
	)
	(segment
		(start 114.54892 -26.867866)
		(end 114.460274 -26.77922)
		(width 0.12954)
		(layer "F.Cu")
		(net "USB3_CPU0_BMC_HUB2_TX_DN")
	)
	(segment
		(start 120.76938 -33.804606)
		(end 120.58396 -33.619186)
		(width 0.12954)
		(layer "F.Cu")
		(net "USB3_CPU0_BMC_HUB2_TX_DN")
	)
	(segment
		(start 120.76938 -35.24123)
		(end 120.76938 -34.86023)
		(width 0.12954)
		(layer "F.Cu")
		(net "USB3_CPU0_BMC_HUB2_TX_DN")
	)
	(segment
		(start 115.417854 -24.670004)
		(end 115.417854 -22.812248)
		(width 0.12954)
		(layer "F.Cu")
		(net "USB3_CPU0_BMC_HUB2_TX_DN")
	)
	(segment
		(start 120.58396 -35.42665)
		(end 120.76938 -35.24123)
		(width 0.12954)
		(layer "F.Cu")
		(net "USB3_CPU0_BMC_HUB2_TX_DN")
	)
	(segment
		(start 122.15622 -35.430968)
		(end 121.756678 -35.430968)
		(width 0.12954)
		(layer "F.Cu")
		(net "USB3_CPU0_BMC_HUB2_TX_DN")
	)
	(segment
		(start 120.76938 -34.185606)
		(end 120.76938 -33.804606)
		(width 0.12954)
		(layer "F.Cu")
		(net "USB3_CPU0_BMC_HUB2_TX_DN")
	)
	(segment
		(start 121.266966 -35.92068)
		(end 120.837198 -35.92068)
		(width 0.12954)
		(layer "F.Cu")
		(net "USB3_CPU0_BMC_HUB2_TX_DN")
	)
	(segment
		(start 121.756678 -35.430968)
		(end 121.266966 -35.92068)
		(width 0.12954)
		(layer "F.Cu")
		(net "USB3_CPU0_BMC_HUB2_TX_DN")
	)
	(segment
		(start 120.58396 -35.667442)
		(end 120.58396 -35.42665)
		(width 0.12954)
		(layer "F.Cu")
		(net "USB3_CPU0_BMC_HUB2_TX_DN")
	)
	(segment
		(start 120.58396 -34.67481)
		(end 120.58396 -34.371026)
		(width 0.12954)
		(layer "F.Cu")
		(net "USB3_CPU0_BMC_HUB2_TX_DN")
	)
	(segment
		(start 120.58396 -34.371026)
		(end 120.76938 -34.185606)
		(width 0.12954)
		(layer "F.Cu")
		(net "USB3_CPU0_BMC_HUB2_TX_DN")
	)
	(segment
		(start 120.837198 -35.92068)
		(end 120.58396 -35.667442)
		(width 0.12954)
		(layer "F.Cu")
		(net "USB3_CPU0_BMC_HUB2_TX_DN")
	)
	(segment
		(start 115.406678 -22.823424)
		(end 115.697508 -22.532594)
		(width 0.14224)
		(layer "In2.Cu")
		(net "USB3_CPU0_BMC_HUB2_TX_DN")
	)
	(segment
		(start 120.6881 -32.73425)
		(end 120.6881 -31.934912)
		(width 0.14224)
		(layer "In2.Cu")
		(net "USB3_CPU0_BMC_HUB2_TX_DN")
	)
	(segment
		(start 120.97893 -33.02508)
		(end 120.6881 -32.73425)
		(width 0.14224)
		(layer "In2.Cu")
		(net "USB3_CPU0_BMC_HUB2_TX_DN")
	)
	(segment
		(start 115.768374 -24.97074)
		(end 115.406678 -23.832058)
		(width 0.14224)
		(layer "In2.Cu")
		(net "USB3_CPU0_BMC_HUB2_TX_DN")
	)
	(segment
		(start 115.406678 -23.832058)
		(end 115.406678 -22.823424)
		(width 0.14224)
		(layer "In2.Cu")
		(net "USB3_CPU0_BMC_HUB2_TX_DN")
	)
	(segment
		(start 120.6881 -31.934912)
		(end 115.768374 -24.97074)
		(width 0.14224)
		(layer "In2.Cu")
		(net "USB3_CPU0_BMC_HUB2_TX_DN")
	)
	(segment
		(start 124.612146 -36.23564)
		(end 125.443234 -36.23564)
		(width 0.12954)
		(layer "F.Cu")
		(net "USB3_CPU0_BMC_HUB1_TX_DP")
	)
	(segment
		(start 128.167384 -35.23488)
		(end 128.205992 -35.273488)
		(width 0.12954)
		(layer "F.Cu")
		(net "USB3_CPU0_BMC_HUB1_TX_DP")
	)
	(segment
		(start 125.443234 -36.23564)
		(end 126.443994 -35.23488)
		(width 0.12954)
		(layer "F.Cu")
		(net "USB3_CPU0_BMC_HUB1_TX_DP")
	)
	(segment
		(start 123.75642 -36.675568)
		(end 124.172218 -36.675568)
		(width 0.12954)
		(layer "F.Cu")
		(net "USB3_CPU0_BMC_HUB1_TX_DP")
	)
	(segment
		(start 124.172218 -36.675568)
		(end 124.612146 -36.23564)
		(width 0.12954)
		(layer "F.Cu")
		(net "USB3_CPU0_BMC_HUB1_TX_DP")
	)
	(segment
		(start 128.205992 -35.273488)
		(end 128.844294 -35.273488)
		(width 0.12954)
		(layer "F.Cu")
		(net "USB3_CPU0_BMC_HUB1_TX_DP")
	)
	(segment
		(start 126.443994 -35.23488)
		(end 128.167384 -35.23488)
		(width 0.12954)
		(layer "F.Cu")
		(net "USB3_CPU0_BMC_HUB1_TX_DP")
	)
	(segment
		(start 123.75642 -35.430968)
		(end 124.160788 -35.430968)
		(width 0.12954)
		(layer "F.Cu")
		(net "USB3_CPU0_BMC_HUB1_TX_DN")
	)
	(segment
		(start 126.310136 -34.9123)
		(end 128.167384 -34.9123)
		(width 0.12954)
		(layer "F.Cu")
		(net "USB3_CPU0_BMC_HUB1_TX_DN")
	)
	(segment
		(start 128.167384 -34.9123)
		(end 128.206246 -34.873438)
		(width 0.12954)
		(layer "F.Cu")
		(net "USB3_CPU0_BMC_HUB1_TX_DN")
	)
	(segment
		(start 128.206246 -34.873438)
		(end 128.844294 -34.873438)
		(width 0.12954)
		(layer "F.Cu")
		(net "USB3_CPU0_BMC_HUB1_TX_DN")
	)
	(segment
		(start 124.64288 -35.91306)
		(end 125.309376 -35.91306)
		(width 0.12954)
		(layer "F.Cu")
		(net "USB3_CPU0_BMC_HUB1_TX_DN")
	)
	(segment
		(start 124.160788 -35.430968)
		(end 124.64288 -35.91306)
		(width 0.12954)
		(layer "F.Cu")
		(net "USB3_CPU0_BMC_HUB1_TX_DN")
	)
	(segment
		(start 125.309376 -35.91306)
		(end 126.310136 -34.9123)
		(width 0.12954)
		(layer "F.Cu")
		(net "USB3_CPU0_BMC_HUB1_TX_DN")
	)
	(segment
		(start 135.93318 -29.24302)
		(end 135.93318 -29.17952)
		(width 0.12954)
		(layer "F.Cu")
		(net "USB2_HUB_EXT_DP")
	)
	(segment
		(start 138.147044 -17.11325)
		(end 138.00836 -17.251934)
		(width 0.12954)
		(layer "F.Cu")
		(net "USB2_HUB_EXT_DP")
	)
	(segment
		(start 138.00836 -17.874742)
		(end 138.278362 -18.144744)
		(width 0.12954)
		(layer "F.Cu")
		(net "USB2_HUB_EXT_DP")
	)
	(segment
		(start 135.93318 -29.17952)
		(end 136.36498 -28.74772)
		(width 0.12954)
		(layer "F.Cu")
		(net "USB2_HUB_EXT_DP")
	)
	(segment
		(start 138.147044 -16.549878)
		(end 138.147044 -17.11325)
		(width 0.12954)
		(layer "F.Cu")
		(net "USB2_HUB_EXT_DP")
	)
	(segment
		(start 136.36498 -28.74772)
		(end 136.50468 -28.74772)
		(width 0.12954)
		(layer "F.Cu")
		(net "USB2_HUB_EXT_DP")
	)
	(segment
		(start 138.00836 -17.251934)
		(end 138.00836 -17.874742)
		(width 0.12954)
		(layer "F.Cu")
		(net "USB2_HUB_EXT_DP")
	)
	(via
		(at 135.93318 -29.24302)
		(size 0.508)
		(drill 0.254)
		(layers "F.Cu" "B.Cu")
		(net "USB2_HUB_EXT_DP")
	)
	(via
		(at 138.278362 -18.144744)
		(size 0.508)
		(drill 0.254)
		(layers "F.Cu" "B.Cu")
		(net "USB2_HUB_EXT_DP")
	)
	(segment
		(start 135.93318 -29.24302)
		(end 136.26719 -28.90901)
		(width 0.12954)
		(layer "B.Cu")
		(net "USB2_HUB_EXT_DP")
	)
	(segment
		(start 138.007852 -18.415254)
		(end 138.278362 -18.144744)
		(width 0.12954)
		(layer "B.Cu")
		(net "USB2_HUB_EXT_DP")
	)
	(segment
		(start 136.26719 -28.90901)
		(end 136.954768 -28.90901)
		(width 0.12954)
		(layer "B.Cu")
		(net "USB2_HUB_EXT_DP")
	)
	(segment
		(start 136.954768 -28.90901)
		(end 139.08532 -26.778458)
		(width 0.12954)
		(layer "B.Cu")
		(net "USB2_HUB_EXT_DP")
	)
	(segment
		(start 138.007852 -21.041614)
		(end 138.007852 -18.415254)
		(width 0.12954)
		(layer "B.Cu")
		(net "USB2_HUB_EXT_DP")
	)
	(segment
		(start 139.08532 -26.778458)
		(end 139.08532 -22.119082)
		(width 0.12954)
		(layer "B.Cu")
		(net "USB2_HUB_EXT_DP")
	)
	(segment
		(start 139.08532 -22.119082)
		(end 138.007852 -21.041614)
		(width 0.12954)
		(layer "B.Cu")
		(net "USB2_HUB_EXT_DP")
	)
	(segment
		(start 137.547096 -17.090898)
		(end 137.68578 -17.229582)
		(width 0.12954)
		(layer "F.Cu")
		(net "USB2_HUB_EXT_DN")
	)
	(segment
		(start 135.93318 -28.31592)
		(end 135.50138 -28.74772)
		(width 0.12954)
		(layer "F.Cu")
		(net "USB2_HUB_EXT_DN")
	)
	(segment
		(start 137.68578 -17.229582)
		(end 137.68578 -17.873726)
		(width 0.12954)
		(layer "F.Cu")
		(net "USB2_HUB_EXT_DN")
	)
	(segment
		(start 137.547096 -16.549878)
		(end 137.547096 -17.090898)
		(width 0.12954)
		(layer "F.Cu")
		(net "USB2_HUB_EXT_DN")
	)
	(segment
		(start 135.50138 -28.74772)
		(end 135.36168 -28.74772)
		(width 0.12954)
		(layer "F.Cu")
		(net "USB2_HUB_EXT_DN")
	)
	(segment
		(start 137.68578 -17.873726)
		(end 137.414762 -18.144744)
		(width 0.12954)
		(layer "F.Cu")
		(net "USB2_HUB_EXT_DN")
	)
	(segment
		(start 135.93318 -28.25242)
		(end 135.93318 -28.31592)
		(width 0.12954)
		(layer "F.Cu")
		(net "USB2_HUB_EXT_DN")
	)
	(via
		(at 135.93318 -28.25242)
		(size 0.508)
		(drill 0.254)
		(layers "F.Cu" "B.Cu")
		(net "USB2_HUB_EXT_DN")
	)
	(via
		(at 137.414762 -18.144744)
		(size 0.508)
		(drill 0.254)
		(layers "F.Cu" "B.Cu")
		(net "USB2_HUB_EXT_DN")
	)
	(segment
		(start 138.61034 -23.335234)
		(end 138.61034 -23.594314)
		(width 0.12954)
		(layer "B.Cu")
		(net "USB2_HUB_EXT_DN")
	)
	(segment
		(start 137.09015 -28.31719)
		(end 136.82091 -28.58643)
		(width 0.12954)
		(layer "B.Cu")
		(net "USB2_HUB_EXT_DN")
	)
	(segment
		(start 138.423142 -26.984198)
		(end 138.161014 -26.984198)
		(width 0.12954)
		(layer "B.Cu")
		(net "USB2_HUB_EXT_DN")
	)
	(segment
		(start 138.57732 -25.69718)
		(end 138.57732 -26.07818)
		(width 0.12954)
		(layer "B.Cu")
		(net "USB2_HUB_EXT_DN")
	)
	(segment
		(start 138.57732 -26.07818)
		(end 138.76274 -26.2636)
		(width 0.12954)
		(layer "B.Cu")
		(net "USB2_HUB_EXT_DN")
	)
	(segment
		(start 138.76274 -25.51176)
		(end 138.57732 -25.69718)
		(width 0.12954)
		(layer "B.Cu")
		(net "USB2_HUB_EXT_DN")
	)
	(segment
		(start 136.26719 -28.58643)
		(end 135.93318 -28.25242)
		(width 0.12954)
		(layer "B.Cu")
		(net "USB2_HUB_EXT_DN")
	)
	(segment
		(start 137.359898 -27.785314)
		(end 137.09015 -28.054808)
		(width 0.12954)
		(layer "B.Cu")
		(net "USB2_HUB_EXT_DN")
	)
	(segment
		(start 137.685272 -21.175472)
		(end 138.76274 -22.25294)
		(width 0.12954)
		(layer "B.Cu")
		(net "USB2_HUB_EXT_DN")
	)
	(segment
		(start 138.76274 -26.2636)
		(end 138.76274 -26.6446)
		(width 0.12954)
		(layer "B.Cu")
		(net "USB2_HUB_EXT_DN")
	)
	(segment
		(start 138.76274 -23.182834)
		(end 138.61034 -23.335234)
		(width 0.12954)
		(layer "B.Cu")
		(net "USB2_HUB_EXT_DN")
	)
	(segment
		(start 137.622026 -27.785314)
		(end 137.359898 -27.785314)
		(width 0.12954)
		(layer "B.Cu")
		(net "USB2_HUB_EXT_DN")
	)
	(segment
		(start 138.61034 -23.594314)
		(end 138.76274 -23.746714)
		(width 0.12954)
		(layer "B.Cu")
		(net "USB2_HUB_EXT_DN")
	)
	(segment
		(start 137.685272 -18.415254)
		(end 137.685272 -21.175472)
		(width 0.12954)
		(layer "B.Cu")
		(net "USB2_HUB_EXT_DN")
	)
	(segment
		(start 137.891266 -27.253692)
		(end 137.891266 -27.516074)
		(width 0.12954)
		(layer "B.Cu")
		(net "USB2_HUB_EXT_DN")
	)
	(segment
		(start 137.09015 -28.054808)
		(end 137.09015 -28.31719)
		(width 0.12954)
		(layer "B.Cu")
		(net "USB2_HUB_EXT_DN")
	)
	(segment
		(start 138.76274 -26.6446)
		(end 138.423142 -26.984198)
		(width 0.12954)
		(layer "B.Cu")
		(net "USB2_HUB_EXT_DN")
	)
	(segment
		(start 136.82091 -28.58643)
		(end 136.26719 -28.58643)
		(width 0.12954)
		(layer "B.Cu")
		(net "USB2_HUB_EXT_DN")
	)
	(segment
		(start 137.891266 -27.516074)
		(end 137.622026 -27.785314)
		(width 0.12954)
		(layer "B.Cu")
		(net "USB2_HUB_EXT_DN")
	)
	(segment
		(start 137.414762 -18.144744)
		(end 137.685272 -18.415254)
		(width 0.12954)
		(layer "B.Cu")
		(net "USB2_HUB_EXT_DN")
	)
	(segment
		(start 138.161014 -26.984198)
		(end 137.891266 -27.253692)
		(width 0.12954)
		(layer "B.Cu")
		(net "USB2_HUB_EXT_DN")
	)
	(segment
		(start 138.76274 -23.746714)
		(end 138.76274 -25.51176)
		(width 0.12954)
		(layer "B.Cu")
		(net "USB2_HUB_EXT_DN")
	)
	(segment
		(start 138.76274 -22.25294)
		(end 138.76274 -23.182834)
		(width 0.12954)
		(layer "B.Cu")
		(net "USB2_HUB_EXT_DN")
	)
	(segment
		(start 104.37622 -32.648144)
		(end 104.269032 -32.648144)
		(width 0.12954)
		(layer "F.Cu")
		(net "USB2_CPU0_P0_R2_DP")
	)
	(segment
		(start 108.166154 -33.247838)
		(end 108.077254 -33.158938)
		(width 0.12954)
		(layer "F.Cu")
		(net "USB2_CPU0_P0_R2_DP")
	)
	(segment
		(start 104.269032 -32.648144)
		(end 103.998522 -32.918654)
		(width 0.12954)
		(layer "F.Cu")
		(net "USB2_CPU0_P0_R2_DP")
	)
	(segment
		(start 107.247182 -33.158938)
		(end 106.807 -33.59912)
		(width 0.12954)
		(layer "F.Cu")
		(net "USB2_CPU0_P0_R2_DP")
	)
	(segment
		(start 130.90017 -24.958294)
		(end 130.90017 -25.561544)
		(width 0.12954)
		(layer "F.Cu")
		(net "USB2_CPU0_P0_R2_DP")
	)
	(segment
		(start 108.398818 -33.247838)
		(end 108.166154 -33.247838)
		(width 0.12954)
		(layer "F.Cu")
		(net "USB2_CPU0_P0_R2_DP")
	)
	(segment
		(start 105.327196 -33.59912)
		(end 104.37622 -32.648144)
		(width 0.12954)
		(layer "F.Cu")
		(net "USB2_CPU0_P0_R2_DP")
	)
	(segment
		(start 130.49758 -25.964134)
		(end 130.49758 -26.72588)
		(width 0.12954)
		(layer "F.Cu")
		(net "USB2_CPU0_P0_R2_DP")
	)
	(segment
		(start 130.61696 -24.675084)
		(end 130.90017 -24.958294)
		(width 0.12954)
		(layer "F.Cu")
		(net "USB2_CPU0_P0_R2_DP")
	)
	(segment
		(start 106.807 -33.59912)
		(end 105.327196 -33.59912)
		(width 0.12954)
		(layer "F.Cu")
		(net "USB2_CPU0_P0_R2_DP")
	)
	(segment
		(start 103.023924 -32.94761)
		(end 103.32339 -32.648144)
		(width 0.12954)
		(layer "F.Cu")
		(net "USB2_CPU0_P0_R2_DP")
	)
	(segment
		(start 103.32339 -32.648144)
		(end 103.728012 -32.648144)
		(width 0.12954)
		(layer "F.Cu")
		(net "USB2_CPU0_P0_R2_DP")
	)
	(segment
		(start 108.077254 -33.158938)
		(end 107.247182 -33.158938)
		(width 0.12954)
		(layer "F.Cu")
		(net "USB2_CPU0_P0_R2_DP")
	)
	(segment
		(start 130.90017 -25.561544)
		(end 130.49758 -25.964134)
		(width 0.12954)
		(layer "F.Cu")
		(net "USB2_CPU0_P0_R2_DP")
	)
	(segment
		(start 103.728012 -32.648144)
		(end 103.998522 -32.918654)
		(width 0.12954)
		(layer "F.Cu")
		(net "USB2_CPU0_P0_R2_DP")
	)
	(segment
		(start 122.327416 -27.2161)
		(end 124.140976 -25.40254)
		(width 0.14224)
		(layer "In6.Cu")
		(net "USB2_CPU0_P0_R2_DP")
	)
	(segment
		(start 103.378254 -32.59328)
		(end 104.2289 -32.59328)
		(width 0.14224)
		(layer "In6.Cu")
		(net "USB2_CPU0_P0_R2_DP")
	)
	(segment
		(start 113.60531 -28.13558)
		(end 116.26596 -28.13558)
		(width 0.14224)
		(layer "In6.Cu")
		(net "USB2_CPU0_P0_R2_DP")
	)
	(segment
		(start 107.420918 -32.78378)
		(end 109.1565 -32.78378)
		(width 0.14224)
		(layer "In6.Cu")
		(net "USB2_CPU0_P0_R2_DP")
	)
	(segment
		(start 106.557318 -33.64738)
		(end 107.420918 -32.78378)
		(width 0.14224)
		(layer "In6.Cu")
		(net "USB2_CPU0_P0_R2_DP")
	)
	(segment
		(start 127.05715 -25.5397)
		(end 127.19431 -25.40254)
		(width 0.14224)
		(layer "In6.Cu")
		(net "USB2_CPU0_P0_R2_DP")
	)
	(segment
		(start 129.9591 -23.38832)
		(end 130.76555 -23.38832)
		(width 0.14224)
		(layer "In6.Cu")
		(net "USB2_CPU0_P0_R2_DP")
	)
	(segment
		(start 112.90681 -28.13558)
		(end 113.04397 -28.27274)
		(width 0.14224)
		(layer "In6.Cu")
		(net "USB2_CPU0_P0_R2_DP")
	)
	(segment
		(start 125.07087 -25.5397)
		(end 125.49505 -25.5397)
		(width 0.14224)
		(layer "In6.Cu")
		(net "USB2_CPU0_P0_R2_DP")
	)
	(segment
		(start 111.78413 -28.13558)
		(end 111.92129 -28.27274)
		(width 0.14224)
		(layer "In6.Cu")
		(net "USB2_CPU0_P0_R2_DP")
	)
	(segment
		(start 103.023924 -32.94761)
		(end 103.378254 -32.59328)
		(width 0.14224)
		(layer "In6.Cu")
		(net "USB2_CPU0_P0_R2_DP")
	)
	(segment
		(start 113.46815 -28.27274)
		(end 113.60531 -28.13558)
		(width 0.14224)
		(layer "In6.Cu")
		(net "USB2_CPU0_P0_R2_DP")
	)
	(segment
		(start 127.19431 -25.40254)
		(end 127.94488 -25.40254)
		(width 0.14224)
		(layer "In6.Cu")
		(net "USB2_CPU0_P0_R2_DP")
	)
	(segment
		(start 111.92129 -28.27274)
		(end 112.34547 -28.27274)
		(width 0.14224)
		(layer "In6.Cu")
		(net "USB2_CPU0_P0_R2_DP")
	)
	(segment
		(start 126.63297 -25.5397)
		(end 127.05715 -25.5397)
		(width 0.14224)
		(layer "In6.Cu")
		(net "USB2_CPU0_P0_R2_DP")
	)
	(segment
		(start 111.27232 -28.13558)
		(end 111.78413 -28.13558)
		(width 0.14224)
		(layer "In6.Cu")
		(net "USB2_CPU0_P0_R2_DP")
	)
	(segment
		(start 112.48263 -28.13558)
		(end 112.90681 -28.13558)
		(width 0.14224)
		(layer "In6.Cu")
		(net "USB2_CPU0_P0_R2_DP")
	)
	(segment
		(start 125.63221 -25.40254)
		(end 126.49581 -25.40254)
		(width 0.14224)
		(layer "In6.Cu")
		(net "USB2_CPU0_P0_R2_DP")
	)
	(segment
		(start 105.283 -33.64738)
		(end 106.557318 -33.64738)
		(width 0.14224)
		(layer "In6.Cu")
		(net "USB2_CPU0_P0_R2_DP")
	)
	(segment
		(start 126.49581 -25.40254)
		(end 126.63297 -25.5397)
		(width 0.14224)
		(layer "In6.Cu")
		(net "USB2_CPU0_P0_R2_DP")
	)
	(segment
		(start 109.8042 -29.6037)
		(end 111.27232 -28.13558)
		(width 0.14224)
		(layer "In6.Cu")
		(net "USB2_CPU0_P0_R2_DP")
	)
	(segment
		(start 109.8042 -32.13608)
		(end 109.8042 -29.6037)
		(width 0.14224)
		(layer "In6.Cu")
		(net "USB2_CPU0_P0_R2_DP")
	)
	(segment
		(start 125.49505 -25.5397)
		(end 125.63221 -25.40254)
		(width 0.14224)
		(layer "In6.Cu")
		(net "USB2_CPU0_P0_R2_DP")
	)
	(segment
		(start 124.93371 -25.40254)
		(end 125.07087 -25.5397)
		(width 0.14224)
		(layer "In6.Cu")
		(net "USB2_CPU0_P0_R2_DP")
	)
	(segment
		(start 109.1565 -32.78378)
		(end 109.8042 -32.13608)
		(width 0.14224)
		(layer "In6.Cu")
		(net "USB2_CPU0_P0_R2_DP")
	)
	(segment
		(start 127.94488 -25.40254)
		(end 129.9591 -23.38832)
		(width 0.14224)
		(layer "In6.Cu")
		(net "USB2_CPU0_P0_R2_DP")
	)
	(segment
		(start 113.04397 -28.27274)
		(end 113.46815 -28.27274)
		(width 0.14224)
		(layer "In6.Cu")
		(net "USB2_CPU0_P0_R2_DP")
	)
	(segment
		(start 112.34547 -28.27274)
		(end 112.48263 -28.13558)
		(width 0.14224)
		(layer "In6.Cu")
		(net "USB2_CPU0_P0_R2_DP")
	)
	(segment
		(start 104.2289 -32.59328)
		(end 105.283 -33.64738)
		(width 0.14224)
		(layer "In6.Cu")
		(net "USB2_CPU0_P0_R2_DP")
	)
	(segment
		(start 116.26596 -28.13558)
		(end 117.18544 -27.2161)
		(width 0.14224)
		(layer "In6.Cu")
		(net "USB2_CPU0_P0_R2_DP")
	)
	(segment
		(start 117.18544 -27.2161)
		(end 122.327416 -27.2161)
		(width 0.14224)
		(layer "In6.Cu")
		(net "USB2_CPU0_P0_R2_DP")
	)
	(segment
		(start 124.140976 -25.40254)
		(end 124.93371 -25.40254)
		(width 0.14224)
		(layer "In6.Cu")
		(net "USB2_CPU0_P0_R2_DP")
	)
	(segment
		(start 130.76555 -23.38832)
		(end 130.90779 -23.53056)
		(width 0.14224)
		(layer "In6.Cu")
		(net "USB2_CPU0_P0_R2_DP")
	)
	(segment
		(start 130.90779 -24.384254)
		(end 130.61696 -24.675084)
		(width 0.14224)
		(layer "In6.Cu")
		(net "USB2_CPU0_P0_R2_DP")
	)
	(segment
		(start 130.90779 -23.53056)
		(end 130.90779 -24.384254)
		(width 0.14224)
		(layer "In6.Cu")
		(net "USB2_CPU0_P0_R2_DP")
	)
	(segment
		(start 104.269032 -32.325564)
		(end 103.998522 -32.055054)
		(width 0.12954)
		(layer "F.Cu")
		(net "USB2_CPU0_P0_R2_DN")
	)
	(segment
		(start 107.113324 -32.836358)
		(end 106.673142 -33.27654)
		(width 0.12954)
		(layer "F.Cu")
		(net "USB2_CPU0_P0_R2_DN")
	)
	(segment
		(start 108.398818 -32.747712)
		(end 108.154216 -32.747712)
		(width 0.12954)
		(layer "F.Cu")
		(net "USB2_CPU0_P0_R2_DN")
	)
	(segment
		(start 108.154216 -32.747712)
		(end 108.06557 -32.836358)
		(width 0.12954)
		(layer "F.Cu")
		(net "USB2_CPU0_P0_R2_DN")
	)
	(segment
		(start 131.64058 -25.999694)
		(end 131.64058 -26.72588)
		(width 0.12954)
		(layer "F.Cu")
		(net "USB2_CPU0_P0_R2_DN")
	)
	(segment
		(start 103.023924 -31.95701)
		(end 103.392478 -32.325564)
		(width 0.12954)
		(layer "F.Cu")
		(net "USB2_CPU0_P0_R2_DN")
	)
	(segment
		(start 131.48056 -24.675084)
		(end 131.22275 -24.932894)
		(width 0.12954)
		(layer "F.Cu")
		(net "USB2_CPU0_P0_R2_DN")
	)
	(segment
		(start 131.22275 -24.932894)
		(end 131.22275 -25.581864)
		(width 0.12954)
		(layer "F.Cu")
		(net "USB2_CPU0_P0_R2_DN")
	)
	(segment
		(start 103.392478 -32.325564)
		(end 103.728012 -32.325564)
		(width 0.12954)
		(layer "F.Cu")
		(net "USB2_CPU0_P0_R2_DN")
	)
	(segment
		(start 103.728012 -32.325564)
		(end 103.998522 -32.055054)
		(width 0.12954)
		(layer "F.Cu")
		(net "USB2_CPU0_P0_R2_DN")
	)
	(segment
		(start 108.06557 -32.836358)
		(end 107.113324 -32.836358)
		(width 0.12954)
		(layer "F.Cu")
		(net "USB2_CPU0_P0_R2_DN")
	)
	(segment
		(start 131.22275 -25.581864)
		(end 131.64058 -25.999694)
		(width 0.12954)
		(layer "F.Cu")
		(net "USB2_CPU0_P0_R2_DN")
	)
	(segment
		(start 104.510078 -32.325564)
		(end 104.269032 -32.325564)
		(width 0.12954)
		(layer "F.Cu")
		(net "USB2_CPU0_P0_R2_DN")
	)
	(segment
		(start 105.461054 -33.27654)
		(end 104.510078 -32.325564)
		(width 0.12954)
		(layer "F.Cu")
		(net "USB2_CPU0_P0_R2_DN")
	)
	(segment
		(start 106.673142 -33.27654)
		(end 105.461054 -33.27654)
		(width 0.12954)
		(layer "F.Cu")
		(net "USB2_CPU0_P0_R2_DN")
	)
	(segment
		(start 103.378254 -32.31134)
		(end 104.34574 -32.31134)
		(width 0.14224)
		(layer "In6.Cu")
		(net "USB2_CPU0_P0_R2_DN")
	)
	(segment
		(start 127.82804 -25.1206)
		(end 129.84226 -23.10638)
		(width 0.14224)
		(layer "In6.Cu")
		(net "USB2_CPU0_P0_R2_DN")
	)
	(segment
		(start 109.03966 -32.50184)
		(end 109.52226 -32.01924)
		(width 0.14224)
		(layer "In6.Cu")
		(net "USB2_CPU0_P0_R2_DN")
	)
	(segment
		(start 104.34574 -32.31134)
		(end 105.39984 -33.36544)
		(width 0.14224)
		(layer "In6.Cu")
		(net "USB2_CPU0_P0_R2_DN")
	)
	(segment
		(start 131.18973 -24.384254)
		(end 131.48056 -24.675084)
		(width 0.14224)
		(layer "In6.Cu")
		(net "USB2_CPU0_P0_R2_DN")
	)
	(segment
		(start 105.39984 -33.36544)
		(end 106.440478 -33.36544)
		(width 0.14224)
		(layer "In6.Cu")
		(net "USB2_CPU0_P0_R2_DN")
	)
	(segment
		(start 122.210576 -26.93416)
		(end 124.024136 -25.1206)
		(width 0.14224)
		(layer "In6.Cu")
		(net "USB2_CPU0_P0_R2_DN")
	)
	(segment
		(start 106.440478 -33.36544)
		(end 107.304078 -32.50184)
		(width 0.14224)
		(layer "In6.Cu")
		(net "USB2_CPU0_P0_R2_DN")
	)
	(segment
		(start 109.52226 -32.01924)
		(end 109.52226 -29.48686)
		(width 0.14224)
		(layer "In6.Cu")
		(net "USB2_CPU0_P0_R2_DN")
	)
	(segment
		(start 124.024136 -25.1206)
		(end 127.82804 -25.1206)
		(width 0.14224)
		(layer "In6.Cu")
		(net "USB2_CPU0_P0_R2_DN")
	)
	(segment
		(start 129.84226 -23.10638)
		(end 130.88239 -23.10638)
		(width 0.14224)
		(layer "In6.Cu")
		(net "USB2_CPU0_P0_R2_DN")
	)
	(segment
		(start 116.14912 -27.85364)
		(end 117.0686 -26.93416)
		(width 0.14224)
		(layer "In6.Cu")
		(net "USB2_CPU0_P0_R2_DN")
	)
	(segment
		(start 131.18973 -23.41372)
		(end 131.18973 -24.384254)
		(width 0.14224)
		(layer "In6.Cu")
		(net "USB2_CPU0_P0_R2_DN")
	)
	(segment
		(start 103.023924 -31.95701)
		(end 103.378254 -32.31134)
		(width 0.14224)
		(layer "In6.Cu")
		(net "USB2_CPU0_P0_R2_DN")
	)
	(segment
		(start 130.88239 -23.10638)
		(end 131.18973 -23.41372)
		(width 0.14224)
		(layer "In6.Cu")
		(net "USB2_CPU0_P0_R2_DN")
	)
	(segment
		(start 107.304078 -32.50184)
		(end 109.03966 -32.50184)
		(width 0.14224)
		(layer "In6.Cu")
		(net "USB2_CPU0_P0_R2_DN")
	)
	(segment
		(start 111.15548 -27.85364)
		(end 116.14912 -27.85364)
		(width 0.14224)
		(layer "In6.Cu")
		(net "USB2_CPU0_P0_R2_DN")
	)
	(segment
		(start 117.0686 -26.93416)
		(end 122.210576 -26.93416)
		(width 0.14224)
		(layer "In6.Cu")
		(net "USB2_CPU0_P0_R2_DN")
	)
	(segment
		(start 109.52226 -29.48686)
		(end 111.15548 -27.85364)
		(width 0.14224)
		(layer "In6.Cu")
		(net "USB2_CPU0_P0_R2_DN")
	)
	(segment
		(start 131.494276 -32.385254)
		(end 131.532884 -32.346646)
		(width 0.12954)
		(layer "F.Cu")
		(net "USB2_CPU0_P0_R1_DP")
	)
	(segment
		(start 130.90779 -28.944316)
		(end 130.49758 -28.534106)
		(width 0.12954)
		(layer "F.Cu")
		(net "USB2_CPU0_P0_R1_DP")
	)
	(segment
		(start 131.532884 -30.568138)
		(end 130.90779 -29.943044)
		(width 0.12954)
		(layer "F.Cu")
		(net "USB2_CPU0_P0_R1_DP")
	)
	(segment
		(start 130.90779 -29.943044)
		(end 130.90779 -29.2862)
		(width 0.12954)
		(layer "F.Cu")
		(net "USB2_CPU0_P0_R1_DP")
	)
	(segment
		(start 131.532884 -32.346646)
		(end 131.532884 -30.568138)
		(width 0.12954)
		(layer "F.Cu")
		(net "USB2_CPU0_P0_R1_DP")
	)
	(segment
		(start 131.494276 -33.023556)
		(end 131.494276 -32.385254)
		(width 0.12954)
		(layer "F.Cu")
		(net "USB2_CPU0_P0_R1_DP")
	)
	(segment
		(start 130.90779 -29.2862)
		(end 130.90779 -28.944316)
		(width 0.12954)
		(layer "F.Cu")
		(net "USB2_CPU0_P0_R1_DP")
	)
	(segment
		(start 130.49758 -28.534106)
		(end 130.49758 -27.79268)
		(width 0.12954)
		(layer "F.Cu")
		(net "USB2_CPU0_P0_R1_DP")
	)
	(via
		(at 130.90779 -29.2862)
		(size 0.4064)
		(drill 0.2032)
		(layers "F.Cu" "B.Cu")
		(net "USB2_CPU0_P0_R1_DP")
	)
	(segment
		(start 131.64058 -28.55722)
		(end 131.64058 -27.79268)
		(width 0.12954)
		(layer "F.Cu")
		(net "USB2_CPU0_P0_R1_DN")
	)
	(segment
		(start 131.855464 -30.43428)
		(end 131.23037 -29.809186)
		(width 0.12954)
		(layer "F.Cu")
		(net "USB2_CPU0_P0_R1_DN")
	)
	(segment
		(start 131.894072 -32.385254)
		(end 131.855464 -32.346646)
		(width 0.12954)
		(layer "F.Cu")
		(net "USB2_CPU0_P0_R1_DN")
	)
	(segment
		(start 131.23037 -29.809186)
		(end 131.23037 -28.96743)
		(width 0.12954)
		(layer "F.Cu")
		(net "USB2_CPU0_P0_R1_DN")
	)
	(segment
		(start 131.855464 -32.346646)
		(end 131.855464 -31.5468)
		(width 0.12954)
		(layer "F.Cu")
		(net "USB2_CPU0_P0_R1_DN")
	)
	(segment
		(start 131.894072 -33.023556)
		(end 131.894072 -32.385254)
		(width 0.12954)
		(layer "F.Cu")
		(net "USB2_CPU0_P0_R1_DN")
	)
	(segment
		(start 131.855464 -31.5468)
		(end 131.855464 -30.43428)
		(width 0.12954)
		(layer "F.Cu")
		(net "USB2_CPU0_P0_R1_DN")
	)
	(segment
		(start 131.23037 -28.96743)
		(end 131.64058 -28.55722)
		(width 0.12954)
		(layer "F.Cu")
		(net "USB2_CPU0_P0_R1_DN")
	)
	(via
		(at 131.855464 -31.5468)
		(size 0.4064)
		(drill 0.2032)
		(layers "F.Cu" "B.Cu")
		(net "USB2_CPU0_P0_R1_DN")
	)
	(segment
		(start 138.91514 -26.10104)
		(end 138.28268 -26.7335)
		(width 0.12954)
		(layer "F.Cu")
		(net "USB2_CPU0_P0_HUB2_R_DP")
	)
	(segment
		(start 136.095994 -26.92527)
		(end 136.095994 -27.089354)
		(width 0.12954)
		(layer "F.Cu")
		(net "USB2_CPU0_P0_HUB2_R_DP")
	)
	(segment
		(start 136.287764 -26.7335)
		(end 136.095994 -26.92527)
		(width 0.12954)
		(layer "F.Cu")
		(net "USB2_CPU0_P0_HUB2_R_DP")
	)
	(segment
		(start 138.91514 -24.84882)
		(end 138.91514 -26.10104)
		(width 0.12954)
		(layer "F.Cu")
		(net "USB2_CPU0_P0_HUB2_R_DP")
	)
	(segment
		(start 136.095994 -27.089354)
		(end 136.50468 -27.49804)
		(width 0.12954)
		(layer "F.Cu")
		(net "USB2_CPU0_P0_HUB2_R_DP")
	)
	(segment
		(start 138.28268 -26.7335)
		(end 136.287764 -26.7335)
		(width 0.12954)
		(layer "F.Cu")
		(net "USB2_CPU0_P0_HUB2_R_DP")
	)
	(segment
		(start 113.137696 -24.772112)
		(end 113.294922 -24.614886)
		(width 0.12954)
		(layer "F.Cu")
		(net "USB2_CPU0_P0_HUB2_R_DP")
	)
	(segment
		(start 113.294922 -24.614886)
		(end 113.294922 -24.311102)
		(width 0.12954)
		(layer "F.Cu")
		(net "USB2_CPU0_P0_HUB2_R_DP")
	)
	(segment
		(start 133.961378 -25.004268)
		(end 134.27583 -25.004268)
		(width 0.12954)
		(layer "F.Cu")
		(net "USB2_CPU0_P0_HUB2_R_DP")
	)
	(segment
		(start 113.048796 -27.097736)
		(end 113.048796 -26.863548)
		(width 0.12954)
		(layer "F.Cu")
		(net "USB2_CPU0_P0_HUB2_R_DP")
	)
	(segment
		(start 134.27583 -25.004268)
		(end 135.063738 -24.21636)
		(width 0.12954)
		(layer "F.Cu")
		(net "USB2_CPU0_P0_HUB2_R_DP")
	)
	(segment
		(start 113.048796 -26.863548)
		(end 113.137696 -26.774648)
		(width 0.12954)
		(layer "F.Cu")
		(net "USB2_CPU0_P0_HUB2_R_DP")
	)
	(segment
		(start 113.137696 -26.774648)
		(end 113.137696 -24.772112)
		(width 0.12954)
		(layer "F.Cu")
		(net "USB2_CPU0_P0_HUB2_R_DP")
	)
	(segment
		(start 138.28268 -24.21636)
		(end 138.91514 -24.84882)
		(width 0.12954)
		(layer "F.Cu")
		(net "USB2_CPU0_P0_HUB2_R_DP")
	)
	(segment
		(start 135.063738 -24.21636)
		(end 138.28268 -24.21636)
		(width 0.12954)
		(layer "F.Cu")
		(net "USB2_CPU0_P0_HUB2_R_DP")
	)
	(segment
		(start 113.294922 -24.311102)
		(end 113.033556 -24.049736)
		(width 0.12954)
		(layer "F.Cu")
		(net "USB2_CPU0_P0_HUB2_R_DP")
	)
	(segment
		(start 133.72084 -24.76373)
		(end 133.961378 -25.004268)
		(width 0.12954)
		(layer "F.Cu")
		(net "USB2_CPU0_P0_HUB2_R_DP")
	)
	(segment
		(start 136.50468 -27.49804)
		(end 136.50468 -28.21432)
		(width 0.12954)
		(layer "F.Cu")
		(net "USB2_CPU0_P0_HUB2_R_DP")
	)
	(segment
		(start 127.892048 -24.00808)
		(end 127.467868 -24.00808)
		(width 0.14224)
		(layer "In6.Cu")
		(net "USB2_CPU0_P0_HUB2_R_DP")
	)
	(segment
		(start 133.78434 -24.76373)
		(end 134.07517 -25.05456)
		(width 0.14224)
		(layer "In6.Cu")
		(net "USB2_CPU0_P0_HUB2_R_DP")
	)
	(segment
		(start 122.14352 -26.17216)
		(end 120.2944 -26.17216)
		(width 0.14224)
		(layer "In6.Cu")
		(net "USB2_CPU0_P0_HUB2_R_DP")
	)
	(segment
		(start 127.330708 -24.14524)
		(end 126.906528 -24.14524)
		(width 0.14224)
		(layer "In6.Cu")
		(net "USB2_CPU0_P0_HUB2_R_DP")
	)
	(segment
		(start 131.30784 -22.22754)
		(end 129.672588 -22.22754)
		(width 0.14224)
		(layer "In6.Cu")
		(net "USB2_CPU0_P0_HUB2_R_DP")
	)
	(segment
		(start 119.544338 -25.422098)
		(end 113.857532 -25.422098)
		(width 0.14224)
		(layer "In6.Cu")
		(net "USB2_CPU0_P0_HUB2_R_DP")
	)
	(segment
		(start 124.3076 -24.00808)
		(end 122.14352 -26.17216)
		(width 0.14224)
		(layer "In6.Cu")
		(net "USB2_CPU0_P0_HUB2_R_DP")
	)
	(segment
		(start 131.445 -22.3647)
		(end 131.30784 -22.22754)
		(width 0.14224)
		(layer "In6.Cu")
		(net "USB2_CPU0_P0_HUB2_R_DP")
	)
	(segment
		(start 134.38378 -25.05456)
		(end 134.52602 -24.91232)
		(width 0.14224)
		(layer "In6.Cu")
		(net "USB2_CPU0_P0_HUB2_R_DP")
	)
	(segment
		(start 125.54331 -24.00808)
		(end 124.3076 -24.00808)
		(width 0.14224)
		(layer "In6.Cu")
		(net "USB2_CPU0_P0_HUB2_R_DP")
	)
	(segment
		(start 134.52602 -24.91232)
		(end 134.52602 -24.32304)
		(width 0.14224)
		(layer "In6.Cu")
		(net "USB2_CPU0_P0_HUB2_R_DP")
	)
	(segment
		(start 126.10465 -24.14524)
		(end 125.68047 -24.14524)
		(width 0.14224)
		(layer "In6.Cu")
		(net "USB2_CPU0_P0_HUB2_R_DP")
	)
	(segment
		(start 113.324386 -24.888952)
		(end 113.324386 -24.340566)
		(width 0.14224)
		(layer "In6.Cu")
		(net "USB2_CPU0_P0_HUB2_R_DP")
	)
	(segment
		(start 133.72084 -24.76373)
		(end 133.78434 -24.76373)
		(width 0.14224)
		(layer "In6.Cu")
		(net "USB2_CPU0_P0_HUB2_R_DP")
	)
	(segment
		(start 134.52602 -24.32304)
		(end 133.820154 -23.617174)
		(width 0.14224)
		(layer "In6.Cu")
		(net "USB2_CPU0_P0_HUB2_R_DP")
	)
	(segment
		(start 133.342126 -23.329646)
		(end 133.342126 -23.139146)
		(width 0.14224)
		(layer "In6.Cu")
		(net "USB2_CPU0_P0_HUB2_R_DP")
	)
	(segment
		(start 129.672588 -22.22754)
		(end 127.892048 -24.00808)
		(width 0.14224)
		(layer "In6.Cu")
		(net "USB2_CPU0_P0_HUB2_R_DP")
	)
	(segment
		(start 126.769368 -24.00808)
		(end 126.24181 -24.00808)
		(width 0.14224)
		(layer "In6.Cu")
		(net "USB2_CPU0_P0_HUB2_R_DP")
	)
	(segment
		(start 125.68047 -24.14524)
		(end 125.54331 -24.00808)
		(width 0.14224)
		(layer "In6.Cu")
		(net "USB2_CPU0_P0_HUB2_R_DP")
	)
	(segment
		(start 120.2944 -26.17216)
		(end 119.544338 -25.422098)
		(width 0.14224)
		(layer "In6.Cu")
		(net "USB2_CPU0_P0_HUB2_R_DP")
	)
	(segment
		(start 133.629654 -23.617174)
		(end 133.342126 -23.329646)
		(width 0.14224)
		(layer "In6.Cu")
		(net "USB2_CPU0_P0_HUB2_R_DP")
	)
	(segment
		(start 132.43052 -22.22754)
		(end 132.00634 -22.22754)
		(width 0.14224)
		(layer "In6.Cu")
		(net "USB2_CPU0_P0_HUB2_R_DP")
	)
	(segment
		(start 126.24181 -24.00808)
		(end 126.10465 -24.14524)
		(width 0.14224)
		(layer "In6.Cu")
		(net "USB2_CPU0_P0_HUB2_R_DP")
	)
	(segment
		(start 133.820154 -23.617174)
		(end 133.629654 -23.617174)
		(width 0.14224)
		(layer "In6.Cu")
		(net "USB2_CPU0_P0_HUB2_R_DP")
	)
	(segment
		(start 133.342126 -23.139146)
		(end 132.43052 -22.22754)
		(width 0.14224)
		(layer "In6.Cu")
		(net "USB2_CPU0_P0_HUB2_R_DP")
	)
	(segment
		(start 132.00634 -22.22754)
		(end 131.86918 -22.3647)
		(width 0.14224)
		(layer "In6.Cu")
		(net "USB2_CPU0_P0_HUB2_R_DP")
	)
	(segment
		(start 126.906528 -24.14524)
		(end 126.769368 -24.00808)
		(width 0.14224)
		(layer "In6.Cu")
		(net "USB2_CPU0_P0_HUB2_R_DP")
	)
	(segment
		(start 131.86918 -22.3647)
		(end 131.445 -22.3647)
		(width 0.14224)
		(layer "In6.Cu")
		(net "USB2_CPU0_P0_HUB2_R_DP")
	)
	(segment
		(start 113.324386 -24.340566)
		(end 113.033556 -24.049736)
		(width 0.14224)
		(layer "In6.Cu")
		(net "USB2_CPU0_P0_HUB2_R_DP")
	)
	(segment
		(start 134.07517 -25.05456)
		(end 134.38378 -25.05456)
		(width 0.14224)
		(layer "In6.Cu")
		(net "USB2_CPU0_P0_HUB2_R_DP")
	)
	(segment
		(start 113.857532 -25.422098)
		(end 113.324386 -24.888952)
		(width 0.14224)
		(layer "In6.Cu")
		(net "USB2_CPU0_P0_HUB2_R_DP")
	)
	(segment
		(start 127.467868 -24.00808)
		(end 127.330708 -24.14524)
		(width 0.14224)
		(layer "In6.Cu")
		(net "USB2_CPU0_P0_HUB2_R_DP")
	)
	(segment
		(start 138.148822 -24.53894)
		(end 138.59256 -24.982678)
		(width 0.12954)
		(layer "F.Cu")
		(net "USB2_CPU0_P0_HUB2_R_DN")
	)
	(segment
		(start 113.548922 -27.097736)
		(end 113.548922 -26.862278)
		(width 0.12954)
		(layer "F.Cu")
		(net "USB2_CPU0_P0_HUB2_R_DN")
	)
	(segment
		(start 113.548922 -26.862278)
		(end 113.460276 -26.773632)
		(width 0.12954)
		(layer "F.Cu")
		(net "USB2_CPU0_P0_HUB2_R_DN")
	)
	(segment
		(start 137.432796 -24.53894)
		(end 138.148822 -24.53894)
		(width 0.12954)
		(layer "F.Cu")
		(net "USB2_CPU0_P0_HUB2_R_DN")
	)
	(segment
		(start 138.59256 -24.982678)
		(end 138.59256 -25.967182)
		(width 0.12954)
		(layer "F.Cu")
		(net "USB2_CPU0_P0_HUB2_R_DN")
	)
	(segment
		(start 134.021322 -25.326848)
		(end 134.409688 -25.326848)
		(width 0.12954)
		(layer "F.Cu")
		(net "USB2_CPU0_P0_HUB2_R_DN")
	)
	(segment
		(start 137.762742 -26.41092)
		(end 137.572242 -26.22042)
		(width 0.12954)
		(layer "F.Cu")
		(net "USB2_CPU0_P0_HUB2_R_DN")
	)
	(segment
		(start 136.153906 -26.41092)
		(end 135.773414 -26.791412)
		(width 0.12954)
		(layer "F.Cu")
		(net "USB2_CPU0_P0_HUB2_R_DN")
	)
	(segment
		(start 138.59256 -25.967182)
		(end 138.148822 -26.41092)
		(width 0.12954)
		(layer "F.Cu")
		(net "USB2_CPU0_P0_HUB2_R_DN")
	)
	(segment
		(start 135.512556 -24.53894)
		(end 135.703056 -24.72944)
		(width 0.12954)
		(layer "F.Cu")
		(net "USB2_CPU0_P0_HUB2_R_DN")
	)
	(segment
		(start 136.279636 -24.53894)
		(end 136.665716 -24.53894)
		(width 0.12954)
		(layer "F.Cu")
		(net "USB2_CPU0_P0_HUB2_R_DN")
	)
	(segment
		(start 135.703056 -24.72944)
		(end 136.089136 -24.72944)
		(width 0.12954)
		(layer "F.Cu")
		(net "USB2_CPU0_P0_HUB2_R_DN")
	)
	(segment
		(start 136.856216 -24.72944)
		(end 137.242296 -24.72944)
		(width 0.12954)
		(layer "F.Cu")
		(net "USB2_CPU0_P0_HUB2_R_DN")
	)
	(segment
		(start 138.148822 -26.41092)
		(end 137.762742 -26.41092)
		(width 0.12954)
		(layer "F.Cu")
		(net "USB2_CPU0_P0_HUB2_R_DN")
	)
	(segment
		(start 113.460276 -24.90597)
		(end 113.617502 -24.748744)
		(width 0.12954)
		(layer "F.Cu")
		(net "USB2_CPU0_P0_HUB2_R_DN")
	)
	(segment
		(start 136.995662 -26.41092)
		(end 136.153906 -26.41092)
		(width 0.12954)
		(layer "F.Cu")
		(net "USB2_CPU0_P0_HUB2_R_DN")
	)
	(segment
		(start 135.773414 -26.791412)
		(end 135.773414 -27.093926)
		(width 0.12954)
		(layer "F.Cu")
		(net "USB2_CPU0_P0_HUB2_R_DN")
	)
	(segment
		(start 133.72084 -25.62733)
		(end 134.021322 -25.326848)
		(width 0.12954)
		(layer "F.Cu")
		(net "USB2_CPU0_P0_HUB2_R_DN")
	)
	(segment
		(start 137.242296 -24.72944)
		(end 137.432796 -24.53894)
		(width 0.12954)
		(layer "F.Cu")
		(net "USB2_CPU0_P0_HUB2_R_DN")
	)
	(segment
		(start 135.197596 -24.53894)
		(end 135.512556 -24.53894)
		(width 0.12954)
		(layer "F.Cu")
		(net "USB2_CPU0_P0_HUB2_R_DN")
	)
	(segment
		(start 135.773414 -27.093926)
		(end 135.36168 -27.50566)
		(width 0.12954)
		(layer "F.Cu")
		(net "USB2_CPU0_P0_HUB2_R_DN")
	)
	(segment
		(start 134.409688 -25.326848)
		(end 135.197596 -24.53894)
		(width 0.12954)
		(layer "F.Cu")
		(net "USB2_CPU0_P0_HUB2_R_DN")
	)
	(segment
		(start 136.089136 -24.72944)
		(end 136.279636 -24.53894)
		(width 0.12954)
		(layer "F.Cu")
		(net "USB2_CPU0_P0_HUB2_R_DN")
	)
	(segment
		(start 113.617502 -24.32939)
		(end 113.897156 -24.049736)
		(width 0.12954)
		(layer "F.Cu")
		(net "USB2_CPU0_P0_HUB2_R_DN")
	)
	(segment
		(start 113.460276 -26.773632)
		(end 113.460276 -24.90597)
		(width 0.12954)
		(layer "F.Cu")
		(net "USB2_CPU0_P0_HUB2_R_DN")
	)
	(segment
		(start 135.36168 -27.50566)
		(end 135.36168 -28.21432)
		(width 0.12954)
		(layer "F.Cu")
		(net "USB2_CPU0_P0_HUB2_R_DN")
	)
	(segment
		(start 136.665716 -24.53894)
		(end 136.856216 -24.72944)
		(width 0.12954)
		(layer "F.Cu")
		(net "USB2_CPU0_P0_HUB2_R_DN")
	)
	(segment
		(start 113.617502 -24.748744)
		(end 113.617502 -24.32939)
		(width 0.12954)
		(layer "F.Cu")
		(net "USB2_CPU0_P0_HUB2_R_DN")
	)
	(segment
		(start 137.572242 -26.22042)
		(end 137.186162 -26.22042)
		(width 0.12954)
		(layer "F.Cu")
		(net "USB2_CPU0_P0_HUB2_R_DN")
	)
	(segment
		(start 137.186162 -26.22042)
		(end 136.995662 -26.41092)
		(width 0.12954)
		(layer "F.Cu")
		(net "USB2_CPU0_P0_HUB2_R_DN")
	)
	(segment
		(start 124.19076 -23.72614)
		(end 122.02668 -25.89022)
		(width 0.14224)
		(layer "In6.Cu")
		(net "USB2_CPU0_P0_HUB2_R_DN")
	)
	(segment
		(start 134.80796 -25.02916)
		(end 134.80796 -24.2062)
		(width 0.14224)
		(layer "In6.Cu")
		(net "USB2_CPU0_P0_HUB2_R_DN")
	)
	(segment
		(start 119.661178 -25.140158)
		(end 113.974372 -25.140158)
		(width 0.14224)
		(layer "In6.Cu")
		(net "USB2_CPU0_P0_HUB2_R_DN")
	)
	(segment
		(start 113.606326 -24.340566)
		(end 113.897156 -24.049736)
		(width 0.14224)
		(layer "In6.Cu")
		(net "USB2_CPU0_P0_HUB2_R_DN")
	)
	(segment
		(start 122.02668 -25.89022)
		(end 120.41124 -25.89022)
		(width 0.14224)
		(layer "In6.Cu")
		(net "USB2_CPU0_P0_HUB2_R_DN")
	)
	(segment
		(start 133.72084 -25.62733)
		(end 133.78434 -25.62733)
		(width 0.14224)
		(layer "In6.Cu")
		(net "USB2_CPU0_P0_HUB2_R_DN")
	)
	(segment
		(start 113.974372 -25.140158)
		(end 113.606326 -24.772112)
		(width 0.14224)
		(layer "In6.Cu")
		(net "USB2_CPU0_P0_HUB2_R_DN")
	)
	(segment
		(start 134.50062 -25.3365)
		(end 134.80796 -25.02916)
		(width 0.14224)
		(layer "In6.Cu")
		(net "USB2_CPU0_P0_HUB2_R_DN")
	)
	(segment
		(start 127.775208 -23.72614)
		(end 124.19076 -23.72614)
		(width 0.14224)
		(layer "In6.Cu")
		(net "USB2_CPU0_P0_HUB2_R_DN")
	)
	(segment
		(start 113.606326 -24.772112)
		(end 113.606326 -24.340566)
		(width 0.14224)
		(layer "In6.Cu")
		(net "USB2_CPU0_P0_HUB2_R_DN")
	)
	(segment
		(start 132.54736 -21.9456)
		(end 129.555748 -21.9456)
		(width 0.14224)
		(layer "In6.Cu")
		(net "USB2_CPU0_P0_HUB2_R_DN")
	)
	(segment
		(start 129.555748 -21.9456)
		(end 127.775208 -23.72614)
		(width 0.14224)
		(layer "In6.Cu")
		(net "USB2_CPU0_P0_HUB2_R_DN")
	)
	(segment
		(start 134.07517 -25.3365)
		(end 134.50062 -25.3365)
		(width 0.14224)
		(layer "In6.Cu")
		(net "USB2_CPU0_P0_HUB2_R_DN")
	)
	(segment
		(start 133.78434 -25.62733)
		(end 134.07517 -25.3365)
		(width 0.14224)
		(layer "In6.Cu")
		(net "USB2_CPU0_P0_HUB2_R_DN")
	)
	(segment
		(start 120.41124 -25.89022)
		(end 119.661178 -25.140158)
		(width 0.14224)
		(layer "In6.Cu")
		(net "USB2_CPU0_P0_HUB2_R_DN")
	)
	(segment
		(start 134.80796 -24.2062)
		(end 132.54736 -21.9456)
		(width 0.14224)
		(layer "In6.Cu")
		(net "USB2_CPU0_P0_HUB2_R_DN")
	)
	(segment
		(start 133.349238 -31.0388)
		(end 135.51408 -31.0388)
		(width 0.12954)
		(layer "F.Cu")
		(net "USB2_CPU0_P0_HUB1_R_DP")
	)
	(segment
		(start 136.11479 -30.692598)
		(end 135.768588 -31.0388)
		(width 0.12954)
		(layer "F.Cu")
		(net "USB2_CPU0_P0_HUB1_R_DP")
	)
	(segment
		(start 136.50468 -29.98724)
		(end 136.11479 -30.37713)
		(width 0.12954)
		(layer "F.Cu")
		(net "USB2_CPU0_P0_HUB1_R_DP")
	)
	(segment
		(start 132.694172 -33.023556)
		(end 132.694172 -32.385508)
		(width 0.12954)
		(layer "F.Cu")
		(net "USB2_CPU0_P0_HUB1_R_DP")
	)
	(segment
		(start 132.65531 -32.346646)
		(end 132.65531 -31.732728)
		(width 0.12954)
		(layer "F.Cu")
		(net "USB2_CPU0_P0_HUB1_R_DP")
	)
	(segment
		(start 132.694172 -32.385508)
		(end 132.65531 -32.346646)
		(width 0.12954)
		(layer "F.Cu")
		(net "USB2_CPU0_P0_HUB1_R_DP")
	)
	(segment
		(start 135.768588 -31.0388)
		(end 135.51408 -31.0388)
		(width 0.12954)
		(layer "F.Cu")
		(net "USB2_CPU0_P0_HUB1_R_DP")
	)
	(segment
		(start 132.65531 -31.732728)
		(end 133.349238 -31.0388)
		(width 0.12954)
		(layer "F.Cu")
		(net "USB2_CPU0_P0_HUB1_R_DP")
	)
	(segment
		(start 136.50468 -29.28112)
		(end 136.50468 -29.98724)
		(width 0.12954)
		(layer "F.Cu")
		(net "USB2_CPU0_P0_HUB1_R_DP")
	)
	(segment
		(start 136.11479 -30.37713)
		(end 136.11479 -30.692598)
		(width 0.12954)
		(layer "F.Cu")
		(net "USB2_CPU0_P0_HUB1_R_DP")
	)
	(via
		(at 135.51408 -31.0388)
		(size 0.4064)
		(drill 0.2032)
		(layers "F.Cu" "B.Cu")
		(net "USB2_CPU0_P0_HUB1_R_DP")
	)
	(segment
		(start 132.294122 -33.023556)
		(end 132.294122 -32.385254)
		(width 0.12954)
		(layer "F.Cu")
		(net "USB2_CPU0_P0_HUB1_R_DN")
	)
	(segment
		(start 135.63473 -30.71622)
		(end 133.92912 -30.71622)
		(width 0.12954)
		(layer "F.Cu")
		(net "USB2_CPU0_P0_HUB1_R_DN")
	)
	(segment
		(start 135.79221 -30.422596)
		(end 135.79221 -30.55874)
		(width 0.12954)
		(layer "F.Cu")
		(net "USB2_CPU0_P0_HUB1_R_DN")
	)
	(segment
		(start 135.36168 -29.992066)
		(end 135.79221 -30.422596)
		(width 0.12954)
		(layer "F.Cu")
		(net "USB2_CPU0_P0_HUB1_R_DN")
	)
	(segment
		(start 132.294122 -32.385254)
		(end 132.33273 -32.346646)
		(width 0.12954)
		(layer "F.Cu")
		(net "USB2_CPU0_P0_HUB1_R_DN")
	)
	(segment
		(start 135.36168 -29.28112)
		(end 135.36168 -29.992066)
		(width 0.12954)
		(layer "F.Cu")
		(net "USB2_CPU0_P0_HUB1_R_DN")
	)
	(segment
		(start 135.79221 -30.55874)
		(end 135.63473 -30.71622)
		(width 0.12954)
		(layer "F.Cu")
		(net "USB2_CPU0_P0_HUB1_R_DN")
	)
	(segment
		(start 132.33273 -32.346646)
		(end 132.33273 -31.59887)
		(width 0.12954)
		(layer "F.Cu")
		(net "USB2_CPU0_P0_HUB1_R_DN")
	)
	(segment
		(start 132.33273 -31.59887)
		(end 133.21538 -30.71622)
		(width 0.12954)
		(layer "F.Cu")
		(net "USB2_CPU0_P0_HUB1_R_DN")
	)
	(segment
		(start 133.21538 -30.71622)
		(end 133.92912 -30.71622)
		(width 0.12954)
		(layer "F.Cu")
		(net "USB2_CPU0_P0_HUB1_R_DN")
	)
	(via
		(at 133.92912 -30.71622)
		(size 0.4064)
		(drill 0.2032)
		(layers "F.Cu" "B.Cu")
		(net "USB2_CPU0_P0_HUB1_R_DN")
	)
	(segment
		(start 135.034528 -42.3672)
		(end 135.5979 -42.930572)
		(width 0.10668)
		(layer "F.Cu")
		(net "TP_CPU0_USB_HUB1_SUSPEND")
	)
	(segment
		(start 135.034528 -41.414192)
		(end 135.034528 -42.3672)
		(width 0.10668)
		(layer "F.Cu")
		(net "TP_CPU0_USB_HUB1_SUSPEND")
	)
	(segment
		(start 135.094218 -40.723312)
		(end 135.094218 -41.354502)
		(width 0.10668)
		(layer "F.Cu")
		(net "TP_CPU0_USB_HUB1_SUSPEND")
	)
	(segment
		(start 135.094218 -41.354502)
		(end 135.034528 -41.414192)
		(width 0.10668)
		(layer "F.Cu")
		(net "TP_CPU0_USB_HUB1_SUSPEND")
	)
	(via
		(at 135.5979 -42.930572)
		(size 0.762)
		(drill 0.381)
		(layers "F.Cu" "B.Cu")
		(net "TP_CPU0_USB_HUB1_SUSPEND")
	)
	(segment
		(start 431.3174 -428.056294)
		(end 431.956718 -427.416976)
		(width 0.10668)
		(layer "F.Cu")
		(net "NC_HSC_TYPE_NC0")
	)
	(segment
		(start 430.42459 -428.056294)
		(end 431.3174 -428.056294)
		(width 0.10668)
		(layer "F.Cu")
		(net "NC_HSC_TYPE_NC0")
	)
	(via
		(at 431.956718 -427.416976)
		(size 0.762)
		(drill 0.381)
		(layers "F.Cu" "B.Cu")
		(net "NC_HSC_TYPE_NC0")
	)
	(via
		(at 146.2532 -80.34782)
		(size 0.762)
		(drill 0.381)
		(layers "F.Cu" "B.Cu")
		(net "SW_P1V8_AUX_PH")
	)
	(segment
		(start 145.65757 -77.700632)
		(end 145.070576 -78.287626)
		(width 0.254)
		(layer "F.Cu")
		(net "SW_P1V8_AUX_BT")
	)
	(segment
		(start 146.194018 -76.477622)
		(end 145.981928 -76.477622)
		(width 0.254)
		(layer "F.Cu")
		(net "SW_P1V8_AUX_BT")
	)
	(segment
		(start 145.070576 -78.287626)
		(end 144.311624 -78.287626)
		(width 0.254)
		(layer "F.Cu")
		(net "SW_P1V8_AUX_BT")
	)
	(segment
		(start 145.981928 -76.477622)
		(end 145.65757 -76.80198)
		(width 0.254)
		(layer "F.Cu")
		(net "SW_P1V8_AUX_BT")
	)
	(segment
		(start 145.65757 -76.80198)
		(end 145.65757 -77.700632)
		(width 0.254)
		(layer "F.Cu")
		(net "SW_P1V8_AUX_BT")
	)
	(via
		(at 124.1552 -78.07452)
		(size 0.762)
		(drill 0.381)
		(layers "F.Cu" "B.Cu")
		(net "SW_P1V2_AUX_PH")
	)
	(segment
		(start 124.090176 -74.155046)
		(end 123.95962 -74.155046)
		(width 0.254)
		(layer "F.Cu")
		(net "SW_P1V2_AUX_BT")
	)
	(segment
		(start 123.473464 -75.384152)
		(end 122.85599 -76.001626)
		(width 0.254)
		(layer "F.Cu")
		(net "SW_P1V2_AUX_BT")
	)
	(segment
		(start 123.473464 -74.641202)
		(end 123.473464 -75.384152)
		(width 0.254)
		(layer "F.Cu")
		(net "SW_P1V2_AUX_BT")
	)
	(segment
		(start 122.85599 -76.001626)
		(end 122.213624 -76.001626)
		(width 0.254)
		(layer "F.Cu")
		(net "SW_P1V2_AUX_BT")
	)
	(segment
		(start 123.95962 -74.155046)
		(end 123.473464 -74.641202)
		(width 0.254)
		(layer "F.Cu")
		(net "SW_P1V2_AUX_BT")
	)
	(via
		(at 139.43203 -76.906628)
		(size 0.762)
		(drill 0.381)
		(layers "F.Cu" "B.Cu")
		(net "SW_P12V_AUX_P1V8_AUX_FLT")
	)
	(via
		(at 117.22989 -74.640948)
		(size 0.762)
		(drill 0.381)
		(layers "F.Cu" "B.Cu")
		(net "SW_P12V_AUX_P1V2_AUX_FLT")
	)
	(segment
		(start 114.551968 -63.187072)
		(end 113.609628 -63.187072)
		(width 0.10668)
		(layer "F.Cu")
		(net "SMB_USB_CPU0_HUB1_SDA_R2")
	)
	(segment
		(start 113.609628 -63.187072)
		(end 113.46434 -63.33236)
		(width 0.10668)
		(layer "F.Cu")
		(net "SMB_USB_CPU0_HUB1_SDA_R2")
	)
	(via
		(at 113.46434 -63.33236)
		(size 0.508)
		(drill 0.254)
		(layers "F.Cu" "B.Cu")
		(net "SMB_USB_CPU0_HUB1_SDA_R2")
	)
	(segment
		(start 113.46434 -62.41796)
		(end 113.71834 -62.16396)
		(width 0.10668)
		(layer "B.Cu")
		(net "SMB_USB_CPU0_HUB1_SDA_R2")
	)
	(segment
		(start 113.46434 -63.33236)
		(end 113.46434 -62.41796)
		(width 0.10668)
		(layer "B.Cu")
		(net "SMB_USB_CPU0_HUB1_SDA_R2")
	)
	(segment
		(start 114.73434 -62.16396)
		(end 113.71834 -62.16396)
		(width 0.10668)
		(layer "B.Cu")
		(net "SMB_USB_CPU0_HUB1_SDA_R2")
	)
	(segment
		(start 280.675842 -121.50217)
		(end 282.19527 -121.50217)
		(width 0.10668)
		(layer "F.Cu")
		(net "SMB_USB_CPU0_HUB1_SDA_R")
	)
	(segment
		(start 284.127956 -120.832118)
		(end 282.865322 -120.832118)
		(width 0.10668)
		(layer "F.Cu")
		(net "SMB_USB_CPU0_HUB1_SDA_R")
	)
	(segment
		(start 279.913842 -120.74017)
		(end 280.675842 -121.50217)
		(width 0.10668)
		(layer "F.Cu")
		(net "SMB_USB_CPU0_HUB1_SDA_R")
	)
	(segment
		(start 282.865322 -120.832118)
		(end 282.19527 -121.50217)
		(width 0.10668)
		(layer "F.Cu")
		(net "SMB_USB_CPU0_HUB1_SDA_R")
	)
	(via
		(at 282.19527 -121.50217)
		(size 0.762)
		(drill 0.381)
		(layers "F.Cu" "B.Cu")
		(net "SMB_USB_CPU0_HUB1_SDA_R")
	)
	(segment
		(start 114.299238 -43.358054)
		(end 119.29364 -43.358054)
		(width 0.10668)
		(layer "F.Cu")
		(net "SMB_USB_CPU0_HUB1_SDA")
	)
	(segment
		(start 121.9708 -48.3616)
		(end 121.9708 -48.7426)
		(width 0.10668)
		(layer "F.Cu")
		(net "SMB_USB_CPU0_HUB1_SDA")
	)
	(segment
		(start 277.608792 -120.97512)
		(end 278.878792 -120.97512)
		(width 0.10668)
		(layer "F.Cu")
		(net "SMB_USB_CPU0_HUB1_SDA")
	)
	(segment
		(start 278.878792 -120.97512)
		(end 279.113742 -120.74017)
		(width 0.10668)
		(layer "F.Cu")
		(net "SMB_USB_CPU0_HUB1_SDA")
	)
	(segment
		(start 119.29364 -43.358054)
		(end 120.395238 -42.256456)
		(width 0.10668)
		(layer "F.Cu")
		(net "SMB_USB_CPU0_HUB1_SDA")
	)
	(segment
		(start 276.86 -121.285)
		(end 277.16988 -120.97512)
		(width 0.10668)
		(layer "F.Cu")
		(net "SMB_USB_CPU0_HUB1_SDA")
	)
	(segment
		(start 129.641092 -41.78046)
		(end 128.55194 -41.78046)
		(width 0.10668)
		(layer "F.Cu")
		(net "SMB_USB_CPU0_HUB1_SDA")
	)
	(segment
		(start 120.395238 -42.256456)
		(end 120.395238 -41.5798)
		(width 0.10668)
		(layer "F.Cu")
		(net "SMB_USB_CPU0_HUB1_SDA")
	)
	(segment
		(start 277.16988 -120.97512)
		(end 277.608792 -120.97512)
		(width 0.10668)
		(layer "F.Cu")
		(net "SMB_USB_CPU0_HUB1_SDA")
	)
	(segment
		(start 129.894076 -40.723312)
		(end 129.894076 -41.527476)
		(width 0.10668)
		(layer "F.Cu")
		(net "SMB_USB_CPU0_HUB1_SDA")
	)
	(segment
		(start 107.517946 -53.26253)
		(end 107.517946 -53.872384)
		(width 0.10668)
		(layer "F.Cu")
		(net "SMB_USB_CPU0_HUB1_SDA")
	)
	(segment
		(start 129.894076 -41.527476)
		(end 129.641092 -41.78046)
		(width 0.10668)
		(layer "F.Cu")
		(net "SMB_USB_CPU0_HUB1_SDA")
	)
	(segment
		(start 128.55194 -41.78046)
		(end 121.9708 -48.3616)
		(width 0.10668)
		(layer "F.Cu")
		(net "SMB_USB_CPU0_HUB1_SDA")
	)
	(via
		(at 112.09528 -79.54518)
		(size 0.508)
		(drill 0.254)
		(layers "F.Cu" "B.Cu")
		(net "SMB_USB_CPU0_HUB1_SDA")
	)
	(via
		(at 107.517946 -53.872384)
		(size 0.508)
		(drill 0.254)
		(layers "F.Cu" "B.Cu")
		(net "SMB_USB_CPU0_HUB1_SDA")
	)
	(via
		(at 114.299238 -43.358054)
		(size 0.508)
		(drill 0.254)
		(layers "F.Cu" "B.Cu")
		(net "SMB_USB_CPU0_HUB1_SDA")
	)
	(via
		(at 112.44834 -60.44946)
		(size 0.508)
		(drill 0.254)
		(layers "F.Cu" "B.Cu")
		(net "SMB_USB_CPU0_HUB1_SDA")
	)
	(via
		(at 121.9708 -48.7426)
		(size 0.508)
		(drill 0.254)
		(layers "F.Cu" "B.Cu")
		(net "SMB_USB_CPU0_HUB1_SDA")
	)
	(via
		(at 276.86 -121.285)
		(size 0.508)
		(drill 0.254)
		(layers "F.Cu" "B.Cu")
		(net "SMB_USB_CPU0_HUB1_SDA")
	)
	(segment
		(start 113.71834 -61.36386)
		(end 113.36274 -61.36386)
		(width 0.10668)
		(layer "B.Cu")
		(net "SMB_USB_CPU0_HUB1_SDA")
	)
	(segment
		(start 113.36274 -61.36386)
		(end 112.44834 -60.44946)
		(width 0.10668)
		(layer "B.Cu")
		(net "SMB_USB_CPU0_HUB1_SDA")
	)
	(segment
		(start 279.18918 -102.22484)
		(end 275.83638 -98.87204)
		(width 0.11684)
		(layer "In2.Cu")
		(net "SMB_USB_CPU0_HUB1_SDA")
	)
	(segment
		(start 275.83638 -98.381312)
		(end 272.961862 -95.506794)
		(width 0.11684)
		(layer "In2.Cu")
		(net "SMB_USB_CPU0_HUB1_SDA")
	)
	(segment
		(start 278.41702 -119.72798)
		(end 278.41702 -110.4646)
		(width 0.11684)
		(layer "In2.Cu")
		(net "SMB_USB_CPU0_HUB1_SDA")
	)
	(segment
		(start 258.511548 -86.54288)
		(end 247.870472 -86.54288)
		(width 0.11684)
		(layer "In2.Cu")
		(net "SMB_USB_CPU0_HUB1_SDA")
	)
	(segment
		(start 214.267542 -90.733118)
		(end 211.57057 -88.036146)
		(width 0.11684)
		(layer "In2.Cu")
		(net "SMB_USB_CPU0_HUB1_SDA")
	)
	(segment
		(start 111.63046 -80.01)
		(end 112.09528 -79.54518)
		(width 0.11684)
		(layer "In2.Cu")
		(net "SMB_USB_CPU0_HUB1_SDA")
	)
	(segment
		(start 181.546754 -84.746338)
		(end 160.991042 -84.746338)
		(width 0.11684)
		(layer "In2.Cu")
		(net "SMB_USB_CPU0_HUB1_SDA")
	)
	(segment
		(start 211.57057 -88.036146)
		(end 197.63486 -88.036146)
		(width 0.11684)
		(layer "In2.Cu")
		(net "SMB_USB_CPU0_HUB1_SDA")
	)
	(segment
		(start 261.10057 -89.93505)
		(end 260.1341 -88.96858)
		(width 0.11684)
		(layer "In2.Cu")
		(net "SMB_USB_CPU0_HUB1_SDA")
	)
	(segment
		(start 197.63486 -88.036146)
		(end 197.23608 -87.637366)
		(width 0.11684)
		(layer "In2.Cu")
		(net "SMB_USB_CPU0_HUB1_SDA")
	)
	(segment
		(start 160.991042 -84.746338)
		(end 159.318452 -86.418928)
		(width 0.11684)
		(layer "In2.Cu")
		(net "SMB_USB_CPU0_HUB1_SDA")
	)
	(segment
		(start 114.450368 -86.418928)
		(end 111.63046 -83.59902)
		(width 0.11684)
		(layer "In2.Cu")
		(net "SMB_USB_CPU0_HUB1_SDA")
	)
	(segment
		(start 247.870472 -86.54288)
		(end 243.680234 -90.733118)
		(width 0.11684)
		(layer "In2.Cu")
		(net "SMB_USB_CPU0_HUB1_SDA")
	)
	(segment
		(start 260.1341 -88.165432)
		(end 258.511548 -86.54288)
		(width 0.11684)
		(layer "In2.Cu")
		(net "SMB_USB_CPU0_HUB1_SDA")
	)
	(segment
		(start 278.41702 -110.4646)
		(end 279.18918 -109.69244)
		(width 0.11684)
		(layer "In2.Cu")
		(net "SMB_USB_CPU0_HUB1_SDA")
	)
	(segment
		(start 197.23608 -87.637366)
		(end 194.304158 -87.637366)
		(width 0.11684)
		(layer "In2.Cu")
		(net "SMB_USB_CPU0_HUB1_SDA")
	)
	(segment
		(start 267.248894 -95.506794)
		(end 261.67715 -89.93505)
		(width 0.11684)
		(layer "In2.Cu")
		(net "SMB_USB_CPU0_HUB1_SDA")
	)
	(segment
		(start 260.1341 -88.96858)
		(end 260.1341 -88.165432)
		(width 0.11684)
		(layer "In2.Cu")
		(net "SMB_USB_CPU0_HUB1_SDA")
	)
	(segment
		(start 276.86 -121.285)
		(end 278.41702 -119.72798)
		(width 0.11684)
		(layer "In2.Cu")
		(net "SMB_USB_CPU0_HUB1_SDA")
	)
	(segment
		(start 159.318452 -86.418928)
		(end 114.450368 -86.418928)
		(width 0.11684)
		(layer "In2.Cu")
		(net "SMB_USB_CPU0_HUB1_SDA")
	)
	(segment
		(start 279.18918 -109.69244)
		(end 279.18918 -102.22484)
		(width 0.11684)
		(layer "In2.Cu")
		(net "SMB_USB_CPU0_HUB1_SDA")
	)
	(segment
		(start 275.83638 -98.87204)
		(end 275.83638 -98.381312)
		(width 0.11684)
		(layer "In2.Cu")
		(net "SMB_USB_CPU0_HUB1_SDA")
	)
	(segment
		(start 272.961862 -95.506794)
		(end 267.248894 -95.506794)
		(width 0.11684)
		(layer "In2.Cu")
		(net "SMB_USB_CPU0_HUB1_SDA")
	)
	(segment
		(start 243.680234 -90.733118)
		(end 214.267542 -90.733118)
		(width 0.11684)
		(layer "In2.Cu")
		(net "SMB_USB_CPU0_HUB1_SDA")
	)
	(segment
		(start 192.572132 -85.90534)
		(end 182.705756 -85.90534)
		(width 0.11684)
		(layer "In2.Cu")
		(net "SMB_USB_CPU0_HUB1_SDA")
	)
	(segment
		(start 111.63046 -83.59902)
		(end 111.63046 -80.01)
		(width 0.11684)
		(layer "In2.Cu")
		(net "SMB_USB_CPU0_HUB1_SDA")
	)
	(segment
		(start 261.67715 -89.93505)
		(end 261.10057 -89.93505)
		(width 0.11684)
		(layer "In2.Cu")
		(net "SMB_USB_CPU0_HUB1_SDA")
	)
	(segment
		(start 194.304158 -87.637366)
		(end 192.572132 -85.90534)
		(width 0.11684)
		(layer "In2.Cu")
		(net "SMB_USB_CPU0_HUB1_SDA")
	)
	(segment
		(start 182.705756 -85.90534)
		(end 181.546754 -84.746338)
		(width 0.11684)
		(layer "In2.Cu")
		(net "SMB_USB_CPU0_HUB1_SDA")
	)
	(segment
		(start 121.9708 -48.7426)
		(end 116.586254 -43.358054)
		(width 0.11684)
		(layer "In11.Cu")
		(net "SMB_USB_CPU0_HUB1_SDA")
	)
	(segment
		(start 116.586254 -43.358054)
		(end 114.299238 -43.358054)
		(width 0.11684)
		(layer "In11.Cu")
		(net "SMB_USB_CPU0_HUB1_SDA")
	)
	(segment
		(start 114.18062 -63.61938)
		(end 114.18062 -61.4553)
		(width 0.11684)
		(layer "In11.Cu")
		(net "SMB_USB_CPU0_HUB1_SDA")
	)
	(segment
		(start 109.2962 -55.650638)
		(end 109.2962 -57.29732)
		(width 0.11684)
		(layer "In11.Cu")
		(net "SMB_USB_CPU0_HUB1_SDA")
	)
	(segment
		(start 109.2962 -57.29732)
		(end 112.44834 -60.44946)
		(width 0.11684)
		(layer "In11.Cu")
		(net "SMB_USB_CPU0_HUB1_SDA")
	)
	(segment
		(start 113.23574 -64.56426)
		(end 114.18062 -63.61938)
		(width 0.11684)
		(layer "In11.Cu")
		(net "SMB_USB_CPU0_HUB1_SDA")
	)
	(segment
		(start 114.299238 -46.190662)
		(end 107.517946 -52.971954)
		(width 0.11684)
		(layer "In11.Cu")
		(net "SMB_USB_CPU0_HUB1_SDA")
	)
	(segment
		(start 107.517946 -52.971954)
		(end 107.517946 -53.872384)
		(width 0.11684)
		(layer "In11.Cu")
		(net "SMB_USB_CPU0_HUB1_SDA")
	)
	(segment
		(start 113.17478 -60.44946)
		(end 112.44834 -60.44946)
		(width 0.11684)
		(layer "In11.Cu")
		(net "SMB_USB_CPU0_HUB1_SDA")
	)
	(segment
		(start 113.23574 -78.40472)
		(end 113.23574 -64.56426)
		(width 0.11684)
		(layer "In11.Cu")
		(net "SMB_USB_CPU0_HUB1_SDA")
	)
	(segment
		(start 114.299238 -43.358054)
		(end 114.299238 -46.190662)
		(width 0.11684)
		(layer "In11.Cu")
		(net "SMB_USB_CPU0_HUB1_SDA")
	)
	(segment
		(start 107.517946 -53.872384)
		(end 109.2962 -55.650638)
		(width 0.11684)
		(layer "In11.Cu")
		(net "SMB_USB_CPU0_HUB1_SDA")
	)
	(segment
		(start 114.18062 -61.4553)
		(end 113.17478 -60.44946)
		(width 0.11684)
		(layer "In11.Cu")
		(net "SMB_USB_CPU0_HUB1_SDA")
	)
	(segment
		(start 112.09528 -79.54518)
		(end 113.23574 -78.40472)
		(width 0.11684)
		(layer "In11.Cu")
		(net "SMB_USB_CPU0_HUB1_SDA")
	)
	(segment
		(start 114.551968 -64.457072)
		(end 112.811052 -64.457072)
		(width 0.10668)
		(layer "F.Cu")
		(net "SMB_USB_CPU0_HUB1_SCL_R2")
	)
	(segment
		(start 112.811052 -64.457072)
		(end 111.94034 -63.58636)
		(width 0.10668)
		(layer "F.Cu")
		(net "SMB_USB_CPU0_HUB1_SCL_R2")
	)
	(via
		(at 111.94034 -63.58636)
		(size 0.508)
		(drill 0.254)
		(layers "F.Cu" "B.Cu")
		(net "SMB_USB_CPU0_HUB1_SCL_R2")
	)
	(segment
		(start 111.94034 -63.58636)
		(end 111.94034 -62.67196)
		(width 0.10668)
		(layer "B.Cu")
		(net "SMB_USB_CPU0_HUB1_SCL_R2")
	)
	(segment
		(start 112.19434 -62.41796)
		(end 111.17834 -62.41796)
		(width 0.10668)
		(layer "B.Cu")
		(net "SMB_USB_CPU0_HUB1_SCL_R2")
	)
	(segment
		(start 111.94034 -62.67196)
		(end 112.19434 -62.41796)
		(width 0.10668)
		(layer "B.Cu")
		(net "SMB_USB_CPU0_HUB1_SCL_R2")
	)
	(segment
		(start 282.383484 -120.74017)
		(end 281.17927 -120.74017)
		(width 0.10668)
		(layer "F.Cu")
		(net "SMB_USB_CPU0_HUB1_SCL_R")
	)
	(segment
		(start 280.35377 -119.91467)
		(end 281.17927 -120.74017)
		(width 0.10668)
		(layer "F.Cu")
		(net "SMB_USB_CPU0_HUB1_SCL_R")
	)
	(segment
		(start 284.127956 -120.182132)
		(end 282.941522 -120.182132)
		(width 0.10668)
		(layer "F.Cu")
		(net "SMB_USB_CPU0_HUB1_SCL_R")
	)
	(segment
		(start 277.752302 -119.91467)
		(end 280.35377 -119.91467)
		(width 0.10668)
		(layer "F.Cu")
		(net "SMB_USB_CPU0_HUB1_SCL_R")
	)
	(segment
		(start 282.941522 -120.182132)
		(end 282.383484 -120.74017)
		(width 0.10668)
		(layer "F.Cu")
		(net "SMB_USB_CPU0_HUB1_SCL_R")
	)
	(via
		(at 281.17927 -120.74017)
		(size 0.762)
		(drill 0.381)
		(layers "F.Cu" "B.Cu")
		(net "SMB_USB_CPU0_HUB1_SCL_R")
	)
	(segment
		(start 128.81229 -42.18051)
		(end 122.8852 -48.1076)
		(width 0.10668)
		(layer "F.Cu")
		(net "SMB_USB_CPU0_HUB1_SCL")
	)
	(segment
		(start 275.974302 -120.646698)
		(end 275.336 -121.285)
		(width 0.10668)
		(layer "F.Cu")
		(net "SMB_USB_CPU0_HUB1_SCL")
	)
	(segment
		(start 119.379238 -42.418762)
		(end 119.379238 -41.5798)
		(width 0.10668)
		(layer "F.Cu")
		(net "SMB_USB_CPU0_HUB1_SCL")
	)
	(segment
		(start 276.952202 -119.91467)
		(end 275.974302 -119.91467)
		(width 0.10668)
		(layer "F.Cu")
		(net "SMB_USB_CPU0_HUB1_SCL")
	)
	(segment
		(start 106.501946 -53.26253)
		(end 106.501946 -53.872384)
		(width 0.10668)
		(layer "F.Cu")
		(net "SMB_USB_CPU0_HUB1_SCL")
	)
	(segment
		(start 130.294126 -41.693338)
		(end 129.806954 -42.18051)
		(width 0.10668)
		(layer "F.Cu")
		(net "SMB_USB_CPU0_HUB1_SCL")
	)
	(segment
		(start 118.97106 -42.82694)
		(end 119.379238 -42.418762)
		(width 0.10668)
		(layer "F.Cu")
		(net "SMB_USB_CPU0_HUB1_SCL")
	)
	(segment
		(start 112.267238 -43.358054)
		(end 112.798352 -42.82694)
		(width 0.10668)
		(layer "F.Cu")
		(net "SMB_USB_CPU0_HUB1_SCL")
	)
	(segment
		(start 112.798352 -42.82694)
		(end 118.97106 -42.82694)
		(width 0.10668)
		(layer "F.Cu")
		(net "SMB_USB_CPU0_HUB1_SCL")
	)
	(segment
		(start 129.806954 -42.18051)
		(end 128.81229 -42.18051)
		(width 0.10668)
		(layer "F.Cu")
		(net "SMB_USB_CPU0_HUB1_SCL")
	)
	(segment
		(start 130.294126 -40.723312)
		(end 130.294126 -41.693338)
		(width 0.10668)
		(layer "F.Cu")
		(net "SMB_USB_CPU0_HUB1_SCL")
	)
	(segment
		(start 275.974302 -119.91467)
		(end 275.974302 -120.646698)
		(width 0.10668)
		(layer "F.Cu")
		(net "SMB_USB_CPU0_HUB1_SCL")
	)
	(via
		(at 112.267238 -43.358054)
		(size 0.508)
		(drill 0.254)
		(layers "F.Cu" "B.Cu")
		(net "SMB_USB_CPU0_HUB1_SCL")
	)
	(via
		(at 122.8852 -48.1076)
		(size 0.508)
		(drill 0.254)
		(layers "F.Cu" "B.Cu")
		(net "SMB_USB_CPU0_HUB1_SCL")
	)
	(via
		(at 111.10976 -60.26658)
		(size 0.508)
		(drill 0.254)
		(layers "F.Cu" "B.Cu")
		(net "SMB_USB_CPU0_HUB1_SCL")
	)
	(via
		(at 275.336 -121.285)
		(size 0.508)
		(drill 0.254)
		(layers "F.Cu" "B.Cu")
		(net "SMB_USB_CPU0_HUB1_SCL")
	)
	(via
		(at 112.09528 -78.02118)
		(size 0.508)
		(drill 0.254)
		(layers "F.Cu" "B.Cu")
		(net "SMB_USB_CPU0_HUB1_SCL")
	)
	(via
		(at 106.501946 -53.872384)
		(size 0.508)
		(drill 0.254)
		(layers "F.Cu" "B.Cu")
		(net "SMB_USB_CPU0_HUB1_SCL")
	)
	(segment
		(start 111.17834 -61.61786)
		(end 111.17834 -60.33516)
		(width 0.10668)
		(layer "B.Cu")
		(net "SMB_USB_CPU0_HUB1_SCL")
	)
	(segment
		(start 111.17834 -60.33516)
		(end 111.10976 -60.26658)
		(width 0.10668)
		(layer "B.Cu")
		(net "SMB_USB_CPU0_HUB1_SCL")
	)
	(segment
		(start 111.20882 -78.90764)
		(end 111.20882 -83.866228)
		(width 0.11684)
		(layer "In2.Cu")
		(net "SMB_USB_CPU0_HUB1_SCL")
	)
	(segment
		(start 159.50692 -86.891368)
		(end 161.21761 -85.180678)
		(width 0.11684)
		(layer "In2.Cu")
		(net "SMB_USB_CPU0_HUB1_SCL")
	)
	(segment
		(start 277.972012 -110.231428)
		(end 277.972012 -119.510048)
		(width 0.11684)
		(layer "In2.Cu")
		(net "SMB_USB_CPU0_HUB1_SCL")
	)
	(segment
		(start 270.250412 -97.986088)
		(end 274.216368 -97.986088)
		(width 0.11684)
		(layer "In2.Cu")
		(net "SMB_USB_CPU0_HUB1_SCL")
	)
	(segment
		(start 181.203346 -85.180678)
		(end 182.367428 -86.34476)
		(width 0.11684)
		(layer "In2.Cu")
		(net "SMB_USB_CPU0_HUB1_SCL")
	)
	(segment
		(start 274.216368 -97.986088)
		(end 278.72182 -102.49154)
		(width 0.11684)
		(layer "In2.Cu")
		(net "SMB_USB_CPU0_HUB1_SCL")
	)
	(segment
		(start 112.09528 -78.02118)
		(end 111.20882 -78.90764)
		(width 0.11684)
		(layer "In2.Cu")
		(net "SMB_USB_CPU0_HUB1_SCL")
	)
	(segment
		(start 211.38642 -88.457786)
		(end 214.126572 -91.197938)
		(width 0.11684)
		(layer "In2.Cu")
		(net "SMB_USB_CPU0_HUB1_SCL")
	)
	(segment
		(start 192.348612 -86.34476)
		(end 194.062858 -88.059006)
		(width 0.11684)
		(layer "In2.Cu")
		(net "SMB_USB_CPU0_HUB1_SCL")
	)
	(segment
		(start 247.979692 -87.04326)
		(end 258.36372 -87.04326)
		(width 0.11684)
		(layer "In2.Cu")
		(net "SMB_USB_CPU0_HUB1_SCL")
	)
	(segment
		(start 182.367428 -86.34476)
		(end 192.348612 -86.34476)
		(width 0.11684)
		(layer "In2.Cu")
		(net "SMB_USB_CPU0_HUB1_SCL")
	)
	(segment
		(start 214.126572 -91.197938)
		(end 243.825014 -91.197938)
		(width 0.11684)
		(layer "In2.Cu")
		(net "SMB_USB_CPU0_HUB1_SCL")
	)
	(segment
		(start 111.20882 -83.866228)
		(end 114.23396 -86.891368)
		(width 0.11684)
		(layer "In2.Cu")
		(net "SMB_USB_CPU0_HUB1_SCL")
	)
	(segment
		(start 278.72182 -102.49154)
		(end 278.72182 -109.48162)
		(width 0.11684)
		(layer "In2.Cu")
		(net "SMB_USB_CPU0_HUB1_SCL")
	)
	(segment
		(start 259.64388 -90.0557)
		(end 265.536934 -95.948754)
		(width 0.11684)
		(layer "In2.Cu")
		(net "SMB_USB_CPU0_HUB1_SCL")
	)
	(segment
		(start 265.536934 -95.948754)
		(end 268.213078 -95.948754)
		(width 0.11684)
		(layer "In2.Cu")
		(net "SMB_USB_CPU0_HUB1_SCL")
	)
	(segment
		(start 278.72182 -109.48162)
		(end 277.972012 -110.231428)
		(width 0.11684)
		(layer "In2.Cu")
		(net "SMB_USB_CPU0_HUB1_SCL")
	)
	(segment
		(start 197.341744 -88.457786)
		(end 211.38642 -88.457786)
		(width 0.11684)
		(layer "In2.Cu")
		(net "SMB_USB_CPU0_HUB1_SCL")
	)
	(segment
		(start 114.23396 -86.891368)
		(end 159.50692 -86.891368)
		(width 0.11684)
		(layer "In2.Cu")
		(net "SMB_USB_CPU0_HUB1_SCL")
	)
	(segment
		(start 277.972012 -119.510048)
		(end 276.7711 -120.71096)
		(width 0.11684)
		(layer "In2.Cu")
		(net "SMB_USB_CPU0_HUB1_SCL")
	)
	(segment
		(start 196.942964 -88.059006)
		(end 197.341744 -88.457786)
		(width 0.11684)
		(layer "In2.Cu")
		(net "SMB_USB_CPU0_HUB1_SCL")
	)
	(segment
		(start 194.062858 -88.059006)
		(end 196.942964 -88.059006)
		(width 0.11684)
		(layer "In2.Cu")
		(net "SMB_USB_CPU0_HUB1_SCL")
	)
	(segment
		(start 258.36372 -87.04326)
		(end 259.64388 -88.32342)
		(width 0.11684)
		(layer "In2.Cu")
		(net "SMB_USB_CPU0_HUB1_SCL")
	)
	(segment
		(start 276.7711 -120.71096)
		(end 275.91004 -120.71096)
		(width 0.11684)
		(layer "In2.Cu")
		(net "SMB_USB_CPU0_HUB1_SCL")
	)
	(segment
		(start 268.213078 -95.948754)
		(end 270.250412 -97.986088)
		(width 0.11684)
		(layer "In2.Cu")
		(net "SMB_USB_CPU0_HUB1_SCL")
	)
	(segment
		(start 275.91004 -120.71096)
		(end 275.336 -121.285)
		(width 0.11684)
		(layer "In2.Cu")
		(net "SMB_USB_CPU0_HUB1_SCL")
	)
	(segment
		(start 161.21761 -85.180678)
		(end 181.203346 -85.180678)
		(width 0.11684)
		(layer "In2.Cu")
		(net "SMB_USB_CPU0_HUB1_SCL")
	)
	(segment
		(start 243.825014 -91.197938)
		(end 247.979692 -87.04326)
		(width 0.11684)
		(layer "In2.Cu")
		(net "SMB_USB_CPU0_HUB1_SCL")
	)
	(segment
		(start 259.64388 -88.32342)
		(end 259.64388 -90.0557)
		(width 0.11684)
		(layer "In2.Cu")
		(net "SMB_USB_CPU0_HUB1_SCL")
	)
	(segment
		(start 106.501946 -52.850034)
		(end 106.501946 -53.872384)
		(width 0.11684)
		(layer "In11.Cu")
		(net "SMB_USB_CPU0_HUB1_SCL")
	)
	(segment
		(start 112.267238 -47.084742)
		(end 106.501946 -52.850034)
		(width 0.11684)
		(layer "In11.Cu")
		(net "SMB_USB_CPU0_HUB1_SCL")
	)
	(segment
		(start 111.17834 -64.21882)
		(end 112.69472 -65.7352)
		(width 0.11684)
		(layer "In11.Cu")
		(net "SMB_USB_CPU0_HUB1_SCL")
	)
	(segment
		(start 112.69472 -65.7352)
		(end 112.69472 -77.42174)
		(width 0.11684)
		(layer "In11.Cu")
		(net "SMB_USB_CPU0_HUB1_SCL")
	)
	(segment
		(start 106.501946 -53.872384)
		(end 106.501946 -54.868826)
		(width 0.11684)
		(layer "In11.Cu")
		(net "SMB_USB_CPU0_HUB1_SCL")
	)
	(segment
		(start 106.501946 -54.868826)
		(end 108.38434 -56.75122)
		(width 0.11684)
		(layer "In11.Cu")
		(net "SMB_USB_CPU0_HUB1_SCL")
	)
	(segment
		(start 117.60454 -42.82694)
		(end 112.798352 -42.82694)
		(width 0.11684)
		(layer "In11.Cu")
		(net "SMB_USB_CPU0_HUB1_SCL")
	)
	(segment
		(start 112.798352 -42.82694)
		(end 112.267238 -43.358054)
		(width 0.11684)
		(layer "In11.Cu")
		(net "SMB_USB_CPU0_HUB1_SCL")
	)
	(segment
		(start 108.38434 -57.65546)
		(end 110.99546 -60.26658)
		(width 0.11684)
		(layer "In11.Cu")
		(net "SMB_USB_CPU0_HUB1_SCL")
	)
	(segment
		(start 111.10976 -60.26658)
		(end 111.17834 -60.33516)
		(width 0.11684)
		(layer "In11.Cu")
		(net "SMB_USB_CPU0_HUB1_SCL")
	)
	(segment
		(start 110.99546 -60.26658)
		(end 111.10976 -60.26658)
		(width 0.11684)
		(layer "In11.Cu")
		(net "SMB_USB_CPU0_HUB1_SCL")
	)
	(segment
		(start 108.38434 -56.75122)
		(end 108.38434 -57.65546)
		(width 0.11684)
		(layer "In11.Cu")
		(net "SMB_USB_CPU0_HUB1_SCL")
	)
	(segment
		(start 112.267238 -43.358054)
		(end 112.267238 -47.084742)
		(width 0.11684)
		(layer "In11.Cu")
		(net "SMB_USB_CPU0_HUB1_SCL")
	)
	(segment
		(start 122.8852 -48.1076)
		(end 117.60454 -42.82694)
		(width 0.11684)
		(layer "In11.Cu")
		(net "SMB_USB_CPU0_HUB1_SCL")
	)
	(segment
		(start 112.69472 -77.42174)
		(end 112.09528 -78.02118)
		(width 0.11684)
		(layer "In11.Cu")
		(net "SMB_USB_CPU0_HUB1_SCL")
	)
	(segment
		(start 111.17834 -60.33516)
		(end 111.17834 -64.21882)
		(width 0.11684)
		(layer "In11.Cu")
		(net "SMB_USB_CPU0_HUB1_SCL")
	)
	(segment
		(start 268.469364 -116.903754)
		(end 268.44117 -116.931948)
		(width 0.10668)
		(layer "F.Cu")
		(net "SMB_P12V_HSC_SDA_R")
	)
	(segment
		(start 272.375122 -116.903754)
		(end 269.320264 -116.903754)
		(width 0.10668)
		(layer "F.Cu")
		(net "SMB_P12V_HSC_SDA_R")
	)
	(segment
		(start 269.320264 -116.903754)
		(end 268.469364 -116.903754)
		(width 0.10668)
		(layer "F.Cu")
		(net "SMB_P12V_HSC_SDA_R")
	)
	(segment
		(start 272.95729 -116.321586)
		(end 272.375122 -116.903754)
		(width 0.10668)
		(layer "F.Cu")
		(net "SMB_P12V_HSC_SDA_R")
	)
	(segment
		(start 268.44117 -116.931948)
		(end 266.975082 -116.931948)
		(width 0.10668)
		(layer "F.Cu")
		(net "SMB_P12V_HSC_SDA_R")
	)
	(via
		(at 269.320264 -116.903754)
		(size 0.762)
		(drill 0.381)
		(layers "F.Cu" "B.Cu")
		(net "SMB_P12V_HSC_SDA_R")
	)
	(segment
		(start 269.988538 -117.48135)
		(end 270.692626 -117.48135)
		(width 0.10668)
		(layer "F.Cu")
		(net "SMB_P12V_HSC_SCL_R")
	)
	(segment
		(start 268.276324 -117.581934)
		(end 268.788642 -118.094252)
		(width 0.10668)
		(layer "F.Cu")
		(net "SMB_P12V_HSC_SCL_R")
	)
	(segment
		(start 266.975082 -117.581934)
		(end 268.276324 -117.581934)
		(width 0.10668)
		(layer "F.Cu")
		(net "SMB_P12V_HSC_SCL_R")
	)
	(segment
		(start 268.788642 -118.094252)
		(end 269.375636 -118.094252)
		(width 0.10668)
		(layer "F.Cu")
		(net "SMB_P12V_HSC_SCL_R")
	)
	(segment
		(start 269.375636 -118.094252)
		(end 269.988538 -117.48135)
		(width 0.10668)
		(layer "F.Cu")
		(net "SMB_P12V_HSC_SCL_R")
	)
	(via
		(at 268.788642 -118.094252)
		(size 0.762)
		(drill 0.381)
		(layers "F.Cu" "B.Cu")
		(net "SMB_P12V_HSC_SCL_R")
	)
	(segment
		(start 125.033278 -49.153064)
		(end 125.033278 -50.169064)
		(width 0.10668)
		(layer "F.Cu")
		(net "RST_USB_CPU0_HUB1_R_N")
	)
	(segment
		(start 125.033278 -50.169064)
		(end 125.033278 -51.185064)
		(width 0.10668)
		(layer "F.Cu")
		(net "RST_USB_CPU0_HUB1_R_N")
	)
	(segment
		(start 127.559816 -44.946824)
		(end 127.559816 -45.487336)
		(width 0.10668)
		(layer "F.Cu")
		(net "RST_USB_CPU0_HUB1_R_N")
	)
	(segment
		(start 130.694176 -40.723312)
		(end 130.694176 -41.812464)
		(width 0.10668)
		(layer "F.Cu")
		(net "RST_USB_CPU0_HUB1_R_N")
	)
	(segment
		(start 130.694176 -41.812464)
		(end 127.559816 -44.946824)
		(width 0.10668)
		(layer "F.Cu")
		(net "RST_USB_CPU0_HUB1_R_N")
	)
	(segment
		(start 125.033278 -49.153064)
		(end 125.033278 -48.137064)
		(width 0.10668)
		(layer "F.Cu")
		(net "RST_USB_CPU0_HUB1_R_N")
	)
	(segment
		(start 127.559816 -45.487336)
		(end 126.493524 -45.487336)
		(width 0.10668)
		(layer "F.Cu")
		(net "RST_USB_CPU0_HUB1_R_N")
	)
	(segment
		(start 125.033278 -46.947582)
		(end 125.033278 -48.137064)
		(width 0.10668)
		(layer "F.Cu")
		(net "RST_USB_CPU0_HUB1_R_N")
	)
	(segment
		(start 126.493524 -45.487336)
		(end 125.033278 -46.947582)
		(width 0.10668)
		(layer "F.Cu")
		(net "RST_USB_CPU0_HUB1_R_N")
	)
	(via
		(at 127.559816 -45.487336)
		(size 0.762)
		(drill 0.381)
		(layers "F.Cu" "B.Cu")
		(net "RST_USB_CPU0_HUB1_R_N")
	)
	(segment
		(start 192.322196 -113.05286)
		(end 192.712086 -112.66297)
		(width 0.10668)
		(layer "F.Cu")
		(net "PWRGD_P1V2_AUX_R")
	)
	(via
		(at 183.933338 -87.703914)
		(size 0.508)
		(drill 0.254)
		(layers "F.Cu" "B.Cu")
		(net "PWRGD_P1V2_AUX_R")
	)
	(via
		(at 198.342758 -109.567472)
		(size 0.508)
		(drill 0.254)
		(layers "F.Cu" "B.Cu")
		(net "PWRGD_P1V2_AUX_R")
	)
	(via
		(at 308.379876 -73.138792)
		(size 0.762)
		(drill 0.254)
		(layers "F.Cu" "B.Cu")
		(net "PWRGD_P1V2_AUX_R")
	)
	(via
		(at 192.712086 -112.66297)
		(size 0.4572)
		(drill 0.254)
		(layers "F.Cu" "B.Cu")
		(net "PWRGD_P1V2_AUX_R")
	)
	(via
		(at 309.70855 -111.290354)
		(size 0.508)
		(drill 0.254)
		(layers "F.Cu" "B.Cu")
		(net "PWRGD_P1V2_AUX_R")
	)
	(segment
		(start 197.017386 -110.53318)
		(end 196.68617 -110.864396)
		(width 0.10668)
		(layer "B.Cu")
		(net "PWRGD_P1V2_AUX_R")
	)
	(segment
		(start 124.859542 -71.093838)
		(end 125.525784 -70.427596)
		(width 0.10668)
		(layer "B.Cu")
		(net "PWRGD_P1V2_AUX_R")
	)
	(segment
		(start 158.52648 -83.7565)
		(end 158.52648 -84.68614)
		(width 0.10668)
		(layer "B.Cu")
		(net "PWRGD_P1V2_AUX_R")
	)
	(segment
		(start 193.17716 -112.66297)
		(end 192.712086 -112.66297)
		(width 0.10668)
		(layer "B.Cu")
		(net "PWRGD_P1V2_AUX_R")
	)
	(segment
		(start 198.342758 -109.567472)
		(end 197.37705 -110.53318)
		(width 0.10668)
		(layer "B.Cu")
		(net "PWRGD_P1V2_AUX_R")
	)
	(segment
		(start 159.05226 -85.21192)
		(end 168.6687 -85.21192)
		(width 0.10668)
		(layer "B.Cu")
		(net "PWRGD_P1V2_AUX_R")
	)
	(segment
		(start 196.68617 -110.864396)
		(end 194.975734 -110.864396)
		(width 0.10668)
		(layer "B.Cu")
		(net "PWRGD_P1V2_AUX_R")
	)
	(segment
		(start 134.138416 -70.427596)
		(end 135.32612 -71.6153)
		(width 0.10668)
		(layer "B.Cu")
		(net "PWRGD_P1V2_AUX_R")
	)
	(segment
		(start 197.37705 -110.53318)
		(end 197.017386 -110.53318)
		(width 0.10668)
		(layer "B.Cu")
		(net "PWRGD_P1V2_AUX_R")
	)
	(segment
		(start 308.62143 -73.534778)
		(end 309.030624 -73.534778)
		(width 0.10668)
		(layer "B.Cu")
		(net "PWRGD_P1V2_AUX_R")
	)
	(segment
		(start 136.20242 -83.69046)
		(end 156.47162 -83.69046)
		(width 0.10668)
		(layer "B.Cu")
		(net "PWRGD_P1V2_AUX_R")
	)
	(segment
		(start 181.78907 -84.2772)
		(end 183.933338 -86.421468)
		(width 0.10668)
		(layer "B.Cu")
		(net "PWRGD_P1V2_AUX_R")
	)
	(segment
		(start 156.47162 -83.69046)
		(end 156.89834 -83.26374)
		(width 0.10668)
		(layer "B.Cu")
		(net "PWRGD_P1V2_AUX_R")
	)
	(segment
		(start 135.32612 -82.81416)
		(end 136.20242 -83.69046)
		(width 0.10668)
		(layer "B.Cu")
		(net "PWRGD_P1V2_AUX_R")
	)
	(segment
		(start 169.60342 -84.2772)
		(end 181.78907 -84.2772)
		(width 0.10668)
		(layer "B.Cu")
		(net "PWRGD_P1V2_AUX_R")
	)
	(segment
		(start 135.32612 -71.6153)
		(end 135.32612 -82.81416)
		(width 0.10668)
		(layer "B.Cu")
		(net "PWRGD_P1V2_AUX_R")
	)
	(segment
		(start 308.379876 -73.138792)
		(end 308.379876 -73.293224)
		(width 0.10668)
		(layer "B.Cu")
		(net "PWRGD_P1V2_AUX_R")
	)
	(segment
		(start 158.03372 -83.26374)
		(end 158.52648 -83.7565)
		(width 0.10668)
		(layer "B.Cu")
		(net "PWRGD_P1V2_AUX_R")
	)
	(segment
		(start 308.379876 -73.293224)
		(end 308.62143 -73.534778)
		(width 0.10668)
		(layer "B.Cu")
		(net "PWRGD_P1V2_AUX_R")
	)
	(segment
		(start 194.975734 -110.864396)
		(end 193.17716 -112.66297)
		(width 0.10668)
		(layer "B.Cu")
		(net "PWRGD_P1V2_AUX_R")
	)
	(segment
		(start 158.52648 -84.68614)
		(end 159.05226 -85.21192)
		(width 0.10668)
		(layer "B.Cu")
		(net "PWRGD_P1V2_AUX_R")
	)
	(segment
		(start 124.859542 -72.616822)
		(end 124.859542 -71.093838)
		(width 0.10668)
		(layer "B.Cu")
		(net "PWRGD_P1V2_AUX_R")
	)
	(segment
		(start 183.933338 -86.421468)
		(end 183.933338 -87.703914)
		(width 0.10668)
		(layer "B.Cu")
		(net "PWRGD_P1V2_AUX_R")
	)
	(segment
		(start 168.6687 -85.21192)
		(end 169.60342 -84.2772)
		(width 0.10668)
		(layer "B.Cu")
		(net "PWRGD_P1V2_AUX_R")
	)
	(segment
		(start 125.525784 -70.427596)
		(end 134.138416 -70.427596)
		(width 0.10668)
		(layer "B.Cu")
		(net "PWRGD_P1V2_AUX_R")
	)
	(segment
		(start 156.89834 -83.26374)
		(end 158.03372 -83.26374)
		(width 0.10668)
		(layer "B.Cu")
		(net "PWRGD_P1V2_AUX_R")
	)
	(segment
		(start 308.379876 -73.138792)
		(end 309.26024 -74.019156)
		(width 0.11684)
		(layer "In4.Cu")
		(net "PWRGD_P1V2_AUX_R")
	)
	(segment
		(start 310.578754 -110.42015)
		(end 309.70855 -111.290354)
		(width 0.11684)
		(layer "In4.Cu")
		(net "PWRGD_P1V2_AUX_R")
	)
	(segment
		(start 309.26024 -74.019156)
		(end 309.26024 -101.487224)
		(width 0.11684)
		(layer "In4.Cu")
		(net "PWRGD_P1V2_AUX_R")
	)
	(segment
		(start 310.578754 -102.805738)
		(end 310.578754 -110.42015)
		(width 0.11684)
		(layer "In4.Cu")
		(net "PWRGD_P1V2_AUX_R")
	)
	(segment
		(start 309.26024 -101.487224)
		(end 310.578754 -102.805738)
		(width 0.11684)
		(layer "In4.Cu")
		(net "PWRGD_P1V2_AUX_R")
	)
	(segment
		(start 198.342758 -109.302804)
		(end 198.635366 -109.010196)
		(width 0.11684)
		(layer "In6.Cu")
		(net "PWRGD_P1V2_AUX_R")
	)
	(segment
		(start 297.594528 -110.279688)
		(end 298.032678 -109.841538)
		(width 0.11684)
		(layer "In6.Cu")
		(net "PWRGD_P1V2_AUX_R")
	)
	(segment
		(start 308.697884 -110.279688)
		(end 309.70855 -111.290354)
		(width 0.11684)
		(layer "In6.Cu")
		(net "PWRGD_P1V2_AUX_R")
	)
	(segment
		(start 207.451452 -109.02442)
		(end 211.263992 -109.02442)
		(width 0.11684)
		(layer "In6.Cu")
		(net "PWRGD_P1V2_AUX_R")
	)
	(segment
		(start 298.032678 -109.841538)
		(end 300.102524 -109.841538)
		(width 0.11684)
		(layer "In6.Cu")
		(net "PWRGD_P1V2_AUX_R")
	)
	(segment
		(start 226.240848 -110.568994)
		(end 253.982474 -110.568994)
		(width 0.11684)
		(layer "In6.Cu")
		(net "PWRGD_P1V2_AUX_R")
	)
	(segment
		(start 273.78152 -111.19612)
		(end 274.697952 -110.279688)
		(width 0.11684)
		(layer "In6.Cu")
		(net "PWRGD_P1V2_AUX_R")
	)
	(segment
		(start 211.263992 -109.02442)
		(end 212.808566 -110.568994)
		(width 0.11684)
		(layer "In6.Cu")
		(net "PWRGD_P1V2_AUX_R")
	)
	(segment
		(start 225.302572 -111.50727)
		(end 226.240848 -110.568994)
		(width 0.11684)
		(layer "In6.Cu")
		(net "PWRGD_P1V2_AUX_R")
	)
	(segment
		(start 217.602816 -111.50727)
		(end 225.302572 -111.50727)
		(width 0.11684)
		(layer "In6.Cu")
		(net "PWRGD_P1V2_AUX_R")
	)
	(segment
		(start 253.982474 -110.568994)
		(end 254.6096 -111.19612)
		(width 0.11684)
		(layer "In6.Cu")
		(net "PWRGD_P1V2_AUX_R")
	)
	(segment
		(start 198.635366 -109.010196)
		(end 207.437228 -109.010196)
		(width 0.11684)
		(layer "In6.Cu")
		(net "PWRGD_P1V2_AUX_R")
	)
	(segment
		(start 274.697952 -110.279688)
		(end 297.594528 -110.279688)
		(width 0.11684)
		(layer "In6.Cu")
		(net "PWRGD_P1V2_AUX_R")
	)
	(segment
		(start 207.437228 -109.010196)
		(end 207.451452 -109.02442)
		(width 0.11684)
		(layer "In6.Cu")
		(net "PWRGD_P1V2_AUX_R")
	)
	(segment
		(start 300.102524 -109.841538)
		(end 300.540674 -110.279688)
		(width 0.11684)
		(layer "In6.Cu")
		(net "PWRGD_P1V2_AUX_R")
	)
	(segment
		(start 300.540674 -110.279688)
		(end 308.697884 -110.279688)
		(width 0.11684)
		(layer "In6.Cu")
		(net "PWRGD_P1V2_AUX_R")
	)
	(segment
		(start 198.342758 -109.567472)
		(end 198.342758 -109.302804)
		(width 0.11684)
		(layer "In6.Cu")
		(net "PWRGD_P1V2_AUX_R")
	)
	(segment
		(start 212.808566 -110.568994)
		(end 216.66454 -110.568994)
		(width 0.11684)
		(layer "In6.Cu")
		(net "PWRGD_P1V2_AUX_R")
	)
	(segment
		(start 216.66454 -110.568994)
		(end 217.602816 -111.50727)
		(width 0.11684)
		(layer "In6.Cu")
		(net "PWRGD_P1V2_AUX_R")
	)
	(segment
		(start 254.6096 -111.19612)
		(end 273.78152 -111.19612)
		(width 0.11684)
		(layer "In6.Cu")
		(net "PWRGD_P1V2_AUX_R")
	)
	(segment
		(start 191.0969 -95.055944)
		(end 191.0969 -96.804988)
		(width 0.11684)
		(layer "In11.Cu")
		(net "PWRGD_P1V2_AUX_R")
	)
	(segment
		(start 191.831722 -94.321122)
		(end 191.0969 -95.055944)
		(width 0.11684)
		(layer "In11.Cu")
		(net "PWRGD_P1V2_AUX_R")
	)
	(segment
		(start 192.405 -99.69246)
		(end 191.6557 -100.44176)
		(width 0.11684)
		(layer "In11.Cu")
		(net "PWRGD_P1V2_AUX_R")
	)
	(segment
		(start 184.48147 -89.058242)
		(end 185.749438 -89.058242)
		(width 0.11684)
		(layer "In11.Cu")
		(net "PWRGD_P1V2_AUX_R")
	)
	(segment
		(start 192.117218 -94.321122)
		(end 191.831722 -94.321122)
		(width 0.11684)
		(layer "In11.Cu")
		(net "PWRGD_P1V2_AUX_R")
	)
	(segment
		(start 191.6557 -100.44176)
		(end 191.6557 -104.44988)
		(width 0.11684)
		(layer "In11.Cu")
		(net "PWRGD_P1V2_AUX_R")
	)
	(segment
		(start 183.933338 -87.703914)
		(end 183.933338 -88.51011)
		(width 0.11684)
		(layer "In11.Cu")
		(net "PWRGD_P1V2_AUX_R")
	)
	(segment
		(start 191.61252 -92.53982)
		(end 192.3923 -93.3196)
		(width 0.11684)
		(layer "In11.Cu")
		(net "PWRGD_P1V2_AUX_R")
	)
	(segment
		(start 191.0969 -96.804988)
		(end 192.405 -98.113088)
		(width 0.11684)
		(layer "In11.Cu")
		(net "PWRGD_P1V2_AUX_R")
	)
	(segment
		(start 192.3923 -93.3196)
		(end 192.3923 -94.04604)
		(width 0.11684)
		(layer "In11.Cu")
		(net "PWRGD_P1V2_AUX_R")
	)
	(segment
		(start 191.6557 -104.44988)
		(end 192.312036 -105.106216)
		(width 0.11684)
		(layer "In11.Cu")
		(net "PWRGD_P1V2_AUX_R")
	)
	(segment
		(start 189.231016 -92.53982)
		(end 191.61252 -92.53982)
		(width 0.11684)
		(layer "In11.Cu")
		(net "PWRGD_P1V2_AUX_R")
	)
	(segment
		(start 192.405 -98.113088)
		(end 192.405 -99.69246)
		(width 0.11684)
		(layer "In11.Cu")
		(net "PWRGD_P1V2_AUX_R")
	)
	(segment
		(start 192.312036 -112.26292)
		(end 192.712086 -112.66297)
		(width 0.11684)
		(layer "In11.Cu")
		(net "PWRGD_P1V2_AUX_R")
	)
	(segment
		(start 192.312036 -105.106216)
		(end 192.312036 -112.26292)
		(width 0.11684)
		(layer "In11.Cu")
		(net "PWRGD_P1V2_AUX_R")
	)
	(segment
		(start 192.3923 -94.04604)
		(end 192.117218 -94.321122)
		(width 0.11684)
		(layer "In11.Cu")
		(net "PWRGD_P1V2_AUX_R")
	)
	(segment
		(start 183.933338 -88.51011)
		(end 184.48147 -89.058242)
		(width 0.11684)
		(layer "In11.Cu")
		(net "PWRGD_P1V2_AUX_R")
	)
	(segment
		(start 185.749438 -89.058242)
		(end 189.231016 -92.53982)
		(width 0.11684)
		(layer "In11.Cu")
		(net "PWRGD_P1V2_AUX_R")
	)
	(segment
		(start 123.725178 -73.541636)
		(end 123.434348 -73.832466)
		(width 0.10668)
		(layer "F.Cu")
		(net "PWRGD_P1V2_AUX")
	)
	(segment
		(start 123.053602 -74.295508)
		(end 123.053602 -75.072494)
		(width 0.10668)
		(layer "F.Cu")
		(net "PWRGD_P1V2_AUX")
	)
	(segment
		(start 123.053602 -75.072494)
		(end 122.624342 -75.501754)
		(width 0.10668)
		(layer "F.Cu")
		(net "PWRGD_P1V2_AUX")
	)
	(segment
		(start 123.725178 -73.229216)
		(end 123.725178 -73.541636)
		(width 0.10668)
		(layer "F.Cu")
		(net "PWRGD_P1V2_AUX")
	)
	(segment
		(start 123.434348 -73.832466)
		(end 123.434348 -73.914762)
		(width 0.10668)
		(layer "F.Cu")
		(net "PWRGD_P1V2_AUX")
	)
	(segment
		(start 122.624342 -75.501754)
		(end 122.213624 -75.501754)
		(width 0.10668)
		(layer "F.Cu")
		(net "PWRGD_P1V2_AUX")
	)
	(segment
		(start 123.434348 -73.914762)
		(end 123.053602 -74.295508)
		(width 0.10668)
		(layer "F.Cu")
		(net "PWRGD_P1V2_AUX")
	)
	(via
		(at 124.264928 -73.766172)
		(size 0.6604)
		(drill 0.3302)
		(layers "F.Cu" "B.Cu")
		(net "PWRGD_P1V2_AUX")
	)
	(via
		(at 123.434348 -73.832466)
		(size 0.508)
		(drill 0.254)
		(layers "F.Cu" "B.Cu")
		(net "PWRGD_P1V2_AUX")
	)
	(segment
		(start 124.264928 -72.822308)
		(end 124.059442 -72.616822)
		(width 0.10668)
		(layer "B.Cu")
		(net "PWRGD_P1V2_AUX")
	)
	(segment
		(start 123.434348 -73.832466)
		(end 124.198634 -73.832466)
		(width 0.10668)
		(layer "B.Cu")
		(net "PWRGD_P1V2_AUX")
	)
	(segment
		(start 124.264928 -73.766172)
		(end 124.264928 -72.822308)
		(width 0.10668)
		(layer "B.Cu")
		(net "PWRGD_P1V2_AUX")
	)
	(segment
		(start 124.198634 -73.832466)
		(end 124.264928 -73.766172)
		(width 0.10668)
		(layer "B.Cu")
		(net "PWRGD_P1V2_AUX")
	)
	(segment
		(start 137.571734 -48.325024)
		(end 136.352534 -48.325024)
		(width 0.10668)
		(layer "F.Cu")
		(net "PU_CPU0_USB_HUB_RESERVED2")
	)
	(segment
		(start 134.294118 -40.723312)
		(end 134.294118 -46.266608)
		(width 0.10668)
		(layer "F.Cu")
		(net "PU_CPU0_USB_HUB_RESERVED2")
	)
	(segment
		(start 134.294118 -46.266608)
		(end 136.352534 -48.325024)
		(width 0.10668)
		(layer "F.Cu")
		(net "PU_CPU0_USB_HUB_RESERVED2")
	)
	(via
		(at 136.352534 -48.325024)
		(size 0.762)
		(drill 0.381)
		(layers "F.Cu" "B.Cu")
		(net "PU_CPU0_USB_HUB_RESERVED2")
	)
	(segment
		(start 139.749784 -46.908974)
		(end 138.530584 -46.908974)
		(width 0.10668)
		(layer "F.Cu")
		(net "PU_CPU0_USB_HUB_RESERVED1")
	)
	(segment
		(start 134.694168 -44.112688)
		(end 137.490454 -46.908974)
		(width 0.10668)
		(layer "F.Cu")
		(net "PU_CPU0_USB_HUB_RESERVED1")
	)
	(segment
		(start 134.694168 -40.723312)
		(end 134.694168 -44.112688)
		(width 0.10668)
		(layer "F.Cu")
		(net "PU_CPU0_USB_HUB_RESERVED1")
	)
	(segment
		(start 137.490454 -46.908974)
		(end 138.530584 -46.908974)
		(width 0.10668)
		(layer "F.Cu")
		(net "PU_CPU0_USB_HUB_RESERVED1")
	)
	(via
		(at 138.530584 -46.908974)
		(size 0.762)
		(drill 0.381)
		(layers "F.Cu" "B.Cu")
		(net "PU_CPU0_USB_HUB_RESERVED1")
	)
	(segment
		(start 131.317746 -42.245534)
		(end 131.317746 -44.269406)
		(width 0.10668)
		(layer "F.Cu")
		(net "PU_CPU0_USB_HUB_PWR_EN")
	)
	(segment
		(start 131.494276 -42.069004)
		(end 131.317746 -42.245534)
		(width 0.10668)
		(layer "F.Cu")
		(net "PU_CPU0_USB_HUB_PWR_EN")
	)
	(segment
		(start 129.306828 -46.280324)
		(end 129.306828 -47.121064)
		(width 0.10668)
		(layer "F.Cu")
		(net "PU_CPU0_USB_HUB_PWR_EN")
	)
	(segment
		(start 130.099816 -45.487336)
		(end 129.306828 -46.280324)
		(width 0.10668)
		(layer "F.Cu")
		(net "PU_CPU0_USB_HUB_PWR_EN")
	)
	(segment
		(start 131.317746 -44.269406)
		(end 130.099816 -45.487336)
		(width 0.10668)
		(layer "F.Cu")
		(net "PU_CPU0_USB_HUB_PWR_EN")
	)
	(segment
		(start 131.494276 -40.723312)
		(end 131.494276 -42.069004)
		(width 0.10668)
		(layer "F.Cu")
		(net "PU_CPU0_USB_HUB_PWR_EN")
	)
	(via
		(at 130.099816 -45.487336)
		(size 0.762)
		(drill 0.381)
		(layers "F.Cu" "B.Cu")
		(net "PU_CPU0_USB_HUB_PWR_EN")
	)
	(segment
		(start 130.92938 -42.113454)
		(end 130.92938 -43.387772)
		(width 0.10668)
		(layer "F.Cu")
		(net "PU_CPU0_USB_HUB_OVRCURR")
	)
	(segment
		(start 131.094226 -41.948608)
		(end 130.92938 -42.113454)
		(width 0.10668)
		(layer "F.Cu")
		(net "PU_CPU0_USB_HUB_OVRCURR")
	)
	(segment
		(start 130.92938 -43.387772)
		(end 128.829816 -45.487336)
		(width 0.10668)
		(layer "F.Cu")
		(net "PU_CPU0_USB_HUB_OVRCURR")
	)
	(segment
		(start 128.426464 -45.487336)
		(end 127.204978 -46.708822)
		(width 0.10668)
		(layer "F.Cu")
		(net "PU_CPU0_USB_HUB_OVRCURR")
	)
	(segment
		(start 128.829816 -45.487336)
		(end 128.426464 -45.487336)
		(width 0.10668)
		(layer "F.Cu")
		(net "PU_CPU0_USB_HUB_OVRCURR")
	)
	(segment
		(start 131.094226 -40.723312)
		(end 131.094226 -41.948608)
		(width 0.10668)
		(layer "F.Cu")
		(net "PU_CPU0_USB_HUB_OVRCURR")
	)
	(segment
		(start 127.204978 -46.708822)
		(end 127.204978 -47.121064)
		(width 0.10668)
		(layer "F.Cu")
		(net "PU_CPU0_USB_HUB_OVRCURR")
	)
	(via
		(at 128.829816 -45.487336)
		(size 0.762)
		(drill 0.381)
		(layers "F.Cu" "B.Cu")
		(net "PU_CPU0_USB_HUB_OVRCURR")
	)
	(segment
		(start 114.551968 -65.727072)
		(end 112.160812 -65.727072)
		(width 0.10668)
		(layer "F.Cu")
		(net "PD_USB_CPU0_WP")
	)
	(segment
		(start 112.160812 -65.727072)
		(end 110.67034 -64.2366)
		(width 0.10668)
		(layer "F.Cu")
		(net "PD_USB_CPU0_WP")
	)
	(segment
		(start 110.67034 -64.2366)
		(end 110.67034 -63.58636)
		(width 0.10668)
		(layer "F.Cu")
		(net "PD_USB_CPU0_WP")
	)
	(via
		(at 110.67034 -63.58636)
		(size 0.508)
		(drill 0.254)
		(layers "F.Cu" "B.Cu")
		(net "PD_USB_CPU0_WP")
	)
	(segment
		(start 110.67034 -62.92596)
		(end 110.67034 -63.58636)
		(width 0.10668)
		(layer "B.Cu")
		(net "PD_USB_CPU0_WP")
	)
	(segment
		(start 110.16234 -62.41796)
		(end 110.67034 -62.92596)
		(width 0.10668)
		(layer "B.Cu")
		(net "PD_USB_CPU0_WP")
	)
	(segment
		(start 137.552938 -34.873438)
		(end 137.58545 -34.840926)
		(width 0.1778)
		(layer "F.Cu")
		(net "P3V3_AUX_CPU0_USB_AVDD33")
	)
	(segment
		(start 136.54405 -34.873438)
		(end 137.552938 -34.873438)
		(width 0.1778)
		(layer "F.Cu")
		(net "P3V3_AUX_CPU0_USB_AVDD33")
	)
	(via
		(at 137.58545 -34.840926)
		(size 0.508)
		(drill 0.254)
		(layers "F.Cu" "B.Cu")
		(net "P3V3_AUX_CPU0_USB_AVDD33")
	)
	(via
		(at 141.859 -35.27552)
		(size 0.6604)
		(drill 0.3302)
		(layers "F.Cu" "B.Cu")
		(net "P3V3_AUX_CPU0_USB_AVDD33")
	)
	(via
		(at 144.214342 -80.302862)
		(size 0.508)
		(drill 0.254)
		(layers "F.Cu" "B.Cu")
		(net "P1V8_AUX_VCC")
	)
	(via
		(at 143.3576 -80.58404)
		(size 0.6604)
		(drill 0.3302)
		(layers "F.Cu" "B.Cu")
		(net "P1V8_AUX_VCC")
	)
	(segment
		(start 143.638778 -80.302862)
		(end 144.214342 -80.302862)
		(width 0.10668)
		(layer "B.Cu")
		(net "P1V8_AUX_VCC")
	)
	(segment
		(start 143.001492 -80.940148)
		(end 143.001492 -81.786222)
		(width 0.10668)
		(layer "B.Cu")
		(net "P1V8_AUX_VCC")
	)
	(segment
		(start 143.3576 -80.58404)
		(end 143.001492 -80.940148)
		(width 0.10668)
		(layer "B.Cu")
		(net "P1V8_AUX_VCC")
	)
	(segment
		(start 143.3576 -80.58404)
		(end 143.638778 -80.302862)
		(width 0.10668)
		(layer "B.Cu")
		(net "P1V8_AUX_VCC")
	)
	(segment
		(start 144.600422 -77.287628)
		(end 144.752822 -77.135228)
		(width 0.254)
		(layer "F.Cu")
		(net "P1V8_AUX_REF")
	)
	(segment
		(start 144.752822 -75.679554)
		(end 144.87525 -75.557126)
		(width 0.254)
		(layer "F.Cu")
		(net "P1V8_AUX_REF")
	)
	(segment
		(start 144.752822 -76.274422)
		(end 144.752822 -75.679554)
		(width 0.254)
		(layer "F.Cu")
		(net "P1V8_AUX_REF")
	)
	(segment
		(start 144.752822 -77.135228)
		(end 144.752822 -76.274422)
		(width 0.254)
		(layer "F.Cu")
		(net "P1V8_AUX_REF")
	)
	(segment
		(start 144.4117 -77.287628)
		(end 144.600422 -77.287628)
		(width 0.254)
		(layer "F.Cu")
		(net "P1V8_AUX_REF")
	)
	(via
		(at 144.752822 -76.274422)
		(size 0.508)
		(drill 0.254)
		(layers "F.Cu" "B.Cu")
		(net "P1V8_AUX_REF")
	)
	(segment
		(start 144.4117 -79.287624)
		(end 144.565624 -79.287624)
		(width 0.10668)
		(layer "F.Cu")
		(net "P1V8_AUX_MODE")
	)
	(segment
		(start 145.050002 -79.925926)
		(end 145.050002 -80.618838)
		(width 0.10668)
		(layer "F.Cu")
		(net "P1V8_AUX_MODE")
	)
	(segment
		(start 145.050002 -79.772002)
		(end 145.050002 -79.925926)
		(width 0.10668)
		(layer "F.Cu")
		(net "P1V8_AUX_MODE")
	)
	(segment
		(start 144.565624 -79.287624)
		(end 145.050002 -79.772002)
		(width 0.10668)
		(layer "F.Cu")
		(net "P1V8_AUX_MODE")
	)
	(via
		(at 145.050002 -79.925926)
		(size 0.508)
		(drill 0.254)
		(layers "F.Cu" "B.Cu")
		(net "P1V8_AUX_MODE")
	)
	(segment
		(start 142.329662 -75.582526)
		(end 142.329662 -74.609452)
		(width 0.254)
		(layer "F.Cu")
		(net "P1V8_AUX_FB")
	)
	(segment
		(start 142.329662 -75.955398)
		(end 142.699232 -76.324968)
		(width 0.254)
		(layer "F.Cu")
		(net "P1V8_AUX_FB")
	)
	(segment
		(start 142.329662 -74.609452)
		(end 142.329662 -73.623932)
		(width 0.254)
		(layer "F.Cu")
		(net "P1V8_AUX_FB")
	)
	(segment
		(start 142.699232 -76.324968)
		(end 143.211804 -76.83754)
		(width 0.254)
		(layer "F.Cu")
		(net "P1V8_AUX_FB")
	)
	(segment
		(start 142.329662 -75.582526)
		(end 142.329662 -75.955398)
		(width 0.254)
		(layer "F.Cu")
		(net "P1V8_AUX_FB")
	)
	(via
		(at 142.699232 -76.324968)
		(size 0.508)
		(drill 0.254)
		(layers "F.Cu" "B.Cu")
		(net "P1V8_AUX_FB")
	)
	(segment
		(start 215.585548 -132.46862)
		(end 219.198698 -128.85547)
		(width 0.10668)
		(layer "F.Cu")
		(net "P1V8_AUX_ENABLE")
	)
	(segment
		(start 216.582498 -133.200902)
		(end 215.585548 -133.200902)
		(width 0.10668)
		(layer "F.Cu")
		(net "P1V8_AUX_ENABLE")
	)
	(segment
		(start 141.539722 -76.204064)
		(end 141.539722 -74.852022)
		(width 0.10668)
		(layer "F.Cu")
		(net "P1V8_AUX_ENABLE")
	)
	(segment
		(start 142.51178 -77.287628)
		(end 142.286228 -77.287628)
		(width 0.10668)
		(layer "F.Cu")
		(net "P1V8_AUX_ENABLE")
	)
	(segment
		(start 141.777974 -76.779374)
		(end 141.539722 -76.204064)
		(width 0.10668)
		(layer "F.Cu")
		(net "P1V8_AUX_ENABLE")
	)
	(segment
		(start 142.286228 -77.287628)
		(end 141.777974 -76.779374)
		(width 0.10668)
		(layer "F.Cu")
		(net "P1V8_AUX_ENABLE")
	)
	(segment
		(start 215.585548 -133.200902)
		(end 215.585548 -132.46862)
		(width 0.10668)
		(layer "F.Cu")
		(net "P1V8_AUX_ENABLE")
	)
	(via
		(at 141.539722 -74.852022)
		(size 0.508)
		(drill 0.254)
		(layers "F.Cu" "B.Cu")
		(net "P1V8_AUX_ENABLE")
	)
	(via
		(at 219.198698 -128.85547)
		(size 0.762)
		(drill 0.254)
		(layers "F.Cu" "B.Cu")
		(net "P1V8_AUX_ENABLE")
	)
	(segment
		(start 161.606992 -83.847686)
		(end 157.06344 -79.304134)
		(width 0.10668)
		(layer "B.Cu")
		(net "P1V8_AUX_ENABLE")
	)
	(segment
		(start 221.505018 -110.916212)
		(end 222.113856 -110.307374)
		(width 0.10668)
		(layer "B.Cu")
		(net "P1V8_AUX_ENABLE")
	)
	(segment
		(start 216.494868 -96.24949)
		(end 212.46846 -92.223082)
		(width 0.10668)
		(layer "B.Cu")
		(net "P1V8_AUX_ENABLE")
	)
	(segment
		(start 157.06344 -79.304134)
		(end 157.06344 -74.41057)
		(width 0.10668)
		(layer "B.Cu")
		(net "P1V8_AUX_ENABLE")
	)
	(segment
		(start 154.98699 -72.33412)
		(end 144.057624 -72.33412)
		(width 0.10668)
		(layer "B.Cu")
		(net "P1V8_AUX_ENABLE")
	)
	(segment
		(start 167.88257 -83.847686)
		(end 161.606992 -83.847686)
		(width 0.10668)
		(layer "B.Cu")
		(net "P1V8_AUX_ENABLE")
	)
	(segment
		(start 186.726322 -83.66506)
		(end 186.081162 -83.0199)
		(width 0.10668)
		(layer "B.Cu")
		(net "P1V8_AUX_ENABLE")
	)
	(segment
		(start 197.695566 -85.7758)
		(end 197.02018 -85.100414)
		(width 0.10668)
		(layer "B.Cu")
		(net "P1V8_AUX_ENABLE")
	)
	(segment
		(start 212.46846 -92.223082)
		(end 212.46846 -90.269314)
		(width 0.10668)
		(layer "B.Cu")
		(net "P1V8_AUX_ENABLE")
	)
	(segment
		(start 168.710356 -83.0199)
		(end 167.88257 -83.847686)
		(width 0.10668)
		(layer "B.Cu")
		(net "P1V8_AUX_ENABLE")
	)
	(segment
		(start 207.974946 -85.7758)
		(end 197.695566 -85.7758)
		(width 0.10668)
		(layer "B.Cu")
		(net "P1V8_AUX_ENABLE")
	)
	(segment
		(start 221.505018 -126.54915)
		(end 221.505018 -110.916212)
		(width 0.10668)
		(layer "B.Cu")
		(net "P1V8_AUX_ENABLE")
	)
	(segment
		(start 157.06344 -74.41057)
		(end 154.98699 -72.33412)
		(width 0.10668)
		(layer "B.Cu")
		(net "P1V8_AUX_ENABLE")
	)
	(segment
		(start 197.02018 -84.48802)
		(end 196.19722 -83.66506)
		(width 0.10668)
		(layer "B.Cu")
		(net "P1V8_AUX_ENABLE")
	)
	(segment
		(start 186.081162 -83.0199)
		(end 168.710356 -83.0199)
		(width 0.10668)
		(layer "B.Cu")
		(net "P1V8_AUX_ENABLE")
	)
	(segment
		(start 216.494868 -97.006664)
		(end 216.494868 -96.24949)
		(width 0.10668)
		(layer "B.Cu")
		(net "P1V8_AUX_ENABLE")
	)
	(segment
		(start 196.19722 -83.66506)
		(end 186.726322 -83.66506)
		(width 0.10668)
		(layer "B.Cu")
		(net "P1V8_AUX_ENABLE")
	)
	(segment
		(start 197.02018 -85.100414)
		(end 197.02018 -84.48802)
		(width 0.10668)
		(layer "B.Cu")
		(net "P1V8_AUX_ENABLE")
	)
	(segment
		(start 222.113856 -110.307374)
		(end 222.113856 -102.625652)
		(width 0.10668)
		(layer "B.Cu")
		(net "P1V8_AUX_ENABLE")
	)
	(segment
		(start 144.057624 -72.33412)
		(end 141.539722 -74.852022)
		(width 0.10668)
		(layer "B.Cu")
		(net "P1V8_AUX_ENABLE")
	)
	(segment
		(start 222.113856 -102.625652)
		(end 216.494868 -97.006664)
		(width 0.10668)
		(layer "B.Cu")
		(net "P1V8_AUX_ENABLE")
	)
	(segment
		(start 219.198698 -128.85547)
		(end 221.505018 -126.54915)
		(width 0.10668)
		(layer "B.Cu")
		(net "P1V8_AUX_ENABLE")
	)
	(segment
		(start 212.46846 -90.269314)
		(end 207.974946 -85.7758)
		(width 0.10668)
		(layer "B.Cu")
		(net "P1V8_AUX_ENABLE")
	)
	(segment
		(start 141.16177 -76.83119)
		(end 140.385546 -76.054966)
		(width 0.254)
		(layer "F.Cu")
		(net "P1V8_AUX_CS")
	)
	(segment
		(start 140.385546 -76.054966)
		(end 140.385546 -75.59929)
		(width 0.254)
		(layer "F.Cu")
		(net "P1V8_AUX_CS")
	)
	(segment
		(start 142.611856 -77.787754)
		(end 142.118334 -77.787754)
		(width 0.254)
		(layer "F.Cu")
		(net "P1V8_AUX_CS")
	)
	(segment
		(start 142.118334 -77.787754)
		(end 141.16177 -76.83119)
		(width 0.254)
		(layer "F.Cu")
		(net "P1V8_AUX_CS")
	)
	(via
		(at 141.16177 -76.83119)
		(size 0.762)
		(drill 0.381)
		(layers "F.Cu" "B.Cu")
		(net "P1V8_AUX_CS")
	)
	(segment
		(start 137.937748 -34.101532)
		(end 138.025632 -34.013648)
		(width 0.1778)
		(layer "F.Cu")
		(net "P1V2_CPU0_USB_DVDD12")
	)
	(segment
		(start 137.040112 -34.473388)
		(end 137.937748 -34.101532)
		(width 0.1778)
		(layer "F.Cu")
		(net "P1V2_CPU0_USB_DVDD12")
	)
	(segment
		(start 132.294122 -40.723312)
		(end 132.294122 -41.821862)
		(width 0.1778)
		(layer "F.Cu")
		(net "P1V2_CPU0_USB_DVDD12")
	)
	(segment
		(start 136.54405 -34.473388)
		(end 137.040112 -34.473388)
		(width 0.1778)
		(layer "F.Cu")
		(net "P1V2_CPU0_USB_DVDD12")
	)
	(segment
		(start 136.694164 -33.673542)
		(end 136.694164 -33.197292)
		(width 0.1778)
		(layer "F.Cu")
		(net "P1V2_CPU0_USB_DVDD12")
	)
	(segment
		(start 132.294122 -41.821862)
		(end 132.490972 -42.018712)
		(width 0.1778)
		(layer "F.Cu")
		(net "P1V2_CPU0_USB_DVDD12")
	)
	(segment
		(start 135.494268 -40.723312)
		(end 135.494268 -41.764712)
		(width 0.1778)
		(layer "F.Cu")
		(net "P1V2_CPU0_USB_DVDD12")
	)
	(via
		(at 133.1976 -42.59072)
		(size 0.6604)
		(drill 0.3302)
		(layers "F.Cu" "B.Cu")
		(net "P1V2_CPU0_USB_DVDD12")
	)
	(via
		(at 132.490972 -42.018712)
		(size 0.508)
		(drill 0.254)
		(layers "F.Cu" "B.Cu")
		(net "P1V2_CPU0_USB_DVDD12")
	)
	(via
		(at 136.694164 -33.197292)
		(size 0.508)
		(drill 0.254)
		(layers "F.Cu" "B.Cu")
		(net "P1V2_CPU0_USB_DVDD12")
	)
	(via
		(at 138.025632 -34.013648)
		(size 0.508)
		(drill 0.254)
		(layers "F.Cu" "B.Cu")
		(net "P1V2_CPU0_USB_DVDD12")
	)
	(via
		(at 135.494268 -41.764712)
		(size 0.508)
		(drill 0.254)
		(layers "F.Cu" "B.Cu")
		(net "P1V2_CPU0_USB_DVDD12")
	)
	(via
		(at 122.116342 -78.016862)
		(size 0.508)
		(drill 0.254)
		(layers "F.Cu" "B.Cu")
		(net "P1V2_AUX_VCC")
	)
	(via
		(at 122.234706 -79.337408)
		(size 0.6604)
		(drill 0.3302)
		(layers "F.Cu" "B.Cu")
		(net "P1V2_AUX_VCC")
	)
	(segment
		(start 121.066306 -79.337408)
		(end 122.234706 -79.337408)
		(width 0.10668)
		(layer "B.Cu")
		(net "P1V2_AUX_VCC")
	)
	(segment
		(start 122.234706 -78.135226)
		(end 122.234706 -79.337408)
		(width 0.10668)
		(layer "B.Cu")
		(net "P1V2_AUX_VCC")
	)
	(segment
		(start 122.116342 -78.016862)
		(end 122.234706 -78.135226)
		(width 0.10668)
		(layer "B.Cu")
		(net "P1V2_AUX_VCC")
	)
	(segment
		(start 122.654822 -73.988422)
		(end 122.77725 -73.865994)
		(width 0.254)
		(layer "F.Cu")
		(net "P1V2_AUX_REF")
	)
	(segment
		(start 122.77725 -73.865994)
		(end 122.77725 -73.271126)
		(width 0.254)
		(layer "F.Cu")
		(net "P1V2_AUX_REF")
	)
	(segment
		(start 122.488198 -75.001628)
		(end 122.3137 -75.001628)
		(width 0.254)
		(layer "F.Cu")
		(net "P1V2_AUX_REF")
	)
	(segment
		(start 122.654822 -74.835004)
		(end 122.488198 -75.001628)
		(width 0.254)
		(layer "F.Cu")
		(net "P1V2_AUX_REF")
	)
	(segment
		(start 122.654822 -73.988422)
		(end 122.654822 -74.835004)
		(width 0.254)
		(layer "F.Cu")
		(net "P1V2_AUX_REF")
	)
	(via
		(at 122.654822 -73.988422)
		(size 0.508)
		(drill 0.254)
		(layers "F.Cu" "B.Cu")
		(net "P1V2_AUX_REF")
	)
	(segment
		(start 122.3137 -77.001624)
		(end 122.467624 -77.001624)
		(width 0.10668)
		(layer "F.Cu")
		(net "P1V2_AUX_MODE")
	)
	(segment
		(start 122.467624 -77.001624)
		(end 122.952002 -77.486002)
		(width 0.10668)
		(layer "F.Cu")
		(net "P1V2_AUX_MODE")
	)
	(segment
		(start 122.952002 -77.486002)
		(end 122.952002 -77.639926)
		(width 0.10668)
		(layer "F.Cu")
		(net "P1V2_AUX_MODE")
	)
	(segment
		(start 122.952002 -77.639926)
		(end 122.952002 -78.332838)
		(width 0.10668)
		(layer "F.Cu")
		(net "P1V2_AUX_MODE")
	)
	(via
		(at 122.952002 -77.639926)
		(size 0.508)
		(drill 0.254)
		(layers "F.Cu" "B.Cu")
		(net "P1V2_AUX_MODE")
	)
	(segment
		(start 120.231662 -72.323452)
		(end 120.231662 -73.296526)
		(width 0.254)
		(layer "F.Cu")
		(net "P1V2_AUX_FB")
	)
	(segment
		(start 120.231662 -73.669398)
		(end 120.601232 -74.038968)
		(width 0.254)
		(layer "F.Cu")
		(net "P1V2_AUX_FB")
	)
	(segment
		(start 120.601232 -74.038968)
		(end 121.113804 -74.55154)
		(width 0.254)
		(layer "F.Cu")
		(net "P1V2_AUX_FB")
	)
	(segment
		(start 120.231662 -71.337932)
		(end 120.231662 -72.323452)
		(width 0.254)
		(layer "F.Cu")
		(net "P1V2_AUX_FB")
	)
	(segment
		(start 120.231662 -73.296526)
		(end 120.231662 -73.669398)
		(width 0.254)
		(layer "F.Cu")
		(net "P1V2_AUX_FB")
	)
	(via
		(at 120.601232 -74.038968)
		(size 0.508)
		(drill 0.254)
		(layers "F.Cu" "B.Cu")
		(net "P1V2_AUX_FB")
	)
	(segment
		(start 119.441722 -73.936352)
		(end 119.441722 -72.566022)
		(width 0.10668)
		(layer "F.Cu")
		(net "P1V2_AUX_ENABLE")
	)
	(segment
		(start 119.64924 -74.43724)
		(end 119.441722 -73.936352)
		(width 0.10668)
		(layer "F.Cu")
		(net "P1V2_AUX_ENABLE")
	)
	(segment
		(start 120.213628 -75.001628)
		(end 119.64924 -74.43724)
		(width 0.10668)
		(layer "F.Cu")
		(net "P1V2_AUX_ENABLE")
	)
	(segment
		(start 120.41378 -75.001628)
		(end 120.213628 -75.001628)
		(width 0.10668)
		(layer "F.Cu")
		(net "P1V2_AUX_ENABLE")
	)
	(via
		(at 119.441722 -72.566022)
		(size 0.508)
		(drill 0.254)
		(layers "F.Cu" "B.Cu")
		(net "P1V2_AUX_ENABLE")
	)
	(segment
		(start 120.610122 -72.566022)
		(end 119.441722 -72.566022)
		(width 0.10668)
		(layer "B.Cu")
		(net "P1V2_AUX_ENABLE")
	)
	(segment
		(start 120.020334 -75.501754)
		(end 120.513856 -75.501754)
		(width 0.254)
		(layer "F.Cu")
		(net "P1V2_AUX_CS")
	)
	(segment
		(start 118.287546 -73.768966)
		(end 119.00916 -74.49058)
		(width 0.254)
		(layer "F.Cu")
		(net "P1V2_AUX_CS")
	)
	(segment
		(start 119.00916 -74.49058)
		(end 120.020334 -75.501754)
		(width 0.254)
		(layer "F.Cu")
		(net "P1V2_AUX_CS")
	)
	(segment
		(start 118.287546 -73.31329)
		(end 118.287546 -73.768966)
		(width 0.254)
		(layer "F.Cu")
		(net "P1V2_AUX_CS")
	)
	(via
		(at 119.00916 -74.49058)
		(size 0.762)
		(drill 0.381)
		(layers "F.Cu" "B.Cu")
		(net "P1V2_AUX_CS")
	)
	(segment
		(start 208.963768 -159.576008)
		(end 206.130398 -156.742638)
		(width 0.381)
		(layer "F.Cu")
		(net "P1V2_AUX")
	)
	(segment
		(start 129.49428 -32.873442)
		(end 129.49428 -32.31642)
		(width 0.1778)
		(layer "F.Cu")
		(net "P1V2_AUX")
	)
	(segment
		(start 136.54405 -39.67353)
		(end 137.58545 -39.67353)
		(width 0.1778)
		(layer "F.Cu")
		(net "P1V2_AUX")
	)
	(segment
		(start 129.373884 -32.196024)
		(end 129.373884 -31.963868)
		(width 0.1778)
		(layer "F.Cu")
		(net "P1V2_AUX")
	)
	(segment
		(start 208.963768 -160.13303)
		(end 208.963768 -159.576008)
		(width 0.381)
		(layer "F.Cu")
		(net "P1V2_AUX")
	)
	(segment
		(start 130.631692 -71.303134)
		(end 130.631692 -70.677532)
		(width 0.254)
		(layer "F.Cu")
		(net "P1V2_AUX")
	)
	(segment
		(start 128.844294 -35.673538)
		(end 128.056894 -35.673538)
		(width 0.1778)
		(layer "F.Cu")
		(net "P1V2_AUX")
	)
	(segment
		(start 127.792988 -34.473388)
		(end 127.762 -34.4424)
		(width 0.1778)
		(layer "F.Cu")
		(net "P1V2_AUX")
	)
	(segment
		(start 127.034544 -36.203128)
		(end 127.034544 -35.828732)
		(width 0.1778)
		(layer "F.Cu")
		(net "P1V2_AUX")
	)
	(segment
		(start 129.49428 -32.31642)
		(end 129.373884 -32.196024)
		(width 0.1778)
		(layer "F.Cu")
		(net "P1V2_AUX")
	)
	(segment
		(start 130.631692 -70.677532)
		(end 130.268218 -70.314058)
		(width 0.254)
		(layer "F.Cu")
		(net "P1V2_AUX")
	)
	(segment
		(start 137.552938 -37.273484)
		(end 137.58545 -37.305996)
		(width 0.1778)
		(layer "F.Cu")
		(net "P1V2_AUX")
	)
	(segment
		(start 127.70485 -36.873434)
		(end 127.034544 -36.203128)
		(width 0.1778)
		(layer "F.Cu")
		(net "P1V2_AUX")
	)
	(segment
		(start 129.894076 -32.216344)
		(end 129.6416 -31.963868)
		(width 0.1778)
		(layer "F.Cu")
		(net "P1V2_AUX")
	)
	(segment
		(start 136.54405 -38.47338)
		(end 137.58545 -38.47338)
		(width 0.1778)
		(layer "F.Cu")
		(net "P1V2_AUX")
	)
	(segment
		(start 128.056894 -35.673538)
		(end 127.9017 -35.828732)
		(width 0.1778)
		(layer "F.Cu")
		(net "P1V2_AUX")
	)
	(segment
		(start 220.103446 -189.998858)
		(end 220.103446 -180.888132)
		(width 0.381)
		(layer "F.Cu")
		(net "P1V2_AUX")
	)
	(segment
		(start 128.844294 -34.473388)
		(end 127.792988 -34.473388)
		(width 0.1778)
		(layer "F.Cu")
		(net "P1V2_AUX")
	)
	(segment
		(start 206.130398 -156.742638)
		(end 200.44029 -156.742638)
		(width 0.381)
		(layer "F.Cu")
		(net "P1V2_AUX")
	)
	(segment
		(start 129.49428 -40.873426)
		(end 129.01803 -40.873426)
		(width 0.1778)
		(layer "F.Cu")
		(net "P1V2_AUX")
	)
	(segment
		(start 136.54405 -37.273484)
		(end 137.552938 -37.273484)
		(width 0.1778)
		(layer "F.Cu")
		(net "P1V2_AUX")
	)
	(segment
		(start 128.844294 -36.873434)
		(end 127.70485 -36.873434)
		(width 0.1778)
		(layer "F.Cu")
		(net "P1V2_AUX")
	)
	(segment
		(start 129.894076 -33.023556)
		(end 129.894076 -32.216344)
		(width 0.1778)
		(layer "F.Cu")
		(net "P1V2_AUX")
	)
	(segment
		(start 220.103446 -180.888132)
		(end 213.304374 -164.473636)
		(width 0.381)
		(layer "F.Cu")
		(net "P1V2_AUX")
	)
	(segment
		(start 213.304374 -164.473636)
		(end 208.963768 -160.13303)
		(width 0.381)
		(layer "F.Cu")
		(net "P1V2_AUX")
	)
	(segment
		(start 123.304554 -70.314058)
		(end 122.28068 -71.337932)
		(width 0.254)
		(layer "F.Cu")
		(net "P1V2_AUX")
	)
	(segment
		(start 122.28068 -71.337932)
		(end 121.031762 -71.337932)
		(width 0.254)
		(layer "F.Cu")
		(net "P1V2_AUX")
	)
	(segment
		(start 136.54405 -36.073334)
		(end 137.58545 -36.073334)
		(width 0.1778)
		(layer "F.Cu")
		(net "P1V2_AUX")
	)
	(segment
		(start 127.9017 -35.828732)
		(end 127.034544 -35.828732)
		(width 0.1778)
		(layer "F.Cu")
		(net "P1V2_AUX")
	)
	(segment
		(start 129.6416 -31.963868)
		(end 129.373884 -31.963868)
		(width 0.1778)
		(layer "F.Cu")
		(net "P1V2_AUX")
	)
	(segment
		(start 121.031762 -71.337932)
		(end 121.031762 -72.323452)
		(width 0.254)
		(layer "F.Cu")
		(net "P1V2_AUX")
	)
	(segment
		(start 128.844294 -39.27348)
		(end 127.802894 -39.27348)
		(width 0.1778)
		(layer "F.Cu")
		(net "P1V2_AUX")
	)
	(segment
		(start 130.268218 -70.314058)
		(end 123.304554 -70.314058)
		(width 0.254)
		(layer "F.Cu")
		(net "P1V2_AUX")
	)
	(via
		(at 132.149342 -73.41489)
		(size 0.508)
		(drill 0.254)
		(layers "F.Cu" "B.Cu")
		(net "P1V2_AUX")
	)
	(via
		(at 133.298692 -75.95489)
		(size 0.6604)
		(drill 0.3302)
		(layers "F.Cu" "B.Cu")
		(net "P1V2_AUX")
	)
	(via
		(at 127.762 -34.4424)
		(size 0.508)
		(drill 0.254)
		(layers "F.Cu" "B.Cu")
		(net "P1V2_AUX")
	)
	(via
		(at 127.802894 -39.27348)
		(size 0.508)
		(drill 0.254)
		(layers "F.Cu" "B.Cu")
		(net "P1V2_AUX")
	)
	(via
		(at 132.149342 -79.5528)
		(size 0.508)
		(drill 0.254)
		(layers "F.Cu" "B.Cu")
		(net "P1V2_AUX")
	)
	(via
		(at 129.373884 -31.963868)
		(size 0.508)
		(drill 0.254)
		(layers "F.Cu" "B.Cu")
		(net "P1V2_AUX")
	)
	(via
		(at 131.888992 -71.303134)
		(size 0.508)
		(drill 0.254)
		(layers "F.Cu" "B.Cu")
		(net "P1V2_AUX")
	)
	(via
		(at 200.44029 -156.742638)
		(size 0.508)
		(drill 0.254)
		(layers "F.Cu" "B.Cu")
		(net "P1V2_AUX")
	)
	(via
		(at 131.507992 -79.5528)
		(size 0.508)
		(drill 0.254)
		(layers "F.Cu" "B.Cu")
		(net "P1V2_AUX")
	)
	(via
		(at 137.58545 -37.305996)
		(size 0.508)
		(drill 0.254)
		(layers "F.Cu" "B.Cu")
		(net "P1V2_AUX")
	)
	(via
		(at 133.298692 -78.49489)
		(size 0.6604)
		(drill 0.3302)
		(layers "F.Cu" "B.Cu")
		(net "P1V2_AUX")
	)
	(via
		(at 131.507992 -77.50683)
		(size 0.508)
		(drill 0.254)
		(layers "F.Cu" "B.Cu")
		(net "P1V2_AUX")
	)
	(via
		(at 137.58545 -39.67353)
		(size 0.508)
		(drill 0.254)
		(layers "F.Cu" "B.Cu")
		(net "P1V2_AUX")
	)
	(via
		(at 240.57229 -327.000362)
		(size 0.508)
		(drill 0.254)
		(layers "F.Cu" "B.Cu")
		(net "P1V2_AUX")
	)
	(via
		(at 126.4158 -39.9288)
		(size 0.508)
		(drill 0.254)
		(layers "F.Cu" "B.Cu")
		(net "P1V2_AUX")
	)
	(via
		(at 220.103446 -189.998858)
		(size 0.508)
		(drill 0.254)
		(layers "F.Cu" "B.Cu")
		(net "P1V2_AUX")
	)
	(via
		(at 130.866642 -79.5528)
		(size 0.508)
		(drill 0.254)
		(layers "F.Cu" "B.Cu")
		(net "P1V2_AUX")
	)
	(via
		(at 119.888 -37.36086)
		(size 0.6604)
		(drill 0.3302)
		(layers "F.Cu" "B.Cu")
		(net "P1V2_AUX")
	)
	(via
		(at 137.58545 -38.47338)
		(size 0.508)
		(drill 0.254)
		(layers "F.Cu" "B.Cu")
		(net "P1V2_AUX")
	)
	(via
		(at 122.428 -37.36086)
		(size 0.6604)
		(drill 0.3302)
		(layers "F.Cu" "B.Cu")
		(net "P1V2_AUX")
	)
	(via
		(at 129.01803 -40.873426)
		(size 0.508)
		(drill 0.254)
		(layers "F.Cu" "B.Cu")
		(net "P1V2_AUX")
	)
	(via
		(at 127.034544 -35.828732)
		(size 0.508)
		(drill 0.254)
		(layers "F.Cu" "B.Cu")
		(net "P1V2_AUX")
	)
	(via
		(at 132.149342 -77.50683)
		(size 0.508)
		(drill 0.254)
		(layers "F.Cu" "B.Cu")
		(net "P1V2_AUX")
	)
	(via
		(at 130.866642 -73.41489)
		(size 0.508)
		(drill 0.254)
		(layers "F.Cu" "B.Cu")
		(net "P1V2_AUX")
	)
	(via
		(at 132.530342 -71.303134)
		(size 0.508)
		(drill 0.254)
		(layers "F.Cu" "B.Cu")
		(net "P1V2_AUX")
	)
	(via
		(at 130.866642 -77.50683)
		(size 0.508)
		(drill 0.254)
		(layers "F.Cu" "B.Cu")
		(net "P1V2_AUX")
	)
	(via
		(at 135.435594 -89.112852)
		(size 0.508)
		(drill 0.254)
		(layers "F.Cu" "B.Cu")
		(net "P1V2_AUX")
	)
	(via
		(at 131.247642 -71.303134)
		(size 0.508)
		(drill 0.254)
		(layers "F.Cu" "B.Cu")
		(net "P1V2_AUX")
	)
	(via
		(at 132.790692 -73.41489)
		(size 0.508)
		(drill 0.254)
		(layers "F.Cu" "B.Cu")
		(net "P1V2_AUX")
	)
	(via
		(at 137.316464 -117.725444)
		(size 0.508)
		(drill 0.254)
		(layers "F.Cu" "B.Cu")
		(net "P1V2_AUX")
	)
	(via
		(at 131.507992 -73.41489)
		(size 0.508)
		(drill 0.254)
		(layers "F.Cu" "B.Cu")
		(net "P1V2_AUX")
	)
	(via
		(at 248.723912 -329.671172)
		(size 0.508)
		(drill 0.254)
		(layers "F.Cu" "B.Cu")
		(net "P1V2_AUX")
	)
	(via
		(at 117.348 -37.36086)
		(size 0.6604)
		(drill 0.3302)
		(layers "F.Cu" "B.Cu")
		(net "P1V2_AUX")
	)
	(via
		(at 127.1524 -39.9034)
		(size 0.508)
		(drill 0.254)
		(layers "F.Cu" "B.Cu")
		(net "P1V2_AUX")
	)
	(via
		(at 247.284748 -218.380818)
		(size 0.508)
		(drill 0.254)
		(layers "F.Cu" "B.Cu")
		(net "P1V2_AUX")
	)
	(via
		(at 137.58545 -36.073334)
		(size 0.508)
		(drill 0.254)
		(layers "F.Cu" "B.Cu")
		(net "P1V2_AUX")
	)
	(segment
		(start 219.670122 -193.22796)
		(end 219.670122 -190.432182)
		(width 0.4572)
		(layer "B.Cu")
		(net "P1V2_AUX")
	)
	(segment
		(start 219.670122 -190.432182)
		(end 220.103446 -189.998858)
		(width 0.4572)
		(layer "B.Cu")
		(net "P1V2_AUX")
	)
	(segment
		(start 238.412274 -206.953358)
		(end 233.39552 -206.953358)
		(width 0.4572)
		(layer "B.Cu")
		(net "P1V2_AUX")
	)
	(segment
		(start 247.284748 -218.380818)
		(end 247.284748 -215.825832)
		(width 0.4572)
		(layer "B.Cu")
		(net "P1V2_AUX")
	)
	(segment
		(start 238.323628 -323.585332)
		(end 240.188242 -323.585332)
		(width 0.381)
		(layer "B.Cu")
		(net "P1V2_AUX")
	)
	(segment
		(start 240.188242 -323.585332)
		(end 240.57229 -323.96938)
		(width 0.381)
		(layer "B.Cu")
		(net "P1V2_AUX")
	)
	(segment
		(start 233.39552 -206.953358)
		(end 219.670122 -193.22796)
		(width 0.4572)
		(layer "B.Cu")
		(net "P1V2_AUX")
	)
	(segment
		(start 247.284748 -215.825832)
		(end 238.412274 -206.953358)
		(width 0.4572)
		(layer "B.Cu")
		(net "P1V2_AUX")
	)
	(segment
		(start 240.57229 -323.96938)
		(end 240.57229 -327.000362)
		(width 0.381)
		(layer "B.Cu")
		(net "P1V2_AUX")
	)
	(segment
		(start 247.121426 -328.068686)
		(end 248.723912 -329.671172)
		(width 0.4572)
		(layer "In2.Cu")
		(net "P1V2_AUX")
	)
	(segment
		(start 136.225788 -131.521708)
		(end 136.225788 -118.81612)
		(width 0.4572)
		(layer "In2.Cu")
		(net "P1V2_AUX")
	)
	(segment
		(start 156.360368 -151.656288)
		(end 136.225788 -131.521708)
		(width 0.4572)
		(layer "In2.Cu")
		(net "P1V2_AUX")
	)
	(segment
		(start 179.06238 -152.573736)
		(end 177.727102 -153.909014)
		(width 0.4572)
		(layer "In2.Cu")
		(net "P1V2_AUX")
	)
	(segment
		(start 184.916064 -154.351228)
		(end 184.555384 -154.351228)
		(width 0.4572)
		(layer "In2.Cu")
		(net "P1V2_AUX")
	)
	(segment
		(start 191.093598 -160.528762)
		(end 184.916064 -154.351228)
		(width 0.4572)
		(layer "In2.Cu")
		(net "P1V2_AUX")
	)
	(segment
		(start 177.727102 -153.909014)
		(end 176.217326 -153.909014)
		(width 0.4572)
		(layer "In2.Cu")
		(net "P1V2_AUX")
	)
	(segment
		(start 182.777892 -152.573736)
		(end 179.06238 -152.573736)
		(width 0.4572)
		(layer "In2.Cu")
		(net "P1V2_AUX")
	)
	(segment
		(start 184.555384 -154.351228)
		(end 182.777892 -152.573736)
		(width 0.4572)
		(layer "In2.Cu")
		(net "P1V2_AUX")
	)
	(segment
		(start 196.6087 -160.528762)
		(end 191.093598 -160.528762)
		(width 0.4572)
		(layer "In2.Cu")
		(net "P1V2_AUX")
	)
	(segment
		(start 136.225788 -118.81612)
		(end 137.316464 -117.725444)
		(width 0.4572)
		(layer "In2.Cu")
		(net "P1V2_AUX")
	)
	(segment
		(start 240.57229 -327.000362)
		(end 241.024918 -327.000362)
		(width 0.4572)
		(layer "In2.Cu")
		(net "P1V2_AUX")
	)
	(segment
		(start 197.793102 -159.34436)
		(end 196.6087 -160.528762)
		(width 0.4572)
		(layer "In2.Cu")
		(net "P1V2_AUX")
	)
	(segment
		(start 200.44029 -156.813758)
		(end 197.909688 -159.34436)
		(width 0.4572)
		(layer "In2.Cu")
		(net "P1V2_AUX")
	)
	(segment
		(start 166.463218 -150.518368)
		(end 165.325298 -151.656288)
		(width 0.4572)
		(layer "In2.Cu")
		(net "P1V2_AUX")
	)
	(segment
		(start 197.909688 -159.34436)
		(end 197.793102 -159.34436)
		(width 0.4572)
		(layer "In2.Cu")
		(net "P1V2_AUX")
	)
	(segment
		(start 176.217326 -153.909014)
		(end 172.82668 -150.518368)
		(width 0.4572)
		(layer "In2.Cu")
		(net "P1V2_AUX")
	)
	(segment
		(start 200.44029 -156.742638)
		(end 200.44029 -156.813758)
		(width 0.4572)
		(layer "In2.Cu")
		(net "P1V2_AUX")
	)
	(segment
		(start 165.325298 -151.656288)
		(end 156.360368 -151.656288)
		(width 0.4572)
		(layer "In2.Cu")
		(net "P1V2_AUX")
	)
	(segment
		(start 242.093242 -328.068686)
		(end 247.121426 -328.068686)
		(width 0.4572)
		(layer "In2.Cu")
		(net "P1V2_AUX")
	)
	(segment
		(start 241.024918 -327.000362)
		(end 242.093242 -328.068686)
		(width 0.4572)
		(layer "In2.Cu")
		(net "P1V2_AUX")
	)
	(segment
		(start 172.82668 -150.518368)
		(end 166.463218 -150.518368)
		(width 0.4572)
		(layer "In2.Cu")
		(net "P1V2_AUX")
	)
	(segment
		(start 248.723912 -326.85101)
		(end 251.719842 -323.85508)
		(width 0.4572)
		(layer "In4.Cu")
		(net "P1V2_AUX")
	)
	(segment
		(start 251.719842 -323.85508)
		(end 251.719842 -321.794632)
		(width 0.4572)
		(layer "In4.Cu")
		(net "P1V2_AUX")
	)
	(segment
		(start 254.251968 -266.734036)
		(end 247.284748 -259.766816)
		(width 0.4572)
		(layer "In4.Cu")
		(net "P1V2_AUX")
	)
	(segment
		(start 247.284748 -259.766816)
		(end 247.284748 -218.380818)
		(width 0.4572)
		(layer "In4.Cu")
		(net "P1V2_AUX")
	)
	(segment
		(start 251.719842 -321.794632)
		(end 254.251968 -319.262506)
		(width 0.4572)
		(layer "In4.Cu")
		(net "P1V2_AUX")
	)
	(segment
		(start 135.435594 -89.089738)
		(end 132.149342 -85.803486)
		(width 0.4572)
		(layer "In4.Cu")
		(net "P1V2_AUX")
	)
	(segment
		(start 132.149342 -85.803486)
		(end 132.149342 -79.5528)
		(width 0.4572)
		(layer "In4.Cu")
		(net "P1V2_AUX")
	)
	(segment
		(start 248.723912 -329.671172)
		(end 248.723912 -326.85101)
		(width 0.4572)
		(layer "In4.Cu")
		(net "P1V2_AUX")
	)
	(segment
		(start 135.435594 -89.112852)
		(end 135.435594 -89.089738)
		(width 0.4572)
		(layer "In4.Cu")
		(net "P1V2_AUX")
	)
	(segment
		(start 254.251968 -319.262506)
		(end 254.251968 -266.734036)
		(width 0.4572)
		(layer "In4.Cu")
		(net "P1V2_AUX")
	)
	(segment
		(start 134.73938 -106.950256)
		(end 134.73938 -104.86009)
		(width 0.4572)
		(layer "In15.Cu")
		(net "P1V2_AUX")
	)
	(segment
		(start 133.810248 -111.734346)
		(end 133.810248 -107.879388)
		(width 0.4572)
		(layer "In15.Cu")
		(net "P1V2_AUX")
	)
	(segment
		(start 133.252972 -100.307902)
		(end 134.50697 -99.053904)
		(width 0.4572)
		(layer "In15.Cu")
		(net "P1V2_AUX")
	)
	(segment
		(start 133.810248 -107.879388)
		(end 134.73938 -106.950256)
		(width 0.4572)
		(layer "In15.Cu")
		(net "P1V2_AUX")
	)
	(segment
		(start 134.50697 -90.041476)
		(end 135.435594 -89.112852)
		(width 0.4572)
		(layer "In15.Cu")
		(net "P1V2_AUX")
	)
	(segment
		(start 133.252972 -103.373682)
		(end 133.252972 -100.307902)
		(width 0.4572)
		(layer "In15.Cu")
		(net "P1V2_AUX")
	)
	(segment
		(start 134.50697 -99.053904)
		(end 134.50697 -90.041476)
		(width 0.4572)
		(layer "In15.Cu")
		(net "P1V2_AUX")
	)
	(segment
		(start 135.737854 -113.661952)
		(end 133.810248 -111.734346)
		(width 0.4572)
		(layer "In15.Cu")
		(net "P1V2_AUX")
	)
	(segment
		(start 137.316464 -117.098572)
		(end 135.737854 -115.519962)
		(width 0.4572)
		(layer "In15.Cu")
		(net "P1V2_AUX")
	)
	(segment
		(start 135.737854 -115.519962)
		(end 135.737854 -113.661952)
		(width 0.4572)
		(layer "In15.Cu")
		(net "P1V2_AUX")
	)
	(segment
		(start 137.316464 -117.725444)
		(end 137.316464 -117.098572)
		(width 0.4572)
		(layer "In15.Cu")
		(net "P1V2_AUX")
	)
	(segment
		(start 134.73938 -104.86009)
		(end 133.252972 -103.373682)
		(width 0.4572)
		(layer "In15.Cu")
		(net "P1V2_AUX")
	)
	(segment
		(start 308.379876 -70.573392)
		(end 308.379876 -71.868792)
		(width 0.10668)
		(layer "F.Cu")
		(net "LED_PWRGD_P1V2_AUX_D")
	)
	(via
		(at 308.379876 -71.868792)
		(size 0.762)
		(drill 0.254)
		(layers "F.Cu" "B.Cu")
		(net "LED_PWRGD_P1V2_AUX_D")
	)
	(segment
		(start 307.8226 -72.426068)
		(end 308.379876 -71.868792)
		(width 0.10668)
		(layer "B.Cu")
		(net "LED_PWRGD_P1V2_AUX_D")
	)
	(segment
		(start 307.495448 -74.184764)
		(end 307.8226 -73.857612)
		(width 0.10668)
		(layer "B.Cu")
		(net "LED_PWRGD_P1V2_AUX_D")
	)
	(segment
		(start 307.8226 -73.857612)
		(end 307.8226 -72.426068)
		(width 0.10668)
		(layer "B.Cu")
		(net "LED_PWRGD_P1V2_AUX_D")
	)
	(segment
		(start 307.130704 -74.184764)
		(end 307.495448 -74.184764)
		(width 0.10668)
		(layer "B.Cu")
		(net "LED_PWRGD_P1V2_AUX_D")
	)
	(segment
		(start 308.379876 -68.328032)
		(end 308.379876 -69.623432)
		(width 0.10668)
		(layer "F.Cu")
		(net "LED_PWRGD_P1V2_AUX")
	)
	(via
		(at 308.379876 -68.328032)
		(size 0.508)
		(drill 0.254)
		(layers "F.Cu" "B.Cu")
		(net "LED_PWRGD_P1V2_AUX")
	)
	(segment
		(start 308.379876 -67.108832)
		(end 308.379876 -68.328032)
		(width 0.10668)
		(layer "B.Cu")
		(net "LED_PWRGD_P1V2_AUX")
	)
	(via
		(at 172.74032 -426.449998)
		(size 0.6604)
		(drill 0.3302)
		(layers "F.Cu" "B.Cu")
		(net "A_HSC_LOW_GATE")
	)
	(segment
		(start 178.878484 -428.270416)
		(end 184.175146 -428.270416)
		(width 0.10668)
		(layer "B.Cu")
		(net "A_HSC_LOW_GATE")
	)
	(segment
		(start 173.31309 -427.92904)
		(end 173.31309 -428.327058)
		(width 0.10668)
		(layer "B.Cu")
		(net "A_HSC_LOW_GATE")
	)
	(segment
		(start 178.213004 -426.70476)
		(end 178.213004 -427.604936)
		(width 0.10668)
		(layer "B.Cu")
		(net "A_HSC_LOW_GATE")
	)
	(segment
		(start 175.341026 -425.700952)
		(end 175.06696 -425.975018)
		(width 0.10668)
		(layer "B.Cu")
		(net "A_HSC_LOW_GATE")
	)
	(segment
		(start 172.376338 -427.923706)
		(end 172.376338 -426.81398)
		(width 0.10668)
		(layer "B.Cu")
		(net "A_HSC_LOW_GATE")
	)
	(segment
		(start 178.213004 -425.981876)
		(end 177.93208 -425.700952)
		(width 0.10668)
		(layer "B.Cu")
		(net "A_HSC_LOW_GATE")
	)
	(segment
		(start 184.175146 -428.270416)
		(end 184.287922 -428.15764)
		(width 0.10668)
		(layer "B.Cu")
		(net "A_HSC_LOW_GATE")
	)
	(segment
		(start 177.93208 -425.700952)
		(end 175.341026 -425.700952)
		(width 0.10668)
		(layer "B.Cu")
		(net "A_HSC_LOW_GATE")
	)
	(segment
		(start 172.74032 -426.449998)
		(end 174.43704 -426.449998)
		(width 0.10668)
		(layer "B.Cu")
		(net "A_HSC_LOW_GATE")
	)
	(segment
		(start 178.213004 -426.70476)
		(end 178.213004 -425.981876)
		(width 0.10668)
		(layer "B.Cu")
		(net "A_HSC_LOW_GATE")
	)
	(segment
		(start 172.376338 -426.81398)
		(end 172.74032 -426.449998)
		(width 0.10668)
		(layer "B.Cu")
		(net "A_HSC_LOW_GATE")
	)
	(segment
		(start 175.06696 -425.975018)
		(end 175.06696 -427.92269)
		(width 0.10668)
		(layer "B.Cu")
		(net "A_HSC_LOW_GATE")
	)
	(segment
		(start 173.307756 -427.923706)
		(end 173.31309 -427.92904)
		(width 0.10668)
		(layer "B.Cu")
		(net "A_HSC_LOW_GATE")
	)
	(segment
		(start 173.54804 -428.562008)
		(end 174.427642 -428.562008)
		(width 0.10668)
		(layer "B.Cu")
		(net "A_HSC_LOW_GATE")
	)
	(segment
		(start 178.213004 -427.604936)
		(end 178.878484 -428.270416)
		(width 0.10668)
		(layer "B.Cu")
		(net "A_HSC_LOW_GATE")
	)
	(segment
		(start 173.31309 -428.327058)
		(end 173.54804 -428.562008)
		(width 0.10668)
		(layer "B.Cu")
		(net "A_HSC_LOW_GATE")
	)
	(segment
		(start 174.427642 -428.562008)
		(end 175.06696 -427.92269)
		(width 0.10668)
		(layer "B.Cu")
		(net "A_HSC_LOW_GATE")
	)
	(segment
		(start 172.376338 -427.923706)
		(end 173.307756 -427.923706)
		(width 0.10668)
		(layer "B.Cu")
		(net "A_HSC_LOW_GATE")
	)
	(via
		(at 175.10633 -423.08399)
		(size 0.6604)
		(drill 0.3302)
		(layers "F.Cu" "B.Cu")
		(net "A_HSC_LOW_DRAIN")
	)
	(segment
		(start 175.387 -424.450002)
		(end 175.387 -423.36466)
		(width 0.10668)
		(layer "B.Cu")
		(net "A_HSC_LOW_DRAIN")
	)
	(segment
		(start 175.10633 -423.08399)
		(end 175.10633 -422.234614)
		(width 0.10668)
		(layer "B.Cu")
		(net "A_HSC_LOW_DRAIN")
	)
	(segment
		(start 175.387 -423.36466)
		(end 175.10633 -423.08399)
		(width 0.10668)
		(layer "B.Cu")
		(net "A_HSC_LOW_DRAIN")
	)
	(via
		(at 183.294528 -426.887132)
		(size 0.6604)
		(drill 0.3302)
		(layers "F.Cu" "B.Cu")
		(net "A_HSC_LOW")
	)
	(segment
		(start 181.845458 -425.939712)
		(end 181.584854 -425.679108)
		(width 0.10668)
		(layer "B.Cu")
		(net "A_HSC_LOW")
	)
	(segment
		(start 180.262276 -425.679108)
		(end 180.110638 -425.830746)
		(width 0.10668)
		(layer "B.Cu")
		(net "A_HSC_LOW")
	)
	(segment
		(start 181.845458 -426.498766)
		(end 182.371746 -426.498766)
		(width 0.10668)
		(layer "B.Cu")
		(net "A_HSC_LOW")
	)
	(segment
		(start 181.584854 -425.679108)
		(end 180.262276 -425.679108)
		(width 0.10668)
		(layer "B.Cu")
		(net "A_HSC_LOW")
	)
	(segment
		(start 182.371746 -426.498766)
		(end 182.760112 -426.887132)
		(width 0.10668)
		(layer "B.Cu")
		(net "A_HSC_LOW")
	)
	(segment
		(start 180.110638 -425.830746)
		(end 180.110638 -426.702474)
		(width 0.10668)
		(layer "B.Cu")
		(net "A_HSC_LOW")
	)
	(segment
		(start 181.845458 -426.498766)
		(end 181.845458 -425.939712)
		(width 0.10668)
		(layer "B.Cu")
		(net "A_HSC_LOW")
	)
	(segment
		(start 180.110638 -426.702474)
		(end 180.112924 -426.70476)
		(width 0.10668)
		(layer "B.Cu")
		(net "A_HSC_LOW")
	)
	(segment
		(start 183.294528 -426.887132)
		(end 183.294528 -426.074332)
		(width 0.10668)
		(layer "B.Cu")
		(net "A_HSC_LOW")
	)
	(segment
		(start 182.760112 -426.887132)
		(end 183.294528 -426.887132)
		(width 0.10668)
		(layer "B.Cu")
		(net "A_HSC_LOW")
	)
	(via
		(at 182.46344 -423.215562)
		(size 0.6604)
		(drill 0.3302)
		(layers "F.Cu" "B.Cu")
		(net "A_HSC_HIGH")
	)
	(segment
		(start 180.478176 -425.16552)
		(end 181.705504 -425.16552)
		(width 0.10668)
		(layer "B.Cu")
		(net "A_HSC_HIGH")
	)
	(segment
		(start 180.112924 -424.085004)
		(end 180.112924 -424.800268)
		(width 0.10668)
		(layer "B.Cu")
		(net "A_HSC_HIGH")
	)
	(segment
		(start 180.112924 -424.800268)
		(end 180.478176 -425.16552)
		(width 0.10668)
		(layer "B.Cu")
		(net "A_HSC_HIGH")
	)
	(segment
		(start 182.46344 -422.41851)
		(end 182.308246 -422.263316)
		(width 0.10668)
		(layer "B.Cu")
		(net "A_HSC_HIGH")
	)
	(segment
		(start 182.46344 -423.215562)
		(end 182.46344 -423.876724)
		(width 0.10668)
		(layer "B.Cu")
		(net "A_HSC_HIGH")
	)
	(segment
		(start 182.46344 -423.215562)
		(end 182.46344 -422.41851)
		(width 0.10668)
		(layer "B.Cu")
		(net "A_HSC_HIGH")
	)
	(segment
		(start 182.480204 -423.893488)
		(end 182.480204 -424.39082)
		(width 0.10668)
		(layer "B.Cu")
		(net "A_HSC_HIGH")
	)
	(segment
		(start 181.705504 -425.16552)
		(end 182.480204 -424.39082)
		(width 0.10668)
		(layer "B.Cu")
		(net "A_HSC_HIGH")
	)
	(segment
		(start 182.46344 -423.876724)
		(end 182.480204 -423.893488)
		(width 0.10668)
		(layer "B.Cu")
		(net "A_HSC_HIGH")
	)
	(segment
		(start 182.308246 -422.263316)
		(end 182.308246 -421.775636)
		(width 0.10668)
		(layer "B.Cu")
		(net "A_HSC_HIGH")
	)
	(via
		(at 239.395 -235.331)
		(size 0.6604)
		(drill 0.3302)
		(layers "F.Cu" "B.Cu")
		(net "SMB_CPU0_SEC_R_SDA")
	)
	(segment
		(start 239.395 -235.331)
		(end 239.395 -234.46105)
		(width 0.10668)
		(layer "B.Cu")
		(net "SMB_CPU0_SEC_R_SDA")
	)
	(segment
		(start 240.411 -234.46105)
		(end 239.395 -234.46105)
		(width 0.10668)
		(layer "B.Cu")
		(net "SMB_CPU0_SEC_R_SDA")
	)
	(segment
		(start 238.919512 -236.590586)
		(end 238.919512 -235.806488)
		(width 0.10668)
		(layer "B.Cu")
		(net "SMB_CPU0_SEC_R_SDA")
	)
	(segment
		(start 238.919512 -235.806488)
		(end 239.395 -235.331)
		(width 0.10668)
		(layer "B.Cu")
		(net "SMB_CPU0_SEC_R_SDA")
	)
	(segment
		(start 25.331166 -73.614788)
		(end 29.214064 -73.614788)
		(width 0.10668)
		(layer "F.Cu")
		(net "PU_U212_EN_N")
	)
	(segment
		(start 29.214064 -73.614788)
		(end 29.214064 -74.833988)
		(width 0.10668)
		(layer "F.Cu")
		(net "PU_U212_EN_N")
	)
	(via
		(at 29.214064 -73.614788)
		(size 0.762)
		(drill 0.381)
		(layers "F.Cu" "B.Cu")
		(net "PU_U212_EN_N")
	)
	(segment
		(start 25.331166 -78.805024)
		(end 29.214064 -78.805024)
		(width 0.10668)
		(layer "F.Cu")
		(net "PU_U160_EN_N")
	)
	(segment
		(start 29.214064 -78.805024)
		(end 29.214064 -80.024224)
		(width 0.10668)
		(layer "F.Cu")
		(net "PU_U160_EN_N")
	)
	(via
		(at 29.214064 -78.805024)
		(size 0.762)
		(drill 0.381)
		(layers "F.Cu" "B.Cu")
		(net "PU_U160_EN_N")
	)
	(segment
		(start 20.251166 -73.614788)
		(end 21.852636 -72.013318)
		(width 0.10668)
		(layer "F.Cu")
		(net "PD_U212_EN_N")
	)
	(segment
		(start 21.852636 -72.013318)
		(end 28.882594 -72.013318)
		(width 0.10668)
		(layer "F.Cu")
		(net "PD_U212_EN_N")
	)
	(segment
		(start 28.882594 -72.013318)
		(end 30.484064 -73.614788)
		(width 0.10668)
		(layer "F.Cu")
		(net "PD_U212_EN_N")
	)
	(segment
		(start 30.484064 -73.614788)
		(end 30.484064 -74.833988)
		(width 0.10668)
		(layer "F.Cu")
		(net "PD_U212_EN_N")
	)
	(via
		(at 30.484064 -73.614788)
		(size 0.762)
		(drill 0.381)
		(layers "F.Cu" "B.Cu")
		(net "PD_U212_EN_N")
	)
	(segment
		(start 21.852636 -77.203554)
		(end 28.882594 -77.203554)
		(width 0.10668)
		(layer "F.Cu")
		(net "PD_U160_EN_N")
	)
	(segment
		(start 28.882594 -77.203554)
		(end 30.484064 -78.805024)
		(width 0.10668)
		(layer "F.Cu")
		(net "PD_U160_EN_N")
	)
	(segment
		(start 30.484064 -78.805024)
		(end 30.484064 -80.024224)
		(width 0.10668)
		(layer "F.Cu")
		(net "PD_U160_EN_N")
	)
	(segment
		(start 20.251166 -78.805024)
		(end 21.852636 -77.203554)
		(width 0.10668)
		(layer "F.Cu")
		(net "PD_U160_EN_N")
	)
	(via
		(at 30.484064 -78.805024)
		(size 0.762)
		(drill 0.381)
		(layers "F.Cu" "B.Cu")
		(net "PD_U160_EN_N")
	)
	(segment
		(start 231.76865 -184.108852)
		(end 231.76865 -166.676578)
		(width 0.10668)
		(layer "F.Cu")
		(net "FM_SEC_MUX_SEL")
	)
	(segment
		(start 165.25748 -101.596698)
		(end 165.994842 -101.596698)
		(width 0.10668)
		(layer "F.Cu")
		(net "FM_SEC_MUX_SEL")
	)
	(segment
		(start 231.51211 -187.220352)
		(end 231.51211 -184.365392)
		(width 0.10668)
		(layer "F.Cu")
		(net "FM_SEC_MUX_SEL")
	)
	(segment
		(start 234.572048 -216.972388)
		(end 232.809034 -215.209374)
		(width 0.10668)
		(layer "F.Cu")
		(net "FM_SEC_MUX_SEL")
	)
	(segment
		(start 238.68253 -227.409502)
		(end 238.68253 -223.013016)
		(width 0.10668)
		(layer "F.Cu")
		(net "FM_SEC_MUX_SEL")
	)
	(segment
		(start 165.994842 -101.596698)
		(end 166.318692 -101.920548)
		(width 0.10668)
		(layer "F.Cu")
		(net "FM_SEC_MUX_SEL")
	)
	(segment
		(start 229.85603 -203.424028)
		(end 229.85603 -191.218312)
		(width 0.10668)
		(layer "F.Cu")
		(net "FM_SEC_MUX_SEL")
	)
	(segment
		(start 169.404792 -101.920548)
		(end 169.858436 -101.920548)
		(width 0.10668)
		(layer "F.Cu")
		(net "FM_SEC_MUX_SEL")
	)
	(segment
		(start 231.51211 -184.365392)
		(end 231.76865 -184.108852)
		(width 0.10668)
		(layer "F.Cu")
		(net "FM_SEC_MUX_SEL")
	)
	(segment
		(start 170.39844 -101.998018)
		(end 170.80738 -101.998018)
		(width 0.10668)
		(layer "F.Cu")
		(net "FM_SEC_MUX_SEL")
	)
	(segment
		(start 239.90681 -238.7219)
		(end 239.90681 -231.92105)
		(width 0.10668)
		(layer "F.Cu")
		(net "FM_SEC_MUX_SEL")
	)
	(segment
		(start 169.939462 -102.001574)
		(end 170.394884 -102.001574)
		(width 0.10668)
		(layer "F.Cu")
		(net "FM_SEC_MUX_SEL")
	)
	(segment
		(start 230.679498 -165.864032)
		(end 230.193596 -166.349934)
		(width 0.10668)
		(layer "F.Cu")
		(net "FM_SEC_MUX_SEL")
	)
	(segment
		(start 232.809034 -215.209374)
		(end 229.24643 -215.209374)
		(width 0.10668)
		(layer "F.Cu")
		(net "FM_SEC_MUX_SEL")
	)
	(segment
		(start 234.572048 -218.902534)
		(end 234.572048 -216.972388)
		(width 0.10668)
		(layer "F.Cu")
		(net "FM_SEC_MUX_SEL")
	)
	(segment
		(start 229.85603 -191.218312)
		(end 231.51211 -187.220352)
		(width 0.10668)
		(layer "F.Cu")
		(net "FM_SEC_MUX_SEL")
	)
	(segment
		(start 230.956104 -165.864032)
		(end 230.679498 -165.864032)
		(width 0.10668)
		(layer "F.Cu")
		(net "FM_SEC_MUX_SEL")
	)
	(segment
		(start 164.852858 -102.00132)
		(end 165.25748 -101.596698)
		(width 0.10668)
		(layer "F.Cu")
		(net "FM_SEC_MUX_SEL")
	)
	(segment
		(start 239.611916 -231.626156)
		(end 239.611916 -228.338888)
		(width 0.10668)
		(layer "F.Cu")
		(net "FM_SEC_MUX_SEL")
	)
	(segment
		(start 166.318692 -101.920548)
		(end 169.404792 -101.920548)
		(width 0.10668)
		(layer "F.Cu")
		(net "FM_SEC_MUX_SEL")
	)
	(segment
		(start 226.715828 -206.56423)
		(end 229.85603 -203.424028)
		(width 0.10668)
		(layer "F.Cu")
		(net "FM_SEC_MUX_SEL")
	)
	(segment
		(start 170.394884 -102.001574)
		(end 170.39844 -101.998018)
		(width 0.10668)
		(layer "F.Cu")
		(net "FM_SEC_MUX_SEL")
	)
	(segment
		(start 238.68253 -223.013016)
		(end 234.572048 -218.902534)
		(width 0.10668)
		(layer "F.Cu")
		(net "FM_SEC_MUX_SEL")
	)
	(segment
		(start 169.858436 -101.920548)
		(end 169.939462 -102.001574)
		(width 0.10668)
		(layer "F.Cu")
		(net "FM_SEC_MUX_SEL")
	)
	(segment
		(start 229.24643 -215.209374)
		(end 226.715828 -212.678772)
		(width 0.10668)
		(layer "F.Cu")
		(net "FM_SEC_MUX_SEL")
	)
	(segment
		(start 239.90681 -231.92105)
		(end 239.611916 -231.626156)
		(width 0.10668)
		(layer "F.Cu")
		(net "FM_SEC_MUX_SEL")
	)
	(segment
		(start 239.611916 -228.338888)
		(end 238.68253 -227.409502)
		(width 0.10668)
		(layer "F.Cu")
		(net "FM_SEC_MUX_SEL")
	)
	(segment
		(start 226.715828 -212.678772)
		(end 226.715828 -206.56423)
		(width 0.10668)
		(layer "F.Cu")
		(net "FM_SEC_MUX_SEL")
	)
	(segment
		(start 163.99637 -102.00132)
		(end 164.852858 -102.00132)
		(width 0.10668)
		(layer "F.Cu")
		(net "FM_SEC_MUX_SEL")
	)
	(segment
		(start 231.76865 -166.676578)
		(end 230.956104 -165.864032)
		(width 0.10668)
		(layer "F.Cu")
		(net "FM_SEC_MUX_SEL")
	)
	(via
		(at 156.580078 -127.585724)
		(size 0.508)
		(drill 0.254)
		(layers "F.Cu" "B.Cu")
		(net "FM_SEC_MUX_SEL")
	)
	(via
		(at 165.994842 -101.596698)
		(size 0.508)
		(drill 0.254)
		(layers "F.Cu" "B.Cu")
		(net "FM_SEC_MUX_SEL")
	)
	(via
		(at 230.193596 -166.349934)
		(size 0.508)
		(drill 0.254)
		(layers "F.Cu" "B.Cu")
		(net "FM_SEC_MUX_SEL")
	)
	(via
		(at 239.90681 -238.7219)
		(size 0.508)
		(drill 0.254)
		(layers "F.Cu" "B.Cu")
		(net "FM_SEC_MUX_SEL")
	)
	(segment
		(start 239.419638 -238.234728)
		(end 239.90681 -238.7219)
		(width 0.10668)
		(layer "B.Cu")
		(net "FM_SEC_MUX_SEL")
	)
	(segment
		(start 239.419638 -237.870746)
		(end 239.419638 -238.234728)
		(width 0.10668)
		(layer "B.Cu")
		(net "FM_SEC_MUX_SEL")
	)
	(segment
		(start 229.970584 -166.572946)
		(end 230.193596 -166.349934)
		(width 0.11684)
		(layer "In4.Cu")
		(net "FM_SEC_MUX_SEL")
	)
	(segment
		(start 159.48533 -144.567402)
		(end 163.211002 -148.293074)
		(width 0.11684)
		(layer "In4.Cu")
		(net "FM_SEC_MUX_SEL")
	)
	(segment
		(start 211.817712 -168.756584)
		(end 227.214176 -168.756584)
		(width 0.11684)
		(layer "In4.Cu")
		(net "FM_SEC_MUX_SEL")
	)
	(segment
		(start 156.580078 -127.585724)
		(end 156.580078 -128.22682)
		(width 0.11684)
		(layer "In4.Cu")
		(net "FM_SEC_MUX_SEL")
	)
	(segment
		(start 163.211002 -148.293074)
		(end 166.567358 -148.293074)
		(width 0.11684)
		(layer "In4.Cu")
		(net "FM_SEC_MUX_SEL")
	)
	(segment
		(start 176.705006 -167.778684)
		(end 210.839812 -167.778684)
		(width 0.11684)
		(layer "In4.Cu")
		(net "FM_SEC_MUX_SEL")
	)
	(segment
		(start 170.101006 -151.826722)
		(end 170.101006 -155.15082)
		(width 0.11684)
		(layer "In4.Cu")
		(net "FM_SEC_MUX_SEL")
	)
	(segment
		(start 229.397814 -166.572946)
		(end 229.970584 -166.572946)
		(width 0.11684)
		(layer "In4.Cu")
		(net "FM_SEC_MUX_SEL")
	)
	(segment
		(start 166.567358 -148.293074)
		(end 170.101006 -151.826722)
		(width 0.11684)
		(layer "In4.Cu")
		(net "FM_SEC_MUX_SEL")
	)
	(segment
		(start 173.603666 -158.65348)
		(end 173.603666 -164.677344)
		(width 0.11684)
		(layer "In4.Cu")
		(net "FM_SEC_MUX_SEL")
	)
	(segment
		(start 156.580078 -128.22682)
		(end 159.48533 -131.132072)
		(width 0.11684)
		(layer "In4.Cu")
		(net "FM_SEC_MUX_SEL")
	)
	(segment
		(start 173.603666 -164.677344)
		(end 176.705006 -167.778684)
		(width 0.11684)
		(layer "In4.Cu")
		(net "FM_SEC_MUX_SEL")
	)
	(segment
		(start 227.214176 -168.756584)
		(end 229.397814 -166.572946)
		(width 0.11684)
		(layer "In4.Cu")
		(net "FM_SEC_MUX_SEL")
	)
	(segment
		(start 159.48533 -131.132072)
		(end 159.48533 -144.567402)
		(width 0.11684)
		(layer "In4.Cu")
		(net "FM_SEC_MUX_SEL")
	)
	(segment
		(start 210.839812 -167.778684)
		(end 211.817712 -168.756584)
		(width 0.11684)
		(layer "In4.Cu")
		(net "FM_SEC_MUX_SEL")
	)
	(segment
		(start 170.101006 -155.15082)
		(end 173.603666 -158.65348)
		(width 0.11684)
		(layer "In4.Cu")
		(net "FM_SEC_MUX_SEL")
	)
	(segment
		(start 157.462982 -124.383038)
		(end 156.670248 -123.590304)
		(width 0.11684)
		(layer "In15.Cu")
		(net "FM_SEC_MUX_SEL")
	)
	(segment
		(start 156.580078 -126.104396)
		(end 157.462982 -125.221492)
		(width 0.11684)
		(layer "In15.Cu")
		(net "FM_SEC_MUX_SEL")
	)
	(segment
		(start 156.670248 -123.590304)
		(end 156.670248 -115.697254)
		(width 0.11684)
		(layer "In15.Cu")
		(net "FM_SEC_MUX_SEL")
	)
	(segment
		(start 158.922974 -113.444528)
		(end 158.922974 -109.25683)
		(width 0.11684)
		(layer "In15.Cu")
		(net "FM_SEC_MUX_SEL")
	)
	(segment
		(start 160.50387 -105.138474)
		(end 164.045646 -101.596698)
		(width 0.11684)
		(layer "In15.Cu")
		(net "FM_SEC_MUX_SEL")
	)
	(segment
		(start 160.50387 -107.675934)
		(end 160.50387 -105.138474)
		(width 0.11684)
		(layer "In15.Cu")
		(net "FM_SEC_MUX_SEL")
	)
	(segment
		(start 156.670248 -115.697254)
		(end 158.922974 -113.444528)
		(width 0.11684)
		(layer "In15.Cu")
		(net "FM_SEC_MUX_SEL")
	)
	(segment
		(start 158.922974 -109.25683)
		(end 160.50387 -107.675934)
		(width 0.11684)
		(layer "In15.Cu")
		(net "FM_SEC_MUX_SEL")
	)
	(segment
		(start 157.462982 -125.221492)
		(end 157.462982 -124.383038)
		(width 0.11684)
		(layer "In15.Cu")
		(net "FM_SEC_MUX_SEL")
	)
	(segment
		(start 164.045646 -101.596698)
		(end 165.994842 -101.596698)
		(width 0.11684)
		(layer "In15.Cu")
		(net "FM_SEC_MUX_SEL")
	)
	(segment
		(start 156.580078 -127.585724)
		(end 156.580078 -126.104396)
		(width 0.11684)
		(layer "In15.Cu")
		(net "FM_SEC_MUX_SEL")
	)
	(segment
		(start 172.992034 -102.368604)
		(end 174.87011 -104.24668)
		(width 0.10668)
		(layer "F.Cu")
		(net "FM_SEC_MUX_R_SEL")
	)
	(segment
		(start 172.356018 -102.368604)
		(end 172.992034 -102.368604)
		(width 0.10668)
		(layer "F.Cu")
		(net "FM_SEC_MUX_R_SEL")
	)
	(segment
		(start 171.985432 -101.998018)
		(end 172.356018 -102.368604)
		(width 0.10668)
		(layer "F.Cu")
		(net "FM_SEC_MUX_R_SEL")
	)
	(segment
		(start 184.322212 -106.652822)
		(end 183.932322 -106.262932)
		(width 0.10668)
		(layer "F.Cu")
		(net "FM_SEC_MUX_R_SEL")
	)
	(segment
		(start 171.60748 -101.998018)
		(end 171.985432 -101.998018)
		(width 0.10668)
		(layer "F.Cu")
		(net "FM_SEC_MUX_R_SEL")
	)
	(segment
		(start 174.87011 -104.24668)
		(end 175.074326 -104.24668)
		(width 0.10668)
		(layer "F.Cu")
		(net "FM_SEC_MUX_R_SEL")
	)
	(via
		(at 175.074326 -104.24668)
		(size 0.508)
		(drill 0.254)
		(layers "F.Cu" "B.Cu")
		(net "FM_SEC_MUX_R_SEL")
	)
	(via
		(at 183.932322 -106.262932)
		(size 0.4572)
		(drill 0.254)
		(layers "F.Cu" "B.Cu")
		(net "FM_SEC_MUX_R_SEL")
	)
	(segment
		(start 183.805322 -104.24668)
		(end 175.074326 -104.24668)
		(width 0.11684)
		(layer "In2.Cu")
		(net "FM_SEC_MUX_R_SEL")
	)
	(segment
		(start 183.932322 -104.37368)
		(end 183.805322 -104.24668)
		(width 0.11684)
		(layer "In2.Cu")
		(net "FM_SEC_MUX_R_SEL")
	)
	(segment
		(start 183.932322 -106.262932)
		(end 183.932322 -104.37368)
		(width 0.11684)
		(layer "In2.Cu")
		(net "FM_SEC_MUX_R_SEL")
	)
	(segment
		(start 184.322212 -107.452922)
		(end 183.932322 -107.063032)
		(width 0.10668)
		(layer "F.Cu")
		(net "FM_SEC_MUX_OE_R_N")
	)
	(segment
		(start 175.056292 -104.929432)
		(end 176.351946 -104.929432)
		(width 0.10668)
		(layer "F.Cu")
		(net "FM_SEC_MUX_OE_R_N")
	)
	(segment
		(start 172.057568 -102.993952)
		(end 172.229272 -103.165656)
		(width 0.10668)
		(layer "F.Cu")
		(net "FM_SEC_MUX_OE_R_N")
	)
	(segment
		(start 171.60748 -102.993952)
		(end 172.057568 -102.993952)
		(width 0.10668)
		(layer "F.Cu")
		(net "FM_SEC_MUX_OE_R_N")
	)
	(segment
		(start 174.192946 -104.5718)
		(end 175.056292 -104.929432)
		(width 0.10668)
		(layer "F.Cu")
		(net "FM_SEC_MUX_OE_R_N")
	)
	(segment
		(start 172.229272 -103.165656)
		(end 172.786802 -103.165656)
		(width 0.10668)
		(layer "F.Cu")
		(net "FM_SEC_MUX_OE_R_N")
	)
	(segment
		(start 172.786802 -103.165656)
		(end 174.192946 -104.5718)
		(width 0.10668)
		(layer "F.Cu")
		(net "FM_SEC_MUX_OE_R_N")
	)
	(via
		(at 183.932322 -107.063032)
		(size 0.4572)
		(drill 0.254)
		(layers "F.Cu" "B.Cu")
		(net "FM_SEC_MUX_OE_R_N")
	)
	(via
		(at 176.351946 -104.929432)
		(size 0.508)
		(drill 0.254)
		(layers "F.Cu" "B.Cu")
		(net "FM_SEC_MUX_OE_R_N")
	)
	(segment
		(start 183.536844 -105.20426)
		(end 183.409844 -105.07726)
		(width 0.11684)
		(layer "In2.Cu")
		(net "FM_SEC_MUX_OE_R_N")
	)
	(segment
		(start 183.409844 -105.07726)
		(end 176.499774 -105.07726)
		(width 0.11684)
		(layer "In2.Cu")
		(net "FM_SEC_MUX_OE_R_N")
	)
	(segment
		(start 183.745632 -107.063032)
		(end 183.536844 -106.854244)
		(width 0.11684)
		(layer "In2.Cu")
		(net "FM_SEC_MUX_OE_R_N")
	)
	(segment
		(start 183.536844 -106.854244)
		(end 183.536844 -105.20426)
		(width 0.11684)
		(layer "In2.Cu")
		(net "FM_SEC_MUX_OE_R_N")
	)
	(segment
		(start 176.499774 -105.07726)
		(end 176.351946 -104.929432)
		(width 0.11684)
		(layer "In2.Cu")
		(net "FM_SEC_MUX_OE_R_N")
	)
	(segment
		(start 183.932322 -107.063032)
		(end 183.745632 -107.063032)
		(width 0.11684)
		(layer "In2.Cu")
		(net "FM_SEC_MUX_OE_R_N")
	)
	(segment
		(start 231.446832 -183.980074)
		(end 231.246172 -184.180734)
		(width 0.10668)
		(layer "F.Cu")
		(net "FM_SEC_MUX_OE_N")
	)
	(segment
		(start 230.841042 -166.399464)
		(end 231.446832 -167.005254)
		(width 0.10668)
		(layer "F.Cu")
		(net "FM_SEC_MUX_OE_N")
	)
	(segment
		(start 232.675684 -215.531192)
		(end 234.25023 -217.105738)
		(width 0.10668)
		(layer "F.Cu")
		(net "FM_SEC_MUX_OE_N")
	)
	(segment
		(start 237.583472 -234.144058)
		(end 237.583472 -238.552228)
		(width 0.10668)
		(layer "F.Cu")
		(net "FM_SEC_MUX_OE_N")
	)
	(segment
		(start 238.360712 -227.542852)
		(end 239.290098 -228.472238)
		(width 0.10668)
		(layer "F.Cu")
		(net "FM_SEC_MUX_OE_N")
	)
	(segment
		(start 238.360712 -223.146366)
		(end 238.360712 -227.542852)
		(width 0.10668)
		(layer "F.Cu")
		(net "FM_SEC_MUX_OE_N")
	)
	(segment
		(start 165.424866 -102.732332)
		(end 164.23386 -102.732332)
		(width 0.10668)
		(layer "F.Cu")
		(net "FM_SEC_MUX_OE_N")
	)
	(segment
		(start 169.38879 -102.91572)
		(end 169.467022 -102.993952)
		(width 0.10668)
		(layer "F.Cu")
		(net "FM_SEC_MUX_OE_N")
	)
	(segment
		(start 234.25023 -217.105738)
		(end 234.25023 -219.035884)
		(width 0.10668)
		(layer "F.Cu")
		(net "FM_SEC_MUX_OE_N")
	)
	(segment
		(start 237.84052 -232.03535)
		(end 237.84052 -233.88701)
		(width 0.10668)
		(layer "F.Cu")
		(net "FM_SEC_MUX_OE_N")
	)
	(segment
		(start 239.290098 -228.472238)
		(end 239.290098 -230.585772)
		(width 0.10668)
		(layer "F.Cu")
		(net "FM_SEC_MUX_OE_N")
	)
	(segment
		(start 229.63251 -203.19238)
		(end 226.39401 -206.43088)
		(width 0.10668)
		(layer "F.Cu")
		(net "FM_SEC_MUX_OE_N")
	)
	(segment
		(start 231.246172 -184.180734)
		(end 231.246172 -187.27674)
		(width 0.10668)
		(layer "F.Cu")
		(net "FM_SEC_MUX_OE_N")
	)
	(segment
		(start 164.23386 -102.732332)
		(end 163.982146 -102.984046)
		(width 0.10668)
		(layer "F.Cu")
		(net "FM_SEC_MUX_OE_N")
	)
	(segment
		(start 169.467022 -102.993952)
		(end 170.80738 -102.993952)
		(width 0.10668)
		(layer "F.Cu")
		(net "FM_SEC_MUX_OE_N")
	)
	(segment
		(start 231.246172 -187.27674)
		(end 229.63251 -191.173862)
		(width 0.10668)
		(layer "F.Cu")
		(net "FM_SEC_MUX_OE_N")
	)
	(segment
		(start 231.446832 -167.005254)
		(end 231.446832 -183.980074)
		(width 0.10668)
		(layer "F.Cu")
		(net "FM_SEC_MUX_OE_N")
	)
	(segment
		(start 169.38879 -102.91572)
		(end 165.608254 -102.91572)
		(width 0.10668)
		(layer "F.Cu")
		(net "FM_SEC_MUX_OE_N")
	)
	(segment
		(start 226.39401 -206.43088)
		(end 226.39401 -212.812122)
		(width 0.10668)
		(layer "F.Cu")
		(net "FM_SEC_MUX_OE_N")
	)
	(segment
		(start 234.25023 -219.035884)
		(end 238.360712 -223.146366)
		(width 0.10668)
		(layer "F.Cu")
		(net "FM_SEC_MUX_OE_N")
	)
	(segment
		(start 226.39401 -212.812122)
		(end 229.11308 -215.531192)
		(width 0.10668)
		(layer "F.Cu")
		(net "FM_SEC_MUX_OE_N")
	)
	(segment
		(start 229.63251 -191.173862)
		(end 229.63251 -203.19238)
		(width 0.10668)
		(layer "F.Cu")
		(net "FM_SEC_MUX_OE_N")
	)
	(segment
		(start 237.84052 -233.88701)
		(end 237.583472 -234.144058)
		(width 0.10668)
		(layer "F.Cu")
		(net "FM_SEC_MUX_OE_N")
	)
	(segment
		(start 229.11308 -215.531192)
		(end 232.675684 -215.531192)
		(width 0.10668)
		(layer "F.Cu")
		(net "FM_SEC_MUX_OE_N")
	)
	(segment
		(start 165.608254 -102.91572)
		(end 165.424866 -102.732332)
		(width 0.10668)
		(layer "F.Cu")
		(net "FM_SEC_MUX_OE_N")
	)
	(segment
		(start 239.290098 -230.585772)
		(end 237.84052 -232.03535)
		(width 0.10668)
		(layer "F.Cu")
		(net "FM_SEC_MUX_OE_N")
	)
	(via
		(at 230.841042 -166.399464)
		(size 0.508)
		(drill 0.254)
		(layers "F.Cu" "B.Cu")
		(net "FM_SEC_MUX_OE_N")
	)
	(via
		(at 157.215078 -127.585724)
		(size 0.508)
		(drill 0.254)
		(layers "F.Cu" "B.Cu")
		(net "FM_SEC_MUX_OE_N")
	)
	(via
		(at 165.424866 -102.732332)
		(size 0.508)
		(drill 0.254)
		(layers "F.Cu" "B.Cu")
		(net "FM_SEC_MUX_OE_N")
	)
	(via
		(at 237.583472 -238.552228)
		(size 0.508)
		(drill 0.254)
		(layers "F.Cu" "B.Cu")
		(net "FM_SEC_MUX_OE_N")
	)
	(segment
		(start 237.919514 -237.870746)
		(end 237.919514 -238.216186)
		(width 0.10668)
		(layer "B.Cu")
		(net "FM_SEC_MUX_OE_N")
	)
	(segment
		(start 237.919514 -238.216186)
		(end 237.583472 -238.552228)
		(width 0.10668)
		(layer "B.Cu")
		(net "FM_SEC_MUX_OE_N")
	)
	(segment
		(start 174.238666 -158.390336)
		(end 174.238666 -164.859716)
		(width 0.11684)
		(layer "In4.Cu")
		(net "FM_SEC_MUX_OE_N")
	)
	(segment
		(start 227.081588 -168.436544)
		(end 229.800404 -165.717728)
		(width 0.11684)
		(layer "In4.Cu")
		(net "FM_SEC_MUX_OE_N")
	)
	(segment
		(start 162.843464 -147.149312)
		(end 166.32174 -147.149312)
		(width 0.11684)
		(layer "In4.Cu")
		(net "FM_SEC_MUX_OE_N")
	)
	(segment
		(start 210.9724 -167.458644)
		(end 211.9503 -168.436544)
		(width 0.11684)
		(layer "In4.Cu")
		(net "FM_SEC_MUX_OE_N")
	)
	(segment
		(start 166.32174 -147.149312)
		(end 170.736006 -151.563578)
		(width 0.11684)
		(layer "In4.Cu")
		(net "FM_SEC_MUX_OE_N")
	)
	(segment
		(start 230.658416 -166.157148)
		(end 230.658416 -166.158418)
		(width 0.11684)
		(layer "In4.Cu")
		(net "FM_SEC_MUX_OE_N")
	)
	(segment
		(start 174.238666 -164.859716)
		(end 176.837594 -167.458644)
		(width 0.11684)
		(layer "In4.Cu")
		(net "FM_SEC_MUX_OE_N")
	)
	(segment
		(start 170.736006 -151.563578)
		(end 170.736006 -154.887676)
		(width 0.11684)
		(layer "In4.Cu")
		(net "FM_SEC_MUX_OE_N")
	)
	(segment
		(start 160.12033 -130.868928)
		(end 160.12033 -144.426178)
		(width 0.11684)
		(layer "In4.Cu")
		(net "FM_SEC_MUX_OE_N")
	)
	(segment
		(start 230.658416 -166.158418)
		(end 230.841042 -166.341044)
		(width 0.11684)
		(layer "In4.Cu")
		(net "FM_SEC_MUX_OE_N")
	)
	(segment
		(start 170.736006 -154.887676)
		(end 174.238666 -158.390336)
		(width 0.11684)
		(layer "In4.Cu")
		(net "FM_SEC_MUX_OE_N")
	)
	(segment
		(start 229.800404 -165.717728)
		(end 230.217726 -165.717728)
		(width 0.11684)
		(layer "In4.Cu")
		(net "FM_SEC_MUX_OE_N")
	)
	(segment
		(start 176.837594 -167.458644)
		(end 210.9724 -167.458644)
		(width 0.11684)
		(layer "In4.Cu")
		(net "FM_SEC_MUX_OE_N")
	)
	(segment
		(start 211.9503 -168.436544)
		(end 227.081588 -168.436544)
		(width 0.11684)
		(layer "In4.Cu")
		(net "FM_SEC_MUX_OE_N")
	)
	(segment
		(start 230.386382 -165.885114)
		(end 230.658416 -166.157148)
		(width 0.11684)
		(layer "In4.Cu")
		(net "FM_SEC_MUX_OE_N")
	)
	(segment
		(start 157.215078 -127.585724)
		(end 157.215078 -127.963676)
		(width 0.11684)
		(layer "In4.Cu")
		(net "FM_SEC_MUX_OE_N")
	)
	(segment
		(start 160.12033 -144.426178)
		(end 162.843464 -147.149312)
		(width 0.11684)
		(layer "In4.Cu")
		(net "FM_SEC_MUX_OE_N")
	)
	(segment
		(start 157.215078 -127.963676)
		(end 160.12033 -130.868928)
		(width 0.11684)
		(layer "In4.Cu")
		(net "FM_SEC_MUX_OE_N")
	)
	(segment
		(start 230.217726 -165.717728)
		(end 230.385112 -165.885114)
		(width 0.11684)
		(layer "In4.Cu")
		(net "FM_SEC_MUX_OE_N")
	)
	(segment
		(start 230.385112 -165.885114)
		(end 230.386382 -165.885114)
		(width 0.11684)
		(layer "In4.Cu")
		(net "FM_SEC_MUX_OE_N")
	)
	(segment
		(start 230.841042 -166.341044)
		(end 230.841042 -166.399464)
		(width 0.11684)
		(layer "In4.Cu")
		(net "FM_SEC_MUX_OE_N")
	)
	(segment
		(start 157.881574 -124.209556)
		(end 157.08884 -123.416822)
		(width 0.11684)
		(layer "In15.Cu")
		(net "FM_SEC_MUX_OE_N")
	)
	(segment
		(start 163.430204 -102.732332)
		(end 165.424866 -102.732332)
		(width 0.11684)
		(layer "In15.Cu")
		(net "FM_SEC_MUX_OE_N")
	)
	(segment
		(start 157.08884 -116.400834)
		(end 159.439864 -114.04981)
		(width 0.11684)
		(layer "In15.Cu")
		(net "FM_SEC_MUX_OE_N")
	)
	(segment
		(start 157.881574 -125.572266)
		(end 157.881574 -124.209556)
		(width 0.11684)
		(layer "In15.Cu")
		(net "FM_SEC_MUX_OE_N")
	)
	(segment
		(start 159.439864 -114.04981)
		(end 159.439864 -109.24667)
		(width 0.11684)
		(layer "In15.Cu")
		(net "FM_SEC_MUX_OE_N")
	)
	(segment
		(start 159.439864 -109.24667)
		(end 160.858962 -107.827572)
		(width 0.11684)
		(layer "In15.Cu")
		(net "FM_SEC_MUX_OE_N")
	)
	(segment
		(start 157.215078 -126.238762)
		(end 157.881574 -125.572266)
		(width 0.11684)
		(layer "In15.Cu")
		(net "FM_SEC_MUX_OE_N")
	)
	(segment
		(start 157.215078 -127.585724)
		(end 157.215078 -126.238762)
		(width 0.11684)
		(layer "In15.Cu")
		(net "FM_SEC_MUX_OE_N")
	)
	(segment
		(start 157.08884 -123.416822)
		(end 157.08884 -116.400834)
		(width 0.11684)
		(layer "In15.Cu")
		(net "FM_SEC_MUX_OE_N")
	)
	(segment
		(start 160.858962 -105.303574)
		(end 163.430204 -102.732332)
		(width 0.11684)
		(layer "In15.Cu")
		(net "FM_SEC_MUX_OE_N")
	)
	(segment
		(start 160.858962 -107.827572)
		(end 160.858962 -105.303574)
		(width 0.11684)
		(layer "In15.Cu")
		(net "FM_SEC_MUX_OE_N")
	)
	(segment
		(start 21.302218 -423.450258)
		(end 20.74926 -423.450258)
		(width 0.10668)
		(layer "F.Cu")
		(net "BUF2_VDD")
	)
	(segment
		(start 21.312632 -423.439844)
		(end 21.302218 -423.450258)
		(width 0.10668)
		(layer "F.Cu")
		(net "BUF2_VDD")
	)
	(segment
		(start 20.74926 -423.450258)
		(end 20.682458 -423.383456)
		(width 0.10668)
		(layer "F.Cu")
		(net "BUF2_VDD")
	)
	(segment
		(start 18.523204 -422.883584)
		(end 19.683222 -422.883584)
		(width 0.10668)
		(layer "F.Cu")
		(net "BUF2_VDD")
	)
	(segment
		(start 20.095718 -423.383456)
		(end 18.523204 -423.383456)
		(width 0.10668)
		(layer "F.Cu")
		(net "BUF2_VDD")
	)
	(segment
		(start 20.682458 -423.383456)
		(end 20.095718 -423.383456)
		(width 0.10668)
		(layer "F.Cu")
		(net "BUF2_VDD")
	)
	(segment
		(start 20.129754 -422.437052)
		(end 21.312632 -422.437052)
		(width 0.10668)
		(layer "F.Cu")
		(net "BUF2_VDD")
	)
	(segment
		(start 19.683222 -422.883584)
		(end 20.129754 -422.437052)
		(width 0.10668)
		(layer "F.Cu")
		(net "BUF2_VDD")
	)
	(segment
		(start 21.312632 -422.437052)
		(end 21.312632 -423.439844)
		(width 0.10668)
		(layer "F.Cu")
		(net "BUF2_VDD")
	)
	(via
		(at 20.095718 -423.383456)
		(size 0.762)
		(drill 0.381)
		(layers "F.Cu" "B.Cu")
		(net "BUF2_VDD")
	)
	(segment
		(start 298.307506 -375.396252)
		(end 296.43959 -377.264168)
		(width 0.10668)
		(layer "F.Cu")
		(net "SMB_P12V_HSC_SDA")
	)
	(segment
		(start 450.447918 -142.113)
		(end 452.94296 -144.608042)
		(width 0.10668)
		(layer "F.Cu")
		(net "SMB_P12V_HSC_SDA")
	)
	(segment
		(start 466.32368 -171.87672)
		(end 466.32368 -196.13372)
		(width 0.10668)
		(layer "F.Cu")
		(net "SMB_P12V_HSC_SDA")
	)
	(segment
		(start 452.94296 -164.380926)
		(end 457.662534 -169.1005)
		(width 0.10668)
		(layer "F.Cu")
		(net "SMB_P12V_HSC_SDA")
	)
	(segment
		(start 273.75739 -116.321586)
		(end 274.435062 -116.321586)
		(width 0.10668)
		(layer "F.Cu")
		(net "SMB_P12V_HSC_SDA")
	)
	(segment
		(start 287.236154 -378.975366)
		(end 283.849318 -378.975366)
		(width 0.10668)
		(layer "F.Cu")
		(net "SMB_P12V_HSC_SDA")
	)
	(segment
		(start 349.372936 -375.396252)
		(end 298.307506 -375.396252)
		(width 0.10668)
		(layer "F.Cu")
		(net "SMB_P12V_HSC_SDA")
	)
	(segment
		(start 449.082414 -141.360398)
		(end 449.082414 -141.617446)
		(width 0.10668)
		(layer "F.Cu")
		(net "SMB_P12V_HSC_SDA")
	)
	(segment
		(start 281.55646 -387.291834)
		(end 282.185364 -387.920738)
		(width 0.10668)
		(layer "F.Cu")
		(net "SMB_P12V_HSC_SDA")
	)
	(segment
		(start 354.266246 -370.502942)
		(end 349.372936 -375.396252)
		(width 0.10668)
		(layer "F.Cu")
		(net "SMB_P12V_HSC_SDA")
	)
	(segment
		(start 463.54746 -169.1005)
		(end 466.32368 -171.87672)
		(width 0.10668)
		(layer "F.Cu")
		(net "SMB_P12V_HSC_SDA")
	)
	(segment
		(start 449.577968 -142.113)
		(end 450.447918 -142.113)
		(width 0.10668)
		(layer "F.Cu")
		(net "SMB_P12V_HSC_SDA")
	)
	(segment
		(start 447.19621 -343.88933)
		(end 447.19621 -362.82503)
		(width 0.10668)
		(layer "F.Cu")
		(net "SMB_P12V_HSC_SDA")
	)
	(segment
		(start 443.428374 -366.592866)
		(end 431.847752 -366.592866)
		(width 0.10668)
		(layer "F.Cu")
		(net "SMB_P12V_HSC_SDA")
	)
	(segment
		(start 282.185364 -387.920738)
		(end 282.185364 -388.552944)
		(width 0.10668)
		(layer "F.Cu")
		(net "SMB_P12V_HSC_SDA")
	)
	(segment
		(start 463.49666 -198.96074)
		(end 463.49666 -327.58888)
		(width 0.10668)
		(layer "F.Cu")
		(net "SMB_P12V_HSC_SDA")
	)
	(segment
		(start 281.55646 -381.268224)
		(end 281.55646 -387.291834)
		(width 0.10668)
		(layer "F.Cu")
		(net "SMB_P12V_HSC_SDA")
	)
	(segment
		(start 282.185364 -388.552944)
		(end 281.621738 -389.11657)
		(width 0.10668)
		(layer "F.Cu")
		(net "SMB_P12V_HSC_SDA")
	)
	(segment
		(start 449.082414 -141.617446)
		(end 449.577968 -142.113)
		(width 0.10668)
		(layer "F.Cu")
		(net "SMB_P12V_HSC_SDA")
	)
	(segment
		(start 283.849318 -378.975366)
		(end 281.55646 -381.268224)
		(width 0.10668)
		(layer "F.Cu")
		(net "SMB_P12V_HSC_SDA")
	)
	(segment
		(start 466.32368 -196.13372)
		(end 463.49666 -198.96074)
		(width 0.10668)
		(layer "F.Cu")
		(net "SMB_P12V_HSC_SDA")
	)
	(segment
		(start 281.621738 -390.09447)
		(end 281.621738 -389.11657)
		(width 0.10668)
		(layer "F.Cu")
		(net "SMB_P12V_HSC_SDA")
	)
	(segment
		(start 452.94296 -144.608042)
		(end 452.94296 -164.380926)
		(width 0.10668)
		(layer "F.Cu")
		(net "SMB_P12V_HSC_SDA")
	)
	(segment
		(start 463.49666 -327.58888)
		(end 447.19621 -343.88933)
		(width 0.10668)
		(layer "F.Cu")
		(net "SMB_P12V_HSC_SDA")
	)
	(segment
		(start 447.19621 -362.82503)
		(end 443.428374 -366.592866)
		(width 0.10668)
		(layer "F.Cu")
		(net "SMB_P12V_HSC_SDA")
	)
	(segment
		(start 457.662534 -169.1005)
		(end 463.54746 -169.1005)
		(width 0.10668)
		(layer "F.Cu")
		(net "SMB_P12V_HSC_SDA")
	)
	(segment
		(start 296.43959 -377.264168)
		(end 288.947352 -377.264168)
		(width 0.10668)
		(layer "F.Cu")
		(net "SMB_P12V_HSC_SDA")
	)
	(segment
		(start 288.947352 -377.264168)
		(end 287.236154 -378.975366)
		(width 0.10668)
		(layer "F.Cu")
		(net "SMB_P12V_HSC_SDA")
	)
	(segment
		(start 431.847752 -366.592866)
		(end 427.937676 -370.502942)
		(width 0.10668)
		(layer "F.Cu")
		(net "SMB_P12V_HSC_SDA")
	)
	(segment
		(start 427.937676 -370.502942)
		(end 354.266246 -370.502942)
		(width 0.10668)
		(layer "F.Cu")
		(net "SMB_P12V_HSC_SDA")
	)
	(via
		(at 274.435062 -116.321586)
		(size 0.508)
		(drill 0.254)
		(layers "F.Cu" "B.Cu")
		(net "SMB_P12V_HSC_SDA")
	)
	(via
		(at 449.082414 -141.360398)
		(size 0.508)
		(drill 0.254)
		(layers "F.Cu" "B.Cu")
		(net "SMB_P12V_HSC_SDA")
	)
	(segment
		(start 275.103336 -118.527576)
		(end 275.103336 -116.98986)
		(width 0.11684)
		(layer "In6.Cu")
		(net "SMB_P12V_HSC_SDA")
	)
	(segment
		(start 400.64436 -124.45492)
		(end 400.567906 -124.531374)
		(width 0.11684)
		(layer "In6.Cu")
		(net "SMB_P12V_HSC_SDA")
	)
	(segment
		(start 289.54984 -120.16994)
		(end 288.33064 -121.38914)
		(width 0.11684)
		(layer "In6.Cu")
		(net "SMB_P12V_HSC_SDA")
	)
	(segment
		(start 449.082414 -141.360398)
		(end 432.176936 -124.45492)
		(width 0.11684)
		(layer "In6.Cu")
		(net "SMB_P12V_HSC_SDA")
	)
	(segment
		(start 312.65622 -120.1039)
		(end 312.08726 -119.53494)
		(width 0.11684)
		(layer "In6.Cu")
		(net "SMB_P12V_HSC_SDA")
	)
	(segment
		(start 295.71696 -120.16994)
		(end 289.54984 -120.16994)
		(width 0.11684)
		(layer "In6.Cu")
		(net "SMB_P12V_HSC_SDA")
	)
	(segment
		(start 306.051712 -120.884188)
		(end 296.431208 -120.884188)
		(width 0.11684)
		(layer "In6.Cu")
		(net "SMB_P12V_HSC_SDA")
	)
	(segment
		(start 369.998498 -118.157498)
		(end 321.024758 -118.157498)
		(width 0.11684)
		(layer "In6.Cu")
		(net "SMB_P12V_HSC_SDA")
	)
	(segment
		(start 376.372374 -124.531374)
		(end 369.998498 -118.157498)
		(width 0.11684)
		(layer "In6.Cu")
		(net "SMB_P12V_HSC_SDA")
	)
	(segment
		(start 319.078356 -120.1039)
		(end 312.65622 -120.1039)
		(width 0.11684)
		(layer "In6.Cu")
		(net "SMB_P12V_HSC_SDA")
	)
	(segment
		(start 432.176936 -124.45492)
		(end 400.64436 -124.45492)
		(width 0.11684)
		(layer "In6.Cu")
		(net "SMB_P12V_HSC_SDA")
	)
	(segment
		(start 286.14624 -121.38914)
		(end 284.62732 -119.87022)
		(width 0.11684)
		(layer "In6.Cu")
		(net "SMB_P12V_HSC_SDA")
	)
	(segment
		(start 321.024758 -118.157498)
		(end 319.078356 -120.1039)
		(width 0.11684)
		(layer "In6.Cu")
		(net "SMB_P12V_HSC_SDA")
	)
	(segment
		(start 296.431208 -120.884188)
		(end 295.71696 -120.16994)
		(width 0.11684)
		(layer "In6.Cu")
		(net "SMB_P12V_HSC_SDA")
	)
	(segment
		(start 307.40096 -119.53494)
		(end 306.051712 -120.884188)
		(width 0.11684)
		(layer "In6.Cu")
		(net "SMB_P12V_HSC_SDA")
	)
	(segment
		(start 312.08726 -119.53494)
		(end 307.40096 -119.53494)
		(width 0.11684)
		(layer "In6.Cu")
		(net "SMB_P12V_HSC_SDA")
	)
	(segment
		(start 288.33064 -121.38914)
		(end 286.14624 -121.38914)
		(width 0.11684)
		(layer "In6.Cu")
		(net "SMB_P12V_HSC_SDA")
	)
	(segment
		(start 284.62732 -119.87022)
		(end 276.44598 -119.87022)
		(width 0.11684)
		(layer "In6.Cu")
		(net "SMB_P12V_HSC_SDA")
	)
	(segment
		(start 400.567906 -124.531374)
		(end 376.372374 -124.531374)
		(width 0.11684)
		(layer "In6.Cu")
		(net "SMB_P12V_HSC_SDA")
	)
	(segment
		(start 276.44598 -119.87022)
		(end 275.103336 -118.527576)
		(width 0.11684)
		(layer "In6.Cu")
		(net "SMB_P12V_HSC_SDA")
	)
	(segment
		(start 275.103336 -116.98986)
		(end 274.435062 -116.321586)
		(width 0.11684)
		(layer "In6.Cu")
		(net "SMB_P12V_HSC_SDA")
	)
	(segment
		(start 354.415852 -370.863622)
		(end 349.522542 -375.756932)
		(width 0.10668)
		(layer "F.Cu")
		(net "SMB_P12V_HSC_SCL")
	)
	(segment
		(start 428.087282 -370.863622)
		(end 354.415852 -370.863622)
		(width 0.10668)
		(layer "F.Cu")
		(net "SMB_P12V_HSC_SCL")
	)
	(segment
		(start 283.112718 -389.96747)
		(end 282.985718 -390.09447)
		(width 0.10668)
		(layer "F.Cu")
		(net "SMB_P12V_HSC_SCL")
	)
	(segment
		(start 463.697066 -168.73982)
		(end 466.68436 -171.727114)
		(width 0.10668)
		(layer "F.Cu")
		(net "SMB_P12V_HSC_SCL")
	)
	(segment
		(start 453.30364 -164.23132)
		(end 457.81214 -168.73982)
		(width 0.10668)
		(layer "F.Cu")
		(net "SMB_P12V_HSC_SCL")
	)
	(segment
		(start 463.85734 -199.110346)
		(end 463.85734 -327.738486)
		(width 0.10668)
		(layer "F.Cu")
		(net "SMB_P12V_HSC_SCL")
	)
	(segment
		(start 289.088576 -377.604528)
		(end 287.377378 -379.315726)
		(width 0.10668)
		(layer "F.Cu")
		(net "SMB_P12V_HSC_SCL")
	)
	(segment
		(start 443.57798 -366.953546)
		(end 431.997358 -366.953546)
		(width 0.10668)
		(layer "F.Cu")
		(net "SMB_P12V_HSC_SCL")
	)
	(segment
		(start 447.55689 -362.974636)
		(end 443.57798 -366.953546)
		(width 0.10668)
		(layer "F.Cu")
		(net "SMB_P12V_HSC_SCL")
	)
	(segment
		(start 298.428664 -375.756932)
		(end 296.581068 -377.604528)
		(width 0.10668)
		(layer "F.Cu")
		(net "SMB_P12V_HSC_SCL")
	)
	(segment
		(start 431.997358 -366.953546)
		(end 428.087282 -370.863622)
		(width 0.10668)
		(layer "F.Cu")
		(net "SMB_P12V_HSC_SCL")
	)
	(segment
		(start 273.546316 -117.48135)
		(end 273.779742 -117.714776)
		(width 0.10668)
		(layer "F.Cu")
		(net "SMB_P12V_HSC_SCL")
	)
	(segment
		(start 457.81214 -168.73982)
		(end 463.697066 -168.73982)
		(width 0.10668)
		(layer "F.Cu")
		(net "SMB_P12V_HSC_SCL")
	)
	(segment
		(start 466.68436 -196.283326)
		(end 463.85734 -199.110346)
		(width 0.10668)
		(layer "F.Cu")
		(net "SMB_P12V_HSC_SCL")
	)
	(segment
		(start 282.551378 -388.55523)
		(end 283.112718 -389.11657)
		(width 0.10668)
		(layer "F.Cu")
		(net "SMB_P12V_HSC_SCL")
	)
	(segment
		(start 283.112718 -389.11657)
		(end 283.112718 -389.96747)
		(width 0.10668)
		(layer "F.Cu")
		(net "SMB_P12V_HSC_SCL")
	)
	(segment
		(start 284.048454 -379.315726)
		(end 281.97048 -381.3937)
		(width 0.10668)
		(layer "F.Cu")
		(net "SMB_P12V_HSC_SCL")
	)
	(segment
		(start 281.97048 -381.3937)
		(end 281.97048 -387.126734)
		(width 0.10668)
		(layer "F.Cu")
		(net "SMB_P12V_HSC_SCL")
	)
	(segment
		(start 463.85734 -327.738486)
		(end 447.55689 -344.038936)
		(width 0.10668)
		(layer "F.Cu")
		(net "SMB_P12V_HSC_SCL")
	)
	(segment
		(start 450.586602 -141.614398)
		(end 453.30364 -144.331436)
		(width 0.10668)
		(layer "F.Cu")
		(net "SMB_P12V_HSC_SCL")
	)
	(segment
		(start 287.377378 -379.315726)
		(end 284.048454 -379.315726)
		(width 0.10668)
		(layer "F.Cu")
		(net "SMB_P12V_HSC_SCL")
	)
	(segment
		(start 271.492726 -117.48135)
		(end 273.546316 -117.48135)
		(width 0.10668)
		(layer "F.Cu")
		(net "SMB_P12V_HSC_SCL")
	)
	(segment
		(start 466.68436 -171.727114)
		(end 466.68436 -196.283326)
		(width 0.10668)
		(layer "F.Cu")
		(net "SMB_P12V_HSC_SCL")
	)
	(segment
		(start 296.581068 -377.604528)
		(end 289.088576 -377.604528)
		(width 0.10668)
		(layer "F.Cu")
		(net "SMB_P12V_HSC_SCL")
	)
	(segment
		(start 281.97048 -387.126734)
		(end 282.551378 -387.707632)
		(width 0.10668)
		(layer "F.Cu")
		(net "SMB_P12V_HSC_SCL")
	)
	(segment
		(start 349.522542 -375.756932)
		(end 298.428664 -375.756932)
		(width 0.10668)
		(layer "F.Cu")
		(net "SMB_P12V_HSC_SCL")
	)
	(segment
		(start 447.55689 -344.038936)
		(end 447.55689 -362.974636)
		(width 0.10668)
		(layer "F.Cu")
		(net "SMB_P12V_HSC_SCL")
	)
	(segment
		(start 282.551378 -387.707632)
		(end 282.551378 -388.55523)
		(width 0.10668)
		(layer "F.Cu")
		(net "SMB_P12V_HSC_SCL")
	)
	(segment
		(start 453.30364 -144.331436)
		(end 453.30364 -164.23132)
		(width 0.10668)
		(layer "F.Cu")
		(net "SMB_P12V_HSC_SCL")
	)
	(via
		(at 450.586602 -141.614398)
		(size 0.508)
		(drill 0.254)
		(layers "F.Cu" "B.Cu")
		(net "SMB_P12V_HSC_SCL")
	)
	(via
		(at 273.779742 -117.714776)
		(size 0.508)
		(drill 0.254)
		(layers "F.Cu" "B.Cu")
		(net "SMB_P12V_HSC_SCL")
	)
	(segment
		(start 321.19951 -118.579138)
		(end 369.785138 -118.579138)
		(width 0.11684)
		(layer "In6.Cu")
		(net "SMB_P12V_HSC_SCL")
	)
	(segment
		(start 295.542208 -120.59158)
		(end 296.256456 -121.305828)
		(width 0.11684)
		(layer "In6.Cu")
		(net "SMB_P12V_HSC_SCL")
	)
	(segment
		(start 400.742658 -124.953014)
		(end 400.819112 -124.87656)
		(width 0.11684)
		(layer "In6.Cu")
		(net "SMB_P12V_HSC_SCL")
	)
	(segment
		(start 284.452568 -120.29186)
		(end 285.971488 -121.81078)
		(width 0.11684)
		(layer "In6.Cu")
		(net "SMB_P12V_HSC_SCL")
	)
	(segment
		(start 296.256456 -121.305828)
		(end 306.226464 -121.305828)
		(width 0.11684)
		(layer "In6.Cu")
		(net "SMB_P12V_HSC_SCL")
	)
	(segment
		(start 285.971488 -121.81078)
		(end 288.505392 -121.81078)
		(width 0.11684)
		(layer "In6.Cu")
		(net "SMB_P12V_HSC_SCL")
	)
	(segment
		(start 449.961 -142.24)
		(end 450.586602 -141.614398)
		(width 0.11684)
		(layer "In6.Cu")
		(net "SMB_P12V_HSC_SCL")
	)
	(segment
		(start 369.785138 -118.579138)
		(end 376.159014 -124.953014)
		(width 0.11684)
		(layer "In6.Cu")
		(net "SMB_P12V_HSC_SCL")
	)
	(segment
		(start 430.31156 -124.87656)
		(end 447.675 -142.24)
		(width 0.11684)
		(layer "In6.Cu")
		(net "SMB_P12V_HSC_SCL")
	)
	(segment
		(start 276.25548 -120.29186)
		(end 284.452568 -120.29186)
		(width 0.11684)
		(layer "In6.Cu")
		(net "SMB_P12V_HSC_SCL")
	)
	(segment
		(start 274.307808 -119.177816)
		(end 275.141436 -119.177816)
		(width 0.11684)
		(layer "In6.Cu")
		(net "SMB_P12V_HSC_SCL")
	)
	(segment
		(start 289.724592 -120.59158)
		(end 295.542208 -120.59158)
		(width 0.11684)
		(layer "In6.Cu")
		(net "SMB_P12V_HSC_SCL")
	)
	(segment
		(start 447.675 -142.24)
		(end 449.961 -142.24)
		(width 0.11684)
		(layer "In6.Cu")
		(net "SMB_P12V_HSC_SCL")
	)
	(segment
		(start 273.779742 -118.64975)
		(end 274.307808 -119.177816)
		(width 0.11684)
		(layer "In6.Cu")
		(net "SMB_P12V_HSC_SCL")
	)
	(segment
		(start 376.159014 -124.953014)
		(end 400.742658 -124.953014)
		(width 0.11684)
		(layer "In6.Cu")
		(net "SMB_P12V_HSC_SCL")
	)
	(segment
		(start 306.226464 -121.305828)
		(end 307.575712 -119.95658)
		(width 0.11684)
		(layer "In6.Cu")
		(net "SMB_P12V_HSC_SCL")
	)
	(segment
		(start 273.779742 -117.714776)
		(end 273.779742 -118.64975)
		(width 0.11684)
		(layer "In6.Cu")
		(net "SMB_P12V_HSC_SCL")
	)
	(segment
		(start 288.505392 -121.81078)
		(end 289.724592 -120.59158)
		(width 0.11684)
		(layer "In6.Cu")
		(net "SMB_P12V_HSC_SCL")
	)
	(segment
		(start 400.819112 -124.87656)
		(end 430.31156 -124.87656)
		(width 0.11684)
		(layer "In6.Cu")
		(net "SMB_P12V_HSC_SCL")
	)
	(segment
		(start 318.67348 -121.105168)
		(end 321.19951 -118.579138)
		(width 0.11684)
		(layer "In6.Cu")
		(net "SMB_P12V_HSC_SCL")
	)
	(segment
		(start 311.912508 -119.95658)
		(end 313.061096 -121.105168)
		(width 0.11684)
		(layer "In6.Cu")
		(net "SMB_P12V_HSC_SCL")
	)
	(segment
		(start 275.141436 -119.177816)
		(end 276.25548 -120.29186)
		(width 0.11684)
		(layer "In6.Cu")
		(net "SMB_P12V_HSC_SCL")
	)
	(segment
		(start 307.575712 -119.95658)
		(end 311.912508 -119.95658)
		(width 0.11684)
		(layer "In6.Cu")
		(net "SMB_P12V_HSC_SCL")
	)
	(segment
		(start 313.061096 -121.105168)
		(end 318.67348 -121.105168)
		(width 0.11684)
		(layer "In6.Cu")
		(net "SMB_P12V_HSC_SCL")
	)
	(segment
		(start 16.87322 -425.337224)
		(end 17.840198 -426.304202)
		(width 0.10668)
		(layer "F.Cu")
		(net "PD_P2E_BUF2_ENSMB")
	)
	(segment
		(start 17.840198 -426.304202)
		(end 17.952212 -426.304202)
		(width 0.10668)
		(layer "F.Cu")
		(net "PD_P2E_BUF2_ENSMB")
	)
	(segment
		(start 16.87322 -425.03344)
		(end 16.87322 -425.337224)
		(width 0.10668)
		(layer "F.Cu")
		(net "PD_P2E_BUF2_ENSMB")
	)
	(segment
		(start 17.952212 -426.304202)
		(end 18.828258 -427.180248)
		(width 0.10668)
		(layer "F.Cu")
		(net "PD_P2E_BUF2_ENSMB")
	)
	(via
		(at 17.840198 -426.304202)
		(size 0.762)
		(drill 0.381)
		(layers "F.Cu" "B.Cu")
		(net "PD_P2E_BUF2_ENSMB")
	)
	(segment
		(start 19.6977 -424.664632)
		(end 19.327876 -424.294808)
		(width 0.12954)
		(layer "F.Cu")
		(net "P2E_MB_BMC_TX_C_R2_DP<0>")
	)
	(segment
		(start 21.034248 -425.057824)
		(end 20.641056 -424.664632)
		(width 0.12954)
		(layer "F.Cu")
		(net "P2E_MB_BMC_TX_C_R2_DP<0>")
	)
	(segment
		(start 40.796972 -422.06037)
		(end 41.21023 -422.473628)
		(width 0.12954)
		(layer "F.Cu")
		(net "P2E_MB_BMC_TX_C_R2_DP<0>")
	)
	(segment
		(start 40.109394 -422.06037)
		(end 40.796972 -422.06037)
		(width 0.12954)
		(layer "F.Cu")
		(net "P2E_MB_BMC_TX_C_R2_DP<0>")
	)
	(segment
		(start 18.835624 -424.294808)
		(end 18.746978 -424.383454)
		(width 0.12954)
		(layer "F.Cu")
		(net "P2E_MB_BMC_TX_C_R2_DP<0>")
	)
	(segment
		(start 41.755314 -422.473628)
		(end 42.034714 -422.194228)
		(width 0.12954)
		(layer "F.Cu")
		(net "P2E_MB_BMC_TX_C_R2_DP<0>")
	)
	(segment
		(start 22.324314 -425.328334)
		(end 22.053804 -425.057824)
		(width 0.12954)
		(layer "F.Cu")
		(net "P2E_MB_BMC_TX_C_R2_DP<0>")
	)
	(segment
		(start 41.21023 -422.473628)
		(end 41.755314 -422.473628)
		(width 0.12954)
		(layer "F.Cu")
		(net "P2E_MB_BMC_TX_C_R2_DP<0>")
	)
	(segment
		(start 18.746978 -424.383454)
		(end 18.523204 -424.383454)
		(width 0.12954)
		(layer "F.Cu")
		(net "P2E_MB_BMC_TX_C_R2_DP<0>")
	)
	(segment
		(start 22.053804 -425.057824)
		(end 21.034248 -425.057824)
		(width 0.12954)
		(layer "F.Cu")
		(net "P2E_MB_BMC_TX_C_R2_DP<0>")
	)
	(segment
		(start 20.641056 -424.664632)
		(end 19.6977 -424.664632)
		(width 0.12954)
		(layer "F.Cu")
		(net "P2E_MB_BMC_TX_C_R2_DP<0>")
	)
	(segment
		(start 19.327876 -424.294808)
		(end 18.835624 -424.294808)
		(width 0.12954)
		(layer "F.Cu")
		(net "P2E_MB_BMC_TX_C_R2_DP<0>")
	)
	(via
		(at 22.324314 -425.328334)
		(size 0.508)
		(drill 0.254)
		(layers "F.Cu" "B.Cu")
		(net "P2E_MB_BMC_TX_C_R2_DP<0>")
	)
	(via
		(at 42.034714 -422.194228)
		(size 0.508)
		(drill 0.254)
		(layers "F.Cu" "B.Cu")
		(net "P2E_MB_BMC_TX_C_R2_DP<0>")
	)
	(segment
		(start 37.264594 -420.7637)
		(end 36.875974 -420.7637)
		(width 0.12954)
		(layer "B.Cu")
		(net "P2E_MB_BMC_TX_C_R2_DP<0>")
	)
	(segment
		(start 39.184834 -420.76624)
		(end 38.994334 -420.57574)
		(width 0.12954)
		(layer "B.Cu")
		(net "P2E_MB_BMC_TX_C_R2_DP<0>")
	)
	(segment
		(start 38.994334 -420.57574)
		(end 38.605714 -420.57574)
		(width 0.12954)
		(layer "B.Cu")
		(net "P2E_MB_BMC_TX_C_R2_DP<0>")
	)
	(segment
		(start 41.604438 -420.57574)
		(end 41.08958 -420.57574)
		(width 0.12954)
		(layer "B.Cu")
		(net "P2E_MB_BMC_TX_C_R2_DP<0>")
	)
	(segment
		(start 42.305224 -422.464738)
		(end 42.602404 -422.464738)
		(width 0.12954)
		(layer "B.Cu")
		(net "P2E_MB_BMC_TX_C_R2_DP<0>")
	)
	(segment
		(start 42.51579 -421.487092)
		(end 42.24655 -421.487092)
		(width 0.12954)
		(layer "B.Cu")
		(net "P2E_MB_BMC_TX_C_R2_DP<0>")
	)
	(segment
		(start 23.701756 -423.572432)
		(end 23.892256 -423.762932)
		(width 0.12954)
		(layer "B.Cu")
		(net "P2E_MB_BMC_TX_C_R2_DP<0>")
	)
	(segment
		(start 40.89908 -420.76624)
		(end 40.51046 -420.76624)
		(width 0.12954)
		(layer "B.Cu")
		(net "P2E_MB_BMC_TX_C_R2_DP<0>")
	)
	(segment
		(start 23.892256 -422.993312)
		(end 23.701756 -423.183812)
		(width 0.12954)
		(layer "B.Cu")
		(net "P2E_MB_BMC_TX_C_R2_DP<0>")
	)
	(segment
		(start 23.892256 -424.151552)
		(end 23.701756 -424.342052)
		(width 0.12954)
		(layer "B.Cu")
		(net "P2E_MB_BMC_TX_C_R2_DP<0>")
	)
	(segment
		(start 38.417754 -420.7637)
		(end 38.029134 -420.7637)
		(width 0.12954)
		(layer "B.Cu")
		(net "P2E_MB_BMC_TX_C_R2_DP<0>")
	)
	(segment
		(start 23.374604 -425.057824)
		(end 22.594824 -425.057824)
		(width 0.12954)
		(layer "B.Cu")
		(net "P2E_MB_BMC_TX_C_R2_DP<0>")
	)
	(segment
		(start 42.602404 -422.464738)
		(end 42.813478 -422.253664)
		(width 0.12954)
		(layer "B.Cu")
		(net "P2E_MB_BMC_TX_C_R2_DP<0>")
	)
	(segment
		(start 23.892256 -423.762932)
		(end 23.892256 -424.151552)
		(width 0.12954)
		(layer "B.Cu")
		(net "P2E_MB_BMC_TX_C_R2_DP<0>")
	)
	(segment
		(start 42.034714 -422.194228)
		(end 42.305224 -422.464738)
		(width 0.12954)
		(layer "B.Cu")
		(net "P2E_MB_BMC_TX_C_R2_DP<0>")
	)
	(segment
		(start 42.24655 -421.487092)
		(end 41.971468 -421.21201)
		(width 0.12954)
		(layer "B.Cu")
		(net "P2E_MB_BMC_TX_C_R2_DP<0>")
	)
	(segment
		(start 41.971468 -421.21201)
		(end 41.971468 -420.94277)
		(width 0.12954)
		(layer "B.Cu")
		(net "P2E_MB_BMC_TX_C_R2_DP<0>")
	)
	(segment
		(start 23.701756 -421.401748)
		(end 23.701756 -422.414192)
		(width 0.12954)
		(layer "B.Cu")
		(net "P2E_MB_BMC_TX_C_R2_DP<0>")
	)
	(segment
		(start 23.701756 -424.730672)
		(end 23.374604 -425.057824)
		(width 0.12954)
		(layer "B.Cu")
		(net "P2E_MB_BMC_TX_C_R2_DP<0>")
	)
	(segment
		(start 23.701756 -422.414192)
		(end 23.892256 -422.604692)
		(width 0.12954)
		(layer "B.Cu")
		(net "P2E_MB_BMC_TX_C_R2_DP<0>")
	)
	(segment
		(start 41.08958 -420.57574)
		(end 40.89908 -420.76624)
		(width 0.12954)
		(layer "B.Cu")
		(net "P2E_MB_BMC_TX_C_R2_DP<0>")
	)
	(segment
		(start 24.527764 -420.57574)
		(end 23.701756 -421.401748)
		(width 0.12954)
		(layer "B.Cu")
		(net "P2E_MB_BMC_TX_C_R2_DP<0>")
	)
	(segment
		(start 42.813478 -422.253664)
		(end 42.813478 -421.78478)
		(width 0.12954)
		(layer "B.Cu")
		(net "P2E_MB_BMC_TX_C_R2_DP<0>")
	)
	(segment
		(start 36.875974 -420.7637)
		(end 36.688014 -420.57574)
		(width 0.12954)
		(layer "B.Cu")
		(net "P2E_MB_BMC_TX_C_R2_DP<0>")
	)
	(segment
		(start 22.594824 -425.057824)
		(end 22.324314 -425.328334)
		(width 0.12954)
		(layer "B.Cu")
		(net "P2E_MB_BMC_TX_C_R2_DP<0>")
	)
	(segment
		(start 38.605714 -420.57574)
		(end 38.417754 -420.7637)
		(width 0.12954)
		(layer "B.Cu")
		(net "P2E_MB_BMC_TX_C_R2_DP<0>")
	)
	(segment
		(start 42.813478 -421.78478)
		(end 42.51579 -421.487092)
		(width 0.12954)
		(layer "B.Cu")
		(net "P2E_MB_BMC_TX_C_R2_DP<0>")
	)
	(segment
		(start 39.573454 -420.76624)
		(end 39.184834 -420.76624)
		(width 0.12954)
		(layer "B.Cu")
		(net "P2E_MB_BMC_TX_C_R2_DP<0>")
	)
	(segment
		(start 37.841174 -420.57574)
		(end 37.452554 -420.57574)
		(width 0.12954)
		(layer "B.Cu")
		(net "P2E_MB_BMC_TX_C_R2_DP<0>")
	)
	(segment
		(start 40.51046 -420.76624)
		(end 40.31996 -420.57574)
		(width 0.12954)
		(layer "B.Cu")
		(net "P2E_MB_BMC_TX_C_R2_DP<0>")
	)
	(segment
		(start 39.763954 -420.57574)
		(end 39.573454 -420.76624)
		(width 0.12954)
		(layer "B.Cu")
		(net "P2E_MB_BMC_TX_C_R2_DP<0>")
	)
	(segment
		(start 23.701756 -423.183812)
		(end 23.701756 -423.572432)
		(width 0.12954)
		(layer "B.Cu")
		(net "P2E_MB_BMC_TX_C_R2_DP<0>")
	)
	(segment
		(start 41.971468 -420.94277)
		(end 41.604438 -420.57574)
		(width 0.12954)
		(layer "B.Cu")
		(net "P2E_MB_BMC_TX_C_R2_DP<0>")
	)
	(segment
		(start 37.452554 -420.57574)
		(end 37.264594 -420.7637)
		(width 0.12954)
		(layer "B.Cu")
		(net "P2E_MB_BMC_TX_C_R2_DP<0>")
	)
	(segment
		(start 38.029134 -420.7637)
		(end 37.841174 -420.57574)
		(width 0.12954)
		(layer "B.Cu")
		(net "P2E_MB_BMC_TX_C_R2_DP<0>")
	)
	(segment
		(start 36.688014 -420.57574)
		(end 24.527764 -420.57574)
		(width 0.12954)
		(layer "B.Cu")
		(net "P2E_MB_BMC_TX_C_R2_DP<0>")
	)
	(segment
		(start 40.31996 -420.57574)
		(end 39.763954 -420.57574)
		(width 0.12954)
		(layer "B.Cu")
		(net "P2E_MB_BMC_TX_C_R2_DP<0>")
	)
	(segment
		(start 23.701756 -424.342052)
		(end 23.701756 -424.730672)
		(width 0.12954)
		(layer "B.Cu")
		(net "P2E_MB_BMC_TX_C_R2_DP<0>")
	)
	(segment
		(start 23.892256 -422.604692)
		(end 23.892256 -422.993312)
		(width 0.12954)
		(layer "B.Cu")
		(net "P2E_MB_BMC_TX_C_R2_DP<0>")
	)
	(segment
		(start 20.774914 -424.342052)
		(end 19.831558 -424.342052)
		(width 0.12954)
		(layer "F.Cu")
		(net "P2E_MB_BMC_TX_C_R2_DN<0>")
	)
	(segment
		(start 21.168106 -424.735244)
		(end 20.774914 -424.342052)
		(width 0.12954)
		(layer "F.Cu")
		(net "P2E_MB_BMC_TX_C_R2_DN<0>")
	)
	(segment
		(start 40.109394 -423.21734)
		(end 40.789098 -423.21734)
		(width 0.12954)
		(layer "F.Cu")
		(net "P2E_MB_BMC_TX_C_R2_DN<0>")
	)
	(segment
		(start 19.831558 -424.342052)
		(end 19.461734 -423.972228)
		(width 0.12954)
		(layer "F.Cu")
		(net "P2E_MB_BMC_TX_C_R2_DN<0>")
	)
	(segment
		(start 41.21023 -422.796208)
		(end 41.773094 -422.796208)
		(width 0.12954)
		(layer "F.Cu")
		(net "P2E_MB_BMC_TX_C_R2_DN<0>")
	)
	(segment
		(start 41.773094 -422.796208)
		(end 42.034714 -423.057828)
		(width 0.12954)
		(layer "F.Cu")
		(net "P2E_MB_BMC_TX_C_R2_DN<0>")
	)
	(segment
		(start 19.461734 -423.972228)
		(end 18.796 -423.972228)
		(width 0.12954)
		(layer "F.Cu")
		(net "P2E_MB_BMC_TX_C_R2_DN<0>")
	)
	(segment
		(start 18.796 -423.972228)
		(end 18.707354 -423.883582)
		(width 0.12954)
		(layer "F.Cu")
		(net "P2E_MB_BMC_TX_C_R2_DN<0>")
	)
	(segment
		(start 40.789098 -423.21734)
		(end 41.21023 -422.796208)
		(width 0.12954)
		(layer "F.Cu")
		(net "P2E_MB_BMC_TX_C_R2_DN<0>")
	)
	(segment
		(start 18.707354 -423.883582)
		(end 18.523204 -423.883582)
		(width 0.12954)
		(layer "F.Cu")
		(net "P2E_MB_BMC_TX_C_R2_DN<0>")
	)
	(segment
		(start 22.053804 -424.735244)
		(end 21.168106 -424.735244)
		(width 0.12954)
		(layer "F.Cu")
		(net "P2E_MB_BMC_TX_C_R2_DN<0>")
	)
	(segment
		(start 22.324314 -424.464734)
		(end 22.053804 -424.735244)
		(width 0.12954)
		(layer "F.Cu")
		(net "P2E_MB_BMC_TX_C_R2_DN<0>")
	)
	(via
		(at 42.034714 -423.057828)
		(size 0.508)
		(drill 0.254)
		(layers "F.Cu" "B.Cu")
		(net "P2E_MB_BMC_TX_C_R2_DN<0>")
	)
	(via
		(at 22.324314 -424.464734)
		(size 0.508)
		(drill 0.254)
		(layers "F.Cu" "B.Cu")
		(net "P2E_MB_BMC_TX_C_R2_DN<0>")
	)
	(segment
		(start 23.379176 -424.596814)
		(end 23.240746 -424.735244)
		(width 0.12954)
		(layer "B.Cu")
		(net "P2E_MB_BMC_TX_C_R2_DN<0>")
	)
	(segment
		(start 22.594824 -424.735244)
		(end 22.324314 -424.464734)
		(width 0.12954)
		(layer "B.Cu")
		(net "P2E_MB_BMC_TX_C_R2_DN<0>")
	)
	(segment
		(start 43.136058 -421.650922)
		(end 41.738296 -420.25316)
		(width 0.12954)
		(layer "B.Cu")
		(net "P2E_MB_BMC_TX_C_R2_DN<0>")
	)
	(segment
		(start 23.240746 -424.735244)
		(end 22.594824 -424.735244)
		(width 0.12954)
		(layer "B.Cu")
		(net "P2E_MB_BMC_TX_C_R2_DN<0>")
	)
	(segment
		(start 43.136058 -422.387522)
		(end 43.136058 -421.650922)
		(width 0.12954)
		(layer "B.Cu")
		(net "P2E_MB_BMC_TX_C_R2_DN<0>")
	)
	(segment
		(start 24.393906 -420.25316)
		(end 23.379176 -421.26789)
		(width 0.12954)
		(layer "B.Cu")
		(net "P2E_MB_BMC_TX_C_R2_DN<0>")
	)
	(segment
		(start 42.034714 -423.057828)
		(end 42.305224 -422.787318)
		(width 0.12954)
		(layer "B.Cu")
		(net "P2E_MB_BMC_TX_C_R2_DN<0>")
	)
	(segment
		(start 42.305224 -422.787318)
		(end 42.736262 -422.787318)
		(width 0.12954)
		(layer "B.Cu")
		(net "P2E_MB_BMC_TX_C_R2_DN<0>")
	)
	(segment
		(start 23.379176 -421.26789)
		(end 23.379176 -424.596814)
		(width 0.12954)
		(layer "B.Cu")
		(net "P2E_MB_BMC_TX_C_R2_DN<0>")
	)
	(segment
		(start 42.736262 -422.787318)
		(end 43.136058 -422.387522)
		(width 0.12954)
		(layer "B.Cu")
		(net "P2E_MB_BMC_TX_C_R2_DN<0>")
	)
	(segment
		(start 41.738296 -420.25316)
		(end 24.393906 -420.25316)
		(width 0.12954)
		(layer "B.Cu")
		(net "P2E_MB_BMC_TX_C_R2_DN<0>")
	)
	(segment
		(start 35.768788 -423.31005)
		(end 35.80765 -423.348912)
		(width 0.12954)
		(layer "F.Cu")
		(net "P2E_MB_BMC_TX_C_R1_DP<0>")
	)
	(segment
		(start 36.673028 -423.348912)
		(end 37.540438 -422.481502)
		(width 0.12954)
		(layer "F.Cu")
		(net "P2E_MB_BMC_TX_C_R1_DP<0>")
	)
	(segment
		(start 35.502596 -423.31005)
		(end 35.768788 -423.31005)
		(width 0.12954)
		(layer "F.Cu")
		(net "P2E_MB_BMC_TX_C_R1_DP<0>")
	)
	(segment
		(start 37.540438 -422.481502)
		(end 37.941758 -422.481502)
		(width 0.12954)
		(layer "F.Cu")
		(net "P2E_MB_BMC_TX_C_R1_DP<0>")
	)
	(segment
		(start 38.36289 -422.06037)
		(end 39.042594 -422.06037)
		(width 0.12954)
		(layer "F.Cu")
		(net "P2E_MB_BMC_TX_C_R1_DP<0>")
	)
	(segment
		(start 35.80765 -423.348912)
		(end 36.673028 -423.348912)
		(width 0.12954)
		(layer "F.Cu")
		(net "P2E_MB_BMC_TX_C_R1_DP<0>")
	)
	(segment
		(start 37.941758 -422.481502)
		(end 38.36289 -422.06037)
		(width 0.12954)
		(layer "F.Cu")
		(net "P2E_MB_BMC_TX_C_R1_DP<0>")
	)
	(segment
		(start 35.502596 -423.7101)
		(end 35.818826 -423.7101)
		(width 0.12954)
		(layer "F.Cu")
		(net "P2E_MB_BMC_TX_C_R1_DN<0>")
	)
	(segment
		(start 38.355016 -423.21734)
		(end 39.042594 -423.21734)
		(width 0.12954)
		(layer "F.Cu")
		(net "P2E_MB_BMC_TX_C_R1_DN<0>")
	)
	(segment
		(start 36.806886 -423.671492)
		(end 37.674296 -422.804082)
		(width 0.12954)
		(layer "F.Cu")
		(net "P2E_MB_BMC_TX_C_R1_DN<0>")
	)
	(segment
		(start 37.674296 -422.804082)
		(end 37.941758 -422.804082)
		(width 0.12954)
		(layer "F.Cu")
		(net "P2E_MB_BMC_TX_C_R1_DN<0>")
	)
	(segment
		(start 37.941758 -422.804082)
		(end 38.355016 -423.21734)
		(width 0.12954)
		(layer "F.Cu")
		(net "P2E_MB_BMC_TX_C_R1_DN<0>")
	)
	(segment
		(start 35.818826 -423.7101)
		(end 35.857434 -423.671492)
		(width 0.12954)
		(layer "F.Cu")
		(net "P2E_MB_BMC_TX_C_R1_DN<0>")
	)
	(segment
		(start 35.857434 -423.671492)
		(end 36.806886 -423.671492)
		(width 0.12954)
		(layer "F.Cu")
		(net "P2E_MB_BMC_TX_C_R1_DN<0>")
	)
	(segment
		(start 14.723364 -424.383454)
		(end 14.539214 -424.383454)
		(width 0.12954)
		(layer "F.Cu")
		(net "P2E_MB_BMC_TX_BUF2_DP<0>")
	)
	(segment
		(start 13.905738 -424.577256)
		(end 13.64742 -424.577256)
		(width 0.12954)
		(layer "F.Cu")
		(net "P2E_MB_BMC_TX_BUF2_DP<0>")
	)
	(segment
		(start 27.33675 -421.069008)
		(end 26.979118 -421.069008)
		(width 0.12954)
		(layer "F.Cu")
		(net "P2E_MB_BMC_TX_BUF2_DP<0>")
	)
	(segment
		(start 11.905234 -425.387008)
		(end 11.67511 -425.617132)
		(width 0.12954)
		(layer "F.Cu")
		(net "P2E_MB_BMC_TX_BUF2_DP<0>")
	)
	(segment
		(start 10.856976 -425.617132)
		(end 10.586466 -425.887642)
		(width 0.12954)
		(layer "F.Cu")
		(net "P2E_MB_BMC_TX_BUF2_DP<0>")
	)
	(segment
		(start 14.188186 -424.294808)
		(end 13.905738 -424.577256)
		(width 0.12954)
		(layer "F.Cu")
		(net "P2E_MB_BMC_TX_BUF2_DP<0>")
	)
	(segment
		(start 11.67511 -425.617132)
		(end 10.856976 -425.617132)
		(width 0.12954)
		(layer "F.Cu")
		(net "P2E_MB_BMC_TX_BUF2_DP<0>")
	)
	(segment
		(start 13.64742 -424.577256)
		(end 12.837668 -425.387008)
		(width 0.12954)
		(layer "F.Cu")
		(net "P2E_MB_BMC_TX_BUF2_DP<0>")
	)
	(segment
		(start 25.529286 -421.537638)
		(end 25.258522 -421.266874)
		(width 0.12954)
		(layer "F.Cu")
		(net "P2E_MB_BMC_TX_BUF2_DP<0>")
	)
	(segment
		(start 14.539214 -424.383454)
		(end 14.450568 -424.294808)
		(width 0.12954)
		(layer "F.Cu")
		(net "P2E_MB_BMC_TX_BUF2_DP<0>")
	)
	(segment
		(start 14.450568 -424.294808)
		(end 14.188186 -424.294808)
		(width 0.12954)
		(layer "F.Cu")
		(net "P2E_MB_BMC_TX_BUF2_DP<0>")
	)
	(segment
		(start 12.837668 -425.387008)
		(end 11.905234 -425.387008)
		(width 0.12954)
		(layer "F.Cu")
		(net "P2E_MB_BMC_TX_BUF2_DP<0>")
	)
	(segment
		(start 26.979118 -421.069008)
		(end 26.510488 -421.537638)
		(width 0.12954)
		(layer "F.Cu")
		(net "P2E_MB_BMC_TX_BUF2_DP<0>")
	)
	(segment
		(start 26.510488 -421.537638)
		(end 25.529286 -421.537638)
		(width 0.12954)
		(layer "F.Cu")
		(net "P2E_MB_BMC_TX_BUF2_DP<0>")
	)
	(segment
		(start 12.971272 -426.787564)
		(end 13.397992 -426.787564)
		(width 0.14224)
		(layer "In15.Cu")
		(net "P2E_MB_BMC_TX_BUF2_DP<0>")
	)
	(segment
		(start 12.270232 -426.787564)
		(end 12.407392 -426.650404)
		(width 0.14224)
		(layer "In15.Cu")
		(net "P2E_MB_BMC_TX_BUF2_DP<0>")
	)
	(segment
		(start 9.915652 -426.266864)
		(end 10.436352 -426.787564)
		(width 0.14224)
		(layer "In15.Cu")
		(net "P2E_MB_BMC_TX_BUF2_DP<0>")
	)
	(segment
		(start 17.057116 -426.787564)
		(end 17.191736 -426.652944)
		(width 0.14224)
		(layer "In15.Cu")
		(net "P2E_MB_BMC_TX_BUF2_DP<0>")
	)
	(segment
		(start 21.12645 -426.787564)
		(end 22.014688 -426.787564)
		(width 0.14224)
		(layer "In15.Cu")
		(net "P2E_MB_BMC_TX_BUF2_DP<0>")
	)
	(segment
		(start 22.014688 -426.787564)
		(end 22.617176 -426.538136)
		(width 0.14224)
		(layer "In15.Cu")
		(net "P2E_MB_BMC_TX_BUF2_DP<0>")
	)
	(segment
		(start 18.179796 -426.787564)
		(end 18.314416 -426.652944)
		(width 0.14224)
		(layer "In15.Cu")
		(net "P2E_MB_BMC_TX_BUF2_DP<0>")
	)
	(segment
		(start 15.653512 -426.787564)
		(end 15.790672 -426.650404)
		(width 0.14224)
		(layer "In15.Cu")
		(net "P2E_MB_BMC_TX_BUF2_DP<0>")
	)
	(segment
		(start 10.586466 -425.887642)
		(end 10.286746 -425.587922)
		(width 0.14224)
		(layer "In15.Cu")
		(net "P2E_MB_BMC_TX_BUF2_DP<0>")
	)
	(segment
		(start 13.961872 -426.650404)
		(end 14.099032 -426.787564)
		(width 0.14224)
		(layer "In15.Cu")
		(net "P2E_MB_BMC_TX_BUF2_DP<0>")
	)
	(segment
		(start 18.741136 -426.652944)
		(end 18.875756 -426.787564)
		(width 0.14224)
		(layer "In15.Cu")
		(net "P2E_MB_BMC_TX_BUF2_DP<0>")
	)
	(segment
		(start 20.44573 -426.787564)
		(end 20.57273 -426.660564)
		(width 0.14224)
		(layer "In15.Cu")
		(net "P2E_MB_BMC_TX_BUF2_DP<0>")
	)
	(segment
		(start 22.617176 -426.538136)
		(end 22.94509 -426.209968)
		(width 0.14224)
		(layer "In15.Cu")
		(net "P2E_MB_BMC_TX_BUF2_DP<0>")
	)
	(segment
		(start 24.01951 -421.92067)
		(end 24.390858 -421.549322)
		(width 0.14224)
		(layer "In15.Cu")
		(net "P2E_MB_BMC_TX_BUF2_DP<0>")
	)
	(segment
		(start 15.790672 -426.650404)
		(end 16.217392 -426.650404)
		(width 0.14224)
		(layer "In15.Cu")
		(net "P2E_MB_BMC_TX_BUF2_DP<0>")
	)
	(segment
		(start 16.354552 -426.787564)
		(end 17.057116 -426.787564)
		(width 0.14224)
		(layer "In15.Cu")
		(net "P2E_MB_BMC_TX_BUF2_DP<0>")
	)
	(segment
		(start 23.152862 -425.380658)
		(end 23.152862 -425.380404)
		(width 0.14224)
		(layer "In15.Cu")
		(net "P2E_MB_BMC_TX_BUF2_DP<0>")
	)
	(segment
		(start 19.302476 -426.787564)
		(end 19.437096 -426.652944)
		(width 0.14224)
		(layer "In15.Cu")
		(net "P2E_MB_BMC_TX_BUF2_DP<0>")
	)
	(segment
		(start 19.863816 -426.652944)
		(end 19.998436 -426.787564)
		(width 0.14224)
		(layer "In15.Cu")
		(net "P2E_MB_BMC_TX_BUF2_DP<0>")
	)
	(segment
		(start 17.191736 -426.652944)
		(end 17.618456 -426.652944)
		(width 0.14224)
		(layer "In15.Cu")
		(net "P2E_MB_BMC_TX_BUF2_DP<0>")
	)
	(segment
		(start 12.407392 -426.650404)
		(end 12.834112 -426.650404)
		(width 0.14224)
		(layer "In15.Cu")
		(net "P2E_MB_BMC_TX_BUF2_DP<0>")
	)
	(segment
		(start 14.525752 -426.787564)
		(end 14.662912 -426.650404)
		(width 0.14224)
		(layer "In15.Cu")
		(net "P2E_MB_BMC_TX_BUF2_DP<0>")
	)
	(segment
		(start 22.94509 -426.209968)
		(end 23.152862 -425.380658)
		(width 0.14224)
		(layer "In15.Cu")
		(net "P2E_MB_BMC_TX_BUF2_DP<0>")
	)
	(segment
		(start 16.217392 -426.650404)
		(end 16.354552 -426.787564)
		(width 0.14224)
		(layer "In15.Cu")
		(net "P2E_MB_BMC_TX_BUF2_DP<0>")
	)
	(segment
		(start 10.436352 -426.787564)
		(end 12.270232 -426.787564)
		(width 0.14224)
		(layer "In15.Cu")
		(net "P2E_MB_BMC_TX_BUF2_DP<0>")
	)
	(segment
		(start 18.314416 -426.652944)
		(end 18.741136 -426.652944)
		(width 0.14224)
		(layer "In15.Cu")
		(net "P2E_MB_BMC_TX_BUF2_DP<0>")
	)
	(segment
		(start 14.099032 -426.787564)
		(end 14.525752 -426.787564)
		(width 0.14224)
		(layer "In15.Cu")
		(net "P2E_MB_BMC_TX_BUF2_DP<0>")
	)
	(segment
		(start 19.437096 -426.652944)
		(end 19.863816 -426.652944)
		(width 0.14224)
		(layer "In15.Cu")
		(net "P2E_MB_BMC_TX_BUF2_DP<0>")
	)
	(segment
		(start 23.184866 -425.25442)
		(end 24.01951 -421.92067)
		(width 0.14224)
		(layer "In15.Cu")
		(net "P2E_MB_BMC_TX_BUF2_DP<0>")
	)
	(segment
		(start 15.089632 -426.650404)
		(end 15.226792 -426.787564)
		(width 0.14224)
		(layer "In15.Cu")
		(net "P2E_MB_BMC_TX_BUF2_DP<0>")
	)
	(segment
		(start 17.753076 -426.787564)
		(end 18.179796 -426.787564)
		(width 0.14224)
		(layer "In15.Cu")
		(net "P2E_MB_BMC_TX_BUF2_DP<0>")
	)
	(segment
		(start 10.042652 -425.587922)
		(end 9.915652 -425.714922)
		(width 0.14224)
		(layer "In15.Cu")
		(net "P2E_MB_BMC_TX_BUF2_DP<0>")
	)
	(segment
		(start 23.152862 -425.380404)
		(end 23.184358 -425.254674)
		(width 0.14224)
		(layer "In15.Cu")
		(net "P2E_MB_BMC_TX_BUF2_DP<0>")
	)
	(segment
		(start 24.390858 -421.549322)
		(end 24.976074 -421.549322)
		(width 0.14224)
		(layer "In15.Cu")
		(net "P2E_MB_BMC_TX_BUF2_DP<0>")
	)
	(segment
		(start 15.226792 -426.787564)
		(end 15.653512 -426.787564)
		(width 0.14224)
		(layer "In15.Cu")
		(net "P2E_MB_BMC_TX_BUF2_DP<0>")
	)
	(segment
		(start 9.915652 -425.714922)
		(end 9.915652 -426.266864)
		(width 0.14224)
		(layer "In15.Cu")
		(net "P2E_MB_BMC_TX_BUF2_DP<0>")
	)
	(segment
		(start 19.998436 -426.787564)
		(end 20.44573 -426.787564)
		(width 0.14224)
		(layer "In15.Cu")
		(net "P2E_MB_BMC_TX_BUF2_DP<0>")
	)
	(segment
		(start 24.976074 -421.549322)
		(end 25.258522 -421.266874)
		(width 0.14224)
		(layer "In15.Cu")
		(net "P2E_MB_BMC_TX_BUF2_DP<0>")
	)
	(segment
		(start 13.535152 -426.650404)
		(end 13.961872 -426.650404)
		(width 0.14224)
		(layer "In15.Cu")
		(net "P2E_MB_BMC_TX_BUF2_DP<0>")
	)
	(segment
		(start 10.286746 -425.587922)
		(end 10.042652 -425.587922)
		(width 0.14224)
		(layer "In15.Cu")
		(net "P2E_MB_BMC_TX_BUF2_DP<0>")
	)
	(segment
		(start 23.184358 -425.254674)
		(end 23.184866 -425.25442)
		(width 0.14224)
		(layer "In15.Cu")
		(net "P2E_MB_BMC_TX_BUF2_DP<0>")
	)
	(segment
		(start 13.397992 -426.787564)
		(end 13.535152 -426.650404)
		(width 0.14224)
		(layer "In15.Cu")
		(net "P2E_MB_BMC_TX_BUF2_DP<0>")
	)
	(segment
		(start 20.99945 -426.660564)
		(end 21.12645 -426.787564)
		(width 0.14224)
		(layer "In15.Cu")
		(net "P2E_MB_BMC_TX_BUF2_DP<0>")
	)
	(segment
		(start 14.662912 -426.650404)
		(end 15.089632 -426.650404)
		(width 0.14224)
		(layer "In15.Cu")
		(net "P2E_MB_BMC_TX_BUF2_DP<0>")
	)
	(segment
		(start 12.834112 -426.650404)
		(end 12.971272 -426.787564)
		(width 0.14224)
		(layer "In15.Cu")
		(net "P2E_MB_BMC_TX_BUF2_DP<0>")
	)
	(segment
		(start 20.57273 -426.660564)
		(end 20.99945 -426.660564)
		(width 0.14224)
		(layer "In15.Cu")
		(net "P2E_MB_BMC_TX_BUF2_DP<0>")
	)
	(segment
		(start 17.618456 -426.652944)
		(end 17.753076 -426.787564)
		(width 0.14224)
		(layer "In15.Cu")
		(net "P2E_MB_BMC_TX_BUF2_DP<0>")
	)
	(segment
		(start 18.875756 -426.787564)
		(end 19.302476 -426.787564)
		(width 0.14224)
		(layer "In15.Cu")
		(net "P2E_MB_BMC_TX_BUF2_DP<0>")
	)
	(segment
		(start 14.410944 -423.972228)
		(end 14.054328 -423.972228)
		(width 0.12954)
		(layer "F.Cu")
		(net "P2E_MB_BMC_TX_BUF2_DN<0>")
	)
	(segment
		(start 25.528778 -421.860218)
		(end 25.258522 -422.130474)
		(width 0.12954)
		(layer "F.Cu")
		(net "P2E_MB_BMC_TX_BUF2_DN<0>")
	)
	(segment
		(start 14.054328 -423.972228)
		(end 13.77188 -424.254676)
		(width 0.12954)
		(layer "F.Cu")
		(net "P2E_MB_BMC_TX_BUF2_DN<0>")
	)
	(segment
		(start 26.97988 -422.330626)
		(end 26.509726 -421.860472)
		(width 0.12954)
		(layer "F.Cu")
		(net "P2E_MB_BMC_TX_BUF2_DN<0>")
	)
	(segment
		(start 14.723364 -423.883582)
		(end 14.49959 -423.883582)
		(width 0.12954)
		(layer "F.Cu")
		(net "P2E_MB_BMC_TX_BUF2_DN<0>")
	)
	(segment
		(start 11.771122 -425.064428)
		(end 11.540998 -425.294552)
		(width 0.12954)
		(layer "F.Cu")
		(net "P2E_MB_BMC_TX_BUF2_DN<0>")
	)
	(segment
		(start 13.77188 -424.254676)
		(end 13.513562 -424.254676)
		(width 0.12954)
		(layer "F.Cu")
		(net "P2E_MB_BMC_TX_BUF2_DN<0>")
	)
	(segment
		(start 26.38044 -421.860472)
		(end 26.380186 -421.860218)
		(width 0.12954)
		(layer "F.Cu")
		(net "P2E_MB_BMC_TX_BUF2_DN<0>")
	)
	(segment
		(start 13.513562 -424.254676)
		(end 12.70381 -425.064428)
		(width 0.12954)
		(layer "F.Cu")
		(net "P2E_MB_BMC_TX_BUF2_DN<0>")
	)
	(segment
		(start 26.509726 -421.860472)
		(end 26.38044 -421.860472)
		(width 0.12954)
		(layer "F.Cu")
		(net "P2E_MB_BMC_TX_BUF2_DN<0>")
	)
	(segment
		(start 12.70381 -425.064428)
		(end 11.771122 -425.064428)
		(width 0.12954)
		(layer "F.Cu")
		(net "P2E_MB_BMC_TX_BUF2_DN<0>")
	)
	(segment
		(start 26.380186 -421.860218)
		(end 25.528778 -421.860218)
		(width 0.12954)
		(layer "F.Cu")
		(net "P2E_MB_BMC_TX_BUF2_DN<0>")
	)
	(segment
		(start 10.856976 -425.294552)
		(end 10.586466 -425.024042)
		(width 0.12954)
		(layer "F.Cu")
		(net "P2E_MB_BMC_TX_BUF2_DN<0>")
	)
	(segment
		(start 27.33548 -422.330626)
		(end 26.97988 -422.330626)
		(width 0.12954)
		(layer "F.Cu")
		(net "P2E_MB_BMC_TX_BUF2_DN<0>")
	)
	(segment
		(start 14.49959 -423.883582)
		(end 14.410944 -423.972228)
		(width 0.12954)
		(layer "F.Cu")
		(net "P2E_MB_BMC_TX_BUF2_DN<0>")
	)
	(segment
		(start 11.540998 -425.294552)
		(end 10.856976 -425.294552)
		(width 0.12954)
		(layer "F.Cu")
		(net "P2E_MB_BMC_TX_BUF2_DN<0>")
	)
	(segment
		(start 23.42642 -425.448984)
		(end 23.426928 -425.44873)
		(width 0.14224)
		(layer "In15.Cu")
		(net "P2E_MB_BMC_TX_BUF2_DN<0>")
	)
	(segment
		(start 22.776942 -426.77715)
		(end 23.199852 -426.35424)
		(width 0.14224)
		(layer "In15.Cu")
		(net "P2E_MB_BMC_TX_BUF2_DN<0>")
	)
	(segment
		(start 9.633712 -425.598082)
		(end 9.633712 -426.383704)
		(width 0.14224)
		(layer "In15.Cu")
		(net "P2E_MB_BMC_TX_BUF2_DN<0>")
	)
	(segment
		(start 9.633712 -426.383704)
		(end 10.319512 -427.069504)
		(width 0.14224)
		(layer "In15.Cu")
		(net "P2E_MB_BMC_TX_BUF2_DN<0>")
	)
	(segment
		(start 10.319512 -427.069504)
		(end 22.070822 -427.069504)
		(width 0.14224)
		(layer "In15.Cu")
		(net "P2E_MB_BMC_TX_BUF2_DN<0>")
	)
	(segment
		(start 24.507952 -421.831262)
		(end 24.95931 -421.831262)
		(width 0.14224)
		(layer "In15.Cu")
		(net "P2E_MB_BMC_TX_BUF2_DN<0>")
	)
	(segment
		(start 23.199852 -426.35424)
		(end 23.42642 -425.448984)
		(width 0.14224)
		(layer "In15.Cu")
		(net "P2E_MB_BMC_TX_BUF2_DN<0>")
	)
	(segment
		(start 23.426928 -425.44873)
		(end 24.274272 -422.064942)
		(width 0.14224)
		(layer "In15.Cu")
		(net "P2E_MB_BMC_TX_BUF2_DN<0>")
	)
	(segment
		(start 9.925812 -425.305982)
		(end 9.633712 -425.598082)
		(width 0.14224)
		(layer "In15.Cu")
		(net "P2E_MB_BMC_TX_BUF2_DN<0>")
	)
	(segment
		(start 22.070822 -427.069504)
		(end 22.776942 -426.77715)
		(width 0.14224)
		(layer "In15.Cu")
		(net "P2E_MB_BMC_TX_BUF2_DN<0>")
	)
	(segment
		(start 10.304526 -425.305982)
		(end 9.925812 -425.305982)
		(width 0.14224)
		(layer "In15.Cu")
		(net "P2E_MB_BMC_TX_BUF2_DN<0>")
	)
	(segment
		(start 24.274272 -422.064942)
		(end 24.507952 -421.831262)
		(width 0.14224)
		(layer "In15.Cu")
		(net "P2E_MB_BMC_TX_BUF2_DN<0>")
	)
	(segment
		(start 10.586466 -425.024042)
		(end 10.304526 -425.305982)
		(width 0.14224)
		(layer "In15.Cu")
		(net "P2E_MB_BMC_TX_BUF2_DN<0>")
	)
	(segment
		(start 24.95931 -421.831262)
		(end 25.258522 -422.130474)
		(width 0.14224)
		(layer "In15.Cu")
		(net "P2E_MB_BMC_TX_BUF2_DN<0>")
	)
	(segment
		(start 13.7668 -421.49903)
		(end 13.197586 -420.929816)
		(width 0.12954)
		(layer "F.Cu")
		(net "P2E_MB_BMC_RX_R2_DP<0>")
	)
	(segment
		(start 26.59253 -428.755302)
		(end 26.18232 -428.345092)
		(width 0.12954)
		(layer "F.Cu")
		(net "P2E_MB_BMC_RX_R2_DP<0>")
	)
	(segment
		(start 13.7668 -421.850058)
		(end 13.7668 -421.49903)
		(width 0.12954)
		(layer "F.Cu")
		(net "P2E_MB_BMC_RX_R2_DP<0>")
	)
	(segment
		(start 13.197586 -420.929816)
		(end 10.664698 -420.929816)
		(width 0.12954)
		(layer "F.Cu")
		(net "P2E_MB_BMC_RX_R2_DP<0>")
	)
	(segment
		(start 14.478254 -422.383458)
		(end 14.389608 -422.294812)
		(width 0.12954)
		(layer "F.Cu")
		(net "P2E_MB_BMC_RX_R2_DP<0>")
	)
	(segment
		(start 10.664698 -420.929816)
		(end 10.394188 -421.200326)
		(width 0.12954)
		(layer "F.Cu")
		(net "P2E_MB_BMC_RX_R2_DP<0>")
	)
	(segment
		(start 14.211554 -422.294812)
		(end 13.7668 -421.850058)
		(width 0.12954)
		(layer "F.Cu")
		(net "P2E_MB_BMC_RX_R2_DP<0>")
	)
	(segment
		(start 25.783032 -428.345092)
		(end 25.512522 -428.615602)
		(width 0.12954)
		(layer "F.Cu")
		(net "P2E_MB_BMC_RX_R2_DP<0>")
	)
	(segment
		(start 14.723364 -422.383458)
		(end 14.478254 -422.383458)
		(width 0.12954)
		(layer "F.Cu")
		(net "P2E_MB_BMC_RX_R2_DP<0>")
	)
	(segment
		(start 14.389608 -422.294812)
		(end 14.211554 -422.294812)
		(width 0.12954)
		(layer "F.Cu")
		(net "P2E_MB_BMC_RX_R2_DP<0>")
	)
	(segment
		(start 26.18232 -428.345092)
		(end 25.783032 -428.345092)
		(width 0.12954)
		(layer "F.Cu")
		(net "P2E_MB_BMC_RX_R2_DP<0>")
	)
	(segment
		(start 27.220926 -428.755302)
		(end 26.59253 -428.755302)
		(width 0.12954)
		(layer "F.Cu")
		(net "P2E_MB_BMC_RX_R2_DP<0>")
	)
	(segment
		(start 11.205718 -421.081962)
		(end 11.038078 -420.914322)
		(width 0.14224)
		(layer "In15.Cu")
		(net "P2E_MB_BMC_RX_R2_DP<0>")
	)
	(segment
		(start 10.628884 -429.517048)
		(end 8.80872 -428.300896)
		(width 0.14224)
		(layer "In15.Cu")
		(net "P2E_MB_BMC_RX_R2_DP<0>")
	)
	(segment
		(start 11.205718 -421.889682)
		(end 11.205718 -421.081962)
		(width 0.14224)
		(layer "In15.Cu")
		(net "P2E_MB_BMC_RX_R2_DP<0>")
	)
	(segment
		(start 8.166862 -424.928538)
		(end 11.205718 -421.889682)
		(width 0.14224)
		(layer "In15.Cu")
		(net "P2E_MB_BMC_RX_R2_DP<0>")
	)
	(segment
		(start 23.401274 -429.517048)
		(end 10.628884 -429.517048)
		(width 0.14224)
		(layer "In15.Cu")
		(net "P2E_MB_BMC_RX_R2_DP<0>")
	)
	(segment
		(start 24.6126 -428.305722)
		(end 23.401274 -429.517048)
		(width 0.14224)
		(layer "In15.Cu")
		(net "P2E_MB_BMC_RX_R2_DP<0>")
	)
	(segment
		(start 11.038078 -420.914322)
		(end 10.680192 -420.914322)
		(width 0.14224)
		(layer "In15.Cu")
		(net "P2E_MB_BMC_RX_R2_DP<0>")
	)
	(segment
		(start 8.80872 -428.300896)
		(end 8.166862 -426.751242)
		(width 0.14224)
		(layer "In15.Cu")
		(net "P2E_MB_BMC_RX_R2_DP<0>")
	)
	(segment
		(start 25.512522 -428.615602)
		(end 25.202642 -428.305722)
		(width 0.14224)
		(layer "In15.Cu")
		(net "P2E_MB_BMC_RX_R2_DP<0>")
	)
	(segment
		(start 8.166862 -426.751242)
		(end 8.166862 -424.928538)
		(width 0.14224)
		(layer "In15.Cu")
		(net "P2E_MB_BMC_RX_R2_DP<0>")
	)
	(segment
		(start 25.202642 -428.305722)
		(end 24.6126 -428.305722)
		(width 0.14224)
		(layer "In15.Cu")
		(net "P2E_MB_BMC_RX_R2_DP<0>")
	)
	(segment
		(start 10.680192 -420.914322)
		(end 10.394188 -421.200326)
		(width 0.14224)
		(layer "In15.Cu")
		(net "P2E_MB_BMC_RX_R2_DP<0>")
	)
	(segment
		(start 14.428216 -421.972232)
		(end 14.345412 -421.972232)
		(width 0.12954)
		(layer "F.Cu")
		(net "P2E_MB_BMC_RX_R2_DN<0>")
	)
	(segment
		(start 14.516862 -421.883586)
		(end 14.428216 -421.972232)
		(width 0.12954)
		(layer "F.Cu")
		(net "P2E_MB_BMC_RX_R2_DN<0>")
	)
	(segment
		(start 26.59253 -427.612302)
		(end 26.217118 -427.987714)
		(width 0.12954)
		(layer "F.Cu")
		(net "P2E_MB_BMC_RX_R2_DN<0>")
	)
	(segment
		(start 14.723364 -421.883586)
		(end 14.516862 -421.883586)
		(width 0.12954)
		(layer "F.Cu")
		(net "P2E_MB_BMC_RX_R2_DN<0>")
	)
	(segment
		(start 10.664698 -420.607236)
		(end 10.394188 -420.336726)
		(width 0.12954)
		(layer "F.Cu")
		(net "P2E_MB_BMC_RX_R2_DN<0>")
	)
	(segment
		(start 14.08938 -421.7162)
		(end 14.08938 -421.365172)
		(width 0.12954)
		(layer "F.Cu")
		(net "P2E_MB_BMC_RX_R2_DN<0>")
	)
	(segment
		(start 14.345412 -421.972232)
		(end 14.08938 -421.7162)
		(width 0.12954)
		(layer "F.Cu")
		(net "P2E_MB_BMC_RX_R2_DN<0>")
	)
	(segment
		(start 25.783032 -428.022512)
		(end 25.512522 -427.752002)
		(width 0.12954)
		(layer "F.Cu")
		(net "P2E_MB_BMC_RX_R2_DN<0>")
	)
	(segment
		(start 13.331444 -420.607236)
		(end 10.664698 -420.607236)
		(width 0.12954)
		(layer "F.Cu")
		(net "P2E_MB_BMC_RX_R2_DN<0>")
	)
	(segment
		(start 26.182066 -428.022512)
		(end 25.783032 -428.022512)
		(width 0.12954)
		(layer "F.Cu")
		(net "P2E_MB_BMC_RX_R2_DN<0>")
	)
	(segment
		(start 26.216864 -427.987714)
		(end 26.182066 -428.022512)
		(width 0.12954)
		(layer "F.Cu")
		(net "P2E_MB_BMC_RX_R2_DN<0>")
	)
	(segment
		(start 26.217118 -427.987714)
		(end 26.216864 -427.987714)
		(width 0.12954)
		(layer "F.Cu")
		(net "P2E_MB_BMC_RX_R2_DN<0>")
	)
	(segment
		(start 27.220926 -427.612302)
		(end 26.59253 -427.612302)
		(width 0.12954)
		(layer "F.Cu")
		(net "P2E_MB_BMC_RX_R2_DN<0>")
	)
	(segment
		(start 14.08938 -421.365172)
		(end 13.331444 -420.607236)
		(width 0.12954)
		(layer "F.Cu")
		(net "P2E_MB_BMC_RX_R2_DN<0>")
	)
	(segment
		(start 9.036558 -428.113952)
		(end 8.448802 -426.695108)
		(width 0.14224)
		(layer "In15.Cu")
		(net "P2E_MB_BMC_RX_R2_DN<0>")
	)
	(segment
		(start 25.512522 -427.752002)
		(end 25.240742 -428.023782)
		(width 0.14224)
		(layer "In15.Cu")
		(net "P2E_MB_BMC_RX_R2_DN<0>")
	)
	(segment
		(start 23.284434 -429.235108)
		(end 10.714482 -429.235108)
		(width 0.14224)
		(layer "In15.Cu")
		(net "P2E_MB_BMC_RX_R2_DN<0>")
	)
	(segment
		(start 24.49576 -428.023782)
		(end 23.284434 -429.235108)
		(width 0.14224)
		(layer "In15.Cu")
		(net "P2E_MB_BMC_RX_R2_DN<0>")
	)
	(segment
		(start 10.689844 -420.632382)
		(end 10.394188 -420.336726)
		(width 0.14224)
		(layer "In15.Cu")
		(net "P2E_MB_BMC_RX_R2_DN<0>")
	)
	(segment
		(start 25.240742 -428.023782)
		(end 24.49576 -428.023782)
		(width 0.14224)
		(layer "In15.Cu")
		(net "P2E_MB_BMC_RX_R2_DN<0>")
	)
	(segment
		(start 8.448802 -426.695108)
		(end 8.448802 -425.045378)
		(width 0.14224)
		(layer "In15.Cu")
		(net "P2E_MB_BMC_RX_R2_DN<0>")
	)
	(segment
		(start 11.487658 -422.006522)
		(end 11.487658 -420.965122)
		(width 0.14224)
		(layer "In15.Cu")
		(net "P2E_MB_BMC_RX_R2_DN<0>")
	)
	(segment
		(start 11.487658 -420.965122)
		(end 11.154918 -420.632382)
		(width 0.14224)
		(layer "In15.Cu")
		(net "P2E_MB_BMC_RX_R2_DN<0>")
	)
	(segment
		(start 8.448802 -425.045378)
		(end 11.487658 -422.006522)
		(width 0.14224)
		(layer "In15.Cu")
		(net "P2E_MB_BMC_RX_R2_DN<0>")
	)
	(segment
		(start 11.154918 -420.632382)
		(end 10.689844 -420.632382)
		(width 0.14224)
		(layer "In15.Cu")
		(net "P2E_MB_BMC_RX_R2_DN<0>")
	)
	(segment
		(start 10.714482 -429.235108)
		(end 9.036558 -428.113952)
		(width 0.14224)
		(layer "In15.Cu")
		(net "P2E_MB_BMC_RX_R2_DN<0>")
	)
	(segment
		(start 32.026098 -426.071538)
		(end 32.748474 -426.071538)
		(width 0.12954)
		(layer "F.Cu")
		(net "P2E_MB_BMC_RX_R1_DP<0>")
	)
	(segment
		(start 32.787082 -426.110146)
		(end 33.002728 -426.110146)
		(width 0.12954)
		(layer "F.Cu")
		(net "P2E_MB_BMC_RX_R1_DP<0>")
	)
	(segment
		(start 28.929838 -428.755302)
		(end 29.346144 -428.338996)
		(width 0.12954)
		(layer "F.Cu")
		(net "P2E_MB_BMC_RX_R1_DP<0>")
	)
	(segment
		(start 28.287726 -428.755302)
		(end 28.929838 -428.755302)
		(width 0.12954)
		(layer "F.Cu")
		(net "P2E_MB_BMC_RX_R1_DP<0>")
	)
	(segment
		(start 32.748474 -426.071538)
		(end 32.787082 -426.110146)
		(width 0.12954)
		(layer "F.Cu")
		(net "P2E_MB_BMC_RX_R1_DP<0>")
	)
	(segment
		(start 29.346144 -428.338996)
		(end 29.75864 -428.338996)
		(width 0.12954)
		(layer "F.Cu")
		(net "P2E_MB_BMC_RX_R1_DP<0>")
	)
	(segment
		(start 29.75864 -428.338996)
		(end 32.026098 -426.071538)
		(width 0.12954)
		(layer "F.Cu")
		(net "P2E_MB_BMC_RX_R1_DP<0>")
	)
	(segment
		(start 28.916122 -427.612302)
		(end 29.320236 -428.016416)
		(width 0.12954)
		(layer "F.Cu")
		(net "P2E_MB_BMC_RX_R1_DN<0>")
	)
	(segment
		(start 29.624782 -428.016416)
		(end 31.89224 -425.748958)
		(width 0.12954)
		(layer "F.Cu")
		(net "P2E_MB_BMC_RX_R1_DN<0>")
	)
	(segment
		(start 32.734504 -425.710096)
		(end 33.002728 -425.710096)
		(width 0.12954)
		(layer "F.Cu")
		(net "P2E_MB_BMC_RX_R1_DN<0>")
	)
	(segment
		(start 32.695642 -425.748958)
		(end 32.734504 -425.710096)
		(width 0.12954)
		(layer "F.Cu")
		(net "P2E_MB_BMC_RX_R1_DN<0>")
	)
	(segment
		(start 28.287726 -427.612302)
		(end 28.916122 -427.612302)
		(width 0.12954)
		(layer "F.Cu")
		(net "P2E_MB_BMC_RX_R1_DN<0>")
	)
	(segment
		(start 29.320236 -428.016416)
		(end 29.624782 -428.016416)
		(width 0.12954)
		(layer "F.Cu")
		(net "P2E_MB_BMC_RX_R1_DN<0>")
	)
	(segment
		(start 31.89224 -425.748958)
		(end 32.695642 -425.748958)
		(width 0.12954)
		(layer "F.Cu")
		(net "P2E_MB_BMC_RX_R1_DN<0>")
	)
	(segment
		(start 18.835624 -422.294812)
		(end 18.746978 -422.383458)
		(width 0.12954)
		(layer "F.Cu")
		(net "P2E_MB_BMC_RX_BUF2_C_DP<0>")
	)
	(segment
		(start 41.173146 -426.075094)
		(end 41.173146 -426.071538)
		(width 0.12954)
		(layer "F.Cu")
		(net "P2E_MB_BMC_RX_BUF2_C_DP<0>")
	)
	(segment
		(start 18.746978 -422.383458)
		(end 18.523204 -422.383458)
		(width 0.12954)
		(layer "F.Cu")
		(net "P2E_MB_BMC_RX_BUF2_C_DP<0>")
	)
	(segment
		(start 41.733724 -426.071538)
		(end 41.995344 -426.333158)
		(width 0.12954)
		(layer "F.Cu")
		(net "P2E_MB_BMC_RX_BUF2_C_DP<0>")
	)
	(segment
		(start 19.191478 -422.294812)
		(end 18.835624 -422.294812)
		(width 0.12954)
		(layer "F.Cu")
		(net "P2E_MB_BMC_RX_BUF2_C_DP<0>")
	)
	(segment
		(start 20.486878 -420.999412)
		(end 19.191478 -422.294812)
		(width 0.12954)
		(layer "F.Cu")
		(net "P2E_MB_BMC_RX_BUF2_C_DP<0>")
	)
	(segment
		(start 40.684704 -426.563536)
		(end 41.173146 -426.075094)
		(width 0.12954)
		(layer "F.Cu")
		(net "P2E_MB_BMC_RX_BUF2_C_DP<0>")
	)
	(segment
		(start 41.173146 -426.071538)
		(end 41.733724 -426.071538)
		(width 0.12954)
		(layer "F.Cu")
		(net "P2E_MB_BMC_RX_BUF2_C_DP<0>")
	)
	(segment
		(start 21.802344 -421.269922)
		(end 21.531834 -420.999412)
		(width 0.12954)
		(layer "F.Cu")
		(net "P2E_MB_BMC_RX_BUF2_C_DP<0>")
	)
	(segment
		(start 40.35044 -426.563536)
		(end 40.684704 -426.563536)
		(width 0.12954)
		(layer "F.Cu")
		(net "P2E_MB_BMC_RX_BUF2_C_DP<0>")
	)
	(segment
		(start 21.531834 -420.999412)
		(end 20.486878 -420.999412)
		(width 0.12954)
		(layer "F.Cu")
		(net "P2E_MB_BMC_RX_BUF2_C_DP<0>")
	)
	(via
		(at 21.802344 -421.269922)
		(size 0.508)
		(drill 0.254)
		(layers "F.Cu" "B.Cu")
		(net "P2E_MB_BMC_RX_BUF2_C_DP<0>")
	)
	(via
		(at 41.995344 -426.333158)
		(size 0.508)
		(drill 0.254)
		(layers "F.Cu" "B.Cu")
		(net "P2E_MB_BMC_RX_BUF2_C_DP<0>")
	)
	(segment
		(start 28.917138 -419.069774)
		(end 27.675332 -418.555424)
		(width 0.12954)
		(layer "B.Cu")
		(net "P2E_MB_BMC_RX_BUF2_C_DP<0>")
	)
	(segment
		(start 20.08251 -418.992558)
		(end 20.08251 -420.408862)
		(width 0.12954)
		(layer "B.Cu")
		(net "P2E_MB_BMC_RX_BUF2_C_DP<0>")
	)
	(segment
		(start 21.531834 -420.999412)
		(end 21.802344 -421.269922)
		(width 0.12954)
		(layer "B.Cu")
		(net "P2E_MB_BMC_RX_BUF2_C_DP<0>")
	)
	(segment
		(start 20.08251 -420.408862)
		(end 20.67306 -420.999412)
		(width 0.12954)
		(layer "B.Cu")
		(net "P2E_MB_BMC_RX_BUF2_C_DP<0>")
	)
	(segment
		(start 20.519644 -418.555424)
		(end 20.08251 -418.992558)
		(width 0.12954)
		(layer "B.Cu")
		(net "P2E_MB_BMC_RX_BUF2_C_DP<0>")
	)
	(segment
		(start 44.41571 -420.9288)
		(end 42.556684 -419.069774)
		(width 0.12954)
		(layer "B.Cu")
		(net "P2E_MB_BMC_RX_BUF2_C_DP<0>")
	)
	(segment
		(start 27.675332 -418.555424)
		(end 20.519644 -418.555424)
		(width 0.12954)
		(layer "B.Cu")
		(net "P2E_MB_BMC_RX_BUF2_C_DP<0>")
	)
	(segment
		(start 42.556684 -419.069774)
		(end 28.917138 -419.069774)
		(width 0.12954)
		(layer "B.Cu")
		(net "P2E_MB_BMC_RX_BUF2_C_DP<0>")
	)
	(segment
		(start 42.839132 -426.062648)
		(end 44.41571 -424.48607)
		(width 0.12954)
		(layer "B.Cu")
		(net "P2E_MB_BMC_RX_BUF2_C_DP<0>")
	)
	(segment
		(start 20.67306 -420.999412)
		(end 21.531834 -420.999412)
		(width 0.12954)
		(layer "B.Cu")
		(net "P2E_MB_BMC_RX_BUF2_C_DP<0>")
	)
	(segment
		(start 41.995344 -426.333158)
		(end 42.265854 -426.062648)
		(width 0.12954)
		(layer "B.Cu")
		(net "P2E_MB_BMC_RX_BUF2_C_DP<0>")
	)
	(segment
		(start 44.41571 -424.48607)
		(end 44.41571 -420.9288)
		(width 0.12954)
		(layer "B.Cu")
		(net "P2E_MB_BMC_RX_BUF2_C_DP<0>")
	)
	(segment
		(start 42.265854 -426.062648)
		(end 42.839132 -426.062648)
		(width 0.12954)
		(layer "B.Cu")
		(net "P2E_MB_BMC_RX_BUF2_C_DP<0>")
	)
	(segment
		(start 18.707354 -421.883586)
		(end 18.523204 -421.883586)
		(width 0.12954)
		(layer "F.Cu")
		(net "P2E_MB_BMC_RX_BUF2_C_DN<0>")
	)
	(segment
		(start 40.678608 -425.256706)
		(end 41.17086 -425.748958)
		(width 0.12954)
		(layer "F.Cu")
		(net "P2E_MB_BMC_RX_BUF2_C_DN<0>")
	)
	(segment
		(start 41.17086 -425.748958)
		(end 41.715944 -425.748958)
		(width 0.12954)
		(layer "F.Cu")
		(net "P2E_MB_BMC_RX_BUF2_C_DN<0>")
	)
	(segment
		(start 18.796 -421.972232)
		(end 18.707354 -421.883586)
		(width 0.12954)
		(layer "F.Cu")
		(net "P2E_MB_BMC_RX_BUF2_C_DN<0>")
	)
	(segment
		(start 19.05762 -421.972232)
		(end 18.796 -421.972232)
		(width 0.12954)
		(layer "F.Cu")
		(net "P2E_MB_BMC_RX_BUF2_C_DN<0>")
	)
	(segment
		(start 41.715944 -425.748958)
		(end 41.995344 -425.469558)
		(width 0.12954)
		(layer "F.Cu")
		(net "P2E_MB_BMC_RX_BUF2_C_DN<0>")
	)
	(segment
		(start 21.802344 -420.406322)
		(end 21.531834 -420.676832)
		(width 0.12954)
		(layer "F.Cu")
		(net "P2E_MB_BMC_RX_BUF2_C_DN<0>")
	)
	(segment
		(start 40.35044 -425.256706)
		(end 40.678608 -425.256706)
		(width 0.12954)
		(layer "F.Cu")
		(net "P2E_MB_BMC_RX_BUF2_C_DN<0>")
	)
	(segment
		(start 20.35302 -420.676832)
		(end 19.05762 -421.972232)
		(width 0.12954)
		(layer "F.Cu")
		(net "P2E_MB_BMC_RX_BUF2_C_DN<0>")
	)
	(segment
		(start 21.531834 -420.676832)
		(end 20.35302 -420.676832)
		(width 0.12954)
		(layer "F.Cu")
		(net "P2E_MB_BMC_RX_BUF2_C_DN<0>")
	)
	(via
		(at 41.995344 -425.469558)
		(size 0.508)
		(drill 0.254)
		(layers "F.Cu" "B.Cu")
		(net "P2E_MB_BMC_RX_BUF2_C_DN<0>")
	)
	(via
		(at 21.802344 -420.406322)
		(size 0.508)
		(drill 0.254)
		(layers "F.Cu" "B.Cu")
		(net "P2E_MB_BMC_RX_BUF2_C_DN<0>")
	)
	(segment
		(start 22.583648 -418.878004)
		(end 22.972268 -418.878004)
		(width 0.12954)
		(layer "B.Cu")
		(net "P2E_MB_BMC_RX_BUF2_C_DN<0>")
	)
	(segment
		(start 32.332168 -419.392354)
		(end 32.758888 -419.392354)
		(width 0.12954)
		(layer "B.Cu")
		(net "P2E_MB_BMC_RX_BUF2_C_DN<0>")
	)
	(segment
		(start 36.288472 -419.529514)
		(end 36.715192 -419.529514)
		(width 0.12954)
		(layer "B.Cu")
		(net "P2E_MB_BMC_RX_BUF2_C_DN<0>")
	)
	(segment
		(start 20.40509 -420.275004)
		(end 20.40509 -419.126416)
		(width 0.12954)
		(layer "B.Cu")
		(net "P2E_MB_BMC_RX_BUF2_C_DN<0>")
	)
	(segment
		(start 33.459928 -419.392354)
		(end 33.895792 -419.392354)
		(width 0.12954)
		(layer "B.Cu")
		(net "P2E_MB_BMC_RX_BUF2_C_DN<0>")
	)
	(segment
		(start 26.637488 -419.068504)
		(end 27.026108 -419.068504)
		(width 0.12954)
		(layer "B.Cu")
		(net "P2E_MB_BMC_RX_BUF2_C_DN<0>")
	)
	(segment
		(start 29.939488 -419.529514)
		(end 30.076648 -419.392354)
		(width 0.12954)
		(layer "B.Cu")
		(net "P2E_MB_BMC_RX_BUF2_C_DN<0>")
	)
	(segment
		(start 26.446988 -418.878004)
		(end 26.637488 -419.068504)
		(width 0.12954)
		(layer "B.Cu")
		(net "P2E_MB_BMC_RX_BUF2_C_DN<0>")
	)
	(segment
		(start 26.058368 -418.878004)
		(end 26.446988 -418.878004)
		(width 0.12954)
		(layer "B.Cu")
		(net "P2E_MB_BMC_RX_BUF2_C_DN<0>")
	)
	(segment
		(start 42.979848 -425.465494)
		(end 42.705274 -425.740068)
		(width 0.12954)
		(layer "B.Cu")
		(net "P2E_MB_BMC_RX_BUF2_C_DN<0>")
	)
	(segment
		(start 29.375608 -419.392354)
		(end 29.512768 -419.529514)
		(width 0.12954)
		(layer "B.Cu")
		(net "P2E_MB_BMC_RX_BUF2_C_DN<0>")
	)
	(segment
		(start 43.209972 -420.44874)
		(end 43.485054 -420.723822)
		(width 0.12954)
		(layer "B.Cu")
		(net "P2E_MB_BMC_RX_BUF2_C_DN<0>")
	)
	(segment
		(start 36.852352 -419.392354)
		(end 42.422826 -419.392354)
		(width 0.12954)
		(layer "B.Cu")
		(net "P2E_MB_BMC_RX_BUF2_C_DN<0>")
	)
	(segment
		(start 34.032952 -419.529514)
		(end 34.459672 -419.529514)
		(width 0.12954)
		(layer "B.Cu")
		(net "P2E_MB_BMC_RX_BUF2_C_DN<0>")
	)
	(segment
		(start 20.806918 -420.676832)
		(end 20.40509 -420.275004)
		(width 0.12954)
		(layer "B.Cu")
		(net "P2E_MB_BMC_RX_BUF2_C_DN<0>")
	)
	(segment
		(start 24.900128 -418.878004)
		(end 25.288748 -418.878004)
		(width 0.12954)
		(layer "B.Cu")
		(net "P2E_MB_BMC_RX_BUF2_C_DN<0>")
	)
	(segment
		(start 34.459672 -419.529514)
		(end 34.596832 -419.392354)
		(width 0.12954)
		(layer "B.Cu")
		(net "P2E_MB_BMC_RX_BUF2_C_DN<0>")
	)
	(segment
		(start 30.076648 -419.392354)
		(end 30.503368 -419.392354)
		(width 0.12954)
		(layer "B.Cu")
		(net "P2E_MB_BMC_RX_BUF2_C_DN<0>")
	)
	(segment
		(start 44.09313 -421.062658)
		(end 44.09313 -423.193972)
		(width 0.12954)
		(layer "B.Cu")
		(net "P2E_MB_BMC_RX_BUF2_C_DN<0>")
	)
	(segment
		(start 24.321008 -419.068504)
		(end 24.709628 -419.068504)
		(width 0.12954)
		(layer "B.Cu")
		(net "P2E_MB_BMC_RX_BUF2_C_DN<0>")
	)
	(segment
		(start 32.195008 -419.529514)
		(end 32.332168 -419.392354)
		(width 0.12954)
		(layer "B.Cu")
		(net "P2E_MB_BMC_RX_BUF2_C_DN<0>")
	)
	(segment
		(start 27.61107 -418.878004)
		(end 28.852876 -419.392354)
		(width 0.12954)
		(layer "B.Cu")
		(net "P2E_MB_BMC_RX_BUF2_C_DN<0>")
	)
	(segment
		(start 35.160712 -419.529514)
		(end 35.587432 -419.529514)
		(width 0.12954)
		(layer "B.Cu")
		(net "P2E_MB_BMC_RX_BUF2_C_DN<0>")
	)
	(segment
		(start 32.758888 -419.392354)
		(end 32.896048 -419.529514)
		(width 0.12954)
		(layer "B.Cu")
		(net "P2E_MB_BMC_RX_BUF2_C_DN<0>")
	)
	(segment
		(start 43.25493 -424.920918)
		(end 42.979848 -425.196)
		(width 0.12954)
		(layer "B.Cu")
		(net "P2E_MB_BMC_RX_BUF2_C_DN<0>")
	)
	(segment
		(start 22.393148 -419.068504)
		(end 22.583648 -418.878004)
		(width 0.12954)
		(layer "B.Cu")
		(net "P2E_MB_BMC_RX_BUF2_C_DN<0>")
	)
	(segment
		(start 32.896048 -419.529514)
		(end 33.322768 -419.529514)
		(width 0.12954)
		(layer "B.Cu")
		(net "P2E_MB_BMC_RX_BUF2_C_DN<0>")
	)
	(segment
		(start 43.485054 -420.723822)
		(end 43.754294 -420.723822)
		(width 0.12954)
		(layer "B.Cu")
		(net "P2E_MB_BMC_RX_BUF2_C_DN<0>")
	)
	(segment
		(start 35.724592 -419.392354)
		(end 36.151312 -419.392354)
		(width 0.12954)
		(layer "B.Cu")
		(net "P2E_MB_BMC_RX_BUF2_C_DN<0>")
	)
	(segment
		(start 22.004528 -419.068504)
		(end 22.393148 -419.068504)
		(width 0.12954)
		(layer "B.Cu")
		(net "P2E_MB_BMC_RX_BUF2_C_DN<0>")
	)
	(segment
		(start 23.551388 -419.068504)
		(end 23.741888 -418.878004)
		(width 0.12954)
		(layer "B.Cu")
		(net "P2E_MB_BMC_RX_BUF2_C_DN<0>")
	)
	(segment
		(start 25.867868 -419.068504)
		(end 26.058368 -418.878004)
		(width 0.12954)
		(layer "B.Cu")
		(net "P2E_MB_BMC_RX_BUF2_C_DN<0>")
	)
	(segment
		(start 33.895792 -419.392354)
		(end 34.032952 -419.529514)
		(width 0.12954)
		(layer "B.Cu")
		(net "P2E_MB_BMC_RX_BUF2_C_DN<0>")
	)
	(segment
		(start 42.979848 -425.196)
		(end 42.979848 -425.465494)
		(width 0.12954)
		(layer "B.Cu")
		(net "P2E_MB_BMC_RX_BUF2_C_DN<0>")
	)
	(segment
		(start 21.814028 -418.878004)
		(end 22.004528 -419.068504)
		(width 0.12954)
		(layer "B.Cu")
		(net "P2E_MB_BMC_RX_BUF2_C_DN<0>")
	)
	(segment
		(start 25.288748 -418.878004)
		(end 25.479248 -419.068504)
		(width 0.12954)
		(layer "B.Cu")
		(net "P2E_MB_BMC_RX_BUF2_C_DN<0>")
	)
	(segment
		(start 24.709628 -419.068504)
		(end 24.900128 -418.878004)
		(width 0.12954)
		(layer "B.Cu")
		(net "P2E_MB_BMC_RX_BUF2_C_DN<0>")
	)
	(segment
		(start 33.322768 -419.529514)
		(end 33.459928 -419.392354)
		(width 0.12954)
		(layer "B.Cu")
		(net "P2E_MB_BMC_RX_BUF2_C_DN<0>")
	)
	(segment
		(start 44.09313 -424.352212)
		(end 43.524424 -424.920918)
		(width 0.12954)
		(layer "B.Cu")
		(net "P2E_MB_BMC_RX_BUF2_C_DN<0>")
	)
	(segment
		(start 20.653502 -418.878004)
		(end 21.814028 -418.878004)
		(width 0.12954)
		(layer "B.Cu")
		(net "P2E_MB_BMC_RX_BUF2_C_DN<0>")
	)
	(segment
		(start 34.596832 -419.392354)
		(end 35.023552 -419.392354)
		(width 0.12954)
		(layer "B.Cu")
		(net "P2E_MB_BMC_RX_BUF2_C_DN<0>")
	)
	(segment
		(start 21.531834 -420.676832)
		(end 20.806918 -420.676832)
		(width 0.12954)
		(layer "B.Cu")
		(net "P2E_MB_BMC_RX_BUF2_C_DN<0>")
	)
	(segment
		(start 22.972268 -418.878004)
		(end 23.162768 -419.068504)
		(width 0.12954)
		(layer "B.Cu")
		(net "P2E_MB_BMC_RX_BUF2_C_DN<0>")
	)
	(segment
		(start 21.802344 -420.406322)
		(end 21.531834 -420.676832)
		(width 0.12954)
		(layer "B.Cu")
		(net "P2E_MB_BMC_RX_BUF2_C_DN<0>")
	)
	(segment
		(start 30.503368 -419.392354)
		(end 30.640528 -419.529514)
		(width 0.12954)
		(layer "B.Cu")
		(net "P2E_MB_BMC_RX_BUF2_C_DN<0>")
	)
	(segment
		(start 42.265854 -425.740068)
		(end 41.995344 -425.469558)
		(width 0.12954)
		(layer "B.Cu")
		(net "P2E_MB_BMC_RX_BUF2_C_DN<0>")
	)
	(segment
		(start 31.067248 -419.529514)
		(end 31.204408 -419.392354)
		(width 0.12954)
		(layer "B.Cu")
		(net "P2E_MB_BMC_RX_BUF2_C_DN<0>")
	)
	(segment
		(start 25.479248 -419.068504)
		(end 25.867868 -419.068504)
		(width 0.12954)
		(layer "B.Cu")
		(net "P2E_MB_BMC_RX_BUF2_C_DN<0>")
	)
	(segment
		(start 43.209972 -420.1795)
		(end 43.209972 -420.44874)
		(width 0.12954)
		(layer "B.Cu")
		(net "P2E_MB_BMC_RX_BUF2_C_DN<0>")
	)
	(segment
		(start 27.026108 -419.068504)
		(end 27.216608 -418.878004)
		(width 0.12954)
		(layer "B.Cu")
		(net "P2E_MB_BMC_RX_BUF2_C_DN<0>")
	)
	(segment
		(start 23.741888 -418.878004)
		(end 24.130508 -418.878004)
		(width 0.12954)
		(layer "B.Cu")
		(net "P2E_MB_BMC_RX_BUF2_C_DN<0>")
	)
	(segment
		(start 36.715192 -419.529514)
		(end 36.852352 -419.392354)
		(width 0.12954)
		(layer "B.Cu")
		(net "P2E_MB_BMC_RX_BUF2_C_DN<0>")
	)
	(segment
		(start 31.204408 -419.392354)
		(end 31.631128 -419.392354)
		(width 0.12954)
		(layer "B.Cu")
		(net "P2E_MB_BMC_RX_BUF2_C_DN<0>")
	)
	(segment
		(start 30.640528 -419.529514)
		(end 31.067248 -419.529514)
		(width 0.12954)
		(layer "B.Cu")
		(net "P2E_MB_BMC_RX_BUF2_C_DN<0>")
	)
	(segment
		(start 44.09313 -423.193972)
		(end 43.90263 -423.384472)
		(width 0.12954)
		(layer "B.Cu")
		(net "P2E_MB_BMC_RX_BUF2_C_DN<0>")
	)
	(segment
		(start 23.162768 -419.068504)
		(end 23.551388 -419.068504)
		(width 0.12954)
		(layer "B.Cu")
		(net "P2E_MB_BMC_RX_BUF2_C_DN<0>")
	)
	(segment
		(start 31.768288 -419.529514)
		(end 32.195008 -419.529514)
		(width 0.12954)
		(layer "B.Cu")
		(net "P2E_MB_BMC_RX_BUF2_C_DN<0>")
	)
	(segment
		(start 43.90263 -423.773092)
		(end 44.09313 -423.963592)
		(width 0.12954)
		(layer "B.Cu")
		(net "P2E_MB_BMC_RX_BUF2_C_DN<0>")
	)
	(segment
		(start 42.705274 -425.740068)
		(end 42.265854 -425.740068)
		(width 0.12954)
		(layer "B.Cu")
		(net "P2E_MB_BMC_RX_BUF2_C_DN<0>")
	)
	(segment
		(start 24.130508 -418.878004)
		(end 24.321008 -419.068504)
		(width 0.12954)
		(layer "B.Cu")
		(net "P2E_MB_BMC_RX_BUF2_C_DN<0>")
	)
	(segment
		(start 44.09313 -423.963592)
		(end 44.09313 -424.352212)
		(width 0.12954)
		(layer "B.Cu")
		(net "P2E_MB_BMC_RX_BUF2_C_DN<0>")
	)
	(segment
		(start 31.631128 -419.392354)
		(end 31.768288 -419.529514)
		(width 0.12954)
		(layer "B.Cu")
		(net "P2E_MB_BMC_RX_BUF2_C_DN<0>")
	)
	(segment
		(start 36.151312 -419.392354)
		(end 36.288472 -419.529514)
		(width 0.12954)
		(layer "B.Cu")
		(net "P2E_MB_BMC_RX_BUF2_C_DN<0>")
	)
	(segment
		(start 29.512768 -419.529514)
		(end 29.939488 -419.529514)
		(width 0.12954)
		(layer "B.Cu")
		(net "P2E_MB_BMC_RX_BUF2_C_DN<0>")
	)
	(segment
		(start 42.422826 -419.392354)
		(end 43.209972 -420.1795)
		(width 0.12954)
		(layer "B.Cu")
		(net "P2E_MB_BMC_RX_BUF2_C_DN<0>")
	)
	(segment
		(start 20.40509 -419.126416)
		(end 20.653502 -418.878004)
		(width 0.12954)
		(layer "B.Cu")
		(net "P2E_MB_BMC_RX_BUF2_C_DN<0>")
	)
	(segment
		(start 27.216608 -418.878004)
		(end 27.61107 -418.878004)
		(width 0.12954)
		(layer "B.Cu")
		(net "P2E_MB_BMC_RX_BUF2_C_DN<0>")
	)
	(segment
		(start 43.90263 -423.384472)
		(end 43.90263 -423.773092)
		(width 0.12954)
		(layer "B.Cu")
		(net "P2E_MB_BMC_RX_BUF2_C_DN<0>")
	)
	(segment
		(start 28.852876 -419.392354)
		(end 29.375608 -419.392354)
		(width 0.12954)
		(layer "B.Cu")
		(net "P2E_MB_BMC_RX_BUF2_C_DN<0>")
	)
	(segment
		(start 43.754294 -420.723822)
		(end 44.09313 -421.062658)
		(width 0.12954)
		(layer "B.Cu")
		(net "P2E_MB_BMC_RX_BUF2_C_DN<0>")
	)
	(segment
		(start 35.023552 -419.392354)
		(end 35.160712 -419.529514)
		(width 0.12954)
		(layer "B.Cu")
		(net "P2E_MB_BMC_RX_BUF2_C_DN<0>")
	)
	(segment
		(start 43.524424 -424.920918)
		(end 43.25493 -424.920918)
		(width 0.12954)
		(layer "B.Cu")
		(net "P2E_MB_BMC_RX_BUF2_C_DN<0>")
	)
	(segment
		(start 35.587432 -419.529514)
		(end 35.724592 -419.392354)
		(width 0.12954)
		(layer "B.Cu")
		(net "P2E_MB_BMC_RX_BUF2_C_DN<0>")
	)
	(via
		(at 276.9362 -389.29564)
		(size 0.508)
		(drill 0.254)
		(layers "F.Cu" "B.Cu")
		(net "P12V_MAIN_R_0")
	)
	(via
		(at 276.1742 -389.29564)
		(size 0.508)
		(drill 0.254)
		(layers "F.Cu" "B.Cu")
		(net "P12V_MAIN_R_0")
	)
	(via
		(at 277.6982 -389.29564)
		(size 0.508)
		(drill 0.254)
		(layers "F.Cu" "B.Cu")
		(net "P12V_MAIN_R_0")
	)
	(via
		(at 280.18994 -389.51408)
		(size 0.762)
		(drill 0.381)
		(layers "F.Cu" "B.Cu")
		(net "P12V_MAIN_R_0")
	)
	(via
		(at 278.4602 -389.29564)
		(size 0.508)
		(drill 0.254)
		(layers "F.Cu" "B.Cu")
		(net "P12V_MAIN_R_0")
	)
	(via
		(at 245.7069 -389.32104)
		(size 0.508)
		(drill 0.254)
		(layers "F.Cu" "B.Cu")
		(net "P12V_MAIN_R")
	)
	(via
		(at 268.372336 -386.10032)
		(size 0.508)
		(drill 0.254)
		(layers "F.Cu" "B.Cu")
		(net "P12V_MAIN_R")
	)
	(via
		(at 262.437372 -387.62432)
		(size 0.508)
		(drill 0.254)
		(layers "F.Cu" "B.Cu")
		(net "P12V_MAIN_R")
	)
	(via
		(at 244.9449 -389.32104)
		(size 0.508)
		(drill 0.254)
		(layers "F.Cu" "B.Cu")
		(net "P12V_MAIN_R")
	)
	(via
		(at 250.567444 -387.62432)
		(size 0.508)
		(drill 0.254)
		(layers "F.Cu" "B.Cu")
		(net "P12V_MAIN_R")
	)
	(via
		(at 250.567444 -386.10032)
		(size 0.508)
		(drill 0.254)
		(layers "F.Cu" "B.Cu")
		(net "P12V_MAIN_R")
	)
	(via
		(at 252.54712 -389.32104)
		(size 0.508)
		(drill 0.254)
		(layers "F.Cu" "B.Cu")
		(net "P12V_MAIN_R")
	)
	(via
		(at 243.4209 -389.32104)
		(size 0.508)
		(drill 0.254)
		(layers "F.Cu" "B.Cu")
		(net "P12V_MAIN_R")
	)
	(via
		(at 267.74394 -389.3439)
		(size 0.508)
		(drill 0.254)
		(layers "F.Cu" "B.Cu")
		(net "P12V_MAIN_R")
	)
	(via
		(at 260.46176 -389.36422)
		(size 0.508)
		(drill 0.254)
		(layers "F.Cu" "B.Cu")
		(net "P12V_MAIN_R")
	)
	(via
		(at 244.63248 -386.86232)
		(size 0.508)
		(drill 0.254)
		(layers "F.Cu" "B.Cu")
		(net "P12V_MAIN_R")
	)
	(via
		(at 256.502408 -386.10032)
		(size 0.508)
		(drill 0.254)
		(layers "F.Cu" "B.Cu")
		(net "P12V_MAIN_R")
	)
	(via
		(at 258.93776 -389.36422)
		(size 0.508)
		(drill 0.254)
		(layers "F.Cu" "B.Cu")
		(net "P12V_MAIN_R")
	)
	(via
		(at 239.879124 -389.328914)
		(size 0.508)
		(drill 0.254)
		(layers "F.Cu" "B.Cu")
		(net "P12V_MAIN_R")
	)
	(via
		(at 268.372336 -386.86232)
		(size 0.508)
		(drill 0.254)
		(layers "F.Cu" "B.Cu")
		(net "P12V_MAIN_R")
	)
	(via
		(at 270.02994 -389.3439)
		(size 0.508)
		(drill 0.254)
		(layers "F.Cu" "B.Cu")
		(net "P12V_MAIN_R")
	)
	(via
		(at 250.567444 -386.86232)
		(size 0.508)
		(drill 0.254)
		(layers "F.Cu" "B.Cu")
		(net "P12V_MAIN_R")
	)
	(via
		(at 256.502408 -387.62432)
		(size 0.508)
		(drill 0.254)
		(layers "F.Cu" "B.Cu")
		(net "P12V_MAIN_R")
	)
	(via
		(at 253.30912 -389.32104)
		(size 0.508)
		(drill 0.254)
		(layers "F.Cu" "B.Cu")
		(net "P12V_MAIN_R")
	)
	(via
		(at 242.6589 -389.32104)
		(size 0.508)
		(drill 0.254)
		(layers "F.Cu" "B.Cu")
		(net "P12V_MAIN_R")
	)
	(via
		(at 262.437372 -386.10032)
		(size 0.508)
		(drill 0.254)
		(layers "F.Cu" "B.Cu")
		(net "P12V_MAIN_R")
	)
	(via
		(at 268.372336 -387.62432)
		(size 0.508)
		(drill 0.254)
		(layers "F.Cu" "B.Cu")
		(net "P12V_MAIN_R")
	)
	(via
		(at 251.78512 -389.32104)
		(size 0.508)
		(drill 0.254)
		(layers "F.Cu" "B.Cu")
		(net "P12V_MAIN_R")
	)
	(via
		(at 259.69976 -389.36422)
		(size 0.508)
		(drill 0.254)
		(layers "F.Cu" "B.Cu")
		(net "P12V_MAIN_R")
	)
	(via
		(at 262.437372 -386.86232)
		(size 0.508)
		(drill 0.254)
		(layers "F.Cu" "B.Cu")
		(net "P12V_MAIN_R")
	)
	(via
		(at 244.1829 -389.32104)
		(size 0.508)
		(drill 0.254)
		(layers "F.Cu" "B.Cu")
		(net "P12V_MAIN_R")
	)
	(via
		(at 261.22376 -389.36422)
		(size 0.508)
		(drill 0.254)
		(layers "F.Cu" "B.Cu")
		(net "P12V_MAIN_R")
	)
	(via
		(at 244.63248 -386.10032)
		(size 0.508)
		(drill 0.254)
		(layers "F.Cu" "B.Cu")
		(net "P12V_MAIN_R")
	)
	(via
		(at 244.63248 -387.62432)
		(size 0.508)
		(drill 0.254)
		(layers "F.Cu" "B.Cu")
		(net "P12V_MAIN_R")
	)
	(via
		(at 266.98194 -389.3439)
		(size 0.508)
		(drill 0.254)
		(layers "F.Cu" "B.Cu")
		(net "P12V_MAIN_R")
	)
	(via
		(at 273.2024 -389.5598)
		(size 0.762)
		(drill 0.381)
		(layers "F.Cu" "B.Cu")
		(net "P12V_MAIN_R")
	)
	(via
		(at 256.502408 -386.86232)
		(size 0.508)
		(drill 0.254)
		(layers "F.Cu" "B.Cu")
		(net "P12V_MAIN_R")
	)
	(via
		(at 268.50594 -389.3439)
		(size 0.508)
		(drill 0.254)
		(layers "F.Cu" "B.Cu")
		(net "P12V_MAIN_R")
	)
	(via
		(at 254.07112 -389.32104)
		(size 0.508)
		(drill 0.254)
		(layers "F.Cu" "B.Cu")
		(net "P12V_MAIN_R")
	)
	(via
		(at 251.02312 -389.32104)
		(size 0.508)
		(drill 0.254)
		(layers "F.Cu" "B.Cu")
		(net "P12V_MAIN_R")
	)
	(via
		(at 261.98576 -389.36422)
		(size 0.508)
		(drill 0.254)
		(layers "F.Cu" "B.Cu")
		(net "P12V_MAIN_R")
	)
	(via
		(at 269.26794 -389.3439)
		(size 0.508)
		(drill 0.254)
		(layers "F.Cu" "B.Cu")
		(net "P12V_MAIN_R")
	)
	(segment
		(start 283.88691 -391.128758)
		(end 284.750002 -391.128758)
		(width 0.10668)
		(layer "F.Cu")
		(net "SMB_P12V_HSC_TEMP_SDA")
	)
	(segment
		(start 284.750002 -391.128758)
		(end 285.543244 -391.922)
		(width 0.10668)
		(layer "F.Cu")
		(net "SMB_P12V_HSC_TEMP_SDA")
	)
	(segment
		(start 285.543244 -391.922)
		(end 285.543244 -392.870182)
		(width 0.10668)
		(layer "F.Cu")
		(net "SMB_P12V_HSC_TEMP_SDA")
	)
	(segment
		(start 281.621738 -390.89457)
		(end 281.621738 -391.223754)
		(width 0.10668)
		(layer "F.Cu")
		(net "SMB_P12V_HSC_TEMP_SDA")
	)
	(segment
		(start 281.621738 -391.223754)
		(end 281.821382 -391.423398)
		(width 0.10668)
		(layer "F.Cu")
		(net "SMB_P12V_HSC_TEMP_SDA")
	)
	(segment
		(start 283.59227 -391.423398)
		(end 283.88691 -391.128758)
		(width 0.10668)
		(layer "F.Cu")
		(net "SMB_P12V_HSC_TEMP_SDA")
	)
	(segment
		(start 281.821382 -391.423398)
		(end 283.59227 -391.423398)
		(width 0.10668)
		(layer "F.Cu")
		(net "SMB_P12V_HSC_TEMP_SDA")
	)
	(via
		(at 283.88691 -391.128758)
		(size 0.762)
		(drill 0.381)
		(layers "F.Cu" "B.Cu")
		(net "SMB_P12V_HSC_TEMP_SDA")
	)
	(segment
		(start 284.027372 -389.852916)
		(end 284.259274 -389.852916)
		(width 0.10668)
		(layer "F.Cu")
		(net "SMB_P12V_HSC_TEMP_SCL")
	)
	(segment
		(start 286.19323 -391.565892)
		(end 286.19323 -392.870182)
		(width 0.10668)
		(layer "F.Cu")
		(net "SMB_P12V_HSC_TEMP_SCL")
	)
	(segment
		(start 284.259274 -389.852916)
		(end 284.480254 -389.852916)
		(width 0.10668)
		(layer "F.Cu")
		(net "SMB_P12V_HSC_TEMP_SCL")
	)
	(segment
		(start 284.480254 -389.852916)
		(end 286.19323 -391.565892)
		(width 0.10668)
		(layer "F.Cu")
		(net "SMB_P12V_HSC_TEMP_SCL")
	)
	(segment
		(start 282.985718 -390.89457)
		(end 284.027372 -389.852916)
		(width 0.10668)
		(layer "F.Cu")
		(net "SMB_P12V_HSC_TEMP_SCL")
	)
	(via
		(at 284.259274 -389.852916)
		(size 0.762)
		(drill 0.381)
		(layers "F.Cu" "B.Cu")
		(net "SMB_P12V_HSC_TEMP_SCL")
	)
	(segment
		(start 285.428944 -406.277572)
		(end 285.942024 -405.764492)
		(width 0.254)
		(layer "F.Cu")
		(net "P12V_HSC_TEMP_R")
	)
	(segment
		(start 286.0675 -408.159458)
		(end 285.428944 -407.520902)
		(width 0.254)
		(layer "F.Cu")
		(net "P12V_HSC_TEMP_R")
	)
	(segment
		(start 287.0835 -409.175458)
		(end 287.0835 -410.394658)
		(width 0.254)
		(layer "F.Cu")
		(net "P12V_HSC_TEMP_R")
	)
	(segment
		(start 285.455106 -404.658576)
		(end 285.75254 -404.361142)
		(width 0.254)
		(layer "F.Cu")
		(net "P12V_HSC_TEMP_R")
	)
	(segment
		(start 285.428944 -407.520902)
		(end 285.428944 -406.277572)
		(width 0.254)
		(layer "F.Cu")
		(net "P12V_HSC_TEMP_R")
	)
	(segment
		(start 286.0675 -408.159458)
		(end 287.0835 -409.175458)
		(width 0.254)
		(layer "F.Cu")
		(net "P12V_HSC_TEMP_R")
	)
	(segment
		(start 285.455106 -405.277574)
		(end 285.455106 -404.658576)
		(width 0.254)
		(layer "F.Cu")
		(net "P12V_HSC_TEMP_R")
	)
	(segment
		(start 285.942024 -405.764492)
		(end 285.455106 -405.277574)
		(width 0.254)
		(layer "F.Cu")
		(net "P12V_HSC_TEMP_R")
	)
	(via
		(at 285.942024 -405.764492)
		(size 0.762)
		(drill 0.381)
		(layers "F.Cu" "B.Cu")
		(net "P12V_HSC_TEMP_R")
	)
	(segment
		(start 285.033974 -405.277574)
		(end 285.033974 -404.658576)
		(width 0.254)
		(layer "F.Cu")
		(net "P12V_HSC_TEMP_E")
	)
	(segment
		(start 285.033974 -404.658576)
		(end 284.73654 -404.361142)
		(width 0.254)
		(layer "F.Cu")
		(net "P12V_HSC_TEMP_E")
	)
	(segment
		(start 285.047944 -406.293828)
		(end 284.518608 -405.764492)
		(width 0.254)
		(layer "F.Cu")
		(net "P12V_HSC_TEMP_E")
	)
	(segment
		(start 284.547056 -405.764492)
		(end 285.033974 -405.277574)
		(width 0.254)
		(layer "F.Cu")
		(net "P12V_HSC_TEMP_E")
	)
	(segment
		(start 285.047944 -410.391102)
		(end 285.047944 -406.293828)
		(width 0.254)
		(layer "F.Cu")
		(net "P12V_HSC_TEMP_E")
	)
	(segment
		(start 284.518608 -405.764492)
		(end 284.547056 -405.764492)
		(width 0.254)
		(layer "F.Cu")
		(net "P12V_HSC_TEMP_E")
	)
	(segment
		(start 285.0515 -410.394658)
		(end 285.047944 -410.391102)
		(width 0.254)
		(layer "F.Cu")
		(net "P12V_HSC_TEMP_E")
	)
	(via
		(at 284.518608 -405.764492)
		(size 0.762)
		(drill 0.381)
		(layers "F.Cu" "B.Cu")
		(net "P12V_HSC_TEMP_E")
	)
	(segment
		(start 284.547056 -401.395692)
		(end 285.033974 -400.908774)
		(width 0.254)
		(layer "F.Cu")
		(net "P12V_HSC_TEMP_D-")
	)
	(segment
		(start 285.033974 -401.88261)
		(end 285.033974 -403.263608)
		(width 0.254)
		(layer "F.Cu")
		(net "P12V_HSC_TEMP_D-")
	)
	(segment
		(start 285.033974 -400.008344)
		(end 284.678374 -399.652744)
		(width 0.254)
		(layer "F.Cu")
		(net "P12V_HSC_TEMP_D-")
	)
	(segment
		(start 285.027624 -399.271744)
		(end 285.027624 -397.704818)
		(width 0.254)
		(layer "F.Cu")
		(net "P12V_HSC_TEMP_D-")
	)
	(segment
		(start 284.547056 -401.395692)
		(end 285.033974 -401.88261)
		(width 0.254)
		(layer "F.Cu")
		(net "P12V_HSC_TEMP_D-")
	)
	(segment
		(start 285.027624 -397.704818)
		(end 284.893004 -397.570198)
		(width 0.254)
		(layer "F.Cu")
		(net "P12V_HSC_TEMP_D-")
	)
	(segment
		(start 284.678374 -399.652744)
		(end 284.646624 -399.652744)
		(width 0.254)
		(layer "F.Cu")
		(net "P12V_HSC_TEMP_D-")
	)
	(segment
		(start 285.033974 -403.263608)
		(end 284.73654 -403.561042)
		(width 0.254)
		(layer "F.Cu")
		(net "P12V_HSC_TEMP_D-")
	)
	(segment
		(start 284.50794 -401.395692)
		(end 284.547056 -401.395692)
		(width 0.254)
		(layer "F.Cu")
		(net "P12V_HSC_TEMP_D-")
	)
	(segment
		(start 284.646624 -399.652744)
		(end 285.027624 -399.271744)
		(width 0.254)
		(layer "F.Cu")
		(net "P12V_HSC_TEMP_D-")
	)
	(segment
		(start 285.033974 -400.908774)
		(end 285.033974 -400.008344)
		(width 0.254)
		(layer "F.Cu")
		(net "P12V_HSC_TEMP_D-")
	)
	(via
		(at 284.646624 -399.652744)
		(size 0.762)
		(drill 0.381)
		(layers "F.Cu" "B.Cu")
		(net "P12V_HSC_TEMP_D-")
	)
	(segment
		(start 285.98114 -401.395692)
		(end 285.970472 -401.395692)
		(width 0.254)
		(layer "F.Cu")
		(net "P12V_HSC_TEMP_D+")
	)
	(segment
		(start 285.408624 -399.271744)
		(end 285.408624 -397.704818)
		(width 0.254)
		(layer "F.Cu")
		(net "P12V_HSC_TEMP_D+")
	)
	(segment
		(start 285.789624 -399.652744)
		(end 285.408624 -399.271744)
		(width 0.254)
		(layer "F.Cu")
		(net "P12V_HSC_TEMP_D+")
	)
	(segment
		(start 285.942024 -401.395692)
		(end 285.455106 -401.88261)
		(width 0.254)
		(layer "F.Cu")
		(net "P12V_HSC_TEMP_D+")
	)
	(segment
		(start 285.414974 -400.008344)
		(end 285.770574 -399.652744)
		(width 0.254)
		(layer "F.Cu")
		(net "P12V_HSC_TEMP_D+")
	)
	(segment
		(start 285.970472 -401.395692)
		(end 285.414974 -400.840194)
		(width 0.254)
		(layer "F.Cu")
		(net "P12V_HSC_TEMP_D+")
	)
	(segment
		(start 285.455106 -403.263608)
		(end 285.75254 -403.561042)
		(width 0.254)
		(layer "F.Cu")
		(net "P12V_HSC_TEMP_D+")
	)
	(segment
		(start 285.408624 -397.704818)
		(end 285.543244 -397.570198)
		(width 0.254)
		(layer "F.Cu")
		(net "P12V_HSC_TEMP_D+")
	)
	(segment
		(start 285.770574 -399.652744)
		(end 285.789624 -399.652744)
		(width 0.254)
		(layer "F.Cu")
		(net "P12V_HSC_TEMP_D+")
	)
	(segment
		(start 285.455106 -401.88261)
		(end 285.455106 -403.263608)
		(width 0.254)
		(layer "F.Cu")
		(net "P12V_HSC_TEMP_D+")
	)
	(segment
		(start 285.414974 -400.840194)
		(end 285.414974 -400.008344)
		(width 0.254)
		(layer "F.Cu")
		(net "P12V_HSC_TEMP_D+")
	)
	(segment
		(start 285.970472 -401.395692)
		(end 285.942024 -401.395692)
		(width 0.254)
		(layer "F.Cu")
		(net "P12V_HSC_TEMP_D+")
	)
	(via
		(at 285.789624 -399.652744)
		(size 0.762)
		(drill 0.381)
		(layers "F.Cu" "B.Cu")
		(net "P12V_HSC_TEMP_D+")
	)
	(segment
		(start 260.171184 -394.29436)
		(end 259.790184 -393.91336)
		(width 0.254)
		(layer "F.Cu")
		(net "P12V_HSC_SENSE2_R4_P")
	)
	(segment
		(start 260.171184 -394.690092)
		(end 260.171184 -394.29436)
		(width 0.254)
		(layer "F.Cu")
		(net "P12V_HSC_SENSE2_R4_P")
	)
	(via
		(at 259.790184 -393.91336)
		(size 0.508)
		(drill 0.254)
		(layers "F.Cu" "B.Cu")
		(net "P12V_HSC_SENSE2_R4_P")
	)
	(via
		(at 207.440022 -382.723136)
		(size 0.508)
		(drill 0.254)
		(layers "F.Cu" "B.Cu")
		(net "P12V_HSC_SENSE2_R4_P")
	)
	(segment
		(start 208.061306 -382.596136)
		(end 207.934306 -382.723136)
		(width 0.254)
		(layer "B.Cu")
		(net "P12V_HSC_SENSE2_R4_P")
	)
	(segment
		(start 207.934306 -382.723136)
		(end 207.440022 -382.723136)
		(width 0.254)
		(layer "B.Cu")
		(net "P12V_HSC_SENSE2_R4_P")
	)
	(segment
		(start 206.956406 -382.723136)
		(end 206.829406 -382.596136)
		(width 0.254)
		(layer "B.Cu")
		(net "P12V_HSC_SENSE2_R4_P")
	)
	(segment
		(start 207.440022 -382.723136)
		(end 206.956406 -382.723136)
		(width 0.254)
		(layer "B.Cu")
		(net "P12V_HSC_SENSE2_R4_P")
	)
	(segment
		(start 259.790184 -394.376656)
		(end 259.980684 -394.567156)
		(width 0.254)
		(layer "In4.Cu")
		(net "P12V_HSC_SENSE2_R4_P")
	)
	(segment
		(start 227.238306 -382.906524)
		(end 211.650072 -382.906524)
		(width 0.254)
		(layer "In4.Cu")
		(net "P12V_HSC_SENSE2_R4_P")
	)
	(segment
		(start 259.980684 -395.180566)
		(end 258.582414 -396.578836)
		(width 0.254)
		(layer "In4.Cu")
		(net "P12V_HSC_SENSE2_R4_P")
	)
	(segment
		(start 240.910618 -396.578836)
		(end 227.238306 -382.906524)
		(width 0.254)
		(layer "In4.Cu")
		(net "P12V_HSC_SENSE2_R4_P")
	)
	(segment
		(start 208.101184 -382.914906)
		(end 207.631792 -382.914906)
		(width 0.254)
		(layer "In4.Cu")
		(net "P12V_HSC_SENSE2_R4_P")
	)
	(segment
		(start 259.980684 -394.567156)
		(end 259.980684 -395.180566)
		(width 0.254)
		(layer "In4.Cu")
		(net "P12V_HSC_SENSE2_R4_P")
	)
	(segment
		(start 210.432904 -384.123692)
		(end 209.30997 -384.123692)
		(width 0.254)
		(layer "In4.Cu")
		(net "P12V_HSC_SENSE2_R4_P")
	)
	(segment
		(start 211.650072 -382.906524)
		(end 210.432904 -384.123692)
		(width 0.254)
		(layer "In4.Cu")
		(net "P12V_HSC_SENSE2_R4_P")
	)
	(segment
		(start 209.30997 -384.123692)
		(end 208.101184 -382.914906)
		(width 0.254)
		(layer "In4.Cu")
		(net "P12V_HSC_SENSE2_R4_P")
	)
	(segment
		(start 258.582414 -396.578836)
		(end 240.910618 -396.578836)
		(width 0.254)
		(layer "In4.Cu")
		(net "P12V_HSC_SENSE2_R4_P")
	)
	(segment
		(start 259.790184 -393.91336)
		(end 259.790184 -394.376656)
		(width 0.254)
		(layer "In4.Cu")
		(net "P12V_HSC_SENSE2_R4_P")
	)
	(segment
		(start 207.631792 -382.914906)
		(end 207.440022 -382.723136)
		(width 0.254)
		(layer "In4.Cu")
		(net "P12V_HSC_SENSE2_R4_P")
	)
	(segment
		(start 260.171184 -393.53236)
		(end 260.171184 -393.136628)
		(width 0.254)
		(layer "F.Cu")
		(net "P12V_HSC_SENSE2_R4_N")
	)
	(segment
		(start 260.552184 -393.91336)
		(end 260.171184 -393.53236)
		(width 0.254)
		(layer "F.Cu")
		(net "P12V_HSC_SENSE2_R4_N")
	)
	(via
		(at 207.440276 -383.488184)
		(size 0.508)
		(drill 0.254)
		(layers "F.Cu" "B.Cu")
		(net "P12V_HSC_SENSE2_R4_N")
	)
	(via
		(at 260.552184 -393.91336)
		(size 0.508)
		(drill 0.254)
		(layers "F.Cu" "B.Cu")
		(net "P12V_HSC_SENSE2_R4_N")
	)
	(segment
		(start 206.953358 -383.488184)
		(end 206.829406 -383.612136)
		(width 0.254)
		(layer "B.Cu")
		(net "P12V_HSC_SENSE2_R4_N")
	)
	(segment
		(start 207.937354 -383.488184)
		(end 207.440276 -383.488184)
		(width 0.254)
		(layer "B.Cu")
		(net "P12V_HSC_SENSE2_R4_N")
	)
	(segment
		(start 208.061306 -383.612136)
		(end 207.937354 -383.488184)
		(width 0.254)
		(layer "B.Cu")
		(net "P12V_HSC_SENSE2_R4_N")
	)
	(segment
		(start 207.440276 -383.488184)
		(end 206.953358 -383.488184)
		(width 0.254)
		(layer "B.Cu")
		(net "P12V_HSC_SENSE2_R4_N")
	)
	(segment
		(start 209.151982 -384.504692)
		(end 207.943196 -383.295906)
		(width 0.254)
		(layer "In4.Cu")
		(net "P12V_HSC_SENSE2_R4_N")
	)
	(segment
		(start 210.590892 -384.504692)
		(end 209.151982 -384.504692)
		(width 0.254)
		(layer "In4.Cu")
		(net "P12V_HSC_SENSE2_R4_N")
	)
	(segment
		(start 240.75263 -396.959836)
		(end 227.080318 -383.287524)
		(width 0.254)
		(layer "In4.Cu")
		(net "P12V_HSC_SENSE2_R4_N")
	)
	(segment
		(start 227.080318 -383.287524)
		(end 211.80806 -383.287524)
		(width 0.254)
		(layer "In4.Cu")
		(net "P12V_HSC_SENSE2_R4_N")
	)
	(segment
		(start 211.80806 -383.287524)
		(end 210.590892 -384.504692)
		(width 0.254)
		(layer "In4.Cu")
		(net "P12V_HSC_SENSE2_R4_N")
	)
	(segment
		(start 260.361684 -395.338554)
		(end 258.740402 -396.959836)
		(width 0.254)
		(layer "In4.Cu")
		(net "P12V_HSC_SENSE2_R4_N")
	)
	(segment
		(start 260.361684 -394.567156)
		(end 260.361684 -395.338554)
		(width 0.254)
		(layer "In4.Cu")
		(net "P12V_HSC_SENSE2_R4_N")
	)
	(segment
		(start 260.552184 -393.91336)
		(end 260.552184 -394.376656)
		(width 0.254)
		(layer "In4.Cu")
		(net "P12V_HSC_SENSE2_R4_N")
	)
	(segment
		(start 260.552184 -394.376656)
		(end 260.361684 -394.567156)
		(width 0.254)
		(layer "In4.Cu")
		(net "P12V_HSC_SENSE2_R4_N")
	)
	(segment
		(start 207.943196 -383.295906)
		(end 207.632554 -383.295906)
		(width 0.254)
		(layer "In4.Cu")
		(net "P12V_HSC_SENSE2_R4_N")
	)
	(segment
		(start 207.632554 -383.295906)
		(end 207.440276 -383.488184)
		(width 0.254)
		(layer "In4.Cu")
		(net "P12V_HSC_SENSE2_R4_N")
	)
	(segment
		(start 258.740402 -396.959836)
		(end 240.75263 -396.959836)
		(width 0.254)
		(layer "In4.Cu")
		(net "P12V_HSC_SENSE2_R4_N")
	)
	(segment
		(start 252.144784 -394.29436)
		(end 252.144784 -394.690092)
		(width 0.254)
		(layer "F.Cu")
		(net "P12V_HSC_SENSE2_R3_P")
	)
	(segment
		(start 251.763784 -393.91336)
		(end 252.144784 -394.29436)
		(width 0.254)
		(layer "F.Cu")
		(net "P12V_HSC_SENSE2_R3_P")
	)
	(via
		(at 207.449166 -380.330456)
		(size 0.508)
		(drill 0.254)
		(layers "F.Cu" "B.Cu")
		(net "P12V_HSC_SENSE2_R3_P")
	)
	(via
		(at 251.763784 -393.91336)
		(size 0.508)
		(drill 0.254)
		(layers "F.Cu" "B.Cu")
		(net "P12V_HSC_SENSE2_R3_P")
	)
	(segment
		(start 206.953358 -380.330456)
		(end 206.829406 -380.206504)
		(width 0.254)
		(layer "B.Cu")
		(net "P12V_HSC_SENSE2_R3_P")
	)
	(segment
		(start 208.061306 -380.206504)
		(end 207.937354 -380.330456)
		(width 0.254)
		(layer "B.Cu")
		(net "P12V_HSC_SENSE2_R3_P")
	)
	(segment
		(start 207.937354 -380.330456)
		(end 207.449166 -380.330456)
		(width 0.254)
		(layer "B.Cu")
		(net "P12V_HSC_SENSE2_R3_P")
	)
	(segment
		(start 207.449166 -380.330456)
		(end 206.953358 -380.330456)
		(width 0.254)
		(layer "B.Cu")
		(net "P12V_HSC_SENSE2_R3_P")
	)
	(segment
		(start 241.524282 -395.633702)
		(end 225.153982 -379.263402)
		(width 0.254)
		(layer "In4.Cu")
		(net "P12V_HSC_SENSE2_R3_P")
	)
	(segment
		(start 207.630522 -380.511812)
		(end 207.449166 -380.330456)
		(width 0.254)
		(layer "In4.Cu")
		(net "P12V_HSC_SENSE2_R3_P")
	)
	(segment
		(start 208.386172 -380.268988)
		(end 208.143348 -380.511812)
		(width 0.254)
		(layer "In4.Cu")
		(net "P12V_HSC_SENSE2_R3_P")
	)
	(segment
		(start 208.143348 -380.511812)
		(end 207.630522 -380.511812)
		(width 0.254)
		(layer "In4.Cu")
		(net "P12V_HSC_SENSE2_R3_P")
	)
	(segment
		(start 225.153982 -379.263402)
		(end 208.900268 -379.263402)
		(width 0.254)
		(layer "In4.Cu")
		(net "P12V_HSC_SENSE2_R3_P")
	)
	(segment
		(start 251.501148 -395.633702)
		(end 241.524282 -395.633702)
		(width 0.254)
		(layer "In4.Cu")
		(net "P12V_HSC_SENSE2_R3_P")
	)
	(segment
		(start 251.954284 -395.180566)
		(end 251.501148 -395.633702)
		(width 0.254)
		(layer "In4.Cu")
		(net "P12V_HSC_SENSE2_R3_P")
	)
	(segment
		(start 251.954284 -394.10386)
		(end 251.954284 -395.180566)
		(width 0.254)
		(layer "In4.Cu")
		(net "P12V_HSC_SENSE2_R3_P")
	)
	(segment
		(start 251.763784 -393.91336)
		(end 251.954284 -394.10386)
		(width 0.254)
		(layer "In4.Cu")
		(net "P12V_HSC_SENSE2_R3_P")
	)
	(segment
		(start 208.386172 -379.777498)
		(end 208.386172 -380.268988)
		(width 0.254)
		(layer "In4.Cu")
		(net "P12V_HSC_SENSE2_R3_P")
	)
	(segment
		(start 208.900268 -379.263402)
		(end 208.386172 -379.777498)
		(width 0.254)
		(layer "In4.Cu")
		(net "P12V_HSC_SENSE2_R3_P")
	)
	(segment
		(start 252.525784 -393.91336)
		(end 252.144784 -393.53236)
		(width 0.254)
		(layer "F.Cu")
		(net "P12V_HSC_SENSE2_R3_N")
	)
	(segment
		(start 252.144784 -393.53236)
		(end 252.144784 -393.136628)
		(width 0.254)
		(layer "F.Cu")
		(net "P12V_HSC_SENSE2_R3_N")
	)
	(via
		(at 207.446118 -381.098552)
		(size 0.508)
		(drill 0.254)
		(layers "F.Cu" "B.Cu")
		(net "P12V_HSC_SENSE2_R3_N")
	)
	(via
		(at 252.525784 -393.91336)
		(size 0.508)
		(drill 0.254)
		(layers "F.Cu" "B.Cu")
		(net "P12V_HSC_SENSE2_R3_N")
	)
	(segment
		(start 206.953358 -381.098552)
		(end 206.829406 -381.222504)
		(width 0.254)
		(layer "B.Cu")
		(net "P12V_HSC_SENSE2_R3_N")
	)
	(segment
		(start 208.061306 -381.222504)
		(end 207.937354 -381.098552)
		(width 0.254)
		(layer "B.Cu")
		(net "P12V_HSC_SENSE2_R3_N")
	)
	(segment
		(start 207.446118 -381.098552)
		(end 206.953358 -381.098552)
		(width 0.254)
		(layer "B.Cu")
		(net "P12V_HSC_SENSE2_R3_N")
	)
	(segment
		(start 207.937354 -381.098552)
		(end 207.446118 -381.098552)
		(width 0.254)
		(layer "B.Cu")
		(net "P12V_HSC_SENSE2_R3_N")
	)
	(segment
		(start 208.767172 -379.935486)
		(end 208.767172 -380.426976)
		(width 0.254)
		(layer "In4.Cu")
		(net "P12V_HSC_SENSE2_R3_N")
	)
	(segment
		(start 252.335284 -394.10386)
		(end 252.335284 -395.338554)
		(width 0.254)
		(layer "In4.Cu")
		(net "P12V_HSC_SENSE2_R3_N")
	)
	(segment
		(start 252.525784 -393.91336)
		(end 252.335284 -394.10386)
		(width 0.254)
		(layer "In4.Cu")
		(net "P12V_HSC_SENSE2_R3_N")
	)
	(segment
		(start 251.659136 -396.014702)
		(end 241.366294 -396.014702)
		(width 0.254)
		(layer "In4.Cu")
		(net "P12V_HSC_SENSE2_R3_N")
	)
	(segment
		(start 241.366294 -396.014702)
		(end 224.995994 -379.644402)
		(width 0.254)
		(layer "In4.Cu")
		(net "P12V_HSC_SENSE2_R3_N")
	)
	(segment
		(start 208.767172 -380.426976)
		(end 208.301336 -380.892812)
		(width 0.254)
		(layer "In4.Cu")
		(net "P12V_HSC_SENSE2_R3_N")
	)
	(segment
		(start 207.651858 -380.892812)
		(end 207.446118 -381.098552)
		(width 0.254)
		(layer "In4.Cu")
		(net "P12V_HSC_SENSE2_R3_N")
	)
	(segment
		(start 252.335284 -395.338554)
		(end 251.659136 -396.014702)
		(width 0.254)
		(layer "In4.Cu")
		(net "P12V_HSC_SENSE2_R3_N")
	)
	(segment
		(start 208.301336 -380.892812)
		(end 207.651858 -380.892812)
		(width 0.254)
		(layer "In4.Cu")
		(net "P12V_HSC_SENSE2_R3_N")
	)
	(segment
		(start 209.058256 -379.644402)
		(end 208.767172 -379.935486)
		(width 0.254)
		(layer "In4.Cu")
		(net "P12V_HSC_SENSE2_R3_N")
	)
	(segment
		(start 224.995994 -379.644402)
		(end 209.058256 -379.644402)
		(width 0.254)
		(layer "In4.Cu")
		(net "P12V_HSC_SENSE2_R3_N")
	)
	(segment
		(start 267.816584 -393.91336)
		(end 268.197584 -394.29436)
		(width 0.254)
		(layer "F.Cu")
		(net "P12V_HSC_SENSE2_R2_P")
	)
	(segment
		(start 268.197584 -394.29436)
		(end 268.197584 -394.690092)
		(width 0.254)
		(layer "F.Cu")
		(net "P12V_HSC_SENSE2_R2_P")
	)
	(via
		(at 267.816584 -393.91336)
		(size 0.508)
		(drill 0.254)
		(layers "F.Cu" "B.Cu")
		(net "P12V_HSC_SENSE2_R2_P")
	)
	(via
		(at 207.440022 -385.263136)
		(size 0.508)
		(drill 0.254)
		(layers "F.Cu" "B.Cu")
		(net "P12V_HSC_SENSE2_R2_P")
	)
	(segment
		(start 208.061306 -385.136136)
		(end 207.934306 -385.263136)
		(width 0.254)
		(layer "B.Cu")
		(net "P12V_HSC_SENSE2_R2_P")
	)
	(segment
		(start 207.934306 -385.263136)
		(end 207.440022 -385.263136)
		(width 0.254)
		(layer "B.Cu")
		(net "P12V_HSC_SENSE2_R2_P")
	)
	(segment
		(start 206.956406 -385.263136)
		(end 206.829406 -385.136136)
		(width 0.254)
		(layer "B.Cu")
		(net "P12V_HSC_SENSE2_R2_P")
	)
	(segment
		(start 207.440022 -385.263136)
		(end 206.956406 -385.263136)
		(width 0.254)
		(layer "B.Cu")
		(net "P12V_HSC_SENSE2_R2_P")
	)
	(segment
		(start 268.007084 -392.848846)
		(end 267.791692 -392.633454)
		(width 0.254)
		(layer "In4.Cu")
		(net "P12V_HSC_SENSE2_R2_P")
	)
	(segment
		(start 268.007084 -393.72286)
		(end 268.007084 -392.848846)
		(width 0.254)
		(layer "In4.Cu")
		(net "P12V_HSC_SENSE2_R2_P")
	)
	(segment
		(start 206.591916 -385.2545)
		(end 206.827882 -385.490466)
		(width 0.254)
		(layer "In4.Cu")
		(net "P12V_HSC_SENSE2_R2_P")
	)
	(segment
		(start 206.827882 -385.490466)
		(end 207.212692 -385.490466)
		(width 0.254)
		(layer "In4.Cu")
		(net "P12V_HSC_SENSE2_R2_P")
	)
	(segment
		(start 267.791692 -392.633454)
		(end 241.312954 -392.633454)
		(width 0.254)
		(layer "In4.Cu")
		(net "P12V_HSC_SENSE2_R2_P")
	)
	(segment
		(start 267.816584 -393.91336)
		(end 268.007084 -393.72286)
		(width 0.254)
		(layer "In4.Cu")
		(net "P12V_HSC_SENSE2_R2_P")
	)
	(segment
		(start 224.493836 -375.814336)
		(end 208.103724 -375.814336)
		(width 0.254)
		(layer "In4.Cu")
		(net "P12V_HSC_SENSE2_R2_P")
	)
	(segment
		(start 207.212692 -385.490466)
		(end 207.440022 -385.263136)
		(width 0.254)
		(layer "In4.Cu")
		(net "P12V_HSC_SENSE2_R2_P")
	)
	(segment
		(start 241.312954 -392.633454)
		(end 224.493836 -375.814336)
		(width 0.254)
		(layer "In4.Cu")
		(net "P12V_HSC_SENSE2_R2_P")
	)
	(segment
		(start 206.591916 -377.326144)
		(end 206.591916 -385.2545)
		(width 0.254)
		(layer "In4.Cu")
		(net "P12V_HSC_SENSE2_R2_P")
	)
	(segment
		(start 208.103724 -375.814336)
		(end 206.591916 -377.326144)
		(width 0.254)
		(layer "In4.Cu")
		(net "P12V_HSC_SENSE2_R2_P")
	)
	(segment
		(start 268.197584 -393.53236)
		(end 268.197584 -393.136628)
		(width 0.254)
		(layer "F.Cu")
		(net "P12V_HSC_SENSE2_R2_N")
	)
	(segment
		(start 268.578584 -393.91336)
		(end 268.197584 -393.53236)
		(width 0.254)
		(layer "F.Cu")
		(net "P12V_HSC_SENSE2_R2_N")
	)
	(via
		(at 268.578584 -393.91336)
		(size 0.508)
		(drill 0.254)
		(layers "F.Cu" "B.Cu")
		(net "P12V_HSC_SENSE2_R2_N")
	)
	(via
		(at 207.443324 -386.03428)
		(size 0.508)
		(drill 0.254)
		(layers "F.Cu" "B.Cu")
		(net "P12V_HSC_SENSE2_R2_N")
	)
	(segment
		(start 208.061306 -386.152136)
		(end 207.94345 -386.03428)
		(width 0.254)
		(layer "B.Cu")
		(net "P12V_HSC_SENSE2_R2_N")
	)
	(segment
		(start 207.94345 -386.03428)
		(end 207.443324 -386.03428)
		(width 0.254)
		(layer "B.Cu")
		(net "P12V_HSC_SENSE2_R2_N")
	)
	(segment
		(start 206.947262 -386.03428)
		(end 206.829406 -386.152136)
		(width 0.254)
		(layer "B.Cu")
		(net "P12V_HSC_SENSE2_R2_N")
	)
	(segment
		(start 207.443324 -386.03428)
		(end 206.947262 -386.03428)
		(width 0.254)
		(layer "B.Cu")
		(net "P12V_HSC_SENSE2_R2_N")
	)
	(segment
		(start 206.210916 -377.168156)
		(end 207.945736 -375.433336)
		(width 0.254)
		(layer "In4.Cu")
		(net "P12V_HSC_SENSE2_R2_N")
	)
	(segment
		(start 207.443324 -386.03428)
		(end 207.28051 -385.871466)
		(width 0.254)
		(layer "In4.Cu")
		(net "P12V_HSC_SENSE2_R2_N")
	)
	(segment
		(start 241.470942 -392.252454)
		(end 267.94968 -392.252454)
		(width 0.254)
		(layer "In4.Cu")
		(net "P12V_HSC_SENSE2_R2_N")
	)
	(segment
		(start 206.210916 -385.412488)
		(end 206.210916 -377.168156)
		(width 0.254)
		(layer "In4.Cu")
		(net "P12V_HSC_SENSE2_R2_N")
	)
	(segment
		(start 268.388084 -392.690858)
		(end 268.388084 -393.72286)
		(width 0.254)
		(layer "In4.Cu")
		(net "P12V_HSC_SENSE2_R2_N")
	)
	(segment
		(start 268.388084 -393.72286)
		(end 268.578584 -393.91336)
		(width 0.254)
		(layer "In4.Cu")
		(net "P12V_HSC_SENSE2_R2_N")
	)
	(segment
		(start 206.669894 -385.871466)
		(end 206.210916 -385.412488)
		(width 0.254)
		(layer "In4.Cu")
		(net "P12V_HSC_SENSE2_R2_N")
	)
	(segment
		(start 224.651824 -375.433336)
		(end 241.470942 -392.252454)
		(width 0.254)
		(layer "In4.Cu")
		(net "P12V_HSC_SENSE2_R2_N")
	)
	(segment
		(start 267.94968 -392.252454)
		(end 268.388084 -392.690858)
		(width 0.254)
		(layer "In4.Cu")
		(net "P12V_HSC_SENSE2_R2_N")
	)
	(segment
		(start 207.28051 -385.871466)
		(end 206.669894 -385.871466)
		(width 0.254)
		(layer "In4.Cu")
		(net "P12V_HSC_SENSE2_R2_N")
	)
	(segment
		(start 207.945736 -375.433336)
		(end 224.651824 -375.433336)
		(width 0.254)
		(layer "In4.Cu")
		(net "P12V_HSC_SENSE2_R2_N")
	)
	(segment
		(start 244.115336 -394.290296)
		(end 243.734336 -393.909296)
		(width 0.254)
		(layer "F.Cu")
		(net "P12V_HSC_SENSE2_R1_P")
	)
	(segment
		(start 244.115336 -394.686028)
		(end 244.115336 -394.290296)
		(width 0.254)
		(layer "F.Cu")
		(net "P12V_HSC_SENSE2_R1_P")
	)
	(via
		(at 243.734336 -393.909296)
		(size 0.508)
		(drill 0.254)
		(layers "F.Cu" "B.Cu")
		(net "P12V_HSC_SENSE2_R1_P")
	)
	(via
		(at 207.43926 -377.793504)
		(size 0.508)
		(drill 0.254)
		(layers "F.Cu" "B.Cu")
		(net "P12V_HSC_SENSE2_R1_P")
	)
	(segment
		(start 207.43926 -377.793504)
		(end 206.956406 -377.793504)
		(width 0.254)
		(layer "B.Cu")
		(net "P12V_HSC_SENSE2_R1_P")
	)
	(segment
		(start 208.061306 -377.666504)
		(end 207.934306 -377.793504)
		(width 0.254)
		(layer "B.Cu")
		(net "P12V_HSC_SENSE2_R1_P")
	)
	(segment
		(start 207.934306 -377.793504)
		(end 207.43926 -377.793504)
		(width 0.254)
		(layer "B.Cu")
		(net "P12V_HSC_SENSE2_R1_P")
	)
	(segment
		(start 206.956406 -377.793504)
		(end 206.829406 -377.666504)
		(width 0.254)
		(layer "B.Cu")
		(net "P12V_HSC_SENSE2_R1_P")
	)
	(segment
		(start 243.924836 -394.099796)
		(end 243.734336 -393.909296)
		(width 0.254)
		(layer "In4.Cu")
		(net "P12V_HSC_SENSE2_R1_P")
	)
	(segment
		(start 224.328482 -376.774202)
		(end 242.149122 -394.594842)
		(width 0.254)
		(layer "In4.Cu")
		(net "P12V_HSC_SENSE2_R1_P")
	)
	(segment
		(start 207.661002 -378.015246)
		(end 207.955388 -378.015246)
		(width 0.254)
		(layer "In4.Cu")
		(net "P12V_HSC_SENSE2_R1_P")
	)
	(segment
		(start 209.196432 -376.774202)
		(end 224.328482 -376.774202)
		(width 0.254)
		(layer "In4.Cu")
		(net "P12V_HSC_SENSE2_R1_P")
	)
	(segment
		(start 243.924836 -394.467842)
		(end 243.924836 -394.099796)
		(width 0.254)
		(layer "In4.Cu")
		(net "P12V_HSC_SENSE2_R1_P")
	)
	(segment
		(start 243.797836 -394.594842)
		(end 243.924836 -394.467842)
		(width 0.254)
		(layer "In4.Cu")
		(net "P12V_HSC_SENSE2_R1_P")
	)
	(segment
		(start 242.149122 -394.594842)
		(end 243.797836 -394.594842)
		(width 0.254)
		(layer "In4.Cu")
		(net "P12V_HSC_SENSE2_R1_P")
	)
	(segment
		(start 207.43926 -377.793504)
		(end 207.661002 -378.015246)
		(width 0.254)
		(layer "In4.Cu")
		(net "P12V_HSC_SENSE2_R1_P")
	)
	(segment
		(start 207.955388 -378.015246)
		(end 209.196432 -376.774202)
		(width 0.254)
		(layer "In4.Cu")
		(net "P12V_HSC_SENSE2_R1_P")
	)
	(segment
		(start 244.496336 -393.909296)
		(end 244.115336 -393.528296)
		(width 0.254)
		(layer "F.Cu")
		(net "P12V_HSC_SENSE2_R1_N")
	)
	(segment
		(start 244.115336 -393.528296)
		(end 244.115336 -393.132564)
		(width 0.254)
		(layer "F.Cu")
		(net "P12V_HSC_SENSE2_R1_N")
	)
	(via
		(at 207.43926 -378.555504)
		(size 0.508)
		(drill 0.254)
		(layers "F.Cu" "B.Cu")
		(net "P12V_HSC_SENSE2_R1_N")
	)
	(via
		(at 244.496336 -393.909296)
		(size 0.508)
		(drill 0.254)
		(layers "F.Cu" "B.Cu")
		(net "P12V_HSC_SENSE2_R1_N")
	)
	(segment
		(start 207.43926 -378.555504)
		(end 206.956406 -378.555504)
		(width 0.254)
		(layer "B.Cu")
		(net "P12V_HSC_SENSE2_R1_N")
	)
	(segment
		(start 207.934306 -378.555504)
		(end 207.43926 -378.555504)
		(width 0.254)
		(layer "B.Cu")
		(net "P12V_HSC_SENSE2_R1_N")
	)
	(segment
		(start 208.061306 -378.682504)
		(end 207.934306 -378.555504)
		(width 0.254)
		(layer "B.Cu")
		(net "P12V_HSC_SENSE2_R1_N")
	)
	(segment
		(start 206.956406 -378.555504)
		(end 206.829406 -378.682504)
		(width 0.254)
		(layer "B.Cu")
		(net "P12V_HSC_SENSE2_R1_N")
	)
	(segment
		(start 208.113376 -378.396246)
		(end 209.35442 -377.155202)
		(width 0.254)
		(layer "In4.Cu")
		(net "P12V_HSC_SENSE2_R1_N")
	)
	(segment
		(start 224.170494 -377.155202)
		(end 241.991134 -394.975842)
		(width 0.254)
		(layer "In4.Cu")
		(net "P12V_HSC_SENSE2_R1_N")
	)
	(segment
		(start 209.35442 -377.155202)
		(end 224.170494 -377.155202)
		(width 0.254)
		(layer "In4.Cu")
		(net "P12V_HSC_SENSE2_R1_N")
	)
	(segment
		(start 244.305836 -394.62583)
		(end 244.305836 -394.099796)
		(width 0.254)
		(layer "In4.Cu")
		(net "P12V_HSC_SENSE2_R1_N")
	)
	(segment
		(start 207.43926 -378.555504)
		(end 207.598518 -378.396246)
		(width 0.254)
		(layer "In4.Cu")
		(net "P12V_HSC_SENSE2_R1_N")
	)
	(segment
		(start 243.955824 -394.975842)
		(end 244.305836 -394.62583)
		(width 0.254)
		(layer "In4.Cu")
		(net "P12V_HSC_SENSE2_R1_N")
	)
	(segment
		(start 244.305836 -394.099796)
		(end 244.496336 -393.909296)
		(width 0.254)
		(layer "In4.Cu")
		(net "P12V_HSC_SENSE2_R1_N")
	)
	(segment
		(start 241.991134 -394.975842)
		(end 243.955824 -394.975842)
		(width 0.254)
		(layer "In4.Cu")
		(net "P12V_HSC_SENSE2_R1_N")
	)
	(segment
		(start 207.598518 -378.396246)
		(end 208.113376 -378.396246)
		(width 0.254)
		(layer "In4.Cu")
		(net "P12V_HSC_SENSE2_R1_N")
	)
	(segment
		(start 197.999858 -381.160528)
		(end 199.206358 -381.160528)
		(width 0.254)
		(layer "F.Cu")
		(net "P12V_HSC_SENSE2_P")
	)
	(via
		(at 205.413356 -385.263136)
		(size 0.508)
		(drill 0.254)
		(layers "F.Cu" "B.Cu")
		(net "P12V_HSC_SENSE2_P")
	)
	(via
		(at 205.413356 -377.793504)
		(size 0.508)
		(drill 0.254)
		(layers "F.Cu" "B.Cu")
		(net "P12V_HSC_SENSE2_P")
	)
	(via
		(at 205.413356 -382.723136)
		(size 0.508)
		(drill 0.254)
		(layers "F.Cu" "B.Cu")
		(net "P12V_HSC_SENSE2_P")
	)
	(via
		(at 199.206358 -381.160528)
		(size 0.508)
		(drill 0.254)
		(layers "F.Cu" "B.Cu")
		(net "P12V_HSC_SENSE2_P")
	)
	(segment
		(start 205.902306 -377.793504)
		(end 205.413356 -377.793504)
		(width 0.254)
		(layer "B.Cu")
		(net "P12V_HSC_SENSE2_P")
	)
	(segment
		(start 206.029306 -380.206504)
		(end 205.711806 -380.524004)
		(width 0.254)
		(layer "B.Cu")
		(net "P12V_HSC_SENSE2_P")
	)
	(segment
		(start 199.515984 -381.470154)
		(end 199.206358 -381.160528)
		(width 0.254)
		(layer "B.Cu")
		(net "P12V_HSC_SENSE2_P")
	)
	(segment
		(start 205.902306 -385.263136)
		(end 205.413356 -385.263136)
		(width 0.254)
		(layer "B.Cu")
		(net "P12V_HSC_SENSE2_P")
	)
	(segment
		(start 206.029306 -377.666504)
		(end 205.902306 -377.793504)
		(width 0.254)
		(layer "B.Cu")
		(net "P12V_HSC_SENSE2_P")
	)
	(segment
		(start 206.029306 -385.136136)
		(end 205.902306 -385.263136)
		(width 0.254)
		(layer "B.Cu")
		(net "P12V_HSC_SENSE2_P")
	)
	(segment
		(start 200.157334 -381.757428)
		(end 199.87006 -381.470154)
		(width 0.254)
		(layer "B.Cu")
		(net "P12V_HSC_SENSE2_P")
	)
	(segment
		(start 205.902306 -382.723136)
		(end 205.413356 -382.723136)
		(width 0.254)
		(layer "B.Cu")
		(net "P12V_HSC_SENSE2_P")
	)
	(segment
		(start 205.711806 -380.524004)
		(end 203.884276 -380.524004)
		(width 0.254)
		(layer "B.Cu")
		(net "P12V_HSC_SENSE2_P")
	)
	(segment
		(start 203.884276 -380.524004)
		(end 202.650852 -381.757428)
		(width 0.254)
		(layer "B.Cu")
		(net "P12V_HSC_SENSE2_P")
	)
	(segment
		(start 199.87006 -381.470154)
		(end 199.515984 -381.470154)
		(width 0.254)
		(layer "B.Cu")
		(net "P12V_HSC_SENSE2_P")
	)
	(segment
		(start 206.029306 -382.596136)
		(end 205.902306 -382.723136)
		(width 0.254)
		(layer "B.Cu")
		(net "P12V_HSC_SENSE2_P")
	)
	(segment
		(start 202.650852 -381.757428)
		(end 200.157334 -381.757428)
		(width 0.254)
		(layer "B.Cu")
		(net "P12V_HSC_SENSE2_P")
	)
	(segment
		(start 203.853542 -385.453636)
		(end 199.87641 -381.476504)
		(width 0.254)
		(layer "In2.Cu")
		(net "P12V_HSC_SENSE2_P")
	)
	(segment
		(start 199.522588 -381.476504)
		(end 199.206358 -381.160528)
		(width 0.254)
		(layer "In2.Cu")
		(net "P12V_HSC_SENSE2_P")
	)
	(segment
		(start 205.222856 -385.453636)
		(end 203.853542 -385.453636)
		(width 0.254)
		(layer "In2.Cu")
		(net "P12V_HSC_SENSE2_P")
	)
	(segment
		(start 199.87641 -381.476504)
		(end 199.522588 -381.476504)
		(width 0.254)
		(layer "In2.Cu")
		(net "P12V_HSC_SENSE2_P")
	)
	(segment
		(start 205.413356 -385.263136)
		(end 205.222856 -385.453636)
		(width 0.254)
		(layer "In2.Cu")
		(net "P12V_HSC_SENSE2_P")
	)
	(segment
		(start 199.87006 -381.470154)
		(end 199.515984 -381.470154)
		(width 0.254)
		(layer "In6.Cu")
		(net "P12V_HSC_SENSE2_P")
	)
	(segment
		(start 201.841608 -382.053846)
		(end 200.453752 -382.053846)
		(width 0.254)
		(layer "In6.Cu")
		(net "P12V_HSC_SENSE2_P")
	)
	(segment
		(start 200.453752 -382.053846)
		(end 199.87006 -381.470154)
		(width 0.254)
		(layer "In6.Cu")
		(net "P12V_HSC_SENSE2_P")
	)
	(segment
		(start 199.515984 -381.470154)
		(end 199.206358 -381.160528)
		(width 0.254)
		(layer "In6.Cu")
		(net "P12V_HSC_SENSE2_P")
	)
	(segment
		(start 205.413356 -382.723136)
		(end 205.222856 -382.913636)
		(width 0.254)
		(layer "In6.Cu")
		(net "P12V_HSC_SENSE2_P")
	)
	(segment
		(start 205.222856 -382.913636)
		(end 202.701398 -382.913636)
		(width 0.254)
		(layer "In6.Cu")
		(net "P12V_HSC_SENSE2_P")
	)
	(segment
		(start 202.701398 -382.913636)
		(end 201.841608 -382.053846)
		(width 0.254)
		(layer "In6.Cu")
		(net "P12V_HSC_SENSE2_P")
	)
	(segment
		(start 200.609708 -381.757428)
		(end 200.182226 -381.757428)
		(width 0.254)
		(layer "In15.Cu")
		(net "P12V_HSC_SENSE2_P")
	)
	(segment
		(start 199.894952 -381.470154)
		(end 199.515984 -381.470154)
		(width 0.254)
		(layer "In15.Cu")
		(net "P12V_HSC_SENSE2_P")
	)
	(segment
		(start 200.182226 -381.757428)
		(end 199.894952 -381.470154)
		(width 0.254)
		(layer "In15.Cu")
		(net "P12V_HSC_SENSE2_P")
	)
	(segment
		(start 205.222856 -377.984004)
		(end 204.383132 -377.984004)
		(width 0.254)
		(layer "In15.Cu")
		(net "P12V_HSC_SENSE2_P")
	)
	(segment
		(start 199.515984 -381.470154)
		(end 199.206358 -381.160528)
		(width 0.254)
		(layer "In15.Cu")
		(net "P12V_HSC_SENSE2_P")
	)
	(segment
		(start 204.383132 -377.984004)
		(end 200.609708 -381.757428)
		(width 0.254)
		(layer "In15.Cu")
		(net "P12V_HSC_SENSE2_P")
	)
	(segment
		(start 205.413356 -377.793504)
		(end 205.222856 -377.984004)
		(width 0.254)
		(layer "In15.Cu")
		(net "P12V_HSC_SENSE2_P")
	)
	(segment
		(start 197.999858 -382.160526)
		(end 199.206358 -382.160526)
		(width 0.254)
		(layer "F.Cu")
		(net "P12V_HSC_SENSE2_N")
	)
	(via
		(at 205.413356 -383.485136)
		(size 0.508)
		(drill 0.254)
		(layers "F.Cu" "B.Cu")
		(net "P12V_HSC_SENSE2_N")
	)
	(via
		(at 205.413356 -386.025136)
		(size 0.508)
		(drill 0.254)
		(layers "F.Cu" "B.Cu")
		(net "P12V_HSC_SENSE2_N")
	)
	(via
		(at 199.206358 -382.160526)
		(size 0.508)
		(drill 0.254)
		(layers "F.Cu" "B.Cu")
		(net "P12V_HSC_SENSE2_N")
	)
	(via
		(at 205.413356 -378.555504)
		(size 0.508)
		(drill 0.254)
		(layers "F.Cu" "B.Cu")
		(net "P12V_HSC_SENSE2_N")
	)
	(segment
		(start 199.999346 -382.138428)
		(end 199.712072 -381.851154)
		(width 0.254)
		(layer "B.Cu")
		(net "P12V_HSC_SENSE2_N")
	)
	(segment
		(start 199.712072 -381.851154)
		(end 199.51573 -381.851154)
		(width 0.254)
		(layer "B.Cu")
		(net "P12V_HSC_SENSE2_N")
	)
	(segment
		(start 199.51573 -381.851154)
		(end 199.206358 -382.160526)
		(width 0.254)
		(layer "B.Cu")
		(net "P12V_HSC_SENSE2_N")
	)
	(segment
		(start 204.042264 -380.905004)
		(end 202.80884 -382.138428)
		(width 0.254)
		(layer "B.Cu")
		(net "P12V_HSC_SENSE2_N")
	)
	(segment
		(start 205.711806 -380.905004)
		(end 204.042264 -380.905004)
		(width 0.254)
		(layer "B.Cu")
		(net "P12V_HSC_SENSE2_N")
	)
	(segment
		(start 206.029306 -378.682504)
		(end 205.902306 -378.555504)
		(width 0.254)
		(layer "B.Cu")
		(net "P12V_HSC_SENSE2_N")
	)
	(segment
		(start 206.029306 -386.152136)
		(end 205.902306 -386.025136)
		(width 0.254)
		(layer "B.Cu")
		(net "P12V_HSC_SENSE2_N")
	)
	(segment
		(start 202.80884 -382.138428)
		(end 199.999346 -382.138428)
		(width 0.254)
		(layer "B.Cu")
		(net "P12V_HSC_SENSE2_N")
	)
	(segment
		(start 205.902306 -386.025136)
		(end 205.413356 -386.025136)
		(width 0.254)
		(layer "B.Cu")
		(net "P12V_HSC_SENSE2_N")
	)
	(segment
		(start 205.902306 -383.485136)
		(end 205.413356 -383.485136)
		(width 0.254)
		(layer "B.Cu")
		(net "P12V_HSC_SENSE2_N")
	)
	(segment
		(start 206.029306 -383.612136)
		(end 205.902306 -383.485136)
		(width 0.254)
		(layer "B.Cu")
		(net "P12V_HSC_SENSE2_N")
	)
	(segment
		(start 205.902306 -378.555504)
		(end 205.413356 -378.555504)
		(width 0.254)
		(layer "B.Cu")
		(net "P12V_HSC_SENSE2_N")
	)
	(segment
		(start 206.029306 -381.222504)
		(end 205.711806 -380.905004)
		(width 0.254)
		(layer "B.Cu")
		(net "P12V_HSC_SENSE2_N")
	)
	(segment
		(start 199.50938 -381.857504)
		(end 199.206358 -382.160526)
		(width 0.254)
		(layer "In2.Cu")
		(net "P12V_HSC_SENSE2_N")
	)
	(segment
		(start 199.718422 -381.857504)
		(end 199.50938 -381.857504)
		(width 0.254)
		(layer "In2.Cu")
		(net "P12V_HSC_SENSE2_N")
	)
	(segment
		(start 205.413356 -386.025136)
		(end 205.222856 -385.834636)
		(width 0.254)
		(layer "In2.Cu")
		(net "P12V_HSC_SENSE2_N")
	)
	(segment
		(start 203.695554 -385.834636)
		(end 199.718422 -381.857504)
		(width 0.254)
		(layer "In2.Cu")
		(net "P12V_HSC_SENSE2_N")
	)
	(segment
		(start 205.222856 -385.834636)
		(end 203.695554 -385.834636)
		(width 0.254)
		(layer "In2.Cu")
		(net "P12V_HSC_SENSE2_N")
	)
	(segment
		(start 199.51573 -381.851154)
		(end 199.206358 -382.160526)
		(width 0.254)
		(layer "In6.Cu")
		(net "P12V_HSC_SENSE2_N")
	)
	(segment
		(start 205.413356 -383.485136)
		(end 205.222856 -383.294636)
		(width 0.254)
		(layer "In6.Cu")
		(net "P12V_HSC_SENSE2_N")
	)
	(segment
		(start 200.295764 -382.434846)
		(end 199.712072 -381.851154)
		(width 0.254)
		(layer "In6.Cu")
		(net "P12V_HSC_SENSE2_N")
	)
	(segment
		(start 201.68362 -382.434846)
		(end 200.295764 -382.434846)
		(width 0.254)
		(layer "In6.Cu")
		(net "P12V_HSC_SENSE2_N")
	)
	(segment
		(start 199.712072 -381.851154)
		(end 199.51573 -381.851154)
		(width 0.254)
		(layer "In6.Cu")
		(net "P12V_HSC_SENSE2_N")
	)
	(segment
		(start 205.222856 -383.294636)
		(end 202.54341 -383.294636)
		(width 0.254)
		(layer "In6.Cu")
		(net "P12V_HSC_SENSE2_N")
	)
	(segment
		(start 202.54341 -383.294636)
		(end 201.68362 -382.434846)
		(width 0.254)
		(layer "In6.Cu")
		(net "P12V_HSC_SENSE2_N")
	)
	(segment
		(start 199.51573 -381.851154)
		(end 199.206358 -382.160526)
		(width 0.254)
		(layer "In15.Cu")
		(net "P12V_HSC_SENSE2_N")
	)
	(segment
		(start 204.54112 -378.365004)
		(end 200.767696 -382.138428)
		(width 0.254)
		(layer "In15.Cu")
		(net "P12V_HSC_SENSE2_N")
	)
	(segment
		(start 200.024238 -382.138428)
		(end 199.736964 -381.851154)
		(width 0.254)
		(layer "In15.Cu")
		(net "P12V_HSC_SENSE2_N")
	)
	(segment
		(start 200.767696 -382.138428)
		(end 200.024238 -382.138428)
		(width 0.254)
		(layer "In15.Cu")
		(net "P12V_HSC_SENSE2_N")
	)
	(segment
		(start 205.222856 -378.365004)
		(end 204.54112 -378.365004)
		(width 0.254)
		(layer "In15.Cu")
		(net "P12V_HSC_SENSE2_N")
	)
	(segment
		(start 205.413356 -378.555504)
		(end 205.222856 -378.365004)
		(width 0.254)
		(layer "In15.Cu")
		(net "P12V_HSC_SENSE2_N")
	)
	(segment
		(start 199.736964 -381.851154)
		(end 199.51573 -381.851154)
		(width 0.254)
		(layer "In15.Cu")
		(net "P12V_HSC_SENSE2_N")
	)
	(segment
		(start 200.91908 -379.470158)
		(end 202.313032 -380.86411)
		(width 0.254)
		(layer "F.Cu")
		(net "P12V_HSC_SENSE1_P")
	)
	(segment
		(start 206.128112 -387.993636)
		(end 207.254856 -387.993636)
		(width 0.254)
		(layer "F.Cu")
		(net "P12V_HSC_SENSE1_P")
	)
	(segment
		(start 207.254856 -387.993636)
		(end 207.445356 -387.803136)
		(width 0.254)
		(layer "F.Cu")
		(net "P12V_HSC_SENSE1_P")
	)
	(segment
		(start 197.999858 -379.160532)
		(end 199.206358 -379.160532)
		(width 0.254)
		(layer "F.Cu")
		(net "P12V_HSC_SENSE1_P")
	)
	(segment
		(start 199.515984 -379.470158)
		(end 200.91908 -379.470158)
		(width 0.254)
		(layer "F.Cu")
		(net "P12V_HSC_SENSE1_P")
	)
	(segment
		(start 277.224236 -394.280136)
		(end 277.224236 -396.073122)
		(width 0.254)
		(layer "F.Cu")
		(net "P12V_HSC_SENSE1_P")
	)
	(segment
		(start 199.206358 -379.160532)
		(end 199.515984 -379.470158)
		(width 0.254)
		(layer "F.Cu")
		(net "P12V_HSC_SENSE1_P")
	)
	(segment
		(start 202.313032 -380.86411)
		(end 202.313032 -384.178556)
		(width 0.254)
		(layer "F.Cu")
		(net "P12V_HSC_SENSE1_P")
	)
	(segment
		(start 202.313032 -384.178556)
		(end 206.128112 -387.993636)
		(width 0.254)
		(layer "F.Cu")
		(net "P12V_HSC_SENSE1_P")
	)
	(segment
		(start 277.605236 -393.899136)
		(end 277.224236 -394.280136)
		(width 0.254)
		(layer "F.Cu")
		(net "P12V_HSC_SENSE1_P")
	)
	(via
		(at 277.605236 -393.899136)
		(size 0.508)
		(drill 0.254)
		(layers "F.Cu" "B.Cu")
		(net "P12V_HSC_SENSE1_P")
	)
	(via
		(at 207.445356 -387.803136)
		(size 0.508)
		(drill 0.254)
		(layers "F.Cu" "B.Cu")
		(net "P12V_HSC_SENSE1_P")
	)
	(segment
		(start 208.061306 -387.676136)
		(end 207.934306 -387.803136)
		(width 0.254)
		(layer "B.Cu")
		(net "P12V_HSC_SENSE1_P")
	)
	(segment
		(start 207.934306 -387.803136)
		(end 207.445356 -387.803136)
		(width 0.254)
		(layer "B.Cu")
		(net "P12V_HSC_SENSE1_P")
	)
	(segment
		(start 224.76333 -374.65762)
		(end 237.702852 -387.597142)
		(width 0.254)
		(layer "In4.Cu")
		(net "P12V_HSC_SENSE1_P")
	)
	(segment
		(start 273.68627 -395.31163)
		(end 277.064724 -395.31163)
		(width 0.254)
		(layer "In4.Cu")
		(net "P12V_HSC_SENSE1_P")
	)
	(segment
		(start 239.018572 -387.597142)
		(end 242.30965 -390.88822)
		(width 0.254)
		(layer "In4.Cu")
		(net "P12V_HSC_SENSE1_P")
	)
	(segment
		(start 237.702852 -387.597142)
		(end 239.018572 -387.597142)
		(width 0.254)
		(layer "In4.Cu")
		(net "P12V_HSC_SENSE1_P")
	)
	(segment
		(start 207.445356 -387.803136)
		(end 207.215486 -388.033006)
		(width 0.254)
		(layer "In4.Cu")
		(net "P12V_HSC_SENSE1_P")
	)
	(segment
		(start 204.389482 -386.87248)
		(end 204.389482 -376.971052)
		(width 0.254)
		(layer "In4.Cu")
		(net "P12V_HSC_SENSE1_P")
	)
	(segment
		(start 204.389482 -376.971052)
		(end 206.702914 -374.65762)
		(width 0.254)
		(layer "In4.Cu")
		(net "P12V_HSC_SENSE1_P")
	)
	(segment
		(start 206.702914 -374.65762)
		(end 224.76333 -374.65762)
		(width 0.254)
		(layer "In4.Cu")
		(net "P12V_HSC_SENSE1_P")
	)
	(segment
		(start 277.414736 -394.089636)
		(end 277.605236 -393.899136)
		(width 0.254)
		(layer "In4.Cu")
		(net "P12V_HSC_SENSE1_P")
	)
	(segment
		(start 277.414736 -394.961618)
		(end 277.414736 -394.089636)
		(width 0.254)
		(layer "In4.Cu")
		(net "P12V_HSC_SENSE1_P")
	)
	(segment
		(start 269.26286 -390.88822)
		(end 273.68627 -395.31163)
		(width 0.254)
		(layer "In4.Cu")
		(net "P12V_HSC_SENSE1_P")
	)
	(segment
		(start 207.215486 -388.033006)
		(end 205.550008 -388.033006)
		(width 0.254)
		(layer "In4.Cu")
		(net "P12V_HSC_SENSE1_P")
	)
	(segment
		(start 277.064724 -395.31163)
		(end 277.414736 -394.961618)
		(width 0.254)
		(layer "In4.Cu")
		(net "P12V_HSC_SENSE1_P")
	)
	(segment
		(start 205.550008 -388.033006)
		(end 204.389482 -386.87248)
		(width 0.254)
		(layer "In4.Cu")
		(net "P12V_HSC_SENSE1_P")
	)
	(segment
		(start 242.30965 -390.88822)
		(end 269.26286 -390.88822)
		(width 0.254)
		(layer "In4.Cu")
		(net "P12V_HSC_SENSE1_P")
	)
	(segment
		(start 199.51573 -379.851158)
		(end 200.761092 -379.851158)
		(width 0.254)
		(layer "F.Cu")
		(net "P12V_HSC_SENSE1_N")
	)
	(segment
		(start 277.224236 -393.518136)
		(end 277.224236 -391.72515)
		(width 0.254)
		(layer "F.Cu")
		(net "P12V_HSC_SENSE1_N")
	)
	(segment
		(start 199.206358 -380.16053)
		(end 199.51573 -379.851158)
		(width 0.254)
		(layer "F.Cu")
		(net "P12V_HSC_SENSE1_N")
	)
	(segment
		(start 201.932032 -384.336544)
		(end 205.970124 -388.374636)
		(width 0.254)
		(layer "F.Cu")
		(net "P12V_HSC_SENSE1_N")
	)
	(segment
		(start 200.761092 -379.851158)
		(end 201.932032 -381.022098)
		(width 0.254)
		(layer "F.Cu")
		(net "P12V_HSC_SENSE1_N")
	)
	(segment
		(start 207.254856 -388.374636)
		(end 207.445356 -388.565136)
		(width 0.254)
		(layer "F.Cu")
		(net "P12V_HSC_SENSE1_N")
	)
	(segment
		(start 197.999858 -380.16053)
		(end 199.206358 -380.16053)
		(width 0.254)
		(layer "F.Cu")
		(net "P12V_HSC_SENSE1_N")
	)
	(segment
		(start 201.932032 -381.022098)
		(end 201.932032 -384.336544)
		(width 0.254)
		(layer "F.Cu")
		(net "P12V_HSC_SENSE1_N")
	)
	(segment
		(start 276.843236 -393.899136)
		(end 277.224236 -393.518136)
		(width 0.254)
		(layer "F.Cu")
		(net "P12V_HSC_SENSE1_N")
	)
	(segment
		(start 205.970124 -388.374636)
		(end 207.254856 -388.374636)
		(width 0.254)
		(layer "F.Cu")
		(net "P12V_HSC_SENSE1_N")
	)
	(via
		(at 207.445356 -388.565136)
		(size 0.508)
		(drill 0.254)
		(layers "F.Cu" "B.Cu")
		(net "P12V_HSC_SENSE1_N")
	)
	(via
		(at 276.843236 -393.899136)
		(size 0.508)
		(drill 0.254)
		(layers "F.Cu" "B.Cu")
		(net "P12V_HSC_SENSE1_N")
	)
	(segment
		(start 207.934306 -388.565136)
		(end 207.445356 -388.565136)
		(width 0.254)
		(layer "B.Cu")
		(net "P12V_HSC_SENSE1_N")
	)
	(segment
		(start 208.061306 -388.692136)
		(end 207.934306 -388.565136)
		(width 0.254)
		(layer "B.Cu")
		(net "P12V_HSC_SENSE1_N")
	)
	(segment
		(start 224.921318 -374.27662)
		(end 237.86084 -387.216142)
		(width 0.254)
		(layer "In4.Cu")
		(net "P12V_HSC_SENSE1_N")
	)
	(segment
		(start 277.033736 -394.80363)
		(end 277.033736 -394.089636)
		(width 0.254)
		(layer "In4.Cu")
		(net "P12V_HSC_SENSE1_N")
	)
	(segment
		(start 277.033736 -394.089636)
		(end 276.843236 -393.899136)
		(width 0.254)
		(layer "In4.Cu")
		(net "P12V_HSC_SENSE1_N")
	)
	(segment
		(start 269.420848 -390.50722)
		(end 273.844258 -394.93063)
		(width 0.254)
		(layer "In4.Cu")
		(net "P12V_HSC_SENSE1_N")
	)
	(segment
		(start 204.008482 -376.813064)
		(end 206.544926 -374.27662)
		(width 0.254)
		(layer "In4.Cu")
		(net "P12V_HSC_SENSE1_N")
	)
	(segment
		(start 242.467638 -390.50722)
		(end 269.420848 -390.50722)
		(width 0.254)
		(layer "In4.Cu")
		(net "P12V_HSC_SENSE1_N")
	)
	(segment
		(start 276.906736 -394.93063)
		(end 277.033736 -394.80363)
		(width 0.254)
		(layer "In4.Cu")
		(net "P12V_HSC_SENSE1_N")
	)
	(segment
		(start 237.86084 -387.216142)
		(end 239.17656 -387.216142)
		(width 0.254)
		(layer "In4.Cu")
		(net "P12V_HSC_SENSE1_N")
	)
	(segment
		(start 273.844258 -394.93063)
		(end 276.906736 -394.93063)
		(width 0.254)
		(layer "In4.Cu")
		(net "P12V_HSC_SENSE1_N")
	)
	(segment
		(start 207.445356 -388.565136)
		(end 207.445356 -388.541006)
		(width 0.254)
		(layer "In4.Cu")
		(net "P12V_HSC_SENSE1_N")
	)
	(segment
		(start 239.17656 -387.216142)
		(end 242.467638 -390.50722)
		(width 0.254)
		(layer "In4.Cu")
		(net "P12V_HSC_SENSE1_N")
	)
	(segment
		(start 207.445356 -388.541006)
		(end 207.318356 -388.414006)
		(width 0.254)
		(layer "In4.Cu")
		(net "P12V_HSC_SENSE1_N")
	)
	(segment
		(start 207.318356 -388.414006)
		(end 205.39202 -388.414006)
		(width 0.254)
		(layer "In4.Cu")
		(net "P12V_HSC_SENSE1_N")
	)
	(segment
		(start 206.544926 -374.27662)
		(end 224.921318 -374.27662)
		(width 0.254)
		(layer "In4.Cu")
		(net "P12V_HSC_SENSE1_N")
	)
	(segment
		(start 205.39202 -388.414006)
		(end 204.008482 -387.030468)
		(width 0.254)
		(layer "In4.Cu")
		(net "P12V_HSC_SENSE1_N")
	)
	(segment
		(start 204.008482 -387.030468)
		(end 204.008482 -376.813064)
		(width 0.254)
		(layer "In4.Cu")
		(net "P12V_HSC_SENSE1_N")
	)
	(via
		(at 249.369072 -381.305816)
		(size 0.508)
		(drill 0.254)
		(layers "F.Cu" "B.Cu")
		(net "P12V_HSC_GATE_G6")
	)
	(via
		(at 243.434108 -381.305816)
		(size 0.508)
		(drill 0.254)
		(layers "F.Cu" "B.Cu")
		(net "P12V_HSC_GATE_G5")
	)
	(via
		(at 273.108928 -381.305816)
		(size 0.508)
		(drill 0.254)
		(layers "F.Cu" "B.Cu")
		(net "P12V_HSC_GATE_G4")
	)
	(via
		(at 267.173964 -381.305816)
		(size 0.508)
		(drill 0.254)
		(layers "F.Cu" "B.Cu")
		(net "P12V_HSC_GATE_G3")
	)
	(via
		(at 261.239 -381.305816)
		(size 0.508)
		(drill 0.254)
		(layers "F.Cu" "B.Cu")
		(net "P12V_HSC_GATE_G2")
	)
	(via
		(at 255.304036 -381.305816)
		(size 0.508)
		(drill 0.254)
		(layers "F.Cu" "B.Cu")
		(net "P12V_HSC_GATE_G1")
	)
	(via
		(at 244.704108 -381.305816)
		(size 0.508)
		(drill 0.254)
		(layers "F.Cu" "B.Cu")
		(net "P12V_HSC_GATE2")
	)
	(via
		(at 196.752464 -386.171694)
		(size 0.508)
		(drill 0.254)
		(layers "F.Cu" "B.Cu")
		(net "P12V_HSC_GATE2")
	)
	(via
		(at 268.443964 -381.305816)
		(size 0.508)
		(drill 0.254)
		(layers "F.Cu" "B.Cu")
		(net "P12V_HSC_GATE2")
	)
	(via
		(at 196.318124 -386.816854)
		(size 0.508)
		(drill 0.254)
		(layers "F.Cu" "B.Cu")
		(net "P12V_HSC_GATE2")
	)
	(via
		(at 262.509 -381.305816)
		(size 0.508)
		(drill 0.254)
		(layers "F.Cu" "B.Cu")
		(net "P12V_HSC_GATE2")
	)
	(via
		(at 256.574036 -381.305816)
		(size 0.508)
		(drill 0.254)
		(layers "F.Cu" "B.Cu")
		(net "P12V_HSC_GATE2")
	)
	(via
		(at 250.639072 -381.305816)
		(size 0.508)
		(drill 0.254)
		(layers "F.Cu" "B.Cu")
		(net "P12V_HSC_GATE2")
	)
	(via
		(at 274.378928 -381.305816)
		(size 0.508)
		(drill 0.254)
		(layers "F.Cu" "B.Cu")
		(net "P12V_HSC_GATE2")
	)
	(via
		(at 279.970992 -380.031244)
		(size 0.508)
		(drill 0.254)
		(layers "F.Cu" "B.Cu")
		(net "P12V_HSC_GATE1")
	)
	(via
		(at 196.760084 -385.176014)
		(size 0.508)
		(drill 0.254)
		(layers "F.Cu" "B.Cu")
		(net "P12V_HSC_GATE1")
	)
	(segment
		(start 209.753454 -388.079234)
		(end 210.185254 -388.079234)
		(width 0.254)
		(layer "F.Cu")
		(net "P12V_HSC_ADC_P")
	)
	(segment
		(start 210.134454 -390.105646)
		(end 206.091536 -390.105646)
		(width 0.254)
		(layer "F.Cu")
		(net "P12V_HSC_ADC_P")
	)
	(segment
		(start 210.662266 -389.577834)
		(end 210.134454 -390.105646)
		(width 0.254)
		(layer "F.Cu")
		(net "P12V_HSC_ADC_P")
	)
	(segment
		(start 199.515984 -383.850896)
		(end 199.206358 -384.160522)
		(width 0.254)
		(layer "F.Cu")
		(net "P12V_HSC_ADC_P")
	)
	(segment
		(start 209.477356 -387.803136)
		(end 209.753454 -388.079234)
		(width 0.254)
		(layer "F.Cu")
		(net "P12V_HSC_ADC_P")
	)
	(segment
		(start 199.206358 -384.160522)
		(end 197.999858 -384.160522)
		(width 0.254)
		(layer "F.Cu")
		(net "P12V_HSC_ADC_P")
	)
	(segment
		(start 210.185254 -388.079234)
		(end 210.662266 -388.556246)
		(width 0.254)
		(layer "F.Cu")
		(net "P12V_HSC_ADC_P")
	)
	(segment
		(start 199.836786 -383.850896)
		(end 199.515984 -383.850896)
		(width 0.254)
		(layer "F.Cu")
		(net "P12V_HSC_ADC_P")
	)
	(segment
		(start 210.662266 -388.556246)
		(end 210.662266 -389.577834)
		(width 0.254)
		(layer "F.Cu")
		(net "P12V_HSC_ADC_P")
	)
	(segment
		(start 206.091536 -390.105646)
		(end 199.836786 -383.850896)
		(width 0.254)
		(layer "F.Cu")
		(net "P12V_HSC_ADC_P")
	)
	(via
		(at 209.477356 -377.793504)
		(size 0.508)
		(drill 0.254)
		(layers "F.Cu" "B.Cu")
		(net "P12V_HSC_ADC_P")
	)
	(via
		(at 209.477356 -387.803136)
		(size 0.508)
		(drill 0.254)
		(layers "F.Cu" "B.Cu")
		(net "P12V_HSC_ADC_P")
	)
	(via
		(at 199.206358 -384.160522)
		(size 0.508)
		(drill 0.254)
		(layers "F.Cu" "B.Cu")
		(net "P12V_HSC_ADC_P")
	)
	(via
		(at 209.477356 -380.333504)
		(size 0.508)
		(drill 0.254)
		(layers "F.Cu" "B.Cu")
		(net "P12V_HSC_ADC_P")
	)
	(via
		(at 209.477356 -382.723136)
		(size 0.508)
		(drill 0.254)
		(layers "F.Cu" "B.Cu")
		(net "P12V_HSC_ADC_P")
	)
	(via
		(at 209.477356 -385.263136)
		(size 0.508)
		(drill 0.254)
		(layers "F.Cu" "B.Cu")
		(net "P12V_HSC_ADC_P")
	)
	(segment
		(start 208.861406 -387.676136)
		(end 208.988406 -387.803136)
		(width 0.254)
		(layer "B.Cu")
		(net "P12V_HSC_ADC_P")
	)
	(segment
		(start 208.861406 -380.206504)
		(end 208.988406 -380.333504)
		(width 0.254)
		(layer "B.Cu")
		(net "P12V_HSC_ADC_P")
	)
	(segment
		(start 208.861406 -377.666504)
		(end 208.988406 -377.793504)
		(width 0.254)
		(layer "B.Cu")
		(net "P12V_HSC_ADC_P")
	)
	(segment
		(start 208.861406 -382.596136)
		(end 208.988406 -382.723136)
		(width 0.254)
		(layer "B.Cu")
		(net "P12V_HSC_ADC_P")
	)
	(segment
		(start 208.988406 -377.793504)
		(end 209.477356 -377.793504)
		(width 0.254)
		(layer "B.Cu")
		(net "P12V_HSC_ADC_P")
	)
	(segment
		(start 208.861406 -385.136136)
		(end 208.988406 -385.263136)
		(width 0.254)
		(layer "B.Cu")
		(net "P12V_HSC_ADC_P")
	)
	(segment
		(start 208.988406 -380.333504)
		(end 209.477356 -380.333504)
		(width 0.254)
		(layer "B.Cu")
		(net "P12V_HSC_ADC_P")
	)
	(segment
		(start 208.988406 -385.263136)
		(end 209.477356 -385.263136)
		(width 0.254)
		(layer "B.Cu")
		(net "P12V_HSC_ADC_P")
	)
	(segment
		(start 208.988406 -382.723136)
		(end 209.477356 -382.723136)
		(width 0.254)
		(layer "B.Cu")
		(net "P12V_HSC_ADC_P")
	)
	(segment
		(start 208.988406 -387.803136)
		(end 209.477356 -387.803136)
		(width 0.254)
		(layer "B.Cu")
		(net "P12V_HSC_ADC_P")
	)
	(segment
		(start 208.673446 -377.093734)
		(end 207.454754 -375.875042)
		(width 0.254)
		(layer "In2.Cu")
		(net "P12V_HSC_ADC_P")
	)
	(segment
		(start 209.286856 -377.984004)
		(end 208.927446 -377.984004)
		(width 0.254)
		(layer "In2.Cu")
		(net "P12V_HSC_ADC_P")
	)
	(segment
		(start 197.62343 -383.500884)
		(end 197.973442 -383.850896)
		(width 0.254)
		(layer "In2.Cu")
		(net "P12V_HSC_ADC_P")
	)
	(segment
		(start 210.662266 -386.606034)
		(end 210.175094 -387.093206)
		(width 0.254)
		(layer "In2.Cu")
		(net "P12V_HSC_ADC_P")
	)
	(segment
		(start 209.667856 -385.453636)
		(end 210.185254 -385.453636)
		(width 0.254)
		(layer "In2.Cu")
		(net "P12V_HSC_ADC_P")
	)
	(segment
		(start 199.515984 -383.850896)
		(end 199.206358 -384.160522)
		(width 0.254)
		(layer "In2.Cu")
		(net "P12V_HSC_ADC_P")
	)
	(segment
		(start 208.673446 -377.730004)
		(end 208.673446 -377.093734)
		(width 0.254)
		(layer "In2.Cu")
		(net "P12V_HSC_ADC_P")
	)
	(segment
		(start 207.454754 -375.875042)
		(end 200.559924 -375.875042)
		(width 0.254)
		(layer "In2.Cu")
		(net "P12V_HSC_ADC_P")
	)
	(segment
		(start 210.662266 -385.930648)
		(end 210.662266 -386.606034)
		(width 0.254)
		(layer "In2.Cu")
		(net "P12V_HSC_ADC_P")
	)
	(segment
		(start 200.559924 -375.875042)
		(end 197.62343 -378.811536)
		(width 0.254)
		(layer "In2.Cu")
		(net "P12V_HSC_ADC_P")
	)
	(segment
		(start 210.175094 -387.093206)
		(end 203.117704 -387.093206)
		(width 0.254)
		(layer "In2.Cu")
		(net "P12V_HSC_ADC_P")
	)
	(segment
		(start 208.927446 -377.984004)
		(end 208.673446 -377.730004)
		(width 0.254)
		(layer "In2.Cu")
		(net "P12V_HSC_ADC_P")
	)
	(segment
		(start 197.973442 -383.850896)
		(end 198.896732 -383.850896)
		(width 0.254)
		(layer "In2.Cu")
		(net "P12V_HSC_ADC_P")
	)
	(segment
		(start 210.185254 -385.453636)
		(end 210.662266 -385.930648)
		(width 0.254)
		(layer "In2.Cu")
		(net "P12V_HSC_ADC_P")
	)
	(segment
		(start 198.896732 -383.850896)
		(end 199.206358 -384.160522)
		(width 0.254)
		(layer "In2.Cu")
		(net "P12V_HSC_ADC_P")
	)
	(segment
		(start 197.62343 -378.811536)
		(end 197.62343 -383.500884)
		(width 0.254)
		(layer "In2.Cu")
		(net "P12V_HSC_ADC_P")
	)
	(segment
		(start 199.875394 -383.850896)
		(end 199.515984 -383.850896)
		(width 0.254)
		(layer "In2.Cu")
		(net "P12V_HSC_ADC_P")
	)
	(segment
		(start 209.477356 -385.263136)
		(end 209.667856 -385.453636)
		(width 0.254)
		(layer "In2.Cu")
		(net "P12V_HSC_ADC_P")
	)
	(segment
		(start 203.117704 -387.093206)
		(end 199.875394 -383.850896)
		(width 0.254)
		(layer "In2.Cu")
		(net "P12V_HSC_ADC_P")
	)
	(segment
		(start 209.477356 -377.793504)
		(end 209.286856 -377.984004)
		(width 0.254)
		(layer "In2.Cu")
		(net "P12V_HSC_ADC_P")
	)
	(segment
		(start 199.515984 -383.850896)
		(end 199.206358 -384.160522)
		(width 0.254)
		(layer "In6.Cu")
		(net "P12V_HSC_ADC_P")
	)
	(segment
		(start 210.662266 -383.390648)
		(end 210.662266 -384.066034)
		(width 0.254)
		(layer "In6.Cu")
		(net "P12V_HSC_ADC_P")
	)
	(segment
		(start 209.477356 -382.723136)
		(end 209.667856 -382.913636)
		(width 0.254)
		(layer "In6.Cu")
		(net "P12V_HSC_ADC_P")
	)
	(segment
		(start 210.185254 -384.543046)
		(end 201.566018 -384.543046)
		(width 0.254)
		(layer "In6.Cu")
		(net "P12V_HSC_ADC_P")
	)
	(segment
		(start 209.667856 -382.913636)
		(end 210.185254 -382.913636)
		(width 0.254)
		(layer "In6.Cu")
		(net "P12V_HSC_ADC_P")
	)
	(segment
		(start 210.185254 -382.913636)
		(end 210.662266 -383.390648)
		(width 0.254)
		(layer "In6.Cu")
		(net "P12V_HSC_ADC_P")
	)
	(segment
		(start 201.566018 -384.543046)
		(end 200.873868 -383.850896)
		(width 0.254)
		(layer "In6.Cu")
		(net "P12V_HSC_ADC_P")
	)
	(segment
		(start 210.662266 -384.066034)
		(end 210.185254 -384.543046)
		(width 0.254)
		(layer "In6.Cu")
		(net "P12V_HSC_ADC_P")
	)
	(segment
		(start 200.873868 -383.850896)
		(end 199.515984 -383.850896)
		(width 0.254)
		(layer "In6.Cu")
		(net "P12V_HSC_ADC_P")
	)
	(segment
		(start 210.662266 -381.001016)
		(end 210.662266 -381.676402)
		(width 0.254)
		(layer "In15.Cu")
		(net "P12V_HSC_ADC_P")
	)
	(segment
		(start 199.51573 -383.85115)
		(end 199.206358 -384.160522)
		(width 0.254)
		(layer "In15.Cu")
		(net "P12V_HSC_ADC_P")
	)
	(segment
		(start 209.477356 -380.333504)
		(end 209.667856 -380.524004)
		(width 0.254)
		(layer "In15.Cu")
		(net "P12V_HSC_ADC_P")
	)
	(segment
		(start 204.672184 -382.153414)
		(end 202.974448 -383.85115)
		(width 0.254)
		(layer "In15.Cu")
		(net "P12V_HSC_ADC_P")
	)
	(segment
		(start 209.667856 -380.524004)
		(end 210.185254 -380.524004)
		(width 0.254)
		(layer "In15.Cu")
		(net "P12V_HSC_ADC_P")
	)
	(segment
		(start 210.185254 -382.153414)
		(end 204.672184 -382.153414)
		(width 0.254)
		(layer "In15.Cu")
		(net "P12V_HSC_ADC_P")
	)
	(segment
		(start 202.974448 -383.85115)
		(end 199.51573 -383.85115)
		(width 0.254)
		(layer "In15.Cu")
		(net "P12V_HSC_ADC_P")
	)
	(segment
		(start 210.185254 -380.524004)
		(end 210.662266 -381.001016)
		(width 0.254)
		(layer "In15.Cu")
		(net "P12V_HSC_ADC_P")
	)
	(segment
		(start 210.662266 -381.676402)
		(end 210.185254 -382.153414)
		(width 0.254)
		(layer "In15.Cu")
		(net "P12V_HSC_ADC_P")
	)
	(segment
		(start 210.027266 -388.460234)
		(end 210.281266 -388.714234)
		(width 0.254)
		(layer "F.Cu")
		(net "P12V_HSC_ADC_N")
	)
	(segment
		(start 199.51573 -383.469896)
		(end 199.206358 -383.160524)
		(width 0.254)
		(layer "F.Cu")
		(net "P12V_HSC_ADC_N")
	)
	(segment
		(start 199.994774 -383.469896)
		(end 199.51573 -383.469896)
		(width 0.254)
		(layer "F.Cu")
		(net "P12V_HSC_ADC_N")
	)
	(segment
		(start 210.281266 -388.714234)
		(end 210.281266 -389.419846)
		(width 0.254)
		(layer "F.Cu")
		(net "P12V_HSC_ADC_N")
	)
	(segment
		(start 206.249524 -389.724646)
		(end 199.994774 -383.469896)
		(width 0.254)
		(layer "F.Cu")
		(net "P12V_HSC_ADC_N")
	)
	(segment
		(start 209.477356 -388.565136)
		(end 209.582258 -388.460234)
		(width 0.254)
		(layer "F.Cu")
		(net "P12V_HSC_ADC_N")
	)
	(segment
		(start 209.582258 -388.460234)
		(end 210.027266 -388.460234)
		(width 0.254)
		(layer "F.Cu")
		(net "P12V_HSC_ADC_N")
	)
	(segment
		(start 210.281266 -389.419846)
		(end 209.976466 -389.724646)
		(width 0.254)
		(layer "F.Cu")
		(net "P12V_HSC_ADC_N")
	)
	(segment
		(start 199.206358 -383.160524)
		(end 197.999858 -383.160524)
		(width 0.254)
		(layer "F.Cu")
		(net "P12V_HSC_ADC_N")
	)
	(segment
		(start 209.976466 -389.724646)
		(end 206.249524 -389.724646)
		(width 0.254)
		(layer "F.Cu")
		(net "P12V_HSC_ADC_N")
	)
	(via
		(at 209.477356 -383.485136)
		(size 0.508)
		(drill 0.254)
		(layers "F.Cu" "B.Cu")
		(net "P12V_HSC_ADC_N")
	)
	(via
		(at 209.477356 -381.095504)
		(size 0.508)
		(drill 0.254)
		(layers "F.Cu" "B.Cu")
		(net "P12V_HSC_ADC_N")
	)
	(via
		(at 209.477356 -388.565136)
		(size 0.508)
		(drill 0.254)
		(layers "F.Cu" "B.Cu")
		(net "P12V_HSC_ADC_N")
	)
	(via
		(at 209.477356 -378.555504)
		(size 0.508)
		(drill 0.254)
		(layers "F.Cu" "B.Cu")
		(net "P12V_HSC_ADC_N")
	)
	(via
		(at 209.477356 -386.025136)
		(size 0.508)
		(drill 0.254)
		(layers "F.Cu" "B.Cu")
		(net "P12V_HSC_ADC_N")
	)
	(via
		(at 199.206358 -383.160524)
		(size 0.508)
		(drill 0.254)
		(layers "F.Cu" "B.Cu")
		(net "P12V_HSC_ADC_N")
	)
	(segment
		(start 208.861406 -388.692136)
		(end 208.988406 -388.565136)
		(width 0.254)
		(layer "B.Cu")
		(net "P12V_HSC_ADC_N")
	)
	(segment
		(start 208.861406 -383.612136)
		(end 208.988406 -383.485136)
		(width 0.254)
		(layer "B.Cu")
		(net "P12V_HSC_ADC_N")
	)
	(segment
		(start 208.861406 -381.222504)
		(end 208.988406 -381.095504)
		(width 0.254)
		(layer "B.Cu")
		(net "P12V_HSC_ADC_N")
	)
	(segment
		(start 208.861406 -386.152136)
		(end 208.988406 -386.025136)
		(width 0.254)
		(layer "B.Cu")
		(net "P12V_HSC_ADC_N")
	)
	(segment
		(start 208.988406 -381.095504)
		(end 209.477356 -381.095504)
		(width 0.254)
		(layer "B.Cu")
		(net "P12V_HSC_ADC_N")
	)
	(segment
		(start 208.861406 -378.682504)
		(end 208.988406 -378.555504)
		(width 0.254)
		(layer "B.Cu")
		(net "P12V_HSC_ADC_N")
	)
	(segment
		(start 208.988406 -388.565136)
		(end 209.477356 -388.565136)
		(width 0.254)
		(layer "B.Cu")
		(net "P12V_HSC_ADC_N")
	)
	(segment
		(start 208.988406 -378.555504)
		(end 209.477356 -378.555504)
		(width 0.254)
		(layer "B.Cu")
		(net "P12V_HSC_ADC_N")
	)
	(segment
		(start 208.988406 -386.025136)
		(end 209.477356 -386.025136)
		(width 0.254)
		(layer "B.Cu")
		(net "P12V_HSC_ADC_N")
	)
	(segment
		(start 208.988406 -383.485136)
		(end 209.477356 -383.485136)
		(width 0.254)
		(layer "B.Cu")
		(net "P12V_HSC_ADC_N")
	)
	(segment
		(start 208.769458 -378.365004)
		(end 208.292446 -377.887992)
		(width 0.254)
		(layer "In2.Cu")
		(net "P12V_HSC_ADC_N")
	)
	(segment
		(start 210.027266 -385.834636)
		(end 210.281266 -386.088636)
		(width 0.254)
		(layer "In2.Cu")
		(net "P12V_HSC_ADC_N")
	)
	(segment
		(start 209.286856 -378.365004)
		(end 208.769458 -378.365004)
		(width 0.254)
		(layer "In2.Cu")
		(net "P12V_HSC_ADC_N")
	)
	(segment
		(start 210.281266 -386.088636)
		(end 210.281266 -386.448046)
		(width 0.254)
		(layer "In2.Cu")
		(net "P12V_HSC_ADC_N")
	)
	(segment
		(start 200.717912 -376.256042)
		(end 198.00443 -378.969524)
		(width 0.254)
		(layer "In2.Cu")
		(net "P12V_HSC_ADC_N")
	)
	(segment
		(start 210.017106 -386.712206)
		(end 203.275692 -386.712206)
		(width 0.254)
		(layer "In2.Cu")
		(net "P12V_HSC_ADC_N")
	)
	(segment
		(start 198.00443 -378.969524)
		(end 198.00443 -383.342896)
		(width 0.254)
		(layer "In2.Cu")
		(net "P12V_HSC_ADC_N")
	)
	(segment
		(start 199.51573 -383.469896)
		(end 199.206358 -383.160524)
		(width 0.254)
		(layer "In2.Cu")
		(net "P12V_HSC_ADC_N")
	)
	(segment
		(start 208.292446 -377.251722)
		(end 207.296766 -376.256042)
		(width 0.254)
		(layer "In2.Cu")
		(net "P12V_HSC_ADC_N")
	)
	(segment
		(start 209.477356 -386.025136)
		(end 209.667856 -385.834636)
		(width 0.254)
		(layer "In2.Cu")
		(net "P12V_HSC_ADC_N")
	)
	(segment
		(start 198.00443 -383.342896)
		(end 198.13143 -383.469896)
		(width 0.254)
		(layer "In2.Cu")
		(net "P12V_HSC_ADC_N")
	)
	(segment
		(start 203.275692 -386.712206)
		(end 200.033382 -383.469896)
		(width 0.254)
		(layer "In2.Cu")
		(net "P12V_HSC_ADC_N")
	)
	(segment
		(start 208.292446 -377.887992)
		(end 208.292446 -377.251722)
		(width 0.254)
		(layer "In2.Cu")
		(net "P12V_HSC_ADC_N")
	)
	(segment
		(start 207.296766 -376.256042)
		(end 200.717912 -376.256042)
		(width 0.254)
		(layer "In2.Cu")
		(net "P12V_HSC_ADC_N")
	)
	(segment
		(start 209.477356 -378.555504)
		(end 209.286856 -378.365004)
		(width 0.254)
		(layer "In2.Cu")
		(net "P12V_HSC_ADC_N")
	)
	(segment
		(start 200.033382 -383.469896)
		(end 199.51573 -383.469896)
		(width 0.254)
		(layer "In2.Cu")
		(net "P12V_HSC_ADC_N")
	)
	(segment
		(start 210.281266 -386.448046)
		(end 210.017106 -386.712206)
		(width 0.254)
		(layer "In2.Cu")
		(net "P12V_HSC_ADC_N")
	)
	(segment
		(start 198.13143 -383.469896)
		(end 198.896986 -383.469896)
		(width 0.254)
		(layer "In2.Cu")
		(net "P12V_HSC_ADC_N")
	)
	(segment
		(start 209.667856 -385.834636)
		(end 210.027266 -385.834636)
		(width 0.254)
		(layer "In2.Cu")
		(net "P12V_HSC_ADC_N")
	)
	(segment
		(start 198.896986 -383.469896)
		(end 199.206358 -383.160524)
		(width 0.254)
		(layer "In2.Cu")
		(net "P12V_HSC_ADC_N")
	)
	(segment
		(start 209.667856 -383.294636)
		(end 210.027266 -383.294636)
		(width 0.254)
		(layer "In6.Cu")
		(net "P12V_HSC_ADC_N")
	)
	(segment
		(start 209.477356 -383.485136)
		(end 209.667856 -383.294636)
		(width 0.254)
		(layer "In6.Cu")
		(net "P12V_HSC_ADC_N")
	)
	(segment
		(start 201.724006 -384.162046)
		(end 201.031856 -383.469896)
		(width 0.254)
		(layer "In6.Cu")
		(net "P12V_HSC_ADC_N")
	)
	(segment
		(start 210.027266 -384.162046)
		(end 201.724006 -384.162046)
		(width 0.254)
		(layer "In6.Cu")
		(net "P12V_HSC_ADC_N")
	)
	(segment
		(start 210.281266 -383.908046)
		(end 210.027266 -384.162046)
		(width 0.254)
		(layer "In6.Cu")
		(net "P12V_HSC_ADC_N")
	)
	(segment
		(start 199.51573 -383.469896)
		(end 199.206358 -383.160524)
		(width 0.254)
		(layer "In6.Cu")
		(net "P12V_HSC_ADC_N")
	)
	(segment
		(start 210.281266 -383.548636)
		(end 210.281266 -383.908046)
		(width 0.254)
		(layer "In6.Cu")
		(net "P12V_HSC_ADC_N")
	)
	(segment
		(start 201.031856 -383.469896)
		(end 199.51573 -383.469896)
		(width 0.254)
		(layer "In6.Cu")
		(net "P12V_HSC_ADC_N")
	)
	(segment
		(start 210.027266 -383.294636)
		(end 210.281266 -383.548636)
		(width 0.254)
		(layer "In6.Cu")
		(net "P12V_HSC_ADC_N")
	)
	(segment
		(start 210.281266 -381.518414)
		(end 210.027266 -381.772414)
		(width 0.254)
		(layer "In15.Cu")
		(net "P12V_HSC_ADC_N")
	)
	(segment
		(start 209.477356 -381.095504)
		(end 209.667856 -380.905004)
		(width 0.254)
		(layer "In15.Cu")
		(net "P12V_HSC_ADC_N")
	)
	(segment
		(start 204.514196 -381.772414)
		(end 202.81646 -383.47015)
		(width 0.254)
		(layer "In15.Cu")
		(net "P12V_HSC_ADC_N")
	)
	(segment
		(start 210.281266 -381.159004)
		(end 210.281266 -381.518414)
		(width 0.254)
		(layer "In15.Cu")
		(net "P12V_HSC_ADC_N")
	)
	(segment
		(start 210.027266 -380.905004)
		(end 210.281266 -381.159004)
		(width 0.254)
		(layer "In15.Cu")
		(net "P12V_HSC_ADC_N")
	)
	(segment
		(start 202.81646 -383.47015)
		(end 199.515984 -383.47015)
		(width 0.254)
		(layer "In15.Cu")
		(net "P12V_HSC_ADC_N")
	)
	(segment
		(start 199.515984 -383.47015)
		(end 199.206358 -383.160524)
		(width 0.254)
		(layer "In15.Cu")
		(net "P12V_HSC_ADC_N")
	)
	(segment
		(start 209.667856 -380.905004)
		(end 210.027266 -380.905004)
		(width 0.254)
		(layer "In15.Cu")
		(net "P12V_HSC_ADC_N")
	)
	(segment
		(start 210.027266 -381.772414)
		(end 204.514196 -381.772414)
		(width 0.254)
		(layer "In15.Cu")
		(net "P12V_HSC_ADC_N")
	)
	(segment
		(start 15.37335 -421.2336)
		(end 15.37335 -420.936674)
		(width 0.10668)
		(layer "F.Cu")
		(net "NC_RES")
	)
	(segment
		(start 15.37335 -420.936674)
		(end 14.432534 -419.995858)
		(width 0.10668)
		(layer "F.Cu")
		(net "NC_RES")
	)
	(via
		(at 14.432534 -419.995858)
		(size 0.762)
		(drill 0.381)
		(layers "F.Cu" "B.Cu")
		(net "NC_RES")
	)
	(segment
		(start 279.170892 -381.305816)
		(end 279.170892 -382.277366)
		(width 0.10668)
		(layer "F.Cu")
		(net "MB0_CM_GATE_G0")
	)
	(segment
		(start 279.170892 -380.66853)
		(end 279.170892 -381.305816)
		(width 0.10668)
		(layer "F.Cu")
		(net "MB0_CM_GATE_G0")
	)
	(via
		(at 279.170892 -381.305816)
		(size 0.508)
		(drill 0.254)
		(layers "F.Cu" "B.Cu")
		(net "MB0_CM_GATE_G0")
	)
	(segment
		(start 428.722282 -431.584608)
		(end 428.722282 -432.001676)
		(width 0.4572)
		(layer "F.Cu")
		(net "HSC_TYPE_ADC")
	)
	(segment
		(start 428.722282 -430.892458)
		(end 428.722282 -431.584608)
		(width 0.381)
		(layer "F.Cu")
		(net "HSC_TYPE_ADC")
	)
	(segment
		(start 428.722282 -430.892458)
		(end 428.774606 -430.840134)
		(width 0.2286)
		(layer "F.Cu")
		(net "HSC_TYPE_ADC")
	)
	(segment
		(start 428.722282 -432.001676)
		(end 429.052736 -432.33213)
		(width 0.4572)
		(layer "F.Cu")
		(net "HSC_TYPE_ADC")
	)
	(segment
		(start 193.779902 -383.660396)
		(end 192.573402 -383.660396)
		(width 0.381)
		(layer "F.Cu")
		(net "HSC_TYPE_ADC")
	)
	(segment
		(start 428.774606 -430.840134)
		(end 428.774606 -429.706278)
		(width 0.2286)
		(layer "F.Cu")
		(net "HSC_TYPE_ADC")
	)
	(via
		(at 429.052736 -432.33213)
		(size 0.508)
		(drill 0.254)
		(layers "F.Cu" "B.Cu")
		(net "HSC_TYPE_ADC")
	)
	(via
		(at 293.41572 -420.505636)
		(size 0.508)
		(drill 0.254)
		(layers "F.Cu" "B.Cu")
		(net "HSC_TYPE_ADC")
	)
	(via
		(at 293.434262 -396.030704)
		(size 0.508)
		(drill 0.254)
		(layers "F.Cu" "B.Cu")
		(net "HSC_TYPE_ADC")
	)
	(via
		(at 192.573402 -383.660396)
		(size 0.508)
		(drill 0.254)
		(layers "F.Cu" "B.Cu")
		(net "HSC_TYPE_ADC")
	)
	(segment
		(start 421.404034 -420.699692)
		(end 421.404034 -412.27375)
		(width 0.508)
		(layer "In2.Cu")
		(net "HSC_TYPE_ADC")
	)
	(segment
		(start 359.26141 -416.28949)
		(end 358.391968 -417.158932)
		(width 0.508)
		(layer "In2.Cu")
		(net "HSC_TYPE_ADC")
	)
	(segment
		(start 368.935 -410.972)
		(end 368.276632 -410.972)
		(width 0.508)
		(layer "In2.Cu")
		(net "HSC_TYPE_ADC")
	)
	(segment
		(start 199.329294 -374.093486)
		(end 196.713094 -376.709686)
		(width 0.508)
		(layer "In2.Cu")
		(net "HSC_TYPE_ADC")
	)
	(segment
		(start 427.784768 -429.629062)
		(end 427.784768 -425.498768)
		(width 0.508)
		(layer "In2.Cu")
		(net "HSC_TYPE_ADC")
	)
	(segment
		(start 368.276632 -410.972)
		(end 362.959142 -416.28949)
		(width 0.508)
		(layer "In2.Cu")
		(net "HSC_TYPE_ADC")
	)
	(segment
		(start 193.977514 -381.410718)
		(end 193.977514 -382.334516)
		(width 0.508)
		(layer "In2.Cu")
		(net "HSC_TYPE_ADC")
	)
	(segment
		(start 428.827946 -432.10734)
		(end 428.827946 -430.67224)
		(width 0.508)
		(layer "In2.Cu")
		(net "HSC_TYPE_ADC")
	)
	(segment
		(start 280.7335 -377.43384)
		(end 279.00884 -375.70918)
		(width 0.508)
		(layer "In2.Cu")
		(net "HSC_TYPE_ADC")
	)
	(segment
		(start 280.32202 -394.948918)
		(end 280.32202 -387.39318)
		(width 0.508)
		(layer "In2.Cu")
		(net "HSC_TYPE_ADC")
	)
	(segment
		(start 293.434262 -396.030704)
		(end 289.790886 -396.030704)
		(width 0.508)
		(layer "In2.Cu")
		(net "HSC_TYPE_ADC")
	)
	(segment
		(start 302.952658 -419.708584)
		(end 302.160686 -420.500556)
		(width 0.508)
		(layer "In2.Cu")
		(net "HSC_TYPE_ADC")
	)
	(segment
		(start 284.621224 -396.75689)
		(end 284.523688 -396.854426)
		(width 0.508)
		(layer "In2.Cu")
		(net "HSC_TYPE_ADC")
	)
	(segment
		(start 192.651634 -383.660396)
		(end 192.573402 -383.660396)
		(width 0.508)
		(layer "In2.Cu")
		(net "HSC_TYPE_ADC")
	)
	(segment
		(start 424.23588 -423.22115)
		(end 423.925492 -423.22115)
		(width 0.508)
		(layer "In2.Cu")
		(net "HSC_TYPE_ADC")
	)
	(segment
		(start 193.977514 -382.334516)
		(end 192.651634 -383.660396)
		(width 0.508)
		(layer "In2.Cu")
		(net "HSC_TYPE_ADC")
	)
	(segment
		(start 279.00884 -375.7041)
		(end 277.5077 -374.20296)
		(width 0.508)
		(layer "In2.Cu")
		(net "HSC_TYPE_ADC")
	)
	(segment
		(start 279.00884 -375.70918)
		(end 279.00884 -375.7041)
		(width 0.508)
		(layer "In2.Cu")
		(net "HSC_TYPE_ADC")
	)
	(segment
		(start 277.50262 -374.20296)
		(end 277.393146 -374.093486)
		(width 0.508)
		(layer "In2.Cu")
		(net "HSC_TYPE_ADC")
	)
	(segment
		(start 426.969428 -424.683428)
		(end 425.698158 -424.683428)
		(width 0.508)
		(layer "In2.Cu")
		(net "HSC_TYPE_ADC")
	)
	(segment
		(start 277.5077 -374.20296)
		(end 277.50262 -374.20296)
		(width 0.508)
		(layer "In2.Cu")
		(net "HSC_TYPE_ADC")
	)
	(segment
		(start 421.404034 -412.27375)
		(end 419.63086 -410.500576)
		(width 0.508)
		(layer "In2.Cu")
		(net "HSC_TYPE_ADC")
	)
	(segment
		(start 280.32202 -387.39318)
		(end 280.7335 -386.9817)
		(width 0.508)
		(layer "In2.Cu")
		(net "HSC_TYPE_ADC")
	)
	(segment
		(start 282.227528 -396.854426)
		(end 280.32202 -394.948918)
		(width 0.508)
		(layer "In2.Cu")
		(net "HSC_TYPE_ADC")
	)
	(segment
		(start 277.393146 -374.093486)
		(end 199.329294 -374.093486)
		(width 0.508)
		(layer "In2.Cu")
		(net "HSC_TYPE_ADC")
	)
	(segment
		(start 352.726498 -419.708584)
		(end 302.952658 -419.708584)
		(width 0.508)
		(layer "In2.Cu")
		(net "HSC_TYPE_ADC")
	)
	(segment
		(start 429.052736 -432.33213)
		(end 428.827946 -432.10734)
		(width 0.508)
		(layer "In2.Cu")
		(net "HSC_TYPE_ADC")
	)
	(segment
		(start 358.391968 -417.158932)
		(end 355.27615 -417.158932)
		(width 0.508)
		(layer "In2.Cu")
		(net "HSC_TYPE_ADC")
	)
	(segment
		(start 419.63086 -410.500576)
		(end 369.406424 -410.500576)
		(width 0.508)
		(layer "In2.Cu")
		(net "HSC_TYPE_ADC")
	)
	(segment
		(start 284.523688 -396.854426)
		(end 282.227528 -396.854426)
		(width 0.508)
		(layer "In2.Cu")
		(net "HSC_TYPE_ADC")
	)
	(segment
		(start 289.0647 -396.75689)
		(end 284.621224 -396.75689)
		(width 0.508)
		(layer "In2.Cu")
		(net "HSC_TYPE_ADC")
	)
	(segment
		(start 196.713094 -378.675138)
		(end 193.977514 -381.410718)
		(width 0.508)
		(layer "In2.Cu")
		(net "HSC_TYPE_ADC")
	)
	(segment
		(start 196.713094 -376.709686)
		(end 196.713094 -378.675138)
		(width 0.508)
		(layer "In2.Cu")
		(net "HSC_TYPE_ADC")
	)
	(segment
		(start 293.4208 -420.500556)
		(end 293.41572 -420.505636)
		(width 0.508)
		(layer "In2.Cu")
		(net "HSC_TYPE_ADC")
	)
	(segment
		(start 289.790886 -396.030704)
		(end 289.0647 -396.75689)
		(width 0.508)
		(layer "In2.Cu")
		(net "HSC_TYPE_ADC")
	)
	(segment
		(start 355.27615 -417.158932)
		(end 352.726498 -419.708584)
		(width 0.508)
		(layer "In2.Cu")
		(net "HSC_TYPE_ADC")
	)
	(segment
		(start 425.698158 -424.683428)
		(end 424.23588 -423.22115)
		(width 0.508)
		(layer "In2.Cu")
		(net "HSC_TYPE_ADC")
	)
	(segment
		(start 428.827946 -430.67224)
		(end 427.784768 -429.629062)
		(width 0.508)
		(layer "In2.Cu")
		(net "HSC_TYPE_ADC")
	)
	(segment
		(start 280.7335 -386.9817)
		(end 280.7335 -377.43384)
		(width 0.508)
		(layer "In2.Cu")
		(net "HSC_TYPE_ADC")
	)
	(segment
		(start 427.784768 -425.498768)
		(end 426.969428 -424.683428)
		(width 0.508)
		(layer "In2.Cu")
		(net "HSC_TYPE_ADC")
	)
	(segment
		(start 362.959142 -416.28949)
		(end 359.26141 -416.28949)
		(width 0.508)
		(layer "In2.Cu")
		(net "HSC_TYPE_ADC")
	)
	(segment
		(start 369.406424 -410.500576)
		(end 368.935 -410.972)
		(width 0.508)
		(layer "In2.Cu")
		(net "HSC_TYPE_ADC")
	)
	(segment
		(start 423.925492 -423.22115)
		(end 421.404034 -420.699692)
		(width 0.508)
		(layer "In2.Cu")
		(net "HSC_TYPE_ADC")
	)
	(segment
		(start 302.160686 -420.500556)
		(end 293.4208 -420.500556)
		(width 0.508)
		(layer "In2.Cu")
		(net "HSC_TYPE_ADC")
	)
	(segment
		(start 293.434262 -400.739356)
		(end 293.434262 -396.030704)
		(width 0.508)
		(layer "In4.Cu")
		(net "HSC_TYPE_ADC")
	)
	(segment
		(start 292.551612 -401.622006)
		(end 293.434262 -400.739356)
		(width 0.508)
		(layer "In4.Cu")
		(net "HSC_TYPE_ADC")
	)
	(segment
		(start 292.551612 -404.466298)
		(end 292.551612 -401.622006)
		(width 0.508)
		(layer "In4.Cu")
		(net "HSC_TYPE_ADC")
	)
	(segment
		(start 293.41572 -419.489128)
		(end 291.715444 -417.788852)
		(width 0.508)
		(layer "In4.Cu")
		(net "HSC_TYPE_ADC")
	)
	(segment
		(start 291.715444 -417.788852)
		(end 291.715444 -405.302466)
		(width 0.508)
		(layer "In4.Cu")
		(net "HSC_TYPE_ADC")
	)
	(segment
		(start 293.41572 -420.505636)
		(end 293.41572 -419.489128)
		(width 0.508)
		(layer "In4.Cu")
		(net "HSC_TYPE_ADC")
	)
	(segment
		(start 291.715444 -405.302466)
		(end 292.551612 -404.466298)
		(width 0.508)
		(layer "In4.Cu")
		(net "HSC_TYPE_ADC")
	)
	(segment
		(start 193.779902 -382.660652)
		(end 192.573402 -382.660652)
		(width 0.10668)
		(layer "F.Cu")
		(net "HSC_CSOUT")
	)
	(via
		(at 175.523144 -412.879032)
		(size 0.508)
		(drill 0.254)
		(layers "F.Cu" "B.Cu")
		(net "HSC_CSOUT")
	)
	(via
		(at 183.50992 -421.034464)
		(size 0.508)
		(drill 0.254)
		(layers "F.Cu" "B.Cu")
		(net "HSC_CSOUT")
	)
	(via
		(at 192.573402 -382.660652)
		(size 0.508)
		(drill 0.254)
		(layers "F.Cu" "B.Cu")
		(net "HSC_CSOUT")
	)
	(segment
		(start 183.54802 -423.411142)
		(end 183.54802 -424.123104)
		(width 0.10668)
		(layer "B.Cu")
		(net "HSC_CSOUT")
	)
	(segment
		(start 178.245262 -420.357046)
		(end 178.835812 -419.766496)
		(width 0.10668)
		(layer "B.Cu")
		(net "HSC_CSOUT")
	)
	(segment
		(start 177.678334 -421.217598)
		(end 178.245262 -420.65067)
		(width 0.10668)
		(layer "B.Cu")
		(net "HSC_CSOUT")
	)
	(segment
		(start 183.50992 -421.034464)
		(end 183.096154 -421.44823)
		(width 0.10668)
		(layer "B.Cu")
		(net "HSC_CSOUT")
	)
	(segment
		(start 183.294528 -425.274232)
		(end 183.294528 -424.405044)
		(width 0.10668)
		(layer "B.Cu")
		(net "HSC_CSOUT")
	)
	(segment
		(start 183.50992 -420.731696)
		(end 183.50992 -421.034464)
		(width 0.10668)
		(layer "B.Cu")
		(net "HSC_CSOUT")
	)
	(segment
		(start 178.835812 -419.766496)
		(end 182.54472 -419.766496)
		(width 0.10668)
		(layer "B.Cu")
		(net "HSC_CSOUT")
	)
	(segment
		(start 183.096154 -421.44823)
		(end 183.096154 -422.959276)
		(width 0.10668)
		(layer "B.Cu")
		(net "HSC_CSOUT")
	)
	(segment
		(start 183.294528 -424.405044)
		(end 183.280304 -424.39082)
		(width 0.10668)
		(layer "B.Cu")
		(net "HSC_CSOUT")
	)
	(segment
		(start 183.54802 -424.123104)
		(end 183.280304 -424.39082)
		(width 0.10668)
		(layer "B.Cu")
		(net "HSC_CSOUT")
	)
	(segment
		(start 183.096154 -422.959276)
		(end 183.54802 -423.411142)
		(width 0.10668)
		(layer "B.Cu")
		(net "HSC_CSOUT")
	)
	(segment
		(start 182.54472 -419.766496)
		(end 183.50992 -420.731696)
		(width 0.10668)
		(layer "B.Cu")
		(net "HSC_CSOUT")
	)
	(segment
		(start 178.245262 -420.65067)
		(end 178.245262 -420.357046)
		(width 0.10668)
		(layer "B.Cu")
		(net "HSC_CSOUT")
	)
	(segment
		(start 183.228742 -383.48793)
		(end 174.723806 -391.992866)
		(width 0.11684)
		(layer "In4.Cu")
		(net "HSC_CSOUT")
	)
	(segment
		(start 169.25163 -400.267678)
		(end 166.669974 -402.849334)
		(width 0.11684)
		(layer "In4.Cu")
		(net "HSC_CSOUT")
	)
	(segment
		(start 172.030898 -400.267678)
		(end 169.25163 -400.267678)
		(width 0.11684)
		(layer "In4.Cu")
		(net "HSC_CSOUT")
	)
	(segment
		(start 174.723806 -397.57477)
		(end 172.030898 -400.267678)
		(width 0.11684)
		(layer "In4.Cu")
		(net "HSC_CSOUT")
	)
	(segment
		(start 176.420018 -411.430724)
		(end 176.420018 -411.72384)
		(width 0.11684)
		(layer "In4.Cu")
		(net "HSC_CSOUT")
	)
	(segment
		(start 174.775368 -409.786074)
		(end 176.420018 -411.430724)
		(width 0.11684)
		(layer "In4.Cu")
		(net "HSC_CSOUT")
	)
	(segment
		(start 166.669974 -406.688036)
		(end 169.768012 -409.786074)
		(width 0.11684)
		(layer "In4.Cu")
		(net "HSC_CSOUT")
	)
	(segment
		(start 175.523144 -412.620714)
		(end 175.523144 -412.879032)
		(width 0.11684)
		(layer "In4.Cu")
		(net "HSC_CSOUT")
	)
	(segment
		(start 192.573402 -382.660652)
		(end 191.746124 -383.48793)
		(width 0.11684)
		(layer "In4.Cu")
		(net "HSC_CSOUT")
	)
	(segment
		(start 176.420018 -411.72384)
		(end 175.523144 -412.620714)
		(width 0.11684)
		(layer "In4.Cu")
		(net "HSC_CSOUT")
	)
	(segment
		(start 174.723806 -391.992866)
		(end 174.723806 -397.57477)
		(width 0.11684)
		(layer "In4.Cu")
		(net "HSC_CSOUT")
	)
	(segment
		(start 166.669974 -402.849334)
		(end 166.669974 -406.688036)
		(width 0.11684)
		(layer "In4.Cu")
		(net "HSC_CSOUT")
	)
	(segment
		(start 191.746124 -383.48793)
		(end 183.228742 -383.48793)
		(width 0.11684)
		(layer "In4.Cu")
		(net "HSC_CSOUT")
	)
	(segment
		(start 169.768012 -409.786074)
		(end 174.775368 -409.786074)
		(width 0.11684)
		(layer "In4.Cu")
		(net "HSC_CSOUT")
	)
	(segment
		(start 177.285904 -414.098994)
		(end 176.065942 -412.879032)
		(width 0.11684)
		(layer "In11.Cu")
		(net "HSC_CSOUT")
	)
	(segment
		(start 178.626008 -415.518346)
		(end 178.284124 -415.518346)
		(width 0.11684)
		(layer "In11.Cu")
		(net "HSC_CSOUT")
	)
	(segment
		(start 178.284124 -415.518346)
		(end 177.285904 -414.520126)
		(width 0.11684)
		(layer "In11.Cu")
		(net "HSC_CSOUT")
	)
	(segment
		(start 177.285904 -414.520126)
		(end 177.285904 -414.098994)
		(width 0.11684)
		(layer "In11.Cu")
		(net "HSC_CSOUT")
	)
	(segment
		(start 183.50992 -421.034464)
		(end 183.50992 -420.402258)
		(width 0.11684)
		(layer "In11.Cu")
		(net "HSC_CSOUT")
	)
	(segment
		(start 183.50992 -420.402258)
		(end 178.626008 -415.518346)
		(width 0.11684)
		(layer "In11.Cu")
		(net "HSC_CSOUT")
	)
	(segment
		(start 176.065942 -412.879032)
		(end 175.523144 -412.879032)
		(width 0.11684)
		(layer "In11.Cu")
		(net "HSC_CSOUT")
	)
	(segment
		(start 12.463526 -426.249846)
		(end 13.389102 -426.249846)
		(width 0.10668)
		(layer "F.Cu")
		(net "FM_P2E_EN2_N")
	)
	(segment
		(start 15.162276 -425.410122)
		(end 15.37335 -425.199048)
		(width 0.10668)
		(layer "F.Cu")
		(net "FM_P2E_EN2_N")
	)
	(segment
		(start 13.389102 -426.249846)
		(end 14.228826 -425.410122)
		(width 0.10668)
		(layer "F.Cu")
		(net "FM_P2E_EN2_N")
	)
	(segment
		(start 12.243308 -426.470064)
		(end 12.463526 -426.249846)
		(width 0.10668)
		(layer "F.Cu")
		(net "FM_P2E_EN2_N")
	)
	(segment
		(start 14.228826 -425.410122)
		(end 15.162276 -425.410122)
		(width 0.10668)
		(layer "F.Cu")
		(net "FM_P2E_EN2_N")
	)
	(segment
		(start 12.243308 -427.13783)
		(end 12.243308 -426.470064)
		(width 0.10668)
		(layer "F.Cu")
		(net "FM_P2E_EN2_N")
	)
	(segment
		(start 15.37335 -425.199048)
		(end 15.37335 -425.03344)
		(width 0.10668)
		(layer "F.Cu")
		(net "FM_P2E_EN2_N")
	)
	(via
		(at 12.463526 -426.249846)
		(size 0.762)
		(drill 0.381)
		(layers "F.Cu" "B.Cu")
		(net "FM_P2E_EN2_N")
	)
	(segment
		(start 17.380458 -419.951916)
		(end 17.373346 -419.959028)
		(width 0.10668)
		(layer "F.Cu")
		(net "FM_P2E_BUF2_VOD_SEL")
	)
	(segment
		(start 17.380458 -419.090348)
		(end 16.364458 -419.090348)
		(width 0.10668)
		(layer "F.Cu")
		(net "FM_P2E_BUF2_VOD_SEL")
	)
	(segment
		(start 17.373346 -419.959028)
		(end 17.373346 -421.2336)
		(width 0.10668)
		(layer "F.Cu")
		(net "FM_P2E_BUF2_VOD_SEL")
	)
	(segment
		(start 17.380458 -419.090348)
		(end 17.380458 -419.951916)
		(width 0.10668)
		(layer "F.Cu")
		(net "FM_P2E_BUF2_VOD_SEL")
	)
	(via
		(at 17.373346 -419.959028)
		(size 0.762)
		(drill 0.381)
		(layers "F.Cu" "B.Cu")
		(net "FM_P2E_BUF2_VOD_SEL")
	)
	(segment
		(start 14.155166 -427.232064)
		(end 14.021308 -427.098206)
		(width 0.10668)
		(layer "F.Cu")
		(net "FM_P2E_BUF2_VODB_DB")
	)
	(segment
		(start 14.999208 -427.232064)
		(end 14.155166 -427.232064)
		(width 0.10668)
		(layer "F.Cu")
		(net "FM_P2E_BUF2_VODB_DB")
	)
	(segment
		(start 14.400276 -426.190664)
		(end 14.91996 -426.190664)
		(width 0.10668)
		(layer "F.Cu")
		(net "FM_P2E_BUF2_VODB_DB")
	)
	(segment
		(start 14.021308 -426.569632)
		(end 14.400276 -426.190664)
		(width 0.10668)
		(layer "F.Cu")
		(net "FM_P2E_BUF2_VODB_DB")
	)
	(segment
		(start 14.91996 -426.190664)
		(end 15.873222 -425.237402)
		(width 0.10668)
		(layer "F.Cu")
		(net "FM_P2E_BUF2_VODB_DB")
	)
	(segment
		(start 15.873222 -425.237402)
		(end 15.873222 -425.03344)
		(width 0.10668)
		(layer "F.Cu")
		(net "FM_P2E_BUF2_VODB_DB")
	)
	(segment
		(start 14.021308 -427.098206)
		(end 14.021308 -426.569632)
		(width 0.10668)
		(layer "F.Cu")
		(net "FM_P2E_BUF2_VODB_DB")
	)
	(via
		(at 14.400276 -426.190664)
		(size 0.762)
		(drill 0.381)
		(layers "F.Cu" "B.Cu")
		(net "FM_P2E_BUF2_VODB_DB")
	)
	(segment
		(start 16.373348 -425.03344)
		(end 16.373348 -426.314616)
		(width 0.10668)
		(layer "F.Cu")
		(net "FM_P2E_BUF2_VODA_DB")
	)
	(segment
		(start 16.373348 -426.314616)
		(end 16.796258 -426.737526)
		(width 0.10668)
		(layer "F.Cu")
		(net "FM_P2E_BUF2_VODA_DB")
	)
	(segment
		(start 16.796258 -427.180248)
		(end 17.812258 -427.180248)
		(width 0.10668)
		(layer "F.Cu")
		(net "FM_P2E_BUF2_VODA_DB")
	)
	(segment
		(start 16.796258 -426.737526)
		(end 16.796258 -427.180248)
		(width 0.10668)
		(layer "F.Cu")
		(net "FM_P2E_BUF2_VODA_DB")
	)
	(via
		(at 16.373348 -426.314616)
		(size 0.762)
		(drill 0.381)
		(layers "F.Cu" "B.Cu")
		(net "FM_P2E_BUF2_VODA_DB")
	)
	(segment
		(start 14.078458 -419.090348)
		(end 15.094458 -419.090348)
		(width 0.10668)
		(layer "F.Cu")
		(net "FM_P2E_BUF2_SD_TH")
	)
	(segment
		(start 15.873222 -420.789862)
		(end 15.786608 -420.703248)
		(width 0.10668)
		(layer "F.Cu")
		(net "FM_P2E_BUF2_SD_TH")
	)
	(segment
		(start 15.786608 -419.975792)
		(end 15.786608 -419.452298)
		(width 0.10668)
		(layer "F.Cu")
		(net "FM_P2E_BUF2_SD_TH")
	)
	(segment
		(start 15.786608 -420.703248)
		(end 15.786608 -419.975792)
		(width 0.10668)
		(layer "F.Cu")
		(net "FM_P2E_BUF2_SD_TH")
	)
	(segment
		(start 15.873222 -421.2336)
		(end 15.873222 -420.789862)
		(width 0.10668)
		(layer "F.Cu")
		(net "FM_P2E_BUF2_SD_TH")
	)
	(segment
		(start 15.786608 -419.452298)
		(end 15.094458 -419.090348)
		(width 0.10668)
		(layer "F.Cu")
		(net "FM_P2E_BUF2_SD_TH")
	)
	(via
		(at 15.786608 -419.975792)
		(size 0.762)
		(drill 0.381)
		(layers "F.Cu" "B.Cu")
		(net "FM_P2E_BUF2_SD_TH")
	)
	(segment
		(start 18.650458 -419.090348)
		(end 18.650458 -419.95852)
		(width 0.10668)
		(layer "F.Cu")
		(net "FM_P2E_BUF2_RXDET")
	)
	(segment
		(start 17.873218 -420.73576)
		(end 17.873218 -421.2336)
		(width 0.10668)
		(layer "F.Cu")
		(net "FM_P2E_BUF2_RXDET")
	)
	(segment
		(start 18.643346 -419.965632)
		(end 17.873218 -420.73576)
		(width 0.10668)
		(layer "F.Cu")
		(net "FM_P2E_BUF2_RXDET")
	)
	(segment
		(start 18.650458 -419.090348)
		(end 19.666458 -419.090348)
		(width 0.10668)
		(layer "F.Cu")
		(net "FM_P2E_BUF2_RXDET")
	)
	(segment
		(start 18.650458 -419.95852)
		(end 18.643346 -419.965632)
		(width 0.10668)
		(layer "F.Cu")
		(net "FM_P2E_BUF2_RXDET")
	)
	(via
		(at 18.643346 -419.965632)
		(size 0.762)
		(drill 0.381)
		(layers "F.Cu" "B.Cu")
		(net "FM_P2E_BUF2_RXDET")
	)
	(segment
		(start 17.838674 -425.689268)
		(end 18.796254 -425.689268)
		(width 0.10668)
		(layer "F.Cu")
		(net "FM_P2E_BUF2_EQB1")
	)
	(segment
		(start 17.373346 -425.22394)
		(end 17.838674 -425.689268)
		(width 0.10668)
		(layer "F.Cu")
		(net "FM_P2E_BUF2_EQB1")
	)
	(segment
		(start 19.844258 -426.737272)
		(end 19.844258 -427.180248)
		(width 0.10668)
		(layer "F.Cu")
		(net "FM_P2E_BUF2_EQB1")
	)
	(segment
		(start 17.373346 -425.03344)
		(end 17.373346 -425.22394)
		(width 0.10668)
		(layer "F.Cu")
		(net "FM_P2E_BUF2_EQB1")
	)
	(segment
		(start 18.796254 -425.689268)
		(end 19.422872 -426.315886)
		(width 0.10668)
		(layer "F.Cu")
		(net "FM_P2E_BUF2_EQB1")
	)
	(segment
		(start 19.422872 -426.315886)
		(end 19.844258 -426.737272)
		(width 0.10668)
		(layer "F.Cu")
		(net "FM_P2E_BUF2_EQB1")
	)
	(segment
		(start 19.844258 -427.180248)
		(end 20.860258 -427.180248)
		(width 0.10668)
		(layer "F.Cu")
		(net "FM_P2E_BUF2_EQB1")
	)
	(via
		(at 19.422872 -426.315886)
		(size 0.762)
		(drill 0.381)
		(layers "F.Cu" "B.Cu")
		(net "FM_P2E_BUF2_EQB1")
	)
	(segment
		(start 17.873218 -425.226226)
		(end 18.043652 -425.39666)
		(width 0.10668)
		(layer "F.Cu")
		(net "FM_P2E_BUF2_EQB0")
	)
	(segment
		(start 20.09267 -425.39666)
		(end 20.98802 -426.29201)
		(width 0.10668)
		(layer "F.Cu")
		(net "FM_P2E_BUF2_EQB0")
	)
	(segment
		(start 17.873218 -425.03344)
		(end 17.873218 -425.226226)
		(width 0.10668)
		(layer "F.Cu")
		(net "FM_P2E_BUF2_EQB0")
	)
	(segment
		(start 20.98802 -426.29201)
		(end 21.876258 -427.180248)
		(width 0.10668)
		(layer "F.Cu")
		(net "FM_P2E_BUF2_EQB0")
	)
	(segment
		(start 18.043652 -425.39666)
		(end 20.09267 -425.39666)
		(width 0.10668)
		(layer "F.Cu")
		(net "FM_P2E_BUF2_EQB0")
	)
	(segment
		(start 21.876258 -427.180248)
		(end 22.892258 -427.180248)
		(width 0.10668)
		(layer "F.Cu")
		(net "FM_P2E_BUF2_EQB0")
	)
	(via
		(at 20.98802 -426.29201)
		(size 0.762)
		(drill 0.381)
		(layers "F.Cu" "B.Cu")
		(net "FM_P2E_BUF2_EQB0")
	)
	(segment
		(start 9.779508 -423.821098)
		(end 10.287508 -424.329098)
		(width 0.10668)
		(layer "F.Cu")
		(net "FM_P2E_BUF2_EQA1")
	)
	(segment
		(start 12.935458 -423.821098)
		(end 13.3731 -423.383456)
		(width 0.10668)
		(layer "F.Cu")
		(net "FM_P2E_BUF2_EQA1")
	)
	(segment
		(start 11.938508 -424.329098)
		(end 12.065508 -424.202098)
		(width 0.10668)
		(layer "F.Cu")
		(net "FM_P2E_BUF2_EQA1")
	)
	(segment
		(start 12.065508 -423.821098)
		(end 12.935458 -423.821098)
		(width 0.10668)
		(layer "F.Cu")
		(net "FM_P2E_BUF2_EQA1")
	)
	(segment
		(start 12.065508 -424.202098)
		(end 12.065508 -423.821098)
		(width 0.10668)
		(layer "F.Cu")
		(net "FM_P2E_BUF2_EQA1")
	)
	(segment
		(start 13.3731 -423.383456)
		(end 14.723364 -423.383456)
		(width 0.10668)
		(layer "F.Cu")
		(net "FM_P2E_BUF2_EQA1")
	)
	(segment
		(start 10.287508 -424.329098)
		(end 11.938508 -424.329098)
		(width 0.10668)
		(layer "F.Cu")
		(net "FM_P2E_BUF2_EQA1")
	)
	(via
		(at 12.935458 -423.821098)
		(size 0.762)
		(drill 0.381)
		(layers "F.Cu" "B.Cu")
		(net "FM_P2E_BUF2_EQA1")
	)
	(segment
		(start 12.065508 -422.551098)
		(end 12.065508 -422.170098)
		(width 0.10668)
		(layer "F.Cu")
		(net "FM_P2E_BUF2_EQA0")
	)
	(segment
		(start 10.287508 -422.043098)
		(end 9.779508 -422.551098)
		(width 0.10668)
		(layer "F.Cu")
		(net "FM_P2E_BUF2_EQA0")
	)
	(segment
		(start 12.935458 -422.551098)
		(end 12.065508 -422.551098)
		(width 0.10668)
		(layer "F.Cu")
		(net "FM_P2E_BUF2_EQA0")
	)
	(segment
		(start 14.723364 -422.883584)
		(end 13.267944 -422.883584)
		(width 0.10668)
		(layer "F.Cu")
		(net "FM_P2E_BUF2_EQA0")
	)
	(segment
		(start 11.938508 -422.043098)
		(end 10.287508 -422.043098)
		(width 0.10668)
		(layer "F.Cu")
		(net "FM_P2E_BUF2_EQA0")
	)
	(segment
		(start 13.267944 -422.883584)
		(end 12.935458 -422.551098)
		(width 0.10668)
		(layer "F.Cu")
		(net "FM_P2E_BUF2_EQA0")
	)
	(segment
		(start 12.065508 -422.170098)
		(end 11.938508 -422.043098)
		(width 0.10668)
		(layer "F.Cu")
		(net "FM_P2E_BUF2_EQA0")
	)
	(via
		(at 12.935458 -422.551098)
		(size 0.762)
		(drill 0.381)
		(layers "F.Cu" "B.Cu")
		(net "FM_P2E_BUF2_EQA0")
	)
	(segment
		(start 456.017884 -94.673928)
		(end 456.017884 -93.437964)
		(width 0.10668)
		(layer "F.Cu")
		(net "OCP_SFF_AUX_PWR_EN_R2")
	)
	(segment
		(start 458.084174 -94.277434)
		(end 457.34478 -95.016828)
		(width 0.10668)
		(layer "F.Cu")
		(net "OCP_SFF_AUX_PWR_EN_R2")
	)
	(segment
		(start 457.34478 -95.016828)
		(end 456.360784 -95.016828)
		(width 0.10668)
		(layer "F.Cu")
		(net "OCP_SFF_AUX_PWR_EN_R2")
	)
	(segment
		(start 458.487526 -94.277434)
		(end 458.084174 -94.277434)
		(width 0.10668)
		(layer "F.Cu")
		(net "OCP_SFF_AUX_PWR_EN_R2")
	)
	(segment
		(start 456.360784 -95.016828)
		(end 456.017884 -94.673928)
		(width 0.10668)
		(layer "F.Cu")
		(net "OCP_SFF_AUX_PWR_EN_R2")
	)
	(via
		(at 456.017884 -94.673928)
		(size 0.762)
		(drill 0.381)
		(layers "F.Cu" "B.Cu")
		(net "OCP_SFF_AUX_PWR_EN_R2")
	)
	(segment
		(start 391.97788 -294.88003)
		(end 391.97788 -296.277284)
		(width 0.10668)
		(layer "F.Cu")
		(net "FM_BOARD_SKU_ID4")
	)
	(segment
		(start 391.97788 -296.277284)
		(end 387.20395 -301.051214)
		(width 0.10668)
		(layer "F.Cu")
		(net "FM_BOARD_SKU_ID4")
	)
	(via
		(at 405.697436 -351.203006)
		(size 0.508)
		(drill 0.254)
		(layers "F.Cu" "B.Cu")
		(net "FM_BOARD_SKU_ID4")
	)
	(via
		(at 387.20395 -301.051214)
		(size 0.508)
		(drill 0.254)
		(layers "F.Cu" "B.Cu")
		(net "FM_BOARD_SKU_ID4")
	)
	(segment
		(start 405.809196 -354.039678)
		(end 405.809196 -351.314766)
		(width 0.10668)
		(layer "B.Cu")
		(net "FM_BOARD_SKU_ID4")
	)
	(segment
		(start 406.312878 -349.609664)
		(end 406.312878 -350.587564)
		(width 0.10668)
		(layer "B.Cu")
		(net "FM_BOARD_SKU_ID4")
	)
	(segment
		(start 405.809196 -351.314766)
		(end 405.697436 -351.203006)
		(width 0.10668)
		(layer "B.Cu")
		(net "FM_BOARD_SKU_ID4")
	)
	(segment
		(start 406.312878 -350.587564)
		(end 405.697436 -351.203006)
		(width 0.10668)
		(layer "B.Cu")
		(net "FM_BOARD_SKU_ID4")
	)
	(segment
		(start 387.20395 -301.051214)
		(end 386.89026 -301.364904)
		(width 0.11684)
		(layer "In15.Cu")
		(net "FM_BOARD_SKU_ID4")
	)
	(segment
		(start 386.89026 -301.364904)
		(end 386.89026 -332.686152)
		(width 0.11684)
		(layer "In15.Cu")
		(net "FM_BOARD_SKU_ID4")
	)
	(segment
		(start 405.235156 -350.740726)
		(end 405.697436 -351.203006)
		(width 0.11684)
		(layer "In15.Cu")
		(net "FM_BOARD_SKU_ID4")
	)
	(segment
		(start 404.600918 -346.16136)
		(end 404.600918 -349.558356)
		(width 0.11684)
		(layer "In15.Cu")
		(net "FM_BOARD_SKU_ID4")
	)
	(segment
		(start 404.600918 -349.558356)
		(end 405.235156 -350.192594)
		(width 0.11684)
		(layer "In15.Cu")
		(net "FM_BOARD_SKU_ID4")
	)
	(segment
		(start 397.638778 -343.43467)
		(end 401.874228 -343.43467)
		(width 0.11684)
		(layer "In15.Cu")
		(net "FM_BOARD_SKU_ID4")
	)
	(segment
		(start 386.89026 -332.686152)
		(end 397.638778 -343.43467)
		(width 0.11684)
		(layer "In15.Cu")
		(net "FM_BOARD_SKU_ID4")
	)
	(segment
		(start 401.874228 -343.43467)
		(end 404.600918 -346.16136)
		(width 0.11684)
		(layer "In15.Cu")
		(net "FM_BOARD_SKU_ID4")
	)
	(segment
		(start 405.235156 -350.192594)
		(end 405.235156 -350.740726)
		(width 0.11684)
		(layer "In15.Cu")
		(net "FM_BOARD_SKU_ID4")
	)
	(segment
		(start 366.128046 -294.070024)
		(end 366.594898 -294.335962)
		(width 0.10668)
		(layer "F.Cu")
		(net "FM_BOARD_SKU_ID3")
	)
	(via
		(at 404.043642 -350.923606)
		(size 0.508)
		(drill 0.254)
		(layers "F.Cu" "B.Cu")
		(net "FM_BOARD_SKU_ID3")
	)
	(via
		(at 366.594898 -294.335962)
		(size 0.4064)
		(drill 0.2032)
		(layers "F.Cu" "B.Cu")
		(net "FM_BOARD_SKU_ID3")
	)
	(segment
		(start 404.043642 -350.923606)
		(end 404.043642 -352.05035)
		(width 0.10668)
		(layer "B.Cu")
		(net "FM_BOARD_SKU_ID3")
	)
	(segment
		(start 404.043642 -349.616014)
		(end 404.043642 -350.923606)
		(width 0.10668)
		(layer "B.Cu")
		(net "FM_BOARD_SKU_ID3")
	)
	(segment
		(start 404.043642 -352.05035)
		(end 403.377146 -352.716846)
		(width 0.10668)
		(layer "B.Cu")
		(net "FM_BOARD_SKU_ID3")
	)
	(segment
		(start 403.377146 -352.716846)
		(end 403.377146 -354.039678)
		(width 0.10668)
		(layer "B.Cu")
		(net "FM_BOARD_SKU_ID3")
	)
	(segment
		(start 386.04698 -333.114904)
		(end 386.46481 -333.532734)
		(width 0.11684)
		(layer "In15.Cu")
		(net "FM_BOARD_SKU_ID3")
	)
	(segment
		(start 386.46481 -333.532734)
		(end 386.46481 -333.532988)
		(width 0.11684)
		(layer "In15.Cu")
		(net "FM_BOARD_SKU_ID3")
	)
	(segment
		(start 403.379686 -349.026734)
		(end 403.379686 -350.25965)
		(width 0.11684)
		(layer "In15.Cu")
		(net "FM_BOARD_SKU_ID3")
	)
	(segment
		(start 397.209772 -344.27795)
		(end 398.630902 -344.27795)
		(width 0.11684)
		(layer "In15.Cu")
		(net "FM_BOARD_SKU_ID3")
	)
	(segment
		(start 365.93399 -296.370756)
		(end 366.000792 -296.437558)
		(width 0.11684)
		(layer "In15.Cu")
		(net "FM_BOARD_SKU_ID3")
	)
	(segment
		(start 365.93399 -295.895014)
		(end 365.93399 -296.370756)
		(width 0.11684)
		(layer "In15.Cu")
		(net "FM_BOARD_SKU_ID3")
	)
	(segment
		(start 366.000792 -298.449238)
		(end 386.04698 -318.495426)
		(width 0.11684)
		(layer "In15.Cu")
		(net "FM_BOARD_SKU_ID3")
	)
	(segment
		(start 366.594898 -295.234106)
		(end 365.93399 -295.895014)
		(width 0.11684)
		(layer "In15.Cu")
		(net "FM_BOARD_SKU_ID3")
	)
	(segment
		(start 386.46481 -333.532988)
		(end 397.209772 -344.27795)
		(width 0.11684)
		(layer "In15.Cu")
		(net "FM_BOARD_SKU_ID3")
	)
	(segment
		(start 386.04698 -318.495426)
		(end 386.04698 -333.114904)
		(width 0.11684)
		(layer "In15.Cu")
		(net "FM_BOARD_SKU_ID3")
	)
	(segment
		(start 366.594898 -294.335962)
		(end 366.594898 -295.234106)
		(width 0.11684)
		(layer "In15.Cu")
		(net "FM_BOARD_SKU_ID3")
	)
	(segment
		(start 366.000792 -296.437558)
		(end 366.000792 -298.449238)
		(width 0.11684)
		(layer "In15.Cu")
		(net "FM_BOARD_SKU_ID3")
	)
	(segment
		(start 398.630902 -344.27795)
		(end 403.379686 -349.026734)
		(width 0.11684)
		(layer "In15.Cu")
		(net "FM_BOARD_SKU_ID3")
	)
	(segment
		(start 403.379686 -350.25965)
		(end 404.043642 -350.923606)
		(width 0.11684)
		(layer "In15.Cu")
		(net "FM_BOARD_SKU_ID3")
	)
	(segment
		(start 366.597946 -293.260018)
		(end 367.064798 -293.525956)
		(width 0.10668)
		(layer "F.Cu")
		(net "FM_BOARD_SKU_ID2")
	)
	(via
		(at 404.568152 -352.632772)
		(size 0.508)
		(drill 0.254)
		(layers "F.Cu" "B.Cu")
		(net "FM_BOARD_SKU_ID2")
	)
	(via
		(at 367.064798 -293.525956)
		(size 0.4064)
		(drill 0.2032)
		(layers "F.Cu" "B.Cu")
		(net "FM_BOARD_SKU_ID2")
	)
	(segment
		(start 404.568152 -351.504504)
		(end 405.241252 -350.831404)
		(width 0.10668)
		(layer "B.Cu")
		(net "FM_BOARD_SKU_ID2")
	)
	(segment
		(start 405.241252 -350.831404)
		(end 405.241252 -349.595694)
		(width 0.10668)
		(layer "B.Cu")
		(net "FM_BOARD_SKU_ID2")
	)
	(segment
		(start 404.568152 -354.039678)
		(end 404.568152 -352.632772)
		(width 0.10668)
		(layer "B.Cu")
		(net "FM_BOARD_SKU_ID2")
	)
	(segment
		(start 404.568152 -352.632772)
		(end 404.568152 -351.504504)
		(width 0.10668)
		(layer "B.Cu")
		(net "FM_BOARD_SKU_ID2")
	)
	(segment
		(start 366.422432 -298.274486)
		(end 386.46862 -318.320674)
		(width 0.11684)
		(layer "In15.Cu")
		(net "FM_BOARD_SKU_ID2")
	)
	(segment
		(start 404.633176 -350.364552)
		(end 404.633176 -352.567748)
		(width 0.11684)
		(layer "In15.Cu")
		(net "FM_BOARD_SKU_ID2")
	)
	(segment
		(start 386.88645 -333.357982)
		(end 386.88645 -333.358236)
		(width 0.11684)
		(layer "In15.Cu")
		(net "FM_BOARD_SKU_ID2")
	)
	(segment
		(start 386.46862 -318.320674)
		(end 386.46862 -332.940152)
		(width 0.11684)
		(layer "In15.Cu")
		(net "FM_BOARD_SKU_ID2")
	)
	(segment
		(start 404.053548 -346.388182)
		(end 404.053548 -349.357188)
		(width 0.11684)
		(layer "In15.Cu")
		(net "FM_BOARD_SKU_ID2")
	)
	(segment
		(start 404.056342 -349.359982)
		(end 404.056342 -349.787718)
		(width 0.11684)
		(layer "In15.Cu")
		(net "FM_BOARD_SKU_ID2")
	)
	(segment
		(start 367.514124 -294.863266)
		(end 367.514124 -296.185336)
		(width 0.11684)
		(layer "In15.Cu")
		(net "FM_BOARD_SKU_ID2")
	)
	(segment
		(start 404.053548 -349.357188)
		(end 404.056342 -349.359982)
		(width 0.11684)
		(layer "In15.Cu")
		(net "FM_BOARD_SKU_ID2")
	)
	(segment
		(start 401.521676 -343.85631)
		(end 404.053548 -346.388182)
		(width 0.11684)
		(layer "In15.Cu")
		(net "FM_BOARD_SKU_ID2")
	)
	(segment
		(start 404.633176 -352.567748)
		(end 404.568152 -352.632772)
		(width 0.11684)
		(layer "In15.Cu")
		(net "FM_BOARD_SKU_ID2")
	)
	(segment
		(start 367.064798 -294.41394)
		(end 367.514124 -294.863266)
		(width 0.11684)
		(layer "In15.Cu")
		(net "FM_BOARD_SKU_ID2")
	)
	(segment
		(start 397.384524 -343.85631)
		(end 401.521676 -343.85631)
		(width 0.11684)
		(layer "In15.Cu")
		(net "FM_BOARD_SKU_ID2")
	)
	(segment
		(start 366.422432 -297.277028)
		(end 366.422432 -298.274486)
		(width 0.11684)
		(layer "In15.Cu")
		(net "FM_BOARD_SKU_ID2")
	)
	(segment
		(start 386.46862 -332.940152)
		(end 386.88645 -333.357982)
		(width 0.11684)
		(layer "In15.Cu")
		(net "FM_BOARD_SKU_ID2")
	)
	(segment
		(start 367.514124 -296.185336)
		(end 366.422432 -297.277028)
		(width 0.11684)
		(layer "In15.Cu")
		(net "FM_BOARD_SKU_ID2")
	)
	(segment
		(start 386.88645 -333.358236)
		(end 397.384524 -343.85631)
		(width 0.11684)
		(layer "In15.Cu")
		(net "FM_BOARD_SKU_ID2")
	)
	(segment
		(start 404.056342 -349.787718)
		(end 404.633176 -350.364552)
		(width 0.11684)
		(layer "In15.Cu")
		(net "FM_BOARD_SKU_ID2")
	)
	(segment
		(start 367.064798 -293.525956)
		(end 367.064798 -294.41394)
		(width 0.11684)
		(layer "In15.Cu")
		(net "FM_BOARD_SKU_ID2")
	)
	(segment
		(start 365.654844 -292.71595)
		(end 365.187992 -292.450012)
		(width 0.10668)
		(layer "F.Cu")
		(net "FM_BOARD_SKU_ID1")
	)
	(via
		(at 402.844 -352.460814)
		(size 0.508)
		(drill 0.254)
		(layers "F.Cu" "B.Cu")
		(net "FM_BOARD_SKU_ID1")
	)
	(via
		(at 365.654844 -292.71595)
		(size 0.4064)
		(drill 0.2032)
		(layers "F.Cu" "B.Cu")
		(net "FM_BOARD_SKU_ID1")
	)
	(segment
		(start 403.214078 -352.090736)
		(end 403.214078 -349.988632)
		(width 0.10668)
		(layer "B.Cu")
		(net "FM_BOARD_SKU_ID1")
	)
	(segment
		(start 402.186394 -353.11842)
		(end 402.844 -352.460814)
		(width 0.10668)
		(layer "B.Cu")
		(net "FM_BOARD_SKU_ID1")
	)
	(segment
		(start 402.186394 -354.039678)
		(end 402.186394 -353.11842)
		(width 0.10668)
		(layer "B.Cu")
		(net "FM_BOARD_SKU_ID1")
	)
	(segment
		(start 402.844 -352.460814)
		(end 403.214078 -352.090736)
		(width 0.10668)
		(layer "B.Cu")
		(net "FM_BOARD_SKU_ID1")
	)
	(segment
		(start 403.214078 -349.988632)
		(end 402.844 -349.618554)
		(width 0.10668)
		(layer "B.Cu")
		(net "FM_BOARD_SKU_ID1")
	)
	(segment
		(start 365.579152 -298.62399)
		(end 365.579152 -295.035224)
		(width 0.11684)
		(layer "In15.Cu")
		(net "FM_BOARD_SKU_ID1")
	)
	(segment
		(start 398.45615 -344.69959)
		(end 397.03502 -344.69959)
		(width 0.11684)
		(layer "In15.Cu")
		(net "FM_BOARD_SKU_ID1")
	)
	(segment
		(start 386.04317 -333.707486)
		(end 385.62534 -333.289656)
		(width 0.11684)
		(layer "In15.Cu")
		(net "FM_BOARD_SKU_ID1")
	)
	(segment
		(start 397.03502 -344.69959)
		(end 386.04317 -333.70774)
		(width 0.11684)
		(layer "In15.Cu")
		(net "FM_BOARD_SKU_ID1")
	)
	(segment
		(start 385.62534 -318.670178)
		(end 365.579152 -298.62399)
		(width 0.11684)
		(layer "In15.Cu")
		(net "FM_BOARD_SKU_ID1")
	)
	(segment
		(start 385.62534 -333.289656)
		(end 385.62534 -318.670178)
		(width 0.11684)
		(layer "In15.Cu")
		(net "FM_BOARD_SKU_ID1")
	)
	(segment
		(start 366.084358 -294.03548)
		(end 365.654844 -293.605966)
		(width 0.11684)
		(layer "In15.Cu")
		(net "FM_BOARD_SKU_ID1")
	)
	(segment
		(start 386.04317 -333.70774)
		(end 386.04317 -333.707486)
		(width 0.11684)
		(layer "In15.Cu")
		(net "FM_BOARD_SKU_ID1")
	)
	(segment
		(start 402.844 -349.08744)
		(end 398.45615 -344.69959)
		(width 0.11684)
		(layer "In15.Cu")
		(net "FM_BOARD_SKU_ID1")
	)
	(segment
		(start 366.084358 -294.530018)
		(end 366.084358 -294.03548)
		(width 0.11684)
		(layer "In15.Cu")
		(net "FM_BOARD_SKU_ID1")
	)
	(segment
		(start 402.844 -352.460814)
		(end 402.844 -349.08744)
		(width 0.11684)
		(layer "In15.Cu")
		(net "FM_BOARD_SKU_ID1")
	)
	(segment
		(start 365.579152 -295.035224)
		(end 366.084358 -294.530018)
		(width 0.11684)
		(layer "In15.Cu")
		(net "FM_BOARD_SKU_ID1")
	)
	(segment
		(start 365.654844 -293.605966)
		(end 365.654844 -292.71595)
		(width 0.11684)
		(layer "In15.Cu")
		(net "FM_BOARD_SKU_ID1")
	)
	(segment
		(start 365.18469 -293.525956)
		(end 364.717838 -293.260018)
		(width 0.10668)
		(layer "F.Cu")
		(net "FM_BOARD_SKU_ID0")
	)
	(via
		(at 365.18469 -293.525956)
		(size 0.4064)
		(drill 0.2032)
		(layers "F.Cu" "B.Cu")
		(net "FM_BOARD_SKU_ID0")
	)
	(via
		(at 402.375624 -350.880426)
		(size 0.508)
		(drill 0.254)
		(layers "F.Cu" "B.Cu")
		(net "FM_BOARD_SKU_ID0")
	)
	(segment
		(start 402.375624 -350.880426)
		(end 402.375624 -350.762316)
		(width 0.10668)
		(layer "B.Cu")
		(net "FM_BOARD_SKU_ID0")
	)
	(segment
		(start 401.870926 -350.880426)
		(end 402.375624 -350.880426)
		(width 0.10668)
		(layer "B.Cu")
		(net "FM_BOARD_SKU_ID0")
	)
	(segment
		(start 400.964146 -354.039678)
		(end 400.964146 -351.787206)
		(width 0.10668)
		(layer "B.Cu")
		(net "FM_BOARD_SKU_ID0")
	)
	(segment
		(start 401.619974 -350.006666)
		(end 401.619974 -349.617792)
		(width 0.10668)
		(layer "B.Cu")
		(net "FM_BOARD_SKU_ID0")
	)
	(segment
		(start 402.375624 -350.762316)
		(end 401.619974 -350.006666)
		(width 0.10668)
		(layer "B.Cu")
		(net "FM_BOARD_SKU_ID0")
	)
	(segment
		(start 400.964146 -351.787206)
		(end 401.870926 -350.880426)
		(width 0.10668)
		(layer "B.Cu")
		(net "FM_BOARD_SKU_ID0")
	)
	(segment
		(start 365.157258 -298.449492)
		(end 365.157258 -298.798488)
		(width 0.11684)
		(layer "In15.Cu")
		(net "FM_BOARD_SKU_ID0")
	)
	(segment
		(start 385.62153 -333.882238)
		(end 385.62153 -333.882492)
		(width 0.11684)
		(layer "In15.Cu")
		(net "FM_BOARD_SKU_ID0")
	)
	(segment
		(start 398.339056 -345.178888)
		(end 402.375624 -349.215456)
		(width 0.11684)
		(layer "In15.Cu")
		(net "FM_BOARD_SKU_ID0")
	)
	(segment
		(start 385.2037 -333.464408)
		(end 385.62153 -333.882238)
		(width 0.11684)
		(layer "In15.Cu")
		(net "FM_BOARD_SKU_ID0")
	)
	(segment
		(start 365.18469 -296.41038)
		(end 365.157512 -296.437558)
		(width 0.11684)
		(layer "In15.Cu")
		(net "FM_BOARD_SKU_ID0")
	)
	(segment
		(start 385.62153 -333.882492)
		(end 396.917926 -345.178888)
		(width 0.11684)
		(layer "In15.Cu")
		(net "FM_BOARD_SKU_ID0")
	)
	(segment
		(start 396.917926 -345.178888)
		(end 398.339056 -345.178888)
		(width 0.11684)
		(layer "In15.Cu")
		(net "FM_BOARD_SKU_ID0")
	)
	(segment
		(start 402.375624 -349.215456)
		(end 402.375624 -350.880426)
		(width 0.11684)
		(layer "In15.Cu")
		(net "FM_BOARD_SKU_ID0")
	)
	(segment
		(start 365.18469 -293.525956)
		(end 365.18469 -296.41038)
		(width 0.11684)
		(layer "In15.Cu")
		(net "FM_BOARD_SKU_ID0")
	)
	(segment
		(start 365.157258 -298.798488)
		(end 385.2037 -318.84493)
		(width 0.11684)
		(layer "In15.Cu")
		(net "FM_BOARD_SKU_ID0")
	)
	(segment
		(start 365.157512 -298.449238)
		(end 365.157258 -298.449492)
		(width 0.11684)
		(layer "In15.Cu")
		(net "FM_BOARD_SKU_ID0")
	)
	(segment
		(start 385.2037 -318.84493)
		(end 385.2037 -333.464408)
		(width 0.11684)
		(layer "In15.Cu")
		(net "FM_BOARD_SKU_ID0")
	)
	(segment
		(start 365.157512 -296.437558)
		(end 365.157512 -298.449238)
		(width 0.11684)
		(layer "In15.Cu")
		(net "FM_BOARD_SKU_ID0")
	)
	(segment
		(start 164.105844 -116.267484)
		(end 164.920676 -116.267484)
		(width 0.10668)
		(layer "F.Cu")
		(net "FM_BOARD_BMC_SKU_ID4")
	)
	(segment
		(start 167.512492 -116.26977)
		(end 168.29278 -116.26977)
		(width 0.10668)
		(layer "F.Cu")
		(net "FM_BOARD_BMC_SKU_ID4")
	)
	(segment
		(start 166.965122 -115.7224)
		(end 165.46576 -115.7224)
		(width 0.10668)
		(layer "F.Cu")
		(net "FM_BOARD_BMC_SKU_ID4")
	)
	(segment
		(start 167.512492 -116.26977)
		(end 166.965122 -115.7224)
		(width 0.10668)
		(layer "F.Cu")
		(net "FM_BOARD_BMC_SKU_ID4")
	)
	(segment
		(start 165.46576 -115.7224)
		(end 165.3032 -115.88496)
		(width 0.10668)
		(layer "F.Cu")
		(net "FM_BOARD_BMC_SKU_ID4")
	)
	(segment
		(start 177.122074 -114.652806)
		(end 176.732184 -114.262916)
		(width 0.10668)
		(layer "F.Cu")
		(net "FM_BOARD_BMC_SKU_ID4")
	)
	(segment
		(start 164.920676 -116.267484)
		(end 165.3032 -115.88496)
		(width 0.10668)
		(layer "F.Cu")
		(net "FM_BOARD_BMC_SKU_ID4")
	)
	(via
		(at 168.29278 -116.26977)
		(size 0.508)
		(drill 0.254)
		(layers "F.Cu" "B.Cu")
		(net "FM_BOARD_BMC_SKU_ID4")
	)
	(via
		(at 165.3032 -115.88496)
		(size 0.762)
		(drill 0.381)
		(layers "F.Cu" "B.Cu")
		(net "FM_BOARD_BMC_SKU_ID4")
	)
	(via
		(at 176.732184 -114.262916)
		(size 0.4572)
		(drill 0.254)
		(layers "F.Cu" "B.Cu")
		(net "FM_BOARD_BMC_SKU_ID4")
	)
	(segment
		(start 168.29278 -116.26977)
		(end 168.29278 -116.227606)
		(width 0.11684)
		(layer "In2.Cu")
		(net "FM_BOARD_BMC_SKU_ID4")
	)
	(segment
		(start 168.76014 -115.760246)
		(end 170.636692 -115.760246)
		(width 0.11684)
		(layer "In2.Cu")
		(net "FM_BOARD_BMC_SKU_ID4")
	)
	(segment
		(start 170.636692 -115.760246)
		(end 172.019468 -114.37747)
		(width 0.11684)
		(layer "In2.Cu")
		(net "FM_BOARD_BMC_SKU_ID4")
	)
	(segment
		(start 168.29278 -116.227606)
		(end 168.76014 -115.760246)
		(width 0.11684)
		(layer "In2.Cu")
		(net "FM_BOARD_BMC_SKU_ID4")
	)
	(segment
		(start 172.019468 -114.37747)
		(end 176.61763 -114.37747)
		(width 0.11684)
		(layer "In2.Cu")
		(net "FM_BOARD_BMC_SKU_ID4")
	)
	(segment
		(start 176.61763 -114.37747)
		(end 176.732184 -114.262916)
		(width 0.11684)
		(layer "In2.Cu")
		(net "FM_BOARD_BMC_SKU_ID4")
	)
	(segment
		(start 167.51681 -117.301772)
		(end 168.223946 -117.301772)
		(width 0.10668)
		(layer "F.Cu")
		(net "FM_BOARD_BMC_SKU_ID3")
	)
	(segment
		(start 177.922174 -114.652806)
		(end 177.532284 -114.262916)
		(width 0.10668)
		(layer "F.Cu")
		(net "FM_BOARD_BMC_SKU_ID3")
	)
	(segment
		(start 167.042846 -117.775736)
		(end 167.51681 -117.301772)
		(width 0.10668)
		(layer "F.Cu")
		(net "FM_BOARD_BMC_SKU_ID3")
	)
	(segment
		(start 166.309294 -117.775736)
		(end 167.042846 -117.775736)
		(width 0.10668)
		(layer "F.Cu")
		(net "FM_BOARD_BMC_SKU_ID3")
	)
	(segment
		(start 164.19957 -117.310662)
		(end 164.578538 -117.68963)
		(width 0.10668)
		(layer "F.Cu")
		(net "FM_BOARD_BMC_SKU_ID3")
	)
	(segment
		(start 164.578538 -117.68963)
		(end 166.223188 -117.68963)
		(width 0.10668)
		(layer "F.Cu")
		(net "FM_BOARD_BMC_SKU_ID3")
	)
	(segment
		(start 164.134546 -117.310662)
		(end 164.19957 -117.310662)
		(width 0.10668)
		(layer "F.Cu")
		(net "FM_BOARD_BMC_SKU_ID3")
	)
	(segment
		(start 166.223188 -117.68963)
		(end 166.309294 -117.775736)
		(width 0.10668)
		(layer "F.Cu")
		(net "FM_BOARD_BMC_SKU_ID3")
	)
	(segment
		(start 168.223946 -117.301772)
		(end 168.29278 -117.232938)
		(width 0.10668)
		(layer "F.Cu")
		(net "FM_BOARD_BMC_SKU_ID3")
	)
	(via
		(at 168.29278 -117.232938)
		(size 0.508)
		(drill 0.254)
		(layers "F.Cu" "B.Cu")
		(net "FM_BOARD_BMC_SKU_ID3")
	)
	(via
		(at 177.532284 -114.262916)
		(size 0.4572)
		(drill 0.254)
		(layers "F.Cu" "B.Cu")
		(net "FM_BOARD_BMC_SKU_ID3")
	)
	(segment
		(start 168.29278 -117.232938)
		(end 168.29278 -117.136164)
		(width 0.11684)
		(layer "In2.Cu")
		(net "FM_BOARD_BMC_SKU_ID3")
	)
	(segment
		(start 168.29278 -117.136164)
		(end 168.599104 -116.82984)
		(width 0.11684)
		(layer "In2.Cu")
		(net "FM_BOARD_BMC_SKU_ID3")
	)
	(segment
		(start 176.852072 -114.943128)
		(end 177.532284 -114.262916)
		(width 0.11684)
		(layer "In2.Cu")
		(net "FM_BOARD_BMC_SKU_ID3")
	)
	(segment
		(start 170.367198 -116.82984)
		(end 172.25391 -114.943128)
		(width 0.11684)
		(layer "In2.Cu")
		(net "FM_BOARD_BMC_SKU_ID3")
	)
	(segment
		(start 172.25391 -114.943128)
		(end 176.852072 -114.943128)
		(width 0.11684)
		(layer "In2.Cu")
		(net "FM_BOARD_BMC_SKU_ID3")
	)
	(segment
		(start 168.599104 -116.82984)
		(end 170.367198 -116.82984)
		(width 0.11684)
		(layer "In2.Cu")
		(net "FM_BOARD_BMC_SKU_ID3")
	)
	(segment
		(start 181.122066 -113.85296)
		(end 180.732176 -113.46307)
		(width 0.10668)
		(layer "F.Cu")
		(net "FM_BOARD_BMC_SKU_ID2")
	)
	(segment
		(start 169.83964 -123.46813)
		(end 170.055032 -123.252738)
		(width 0.10668)
		(layer "F.Cu")
		(net "FM_BOARD_BMC_SKU_ID2")
	)
	(segment
		(start 170.055032 -123.252738)
		(end 171.173648 -123.252738)
		(width 0.10668)
		(layer "F.Cu")
		(net "FM_BOARD_BMC_SKU_ID2")
	)
	(segment
		(start 171.604178 -123.683268)
		(end 171.604178 -123.973336)
		(width 0.10668)
		(layer "F.Cu")
		(net "FM_BOARD_BMC_SKU_ID2")
	)
	(segment
		(start 169.624756 -123.683014)
		(end 169.83964 -123.46813)
		(width 0.10668)
		(layer "F.Cu")
		(net "FM_BOARD_BMC_SKU_ID2")
	)
	(segment
		(start 171.604178 -123.973336)
		(end 172.406564 -124.775722)
		(width 0.10668)
		(layer "F.Cu")
		(net "FM_BOARD_BMC_SKU_ID2")
	)
	(segment
		(start 168.79062 -123.683014)
		(end 169.624756 -123.683014)
		(width 0.10668)
		(layer "F.Cu")
		(net "FM_BOARD_BMC_SKU_ID2")
	)
	(segment
		(start 172.406564 -124.775722)
		(end 172.767498 -124.775722)
		(width 0.10668)
		(layer "F.Cu")
		(net "FM_BOARD_BMC_SKU_ID2")
	)
	(segment
		(start 171.173648 -123.252738)
		(end 171.604178 -123.683268)
		(width 0.10668)
		(layer "F.Cu")
		(net "FM_BOARD_BMC_SKU_ID2")
	)
	(via
		(at 180.732176 -113.46307)
		(size 0.4572)
		(drill 0.254)
		(layers "F.Cu" "B.Cu")
		(net "FM_BOARD_BMC_SKU_ID2")
	)
	(via
		(at 172.767498 -124.775722)
		(size 0.508)
		(drill 0.254)
		(layers "F.Cu" "B.Cu")
		(net "FM_BOARD_BMC_SKU_ID2")
	)
	(via
		(at 169.83964 -123.46813)
		(size 0.762)
		(drill 0.381)
		(layers "F.Cu" "B.Cu")
		(net "FM_BOARD_BMC_SKU_ID2")
	)
	(segment
		(start 173.485302 -124.775722)
		(end 172.767498 -124.775722)
		(width 0.11684)
		(layer "In11.Cu")
		(net "FM_BOARD_BMC_SKU_ID2")
	)
	(segment
		(start 179.52085 -119.248682)
		(end 179.33289 -119.436642)
		(width 0.11684)
		(layer "In11.Cu")
		(net "FM_BOARD_BMC_SKU_ID2")
	)
	(segment
		(start 178.73599 -119.549418)
		(end 178.73599 -123.419108)
		(width 0.11684)
		(layer "In11.Cu")
		(net "FM_BOARD_BMC_SKU_ID2")
	)
	(segment
		(start 180.656738 -113.46307)
		(end 180.327046 -113.792762)
		(width 0.11684)
		(layer "In11.Cu")
		(net "FM_BOARD_BMC_SKU_ID2")
	)
	(segment
		(start 178.848766 -119.436642)
		(end 178.73599 -119.549418)
		(width 0.11684)
		(layer "In11.Cu")
		(net "FM_BOARD_BMC_SKU_ID2")
	)
	(segment
		(start 174.004732 -125.295152)
		(end 173.485302 -124.775722)
		(width 0.11684)
		(layer "In11.Cu")
		(net "FM_BOARD_BMC_SKU_ID2")
	)
	(segment
		(start 176.859946 -125.295152)
		(end 174.004732 -125.295152)
		(width 0.11684)
		(layer "In11.Cu")
		(net "FM_BOARD_BMC_SKU_ID2")
	)
	(segment
		(start 180.732176 -113.46307)
		(end 180.656738 -113.46307)
		(width 0.11684)
		(layer "In11.Cu")
		(net "FM_BOARD_BMC_SKU_ID2")
	)
	(segment
		(start 178.73599 -123.419108)
		(end 176.859946 -125.295152)
		(width 0.11684)
		(layer "In11.Cu")
		(net "FM_BOARD_BMC_SKU_ID2")
	)
	(segment
		(start 180.327046 -113.792762)
		(end 180.327046 -114.63147)
		(width 0.11684)
		(layer "In11.Cu")
		(net "FM_BOARD_BMC_SKU_ID2")
	)
	(segment
		(start 179.33289 -119.436642)
		(end 178.848766 -119.436642)
		(width 0.11684)
		(layer "In11.Cu")
		(net "FM_BOARD_BMC_SKU_ID2")
	)
	(segment
		(start 180.327046 -114.63147)
		(end 179.52085 -115.437666)
		(width 0.11684)
		(layer "In11.Cu")
		(net "FM_BOARD_BMC_SKU_ID2")
	)
	(segment
		(start 179.52085 -115.437666)
		(end 179.52085 -119.248682)
		(width 0.11684)
		(layer "In11.Cu")
		(net "FM_BOARD_BMC_SKU_ID2")
	)
	(segment
		(start 172.882306 -125.751336)
		(end 173.028102 -125.897132)
		(width 0.10668)
		(layer "F.Cu")
		(net "FM_BOARD_BMC_SKU_ID1")
	)
	(segment
		(start 181.922166 -113.05286)
		(end 181.532276 -112.66297)
		(width 0.10668)
		(layer "F.Cu")
		(net "FM_BOARD_BMC_SKU_ID1")
	)
	(segment
		(start 168.755568 -125.762004)
		(end 168.755568 -126.064518)
		(width 0.10668)
		(layer "F.Cu")
		(net "FM_BOARD_BMC_SKU_ID1")
	)
	(segment
		(start 168.755568 -126.064518)
		(end 169.147236 -126.456186)
		(width 0.10668)
		(layer "F.Cu")
		(net "FM_BOARD_BMC_SKU_ID1")
	)
	(segment
		(start 170.964606 -126.456186)
		(end 171.669456 -125.751336)
		(width 0.10668)
		(layer "F.Cu")
		(net "FM_BOARD_BMC_SKU_ID1")
	)
	(segment
		(start 171.669456 -125.751336)
		(end 172.882306 -125.751336)
		(width 0.10668)
		(layer "F.Cu")
		(net "FM_BOARD_BMC_SKU_ID1")
	)
	(segment
		(start 169.147236 -126.456186)
		(end 170.964606 -126.456186)
		(width 0.10668)
		(layer "F.Cu")
		(net "FM_BOARD_BMC_SKU_ID1")
	)
	(via
		(at 181.532276 -112.66297)
		(size 0.4572)
		(drill 0.254)
		(layers "F.Cu" "B.Cu")
		(net "FM_BOARD_BMC_SKU_ID1")
	)
	(via
		(at 173.028102 -125.897132)
		(size 0.508)
		(drill 0.254)
		(layers "F.Cu" "B.Cu")
		(net "FM_BOARD_BMC_SKU_ID1")
	)
	(segment
		(start 180.101748 -120.23217)
		(end 179.719478 -120.23217)
		(width 0.11684)
		(layer "In11.Cu")
		(net "FM_BOARD_BMC_SKU_ID1")
	)
	(segment
		(start 179.088542 -123.732798)
		(end 176.719738 -126.101602)
		(width 0.11684)
		(layer "In11.Cu")
		(net "FM_BOARD_BMC_SKU_ID1")
	)
	(segment
		(start 179.54244 -122.398536)
		(end 179.088542 -122.852434)
		(width 0.11684)
		(layer "In11.Cu")
		(net "FM_BOARD_BMC_SKU_ID1")
	)
	(segment
		(start 179.54244 -120.409208)
		(end 179.54244 -122.398536)
		(width 0.11684)
		(layer "In11.Cu")
		(net "FM_BOARD_BMC_SKU_ID1")
	)
	(segment
		(start 181.605174 -112.66297)
		(end 181.923436 -112.981232)
		(width 0.11684)
		(layer "In11.Cu")
		(net "FM_BOARD_BMC_SKU_ID1")
	)
	(segment
		(start 179.088542 -122.852434)
		(end 179.088542 -123.732798)
		(width 0.11684)
		(layer "In11.Cu")
		(net "FM_BOARD_BMC_SKU_ID1")
	)
	(segment
		(start 179.719478 -120.23217)
		(end 179.54244 -120.409208)
		(width 0.11684)
		(layer "In11.Cu")
		(net "FM_BOARD_BMC_SKU_ID1")
	)
	(segment
		(start 173.144942 -126.101602)
		(end 173.028102 -125.984762)
		(width 0.11684)
		(layer "In11.Cu")
		(net "FM_BOARD_BMC_SKU_ID1")
	)
	(segment
		(start 180.32222 -115.517676)
		(end 180.32222 -120.011698)
		(width 0.11684)
		(layer "In11.Cu")
		(net "FM_BOARD_BMC_SKU_ID1")
	)
	(segment
		(start 181.004464 -114.835432)
		(end 180.32222 -115.517676)
		(width 0.11684)
		(layer "In11.Cu")
		(net "FM_BOARD_BMC_SKU_ID1")
	)
	(segment
		(start 176.719738 -126.101602)
		(end 173.144942 -126.101602)
		(width 0.11684)
		(layer "In11.Cu")
		(net "FM_BOARD_BMC_SKU_ID1")
	)
	(segment
		(start 173.028102 -125.984762)
		(end 173.028102 -125.897132)
		(width 0.11684)
		(layer "In11.Cu")
		(net "FM_BOARD_BMC_SKU_ID1")
	)
	(segment
		(start 181.923436 -114.421666)
		(end 181.50967 -114.835432)
		(width 0.11684)
		(layer "In11.Cu")
		(net "FM_BOARD_BMC_SKU_ID1")
	)
	(segment
		(start 181.532276 -112.66297)
		(end 181.605174 -112.66297)
		(width 0.11684)
		(layer "In11.Cu")
		(net "FM_BOARD_BMC_SKU_ID1")
	)
	(segment
		(start 181.50967 -114.835432)
		(end 181.004464 -114.835432)
		(width 0.11684)
		(layer "In11.Cu")
		(net "FM_BOARD_BMC_SKU_ID1")
	)
	(segment
		(start 181.923436 -112.981232)
		(end 181.923436 -114.421666)
		(width 0.11684)
		(layer "In11.Cu")
		(net "FM_BOARD_BMC_SKU_ID1")
	)
	(segment
		(start 180.32222 -120.011698)
		(end 180.101748 -120.23217)
		(width 0.11684)
		(layer "In11.Cu")
		(net "FM_BOARD_BMC_SKU_ID1")
	)
	(segment
		(start 178.72202 -109.852968)
		(end 178.33213 -109.463078)
		(width 0.10668)
		(layer "F.Cu")
		(net "FM_BOARD_BMC_SKU_ID0")
	)
	(via
		(at 178.33213 -109.463078)
		(size 0.4572)
		(drill 0.254)
		(layers "F.Cu" "B.Cu")
		(net "FM_BOARD_BMC_SKU_ID0")
	)
	(via
		(at 165.570662 -111.637572)
		(size 0.508)
		(drill 0.254)
		(layers "F.Cu" "B.Cu")
		(net "FM_BOARD_BMC_SKU_ID0")
	)
	(segment
		(start 164.444426 -111.637572)
		(end 165.570662 -111.637572)
		(width 0.10668)
		(layer "B.Cu")
		(net "FM_BOARD_BMC_SKU_ID0")
	)
	(segment
		(start 164.444426 -111.637572)
		(end 164.444426 -112.694212)
		(width 0.10668)
		(layer "B.Cu")
		(net "FM_BOARD_BMC_SKU_ID0")
	)
	(segment
		(start 164.444426 -112.694212)
		(end 164.763958 -113.013744)
		(width 0.10668)
		(layer "B.Cu")
		(net "FM_BOARD_BMC_SKU_ID0")
	)
	(segment
		(start 165.570662 -111.637572)
		(end 166.922196 -110.286038)
		(width 0.11684)
		(layer "In2.Cu")
		(net "FM_BOARD_BMC_SKU_ID0")
	)
	(segment
		(start 168.80713 -107.056174)
		(end 175.75784 -107.056174)
		(width 0.11684)
		(layer "In2.Cu")
		(net "FM_BOARD_BMC_SKU_ID0")
	)
	(segment
		(start 166.922196 -110.286038)
		(end 166.922196 -108.941108)
		(width 0.11684)
		(layer "In2.Cu")
		(net "FM_BOARD_BMC_SKU_ID0")
	)
	(segment
		(start 177.935636 -109.132624)
		(end 178.26609 -109.463078)
		(width 0.11684)
		(layer "In2.Cu")
		(net "FM_BOARD_BMC_SKU_ID0")
	)
	(segment
		(start 178.26609 -109.463078)
		(end 178.33213 -109.463078)
		(width 0.11684)
		(layer "In2.Cu")
		(net "FM_BOARD_BMC_SKU_ID0")
	)
	(segment
		(start 177.70221 -108.080302)
		(end 177.935636 -108.313728)
		(width 0.11684)
		(layer "In2.Cu")
		(net "FM_BOARD_BMC_SKU_ID0")
	)
	(segment
		(start 177.935636 -108.313728)
		(end 177.935636 -109.132624)
		(width 0.11684)
		(layer "In2.Cu")
		(net "FM_BOARD_BMC_SKU_ID0")
	)
	(segment
		(start 166.922196 -108.941108)
		(end 168.80713 -107.056174)
		(width 0.11684)
		(layer "In2.Cu")
		(net "FM_BOARD_BMC_SKU_ID0")
	)
	(segment
		(start 176.781968 -108.080302)
		(end 177.70221 -108.080302)
		(width 0.11684)
		(layer "In2.Cu")
		(net "FM_BOARD_BMC_SKU_ID0")
	)
	(segment
		(start 175.75784 -107.056174)
		(end 176.781968 -108.080302)
		(width 0.11684)
		(layer "In2.Cu")
		(net "FM_BOARD_BMC_SKU_ID0")
	)
	(segment
		(start 384.358896 -217.075258)
		(end 384.358896 -220.87459)
		(width 0.10668)
		(layer "F.Cu")
		(net "FAB_REV_ID2")
	)
	(segment
		(start 382.502664 -215.219026)
		(end 384.358896 -217.075258)
		(width 0.10668)
		(layer "F.Cu")
		(net "FAB_REV_ID2")
	)
	(segment
		(start 383.163318 -222.070168)
		(end 382.748028 -222.070168)
		(width 0.10668)
		(layer "F.Cu")
		(net "FAB_REV_ID2")
	)
	(segment
		(start 384.358896 -220.87459)
		(end 383.163318 -222.070168)
		(width 0.10668)
		(layer "F.Cu")
		(net "FAB_REV_ID2")
	)
	(segment
		(start 382.274064 -207.545178)
		(end 382.502664 -207.773778)
		(width 0.10668)
		(layer "F.Cu")
		(net "FAB_REV_ID2")
	)
	(segment
		(start 382.502664 -207.773778)
		(end 382.502664 -215.219026)
		(width 0.10668)
		(layer "F.Cu")
		(net "FAB_REV_ID2")
	)
	(via
		(at 393.291822 -202.715622)
		(size 0.6604)
		(drill 0.3302)
		(layers "F.Cu" "B.Cu")
		(net "FAB_REV_ID2")
	)
	(via
		(at 393.080494 -205.046326)
		(size 0.508)
		(drill 0.254)
		(layers "F.Cu" "B.Cu")
		(net "FAB_REV_ID2")
	)
	(via
		(at 382.274064 -207.545178)
		(size 0.508)
		(drill 0.254)
		(layers "F.Cu" "B.Cu")
		(net "FAB_REV_ID2")
	)
	(segment
		(start 392.981434 -203.02601)
		(end 393.291822 -202.715622)
		(width 0.10668)
		(layer "B.Cu")
		(net "FAB_REV_ID2")
	)
	(segment
		(start 392.981434 -204.249782)
		(end 392.981434 -203.02601)
		(width 0.10668)
		(layer "B.Cu")
		(net "FAB_REV_ID2")
	)
	(segment
		(start 393.291822 -202.715622)
		(end 393.809728 -202.197716)
		(width 0.10668)
		(layer "B.Cu")
		(net "FAB_REV_ID2")
	)
	(segment
		(start 393.809728 -202.197716)
		(end 393.809728 -201.142854)
		(width 0.10668)
		(layer "B.Cu")
		(net "FAB_REV_ID2")
	)
	(segment
		(start 392.981434 -204.249782)
		(end 392.981434 -204.947266)
		(width 0.10668)
		(layer "B.Cu")
		(net "FAB_REV_ID2")
	)
	(segment
		(start 392.981434 -204.947266)
		(end 393.080494 -205.046326)
		(width 0.10668)
		(layer "B.Cu")
		(net "FAB_REV_ID2")
	)
	(segment
		(start 392.05408 -206.202026)
		(end 386.602986 -206.202026)
		(width 0.11684)
		(layer "In2.Cu")
		(net "FAB_REV_ID2")
	)
	(segment
		(start 386.602986 -206.202026)
		(end 385.2545 -207.550512)
		(width 0.11684)
		(layer "In2.Cu")
		(net "FAB_REV_ID2")
	)
	(segment
		(start 393.080494 -205.046326)
		(end 393.080494 -205.175612)
		(width 0.11684)
		(layer "In2.Cu")
		(net "FAB_REV_ID2")
	)
	(segment
		(start 385.2545 -207.550512)
		(end 382.279398 -207.550512)
		(width 0.11684)
		(layer "In2.Cu")
		(net "FAB_REV_ID2")
	)
	(segment
		(start 382.279398 -207.550512)
		(end 382.274064 -207.545178)
		(width 0.11684)
		(layer "In2.Cu")
		(net "FAB_REV_ID2")
	)
	(segment
		(start 393.080494 -205.175612)
		(end 392.05408 -206.202026)
		(width 0.11684)
		(layer "In2.Cu")
		(net "FAB_REV_ID2")
	)
	(segment
		(start 381.807974 -223.69018)
		(end 382.274826 -223.424242)
		(width 0.10668)
		(layer "F.Cu")
		(net "FAB_REV_ID1")
	)
	(via
		(at 382.274826 -223.424242)
		(size 0.4064)
		(drill 0.2032)
		(layers "F.Cu" "B.Cu")
		(net "FAB_REV_ID1")
	)
	(via
		(at 395.315694 -205.046326)
		(size 0.508)
		(drill 0.254)
		(layers "F.Cu" "B.Cu")
		(net "FAB_REV_ID1")
	)
	(via
		(at 396.248382 -202.290934)
		(size 0.6604)
		(drill 0.3302)
		(layers "F.Cu" "B.Cu")
		(net "FAB_REV_ID1")
	)
	(segment
		(start 396.796514 -204.059282)
		(end 396.575788 -204.280008)
		(width 0.10668)
		(layer "B.Cu")
		(net "FAB_REV_ID1")
	)
	(segment
		(start 396.248382 -202.290934)
		(end 396.248382 -202.43419)
		(width 0.10668)
		(layer "B.Cu")
		(net "FAB_REV_ID1")
	)
	(segment
		(start 396.248382 -202.43419)
		(end 396.796514 -202.982322)
		(width 0.10668)
		(layer "B.Cu")
		(net "FAB_REV_ID1")
	)
	(segment
		(start 396.796514 -202.982322)
		(end 396.796514 -204.059282)
		(width 0.10668)
		(layer "B.Cu")
		(net "FAB_REV_ID1")
	)
	(segment
		(start 396.218918 -204.280008)
		(end 396.082012 -204.280008)
		(width 0.10668)
		(layer "B.Cu")
		(net "FAB_REV_ID1")
	)
	(segment
		(start 396.142972 -201.155046)
		(end 396.248382 -201.260456)
		(width 0.10668)
		(layer "B.Cu")
		(net "FAB_REV_ID1")
	)
	(segment
		(start 396.575788 -204.280008)
		(end 396.218918 -204.280008)
		(width 0.10668)
		(layer "B.Cu")
		(net "FAB_REV_ID1")
	)
	(segment
		(start 396.082012 -204.280008)
		(end 395.315694 -205.046326)
		(width 0.10668)
		(layer "B.Cu")
		(net "FAB_REV_ID1")
	)
	(segment
		(start 396.248382 -201.260456)
		(end 396.248382 -202.290934)
		(width 0.10668)
		(layer "B.Cu")
		(net "FAB_REV_ID1")
	)
	(segment
		(start 382.46939 -223.424242)
		(end 382.274826 -223.424242)
		(width 0.11684)
		(layer "In2.Cu")
		(net "FAB_REV_ID1")
	)
	(segment
		(start 383.184146 -212.885274)
		(end 383.184146 -222.709486)
		(width 0.11684)
		(layer "In2.Cu")
		(net "FAB_REV_ID1")
	)
	(segment
		(start 395.315694 -205.046326)
		(end 395.315694 -206.09941)
		(width 0.11684)
		(layer "In2.Cu")
		(net "FAB_REV_ID1")
	)
	(segment
		(start 395.315694 -206.09941)
		(end 393.528804 -207.8863)
		(width 0.11684)
		(layer "In2.Cu")
		(net "FAB_REV_ID1")
	)
	(segment
		(start 393.528804 -207.8863)
		(end 388.18312 -207.8863)
		(width 0.11684)
		(layer "In2.Cu")
		(net "FAB_REV_ID1")
	)
	(segment
		(start 383.184146 -222.709486)
		(end 382.46939 -223.424242)
		(width 0.11684)
		(layer "In2.Cu")
		(net "FAB_REV_ID1")
	)
	(segment
		(start 388.18312 -207.8863)
		(end 383.184146 -212.885274)
		(width 0.11684)
		(layer "In2.Cu")
		(net "FAB_REV_ID1")
	)
	(segment
		(start 383.52095 -217.513408)
		(end 381.18542 -215.177878)
		(width 0.10668)
		(layer "F.Cu")
		(net "FAB_REV_ID0")
	)
	(segment
		(start 383.52095 -220.417644)
		(end 383.52095 -217.513408)
		(width 0.10668)
		(layer "F.Cu")
		(net "FAB_REV_ID0")
	)
	(segment
		(start 381.18542 -210.718908)
		(end 381.390144 -210.514184)
		(width 0.10668)
		(layer "F.Cu")
		(net "FAB_REV_ID0")
	)
	(segment
		(start 381.807974 -221.860872)
		(end 382.288542 -221.380304)
		(width 0.10668)
		(layer "F.Cu")
		(net "FAB_REV_ID0")
	)
	(segment
		(start 381.18542 -215.177878)
		(end 381.18542 -210.718908)
		(width 0.10668)
		(layer "F.Cu")
		(net "FAB_REV_ID0")
	)
	(segment
		(start 381.807974 -222.070168)
		(end 381.807974 -221.860872)
		(width 0.10668)
		(layer "F.Cu")
		(net "FAB_REV_ID0")
	)
	(segment
		(start 381.390144 -210.514184)
		(end 381.415544 -210.514184)
		(width 0.10668)
		(layer "F.Cu")
		(net "FAB_REV_ID0")
	)
	(segment
		(start 382.55829 -221.380304)
		(end 383.52095 -220.417644)
		(width 0.10668)
		(layer "F.Cu")
		(net "FAB_REV_ID0")
	)
	(segment
		(start 382.288542 -221.380304)
		(end 382.55829 -221.380304)
		(width 0.10668)
		(layer "F.Cu")
		(net "FAB_REV_ID0")
	)
	(via
		(at 394.625576 -202.322176)
		(size 0.6604)
		(drill 0.3302)
		(layers "F.Cu" "B.Cu")
		(net "FAB_REV_ID0")
	)
	(via
		(at 394.198094 -205.046326)
		(size 0.508)
		(drill 0.254)
		(layers "F.Cu" "B.Cu")
		(net "FAB_REV_ID0")
	)
	(via
		(at 381.415544 -210.514184)
		(size 0.508)
		(drill 0.254)
		(layers "F.Cu" "B.Cu")
		(net "FAB_REV_ID0")
	)
	(segment
		(start 394.625576 -203.76388)
		(end 395.144244 -204.282548)
		(width 0.10668)
		(layer "B.Cu")
		(net "FAB_REV_ID0")
	)
	(segment
		(start 394.625576 -201.661268)
		(end 394.625576 -202.322176)
		(width 0.10668)
		(layer "B.Cu")
		(net "FAB_REV_ID0")
	)
	(segment
		(start 394.198094 -205.046326)
		(end 394.530072 -205.046326)
		(width 0.10668)
		(layer "B.Cu")
		(net "FAB_REV_ID0")
	)
	(segment
		(start 394.625576 -202.322176)
		(end 394.625576 -203.76388)
		(width 0.10668)
		(layer "B.Cu")
		(net "FAB_REV_ID0")
	)
	(segment
		(start 394.530072 -205.046326)
		(end 395.252194 -204.324204)
		(width 0.10668)
		(layer "B.Cu")
		(net "FAB_REV_ID0")
	)
	(segment
		(start 395.144244 -204.282548)
		(end 395.252194 -204.282548)
		(width 0.10668)
		(layer "B.Cu")
		(net "FAB_REV_ID0")
	)
	(segment
		(start 395.252194 -204.324204)
		(end 395.252194 -204.282548)
		(width 0.10668)
		(layer "B.Cu")
		(net "FAB_REV_ID0")
	)
	(segment
		(start 395.123162 -201.163682)
		(end 394.625576 -201.661268)
		(width 0.10668)
		(layer "B.Cu")
		(net "FAB_REV_ID0")
	)
	(segment
		(start 387.739382 -206.779876)
		(end 383.886964 -210.632294)
		(width 0.11684)
		(layer "In2.Cu")
		(net "FAB_REV_ID0")
	)
	(segment
		(start 394.198094 -205.907132)
		(end 393.32535 -206.779876)
		(width 0.11684)
		(layer "In2.Cu")
		(net "FAB_REV_ID0")
	)
	(segment
		(start 394.198094 -205.046326)
		(end 394.198094 -205.907132)
		(width 0.11684)
		(layer "In2.Cu")
		(net "FAB_REV_ID0")
	)
	(segment
		(start 393.32535 -206.779876)
		(end 387.739382 -206.779876)
		(width 0.11684)
		(layer "In2.Cu")
		(net "FAB_REV_ID0")
	)
	(segment
		(start 381.532384 -210.632294)
		(end 381.415544 -210.515454)
		(width 0.11684)
		(layer "In2.Cu")
		(net "FAB_REV_ID0")
	)
	(segment
		(start 381.415544 -210.515454)
		(end 381.415544 -210.514184)
		(width 0.11684)
		(layer "In2.Cu")
		(net "FAB_REV_ID0")
	)
	(segment
		(start 383.886964 -210.632294)
		(end 381.532384 -210.632294)
		(width 0.11684)
		(layer "In2.Cu")
		(net "FAB_REV_ID0")
	)
	(segment
		(start 180.700426 -93.064584)
		(end 180.710332 -93.07449)
		(width 0.10668)
		(layer "F.Cu")
		(net "FAB_BMC_REV_ID2")
	)
	(segment
		(start 179.71643 -93.064584)
		(end 179.71643 -93.679518)
		(width 0.10668)
		(layer "F.Cu")
		(net "FAB_BMC_REV_ID2")
	)
	(segment
		(start 179.71643 -93.679518)
		(end 179.705 -93.690948)
		(width 0.10668)
		(layer "F.Cu")
		(net "FAB_BMC_REV_ID2")
	)
	(segment
		(start 179.71643 -93.064584)
		(end 180.700426 -93.064584)
		(width 0.10668)
		(layer "F.Cu")
		(net "FAB_BMC_REV_ID2")
	)
	(segment
		(start 184.322212 -110.652814)
		(end 183.932322 -110.262924)
		(width 0.10668)
		(layer "F.Cu")
		(net "FAB_BMC_REV_ID2")
	)
	(via
		(at 179.705 -93.690948)
		(size 0.508)
		(drill 0.254)
		(layers "F.Cu" "B.Cu")
		(net "FAB_BMC_REV_ID2")
	)
	(via
		(at 183.932322 -110.262924)
		(size 0.4572)
		(drill 0.254)
		(layers "F.Cu" "B.Cu")
		(net "FAB_BMC_REV_ID2")
	)
	(segment
		(start 183.52516 -109.966506)
		(end 183.52516 -108.379006)
		(width 0.11684)
		(layer "In11.Cu")
		(net "FAB_BMC_REV_ID2")
	)
	(segment
		(start 183.52516 -108.379006)
		(end 183.40832 -108.262166)
		(width 0.11684)
		(layer "In11.Cu")
		(net "FAB_BMC_REV_ID2")
	)
	(segment
		(start 179.247038 -94.14891)
		(end 179.705 -93.690948)
		(width 0.11684)
		(layer "In11.Cu")
		(net "FAB_BMC_REV_ID2")
	)
	(segment
		(start 183.40832 -108.262166)
		(end 182.844694 -108.262166)
		(width 0.11684)
		(layer "In11.Cu")
		(net "FAB_BMC_REV_ID2")
	)
	(segment
		(start 179.604416 -101.181408)
		(end 179.247038 -100.82403)
		(width 0.11684)
		(layer "In11.Cu")
		(net "FAB_BMC_REV_ID2")
	)
	(segment
		(start 179.451508 -102.387908)
		(end 179.604416 -102.235)
		(width 0.11684)
		(layer "In11.Cu")
		(net "FAB_BMC_REV_ID2")
	)
	(segment
		(start 183.932322 -110.262924)
		(end 183.821578 -110.262924)
		(width 0.11684)
		(layer "In11.Cu")
		(net "FAB_BMC_REV_ID2")
	)
	(segment
		(start 179.604416 -102.235)
		(end 179.604416 -101.181408)
		(width 0.11684)
		(layer "In11.Cu")
		(net "FAB_BMC_REV_ID2")
	)
	(segment
		(start 179.451508 -104.755188)
		(end 179.451508 -102.387908)
		(width 0.11684)
		(layer "In11.Cu")
		(net "FAB_BMC_REV_ID2")
	)
	(segment
		(start 182.72252 -108.139992)
		(end 182.72252 -107.614974)
		(width 0.11684)
		(layer "In11.Cu")
		(net "FAB_BMC_REV_ID2")
	)
	(segment
		(start 182.72252 -107.614974)
		(end 182.572914 -107.465368)
		(width 0.11684)
		(layer "In11.Cu")
		(net "FAB_BMC_REV_ID2")
	)
	(segment
		(start 182.572914 -107.465368)
		(end 182.161688 -107.465368)
		(width 0.11684)
		(layer "In11.Cu")
		(net "FAB_BMC_REV_ID2")
	)
	(segment
		(start 182.844694 -108.262166)
		(end 182.72252 -108.139992)
		(width 0.11684)
		(layer "In11.Cu")
		(net "FAB_BMC_REV_ID2")
	)
	(segment
		(start 182.161688 -107.465368)
		(end 179.451508 -104.755188)
		(width 0.11684)
		(layer "In11.Cu")
		(net "FAB_BMC_REV_ID2")
	)
	(segment
		(start 179.247038 -100.82403)
		(end 179.247038 -94.14891)
		(width 0.11684)
		(layer "In11.Cu")
		(net "FAB_BMC_REV_ID2")
	)
	(segment
		(start 183.821578 -110.262924)
		(end 183.52516 -109.966506)
		(width 0.11684)
		(layer "In11.Cu")
		(net "FAB_BMC_REV_ID2")
	)
	(segment
		(start 184.322212 -111.452914)
		(end 183.932322 -111.063024)
		(width 0.10668)
		(layer "F.Cu")
		(net "FAB_BMC_REV_ID1")
	)
	(via
		(at 176.020984 -106.262932)
		(size 0.508)
		(drill 0.254)
		(layers "F.Cu" "B.Cu")
		(net "FAB_BMC_REV_ID1")
	)
	(via
		(at 183.932322 -111.063024)
		(size 0.4572)
		(drill 0.254)
		(layers "F.Cu" "B.Cu")
		(net "FAB_BMC_REV_ID1")
	)
	(segment
		(start 173.248828 -104.357424)
		(end 174.115476 -104.357424)
		(width 0.10668)
		(layer "B.Cu")
		(net "FAB_BMC_REV_ID1")
	)
	(segment
		(start 170.802046 -103.942388)
		(end 171.356782 -104.497124)
		(width 0.10668)
		(layer "B.Cu")
		(net "FAB_BMC_REV_ID1")
	)
	(segment
		(start 171.356782 -104.497124)
		(end 173.109128 -104.497124)
		(width 0.10668)
		(layer "B.Cu")
		(net "FAB_BMC_REV_ID1")
	)
	(segment
		(start 170.801284 -103.942388)
		(end 170.802046 -103.942388)
		(width 0.10668)
		(layer "B.Cu")
		(net "FAB_BMC_REV_ID1")
	)
	(segment
		(start 174.115476 -104.357424)
		(end 176.020984 -106.262932)
		(width 0.10668)
		(layer "B.Cu")
		(net "FAB_BMC_REV_ID1")
	)
	(segment
		(start 171.595542 -103.01351)
		(end 170.801284 -103.807768)
		(width 0.10668)
		(layer "B.Cu")
		(net "FAB_BMC_REV_ID1")
	)
	(segment
		(start 171.595542 -102.780084)
		(end 171.595542 -103.01351)
		(width 0.10668)
		(layer "B.Cu")
		(net "FAB_BMC_REV_ID1")
	)
	(segment
		(start 170.801284 -103.807768)
		(end 170.801284 -103.942388)
		(width 0.10668)
		(layer "B.Cu")
		(net "FAB_BMC_REV_ID1")
	)
	(segment
		(start 173.109128 -104.497124)
		(end 173.248828 -104.357424)
		(width 0.10668)
		(layer "B.Cu")
		(net "FAB_BMC_REV_ID1")
	)
	(segment
		(start 177.469038 -107.634786)
		(end 177.9397 -107.634786)
		(width 0.11684)
		(layer "In2.Cu")
		(net "FAB_BMC_REV_ID1")
	)
	(segment
		(start 180.32095 -110.101888)
		(end 180.32095 -110.50016)
		(width 0.11684)
		(layer "In2.Cu")
		(net "FAB_BMC_REV_ID1")
	)
	(segment
		(start 180.32095 -110.50016)
		(end 180.472334 -110.651544)
		(width 0.11684)
		(layer "In2.Cu")
		(net "FAB_BMC_REV_ID1")
	)
	(segment
		(start 178.742848 -108.438188)
		(end 178.742848 -108.896658)
		(width 0.11684)
		(layer "In2.Cu")
		(net "FAB_BMC_REV_ID1")
	)
	(segment
		(start 180.093366 -109.874304)
		(end 180.32095 -110.101888)
		(width 0.11684)
		(layer "In2.Cu")
		(net "FAB_BMC_REV_ID1")
	)
	(segment
		(start 179.54371 -109.324902)
		(end 179.54371 -109.624114)
		(width 0.11684)
		(layer "In2.Cu")
		(net "FAB_BMC_REV_ID1")
	)
	(segment
		(start 179.54371 -109.624114)
		(end 179.7939 -109.874304)
		(width 0.11684)
		(layer "In2.Cu")
		(net "FAB_BMC_REV_ID1")
	)
	(segment
		(start 179.7939 -109.874304)
		(end 180.093366 -109.874304)
		(width 0.11684)
		(layer "In2.Cu")
		(net "FAB_BMC_REV_ID1")
	)
	(segment
		(start 183.521096 -111.47425)
		(end 183.932322 -111.063024)
		(width 0.11684)
		(layer "In2.Cu")
		(net "FAB_BMC_REV_ID1")
	)
	(segment
		(start 179.293266 -109.074458)
		(end 179.54371 -109.324902)
		(width 0.11684)
		(layer "In2.Cu")
		(net "FAB_BMC_REV_ID1")
	)
	(segment
		(start 181.393846 -111.47425)
		(end 183.521096 -111.47425)
		(width 0.11684)
		(layer "In2.Cu")
		(net "FAB_BMC_REV_ID1")
	)
	(segment
		(start 181.140608 -111.221012)
		(end 181.393846 -111.47425)
		(width 0.11684)
		(layer "In2.Cu")
		(net "FAB_BMC_REV_ID1")
	)
	(segment
		(start 178.742848 -108.896658)
		(end 178.920648 -109.074458)
		(width 0.11684)
		(layer "In2.Cu")
		(net "FAB_BMC_REV_ID1")
	)
	(segment
		(start 180.472334 -110.651544)
		(end 180.884576 -110.651544)
		(width 0.11684)
		(layer "In2.Cu")
		(net "FAB_BMC_REV_ID1")
	)
	(segment
		(start 180.884576 -110.651544)
		(end 181.140608 -110.907576)
		(width 0.11684)
		(layer "In2.Cu")
		(net "FAB_BMC_REV_ID1")
	)
	(segment
		(start 176.020984 -106.262932)
		(end 176.097184 -106.262932)
		(width 0.11684)
		(layer "In2.Cu")
		(net "FAB_BMC_REV_ID1")
	)
	(segment
		(start 181.140608 -110.907576)
		(end 181.140608 -111.221012)
		(width 0.11684)
		(layer "In2.Cu")
		(net "FAB_BMC_REV_ID1")
	)
	(segment
		(start 178.920648 -109.074458)
		(end 179.293266 -109.074458)
		(width 0.11684)
		(layer "In2.Cu")
		(net "FAB_BMC_REV_ID1")
	)
	(segment
		(start 176.097184 -106.262932)
		(end 177.469038 -107.634786)
		(width 0.11684)
		(layer "In2.Cu")
		(net "FAB_BMC_REV_ID1")
	)
	(segment
		(start 177.9397 -107.634786)
		(end 178.742848 -108.438188)
		(width 0.11684)
		(layer "In2.Cu")
		(net "FAB_BMC_REV_ID1")
	)
	(segment
		(start 181.71033 -93.664278)
		(end 181.737 -93.690948)
		(width 0.10668)
		(layer "F.Cu")
		(net "FAB_BMC_REV_ID0")
	)
	(segment
		(start 182.708296 -93.072458)
		(end 182.710836 -93.074998)
		(width 0.10668)
		(layer "F.Cu")
		(net "FAB_BMC_REV_ID0")
	)
	(segment
		(start 181.71033 -93.072458)
		(end 182.708296 -93.072458)
		(width 0.10668)
		(layer "F.Cu")
		(net "FAB_BMC_REV_ID0")
	)
	(segment
		(start 183.522112 -106.652822)
		(end 183.132222 -106.262932)
		(width 0.10668)
		(layer "F.Cu")
		(net "FAB_BMC_REV_ID0")
	)
	(segment
		(start 181.71033 -93.072458)
		(end 181.71033 -93.664278)
		(width 0.10668)
		(layer "F.Cu")
		(net "FAB_BMC_REV_ID0")
	)
	(via
		(at 181.737 -93.690948)
		(size 0.508)
		(drill 0.254)
		(layers "F.Cu" "B.Cu")
		(net "FAB_BMC_REV_ID0")
	)
	(via
		(at 183.132222 -106.262932)
		(size 0.4572)
		(drill 0.254)
		(layers "F.Cu" "B.Cu")
		(net "FAB_BMC_REV_ID0")
	)
	(segment
		(start 183.132222 -103.960422)
		(end 183.132222 -106.262932)
		(width 0.11684)
		(layer "In11.Cu")
		(net "FAB_BMC_REV_ID0")
	)
	(segment
		(start 181.737 -94.260162)
		(end 182.218838 -94.742)
		(width 0.11684)
		(layer "In11.Cu")
		(net "FAB_BMC_REV_ID0")
	)
	(segment
		(start 182.218838 -103.047038)
		(end 183.132222 -103.960422)
		(width 0.11684)
		(layer "In11.Cu")
		(net "FAB_BMC_REV_ID0")
	)
	(segment
		(start 181.737 -93.690948)
		(end 181.737 -94.260162)
		(width 0.11684)
		(layer "In11.Cu")
		(net "FAB_BMC_REV_ID0")
	)
	(segment
		(start 182.218838 -94.742)
		(end 182.218838 -103.047038)
		(width 0.11684)
		(layer "In11.Cu")
		(net "FAB_BMC_REV_ID0")
	)
	(segment
		(start 117.247924 -292.450266)
		(end 117.714776 -292.716204)
		(width 0.10668)
		(layer "F.Cu")
		(net "TP_SLOT2_BUF_SKU_ID1")
	)
	(via
		(at 160.777682 -329.475592)
		(size 0.6604)
		(drill 0.3302)
		(layers "F.Cu" "B.Cu")
		(net "TP_SLOT2_BUF_SKU_ID1")
	)
	(via
		(at 117.714776 -292.716204)
		(size 0.4064)
		(drill 0.2032)
		(layers "F.Cu" "B.Cu")
		(net "TP_SLOT2_BUF_SKU_ID1")
	)
	(segment
		(start 154.596592 -326.473312)
		(end 156.072332 -326.473312)
		(width 0.10668)
		(layer "B.Cu")
		(net "TP_SLOT2_BUF_SKU_ID1")
	)
	(segment
		(start 142.736316 -323.581268)
		(end 149.704806 -323.581268)
		(width 0.10668)
		(layer "B.Cu")
		(net "TP_SLOT2_BUF_SKU_ID1")
	)
	(segment
		(start 118.242334 -295.868852)
		(end 118.242334 -299.087286)
		(width 0.10668)
		(layer "B.Cu")
		(net "TP_SLOT2_BUF_SKU_ID1")
	)
	(segment
		(start 117.714776 -293.705534)
		(end 118.130574 -294.121332)
		(width 0.10668)
		(layer "B.Cu")
		(net "TP_SLOT2_BUF_SKU_ID1")
	)
	(segment
		(start 118.130574 -294.499792)
		(end 117.706394 -294.923972)
		(width 0.10668)
		(layer "B.Cu")
		(net "TP_SLOT2_BUF_SKU_ID1")
	)
	(segment
		(start 117.706394 -294.923972)
		(end 117.706394 -295.332912)
		(width 0.10668)
		(layer "B.Cu")
		(net "TP_SLOT2_BUF_SKU_ID1")
	)
	(segment
		(start 152.660096 -324.536816)
		(end 154.596592 -326.473312)
		(width 0.10668)
		(layer "B.Cu")
		(net "TP_SLOT2_BUF_SKU_ID1")
	)
	(segment
		(start 118.242334 -299.087286)
		(end 142.736316 -323.581268)
		(width 0.10668)
		(layer "B.Cu")
		(net "TP_SLOT2_BUF_SKU_ID1")
	)
	(segment
		(start 159.074612 -329.475592)
		(end 160.777682 -329.475592)
		(width 0.10668)
		(layer "B.Cu")
		(net "TP_SLOT2_BUF_SKU_ID1")
	)
	(segment
		(start 117.706394 -295.332912)
		(end 118.242334 -295.868852)
		(width 0.10668)
		(layer "B.Cu")
		(net "TP_SLOT2_BUF_SKU_ID1")
	)
	(segment
		(start 117.714776 -292.716204)
		(end 117.714776 -293.705534)
		(width 0.10668)
		(layer "B.Cu")
		(net "TP_SLOT2_BUF_SKU_ID1")
	)
	(segment
		(start 149.704806 -323.581268)
		(end 150.660354 -324.536816)
		(width 0.10668)
		(layer "B.Cu")
		(net "TP_SLOT2_BUF_SKU_ID1")
	)
	(segment
		(start 118.130574 -294.121332)
		(end 118.130574 -294.499792)
		(width 0.10668)
		(layer "B.Cu")
		(net "TP_SLOT2_BUF_SKU_ID1")
	)
	(segment
		(start 150.660354 -324.536816)
		(end 152.660096 -324.536816)
		(width 0.10668)
		(layer "B.Cu")
		(net "TP_SLOT2_BUF_SKU_ID1")
	)
	(segment
		(start 156.072332 -326.473312)
		(end 159.074612 -329.475592)
		(width 0.10668)
		(layer "B.Cu")
		(net "TP_SLOT2_BUF_SKU_ID1")
	)
	(segment
		(start 116.77777 -293.260272)
		(end 117.244622 -293.52621)
		(width 0.10668)
		(layer "F.Cu")
		(net "TP_SLOT2_BUF_SKU_ID0")
	)
	(via
		(at 117.244622 -293.52621)
		(size 0.4064)
		(drill 0.2032)
		(layers "F.Cu" "B.Cu")
		(net "TP_SLOT2_BUF_SKU_ID0")
	)
	(via
		(at 159.032448 -330.68768)
		(size 0.6604)
		(drill 0.3302)
		(layers "F.Cu" "B.Cu")
		(net "TP_SLOT2_BUF_SKU_ID0")
	)
	(segment
		(start 117.244622 -293.52621)
		(end 117.244622 -294.48506)
		(width 0.10668)
		(layer "B.Cu")
		(net "TP_SLOT2_BUF_SKU_ID0")
	)
	(segment
		(start 154.373072 -326.818752)
		(end 155.16352 -326.818752)
		(width 0.10668)
		(layer "B.Cu")
		(net "TP_SLOT2_BUF_SKU_ID0")
	)
	(segment
		(start 152.40381 -324.84949)
		(end 154.373072 -326.818752)
		(width 0.10668)
		(layer "B.Cu")
		(net "TP_SLOT2_BUF_SKU_ID0")
	)
	(segment
		(start 149.646132 -324.053708)
		(end 150.441914 -324.84949)
		(width 0.10668)
		(layer "B.Cu")
		(net "TP_SLOT2_BUF_SKU_ID0")
	)
	(segment
		(start 116.819934 -294.909748)
		(end 116.819934 -295.381172)
		(width 0.10668)
		(layer "B.Cu")
		(net "TP_SLOT2_BUF_SKU_ID0")
	)
	(segment
		(start 150.441914 -324.84949)
		(end 152.40381 -324.84949)
		(width 0.10668)
		(layer "B.Cu")
		(net "TP_SLOT2_BUF_SKU_ID0")
	)
	(segment
		(start 116.819934 -295.381172)
		(end 117.274594 -295.835832)
		(width 0.10668)
		(layer "B.Cu")
		(net "TP_SLOT2_BUF_SKU_ID0")
	)
	(segment
		(start 117.274594 -298.730924)
		(end 142.597378 -324.053708)
		(width 0.10668)
		(layer "B.Cu")
		(net "TP_SLOT2_BUF_SKU_ID0")
	)
	(segment
		(start 142.597378 -324.053708)
		(end 149.646132 -324.053708)
		(width 0.10668)
		(layer "B.Cu")
		(net "TP_SLOT2_BUF_SKU_ID0")
	)
	(segment
		(start 117.244622 -294.48506)
		(end 116.819934 -294.909748)
		(width 0.10668)
		(layer "B.Cu")
		(net "TP_SLOT2_BUF_SKU_ID0")
	)
	(segment
		(start 155.16352 -326.818752)
		(end 159.032448 -330.68768)
		(width 0.10668)
		(layer "B.Cu")
		(net "TP_SLOT2_BUF_SKU_ID0")
	)
	(segment
		(start 117.274594 -295.835832)
		(end 117.274594 -298.730924)
		(width 0.10668)
		(layer "B.Cu")
		(net "TP_SLOT2_BUF_SKU_ID0")
	)
	(segment
		(start 174.58563 -12.04976)
		(end 174.58563 -11.92276)
		(width 0.10668)
		(layer "F.Cu")
		(net "SMB_CPU0_CPU1_SEC_SDA_R")
	)
	(segment
		(start 174.66691 -12.13104)
		(end 174.58563 -12.04976)
		(width 0.10668)
		(layer "F.Cu")
		(net "SMB_CPU0_CPU1_SEC_SDA_R")
	)
	(segment
		(start 174.66691 -13.599922)
		(end 174.66691 -12.13104)
		(width 0.10668)
		(layer "F.Cu")
		(net "SMB_CPU0_CPU1_SEC_SDA_R")
	)
	(via
		(at 174.58563 -11.92276)
		(size 0.508)
		(drill 0.254)
		(layers "F.Cu" "B.Cu")
		(net "SMB_CPU0_CPU1_SEC_SDA_R")
	)
	(segment
		(start 175.583088 -13.362178)
		(end 174.58563 -12.36472)
		(width 0.10668)
		(layer "B.Cu")
		(net "SMB_CPU0_CPU1_SEC_SDA_R")
	)
	(segment
		(start 176.3776 -13.362178)
		(end 175.583088 -13.362178)
		(width 0.10668)
		(layer "B.Cu")
		(net "SMB_CPU0_CPU1_SEC_SDA_R")
	)
	(segment
		(start 174.58563 -12.36472)
		(end 174.58563 -11.92276)
		(width 0.10668)
		(layer "B.Cu")
		(net "SMB_CPU0_CPU1_SEC_SDA_R")
	)
	(segment
		(start 175.267112 -10.170922)
		(end 174.71009 -9.6139)
		(width 0.10668)
		(layer "F.Cu")
		(net "SMB_CPU0_CPU1_SEC_SCL_R")
	)
	(segment
		(start 175.267112 -13.599922)
		(end 175.267112 -10.170922)
		(width 0.10668)
		(layer "F.Cu")
		(net "SMB_CPU0_CPU1_SEC_SCL_R")
	)
	(via
		(at 174.71009 -9.6139)
		(size 0.508)
		(drill 0.254)
		(layers "F.Cu" "B.Cu")
		(net "SMB_CPU0_CPU1_SEC_SCL_R")
	)
	(segment
		(start 176.769776 -12.688316)
		(end 177.443638 -13.362178)
		(width 0.10668)
		(layer "B.Cu")
		(net "SMB_CPU0_CPU1_SEC_SCL_R")
	)
	(segment
		(start 174.71009 -9.6139)
		(end 175.288194 -10.192004)
		(width 0.10668)
		(layer "B.Cu")
		(net "SMB_CPU0_CPU1_SEC_SCL_R")
	)
	(segment
		(start 175.288194 -10.192004)
		(end 175.288194 -12.194794)
		(width 0.10668)
		(layer "B.Cu")
		(net "SMB_CPU0_CPU1_SEC_SCL_R")
	)
	(segment
		(start 175.288194 -12.194794)
		(end 175.781716 -12.688316)
		(width 0.10668)
		(layer "B.Cu")
		(net "SMB_CPU0_CPU1_SEC_SCL_R")
	)
	(segment
		(start 175.781716 -12.688316)
		(end 176.769776 -12.688316)
		(width 0.10668)
		(layer "B.Cu")
		(net "SMB_CPU0_CPU1_SEC_SCL_R")
	)
	(segment
		(start 208.492344 -107.467146)
		(end 208.492344 -106.515408)
		(width 0.10668)
		(layer "F.Cu")
		(net "PWRGD_P5V_AUX_R3")
	)
	(segment
		(start 189.92215 -109.052868)
		(end 190.31204 -108.662978)
		(width 0.10668)
		(layer "F.Cu")
		(net "PWRGD_P5V_AUX_R3")
	)
	(segment
		(start 208.492344 -106.515408)
		(end 208.494376 -106.513376)
		(width 0.10668)
		(layer "F.Cu")
		(net "PWRGD_P5V_AUX_R3")
	)
	(segment
		(start 208.494376 -106.513376)
		(end 207.644238 -106.513376)
		(width 0.10668)
		(layer "F.Cu")
		(net "PWRGD_P5V_AUX_R3")
	)
	(via
		(at 190.31204 -108.662978)
		(size 0.4572)
		(drill 0.254)
		(layers "F.Cu" "B.Cu")
		(net "PWRGD_P5V_AUX_R3")
	)
	(via
		(at 207.644238 -106.513376)
		(size 0.508)
		(drill 0.254)
		(layers "F.Cu" "B.Cu")
		(net "PWRGD_P5V_AUX_R3")
	)
	(segment
		(start 194.889882 -107.031536)
		(end 195.921884 -105.999534)
		(width 0.11684)
		(layer "In6.Cu")
		(net "PWRGD_P5V_AUX_R3")
	)
	(segment
		(start 190.703962 -107.62361)
		(end 190.855854 -107.471718)
		(width 0.11684)
		(layer "In6.Cu")
		(net "PWRGD_P5V_AUX_R3")
	)
	(segment
		(start 190.703962 -108.271056)
		(end 190.703962 -107.62361)
		(width 0.11684)
		(layer "In6.Cu")
		(net "PWRGD_P5V_AUX_R3")
	)
	(segment
		(start 190.855854 -107.471718)
		(end 192.986406 -107.471718)
		(width 0.11684)
		(layer "In6.Cu")
		(net "PWRGD_P5V_AUX_R3")
	)
	(segment
		(start 203.217272 -107.064302)
		(end 203.768198 -106.513376)
		(width 0.11684)
		(layer "In6.Cu")
		(net "PWRGD_P5V_AUX_R3")
	)
	(segment
		(start 203.768198 -106.513376)
		(end 207.644238 -106.513376)
		(width 0.11684)
		(layer "In6.Cu")
		(net "PWRGD_P5V_AUX_R3")
	)
	(segment
		(start 193.426588 -107.031536)
		(end 194.889882 -107.031536)
		(width 0.11684)
		(layer "In6.Cu")
		(net "PWRGD_P5V_AUX_R3")
	)
	(segment
		(start 190.31204 -108.662978)
		(end 190.703962 -108.271056)
		(width 0.11684)
		(layer "In6.Cu")
		(net "PWRGD_P5V_AUX_R3")
	)
	(segment
		(start 192.986406 -107.471718)
		(end 193.426588 -107.031536)
		(width 0.11684)
		(layer "In6.Cu")
		(net "PWRGD_P5V_AUX_R3")
	)
	(segment
		(start 201.016362 -105.999534)
		(end 202.08113 -107.064302)
		(width 0.11684)
		(layer "In6.Cu")
		(net "PWRGD_P5V_AUX_R3")
	)
	(segment
		(start 195.921884 -105.999534)
		(end 201.016362 -105.999534)
		(width 0.11684)
		(layer "In6.Cu")
		(net "PWRGD_P5V_AUX_R3")
	)
	(segment
		(start 202.08113 -107.064302)
		(end 203.217272 -107.064302)
		(width 0.11684)
		(layer "In6.Cu")
		(net "PWRGD_P5V_AUX_R3")
	)
	(segment
		(start 179.52212 -117.852952)
		(end 179.13223 -118.242842)
		(width 0.10668)
		(layer "F.Cu")
		(net "PRSNT_OCP_V3_2_N")
	)
	(via
		(at 179.13223 -118.242842)
		(size 0.4572)
		(drill 0.254)
		(layers "F.Cu" "B.Cu")
		(net "PRSNT_OCP_V3_2_N")
	)
	(via
		(at 175.342042 -119.020336)
		(size 0.6604)
		(drill 0.3302)
		(layers "F.Cu" "B.Cu")
		(net "PRSNT_OCP_V3_2_N")
	)
	(segment
		(start 173.530514 -120.233948)
		(end 174.47768 -119.286782)
		(width 0.10668)
		(layer "B.Cu")
		(net "PRSNT_OCP_V3_2_N")
	)
	(segment
		(start 175.075596 -119.286782)
		(end 175.342042 -119.020336)
		(width 0.10668)
		(layer "B.Cu")
		(net "PRSNT_OCP_V3_2_N")
	)
	(segment
		(start 176.093882 -119.020336)
		(end 176.475136 -118.639082)
		(width 0.10668)
		(layer "B.Cu")
		(net "PRSNT_OCP_V3_2_N")
	)
	(segment
		(start 176.475136 -118.639082)
		(end 178.550062 -118.639082)
		(width 0.10668)
		(layer "B.Cu")
		(net "PRSNT_OCP_V3_2_N")
	)
	(segment
		(start 178.550062 -118.639082)
		(end 178.946302 -118.242842)
		(width 0.10668)
		(layer "B.Cu")
		(net "PRSNT_OCP_V3_2_N")
	)
	(segment
		(start 171.6024 -120.233948)
		(end 173.530514 -120.233948)
		(width 0.10668)
		(layer "B.Cu")
		(net "PRSNT_OCP_V3_2_N")
	)
	(segment
		(start 174.47768 -119.286782)
		(end 175.075596 -119.286782)
		(width 0.10668)
		(layer "B.Cu")
		(net "PRSNT_OCP_V3_2_N")
	)
	(segment
		(start 178.946302 -118.242842)
		(end 179.13223 -118.242842)
		(width 0.10668)
		(layer "B.Cu")
		(net "PRSNT_OCP_V3_2_N")
	)
	(segment
		(start 175.342042 -119.020336)
		(end 176.093882 -119.020336)
		(width 0.10668)
		(layer "B.Cu")
		(net "PRSNT_OCP_V3_2_N")
	)
	(segment
		(start 208.494376 -116.673376)
		(end 208.286096 -116.465096)
		(width 0.10668)
		(layer "F.Cu")
		(net "FM_GPU_HSC_EN_R")
	)
	(segment
		(start 208.286096 -116.465096)
		(end 207.30718 -116.465096)
		(width 0.10668)
		(layer "F.Cu")
		(net "FM_GPU_HSC_EN_R")
	)
	(segment
		(start 189.12205 -113.85296)
		(end 189.51194 -113.46307)
		(width 0.10668)
		(layer "F.Cu")
		(net "FM_GPU_HSC_EN_R")
	)
	(via
		(at 207.30718 -116.465096)
		(size 0.762)
		(drill 0.254)
		(layers "F.Cu" "B.Cu")
		(net "FM_GPU_HSC_EN_R")
	)
	(via
		(at 189.51194 -113.46307)
		(size 0.4572)
		(drill 0.254)
		(layers "F.Cu" "B.Cu")
		(net "FM_GPU_HSC_EN_R")
	)
	(segment
		(start 189.51194 -113.326418)
		(end 189.51194 -113.46307)
		(width 0.11684)
		(layer "In2.Cu")
		(net "FM_GPU_HSC_EN_R")
	)
	(segment
		(start 207.887062 -115.885214)
		(end 207.887062 -115.512596)
		(width 0.11684)
		(layer "In2.Cu")
		(net "FM_GPU_HSC_EN_R")
	)
	(segment
		(start 194.450462 -113.05159)
		(end 189.786768 -113.05159)
		(width 0.11684)
		(layer "In2.Cu")
		(net "FM_GPU_HSC_EN_R")
	)
	(segment
		(start 207.887062 -115.512596)
		(end 207.567022 -115.192556)
		(width 0.11684)
		(layer "In2.Cu")
		(net "FM_GPU_HSC_EN_R")
	)
	(segment
		(start 201.078338 -115.192556)
		(end 200.034652 -114.14887)
		(width 0.11684)
		(layer "In2.Cu")
		(net "FM_GPU_HSC_EN_R")
	)
	(segment
		(start 207.567022 -115.192556)
		(end 201.078338 -115.192556)
		(width 0.11684)
		(layer "In2.Cu")
		(net "FM_GPU_HSC_EN_R")
	)
	(segment
		(start 189.786768 -113.05159)
		(end 189.51194 -113.326418)
		(width 0.11684)
		(layer "In2.Cu")
		(net "FM_GPU_HSC_EN_R")
	)
	(segment
		(start 200.034652 -114.14887)
		(end 195.547742 -114.14887)
		(width 0.11684)
		(layer "In2.Cu")
		(net "FM_GPU_HSC_EN_R")
	)
	(segment
		(start 207.30718 -116.465096)
		(end 207.887062 -115.885214)
		(width 0.11684)
		(layer "In2.Cu")
		(net "FM_GPU_HSC_EN_R")
	)
	(segment
		(start 195.547742 -114.14887)
		(end 194.450462 -113.05159)
		(width 0.11684)
		(layer "In2.Cu")
		(net "FM_GPU_HSC_EN_R")
	)
	(segment
		(start 50.48504 -436.259986)
		(end 50.48504 -436.877714)
		(width 0.10668)
		(layer "F.Cu")
		(net "RST_PERST_CPU1_SWB_R_N")
	)
	(via
		(at 198.972932 -125.817376)
		(size 0.508)
		(drill 0.254)
		(layers "F.Cu" "B.Cu")
		(net "RST_PERST_CPU1_SWB_R_N")
	)
	(via
		(at 161.691066 -93.203014)
		(size 0.508)
		(drill 0.254)
		(layers "F.Cu" "B.Cu")
		(net "RST_PERST_CPU1_SWB_R_N")
	)
	(via
		(at 37.105844 -433.223162)
		(size 0.508)
		(drill 0.254)
		(layers "F.Cu" "B.Cu")
		(net "RST_PERST_CPU1_SWB_R_N")
	)
	(via
		(at 50.48504 -436.877714)
		(size 0.508)
		(drill 0.254)
		(layers "F.Cu" "B.Cu")
		(net "RST_PERST_CPU1_SWB_R_N")
	)
	(via
		(at 201.016362 -86.934548)
		(size 0.508)
		(drill 0.254)
		(layers "F.Cu" "B.Cu")
		(net "RST_PERST_CPU1_SWB_R_N")
	)
	(via
		(at 110.801404 -120.783604)
		(size 0.508)
		(drill 0.254)
		(layers "F.Cu" "B.Cu")
		(net "RST_PERST_CPU1_SWB_R_N")
	)
	(segment
		(start 46.763432 -434.597302)
		(end 42.949368 -434.597302)
		(width 0.10668)
		(layer "B.Cu")
		(net "RST_PERST_CPU1_SWB_R_N")
	)
	(segment
		(start 48.305974 -436.139844)
		(end 46.763432 -434.597302)
		(width 0.10668)
		(layer "B.Cu")
		(net "RST_PERST_CPU1_SWB_R_N")
	)
	(segment
		(start 42.949368 -434.597302)
		(end 42.50817 -434.156104)
		(width 0.10668)
		(layer "B.Cu")
		(net "RST_PERST_CPU1_SWB_R_N")
	)
	(segment
		(start 49.74717 -436.139844)
		(end 48.305974 -436.139844)
		(width 0.10668)
		(layer "B.Cu")
		(net "RST_PERST_CPU1_SWB_R_N")
	)
	(segment
		(start 50.48504 -436.877714)
		(end 49.74717 -436.139844)
		(width 0.10668)
		(layer "B.Cu")
		(net "RST_PERST_CPU1_SWB_R_N")
	)
	(segment
		(start 197.669658 -125.817376)
		(end 198.972932 -125.817376)
		(width 0.10668)
		(layer "B.Cu")
		(net "RST_PERST_CPU1_SWB_R_N")
	)
	(segment
		(start 42.50817 -434.156104)
		(end 38.038786 -434.156104)
		(width 0.10668)
		(layer "B.Cu")
		(net "RST_PERST_CPU1_SWB_R_N")
	)
	(segment
		(start 38.038786 -434.156104)
		(end 37.105844 -433.223162)
		(width 0.10668)
		(layer "B.Cu")
		(net "RST_PERST_CPU1_SWB_R_N")
	)
	(segment
		(start 202.045824 -97.143062)
		(end 202.045824 -99.153472)
		(width 0.11684)
		(layer "In4.Cu")
		(net "RST_PERST_CPU1_SWB_R_N")
	)
	(segment
		(start 203.73594 -94.049342)
		(end 203.73594 -95.452946)
		(width 0.11684)
		(layer "In4.Cu")
		(net "RST_PERST_CPU1_SWB_R_N")
	)
	(segment
		(start 202.67168 -110.106968)
		(end 202.07732 -110.106968)
		(width 0.11684)
		(layer "In4.Cu")
		(net "RST_PERST_CPU1_SWB_R_N")
	)
	(segment
		(start 200.2917 -125.197108)
		(end 199.5932 -125.197108)
		(width 0.11684)
		(layer "In4.Cu")
		(net "RST_PERST_CPU1_SWB_R_N")
	)
	(segment
		(start 203.235052 -89.30386)
		(end 203.235052 -93.548454)
		(width 0.11684)
		(layer "In4.Cu")
		(net "RST_PERST_CPU1_SWB_R_N")
	)
	(segment
		(start 200.996042 -122.661426)
		(end 200.636886 -123.020582)
		(width 0.11684)
		(layer "In4.Cu")
		(net "RST_PERST_CPU1_SWB_R_N")
	)
	(segment
		(start 201.016362 -87.08517)
		(end 203.235052 -89.30386)
		(width 0.11684)
		(layer "In4.Cu")
		(net "RST_PERST_CPU1_SWB_R_N")
	)
	(segment
		(start 201.731372 -110.452916)
		(end 201.731372 -110.876334)
		(width 0.11684)
		(layer "In4.Cu")
		(net "RST_PERST_CPU1_SWB_R_N")
	)
	(segment
		(start 200.636886 -124.851922)
		(end 200.2917 -125.197108)
		(width 0.11684)
		(layer "In4.Cu")
		(net "RST_PERST_CPU1_SWB_R_N")
	)
	(segment
		(start 200.996042 -111.611664)
		(end 200.996042 -122.661426)
		(width 0.11684)
		(layer "In4.Cu")
		(net "RST_PERST_CPU1_SWB_R_N")
	)
	(segment
		(start 200.636886 -123.020582)
		(end 200.636886 -124.851922)
		(width 0.11684)
		(layer "In4.Cu")
		(net "RST_PERST_CPU1_SWB_R_N")
	)
	(segment
		(start 199.5932 -125.197108)
		(end 198.972932 -125.817376)
		(width 0.11684)
		(layer "In4.Cu")
		(net "RST_PERST_CPU1_SWB_R_N")
	)
	(segment
		(start 202.045824 -99.153472)
		(end 203.142342 -100.24999)
		(width 0.11684)
		(layer "In4.Cu")
		(net "RST_PERST_CPU1_SWB_R_N")
	)
	(segment
		(start 202.07732 -110.106968)
		(end 201.731372 -110.452916)
		(width 0.11684)
		(layer "In4.Cu")
		(net "RST_PERST_CPU1_SWB_R_N")
	)
	(segment
		(start 203.142342 -100.24999)
		(end 203.142342 -109.636306)
		(width 0.11684)
		(layer "In4.Cu")
		(net "RST_PERST_CPU1_SWB_R_N")
	)
	(segment
		(start 203.142342 -109.636306)
		(end 202.67168 -110.106968)
		(width 0.11684)
		(layer "In4.Cu")
		(net "RST_PERST_CPU1_SWB_R_N")
	)
	(segment
		(start 201.016362 -86.934548)
		(end 201.016362 -87.08517)
		(width 0.11684)
		(layer "In4.Cu")
		(net "RST_PERST_CPU1_SWB_R_N")
	)
	(segment
		(start 203.73594 -95.452946)
		(end 202.045824 -97.143062)
		(width 0.11684)
		(layer "In4.Cu")
		(net "RST_PERST_CPU1_SWB_R_N")
	)
	(segment
		(start 201.731372 -110.876334)
		(end 200.996042 -111.611664)
		(width 0.11684)
		(layer "In4.Cu")
		(net "RST_PERST_CPU1_SWB_R_N")
	)
	(segment
		(start 203.235052 -93.548454)
		(end 203.73594 -94.049342)
		(width 0.11684)
		(layer "In4.Cu")
		(net "RST_PERST_CPU1_SWB_R_N")
	)
	(segment
		(start 113.729516 -117.855492)
		(end 136.352534 -117.855492)
		(width 0.11684)
		(layer "In6.Cu")
		(net "RST_PERST_CPU1_SWB_R_N")
	)
	(segment
		(start 147.307554 -115.03025)
		(end 150.919434 -115.03025)
		(width 0.11684)
		(layer "In6.Cu")
		(net "RST_PERST_CPU1_SWB_R_N")
	)
	(segment
		(start 151.880824 -114.06886)
		(end 156.001212 -114.06886)
		(width 0.11684)
		(layer "In6.Cu")
		(net "RST_PERST_CPU1_SWB_R_N")
	)
	(segment
		(start 158.364682 -96.529398)
		(end 161.691066 -93.203014)
		(width 0.11684)
		(layer "In6.Cu")
		(net "RST_PERST_CPU1_SWB_R_N")
	)
	(segment
		(start 137.669016 -116.53901)
		(end 145.798794 -116.53901)
		(width 0.11684)
		(layer "In6.Cu")
		(net "RST_PERST_CPU1_SWB_R_N")
	)
	(segment
		(start 145.798794 -116.53901)
		(end 147.307554 -115.03025)
		(width 0.11684)
		(layer "In6.Cu")
		(net "RST_PERST_CPU1_SWB_R_N")
	)
	(segment
		(start 156.78785 -108.39704)
		(end 158.364682 -106.820208)
		(width 0.11684)
		(layer "In6.Cu")
		(net "RST_PERST_CPU1_SWB_R_N")
	)
	(segment
		(start 158.364682 -106.820208)
		(end 158.364682 -96.529398)
		(width 0.11684)
		(layer "In6.Cu")
		(net "RST_PERST_CPU1_SWB_R_N")
	)
	(segment
		(start 150.919434 -115.03025)
		(end 151.880824 -114.06886)
		(width 0.11684)
		(layer "In6.Cu")
		(net "RST_PERST_CPU1_SWB_R_N")
	)
	(segment
		(start 156.78785 -113.282222)
		(end 156.78785 -108.39704)
		(width 0.11684)
		(layer "In6.Cu")
		(net "RST_PERST_CPU1_SWB_R_N")
	)
	(segment
		(start 136.352534 -117.855492)
		(end 137.669016 -116.53901)
		(width 0.11684)
		(layer "In6.Cu")
		(net "RST_PERST_CPU1_SWB_R_N")
	)
	(segment
		(start 156.001212 -114.06886)
		(end 156.78785 -113.282222)
		(width 0.11684)
		(layer "In6.Cu")
		(net "RST_PERST_CPU1_SWB_R_N")
	)
	(segment
		(start 110.801404 -120.783604)
		(end 113.729516 -117.855492)
		(width 0.11684)
		(layer "In6.Cu")
		(net "RST_PERST_CPU1_SWB_R_N")
	)
	(segment
		(start 38.431978 -427.591728)
		(end 38.431978 -429.495712)
		(width 0.11684)
		(layer "In11.Cu")
		(net "RST_PERST_CPU1_SWB_R_N")
	)
	(segment
		(start 38.431978 -429.495712)
		(end 37.917374 -430.010316)
		(width 0.11684)
		(layer "In11.Cu")
		(net "RST_PERST_CPU1_SWB_R_N")
	)
	(segment
		(start 26.50744 -369.259358)
		(end 29.691076 -372.442994)
		(width 0.11684)
		(layer "In11.Cu")
		(net "RST_PERST_CPU1_SWB_R_N")
	)
	(segment
		(start 94.302834 -123.193048)
		(end 88.315292 -129.18059)
		(width 0.11684)
		(layer "In11.Cu")
		(net "RST_PERST_CPU1_SWB_R_N")
	)
	(segment
		(start 108.962444 -123.193048)
		(end 94.302834 -123.193048)
		(width 0.11684)
		(layer "In11.Cu")
		(net "RST_PERST_CPU1_SWB_R_N")
	)
	(segment
		(start 19.767296 -365.252254)
		(end 20.828762 -366.31372)
		(width 0.11684)
		(layer "In11.Cu")
		(net "RST_PERST_CPU1_SWB_R_N")
	)
	(segment
		(start 34.888424 -432.839368)
		(end 35.696652 -433.647596)
		(width 0.11684)
		(layer "In11.Cu")
		(net "RST_PERST_CPU1_SWB_R_N")
	)
	(segment
		(start 29.691076 -372.442994)
		(end 29.691076 -373.750332)
		(width 0.11684)
		(layer "In11.Cu")
		(net "RST_PERST_CPU1_SWB_R_N")
	)
	(segment
		(start 23.347172 -367.374424)
		(end 26.056336 -367.374424)
		(width 0.11684)
		(layer "In11.Cu")
		(net "RST_PERST_CPU1_SWB_R_N")
	)
	(segment
		(start 29.969714 -378.937012)
		(end 31.063184 -380.030482)
		(width 0.11684)
		(layer "In11.Cu")
		(net "RST_PERST_CPU1_SWB_R_N")
	)
	(segment
		(start 37.917374 -430.010316)
		(end 35.27425 -430.010316)
		(width 0.11684)
		(layer "In11.Cu")
		(net "RST_PERST_CPU1_SWB_R_N")
	)
	(segment
		(start 110.801404 -121.354088)
		(end 108.962444 -123.193048)
		(width 0.11684)
		(layer "In11.Cu")
		(net "RST_PERST_CPU1_SWB_R_N")
	)
	(segment
		(start 29.969714 -374.02897)
		(end 29.969714 -378.937012)
		(width 0.11684)
		(layer "In11.Cu")
		(net "RST_PERST_CPU1_SWB_R_N")
	)
	(segment
		(start 37.488876 -426.648626)
		(end 38.431978 -427.591728)
		(width 0.11684)
		(layer "In11.Cu")
		(net "RST_PERST_CPU1_SWB_R_N")
	)
	(segment
		(start 48.380904 -131.924044)
		(end 29.035502 -131.924044)
		(width 0.11684)
		(layer "In11.Cu")
		(net "RST_PERST_CPU1_SWB_R_N")
	)
	(segment
		(start 31.063184 -392.321542)
		(end 34.441638 -395.699996)
		(width 0.11684)
		(layer "In11.Cu")
		(net "RST_PERST_CPU1_SWB_R_N")
	)
	(segment
		(start 34.888424 -430.396142)
		(end 34.888424 -432.839368)
		(width 0.11684)
		(layer "In11.Cu")
		(net "RST_PERST_CPU1_SWB_R_N")
	)
	(segment
		(start 5.436616 -364.856014)
		(end 18.810478 -364.856014)
		(width 0.11684)
		(layer "In11.Cu")
		(net "RST_PERST_CPU1_SWB_R_N")
	)
	(segment
		(start 37.478208 -412.47441)
		(end 37.478208 -413.939228)
		(width 0.11684)
		(layer "In11.Cu")
		(net "RST_PERST_CPU1_SWB_R_N")
	)
	(segment
		(start 39.557198 -416.018218)
		(end 39.557198 -420.255192)
		(width 0.11684)
		(layer "In11.Cu")
		(net "RST_PERST_CPU1_SWB_R_N")
	)
	(segment
		(start 4.173982 -363.59338)
		(end 5.436616 -364.856014)
		(width 0.11684)
		(layer "In11.Cu")
		(net "RST_PERST_CPU1_SWB_R_N")
	)
	(segment
		(start 4.310888 -156.648658)
		(end 4.310888 -343.529412)
		(width 0.11684)
		(layer "In11.Cu")
		(net "RST_PERST_CPU1_SWB_R_N")
	)
	(segment
		(start 26.50744 -367.825528)
		(end 26.50744 -369.259358)
		(width 0.11684)
		(layer "In11.Cu")
		(net "RST_PERST_CPU1_SWB_R_N")
	)
	(segment
		(start 31.063184 -380.030482)
		(end 31.063184 -392.321542)
		(width 0.11684)
		(layer "In11.Cu")
		(net "RST_PERST_CPU1_SWB_R_N")
	)
	(segment
		(start 22.286468 -366.31372)
		(end 23.347172 -367.374424)
		(width 0.11684)
		(layer "In11.Cu")
		(net "RST_PERST_CPU1_SWB_R_N")
	)
	(segment
		(start 20.828762 -366.31372)
		(end 22.286468 -366.31372)
		(width 0.11684)
		(layer "In11.Cu")
		(net "RST_PERST_CPU1_SWB_R_N")
	)
	(segment
		(start 4.173982 -352.888296)
		(end 4.173982 -363.59338)
		(width 0.11684)
		(layer "In11.Cu")
		(net "RST_PERST_CPU1_SWB_R_N")
	)
	(segment
		(start 37.478208 -413.939228)
		(end 39.557198 -416.018218)
		(width 0.11684)
		(layer "In11.Cu")
		(net "RST_PERST_CPU1_SWB_R_N")
	)
	(segment
		(start 35.696652 -433.647596)
		(end 36.68141 -433.647596)
		(width 0.11684)
		(layer "In11.Cu")
		(net "RST_PERST_CPU1_SWB_R_N")
	)
	(segment
		(start 36.68141 -433.647596)
		(end 37.105844 -433.223162)
		(width 0.11684)
		(layer "In11.Cu")
		(net "RST_PERST_CPU1_SWB_R_N")
	)
	(segment
		(start 88.315292 -129.18059)
		(end 51.124358 -129.18059)
		(width 0.11684)
		(layer "In11.Cu")
		(net "RST_PERST_CPU1_SWB_R_N")
	)
	(segment
		(start 29.035502 -131.924044)
		(end 4.310888 -156.648658)
		(width 0.11684)
		(layer "In11.Cu")
		(net "RST_PERST_CPU1_SWB_R_N")
	)
	(segment
		(start 39.557198 -420.255192)
		(end 37.488876 -422.323514)
		(width 0.11684)
		(layer "In11.Cu")
		(net "RST_PERST_CPU1_SWB_R_N")
	)
	(segment
		(start 34.441638 -409.43784)
		(end 37.478208 -412.47441)
		(width 0.11684)
		(layer "In11.Cu")
		(net "RST_PERST_CPU1_SWB_R_N")
	)
	(segment
		(start 37.488876 -422.323514)
		(end 37.488876 -426.648626)
		(width 0.11684)
		(layer "In11.Cu")
		(net "RST_PERST_CPU1_SWB_R_N")
	)
	(segment
		(start 18.810478 -364.856014)
		(end 19.767296 -365.252254)
		(width 0.11684)
		(layer "In11.Cu")
		(net "RST_PERST_CPU1_SWB_R_N")
	)
	(segment
		(start 110.801404 -120.783604)
		(end 110.801404 -121.354088)
		(width 0.11684)
		(layer "In11.Cu")
		(net "RST_PERST_CPU1_SWB_R_N")
	)
	(segment
		(start 29.691076 -373.750332)
		(end 29.969714 -374.02897)
		(width 0.11684)
		(layer "In11.Cu")
		(net "RST_PERST_CPU1_SWB_R_N")
	)
	(segment
		(start 4.310888 -343.529412)
		(end 3.626866 -344.213434)
		(width 0.11684)
		(layer "In11.Cu")
		(net "RST_PERST_CPU1_SWB_R_N")
	)
	(segment
		(start 35.27425 -430.010316)
		(end 34.888424 -430.396142)
		(width 0.11684)
		(layer "In11.Cu")
		(net "RST_PERST_CPU1_SWB_R_N")
	)
	(segment
		(start 51.124358 -129.18059)
		(end 48.380904 -131.924044)
		(width 0.11684)
		(layer "In11.Cu")
		(net "RST_PERST_CPU1_SWB_R_N")
	)
	(segment
		(start 34.441638 -395.699996)
		(end 34.441638 -409.43784)
		(width 0.11684)
		(layer "In11.Cu")
		(net "RST_PERST_CPU1_SWB_R_N")
	)
	(segment
		(start 26.056336 -367.374424)
		(end 26.50744 -367.825528)
		(width 0.11684)
		(layer "In11.Cu")
		(net "RST_PERST_CPU1_SWB_R_N")
	)
	(segment
		(start 3.626866 -352.34118)
		(end 4.173982 -352.888296)
		(width 0.11684)
		(layer "In11.Cu")
		(net "RST_PERST_CPU1_SWB_R_N")
	)
	(segment
		(start 3.626866 -344.213434)
		(end 3.626866 -352.34118)
		(width 0.11684)
		(layer "In11.Cu")
		(net "RST_PERST_CPU1_SWB_R_N")
	)
	(segment
		(start 199.084438 -86.750398)
		(end 199.451468 -86.383368)
		(width 0.11684)
		(layer "In15.Cu")
		(net "RST_PERST_CPU1_SWB_R_N")
	)
	(segment
		(start 163.555934 -93.203014)
		(end 163.99764 -92.761308)
		(width 0.11684)
		(layer "In15.Cu")
		(net "RST_PERST_CPU1_SWB_R_N")
	)
	(segment
		(start 186.399424 -86.298532)
		(end 194.209924 -86.298532)
		(width 0.11684)
		(layer "In15.Cu")
		(net "RST_PERST_CPU1_SWB_R_N")
	)
	(segment
		(start 194.209924 -86.298532)
		(end 195.27012 -87.358728)
		(width 0.11684)
		(layer "In15.Cu")
		(net "RST_PERST_CPU1_SWB_R_N")
	)
	(segment
		(start 198.957438 -87.358728)
		(end 199.084438 -87.231728)
		(width 0.11684)
		(layer "In15.Cu")
		(net "RST_PERST_CPU1_SWB_R_N")
	)
	(segment
		(start 185.71718 -85.616288)
		(end 186.399424 -86.298532)
		(width 0.11684)
		(layer "In15.Cu")
		(net "RST_PERST_CPU1_SWB_R_N")
	)
	(segment
		(start 167.04818 -85.616288)
		(end 185.71718 -85.616288)
		(width 0.11684)
		(layer "In15.Cu")
		(net "RST_PERST_CPU1_SWB_R_N")
	)
	(segment
		(start 199.084438 -87.231728)
		(end 199.084438 -86.750398)
		(width 0.11684)
		(layer "In15.Cu")
		(net "RST_PERST_CPU1_SWB_R_N")
	)
	(segment
		(start 195.27012 -87.358728)
		(end 198.957438 -87.358728)
		(width 0.11684)
		(layer "In15.Cu")
		(net "RST_PERST_CPU1_SWB_R_N")
	)
	(segment
		(start 161.691066 -93.203014)
		(end 163.555934 -93.203014)
		(width 0.11684)
		(layer "In15.Cu")
		(net "RST_PERST_CPU1_SWB_R_N")
	)
	(segment
		(start 163.99764 -92.761308)
		(end 163.99764 -88.666828)
		(width 0.11684)
		(layer "In15.Cu")
		(net "RST_PERST_CPU1_SWB_R_N")
	)
	(segment
		(start 163.99764 -88.666828)
		(end 167.04818 -85.616288)
		(width 0.11684)
		(layer "In15.Cu")
		(net "RST_PERST_CPU1_SWB_R_N")
	)
	(segment
		(start 199.451468 -86.383368)
		(end 200.53046 -86.383368)
		(width 0.11684)
		(layer "In15.Cu")
		(net "RST_PERST_CPU1_SWB_R_N")
	)
	(segment
		(start 201.016362 -86.86927)
		(end 201.016362 -86.934548)
		(width 0.11684)
		(layer "In15.Cu")
		(net "RST_PERST_CPU1_SWB_R_N")
	)
	(segment
		(start 200.53046 -86.383368)
		(end 201.016362 -86.86927)
		(width 0.11684)
		(layer "In15.Cu")
		(net "RST_PERST_CPU1_SWB_R_N")
	)
	(segment
		(start 189.92215 -117.052852)
		(end 190.31204 -117.442742)
		(width 0.10668)
		(layer "F.Cu")
		(net "RST_PERST_CPU1_SWB_N")
	)
	(via
		(at 194.337178 -123.011946)
		(size 0.6604)
		(drill 0.3302)
		(layers "F.Cu" "B.Cu")
		(net "RST_PERST_CPU1_SWB_N")
	)
	(via
		(at 190.31204 -117.442742)
		(size 0.4572)
		(drill 0.254)
		(layers "F.Cu" "B.Cu")
		(net "RST_PERST_CPU1_SWB_N")
	)
	(segment
		(start 190.715646 -120.007126)
		(end 190.947548 -120.239028)
		(width 0.10668)
		(layer "B.Cu")
		(net "RST_PERST_CPU1_SWB_N")
	)
	(segment
		(start 191.747648 -121.038874)
		(end 193.66865 -121.038874)
		(width 0.10668)
		(layer "B.Cu")
		(net "RST_PERST_CPU1_SWB_N")
	)
	(segment
		(start 193.66865 -121.038874)
		(end 193.908172 -121.278396)
		(width 0.10668)
		(layer "B.Cu")
		(net "RST_PERST_CPU1_SWB_N")
	)
	(segment
		(start 191.508126 -120.799352)
		(end 191.747648 -121.038874)
		(width 0.10668)
		(layer "B.Cu")
		(net "RST_PERST_CPU1_SWB_N")
	)
	(segment
		(start 191.347598 -120.239028)
		(end 191.508126 -120.399556)
		(width 0.10668)
		(layer "B.Cu")
		(net "RST_PERST_CPU1_SWB_N")
	)
	(segment
		(start 190.947548 -120.239028)
		(end 191.347598 -120.239028)
		(width 0.10668)
		(layer "B.Cu")
		(net "RST_PERST_CPU1_SWB_N")
	)
	(segment
		(start 196.846698 -125.817376)
		(end 196.285358 -125.256036)
		(width 0.10668)
		(layer "B.Cu")
		(net "RST_PERST_CPU1_SWB_N")
	)
	(segment
		(start 193.908172 -122.58294)
		(end 194.337178 -123.011946)
		(width 0.10668)
		(layer "B.Cu")
		(net "RST_PERST_CPU1_SWB_N")
	)
	(segment
		(start 196.892926 -124.930408)
		(end 196.945758 -124.877576)
		(width 0.10668)
		(layer "B.Cu")
		(net "RST_PERST_CPU1_SWB_N")
	)
	(segment
		(start 191.508126 -120.399556)
		(end 191.508126 -120.799352)
		(width 0.10668)
		(layer "B.Cu")
		(net "RST_PERST_CPU1_SWB_N")
	)
	(segment
		(start 195.53428 -124.958094)
		(end 195.53428 -124.209048)
		(width 0.10668)
		(layer "B.Cu")
		(net "RST_PERST_CPU1_SWB_N")
	)
	(segment
		(start 196.869558 -125.817376)
		(end 196.846698 -125.817376)
		(width 0.10668)
		(layer "B.Cu")
		(net "RST_PERST_CPU1_SWB_N")
	)
	(segment
		(start 195.53428 -124.209048)
		(end 194.337178 -123.011946)
		(width 0.10668)
		(layer "B.Cu")
		(net "RST_PERST_CPU1_SWB_N")
	)
	(segment
		(start 193.908172 -121.278396)
		(end 193.908172 -122.58294)
		(width 0.10668)
		(layer "B.Cu")
		(net "RST_PERST_CPU1_SWB_N")
	)
	(segment
		(start 190.31204 -117.442742)
		(end 190.715646 -117.846348)
		(width 0.10668)
		(layer "B.Cu")
		(net "RST_PERST_CPU1_SWB_N")
	)
	(segment
		(start 196.869558 -125.817376)
		(end 196.892926 -125.794008)
		(width 0.10668)
		(layer "B.Cu")
		(net "RST_PERST_CPU1_SWB_N")
	)
	(segment
		(start 195.832222 -125.256036)
		(end 195.53428 -124.958094)
		(width 0.10668)
		(layer "B.Cu")
		(net "RST_PERST_CPU1_SWB_N")
	)
	(segment
		(start 196.285358 -125.256036)
		(end 195.832222 -125.256036)
		(width 0.10668)
		(layer "B.Cu")
		(net "RST_PERST_CPU1_SWB_N")
	)
	(segment
		(start 190.715646 -117.846348)
		(end 190.715646 -120.007126)
		(width 0.10668)
		(layer "B.Cu")
		(net "RST_PERST_CPU1_SWB_N")
	)
	(segment
		(start 196.892926 -125.794008)
		(end 196.892926 -124.930408)
		(width 0.10668)
		(layer "B.Cu")
		(net "RST_PERST_CPU1_SWB_N")
	)
	(segment
		(start 39.43604 -437.148986)
		(end 39.43604 -437.815228)
		(width 0.10668)
		(layer "F.Cu")
		(net "RST_PERST_CPU0_SWB_R_N")
	)
	(segment
		(start 201.352658 -115.657376)
		(end 202.502008 -115.657376)
		(width 0.10668)
		(layer "F.Cu")
		(net "RST_PERST_CPU0_SWB_R_N")
	)
	(via
		(at 204.06614 -86.759288)
		(size 0.508)
		(drill 0.254)
		(layers "F.Cu" "B.Cu")
		(net "RST_PERST_CPU0_SWB_R_N")
	)
	(via
		(at 161.671 -91.531948)
		(size 0.508)
		(drill 0.254)
		(layers "F.Cu" "B.Cu")
		(net "RST_PERST_CPU0_SWB_R_N")
	)
	(via
		(at 108.256832 -119.120158)
		(size 0.508)
		(drill 0.254)
		(layers "F.Cu" "B.Cu")
		(net "RST_PERST_CPU0_SWB_R_N")
	)
	(via
		(at 39.43604 -437.815228)
		(size 0.508)
		(drill 0.254)
		(layers "F.Cu" "B.Cu")
		(net "RST_PERST_CPU0_SWB_R_N")
	)
	(via
		(at 202.502008 -115.657376)
		(size 0.508)
		(drill 0.254)
		(layers "F.Cu" "B.Cu")
		(net "RST_PERST_CPU0_SWB_R_N")
	)
	(segment
		(start 203.570586 -109.846618)
		(end 203.135738 -110.281466)
		(width 0.11684)
		(layer "In4.Cu")
		(net "RST_PERST_CPU0_SWB_R_N")
	)
	(segment
		(start 203.135738 -111.67237)
		(end 202.67168 -112.136428)
		(width 0.11684)
		(layer "In4.Cu")
		(net "RST_PERST_CPU0_SWB_R_N")
	)
	(segment
		(start 201.839322 -114.99469)
		(end 202.502008 -115.657376)
		(width 0.11684)
		(layer "In4.Cu")
		(net "RST_PERST_CPU0_SWB_R_N")
	)
	(segment
		(start 202.694032 -98.966782)
		(end 203.570586 -99.843336)
		(width 0.11684)
		(layer "In4.Cu")
		(net "RST_PERST_CPU0_SWB_R_N")
	)
	(segment
		(start 203.570586 -99.843336)
		(end 203.570586 -109.846618)
		(width 0.11684)
		(layer "In4.Cu")
		(net "RST_PERST_CPU0_SWB_R_N")
	)
	(segment
		(start 202.694032 -97.095818)
		(end 202.694032 -98.966782)
		(width 0.11684)
		(layer "In4.Cu")
		(net "RST_PERST_CPU0_SWB_R_N")
	)
	(segment
		(start 204.1906 -86.883748)
		(end 204.1906 -90.894916)
		(width 0.11684)
		(layer "In4.Cu")
		(net "RST_PERST_CPU0_SWB_R_N")
	)
	(segment
		(start 204.1906 -93.736414)
		(end 204.1906 -95.59925)
		(width 0.11684)
		(layer "In4.Cu")
		(net "RST_PERST_CPU0_SWB_R_N")
	)
	(segment
		(start 204.1906 -95.59925)
		(end 202.694032 -97.095818)
		(width 0.11684)
		(layer "In4.Cu")
		(net "RST_PERST_CPU0_SWB_R_N")
	)
	(segment
		(start 202.67168 -112.136428)
		(end 202.28814 -112.136428)
		(width 0.11684)
		(layer "In4.Cu")
		(net "RST_PERST_CPU0_SWB_R_N")
	)
	(segment
		(start 204.60462 -91.308936)
		(end 204.60462 -93.322394)
		(width 0.11684)
		(layer "In4.Cu")
		(net "RST_PERST_CPU0_SWB_R_N")
	)
	(segment
		(start 204.60462 -93.322394)
		(end 204.1906 -93.736414)
		(width 0.11684)
		(layer "In4.Cu")
		(net "RST_PERST_CPU0_SWB_R_N")
	)
	(segment
		(start 203.135738 -110.281466)
		(end 203.135738 -111.67237)
		(width 0.11684)
		(layer "In4.Cu")
		(net "RST_PERST_CPU0_SWB_R_N")
	)
	(segment
		(start 202.28814 -112.136428)
		(end 201.839322 -112.585246)
		(width 0.11684)
		(layer "In4.Cu")
		(net "RST_PERST_CPU0_SWB_R_N")
	)
	(segment
		(start 204.1906 -90.894916)
		(end 204.60462 -91.308936)
		(width 0.11684)
		(layer "In4.Cu")
		(net "RST_PERST_CPU0_SWB_R_N")
	)
	(segment
		(start 204.06614 -86.759288)
		(end 204.1906 -86.883748)
		(width 0.11684)
		(layer "In4.Cu")
		(net "RST_PERST_CPU0_SWB_R_N")
	)
	(segment
		(start 201.839322 -112.585246)
		(end 201.839322 -114.99469)
		(width 0.11684)
		(layer "In4.Cu")
		(net "RST_PERST_CPU0_SWB_R_N")
	)
	(segment
		(start 157.521402 -106.432096)
		(end 155.94457 -108.008928)
		(width 0.11684)
		(layer "In6.Cu")
		(net "RST_PERST_CPU0_SWB_R_N")
	)
	(segment
		(start 150.014432 -113.670588)
		(end 148.82114 -113.670588)
		(width 0.11684)
		(layer "In6.Cu")
		(net "RST_PERST_CPU0_SWB_R_N")
	)
	(segment
		(start 148.82114 -113.670588)
		(end 148.23186 -113.081308)
		(width 0.11684)
		(layer "In6.Cu")
		(net "RST_PERST_CPU0_SWB_R_N")
	)
	(segment
		(start 112.32388 -117.012212)
		(end 110.215934 -119.120158)
		(width 0.11684)
		(layer "In6.Cu")
		(net "RST_PERST_CPU0_SWB_R_N")
	)
	(segment
		(start 161.671 -91.531948)
		(end 157.521402 -95.681546)
		(width 0.11684)
		(layer "In6.Cu")
		(net "RST_PERST_CPU0_SWB_R_N")
	)
	(segment
		(start 110.215934 -119.120158)
		(end 108.256832 -119.120158)
		(width 0.11684)
		(layer "In6.Cu")
		(net "RST_PERST_CPU0_SWB_R_N")
	)
	(segment
		(start 155.94457 -111.211614)
		(end 154.272742 -112.883442)
		(width 0.11684)
		(layer "In6.Cu")
		(net "RST_PERST_CPU0_SWB_R_N")
	)
	(segment
		(start 154.272742 -112.883442)
		(end 150.801578 -112.883442)
		(width 0.11684)
		(layer "In6.Cu")
		(net "RST_PERST_CPU0_SWB_R_N")
	)
	(segment
		(start 142.547848 -115.604544)
		(end 137.10031 -115.604544)
		(width 0.11684)
		(layer "In6.Cu")
		(net "RST_PERST_CPU0_SWB_R_N")
	)
	(segment
		(start 137.10031 -115.604544)
		(end 135.692642 -117.012212)
		(width 0.11684)
		(layer "In6.Cu")
		(net "RST_PERST_CPU0_SWB_R_N")
	)
	(segment
		(start 150.801578 -112.883442)
		(end 150.014432 -113.670588)
		(width 0.11684)
		(layer "In6.Cu")
		(net "RST_PERST_CPU0_SWB_R_N")
	)
	(segment
		(start 148.23186 -113.081308)
		(end 145.071084 -113.081308)
		(width 0.11684)
		(layer "In6.Cu")
		(net "RST_PERST_CPU0_SWB_R_N")
	)
	(segment
		(start 155.94457 -108.008928)
		(end 155.94457 -111.211614)
		(width 0.11684)
		(layer "In6.Cu")
		(net "RST_PERST_CPU0_SWB_R_N")
	)
	(segment
		(start 157.521402 -95.681546)
		(end 157.521402 -106.432096)
		(width 0.11684)
		(layer "In6.Cu")
		(net "RST_PERST_CPU0_SWB_R_N")
	)
	(segment
		(start 135.692642 -117.012212)
		(end 112.32388 -117.012212)
		(width 0.11684)
		(layer "In6.Cu")
		(net "RST_PERST_CPU0_SWB_R_N")
	)
	(segment
		(start 145.071084 -113.081308)
		(end 142.547848 -115.604544)
		(width 0.11684)
		(layer "In6.Cu")
		(net "RST_PERST_CPU0_SWB_R_N")
	)
	(segment
		(start 39.034466 -436.922926)
		(end 39.43604 -437.3245)
		(width 0.11684)
		(layer "In11.Cu")
		(net "RST_PERST_CPU0_SWB_R_N")
	)
	(segment
		(start 3.330702 -353.238054)
		(end 3.330702 -402.802852)
		(width 0.11684)
		(layer "In11.Cu")
		(net "RST_PERST_CPU0_SWB_R_N")
	)
	(segment
		(start 2.783586 -343.85123)
		(end 2.783586 -352.690938)
		(width 0.11684)
		(layer "In11.Cu")
		(net "RST_PERST_CPU0_SWB_R_N")
	)
	(segment
		(start 48.0314 -131.080764)
		(end 28.685998 -131.080764)
		(width 0.11684)
		(layer "In11.Cu")
		(net "RST_PERST_CPU0_SWB_R_N")
	)
	(segment
		(start 18.843244 -433.553616)
		(end 19.52752 -433.553616)
		(width 0.11684)
		(layer "In11.Cu")
		(net "RST_PERST_CPU0_SWB_R_N")
	)
	(segment
		(start 50.774854 -128.33731)
		(end 48.0314 -131.080764)
		(width 0.11684)
		(layer "In11.Cu")
		(net "RST_PERST_CPU0_SWB_R_N")
	)
	(segment
		(start 3.467608 -156.299154)
		(end 3.467608 -343.167208)
		(width 0.11684)
		(layer "In11.Cu")
		(net "RST_PERST_CPU0_SWB_R_N")
	)
	(segment
		(start 7.851648 -420.97325)
		(end 8.885682 -422.007284)
		(width 0.11684)
		(layer "In11.Cu")
		(net "RST_PERST_CPU0_SWB_R_N")
	)
	(segment
		(start 29.666692 -436.259732)
		(end 31.251144 -437.844184)
		(width 0.11684)
		(layer "In11.Cu")
		(net "RST_PERST_CPU0_SWB_R_N")
	)
	(segment
		(start 108.256832 -119.120158)
		(end 108.256832 -120.308116)
		(width 0.11684)
		(layer "In11.Cu")
		(net "RST_PERST_CPU0_SWB_R_N")
	)
	(segment
		(start 108.256832 -120.308116)
		(end 106.21518 -122.349768)
		(width 0.11684)
		(layer "In11.Cu")
		(net "RST_PERST_CPU0_SWB_R_N")
	)
	(segment
		(start 34.515298 -437.844184)
		(end 35.436556 -436.922926)
		(width 0.11684)
		(layer "In11.Cu")
		(net "RST_PERST_CPU0_SWB_R_N")
	)
	(segment
		(start 19.52752 -433.553616)
		(end 22.233636 -436.259732)
		(width 0.11684)
		(layer "In11.Cu")
		(net "RST_PERST_CPU0_SWB_R_N")
	)
	(segment
		(start 11.376406 -430.146206)
		(end 15.435834 -430.146206)
		(width 0.11684)
		(layer "In11.Cu")
		(net "RST_PERST_CPU0_SWB_R_N")
	)
	(segment
		(start 3.330702 -402.802852)
		(end 7.851648 -407.323798)
		(width 0.11684)
		(layer "In11.Cu")
		(net "RST_PERST_CPU0_SWB_R_N")
	)
	(segment
		(start 7.851648 -407.323798)
		(end 7.851648 -420.97325)
		(width 0.11684)
		(layer "In11.Cu")
		(net "RST_PERST_CPU0_SWB_R_N")
	)
	(segment
		(start 87.965788 -128.33731)
		(end 50.774854 -128.33731)
		(width 0.11684)
		(layer "In11.Cu")
		(net "RST_PERST_CPU0_SWB_R_N")
	)
	(segment
		(start 93.95333 -122.349768)
		(end 87.965788 -128.33731)
		(width 0.11684)
		(layer "In11.Cu")
		(net "RST_PERST_CPU0_SWB_R_N")
	)
	(segment
		(start 22.233636 -436.259732)
		(end 29.666692 -436.259732)
		(width 0.11684)
		(layer "In11.Cu")
		(net "RST_PERST_CPU0_SWB_R_N")
	)
	(segment
		(start 8.885682 -427.655482)
		(end 11.376406 -430.146206)
		(width 0.11684)
		(layer "In11.Cu")
		(net "RST_PERST_CPU0_SWB_R_N")
	)
	(segment
		(start 31.251144 -437.844184)
		(end 34.515298 -437.844184)
		(width 0.11684)
		(layer "In11.Cu")
		(net "RST_PERST_CPU0_SWB_R_N")
	)
	(segment
		(start 8.885682 -422.007284)
		(end 8.885682 -427.655482)
		(width 0.11684)
		(layer "In11.Cu")
		(net "RST_PERST_CPU0_SWB_R_N")
	)
	(segment
		(start 35.436556 -436.922926)
		(end 39.034466 -436.922926)
		(width 0.11684)
		(layer "In11.Cu")
		(net "RST_PERST_CPU0_SWB_R_N")
	)
	(segment
		(start 106.21518 -122.349768)
		(end 93.95333 -122.349768)
		(width 0.11684)
		(layer "In11.Cu")
		(net "RST_PERST_CPU0_SWB_R_N")
	)
	(segment
		(start 15.435834 -430.146206)
		(end 18.843244 -433.553616)
		(width 0.11684)
		(layer "In11.Cu")
		(net "RST_PERST_CPU0_SWB_R_N")
	)
	(segment
		(start 28.685998 -131.080764)
		(end 3.467608 -156.299154)
		(width 0.11684)
		(layer "In11.Cu")
		(net "RST_PERST_CPU0_SWB_R_N")
	)
	(segment
		(start 3.467608 -343.167208)
		(end 2.783586 -343.85123)
		(width 0.11684)
		(layer "In11.Cu")
		(net "RST_PERST_CPU0_SWB_R_N")
	)
	(segment
		(start 39.43604 -437.3245)
		(end 39.43604 -437.815228)
		(width 0.11684)
		(layer "In11.Cu")
		(net "RST_PERST_CPU0_SWB_R_N")
	)
	(segment
		(start 2.783586 -352.690938)
		(end 3.330702 -353.238054)
		(width 0.11684)
		(layer "In11.Cu")
		(net "RST_PERST_CPU0_SWB_R_N")
	)
	(segment
		(start 189.27191 -83.579208)
		(end 188.49975 -84.351368)
		(width 0.11684)
		(layer "In15.Cu")
		(net "RST_PERST_CPU0_SWB_R_N")
	)
	(segment
		(start 201.365104 -85.988144)
		(end 199.803512 -84.426552)
		(width 0.11684)
		(layer "In15.Cu")
		(net "RST_PERST_CPU0_SWB_R_N")
	)
	(segment
		(start 204.06614 -86.759288)
		(end 203.294996 -85.988144)
		(width 0.11684)
		(layer "In15.Cu")
		(net "RST_PERST_CPU0_SWB_R_N")
	)
	(segment
		(start 166.035228 -84.351368)
		(end 161.671 -88.715596)
		(width 0.11684)
		(layer "In15.Cu")
		(net "RST_PERST_CPU0_SWB_R_N")
	)
	(segment
		(start 199.803512 -84.426552)
		(end 197.83298 -84.426552)
		(width 0.11684)
		(layer "In15.Cu")
		(net "RST_PERST_CPU0_SWB_R_N")
	)
	(segment
		(start 161.671 -88.715596)
		(end 161.671 -91.531948)
		(width 0.11684)
		(layer "In15.Cu")
		(net "RST_PERST_CPU0_SWB_R_N")
	)
	(segment
		(start 197.83298 -84.426552)
		(end 196.985636 -83.579208)
		(width 0.11684)
		(layer "In15.Cu")
		(net "RST_PERST_CPU0_SWB_R_N")
	)
	(segment
		(start 203.294996 -85.988144)
		(end 201.365104 -85.988144)
		(width 0.11684)
		(layer "In15.Cu")
		(net "RST_PERST_CPU0_SWB_R_N")
	)
	(segment
		(start 188.49975 -84.351368)
		(end 166.035228 -84.351368)
		(width 0.11684)
		(layer "In15.Cu")
		(net "RST_PERST_CPU0_SWB_R_N")
	)
	(segment
		(start 196.985636 -83.579208)
		(end 189.27191 -83.579208)
		(width 0.11684)
		(layer "In15.Cu")
		(net "RST_PERST_CPU0_SWB_R_N")
	)
	(segment
		(start 189.12205 -117.052852)
		(end 189.51194 -117.442742)
		(width 0.10668)
		(layer "F.Cu")
		(net "RST_PERST_CPU0_SWB_N")
	)
	(segment
		(start 199.88149 -115.657376)
		(end 199.83577 -115.703096)
		(width 0.10668)
		(layer "F.Cu")
		(net "RST_PERST_CPU0_SWB_N")
	)
	(segment
		(start 200.552558 -115.657376)
		(end 199.88149 -115.657376)
		(width 0.10668)
		(layer "F.Cu")
		(net "RST_PERST_CPU0_SWB_N")
	)
	(segment
		(start 205.615032 -115.657376)
		(end 206.530956 -115.657376)
		(width 0.10668)
		(layer "F.Cu")
		(net "RST_PERST_CPU0_SWB_N")
	)
	(via
		(at 189.51194 -117.442742)
		(size 0.4572)
		(drill 0.254)
		(layers "F.Cu" "B.Cu")
		(net "RST_PERST_CPU0_SWB_N")
	)
	(via
		(at 206.530956 -115.657376)
		(size 0.508)
		(drill 0.254)
		(layers "F.Cu" "B.Cu")
		(net "RST_PERST_CPU0_SWB_N")
	)
	(via
		(at 199.83577 -115.703096)
		(size 0.508)
		(drill 0.254)
		(layers "F.Cu" "B.Cu")
		(net "RST_PERST_CPU0_SWB_N")
	)
	(segment
		(start 199.299576 -116.23929)
		(end 199.83577 -115.703096)
		(width 0.11684)
		(layer "In6.Cu")
		(net "RST_PERST_CPU0_SWB_N")
	)
	(segment
		(start 189.911736 -117.042946)
		(end 197.140068 -117.042946)
		(width 0.11684)
		(layer "In6.Cu")
		(net "RST_PERST_CPU0_SWB_N")
	)
	(segment
		(start 197.140068 -117.042946)
		(end 197.943724 -116.23929)
		(width 0.11684)
		(layer "In6.Cu")
		(net "RST_PERST_CPU0_SWB_N")
	)
	(segment
		(start 189.51194 -117.442742)
		(end 189.911736 -117.042946)
		(width 0.11684)
		(layer "In6.Cu")
		(net "RST_PERST_CPU0_SWB_N")
	)
	(segment
		(start 197.943724 -116.23929)
		(end 199.299576 -116.23929)
		(width 0.11684)
		(layer "In6.Cu")
		(net "RST_PERST_CPU0_SWB_N")
	)
	(segment
		(start 199.83577 -115.703096)
		(end 199.83577 -115.508278)
		(width 0.11684)
		(layer "In15.Cu")
		(net "RST_PERST_CPU0_SWB_N")
	)
	(segment
		(start 200.180956 -115.163092)
		(end 204.216508 -115.163092)
		(width 0.11684)
		(layer "In15.Cu")
		(net "RST_PERST_CPU0_SWB_N")
	)
	(segment
		(start 204.710792 -115.657376)
		(end 206.530956 -115.657376)
		(width 0.11684)
		(layer "In15.Cu")
		(net "RST_PERST_CPU0_SWB_N")
	)
	(segment
		(start 204.216508 -115.163092)
		(end 204.710792 -115.657376)
		(width 0.11684)
		(layer "In15.Cu")
		(net "RST_PERST_CPU0_SWB_N")
	)
	(segment
		(start 199.83577 -115.508278)
		(end 200.180956 -115.163092)
		(width 0.11684)
		(layer "In15.Cu")
		(net "RST_PERST_CPU0_SWB_N")
	)
	(segment
		(start 192.322196 -110.652814)
		(end 192.712086 -110.262924)
		(width 0.10668)
		(layer "F.Cu")
		(net "P12V_SCM_PWRGD_R")
	)
	(segment
		(start 208.494376 -109.561376)
		(end 207.716374 -109.561376)
		(width 0.10668)
		(layer "F.Cu")
		(net "P12V_SCM_PWRGD_R")
	)
	(segment
		(start 207.716374 -109.561376)
		(end 207.644238 -109.48924)
		(width 0.10668)
		(layer "F.Cu")
		(net "P12V_SCM_PWRGD_R")
	)
	(via
		(at 192.712086 -110.262924)
		(size 0.4572)
		(drill 0.254)
		(layers "F.Cu" "B.Cu")
		(net "P12V_SCM_PWRGD_R")
	)
	(via
		(at 207.644238 -109.48924)
		(size 0.508)
		(drill 0.254)
		(layers "F.Cu" "B.Cu")
		(net "P12V_SCM_PWRGD_R")
	)
	(segment
		(start 203.450698 -109.590078)
		(end 207.5434 -109.590078)
		(width 0.11684)
		(layer "In6.Cu")
		(net "P12V_SCM_PWRGD_R")
	)
	(segment
		(start 195.309744 -110.262924)
		(end 196.09308 -111.04626)
		(width 0.11684)
		(layer "In6.Cu")
		(net "P12V_SCM_PWRGD_R")
	)
	(segment
		(start 201.321416 -110.086648)
		(end 202.954128 -110.086648)
		(width 0.11684)
		(layer "In6.Cu")
		(net "P12V_SCM_PWRGD_R")
	)
	(segment
		(start 200.283064 -111.125)
		(end 201.321416 -110.086648)
		(width 0.11684)
		(layer "In6.Cu")
		(net "P12V_SCM_PWRGD_R")
	)
	(segment
		(start 197.49516 -111.04626)
		(end 197.5739 -111.125)
		(width 0.11684)
		(layer "In6.Cu")
		(net "P12V_SCM_PWRGD_R")
	)
	(segment
		(start 202.954128 -110.086648)
		(end 203.450698 -109.590078)
		(width 0.11684)
		(layer "In6.Cu")
		(net "P12V_SCM_PWRGD_R")
	)
	(segment
		(start 207.5434 -109.590078)
		(end 207.644238 -109.48924)
		(width 0.11684)
		(layer "In6.Cu")
		(net "P12V_SCM_PWRGD_R")
	)
	(segment
		(start 196.09308 -111.04626)
		(end 197.49516 -111.04626)
		(width 0.11684)
		(layer "In6.Cu")
		(net "P12V_SCM_PWRGD_R")
	)
	(segment
		(start 192.712086 -110.262924)
		(end 195.309744 -110.262924)
		(width 0.11684)
		(layer "In6.Cu")
		(net "P12V_SCM_PWRGD_R")
	)
	(segment
		(start 197.5739 -111.125)
		(end 200.283064 -111.125)
		(width 0.11684)
		(layer "In6.Cu")
		(net "P12V_SCM_PWRGD_R")
	)
	(via
		(at 334.501236 -77.008736)
		(size 0.6604)
		(drill 0.3302)
		(layers "F.Cu" "B.Cu")
		(net "NC_Q83_S2")
	)
	(segment
		(start 333.266796 -77.008736)
		(end 334.501236 -77.008736)
		(width 0.10668)
		(layer "B.Cu")
		(net "NC_Q83_S2")
	)
	(via
		(at 334.501236 -75.738736)
		(size 0.6604)
		(drill 0.3302)
		(layers "F.Cu" "B.Cu")
		(net "NC_Q83_G2")
	)
	(segment
		(start 333.881222 -76.35875)
		(end 333.266796 -76.35875)
		(width 0.10668)
		(layer "B.Cu")
		(net "NC_Q83_G2")
	)
	(segment
		(start 334.501236 -75.738736)
		(end 333.881222 -76.35875)
		(width 0.10668)
		(layer "B.Cu")
		(net "NC_Q83_G2")
	)
	(via
		(at 331.366876 -78.35265)
		(size 0.6604)
		(drill 0.3302)
		(layers "F.Cu" "B.Cu")
		(net "NC_Q83_D2")
	)
	(segment
		(start 331.366876 -78.35265)
		(end 331.366876 -77.008736)
		(width 0.10668)
		(layer "B.Cu")
		(net "NC_Q83_D2")
	)
	(segment
		(start 310.411876 -70.573392)
		(end 310.411876 -71.868792)
		(width 0.10668)
		(layer "F.Cu")
		(net "LED_RST_RSMRST_PLD_R_N_D")
	)
	(via
		(at 310.411876 -71.868792)
		(size 0.762)
		(drill 0.254)
		(layers "F.Cu" "B.Cu")
		(net "LED_RST_RSMRST_PLD_R_N_D")
	)
	(segment
		(start 310.411876 -71.868792)
		(end 311.302146 -71.868792)
		(width 0.10668)
		(layer "B.Cu")
		(net "LED_RST_RSMRST_PLD_R_N_D")
	)
	(segment
		(start 311.629044 -74.184764)
		(end 311.194704 -74.184764)
		(width 0.10668)
		(layer "B.Cu")
		(net "LED_RST_RSMRST_PLD_R_N_D")
	)
	(segment
		(start 311.302146 -71.868792)
		(end 311.750456 -72.317102)
		(width 0.10668)
		(layer "B.Cu")
		(net "LED_RST_RSMRST_PLD_R_N_D")
	)
	(segment
		(start 311.750456 -74.063352)
		(end 311.629044 -74.184764)
		(width 0.10668)
		(layer "B.Cu")
		(net "LED_RST_RSMRST_PLD_R_N_D")
	)
	(segment
		(start 311.750456 -72.317102)
		(end 311.750456 -74.063352)
		(width 0.10668)
		(layer "B.Cu")
		(net "LED_RST_RSMRST_PLD_R_N_D")
	)
	(segment
		(start 310.411876 -68.328032)
		(end 310.411876 -69.623432)
		(width 0.10668)
		(layer "F.Cu")
		(net "LED_RST_RSMRST_PLD_R_N")
	)
	(via
		(at 310.411876 -68.328032)
		(size 0.508)
		(drill 0.254)
		(layers "F.Cu" "B.Cu")
		(net "LED_RST_RSMRST_PLD_R_N")
	)
	(segment
		(start 310.411876 -67.108832)
		(end 310.411876 -68.328032)
		(width 0.10668)
		(layer "B.Cu")
		(net "LED_RST_RSMRST_PLD_R_N")
	)
	(segment
		(start 342.923876 -68.328032)
		(end 342.923876 -69.623432)
		(width 0.10668)
		(layer "F.Cu")
		(net "LED_PWRGD_PVDDIO_P1_R")
	)
	(via
		(at 342.923876 -68.328032)
		(size 0.508)
		(drill 0.254)
		(layers "F.Cu" "B.Cu")
		(net "LED_PWRGD_PVDDIO_P1_R")
	)
	(segment
		(start 342.923876 -67.108832)
		(end 342.923876 -68.328032)
		(width 0.10668)
		(layer "B.Cu")
		(net "LED_PWRGD_PVDDIO_P1_R")
	)
	(segment
		(start 342.923876 -70.573392)
		(end 342.923876 -71.868792)
		(width 0.10668)
		(layer "F.Cu")
		(net "LED_PWRGD_PVDDIO_P1_D")
	)
	(via
		(at 342.923876 -71.868792)
		(size 0.762)
		(drill 0.254)
		(layers "F.Cu" "B.Cu")
		(net "LED_PWRGD_PVDDIO_P1_D")
	)
	(segment
		(start 343.574624 -72.884792)
		(end 342.923876 -72.234044)
		(width 0.10668)
		(layer "B.Cu")
		(net "LED_PWRGD_PVDDIO_P1_D")
	)
	(segment
		(start 342.923876 -72.234044)
		(end 342.923876 -71.868792)
		(width 0.10668)
		(layer "B.Cu")
		(net "LED_PWRGD_PVDDIO_P1_D")
	)
	(segment
		(start 330.731876 -68.328032)
		(end 330.731876 -69.623432)
		(width 0.10668)
		(layer "F.Cu")
		(net "LED_PWRGD_PVDDIO_P0_R")
	)
	(via
		(at 330.731876 -68.328032)
		(size 0.508)
		(drill 0.254)
		(layers "F.Cu" "B.Cu")
		(net "LED_PWRGD_PVDDIO_P0_R")
	)
	(segment
		(start 330.731876 -67.108832)
		(end 330.731876 -68.328032)
		(width 0.10668)
		(layer "B.Cu")
		(net "LED_PWRGD_PVDDIO_P0_R")
	)
	(segment
		(start 330.731876 -70.573392)
		(end 330.731876 -71.868792)
		(width 0.10668)
		(layer "F.Cu")
		(net "LED_PWRGD_PVDDIO_P0_D")
	)
	(via
		(at 330.731876 -71.868792)
		(size 0.762)
		(drill 0.254)
		(layers "F.Cu" "B.Cu")
		(net "LED_PWRGD_PVDDIO_P0_D")
	)
	(segment
		(start 332.070456 -72.317102)
		(end 332.070456 -74.063352)
		(width 0.10668)
		(layer "B.Cu")
		(net "LED_PWRGD_PVDDIO_P0_D")
	)
	(segment
		(start 332.070456 -74.063352)
		(end 331.949044 -74.184764)
		(width 0.10668)
		(layer "B.Cu")
		(net "LED_PWRGD_PVDDIO_P0_D")
	)
	(segment
		(start 331.622146 -71.868792)
		(end 332.070456 -72.317102)
		(width 0.10668)
		(layer "B.Cu")
		(net "LED_PWRGD_PVDDIO_P0_D")
	)
	(segment
		(start 331.949044 -74.184764)
		(end 331.514704 -74.184764)
		(width 0.10668)
		(layer "B.Cu")
		(net "LED_PWRGD_PVDDIO_P0_D")
	)
	(segment
		(start 330.731876 -71.868792)
		(end 331.622146 -71.868792)
		(width 0.10668)
		(layer "B.Cu")
		(net "LED_PWRGD_PVDDIO_P0_D")
	)
	(segment
		(start 338.859876 -68.328032)
		(end 338.859876 -69.623432)
		(width 0.10668)
		(layer "F.Cu")
		(net "LED_PWRGD_PVDDCR_SOC_P1_R")
	)
	(via
		(at 338.859876 -68.328032)
		(size 0.508)
		(drill 0.254)
		(layers "F.Cu" "B.Cu")
		(net "LED_PWRGD_PVDDCR_SOC_P1_R")
	)
	(segment
		(start 338.859876 -67.108832)
		(end 338.859876 -68.328032)
		(width 0.10668)
		(layer "B.Cu")
		(net "LED_PWRGD_PVDDCR_SOC_P1_R")
	)
	(segment
		(start 338.859876 -70.573392)
		(end 338.859876 -71.868792)
		(width 0.10668)
		(layer "F.Cu")
		(net "LED_PWRGD_PVDDCR_SOC_P1_D")
	)
	(via
		(at 338.859876 -71.868792)
		(size 0.762)
		(drill 0.254)
		(layers "F.Cu" "B.Cu")
		(net "LED_PWRGD_PVDDCR_SOC_P1_D")
	)
	(segment
		(start 338.859876 -72.234044)
		(end 338.859876 -71.868792)
		(width 0.10668)
		(layer "B.Cu")
		(net "LED_PWRGD_PVDDCR_SOC_P1_D")
	)
	(segment
		(start 339.510624 -72.884792)
		(end 338.859876 -72.234044)
		(width 0.10668)
		(layer "B.Cu")
		(net "LED_PWRGD_PVDDCR_SOC_P1_D")
	)
	(segment
		(start 326.667876 -68.328032)
		(end 326.667876 -69.623432)
		(width 0.10668)
		(layer "F.Cu")
		(net "LED_PWRGD_PVDDCR_SOC_P0_R")
	)
	(via
		(at 326.667876 -68.328032)
		(size 0.508)
		(drill 0.254)
		(layers "F.Cu" "B.Cu")
		(net "LED_PWRGD_PVDDCR_SOC_P0_R")
	)
	(segment
		(start 326.667876 -67.108832)
		(end 326.667876 -68.328032)
		(width 0.10668)
		(layer "B.Cu")
		(net "LED_PWRGD_PVDDCR_SOC_P0_R")
	)
	(segment
		(start 326.667876 -70.573392)
		(end 326.667876 -71.868792)
		(width 0.10668)
		(layer "F.Cu")
		(net "LED_PWRGD_PVDDCR_SOC_P0_D")
	)
	(via
		(at 326.667876 -71.868792)
		(size 0.762)
		(drill 0.254)
		(layers "F.Cu" "B.Cu")
		(net "LED_PWRGD_PVDDCR_SOC_P0_D")
	)
	(segment
		(start 327.885044 -74.184764)
		(end 327.450704 -74.184764)
		(width 0.10668)
		(layer "B.Cu")
		(net "LED_PWRGD_PVDDCR_SOC_P0_D")
	)
	(segment
		(start 328.006456 -72.317102)
		(end 328.006456 -74.063352)
		(width 0.10668)
		(layer "B.Cu")
		(net "LED_PWRGD_PVDDCR_SOC_P0_D")
	)
	(segment
		(start 328.006456 -74.063352)
		(end 327.885044 -74.184764)
		(width 0.10668)
		(layer "B.Cu")
		(net "LED_PWRGD_PVDDCR_SOC_P0_D")
	)
	(segment
		(start 327.558146 -71.868792)
		(end 328.006456 -72.317102)
		(width 0.10668)
		(layer "B.Cu")
		(net "LED_PWRGD_PVDDCR_SOC_P0_D")
	)
	(segment
		(start 326.667876 -71.868792)
		(end 327.558146 -71.868792)
		(width 0.10668)
		(layer "B.Cu")
		(net "LED_PWRGD_PVDDCR_SOC_P0_D")
	)
	(segment
		(start 340.891876 -68.328032)
		(end 340.891876 -69.623432)
		(width 0.10668)
		(layer "F.Cu")
		(net "LED_PWRGD_PVDDCR_CPU1_P1_R")
	)
	(via
		(at 340.891876 -68.328032)
		(size 0.508)
		(drill 0.254)
		(layers "F.Cu" "B.Cu")
		(net "LED_PWRGD_PVDDCR_CPU1_P1_R")
	)
	(segment
		(start 340.891876 -67.108832)
		(end 340.891876 -68.328032)
		(width 0.10668)
		(layer "B.Cu")
		(net "LED_PWRGD_PVDDCR_CPU1_P1_R")
	)
	(segment
		(start 340.891876 -70.573392)
		(end 340.891876 -71.868792)
		(width 0.10668)
		(layer "F.Cu")
		(net "LED_PWRGD_PVDDCR_CPU1_P1_D")
	)
	(via
		(at 340.891876 -71.868792)
		(size 0.762)
		(drill 0.254)
		(layers "F.Cu" "B.Cu")
		(net "LED_PWRGD_PVDDCR_CPU1_P1_D")
	)
	(segment
		(start 341.782146 -71.868792)
		(end 342.230456 -72.317102)
		(width 0.10668)
		(layer "B.Cu")
		(net "LED_PWRGD_PVDDCR_CPU1_P1_D")
	)
	(segment
		(start 342.109044 -74.184764)
		(end 341.674704 -74.184764)
		(width 0.10668)
		(layer "B.Cu")
		(net "LED_PWRGD_PVDDCR_CPU1_P1_D")
	)
	(segment
		(start 342.230456 -72.317102)
		(end 342.230456 -74.063352)
		(width 0.10668)
		(layer "B.Cu")
		(net "LED_PWRGD_PVDDCR_CPU1_P1_D")
	)
	(segment
		(start 342.230456 -74.063352)
		(end 342.109044 -74.184764)
		(width 0.10668)
		(layer "B.Cu")
		(net "LED_PWRGD_PVDDCR_CPU1_P1_D")
	)
	(segment
		(start 340.891876 -71.868792)
		(end 341.782146 -71.868792)
		(width 0.10668)
		(layer "B.Cu")
		(net "LED_PWRGD_PVDDCR_CPU1_P1_D")
	)
	(segment
		(start 328.699876 -68.328032)
		(end 328.699876 -69.623432)
		(width 0.10668)
		(layer "F.Cu")
		(net "LED_PWRGD_PVDDCR_CPU1_P0_R")
	)
	(via
		(at 328.699876 -68.328032)
		(size 0.508)
		(drill 0.254)
		(layers "F.Cu" "B.Cu")
		(net "LED_PWRGD_PVDDCR_CPU1_P0_R")
	)
	(segment
		(start 328.699876 -67.108832)
		(end 328.699876 -68.328032)
		(width 0.10668)
		(layer "B.Cu")
		(net "LED_PWRGD_PVDDCR_CPU1_P0_R")
	)
	(segment
		(start 328.699876 -70.573392)
		(end 328.699876 -71.868792)
		(width 0.10668)
		(layer "F.Cu")
		(net "LED_PWRGD_PVDDCR_CPU1_P0_D")
	)
	(via
		(at 328.699876 -71.868792)
		(size 0.762)
		(drill 0.254)
		(layers "F.Cu" "B.Cu")
		(net "LED_PWRGD_PVDDCR_CPU1_P0_D")
	)
	(segment
		(start 328.699876 -72.234044)
		(end 328.699876 -71.868792)
		(width 0.10668)
		(layer "B.Cu")
		(net "LED_PWRGD_PVDDCR_CPU1_P0_D")
	)
	(segment
		(start 329.350624 -72.884792)
		(end 328.699876 -72.234044)
		(width 0.10668)
		(layer "B.Cu")
		(net "LED_PWRGD_PVDDCR_CPU1_P0_D")
	)
	(segment
		(start 336.827876 -68.328032)
		(end 336.827876 -69.623432)
		(width 0.10668)
		(layer "F.Cu")
		(net "LED_PWRGD_PVDDCR_CPU0_P1_R")
	)
	(via
		(at 336.827876 -68.328032)
		(size 0.508)
		(drill 0.254)
		(layers "F.Cu" "B.Cu")
		(net "LED_PWRGD_PVDDCR_CPU0_P1_R")
	)
	(segment
		(start 336.827876 -67.108832)
		(end 336.827876 -68.328032)
		(width 0.10668)
		(layer "B.Cu")
		(net "LED_PWRGD_PVDDCR_CPU0_P1_R")
	)
	(segment
		(start 336.827876 -70.573392)
		(end 336.827876 -71.868792)
		(width 0.10668)
		(layer "F.Cu")
		(net "LED_PWRGD_PVDDCR_CPU0_P1_D")
	)
	(via
		(at 336.827876 -71.868792)
		(size 0.762)
		(drill 0.254)
		(layers "F.Cu" "B.Cu")
		(net "LED_PWRGD_PVDDCR_CPU0_P1_D")
	)
	(segment
		(start 338.166456 -72.317102)
		(end 338.166456 -74.063352)
		(width 0.10668)
		(layer "B.Cu")
		(net "LED_PWRGD_PVDDCR_CPU0_P1_D")
	)
	(segment
		(start 338.166456 -74.063352)
		(end 338.045044 -74.184764)
		(width 0.10668)
		(layer "B.Cu")
		(net "LED_PWRGD_PVDDCR_CPU0_P1_D")
	)
	(segment
		(start 337.718146 -71.868792)
		(end 338.166456 -72.317102)
		(width 0.10668)
		(layer "B.Cu")
		(net "LED_PWRGD_PVDDCR_CPU0_P1_D")
	)
	(segment
		(start 336.827876 -71.868792)
		(end 337.718146 -71.868792)
		(width 0.10668)
		(layer "B.Cu")
		(net "LED_PWRGD_PVDDCR_CPU0_P1_D")
	)
	(segment
		(start 338.045044 -74.184764)
		(end 337.610704 -74.184764)
		(width 0.10668)
		(layer "B.Cu")
		(net "LED_PWRGD_PVDDCR_CPU0_P1_D")
	)
	(segment
		(start 324.635876 -68.328032)
		(end 324.635876 -69.623432)
		(width 0.10668)
		(layer "F.Cu")
		(net "LED_PWRGD_PVDDCR_CPU0_P0_R")
	)
	(via
		(at 324.635876 -68.328032)
		(size 0.508)
		(drill 0.254)
		(layers "F.Cu" "B.Cu")
		(net "LED_PWRGD_PVDDCR_CPU0_P0_R")
	)
	(segment
		(start 324.635876 -67.108832)
		(end 324.635876 -68.328032)
		(width 0.10668)
		(layer "B.Cu")
		(net "LED_PWRGD_PVDDCR_CPU0_P0_R")
	)
	(segment
		(start 324.635876 -70.573392)
		(end 324.635876 -71.868792)
		(width 0.10668)
		(layer "F.Cu")
		(net "LED_PWRGD_PVDDCR_CPU0_P0_D")
	)
	(via
		(at 324.635876 -71.868792)
		(size 0.762)
		(drill 0.254)
		(layers "F.Cu" "B.Cu")
		(net "LED_PWRGD_PVDDCR_CPU0_P0_D")
	)
	(segment
		(start 325.286624 -72.884792)
		(end 324.635876 -72.234044)
		(width 0.10668)
		(layer "B.Cu")
		(net "LED_PWRGD_PVDDCR_CPU0_P0_D")
	)
	(segment
		(start 324.635876 -72.234044)
		(end 324.635876 -71.868792)
		(width 0.10668)
		(layer "B.Cu")
		(net "LED_PWRGD_PVDDCR_CPU0_P0_D")
	)
	(segment
		(start 322.603876 -68.328032)
		(end 322.603876 -69.623432)
		(width 0.10668)
		(layer "F.Cu")
		(net "LED_PWRGD_PVDD33_S5_R")
	)
	(via
		(at 322.603876 -68.328032)
		(size 0.508)
		(drill 0.254)
		(layers "F.Cu" "B.Cu")
		(net "LED_PWRGD_PVDD33_S5_R")
	)
	(segment
		(start 322.603876 -67.108832)
		(end 322.603876 -68.328032)
		(width 0.10668)
		(layer "B.Cu")
		(net "LED_PWRGD_PVDD33_S5_R")
	)
	(segment
		(start 322.603876 -70.573392)
		(end 322.603876 -71.868792)
		(width 0.10668)
		(layer "F.Cu")
		(net "LED_PWRGD_PVDD33_S5_D")
	)
	(via
		(at 322.603876 -71.868792)
		(size 0.762)
		(drill 0.254)
		(layers "F.Cu" "B.Cu")
		(net "LED_PWRGD_PVDD33_S5_D")
	)
	(segment
		(start 323.821044 -74.184764)
		(end 323.386704 -74.184764)
		(width 0.10668)
		(layer "B.Cu")
		(net "LED_PWRGD_PVDD33_S5_D")
	)
	(segment
		(start 323.942456 -72.317102)
		(end 323.942456 -74.063352)
		(width 0.10668)
		(layer "B.Cu")
		(net "LED_PWRGD_PVDD33_S5_D")
	)
	(segment
		(start 323.942456 -74.063352)
		(end 323.821044 -74.184764)
		(width 0.10668)
		(layer "B.Cu")
		(net "LED_PWRGD_PVDD33_S5_D")
	)
	(segment
		(start 322.603876 -71.868792)
		(end 323.494146 -71.868792)
		(width 0.10668)
		(layer "B.Cu")
		(net "LED_PWRGD_PVDD33_S5_D")
	)
	(segment
		(start 323.494146 -71.868792)
		(end 323.942456 -72.317102)
		(width 0.10668)
		(layer "B.Cu")
		(net "LED_PWRGD_PVDD33_S5_D")
	)
	(segment
		(start 346.987876 -68.328032)
		(end 346.987876 -69.623432)
		(width 0.10668)
		(layer "F.Cu")
		(net "LED_PWRGD_PVDD18_S5_P1_R")
	)
	(via
		(at 346.987876 -68.328032)
		(size 0.508)
		(drill 0.254)
		(layers "F.Cu" "B.Cu")
		(net "LED_PWRGD_PVDD18_S5_P1_R")
	)
	(segment
		(start 346.987876 -67.108832)
		(end 346.987876 -68.328032)
		(width 0.10668)
		(layer "B.Cu")
		(net "LED_PWRGD_PVDD18_S5_P1_R")
	)
	(segment
		(start 346.987876 -70.573392)
		(end 346.987876 -71.868792)
		(width 0.10668)
		(layer "F.Cu")
		(net "LED_PWRGD_PVDD18_S5_P1_D")
	)
	(via
		(at 346.987876 -71.868792)
		(size 0.762)
		(drill 0.254)
		(layers "F.Cu" "B.Cu")
		(net "LED_PWRGD_PVDD18_S5_P1_D")
	)
	(segment
		(start 346.987876 -72.234044)
		(end 346.987876 -71.868792)
		(width 0.10668)
		(layer "B.Cu")
		(net "LED_PWRGD_PVDD18_S5_P1_D")
	)
	(segment
		(start 347.638624 -72.884792)
		(end 346.987876 -72.234044)
		(width 0.10668)
		(layer "B.Cu")
		(net "LED_PWRGD_PVDD18_S5_P1_D")
	)
	(segment
		(start 334.795876 -68.328032)
		(end 334.795876 -69.623432)
		(width 0.10668)
		(layer "F.Cu")
		(net "LED_PWRGD_PVDD18_S5_P0_R")
	)
	(via
		(at 334.795876 -68.328032)
		(size 0.508)
		(drill 0.254)
		(layers "F.Cu" "B.Cu")
		(net "LED_PWRGD_PVDD18_S5_P0_R")
	)
	(segment
		(start 334.795876 -67.108832)
		(end 334.795876 -68.328032)
		(width 0.10668)
		(layer "B.Cu")
		(net "LED_PWRGD_PVDD18_S5_P0_R")
	)
	(segment
		(start 334.795876 -70.573392)
		(end 334.795876 -71.868792)
		(width 0.10668)
		(layer "F.Cu")
		(net "LED_PWRGD_PVDD18_S5_P0_D")
	)
	(via
		(at 334.795876 -71.868792)
		(size 0.762)
		(drill 0.254)
		(layers "F.Cu" "B.Cu")
		(net "LED_PWRGD_PVDD18_S5_P0_D")
	)
	(segment
		(start 333.266796 -75.708764)
		(end 334.795876 -74.179684)
		(width 0.10668)
		(layer "B.Cu")
		(net "LED_PWRGD_PVDD18_S5_P0_D")
	)
	(segment
		(start 334.795876 -74.179684)
		(end 334.795876 -71.868792)
		(width 0.10668)
		(layer "B.Cu")
		(net "LED_PWRGD_PVDD18_S5_P0_D")
	)
	(segment
		(start 344.955876 -68.328032)
		(end 344.955876 -69.623432)
		(width 0.10668)
		(layer "F.Cu")
		(net "LED_PWRGD_PVDD11_S3_P1_R")
	)
	(via
		(at 344.955876 -68.328032)
		(size 0.508)
		(drill 0.254)
		(layers "F.Cu" "B.Cu")
		(net "LED_PWRGD_PVDD11_S3_P1_R")
	)
	(segment
		(start 344.955876 -67.108832)
		(end 344.955876 -68.328032)
		(width 0.10668)
		(layer "B.Cu")
		(net "LED_PWRGD_PVDD11_S3_P1_R")
	)
	(segment
		(start 344.955876 -70.573392)
		(end 344.955876 -71.868792)
		(width 0.10668)
		(layer "F.Cu")
		(net "LED_PWRGD_PVDD11_S3_P1_D")
	)
	(via
		(at 344.955876 -71.868792)
		(size 0.762)
		(drill 0.254)
		(layers "F.Cu" "B.Cu")
		(net "LED_PWRGD_PVDD11_S3_P1_D")
	)
	(segment
		(start 345.846146 -71.868792)
		(end 346.294456 -72.317102)
		(width 0.10668)
		(layer "B.Cu")
		(net "LED_PWRGD_PVDD11_S3_P1_D")
	)
	(segment
		(start 346.294456 -74.063352)
		(end 346.173044 -74.184764)
		(width 0.10668)
		(layer "B.Cu")
		(net "LED_PWRGD_PVDD11_S3_P1_D")
	)
	(segment
		(start 346.173044 -74.184764)
		(end 345.738704 -74.184764)
		(width 0.10668)
		(layer "B.Cu")
		(net "LED_PWRGD_PVDD11_S3_P1_D")
	)
	(segment
		(start 346.294456 -72.317102)
		(end 346.294456 -74.063352)
		(width 0.10668)
		(layer "B.Cu")
		(net "LED_PWRGD_PVDD11_S3_P1_D")
	)
	(segment
		(start 344.955876 -71.868792)
		(end 345.846146 -71.868792)
		(width 0.10668)
		(layer "B.Cu")
		(net "LED_PWRGD_PVDD11_S3_P1_D")
	)
	(segment
		(start 332.763876 -68.328032)
		(end 332.763876 -69.623432)
		(width 0.10668)
		(layer "F.Cu")
		(net "LED_PWRGD_PVDD11_S3_P0_R")
	)
	(via
		(at 332.763876 -68.328032)
		(size 0.508)
		(drill 0.254)
		(layers "F.Cu" "B.Cu")
		(net "LED_PWRGD_PVDD11_S3_P0_R")
	)
	(segment
		(start 332.763876 -67.108832)
		(end 332.763876 -68.328032)
		(width 0.10668)
		(layer "B.Cu")
		(net "LED_PWRGD_PVDD11_S3_P0_R")
	)
	(segment
		(start 332.763876 -70.573392)
		(end 332.763876 -71.868792)
		(width 0.10668)
		(layer "F.Cu")
		(net "LED_PWRGD_PVDD11_S3_P0_D")
	)
	(via
		(at 332.763876 -71.868792)
		(size 0.762)
		(drill 0.254)
		(layers "F.Cu" "B.Cu")
		(net "LED_PWRGD_PVDD11_S3_P0_D")
	)
	(segment
		(start 333.414624 -72.884792)
		(end 332.763876 -72.234044)
		(width 0.10668)
		(layer "B.Cu")
		(net "LED_PWRGD_PVDD11_S3_P0_D")
	)
	(segment
		(start 332.763876 -72.234044)
		(end 332.763876 -71.868792)
		(width 0.10668)
		(layer "B.Cu")
		(net "LED_PWRGD_PVDD11_S3_P0_D")
	)
	(segment
		(start 124.87529 -54.775608)
		(end 125.512576 -54.775608)
		(width 0.10668)
		(layer "F.Cu")
		(net "JTAG_TDO_R1")
	)
	(segment
		(start 124.027438 -54.775608)
		(end 124.87529 -54.775608)
		(width 0.10668)
		(layer "F.Cu")
		(net "JTAG_TDO_R1")
	)
	(segment
		(start 145.374868 -57.275984)
		(end 144.527016 -57.275984)
		(width 0.10668)
		(layer "F.Cu")
		(net "JTAG_TDO_R1")
	)
	(via
		(at 124.87529 -54.775608)
		(size 0.508)
		(drill 0.254)
		(layers "F.Cu" "B.Cu")
		(net "JTAG_TDO_R1")
	)
	(via
		(at 144.527016 -57.275984)
		(size 0.508)
		(drill 0.254)
		(layers "F.Cu" "B.Cu")
		(net "JTAG_TDO_R1")
	)
	(segment
		(start 144.527016 -57.275984)
		(end 145.13941 -56.66359)
		(width 0.10668)
		(layer "B.Cu")
		(net "JTAG_TDO_R1")
	)
	(segment
		(start 124.2695 -54.169818)
		(end 124.87529 -54.775608)
		(width 0.10668)
		(layer "B.Cu")
		(net "JTAG_TDO_R1")
	)
	(segment
		(start 145.13941 -56.12003)
		(end 144.89176 -55.87238)
		(width 0.10668)
		(layer "B.Cu")
		(net "JTAG_TDO_R1")
	)
	(segment
		(start 141.3002 -55.72252)
		(end 139.80922 -54.23154)
		(width 0.10668)
		(layer "B.Cu")
		(net "JTAG_TDO_R1")
	)
	(segment
		(start 124.2695 -52.338732)
		(end 124.2695 -54.169818)
		(width 0.10668)
		(layer "B.Cu")
		(net "JTAG_TDO_R1")
	)
	(segment
		(start 128.902968 -47.705264)
		(end 124.2695 -52.338732)
		(width 0.10668)
		(layer "B.Cu")
		(net "JTAG_TDO_R1")
	)
	(segment
		(start 132.233924 -47.705264)
		(end 128.902968 -47.705264)
		(width 0.10668)
		(layer "B.Cu")
		(net "JTAG_TDO_R1")
	)
	(segment
		(start 138.7602 -54.23154)
		(end 132.233924 -47.705264)
		(width 0.10668)
		(layer "B.Cu")
		(net "JTAG_TDO_R1")
	)
	(segment
		(start 145.13941 -56.66359)
		(end 145.13941 -56.12003)
		(width 0.10668)
		(layer "B.Cu")
		(net "JTAG_TDO_R1")
	)
	(segment
		(start 144.52981 -55.72252)
		(end 141.3002 -55.72252)
		(width 0.10668)
		(layer "B.Cu")
		(net "JTAG_TDO_R1")
	)
	(segment
		(start 139.80922 -54.23154)
		(end 138.7602 -54.23154)
		(width 0.10668)
		(layer "B.Cu")
		(net "JTAG_TDO_R1")
	)
	(segment
		(start 144.89176 -55.87238)
		(end 144.52981 -55.72252)
		(width 0.10668)
		(layer "B.Cu")
		(net "JTAG_TDO_R1")
	)
	(segment
		(start 177.122074 -120.252744)
		(end 175.7426 -120.252744)
		(width 0.10668)
		(layer "F.Cu")
		(net "FM_LED_PWRGD_PVDDIO_P1")
	)
	(segment
		(start 175.7426 -120.252744)
		(end 174.618396 -121.376948)
		(width 0.10668)
		(layer "F.Cu")
		(net "FM_LED_PWRGD_PVDDIO_P1")
	)
	(segment
		(start 174.618396 -121.376948)
		(end 173.9392 -121.376948)
		(width 0.10668)
		(layer "F.Cu")
		(net "FM_LED_PWRGD_PVDDIO_P1")
	)
	(via
		(at 340.891876 -74.184764)
		(size 0.762)
		(drill 0.254)
		(layers "F.Cu" "B.Cu")
		(net "FM_LED_PWRGD_PVDDIO_P1")
	)
	(via
		(at 173.9392 -121.376948)
		(size 0.508)
		(drill 0.254)
		(layers "F.Cu" "B.Cu")
		(net "FM_LED_PWRGD_PVDDIO_P1")
	)
	(via
		(at 171.351194 -87.798148)
		(size 0.508)
		(drill 0.254)
		(layers "F.Cu" "B.Cu")
		(net "FM_LED_PWRGD_PVDDIO_P1")
	)
	(segment
		(start 340.891876 -74.184764)
		(end 340.891876 -73.861422)
		(width 0.10668)
		(layer "B.Cu")
		(net "FM_LED_PWRGD_PVDDIO_P1")
	)
	(segment
		(start 341.21852 -73.534778)
		(end 341.674704 -73.534778)
		(width 0.10668)
		(layer "B.Cu")
		(net "FM_LED_PWRGD_PVDDIO_P1")
	)
	(segment
		(start 340.891876 -73.861422)
		(end 341.21852 -73.534778)
		(width 0.10668)
		(layer "B.Cu")
		(net "FM_LED_PWRGD_PVDDIO_P1")
	)
	(segment
		(start 173.9392 -115.7605)
		(end 172.9359 -114.7572)
		(width 0.11684)
		(layer "In11.Cu")
		(net "FM_LED_PWRGD_PVDDIO_P1")
	)
	(segment
		(start 169.897806 -104.32034)
		(end 168.80586 -103.228394)
		(width 0.11684)
		(layer "In11.Cu")
		(net "FM_LED_PWRGD_PVDDIO_P1")
	)
	(segment
		(start 168.0972 -96.189292)
		(end 167.848534 -95.940626)
		(width 0.11684)
		(layer "In11.Cu")
		(net "FM_LED_PWRGD_PVDDIO_P1")
	)
	(segment
		(start 168.80586 -99.155504)
		(end 168.0972 -98.446844)
		(width 0.11684)
		(layer "In11.Cu")
		(net "FM_LED_PWRGD_PVDDIO_P1")
	)
	(segment
		(start 171.425108 -87.958168)
		(end 171.351194 -87.884254)
		(width 0.11684)
		(layer "In11.Cu")
		(net "FM_LED_PWRGD_PVDDIO_P1")
	)
	(segment
		(start 167.848534 -95.124778)
		(end 168.607232 -94.36608)
		(width 0.11684)
		(layer "In11.Cu")
		(net "FM_LED_PWRGD_PVDDIO_P1")
	)
	(segment
		(start 170.570398 -104.32034)
		(end 169.897806 -104.32034)
		(width 0.11684)
		(layer "In11.Cu")
		(net "FM_LED_PWRGD_PVDDIO_P1")
	)
	(segment
		(start 168.607232 -90.941652)
		(end 171.425108 -88.123776)
		(width 0.11684)
		(layer "In11.Cu")
		(net "FM_LED_PWRGD_PVDDIO_P1")
	)
	(segment
		(start 173.9392 -121.376948)
		(end 173.9392 -115.7605)
		(width 0.11684)
		(layer "In11.Cu")
		(net "FM_LED_PWRGD_PVDDIO_P1")
	)
	(segment
		(start 168.607232 -94.36608)
		(end 168.607232 -90.941652)
		(width 0.11684)
		(layer "In11.Cu")
		(net "FM_LED_PWRGD_PVDDIO_P1")
	)
	(segment
		(start 168.0972 -98.446844)
		(end 168.0972 -96.189292)
		(width 0.11684)
		(layer "In11.Cu")
		(net "FM_LED_PWRGD_PVDDIO_P1")
	)
	(segment
		(start 171.658026 -108.706158)
		(end 171.658026 -105.407968)
		(width 0.11684)
		(layer "In11.Cu")
		(net "FM_LED_PWRGD_PVDDIO_P1")
	)
	(segment
		(start 171.351194 -87.884254)
		(end 171.351194 -87.798148)
		(width 0.11684)
		(layer "In11.Cu")
		(net "FM_LED_PWRGD_PVDDIO_P1")
	)
	(segment
		(start 172.9359 -114.7572)
		(end 172.9359 -109.984032)
		(width 0.11684)
		(layer "In11.Cu")
		(net "FM_LED_PWRGD_PVDDIO_P1")
	)
	(segment
		(start 168.80586 -103.228394)
		(end 168.80586 -99.155504)
		(width 0.11684)
		(layer "In11.Cu")
		(net "FM_LED_PWRGD_PVDDIO_P1")
	)
	(segment
		(start 171.425108 -88.123776)
		(end 171.425108 -87.958168)
		(width 0.11684)
		(layer "In11.Cu")
		(net "FM_LED_PWRGD_PVDDIO_P1")
	)
	(segment
		(start 171.658026 -105.407968)
		(end 170.570398 -104.32034)
		(width 0.11684)
		(layer "In11.Cu")
		(net "FM_LED_PWRGD_PVDDIO_P1")
	)
	(segment
		(start 172.9359 -109.984032)
		(end 171.658026 -108.706158)
		(width 0.11684)
		(layer "In11.Cu")
		(net "FM_LED_PWRGD_PVDDIO_P1")
	)
	(segment
		(start 167.848534 -95.940626)
		(end 167.848534 -95.124778)
		(width 0.11684)
		(layer "In11.Cu")
		(net "FM_LED_PWRGD_PVDDIO_P1")
	)
	(segment
		(start 188.83249 -94.451678)
		(end 189.381892 -93.902276)
		(width 0.11684)
		(layer "In15.Cu")
		(net "FM_LED_PWRGD_PVDDIO_P1")
	)
	(segment
		(start 183.262016 -90.724482)
		(end 183.262016 -91.984068)
		(width 0.11684)
		(layer "In15.Cu")
		(net "FM_LED_PWRGD_PVDDIO_P1")
	)
	(segment
		(start 189.841378 -92.735654)
		(end 194.569842 -92.735654)
		(width 0.11684)
		(layer "In15.Cu")
		(net "FM_LED_PWRGD_PVDDIO_P1")
	)
	(segment
		(start 171.351194 -87.486236)
		(end 171.143422 -87.278464)
		(width 0.11684)
		(layer "In15.Cu")
		(net "FM_LED_PWRGD_PVDDIO_P1")
	)
	(segment
		(start 200.999598 -101.01453)
		(end 200.999598 -102.066852)
		(width 0.11684)
		(layer "In15.Cu")
		(net "FM_LED_PWRGD_PVDDIO_P1")
	)
	(segment
		(start 189.381892 -93.19514)
		(end 189.841378 -92.735654)
		(width 0.11684)
		(layer "In15.Cu")
		(net "FM_LED_PWRGD_PVDDIO_P1")
	)
	(segment
		(start 171.143422 -87.278464)
		(end 170.430444 -87.278464)
		(width 0.11684)
		(layer "In15.Cu")
		(net "FM_LED_PWRGD_PVDDIO_P1")
	)
	(segment
		(start 198.046594 -98.061526)
		(end 200.999598 -101.01453)
		(width 0.11684)
		(layer "In15.Cu")
		(net "FM_LED_PWRGD_PVDDIO_P1")
	)
	(segment
		(start 198.046594 -96.212406)
		(end 198.046594 -98.061526)
		(width 0.11684)
		(layer "In15.Cu")
		(net "FM_LED_PWRGD_PVDDIO_P1")
	)
	(segment
		(start 215.92667 -102.479094)
		(end 216.619836 -103.17226)
		(width 0.11684)
		(layer "In15.Cu")
		(net "FM_LED_PWRGD_PVDDIO_P1")
	)
	(segment
		(start 182.767224 -90.22969)
		(end 183.262016 -90.724482)
		(width 0.11684)
		(layer "In15.Cu")
		(net "FM_LED_PWRGD_PVDDIO_P1")
	)
	(segment
		(start 194.569842 -92.735654)
		(end 198.046594 -96.212406)
		(width 0.11684)
		(layer "In15.Cu")
		(net "FM_LED_PWRGD_PVDDIO_P1")
	)
	(segment
		(start 248.279158 -87.665052)
		(end 327.411588 -87.665052)
		(width 0.11684)
		(layer "In15.Cu")
		(net "FM_LED_PWRGD_PVDDIO_P1")
	)
	(segment
		(start 200.999598 -102.066852)
		(end 202.502008 -103.569262)
		(width 0.11684)
		(layer "In15.Cu")
		(net "FM_LED_PWRGD_PVDDIO_P1")
	)
	(segment
		(start 188.32322 -94.793308)
		(end 188.66485 -94.451678)
		(width 0.11684)
		(layer "In15.Cu")
		(net "FM_LED_PWRGD_PVDDIO_P1")
	)
	(segment
		(start 202.502008 -103.569262)
		(end 210.212432 -103.569262)
		(width 0.11684)
		(layer "In15.Cu")
		(net "FM_LED_PWRGD_PVDDIO_P1")
	)
	(segment
		(start 210.212432 -103.569262)
		(end 211.3026 -102.479094)
		(width 0.11684)
		(layer "In15.Cu")
		(net "FM_LED_PWRGD_PVDDIO_P1")
	)
	(segment
		(start 189.381892 -93.902276)
		(end 189.381892 -93.19514)
		(width 0.11684)
		(layer "In15.Cu")
		(net "FM_LED_PWRGD_PVDDIO_P1")
	)
	(segment
		(start 188.66485 -94.451678)
		(end 188.83249 -94.451678)
		(width 0.11684)
		(layer "In15.Cu")
		(net "FM_LED_PWRGD_PVDDIO_P1")
	)
	(segment
		(start 170.12158 -88.443816)
		(end 171.907454 -90.22969)
		(width 0.11684)
		(layer "In15.Cu")
		(net "FM_LED_PWRGD_PVDDIO_P1")
	)
	(segment
		(start 216.619836 -103.17226)
		(end 232.77195 -103.17226)
		(width 0.11684)
		(layer "In15.Cu")
		(net "FM_LED_PWRGD_PVDDIO_P1")
	)
	(segment
		(start 188.32322 -95.255334)
		(end 188.32322 -94.793308)
		(width 0.11684)
		(layer "In15.Cu")
		(net "FM_LED_PWRGD_PVDDIO_P1")
	)
	(segment
		(start 170.430444 -87.278464)
		(end 170.12158 -87.587328)
		(width 0.11684)
		(layer "In15.Cu")
		(net "FM_LED_PWRGD_PVDDIO_P1")
	)
	(segment
		(start 185.531506 -95.609156)
		(end 187.969398 -95.609156)
		(width 0.11684)
		(layer "In15.Cu")
		(net "FM_LED_PWRGD_PVDDIO_P1")
	)
	(segment
		(start 170.12158 -87.587328)
		(end 170.12158 -88.443816)
		(width 0.11684)
		(layer "In15.Cu")
		(net "FM_LED_PWRGD_PVDDIO_P1")
	)
	(segment
		(start 171.351194 -87.798148)
		(end 171.351194 -87.486236)
		(width 0.11684)
		(layer "In15.Cu")
		(net "FM_LED_PWRGD_PVDDIO_P1")
	)
	(segment
		(start 183.262016 -91.984068)
		(end 184.296304 -93.018356)
		(width 0.11684)
		(layer "In15.Cu")
		(net "FM_LED_PWRGD_PVDDIO_P1")
	)
	(segment
		(start 171.907454 -90.22969)
		(end 182.767224 -90.22969)
		(width 0.11684)
		(layer "In15.Cu")
		(net "FM_LED_PWRGD_PVDDIO_P1")
	)
	(segment
		(start 232.77195 -103.17226)
		(end 248.279158 -87.665052)
		(width 0.11684)
		(layer "In15.Cu")
		(net "FM_LED_PWRGD_PVDDIO_P1")
	)
	(segment
		(start 184.296304 -94.373954)
		(end 185.531506 -95.609156)
		(width 0.11684)
		(layer "In15.Cu")
		(net "FM_LED_PWRGD_PVDDIO_P1")
	)
	(segment
		(start 187.969398 -95.609156)
		(end 188.32322 -95.255334)
		(width 0.11684)
		(layer "In15.Cu")
		(net "FM_LED_PWRGD_PVDDIO_P1")
	)
	(segment
		(start 184.296304 -93.018356)
		(end 184.296304 -94.373954)
		(width 0.11684)
		(layer "In15.Cu")
		(net "FM_LED_PWRGD_PVDDIO_P1")
	)
	(segment
		(start 211.3026 -102.479094)
		(end 215.92667 -102.479094)
		(width 0.11684)
		(layer "In15.Cu")
		(net "FM_LED_PWRGD_PVDDIO_P1")
	)
	(segment
		(start 327.411588 -87.665052)
		(end 340.891876 -74.184764)
		(width 0.11684)
		(layer "In15.Cu")
		(net "FM_LED_PWRGD_PVDDIO_P1")
	)
	(segment
		(start 192.322196 -114.652806)
		(end 192.712086 -114.262916)
		(width 0.10668)
		(layer "F.Cu")
		(net "FM_LED_PWRGD_PVDDIO_P0")
	)
	(via
		(at 192.712086 -114.262916)
		(size 0.4572)
		(drill 0.254)
		(layers "F.Cu" "B.Cu")
		(net "FM_LED_PWRGD_PVDDIO_P0")
	)
	(via
		(at 332.763876 -73.138792)
		(size 0.762)
		(drill 0.254)
		(layers "F.Cu" "B.Cu")
		(net "FM_LED_PWRGD_PVDDIO_P0")
	)
	(via
		(at 210.384644 -101.998018)
		(size 0.508)
		(drill 0.254)
		(layers "F.Cu" "B.Cu")
		(net "FM_LED_PWRGD_PVDDIO_P0")
	)
	(via
		(at 209.011012 -113.39195)
		(size 0.508)
		(drill 0.254)
		(layers "F.Cu" "B.Cu")
		(net "FM_LED_PWRGD_PVDDIO_P0")
	)
	(segment
		(start 332.763876 -73.138792)
		(end 332.763876 -73.293224)
		(width 0.10668)
		(layer "B.Cu")
		(net "FM_LED_PWRGD_PVDDIO_P0")
	)
	(segment
		(start 333.00543 -73.534778)
		(end 333.414624 -73.534778)
		(width 0.10668)
		(layer "B.Cu")
		(net "FM_LED_PWRGD_PVDDIO_P0")
	)
	(segment
		(start 332.763876 -73.293224)
		(end 333.00543 -73.534778)
		(width 0.10668)
		(layer "B.Cu")
		(net "FM_LED_PWRGD_PVDDIO_P0")
	)
	(segment
		(start 210.751928 -103.319834)
		(end 210.751928 -102.365302)
		(width 0.11684)
		(layer "In4.Cu")
		(net "FM_LED_PWRGD_PVDDIO_P0")
	)
	(segment
		(start 209.011012 -105.06075)
		(end 210.751928 -103.319834)
		(width 0.11684)
		(layer "In4.Cu")
		(net "FM_LED_PWRGD_PVDDIO_P0")
	)
	(segment
		(start 210.751928 -102.365302)
		(end 210.384644 -101.998018)
		(width 0.11684)
		(layer "In4.Cu")
		(net "FM_LED_PWRGD_PVDDIO_P0")
	)
	(segment
		(start 209.011012 -113.39195)
		(end 209.011012 -105.06075)
		(width 0.11684)
		(layer "In4.Cu")
		(net "FM_LED_PWRGD_PVDDIO_P0")
	)
	(segment
		(start 198.375524 -114.144552)
		(end 202.979782 -114.144552)
		(width 0.11684)
		(layer "In6.Cu")
		(net "FM_LED_PWRGD_PVDDIO_P0")
	)
	(segment
		(start 203.510134 -113.6142)
		(end 208.788762 -113.6142)
		(width 0.11684)
		(layer "In6.Cu")
		(net "FM_LED_PWRGD_PVDDIO_P0")
	)
	(segment
		(start 192.796414 -114.178588)
		(end 198.341488 -114.178588)
		(width 0.11684)
		(layer "In6.Cu")
		(net "FM_LED_PWRGD_PVDDIO_P0")
	)
	(segment
		(start 208.788762 -113.6142)
		(end 209.011012 -113.39195)
		(width 0.11684)
		(layer "In6.Cu")
		(net "FM_LED_PWRGD_PVDDIO_P0")
	)
	(segment
		(start 198.341488 -114.178588)
		(end 198.375524 -114.144552)
		(width 0.11684)
		(layer "In6.Cu")
		(net "FM_LED_PWRGD_PVDDIO_P0")
	)
	(segment
		(start 192.712086 -114.262916)
		(end 192.796414 -114.178588)
		(width 0.11684)
		(layer "In6.Cu")
		(net "FM_LED_PWRGD_PVDDIO_P0")
	)
	(segment
		(start 202.979782 -114.144552)
		(end 203.510134 -113.6142)
		(width 0.11684)
		(layer "In6.Cu")
		(net "FM_LED_PWRGD_PVDDIO_P0")
	)
	(segment
		(start 325.222362 -74.58964)
		(end 326.806306 -76.173584)
		(width 0.11684)
		(layer "In15.Cu")
		(net "FM_LED_PWRGD_PVDDIO_P0")
	)
	(segment
		(start 323.527674 -73.262744)
		(end 324.116446 -72.673972)
		(width 0.11684)
		(layer "In15.Cu")
		(net "FM_LED_PWRGD_PVDDIO_P0")
	)
	(segment
		(start 232.97769 -100.2284)
		(end 247.381776 -85.824314)
		(width 0.11684)
		(layer "In15.Cu")
		(net "FM_LED_PWRGD_PVDDIO_P0")
	)
	(segment
		(start 247.381776 -85.824314)
		(end 312.59653 -85.824314)
		(width 0.11684)
		(layer "In15.Cu")
		(net "FM_LED_PWRGD_PVDDIO_P0")
	)
	(segment
		(start 213.003638 -100.2284)
		(end 232.97769 -100.2284)
		(width 0.11684)
		(layer "In15.Cu")
		(net "FM_LED_PWRGD_PVDDIO_P0")
	)
	(segment
		(start 331.734922 -74.167746)
		(end 332.763876 -73.138792)
		(width 0.11684)
		(layer "In15.Cu")
		(net "FM_LED_PWRGD_PVDDIO_P0")
	)
	(segment
		(start 326.806306 -76.173584)
		(end 330.924662 -76.173584)
		(width 0.11684)
		(layer "In15.Cu")
		(net "FM_LED_PWRGD_PVDDIO_P0")
	)
	(segment
		(start 324.828662 -72.673972)
		(end 325.222362 -73.067672)
		(width 0.11684)
		(layer "In15.Cu")
		(net "FM_LED_PWRGD_PVDDIO_P0")
	)
	(segment
		(start 211.944204 -101.287834)
		(end 213.003638 -100.2284)
		(width 0.11684)
		(layer "In15.Cu")
		(net "FM_LED_PWRGD_PVDDIO_P0")
	)
	(segment
		(start 325.222362 -73.067672)
		(end 325.222362 -74.58964)
		(width 0.11684)
		(layer "In15.Cu")
		(net "FM_LED_PWRGD_PVDDIO_P0")
	)
	(segment
		(start 312.59653 -85.824314)
		(end 323.527674 -74.89317)
		(width 0.11684)
		(layer "In15.Cu")
		(net "FM_LED_PWRGD_PVDDIO_P0")
	)
	(segment
		(start 211.094828 -101.287834)
		(end 211.944204 -101.287834)
		(width 0.11684)
		(layer "In15.Cu")
		(net "FM_LED_PWRGD_PVDDIO_P0")
	)
	(segment
		(start 210.384644 -101.998018)
		(end 211.094828 -101.287834)
		(width 0.11684)
		(layer "In15.Cu")
		(net "FM_LED_PWRGD_PVDDIO_P0")
	)
	(segment
		(start 331.734922 -75.363324)
		(end 331.734922 -74.167746)
		(width 0.11684)
		(layer "In15.Cu")
		(net "FM_LED_PWRGD_PVDDIO_P0")
	)
	(segment
		(start 323.527674 -74.89317)
		(end 323.527674 -73.262744)
		(width 0.11684)
		(layer "In15.Cu")
		(net "FM_LED_PWRGD_PVDDIO_P0")
	)
	(segment
		(start 330.924662 -76.173584)
		(end 331.734922 -75.363324)
		(width 0.11684)
		(layer "In15.Cu")
		(net "FM_LED_PWRGD_PVDDIO_P0")
	)
	(segment
		(start 324.116446 -72.673972)
		(end 324.828662 -72.673972)
		(width 0.11684)
		(layer "In15.Cu")
		(net "FM_LED_PWRGD_PVDDIO_P0")
	)
	(segment
		(start 177.521362 -120.653556)
		(end 176.148238 -120.653556)
		(width 0.10668)
		(layer "F.Cu")
		(net "FM_LED_PWRGD_PVDDCR_SOC_P1")
	)
	(segment
		(start 177.922174 -120.252744)
		(end 177.521362 -120.653556)
		(width 0.10668)
		(layer "F.Cu")
		(net "FM_LED_PWRGD_PVDDCR_SOC_P1")
	)
	(segment
		(start 176.148238 -120.653556)
		(end 174.408846 -122.392948)
		(width 0.10668)
		(layer "F.Cu")
		(net "FM_LED_PWRGD_PVDDCR_SOC_P1")
	)
	(segment
		(start 174.408846 -122.392948)
		(end 173.9392 -122.392948)
		(width 0.10668)
		(layer "F.Cu")
		(net "FM_LED_PWRGD_PVDDCR_SOC_P1")
	)
	(via
		(at 336.827876 -74.184764)
		(size 0.762)
		(drill 0.254)
		(layers "F.Cu" "B.Cu")
		(net "FM_LED_PWRGD_PVDDCR_SOC_P1")
	)
	(via
		(at 170.716194 -87.798148)
		(size 0.508)
		(drill 0.254)
		(layers "F.Cu" "B.Cu")
		(net "FM_LED_PWRGD_PVDDCR_SOC_P1")
	)
	(via
		(at 173.9392 -122.392948)
		(size 0.508)
		(drill 0.254)
		(layers "F.Cu" "B.Cu")
		(net "FM_LED_PWRGD_PVDDCR_SOC_P1")
	)
	(segment
		(start 336.827876 -74.184764)
		(end 336.827876 -73.861422)
		(width 0.10668)
		(layer "B.Cu")
		(net "FM_LED_PWRGD_PVDDCR_SOC_P1")
	)
	(segment
		(start 337.15452 -73.534778)
		(end 337.610704 -73.534778)
		(width 0.10668)
		(layer "B.Cu")
		(net "FM_LED_PWRGD_PVDDCR_SOC_P1")
	)
	(segment
		(start 336.827876 -73.861422)
		(end 337.15452 -73.534778)
		(width 0.10668)
		(layer "B.Cu")
		(net "FM_LED_PWRGD_PVDDCR_SOC_P1")
	)
	(segment
		(start 173.9392 -122.392948)
		(end 173.45406 -121.907808)
		(width 0.11684)
		(layer "In11.Cu")
		(net "FM_LED_PWRGD_PVDDCR_SOC_P1")
	)
	(segment
		(start 169.922698 -106.860848)
		(end 169.609516 -106.547666)
		(width 0.11684)
		(layer "In11.Cu")
		(net "FM_LED_PWRGD_PVDDCR_SOC_P1")
	)
	(segment
		(start 168.38422 -99.330256)
		(end 166.857426 -97.803462)
		(width 0.11684)
		(layer "In11.Cu")
		(net "FM_LED_PWRGD_PVDDCR_SOC_P1")
	)
	(segment
		(start 171.21251 -113.660682)
		(end 171.21251 -107.471972)
		(width 0.11684)
		(layer "In11.Cu")
		(net "FM_LED_PWRGD_PVDDCR_SOC_P1")
	)
	(segment
		(start 169.609516 -106.547666)
		(end 169.609516 -105.773474)
		(width 0.11684)
		(layer "In11.Cu")
		(net "FM_LED_PWRGD_PVDDCR_SOC_P1")
	)
	(segment
		(start 170.601386 -106.860848)
		(end 169.922698 -106.860848)
		(width 0.11684)
		(layer "In11.Cu")
		(net "FM_LED_PWRGD_PVDDCR_SOC_P1")
	)
	(segment
		(start 169.028872 -104.268524)
		(end 168.38422 -103.623872)
		(width 0.11684)
		(layer "In11.Cu")
		(net "FM_LED_PWRGD_PVDDCR_SOC_P1")
	)
	(segment
		(start 171.21251 -107.471972)
		(end 170.601386 -106.860848)
		(width 0.11684)
		(layer "In11.Cu")
		(net "FM_LED_PWRGD_PVDDCR_SOC_P1")
	)
	(segment
		(start 173.45406 -121.907808)
		(end 173.45406 -115.902232)
		(width 0.11684)
		(layer "In11.Cu")
		(net "FM_LED_PWRGD_PVDDCR_SOC_P1")
	)
	(segment
		(start 169.609516 -105.773474)
		(end 169.028872 -105.19283)
		(width 0.11684)
		(layer "In11.Cu")
		(net "FM_LED_PWRGD_PVDDCR_SOC_P1")
	)
	(segment
		(start 168.155112 -90.763598)
		(end 170.716194 -88.202516)
		(width 0.11684)
		(layer "In11.Cu")
		(net "FM_LED_PWRGD_PVDDCR_SOC_P1")
	)
	(segment
		(start 166.857426 -95.43415)
		(end 168.155112 -94.136464)
		(width 0.11684)
		(layer "In11.Cu")
		(net "FM_LED_PWRGD_PVDDCR_SOC_P1")
	)
	(segment
		(start 168.155112 -94.136464)
		(end 168.155112 -90.763598)
		(width 0.11684)
		(layer "In11.Cu")
		(net "FM_LED_PWRGD_PVDDCR_SOC_P1")
	)
	(segment
		(start 168.38422 -103.623872)
		(end 168.38422 -99.330256)
		(width 0.11684)
		(layer "In11.Cu")
		(net "FM_LED_PWRGD_PVDDCR_SOC_P1")
	)
	(segment
		(start 170.716194 -88.202516)
		(end 170.716194 -87.798148)
		(width 0.11684)
		(layer "In11.Cu")
		(net "FM_LED_PWRGD_PVDDCR_SOC_P1")
	)
	(segment
		(start 173.45406 -115.902232)
		(end 171.21251 -113.660682)
		(width 0.11684)
		(layer "In11.Cu")
		(net "FM_LED_PWRGD_PVDDCR_SOC_P1")
	)
	(segment
		(start 166.857426 -97.803462)
		(end 166.857426 -95.43415)
		(width 0.11684)
		(layer "In11.Cu")
		(net "FM_LED_PWRGD_PVDDCR_SOC_P1")
	)
	(segment
		(start 169.028872 -105.19283)
		(end 169.028872 -104.268524)
		(width 0.11684)
		(layer "In11.Cu")
		(net "FM_LED_PWRGD_PVDDCR_SOC_P1")
	)
	(segment
		(start 182.921656 -89.78773)
		(end 183.886094 -90.752168)
		(width 0.11684)
		(layer "In15.Cu")
		(net "FM_LED_PWRGD_PVDDCR_SOC_P1")
	)
	(segment
		(start 170.716194 -87.798148)
		(end 170.716194 -88.237568)
		(width 0.11684)
		(layer "In15.Cu")
		(net "FM_LED_PWRGD_PVDDCR_SOC_P1")
	)
	(segment
		(start 333.302102 -69.717412)
		(end 336.363056 -72.778366)
		(width 0.11684)
		(layer "In15.Cu")
		(net "FM_LED_PWRGD_PVDDCR_SOC_P1")
	)
	(segment
		(start 172.266356 -89.78773)
		(end 182.921656 -89.78773)
		(width 0.11684)
		(layer "In15.Cu")
		(net "FM_LED_PWRGD_PVDDCR_SOC_P1")
	)
	(segment
		(start 205.559914 -89.78773)
		(end 239.840008 -89.78773)
		(width 0.11684)
		(layer "In15.Cu")
		(net "FM_LED_PWRGD_PVDDCR_SOC_P1")
	)
	(segment
		(start 317.253366 -75.65898)
		(end 317.253366 -71.901304)
		(width 0.11684)
		(layer "In15.Cu")
		(net "FM_LED_PWRGD_PVDDCR_SOC_P1")
	)
	(segment
		(start 188.50991 -90.014552)
		(end 196.714364 -90.014552)
		(width 0.11684)
		(layer "In15.Cu")
		(net "FM_LED_PWRGD_PVDDCR_SOC_P1")
	)
	(segment
		(start 246.333264 -83.294474)
		(end 309.617872 -83.294474)
		(width 0.11684)
		(layer "In15.Cu")
		(net "FM_LED_PWRGD_PVDDCR_SOC_P1")
	)
	(segment
		(start 319.437258 -69.717412)
		(end 333.302102 -69.717412)
		(width 0.11684)
		(layer "In15.Cu")
		(net "FM_LED_PWRGD_PVDDCR_SOC_P1")
	)
	(segment
		(start 309.617872 -83.294474)
		(end 317.253366 -75.65898)
		(width 0.11684)
		(layer "In15.Cu")
		(net "FM_LED_PWRGD_PVDDCR_SOC_P1")
	)
	(segment
		(start 170.716194 -88.237568)
		(end 172.266356 -89.78773)
		(width 0.11684)
		(layer "In15.Cu")
		(net "FM_LED_PWRGD_PVDDCR_SOC_P1")
	)
	(segment
		(start 204.018388 -91.329256)
		(end 205.559914 -89.78773)
		(width 0.11684)
		(layer "In15.Cu")
		(net "FM_LED_PWRGD_PVDDCR_SOC_P1")
	)
	(segment
		(start 336.363056 -73.719944)
		(end 336.827876 -74.184764)
		(width 0.11684)
		(layer "In15.Cu")
		(net "FM_LED_PWRGD_PVDDCR_SOC_P1")
	)
	(segment
		(start 183.886094 -90.752168)
		(end 187.772294 -90.752168)
		(width 0.11684)
		(layer "In15.Cu")
		(net "FM_LED_PWRGD_PVDDCR_SOC_P1")
	)
	(segment
		(start 198.029068 -91.329256)
		(end 204.018388 -91.329256)
		(width 0.11684)
		(layer "In15.Cu")
		(net "FM_LED_PWRGD_PVDDCR_SOC_P1")
	)
	(segment
		(start 336.363056 -72.778366)
		(end 336.363056 -73.719944)
		(width 0.11684)
		(layer "In15.Cu")
		(net "FM_LED_PWRGD_PVDDCR_SOC_P1")
	)
	(segment
		(start 239.840008 -89.78773)
		(end 246.333264 -83.294474)
		(width 0.11684)
		(layer "In15.Cu")
		(net "FM_LED_PWRGD_PVDDCR_SOC_P1")
	)
	(segment
		(start 196.714364 -90.014552)
		(end 198.029068 -91.329256)
		(width 0.11684)
		(layer "In15.Cu")
		(net "FM_LED_PWRGD_PVDDCR_SOC_P1")
	)
	(segment
		(start 317.253366 -71.901304)
		(end 319.437258 -69.717412)
		(width 0.11684)
		(layer "In15.Cu")
		(net "FM_LED_PWRGD_PVDDCR_SOC_P1")
	)
	(segment
		(start 187.772294 -90.752168)
		(end 188.50991 -90.014552)
		(width 0.11684)
		(layer "In15.Cu")
		(net "FM_LED_PWRGD_PVDDCR_SOC_P1")
	)
	(segment
		(start 190.721996 -109.052868)
		(end 191.111886 -108.662978)
		(width 0.10668)
		(layer "F.Cu")
		(net "FM_LED_PWRGD_PVDDCR_SOC_P0")
	)
	(via
		(at 207.335374 -102.568756)
		(size 0.508)
		(drill 0.254)
		(layers "F.Cu" "B.Cu")
		(net "FM_LED_PWRGD_PVDDCR_SOC_P0")
	)
	(via
		(at 191.111886 -108.662978)
		(size 0.4572)
		(drill 0.254)
		(layers "F.Cu" "B.Cu")
		(net "FM_LED_PWRGD_PVDDCR_SOC_P0")
	)
	(via
		(at 328.699876 -73.138792)
		(size 0.762)
		(drill 0.254)
		(layers "F.Cu" "B.Cu")
		(net "FM_LED_PWRGD_PVDDCR_SOC_P0")
	)
	(segment
		(start 191.111886 -108.662978)
		(end 191.185038 -108.662978)
		(width 0.10668)
		(layer "B.Cu")
		(net "FM_LED_PWRGD_PVDDCR_SOC_P0")
	)
	(segment
		(start 198.754492 -102.15372)
		(end 199.590152 -101.31806)
		(width 0.10668)
		(layer "B.Cu")
		(net "FM_LED_PWRGD_PVDDCR_SOC_P0")
	)
	(segment
		(start 328.699876 -73.293224)
		(end 328.94143 -73.534778)
		(width 0.10668)
		(layer "B.Cu")
		(net "FM_LED_PWRGD_PVDDCR_SOC_P0")
	)
	(segment
		(start 207.335374 -101.784404)
		(end 207.335374 -102.568756)
		(width 0.10668)
		(layer "B.Cu")
		(net "FM_LED_PWRGD_PVDDCR_SOC_P0")
	)
	(segment
		(start 206.699866 -101.148896)
		(end 207.335374 -101.784404)
		(width 0.10668)
		(layer "B.Cu")
		(net "FM_LED_PWRGD_PVDDCR_SOC_P0")
	)
	(segment
		(start 200.039478 -101.31806)
		(end 201.519536 -99.838002)
		(width 0.10668)
		(layer "B.Cu")
		(net "FM_LED_PWRGD_PVDDCR_SOC_P0")
	)
	(segment
		(start 201.519536 -99.838002)
		(end 206.214218 -99.838002)
		(width 0.10668)
		(layer "B.Cu")
		(net "FM_LED_PWRGD_PVDDCR_SOC_P0")
	)
	(segment
		(start 328.699876 -73.138792)
		(end 328.699876 -73.293224)
		(width 0.10668)
		(layer "B.Cu")
		(net "FM_LED_PWRGD_PVDDCR_SOC_P0")
	)
	(segment
		(start 328.94143 -73.534778)
		(end 329.350624 -73.534778)
		(width 0.10668)
		(layer "B.Cu")
		(net "FM_LED_PWRGD_PVDDCR_SOC_P0")
	)
	(segment
		(start 191.581278 -108.266738)
		(end 192.076324 -108.266738)
		(width 0.10668)
		(layer "B.Cu")
		(net "FM_LED_PWRGD_PVDDCR_SOC_P0")
	)
	(segment
		(start 198.754492 -102.603046)
		(end 198.754492 -102.15372)
		(width 0.10668)
		(layer "B.Cu")
		(net "FM_LED_PWRGD_PVDDCR_SOC_P0")
	)
	(segment
		(start 194.984624 -102.958392)
		(end 198.399146 -102.958392)
		(width 0.10668)
		(layer "B.Cu")
		(net "FM_LED_PWRGD_PVDDCR_SOC_P0")
	)
	(segment
		(start 199.590152 -101.31806)
		(end 200.039478 -101.31806)
		(width 0.10668)
		(layer "B.Cu")
		(net "FM_LED_PWRGD_PVDDCR_SOC_P0")
	)
	(segment
		(start 206.214218 -99.838002)
		(end 206.699866 -100.32365)
		(width 0.10668)
		(layer "B.Cu")
		(net "FM_LED_PWRGD_PVDDCR_SOC_P0")
	)
	(segment
		(start 206.699866 -100.32365)
		(end 206.699866 -101.148896)
		(width 0.10668)
		(layer "B.Cu")
		(net "FM_LED_PWRGD_PVDDCR_SOC_P0")
	)
	(segment
		(start 191.185038 -108.662978)
		(end 191.581278 -108.266738)
		(width 0.10668)
		(layer "B.Cu")
		(net "FM_LED_PWRGD_PVDDCR_SOC_P0")
	)
	(segment
		(start 192.315846 -105.62717)
		(end 194.984624 -102.958392)
		(width 0.10668)
		(layer "B.Cu")
		(net "FM_LED_PWRGD_PVDDCR_SOC_P0")
	)
	(segment
		(start 192.076324 -108.266738)
		(end 192.315846 -108.027216)
		(width 0.10668)
		(layer "B.Cu")
		(net "FM_LED_PWRGD_PVDDCR_SOC_P0")
	)
	(segment
		(start 192.315846 -108.027216)
		(end 192.315846 -105.62717)
		(width 0.10668)
		(layer "B.Cu")
		(net "FM_LED_PWRGD_PVDDCR_SOC_P0")
	)
	(segment
		(start 198.399146 -102.958392)
		(end 198.754492 -102.603046)
		(width 0.10668)
		(layer "B.Cu")
		(net "FM_LED_PWRGD_PVDDCR_SOC_P0")
	)
	(segment
		(start 219.668598 -98.160586)
		(end 211.1502 -98.160586)
		(width 0.11684)
		(layer "In15.Cu")
		(net "FM_LED_PWRGD_PVDDCR_SOC_P0")
	)
	(segment
		(start 320.80073 -70.982332)
		(end 319.698878 -72.084184)
		(width 0.11684)
		(layer "In15.Cu")
		(net "FM_LED_PWRGD_PVDDCR_SOC_P0")
	)
	(segment
		(start 326.203056 -71.98487)
		(end 325.200518 -70.982332)
		(width 0.11684)
		(layer "In15.Cu")
		(net "FM_LED_PWRGD_PVDDCR_SOC_P0")
	)
	(segment
		(start 207.335374 -101.975412)
		(end 207.335374 -102.568756)
		(width 0.11684)
		(layer "In15.Cu")
		(net "FM_LED_PWRGD_PVDDCR_SOC_P0")
	)
	(segment
		(start 232.837736 -98.579178)
		(end 220.08719 -98.579178)
		(width 0.11684)
		(layer "In15.Cu")
		(net "FM_LED_PWRGD_PVDDCR_SOC_P0")
	)
	(segment
		(start 246.85752 -84.559394)
		(end 232.837736 -98.579178)
		(width 0.11684)
		(layer "In15.Cu")
		(net "FM_LED_PWRGD_PVDDCR_SOC_P0")
	)
	(segment
		(start 319.698878 -72.084184)
		(end 319.698878 -76.835508)
		(width 0.11684)
		(layer "In15.Cu")
		(net "FM_LED_PWRGD_PVDDCR_SOC_P0")
	)
	(segment
		(start 220.08719 -98.579178)
		(end 219.668598 -98.160586)
		(width 0.11684)
		(layer "In15.Cu")
		(net "FM_LED_PWRGD_PVDDCR_SOC_P0")
	)
	(segment
		(start 327.189084 -74.649584)
		(end 326.47509 -74.649584)
		(width 0.11684)
		(layer "In15.Cu")
		(net "FM_LED_PWRGD_PVDDCR_SOC_P0")
	)
	(segment
		(start 326.47509 -74.649584)
		(end 326.203056 -74.37755)
		(width 0.11684)
		(layer "In15.Cu")
		(net "FM_LED_PWRGD_PVDDCR_SOC_P0")
	)
	(segment
		(start 211.1502 -98.160586)
		(end 207.335374 -101.975412)
		(width 0.11684)
		(layer "In15.Cu")
		(net "FM_LED_PWRGD_PVDDCR_SOC_P0")
	)
	(segment
		(start 326.203056 -74.37755)
		(end 326.203056 -71.98487)
		(width 0.11684)
		(layer "In15.Cu")
		(net "FM_LED_PWRGD_PVDDCR_SOC_P0")
	)
	(segment
		(start 328.699876 -73.138792)
		(end 327.189084 -74.649584)
		(width 0.11684)
		(layer "In15.Cu")
		(net "FM_LED_PWRGD_PVDDCR_SOC_P0")
	)
	(segment
		(start 311.974992 -84.559394)
		(end 246.85752 -84.559394)
		(width 0.11684)
		(layer "In15.Cu")
		(net "FM_LED_PWRGD_PVDDCR_SOC_P0")
	)
	(segment
		(start 319.698878 -76.835508)
		(end 311.974992 -84.559394)
		(width 0.11684)
		(layer "In15.Cu")
		(net "FM_LED_PWRGD_PVDDCR_SOC_P0")
	)
	(segment
		(start 325.200518 -70.982332)
		(end 320.80073 -70.982332)
		(width 0.11684)
		(layer "In15.Cu")
		(net "FM_LED_PWRGD_PVDDCR_SOC_P0")
	)
	(segment
		(start 180.32222 -118.652798)
		(end 179.93233 -119.042688)
		(width 0.10668)
		(layer "F.Cu")
		(net "FM_LED_PWRGD_PVDDCR_CPU1_P1")
	)
	(via
		(at 342.923876 -73.138792)
		(size 0.762)
		(drill 0.254)
		(layers "F.Cu" "B.Cu")
		(net "FM_LED_PWRGD_PVDDCR_CPU1_P1")
	)
	(via
		(at 179.93233 -119.042688)
		(size 0.4572)
		(drill 0.254)
		(layers "F.Cu" "B.Cu")
		(net "FM_LED_PWRGD_PVDDCR_CPU1_P1")
	)
	(segment
		(start 342.923876 -73.293224)
		(end 343.16543 -73.534778)
		(width 0.10668)
		(layer "B.Cu")
		(net "FM_LED_PWRGD_PVDDCR_CPU1_P1")
	)
	(segment
		(start 343.16543 -73.534778)
		(end 343.574624 -73.534778)
		(width 0.10668)
		(layer "B.Cu")
		(net "FM_LED_PWRGD_PVDDCR_CPU1_P1")
	)
	(segment
		(start 342.923876 -73.138792)
		(end 342.923876 -73.293224)
		(width 0.10668)
		(layer "B.Cu")
		(net "FM_LED_PWRGD_PVDDCR_CPU1_P1")
	)
	(segment
		(start 248.20372 -88.54567)
		(end 248.662698 -88.086692)
		(width 0.11684)
		(layer "In15.Cu")
		(net "FM_LED_PWRGD_PVDDCR_CPU1_P1")
	)
	(segment
		(start 182.733442 -100.799138)
		(end 194.446906 -100.799138)
		(width 0.11684)
		(layer "In15.Cu")
		(net "FM_LED_PWRGD_PVDDCR_CPU1_P1")
	)
	(segment
		(start 218.911932 -106.598212)
		(end 233.361992 -106.598212)
		(width 0.11684)
		(layer "In15.Cu")
		(net "FM_LED_PWRGD_PVDDCR_CPU1_P1")
	)
	(segment
		(start 215.258142 -105.866692)
		(end 216.41562 -107.02417)
		(width 0.11684)
		(layer "In15.Cu")
		(net "FM_LED_PWRGD_PVDDCR_CPU1_P1")
	)
	(segment
		(start 179.93233 -119.042688)
		(end 179.75453 -119.042688)
		(width 0.11684)
		(layer "In15.Cu")
		(net "FM_LED_PWRGD_PVDDCR_CPU1_P1")
	)
	(segment
		(start 216.41562 -107.02417)
		(end 218.485974 -107.02417)
		(width 0.11684)
		(layer "In15.Cu")
		(net "FM_LED_PWRGD_PVDDCR_CPU1_P1")
	)
	(segment
		(start 214.450422 -106.036872)
		(end 214.620602 -105.866692)
		(width 0.11684)
		(layer "In15.Cu")
		(net "FM_LED_PWRGD_PVDDCR_CPU1_P1")
	)
	(segment
		(start 233.361992 -106.598212)
		(end 248.20372 -91.756484)
		(width 0.11684)
		(layer "In15.Cu")
		(net "FM_LED_PWRGD_PVDDCR_CPU1_P1")
	)
	(segment
		(start 200.143872 -106.036872)
		(end 214.450422 -106.036872)
		(width 0.11684)
		(layer "In15.Cu")
		(net "FM_LED_PWRGD_PVDDCR_CPU1_P1")
	)
	(segment
		(start 179.75453 -119.042688)
		(end 179.524406 -118.812564)
		(width 0.11684)
		(layer "In15.Cu")
		(net "FM_LED_PWRGD_PVDDCR_CPU1_P1")
	)
	(segment
		(start 218.485974 -107.02417)
		(end 218.911932 -106.598212)
		(width 0.11684)
		(layer "In15.Cu")
		(net "FM_LED_PWRGD_PVDDCR_CPU1_P1")
	)
	(segment
		(start 179.524406 -118.812564)
		(end 179.524406 -104.008174)
		(width 0.11684)
		(layer "In15.Cu")
		(net "FM_LED_PWRGD_PVDDCR_CPU1_P1")
	)
	(segment
		(start 198.631556 -104.983788)
		(end 199.090788 -104.983788)
		(width 0.11684)
		(layer "In15.Cu")
		(net "FM_LED_PWRGD_PVDDCR_CPU1_P1")
	)
	(segment
		(start 327.975976 -88.086692)
		(end 342.923876 -73.138792)
		(width 0.11684)
		(layer "In15.Cu")
		(net "FM_LED_PWRGD_PVDDCR_CPU1_P1")
	)
	(segment
		(start 199.090788 -104.983788)
		(end 200.143872 -106.036872)
		(width 0.11684)
		(layer "In15.Cu")
		(net "FM_LED_PWRGD_PVDDCR_CPU1_P1")
	)
	(segment
		(start 214.620602 -105.866692)
		(end 215.258142 -105.866692)
		(width 0.11684)
		(layer "In15.Cu")
		(net "FM_LED_PWRGD_PVDDCR_CPU1_P1")
	)
	(segment
		(start 248.662698 -88.086692)
		(end 327.975976 -88.086692)
		(width 0.11684)
		(layer "In15.Cu")
		(net "FM_LED_PWRGD_PVDDCR_CPU1_P1")
	)
	(segment
		(start 248.20372 -91.756484)
		(end 248.20372 -88.54567)
		(width 0.11684)
		(layer "In15.Cu")
		(net "FM_LED_PWRGD_PVDDCR_CPU1_P1")
	)
	(segment
		(start 179.524406 -104.008174)
		(end 182.733442 -100.799138)
		(width 0.11684)
		(layer "In15.Cu")
		(net "FM_LED_PWRGD_PVDDCR_CPU1_P1")
	)
	(segment
		(start 194.446906 -100.799138)
		(end 198.631556 -104.983788)
		(width 0.11684)
		(layer "In15.Cu")
		(net "FM_LED_PWRGD_PVDDCR_CPU1_P1")
	)
	(segment
		(start 188.322204 -109.852968)
		(end 188.712094 -109.463078)
		(width 0.10668)
		(layer "F.Cu")
		(net "FM_LED_PWRGD_PVDDCR_CPU1_P0")
	)
	(via
		(at 326.667876 -74.184764)
		(size 0.762)
		(drill 0.254)
		(layers "F.Cu" "B.Cu")
		(net "FM_LED_PWRGD_PVDDCR_CPU1_P0")
	)
	(via
		(at 206.539592 -102.592632)
		(size 0.508)
		(drill 0.254)
		(layers "F.Cu" "B.Cu")
		(net "FM_LED_PWRGD_PVDDCR_CPU1_P0")
	)
	(via
		(at 188.712094 -109.463078)
		(size 0.4572)
		(drill 0.254)
		(layers "F.Cu" "B.Cu")
		(net "FM_LED_PWRGD_PVDDCR_CPU1_P0")
	)
	(segment
		(start 326.667876 -74.184764)
		(end 326.667876 -73.861422)
		(width 0.10668)
		(layer "B.Cu")
		(net "FM_LED_PWRGD_PVDDCR_CPU1_P0")
	)
	(segment
		(start 326.667876 -73.861422)
		(end 326.99452 -73.534778)
		(width 0.10668)
		(layer "B.Cu")
		(net "FM_LED_PWRGD_PVDDCR_CPU1_P0")
	)
	(segment
		(start 326.99452 -73.534778)
		(end 327.450704 -73.534778)
		(width 0.10668)
		(layer "B.Cu")
		(net "FM_LED_PWRGD_PVDDCR_CPU1_P0")
	)
	(segment
		(start 192.164462 -104.809544)
		(end 191.320928 -104.809544)
		(width 0.11684)
		(layer "In2.Cu")
		(net "FM_LED_PWRGD_PVDDCR_CPU1_P0")
	)
	(segment
		(start 188.836808 -109.463078)
		(end 188.712094 -109.463078)
		(width 0.11684)
		(layer "In2.Cu")
		(net "FM_LED_PWRGD_PVDDCR_CPU1_P0")
	)
	(segment
		(start 206.539592 -102.592632)
		(end 205.90256 -101.9556)
		(width 0.11684)
		(layer "In2.Cu")
		(net "FM_LED_PWRGD_PVDDCR_CPU1_P0")
	)
	(segment
		(start 205.90256 -101.9556)
		(end 195.7324 -101.9556)
		(width 0.11684)
		(layer "In2.Cu")
		(net "FM_LED_PWRGD_PVDDCR_CPU1_P0")
	)
	(segment
		(start 191.320928 -104.809544)
		(end 189.119764 -107.010708)
		(width 0.11684)
		(layer "In2.Cu")
		(net "FM_LED_PWRGD_PVDDCR_CPU1_P0")
	)
	(segment
		(start 194.73926 -102.94874)
		(end 194.025266 -102.94874)
		(width 0.11684)
		(layer "In2.Cu")
		(net "FM_LED_PWRGD_PVDDCR_CPU1_P0")
	)
	(segment
		(start 195.7324 -101.9556)
		(end 194.73926 -102.94874)
		(width 0.11684)
		(layer "In2.Cu")
		(net "FM_LED_PWRGD_PVDDCR_CPU1_P0")
	)
	(segment
		(start 194.025266 -102.94874)
		(end 192.164462 -104.809544)
		(width 0.11684)
		(layer "In2.Cu")
		(net "FM_LED_PWRGD_PVDDCR_CPU1_P0")
	)
	(segment
		(start 189.119764 -109.180122)
		(end 188.836808 -109.463078)
		(width 0.11684)
		(layer "In2.Cu")
		(net "FM_LED_PWRGD_PVDDCR_CPU1_P0")
	)
	(segment
		(start 189.119764 -107.010708)
		(end 189.119764 -109.180122)
		(width 0.11684)
		(layer "In2.Cu")
		(net "FM_LED_PWRGD_PVDDCR_CPU1_P0")
	)
	(segment
		(start 220.503242 -98.150426)
		(end 220.07195 -97.719134)
		(width 0.11684)
		(layer "In15.Cu")
		(net "FM_LED_PWRGD_PVDDCR_CPU1_P0")
	)
	(segment
		(start 320.625978 -70.560692)
		(end 319.277238 -71.909432)
		(width 0.11684)
		(layer "In15.Cu")
		(net "FM_LED_PWRGD_PVDDCR_CPU1_P0")
	)
	(segment
		(start 246.682768 -84.137754)
		(end 232.670096 -98.150426)
		(width 0.11684)
		(layer "In15.Cu")
		(net "FM_LED_PWRGD_PVDDCR_CPU1_P0")
	)
	(segment
		(start 327.132696 -73.719944)
		(end 327.132696 -71.676006)
		(width 0.11684)
		(layer "In15.Cu")
		(net "FM_LED_PWRGD_PVDDCR_CPU1_P0")
	)
	(segment
		(start 232.670096 -98.150426)
		(end 220.503242 -98.150426)
		(width 0.11684)
		(layer "In15.Cu")
		(net "FM_LED_PWRGD_PVDDCR_CPU1_P0")
	)
	(segment
		(start 326.017382 -70.560692)
		(end 320.625978 -70.560692)
		(width 0.11684)
		(layer "In15.Cu")
		(net "FM_LED_PWRGD_PVDDCR_CPU1_P0")
	)
	(segment
		(start 210.986878 -97.719134)
		(end 206.539592 -102.16642)
		(width 0.11684)
		(layer "In15.Cu")
		(net "FM_LED_PWRGD_PVDDCR_CPU1_P0")
	)
	(segment
		(start 206.539592 -102.16642)
		(end 206.539592 -102.592632)
		(width 0.11684)
		(layer "In15.Cu")
		(net "FM_LED_PWRGD_PVDDCR_CPU1_P0")
	)
	(segment
		(start 319.277238 -76.660756)
		(end 311.80024 -84.137754)
		(width 0.11684)
		(layer "In15.Cu")
		(net "FM_LED_PWRGD_PVDDCR_CPU1_P0")
	)
	(segment
		(start 327.132696 -71.676006)
		(end 326.017382 -70.560692)
		(width 0.11684)
		(layer "In15.Cu")
		(net "FM_LED_PWRGD_PVDDCR_CPU1_P0")
	)
	(segment
		(start 220.07195 -97.719134)
		(end 210.986878 -97.719134)
		(width 0.11684)
		(layer "In15.Cu")
		(net "FM_LED_PWRGD_PVDDCR_CPU1_P0")
	)
	(segment
		(start 311.80024 -84.137754)
		(end 246.682768 -84.137754)
		(width 0.11684)
		(layer "In15.Cu")
		(net "FM_LED_PWRGD_PVDDCR_CPU1_P0")
	)
	(segment
		(start 319.277238 -71.909432)
		(end 319.277238 -76.660756)
		(width 0.11684)
		(layer "In15.Cu")
		(net "FM_LED_PWRGD_PVDDCR_CPU1_P0")
	)
	(segment
		(start 326.667876 -74.184764)
		(end 327.132696 -73.719944)
		(width 0.11684)
		(layer "In15.Cu")
		(net "FM_LED_PWRGD_PVDDCR_CPU1_P0")
	)
	(segment
		(start 190.721996 -113.85296)
		(end 191.111886 -113.46307)
		(width 0.10668)
		(layer "F.Cu")
		(net "FM_LED_PWRGD_PVDDCR_CPU0_P1")
	)
	(via
		(at 338.859876 -73.138792)
		(size 0.762)
		(drill 0.254)
		(layers "F.Cu" "B.Cu")
		(net "FM_LED_PWRGD_PVDDCR_CPU0_P1")
	)
	(via
		(at 191.111886 -113.46307)
		(size 0.4572)
		(drill 0.254)
		(layers "F.Cu" "B.Cu")
		(net "FM_LED_PWRGD_PVDDCR_CPU0_P1")
	)
	(via
		(at 202.771248 -94.633034)
		(size 0.508)
		(drill 0.254)
		(layers "F.Cu" "B.Cu")
		(net "FM_LED_PWRGD_PVDDCR_CPU0_P1")
	)
	(segment
		(start 338.859876 -73.138792)
		(end 338.859876 -73.293224)
		(width 0.10668)
		(layer "B.Cu")
		(net "FM_LED_PWRGD_PVDDCR_CPU0_P1")
	)
	(segment
		(start 339.10143 -73.534778)
		(end 339.510624 -73.534778)
		(width 0.10668)
		(layer "B.Cu")
		(net "FM_LED_PWRGD_PVDDCR_CPU0_P1")
	)
	(segment
		(start 338.859876 -73.293224)
		(end 339.10143 -73.534778)
		(width 0.10668)
		(layer "B.Cu")
		(net "FM_LED_PWRGD_PVDDCR_CPU0_P1")
	)
	(segment
		(start 196.95414 -112.37214)
		(end 196.27469 -113.05159)
		(width 0.11684)
		(layer "In4.Cu")
		(net "FM_LED_PWRGD_PVDDCR_CPU0_P1")
	)
	(segment
		(start 196.27469 -113.05159)
		(end 191.459104 -113.05159)
		(width 0.11684)
		(layer "In4.Cu")
		(net "FM_LED_PWRGD_PVDDCR_CPU0_P1")
	)
	(segment
		(start 200.00595 -110.080552)
		(end 197.945502 -110.080552)
		(width 0.11684)
		(layer "In4.Cu")
		(net "FM_LED_PWRGD_PVDDCR_CPU0_P1")
	)
	(segment
		(start 197.945502 -110.080552)
		(end 196.95414 -111.071914)
		(width 0.11684)
		(layer "In4.Cu")
		(net "FM_LED_PWRGD_PVDDCR_CPU0_P1")
	)
	(segment
		(start 201.174858 -96.762824)
		(end 201.174858 -108.491528)
		(width 0.11684)
		(layer "In4.Cu")
		(net "FM_LED_PWRGD_PVDDCR_CPU0_P1")
	)
	(segment
		(start 200.45172 -109.634782)
		(end 200.00595 -110.080552)
		(width 0.11684)
		(layer "In4.Cu")
		(net "FM_LED_PWRGD_PVDDCR_CPU0_P1")
	)
	(segment
		(start 200.45172 -109.214666)
		(end 200.45172 -109.634782)
		(width 0.11684)
		(layer "In4.Cu")
		(net "FM_LED_PWRGD_PVDDCR_CPU0_P1")
	)
	(segment
		(start 191.111886 -113.398808)
		(end 191.111886 -113.46307)
		(width 0.11684)
		(layer "In4.Cu")
		(net "FM_LED_PWRGD_PVDDCR_CPU0_P1")
	)
	(segment
		(start 201.174858 -108.491528)
		(end 200.45172 -109.214666)
		(width 0.11684)
		(layer "In4.Cu")
		(net "FM_LED_PWRGD_PVDDCR_CPU0_P1")
	)
	(segment
		(start 191.459104 -113.05159)
		(end 191.111886 -113.398808)
		(width 0.11684)
		(layer "In4.Cu")
		(net "FM_LED_PWRGD_PVDDCR_CPU0_P1")
	)
	(segment
		(start 202.771248 -94.633034)
		(end 202.771248 -95.166434)
		(width 0.11684)
		(layer "In4.Cu")
		(net "FM_LED_PWRGD_PVDDCR_CPU0_P1")
	)
	(segment
		(start 202.771248 -95.166434)
		(end 201.174858 -96.762824)
		(width 0.11684)
		(layer "In4.Cu")
		(net "FM_LED_PWRGD_PVDDCR_CPU0_P1")
	)
	(segment
		(start 196.95414 -111.071914)
		(end 196.95414 -112.37214)
		(width 0.11684)
		(layer "In4.Cu")
		(net "FM_LED_PWRGD_PVDDCR_CPU0_P1")
	)
	(segment
		(start 319.61201 -70.139052)
		(end 318.075056 -71.676006)
		(width 0.11684)
		(layer "In15.Cu")
		(net "FM_LED_PWRGD_PVDDCR_CPU0_P1")
	)
	(segment
		(start 332.124558 -70.139052)
		(end 319.61201 -70.139052)
		(width 0.11684)
		(layer "In15.Cu")
		(net "FM_LED_PWRGD_PVDDCR_CPU0_P1")
	)
	(segment
		(start 311.625488 -83.716114)
		(end 246.508016 -83.716114)
		(width 0.11684)
		(layer "In15.Cu")
		(net "FM_LED_PWRGD_PVDDCR_CPU0_P1")
	)
	(segment
		(start 338.859876 -73.138792)
		(end 337.349084 -74.649584)
		(width 0.11684)
		(layer "In15.Cu")
		(net "FM_LED_PWRGD_PVDDCR_CPU0_P1")
	)
	(segment
		(start 215.695022 -94.46768)
		(end 208.61528 -94.46768)
		(width 0.11684)
		(layer "In15.Cu")
		(net "FM_LED_PWRGD_PVDDCR_CPU0_P1")
	)
	(segment
		(start 318.075056 -75.729592)
		(end 318.08801 -75.742546)
		(width 0.11684)
		(layer "In15.Cu")
		(net "FM_LED_PWRGD_PVDDCR_CPU0_P1")
	)
	(segment
		(start 208.61528 -94.46768)
		(end 207.000348 -96.082612)
		(width 0.11684)
		(layer "In15.Cu")
		(net "FM_LED_PWRGD_PVDDCR_CPU0_P1")
	)
	(segment
		(start 234.566714 -95.657416)
		(end 219.554044 -95.657416)
		(width 0.11684)
		(layer "In15.Cu")
		(net "FM_LED_PWRGD_PVDDCR_CPU0_P1")
	)
	(segment
		(start 217.360246 -96.132904)
		(end 215.695022 -94.46768)
		(width 0.11684)
		(layer "In15.Cu")
		(net "FM_LED_PWRGD_PVDDCR_CPU0_P1")
	)
	(segment
		(start 337.349084 -74.649584)
		(end 336.63509 -74.649584)
		(width 0.11684)
		(layer "In15.Cu")
		(net "FM_LED_PWRGD_PVDDCR_CPU0_P1")
	)
	(segment
		(start 219.554044 -95.657416)
		(end 219.078556 -96.132904)
		(width 0.11684)
		(layer "In15.Cu")
		(net "FM_LED_PWRGD_PVDDCR_CPU0_P1")
	)
	(segment
		(start 336.63509 -74.649584)
		(end 332.124558 -70.139052)
		(width 0.11684)
		(layer "In15.Cu")
		(net "FM_LED_PWRGD_PVDDCR_CPU0_P1")
	)
	(segment
		(start 318.075056 -71.676006)
		(end 318.075056 -75.729592)
		(width 0.11684)
		(layer "In15.Cu")
		(net "FM_LED_PWRGD_PVDDCR_CPU0_P1")
	)
	(segment
		(start 207.000348 -96.082612)
		(end 204.220826 -96.082612)
		(width 0.11684)
		(layer "In15.Cu")
		(net "FM_LED_PWRGD_PVDDCR_CPU0_P1")
	)
	(segment
		(start 318.08801 -75.742546)
		(end 318.08801 -77.253592)
		(width 0.11684)
		(layer "In15.Cu")
		(net "FM_LED_PWRGD_PVDDCR_CPU0_P1")
	)
	(segment
		(start 246.508016 -83.716114)
		(end 234.566714 -95.657416)
		(width 0.11684)
		(layer "In15.Cu")
		(net "FM_LED_PWRGD_PVDDCR_CPU0_P1")
	)
	(segment
		(start 318.08801 -77.253592)
		(end 311.625488 -83.716114)
		(width 0.11684)
		(layer "In15.Cu")
		(net "FM_LED_PWRGD_PVDDCR_CPU0_P1")
	)
	(segment
		(start 219.078556 -96.132904)
		(end 217.360246 -96.132904)
		(width 0.11684)
		(layer "In15.Cu")
		(net "FM_LED_PWRGD_PVDDCR_CPU0_P1")
	)
	(segment
		(start 204.220826 -96.082612)
		(end 202.771248 -94.633034)
		(width 0.11684)
		(layer "In15.Cu")
		(net "FM_LED_PWRGD_PVDDCR_CPU0_P1")
	)
	(segment
		(start 189.92215 -109.852968)
		(end 190.31204 -109.463078)
		(width 0.10668)
		(layer "F.Cu")
		(net "FM_LED_PWRGD_PVDDCR_CPU0_P0")
	)
	(via
		(at 208.284572 -102.54234)
		(size 0.508)
		(drill 0.254)
		(layers "F.Cu" "B.Cu")
		(net "FM_LED_PWRGD_PVDDCR_CPU0_P0")
	)
	(via
		(at 190.31204 -109.463078)
		(size 0.4572)
		(drill 0.254)
		(layers "F.Cu" "B.Cu")
		(net "FM_LED_PWRGD_PVDDCR_CPU0_P0")
	)
	(via
		(at 322.603876 -74.184764)
		(size 0.762)
		(drill 0.254)
		(layers "F.Cu" "B.Cu")
		(net "FM_LED_PWRGD_PVDDCR_CPU0_P0")
	)
	(segment
		(start 322.93052 -73.534778)
		(end 323.386704 -73.534778)
		(width 0.10668)
		(layer "B.Cu")
		(net "FM_LED_PWRGD_PVDDCR_CPU0_P0")
	)
	(segment
		(start 322.603876 -74.184764)
		(end 322.603876 -73.861422)
		(width 0.10668)
		(layer "B.Cu")
		(net "FM_LED_PWRGD_PVDDCR_CPU0_P0")
	)
	(segment
		(start 322.603876 -73.861422)
		(end 322.93052 -73.534778)
		(width 0.10668)
		(layer "B.Cu")
		(net "FM_LED_PWRGD_PVDDCR_CPU0_P0")
	)
	(segment
		(start 195.325746 -102.997)
		(end 194.906646 -103.4161)
		(width 0.11684)
		(layer "In2.Cu")
		(net "FM_LED_PWRGD_PVDDCR_CPU0_P0")
	)
	(segment
		(start 198.722488 -102.997)
		(end 195.325746 -102.997)
		(width 0.11684)
		(layer "In2.Cu")
		(net "FM_LED_PWRGD_PVDDCR_CPU0_P0")
	)
	(segment
		(start 191.057276 -105.71988)
		(end 190.716662 -106.060494)
		(width 0.11684)
		(layer "In2.Cu")
		(net "FM_LED_PWRGD_PVDDCR_CPU0_P0")
	)
	(segment
		(start 190.716662 -109.222286)
		(end 190.47587 -109.463078)
		(width 0.11684)
		(layer "In2.Cu")
		(net "FM_LED_PWRGD_PVDDCR_CPU0_P0")
	)
	(segment
		(start 207.855312 -103.218488)
		(end 200.500488 -103.218488)
		(width 0.11684)
		(layer "In2.Cu")
		(net "FM_LED_PWRGD_PVDDCR_CPU0_P0")
	)
	(segment
		(start 200.246996 -102.964996)
		(end 198.754492 -102.964996)
		(width 0.11684)
		(layer "In2.Cu")
		(net "FM_LED_PWRGD_PVDDCR_CPU0_P0")
	)
	(segment
		(start 190.47587 -109.463078)
		(end 190.31204 -109.463078)
		(width 0.11684)
		(layer "In2.Cu")
		(net "FM_LED_PWRGD_PVDDCR_CPU0_P0")
	)
	(segment
		(start 208.284572 -102.789228)
		(end 207.855312 -103.218488)
		(width 0.11684)
		(layer "In2.Cu")
		(net "FM_LED_PWRGD_PVDDCR_CPU0_P0")
	)
	(segment
		(start 194.906646 -103.4161)
		(end 194.16776 -103.4161)
		(width 0.11684)
		(layer "In2.Cu")
		(net "FM_LED_PWRGD_PVDDCR_CPU0_P0")
	)
	(segment
		(start 194.16776 -103.4161)
		(end 191.86398 -105.71988)
		(width 0.11684)
		(layer "In2.Cu")
		(net "FM_LED_PWRGD_PVDDCR_CPU0_P0")
	)
	(segment
		(start 191.86398 -105.71988)
		(end 191.057276 -105.71988)
		(width 0.11684)
		(layer "In2.Cu")
		(net "FM_LED_PWRGD_PVDDCR_CPU0_P0")
	)
	(segment
		(start 200.500488 -103.218488)
		(end 200.246996 -102.964996)
		(width 0.11684)
		(layer "In2.Cu")
		(net "FM_LED_PWRGD_PVDDCR_CPU0_P0")
	)
	(segment
		(start 198.754492 -102.964996)
		(end 198.722488 -102.997)
		(width 0.11684)
		(layer "In2.Cu")
		(net "FM_LED_PWRGD_PVDDCR_CPU0_P0")
	)
	(segment
		(start 208.284572 -102.54234)
		(end 208.284572 -102.789228)
		(width 0.11684)
		(layer "In2.Cu")
		(net "FM_LED_PWRGD_PVDDCR_CPU0_P0")
	)
	(segment
		(start 190.716662 -106.060494)
		(end 190.716662 -109.222286)
		(width 0.11684)
		(layer "In2.Cu")
		(net "FM_LED_PWRGD_PVDDCR_CPU0_P0")
	)
	(segment
		(start 232.98023 -99.033076)
		(end 247.032272 -84.981034)
		(width 0.11684)
		(layer "In15.Cu")
		(net "FM_LED_PWRGD_PVDDCR_CPU0_P0")
	)
	(segment
		(start 312.247026 -84.981034)
		(end 322.603876 -74.624184)
		(width 0.11684)
		(layer "In15.Cu")
		(net "FM_LED_PWRGD_PVDDCR_CPU0_P0")
	)
	(segment
		(start 211.339684 -98.589084)
		(end 218.98483 -98.589084)
		(width 0.11684)
		(layer "In15.Cu")
		(net "FM_LED_PWRGD_PVDDCR_CPU0_P0")
	)
	(segment
		(start 208.481168 -101.4476)
		(end 211.339684 -98.589084)
		(width 0.11684)
		(layer "In15.Cu")
		(net "FM_LED_PWRGD_PVDDCR_CPU0_P0")
	)
	(segment
		(start 322.603876 -74.624184)
		(end 322.603876 -74.184764)
		(width 0.11684)
		(layer "In15.Cu")
		(net "FM_LED_PWRGD_PVDDCR_CPU0_P0")
	)
	(segment
		(start 208.284572 -102.54234)
		(end 208.481168 -102.345744)
		(width 0.11684)
		(layer "In15.Cu")
		(net "FM_LED_PWRGD_PVDDCR_CPU0_P0")
	)
	(segment
		(start 247.032272 -84.981034)
		(end 312.247026 -84.981034)
		(width 0.11684)
		(layer "In15.Cu")
		(net "FM_LED_PWRGD_PVDDCR_CPU0_P0")
	)
	(segment
		(start 219.428822 -99.033076)
		(end 232.98023 -99.033076)
		(width 0.11684)
		(layer "In15.Cu")
		(net "FM_LED_PWRGD_PVDDCR_CPU0_P0")
	)
	(segment
		(start 208.481168 -102.345744)
		(end 208.481168 -101.4476)
		(width 0.11684)
		(layer "In15.Cu")
		(net "FM_LED_PWRGD_PVDDCR_CPU0_P0")
	)
	(segment
		(start 218.98483 -98.589084)
		(end 219.428822 -99.033076)
		(width 0.11684)
		(layer "In15.Cu")
		(net "FM_LED_PWRGD_PVDDCR_CPU0_P0")
	)
	(segment
		(start 189.12205 -114.652806)
		(end 189.51194 -114.262916)
		(width 0.10668)
		(layer "F.Cu")
		(net "FM_LED_PWRGD_PVDD33_S5")
	)
	(via
		(at 211.944204 -101.982016)
		(size 0.508)
		(drill 0.254)
		(layers "F.Cu" "B.Cu")
		(net "FM_LED_PWRGD_PVDD33_S5")
	)
	(via
		(at 189.51194 -114.262916)
		(size 0.4572)
		(drill 0.254)
		(layers "F.Cu" "B.Cu")
		(net "FM_LED_PWRGD_PVDD33_S5")
	)
	(via
		(at 193.582544 -115.731036)
		(size 0.6604)
		(drill 0.3302)
		(layers "F.Cu" "B.Cu")
		(net "FM_LED_PWRGD_PVDD33_S5")
	)
	(via
		(at 211.170774 -115.612418)
		(size 0.508)
		(drill 0.254)
		(layers "F.Cu" "B.Cu")
		(net "FM_LED_PWRGD_PVDD33_S5")
	)
	(via
		(at 324.635876 -73.138792)
		(size 0.508)
		(drill 0.254)
		(layers "F.Cu" "B.Cu")
		(net "FM_LED_PWRGD_PVDD33_S5")
	)
	(segment
		(start 189.51194 -114.757708)
		(end 189.51194 -114.262916)
		(width 0.10668)
		(layer "B.Cu")
		(net "FM_LED_PWRGD_PVDD33_S5")
	)
	(segment
		(start 199.81799 -118.260622)
		(end 204.624178 -118.260622)
		(width 0.10668)
		(layer "B.Cu")
		(net "FM_LED_PWRGD_PVDD33_S5")
	)
	(segment
		(start 198.780908 -117.22354)
		(end 199.81799 -118.260622)
		(width 0.10668)
		(layer "B.Cu")
		(net "FM_LED_PWRGD_PVDD33_S5")
	)
	(segment
		(start 210.85302 -117.210586)
		(end 211.170774 -116.892832)
		(width 0.10668)
		(layer "B.Cu")
		(net "FM_LED_PWRGD_PVDD33_S5")
	)
	(segment
		(start 324.87743 -73.534778)
		(end 325.286624 -73.534778)
		(width 0.10668)
		(layer "B.Cu")
		(net "FM_LED_PWRGD_PVDD33_S5")
	)
	(segment
		(start 194.970146 -115.44427)
		(end 195.352416 -115.82654)
		(width 0.10668)
		(layer "B.Cu")
		(net "FM_LED_PWRGD_PVDD33_S5")
	)
	(segment
		(start 197.7263 -116.25834)
		(end 197.7263 -116.80444)
		(width 0.10668)
		(layer "B.Cu")
		(net "FM_LED_PWRGD_PVDD33_S5")
	)
	(segment
		(start 193.254884 -115.403376)
		(end 190.157608 -115.403376)
		(width 0.10668)
		(layer "B.Cu")
		(net "FM_LED_PWRGD_PVDD33_S5")
	)
	(segment
		(start 324.635876 -73.293224)
		(end 324.87743 -73.534778)
		(width 0.10668)
		(layer "B.Cu")
		(net "FM_LED_PWRGD_PVDD33_S5")
	)
	(segment
		(start 193.918586 -115.44427)
		(end 194.970146 -115.44427)
		(width 0.10668)
		(layer "B.Cu")
		(net "FM_LED_PWRGD_PVDD33_S5")
	)
	(segment
		(start 197.7263 -116.80444)
		(end 198.1454 -117.22354)
		(width 0.10668)
		(layer "B.Cu")
		(net "FM_LED_PWRGD_PVDD33_S5")
	)
	(segment
		(start 190.157608 -115.403376)
		(end 189.51194 -114.757708)
		(width 0.10668)
		(layer "B.Cu")
		(net "FM_LED_PWRGD_PVDD33_S5")
	)
	(segment
		(start 211.170774 -116.892832)
		(end 211.170774 -115.612418)
		(width 0.10668)
		(layer "B.Cu")
		(net "FM_LED_PWRGD_PVDD33_S5")
	)
	(segment
		(start 324.635876 -73.138792)
		(end 324.635876 -73.293224)
		(width 0.10668)
		(layer "B.Cu")
		(net "FM_LED_PWRGD_PVDD33_S5")
	)
	(segment
		(start 193.63182 -115.731036)
		(end 193.918586 -115.44427)
		(width 0.10668)
		(layer "B.Cu")
		(net "FM_LED_PWRGD_PVDD33_S5")
	)
	(segment
		(start 193.582544 -115.731036)
		(end 193.254884 -115.403376)
		(width 0.10668)
		(layer "B.Cu")
		(net "FM_LED_PWRGD_PVDD33_S5")
	)
	(segment
		(start 204.624178 -118.260622)
		(end 205.674214 -117.210586)
		(width 0.10668)
		(layer "B.Cu")
		(net "FM_LED_PWRGD_PVDD33_S5")
	)
	(segment
		(start 205.674214 -117.210586)
		(end 210.85302 -117.210586)
		(width 0.10668)
		(layer "B.Cu")
		(net "FM_LED_PWRGD_PVDD33_S5")
	)
	(segment
		(start 193.582544 -115.731036)
		(end 193.63182 -115.731036)
		(width 0.10668)
		(layer "B.Cu")
		(net "FM_LED_PWRGD_PVDD33_S5")
	)
	(segment
		(start 198.1454 -117.22354)
		(end 198.780908 -117.22354)
		(width 0.10668)
		(layer "B.Cu")
		(net "FM_LED_PWRGD_PVDD33_S5")
	)
	(segment
		(start 195.352416 -115.82654)
		(end 197.2945 -115.82654)
		(width 0.10668)
		(layer "B.Cu")
		(net "FM_LED_PWRGD_PVDD33_S5")
	)
	(segment
		(start 197.2945 -115.82654)
		(end 197.7263 -116.25834)
		(width 0.10668)
		(layer "B.Cu")
		(net "FM_LED_PWRGD_PVDD33_S5")
	)
	(segment
		(start 212.4202 -112.8776)
		(end 212.4202 -113.965482)
		(width 0.11684)
		(layer "In4.Cu")
		(net "FM_LED_PWRGD_PVDD33_S5")
	)
	(segment
		(start 212.60943 -114.154712)
		(end 212.60943 -114.912902)
		(width 0.11684)
		(layer "In4.Cu")
		(net "FM_LED_PWRGD_PVDD33_S5")
	)
	(segment
		(start 212.217 -103.632)
		(end 212.217 -104.139746)
		(width 0.11684)
		(layer "In4.Cu")
		(net "FM_LED_PWRGD_PVDD33_S5")
	)
	(segment
		(start 211.51215 -115.029742)
		(end 211.170774 -115.371118)
		(width 0.11684)
		(layer "In4.Cu")
		(net "FM_LED_PWRGD_PVDD33_S5")
	)
	(segment
		(start 212.60943 -114.912902)
		(end 212.49259 -115.029742)
		(width 0.11684)
		(layer "In4.Cu")
		(net "FM_LED_PWRGD_PVDD33_S5")
	)
	(segment
		(start 212.4202 -113.965482)
		(end 212.60943 -114.154712)
		(width 0.11684)
		(layer "In4.Cu")
		(net "FM_LED_PWRGD_PVDD33_S5")
	)
	(segment
		(start 211.944204 -101.982016)
		(end 211.944204 -103.359204)
		(width 0.11684)
		(layer "In4.Cu")
		(net "FM_LED_PWRGD_PVDD33_S5")
	)
	(segment
		(start 212.49259 -115.029742)
		(end 211.51215 -115.029742)
		(width 0.11684)
		(layer "In4.Cu")
		(net "FM_LED_PWRGD_PVDD33_S5")
	)
	(segment
		(start 211.3026 -110.013496)
		(end 211.3026 -111.76)
		(width 0.11684)
		(layer "In4.Cu")
		(net "FM_LED_PWRGD_PVDD33_S5")
	)
	(segment
		(start 211.170774 -115.371118)
		(end 211.170774 -115.612418)
		(width 0.11684)
		(layer "In4.Cu")
		(net "FM_LED_PWRGD_PVDD33_S5")
	)
	(segment
		(start 212.217 -104.139746)
		(end 211.116418 -105.240328)
		(width 0.11684)
		(layer "In4.Cu")
		(net "FM_LED_PWRGD_PVDD33_S5")
	)
	(segment
		(start 211.944204 -103.359204)
		(end 212.217 -103.632)
		(width 0.11684)
		(layer "In4.Cu")
		(net "FM_LED_PWRGD_PVDD33_S5")
	)
	(segment
		(start 211.116418 -109.827314)
		(end 211.3026 -110.013496)
		(width 0.11684)
		(layer "In4.Cu")
		(net "FM_LED_PWRGD_PVDD33_S5")
	)
	(segment
		(start 211.3026 -111.76)
		(end 212.4202 -112.8776)
		(width 0.11684)
		(layer "In4.Cu")
		(net "FM_LED_PWRGD_PVDD33_S5")
	)
	(segment
		(start 211.116418 -105.240328)
		(end 211.116418 -109.827314)
		(width 0.11684)
		(layer "In4.Cu")
		(net "FM_LED_PWRGD_PVDD33_S5")
	)
	(segment
		(start 247.556528 -86.245954)
		(end 312.771282 -86.245954)
		(width 0.11684)
		(layer "In15.Cu")
		(net "FM_LED_PWRGD_PVDD33_S5")
	)
	(segment
		(start 213.269322 -100.656898)
		(end 233.145584 -100.656898)
		(width 0.11684)
		(layer "In15.Cu")
		(net "FM_LED_PWRGD_PVDD33_S5")
	)
	(segment
		(start 324.186804 -74.830432)
		(end 324.186804 -73.587864)
		(width 0.11684)
		(layer "In15.Cu")
		(net "FM_LED_PWRGD_PVDD33_S5")
	)
	(segment
		(start 211.944204 -101.982016)
		(end 213.269322 -100.656898)
		(width 0.11684)
		(layer "In15.Cu")
		(net "FM_LED_PWRGD_PVDD33_S5")
	)
	(segment
		(start 233.145584 -100.656898)
		(end 247.556528 -86.245954)
		(width 0.11684)
		(layer "In15.Cu")
		(net "FM_LED_PWRGD_PVDD33_S5")
	)
	(segment
		(start 324.186804 -73.587864)
		(end 324.635876 -73.138792)
		(width 0.11684)
		(layer "In15.Cu")
		(net "FM_LED_PWRGD_PVDD33_S5")
	)
	(segment
		(start 312.771282 -86.245954)
		(end 324.186804 -74.830432)
		(width 0.11684)
		(layer "In15.Cu")
		(net "FM_LED_PWRGD_PVDD33_S5")
	)
	(segment
		(start 177.122074 -121.052844)
		(end 176.52619 -121.052844)
		(width 0.10668)
		(layer "F.Cu")
		(net "FM_LED_PWRGD_PVDD18_S5_P1")
	)
	(segment
		(start 176.52619 -121.052844)
		(end 174.149766 -123.429268)
		(width 0.10668)
		(layer "F.Cu")
		(net "FM_LED_PWRGD_PVDD18_S5_P1")
	)
	(segment
		(start 174.149766 -123.429268)
		(end 173.90872 -123.429268)
		(width 0.10668)
		(layer "F.Cu")
		(net "FM_LED_PWRGD_PVDD18_S5_P1")
	)
	(via
		(at 173.90872 -123.429268)
		(size 0.508)
		(drill 0.254)
		(layers "F.Cu" "B.Cu")
		(net "FM_LED_PWRGD_PVDD18_S5_P1")
	)
	(via
		(at 168.541954 -87.89289)
		(size 0.508)
		(drill 0.254)
		(layers "F.Cu" "B.Cu")
		(net "FM_LED_PWRGD_PVDD18_S5_P1")
	)
	(via
		(at 344.955876 -74.184764)
		(size 0.762)
		(drill 0.254)
		(layers "F.Cu" "B.Cu")
		(net "FM_LED_PWRGD_PVDD18_S5_P1")
	)
	(segment
		(start 344.955876 -74.184764)
		(end 344.955876 -73.861422)
		(width 0.10668)
		(layer "B.Cu")
		(net "FM_LED_PWRGD_PVDD18_S5_P1")
	)
	(segment
		(start 345.28252 -73.534778)
		(end 345.738704 -73.534778)
		(width 0.10668)
		(layer "B.Cu")
		(net "FM_LED_PWRGD_PVDD18_S5_P1")
	)
	(segment
		(start 344.955876 -73.861422)
		(end 345.28252 -73.534778)
		(width 0.10668)
		(layer "B.Cu")
		(net "FM_LED_PWRGD_PVDD18_S5_P1")
	)
	(segment
		(start 170.761406 -107.842812)
		(end 170.761406 -114.398806)
		(width 0.11684)
		(layer "In11.Cu")
		(net "FM_LED_PWRGD_PVDD18_S5_P1")
	)
	(segment
		(start 169.642028 -107.282488)
		(end 170.201082 -107.282488)
		(width 0.11684)
		(layer "In11.Cu")
		(net "FM_LED_PWRGD_PVDD18_S5_P1")
	)
	(segment
		(start 172.96892 -120.157748)
		(end 172.96892 -122.489468)
		(width 0.11684)
		(layer "In11.Cu")
		(net "FM_LED_PWRGD_PVDD18_S5_P1")
	)
	(segment
		(start 168.541954 -87.89289)
		(end 168.541954 -88.069674)
		(width 0.11684)
		(layer "In11.Cu")
		(net "FM_LED_PWRGD_PVDD18_S5_P1")
	)
	(segment
		(start 171.994576 -115.631976)
		(end 171.994576 -119.183404)
		(width 0.11684)
		(layer "In11.Cu")
		(net "FM_LED_PWRGD_PVDD18_S5_P1")
	)
	(segment
		(start 166.400734 -100.034852)
		(end 167.352218 -100.986336)
		(width 0.11684)
		(layer "In11.Cu")
		(net "FM_LED_PWRGD_PVDD18_S5_P1")
	)
	(segment
		(start 170.201082 -107.282488)
		(end 170.761406 -107.842812)
		(width 0.11684)
		(layer "In11.Cu")
		(net "FM_LED_PWRGD_PVDD18_S5_P1")
	)
	(segment
		(start 170.761406 -114.398806)
		(end 171.994576 -115.631976)
		(width 0.11684)
		(layer "In11.Cu")
		(net "FM_LED_PWRGD_PVDD18_S5_P1")
	)
	(segment
		(start 171.994576 -119.183404)
		(end 172.96892 -120.157748)
		(width 0.11684)
		(layer "In11.Cu")
		(net "FM_LED_PWRGD_PVDD18_S5_P1")
	)
	(segment
		(start 167.732456 -88.879172)
		(end 167.732456 -93.785436)
		(width 0.11684)
		(layer "In11.Cu")
		(net "FM_LED_PWRGD_PVDD18_S5_P1")
	)
	(segment
		(start 167.352218 -100.986336)
		(end 167.352218 -105.17505)
		(width 0.11684)
		(layer "In11.Cu")
		(net "FM_LED_PWRGD_PVDD18_S5_P1")
	)
	(segment
		(start 172.96892 -122.489468)
		(end 173.90872 -123.429268)
		(width 0.11684)
		(layer "In11.Cu")
		(net "FM_LED_PWRGD_PVDD18_S5_P1")
	)
	(segment
		(start 169.009314 -106.649774)
		(end 169.642028 -107.282488)
		(width 0.11684)
		(layer "In11.Cu")
		(net "FM_LED_PWRGD_PVDD18_S5_P1")
	)
	(segment
		(start 166.400734 -95.117158)
		(end 166.400734 -100.034852)
		(width 0.11684)
		(layer "In11.Cu")
		(net "FM_LED_PWRGD_PVDD18_S5_P1")
	)
	(segment
		(start 169.009314 -105.919778)
		(end 169.009314 -106.649774)
		(width 0.11684)
		(layer "In11.Cu")
		(net "FM_LED_PWRGD_PVDD18_S5_P1")
	)
	(segment
		(start 167.65524 -105.478072)
		(end 168.567608 -105.478072)
		(width 0.11684)
		(layer "In11.Cu")
		(net "FM_LED_PWRGD_PVDD18_S5_P1")
	)
	(segment
		(start 168.541954 -88.069674)
		(end 167.732456 -88.879172)
		(width 0.11684)
		(layer "In11.Cu")
		(net "FM_LED_PWRGD_PVDD18_S5_P1")
	)
	(segment
		(start 167.732456 -93.785436)
		(end 166.400734 -95.117158)
		(width 0.11684)
		(layer "In11.Cu")
		(net "FM_LED_PWRGD_PVDD18_S5_P1")
	)
	(segment
		(start 168.567608 -105.478072)
		(end 169.009314 -105.919778)
		(width 0.11684)
		(layer "In11.Cu")
		(net "FM_LED_PWRGD_PVDD18_S5_P1")
	)
	(segment
		(start 167.352218 -105.17505)
		(end 167.65524 -105.478072)
		(width 0.11684)
		(layer "In11.Cu")
		(net "FM_LED_PWRGD_PVDD18_S5_P1")
	)
	(segment
		(start 206.345536 -87.809324)
		(end 214.94242 -87.809324)
		(width 0.11684)
		(layer "In15.Cu")
		(net "FM_LED_PWRGD_PVDD18_S5_P1")
	)
	(segment
		(start 168.541954 -87.89289)
		(end 169.90441 -86.530434)
		(width 0.11684)
		(layer "In15.Cu")
		(net "FM_LED_PWRGD_PVDD18_S5_P1")
	)
	(segment
		(start 184.235598 -89.908888)
		(end 187.422536 -89.908888)
		(width 0.11684)
		(layer "In15.Cu")
		(net "FM_LED_PWRGD_PVDD18_S5_P1")
	)
	(segment
		(start 310.603138 -69.66077)
		(end 316.538102 -69.66077)
		(width 0.11684)
		(layer "In15.Cu")
		(net "FM_LED_PWRGD_PVDD18_S5_P1")
	)
	(segment
		(start 340.711282 -66.830194)
		(end 344.020902 -70.139814)
		(width 0.11684)
		(layer "In15.Cu")
		(net "FM_LED_PWRGD_PVDD18_S5_P1")
	)
	(segment
		(start 188.160152 -89.171272)
		(end 204.983588 -89.171272)
		(width 0.11684)
		(layer "In15.Cu")
		(net "FM_LED_PWRGD_PVDD18_S5_P1")
	)
	(segment
		(start 317.86195 -66.830194)
		(end 340.711282 -66.830194)
		(width 0.11684)
		(layer "In15.Cu")
		(net "FM_LED_PWRGD_PVDD18_S5_P1")
	)
	(segment
		(start 308.887876 -81.1657)
		(end 308.887876 -71.376032)
		(width 0.11684)
		(layer "In15.Cu")
		(net "FM_LED_PWRGD_PVDD18_S5_P1")
	)
	(segment
		(start 214.94242 -87.809324)
		(end 216.077546 -88.94445)
		(width 0.11684)
		(layer "In15.Cu")
		(net "FM_LED_PWRGD_PVDD18_S5_P1")
	)
	(segment
		(start 175.259746 -88.94445)
		(end 183.27116 -88.94445)
		(width 0.11684)
		(layer "In15.Cu")
		(net "FM_LED_PWRGD_PVDD18_S5_P1")
	)
	(segment
		(start 344.020902 -70.139814)
		(end 344.020902 -73.24979)
		(width 0.11684)
		(layer "In15.Cu")
		(net "FM_LED_PWRGD_PVDD18_S5_P1")
	)
	(segment
		(start 308.887876 -71.376032)
		(end 310.603138 -69.66077)
		(width 0.11684)
		(layer "In15.Cu")
		(net "FM_LED_PWRGD_PVDD18_S5_P1")
	)
	(segment
		(start 239.490504 -88.94445)
		(end 245.98376 -82.451194)
		(width 0.11684)
		(layer "In15.Cu")
		(net "FM_LED_PWRGD_PVDD18_S5_P1")
	)
	(segment
		(start 172.84573 -86.530434)
		(end 175.259746 -88.94445)
		(width 0.11684)
		(layer "In15.Cu")
		(net "FM_LED_PWRGD_PVDD18_S5_P1")
	)
	(segment
		(start 216.077546 -88.94445)
		(end 239.490504 -88.94445)
		(width 0.11684)
		(layer "In15.Cu")
		(net "FM_LED_PWRGD_PVDD18_S5_P1")
	)
	(segment
		(start 344.020902 -73.24979)
		(end 344.955876 -74.184764)
		(width 0.11684)
		(layer "In15.Cu")
		(net "FM_LED_PWRGD_PVDD18_S5_P1")
	)
	(segment
		(start 187.422536 -89.908888)
		(end 188.160152 -89.171272)
		(width 0.11684)
		(layer "In15.Cu")
		(net "FM_LED_PWRGD_PVDD18_S5_P1")
	)
	(segment
		(start 245.98376 -82.451194)
		(end 307.602382 -82.451194)
		(width 0.11684)
		(layer "In15.Cu")
		(net "FM_LED_PWRGD_PVDD18_S5_P1")
	)
	(segment
		(start 204.983588 -89.171272)
		(end 206.345536 -87.809324)
		(width 0.11684)
		(layer "In15.Cu")
		(net "FM_LED_PWRGD_PVDD18_S5_P1")
	)
	(segment
		(start 307.602382 -82.451194)
		(end 308.887876 -81.1657)
		(width 0.11684)
		(layer "In15.Cu")
		(net "FM_LED_PWRGD_PVDD18_S5_P1")
	)
	(segment
		(start 183.27116 -88.94445)
		(end 184.235598 -89.908888)
		(width 0.11684)
		(layer "In15.Cu")
		(net "FM_LED_PWRGD_PVDD18_S5_P1")
	)
	(segment
		(start 317.245746 -68.953126)
		(end 317.245746 -67.446398)
		(width 0.11684)
		(layer "In15.Cu")
		(net "FM_LED_PWRGD_PVDD18_S5_P1")
	)
	(segment
		(start 169.90441 -86.530434)
		(end 172.84573 -86.530434)
		(width 0.11684)
		(layer "In15.Cu")
		(net "FM_LED_PWRGD_PVDD18_S5_P1")
	)
	(segment
		(start 316.538102 -69.66077)
		(end 317.245746 -68.953126)
		(width 0.11684)
		(layer "In15.Cu")
		(net "FM_LED_PWRGD_PVDD18_S5_P1")
	)
	(segment
		(start 317.245746 -67.446398)
		(end 317.86195 -66.830194)
		(width 0.11684)
		(layer "In15.Cu")
		(net "FM_LED_PWRGD_PVDD18_S5_P1")
	)
	(segment
		(start 203.4413 -114.964464)
		(end 210.833208 -114.964464)
		(width 0.10668)
		(layer "F.Cu")
		(net "FM_LED_PWRGD_PVDD18_S5_P0")
	)
	(segment
		(start 195.335652 -114.652806)
		(end 195.84162 -115.158774)
		(width 0.10668)
		(layer "F.Cu")
		(net "FM_LED_PWRGD_PVDD18_S5_P0")
	)
	(segment
		(start 326.86117 -80.873092)
		(end 308.607968 -80.873092)
		(width 0.10668)
		(layer "F.Cu")
		(net "FM_LED_PWRGD_PVDD18_S5_P0")
	)
	(segment
		(start 210.833208 -114.964464)
		(end 211.384896 -114.412776)
		(width 0.10668)
		(layer "F.Cu")
		(net "FM_LED_PWRGD_PVDD18_S5_P0")
	)
	(segment
		(start 203.24699 -115.158774)
		(end 203.4413 -114.964464)
		(width 0.10668)
		(layer "F.Cu")
		(net "FM_LED_PWRGD_PVDD18_S5_P0")
	)
	(segment
		(start 193.922142 -114.652806)
		(end 195.335652 -114.652806)
		(width 0.10668)
		(layer "F.Cu")
		(net "FM_LED_PWRGD_PVDD18_S5_P0")
	)
	(segment
		(start 195.84162 -115.158774)
		(end 203.24699 -115.158774)
		(width 0.10668)
		(layer "F.Cu")
		(net "FM_LED_PWRGD_PVDD18_S5_P0")
	)
	(segment
		(start 211.384896 -114.412776)
		(end 211.384896 -114.383312)
		(width 0.10668)
		(layer "F.Cu")
		(net "FM_LED_PWRGD_PVDD18_S5_P0")
	)
	(segment
		(start 330.725526 -77.008736)
		(end 326.86117 -80.873092)
		(width 0.10668)
		(layer "F.Cu")
		(net "FM_LED_PWRGD_PVDD18_S5_P0")
	)
	(segment
		(start 308.607968 -80.873092)
		(end 307.517292 -79.782416)
		(width 0.10668)
		(layer "F.Cu")
		(net "FM_LED_PWRGD_PVDD18_S5_P0")
	)
	(segment
		(start 307.517292 -79.782416)
		(end 307.517292 -79.672434)
		(width 0.10668)
		(layer "F.Cu")
		(net "FM_LED_PWRGD_PVDD18_S5_P0")
	)
	(via
		(at 330.725526 -77.008736)
		(size 0.508)
		(drill 0.254)
		(layers "F.Cu" "B.Cu")
		(net "FM_LED_PWRGD_PVDD18_S5_P0")
	)
	(via
		(at 307.517292 -79.672434)
		(size 0.508)
		(drill 0.254)
		(layers "F.Cu" "B.Cu")
		(net "FM_LED_PWRGD_PVDD18_S5_P0")
	)
	(via
		(at 215.39962 -85.969094)
		(size 0.508)
		(drill 0.254)
		(layers "F.Cu" "B.Cu")
		(net "FM_LED_PWRGD_PVDD18_S5_P0")
	)
	(via
		(at 211.384896 -114.383312)
		(size 0.508)
		(drill 0.254)
		(layers "F.Cu" "B.Cu")
		(net "FM_LED_PWRGD_PVDD18_S5_P0")
	)
	(via
		(at 217.917268 -113.93805)
		(size 0.508)
		(drill 0.254)
		(layers "F.Cu" "B.Cu")
		(net "FM_LED_PWRGD_PVDD18_S5_P0")
	)
	(via
		(at 203.24699 -115.158774)
		(size 0.762)
		(drill 0.381)
		(layers "F.Cu" "B.Cu")
		(net "FM_LED_PWRGD_PVDD18_S5_P0")
	)
	(segment
		(start 330.725526 -77.008736)
		(end 330.725526 -76.663042)
		(width 0.10668)
		(layer "B.Cu")
		(net "FM_LED_PWRGD_PVDD18_S5_P0")
	)
	(segment
		(start 330.725526 -76.663042)
		(end 331.029818 -76.35875)
		(width 0.10668)
		(layer "B.Cu")
		(net "FM_LED_PWRGD_PVDD18_S5_P0")
	)
	(segment
		(start 331.029818 -76.35875)
		(end 331.366876 -76.35875)
		(width 0.10668)
		(layer "B.Cu")
		(net "FM_LED_PWRGD_PVDD18_S5_P0")
	)
	(segment
		(start 210.885278 -97.625154)
		(end 210.885278 -91.839542)
		(width 0.11684)
		(layer "In4.Cu")
		(net "FM_LED_PWRGD_PVDD18_S5_P0")
	)
	(segment
		(start 215.998806 -106.304588)
		(end 214.967058 -105.27284)
		(width 0.11684)
		(layer "In4.Cu")
		(net "FM_LED_PWRGD_PVDD18_S5_P0")
	)
	(segment
		(start 214.967058 -105.27284)
		(end 214.967058 -101.706934)
		(width 0.11684)
		(layer "In4.Cu")
		(net "FM_LED_PWRGD_PVDD18_S5_P0")
	)
	(segment
		(start 214.967058 -101.706934)
		(end 210.885278 -97.625154)
		(width 0.11684)
		(layer "In4.Cu")
		(net "FM_LED_PWRGD_PVDD18_S5_P0")
	)
	(segment
		(start 212.406738 -88.961976)
		(end 215.39962 -85.969094)
		(width 0.11684)
		(layer "In4.Cu")
		(net "FM_LED_PWRGD_PVDD18_S5_P0")
	)
	(segment
		(start 215.998806 -108.812584)
		(end 215.998806 -106.304588)
		(width 0.11684)
		(layer "In4.Cu")
		(net "FM_LED_PWRGD_PVDD18_S5_P0")
	)
	(segment
		(start 217.917268 -110.731046)
		(end 215.998806 -108.812584)
		(width 0.11684)
		(layer "In4.Cu")
		(net "FM_LED_PWRGD_PVDD18_S5_P0")
	)
	(segment
		(start 212.406738 -90.318082)
		(end 212.406738 -88.961976)
		(width 0.11684)
		(layer "In4.Cu")
		(net "FM_LED_PWRGD_PVDD18_S5_P0")
	)
	(segment
		(start 217.917268 -113.93805)
		(end 217.917268 -110.731046)
		(width 0.11684)
		(layer "In4.Cu")
		(net "FM_LED_PWRGD_PVDD18_S5_P0")
	)
	(segment
		(start 210.885278 -91.839542)
		(end 212.406738 -90.318082)
		(width 0.11684)
		(layer "In4.Cu")
		(net "FM_LED_PWRGD_PVDD18_S5_P0")
	)
	(segment
		(start 216.5604 -88.52281)
		(end 239.315752 -88.52281)
		(width 0.11684)
		(layer "In15.Cu")
		(net "FM_LED_PWRGD_PVDD18_S5_P0")
	)
	(segment
		(start 217.29192 -113.312702)
		(end 217.917268 -113.93805)
		(width 0.11684)
		(layer "In15.Cu")
		(net "FM_LED_PWRGD_PVDD18_S5_P0")
	)
	(segment
		(start 239.315752 -88.52281)
		(end 245.809008 -82.029554)
		(width 0.11684)
		(layer "In15.Cu")
		(net "FM_LED_PWRGD_PVDD18_S5_P0")
	)
	(segment
		(start 215.39962 -85.969094)
		(end 215.39962 -87.36203)
		(width 0.11684)
		(layer "In15.Cu")
		(net "FM_LED_PWRGD_PVDD18_S5_P0")
	)
	(segment
		(start 245.809008 -82.029554)
		(end 305.164236 -82.029554)
		(width 0.11684)
		(layer "In15.Cu")
		(net "FM_LED_PWRGD_PVDD18_S5_P0")
	)
	(segment
		(start 211.384896 -114.383312)
		(end 211.41436 -114.353848)
		(width 0.11684)
		(layer "In15.Cu")
		(net "FM_LED_PWRGD_PVDD18_S5_P0")
	)
	(segment
		(start 211.41436 -114.353848)
		(end 213.001098 -114.353848)
		(width 0.11684)
		(layer "In15.Cu")
		(net "FM_LED_PWRGD_PVDD18_S5_P0")
	)
	(segment
		(start 214.042244 -113.312702)
		(end 217.29192 -113.312702)
		(width 0.11684)
		(layer "In15.Cu")
		(net "FM_LED_PWRGD_PVDD18_S5_P0")
	)
	(segment
		(start 305.437032 -81.756758)
		(end 305.437032 -81.752694)
		(width 0.11684)
		(layer "In15.Cu")
		(net "FM_LED_PWRGD_PVDD18_S5_P0")
	)
	(segment
		(start 213.001098 -114.353848)
		(end 214.042244 -113.312702)
		(width 0.11684)
		(layer "In15.Cu")
		(net "FM_LED_PWRGD_PVDD18_S5_P0")
	)
	(segment
		(start 305.437032 -81.752694)
		(end 307.517292 -79.672434)
		(width 0.11684)
		(layer "In15.Cu")
		(net "FM_LED_PWRGD_PVDD18_S5_P0")
	)
	(segment
		(start 215.39962 -87.36203)
		(end 216.5604 -88.52281)
		(width 0.11684)
		(layer "In15.Cu")
		(net "FM_LED_PWRGD_PVDD18_S5_P0")
	)
	(segment
		(start 305.164236 -82.029554)
		(end 305.437032 -81.756758)
		(width 0.11684)
		(layer "In15.Cu")
		(net "FM_LED_PWRGD_PVDD18_S5_P0")
	)
	(segment
		(start 177.922174 -121.052844)
		(end 177.523902 -121.451116)
		(width 0.10668)
		(layer "F.Cu")
		(net "FM_LED_PWRGD_PVDD11_S3_P1")
	)
	(segment
		(start 176.863248 -121.451116)
		(end 174.617888 -123.696476)
		(width 0.10668)
		(layer "F.Cu")
		(net "FM_LED_PWRGD_PVDD11_S3_P1")
	)
	(segment
		(start 177.523902 -121.451116)
		(end 176.863248 -121.451116)
		(width 0.10668)
		(layer "F.Cu")
		(net "FM_LED_PWRGD_PVDD11_S3_P1")
	)
	(via
		(at 171.986194 -87.798148)
		(size 0.508)
		(drill 0.254)
		(layers "F.Cu" "B.Cu")
		(net "FM_LED_PWRGD_PVDD11_S3_P1")
	)
	(via
		(at 346.987876 -73.138792)
		(size 0.762)
		(drill 0.254)
		(layers "F.Cu" "B.Cu")
		(net "FM_LED_PWRGD_PVDD11_S3_P1")
	)
	(via
		(at 174.617888 -123.696476)
		(size 0.508)
		(drill 0.254)
		(layers "F.Cu" "B.Cu")
		(net "FM_LED_PWRGD_PVDD11_S3_P1")
	)
	(segment
		(start 347.22943 -73.534778)
		(end 347.638624 -73.534778)
		(width 0.10668)
		(layer "B.Cu")
		(net "FM_LED_PWRGD_PVDD11_S3_P1")
	)
	(segment
		(start 346.987876 -73.138792)
		(end 346.987876 -73.293224)
		(width 0.10668)
		(layer "B.Cu")
		(net "FM_LED_PWRGD_PVDD11_S3_P1")
	)
	(segment
		(start 346.987876 -73.293224)
		(end 347.22943 -73.534778)
		(width 0.10668)
		(layer "B.Cu")
		(net "FM_LED_PWRGD_PVDD11_S3_P1")
	)
	(segment
		(start 172.08754 -107.178348)
		(end 172.08754 -104.768142)
		(width 0.11684)
		(layer "In11.Cu")
		(net "FM_LED_PWRGD_PVDD11_S3_P1")
	)
	(segment
		(start 175.28286 -119.791988)
		(end 174.42688 -118.936008)
		(width 0.11684)
		(layer "In11.Cu")
		(net "FM_LED_PWRGD_PVDD11_S3_P1")
	)
	(segment
		(start 168.51884 -97.388426)
		(end 169.079164 -96.828102)
		(width 0.11684)
		(layer "In11.Cu")
		(net "FM_LED_PWRGD_PVDD11_S3_P1")
	)
	(segment
		(start 172.08754 -88.068912)
		(end 172.08754 -87.899494)
		(width 0.11684)
		(layer "In11.Cu")
		(net "FM_LED_PWRGD_PVDD11_S3_P1")
	)
	(segment
		(start 170.673776 -89.482676)
		(end 172.08754 -88.068912)
		(width 0.11684)
		(layer "In11.Cu")
		(net "FM_LED_PWRGD_PVDD11_S3_P1")
	)
	(segment
		(start 170.673776 -90.201242)
		(end 170.673776 -89.482676)
		(width 0.11684)
		(layer "In11.Cu")
		(net "FM_LED_PWRGD_PVDD11_S3_P1")
	)
	(segment
		(start 174.617888 -123.696476)
		(end 174.617888 -121.151396)
		(width 0.11684)
		(layer "In11.Cu")
		(net "FM_LED_PWRGD_PVDD11_S3_P1")
	)
	(segment
		(start 168.51884 -98.272092)
		(end 168.51884 -97.388426)
		(width 0.11684)
		(layer "In11.Cu")
		(net "FM_LED_PWRGD_PVDD11_S3_P1")
	)
	(segment
		(start 174.42688 -115.651788)
		(end 173.35754 -114.582448)
		(width 0.11684)
		(layer "In11.Cu")
		(net "FM_LED_PWRGD_PVDD11_S3_P1")
	)
	(segment
		(start 169.2275 -101.908102)
		(end 169.2275 -98.980752)
		(width 0.11684)
		(layer "In11.Cu")
		(net "FM_LED_PWRGD_PVDD11_S3_P1")
	)
	(segment
		(start 175.28286 -120.486424)
		(end 175.28286 -119.791988)
		(width 0.11684)
		(layer "In11.Cu")
		(net "FM_LED_PWRGD_PVDD11_S3_P1")
	)
	(segment
		(start 169.079164 -91.795854)
		(end 170.673776 -90.201242)
		(width 0.11684)
		(layer "In11.Cu")
		(net "FM_LED_PWRGD_PVDD11_S3_P1")
	)
	(segment
		(start 172.08754 -87.899494)
		(end 171.986194 -87.798148)
		(width 0.11684)
		(layer "In11.Cu")
		(net "FM_LED_PWRGD_PVDD11_S3_P1")
	)
	(segment
		(start 173.35754 -108.448348)
		(end 172.08754 -107.178348)
		(width 0.11684)
		(layer "In11.Cu")
		(net "FM_LED_PWRGD_PVDD11_S3_P1")
	)
	(segment
		(start 169.079164 -96.828102)
		(end 169.079164 -91.795854)
		(width 0.11684)
		(layer "In11.Cu")
		(net "FM_LED_PWRGD_PVDD11_S3_P1")
	)
	(segment
		(start 173.35754 -114.582448)
		(end 173.35754 -108.448348)
		(width 0.11684)
		(layer "In11.Cu")
		(net "FM_LED_PWRGD_PVDD11_S3_P1")
	)
	(segment
		(start 172.08754 -104.768142)
		(end 169.2275 -101.908102)
		(width 0.11684)
		(layer "In11.Cu")
		(net "FM_LED_PWRGD_PVDD11_S3_P1")
	)
	(segment
		(start 169.2275 -98.980752)
		(end 168.51884 -98.272092)
		(width 0.11684)
		(layer "In11.Cu")
		(net "FM_LED_PWRGD_PVDD11_S3_P1")
	)
	(segment
		(start 174.617888 -121.151396)
		(end 175.28286 -120.486424)
		(width 0.11684)
		(layer "In11.Cu")
		(net "FM_LED_PWRGD_PVDD11_S3_P1")
	)
	(segment
		(start 174.42688 -118.936008)
		(end 174.42688 -115.651788)
		(width 0.11684)
		(layer "In11.Cu")
		(net "FM_LED_PWRGD_PVDD11_S3_P1")
	)
	(segment
		(start 310.77789 -70.08241)
		(end 316.712854 -70.08241)
		(width 0.11684)
		(layer "In15.Cu")
		(net "FM_LED_PWRGD_PVDD11_S3_P1")
	)
	(segment
		(start 318.036702 -67.251834)
		(end 340.53653 -67.251834)
		(width 0.11684)
		(layer "In15.Cu")
		(net "FM_LED_PWRGD_PVDD11_S3_P1")
	)
	(segment
		(start 187.597542 -90.330528)
		(end 188.335158 -89.592912)
		(width 0.11684)
		(layer "In15.Cu")
		(net "FM_LED_PWRGD_PVDD11_S3_P1")
	)
	(segment
		(start 317.667386 -67.62115)
		(end 318.036702 -67.251834)
		(width 0.11684)
		(layer "In15.Cu")
		(net "FM_LED_PWRGD_PVDD11_S3_P1")
	)
	(segment
		(start 206.362046 -88.389206)
		(end 214.568278 -88.389206)
		(width 0.11684)
		(layer "In15.Cu")
		(net "FM_LED_PWRGD_PVDD11_S3_P1")
	)
	(segment
		(start 205.15834 -89.592912)
		(end 206.362046 -88.389206)
		(width 0.11684)
		(layer "In15.Cu")
		(net "FM_LED_PWRGD_PVDD11_S3_P1")
	)
	(segment
		(start 246.158512 -82.872834)
		(end 307.777134 -82.872834)
		(width 0.11684)
		(layer "In15.Cu")
		(net "FM_LED_PWRGD_PVDD11_S3_P1")
	)
	(segment
		(start 173.554136 -89.36609)
		(end 183.096408 -89.36609)
		(width 0.11684)
		(layer "In15.Cu")
		(net "FM_LED_PWRGD_PVDD11_S3_P1")
	)
	(segment
		(start 340.53653 -67.251834)
		(end 343.599262 -70.314566)
		(width 0.11684)
		(layer "In15.Cu")
		(net "FM_LED_PWRGD_PVDD11_S3_P1")
	)
	(segment
		(start 316.712854 -70.08241)
		(end 317.667386 -69.127878)
		(width 0.11684)
		(layer "In15.Cu")
		(net "FM_LED_PWRGD_PVDD11_S3_P1")
	)
	(segment
		(start 317.667386 -69.127878)
		(end 317.667386 -67.62115)
		(width 0.11684)
		(layer "In15.Cu")
		(net "FM_LED_PWRGD_PVDD11_S3_P1")
	)
	(segment
		(start 215.545162 -89.36609)
		(end 239.665256 -89.36609)
		(width 0.11684)
		(layer "In15.Cu")
		(net "FM_LED_PWRGD_PVDD11_S3_P1")
	)
	(segment
		(start 343.599262 -73.485756)
		(end 344.76309 -74.649584)
		(width 0.11684)
		(layer "In15.Cu")
		(net "FM_LED_PWRGD_PVDD11_S3_P1")
	)
	(segment
		(start 307.777134 -82.872834)
		(end 309.309516 -81.340452)
		(width 0.11684)
		(layer "In15.Cu")
		(net "FM_LED_PWRGD_PVDD11_S3_P1")
	)
	(segment
		(start 183.096408 -89.36609)
		(end 184.060846 -90.330528)
		(width 0.11684)
		(layer "In15.Cu")
		(net "FM_LED_PWRGD_PVDD11_S3_P1")
	)
	(segment
		(start 344.76309 -74.649584)
		(end 345.477084 -74.649584)
		(width 0.11684)
		(layer "In15.Cu")
		(net "FM_LED_PWRGD_PVDD11_S3_P1")
	)
	(segment
		(start 184.060846 -90.330528)
		(end 187.597542 -90.330528)
		(width 0.11684)
		(layer "In15.Cu")
		(net "FM_LED_PWRGD_PVDD11_S3_P1")
	)
	(segment
		(start 171.986194 -87.798148)
		(end 173.554136 -89.36609)
		(width 0.11684)
		(layer "In15.Cu")
		(net "FM_LED_PWRGD_PVDD11_S3_P1")
	)
	(segment
		(start 239.665256 -89.36609)
		(end 246.158512 -82.872834)
		(width 0.11684)
		(layer "In15.Cu")
		(net "FM_LED_PWRGD_PVDD11_S3_P1")
	)
	(segment
		(start 343.599262 -70.314566)
		(end 343.599262 -73.485756)
		(width 0.11684)
		(layer "In15.Cu")
		(net "FM_LED_PWRGD_PVDD11_S3_P1")
	)
	(segment
		(start 188.335158 -89.592912)
		(end 205.15834 -89.592912)
		(width 0.11684)
		(layer "In15.Cu")
		(net "FM_LED_PWRGD_PVDD11_S3_P1")
	)
	(segment
		(start 309.309516 -71.550784)
		(end 310.77789 -70.08241)
		(width 0.11684)
		(layer "In15.Cu")
		(net "FM_LED_PWRGD_PVDD11_S3_P1")
	)
	(segment
		(start 309.309516 -81.340452)
		(end 309.309516 -71.550784)
		(width 0.11684)
		(layer "In15.Cu")
		(net "FM_LED_PWRGD_PVDD11_S3_P1")
	)
	(segment
		(start 345.477084 -74.649584)
		(end 346.987876 -73.138792)
		(width 0.11684)
		(layer "In15.Cu")
		(net "FM_LED_PWRGD_PVDD11_S3_P1")
	)
	(segment
		(start 214.568278 -88.389206)
		(end 215.545162 -89.36609)
		(width 0.11684)
		(layer "In15.Cu")
		(net "FM_LED_PWRGD_PVDD11_S3_P1")
	)
	(segment
		(start 192.322196 -115.452906)
		(end 192.712086 -115.842796)
		(width 0.10668)
		(layer "F.Cu")
		(net "FM_LED_PWRGD_PVDD11_S3_P0")
	)
	(via
		(at 202.438 -102.616)
		(size 0.508)
		(drill 0.254)
		(layers "F.Cu" "B.Cu")
		(net "FM_LED_PWRGD_PVDD11_S3_P0")
	)
	(via
		(at 330.731876 -74.184764)
		(size 0.762)
		(drill 0.254)
		(layers "F.Cu" "B.Cu")
		(net "FM_LED_PWRGD_PVDD11_S3_P0")
	)
	(via
		(at 192.712086 -115.842796)
		(size 0.4572)
		(drill 0.254)
		(layers "F.Cu" "B.Cu")
		(net "FM_LED_PWRGD_PVDD11_S3_P0")
	)
	(segment
		(start 330.731876 -74.184764)
		(end 330.731876 -73.861422)
		(width 0.10668)
		(layer "B.Cu")
		(net "FM_LED_PWRGD_PVDD11_S3_P0")
	)
	(segment
		(start 330.731876 -73.861422)
		(end 331.05852 -73.534778)
		(width 0.10668)
		(layer "B.Cu")
		(net "FM_LED_PWRGD_PVDD11_S3_P0")
	)
	(segment
		(start 331.05852 -73.534778)
		(end 331.514704 -73.534778)
		(width 0.10668)
		(layer "B.Cu")
		(net "FM_LED_PWRGD_PVDD11_S3_P0")
	)
	(segment
		(start 192.94348 -115.842796)
		(end 193.447416 -115.33886)
		(width 0.11684)
		(layer "In4.Cu")
		(net "FM_LED_PWRGD_PVDD11_S3_P0")
	)
	(segment
		(start 200.362058 -113.839244)
		(end 200.362058 -111.468408)
		(width 0.11684)
		(layer "In4.Cu")
		(net "FM_LED_PWRGD_PVDD11_S3_P0")
	)
	(segment
		(start 202.438 -104.121458)
		(end 202.438 -102.616)
		(width 0.11684)
		(layer "In4.Cu")
		(net "FM_LED_PWRGD_PVDD11_S3_P0")
	)
	(segment
		(start 198.174102 -114.15522)
		(end 200.046082 -114.15522)
		(width 0.11684)
		(layer "In4.Cu")
		(net "FM_LED_PWRGD_PVDD11_S3_P0")
	)
	(segment
		(start 200.046082 -114.15522)
		(end 200.362058 -113.839244)
		(width 0.11684)
		(layer "In4.Cu")
		(net "FM_LED_PWRGD_PVDD11_S3_P0")
	)
	(segment
		(start 193.447416 -115.33886)
		(end 196.990462 -115.33886)
		(width 0.11684)
		(layer "In4.Cu")
		(net "FM_LED_PWRGD_PVDD11_S3_P0")
	)
	(segment
		(start 202.720702 -108.829348)
		(end 202.720702 -104.40416)
		(width 0.11684)
		(layer "In4.Cu")
		(net "FM_LED_PWRGD_PVDD11_S3_P0")
	)
	(segment
		(start 192.712086 -115.842796)
		(end 192.94348 -115.842796)
		(width 0.11684)
		(layer "In4.Cu")
		(net "FM_LED_PWRGD_PVDD11_S3_P0")
	)
	(segment
		(start 201.832464 -109.026706)
		(end 202.523344 -109.026706)
		(width 0.11684)
		(layer "In4.Cu")
		(net "FM_LED_PWRGD_PVDD11_S3_P0")
	)
	(segment
		(start 196.990462 -115.33886)
		(end 198.174102 -114.15522)
		(width 0.11684)
		(layer "In4.Cu")
		(net "FM_LED_PWRGD_PVDD11_S3_P0")
	)
	(segment
		(start 202.523344 -109.026706)
		(end 202.720702 -108.829348)
		(width 0.11684)
		(layer "In4.Cu")
		(net "FM_LED_PWRGD_PVDD11_S3_P0")
	)
	(segment
		(start 201.309732 -109.549438)
		(end 201.832464 -109.026706)
		(width 0.11684)
		(layer "In4.Cu")
		(net "FM_LED_PWRGD_PVDD11_S3_P0")
	)
	(segment
		(start 200.362058 -111.468408)
		(end 201.309732 -110.520734)
		(width 0.11684)
		(layer "In4.Cu")
		(net "FM_LED_PWRGD_PVDD11_S3_P0")
	)
	(segment
		(start 201.309732 -110.520734)
		(end 201.309732 -109.549438)
		(width 0.11684)
		(layer "In4.Cu")
		(net "FM_LED_PWRGD_PVDD11_S3_P0")
	)
	(segment
		(start 202.720702 -104.40416)
		(end 202.438 -104.121458)
		(width 0.11684)
		(layer "In4.Cu")
		(net "FM_LED_PWRGD_PVDD11_S3_P0")
	)
	(segment
		(start 326.300338 -75.071224)
		(end 325.781416 -74.552302)
		(width 0.11684)
		(layer "In15.Cu")
		(net "FM_LED_PWRGD_PVDD11_S3_P0")
	)
	(segment
		(start 329.845416 -75.071224)
		(end 326.300338 -75.071224)
		(width 0.11684)
		(layer "In15.Cu")
		(net "FM_LED_PWRGD_PVDD11_S3_P0")
	)
	(segment
		(start 211.689696 -100.76053)
		(end 210.964526 -100.76053)
		(width 0.11684)
		(layer "In15.Cu")
		(net "FM_LED_PWRGD_PVDD11_S3_P0")
	)
	(segment
		(start 202.922124 -103.100124)
		(end 202.438 -102.616)
		(width 0.11684)
		(layer "In15.Cu")
		(net "FM_LED_PWRGD_PVDD11_S3_P0")
	)
	(segment
		(start 325.781416 -74.552302)
		(end 325.781416 -72.159622)
		(width 0.11684)
		(layer "In15.Cu")
		(net "FM_LED_PWRGD_PVDD11_S3_P0")
	)
	(segment
		(start 312.421778 -85.402674)
		(end 247.207024 -85.402674)
		(width 0.11684)
		(layer "In15.Cu")
		(net "FM_LED_PWRGD_PVDD11_S3_P0")
	)
	(segment
		(start 247.207024 -85.402674)
		(end 232.923588 -99.68611)
		(width 0.11684)
		(layer "In15.Cu")
		(net "FM_LED_PWRGD_PVDD11_S3_P0")
	)
	(segment
		(start 210.964526 -100.76053)
		(end 208.624932 -103.100124)
		(width 0.11684)
		(layer "In15.Cu")
		(net "FM_LED_PWRGD_PVDD11_S3_P0")
	)
	(segment
		(start 208.624932 -103.100124)
		(end 202.922124 -103.100124)
		(width 0.11684)
		(layer "In15.Cu")
		(net "FM_LED_PWRGD_PVDD11_S3_P0")
	)
	(segment
		(start 324.44309 -71.403972)
		(end 323.068696 -72.778366)
		(width 0.11684)
		(layer "In15.Cu")
		(net "FM_LED_PWRGD_PVDD11_S3_P0")
	)
	(segment
		(start 212.764116 -99.68611)
		(end 211.689696 -100.76053)
		(width 0.11684)
		(layer "In15.Cu")
		(net "FM_LED_PWRGD_PVDD11_S3_P0")
	)
	(segment
		(start 330.731876 -74.184764)
		(end 329.845416 -75.071224)
		(width 0.11684)
		(layer "In15.Cu")
		(net "FM_LED_PWRGD_PVDD11_S3_P0")
	)
	(segment
		(start 325.025766 -71.403972)
		(end 324.44309 -71.403972)
		(width 0.11684)
		(layer "In15.Cu")
		(net "FM_LED_PWRGD_PVDD11_S3_P0")
	)
	(segment
		(start 323.068696 -74.755756)
		(end 312.421778 -85.402674)
		(width 0.11684)
		(layer "In15.Cu")
		(net "FM_LED_PWRGD_PVDD11_S3_P0")
	)
	(segment
		(start 232.923588 -99.68611)
		(end 212.764116 -99.68611)
		(width 0.11684)
		(layer "In15.Cu")
		(net "FM_LED_PWRGD_PVDD11_S3_P0")
	)
	(segment
		(start 323.068696 -72.778366)
		(end 323.068696 -74.755756)
		(width 0.11684)
		(layer "In15.Cu")
		(net "FM_LED_PWRGD_PVDD11_S3_P0")
	)
	(segment
		(start 325.781416 -72.159622)
		(end 325.025766 -71.403972)
		(width 0.11684)
		(layer "In15.Cu")
		(net "FM_LED_PWRGD_PVDD11_S3_P0")
	)
	(segment
		(start 149.987254 -22.074886)
		(end 149.987254 -22.884892)
		(width 0.10668)
		(layer "F.Cu")
		(net "SGPIO_SCM_INTR_R1_N")
	)
	(segment
		(start 152.0571 -16.549878)
		(end 152.0571 -17.882616)
		(width 0.10668)
		(layer "F.Cu")
		(net "SGPIO_SCM_INTR_R1_N")
	)
	(segment
		(start 149.987254 -19.952462)
		(end 149.987254 -22.074886)
		(width 0.10668)
		(layer "F.Cu")
		(net "SGPIO_SCM_INTR_R1_N")
	)
	(segment
		(start 152.0571 -17.882616)
		(end 149.987254 -19.952462)
		(width 0.10668)
		(layer "F.Cu")
		(net "SGPIO_SCM_INTR_R1_N")
	)
	(via
		(at 149.987254 -22.074886)
		(size 0.508)
		(drill 0.254)
		(layers "F.Cu" "B.Cu")
		(net "SGPIO_SCM_INTR_R1_N")
	)
	(segment
		(start 145.640552 -104.324912)
		(end 144.999202 -104.324912)
		(width 0.10668)
		(layer "F.Cu")
		(net "NC_Q95_S2")
	)
	(via
		(at 144.999202 -104.324912)
		(size 0.508)
		(drill 0.254)
		(layers "F.Cu" "B.Cu")
		(net "NC_Q95_S2")
	)
	(segment
		(start 145.640552 -104.974898)
		(end 146.281902 -104.974898)
		(width 0.10668)
		(layer "F.Cu")
		(net "NC_Q95_G2")
	)
	(via
		(at 146.281902 -104.974898)
		(size 0.508)
		(drill 0.254)
		(layers "F.Cu" "B.Cu")
		(net "NC_Q95_G2")
	)
	(segment
		(start 143.740632 -104.324912)
		(end 143.740632 -104.307132)
		(width 0.10668)
		(layer "F.Cu")
		(net "NC_Q95_D2")
	)
	(segment
		(start 143.225012 -103.791512)
		(end 140.64361 -103.791512)
		(width 0.10668)
		(layer "F.Cu")
		(net "NC_Q95_D2")
	)
	(segment
		(start 143.740632 -104.307132)
		(end 143.225012 -103.791512)
		(width 0.10668)
		(layer "F.Cu")
		(net "NC_Q95_D2")
	)
	(via
		(at 140.64361 -103.791512)
		(size 0.762)
		(drill 0.381)
		(layers "F.Cu" "B.Cu")
		(net "NC_Q95_D2")
	)
	(segment
		(start 130.067304 -51.594766)
		(end 129.883154 -51.410616)
		(width 0.10668)
		(layer "F.Cu")
		(net "JTAG_TDO_R")
	)
	(segment
		(start 130.067304 -53.274468)
		(end 130.067304 -52.426616)
		(width 0.10668)
		(layer "F.Cu")
		(net "JTAG_TDO_R")
	)
	(segment
		(start 130.067304 -52.426616)
		(end 130.067304 -51.594766)
		(width 0.10668)
		(layer "F.Cu")
		(net "JTAG_TDO_R")
	)
	(via
		(at 130.067304 -52.426616)
		(size 0.508)
		(drill 0.254)
		(layers "F.Cu" "B.Cu")
		(net "JTAG_TDO_R")
	)
	(segment
		(start 235.315506 -161.231326)
		(end 235.315506 -159.943546)
		(width 0.10668)
		(layer "F.Cu")
		(net "JTAG_CPUX_TDO_R")
	)
	(segment
		(start 231.660954 -161.421572)
		(end 231.9528 -161.713418)
		(width 0.10668)
		(layer "F.Cu")
		(net "JTAG_CPUX_TDO_R")
	)
	(segment
		(start 231.92232 -160.322768)
		(end 231.660954 -160.584134)
		(width 0.10668)
		(layer "F.Cu")
		(net "JTAG_CPUX_TDO_R")
	)
	(segment
		(start 235.315506 -159.943546)
		(end 235.581952 -159.6771)
		(width 0.10668)
		(layer "F.Cu")
		(net "JTAG_CPUX_TDO_R")
	)
	(segment
		(start 235.581952 -159.6771)
		(end 236.584998 -159.6771)
		(width 0.10668)
		(layer "F.Cu")
		(net "JTAG_CPUX_TDO_R")
	)
	(segment
		(start 232.889806 -160.322768)
		(end 231.92232 -160.322768)
		(width 0.10668)
		(layer "F.Cu")
		(net "JTAG_CPUX_TDO_R")
	)
	(segment
		(start 231.660954 -160.584134)
		(end 231.660954 -161.421572)
		(width 0.10668)
		(layer "F.Cu")
		(net "JTAG_CPUX_TDO_R")
	)
	(segment
		(start 231.9528 -161.713418)
		(end 234.833414 -161.713418)
		(width 0.10668)
		(layer "F.Cu")
		(net "JTAG_CPUX_TDO_R")
	)
	(segment
		(start 239.898174 -159.680148)
		(end 238.678974 -159.680148)
		(width 0.10668)
		(layer "F.Cu")
		(net "JTAG_CPUX_TDO_R")
	)
	(segment
		(start 236.58957 -159.672528)
		(end 238.671354 -159.672528)
		(width 0.10668)
		(layer "F.Cu")
		(net "JTAG_CPUX_TDO_R")
	)
	(segment
		(start 238.671354 -159.672528)
		(end 238.678974 -159.680148)
		(width 0.10668)
		(layer "F.Cu")
		(net "JTAG_CPUX_TDO_R")
	)
	(segment
		(start 234.833414 -161.713418)
		(end 235.315506 -161.231326)
		(width 0.10668)
		(layer "F.Cu")
		(net "JTAG_CPUX_TDO_R")
	)
	(segment
		(start 236.584998 -159.6771)
		(end 236.58957 -159.672528)
		(width 0.10668)
		(layer "F.Cu")
		(net "JTAG_CPUX_TDO_R")
	)
	(via
		(at 238.678974 -159.680148)
		(size 0.762)
		(drill 0.381)
		(layers "F.Cu" "B.Cu")
		(net "JTAG_CPUX_TDO_R")
	)
	(segment
		(start 120.796812 -54.60619)
		(end 120.96623 -54.775608)
		(width 0.10668)
		(layer "F.Cu")
		(net "HDT_HDR_TDO_R")
	)
	(segment
		(start 120.76049 -54.569868)
		(end 120.796812 -54.60619)
		(width 0.10668)
		(layer "F.Cu")
		(net "HDT_HDR_TDO_R")
	)
	(segment
		(start 120.96623 -54.775608)
		(end 122.227594 -54.775608)
		(width 0.10668)
		(layer "F.Cu")
		(net "HDT_HDR_TDO_R")
	)
	(segment
		(start 120.76049 -53.26634)
		(end 120.76049 -54.569868)
		(width 0.10668)
		(layer "F.Cu")
		(net "HDT_HDR_TDO_R")
	)
	(via
		(at 120.796812 -54.60619)
		(size 0.762)
		(drill 0.381)
		(layers "F.Cu" "B.Cu")
		(net "HDT_HDR_TDO_R")
	)
	(segment
		(start 474.905324 -359.265982)
		(end 474.650308 -359.010966)
		(width 0.10668)
		(layer "F.Cu")
		(net "TDR_SE_50_OHM_TOP")
	)
	(segment
		(start 472.365324 -359.250742)
		(end 472.365324 -434.088794)
		(width 0.10668)
		(layer "F.Cu")
		(net "TDR_SE_50_OHM_TOP")
	)
	(segment
		(start 472.6051 -359.010966)
		(end 472.365324 -359.250742)
		(width 0.10668)
		(layer "F.Cu")
		(net "TDR_SE_50_OHM_TOP")
	)
	(segment
		(start 474.650308 -359.010966)
		(end 472.6051 -359.010966)
		(width 0.10668)
		(layer "F.Cu")
		(net "TDR_SE_50_OHM_TOP")
	)
	(segment
		(start 474.905324 -434.088794)
		(end 474.905324 -359.265982)
		(width 0.10668)
		(layer "F.Cu")
		(net "TDR_SE_50_OHM_TOP")
	)
	(segment
		(start 526.291048 -102.328472)
		(end 526.556732 -102.594156)
		(width 0.11684)
		(layer "In15.Cu")
		(net "TDR_SE_50_OHM_IN6")
	)
	(segment
		(start 526.556732 -102.594156)
		(end 528.585684 -102.594156)
		(width 0.11684)
		(layer "In15.Cu")
		(net "TDR_SE_50_OHM_IN6")
	)
	(segment
		(start 528.831048 -102.348792)
		(end 528.831048 -27.511248)
		(width 0.11684)
		(layer "In15.Cu")
		(net "TDR_SE_50_OHM_IN6")
	)
	(segment
		(start 528.585684 -102.594156)
		(end 528.831048 -102.348792)
		(width 0.11684)
		(layer "In15.Cu")
		(net "TDR_SE_50_OHM_IN6")
	)
	(segment
		(start 526.291048 -27.511248)
		(end 526.291048 -102.328472)
		(width 0.11684)
		(layer "In15.Cu")
		(net "TDR_SE_50_OHM_IN6")
	)
	(segment
		(start 477.830642 -356.734618)
		(end 477.830642 -431.551842)
		(width 0.11684)
		(layer "In13.Cu")
		(net "TDR_SE_50_OHM_IN5")
	)
	(segment
		(start 480.370642 -431.572162)
		(end 480.370642 -356.734618)
		(width 0.11684)
		(layer "In13.Cu")
		(net "TDR_SE_50_OHM_IN5")
	)
	(segment
		(start 480.125278 -431.817526)
		(end 480.370642 -431.572162)
		(width 0.11684)
		(layer "In13.Cu")
		(net "TDR_SE_50_OHM_IN5")
	)
	(segment
		(start 477.830642 -431.551842)
		(end 478.096326 -431.817526)
		(width 0.11684)
		(layer "In13.Cu")
		(net "TDR_SE_50_OHM_IN5")
	)
	(segment
		(start 478.096326 -431.817526)
		(end 480.125278 -431.817526)
		(width 0.11684)
		(layer "In13.Cu")
		(net "TDR_SE_50_OHM_IN5")
	)
	(segment
		(start 480.093274 -359.085134)
		(end 478.064322 -359.085134)
		(width 0.11684)
		(layer "In11.Cu")
		(net "TDR_SE_50_OHM_IN4")
	)
	(segment
		(start 478.064322 -359.085134)
		(end 477.818958 -359.330498)
		(width 0.11684)
		(layer "In11.Cu")
		(net "TDR_SE_50_OHM_IN4")
	)
	(segment
		(start 480.358958 -359.350818)
		(end 480.093274 -359.085134)
		(width 0.11684)
		(layer "In11.Cu")
		(net "TDR_SE_50_OHM_IN4")
	)
	(segment
		(start 480.358958 -434.168042)
		(end 480.358958 -359.350818)
		(width 0.11684)
		(layer "In11.Cu")
		(net "TDR_SE_50_OHM_IN4")
	)
	(segment
		(start 477.818958 -359.330498)
		(end 477.818958 -434.168042)
		(width 0.11684)
		(layer "In11.Cu")
		(net "TDR_SE_50_OHM_IN4")
	)
	(segment
		(start 480.65436 -29.533342)
		(end 480.65436 -104.350566)
		(width 0.11684)
		(layer "In6.Cu")
		(net "TDR_SE_50_OHM_IN3")
	)
	(segment
		(start 480.388676 -29.267658)
		(end 480.65436 -29.533342)
		(width 0.11684)
		(layer "In6.Cu")
		(net "TDR_SE_50_OHM_IN3")
	)
	(segment
		(start 478.11436 -104.350566)
		(end 478.11436 -29.513022)
		(width 0.11684)
		(layer "In6.Cu")
		(net "TDR_SE_50_OHM_IN3")
	)
	(segment
		(start 478.359724 -29.267658)
		(end 480.388676 -29.267658)
		(width 0.11684)
		(layer "In6.Cu")
		(net "TDR_SE_50_OHM_IN3")
	)
	(segment
		(start 478.11436 -29.513022)
		(end 478.359724 -29.267658)
		(width 0.11684)
		(layer "In6.Cu")
		(net "TDR_SE_50_OHM_IN3")
	)
	(segment
		(start 480.287584 -102.334822)
		(end 480.532948 -102.089458)
		(width 0.11684)
		(layer "In4.Cu")
		(net "TDR_SE_50_OHM_IN2")
	)
	(segment
		(start 477.992948 -27.251914)
		(end 477.992948 -102.069138)
		(width 0.11684)
		(layer "In4.Cu")
		(net "TDR_SE_50_OHM_IN2")
	)
	(segment
		(start 477.992948 -102.069138)
		(end 478.258632 -102.334822)
		(width 0.11684)
		(layer "In4.Cu")
		(net "TDR_SE_50_OHM_IN2")
	)
	(segment
		(start 478.258632 -102.334822)
		(end 480.287584 -102.334822)
		(width 0.11684)
		(layer "In4.Cu")
		(net "TDR_SE_50_OHM_IN2")
	)
	(segment
		(start 480.532948 -102.089458)
		(end 480.532948 -27.251914)
		(width 0.11684)
		(layer "In4.Cu")
		(net "TDR_SE_50_OHM_IN2")
	)
	(segment
		(start 472.436444 -356.468172)
		(end 472.436444 -431.285396)
		(width 0.11684)
		(layer "In2.Cu")
		(net "TDR_SE_50_OHM_IN1")
	)
	(segment
		(start 472.436444 -431.285396)
		(end 472.702128 -431.55108)
		(width 0.11684)
		(layer "In2.Cu")
		(net "TDR_SE_50_OHM_IN1")
	)
	(segment
		(start 474.976444 -431.305716)
		(end 474.976444 -356.468172)
		(width 0.11684)
		(layer "In2.Cu")
		(net "TDR_SE_50_OHM_IN1")
	)
	(segment
		(start 474.73108 -431.55108)
		(end 474.976444 -431.305716)
		(width 0.11684)
		(layer "In2.Cu")
		(net "TDR_SE_50_OHM_IN1")
	)
	(segment
		(start 472.702128 -431.55108)
		(end 474.73108 -431.55108)
		(width 0.11684)
		(layer "In2.Cu")
		(net "TDR_SE_50_OHM_IN1")
	)
	(segment
		(start 526.066512 -29.512514)
		(end 526.066512 -104.350566)
		(width 0.10668)
		(layer "B.Cu")
		(net "TDR_SE_50_OHM_BOT")
	)
	(segment
		(start 528.35302 -29.274262)
		(end 526.304764 -29.274262)
		(width 0.10668)
		(layer "B.Cu")
		(net "TDR_SE_50_OHM_BOT")
	)
	(segment
		(start 526.304764 -29.274262)
		(end 526.066512 -29.512514)
		(width 0.10668)
		(layer "B.Cu")
		(net "TDR_SE_50_OHM_BOT")
	)
	(segment
		(start 528.606512 -104.350566)
		(end 528.606512 -29.527754)
		(width 0.10668)
		(layer "B.Cu")
		(net "TDR_SE_50_OHM_BOT")
	)
	(segment
		(start 528.606512 -29.527754)
		(end 528.35302 -29.274262)
		(width 0.10668)
		(layer "B.Cu")
		(net "TDR_SE_50_OHM_BOT")
	)
	(segment
		(start 478.351342 -216.107264)
		(end 478.351342 -290.930076)
		(width 0.13208)
		(layer "F.Cu")
		(net "TDR_SE_45_OHM_TOP")
	)
	(segment
		(start 480.891342 -290.945316)
		(end 480.891342 -216.107264)
		(width 0.13208)
		(layer "F.Cu")
		(net "TDR_SE_45_OHM_TOP")
	)
	(segment
		(start 478.606358 -291.185092)
		(end 480.651566 -291.185092)
		(width 0.13208)
		(layer "F.Cu")
		(net "TDR_SE_45_OHM_TOP")
	)
	(segment
		(start 480.651566 -291.185092)
		(end 480.891342 -290.945316)
		(width 0.13208)
		(layer "F.Cu")
		(net "TDR_SE_45_OHM_TOP")
	)
	(segment
		(start 478.351342 -290.930076)
		(end 478.606358 -291.185092)
		(width 0.13208)
		(layer "F.Cu")
		(net "TDR_SE_45_OHM_TOP")
	)
	(segment
		(start 473.02293 -290.912042)
		(end 473.283026 -291.172138)
		(width 0.14478)
		(layer "In15.Cu")
		(net "TDR_SE_45_OHM_IN6")
	)
	(segment
		(start 473.02293 -216.094818)
		(end 473.02293 -290.912042)
		(width 0.14478)
		(layer "In15.Cu")
		(net "TDR_SE_45_OHM_IN6")
	)
	(segment
		(start 475.56293 -290.932362)
		(end 475.56293 -216.094818)
		(width 0.14478)
		(layer "In15.Cu")
		(net "TDR_SE_45_OHM_IN6")
	)
	(segment
		(start 475.323154 -291.172138)
		(end 475.56293 -290.932362)
		(width 0.14478)
		(layer "In15.Cu")
		(net "TDR_SE_45_OHM_IN6")
	)
	(segment
		(start 473.283026 -291.172138)
		(end 475.323154 -291.172138)
		(width 0.14478)
		(layer "In15.Cu")
		(net "TDR_SE_45_OHM_IN6")
	)
	(segment
		(start 472.859608 -123.974606)
		(end 472.604592 -124.229622)
		(width 0.14478)
		(layer "In13.Cu")
		(net "TDR_SE_45_OHM_IN5")
	)
	(segment
		(start 474.869256 -123.974606)
		(end 472.859608 -123.974606)
		(width 0.14478)
		(layer "In13.Cu")
		(net "TDR_SE_45_OHM_IN5")
	)
	(segment
		(start 475.144592 -199.067166)
		(end 475.144592 -124.249942)
		(width 0.14478)
		(layer "In13.Cu")
		(net "TDR_SE_45_OHM_IN5")
	)
	(segment
		(start 475.144592 -124.249942)
		(end 474.869256 -123.974606)
		(width 0.14478)
		(layer "In13.Cu")
		(net "TDR_SE_45_OHM_IN5")
	)
	(segment
		(start 472.604592 -124.229622)
		(end 472.604592 -199.067166)
		(width 0.14478)
		(layer "In13.Cu")
		(net "TDR_SE_45_OHM_IN5")
	)
	(segment
		(start 475.43466 -195.887086)
		(end 475.43466 -121.049542)
		(width 0.14478)
		(layer "In11.Cu")
		(net "TDR_SE_45_OHM_IN4")
	)
	(segment
		(start 472.89466 -121.049542)
		(end 472.89466 -195.866766)
		(width 0.14478)
		(layer "In11.Cu")
		(net "TDR_SE_45_OHM_IN4")
	)
	(segment
		(start 475.13748 -196.184266)
		(end 475.43466 -195.887086)
		(width 0.14478)
		(layer "In11.Cu")
		(net "TDR_SE_45_OHM_IN4")
	)
	(segment
		(start 473.21216 -196.184266)
		(end 475.13748 -196.184266)
		(width 0.14478)
		(layer "In11.Cu")
		(net "TDR_SE_45_OHM_IN4")
	)
	(segment
		(start 472.89466 -195.866766)
		(end 473.21216 -196.184266)
		(width 0.14478)
		(layer "In11.Cu")
		(net "TDR_SE_45_OHM_IN4")
	)
	(segment
		(start 480.715066 -219.403168)
		(end 480.715066 -294.220392)
		(width 0.14478)
		(layer "In6.Cu")
		(net "TDR_SE_45_OHM_IN3")
	)
	(segment
		(start 478.472246 -219.085668)
		(end 480.397566 -219.085668)
		(width 0.14478)
		(layer "In6.Cu")
		(net "TDR_SE_45_OHM_IN3")
	)
	(segment
		(start 480.397566 -219.085668)
		(end 480.715066 -219.403168)
		(width 0.14478)
		(layer "In6.Cu")
		(net "TDR_SE_45_OHM_IN3")
	)
	(segment
		(start 478.175066 -219.382848)
		(end 478.472246 -219.085668)
		(width 0.14478)
		(layer "In6.Cu")
		(net "TDR_SE_45_OHM_IN3")
	)
	(segment
		(start 478.175066 -294.220392)
		(end 478.175066 -219.382848)
		(width 0.14478)
		(layer "In6.Cu")
		(net "TDR_SE_45_OHM_IN3")
	)
	(segment
		(start 480.62896 -199.002396)
		(end 480.62896 -124.185172)
		(width 0.14478)
		(layer "In4.Cu")
		(net "TDR_SE_45_OHM_IN2")
	)
	(segment
		(start 480.31146 -123.867672)
		(end 478.38614 -123.867672)
		(width 0.14478)
		(layer "In4.Cu")
		(net "TDR_SE_45_OHM_IN2")
	)
	(segment
		(start 480.62896 -124.185172)
		(end 480.31146 -123.867672)
		(width 0.14478)
		(layer "In4.Cu")
		(net "TDR_SE_45_OHM_IN2")
	)
	(segment
		(start 478.38614 -123.867672)
		(end 478.08896 -124.164852)
		(width 0.14478)
		(layer "In4.Cu")
		(net "TDR_SE_45_OHM_IN2")
	)
	(segment
		(start 478.08896 -124.164852)
		(end 478.08896 -199.002396)
		(width 0.14478)
		(layer "In4.Cu")
		(net "TDR_SE_45_OHM_IN2")
	)
	(segment
		(start 480.748594 -121.123456)
		(end 480.748594 -195.961)
		(width 0.14478)
		(layer "In2.Cu")
		(net "TDR_SE_45_OHM_IN1")
	)
	(segment
		(start 478.208594 -195.94068)
		(end 478.208594 -121.123456)
		(width 0.14478)
		(layer "In2.Cu")
		(net "TDR_SE_45_OHM_IN1")
	)
	(segment
		(start 480.748594 -195.961)
		(end 480.451414 -196.25818)
		(width 0.14478)
		(layer "In2.Cu")
		(net "TDR_SE_45_OHM_IN1")
	)
	(segment
		(start 478.526094 -196.25818)
		(end 478.208594 -195.94068)
		(width 0.14478)
		(layer "In2.Cu")
		(net "TDR_SE_45_OHM_IN1")
	)
	(segment
		(start 480.451414 -196.25818)
		(end 478.526094 -196.25818)
		(width 0.14478)
		(layer "In2.Cu")
		(net "TDR_SE_45_OHM_IN1")
	)
	(segment
		(start 475.169992 -219.062554)
		(end 475.43466 -219.327222)
		(width 0.13208)
		(layer "B.Cu")
		(net "TDR_SE_45_OHM_BOT")
	)
	(segment
		(start 475.43466 -219.327222)
		(end 475.43466 -294.150034)
		(width 0.13208)
		(layer "B.Cu")
		(net "TDR_SE_45_OHM_BOT")
	)
	(segment
		(start 473.144088 -219.062554)
		(end 475.169992 -219.062554)
		(width 0.13208)
		(layer "B.Cu")
		(net "TDR_SE_45_OHM_BOT")
	)
	(segment
		(start 472.89466 -219.311982)
		(end 473.144088 -219.062554)
		(width 0.13208)
		(layer "B.Cu")
		(net "TDR_SE_45_OHM_BOT")
	)
	(segment
		(start 472.89466 -294.150034)
		(end 472.89466 -219.311982)
		(width 0.13208)
		(layer "B.Cu")
		(net "TDR_SE_45_OHM_BOT")
	)
	(segment
		(start 521.475208 -142.753334)
		(end 521.475208 7.406386)
		(width 0.12954)
		(layer "F.Cu")
		(net "TDR_DIFF_85_TOP_DP")
	)
	(segment
		(start 521.475208 7.406386)
		(end 521.604748 7.535926)
		(width 0.12954)
		(layer "F.Cu")
		(net "TDR_DIFF_85_TOP_DP")
	)
	(segment
		(start 522.584426 -142.882874)
		(end 521.604748 -142.882874)
		(width 0.12954)
		(layer "F.Cu")
		(net "TDR_DIFF_85_TOP_DP")
	)
	(segment
		(start 521.604748 -142.882874)
		(end 521.475208 -142.753334)
		(width 0.12954)
		(layer "F.Cu")
		(net "TDR_DIFF_85_TOP_DP")
	)
	(segment
		(start 521.604748 7.535926)
		(end 522.584426 7.535926)
		(width 0.12954)
		(layer "F.Cu")
		(net "TDR_DIFF_85_TOP_DP")
	)
	(segment
		(start 521.152628 7.409434)
		(end 521.152628 -142.756382)
		(width 0.12954)
		(layer "F.Cu")
		(net "TDR_DIFF_85_TOP_DN")
	)
	(segment
		(start 521.152628 -142.756382)
		(end 521.026136 -142.882874)
		(width 0.12954)
		(layer "F.Cu")
		(net "TDR_DIFF_85_TOP_DN")
	)
	(segment
		(start 521.026136 7.535926)
		(end 521.152628 7.409434)
		(width 0.12954)
		(layer "F.Cu")
		(net "TDR_DIFF_85_TOP_DN")
	)
	(segment
		(start 520.044426 7.535926)
		(end 521.026136 7.535926)
		(width 0.12954)
		(layer "F.Cu")
		(net "TDR_DIFF_85_TOP_DN")
	)
	(segment
		(start 521.026136 -142.882874)
		(end 520.044426 -142.882874)
		(width 0.12954)
		(layer "F.Cu")
		(net "TDR_DIFF_85_TOP_DN")
	)
	(segment
		(start 489.175044 -306.87264)
		(end 488.986322 -307.061362)
		(width 0.1143)
		(layer "In15.Cu")
		(net "TDR_DIFF_85_NECK_IN6_DP")
	)
	(segment
		(start 488.986322 -307.061362)
		(end 488.986322 -457.061062)
		(width 0.1143)
		(layer "In15.Cu")
		(net "TDR_DIFF_85_NECK_IN6_DP")
	)
	(segment
		(start 489.2167 -457.29144)
		(end 490.160564 -457.29144)
		(width 0.1143)
		(layer "In15.Cu")
		(net "TDR_DIFF_85_NECK_IN6_DP")
	)
	(segment
		(start 490.160564 -306.87264)
		(end 489.175044 -306.87264)
		(width 0.1143)
		(layer "In15.Cu")
		(net "TDR_DIFF_85_NECK_IN6_DP")
	)
	(segment
		(start 488.986322 -457.061062)
		(end 489.2167 -457.29144)
		(width 0.1143)
		(layer "In15.Cu")
		(net "TDR_DIFF_85_NECK_IN6_DP")
	)
	(segment
		(start 488.795822 -307.062378)
		(end 488.795822 -457.062078)
		(width 0.1143)
		(layer "In15.Cu")
		(net "TDR_DIFF_85_NECK_IN6_DN")
	)
	(segment
		(start 488.56646 -457.29144)
		(end 487.620564 -457.29144)
		(width 0.1143)
		(layer "In15.Cu")
		(net "TDR_DIFF_85_NECK_IN6_DN")
	)
	(segment
		(start 487.620564 -306.87264)
		(end 488.606084 -306.87264)
		(width 0.1143)
		(layer "In15.Cu")
		(net "TDR_DIFF_85_NECK_IN6_DN")
	)
	(segment
		(start 488.606084 -306.87264)
		(end 488.795822 -307.062378)
		(width 0.1143)
		(layer "In15.Cu")
		(net "TDR_DIFF_85_NECK_IN6_DN")
	)
	(segment
		(start 488.795822 -457.062078)
		(end 488.56646 -457.29144)
		(width 0.1143)
		(layer "In15.Cu")
		(net "TDR_DIFF_85_NECK_IN6_DN")
	)
	(segment
		(start 498.311424 -306.87518)
		(end 499.296944 -306.87518)
		(width 0.1143)
		(layer "In13.Cu")
		(net "TDR_DIFF_85_NECK_IN5_DP")
	)
	(segment
		(start 499.486682 -457.06665)
		(end 499.259352 -457.29398)
		(width 0.1143)
		(layer "In13.Cu")
		(net "TDR_DIFF_85_NECK_IN5_DP")
	)
	(segment
		(start 499.259352 -457.29398)
		(end 498.311424 -457.29398)
		(width 0.1143)
		(layer "In13.Cu")
		(net "TDR_DIFF_85_NECK_IN5_DP")
	)
	(segment
		(start 499.296944 -306.87518)
		(end 499.486682 -307.064918)
		(width 0.1143)
		(layer "In13.Cu")
		(net "TDR_DIFF_85_NECK_IN5_DP")
	)
	(segment
		(start 499.486682 -307.064918)
		(end 499.486682 -457.06665)
		(width 0.1143)
		(layer "In13.Cu")
		(net "TDR_DIFF_85_NECK_IN5_DP")
	)
	(segment
		(start 499.677182 -307.063902)
		(end 499.677182 -457.052426)
		(width 0.1143)
		(layer "In13.Cu")
		(net "TDR_DIFF_85_NECK_IN5_DN")
	)
	(segment
		(start 499.918736 -457.29398)
		(end 500.851424 -457.29398)
		(width 0.1143)
		(layer "In13.Cu")
		(net "TDR_DIFF_85_NECK_IN5_DN")
	)
	(segment
		(start 500.851424 -306.87518)
		(end 499.865904 -306.87518)
		(width 0.1143)
		(layer "In13.Cu")
		(net "TDR_DIFF_85_NECK_IN5_DN")
	)
	(segment
		(start 499.677182 -457.052426)
		(end 499.918736 -457.29398)
		(width 0.1143)
		(layer "In13.Cu")
		(net "TDR_DIFF_85_NECK_IN5_DN")
	)
	(segment
		(start 499.865904 -306.87518)
		(end 499.677182 -307.063902)
		(width 0.1143)
		(layer "In13.Cu")
		(net "TDR_DIFF_85_NECK_IN5_DN")
	)
	(segment
		(start 508.971042 -306.911248)
		(end 509.956562 -306.911248)
		(width 0.1143)
		(layer "In11.Cu")
		(net "TDR_DIFF_85_NECK_IN4_DP")
	)
	(segment
		(start 510.1463 -457.09459)
		(end 509.910842 -457.330048)
		(width 0.1143)
		(layer "In11.Cu")
		(net "TDR_DIFF_85_NECK_IN4_DP")
	)
	(segment
		(start 509.956562 -306.911248)
		(end 510.1463 -307.100986)
		(width 0.1143)
		(layer "In11.Cu")
		(net "TDR_DIFF_85_NECK_IN4_DP")
	)
	(segment
		(start 510.1463 -307.100986)
		(end 510.1463 -457.09459)
		(width 0.1143)
		(layer "In11.Cu")
		(net "TDR_DIFF_85_NECK_IN4_DP")
	)
	(segment
		(start 509.910842 -457.330048)
		(end 508.971042 -457.330048)
		(width 0.1143)
		(layer "In11.Cu")
		(net "TDR_DIFF_85_NECK_IN4_DP")
	)
	(segment
		(start 510.3368 -457.093574)
		(end 510.573274 -457.330048)
		(width 0.1143)
		(layer "In11.Cu")
		(net "TDR_DIFF_85_NECK_IN4_DN")
	)
	(segment
		(start 510.573274 -457.330048)
		(end 511.511042 -457.330048)
		(width 0.1143)
		(layer "In11.Cu")
		(net "TDR_DIFF_85_NECK_IN4_DN")
	)
	(segment
		(start 510.3368 -307.09997)
		(end 510.3368 -457.093574)
		(width 0.1143)
		(layer "In11.Cu")
		(net "TDR_DIFF_85_NECK_IN4_DN")
	)
	(segment
		(start 510.525522 -306.911248)
		(end 510.3368 -307.09997)
		(width 0.1143)
		(layer "In11.Cu")
		(net "TDR_DIFF_85_NECK_IN4_DN")
	)
	(segment
		(start 511.511042 -306.911248)
		(end 510.525522 -306.911248)
		(width 0.1143)
		(layer "In11.Cu")
		(net "TDR_DIFF_85_NECK_IN4_DN")
	)
	(segment
		(start 483.222554 -457.301092)
		(end 483.470204 -457.053442)
		(width 0.1143)
		(layer "In6.Cu")
		(net "TDR_DIFF_85_NECK_IN3_DP")
	)
	(segment
		(start 483.470204 -307.07203)
		(end 483.280466 -306.882292)
		(width 0.1143)
		(layer "In6.Cu")
		(net "TDR_DIFF_85_NECK_IN3_DP")
	)
	(segment
		(start 483.470204 -457.053442)
		(end 483.470204 -307.07203)
		(width 0.1143)
		(layer "In6.Cu")
		(net "TDR_DIFF_85_NECK_IN3_DP")
	)
	(segment
		(start 482.294946 -457.301092)
		(end 483.222554 -457.301092)
		(width 0.1143)
		(layer "In6.Cu")
		(net "TDR_DIFF_85_NECK_IN3_DP")
	)
	(segment
		(start 483.280466 -306.882292)
		(end 482.294946 -306.882292)
		(width 0.1143)
		(layer "In6.Cu")
		(net "TDR_DIFF_85_NECK_IN3_DP")
	)
	(segment
		(start 483.907338 -457.301092)
		(end 483.660704 -457.054458)
		(width 0.1143)
		(layer "In6.Cu")
		(net "TDR_DIFF_85_NECK_IN3_DN")
	)
	(segment
		(start 484.834946 -457.301092)
		(end 483.907338 -457.301092)
		(width 0.1143)
		(layer "In6.Cu")
		(net "TDR_DIFF_85_NECK_IN3_DN")
	)
	(segment
		(start 483.660704 -457.054458)
		(end 483.660704 -307.071014)
		(width 0.1143)
		(layer "In6.Cu")
		(net "TDR_DIFF_85_NECK_IN3_DN")
	)
	(segment
		(start 483.660704 -307.071014)
		(end 483.849426 -306.882292)
		(width 0.1143)
		(layer "In6.Cu")
		(net "TDR_DIFF_85_NECK_IN3_DN")
	)
	(segment
		(start 483.849426 -306.882292)
		(end 484.834946 -306.882292)
		(width 0.1143)
		(layer "In6.Cu")
		(net "TDR_DIFF_85_NECK_IN3_DN")
	)
	(segment
		(start 494.575084 -457.29398)
		(end 494.350802 -457.069698)
		(width 0.1143)
		(layer "In4.Cu")
		(net "TDR_DIFF_85_NECK_IN2_DP")
	)
	(segment
		(start 495.525044 -457.29398)
		(end 494.575084 -457.29398)
		(width 0.1143)
		(layer "In4.Cu")
		(net "TDR_DIFF_85_NECK_IN2_DP")
	)
	(segment
		(start 494.539524 -306.87518)
		(end 495.525044 -306.87518)
		(width 0.1143)
		(layer "In4.Cu")
		(net "TDR_DIFF_85_NECK_IN2_DP")
	)
	(segment
		(start 494.350802 -307.063902)
		(end 494.539524 -306.87518)
		(width 0.1143)
		(layer "In4.Cu")
		(net "TDR_DIFF_85_NECK_IN2_DP")
	)
	(segment
		(start 494.350802 -457.069698)
		(end 494.350802 -307.063902)
		(width 0.1143)
		(layer "In4.Cu")
		(net "TDR_DIFF_85_NECK_IN2_DP")
	)
	(segment
		(start 494.160302 -457.064618)
		(end 494.160302 -307.064918)
		(width 0.1143)
		(layer "In4.Cu")
		(net "TDR_DIFF_85_NECK_IN2_DN")
	)
	(segment
		(start 492.985044 -457.29398)
		(end 493.93094 -457.29398)
		(width 0.1143)
		(layer "In4.Cu")
		(net "TDR_DIFF_85_NECK_IN2_DN")
	)
	(segment
		(start 493.970564 -306.87518)
		(end 492.985044 -306.87518)
		(width 0.1143)
		(layer "In4.Cu")
		(net "TDR_DIFF_85_NECK_IN2_DN")
	)
	(segment
		(start 494.160302 -307.064918)
		(end 493.970564 -306.87518)
		(width 0.1143)
		(layer "In4.Cu")
		(net "TDR_DIFF_85_NECK_IN2_DN")
	)
	(segment
		(start 493.93094 -457.29398)
		(end 494.160302 -457.064618)
		(width 0.1143)
		(layer "In4.Cu")
		(net "TDR_DIFF_85_NECK_IN2_DN")
	)
	(segment
		(start 506.185424 -457.3397)
		(end 505.234956 -457.3397)
		(width 0.1143)
		(layer "In2.Cu")
		(net "TDR_DIFF_85_NECK_IN1_DP")
	)
	(segment
		(start 505.011436 -457.11618)
		(end 505.011436 -307.131466)
		(width 0.1143)
		(layer "In2.Cu")
		(net "TDR_DIFF_85_NECK_IN1_DP")
	)
	(segment
		(start 505.011436 -307.131466)
		(end 505.222002 -306.9209)
		(width 0.1143)
		(layer "In2.Cu")
		(net "TDR_DIFF_85_NECK_IN1_DP")
	)
	(segment
		(start 505.234956 -457.3397)
		(end 505.011436 -457.11618)
		(width 0.1143)
		(layer "In2.Cu")
		(net "TDR_DIFF_85_NECK_IN1_DP")
	)
	(segment
		(start 505.222002 -306.9209)
		(end 506.185424 -306.9209)
		(width 0.1143)
		(layer "In2.Cu")
		(net "TDR_DIFF_85_NECK_IN1_DP")
	)
	(segment
		(start 503.645424 -306.9209)
		(end 504.608592 -306.9209)
		(width 0.1143)
		(layer "In2.Cu")
		(net "TDR_DIFF_85_NECK_IN1_DN")
	)
	(segment
		(start 504.597162 -457.3397)
		(end 503.645424 -457.3397)
		(width 0.1143)
		(layer "In2.Cu")
		(net "TDR_DIFF_85_NECK_IN1_DN")
	)
	(segment
		(start 504.820936 -457.115926)
		(end 504.597162 -457.3397)
		(width 0.1143)
		(layer "In2.Cu")
		(net "TDR_DIFF_85_NECK_IN1_DN")
	)
	(segment
		(start 504.608592 -306.9209)
		(end 504.820936 -307.133244)
		(width 0.1143)
		(layer "In2.Cu")
		(net "TDR_DIFF_85_NECK_IN1_DN")
	)
	(segment
		(start 504.820936 -307.133244)
		(end 504.820936 -457.115926)
		(width 0.1143)
		(layer "In2.Cu")
		(net "TDR_DIFF_85_NECK_IN1_DN")
	)
	(segment
		(start 494.333276 -142.853918)
		(end 493.36833 -142.853918)
		(width 0.14224)
		(layer "In15.Cu")
		(net "TDR_DIFF_85_IN6_DP")
	)
	(segment
		(start 493.36833 7.564882)
		(end 494.30178 7.564882)
		(width 0.14224)
		(layer "In15.Cu")
		(net "TDR_DIFF_85_IN6_DP")
	)
	(segment
		(start 494.50244 7.364222)
		(end 494.50244 -142.684754)
		(width 0.14224)
		(layer "In15.Cu")
		(net "TDR_DIFF_85_IN6_DP")
	)
	(segment
		(start 494.30178 7.564882)
		(end 494.50244 7.364222)
		(width 0.14224)
		(layer "In15.Cu")
		(net "TDR_DIFF_85_IN6_DP")
	)
	(segment
		(start 494.50244 -142.684754)
		(end 494.333276 -142.853918)
		(width 0.14224)
		(layer "In15.Cu")
		(net "TDR_DIFF_85_IN6_DP")
	)
	(segment
		(start 494.78438 -142.684754)
		(end 494.953544 -142.853918)
		(width 0.14224)
		(layer "In15.Cu")
		(net "TDR_DIFF_85_IN6_DN")
	)
	(segment
		(start 494.953544 -142.853918)
		(end 495.90833 -142.853918)
		(width 0.14224)
		(layer "In15.Cu")
		(net "TDR_DIFF_85_IN6_DN")
	)
	(segment
		(start 494.97488 7.564882)
		(end 494.78438 7.374382)
		(width 0.14224)
		(layer "In15.Cu")
		(net "TDR_DIFF_85_IN6_DN")
	)
	(segment
		(start 494.78438 7.374382)
		(end 494.78438 -142.684754)
		(width 0.14224)
		(layer "In15.Cu")
		(net "TDR_DIFF_85_IN6_DN")
	)
	(segment
		(start 495.90833 7.564882)
		(end 494.97488 7.564882)
		(width 0.14224)
		(layer "In15.Cu")
		(net "TDR_DIFF_85_IN6_DN")
	)
	(segment
		(start 504.058428 7.571994)
		(end 504.991878 7.571994)
		(width 0.14224)
		(layer "In13.Cu")
		(net "TDR_DIFF_85_IN5_DP")
	)
	(segment
		(start 505.193808 -142.676372)
		(end 505.023374 -142.846806)
		(width 0.14224)
		(layer "In13.Cu")
		(net "TDR_DIFF_85_IN5_DP")
	)
	(segment
		(start 504.991878 7.571994)
		(end 505.193808 7.370064)
		(width 0.14224)
		(layer "In13.Cu")
		(net "TDR_DIFF_85_IN5_DP")
	)
	(segment
		(start 505.023374 -142.846806)
		(end 504.058428 -142.846806)
		(width 0.14224)
		(layer "In13.Cu")
		(net "TDR_DIFF_85_IN5_DP")
	)
	(segment
		(start 505.193808 7.370064)
		(end 505.193808 -142.676372)
		(width 0.14224)
		(layer "In13.Cu")
		(net "TDR_DIFF_85_IN5_DP")
	)
	(segment
		(start 505.475748 7.382764)
		(end 505.475748 -142.678912)
		(width 0.14224)
		(layer "In13.Cu")
		(net "TDR_DIFF_85_IN5_DN")
	)
	(segment
		(start 505.643642 -142.846806)
		(end 506.598428 -142.846806)
		(width 0.14224)
		(layer "In13.Cu")
		(net "TDR_DIFF_85_IN5_DN")
	)
	(segment
		(start 505.475748 -142.678912)
		(end 505.643642 -142.846806)
		(width 0.14224)
		(layer "In13.Cu")
		(net "TDR_DIFF_85_IN5_DN")
	)
	(segment
		(start 505.664978 7.571994)
		(end 505.475748 7.382764)
		(width 0.14224)
		(layer "In13.Cu")
		(net "TDR_DIFF_85_IN5_DN")
	)
	(segment
		(start 506.598428 7.571994)
		(end 505.664978 7.571994)
		(width 0.14224)
		(layer "In13.Cu")
		(net "TDR_DIFF_85_IN5_DN")
	)
	(segment
		(start 514.718808 7.526274)
		(end 515.652258 7.526274)
		(width 0.14224)
		(layer "In11.Cu")
		(net "TDR_DIFF_85_IN4_DP")
	)
	(segment
		(start 515.851394 7.327138)
		(end 515.851394 -142.724886)
		(width 0.14224)
		(layer "In11.Cu")
		(net "TDR_DIFF_85_IN4_DP")
	)
	(segment
		(start 515.683754 -142.892526)
		(end 514.718808 -142.892526)
		(width 0.14224)
		(layer "In11.Cu")
		(net "TDR_DIFF_85_IN4_DP")
	)
	(segment
		(start 515.652258 7.526274)
		(end 515.851394 7.327138)
		(width 0.14224)
		(layer "In11.Cu")
		(net "TDR_DIFF_85_IN4_DP")
	)
	(segment
		(start 515.851394 -142.724886)
		(end 515.683754 -142.892526)
		(width 0.14224)
		(layer "In11.Cu")
		(net "TDR_DIFF_85_IN4_DP")
	)
	(segment
		(start 516.325358 7.526274)
		(end 516.133334 7.33425)
		(width 0.14224)
		(layer "In11.Cu")
		(net "TDR_DIFF_85_IN4_DN")
	)
	(segment
		(start 517.258808 7.526274)
		(end 516.325358 7.526274)
		(width 0.14224)
		(layer "In11.Cu")
		(net "TDR_DIFF_85_IN4_DN")
	)
	(segment
		(start 516.133334 -142.721838)
		(end 516.304022 -142.892526)
		(width 0.14224)
		(layer "In11.Cu")
		(net "TDR_DIFF_85_IN4_DN")
	)
	(segment
		(start 516.304022 -142.892526)
		(end 517.258808 -142.892526)
		(width 0.14224)
		(layer "In11.Cu")
		(net "TDR_DIFF_85_IN4_DN")
	)
	(segment
		(start 516.133334 7.33425)
		(end 516.133334 -142.721838)
		(width 0.14224)
		(layer "In11.Cu")
		(net "TDR_DIFF_85_IN4_DN")
	)
	(segment
		(start 489.441744 -142.635478)
		(end 489.614464 -142.808198)
		(width 0.14224)
		(layer "In6.Cu")
		(net "TDR_DIFF_85_IN3_DP")
	)
	(segment
		(start 490.57433 7.610602)
		(end 489.64088 7.610602)
		(width 0.14224)
		(layer "In6.Cu")
		(net "TDR_DIFF_85_IN3_DP")
	)
	(segment
		(start 489.614464 -142.808198)
		(end 490.57433 -142.808198)
		(width 0.14224)
		(layer "In6.Cu")
		(net "TDR_DIFF_85_IN3_DP")
	)
	(segment
		(start 489.441744 7.411466)
		(end 489.441744 -142.635478)
		(width 0.14224)
		(layer "In6.Cu")
		(net "TDR_DIFF_85_IN3_DP")
	)
	(segment
		(start 489.64088 7.610602)
		(end 489.441744 7.411466)
		(width 0.14224)
		(layer "In6.Cu")
		(net "TDR_DIFF_85_IN3_DP")
	)
	(segment
		(start 488.96778 7.610602)
		(end 489.159804 7.418578)
		(width 0.14224)
		(layer "In6.Cu")
		(net "TDR_DIFF_85_IN3_DN")
	)
	(segment
		(start 489.159804 7.418578)
		(end 489.159804 -142.639542)
		(width 0.14224)
		(layer "In6.Cu")
		(net "TDR_DIFF_85_IN3_DN")
	)
	(segment
		(start 489.159804 -142.639542)
		(end 488.991148 -142.808198)
		(width 0.14224)
		(layer "In6.Cu")
		(net "TDR_DIFF_85_IN3_DN")
	)
	(segment
		(start 488.03433 7.610602)
		(end 488.96778 7.610602)
		(width 0.14224)
		(layer "In6.Cu")
		(net "TDR_DIFF_85_IN3_DN")
	)
	(segment
		(start 488.991148 -142.808198)
		(end 488.03433 -142.808198)
		(width 0.14224)
		(layer "In6.Cu")
		(net "TDR_DIFF_85_IN3_DN")
	)
	(segment
		(start 499.821454 -142.673578)
		(end 499.650766 -142.844266)
		(width 0.14224)
		(layer "In4.Cu")
		(net "TDR_DIFF_85_IN2_DP")
	)
	(segment
		(start 498.693948 7.574534)
		(end 499.627398 7.574534)
		(width 0.14224)
		(layer "In4.Cu")
		(net "TDR_DIFF_85_IN2_DP")
	)
	(segment
		(start 499.650766 -142.844266)
		(end 498.693948 -142.844266)
		(width 0.14224)
		(layer "In4.Cu")
		(net "TDR_DIFF_85_IN2_DP")
	)
	(segment
		(start 499.821454 7.380478)
		(end 499.821454 -142.673578)
		(width 0.14224)
		(layer "In4.Cu")
		(net "TDR_DIFF_85_IN2_DP")
	)
	(segment
		(start 499.627398 7.574534)
		(end 499.821454 7.380478)
		(width 0.14224)
		(layer "In4.Cu")
		(net "TDR_DIFF_85_IN2_DP")
	)
	(segment
		(start 500.103394 -142.673578)
		(end 500.274082 -142.844266)
		(width 0.14224)
		(layer "In4.Cu")
		(net "TDR_DIFF_85_IN2_DN")
	)
	(segment
		(start 500.300498 7.574534)
		(end 500.103394 7.37743)
		(width 0.14224)
		(layer "In4.Cu")
		(net "TDR_DIFF_85_IN2_DN")
	)
	(segment
		(start 500.274082 -142.844266)
		(end 501.233948 -142.844266)
		(width 0.14224)
		(layer "In4.Cu")
		(net "TDR_DIFF_85_IN2_DN")
	)
	(segment
		(start 500.103394 7.37743)
		(end 500.103394 -142.673578)
		(width 0.14224)
		(layer "In4.Cu")
		(net "TDR_DIFF_85_IN2_DN")
	)
	(segment
		(start 501.233948 7.574534)
		(end 500.300498 7.574534)
		(width 0.14224)
		(layer "In4.Cu")
		(net "TDR_DIFF_85_IN2_DN")
	)
	(segment
		(start 510.795524 7.37616)
		(end 510.991358 7.571994)
		(width 0.14224)
		(layer "In2.Cu")
		(net "TDR_DIFF_85_IN1_DP")
	)
	(segment
		(start 510.964942 -142.846806)
		(end 510.795524 -142.677388)
		(width 0.14224)
		(layer "In2.Cu")
		(net "TDR_DIFF_85_IN1_DP")
	)
	(segment
		(start 510.991358 7.571994)
		(end 511.924808 7.571994)
		(width 0.14224)
		(layer "In2.Cu")
		(net "TDR_DIFF_85_IN1_DP")
	)
	(segment
		(start 510.795524 -142.677388)
		(end 510.795524 7.37616)
		(width 0.14224)
		(layer "In2.Cu")
		(net "TDR_DIFF_85_IN1_DP")
	)
	(segment
		(start 511.924808 -142.846806)
		(end 510.964942 -142.846806)
		(width 0.14224)
		(layer "In2.Cu")
		(net "TDR_DIFF_85_IN1_DP")
	)
	(segment
		(start 509.384808 -142.846806)
		(end 510.341626 -142.846806)
		(width 0.14224)
		(layer "In2.Cu")
		(net "TDR_DIFF_85_IN1_DN")
	)
	(segment
		(start 510.513584 7.376668)
		(end 510.318258 7.571994)
		(width 0.14224)
		(layer "In2.Cu")
		(net "TDR_DIFF_85_IN1_DN")
	)
	(segment
		(start 510.341626 -142.846806)
		(end 510.513584 -142.674848)
		(width 0.14224)
		(layer "In2.Cu")
		(net "TDR_DIFF_85_IN1_DN")
	)
	(segment
		(start 510.513584 -142.674848)
		(end 510.513584 7.376668)
		(width 0.14224)
		(layer "In2.Cu")
		(net "TDR_DIFF_85_IN1_DN")
	)
	(segment
		(start 510.318258 7.571994)
		(end 509.384808 7.571994)
		(width 0.14224)
		(layer "In2.Cu")
		(net "TDR_DIFF_85_IN1_DN")
	)
	(segment
		(start 483.65156 -142.805658)
		(end 482.66985 -142.805658)
		(width 0.12954)
		(layer "B.Cu")
		(net "TDR_DIFF_85_BOT_DP")
	)
	(segment
		(start 483.65156 7.613142)
		(end 483.779068 7.485634)
		(width 0.12954)
		(layer "B.Cu")
		(net "TDR_DIFF_85_BOT_DP")
	)
	(segment
		(start 482.66985 7.613142)
		(end 483.65156 7.613142)
		(width 0.12954)
		(layer "B.Cu")
		(net "TDR_DIFF_85_BOT_DP")
	)
	(segment
		(start 483.779068 7.485634)
		(end 483.779068 -142.67815)
		(width 0.12954)
		(layer "B.Cu")
		(net "TDR_DIFF_85_BOT_DP")
	)
	(segment
		(start 483.779068 -142.67815)
		(end 483.65156 -142.805658)
		(width 0.12954)
		(layer "B.Cu")
		(net "TDR_DIFF_85_BOT_DP")
	)
	(segment
		(start 484.101648 7.483602)
		(end 484.231188 7.613142)
		(width 0.12954)
		(layer "B.Cu")
		(net "TDR_DIFF_85_BOT_DN")
	)
	(segment
		(start 484.231188 -142.805658)
		(end 484.101648 -142.676118)
		(width 0.12954)
		(layer "B.Cu")
		(net "TDR_DIFF_85_BOT_DN")
	)
	(segment
		(start 484.231188 7.613142)
		(end 485.20985 7.613142)
		(width 0.12954)
		(layer "B.Cu")
		(net "TDR_DIFF_85_BOT_DN")
	)
	(segment
		(start 484.101648 -142.676118)
		(end 484.101648 7.483602)
		(width 0.12954)
		(layer "B.Cu")
		(net "TDR_DIFF_85_BOT_DN")
	)
	(segment
		(start 485.20985 -142.805658)
		(end 484.231188 -142.805658)
		(width 0.12954)
		(layer "B.Cu")
		(net "TDR_DIFF_85_BOT_DN")
	)
	(segment
		(start 526.524982 -298.235878)
		(end 526.376646 -298.384214)
		(width 0.14732)
		(layer "F.Cu")
		(net "TDR_DIFF_80_TOP_DP")
	)
	(segment
		(start 526.524982 -148.07311)
		(end 526.524982 -298.235878)
		(width 0.14732)
		(layer "F.Cu")
		(net "TDR_DIFF_80_TOP_DP")
	)
	(segment
		(start 526.417286 -147.965414)
		(end 526.524982 -148.07311)
		(width 0.14732)
		(layer "F.Cu")
		(net "TDR_DIFF_80_TOP_DP")
	)
	(segment
		(start 526.376646 -298.384214)
		(end 525.408906 -298.384214)
		(width 0.14732)
		(layer "F.Cu")
		(net "TDR_DIFF_80_TOP_DP")
	)
	(segment
		(start 525.408906 -147.965414)
		(end 526.417286 -147.965414)
		(width 0.14732)
		(layer "F.Cu")
		(net "TDR_DIFF_80_TOP_DP")
	)
	(segment
		(start 526.865342 -148.098256)
		(end 526.865342 -298.236894)
		(width 0.14732)
		(layer "F.Cu")
		(net "TDR_DIFF_80_TOP_DN")
	)
	(segment
		(start 527.948906 -147.965414)
		(end 526.998184 -147.965414)
		(width 0.14732)
		(layer "F.Cu")
		(net "TDR_DIFF_80_TOP_DN")
	)
	(segment
		(start 527.012662 -298.384214)
		(end 527.948906 -298.384214)
		(width 0.14732)
		(layer "F.Cu")
		(net "TDR_DIFF_80_TOP_DN")
	)
	(segment
		(start 526.998184 -147.965414)
		(end 526.865342 -148.098256)
		(width 0.14732)
		(layer "F.Cu")
		(net "TDR_DIFF_80_TOP_DN")
	)
	(segment
		(start 526.865342 -298.236894)
		(end 527.012662 -298.384214)
		(width 0.14732)
		(layer "F.Cu")
		(net "TDR_DIFF_80_TOP_DN")
	)
	(segment
		(start 501.233948 -147.924266)
		(end 500.276368 -147.924266)
		(width 0.16002)
		(layer "In15.Cu")
		(net "TDR_DIFF_80_IN6_DP")
	)
	(segment
		(start 500.276368 -298.343066)
		(end 501.233948 -298.343066)
		(width 0.16002)
		(layer "In15.Cu")
		(net "TDR_DIFF_80_IN6_DP")
	)
	(segment
		(start 500.276368 -147.924266)
		(end 500.129048 -148.071586)
		(width 0.16002)
		(layer "In15.Cu")
		(net "TDR_DIFF_80_IN6_DP")
	)
	(segment
		(start 500.129048 -148.071586)
		(end 500.129048 -298.195746)
		(width 0.16002)
		(layer "In15.Cu")
		(net "TDR_DIFF_80_IN6_DP")
	)
	(segment
		(start 500.129048 -298.195746)
		(end 500.276368 -298.343066)
		(width 0.16002)
		(layer "In15.Cu")
		(net "TDR_DIFF_80_IN6_DP")
	)
	(segment
		(start 499.679468 -298.343066)
		(end 498.693948 -298.343066)
		(width 0.16002)
		(layer "In15.Cu")
		(net "TDR_DIFF_80_IN6_DN")
	)
	(segment
		(start 498.693948 -147.924266)
		(end 499.679468 -147.924266)
		(width 0.16002)
		(layer "In15.Cu")
		(net "TDR_DIFF_80_IN6_DN")
	)
	(segment
		(start 499.826788 -298.195746)
		(end 499.679468 -298.343066)
		(width 0.16002)
		(layer "In15.Cu")
		(net "TDR_DIFF_80_IN6_DN")
	)
	(segment
		(start 499.679468 -147.924266)
		(end 499.826788 -148.071586)
		(width 0.16002)
		(layer "In15.Cu")
		(net "TDR_DIFF_80_IN6_DN")
	)
	(segment
		(start 499.826788 -148.071586)
		(end 499.826788 -298.195746)
		(width 0.16002)
		(layer "In15.Cu")
		(net "TDR_DIFF_80_IN6_DN")
	)
	(segment
		(start 510.370328 -298.345606)
		(end 509.384808 -298.345606)
		(width 0.16002)
		(layer "In13.Cu")
		(net "TDR_DIFF_80_IN5_DP")
	)
	(segment
		(start 510.370328 -147.926806)
		(end 510.519172 -148.07565)
		(width 0.16002)
		(layer "In13.Cu")
		(net "TDR_DIFF_80_IN5_DP")
	)
	(segment
		(start 509.384808 -147.926806)
		(end 510.370328 -147.926806)
		(width 0.16002)
		(layer "In13.Cu")
		(net "TDR_DIFF_80_IN5_DP")
	)
	(segment
		(start 510.519172 -148.07565)
		(end 510.519172 -298.196762)
		(width 0.16002)
		(layer "In13.Cu")
		(net "TDR_DIFF_80_IN5_DP")
	)
	(segment
		(start 510.519172 -298.196762)
		(end 510.370328 -298.345606)
		(width 0.16002)
		(layer "In13.Cu")
		(net "TDR_DIFF_80_IN5_DP")
	)
	(segment
		(start 511.924808 -147.926806)
		(end 510.968752 -147.926806)
		(width 0.16002)
		(layer "In13.Cu")
		(net "TDR_DIFF_80_IN5_DN")
	)
	(segment
		(start 510.821432 -298.198286)
		(end 510.968752 -298.345606)
		(width 0.16002)
		(layer "In13.Cu")
		(net "TDR_DIFF_80_IN5_DN")
	)
	(segment
		(start 510.821432 -148.074126)
		(end 510.821432 -298.198286)
		(width 0.16002)
		(layer "In13.Cu")
		(net "TDR_DIFF_80_IN5_DN")
	)
	(segment
		(start 510.968752 -298.345606)
		(end 511.924808 -298.345606)
		(width 0.16002)
		(layer "In13.Cu")
		(net "TDR_DIFF_80_IN5_DN")
	)
	(segment
		(start 510.968752 -147.926806)
		(end 510.821432 -148.074126)
		(width 0.16002)
		(layer "In13.Cu")
		(net "TDR_DIFF_80_IN5_DN")
	)
	(segment
		(start 520.044426 -147.962874)
		(end 521.029946 -147.962874)
		(width 0.16002)
		(layer "In11.Cu")
		(net "TDR_DIFF_80_IN4_DP")
	)
	(segment
		(start 521.029946 -298.381674)
		(end 520.044426 -298.381674)
		(width 0.16002)
		(layer "In11.Cu")
		(net "TDR_DIFF_80_IN4_DP")
	)
	(segment
		(start 521.029946 -147.962874)
		(end 521.176504 -148.109432)
		(width 0.16002)
		(layer "In11.Cu")
		(net "TDR_DIFF_80_IN4_DP")
	)
	(segment
		(start 521.176504 -298.235116)
		(end 521.029946 -298.381674)
		(width 0.16002)
		(layer "In11.Cu")
		(net "TDR_DIFF_80_IN4_DP")
	)
	(segment
		(start 521.176504 -148.109432)
		(end 521.176504 -298.235116)
		(width 0.16002)
		(layer "In11.Cu")
		(net "TDR_DIFF_80_IN4_DP")
	)
	(segment
		(start 521.626084 -298.381674)
		(end 522.584426 -298.381674)
		(width 0.16002)
		(layer "In11.Cu")
		(net "TDR_DIFF_80_IN4_DN")
	)
	(segment
		(start 521.626084 -147.962874)
		(end 521.478764 -148.110194)
		(width 0.16002)
		(layer "In11.Cu")
		(net "TDR_DIFF_80_IN4_DN")
	)
	(segment
		(start 521.478764 -148.110194)
		(end 521.478764 -298.234354)
		(width 0.16002)
		(layer "In11.Cu")
		(net "TDR_DIFF_80_IN4_DN")
	)
	(segment
		(start 522.584426 -147.962874)
		(end 521.626084 -147.962874)
		(width 0.16002)
		(layer "In11.Cu")
		(net "TDR_DIFF_80_IN4_DN")
	)
	(segment
		(start 521.478764 -298.234354)
		(end 521.626084 -298.381674)
		(width 0.16002)
		(layer "In11.Cu")
		(net "TDR_DIFF_80_IN4_DN")
	)
	(segment
		(start 495.90833 -147.933918)
		(end 494.952782 -147.933918)
		(width 0.16002)
		(layer "In6.Cu")
		(net "TDR_DIFF_80_IN3_DP")
	)
	(segment
		(start 494.952782 -298.352718)
		(end 495.90833 -298.352718)
		(width 0.16002)
		(layer "In6.Cu")
		(net "TDR_DIFF_80_IN3_DP")
	)
	(segment
		(start 494.805462 -148.081238)
		(end 494.805462 -298.205398)
		(width 0.16002)
		(layer "In6.Cu")
		(net "TDR_DIFF_80_IN3_DP")
	)
	(segment
		(start 494.805462 -298.205398)
		(end 494.952782 -298.352718)
		(width 0.16002)
		(layer "In6.Cu")
		(net "TDR_DIFF_80_IN3_DP")
	)
	(segment
		(start 494.952782 -147.933918)
		(end 494.805462 -148.081238)
		(width 0.16002)
		(layer "In6.Cu")
		(net "TDR_DIFF_80_IN3_DP")
	)
	(segment
		(start 493.36833 -147.933918)
		(end 494.35385 -147.933918)
		(width 0.16002)
		(layer "In6.Cu")
		(net "TDR_DIFF_80_IN3_DN")
	)
	(segment
		(start 494.503202 -298.203366)
		(end 494.35385 -298.352718)
		(width 0.16002)
		(layer "In6.Cu")
		(net "TDR_DIFF_80_IN3_DN")
	)
	(segment
		(start 494.35385 -147.933918)
		(end 494.503202 -148.08327)
		(width 0.16002)
		(layer "In6.Cu")
		(net "TDR_DIFF_80_IN3_DN")
	)
	(segment
		(start 494.35385 -298.352718)
		(end 493.36833 -298.352718)
		(width 0.16002)
		(layer "In6.Cu")
		(net "TDR_DIFF_80_IN3_DN")
	)
	(segment
		(start 494.503202 -148.08327)
		(end 494.503202 -298.203366)
		(width 0.16002)
		(layer "In6.Cu")
		(net "TDR_DIFF_80_IN3_DN")
	)
	(segment
		(start 505.193046 -148.075904)
		(end 505.193046 -298.196508)
		(width 0.16002)
		(layer "In4.Cu")
		(net "TDR_DIFF_80_IN2_DP")
	)
	(segment
		(start 504.058428 -147.926806)
		(end 505.043948 -147.926806)
		(width 0.16002)
		(layer "In4.Cu")
		(net "TDR_DIFF_80_IN2_DP")
	)
	(segment
		(start 505.043948 -147.926806)
		(end 505.193046 -148.075904)
		(width 0.16002)
		(layer "In4.Cu")
		(net "TDR_DIFF_80_IN2_DP")
	)
	(segment
		(start 505.043948 -298.345606)
		(end 504.058428 -298.345606)
		(width 0.16002)
		(layer "In4.Cu")
		(net "TDR_DIFF_80_IN2_DP")
	)
	(segment
		(start 505.193046 -298.196508)
		(end 505.043948 -298.345606)
		(width 0.16002)
		(layer "In4.Cu")
		(net "TDR_DIFF_80_IN2_DP")
	)
	(segment
		(start 505.642626 -298.345606)
		(end 506.598428 -298.345606)
		(width 0.16002)
		(layer "In4.Cu")
		(net "TDR_DIFF_80_IN2_DN")
	)
	(segment
		(start 505.642626 -147.926806)
		(end 505.495306 -148.074126)
		(width 0.16002)
		(layer "In4.Cu")
		(net "TDR_DIFF_80_IN2_DN")
	)
	(segment
		(start 505.495306 -298.198286)
		(end 505.642626 -298.345606)
		(width 0.16002)
		(layer "In4.Cu")
		(net "TDR_DIFF_80_IN2_DN")
	)
	(segment
		(start 506.598428 -147.926806)
		(end 505.642626 -147.926806)
		(width 0.16002)
		(layer "In4.Cu")
		(net "TDR_DIFF_80_IN2_DN")
	)
	(segment
		(start 505.495306 -148.074126)
		(end 505.495306 -298.198286)
		(width 0.16002)
		(layer "In4.Cu")
		(net "TDR_DIFF_80_IN2_DN")
	)
	(segment
		(start 516.156702 -298.244006)
		(end 516.304022 -298.391326)
		(width 0.16002)
		(layer "In2.Cu")
		(net "TDR_DIFF_80_IN1_DP")
	)
	(segment
		(start 516.156702 -148.119846)
		(end 516.156702 -298.244006)
		(width 0.16002)
		(layer "In2.Cu")
		(net "TDR_DIFF_80_IN1_DP")
	)
	(segment
		(start 516.304022 -298.391326)
		(end 517.258808 -298.391326)
		(width 0.16002)
		(layer "In2.Cu")
		(net "TDR_DIFF_80_IN1_DP")
	)
	(segment
		(start 516.304022 -147.972526)
		(end 516.156702 -148.119846)
		(width 0.16002)
		(layer "In2.Cu")
		(net "TDR_DIFF_80_IN1_DP")
	)
	(segment
		(start 517.258808 -147.972526)
		(end 516.304022 -147.972526)
		(width 0.16002)
		(layer "In2.Cu")
		(net "TDR_DIFF_80_IN1_DP")
	)
	(segment
		(start 515.704328 -298.391326)
		(end 514.718808 -298.391326)
		(width 0.16002)
		(layer "In2.Cu")
		(net "TDR_DIFF_80_IN1_DN")
	)
	(segment
		(start 515.854442 -298.241212)
		(end 515.704328 -298.391326)
		(width 0.16002)
		(layer "In2.Cu")
		(net "TDR_DIFF_80_IN1_DN")
	)
	(segment
		(start 515.704328 -147.972526)
		(end 515.854442 -148.12264)
		(width 0.16002)
		(layer "In2.Cu")
		(net "TDR_DIFF_80_IN1_DN")
	)
	(segment
		(start 515.854442 -148.12264)
		(end 515.854442 -298.241212)
		(width 0.16002)
		(layer "In2.Cu")
		(net "TDR_DIFF_80_IN1_DN")
	)
	(segment
		(start 514.718808 -147.972526)
		(end 515.704328 -147.972526)
		(width 0.16002)
		(layer "In2.Cu")
		(net "TDR_DIFF_80_IN1_DN")
	)
	(segment
		(start 489.145326 -298.163742)
		(end 489.00207 -298.306998)
		(width 0.14732)
		(layer "B.Cu")
		(net "TDR_DIFF_80_BOT_DP")
	)
	(segment
		(start 488.03433 -147.888198)
		(end 489.04271 -147.888198)
		(width 0.14732)
		(layer "B.Cu")
		(net "TDR_DIFF_80_BOT_DP")
	)
	(segment
		(start 489.04271 -147.888198)
		(end 489.145326 -147.990814)
		(width 0.14732)
		(layer "B.Cu")
		(net "TDR_DIFF_80_BOT_DP")
	)
	(segment
		(start 489.00207 -298.306998)
		(end 488.03433 -298.306998)
		(width 0.14732)
		(layer "B.Cu")
		(net "TDR_DIFF_80_BOT_DP")
	)
	(segment
		(start 489.145326 -147.990814)
		(end 489.145326 -298.163742)
		(width 0.14732)
		(layer "B.Cu")
		(net "TDR_DIFF_80_BOT_DP")
	)
	(segment
		(start 489.485686 -148.02104)
		(end 489.485686 -298.159678)
		(width 0.14732)
		(layer "B.Cu")
		(net "TDR_DIFF_80_BOT_DN")
	)
	(segment
		(start 489.618528 -147.888198)
		(end 489.485686 -148.02104)
		(width 0.14732)
		(layer "B.Cu")
		(net "TDR_DIFF_80_BOT_DN")
	)
	(segment
		(start 489.485686 -298.159678)
		(end 489.633006 -298.306998)
		(width 0.14732)
		(layer "B.Cu")
		(net "TDR_DIFF_80_BOT_DN")
	)
	(segment
		(start 489.633006 -298.306998)
		(end 490.57433 -298.306998)
		(width 0.14732)
		(layer "B.Cu")
		(net "TDR_DIFF_80_BOT_DN")
	)
	(segment
		(start 490.57433 -147.888198)
		(end 489.618528 -147.888198)
		(width 0.14732)
		(layer "B.Cu")
		(net "TDR_DIFF_80_BOT_DN")
	)
	(segment
		(start 136.807702 -57.882028)
		(end 134.614158 -57.882028)
		(width 0.10668)
		(layer "F.Cu")
		(net "SCM_JTAG_MUX_S0_R2")
	)
	(segment
		(start 137.173716 -57.516014)
		(end 138.026902 -57.516014)
		(width 0.10668)
		(layer "F.Cu")
		(net "SCM_JTAG_MUX_S0_R2")
	)
	(segment
		(start 136.807702 -57.882028)
		(end 137.173716 -57.516014)
		(width 0.10668)
		(layer "F.Cu")
		(net "SCM_JTAG_MUX_S0_R2")
	)
	(via
		(at 136.807702 -57.882028)
		(size 0.508)
		(drill 0.254)
		(layers "F.Cu" "B.Cu")
		(net "SCM_JTAG_MUX_S0_R2")
	)
	(segment
		(start 116.984018 -57.20207)
		(end 114.790474 -57.20207)
		(width 0.10668)
		(layer "F.Cu")
		(net "SCM_JTAG_MUX_S0_R1")
	)
	(segment
		(start 117.604032 -56.582056)
		(end 118.318534 -56.582056)
		(width 0.10668)
		(layer "F.Cu")
		(net "SCM_JTAG_MUX_S0_R1")
	)
	(segment
		(start 116.984018 -57.20207)
		(end 117.604032 -56.582056)
		(width 0.10668)
		(layer "F.Cu")
		(net "SCM_JTAG_MUX_S0_R1")
	)
	(via
		(at 116.984018 -57.20207)
		(size 0.508)
		(drill 0.254)
		(layers "F.Cu" "B.Cu")
		(net "SCM_JTAG_MUX_S0_R1")
	)
	(segment
		(start 459.377796 -47.53991)
		(end 459.377796 -49.054512)
		(width 0.10668)
		(layer "F.Cu")
		(net "PWRGD_P3V3_AUX_R1")
	)
	(segment
		(start 459.377796 -49.054512)
		(end 459.115414 -49.316894)
		(width 0.10668)
		(layer "F.Cu")
		(net "PWRGD_P3V3_AUX_R1")
	)
	(segment
		(start 460.174594 -45.877226)
		(end 460.174594 -45.964348)
		(width 0.10668)
		(layer "F.Cu")
		(net "PWRGD_P3V3_AUX_R1")
	)
	(segment
		(start 459.115414 -49.316894)
		(end 458.850238 -49.316894)
		(width 0.10668)
		(layer "F.Cu")
		(net "PWRGD_P3V3_AUX_R1")
	)
	(segment
		(start 459.928468 -46.210474)
		(end 459.377796 -47.53991)
		(width 0.10668)
		(layer "F.Cu")
		(net "PWRGD_P3V3_AUX_R1")
	)
	(segment
		(start 460.174594 -45.964348)
		(end 459.928468 -46.210474)
		(width 0.10668)
		(layer "F.Cu")
		(net "PWRGD_P3V3_AUX_R1")
	)
	(segment
		(start 461.58785 -45.877226)
		(end 460.174594 -45.877226)
		(width 0.10668)
		(layer "F.Cu")
		(net "PWRGD_P3V3_AUX_R1")
	)
	(via
		(at 461.58785 -45.877226)
		(size 0.508)
		(drill 0.254)
		(layers "F.Cu" "B.Cu")
		(net "PWRGD_P3V3_AUX_R1")
	)
	(segment
		(start 461.98536 -43.400726)
		(end 460.806038 -43.400726)
		(width 0.10668)
		(layer "B.Cu")
		(net "PWRGD_P3V3_AUX_R1")
	)
	(segment
		(start 462.577942 -43.993308)
		(end 461.98536 -43.400726)
		(width 0.10668)
		(layer "B.Cu")
		(net "PWRGD_P3V3_AUX_R1")
	)
	(segment
		(start 461.872838 -45.877226)
		(end 462.577942 -45.172122)
		(width 0.10668)
		(layer "B.Cu")
		(net "PWRGD_P3V3_AUX_R1")
	)
	(segment
		(start 461.58785 -45.877226)
		(end 461.872838 -45.877226)
		(width 0.10668)
		(layer "B.Cu")
		(net "PWRGD_P3V3_AUX_R1")
	)
	(segment
		(start 462.577942 -45.172122)
		(end 462.577942 -43.993308)
		(width 0.10668)
		(layer "B.Cu")
		(net "PWRGD_P3V3_AUX_R1")
	)
	(segment
		(start 12.896342 -195.79717)
		(end 12.5222 -195.423028)
		(width 0.10668)
		(layer "F.Cu")
		(net "TP_P12V_AUX_CPU1_DIMM_ISEN_P")
	)
	(segment
		(start 12.896342 -197.06717)
		(end 12.896342 -195.79717)
		(width 0.10668)
		(layer "F.Cu")
		(net "TP_P12V_AUX_CPU1_DIMM_ISEN_P")
	)
	(segment
		(start 10.521442 -195.423028)
		(end 10.254742 -195.156328)
		(width 0.10668)
		(layer "F.Cu")
		(net "TP_P12V_AUX_CPU1_DIMM_ISEN_P")
	)
	(segment
		(start 12.5222 -195.423028)
		(end 10.521442 -195.423028)
		(width 0.10668)
		(layer "F.Cu")
		(net "TP_P12V_AUX_CPU1_DIMM_ISEN_P")
	)
	(via
		(at 10.254742 -195.156328)
		(size 0.762)
		(drill 0.381)
		(layers "F.Cu" "B.Cu")
		(net "TP_P12V_AUX_CPU1_DIMM_ISEN_P")
	)
	(segment
		(start 11.58494 -193.577972)
		(end 10.254742 -193.577972)
		(width 0.10668)
		(layer "F.Cu")
		(net "TP_P12V_AUX_CPU1_DIMM_ISEN_N")
	)
	(segment
		(start 12.896342 -191.66713)
		(end 12.896342 -192.26657)
		(width 0.10668)
		(layer "F.Cu")
		(net "TP_P12V_AUX_CPU1_DIMM_ISEN_N")
	)
	(segment
		(start 12.896342 -192.26657)
		(end 11.58494 -193.577972)
		(width 0.10668)
		(layer "F.Cu")
		(net "TP_P12V_AUX_CPU1_DIMM_ISEN_N")
	)
	(via
		(at 10.254742 -193.577972)
		(size 0.762)
		(drill 0.381)
		(layers "F.Cu" "B.Cu")
		(net "TP_P12V_AUX_CPU1_DIMM_ISEN_N")
	)
	(segment
		(start 451.0024 -179.10556)
		(end 452.002906 -180.106066)
		(width 0.10668)
		(layer "F.Cu")
		(net "TP_P12V_AUX_CPU0_DIMM_ISEN_P")
	)
	(segment
		(start 451.0024 -175.333914)
		(end 451.0024 -179.10556)
		(width 0.10668)
		(layer "F.Cu")
		(net "TP_P12V_AUX_CPU0_DIMM_ISEN_P")
	)
	(segment
		(start 452.002906 -180.106066)
		(end 453.557386 -180.106066)
		(width 0.10668)
		(layer "F.Cu")
		(net "TP_P12V_AUX_CPU0_DIMM_ISEN_P")
	)
	(segment
		(start 447.754248 -172.085762)
		(end 451.0024 -175.333914)
		(width 0.10668)
		(layer "F.Cu")
		(net "TP_P12V_AUX_CPU0_DIMM_ISEN_P")
	)
	(via
		(at 447.754248 -172.085762)
		(size 0.762)
		(drill 0.381)
		(layers "F.Cu" "B.Cu")
		(net "TP_P12V_AUX_CPU0_DIMM_ISEN_P")
	)
	(segment
		(start 450.33946 -176.24933)
		(end 450.33946 -179.02936)
		(width 0.10668)
		(layer "F.Cu")
		(net "TP_P12V_AUX_CPU0_DIMM_ISEN_N")
	)
	(segment
		(start 450.33946 -179.02936)
		(end 449.262754 -180.106066)
		(width 0.10668)
		(layer "F.Cu")
		(net "TP_P12V_AUX_CPU0_DIMM_ISEN_N")
	)
	(segment
		(start 446.175892 -172.085762)
		(end 450.33946 -176.24933)
		(width 0.10668)
		(layer "F.Cu")
		(net "TP_P12V_AUX_CPU0_DIMM_ISEN_N")
	)
	(segment
		(start 449.262754 -180.106066)
		(end 448.157346 -180.106066)
		(width 0.10668)
		(layer "F.Cu")
		(net "TP_P12V_AUX_CPU0_DIMM_ISEN_N")
	)
	(via
		(at 446.175892 -172.085762)
		(size 0.762)
		(drill 0.381)
		(layers "F.Cu" "B.Cu")
		(net "TP_P12V_AUX_CPU0_DIMM_ISEN_N")
	)
	(segment
		(start 129.184654 -55.922164)
		(end 129.667254 -55.439564)
		(width 0.10668)
		(layer "F.Cu")
		(net "JTAG_CPUX_TDI_R1")
	)
	(segment
		(start 129.667254 -55.439564)
		(end 129.667254 -55.074312)
		(width 0.10668)
		(layer "F.Cu")
		(net "JTAG_CPUX_TDI_R1")
	)
	(segment
		(start 128.105154 -55.922164)
		(end 129.032254 -55.922164)
		(width 0.10668)
		(layer "F.Cu")
		(net "JTAG_CPUX_TDI_R1")
	)
	(segment
		(start 129.032254 -55.922164)
		(end 129.184654 -55.922164)
		(width 0.10668)
		(layer "F.Cu")
		(net "JTAG_CPUX_TDI_R1")
	)
	(via
		(at 129.032254 -55.922164)
		(size 0.508)
		(drill 0.254)
		(layers "F.Cu" "B.Cu")
		(net "JTAG_CPUX_TDI_R1")
	)
	(segment
		(start 230.328724 -152.590754)
		(end 229.96525 -152.954228)
		(width 0.10668)
		(layer "F.Cu")
		(net "JTAG_CPU0_TDO_CPU1_TDI_R1")
	)
	(segment
		(start 232.008934 -152.956768)
		(end 231.64292 -152.590754)
		(width 0.10668)
		(layer "F.Cu")
		(net "JTAG_CPU0_TDO_CPU1_TDI_R1")
	)
	(segment
		(start 231.205532 -152.590754)
		(end 230.328724 -152.590754)
		(width 0.10668)
		(layer "F.Cu")
		(net "JTAG_CPU0_TDO_CPU1_TDI_R1")
	)
	(segment
		(start 232.889806 -152.956768)
		(end 232.008934 -152.956768)
		(width 0.10668)
		(layer "F.Cu")
		(net "JTAG_CPU0_TDO_CPU1_TDI_R1")
	)
	(segment
		(start 231.64292 -152.590754)
		(end 231.205532 -152.590754)
		(width 0.10668)
		(layer "F.Cu")
		(net "JTAG_CPU0_TDO_CPU1_TDI_R1")
	)
	(via
		(at 231.205532 -152.590754)
		(size 0.762)
		(drill 0.381)
		(layers "F.Cu" "B.Cu")
		(net "JTAG_CPU0_TDO_CPU1_TDI_R1")
	)
	(segment
		(start 231.235758 -154.100276)
		(end 230.016558 -154.100276)
		(width 0.10668)
		(layer "F.Cu")
		(net "JTAG_CPU0_BYPASS_R1")
	)
	(segment
		(start 232.889806 -153.606754)
		(end 232.014776 -153.606754)
		(width 0.10668)
		(layer "F.Cu")
		(net "JTAG_CPU0_BYPASS_R1")
	)
	(segment
		(start 230.016558 -154.100276)
		(end 229.960424 -154.15641)
		(width 0.10668)
		(layer "F.Cu")
		(net "JTAG_CPU0_BYPASS_R1")
	)
	(segment
		(start 231.46512 -154.15641)
		(end 231.291892 -154.15641)
		(width 0.10668)
		(layer "F.Cu")
		(net "JTAG_CPU0_BYPASS_R1")
	)
	(segment
		(start 231.291892 -154.15641)
		(end 231.235758 -154.100276)
		(width 0.10668)
		(layer "F.Cu")
		(net "JTAG_CPU0_BYPASS_R1")
	)
	(segment
		(start 232.014776 -153.606754)
		(end 231.46512 -154.15641)
		(width 0.10668)
		(layer "F.Cu")
		(net "JTAG_CPU0_BYPASS_R1")
	)
	(via
		(at 231.235758 -154.100276)
		(size 0.762)
		(drill 0.381)
		(layers "F.Cu" "B.Cu")
		(net "JTAG_CPU0_BYPASS_R1")
	)
	(via
		(at 398.79016 -343.586308)
		(size 0.6604)
		(drill 0.3302)
		(layers "F.Cu" "B.Cu")
		(net "FM_BIOS_POST_CMPLT_BUF_R1_N")
	)
	(segment
		(start 398.502124 -343.874344)
		(end 398.502124 -344.450162)
		(width 0.10668)
		(layer "B.Cu")
		(net "FM_BIOS_POST_CMPLT_BUF_R1_N")
	)
	(segment
		(start 401.554696 -343.350342)
		(end 403.250654 -343.350342)
		(width 0.10668)
		(layer "B.Cu")
		(net "FM_BIOS_POST_CMPLT_BUF_R1_N")
	)
	(segment
		(start 401.554696 -343.350342)
		(end 399.026126 -343.350342)
		(width 0.10668)
		(layer "B.Cu")
		(net "FM_BIOS_POST_CMPLT_BUF_R1_N")
	)
	(segment
		(start 398.79016 -343.586308)
		(end 398.502124 -343.874344)
		(width 0.10668)
		(layer "B.Cu")
		(net "FM_BIOS_POST_CMPLT_BUF_R1_N")
	)
	(segment
		(start 399.026126 -343.350342)
		(end 398.79016 -343.586308)
		(width 0.10668)
		(layer "B.Cu")
		(net "FM_BIOS_POST_CMPLT_BUF_R1_N")
	)
	(via
		(at 314.150502 7.356094)
		(size 0.508)
		(drill 0.254)
		(layers "F.Cu" "B.Cu")
		(net "DELTA_L_GND_1")
	)
	(via
		(at 366.244632 1.61798)
		(size 0.508)
		(drill 0.254)
		(layers "F.Cu" "B.Cu")
		(net "DELTA_L_GND_1")
	)
	(via
		(at 391.56132 7.327646)
		(size 0.508)
		(drill 0.254)
		(layers "F.Cu" "B.Cu")
		(net "DELTA_L_GND_1")
	)
	(via
		(at 300.517306 -0.970534)
		(size 0.508)
		(drill 0.254)
		(layers "F.Cu" "B.Cu")
		(net "DELTA_L_GND_1")
	)
	(via
		(at 301.323248 2.558796)
		(size 0.508)
		(drill 0.254)
		(layers "F.Cu" "B.Cu")
		(net "DELTA_L_GND_1")
	)
	(via
		(at 97.795842 7.768336)
		(size 0.508)
		(drill 0.254)
		(layers "F.Cu" "B.Cu")
		(net "DELTA_L_GND_1")
	)
	(via
		(at 364.189518 3.904996)
		(size 0.508)
		(drill 0.254)
		(layers "F.Cu" "B.Cu")
		(net "DELTA_L_GND_1")
	)
	(via
		(at 211.689188 -4.148836)
		(size 0.508)
		(drill 0.254)
		(layers "F.Cu" "B.Cu")
		(net "DELTA_L_GND_1")
	)
	(via
		(at 96.95815 5.84835)
		(size 0.508)
		(drill 0.254)
		(layers "F.Cu" "B.Cu")
		(net "DELTA_L_GND_1")
	)
	(via
		(at 364.189518 1.180592)
		(size 0.508)
		(drill 0.254)
		(layers "F.Cu" "B.Cu")
		(net "DELTA_L_GND_1")
	)
	(via
		(at 211.686648 -2.553208)
		(size 0.508)
		(drill 0.254)
		(layers "F.Cu" "B.Cu")
		(net "DELTA_L_GND_1")
	)
	(via
		(at 314.146692 7.994904)
		(size 0.508)
		(drill 0.254)
		(layers "F.Cu" "B.Cu")
		(net "DELTA_L_GND_1")
	)
	(via
		(at 315.00953 -1.612392)
		(size 0.508)
		(drill 0.254)
		(layers "F.Cu" "B.Cu")
		(net "DELTA_L_GND_1")
	)
	(via
		(at 317.064644 -1.359408)
		(size 0.508)
		(drill 0.254)
		(layers "F.Cu" "B.Cu")
		(net "DELTA_L_GND_1")
	)
	(via
		(at 300.517306 4.109466)
		(size 0.508)
		(drill 0.254)
		(layers "F.Cu" "B.Cu")
		(net "DELTA_L_GND_1")
	)
	(via
		(at 366.244632 4.15798)
		(size 0.508)
		(drill 0.254)
		(layers "F.Cu" "B.Cu")
		(net "DELTA_L_GND_1")
	)
	(via
		(at 99.894898 2.345436)
		(size 0.508)
		(drill 0.254)
		(layers "F.Cu" "B.Cu")
		(net "DELTA_L_GND_1")
	)
	(via
		(at 366.244886 2.526792)
		(size 0.508)
		(drill 0.254)
		(layers "F.Cu" "B.Cu")
		(net "DELTA_L_GND_1")
	)
	(via
		(at 213.2838 6.342888)
		(size 0.508)
		(drill 0.254)
		(layers "F.Cu" "B.Cu")
		(net "DELTA_L_GND_1")
	)
	(via
		(at 212.51164 -3.513582)
		(size 0.508)
		(drill 0.254)
		(layers "F.Cu" "B.Cu")
		(net "DELTA_L_GND_1")
	)
	(via
		(at 438.686194 9.867646)
		(size 0.508)
		(drill 0.254)
		(layers "F.Cu" "B.Cu")
		(net "DELTA_L_GND_1")
	)
	(via
		(at 367.070894 6.694424)
		(size 0.508)
		(drill 0.254)
		(layers "F.Cu" "B.Cu")
		(net "DELTA_L_GND_1")
	)
	(via
		(at 365.501682 9.034526)
		(size 0.508)
		(drill 0.254)
		(layers "F.Cu" "B.Cu")
		(net "DELTA_L_GND_1")
	)
	(via
		(at 299.745146 6.345936)
		(size 0.508)
		(drill 0.254)
		(layers "F.Cu" "B.Cu")
		(net "DELTA_L_GND_1")
	)
	(via
		(at 214.570564 1.364996)
		(size 0.508)
		(drill 0.254)
		(layers "F.Cu" "B.Cu")
		(net "DELTA_L_GND_1")
	)
	(via
		(at 314.179204 -6.155944)
		(size 0.508)
		(drill 0.254)
		(layers "F.Cu" "B.Cu")
		(net "DELTA_L_GND_1")
	)
	(via
		(at 185.094372 2.153412)
		(size 0.508)
		(drill 0.254)
		(layers "F.Cu" "B.Cu")
		(net "DELTA_L_GND_1")
	)
	(via
		(at 315.009276 2.526792)
		(size 0.508)
		(drill 0.254)
		(layers "F.Cu" "B.Cu")
		(net "DELTA_L_GND_1")
	)
	(via
		(at 441.622942 6.364732)
		(size 0.508)
		(drill 0.254)
		(layers "F.Cu" "B.Cu")
		(net "DELTA_L_GND_1")
	)
	(via
		(at 366.244632 -0.92202)
		(size 0.508)
		(drill 0.254)
		(layers "F.Cu" "B.Cu")
		(net "DELTA_L_GND_1")
	)
	(via
		(at 317.064644 8.800592)
		(size 0.508)
		(drill 0.254)
		(layers "F.Cu" "B.Cu")
		(net "DELTA_L_GND_1")
	)
	(via
		(at 213.2838 3.802888)
		(size 0.508)
		(drill 0.254)
		(layers "F.Cu" "B.Cu")
		(net "DELTA_L_GND_1")
	)
	(via
		(at 212.507576 8.034274)
		(size 0.508)
		(drill 0.254)
		(layers "F.Cu" "B.Cu")
		(net "DELTA_L_GND_1")
	)
	(via
		(at 314.179458 -0.970026)
		(size 0.508)
		(drill 0.254)
		(layers "F.Cu" "B.Cu")
		(net "DELTA_L_GND_1")
	)
	(via
		(at 186.692794 7.12597)
		(size 0.508)
		(drill 0.254)
		(layers "F.Cu" "B.Cu")
		(net "DELTA_L_GND_1")
	)
	(via
		(at 314.179458 -3.510026)
		(size 0.508)
		(drill 0.254)
		(layers "F.Cu" "B.Cu")
		(net "DELTA_L_GND_1")
	)
	(via
		(at 364.189518 -3.715004)
		(size 0.508)
		(drill 0.254)
		(layers "F.Cu" "B.Cu")
		(net "DELTA_L_GND_1")
	)
	(via
		(at 388.624572 8.474964)
		(size 0.508)
		(drill 0.254)
		(layers "F.Cu" "B.Cu")
		(net "DELTA_L_GND_1")
	)
	(via
		(at 388.636002 4.448302)
		(size 0.508)
		(drill 0.254)
		(layers "F.Cu" "B.Cu")
		(net "DELTA_L_GND_1")
	)
	(via
		(at 314.99683 6.019292)
		(size 0.508)
		(drill 0.254)
		(layers "F.Cu" "B.Cu")
		(net "DELTA_L_GND_1")
	)
	(via
		(at 301.343568 -0.966978)
		(size 0.508)
		(drill 0.254)
		(layers "F.Cu" "B.Cu")
		(net "DELTA_L_GND_1")
	)
	(via
		(at 185.094372 7.433056)
		(size 0.508)
		(drill 0.254)
		(layers "F.Cu" "B.Cu")
		(net "DELTA_L_GND_1")
	)
	(via
		(at 440.0169 10.05967)
		(size 0.508)
		(drill 0.254)
		(layers "F.Cu" "B.Cu")
		(net "DELTA_L_GND_1")
	)
	(via
		(at 315.009276 -0.013208)
		(size 0.508)
		(drill 0.254)
		(layers "F.Cu" "B.Cu")
		(net "DELTA_L_GND_1")
	)
	(via
		(at 366.244886 -2.553208)
		(size 0.508)
		(drill 0.254)
		(layers "F.Cu" "B.Cu")
		(net "DELTA_L_GND_1")
	)
	(via
		(at 389.458454 9.75614)
		(size 0.508)
		(drill 0.254)
		(layers "F.Cu" "B.Cu")
		(net "DELTA_L_GND_1")
	)
	(via
		(at 389.458454 5.083556)
		(size 0.508)
		(drill 0.254)
		(layers "F.Cu" "B.Cu")
		(net "DELTA_L_GND_1")
	)
	(via
		(at 213.2838 -1.277112)
		(size 0.508)
		(drill 0.254)
		(layers "F.Cu" "B.Cu")
		(net "DELTA_L_GND_1")
	)
	(via
		(at 301.339758 0.934212)
		(size 0.508)
		(drill 0.254)
		(layers "F.Cu" "B.Cu")
		(net "DELTA_L_GND_1")
	)
	(via
		(at 300.523656 9.338056)
		(size 0.508)
		(drill 0.254)
		(layers "F.Cu" "B.Cu")
		(net "DELTA_L_GND_1")
	)
	(via
		(at 300.4947 2.558796)
		(size 0.508)
		(drill 0.254)
		(layers "F.Cu" "B.Cu")
		(net "DELTA_L_GND_1")
	)
	(via
		(at 367.074704 6.055614)
		(size 0.508)
		(drill 0.254)
		(layers "F.Cu" "B.Cu")
		(net "DELTA_L_GND_1")
	)
	(via
		(at 314.171584 -4.878324)
		(size 0.508)
		(drill 0.254)
		(layers "F.Cu" "B.Cu")
		(net "DELTA_L_GND_1")
	)
	(via
		(at 440.788806 7.729474)
		(size 0.508)
		(drill 0.254)
		(layers "F.Cu" "B.Cu")
		(net "DELTA_L_GND_1")
	)
	(via
		(at 300.517306 -3.510534)
		(size 0.508)
		(drill 0.254)
		(layers "F.Cu" "B.Cu")
		(net "DELTA_L_GND_1")
	)
	(via
		(at 440.784996 7.090664)
		(size 0.508)
		(drill 0.254)
		(layers "F.Cu" "B.Cu")
		(net "DELTA_L_GND_1")
	)
	(via
		(at 366.244632 -3.46202)
		(size 0.508)
		(drill 0.254)
		(layers "F.Cu" "B.Cu")
		(net "DELTA_L_GND_1")
	)
	(via
		(at 441.615322 9.752584)
		(size 0.508)
		(drill 0.254)
		(layers "F.Cu" "B.Cu")
		(net "DELTA_L_GND_1")
	)
	(via
		(at 213.2838 -3.817112)
		(size 0.508)
		(drill 0.254)
		(layers "F.Cu" "B.Cu")
		(net "DELTA_L_GND_1")
	)
	(via
		(at 98.564446 4.79933)
		(size 0.508)
		(drill 0.254)
		(layers "F.Cu" "B.Cu")
		(net "DELTA_L_GND_1")
	)
	(via
		(at 315.009276 -2.553208)
		(size 0.508)
		(drill 0.254)
		(layers "F.Cu" "B.Cu")
		(net "DELTA_L_GND_1")
	)
	(via
		(at 366.263936 -6.782308)
		(size 0.508)
		(drill 0.254)
		(layers "F.Cu" "B.Cu")
		(net "DELTA_L_GND_1")
	)
	(via
		(at 365.495586 -6.447028)
		(size 0.508)
		(drill 0.254)
		(layers "F.Cu" "B.Cu")
		(net "DELTA_L_GND_1")
	)
	(via
		(at 212.515196 -0.013208)
		(size 0.508)
		(drill 0.254)
		(layers "F.Cu" "B.Cu")
		(net "DELTA_L_GND_1")
	)
	(via
		(at 186.68873 4.467606)
		(size 0.508)
		(drill 0.254)
		(layers "F.Cu" "B.Cu")
		(net "DELTA_L_GND_1")
	)
	(via
		(at 301.343568 -3.506978)
		(size 0.508)
		(drill 0.254)
		(layers "F.Cu" "B.Cu")
		(net "DELTA_L_GND_1")
	)
	(via
		(at 388.636002 10.391394)
		(size 0.508)
		(drill 0.254)
		(layers "F.Cu" "B.Cu")
		(net "DELTA_L_GND_1")
	)
	(via
		(at 96.96196 3.099308)
		(size 0.508)
		(drill 0.254)
		(layers "F.Cu" "B.Cu")
		(net "DELTA_L_GND_1")
	)
	(via
		(at 299.745146 -3.814064)
		(size 0.508)
		(drill 0.254)
		(layers "F.Cu" "B.Cu")
		(net "DELTA_L_GND_1")
	)
	(via
		(at 298.439332 3.904996)
		(size 0.508)
		(drill 0.254)
		(layers "F.Cu" "B.Cu")
		(net "DELTA_L_GND_1")
	)
	(via
		(at 314.183268 3.471164)
		(size 0.508)
		(drill 0.254)
		(layers "F.Cu" "B.Cu")
		(net "DELTA_L_GND_1")
	)
	(via
		(at 96.96577 7.12597)
		(size 0.508)
		(drill 0.254)
		(layers "F.Cu" "B.Cu")
		(net "DELTA_L_GND_1")
	)
	(via
		(at 99.894898 4.701032)
		(size 0.508)
		(drill 0.254)
		(layers "F.Cu" "B.Cu")
		(net "DELTA_L_GND_1")
	)
	(via
		(at 301.347632 -5.501132)
		(size 0.508)
		(drill 0.254)
		(layers "F.Cu" "B.Cu")
		(net "DELTA_L_GND_1")
	)
	(via
		(at 314.183268 0.931164)
		(size 0.508)
		(drill 0.254)
		(layers "F.Cu" "B.Cu")
		(net "DELTA_L_GND_1")
	)
	(via
		(at 212.515196 9.311894)
		(size 0.508)
		(drill 0.254)
		(layers "F.Cu" "B.Cu")
		(net "DELTA_L_GND_1")
	)
	(via
		(at 300.513496 0.930656)
		(size 0.508)
		(drill 0.254)
		(layers "F.Cu" "B.Cu")
		(net "DELTA_L_GND_1")
	)
	(via
		(at 367.074704 0.975614)
		(size 0.508)
		(drill 0.254)
		(layers "F.Cu" "B.Cu")
		(net "DELTA_L_GND_1")
	)
	(via
		(at 96.966024 5.106416)
		(size 0.508)
		(drill 0.254)
		(layers "F.Cu" "B.Cu")
		(net "DELTA_L_GND_1")
	)
	(via
		(at 212.51545 6.007608)
		(size 0.508)
		(drill 0.254)
		(layers "F.Cu" "B.Cu")
		(net "DELTA_L_GND_1")
	)
	(via
		(at 214.570564 -6.255004)
		(size 0.508)
		(drill 0.254)
		(layers "F.Cu" "B.Cu")
		(net "DELTA_L_GND_1")
	)
	(via
		(at 300.513496 3.470656)
		(size 0.508)
		(drill 0.254)
		(layers "F.Cu" "B.Cu")
		(net "DELTA_L_GND_1")
	)
	(via
		(at 299.745146 -1.274064)
		(size 0.508)
		(drill 0.254)
		(layers "F.Cu" "B.Cu")
		(net "DELTA_L_GND_1")
	)
	(via
		(at 213.283546 -6.46303)
		(size 0.508)
		(drill 0.254)
		(layers "F.Cu" "B.Cu")
		(net "DELTA_L_GND_1")
	)
	(via
		(at 183.763666 7.241032)
		(size 0.508)
		(drill 0.254)
		(layers "F.Cu" "B.Cu")
		(net "DELTA_L_GND_1")
	)
	(via
		(at 315.009276 5.066792)
		(size 0.508)
		(drill 0.254)
		(layers "F.Cu" "B.Cu")
		(net "DELTA_L_GND_1")
	)
	(via
		(at 213.283546 8.976614)
		(size 0.508)
		(drill 0.254)
		(layers "F.Cu" "B.Cu")
		(net "DELTA_L_GND_1")
	)
	(via
		(at 212.51164 1.566418)
		(size 0.508)
		(drill 0.254)
		(layers "F.Cu" "B.Cu")
		(net "DELTA_L_GND_1")
	)
	(via
		(at 315.00953 3.467608)
		(size 0.508)
		(drill 0.254)
		(layers "F.Cu" "B.Cu")
		(net "DELTA_L_GND_1")
	)
	(via
		(at 314.158376 8.724392)
		(size 0.508)
		(drill 0.254)
		(layers "F.Cu" "B.Cu")
		(net "DELTA_L_GND_1")
	)
	(via
		(at 300.51756 -6.143498)
		(size 0.508)
		(drill 0.254)
		(layers "F.Cu" "B.Cu")
		(net "DELTA_L_GND_1")
	)
	(via
		(at 186.69254 5.106416)
		(size 0.508)
		(drill 0.254)
		(layers "F.Cu" "B.Cu")
		(net "DELTA_L_GND_1")
	)
	(via
		(at 301.323248 -2.521204)
		(size 0.508)
		(drill 0.254)
		(layers "F.Cu" "B.Cu")
		(net "DELTA_L_GND_1")
	)
	(via
		(at 299.751496 9.034526)
		(size 0.508)
		(drill 0.254)
		(layers "F.Cu" "B.Cu")
		(net "DELTA_L_GND_1")
	)
	(via
		(at 314.179458 4.109974)
		(size 0.508)
		(drill 0.254)
		(layers "F.Cu" "B.Cu")
		(net "DELTA_L_GND_1")
	)
	(via
		(at 314.180728 2.526792)
		(size 0.508)
		(drill 0.254)
		(layers "F.Cu" "B.Cu")
		(net "DELTA_L_GND_1")
	)
	(via
		(at 186.696604 6.48716)
		(size 0.508)
		(drill 0.254)
		(layers "F.Cu" "B.Cu")
		(net "DELTA_L_GND_1")
	)
	(via
		(at 301.353982 7.347458)
		(size 0.508)
		(drill 0.254)
		(layers "F.Cu" "B.Cu")
		(net "DELTA_L_GND_1")
	)
	(via
		(at 211.681314 -5.517134)
		(size 0.508)
		(drill 0.254)
		(layers "F.Cu" "B.Cu")
		(net "DELTA_L_GND_1")
	)
	(via
		(at 301.323248 5.098796)
		(size 0.508)
		(drill 0.254)
		(layers "F.Cu" "B.Cu")
		(net "DELTA_L_GND_1")
	)
	(via
		(at 315.77788 1.262888)
		(size 0.508)
		(drill 0.254)
		(layers "F.Cu" "B.Cu")
		(net "DELTA_L_GND_1")
	)
	(via
		(at 186.700414 3.738118)
		(size 0.508)
		(drill 0.254)
		(layers "F.Cu" "B.Cu")
		(net "DELTA_L_GND_1")
	)
	(via
		(at 211.685378 -0.970026)
		(size 0.508)
		(drill 0.254)
		(layers "F.Cu" "B.Cu")
		(net "DELTA_L_GND_1")
	)
	(via
		(at 96.96958 1.821688)
		(size 0.508)
		(drill 0.254)
		(layers "F.Cu" "B.Cu")
		(net "DELTA_L_GND_1")
	)
	(via
		(at 186.696604 3.099308)
		(size 0.508)
		(drill 0.254)
		(layers "F.Cu" "B.Cu")
		(net "DELTA_L_GND_1")
	)
	(via
		(at 366.270032 8.699246)
		(size 0.508)
		(drill 0.254)
		(layers "F.Cu" "B.Cu")
		(net "DELTA_L_GND_1")
	)
	(via
		(at 212.51164 4.106418)
		(size 0.508)
		(drill 0.254)
		(layers "F.Cu" "B.Cu")
		(net "DELTA_L_GND_1")
	)
	(via
		(at 315.00572 1.566418)
		(size 0.508)
		(drill 0.254)
		(layers "F.Cu" "B.Cu")
		(net "DELTA_L_GND_1")
	)
	(via
		(at 97.795842 1.818132)
		(size 0.508)
		(drill 0.254)
		(layers "F.Cu" "B.Cu")
		(net "DELTA_L_GND_1")
	)
	(via
		(at 300.51375 -6.782308)
		(size 0.508)
		(drill 0.254)
		(layers "F.Cu" "B.Cu")
		(net "DELTA_L_GND_1")
	)
	(via
		(at 366.248442 -1.56083)
		(size 0.508)
		(drill 0.254)
		(layers "F.Cu" "B.Cu")
		(net "DELTA_L_GND_1")
	)
	(via
		(at 211.685124 -6.155944)
		(size 0.508)
		(drill 0.254)
		(layers "F.Cu" "B.Cu")
		(net "DELTA_L_GND_1")
	)
	(via
		(at 365.476282 6.3627)
		(size 0.508)
		(drill 0.254)
		(layers "F.Cu" "B.Cu")
		(net "DELTA_L_GND_1")
	)
	(via
		(at 314.170568 6.022848)
		(size 0.508)
		(drill 0.254)
		(layers "F.Cu" "B.Cu")
		(net "DELTA_L_GND_1")
	)
	(via
		(at 366.273842 9.338056)
		(size 0.508)
		(drill 0.254)
		(layers "F.Cu" "B.Cu")
		(net "DELTA_L_GND_1")
	)
	(via
		(at 365.476282 -1.2573)
		(size 0.508)
		(drill 0.254)
		(layers "F.Cu" "B.Cu")
		(net "DELTA_L_GND_1")
	)
	(via
		(at 185.866532 2.456942)
		(size 0.508)
		(drill 0.254)
		(layers "F.Cu" "B.Cu")
		(net "DELTA_L_GND_1")
	)
	(via
		(at 212.511386 8.673084)
		(size 0.508)
		(drill 0.254)
		(layers "F.Cu" "B.Cu")
		(net "DELTA_L_GND_1")
	)
	(via
		(at 314.183268 -1.608836)
		(size 0.508)
		(drill 0.254)
		(layers "F.Cu" "B.Cu")
		(net "DELTA_L_GND_1")
	)
	(via
		(at 300.4947 5.098796)
		(size 0.508)
		(drill 0.254)
		(layers "F.Cu" "B.Cu")
		(net "DELTA_L_GND_1")
	)
	(via
		(at 96.96196 6.48716)
		(size 0.508)
		(drill 0.254)
		(layers "F.Cu" "B.Cu")
		(net "DELTA_L_GND_1")
	)
	(via
		(at 314.180728 -2.553208)
		(size 0.508)
		(drill 0.254)
		(layers "F.Cu" "B.Cu")
		(net "DELTA_L_GND_1")
	)
	(via
		(at 211.677504 -4.878324)
		(size 0.508)
		(drill 0.254)
		(layers "F.Cu" "B.Cu")
		(net "DELTA_L_GND_1")
	)
	(via
		(at 211.677504 7.391908)
		(size 0.508)
		(drill 0.254)
		(layers "F.Cu" "B.Cu")
		(net "DELTA_L_GND_1")
	)
	(via
		(at 183.763666 2.345436)
		(size 0.508)
		(drill 0.254)
		(layers "F.Cu" "B.Cu")
		(net "DELTA_L_GND_1")
	)
	(via
		(at 364.189518 6.444996)
		(size 0.508)
		(drill 0.254)
		(layers "F.Cu" "B.Cu")
		(net "DELTA_L_GND_1")
	)
	(via
		(at 212.51545 3.467608)
		(size 0.508)
		(drill 0.254)
		(layers "F.Cu" "B.Cu")
		(net "DELTA_L_GND_1")
	)
	(via
		(at 99.894898 7.241032)
		(size 0.508)
		(drill 0.254)
		(layers "F.Cu" "B.Cu")
		(net "DELTA_L_GND_1")
	)
	(via
		(at 441.611512 4.448302)
		(size 0.508)
		(drill 0.254)
		(layers "F.Cu" "B.Cu")
		(net "DELTA_L_GND_1")
	)
	(via
		(at 212.503766 7.395464)
		(size 0.508)
		(drill 0.254)
		(layers "F.Cu" "B.Cu")
		(net "DELTA_L_GND_1")
	)
	(via
		(at 367.100104 9.341612)
		(size 0.508)
		(drill 0.254)
		(layers "F.Cu" "B.Cu")
		(net "DELTA_L_GND_1")
	)
	(via
		(at 367.070894 -3.465576)
		(size 0.508)
		(drill 0.254)
		(layers "F.Cu" "B.Cu")
		(net "DELTA_L_GND_1")
	)
	(via
		(at 364.189518 8.800592)
		(size 0.508)
		(drill 0.254)
		(layers "F.Cu" "B.Cu")
		(net "DELTA_L_GND_1")
	)
	(via
		(at 315.76518 6.354572)
		(size 0.508)
		(drill 0.254)
		(layers "F.Cu" "B.Cu")
		(net "DELTA_L_GND_1")
	)
	(via
		(at 441.615068 7.73303)
		(size 0.508)
		(drill 0.254)
		(layers "F.Cu" "B.Cu")
		(net "DELTA_L_GND_1")
	)
	(via
		(at 299.7454 -6.447028)
		(size 0.508)
		(drill 0.254)
		(layers "F.Cu" "B.Cu")
		(net "DELTA_L_GND_1")
	)
	(via
		(at 390.230614 10.05967)
		(size 0.508)
		(drill 0.254)
		(layers "F.Cu" "B.Cu")
		(net "DELTA_L_GND_1")
	)
	(via
		(at 211.685378 6.649974)
		(size 0.508)
		(drill 0.254)
		(layers "F.Cu" "B.Cu")
		(net "DELTA_L_GND_1")
	)
	(via
		(at 440.78906 5.083556)
		(size 0.508)
		(drill 0.254)
		(layers "F.Cu" "B.Cu")
		(net "DELTA_L_GND_1")
	)
	(via
		(at 96.96577 2.460498)
		(size 0.508)
		(drill 0.254)
		(layers "F.Cu" "B.Cu")
		(net "DELTA_L_GND_1")
	)
	(via
		(at 441.619132 5.725922)
		(size 0.508)
		(drill 0.254)
		(layers "F.Cu" "B.Cu")
		(net "DELTA_L_GND_1")
	)
	(via
		(at 186.688984 1.821688)
		(size 0.508)
		(drill 0.254)
		(layers "F.Cu" "B.Cu")
		(net "DELTA_L_GND_1")
	)
	(via
		(at 388.632446 7.73303)
		(size 0.508)
		(drill 0.254)
		(layers "F.Cu" "B.Cu")
		(net "DELTA_L_GND_1")
	)
	(via
		(at 314.154566 9.363202)
		(size 0.508)
		(drill 0.254)
		(layers "F.Cu" "B.Cu")
		(net "DELTA_L_GND_1")
	)
	(via
		(at 211.688934 -6.794754)
		(size 0.508)
		(drill 0.254)
		(layers "F.Cu" "B.Cu")
		(net "DELTA_L_GND_1")
	)
	(via
		(at 300.513496 -1.609344)
		(size 0.508)
		(drill 0.254)
		(layers "F.Cu" "B.Cu")
		(net "DELTA_L_GND_1")
	)
	(via
		(at 185.866532 7.129526)
		(size 0.508)
		(drill 0.254)
		(layers "F.Cu" "B.Cu")
		(net "DELTA_L_GND_1")
	)
	(via
		(at 96.95815 3.738118)
		(size 0.508)
		(drill 0.254)
		(layers "F.Cu" "B.Cu")
		(net "DELTA_L_GND_1")
	)
	(via
		(at 366.248442 -4.10083)
		(size 0.508)
		(drill 0.254)
		(layers "F.Cu" "B.Cu")
		(net "DELTA_L_GND_1")
	)
	(via
		(at 98.564192 7.433056)
		(size 0.508)
		(drill 0.254)
		(layers "F.Cu" "B.Cu")
		(net "DELTA_L_GND_1")
	)
	(via
		(at 388.628382 9.113774)
		(size 0.508)
		(drill 0.254)
		(layers "F.Cu" "B.Cu")
		(net "DELTA_L_GND_1")
	)
	(via
		(at 314.180728 5.066792)
		(size 0.508)
		(drill 0.254)
		(layers "F.Cu" "B.Cu")
		(net "DELTA_L_GND_1")
	)
	(via
		(at 367.074704 -1.564386)
		(size 0.508)
		(drill 0.254)
		(layers "F.Cu" "B.Cu")
		(net "DELTA_L_GND_1")
	)
	(via
		(at 441.611258 7.09422)
		(size 0.508)
		(drill 0.254)
		(layers "F.Cu" "B.Cu")
		(net "DELTA_L_GND_1")
	)
	(via
		(at 314.984638 8.720836)
		(size 0.508)
		(drill 0.254)
		(layers "F.Cu" "B.Cu")
		(net "DELTA_L_GND_1")
	)
	(via
		(at 298.439332 6.260592)
		(size 0.508)
		(drill 0.254)
		(layers "F.Cu" "B.Cu")
		(net "DELTA_L_GND_1")
	)
	(via
		(at 212.515196 -2.553208)
		(size 0.508)
		(drill 0.254)
		(layers "F.Cu" "B.Cu")
		(net "DELTA_L_GND_1")
	)
	(via
		(at 185.866278 5.10286)
		(size 0.508)
		(drill 0.254)
		(layers "F.Cu" "B.Cu")
		(net "DELTA_L_GND_1")
	)
	(via
		(at 441.622942 8.474964)
		(size 0.508)
		(drill 0.254)
		(layers "F.Cu" "B.Cu")
		(net "DELTA_L_GND_1")
	)
	(via
		(at 367.074704 -4.104386)
		(size 0.508)
		(drill 0.254)
		(layers "F.Cu" "B.Cu")
		(net "DELTA_L_GND_1")
	)
	(via
		(at 212.515196 2.526792)
		(size 0.508)
		(drill 0.254)
		(layers "F.Cu" "B.Cu")
		(net "DELTA_L_GND_1")
	)
	(via
		(at 367.073434 2.526792)
		(size 0.508)
		(drill 0.254)
		(layers "F.Cu" "B.Cu")
		(net "DELTA_L_GND_1")
	)
	(via
		(at 367.073434 5.066792)
		(size 0.508)
		(drill 0.254)
		(layers "F.Cu" "B.Cu")
		(net "DELTA_L_GND_1")
	)
	(via
		(at 391.56132 9.867646)
		(size 0.508)
		(drill 0.254)
		(layers "F.Cu" "B.Cu")
		(net "DELTA_L_GND_1")
	)
	(via
		(at 440.016646 7.425944)
		(size 0.508)
		(drill 0.254)
		(layers "F.Cu" "B.Cu")
		(net "DELTA_L_GND_1")
	)
	(via
		(at 315.752988 9.056116)
		(size 0.508)
		(drill 0.254)
		(layers "F.Cu" "B.Cu")
		(net "DELTA_L_GND_1")
	)
	(via
		(at 367.073434 -0.013208)
		(size 0.508)
		(drill 0.254)
		(layers "F.Cu" "B.Cu")
		(net "DELTA_L_GND_1")
	)
	(via
		(at 212.51164 6.646418)
		(size 0.508)
		(drill 0.254)
		(layers "F.Cu" "B.Cu")
		(net "DELTA_L_GND_1")
	)
	(via
		(at 315.777626 -6.46303)
		(size 0.508)
		(drill 0.254)
		(layers "F.Cu" "B.Cu")
		(net "DELTA_L_GND_1")
	)
	(via
		(at 300.4947 0.018796)
		(size 0.508)
		(drill 0.254)
		(layers "F.Cu" "B.Cu")
		(net "DELTA_L_GND_1")
	)
	(via
		(at 441.615322 5.087112)
		(size 0.508)
		(drill 0.254)
		(layers "F.Cu" "B.Cu")
		(net "DELTA_L_GND_1")
	)
	(via
		(at 96.969834 4.467606)
		(size 0.508)
		(drill 0.254)
		(layers "F.Cu" "B.Cu")
		(net "DELTA_L_GND_1")
	)
	(via
		(at 365.476282 -3.7973)
		(size 0.508)
		(drill 0.254)
		(layers "F.Cu" "B.Cu")
		(net "DELTA_L_GND_1")
	)
	(via
		(at 300.517306 1.569466)
		(size 0.508)
		(drill 0.254)
		(layers "F.Cu" "B.Cu")
		(net "DELTA_L_GND_1")
	)
	(via
		(at 367.107978 7.986268)
		(size 0.508)
		(drill 0.254)
		(layers "F.Cu" "B.Cu")
		(net "DELTA_L_GND_1")
	)
	(via
		(at 366.248442 0.97917)
		(size 0.508)
		(drill 0.254)
		(layers "F.Cu" "B.Cu")
		(net "DELTA_L_GND_1")
	)
	(via
		(at 301.343568 1.573022)
		(size 0.508)
		(drill 0.254)
		(layers "F.Cu" "B.Cu")
		(net "DELTA_L_GND_1")
	)
	(via
		(at 314.980828 9.359646)
		(size 0.508)
		(drill 0.254)
		(layers "F.Cu" "B.Cu")
		(net "DELTA_L_GND_1")
	)
	(via
		(at 440.78906 9.75614)
		(size 0.508)
		(drill 0.254)
		(layers "F.Cu" "B.Cu")
		(net "DELTA_L_GND_1")
	)
	(via
		(at 300.519846 8.699246)
		(size 0.508)
		(drill 0.254)
		(layers "F.Cu" "B.Cu")
		(net "DELTA_L_GND_1")
	)
	(via
		(at 315.009276 -6.79831)
		(size 0.508)
		(drill 0.254)
		(layers "F.Cu" "B.Cu")
		(net "DELTA_L_GND_1")
	)
	(via
		(at 314.99302 6.658102)
		(size 0.508)
		(drill 0.254)
		(layers "F.Cu" "B.Cu")
		(net "DELTA_L_GND_1")
	)
	(via
		(at 185.862722 7.768336)
		(size 0.508)
		(drill 0.254)
		(layers "F.Cu" "B.Cu")
		(net "DELTA_L_GND_1")
	)
	(via
		(at 300.513496 -4.149344)
		(size 0.508)
		(drill 0.254)
		(layers "F.Cu" "B.Cu")
		(net "DELTA_L_GND_1")
	)
	(via
		(at 183.763666 4.885436)
		(size 0.508)
		(drill 0.254)
		(layers "F.Cu" "B.Cu")
		(net "DELTA_L_GND_1")
	)
	(via
		(at 389.462264 4.444746)
		(size 0.508)
		(drill 0.254)
		(layers "F.Cu" "B.Cu")
		(net "DELTA_L_GND_1")
	)
	(via
		(at 366.244632 6.69798)
		(size 0.508)
		(drill 0.254)
		(layers "F.Cu" "B.Cu")
		(net "DELTA_L_GND_1")
	)
	(via
		(at 301.343568 6.653022)
		(size 0.508)
		(drill 0.254)
		(layers "F.Cu" "B.Cu")
		(net "DELTA_L_GND_1")
	)
	(via
		(at 317.064644 1.180592)
		(size 0.508)
		(drill 0.254)
		(layers "F.Cu" "B.Cu")
		(net "DELTA_L_GND_1")
	)
	(via
		(at 438.686194 4.97205)
		(size 0.508)
		(drill 0.254)
		(layers "F.Cu" "B.Cu")
		(net "DELTA_L_GND_1")
	)
	(via
		(at 301.357792 7.986268)
		(size 0.508)
		(drill 0.254)
		(layers "F.Cu" "B.Cu")
		(net "DELTA_L_GND_1")
	)
	(via
		(at 211.688934 9.308338)
		(size 0.508)
		(drill 0.254)
		(layers "F.Cu" "B.Cu")
		(net "DELTA_L_GND_1")
	)
	(via
		(at 185.862722 1.818132)
		(size 0.508)
		(drill 0.254)
		(layers "F.Cu" "B.Cu")
		(net "DELTA_L_GND_1")
	)
	(via
		(at 211.686648 -0.013208)
		(size 0.508)
		(drill 0.254)
		(layers "F.Cu" "B.Cu")
		(net "DELTA_L_GND_1")
	)
	(via
		(at 211.686648 2.526792)
		(size 0.508)
		(drill 0.254)
		(layers "F.Cu" "B.Cu")
		(net "DELTA_L_GND_1")
	)
	(via
		(at 314.175394 -5.517134)
		(size 0.508)
		(drill 0.254)
		(layers "F.Cu" "B.Cu")
		(net "DELTA_L_GND_1")
	)
	(via
		(at 315.00572 4.106418)
		(size 0.508)
		(drill 0.254)
		(layers "F.Cu" "B.Cu")
		(net "DELTA_L_GND_1")
	)
	(via
		(at 300.513496 6.010656)
		(size 0.508)
		(drill 0.254)
		(layers "F.Cu" "B.Cu")
		(net "DELTA_L_GND_1")
	)
	(via
		(at 211.681314 8.030718)
		(size 0.508)
		(drill 0.254)
		(layers "F.Cu" "B.Cu")
		(net "DELTA_L_GND_1")
	)
	(via
		(at 389.462518 7.090664)
		(size 0.508)
		(drill 0.254)
		(layers "F.Cu" "B.Cu")
		(net "DELTA_L_GND_1")
	)
	(via
		(at 314.183268 -4.148836)
		(size 0.508)
		(drill 0.254)
		(layers "F.Cu" "B.Cu")
		(net "DELTA_L_GND_1")
	)
	(via
		(at 315.77788 -3.817112)
		(size 0.508)
		(drill 0.254)
		(layers "F.Cu" "B.Cu")
		(net "DELTA_L_GND_1")
	)
	(via
		(at 214.570564 6.260592)
		(size 0.508)
		(drill 0.254)
		(layers "F.Cu" "B.Cu")
		(net "DELTA_L_GND_1")
	)
	(via
		(at 97.796096 4.46405)
		(size 0.508)
		(drill 0.254)
		(layers "F.Cu" "B.Cu")
		(net "DELTA_L_GND_1")
	)
	(via
		(at 212.511386 -6.1595)
		(size 0.508)
		(drill 0.254)
		(layers "F.Cu" "B.Cu")
		(net "DELTA_L_GND_1")
	)
	(via
		(at 300.4947 -2.521204)
		(size 0.508)
		(drill 0.254)
		(layers "F.Cu" "B.Cu")
		(net "DELTA_L_GND_1")
	)
	(via
		(at 212.51545 -4.152392)
		(size 0.508)
		(drill 0.254)
		(layers "F.Cu" "B.Cu")
		(net "DELTA_L_GND_1")
	)
	(via
		(at 211.689188 -1.608836)
		(size 0.508)
		(drill 0.254)
		(layers "F.Cu" "B.Cu")
		(net "DELTA_L_GND_1")
	)
	(via
		(at 314.183014 -6.794754)
		(size 0.508)
		(drill 0.254)
		(layers "F.Cu" "B.Cu")
		(net "DELTA_L_GND_1")
	)
	(via
		(at 317.064644 3.904996)
		(size 0.508)
		(drill 0.254)
		(layers "F.Cu" "B.Cu")
		(net "DELTA_L_GND_1")
	)
	(via
		(at 367.070894 4.154424)
		(size 0.508)
		(drill 0.254)
		(layers "F.Cu" "B.Cu")
		(net "DELTA_L_GND_1")
	)
	(via
		(at 365.476282 3.8227)
		(size 0.508)
		(drill 0.254)
		(layers "F.Cu" "B.Cu")
		(net "DELTA_L_GND_1")
	)
	(via
		(at 186.688984 7.76478)
		(size 0.508)
		(drill 0.254)
		(layers "F.Cu" "B.Cu")
		(net "DELTA_L_GND_1")
	)
	(via
		(at 441.611512 10.391394)
		(size 0.508)
		(drill 0.254)
		(layers "F.Cu" "B.Cu")
		(net "DELTA_L_GND_1")
	)
	(via
		(at 301.339758 3.474212)
		(size 0.508)
		(drill 0.254)
		(layers "F.Cu" "B.Cu")
		(net "DELTA_L_GND_1")
	)
	(via
		(at 367.090198 -6.778752)
		(size 0.508)
		(drill 0.254)
		(layers "F.Cu" "B.Cu")
		(net "DELTA_L_GND_1")
	)
	(via
		(at 314.180728 -0.013208)
		(size 0.508)
		(drill 0.254)
		(layers "F.Cu" "B.Cu")
		(net "DELTA_L_GND_1")
	)
	(via
		(at 214.570564 -1.359408)
		(size 0.508)
		(drill 0.254)
		(layers "F.Cu" "B.Cu")
		(net "DELTA_L_GND_1")
	)
	(via
		(at 211.689188 6.011164)
		(size 0.508)
		(drill 0.254)
		(layers "F.Cu" "B.Cu")
		(net "DELTA_L_GND_1")
	)
	(via
		(at 212.51545 0.927608)
		(size 0.508)
		(drill 0.254)
		(layers "F.Cu" "B.Cu")
		(net "DELTA_L_GND_1")
	)
	(via
		(at 186.692794 2.460498)
		(size 0.508)
		(drill 0.254)
		(layers "F.Cu" "B.Cu")
		(net "DELTA_L_GND_1")
	)
	(via
		(at 186.700414 5.84835)
		(size 0.508)
		(drill 0.254)
		(layers "F.Cu" "B.Cu")
		(net "DELTA_L_GND_1")
	)
	(via
		(at 214.570564 -3.899408)
		(size 0.508)
		(drill 0.254)
		(layers "F.Cu" "B.Cu")
		(net "DELTA_L_GND_1")
	)
	(via
		(at 97.792032 2.456942)
		(size 0.508)
		(drill 0.254)
		(layers "F.Cu" "B.Cu")
		(net "DELTA_L_GND_1")
	)
	(via
		(at 299.745146 1.265936)
		(size 0.508)
		(drill 0.254)
		(layers "F.Cu" "B.Cu")
		(net "DELTA_L_GND_1")
	)
	(via
		(at 300.517306 6.649466)
		(size 0.508)
		(drill 0.254)
		(layers "F.Cu" "B.Cu")
		(net "DELTA_L_GND_1")
	)
	(via
		(at 315.00572 -0.973582)
		(size 0.508)
		(drill 0.254)
		(layers "F.Cu" "B.Cu")
		(net "DELTA_L_GND_1")
	)
	(via
		(at 211.689188 3.471164)
		(size 0.508)
		(drill 0.254)
		(layers "F.Cu" "B.Cu")
		(net "DELTA_L_GND_1")
	)
	(via
		(at 365.476282 1.2827)
		(size 0.508)
		(drill 0.254)
		(layers "F.Cu" "B.Cu")
		(net "DELTA_L_GND_1")
	)
	(via
		(at 301.339758 -4.145788)
		(size 0.508)
		(drill 0.254)
		(layers "F.Cu" "B.Cu")
		(net "DELTA_L_GND_1")
	)
	(via
		(at 367.070894 1.614424)
		(size 0.508)
		(drill 0.254)
		(layers "F.Cu" "B.Cu")
		(net "DELTA_L_GND_1")
	)
	(via
		(at 440.78525 10.39495)
		(size 0.508)
		(drill 0.254)
		(layers "F.Cu" "B.Cu")
		(net "DELTA_L_GND_1")
	)
	(via
		(at 388.628382 5.725922)
		(size 0.508)
		(drill 0.254)
		(layers "F.Cu" "B.Cu")
		(net "DELTA_L_GND_1")
	)
	(via
		(at 213.2838 1.262888)
		(size 0.508)
		(drill 0.254)
		(layers "F.Cu" "B.Cu")
		(net "DELTA_L_GND_1")
	)
	(via
		(at 211.685124 8.669528)
		(size 0.508)
		(drill 0.254)
		(layers "F.Cu" "B.Cu")
		(net "DELTA_L_GND_1")
	)
	(via
		(at 212.51164 -0.973582)
		(size 0.508)
		(drill 0.254)
		(layers "F.Cu" "B.Cu")
		(net "DELTA_L_GND_1")
	)
	(via
		(at 298.439332 -6.255004)
		(size 0.508)
		(drill 0.254)
		(layers "F.Cu" "B.Cu")
		(net "DELTA_L_GND_1")
	)
	(via
		(at 315.005466 -6.1595)
		(size 0.508)
		(drill 0.254)
		(layers "F.Cu" "B.Cu")
		(net "DELTA_L_GND_1")
	)
	(via
		(at 388.632192 9.752584)
		(size 0.508)
		(drill 0.254)
		(layers "F.Cu" "B.Cu")
		(net "DELTA_L_GND_1")
	)
	(via
		(at 367.101628 -4.862322)
		(size 0.508)
		(drill 0.254)
		(layers "F.Cu" "B.Cu")
		(net "DELTA_L_GND_1")
	)
	(via
		(at 440.0169 4.780026)
		(size 0.508)
		(drill 0.254)
		(layers "F.Cu" "B.Cu")
		(net "DELTA_L_GND_1")
	)
	(via
		(at 389.458708 7.729474)
		(size 0.508)
		(drill 0.254)
		(layers "F.Cu" "B.Cu")
		(net "DELTA_L_GND_1")
	)
	(via
		(at 367.097818 -5.501132)
		(size 0.508)
		(drill 0.254)
		(layers "F.Cu" "B.Cu")
		(net "DELTA_L_GND_1")
	)
	(via
		(at 298.439332 1.364996)
		(size 0.508)
		(drill 0.254)
		(layers "F.Cu" "B.Cu")
		(net "DELTA_L_GND_1")
	)
	(via
		(at 212.515196 5.066792)
		(size 0.508)
		(drill 0.254)
		(layers "F.Cu" "B.Cu")
		(net "DELTA_L_GND_1")
	)
	(via
		(at 390.230868 7.425944)
		(size 0.508)
		(drill 0.254)
		(layers "F.Cu" "B.Cu")
		(net "DELTA_L_GND_1")
	)
	(via
		(at 211.685378 1.569974)
		(size 0.508)
		(drill 0.254)
		(layers "F.Cu" "B.Cu")
		(net "DELTA_L_GND_1")
	)
	(via
		(at 366.267746 -6.143498)
		(size 0.508)
		(drill 0.254)
		(layers "F.Cu" "B.Cu")
		(net "DELTA_L_GND_1")
	)
	(via
		(at 441.619132 9.113774)
		(size 0.508)
		(drill 0.254)
		(layers "F.Cu" "B.Cu")
		(net "DELTA_L_GND_1")
	)
	(via
		(at 298.439332 -3.899408)
		(size 0.508)
		(drill 0.254)
		(layers "F.Cu" "B.Cu")
		(net "DELTA_L_GND_1")
	)
	(via
		(at 317.064644 -3.715004)
		(size 0.508)
		(drill 0.254)
		(layers "F.Cu" "B.Cu")
		(net "DELTA_L_GND_1")
	)
	(via
		(at 301.351442 -4.862322)
		(size 0.508)
		(drill 0.254)
		(layers "F.Cu" "B.Cu")
		(net "DELTA_L_GND_1")
	)
	(via
		(at 211.689188 0.931164)
		(size 0.508)
		(drill 0.254)
		(layers "F.Cu" "B.Cu")
		(net "DELTA_L_GND_1")
	)
	(via
		(at 367.096294 8.702802)
		(size 0.508)
		(drill 0.254)
		(layers "F.Cu" "B.Cu")
		(net "DELTA_L_GND_1")
	)
	(via
		(at 314.166758 6.661658)
		(size 0.508)
		(drill 0.254)
		(layers "F.Cu" "B.Cu")
		(net "DELTA_L_GND_1")
	)
	(via
		(at 98.564192 2.153412)
		(size 0.508)
		(drill 0.254)
		(layers "F.Cu" "B.Cu")
		(net "DELTA_L_GND_1")
	)
	(via
		(at 367.074704 3.515614)
		(size 0.508)
		(drill 0.254)
		(layers "F.Cu" "B.Cu")
		(net "DELTA_L_GND_1")
	)
	(via
		(at 315.00953 0.927608)
		(size 0.508)
		(drill 0.254)
		(layers "F.Cu" "B.Cu")
		(net "DELTA_L_GND_1")
	)
	(via
		(at 212.515196 -6.79831)
		(size 0.508)
		(drill 0.254)
		(layers "F.Cu" "B.Cu")
		(net "DELTA_L_GND_1")
	)
	(via
		(at 301.343568 4.113022)
		(size 0.508)
		(drill 0.254)
		(layers "F.Cu" "B.Cu")
		(net "DELTA_L_GND_1")
	)
	(via
		(at 315.77788 3.802888)
		(size 0.508)
		(drill 0.254)
		(layers "F.Cu" "B.Cu")
		(net "DELTA_L_GND_1")
	)
	(via
		(at 301.346108 8.702802)
		(size 0.508)
		(drill 0.254)
		(layers "F.Cu" "B.Cu")
		(net "DELTA_L_GND_1")
	)
	(via
		(at 298.439332 -1.359408)
		(size 0.508)
		(drill 0.254)
		(layers "F.Cu" "B.Cu")
		(net "DELTA_L_GND_1")
	)
	(via
		(at 367.094008 -6.139942)
		(size 0.508)
		(drill 0.254)
		(layers "F.Cu" "B.Cu")
		(net "DELTA_L_GND_1")
	)
	(via
		(at 440.78525 4.444746)
		(size 0.508)
		(drill 0.254)
		(layers "F.Cu" "B.Cu")
		(net "DELTA_L_GND_1")
	)
	(via
		(at 367.073434 -2.553208)
		(size 0.508)
		(drill 0.254)
		(layers "F.Cu" "B.Cu")
		(net "DELTA_L_GND_1")
	)
	(via
		(at 367.070894 -0.925576)
		(size 0.508)
		(drill 0.254)
		(layers "F.Cu" "B.Cu")
		(net "DELTA_L_GND_1")
	)
	(via
		(at 211.685378 -3.510026)
		(size 0.508)
		(drill 0.254)
		(layers "F.Cu" "B.Cu")
		(net "DELTA_L_GND_1")
	)
	(via
		(at 301.323248 0.018796)
		(size 0.508)
		(drill 0.254)
		(layers "F.Cu" "B.Cu")
		(net "DELTA_L_GND_1")
	)
	(via
		(at 389.462264 10.39495)
		(size 0.508)
		(drill 0.254)
		(layers "F.Cu" "B.Cu")
		(net "DELTA_L_GND_1")
	)
	(via
		(at 97.792286 5.10286)
		(size 0.508)
		(drill 0.254)
		(layers "F.Cu" "B.Cu")
		(net "DELTA_L_GND_1")
	)
	(via
		(at 366.244886 -0.013208)
		(size 0.508)
		(drill 0.254)
		(layers "F.Cu" "B.Cu")
		(net "DELTA_L_GND_1")
	)
	(via
		(at 96.96958 7.76478)
		(size 0.508)
		(drill 0.254)
		(layers "F.Cu" "B.Cu")
		(net "DELTA_L_GND_1")
	)
	(via
		(at 185.862468 4.46405)
		(size 0.508)
		(drill 0.254)
		(layers "F.Cu" "B.Cu")
		(net "DELTA_L_GND_1")
	)
	(via
		(at 97.792032 7.129526)
		(size 0.508)
		(drill 0.254)
		(layers "F.Cu" "B.Cu")
		(net "DELTA_L_GND_1")
	)
	(via
		(at 214.570564 3.904996)
		(size 0.508)
		(drill 0.254)
		(layers "F.Cu" "B.Cu")
		(net "DELTA_L_GND_1")
	)
	(via
		(at 301.343822 -6.139942)
		(size 0.508)
		(drill 0.254)
		(layers "F.Cu" "B.Cu")
		(net "DELTA_L_GND_1")
	)
	(via
		(at 366.244886 5.066792)
		(size 0.508)
		(drill 0.254)
		(layers "F.Cu" "B.Cu")
		(net "DELTA_L_GND_1")
	)
	(via
		(at 388.636256 7.09422)
		(size 0.508)
		(drill 0.254)
		(layers "F.Cu" "B.Cu")
		(net "DELTA_L_GND_1")
	)
	(via
		(at 212.51545 -1.612392)
		(size 0.508)
		(drill 0.254)
		(layers "F.Cu" "B.Cu")
		(net "DELTA_L_GND_1")
	)
	(via
		(at 301.340012 -6.778752)
		(size 0.508)
		(drill 0.254)
		(layers "F.Cu" "B.Cu")
		(net "DELTA_L_GND_1")
	)
	(via
		(at 211.686648 5.066792)
		(size 0.508)
		(drill 0.254)
		(layers "F.Cu" "B.Cu")
		(net "DELTA_L_GND_1")
	)
	(via
		(at 314.179458 1.569974)
		(size 0.508)
		(drill 0.254)
		(layers "F.Cu" "B.Cu")
		(net "DELTA_L_GND_1")
	)
	(via
		(at 367.104168 7.347458)
		(size 0.508)
		(drill 0.254)
		(layers "F.Cu" "B.Cu")
		(net "DELTA_L_GND_1")
	)
	(via
		(at 299.745146 3.805936)
		(size 0.508)
		(drill 0.254)
		(layers "F.Cu" "B.Cu")
		(net "DELTA_L_GND_1")
	)
	(via
		(at 315.00953 -4.152392)
		(size 0.508)
		(drill 0.254)
		(layers "F.Cu" "B.Cu")
		(net "DELTA_L_GND_1")
	)
	(via
		(at 364.189518 -1.359408)
		(size 0.508)
		(drill 0.254)
		(layers "F.Cu" "B.Cu")
		(net "DELTA_L_GND_1")
	)
	(via
		(at 366.248442 3.51917)
		(size 0.508)
		(drill 0.254)
		(layers "F.Cu" "B.Cu")
		(net "DELTA_L_GND_1")
	)
	(via
		(at 317.064644 6.444996)
		(size 0.508)
		(drill 0.254)
		(layers "F.Cu" "B.Cu")
		(net "DELTA_L_GND_1")
	)
	(via
		(at 388.624572 6.364732)
		(size 0.508)
		(drill 0.254)
		(layers "F.Cu" "B.Cu")
		(net "DELTA_L_GND_1")
	)
	(via
		(at 301.339758 -1.605788)
		(size 0.508)
		(drill 0.254)
		(layers "F.Cu" "B.Cu")
		(net "DELTA_L_GND_1")
	)
	(via
		(at 315.77788 -1.277112)
		(size 0.508)
		(drill 0.254)
		(layers "F.Cu" "B.Cu")
		(net "DELTA_L_GND_1")
	)
	(via
		(at 301.339758 6.014212)
		(size 0.508)
		(drill 0.254)
		(layers "F.Cu" "B.Cu")
		(net "DELTA_L_GND_1")
	)
	(via
		(at 438.686194 7.327646)
		(size 0.508)
		(drill 0.254)
		(layers "F.Cu" "B.Cu")
		(net "DELTA_L_GND_1")
	)
	(via
		(at 211.685378 4.109974)
		(size 0.508)
		(drill 0.254)
		(layers "F.Cu" "B.Cu")
		(net "DELTA_L_GND_1")
	)
	(via
		(at 185.094118 4.79933)
		(size 0.508)
		(drill 0.254)
		(layers "F.Cu" "B.Cu")
		(net "DELTA_L_GND_1")
	)
	(via
		(at 301.349918 9.341612)
		(size 0.508)
		(drill 0.254)
		(layers "F.Cu" "B.Cu")
		(net "DELTA_L_GND_1")
	)
	(via
		(at 390.230614 4.780026)
		(size 0.508)
		(drill 0.254)
		(layers "F.Cu" "B.Cu")
		(net "DELTA_L_GND_1")
	)
	(via
		(at 366.248442 6.05917)
		(size 0.508)
		(drill 0.254)
		(layers "F.Cu" "B.Cu")
		(net "DELTA_L_GND_1")
	)
	(via
		(at 391.56132 4.97205)
		(size 0.508)
		(drill 0.254)
		(layers "F.Cu" "B.Cu")
		(net "DELTA_L_GND_1")
	)
	(via
		(at 315.00572 -3.513582)
		(size 0.508)
		(drill 0.254)
		(layers "F.Cu" "B.Cu")
		(net "DELTA_L_GND_1")
	)
	(via
		(at 388.632192 5.087112)
		(size 0.508)
		(drill 0.254)
		(layers "F.Cu" "B.Cu")
		(net "DELTA_L_GND_1")
	)
	(segment
		(start 351.940368 -7.053326)
		(end 351.790508 -7.158482)
		(width 0.12954)
		(layer "F.Cu")
		(net "DELTA_L_85_5INCH_TOP_DP")
	)
	(segment
		(start 339.729318 -7.158736)
		(end 338.3534 -6.91515)
		(width 0.12954)
		(layer "F.Cu")
		(net "DELTA_L_85_5INCH_TOP_DP")
	)
	(segment
		(start 324.50532 -3.047238)
		(end 323.798692 -7.04723)
		(width 0.12954)
		(layer "F.Cu")
		(net "DELTA_L_85_5INCH_TOP_DP")
	)
	(segment
		(start 358.943656 -3.406648)
		(end 358.685846 -3.038094)
		(width 0.12954)
		(layer "F.Cu")
		(net "DELTA_L_85_5INCH_TOP_DP")
	)
	(segment
		(start 346.880434 -3.41884)
		(end 346.622624 -3.050032)
		(width 0.12954)
		(layer "F.Cu")
		(net "DELTA_L_85_5INCH_TOP_DP")
	)
	(segment
		(start 332.546706 -3.04419)
		(end 331.84084 -7.03961)
		(width 0.12954)
		(layer "F.Cu")
		(net "DELTA_L_85_5INCH_TOP_DP")
	)
	(segment
		(start 354.435918 -6.910324)
		(end 354.330762 -6.760464)
		(width 0.12954)
		(layer "F.Cu")
		(net "DELTA_L_85_5INCH_TOP_DP")
	)
	(segment
		(start 326.18934 -6.751828)
		(end 326.773032 -3.448304)
		(width 0.12954)
		(layer "F.Cu")
		(net "DELTA_L_85_5INCH_TOP_DP")
	)
	(segment
		(start 320.486532 -3.039364)
		(end 320.237104 -4.450842)
		(width 0.12954)
		(layer "F.Cu")
		(net "DELTA_L_85_5INCH_TOP_DP")
	)
	(segment
		(start 320.854832 -2.781554)
		(end 320.486532 -3.039364)
		(width 0.12954)
		(layer "F.Cu")
		(net "DELTA_L_85_5INCH_TOP_DP")
	)
	(segment
		(start 346.394786 -6.912102)
		(end 346.28963 -6.761988)
		(width 0.12954)
		(layer "F.Cu")
		(net "DELTA_L_85_5INCH_TOP_DP")
	)
	(segment
		(start 334.333088 -6.914896)
		(end 334.227932 -6.764782)
		(width 0.12954)
		(layer "F.Cu")
		(net "DELTA_L_85_5INCH_TOP_DP")
	)
	(segment
		(start 336.562192 -3.07213)
		(end 335.858612 -7.053326)
		(width 0.12954)
		(layer "F.Cu")
		(net "DELTA_L_85_5INCH_TOP_DP")
	)
	(segment
		(start 358.46512 -6.94817)
		(end 358.347518 -6.780784)
		(width 0.12954)
		(layer "F.Cu")
		(net "DELTA_L_85_5INCH_TOP_DP")
	)
	(segment
		(start 322.496434 -3.071622)
		(end 320.854832 -2.781554)
		(width 0.12954)
		(layer "F.Cu")
		(net "DELTA_L_85_5INCH_TOP_DP")
	)
	(segment
		(start 365.463074 -4.82727)
		(end 365.302546 -4.82727)
		(width 0.12954)
		(layer "F.Cu")
		(net "DELTA_L_85_5INCH_TOP_DP")
	)
	(segment
		(start 343.751916 -7.145782)
		(end 342.375998 -6.902196)
		(width 0.12954)
		(layer "F.Cu")
		(net "DELTA_L_85_5INCH_TOP_DP")
	)
	(segment
		(start 336.930492 -2.81432)
		(end 336.562192 -3.07213)
		(width 0.12954)
		(layer "F.Cu")
		(net "DELTA_L_85_5INCH_TOP_DP")
	)
	(segment
		(start 335.709006 -7.158482)
		(end 334.333088 -6.914896)
		(width 0.12954)
		(layer "F.Cu")
		(net "DELTA_L_85_5INCH_TOP_DP")
	)
	(segment
		(start 342.604598 -3.0353)
		(end 340.96325 -2.745232)
		(width 0.12954)
		(layer "F.Cu")
		(net "DELTA_L_85_5INCH_TOP_DP")
	)
	(segment
		(start 326.294496 -6.902196)
		(end 326.18934 -6.751828)
		(width 0.12954)
		(layer "F.Cu")
		(net "DELTA_L_85_5INCH_TOP_DP")
	)
	(segment
		(start 334.814418 -3.445256)
		(end 334.556608 -3.076448)
		(width 0.12954)
		(layer "F.Cu")
		(net "DELTA_L_85_5INCH_TOP_DP")
	)
	(segment
		(start 328.905108 -2.727706)
		(end 328.536554 -2.985262)
		(width 0.12954)
		(layer "F.Cu")
		(net "DELTA_L_85_5INCH_TOP_DP")
	)
	(segment
		(start 356.675944 -3.005836)
		(end 355.961696 -7.048754)
		(width 0.12954)
		(layer "F.Cu")
		(net "DELTA_L_85_5INCH_TOP_DP")
	)
	(segment
		(start 358.347518 -6.780784)
		(end 358.943656 -3.406648)
		(width 0.12954)
		(layer "F.Cu")
		(net "DELTA_L_85_5INCH_TOP_DP")
	)
	(segment
		(start 347.92031 -7.050532)
		(end 347.770704 -7.155688)
		(width 0.12954)
		(layer "F.Cu")
		(net "DELTA_L_85_5INCH_TOP_DP")
	)
	(segment
		(start 350.309434 -6.765036)
		(end 350.89465 -3.452876)
		(width 0.12954)
		(layer "F.Cu")
		(net "DELTA_L_85_5INCH_TOP_DP")
	)
	(segment
		(start 327.82002 -7.040372)
		(end 327.670414 -7.145528)
		(width 0.12954)
		(layer "F.Cu")
		(net "DELTA_L_85_5INCH_TOP_DP")
	)
	(segment
		(start 331.69098 -7.144766)
		(end 330.315062 -6.90118)
		(width 0.12954)
		(layer "F.Cu")
		(net "DELTA_L_85_5INCH_TOP_DP")
	)
	(segment
		(start 354.330762 -6.760464)
		(end 354.923344 -3.406648)
		(width 0.12954)
		(layer "F.Cu")
		(net "DELTA_L_85_5INCH_TOP_DP")
	)
	(segment
		(start 344.981022 -2.759964)
		(end 344.612722 -3.017774)
		(width 0.12954)
		(layer "F.Cu")
		(net "DELTA_L_85_5INCH_TOP_DP")
	)
	(segment
		(start 365.2139 -4.915916)
		(end 361.04068 -4.915916)
		(width 0.12954)
		(layer "F.Cu")
		(net "DELTA_L_85_5INCH_TOP_DP")
	)
	(segment
		(start 365.302546 -4.82727)
		(end 365.2139 -4.915916)
		(width 0.12954)
		(layer "F.Cu")
		(net "DELTA_L_85_5INCH_TOP_DP")
	)
	(segment
		(start 350.636586 -3.084576)
		(end 348.995238 -2.794508)
		(width 0.12954)
		(layer "F.Cu")
		(net "DELTA_L_85_5INCH_TOP_DP")
	)
	(segment
		(start 342.375998 -6.902196)
		(end 342.270842 -6.75259)
		(width 0.12954)
		(layer "F.Cu")
		(net "DELTA_L_85_5INCH_TOP_DP")
	)
	(segment
		(start 327.670414 -7.145528)
		(end 326.294496 -6.902196)
		(width 0.12954)
		(layer "F.Cu")
		(net "DELTA_L_85_5INCH_TOP_DP")
	)
	(segment
		(start 358.685846 -3.038094)
		(end 357.044244 -2.748026)
		(width 0.12954)
		(layer "F.Cu")
		(net "DELTA_L_85_5INCH_TOP_DP")
	)
	(segment
		(start 315.957712 -4.82727)
		(end 315.791088 -4.82727)
		(width 0.12954)
		(layer "F.Cu")
		(net "DELTA_L_85_5INCH_TOP_DP")
	)
	(segment
		(start 323.798692 -7.04723)
		(end 323.648832 -7.152386)
		(width 0.12954)
		(layer "F.Cu")
		(net "DELTA_L_85_5INCH_TOP_DP")
	)
	(segment
		(start 359.811066 -7.186676)
		(end 358.46512 -6.94817)
		(width 0.12954)
		(layer "F.Cu")
		(net "DELTA_L_85_5INCH_TOP_DP")
	)
	(segment
		(start 332.915006 -2.78638)
		(end 332.546706 -3.04419)
		(width 0.12954)
		(layer "F.Cu")
		(net "DELTA_L_85_5INCH_TOP_DP")
	)
	(segment
		(start 316.046358 -4.915916)
		(end 315.957712 -4.82727)
		(width 0.12954)
		(layer "F.Cu")
		(net "DELTA_L_85_5INCH_TOP_DP")
	)
	(segment
		(start 334.227932 -6.764782)
		(end 334.814418 -3.445256)
		(width 0.12954)
		(layer "F.Cu")
		(net "DELTA_L_85_5INCH_TOP_DP")
	)
	(segment
		(start 324.87362 -2.789428)
		(end 324.50532 -3.047238)
		(width 0.12954)
		(layer "F.Cu")
		(net "DELTA_L_85_5INCH_TOP_DP")
	)
	(segment
		(start 344.612722 -3.017774)
		(end 343.90203 -7.040626)
		(width 0.12954)
		(layer "F.Cu")
		(net "DELTA_L_85_5INCH_TOP_DP")
	)
	(segment
		(start 340.594696 -3.002788)
		(end 339.878924 -7.05358)
		(width 0.12954)
		(layer "F.Cu")
		(net "DELTA_L_85_5INCH_TOP_DP")
	)
	(segment
		(start 342.862662 -3.4036)
		(end 342.604598 -3.0353)
		(width 0.12954)
		(layer "F.Cu")
		(net "DELTA_L_85_5INCH_TOP_DP")
	)
	(segment
		(start 343.90203 -7.040626)
		(end 343.751916 -7.145782)
		(width 0.12954)
		(layer "F.Cu")
		(net "DELTA_L_85_5INCH_TOP_DP")
	)
	(segment
		(start 334.556608 -3.076448)
		(end 332.915006 -2.78638)
		(width 0.12954)
		(layer "F.Cu")
		(net "DELTA_L_85_5INCH_TOP_DP")
	)
	(segment
		(start 342.270842 -6.75259)
		(end 342.862662 -3.4036)
		(width 0.12954)
		(layer "F.Cu")
		(net "DELTA_L_85_5INCH_TOP_DP")
	)
	(segment
		(start 346.622624 -3.050032)
		(end 344.981022 -2.759964)
		(width 0.12954)
		(layer "F.Cu")
		(net "DELTA_L_85_5INCH_TOP_DP")
	)
	(segment
		(start 352.655632 -3.005582)
		(end 351.940368 -7.053326)
		(width 0.12954)
		(layer "F.Cu")
		(net "DELTA_L_85_5INCH_TOP_DP")
	)
	(segment
		(start 322.167758 -6.75894)
		(end 322.754244 -3.440176)
		(width 0.12954)
		(layer "F.Cu")
		(net "DELTA_L_85_5INCH_TOP_DP")
	)
	(segment
		(start 335.858612 -7.053326)
		(end 335.709006 -7.158482)
		(width 0.12954)
		(layer "F.Cu")
		(net "DELTA_L_85_5INCH_TOP_DP")
	)
	(segment
		(start 348.995238 -2.794508)
		(end 348.626684 -3.052064)
		(width 0.12954)
		(layer "F.Cu")
		(net "DELTA_L_85_5INCH_TOP_DP")
	)
	(segment
		(start 361.04068 -4.915916)
		(end 360.262424 -5.460492)
		(width 0.12954)
		(layer "F.Cu")
		(net "DELTA_L_85_5INCH_TOP_DP")
	)
	(segment
		(start 359.978452 -7.069074)
		(end 359.811066 -7.186676)
		(width 0.12954)
		(layer "F.Cu")
		(net "DELTA_L_85_5INCH_TOP_DP")
	)
	(segment
		(start 323.648832 -7.152386)
		(end 322.272914 -6.9088)
		(width 0.12954)
		(layer "F.Cu")
		(net "DELTA_L_85_5INCH_TOP_DP")
	)
	(segment
		(start 339.878924 -7.05358)
		(end 339.729318 -7.158736)
		(width 0.12954)
		(layer "F.Cu")
		(net "DELTA_L_85_5INCH_TOP_DP")
	)
	(segment
		(start 357.044244 -2.748026)
		(end 356.675944 -3.005836)
		(width 0.12954)
		(layer "F.Cu")
		(net "DELTA_L_85_5INCH_TOP_DP")
	)
	(segment
		(start 338.829904 -3.473196)
		(end 338.572094 -3.104388)
		(width 0.12954)
		(layer "F.Cu")
		(net "DELTA_L_85_5INCH_TOP_DP")
	)
	(segment
		(start 346.28963 -6.761988)
		(end 346.880434 -3.41884)
		(width 0.12954)
		(layer "F.Cu")
		(net "DELTA_L_85_5INCH_TOP_DP")
	)
	(segment
		(start 355.811836 -7.15391)
		(end 354.435918 -6.910324)
		(width 0.12954)
		(layer "F.Cu")
		(net "DELTA_L_85_5INCH_TOP_DP")
	)
	(segment
		(start 355.961696 -7.048754)
		(end 355.811836 -7.15391)
		(width 0.12954)
		(layer "F.Cu")
		(net "DELTA_L_85_5INCH_TOP_DP")
	)
	(segment
		(start 326.773032 -3.448304)
		(end 326.515222 -3.079496)
		(width 0.12954)
		(layer "F.Cu")
		(net "DELTA_L_85_5INCH_TOP_DP")
	)
	(segment
		(start 354.665534 -3.03784)
		(end 353.023932 -2.747772)
		(width 0.12954)
		(layer "F.Cu")
		(net "DELTA_L_85_5INCH_TOP_DP")
	)
	(segment
		(start 350.41459 -6.914896)
		(end 350.309434 -6.765036)
		(width 0.12954)
		(layer "F.Cu")
		(net "DELTA_L_85_5INCH_TOP_DP")
	)
	(segment
		(start 319.57264 -4.915916)
		(end 316.046358 -4.915916)
		(width 0.12954)
		(layer "F.Cu")
		(net "DELTA_L_85_5INCH_TOP_DP")
	)
	(segment
		(start 331.84084 -7.03961)
		(end 331.69098 -7.144766)
		(width 0.12954)
		(layer "F.Cu")
		(net "DELTA_L_85_5INCH_TOP_DP")
	)
	(segment
		(start 338.572094 -3.104388)
		(end 336.930492 -2.81432)
		(width 0.12954)
		(layer "F.Cu")
		(net "DELTA_L_85_5INCH_TOP_DP")
	)
	(segment
		(start 351.790508 -7.158482)
		(end 350.41459 -6.914896)
		(width 0.12954)
		(layer "F.Cu")
		(net "DELTA_L_85_5INCH_TOP_DP")
	)
	(segment
		(start 322.754244 -3.440176)
		(end 322.496434 -3.071622)
		(width 0.12954)
		(layer "F.Cu")
		(net "DELTA_L_85_5INCH_TOP_DP")
	)
	(segment
		(start 347.770704 -7.155688)
		(end 346.394786 -6.912102)
		(width 0.12954)
		(layer "F.Cu")
		(net "DELTA_L_85_5INCH_TOP_DP")
	)
	(segment
		(start 348.626684 -3.052064)
		(end 347.92031 -7.050532)
		(width 0.12954)
		(layer "F.Cu")
		(net "DELTA_L_85_5INCH_TOP_DP")
	)
	(segment
		(start 330.209906 -6.75132)
		(end 330.80452 -3.386074)
		(width 0.12954)
		(layer "F.Cu")
		(net "DELTA_L_85_5INCH_TOP_DP")
	)
	(segment
		(start 330.546456 -3.017774)
		(end 328.905108 -2.727706)
		(width 0.12954)
		(layer "F.Cu")
		(net "DELTA_L_85_5INCH_TOP_DP")
	)
	(segment
		(start 338.248244 -6.76529)
		(end 338.829904 -3.473196)
		(width 0.12954)
		(layer "F.Cu")
		(net "DELTA_L_85_5INCH_TOP_DP")
	)
	(segment
		(start 340.96325 -2.745232)
		(end 340.594696 -3.002788)
		(width 0.12954)
		(layer "F.Cu")
		(net "DELTA_L_85_5INCH_TOP_DP")
	)
	(segment
		(start 360.262424 -5.460492)
		(end 359.978452 -7.069074)
		(width 0.12954)
		(layer "F.Cu")
		(net "DELTA_L_85_5INCH_TOP_DP")
	)
	(segment
		(start 326.515222 -3.079496)
		(end 324.87362 -2.789428)
		(width 0.12954)
		(layer "F.Cu")
		(net "DELTA_L_85_5INCH_TOP_DP")
	)
	(segment
		(start 354.923344 -3.406648)
		(end 354.665534 -3.03784)
		(width 0.12954)
		(layer "F.Cu")
		(net "DELTA_L_85_5INCH_TOP_DP")
	)
	(segment
		(start 328.536554 -2.985262)
		(end 327.82002 -7.040372)
		(width 0.12954)
		(layer "F.Cu")
		(net "DELTA_L_85_5INCH_TOP_DP")
	)
	(segment
		(start 330.315062 -6.90118)
		(end 330.209906 -6.75132)
		(width 0.12954)
		(layer "F.Cu")
		(net "DELTA_L_85_5INCH_TOP_DP")
	)
	(segment
		(start 338.3534 -6.91515)
		(end 338.248244 -6.76529)
		(width 0.12954)
		(layer "F.Cu")
		(net "DELTA_L_85_5INCH_TOP_DP")
	)
	(segment
		(start 353.023932 -2.747772)
		(end 352.655632 -3.005582)
		(width 0.12954)
		(layer "F.Cu")
		(net "DELTA_L_85_5INCH_TOP_DP")
	)
	(segment
		(start 330.80452 -3.386074)
		(end 330.546456 -3.017774)
		(width 0.12954)
		(layer "F.Cu")
		(net "DELTA_L_85_5INCH_TOP_DP")
	)
	(segment
		(start 350.89465 -3.452876)
		(end 350.636586 -3.084576)
		(width 0.12954)
		(layer "F.Cu")
		(net "DELTA_L_85_5INCH_TOP_DP")
	)
	(segment
		(start 322.272914 -6.9088)
		(end 322.167758 -6.75894)
		(width 0.12954)
		(layer "F.Cu")
		(net "DELTA_L_85_5INCH_TOP_DP")
	)
	(segment
		(start 320.237104 -4.450842)
		(end 319.57264 -4.915916)
		(width 0.12954)
		(layer "F.Cu")
		(net "DELTA_L_85_5INCH_TOP_DP")
	)
	(segment
		(start 353.98964 -6.836156)
		(end 354.582222 -3.482086)
		(width 0.12954)
		(layer "F.Cu")
		(net "DELTA_L_85_5INCH_TOP_DN")
	)
	(segment
		(start 350.226884 -7.209536)
		(end 349.968312 -6.840728)
		(width 0.12954)
		(layer "F.Cu")
		(net "DELTA_L_85_5INCH_TOP_DN")
	)
	(segment
		(start 345.948508 -6.83768)
		(end 346.539312 -3.494278)
		(width 0.12954)
		(layer "F.Cu")
		(net "DELTA_L_85_5INCH_TOP_DN")
	)
	(segment
		(start 332.13548 -7.227316)
		(end 331.766672 -7.485888)
		(width 0.12954)
		(layer "F.Cu")
		(net "DELTA_L_85_5INCH_TOP_DN")
	)
	(segment
		(start 336.153252 -7.240778)
		(end 335.784952 -7.499604)
		(width 0.12954)
		(layer "F.Cu")
		(net "DELTA_L_85_5INCH_TOP_DN")
	)
	(segment
		(start 337.907122 -6.840982)
		(end 338.488782 -3.548634)
		(width 0.12954)
		(layer "F.Cu")
		(net "DELTA_L_85_5INCH_TOP_DN")
	)
	(segment
		(start 333.88681 -6.840474)
		(end 334.473296 -3.520694)
		(width 0.12954)
		(layer "F.Cu")
		(net "DELTA_L_85_5INCH_TOP_DN")
	)
	(segment
		(start 338.488782 -3.548634)
		(end 338.384134 -3.399028)
		(width 0.12954)
		(layer "F.Cu")
		(net "DELTA_L_85_5INCH_TOP_DN")
	)
	(segment
		(start 352.950272 -3.193288)
		(end 352.235008 -7.241032)
		(width 0.12954)
		(layer "F.Cu")
		(net "DELTA_L_85_5INCH_TOP_DN")
	)
	(segment
		(start 322.413122 -3.515614)
		(end 322.308474 -3.366262)
		(width 0.12954)
		(layer "F.Cu")
		(net "DELTA_L_85_5INCH_TOP_DN")
	)
	(segment
		(start 360.273092 -7.256526)
		(end 359.886758 -7.527798)
		(width 0.12954)
		(layer "F.Cu")
		(net "DELTA_L_85_5INCH_TOP_DN")
	)
	(segment
		(start 334.473296 -3.520694)
		(end 334.368648 -3.371088)
		(width 0.12954)
		(layer "F.Cu")
		(net "DELTA_L_85_5INCH_TOP_DN")
	)
	(segment
		(start 355.887528 -7.495032)
		(end 354.248212 -7.204964)
		(width 0.12954)
		(layer "F.Cu")
		(net "DELTA_L_85_5INCH_TOP_DN")
	)
	(segment
		(start 320.781172 -3.22707)
		(end 320.531744 -4.638548)
		(width 0.12954)
		(layer "F.Cu")
		(net "DELTA_L_85_5INCH_TOP_DN")
	)
	(segment
		(start 361.142534 -5.238496)
		(end 360.557064 -5.648198)
		(width 0.12954)
		(layer "F.Cu")
		(net "DELTA_L_85_5INCH_TOP_DN")
	)
	(segment
		(start 336.856832 -3.259836)
		(end 336.153252 -7.240778)
		(width 0.12954)
		(layer "F.Cu")
		(net "DELTA_L_85_5INCH_TOP_DN")
	)
	(segment
		(start 315.936884 -5.327142)
		(end 315.791088 -5.327142)
		(width 0.12954)
		(layer "F.Cu")
		(net "DELTA_L_85_5INCH_TOP_DN")
	)
	(segment
		(start 346.434664 -3.344672)
		(end 345.05646 -3.101086)
		(width 0.12954)
		(layer "F.Cu")
		(net "DELTA_L_85_5INCH_TOP_DN")
	)
	(segment
		(start 328.831194 -3.173222)
		(end 328.11466 -7.227824)
		(width 0.12954)
		(layer "F.Cu")
		(net "DELTA_L_85_5INCH_TOP_DN")
	)
	(segment
		(start 342.188546 -7.196836)
		(end 341.92972 -6.828536)
		(width 0.12954)
		(layer "F.Cu")
		(net "DELTA_L_85_5INCH_TOP_DN")
	)
	(segment
		(start 339.80501 -7.499858)
		(end 338.165694 -7.20979)
		(width 0.12954)
		(layer "F.Cu")
		(net "DELTA_L_85_5INCH_TOP_DN")
	)
	(segment
		(start 327.74636 -7.48665)
		(end 326.106536 -7.196836)
		(width 0.12954)
		(layer "F.Cu")
		(net "DELTA_L_85_5INCH_TOP_DN")
	)
	(segment
		(start 351.8662 -7.499604)
		(end 350.226884 -7.209536)
		(width 0.12954)
		(layer "F.Cu")
		(net "DELTA_L_85_5INCH_TOP_DN")
	)
	(segment
		(start 346.20708 -7.206488)
		(end 345.948508 -6.83768)
		(width 0.12954)
		(layer "F.Cu")
		(net "DELTA_L_85_5INCH_TOP_DN")
	)
	(segment
		(start 346.539312 -3.494278)
		(end 346.434664 -3.344672)
		(width 0.12954)
		(layer "F.Cu")
		(net "DELTA_L_85_5INCH_TOP_DN")
	)
	(segment
		(start 358.497886 -3.332734)
		(end 357.119682 -3.089148)
		(width 0.12954)
		(layer "F.Cu")
		(net "DELTA_L_85_5INCH_TOP_DN")
	)
	(segment
		(start 349.070676 -3.13563)
		(end 348.921324 -3.240024)
		(width 0.12954)
		(layer "F.Cu")
		(net "DELTA_L_85_5INCH_TOP_DN")
	)
	(segment
		(start 360.557064 -5.648198)
		(end 360.273092 -7.256526)
		(width 0.12954)
		(layer "F.Cu")
		(net "DELTA_L_85_5INCH_TOP_DN")
	)
	(segment
		(start 341.038688 -3.086354)
		(end 340.889336 -3.190748)
		(width 0.12954)
		(layer "F.Cu")
		(net "DELTA_L_85_5INCH_TOP_DN")
	)
	(segment
		(start 359.886758 -7.527798)
		(end 358.277414 -7.24281)
		(width 0.12954)
		(layer "F.Cu")
		(net "DELTA_L_85_5INCH_TOP_DN")
	)
	(segment
		(start 343.827354 -7.486904)
		(end 342.188546 -7.196836)
		(width 0.12954)
		(layer "F.Cu")
		(net "DELTA_L_85_5INCH_TOP_DN")
	)
	(segment
		(start 330.35875 -3.312414)
		(end 328.980546 -3.068828)
		(width 0.12954)
		(layer "F.Cu")
		(net "DELTA_L_85_5INCH_TOP_DN")
	)
	(segment
		(start 321.826636 -6.834632)
		(end 322.413122 -3.515614)
		(width 0.12954)
		(layer "F.Cu")
		(net "DELTA_L_85_5INCH_TOP_DN")
	)
	(segment
		(start 322.085208 -7.20344)
		(end 321.826636 -6.834632)
		(width 0.12954)
		(layer "F.Cu")
		(net "DELTA_L_85_5INCH_TOP_DN")
	)
	(segment
		(start 335.784952 -7.499604)
		(end 334.145382 -7.209282)
		(width 0.12954)
		(layer "F.Cu")
		(net "DELTA_L_85_5INCH_TOP_DN")
	)
	(segment
		(start 358.006396 -6.856476)
		(end 358.602534 -3.48234)
		(width 0.12954)
		(layer "F.Cu")
		(net "DELTA_L_85_5INCH_TOP_DN")
	)
	(segment
		(start 319.674494 -5.238496)
		(end 316.02553 -5.238496)
		(width 0.12954)
		(layer "F.Cu")
		(net "DELTA_L_85_5INCH_TOP_DN")
	)
	(segment
		(start 365.217964 -5.238496)
		(end 361.142534 -5.238496)
		(width 0.12954)
		(layer "F.Cu")
		(net "DELTA_L_85_5INCH_TOP_DN")
	)
	(segment
		(start 325.848218 -6.827266)
		(end 326.43191 -3.523742)
		(width 0.12954)
		(layer "F.Cu")
		(net "DELTA_L_85_5INCH_TOP_DN")
	)
	(segment
		(start 345.05646 -3.101086)
		(end 344.907362 -3.20548)
		(width 0.12954)
		(layer "F.Cu")
		(net "DELTA_L_85_5INCH_TOP_DN")
	)
	(segment
		(start 330.463398 -3.461766)
		(end 330.35875 -3.312414)
		(width 0.12954)
		(layer "F.Cu")
		(net "DELTA_L_85_5INCH_TOP_DN")
	)
	(segment
		(start 365.30661 -5.327142)
		(end 365.217964 -5.238496)
		(width 0.12954)
		(layer "F.Cu")
		(net "DELTA_L_85_5INCH_TOP_DN")
	)
	(segment
		(start 354.582222 -3.482086)
		(end 354.477574 -3.33248)
		(width 0.12954)
		(layer "F.Cu")
		(net "DELTA_L_85_5INCH_TOP_DN")
	)
	(segment
		(start 340.173564 -7.241032)
		(end 339.80501 -7.499858)
		(width 0.12954)
		(layer "F.Cu")
		(net "DELTA_L_85_5INCH_TOP_DN")
	)
	(segment
		(start 354.477574 -3.33248)
		(end 353.09937 -3.088894)
		(width 0.12954)
		(layer "F.Cu")
		(net "DELTA_L_85_5INCH_TOP_DN")
	)
	(segment
		(start 323.724524 -7.493508)
		(end 322.085208 -7.20344)
		(width 0.12954)
		(layer "F.Cu")
		(net "DELTA_L_85_5INCH_TOP_DN")
	)
	(segment
		(start 332.990444 -3.127502)
		(end 332.841346 -3.231896)
		(width 0.12954)
		(layer "F.Cu")
		(net "DELTA_L_85_5INCH_TOP_DN")
	)
	(segment
		(start 328.980546 -3.068828)
		(end 328.831194 -3.173222)
		(width 0.12954)
		(layer "F.Cu")
		(net "DELTA_L_85_5INCH_TOP_DN")
	)
	(segment
		(start 330.127356 -7.19582)
		(end 329.868784 -6.827012)
		(width 0.12954)
		(layer "F.Cu")
		(net "DELTA_L_85_5INCH_TOP_DN")
	)
	(segment
		(start 324.949058 -3.13055)
		(end 324.79996 -3.234944)
		(width 0.12954)
		(layer "F.Cu")
		(net "DELTA_L_85_5INCH_TOP_DN")
	)
	(segment
		(start 340.889336 -3.190748)
		(end 340.173564 -7.241032)
		(width 0.12954)
		(layer "F.Cu")
		(net "DELTA_L_85_5INCH_TOP_DN")
	)
	(segment
		(start 331.766672 -7.485888)
		(end 330.127356 -7.19582)
		(width 0.12954)
		(layer "F.Cu")
		(net "DELTA_L_85_5INCH_TOP_DN")
	)
	(segment
		(start 352.235008 -7.241032)
		(end 351.8662 -7.499604)
		(width 0.12954)
		(layer "F.Cu")
		(net "DELTA_L_85_5INCH_TOP_DN")
	)
	(segment
		(start 334.145382 -7.209282)
		(end 333.88681 -6.840474)
		(width 0.12954)
		(layer "F.Cu")
		(net "DELTA_L_85_5INCH_TOP_DN")
	)
	(segment
		(start 341.92972 -6.828536)
		(end 342.52154 -3.479292)
		(width 0.12954)
		(layer "F.Cu")
		(net "DELTA_L_85_5INCH_TOP_DN")
	)
	(segment
		(start 342.416892 -3.32994)
		(end 341.038688 -3.086354)
		(width 0.12954)
		(layer "F.Cu")
		(net "DELTA_L_85_5INCH_TOP_DN")
	)
	(segment
		(start 337.00593 -3.155442)
		(end 336.856832 -3.259836)
		(width 0.12954)
		(layer "F.Cu")
		(net "DELTA_L_85_5INCH_TOP_DN")
	)
	(segment
		(start 334.368648 -3.371088)
		(end 332.990444 -3.127502)
		(width 0.12954)
		(layer "F.Cu")
		(net "DELTA_L_85_5INCH_TOP_DN")
	)
	(segment
		(start 326.106536 -7.196836)
		(end 325.848218 -6.827266)
		(width 0.12954)
		(layer "F.Cu")
		(net "DELTA_L_85_5INCH_TOP_DN")
	)
	(segment
		(start 338.165694 -7.20979)
		(end 337.907122 -6.840982)
		(width 0.12954)
		(layer "F.Cu")
		(net "DELTA_L_85_5INCH_TOP_DN")
	)
	(segment
		(start 320.93027 -3.122676)
		(end 320.781172 -3.22707)
		(width 0.12954)
		(layer "F.Cu")
		(net "DELTA_L_85_5INCH_TOP_DN")
	)
	(segment
		(start 320.531744 -4.638548)
		(end 319.674494 -5.238496)
		(width 0.12954)
		(layer "F.Cu")
		(net "DELTA_L_85_5INCH_TOP_DN")
	)
	(segment
		(start 356.256336 -7.23646)
		(end 355.887528 -7.495032)
		(width 0.12954)
		(layer "F.Cu")
		(net "DELTA_L_85_5INCH_TOP_DN")
	)
	(segment
		(start 344.907362 -3.20548)
		(end 344.19667 -7.228332)
		(width 0.12954)
		(layer "F.Cu")
		(net "DELTA_L_85_5INCH_TOP_DN")
	)
	(segment
		(start 350.553528 -3.528568)
		(end 350.44888 -3.379216)
		(width 0.12954)
		(layer "F.Cu")
		(net "DELTA_L_85_5INCH_TOP_DN")
	)
	(segment
		(start 365.463074 -5.327142)
		(end 365.30661 -5.327142)
		(width 0.12954)
		(layer "F.Cu")
		(net "DELTA_L_85_5INCH_TOP_DN")
	)
	(segment
		(start 332.841346 -3.231896)
		(end 332.13548 -7.227316)
		(width 0.12954)
		(layer "F.Cu")
		(net "DELTA_L_85_5INCH_TOP_DN")
	)
	(segment
		(start 329.868784 -6.827012)
		(end 330.463398 -3.461766)
		(width 0.12954)
		(layer "F.Cu")
		(net "DELTA_L_85_5INCH_TOP_DN")
	)
	(segment
		(start 322.308474 -3.366262)
		(end 320.93027 -3.122676)
		(width 0.12954)
		(layer "F.Cu")
		(net "DELTA_L_85_5INCH_TOP_DN")
	)
	(segment
		(start 324.093332 -7.234936)
		(end 323.724524 -7.493508)
		(width 0.12954)
		(layer "F.Cu")
		(net "DELTA_L_85_5INCH_TOP_DN")
	)
	(segment
		(start 324.79996 -3.234944)
		(end 324.093332 -7.234936)
		(width 0.12954)
		(layer "F.Cu")
		(net "DELTA_L_85_5INCH_TOP_DN")
	)
	(segment
		(start 358.602534 -3.48234)
		(end 358.497886 -3.332734)
		(width 0.12954)
		(layer "F.Cu")
		(net "DELTA_L_85_5INCH_TOP_DN")
	)
	(segment
		(start 326.43191 -3.523742)
		(end 326.327262 -3.374136)
		(width 0.12954)
		(layer "F.Cu")
		(net "DELTA_L_85_5INCH_TOP_DN")
	)
	(segment
		(start 349.968312 -6.840728)
		(end 350.553528 -3.528568)
		(width 0.12954)
		(layer "F.Cu")
		(net "DELTA_L_85_5INCH_TOP_DN")
	)
	(segment
		(start 338.384134 -3.399028)
		(end 337.00593 -3.155442)
		(width 0.12954)
		(layer "F.Cu")
		(net "DELTA_L_85_5INCH_TOP_DN")
	)
	(segment
		(start 353.09937 -3.088894)
		(end 352.950272 -3.193288)
		(width 0.12954)
		(layer "F.Cu")
		(net "DELTA_L_85_5INCH_TOP_DN")
	)
	(segment
		(start 357.119682 -3.089148)
		(end 356.970584 -3.193542)
		(width 0.12954)
		(layer "F.Cu")
		(net "DELTA_L_85_5INCH_TOP_DN")
	)
	(segment
		(start 344.19667 -7.228332)
		(end 343.827354 -7.486904)
		(width 0.12954)
		(layer "F.Cu")
		(net "DELTA_L_85_5INCH_TOP_DN")
	)
	(segment
		(start 348.921324 -3.240024)
		(end 348.21495 -7.237984)
		(width 0.12954)
		(layer "F.Cu")
		(net "DELTA_L_85_5INCH_TOP_DN")
	)
	(segment
		(start 348.21495 -7.237984)
		(end 347.84665 -7.49681)
		(width 0.12954)
		(layer "F.Cu")
		(net "DELTA_L_85_5INCH_TOP_DN")
	)
	(segment
		(start 347.84665 -7.49681)
		(end 346.20708 -7.206488)
		(width 0.12954)
		(layer "F.Cu")
		(net "DELTA_L_85_5INCH_TOP_DN")
	)
	(segment
		(start 342.52154 -3.479292)
		(end 342.416892 -3.32994)
		(width 0.12954)
		(layer "F.Cu")
		(net "DELTA_L_85_5INCH_TOP_DN")
	)
	(segment
		(start 356.970584 -3.193542)
		(end 356.256336 -7.23646)
		(width 0.12954)
		(layer "F.Cu")
		(net "DELTA_L_85_5INCH_TOP_DN")
	)
	(segment
		(start 354.248212 -7.204964)
		(end 353.98964 -6.836156)
		(width 0.12954)
		(layer "F.Cu")
		(net "DELTA_L_85_5INCH_TOP_DN")
	)
	(segment
		(start 350.44888 -3.379216)
		(end 349.070676 -3.13563)
		(width 0.12954)
		(layer "F.Cu")
		(net "DELTA_L_85_5INCH_TOP_DN")
	)
	(segment
		(start 328.11466 -7.227824)
		(end 327.74636 -7.48665)
		(width 0.12954)
		(layer "F.Cu")
		(net "DELTA_L_85_5INCH_TOP_DN")
	)
	(segment
		(start 316.02553 -5.238496)
		(end 315.936884 -5.327142)
		(width 0.12954)
		(layer "F.Cu")
		(net "DELTA_L_85_5INCH_TOP_DN")
	)
	(segment
		(start 358.277414 -7.24281)
		(end 358.006396 -6.856476)
		(width 0.12954)
		(layer "F.Cu")
		(net "DELTA_L_85_5INCH_TOP_DN")
	)
	(segment
		(start 326.327262 -3.374136)
		(end 324.949058 -3.13055)
		(width 0.12954)
		(layer "F.Cu")
		(net "DELTA_L_85_5INCH_TOP_DN")
	)
	(segment
		(start 365.463074 -2.28727)
		(end 364.810802 -2.105406)
		(width 0.12954)
		(layer "B.Cu")
		(net "DELTA_L_85_5INCH_IN6_DP")
	)
	(segment
		(start 315.791088 -2.28727)
		(end 316.44336 -2.105406)
		(width 0.12954)
		(layer "B.Cu")
		(net "DELTA_L_85_5INCH_IN6_DP")
	)
	(segment
		(start 342.494616 -4.178046)
		(end 342.609678 -4.342638)
		(width 0.14224)
		(layer "In15.Cu")
		(net "DELTA_L_85_5INCH_IN6_DP")
	)
	(segment
		(start 352.055176 -4.516628)
		(end 352.760026 -0.524764)
		(width 0.14224)
		(layer "In15.Cu")
		(net "DELTA_L_85_5INCH_IN6_DP")
	)
	(segment
		(start 347.931994 -4.609846)
		(end 348.096332 -4.494784)
		(width 0.14224)
		(layer "In15.Cu")
		(net "DELTA_L_85_5INCH_IN6_DP")
	)
	(segment
		(start 359.817416 -4.625594)
		(end 359.981754 -4.510532)
		(width 0.14224)
		(layer "In15.Cu")
		(net "DELTA_L_85_5INCH_IN6_DP")
	)
	(segment
		(start 327.226676 -0.879602)
		(end 326.63257 -4.242054)
		(width 0.14224)
		(layer "In15.Cu")
		(net "DELTA_L_85_5INCH_IN6_DP")
	)
	(segment
		(start 340.00694 -4.608068)
		(end 340.171278 -4.493006)
		(width 0.14224)
		(layer "In15.Cu")
		(net "DELTA_L_85_5INCH_IN6_DP")
	)
	(segment
		(start 334.675988 -4.389882)
		(end 336.040222 -4.630928)
		(width 0.14224)
		(layer "In15.Cu")
		(net "DELTA_L_85_5INCH_IN6_DP")
	)
	(segment
		(start 326.63257 -4.242054)
		(end 326.747632 -4.4069)
		(width 0.14224)
		(layer "In15.Cu")
		(net "DELTA_L_85_5INCH_IN6_DP")
	)
	(segment
		(start 320.203576 -2.396236)
		(end 320.802508 -1.976882)
		(width 0.14224)
		(layer "In15.Cu")
		(net "DELTA_L_85_5INCH_IN6_DP")
	)
	(segment
		(start 342.609678 -4.342638)
		(end 343.973912 -4.583684)
		(width 0.14224)
		(layer "In15.Cu")
		(net "DELTA_L_85_5INCH_IN6_DP")
	)
	(segment
		(start 354.374196 -4.225798)
		(end 354.489258 -4.39039)
		(width 0.14224)
		(layer "In15.Cu")
		(net "DELTA_L_85_5INCH_IN6_DP")
	)
	(segment
		(start 316.44336 -2.105406)
		(end 316.73419 -2.396236)
		(width 0.14224)
		(layer "In15.Cu")
		(net "DELTA_L_85_5INCH_IN6_DP")
	)
	(segment
		(start 343.973912 -4.583684)
		(end 344.13825 -4.468622)
		(width 0.14224)
		(layer "In15.Cu")
		(net "DELTA_L_85_5INCH_IN6_DP")
	)
	(segment
		(start 354.959412 -0.912622)
		(end 354.374196 -4.225798)
		(width 0.14224)
		(layer "In15.Cu")
		(net "DELTA_L_85_5INCH_IN6_DP")
	)
	(segment
		(start 321.420744 -0.242824)
		(end 323.01434 -0.52451)
		(width 0.14224)
		(layer "In15.Cu")
		(net "DELTA_L_85_5INCH_IN6_DP")
	)
	(segment
		(start 324.156324 -4.607052)
		(end 324.320662 -4.49199)
		(width 0.14224)
		(layer "In15.Cu")
		(net "DELTA_L_85_5INCH_IN6_DP")
	)
	(segment
		(start 345.193366 -0.26289)
		(end 346.786962 -0.544576)
		(width 0.14224)
		(layer "In15.Cu")
		(net "DELTA_L_85_5INCH_IN6_DP")
	)
	(segment
		(start 358.92232 -0.911098)
		(end 358.33812 -4.219956)
		(width 0.14224)
		(layer "In15.Cu")
		(net "DELTA_L_85_5INCH_IN6_DP")
	)
	(segment
		(start 334.560926 -4.225036)
		(end 334.675988 -4.389882)
		(width 0.14224)
		(layer "In15.Cu")
		(net "DELTA_L_85_5INCH_IN6_DP")
	)
	(segment
		(start 346.786962 -0.544576)
		(end 347.03639 -0.900684)
		(width 0.14224)
		(layer "In15.Cu")
		(net "DELTA_L_85_5INCH_IN6_DP")
	)
	(segment
		(start 338.527644 -4.20243)
		(end 338.642706 -4.367022)
		(width 0.14224)
		(layer "In15.Cu")
		(net "DELTA_L_85_5INCH_IN6_DP")
	)
	(segment
		(start 316.73419 -2.396236)
		(end 320.203576 -2.396236)
		(width 0.14224)
		(layer "In15.Cu")
		(net "DELTA_L_85_5INCH_IN6_DP")
	)
	(segment
		(start 336.040222 -4.630928)
		(end 336.20456 -4.515866)
		(width 0.14224)
		(layer "In15.Cu")
		(net "DELTA_L_85_5INCH_IN6_DP")
	)
	(segment
		(start 336.91576 -0.48895)
		(end 337.271868 -0.239522)
		(width 0.14224)
		(layer "In15.Cu")
		(net "DELTA_L_85_5INCH_IN6_DP")
	)
	(segment
		(start 339.114892 -0.877316)
		(end 338.527644 -4.20243)
		(width 0.14224)
		(layer "In15.Cu")
		(net "DELTA_L_85_5INCH_IN6_DP")
	)
	(segment
		(start 354.709984 -0.557022)
		(end 354.959412 -0.912622)
		(width 0.14224)
		(layer "In15.Cu")
		(net "DELTA_L_85_5INCH_IN6_DP")
	)
	(segment
		(start 332.956916 -0.468376)
		(end 333.313024 -0.218948)
		(width 0.14224)
		(layer "In15.Cu")
		(net "DELTA_L_85_5INCH_IN6_DP")
	)
	(segment
		(start 325.027544 -0.491236)
		(end 325.383652 -0.241808)
		(width 0.14224)
		(layer "In15.Cu")
		(net "DELTA_L_85_5INCH_IN6_DP")
	)
	(segment
		(start 328.988928 -0.499364)
		(end 329.344528 -0.249936)
		(width 0.14224)
		(layer "In15.Cu")
		(net "DELTA_L_85_5INCH_IN6_DP")
	)
	(segment
		(start 325.383652 -0.241808)
		(end 326.977248 -0.523494)
		(width 0.14224)
		(layer "In15.Cu")
		(net "DELTA_L_85_5INCH_IN6_DP")
	)
	(segment
		(start 358.453182 -4.384548)
		(end 359.817416 -4.625594)
		(width 0.14224)
		(layer "In15.Cu")
		(net "DELTA_L_85_5INCH_IN6_DP")
	)
	(segment
		(start 338.642706 -4.367022)
		(end 340.00694 -4.608068)
		(width 0.14224)
		(layer "In15.Cu")
		(net "DELTA_L_85_5INCH_IN6_DP")
	)
	(segment
		(start 320.802508 -1.976882)
		(end 321.064636 -0.492252)
		(width 0.14224)
		(layer "In15.Cu")
		(net "DELTA_L_85_5INCH_IN6_DP")
	)
	(segment
		(start 340.171278 -4.493006)
		(end 340.879938 -0.480314)
		(width 0.14224)
		(layer "In15.Cu")
		(net "DELTA_L_85_5INCH_IN6_DP")
	)
	(segment
		(start 340.879938 -0.480314)
		(end 341.236046 -0.230886)
		(width 0.14224)
		(layer "In15.Cu")
		(net "DELTA_L_85_5INCH_IN6_DP")
	)
	(segment
		(start 326.747632 -4.4069)
		(end 328.111866 -4.647946)
		(width 0.14224)
		(layer "In15.Cu")
		(net "DELTA_L_85_5INCH_IN6_DP")
	)
	(segment
		(start 331.187806 -0.887984)
		(end 330.599288 -4.219448)
		(width 0.14224)
		(layer "In15.Cu")
		(net "DELTA_L_85_5INCH_IN6_DP")
	)
	(segment
		(start 336.20456 -4.515866)
		(end 336.91576 -0.48895)
		(width 0.14224)
		(layer "In15.Cu")
		(net "DELTA_L_85_5INCH_IN6_DP")
	)
	(segment
		(start 351.890838 -4.63169)
		(end 352.055176 -4.516628)
		(width 0.14224)
		(layer "In15.Cu")
		(net "DELTA_L_85_5INCH_IN6_DP")
	)
	(segment
		(start 333.313024 -0.218948)
		(end 334.90662 -0.500634)
		(width 0.14224)
		(layer "In15.Cu")
		(net "DELTA_L_85_5INCH_IN6_DP")
	)
	(segment
		(start 332.242922 -4.510278)
		(end 332.956916 -0.468376)
		(width 0.14224)
		(layer "In15.Cu")
		(net "DELTA_L_85_5INCH_IN6_DP")
	)
	(segment
		(start 332.078584 -4.62534)
		(end 332.242922 -4.510278)
		(width 0.14224)
		(layer "In15.Cu")
		(net "DELTA_L_85_5INCH_IN6_DP")
	)
	(segment
		(start 346.56776 -4.3688)
		(end 347.931994 -4.609846)
		(width 0.14224)
		(layer "In15.Cu")
		(net "DELTA_L_85_5INCH_IN6_DP")
	)
	(segment
		(start 326.977248 -0.523494)
		(end 327.226676 -0.879602)
		(width 0.14224)
		(layer "In15.Cu")
		(net "DELTA_L_85_5INCH_IN6_DP")
	)
	(segment
		(start 358.672892 -0.55499)
		(end 358.92232 -0.911098)
		(width 0.14224)
		(layer "In15.Cu")
		(net "DELTA_L_85_5INCH_IN6_DP")
	)
	(segment
		(start 356.01783 -4.516374)
		(end 356.723188 -0.522732)
		(width 0.14224)
		(layer "In15.Cu")
		(net "DELTA_L_85_5INCH_IN6_DP")
	)
	(segment
		(start 358.33812 -4.219956)
		(end 358.453182 -4.384548)
		(width 0.14224)
		(layer "In15.Cu")
		(net "DELTA_L_85_5INCH_IN6_DP")
	)
	(segment
		(start 352.760026 -0.524764)
		(end 353.116388 -0.275336)
		(width 0.14224)
		(layer "In15.Cu")
		(net "DELTA_L_85_5INCH_IN6_DP")
	)
	(segment
		(start 364.519972 -2.396236)
		(end 364.810802 -2.105406)
		(width 0.14224)
		(layer "In15.Cu")
		(net "DELTA_L_85_5INCH_IN6_DP")
	)
	(segment
		(start 330.938632 -0.531622)
		(end 331.187806 -0.887984)
		(width 0.14224)
		(layer "In15.Cu")
		(net "DELTA_L_85_5INCH_IN6_DP")
	)
	(segment
		(start 324.320662 -4.49199)
		(end 325.027544 -0.491236)
		(width 0.14224)
		(layer "In15.Cu")
		(net "DELTA_L_85_5INCH_IN6_DP")
	)
	(segment
		(start 359.981754 -4.510532)
		(end 360.249216 -2.996184)
		(width 0.14224)
		(layer "In15.Cu")
		(net "DELTA_L_85_5INCH_IN6_DP")
	)
	(segment
		(start 348.096332 -4.494784)
		(end 348.799658 -0.512572)
		(width 0.14224)
		(layer "In15.Cu")
		(net "DELTA_L_85_5INCH_IN6_DP")
	)
	(segment
		(start 353.116388 -0.275336)
		(end 354.709984 -0.557022)
		(width 0.14224)
		(layer "In15.Cu")
		(net "DELTA_L_85_5INCH_IN6_DP")
	)
	(segment
		(start 348.799658 -0.512572)
		(end 349.155766 -0.263144)
		(width 0.14224)
		(layer "In15.Cu")
		(net "DELTA_L_85_5INCH_IN6_DP")
	)
	(segment
		(start 329.344528 -0.249936)
		(end 330.938632 -0.531622)
		(width 0.14224)
		(layer "In15.Cu")
		(net "DELTA_L_85_5INCH_IN6_DP")
	)
	(segment
		(start 343.07907 -0.86868)
		(end 342.494616 -4.178046)
		(width 0.14224)
		(layer "In15.Cu")
		(net "DELTA_L_85_5INCH_IN6_DP")
	)
	(segment
		(start 350.411542 -4.226052)
		(end 350.526604 -4.390644)
		(width 0.14224)
		(layer "In15.Cu")
		(net "DELTA_L_85_5INCH_IN6_DP")
	)
	(segment
		(start 323.01434 -0.52451)
		(end 323.263768 -0.880618)
		(width 0.14224)
		(layer "In15.Cu")
		(net "DELTA_L_85_5INCH_IN6_DP")
	)
	(segment
		(start 334.90662 -0.500634)
		(end 335.156048 -0.856742)
		(width 0.14224)
		(layer "In15.Cu")
		(net "DELTA_L_85_5INCH_IN6_DP")
	)
	(segment
		(start 335.156048 -0.856742)
		(end 334.560926 -4.225036)
		(width 0.14224)
		(layer "In15.Cu")
		(net "DELTA_L_85_5INCH_IN6_DP")
	)
	(segment
		(start 338.865464 -0.521208)
		(end 339.114892 -0.877316)
		(width 0.14224)
		(layer "In15.Cu")
		(net "DELTA_L_85_5INCH_IN6_DP")
	)
	(segment
		(start 350.526604 -4.390644)
		(end 351.890838 -4.63169)
		(width 0.14224)
		(layer "In15.Cu")
		(net "DELTA_L_85_5INCH_IN6_DP")
	)
	(segment
		(start 328.276204 -4.532884)
		(end 328.988928 -0.499364)
		(width 0.14224)
		(layer "In15.Cu")
		(net "DELTA_L_85_5INCH_IN6_DP")
	)
	(segment
		(start 349.155766 -0.263144)
		(end 350.749362 -0.545084)
		(width 0.14224)
		(layer "In15.Cu")
		(net "DELTA_L_85_5INCH_IN6_DP")
	)
	(segment
		(start 322.677028 -4.201414)
		(end 322.79209 -4.366006)
		(width 0.14224)
		(layer "In15.Cu")
		(net "DELTA_L_85_5INCH_IN6_DP")
	)
	(segment
		(start 361.103672 -2.396236)
		(end 364.519972 -2.396236)
		(width 0.14224)
		(layer "In15.Cu")
		(net "DELTA_L_85_5INCH_IN6_DP")
	)
	(segment
		(start 346.452698 -4.204208)
		(end 346.56776 -4.3688)
		(width 0.14224)
		(layer "In15.Cu")
		(net "DELTA_L_85_5INCH_IN6_DP")
	)
	(segment
		(start 356.723188 -0.522732)
		(end 357.079296 -0.273304)
		(width 0.14224)
		(layer "In15.Cu")
		(net "DELTA_L_85_5INCH_IN6_DP")
	)
	(segment
		(start 354.489258 -4.39039)
		(end 355.853492 -4.631436)
		(width 0.14224)
		(layer "In15.Cu")
		(net "DELTA_L_85_5INCH_IN6_DP")
	)
	(segment
		(start 321.064636 -0.492252)
		(end 321.420744 -0.242824)
		(width 0.14224)
		(layer "In15.Cu")
		(net "DELTA_L_85_5INCH_IN6_DP")
	)
	(segment
		(start 360.249216 -2.996184)
		(end 361.103672 -2.396236)
		(width 0.14224)
		(layer "In15.Cu")
		(net "DELTA_L_85_5INCH_IN6_DP")
	)
	(segment
		(start 355.853492 -4.631436)
		(end 356.01783 -4.516374)
		(width 0.14224)
		(layer "In15.Cu")
		(net "DELTA_L_85_5INCH_IN6_DP")
	)
	(segment
		(start 347.03639 -0.900684)
		(end 346.452698 -4.204208)
		(width 0.14224)
		(layer "In15.Cu")
		(net "DELTA_L_85_5INCH_IN6_DP")
	)
	(segment
		(start 350.99879 -0.900938)
		(end 350.411542 -4.226052)
		(width 0.14224)
		(layer "In15.Cu")
		(net "DELTA_L_85_5INCH_IN6_DP")
	)
	(segment
		(start 337.271868 -0.239522)
		(end 338.865464 -0.521208)
		(width 0.14224)
		(layer "In15.Cu")
		(net "DELTA_L_85_5INCH_IN6_DP")
	)
	(segment
		(start 330.71435 -4.384294)
		(end 332.078584 -4.62534)
		(width 0.14224)
		(layer "In15.Cu")
		(net "DELTA_L_85_5INCH_IN6_DP")
	)
	(segment
		(start 323.263768 -0.880618)
		(end 322.677028 -4.201414)
		(width 0.14224)
		(layer "In15.Cu")
		(net "DELTA_L_85_5INCH_IN6_DP")
	)
	(segment
		(start 357.079296 -0.273304)
		(end 358.672892 -0.55499)
		(width 0.14224)
		(layer "In15.Cu")
		(net "DELTA_L_85_5INCH_IN6_DP")
	)
	(segment
		(start 330.599288 -4.219448)
		(end 330.71435 -4.384294)
		(width 0.14224)
		(layer "In15.Cu")
		(net "DELTA_L_85_5INCH_IN6_DP")
	)
	(segment
		(start 342.829642 -0.512572)
		(end 343.07907 -0.86868)
		(width 0.14224)
		(layer "In15.Cu")
		(net "DELTA_L_85_5INCH_IN6_DP")
	)
	(segment
		(start 322.79209 -4.366006)
		(end 324.156324 -4.607052)
		(width 0.14224)
		(layer "In15.Cu")
		(net "DELTA_L_85_5INCH_IN6_DP")
	)
	(segment
		(start 328.111866 -4.647946)
		(end 328.276204 -4.532884)
		(width 0.14224)
		(layer "In15.Cu")
		(net "DELTA_L_85_5INCH_IN6_DP")
	)
	(segment
		(start 350.749362 -0.545084)
		(end 350.99879 -0.900938)
		(width 0.14224)
		(layer "In15.Cu")
		(net "DELTA_L_85_5INCH_IN6_DP")
	)
	(segment
		(start 341.236046 -0.230886)
		(end 342.829642 -0.512572)
		(width 0.14224)
		(layer "In15.Cu")
		(net "DELTA_L_85_5INCH_IN6_DP")
	)
	(segment
		(start 344.837258 -0.512318)
		(end 345.193366 -0.26289)
		(width 0.14224)
		(layer "In15.Cu")
		(net "DELTA_L_85_5INCH_IN6_DP")
	)
	(segment
		(start 344.13825 -4.468622)
		(end 344.837258 -0.512318)
		(width 0.14224)
		(layer "In15.Cu")
		(net "DELTA_L_85_5INCH_IN6_DP")
	)
	(segment
		(start 365.463074 -2.787142)
		(end 364.810802 -2.969006)
		(width 0.12954)
		(layer "B.Cu")
		(net "DELTA_L_85_5INCH_IN6_DN")
	)
	(segment
		(start 315.791088 -2.787142)
		(end 316.44336 -2.969006)
		(width 0.12954)
		(layer "B.Cu")
		(net "DELTA_L_85_5INCH_IN6_DN")
	)
	(segment
		(start 334.51165 -4.647438)
		(end 334.26273 -4.29133)
		(width 0.14224)
		(layer "In15.Cu")
		(net "DELTA_L_85_5INCH_IN6_DN")
	)
	(segment
		(start 336.106262 -4.929124)
		(end 334.51165 -4.647438)
		(width 0.14224)
		(layer "In15.Cu")
		(net "DELTA_L_85_5INCH_IN6_DN")
	)
	(segment
		(start 355.919532 -4.929632)
		(end 354.32492 -4.647946)
		(width 0.14224)
		(layer "In15.Cu")
		(net "DELTA_L_85_5INCH_IN6_DN")
	)
	(segment
		(start 333.214472 -0.63246)
		(end 332.500478 -4.674362)
		(width 0.14224)
		(layer "In15.Cu")
		(net "DELTA_L_85_5INCH_IN6_DN")
	)
	(segment
		(start 333.379064 -0.517144)
		(end 333.214472 -0.63246)
		(width 0.14224)
		(layer "In15.Cu")
		(net "DELTA_L_85_5INCH_IN6_DN")
	)
	(segment
		(start 326.813164 -0.78105)
		(end 325.449692 -0.540004)
		(width 0.14224)
		(layer "In15.Cu")
		(net "DELTA_L_85_5INCH_IN6_DN")
	)
	(segment
		(start 357.145336 -0.5715)
		(end 356.980744 -0.686816)
		(width 0.14224)
		(layer "In15.Cu")
		(net "DELTA_L_85_5INCH_IN6_DN")
	)
	(segment
		(start 322.627752 -4.623562)
		(end 322.378832 -4.267454)
		(width 0.14224)
		(layer "In15.Cu")
		(net "DELTA_L_85_5INCH_IN6_DN")
	)
	(segment
		(start 340.428834 -4.65709)
		(end 340.07298 -4.906264)
		(width 0.14224)
		(layer "In15.Cu")
		(net "DELTA_L_85_5INCH_IN6_DN")
	)
	(segment
		(start 341.302086 -0.529082)
		(end 341.137494 -0.644398)
		(width 0.14224)
		(layer "In15.Cu")
		(net "DELTA_L_85_5INCH_IN6_DN")
	)
	(segment
		(start 345.094814 -0.676402)
		(end 344.395806 -4.632706)
		(width 0.14224)
		(layer "In15.Cu")
		(net "DELTA_L_85_5INCH_IN6_DN")
	)
	(segment
		(start 329.246484 -0.663448)
		(end 328.53376 -4.696968)
		(width 0.14224)
		(layer "In15.Cu")
		(net "DELTA_L_85_5INCH_IN6_DN")
	)
	(segment
		(start 334.742536 -0.75819)
		(end 333.379064 -0.517144)
		(width 0.14224)
		(layer "In15.Cu")
		(net "DELTA_L_85_5INCH_IN6_DN")
	)
	(segment
		(start 316.73419 -2.678176)
		(end 316.44336 -2.969006)
		(width 0.14224)
		(layer "In15.Cu")
		(net "DELTA_L_85_5INCH_IN6_DN")
	)
	(segment
		(start 336.462116 -4.67995)
		(end 336.106262 -4.929124)
		(width 0.14224)
		(layer "In15.Cu")
		(net "DELTA_L_85_5INCH_IN6_DN")
	)
	(segment
		(start 360.506772 -3.160014)
		(end 360.23931 -4.674616)
		(width 0.14224)
		(layer "In15.Cu")
		(net "DELTA_L_85_5INCH_IN6_DN")
	)
	(segment
		(start 338.229448 -4.26847)
		(end 338.816696 -0.943356)
		(width 0.14224)
		(layer "In15.Cu")
		(net "DELTA_L_85_5INCH_IN6_DN")
	)
	(segment
		(start 330.774294 -0.789178)
		(end 329.410822 -0.548132)
		(width 0.14224)
		(layer "In15.Cu")
		(net "DELTA_L_85_5INCH_IN6_DN")
	)
	(segment
		(start 332.144624 -4.923536)
		(end 330.550012 -4.64185)
		(width 0.14224)
		(layer "In15.Cu")
		(net "DELTA_L_85_5INCH_IN6_DN")
	)
	(segment
		(start 350.700594 -0.966978)
		(end 350.585278 -0.80264)
		(width 0.14224)
		(layer "In15.Cu")
		(net "DELTA_L_85_5INCH_IN6_DN")
	)
	(segment
		(start 358.624124 -0.977138)
		(end 358.508808 -0.812546)
		(width 0.14224)
		(layer "In15.Cu")
		(net "DELTA_L_85_5INCH_IN6_DN")
	)
	(segment
		(start 324.222364 -4.905248)
		(end 322.627752 -4.623562)
		(width 0.14224)
		(layer "In15.Cu")
		(net "DELTA_L_85_5INCH_IN6_DN")
	)
	(segment
		(start 364.810802 -2.969006)
		(end 364.519972 -2.678176)
		(width 0.14224)
		(layer "In15.Cu")
		(net "DELTA_L_85_5INCH_IN6_DN")
	)
	(segment
		(start 350.585278 -0.80264)
		(end 349.221806 -0.56134)
		(width 0.14224)
		(layer "In15.Cu")
		(net "DELTA_L_85_5INCH_IN6_DN")
	)
	(segment
		(start 322.378832 -4.267454)
		(end 322.965572 -0.946658)
		(width 0.14224)
		(layer "In15.Cu")
		(net "DELTA_L_85_5INCH_IN6_DN")
	)
	(segment
		(start 346.403422 -4.626356)
		(end 346.154502 -4.270248)
		(width 0.14224)
		(layer "In15.Cu")
		(net "DELTA_L_85_5INCH_IN6_DN")
	)
	(segment
		(start 353.017582 -0.688848)
		(end 352.312732 -4.680712)
		(width 0.14224)
		(layer "In15.Cu")
		(net "DELTA_L_85_5INCH_IN6_DN")
	)
	(segment
		(start 344.039952 -4.88188)
		(end 342.44534 -4.600194)
		(width 0.14224)
		(layer "In15.Cu")
		(net "DELTA_L_85_5INCH_IN6_DN")
	)
	(segment
		(start 328.177906 -4.946142)
		(end 326.583294 -4.664456)
		(width 0.14224)
		(layer "In15.Cu")
		(net "DELTA_L_85_5INCH_IN6_DN")
	)
	(segment
		(start 351.956878 -4.929886)
		(end 350.362266 -4.6482)
		(width 0.14224)
		(layer "In15.Cu")
		(net "DELTA_L_85_5INCH_IN6_DN")
	)
	(segment
		(start 346.622878 -0.802132)
		(end 345.259406 -0.561086)
		(width 0.14224)
		(layer "In15.Cu")
		(net "DELTA_L_85_5INCH_IN6_DN")
	)
	(segment
		(start 354.661216 -0.978916)
		(end 354.5459 -0.814578)
		(width 0.14224)
		(layer "In15.Cu")
		(net "DELTA_L_85_5INCH_IN6_DN")
	)
	(segment
		(start 348.353888 -4.658868)
		(end 347.998034 -4.908042)
		(width 0.14224)
		(layer "In15.Cu")
		(net "DELTA_L_85_5INCH_IN6_DN")
	)
	(segment
		(start 334.26273 -4.29133)
		(end 334.857852 -0.922782)
		(width 0.14224)
		(layer "In15.Cu")
		(net "DELTA_L_85_5INCH_IN6_DN")
	)
	(segment
		(start 350.113346 -4.292092)
		(end 350.700594 -0.966978)
		(width 0.14224)
		(layer "In15.Cu")
		(net "DELTA_L_85_5INCH_IN6_DN")
	)
	(segment
		(start 346.154502 -4.270248)
		(end 346.738194 -0.966724)
		(width 0.14224)
		(layer "In15.Cu")
		(net "DELTA_L_85_5INCH_IN6_DN")
	)
	(segment
		(start 329.410822 -0.548132)
		(end 329.246484 -0.663448)
		(width 0.14224)
		(layer "In15.Cu")
		(net "DELTA_L_85_5INCH_IN6_DN")
	)
	(segment
		(start 326.92848 -0.945642)
		(end 326.813164 -0.78105)
		(width 0.14224)
		(layer "In15.Cu")
		(net "DELTA_L_85_5INCH_IN6_DN")
	)
	(segment
		(start 356.275386 -4.680458)
		(end 355.919532 -4.929632)
		(width 0.14224)
		(layer "In15.Cu")
		(net "DELTA_L_85_5INCH_IN6_DN")
	)
	(segment
		(start 364.519972 -2.678176)
		(end 361.192826 -2.678176)
		(width 0.14224)
		(layer "In15.Cu")
		(net "DELTA_L_85_5INCH_IN6_DN")
	)
	(segment
		(start 345.259406 -0.561086)
		(end 345.094814 -0.676402)
		(width 0.14224)
		(layer "In15.Cu")
		(net "DELTA_L_85_5INCH_IN6_DN")
	)
	(segment
		(start 358.288844 -4.642104)
		(end 358.039924 -4.285996)
		(width 0.14224)
		(layer "In15.Cu")
		(net "DELTA_L_85_5INCH_IN6_DN")
	)
	(segment
		(start 340.07298 -4.906264)
		(end 338.478368 -4.624578)
		(width 0.14224)
		(layer "In15.Cu")
		(net "DELTA_L_85_5INCH_IN6_DN")
	)
	(segment
		(start 342.665558 -0.770128)
		(end 341.302086 -0.529082)
		(width 0.14224)
		(layer "In15.Cu")
		(net "DELTA_L_85_5INCH_IN6_DN")
	)
	(segment
		(start 337.337908 -0.537718)
		(end 337.173316 -0.653034)
		(width 0.14224)
		(layer "In15.Cu")
		(net "DELTA_L_85_5INCH_IN6_DN")
	)
	(segment
		(start 325.2851 -0.65532)
		(end 324.578218 -4.656074)
		(width 0.14224)
		(layer "In15.Cu")
		(net "DELTA_L_85_5INCH_IN6_DN")
	)
	(segment
		(start 358.508808 -0.812546)
		(end 357.145336 -0.5715)
		(width 0.14224)
		(layer "In15.Cu")
		(net "DELTA_L_85_5INCH_IN6_DN")
	)
	(segment
		(start 361.192826 -2.678176)
		(end 360.506772 -3.160014)
		(width 0.14224)
		(layer "In15.Cu")
		(net "DELTA_L_85_5INCH_IN6_DN")
	)
	(segment
		(start 352.312732 -4.680712)
		(end 351.956878 -4.929886)
		(width 0.14224)
		(layer "In15.Cu")
		(net "DELTA_L_85_5INCH_IN6_DN")
	)
	(segment
		(start 349.057214 -0.676656)
		(end 348.353888 -4.658868)
		(width 0.14224)
		(layer "In15.Cu")
		(net "DELTA_L_85_5INCH_IN6_DN")
	)
	(segment
		(start 326.583294 -4.664456)
		(end 326.334374 -4.308348)
		(width 0.14224)
		(layer "In15.Cu")
		(net "DELTA_L_85_5INCH_IN6_DN")
	)
	(segment
		(start 341.137494 -0.644398)
		(end 340.428834 -4.65709)
		(width 0.14224)
		(layer "In15.Cu")
		(net "DELTA_L_85_5INCH_IN6_DN")
	)
	(segment
		(start 338.70138 -0.778764)
		(end 337.337908 -0.537718)
		(width 0.14224)
		(layer "In15.Cu")
		(net "DELTA_L_85_5INCH_IN6_DN")
	)
	(segment
		(start 330.88961 -0.954024)
		(end 330.774294 -0.789178)
		(width 0.14224)
		(layer "In15.Cu")
		(net "DELTA_L_85_5INCH_IN6_DN")
	)
	(segment
		(start 360.23931 -4.674616)
		(end 359.883456 -4.92379)
		(width 0.14224)
		(layer "In15.Cu")
		(net "DELTA_L_85_5INCH_IN6_DN")
	)
	(segment
		(start 342.19642 -4.244086)
		(end 342.780874 -0.93472)
		(width 0.14224)
		(layer "In15.Cu")
		(net "DELTA_L_85_5INCH_IN6_DN")
	)
	(segment
		(start 338.816696 -0.943356)
		(end 338.70138 -0.778764)
		(width 0.14224)
		(layer "In15.Cu")
		(net "DELTA_L_85_5INCH_IN6_DN")
	)
	(segment
		(start 342.44534 -4.600194)
		(end 342.19642 -4.244086)
		(width 0.14224)
		(layer "In15.Cu")
		(net "DELTA_L_85_5INCH_IN6_DN")
	)
	(segment
		(start 347.998034 -4.908042)
		(end 346.403422 -4.626356)
		(width 0.14224)
		(layer "In15.Cu")
		(net "DELTA_L_85_5INCH_IN6_DN")
	)
	(segment
		(start 354.5459 -0.814578)
		(end 353.182428 -0.573532)
		(width 0.14224)
		(layer "In15.Cu")
		(net "DELTA_L_85_5INCH_IN6_DN")
	)
	(segment
		(start 344.395806 -4.632706)
		(end 344.039952 -4.88188)
		(width 0.14224)
		(layer "In15.Cu")
		(net "DELTA_L_85_5INCH_IN6_DN")
	)
	(segment
		(start 330.301092 -4.285742)
		(end 330.88961 -0.954024)
		(width 0.14224)
		(layer "In15.Cu")
		(net "DELTA_L_85_5INCH_IN6_DN")
	)
	(segment
		(start 342.780874 -0.93472)
		(end 342.665558 -0.770128)
		(width 0.14224)
		(layer "In15.Cu")
		(net "DELTA_L_85_5INCH_IN6_DN")
	)
	(segment
		(start 359.883456 -4.92379)
		(end 359.086404 -4.783074)
		(width 0.14224)
		(layer "In15.Cu")
		(net "DELTA_L_85_5INCH_IN6_DN")
	)
	(segment
		(start 350.362266 -4.6482)
		(end 350.113346 -4.292092)
		(width 0.14224)
		(layer "In15.Cu")
		(net "DELTA_L_85_5INCH_IN6_DN")
	)
	(segment
		(start 321.060064 -2.140966)
		(end 320.292476 -2.678176)
		(width 0.14224)
		(layer "In15.Cu")
		(net "DELTA_L_85_5INCH_IN6_DN")
	)
	(segment
		(start 354.076 -4.291838)
		(end 354.661216 -0.978916)
		(width 0.14224)
		(layer "In15.Cu")
		(net "DELTA_L_85_5INCH_IN6_DN")
	)
	(segment
		(start 332.500478 -4.674362)
		(end 332.144624 -4.923536)
		(width 0.14224)
		(layer "In15.Cu")
		(net "DELTA_L_85_5INCH_IN6_DN")
	)
	(segment
		(start 349.221806 -0.56134)
		(end 349.057214 -0.676656)
		(width 0.14224)
		(layer "In15.Cu")
		(net "DELTA_L_85_5INCH_IN6_DN")
	)
	(segment
		(start 353.182428 -0.573532)
		(end 353.017582 -0.688848)
		(width 0.14224)
		(layer "In15.Cu")
		(net "DELTA_L_85_5INCH_IN6_DN")
	)
	(segment
		(start 334.857852 -0.922782)
		(end 334.742536 -0.75819)
		(width 0.14224)
		(layer "In15.Cu")
		(net "DELTA_L_85_5INCH_IN6_DN")
	)
	(segment
		(start 324.578218 -4.656074)
		(end 324.222364 -4.905248)
		(width 0.14224)
		(layer "In15.Cu")
		(net "DELTA_L_85_5INCH_IN6_DN")
	)
	(segment
		(start 320.292476 -2.678176)
		(end 316.73419 -2.678176)
		(width 0.14224)
		(layer "In15.Cu")
		(net "DELTA_L_85_5INCH_IN6_DN")
	)
	(segment
		(start 338.478368 -4.624578)
		(end 338.229448 -4.26847)
		(width 0.14224)
		(layer "In15.Cu")
		(net "DELTA_L_85_5INCH_IN6_DN")
	)
	(segment
		(start 322.850256 -0.782066)
		(end 321.486784 -0.54102)
		(width 0.14224)
		(layer "In15.Cu")
		(net "DELTA_L_85_5INCH_IN6_DN")
	)
	(segment
		(start 321.486784 -0.54102)
		(end 321.322192 -0.656336)
		(width 0.14224)
		(layer "In15.Cu")
		(net "DELTA_L_85_5INCH_IN6_DN")
	)
	(segment
		(start 356.980744 -0.686816)
		(end 356.275386 -4.680458)
		(width 0.14224)
		(layer "In15.Cu")
		(net "DELTA_L_85_5INCH_IN6_DN")
	)
	(segment
		(start 328.53376 -4.696968)
		(end 328.177906 -4.946142)
		(width 0.14224)
		(layer "In15.Cu")
		(net "DELTA_L_85_5INCH_IN6_DN")
	)
	(segment
		(start 330.550012 -4.64185)
		(end 330.301092 -4.285742)
		(width 0.14224)
		(layer "In15.Cu")
		(net "DELTA_L_85_5INCH_IN6_DN")
	)
	(segment
		(start 354.32492 -4.647946)
		(end 354.076 -4.291838)
		(width 0.14224)
		(layer "In15.Cu")
		(net "DELTA_L_85_5INCH_IN6_DN")
	)
	(segment
		(start 359.086404 -4.783074)
		(end 358.288844 -4.642104)
		(width 0.14224)
		(layer "In15.Cu")
		(net "DELTA_L_85_5INCH_IN6_DN")
	)
	(segment
		(start 321.322192 -0.656336)
		(end 321.060064 -2.140966)
		(width 0.14224)
		(layer "In15.Cu")
		(net "DELTA_L_85_5INCH_IN6_DN")
	)
	(segment
		(start 322.965572 -0.946658)
		(end 322.850256 -0.782066)
		(width 0.14224)
		(layer "In15.Cu")
		(net "DELTA_L_85_5INCH_IN6_DN")
	)
	(segment
		(start 325.449692 -0.540004)
		(end 325.2851 -0.65532)
		(width 0.14224)
		(layer "In15.Cu")
		(net "DELTA_L_85_5INCH_IN6_DN")
	)
	(segment
		(start 358.039924 -4.285996)
		(end 358.624124 -0.977138)
		(width 0.14224)
		(layer "In15.Cu")
		(net "DELTA_L_85_5INCH_IN6_DN")
	)
	(segment
		(start 346.738194 -0.966724)
		(end 346.622878 -0.802132)
		(width 0.14224)
		(layer "In15.Cu")
		(net "DELTA_L_85_5INCH_IN6_DN")
	)
	(segment
		(start 337.173316 -0.653034)
		(end 336.462116 -4.67995)
		(width 0.14224)
		(layer "In15.Cu")
		(net "DELTA_L_85_5INCH_IN6_DN")
	)
	(segment
		(start 326.334374 -4.308348)
		(end 326.92848 -0.945642)
		(width 0.14224)
		(layer "In15.Cu")
		(net "DELTA_L_85_5INCH_IN6_DN")
	)
	(segment
		(start 315.791088 7.87273)
		(end 316.44336 8.054594)
		(width 0.12954)
		(layer "B.Cu")
		(net "DELTA_L_85_5INCH_IN5_DP")
	)
	(segment
		(start 365.463074 7.87273)
		(end 364.810802 8.054594)
		(width 0.12954)
		(layer "B.Cu")
		(net "DELTA_L_85_5INCH_IN5_DP")
	)
	(segment
		(start 347.03639 9.259316)
		(end 346.452698 5.955792)
		(width 0.14224)
		(layer "In13.Cu")
		(net "DELTA_L_85_5INCH_IN5_DP")
	)
	(segment
		(start 332.242922 5.649722)
		(end 332.956916 9.691624)
		(width 0.14224)
		(layer "In13.Cu")
		(net "DELTA_L_85_5INCH_IN5_DP")
	)
	(segment
		(start 316.73419 7.763764)
		(end 320.203576 7.763764)
		(width 0.14224)
		(layer "In13.Cu")
		(net "DELTA_L_85_5INCH_IN5_DP")
	)
	(segment
		(start 341.236046 9.929114)
		(end 342.829642 9.647428)
		(width 0.14224)
		(layer "In13.Cu")
		(net "DELTA_L_85_5INCH_IN5_DP")
	)
	(segment
		(start 326.747632 5.7531)
		(end 328.111866 5.512054)
		(width 0.14224)
		(layer "In13.Cu")
		(net "DELTA_L_85_5INCH_IN5_DP")
	)
	(segment
		(start 332.956916 9.691624)
		(end 333.313024 9.941052)
		(width 0.14224)
		(layer "In13.Cu")
		(net "DELTA_L_85_5INCH_IN5_DP")
	)
	(segment
		(start 350.526604 5.769356)
		(end 351.890838 5.52831)
		(width 0.14224)
		(layer "In13.Cu")
		(net "DELTA_L_85_5INCH_IN5_DP")
	)
	(segment
		(start 326.977248 9.636506)
		(end 327.226676 9.280398)
		(width 0.14224)
		(layer "In13.Cu")
		(net "DELTA_L_85_5INCH_IN5_DP")
	)
	(segment
		(start 348.799658 9.647428)
		(end 349.155766 9.896856)
		(width 0.14224)
		(layer "In13.Cu")
		(net "DELTA_L_85_5INCH_IN5_DP")
	)
	(segment
		(start 323.263768 9.279382)
		(end 322.677028 5.958586)
		(width 0.14224)
		(layer "In13.Cu")
		(net "DELTA_L_85_5INCH_IN5_DP")
	)
	(segment
		(start 342.494616 5.981954)
		(end 342.609678 5.817362)
		(width 0.14224)
		(layer "In13.Cu")
		(net "DELTA_L_85_5INCH_IN5_DP")
	)
	(segment
		(start 359.981754 5.649468)
		(end 360.249216 7.163816)
		(width 0.14224)
		(layer "In13.Cu")
		(net "DELTA_L_85_5INCH_IN5_DP")
	)
	(segment
		(start 346.452698 5.955792)
		(end 346.56776 5.7912)
		(width 0.14224)
		(layer "In13.Cu")
		(net "DELTA_L_85_5INCH_IN5_DP")
	)
	(segment
		(start 339.114892 9.282684)
		(end 338.527644 5.95757)
		(width 0.14224)
		(layer "In13.Cu")
		(net "DELTA_L_85_5INCH_IN5_DP")
	)
	(segment
		(start 353.116388 9.884664)
		(end 354.709984 9.602978)
		(width 0.14224)
		(layer "In13.Cu")
		(net "DELTA_L_85_5INCH_IN5_DP")
	)
	(segment
		(start 330.71435 5.775706)
		(end 332.078584 5.53466)
		(width 0.14224)
		(layer "In13.Cu")
		(net "DELTA_L_85_5INCH_IN5_DP")
	)
	(segment
		(start 324.320662 5.66801)
		(end 325.027544 9.668764)
		(width 0.14224)
		(layer "In13.Cu")
		(net "DELTA_L_85_5INCH_IN5_DP")
	)
	(segment
		(start 336.20456 5.644134)
		(end 336.91576 9.67105)
		(width 0.14224)
		(layer "In13.Cu")
		(net "DELTA_L_85_5INCH_IN5_DP")
	)
	(segment
		(start 348.096332 5.665216)
		(end 348.799658 9.647428)
		(width 0.14224)
		(layer "In13.Cu")
		(net "DELTA_L_85_5INCH_IN5_DP")
	)
	(segment
		(start 320.802508 8.183118)
		(end 321.064636 9.667748)
		(width 0.14224)
		(layer "In13.Cu")
		(net "DELTA_L_85_5INCH_IN5_DP")
	)
	(segment
		(start 346.786962 9.615424)
		(end 347.03639 9.259316)
		(width 0.14224)
		(layer "In13.Cu")
		(net "DELTA_L_85_5INCH_IN5_DP")
	)
	(segment
		(start 342.829642 9.647428)
		(end 343.07907 9.29132)
		(width 0.14224)
		(layer "In13.Cu")
		(net "DELTA_L_85_5INCH_IN5_DP")
	)
	(segment
		(start 364.519972 7.763764)
		(end 364.810802 8.054594)
		(width 0.14224)
		(layer "In13.Cu")
		(net "DELTA_L_85_5INCH_IN5_DP")
	)
	(segment
		(start 325.027544 9.668764)
		(end 325.383652 9.918192)
		(width 0.14224)
		(layer "In13.Cu")
		(net "DELTA_L_85_5INCH_IN5_DP")
	)
	(segment
		(start 354.709984 9.602978)
		(end 354.959412 9.247378)
		(width 0.14224)
		(layer "In13.Cu")
		(net "DELTA_L_85_5INCH_IN5_DP")
	)
	(segment
		(start 358.92232 9.248902)
		(end 358.33812 5.940044)
		(width 0.14224)
		(layer "In13.Cu")
		(net "DELTA_L_85_5INCH_IN5_DP")
	)
	(segment
		(start 332.078584 5.53466)
		(end 332.242922 5.649722)
		(width 0.14224)
		(layer "In13.Cu")
		(net "DELTA_L_85_5INCH_IN5_DP")
	)
	(segment
		(start 330.938632 9.628378)
		(end 331.187806 9.272016)
		(width 0.14224)
		(layer "In13.Cu")
		(net "DELTA_L_85_5INCH_IN5_DP")
	)
	(segment
		(start 352.055176 5.643372)
		(end 352.760026 9.635236)
		(width 0.14224)
		(layer "In13.Cu")
		(net "DELTA_L_85_5INCH_IN5_DP")
	)
	(segment
		(start 328.111866 5.512054)
		(end 328.276204 5.627116)
		(width 0.14224)
		(layer "In13.Cu")
		(net "DELTA_L_85_5INCH_IN5_DP")
	)
	(segment
		(start 344.13825 5.691378)
		(end 344.837258 9.647682)
		(width 0.14224)
		(layer "In13.Cu")
		(net "DELTA_L_85_5INCH_IN5_DP")
	)
	(segment
		(start 328.988928 9.660636)
		(end 329.344528 9.910064)
		(width 0.14224)
		(layer "In13.Cu")
		(net "DELTA_L_85_5INCH_IN5_DP")
	)
	(segment
		(start 358.672892 9.60501)
		(end 358.92232 9.248902)
		(width 0.14224)
		(layer "In13.Cu")
		(net "DELTA_L_85_5INCH_IN5_DP")
	)
	(segment
		(start 340.171278 5.666994)
		(end 340.879938 9.679686)
		(width 0.14224)
		(layer "In13.Cu")
		(net "DELTA_L_85_5INCH_IN5_DP")
	)
	(segment
		(start 335.156048 9.303258)
		(end 334.560926 5.934964)
		(width 0.14224)
		(layer "In13.Cu")
		(net "DELTA_L_85_5INCH_IN5_DP")
	)
	(segment
		(start 321.064636 9.667748)
		(end 321.420744 9.917176)
		(width 0.14224)
		(layer "In13.Cu")
		(net "DELTA_L_85_5INCH_IN5_DP")
	)
	(segment
		(start 327.226676 9.280398)
		(end 326.63257 5.917946)
		(width 0.14224)
		(layer "In13.Cu")
		(net "DELTA_L_85_5INCH_IN5_DP")
	)
	(segment
		(start 355.853492 5.528564)
		(end 356.01783 5.643626)
		(width 0.14224)
		(layer "In13.Cu")
		(net "DELTA_L_85_5INCH_IN5_DP")
	)
	(segment
		(start 334.675988 5.770118)
		(end 336.040222 5.529072)
		(width 0.14224)
		(layer "In13.Cu")
		(net "DELTA_L_85_5INCH_IN5_DP")
	)
	(segment
		(start 354.489258 5.76961)
		(end 355.853492 5.528564)
		(width 0.14224)
		(layer "In13.Cu")
		(net "DELTA_L_85_5INCH_IN5_DP")
	)
	(segment
		(start 361.103672 7.763764)
		(end 364.519972 7.763764)
		(width 0.14224)
		(layer "In13.Cu")
		(net "DELTA_L_85_5INCH_IN5_DP")
	)
	(segment
		(start 334.560926 5.934964)
		(end 334.675988 5.770118)
		(width 0.14224)
		(layer "In13.Cu")
		(net "DELTA_L_85_5INCH_IN5_DP")
	)
	(segment
		(start 324.156324 5.552948)
		(end 324.320662 5.66801)
		(width 0.14224)
		(layer "In13.Cu")
		(net "DELTA_L_85_5INCH_IN5_DP")
	)
	(segment
		(start 323.01434 9.63549)
		(end 323.263768 9.279382)
		(width 0.14224)
		(layer "In13.Cu")
		(net "DELTA_L_85_5INCH_IN5_DP")
	)
	(segment
		(start 316.44336 8.054594)
		(end 316.73419 7.763764)
		(width 0.14224)
		(layer "In13.Cu")
		(net "DELTA_L_85_5INCH_IN5_DP")
	)
	(segment
		(start 350.411542 5.933948)
		(end 350.526604 5.769356)
		(width 0.14224)
		(layer "In13.Cu")
		(net "DELTA_L_85_5INCH_IN5_DP")
	)
	(segment
		(start 352.760026 9.635236)
		(end 353.116388 9.884664)
		(width 0.14224)
		(layer "In13.Cu")
		(net "DELTA_L_85_5INCH_IN5_DP")
	)
	(segment
		(start 345.193366 9.89711)
		(end 346.786962 9.615424)
		(width 0.14224)
		(layer "In13.Cu")
		(net "DELTA_L_85_5INCH_IN5_DP")
	)
	(segment
		(start 340.879938 9.679686)
		(end 341.236046 9.929114)
		(width 0.14224)
		(layer "In13.Cu")
		(net "DELTA_L_85_5INCH_IN5_DP")
	)
	(segment
		(start 347.931994 5.550154)
		(end 348.096332 5.665216)
		(width 0.14224)
		(layer "In13.Cu")
		(net "DELTA_L_85_5INCH_IN5_DP")
	)
	(segment
		(start 354.959412 9.247378)
		(end 354.374196 5.934202)
		(width 0.14224)
		(layer "In13.Cu")
		(net "DELTA_L_85_5INCH_IN5_DP")
	)
	(segment
		(start 351.890838 5.52831)
		(end 352.055176 5.643372)
		(width 0.14224)
		(layer "In13.Cu")
		(net "DELTA_L_85_5INCH_IN5_DP")
	)
	(segment
		(start 342.609678 5.817362)
		(end 343.973912 5.576316)
		(width 0.14224)
		(layer "In13.Cu")
		(net "DELTA_L_85_5INCH_IN5_DP")
	)
	(segment
		(start 340.00694 5.551932)
		(end 340.171278 5.666994)
		(width 0.14224)
		(layer "In13.Cu")
		(net "DELTA_L_85_5INCH_IN5_DP")
	)
	(segment
		(start 360.249216 7.163816)
		(end 361.103672 7.763764)
		(width 0.14224)
		(layer "In13.Cu")
		(net "DELTA_L_85_5INCH_IN5_DP")
	)
	(segment
		(start 338.865464 9.638792)
		(end 339.114892 9.282684)
		(width 0.14224)
		(layer "In13.Cu")
		(net "DELTA_L_85_5INCH_IN5_DP")
	)
	(segment
		(start 349.155766 9.896856)
		(end 350.749362 9.614916)
		(width 0.14224)
		(layer "In13.Cu")
		(net "DELTA_L_85_5INCH_IN5_DP")
	)
	(segment
		(start 331.187806 9.272016)
		(end 330.599288 5.940552)
		(width 0.14224)
		(layer "In13.Cu")
		(net "DELTA_L_85_5INCH_IN5_DP")
	)
	(segment
		(start 330.599288 5.940552)
		(end 330.71435 5.775706)
		(width 0.14224)
		(layer "In13.Cu")
		(net "DELTA_L_85_5INCH_IN5_DP")
	)
	(segment
		(start 357.079296 9.886696)
		(end 358.672892 9.60501)
		(width 0.14224)
		(layer "In13.Cu")
		(net "DELTA_L_85_5INCH_IN5_DP")
	)
	(segment
		(start 354.374196 5.934202)
		(end 354.489258 5.76961)
		(width 0.14224)
		(layer "In13.Cu")
		(net "DELTA_L_85_5INCH_IN5_DP")
	)
	(segment
		(start 358.33812 5.940044)
		(end 358.453182 5.775452)
		(width 0.14224)
		(layer "In13.Cu")
		(net "DELTA_L_85_5INCH_IN5_DP")
	)
	(segment
		(start 322.79209 5.793994)
		(end 324.156324 5.552948)
		(width 0.14224)
		(layer "In13.Cu")
		(net "DELTA_L_85_5INCH_IN5_DP")
	)
	(segment
		(start 322.677028 5.958586)
		(end 322.79209 5.793994)
		(width 0.14224)
		(layer "In13.Cu")
		(net "DELTA_L_85_5INCH_IN5_DP")
	)
	(segment
		(start 334.90662 9.659366)
		(end 335.156048 9.303258)
		(width 0.14224)
		(layer "In13.Cu")
		(net "DELTA_L_85_5INCH_IN5_DP")
	)
	(segment
		(start 344.837258 9.647682)
		(end 345.193366 9.89711)
		(width 0.14224)
		(layer "In13.Cu")
		(net "DELTA_L_85_5INCH_IN5_DP")
	)
	(segment
		(start 329.344528 9.910064)
		(end 330.938632 9.628378)
		(width 0.14224)
		(layer "In13.Cu")
		(net "DELTA_L_85_5INCH_IN5_DP")
	)
	(segment
		(start 326.63257 5.917946)
		(end 326.747632 5.7531)
		(width 0.14224)
		(layer "In13.Cu")
		(net "DELTA_L_85_5INCH_IN5_DP")
	)
	(segment
		(start 350.749362 9.614916)
		(end 350.99879 9.259062)
		(width 0.14224)
		(layer "In13.Cu")
		(net "DELTA_L_85_5INCH_IN5_DP")
	)
	(segment
		(start 356.01783 5.643626)
		(end 356.723188 9.637268)
		(width 0.14224)
		(layer "In13.Cu")
		(net "DELTA_L_85_5INCH_IN5_DP")
	)
	(segment
		(start 325.383652 9.918192)
		(end 326.977248 9.636506)
		(width 0.14224)
		(layer "In13.Cu")
		(net "DELTA_L_85_5INCH_IN5_DP")
	)
	(segment
		(start 343.973912 5.576316)
		(end 344.13825 5.691378)
		(width 0.14224)
		(layer "In13.Cu")
		(net "DELTA_L_85_5INCH_IN5_DP")
	)
	(segment
		(start 337.271868 9.920478)
		(end 338.865464 9.638792)
		(width 0.14224)
		(layer "In13.Cu")
		(net "DELTA_L_85_5INCH_IN5_DP")
	)
	(segment
		(start 338.527644 5.95757)
		(end 338.642706 5.792978)
		(width 0.14224)
		(layer "In13.Cu")
		(net "DELTA_L_85_5INCH_IN5_DP")
	)
	(segment
		(start 350.99879 9.259062)
		(end 350.411542 5.933948)
		(width 0.14224)
		(layer "In13.Cu")
		(net "DELTA_L_85_5INCH_IN5_DP")
	)
	(segment
		(start 333.313024 9.941052)
		(end 334.90662 9.659366)
		(width 0.14224)
		(layer "In13.Cu")
		(net "DELTA_L_85_5INCH_IN5_DP")
	)
	(segment
		(start 358.453182 5.775452)
		(end 359.817416 5.534406)
		(width 0.14224)
		(layer "In13.Cu")
		(net "DELTA_L_85_5INCH_IN5_DP")
	)
	(segment
		(start 343.07907 9.29132)
		(end 342.494616 5.981954)
		(width 0.14224)
		(layer "In13.Cu")
		(net "DELTA_L_85_5INCH_IN5_DP")
	)
	(segment
		(start 336.040222 5.529072)
		(end 336.20456 5.644134)
		(width 0.14224)
		(layer "In13.Cu")
		(net "DELTA_L_85_5INCH_IN5_DP")
	)
	(segment
		(start 321.420744 9.917176)
		(end 323.01434 9.63549)
		(width 0.14224)
		(layer "In13.Cu")
		(net "DELTA_L_85_5INCH_IN5_DP")
	)
	(segment
		(start 338.642706 5.792978)
		(end 340.00694 5.551932)
		(width 0.14224)
		(layer "In13.Cu")
		(net "DELTA_L_85_5INCH_IN5_DP")
	)
	(segment
		(start 356.723188 9.637268)
		(end 357.079296 9.886696)
		(width 0.14224)
		(layer "In13.Cu")
		(net "DELTA_L_85_5INCH_IN5_DP")
	)
	(segment
		(start 346.56776 5.7912)
		(end 347.931994 5.550154)
		(width 0.14224)
		(layer "In13.Cu")
		(net "DELTA_L_85_5INCH_IN5_DP")
	)
	(segment
		(start 328.276204 5.627116)
		(end 328.988928 9.660636)
		(width 0.14224)
		(layer "In13.Cu")
		(net "DELTA_L_85_5INCH_IN5_DP")
	)
	(segment
		(start 359.817416 5.534406)
		(end 359.981754 5.649468)
		(width 0.14224)
		(layer "In13.Cu")
		(net "DELTA_L_85_5INCH_IN5_DP")
	)
	(segment
		(start 336.91576 9.67105)
		(end 337.271868 9.920478)
		(width 0.14224)
		(layer "In13.Cu")
		(net "DELTA_L_85_5INCH_IN5_DP")
	)
	(segment
		(start 320.203576 7.763764)
		(end 320.802508 8.183118)
		(width 0.14224)
		(layer "In13.Cu")
		(net "DELTA_L_85_5INCH_IN5_DP")
	)
	(segment
		(start 365.463074 7.372858)
		(end 364.810802 7.190994)
		(width 0.12954)
		(layer "B.Cu")
		(net "DELTA_L_85_5INCH_IN5_DN")
	)
	(segment
		(start 315.791088 7.372858)
		(end 316.44336 7.190994)
		(width 0.12954)
		(layer "B.Cu")
		(net "DELTA_L_85_5INCH_IN5_DN")
	)
	(segment
		(start 348.353888 5.501132)
		(end 347.998034 5.251958)
		(width 0.14224)
		(layer "In13.Cu")
		(net "DELTA_L_85_5INCH_IN5_DN")
	)
	(segment
		(start 329.246484 9.496552)
		(end 328.53376 5.463032)
		(width 0.14224)
		(layer "In13.Cu")
		(net "DELTA_L_85_5INCH_IN5_DN")
	)
	(segment
		(start 337.337908 9.622282)
		(end 337.173316 9.506966)
		(width 0.14224)
		(layer "In13.Cu")
		(net "DELTA_L_85_5INCH_IN5_DN")
	)
	(segment
		(start 357.145336 9.5885)
		(end 356.980744 9.473184)
		(width 0.14224)
		(layer "In13.Cu")
		(net "DELTA_L_85_5INCH_IN5_DN")
	)
	(segment
		(start 364.810802 7.190994)
		(end 364.519972 7.481824)
		(width 0.14224)
		(layer "In13.Cu")
		(net "DELTA_L_85_5INCH_IN5_DN")
	)
	(segment
		(start 358.288844 5.517896)
		(end 358.039924 5.874004)
		(width 0.14224)
		(layer "In13.Cu")
		(net "DELTA_L_85_5INCH_IN5_DN")
	)
	(segment
		(start 328.177906 5.213858)
		(end 326.583294 5.495544)
		(width 0.14224)
		(layer "In13.Cu")
		(net "DELTA_L_85_5INCH_IN5_DN")
	)
	(segment
		(start 364.519972 7.481824)
		(end 361.192826 7.481824)
		(width 0.14224)
		(layer "In13.Cu")
		(net "DELTA_L_85_5INCH_IN5_DN")
	)
	(segment
		(start 342.44534 5.559806)
		(end 342.19642 5.915914)
		(width 0.14224)
		(layer "In13.Cu")
		(net "DELTA_L_85_5INCH_IN5_DN")
	)
	(segment
		(start 340.428834 5.50291)
		(end 340.07298 5.253736)
		(width 0.14224)
		(layer "In13.Cu")
		(net "DELTA_L_85_5INCH_IN5_DN")
	)
	(segment
		(start 334.26273 5.86867)
		(end 334.857852 9.237218)
		(width 0.14224)
		(layer "In13.Cu")
		(net "DELTA_L_85_5INCH_IN5_DN")
	)
	(segment
		(start 330.301092 5.874258)
		(end 330.88961 9.205976)
		(width 0.14224)
		(layer "In13.Cu")
		(net "DELTA_L_85_5INCH_IN5_DN")
	)
	(segment
		(start 324.578218 5.503926)
		(end 324.222364 5.254752)
		(width 0.14224)
		(layer "In13.Cu")
		(net "DELTA_L_85_5INCH_IN5_DN")
	)
	(segment
		(start 358.039924 5.874004)
		(end 358.624124 9.182862)
		(width 0.14224)
		(layer "In13.Cu")
		(net "DELTA_L_85_5INCH_IN5_DN")
	)
	(segment
		(start 356.275386 5.479542)
		(end 355.919532 5.230368)
		(width 0.14224)
		(layer "In13.Cu")
		(net "DELTA_L_85_5INCH_IN5_DN")
	)
	(segment
		(start 345.259406 9.598914)
		(end 345.094814 9.483598)
		(width 0.14224)
		(layer "In13.Cu")
		(net "DELTA_L_85_5INCH_IN5_DN")
	)
	(segment
		(start 325.449692 9.619996)
		(end 325.2851 9.50468)
		(width 0.14224)
		(layer "In13.Cu")
		(net "DELTA_L_85_5INCH_IN5_DN")
	)
	(segment
		(start 353.017582 9.471152)
		(end 352.312732 5.479288)
		(width 0.14224)
		(layer "In13.Cu")
		(net "DELTA_L_85_5INCH_IN5_DN")
	)
	(segment
		(start 344.395806 5.527294)
		(end 344.039952 5.27812)
		(width 0.14224)
		(layer "In13.Cu")
		(net "DELTA_L_85_5INCH_IN5_DN")
	)
	(segment
		(start 332.144624 5.236464)
		(end 330.550012 5.51815)
		(width 0.14224)
		(layer "In13.Cu")
		(net "DELTA_L_85_5INCH_IN5_DN")
	)
	(segment
		(start 355.919532 5.230368)
		(end 354.32492 5.512054)
		(width 0.14224)
		(layer "In13.Cu")
		(net "DELTA_L_85_5INCH_IN5_DN")
	)
	(segment
		(start 346.622878 9.357868)
		(end 345.259406 9.598914)
		(width 0.14224)
		(layer "In13.Cu")
		(net "DELTA_L_85_5INCH_IN5_DN")
	)
	(segment
		(start 322.965572 9.213342)
		(end 322.850256 9.377934)
		(width 0.14224)
		(layer "In13.Cu")
		(net "DELTA_L_85_5INCH_IN5_DN")
	)
	(segment
		(start 360.506772 6.999986)
		(end 360.23931 5.485384)
		(width 0.14224)
		(layer "In13.Cu")
		(net "DELTA_L_85_5INCH_IN5_DN")
	)
	(segment
		(start 346.154502 5.889752)
		(end 346.738194 9.193276)
		(width 0.14224)
		(layer "In13.Cu")
		(net "DELTA_L_85_5INCH_IN5_DN")
	)
	(segment
		(start 328.53376 5.463032)
		(end 328.177906 5.213858)
		(width 0.14224)
		(layer "In13.Cu")
		(net "DELTA_L_85_5INCH_IN5_DN")
	)
	(segment
		(start 347.998034 5.251958)
		(end 346.403422 5.533644)
		(width 0.14224)
		(layer "In13.Cu")
		(net "DELTA_L_85_5INCH_IN5_DN")
	)
	(segment
		(start 321.060064 8.019034)
		(end 320.292476 7.481824)
		(width 0.14224)
		(layer "In13.Cu")
		(net "DELTA_L_85_5INCH_IN5_DN")
	)
	(segment
		(start 334.51165 5.512562)
		(end 334.26273 5.86867)
		(width 0.14224)
		(layer "In13.Cu")
		(net "DELTA_L_85_5INCH_IN5_DN")
	)
	(segment
		(start 350.113346 5.867908)
		(end 350.700594 9.193022)
		(width 0.14224)
		(layer "In13.Cu")
		(net "DELTA_L_85_5INCH_IN5_DN")
	)
	(segment
		(start 320.292476 7.481824)
		(end 316.73419 7.481824)
		(width 0.14224)
		(layer "In13.Cu")
		(net "DELTA_L_85_5INCH_IN5_DN")
	)
	(segment
		(start 340.07298 5.253736)
		(end 338.478368 5.535422)
		(width 0.14224)
		(layer "In13.Cu")
		(net "DELTA_L_85_5INCH_IN5_DN")
	)
	(segment
		(start 359.883456 5.23621)
		(end 359.086404 5.376926)
		(width 0.14224)
		(layer "In13.Cu")
		(net "DELTA_L_85_5INCH_IN5_DN")
	)
	(segment
		(start 349.057214 9.483344)
		(end 348.353888 5.501132)
		(width 0.14224)
		(layer "In13.Cu")
		(net "DELTA_L_85_5INCH_IN5_DN")
	)
	(segment
		(start 334.742536 9.40181)
		(end 333.379064 9.642856)
		(width 0.14224)
		(layer "In13.Cu")
		(net "DELTA_L_85_5INCH_IN5_DN")
	)
	(segment
		(start 354.661216 9.181084)
		(end 354.5459 9.345422)
		(width 0.14224)
		(layer "In13.Cu")
		(net "DELTA_L_85_5INCH_IN5_DN")
	)
	(segment
		(start 322.378832 5.892546)
		(end 322.965572 9.213342)
		(width 0.14224)
		(layer "In13.Cu")
		(net "DELTA_L_85_5INCH_IN5_DN")
	)
	(segment
		(start 322.627752 5.536438)
		(end 322.378832 5.892546)
		(width 0.14224)
		(layer "In13.Cu")
		(net "DELTA_L_85_5INCH_IN5_DN")
	)
	(segment
		(start 361.192826 7.481824)
		(end 360.506772 6.999986)
		(width 0.14224)
		(layer "In13.Cu")
		(net "DELTA_L_85_5INCH_IN5_DN")
	)
	(segment
		(start 324.222364 5.254752)
		(end 322.627752 5.536438)
		(width 0.14224)
		(layer "In13.Cu")
		(net "DELTA_L_85_5INCH_IN5_DN")
	)
	(segment
		(start 360.23931 5.485384)
		(end 359.883456 5.23621)
		(width 0.14224)
		(layer "In13.Cu")
		(net "DELTA_L_85_5INCH_IN5_DN")
	)
	(segment
		(start 341.302086 9.630918)
		(end 341.137494 9.515602)
		(width 0.14224)
		(layer "In13.Cu")
		(net "DELTA_L_85_5INCH_IN5_DN")
	)
	(segment
		(start 337.173316 9.506966)
		(end 336.462116 5.48005)
		(width 0.14224)
		(layer "In13.Cu")
		(net "DELTA_L_85_5INCH_IN5_DN")
	)
	(segment
		(start 338.70138 9.381236)
		(end 337.337908 9.622282)
		(width 0.14224)
		(layer "In13.Cu")
		(net "DELTA_L_85_5INCH_IN5_DN")
	)
	(segment
		(start 358.508808 9.347454)
		(end 357.145336 9.5885)
		(width 0.14224)
		(layer "In13.Cu")
		(net "DELTA_L_85_5INCH_IN5_DN")
	)
	(segment
		(start 350.362266 5.5118)
		(end 350.113346 5.867908)
		(width 0.14224)
		(layer "In13.Cu")
		(net "DELTA_L_85_5INCH_IN5_DN")
	)
	(segment
		(start 342.19642 5.915914)
		(end 342.780874 9.22528)
		(width 0.14224)
		(layer "In13.Cu")
		(net "DELTA_L_85_5INCH_IN5_DN")
	)
	(segment
		(start 321.486784 9.61898)
		(end 321.322192 9.503664)
		(width 0.14224)
		(layer "In13.Cu")
		(net "DELTA_L_85_5INCH_IN5_DN")
	)
	(segment
		(start 333.379064 9.642856)
		(end 333.214472 9.52754)
		(width 0.14224)
		(layer "In13.Cu")
		(net "DELTA_L_85_5INCH_IN5_DN")
	)
	(segment
		(start 326.92848 9.214358)
		(end 326.813164 9.37895)
		(width 0.14224)
		(layer "In13.Cu")
		(net "DELTA_L_85_5INCH_IN5_DN")
	)
	(segment
		(start 358.624124 9.182862)
		(end 358.508808 9.347454)
		(width 0.14224)
		(layer "In13.Cu")
		(net "DELTA_L_85_5INCH_IN5_DN")
	)
	(segment
		(start 350.585278 9.35736)
		(end 349.221806 9.59866)
		(width 0.14224)
		(layer "In13.Cu")
		(net "DELTA_L_85_5INCH_IN5_DN")
	)
	(segment
		(start 326.813164 9.37895)
		(end 325.449692 9.619996)
		(width 0.14224)
		(layer "In13.Cu")
		(net "DELTA_L_85_5INCH_IN5_DN")
	)
	(segment
		(start 332.500478 5.485638)
		(end 332.144624 5.236464)
		(width 0.14224)
		(layer "In13.Cu")
		(net "DELTA_L_85_5INCH_IN5_DN")
	)
	(segment
		(start 346.403422 5.533644)
		(end 346.154502 5.889752)
		(width 0.14224)
		(layer "In13.Cu")
		(net "DELTA_L_85_5INCH_IN5_DN")
	)
	(segment
		(start 336.106262 5.230876)
		(end 334.51165 5.512562)
		(width 0.14224)
		(layer "In13.Cu")
		(net "DELTA_L_85_5INCH_IN5_DN")
	)
	(segment
		(start 342.780874 9.22528)
		(end 342.665558 9.389872)
		(width 0.14224)
		(layer "In13.Cu")
		(net "DELTA_L_85_5INCH_IN5_DN")
	)
	(segment
		(start 353.182428 9.586468)
		(end 353.017582 9.471152)
		(width 0.14224)
		(layer "In13.Cu")
		(net "DELTA_L_85_5INCH_IN5_DN")
	)
	(segment
		(start 342.665558 9.389872)
		(end 341.302086 9.630918)
		(width 0.14224)
		(layer "In13.Cu")
		(net "DELTA_L_85_5INCH_IN5_DN")
	)
	(segment
		(start 330.774294 9.370822)
		(end 329.410822 9.611868)
		(width 0.14224)
		(layer "In13.Cu")
		(net "DELTA_L_85_5INCH_IN5_DN")
	)
	(segment
		(start 341.137494 9.515602)
		(end 340.428834 5.50291)
		(width 0.14224)
		(layer "In13.Cu")
		(net "DELTA_L_85_5INCH_IN5_DN")
	)
	(segment
		(start 326.583294 5.495544)
		(end 326.334374 5.851652)
		(width 0.14224)
		(layer "In13.Cu")
		(net "DELTA_L_85_5INCH_IN5_DN")
	)
	(segment
		(start 334.857852 9.237218)
		(end 334.742536 9.40181)
		(width 0.14224)
		(layer "In13.Cu")
		(net "DELTA_L_85_5INCH_IN5_DN")
	)
	(segment
		(start 356.980744 9.473184)
		(end 356.275386 5.479542)
		(width 0.14224)
		(layer "In13.Cu")
		(net "DELTA_L_85_5INCH_IN5_DN")
	)
	(segment
		(start 336.462116 5.48005)
		(end 336.106262 5.230876)
		(width 0.14224)
		(layer "In13.Cu")
		(net "DELTA_L_85_5INCH_IN5_DN")
	)
	(segment
		(start 321.322192 9.503664)
		(end 321.060064 8.019034)
		(width 0.14224)
		(layer "In13.Cu")
		(net "DELTA_L_85_5INCH_IN5_DN")
	)
	(segment
		(start 350.700594 9.193022)
		(end 350.585278 9.35736)
		(width 0.14224)
		(layer "In13.Cu")
		(net "DELTA_L_85_5INCH_IN5_DN")
	)
	(segment
		(start 354.32492 5.512054)
		(end 354.076 5.868162)
		(width 0.14224)
		(layer "In13.Cu")
		(net "DELTA_L_85_5INCH_IN5_DN")
	)
	(segment
		(start 330.88961 9.205976)
		(end 330.774294 9.370822)
		(width 0.14224)
		(layer "In13.Cu")
		(net "DELTA_L_85_5INCH_IN5_DN")
	)
	(segment
		(start 359.086404 5.376926)
		(end 358.288844 5.517896)
		(width 0.14224)
		(layer "In13.Cu")
		(net "DELTA_L_85_5INCH_IN5_DN")
	)
	(segment
		(start 344.039952 5.27812)
		(end 342.44534 5.559806)
		(width 0.14224)
		(layer "In13.Cu")
		(net "DELTA_L_85_5INCH_IN5_DN")
	)
	(segment
		(start 322.850256 9.377934)
		(end 321.486784 9.61898)
		(width 0.14224)
		(layer "In13.Cu")
		(net "DELTA_L_85_5INCH_IN5_DN")
	)
	(segment
		(start 349.221806 9.59866)
		(end 349.057214 9.483344)
		(width 0.14224)
		(layer "In13.Cu")
		(net "DELTA_L_85_5INCH_IN5_DN")
	)
	(segment
		(start 354.076 5.868162)
		(end 354.661216 9.181084)
		(width 0.14224)
		(layer "In13.Cu")
		(net "DELTA_L_85_5INCH_IN5_DN")
	)
	(segment
		(start 351.956878 5.230114)
		(end 350.362266 5.5118)
		(width 0.14224)
		(layer "In13.Cu")
		(net "DELTA_L_85_5INCH_IN5_DN")
	)
	(segment
		(start 325.2851 9.50468)
		(end 324.578218 5.503926)
		(width 0.14224)
		(layer "In13.Cu")
		(net "DELTA_L_85_5INCH_IN5_DN")
	)
	(segment
		(start 346.738194 9.193276)
		(end 346.622878 9.357868)
		(width 0.14224)
		(layer "In13.Cu")
		(net "DELTA_L_85_5INCH_IN5_DN")
	)
	(segment
		(start 354.5459 9.345422)
		(end 353.182428 9.586468)
		(width 0.14224)
		(layer "In13.Cu")
		(net "DELTA_L_85_5INCH_IN5_DN")
	)
	(segment
		(start 333.214472 9.52754)
		(end 332.500478 5.485638)
		(width 0.14224)
		(layer "In13.Cu")
		(net "DELTA_L_85_5INCH_IN5_DN")
	)
	(segment
		(start 338.478368 5.535422)
		(end 338.229448 5.89153)
		(width 0.14224)
		(layer "In13.Cu")
		(net "DELTA_L_85_5INCH_IN5_DN")
	)
	(segment
		(start 330.550012 5.51815)
		(end 330.301092 5.874258)
		(width 0.14224)
		(layer "In13.Cu")
		(net "DELTA_L_85_5INCH_IN5_DN")
	)
	(segment
		(start 316.73419 7.481824)
		(end 316.44336 7.190994)
		(width 0.14224)
		(layer "In13.Cu")
		(net "DELTA_L_85_5INCH_IN5_DN")
	)
	(segment
		(start 329.410822 9.611868)
		(end 329.246484 9.496552)
		(width 0.14224)
		(layer "In13.Cu")
		(net "DELTA_L_85_5INCH_IN5_DN")
	)
	(segment
		(start 345.094814 9.483598)
		(end 344.395806 5.527294)
		(width 0.14224)
		(layer "In13.Cu")
		(net "DELTA_L_85_5INCH_IN5_DN")
	)
	(segment
		(start 326.334374 5.851652)
		(end 326.92848 9.214358)
		(width 0.14224)
		(layer "In13.Cu")
		(net "DELTA_L_85_5INCH_IN5_DN")
	)
	(segment
		(start 338.816696 9.216644)
		(end 338.70138 9.381236)
		(width 0.14224)
		(layer "In13.Cu")
		(net "DELTA_L_85_5INCH_IN5_DN")
	)
	(segment
		(start 352.312732 5.479288)
		(end 351.956878 5.230114)
		(width 0.14224)
		(layer "In13.Cu")
		(net "DELTA_L_85_5INCH_IN5_DN")
	)
	(segment
		(start 338.229448 5.89153)
		(end 338.816696 9.216644)
		(width 0.14224)
		(layer "In13.Cu")
		(net "DELTA_L_85_5INCH_IN5_DN")
	)
	(segment
		(start 439.95975 8.439912)
		(end 439.307478 8.258048)
		(width 0.12954)
		(layer "B.Cu")
		(net "DELTA_L_85_5INCH_IN4_DP")
	)
	(segment
		(start 390.287764 8.439912)
		(end 390.940036 8.258048)
		(width 0.12954)
		(layer "B.Cu")
		(net "DELTA_L_85_5INCH_IN4_DP")
	)
	(segment
		(start 433.005484 10.414508)
		(end 431.642012 10.655554)
		(width 0.14224)
		(layer "In11.Cu")
		(net "DELTA_L_85_5INCH_IN4_DP")
	)
	(segment
		(start 397.124428 6.603492)
		(end 396.875508 6.9596)
		(width 0.14224)
		(layer "In11.Cu")
		(net "DELTA_L_85_5INCH_IN4_DP")
	)
	(segment
		(start 416.942016 6.62686)
		(end 416.693096 6.982968)
		(width 0.14224)
		(layer "In11.Cu")
		(net "DELTA_L_85_5INCH_IN4_DP")
	)
	(segment
		(start 418.892482 6.594348)
		(end 418.536628 6.345174)
		(width 0.14224)
		(layer "In11.Cu")
		(net "DELTA_L_85_5INCH_IN4_DP")
	)
	(segment
		(start 399.074894 6.57098)
		(end 398.71904 6.321806)
		(width 0.14224)
		(layer "In11.Cu")
		(net "DELTA_L_85_5INCH_IN4_DP")
	)
	(segment
		(start 415.63417 10.582656)
		(end 414.92551 6.569964)
		(width 0.14224)
		(layer "In11.Cu")
		(net "DELTA_L_85_5INCH_IN4_DP")
	)
	(segment
		(start 420.900098 6.600698)
		(end 420.651178 6.956806)
		(width 0.14224)
		(layer "In11.Cu")
		(net "DELTA_L_85_5INCH_IN4_DP")
	)
	(segment
		(start 430.416208 6.297422)
		(end 428.821596 6.579108)
		(width 0.14224)
		(layer "In11.Cu")
		(net "DELTA_L_85_5INCH_IN4_DP")
	)
	(segment
		(start 403.030436 6.530086)
		(end 402.674582 6.280912)
		(width 0.14224)
		(layer "In11.Cu")
		(net "DELTA_L_85_5INCH_IN4_DP")
	)
	(segment
		(start 407.87574 10.70991)
		(end 407.711148 10.594594)
		(width 0.14224)
		(layer "In11.Cu")
		(net "DELTA_L_85_5INCH_IN4_DP")
	)
	(segment
		(start 411.834584 10.689336)
		(end 411.669992 10.57402)
		(width 0.14224)
		(layer "In11.Cu")
		(net "DELTA_L_85_5INCH_IN4_DP")
	)
	(segment
		(start 400.83105 6.918706)
		(end 401.425156 10.281412)
		(width 0.14224)
		(layer "In11.Cu")
		(net "DELTA_L_85_5INCH_IN4_DP")
	)
	(segment
		(start 407.711148 10.594594)
		(end 406.997154 6.552692)
		(width 0.14224)
		(layer "In11.Cu")
		(net "DELTA_L_85_5INCH_IN4_DP")
	)
	(segment
		(start 429.042576 10.412476)
		(end 427.679104 10.653522)
		(width 0.14224)
		(layer "In11.Cu")
		(net "DELTA_L_85_5INCH_IN4_DP")
	)
	(segment
		(start 403.74316 10.563606)
		(end 403.030436 6.530086)
		(width 0.14224)
		(layer "In11.Cu")
		(net "DELTA_L_85_5INCH_IN4_DP")
	)
	(segment
		(start 423.55389 10.550398)
		(end 422.850564 6.568186)
		(width 0.14224)
		(layer "In11.Cu")
		(net "DELTA_L_85_5INCH_IN4_DP")
	)
	(segment
		(start 434.735986 6.552438)
		(end 434.380132 6.303264)
		(width 0.14224)
		(layer "In11.Cu")
		(net "DELTA_L_85_5INCH_IN4_DP")
	)
	(segment
		(start 394.789152 8.548878)
		(end 391.230866 8.548878)
		(width 0.14224)
		(layer "In11.Cu")
		(net "DELTA_L_85_5INCH_IN4_DP")
	)
	(segment
		(start 405.386286 10.27303)
		(end 405.27097 10.437876)
		(width 0.14224)
		(layer "In11.Cu")
		(net "DELTA_L_85_5INCH_IN4_DP")
	)
	(segment
		(start 412.975044 6.602476)
		(end 412.726124 6.958584)
		(width 0.14224)
		(layer "In11.Cu")
		(net "DELTA_L_85_5INCH_IN4_DP")
	)
	(segment
		(start 432.5366 6.941058)
		(end 433.1208 10.249916)
		(width 0.14224)
		(layer "In11.Cu")
		(net "DELTA_L_85_5INCH_IN4_DP")
	)
	(segment
		(start 431.642012 10.655554)
		(end 431.47742 10.540238)
		(width 0.14224)
		(layer "In11.Cu")
		(net "DELTA_L_85_5INCH_IN4_DP")
	)
	(segment
		(start 408.759406 6.935724)
		(end 409.354528 10.304272)
		(width 0.14224)
		(layer "In11.Cu")
		(net "DELTA_L_85_5INCH_IN4_DP")
	)
	(segment
		(start 403.907498 10.678922)
		(end 403.74316 10.563606)
		(width 0.14224)
		(layer "In11.Cu")
		(net "DELTA_L_85_5INCH_IN4_DP")
	)
	(segment
		(start 435.003448 8.06704)
		(end 434.735986 6.552438)
		(width 0.14224)
		(layer "In11.Cu")
		(net "DELTA_L_85_5INCH_IN4_DP")
	)
	(segment
		(start 431.47742 10.540238)
		(end 430.772062 6.546596)
		(width 0.14224)
		(layer "In11.Cu")
		(net "DELTA_L_85_5INCH_IN4_DP")
	)
	(segment
		(start 409.008326 6.579616)
		(end 408.759406 6.935724)
		(width 0.14224)
		(layer "In11.Cu")
		(net "DELTA_L_85_5INCH_IN4_DP")
	)
	(segment
		(start 430.772062 6.546596)
		(end 430.416208 6.297422)
		(width 0.14224)
		(layer "In11.Cu")
		(net "DELTA_L_85_5INCH_IN4_DP")
	)
	(segment
		(start 410.958792 6.547104)
		(end 410.602938 6.29793)
		(width 0.14224)
		(layer "In11.Cu")
		(net "DELTA_L_85_5INCH_IN4_DP")
	)
	(segment
		(start 397.346932 10.444988)
		(end 395.98346 10.686034)
		(width 0.14224)
		(layer "In11.Cu")
		(net "DELTA_L_85_5INCH_IN4_DP")
	)
	(segment
		(start 429.157892 10.248138)
		(end 429.042576 10.412476)
		(width 0.14224)
		(layer "In11.Cu")
		(net "DELTA_L_85_5INCH_IN4_DP")
	)
	(segment
		(start 399.946368 10.68705)
		(end 399.781776 10.571734)
		(width 0.14224)
		(layer "In11.Cu")
		(net "DELTA_L_85_5INCH_IN4_DP")
	)
	(segment
		(start 399.781776 10.571734)
		(end 399.074894 6.57098)
		(width 0.14224)
		(layer "In11.Cu")
		(net "DELTA_L_85_5INCH_IN4_DP")
	)
	(segment
		(start 406.997154 6.552692)
		(end 406.6413 6.303518)
		(width 0.14224)
		(layer "In11.Cu")
		(net "DELTA_L_85_5INCH_IN4_DP")
	)
	(segment
		(start 397.462248 10.280396)
		(end 397.346932 10.444988)
		(width 0.14224)
		(layer "In11.Cu")
		(net "DELTA_L_85_5INCH_IN4_DP")
	)
	(segment
		(start 425.081954 10.424414)
		(end 423.718482 10.665714)
		(width 0.14224)
		(layer "In11.Cu")
		(net "DELTA_L_85_5INCH_IN4_DP")
	)
	(segment
		(start 434.380132 6.303264)
		(end 433.58308 6.44398)
		(width 0.14224)
		(layer "In11.Cu")
		(net "DELTA_L_85_5INCH_IN4_DP")
	)
	(segment
		(start 421.23487 10.26033)
		(end 421.119554 10.424922)
		(width 0.14224)
		(layer "In11.Cu")
		(net "DELTA_L_85_5INCH_IN4_DP")
	)
	(segment
		(start 433.1208 10.249916)
		(end 433.005484 10.414508)
		(width 0.14224)
		(layer "In11.Cu")
		(net "DELTA_L_85_5INCH_IN4_DP")
	)
	(segment
		(start 420.651178 6.956806)
		(end 421.23487 10.26033)
		(width 0.14224)
		(layer "In11.Cu")
		(net "DELTA_L_85_5INCH_IN4_DP")
	)
	(segment
		(start 439.307478 8.258048)
		(end 439.016648 8.548878)
		(width 0.14224)
		(layer "In11.Cu")
		(net "DELTA_L_85_5INCH_IN4_DP")
	)
	(segment
		(start 409.239212 10.468864)
		(end 407.87574 10.70991)
		(width 0.14224)
		(layer "In11.Cu")
		(net "DELTA_L_85_5INCH_IN4_DP")
	)
	(segment
		(start 401.425156 10.281412)
		(end 401.30984 10.446004)
		(width 0.14224)
		(layer "In11.Cu")
		(net "DELTA_L_85_5INCH_IN4_DP")
	)
	(segment
		(start 424.858942 6.578854)
		(end 424.610022 6.934962)
		(width 0.14224)
		(layer "In11.Cu")
		(net "DELTA_L_85_5INCH_IN4_DP")
	)
	(segment
		(start 419.59149 10.550652)
		(end 418.892482 6.594348)
		(width 0.14224)
		(layer "In11.Cu")
		(net "DELTA_L_85_5INCH_IN4_DP")
	)
	(segment
		(start 416.693096 6.982968)
		(end 417.27755 10.292334)
		(width 0.14224)
		(layer "In11.Cu")
		(net "DELTA_L_85_5INCH_IN4_DP")
	)
	(segment
		(start 432.78552 6.58495)
		(end 432.5366 6.941058)
		(width 0.14224)
		(layer "In11.Cu")
		(net "DELTA_L_85_5INCH_IN4_DP")
	)
	(segment
		(start 427.679104 10.653522)
		(end 427.514258 10.538206)
		(width 0.14224)
		(layer "In11.Cu")
		(net "DELTA_L_85_5INCH_IN4_DP")
	)
	(segment
		(start 405.27097 10.437876)
		(end 403.907498 10.678922)
		(width 0.14224)
		(layer "In11.Cu")
		(net "DELTA_L_85_5INCH_IN4_DP")
	)
	(segment
		(start 402.674582 6.280912)
		(end 401.07997 6.562598)
		(width 0.14224)
		(layer "In11.Cu")
		(net "DELTA_L_85_5INCH_IN4_DP")
	)
	(segment
		(start 391.230866 8.548878)
		(end 390.940036 8.258048)
		(width 0.14224)
		(layer "In11.Cu")
		(net "DELTA_L_85_5INCH_IN4_DP")
	)
	(segment
		(start 422.850564 6.568186)
		(end 422.49471 6.319012)
		(width 0.14224)
		(layer "In11.Cu")
		(net "DELTA_L_85_5INCH_IN4_DP")
	)
	(segment
		(start 412.726124 6.958584)
		(end 413.313372 10.283698)
		(width 0.14224)
		(layer "In11.Cu")
		(net "DELTA_L_85_5INCH_IN4_DP")
	)
	(segment
		(start 435.689502 8.548878)
		(end 435.003448 8.06704)
		(width 0.14224)
		(layer "In11.Cu")
		(net "DELTA_L_85_5INCH_IN4_DP")
	)
	(segment
		(start 401.07997 6.562598)
		(end 400.83105 6.918706)
		(width 0.14224)
		(layer "In11.Cu")
		(net "DELTA_L_85_5INCH_IN4_DP")
	)
	(segment
		(start 427.514258 10.538206)
		(end 426.809408 6.546342)
		(width 0.14224)
		(layer "In11.Cu")
		(net "DELTA_L_85_5INCH_IN4_DP")
	)
	(segment
		(start 422.49471 6.319012)
		(end 420.900098 6.600698)
		(width 0.14224)
		(layer "In11.Cu")
		(net "DELTA_L_85_5INCH_IN4_DP")
	)
	(segment
		(start 413.198056 10.44829)
		(end 411.834584 10.689336)
		(width 0.14224)
		(layer "In11.Cu")
		(net "DELTA_L_85_5INCH_IN4_DP")
	)
	(segment
		(start 395.98346 10.686034)
		(end 395.818868 10.570718)
		(width 0.14224)
		(layer "In11.Cu")
		(net "DELTA_L_85_5INCH_IN4_DP")
	)
	(segment
		(start 428.821596 6.579108)
		(end 428.572676 6.935216)
		(width 0.14224)
		(layer "In11.Cu")
		(net "DELTA_L_85_5INCH_IN4_DP")
	)
	(segment
		(start 417.27755 10.292334)
		(end 417.162234 10.456926)
		(width 0.14224)
		(layer "In11.Cu")
		(net "DELTA_L_85_5INCH_IN4_DP")
	)
	(segment
		(start 425.19727 10.260076)
		(end 425.081954 10.424414)
		(width 0.14224)
		(layer "In11.Cu")
		(net "DELTA_L_85_5INCH_IN4_DP")
	)
	(segment
		(start 395.818868 10.570718)
		(end 395.55674 9.086088)
		(width 0.14224)
		(layer "In11.Cu")
		(net "DELTA_L_85_5INCH_IN4_DP")
	)
	(segment
		(start 398.71904 6.321806)
		(end 397.124428 6.603492)
		(width 0.14224)
		(layer "In11.Cu")
		(net "DELTA_L_85_5INCH_IN4_DP")
	)
	(segment
		(start 421.119554 10.424922)
		(end 419.756082 10.665968)
		(width 0.14224)
		(layer "In11.Cu")
		(net "DELTA_L_85_5INCH_IN4_DP")
	)
	(segment
		(start 433.58308 6.44398)
		(end 432.78552 6.58495)
		(width 0.14224)
		(layer "In11.Cu")
		(net "DELTA_L_85_5INCH_IN4_DP")
	)
	(segment
		(start 423.718482 10.665714)
		(end 423.55389 10.550398)
		(width 0.14224)
		(layer "In11.Cu")
		(net "DELTA_L_85_5INCH_IN4_DP")
	)
	(segment
		(start 415.798762 10.697972)
		(end 415.63417 10.582656)
		(width 0.14224)
		(layer "In11.Cu")
		(net "DELTA_L_85_5INCH_IN4_DP")
	)
	(segment
		(start 424.610022 6.934962)
		(end 425.19727 10.260076)
		(width 0.14224)
		(layer "In11.Cu")
		(net "DELTA_L_85_5INCH_IN4_DP")
	)
	(segment
		(start 395.55674 9.086088)
		(end 394.789152 8.548878)
		(width 0.14224)
		(layer "In11.Cu")
		(net "DELTA_L_85_5INCH_IN4_DP")
	)
	(segment
		(start 417.162234 10.456926)
		(end 415.798762 10.697972)
		(width 0.14224)
		(layer "In11.Cu")
		(net "DELTA_L_85_5INCH_IN4_DP")
	)
	(segment
		(start 428.572676 6.935216)
		(end 429.157892 10.248138)
		(width 0.14224)
		(layer "In11.Cu")
		(net "DELTA_L_85_5INCH_IN4_DP")
	)
	(segment
		(start 414.92551 6.569964)
		(end 414.569656 6.32079)
		(width 0.14224)
		(layer "In11.Cu")
		(net "DELTA_L_85_5INCH_IN4_DP")
	)
	(segment
		(start 409.354528 10.304272)
		(end 409.239212 10.468864)
		(width 0.14224)
		(layer "In11.Cu")
		(net "DELTA_L_85_5INCH_IN4_DP")
	)
	(segment
		(start 405.046688 6.585204)
		(end 404.797768 6.941312)
		(width 0.14224)
		(layer "In11.Cu")
		(net "DELTA_L_85_5INCH_IN4_DP")
	)
	(segment
		(start 439.016648 8.548878)
		(end 435.689502 8.548878)
		(width 0.14224)
		(layer "In11.Cu")
		(net "DELTA_L_85_5INCH_IN4_DP")
	)
	(segment
		(start 404.797768 6.941312)
		(end 405.386286 10.27303)
		(width 0.14224)
		(layer "In11.Cu")
		(net "DELTA_L_85_5INCH_IN4_DP")
	)
	(segment
		(start 396.875508 6.9596)
		(end 397.462248 10.280396)
		(width 0.14224)
		(layer "In11.Cu")
		(net "DELTA_L_85_5INCH_IN4_DP")
	)
	(segment
		(start 418.536628 6.345174)
		(end 416.942016 6.62686)
		(width 0.14224)
		(layer "In11.Cu")
		(net "DELTA_L_85_5INCH_IN4_DP")
	)
	(segment
		(start 410.602938 6.29793)
		(end 409.008326 6.579616)
		(width 0.14224)
		(layer "In11.Cu")
		(net "DELTA_L_85_5INCH_IN4_DP")
	)
	(segment
		(start 413.313372 10.283698)
		(end 413.198056 10.44829)
		(width 0.14224)
		(layer "In11.Cu")
		(net "DELTA_L_85_5INCH_IN4_DP")
	)
	(segment
		(start 401.30984 10.446004)
		(end 399.946368 10.68705)
		(width 0.14224)
		(layer "In11.Cu")
		(net "DELTA_L_85_5INCH_IN4_DP")
	)
	(segment
		(start 426.453554 6.297168)
		(end 424.858942 6.578854)
		(width 0.14224)
		(layer "In11.Cu")
		(net "DELTA_L_85_5INCH_IN4_DP")
	)
	(segment
		(start 426.809408 6.546342)
		(end 426.453554 6.297168)
		(width 0.14224)
		(layer "In11.Cu")
		(net "DELTA_L_85_5INCH_IN4_DP")
	)
	(segment
		(start 414.569656 6.32079)
		(end 412.975044 6.602476)
		(width 0.14224)
		(layer "In11.Cu")
		(net "DELTA_L_85_5INCH_IN4_DP")
	)
	(segment
		(start 411.669992 10.57402)
		(end 410.958792 6.547104)
		(width 0.14224)
		(layer "In11.Cu")
		(net "DELTA_L_85_5INCH_IN4_DP")
	)
	(segment
		(start 406.6413 6.303518)
		(end 405.046688 6.585204)
		(width 0.14224)
		(layer "In11.Cu")
		(net "DELTA_L_85_5INCH_IN4_DP")
	)
	(segment
		(start 419.756082 10.665968)
		(end 419.59149 10.550652)
		(width 0.14224)
		(layer "In11.Cu")
		(net "DELTA_L_85_5INCH_IN4_DP")
	)
	(segment
		(start 439.95975 8.939784)
		(end 439.307478 9.121648)
		(width 0.12954)
		(layer "B.Cu")
		(net "DELTA_L_85_5INCH_IN4_DN")
	)
	(segment
		(start 390.287764 8.939784)
		(end 390.940036 9.121648)
		(width 0.12954)
		(layer "B.Cu")
		(net "DELTA_L_85_5INCH_IN4_DN")
	)
	(segment
		(start 433.418996 10.315956)
		(end 432.834796 7.007098)
		(width 0.14224)
		(layer "In11.Cu")
		(net "DELTA_L_85_5INCH_IN4_DN")
	)
	(segment
		(start 413.611568 10.349738)
		(end 413.02432 7.024624)
		(width 0.14224)
		(layer "In11.Cu")
		(net "DELTA_L_85_5INCH_IN4_DN")
	)
	(segment
		(start 416.991292 7.049008)
		(end 417.106354 6.884416)
		(width 0.14224)
		(layer "In11.Cu")
		(net "DELTA_L_85_5INCH_IN4_DN")
	)
	(segment
		(start 410.536898 6.596126)
		(end 410.701236 6.711188)
		(width 0.14224)
		(layer "In11.Cu")
		(net "DELTA_L_85_5INCH_IN4_DN")
	)
	(segment
		(start 399.52422 10.735818)
		(end 399.880328 10.985246)
		(width 0.14224)
		(layer "In11.Cu")
		(net "DELTA_L_85_5INCH_IN4_DN")
	)
	(segment
		(start 429.20666 10.670032)
		(end 429.456088 10.314432)
		(width 0.14224)
		(layer "In11.Cu")
		(net "DELTA_L_85_5INCH_IN4_DN")
	)
	(segment
		(start 433.169568 10.672064)
		(end 433.418996 10.315956)
		(width 0.14224)
		(layer "In11.Cu")
		(net "DELTA_L_85_5INCH_IN4_DN")
	)
	(segment
		(start 432.949858 6.842506)
		(end 434.314092 6.60146)
		(width 0.14224)
		(layer "In11.Cu")
		(net "DELTA_L_85_5INCH_IN4_DN")
	)
	(segment
		(start 406.57526 6.601714)
		(end 406.739598 6.716776)
		(width 0.14224)
		(layer "In11.Cu")
		(net "DELTA_L_85_5INCH_IN4_DN")
	)
	(segment
		(start 403.841204 10.977118)
		(end 405.435308 10.695432)
		(width 0.14224)
		(layer "In11.Cu")
		(net "DELTA_L_85_5INCH_IN4_DN")
	)
	(segment
		(start 439.016648 8.830818)
		(end 439.307478 9.121648)
		(width 0.14224)
		(layer "In11.Cu")
		(net "DELTA_L_85_5INCH_IN4_DN")
	)
	(segment
		(start 413.139382 6.860032)
		(end 414.503616 6.618986)
		(width 0.14224)
		(layer "In11.Cu")
		(net "DELTA_L_85_5INCH_IN4_DN")
	)
	(segment
		(start 398.817338 6.735064)
		(end 399.52422 10.735818)
		(width 0.14224)
		(layer "In11.Cu")
		(net "DELTA_L_85_5INCH_IN4_DN")
	)
	(segment
		(start 405.435308 10.695432)
		(end 405.684482 10.33907)
		(width 0.14224)
		(layer "In11.Cu")
		(net "DELTA_L_85_5INCH_IN4_DN")
	)
	(segment
		(start 434.47843 6.716522)
		(end 434.745892 8.23087)
		(width 0.14224)
		(layer "In11.Cu")
		(net "DELTA_L_85_5INCH_IN4_DN")
	)
	(segment
		(start 435.600348 8.830818)
		(end 439.016648 8.830818)
		(width 0.14224)
		(layer "In11.Cu")
		(net "DELTA_L_85_5INCH_IN4_DN")
	)
	(segment
		(start 397.288766 6.861048)
		(end 398.653 6.620002)
		(width 0.14224)
		(layer "In11.Cu")
		(net "DELTA_L_85_5INCH_IN4_DN")
	)
	(segment
		(start 430.514506 6.71068)
		(end 431.219864 10.704322)
		(width 0.14224)
		(layer "In11.Cu")
		(net "DELTA_L_85_5INCH_IN4_DN")
	)
	(segment
		(start 428.985934 6.836664)
		(end 430.350168 6.595618)
		(width 0.14224)
		(layer "In11.Cu")
		(net "DELTA_L_85_5INCH_IN4_DN")
	)
	(segment
		(start 422.593008 6.73227)
		(end 423.296334 10.714482)
		(width 0.14224)
		(layer "In11.Cu")
		(net "DELTA_L_85_5INCH_IN4_DN")
	)
	(segment
		(start 401.129246 6.985)
		(end 401.244308 6.820154)
		(width 0.14224)
		(layer "In11.Cu")
		(net "DELTA_L_85_5INCH_IN4_DN")
	)
	(segment
		(start 423.296334 10.714482)
		(end 423.652442 10.96391)
		(width 0.14224)
		(layer "In11.Cu")
		(net "DELTA_L_85_5INCH_IN4_DN")
	)
	(segment
		(start 425.495466 10.326116)
		(end 424.908218 7.001002)
		(width 0.14224)
		(layer "In11.Cu")
		(net "DELTA_L_85_5INCH_IN4_DN")
	)
	(segment
		(start 417.575746 10.358374)
		(end 416.991292 7.049008)
		(width 0.14224)
		(layer "In11.Cu")
		(net "DELTA_L_85_5INCH_IN4_DN")
	)
	(segment
		(start 434.745892 8.23087)
		(end 435.600348 8.830818)
		(width 0.14224)
		(layer "In11.Cu")
		(net "DELTA_L_85_5INCH_IN4_DN")
	)
	(segment
		(start 431.219864 10.704322)
		(end 431.575972 10.95375)
		(width 0.14224)
		(layer "In11.Cu")
		(net "DELTA_L_85_5INCH_IN4_DN")
	)
	(segment
		(start 405.684482 10.33907)
		(end 405.095964 7.007606)
		(width 0.14224)
		(layer "In11.Cu")
		(net "DELTA_L_85_5INCH_IN4_DN")
	)
	(segment
		(start 401.723352 10.347452)
		(end 401.129246 6.985)
		(width 0.14224)
		(layer "In11.Cu")
		(net "DELTA_L_85_5INCH_IN4_DN")
	)
	(segment
		(start 427.256702 10.70229)
		(end 427.613064 10.951718)
		(width 0.14224)
		(layer "In11.Cu")
		(net "DELTA_L_85_5INCH_IN4_DN")
	)
	(segment
		(start 431.575972 10.95375)
		(end 433.169568 10.672064)
		(width 0.14224)
		(layer "In11.Cu")
		(net "DELTA_L_85_5INCH_IN4_DN")
	)
	(segment
		(start 425.246038 10.68197)
		(end 425.495466 10.326116)
		(width 0.14224)
		(layer "In11.Cu")
		(net "DELTA_L_85_5INCH_IN4_DN")
	)
	(segment
		(start 394.700252 8.830818)
		(end 395.299184 9.250172)
		(width 0.14224)
		(layer "In11.Cu")
		(net "DELTA_L_85_5INCH_IN4_DN")
	)
	(segment
		(start 409.057602 7.002018)
		(end 409.172664 6.837172)
		(width 0.14224)
		(layer "In11.Cu")
		(net "DELTA_L_85_5INCH_IN4_DN")
	)
	(segment
		(start 430.350168 6.595618)
		(end 430.514506 6.71068)
		(width 0.14224)
		(layer "In11.Cu")
		(net "DELTA_L_85_5INCH_IN4_DN")
	)
	(segment
		(start 397.173704 7.02564)
		(end 397.288766 6.861048)
		(width 0.14224)
		(layer "In11.Cu")
		(net "DELTA_L_85_5INCH_IN4_DN")
	)
	(segment
		(start 401.244308 6.820154)
		(end 402.608542 6.579108)
		(width 0.14224)
		(layer "In11.Cu")
		(net "DELTA_L_85_5INCH_IN4_DN")
	)
	(segment
		(start 398.653 6.620002)
		(end 398.817338 6.735064)
		(width 0.14224)
		(layer "In11.Cu")
		(net "DELTA_L_85_5INCH_IN4_DN")
	)
	(segment
		(start 405.095964 7.007606)
		(end 405.211026 6.84276)
		(width 0.14224)
		(layer "In11.Cu")
		(net "DELTA_L_85_5INCH_IN4_DN")
	)
	(segment
		(start 391.230866 8.830818)
		(end 394.700252 8.830818)
		(width 0.14224)
		(layer "In11.Cu")
		(net "DELTA_L_85_5INCH_IN4_DN")
	)
	(segment
		(start 426.387514 6.595364)
		(end 426.551852 6.710426)
		(width 0.14224)
		(layer "In11.Cu")
		(net "DELTA_L_85_5INCH_IN4_DN")
	)
	(segment
		(start 401.473924 10.70356)
		(end 401.723352 10.347452)
		(width 0.14224)
		(layer "In11.Cu")
		(net "DELTA_L_85_5INCH_IN4_DN")
	)
	(segment
		(start 399.880328 10.985246)
		(end 401.473924 10.70356)
		(width 0.14224)
		(layer "In11.Cu")
		(net "DELTA_L_85_5INCH_IN4_DN")
	)
	(segment
		(start 418.470588 6.64337)
		(end 418.634926 6.758432)
		(width 0.14224)
		(layer "In11.Cu")
		(net "DELTA_L_85_5INCH_IN4_DN")
	)
	(segment
		(start 422.42867 6.617208)
		(end 422.593008 6.73227)
		(width 0.14224)
		(layer "In11.Cu")
		(net "DELTA_L_85_5INCH_IN4_DN")
	)
	(segment
		(start 409.172664 6.837172)
		(end 410.536898 6.596126)
		(width 0.14224)
		(layer "In11.Cu")
		(net "DELTA_L_85_5INCH_IN4_DN")
	)
	(segment
		(start 418.634926 6.758432)
		(end 419.333934 10.714736)
		(width 0.14224)
		(layer "In11.Cu")
		(net "DELTA_L_85_5INCH_IN4_DN")
	)
	(segment
		(start 413.02432 7.024624)
		(end 413.139382 6.860032)
		(width 0.14224)
		(layer "In11.Cu")
		(net "DELTA_L_85_5INCH_IN4_DN")
	)
	(segment
		(start 426.551852 6.710426)
		(end 427.256702 10.70229)
		(width 0.14224)
		(layer "In11.Cu")
		(net "DELTA_L_85_5INCH_IN4_DN")
	)
	(segment
		(start 397.511016 10.702544)
		(end 397.760444 10.346436)
		(width 0.14224)
		(layer "In11.Cu")
		(net "DELTA_L_85_5INCH_IN4_DN")
	)
	(segment
		(start 403.485604 10.72769)
		(end 403.841204 10.977118)
		(width 0.14224)
		(layer "In11.Cu")
		(net "DELTA_L_85_5INCH_IN4_DN")
	)
	(segment
		(start 402.608542 6.579108)
		(end 402.77288 6.69417)
		(width 0.14224)
		(layer "In11.Cu")
		(net "DELTA_L_85_5INCH_IN4_DN")
	)
	(segment
		(start 395.561312 10.734802)
		(end 395.91742 10.98423)
		(width 0.14224)
		(layer "In11.Cu")
		(net "DELTA_L_85_5INCH_IN4_DN")
	)
	(segment
		(start 406.739598 6.716776)
		(end 407.453592 10.758678)
		(width 0.14224)
		(layer "In11.Cu")
		(net "DELTA_L_85_5INCH_IN4_DN")
	)
	(segment
		(start 402.77288 6.69417)
		(end 403.485604 10.72769)
		(width 0.14224)
		(layer "In11.Cu")
		(net "DELTA_L_85_5INCH_IN4_DN")
	)
	(segment
		(start 409.403296 10.72642)
		(end 409.652724 10.370312)
		(width 0.14224)
		(layer "In11.Cu")
		(net "DELTA_L_85_5INCH_IN4_DN")
	)
	(segment
		(start 390.940036 9.121648)
		(end 391.230866 8.830818)
		(width 0.14224)
		(layer "In11.Cu")
		(net "DELTA_L_85_5INCH_IN4_DN")
	)
	(segment
		(start 411.768544 10.987532)
		(end 413.36214 10.705846)
		(width 0.14224)
		(layer "In11.Cu")
		(net "DELTA_L_85_5INCH_IN4_DN")
	)
	(segment
		(start 421.283638 10.682478)
		(end 421.533066 10.32637)
		(width 0.14224)
		(layer "In11.Cu")
		(net "DELTA_L_85_5INCH_IN4_DN")
	)
	(segment
		(start 434.314092 6.60146)
		(end 434.47843 6.716522)
		(width 0.14224)
		(layer "In11.Cu")
		(net "DELTA_L_85_5INCH_IN4_DN")
	)
	(segment
		(start 414.503616 6.618986)
		(end 414.667954 6.734048)
		(width 0.14224)
		(layer "In11.Cu")
		(net "DELTA_L_85_5INCH_IN4_DN")
	)
	(segment
		(start 415.732722 10.996168)
		(end 417.326318 10.714482)
		(width 0.14224)
		(layer "In11.Cu")
		(net "DELTA_L_85_5INCH_IN4_DN")
	)
	(segment
		(start 421.064436 6.858254)
		(end 422.42867 6.617208)
		(width 0.14224)
		(layer "In11.Cu")
		(net "DELTA_L_85_5INCH_IN4_DN")
	)
	(segment
		(start 410.701236 6.711188)
		(end 411.412436 10.738104)
		(width 0.14224)
		(layer "In11.Cu")
		(net "DELTA_L_85_5INCH_IN4_DN")
	)
	(segment
		(start 413.36214 10.705846)
		(end 413.611568 10.349738)
		(width 0.14224)
		(layer "In11.Cu")
		(net "DELTA_L_85_5INCH_IN4_DN")
	)
	(segment
		(start 425.02328 6.83641)
		(end 426.387514 6.595364)
		(width 0.14224)
		(layer "In11.Cu")
		(net "DELTA_L_85_5INCH_IN4_DN")
	)
	(segment
		(start 420.949374 7.022846)
		(end 421.064436 6.858254)
		(width 0.14224)
		(layer "In11.Cu")
		(net "DELTA_L_85_5INCH_IN4_DN")
	)
	(segment
		(start 417.106354 6.884416)
		(end 418.470588 6.64337)
		(width 0.14224)
		(layer "In11.Cu")
		(net "DELTA_L_85_5INCH_IN4_DN")
	)
	(segment
		(start 407.8097 11.008106)
		(end 409.403296 10.72642)
		(width 0.14224)
		(layer "In11.Cu")
		(net "DELTA_L_85_5INCH_IN4_DN")
	)
	(segment
		(start 421.533066 10.32637)
		(end 420.949374 7.022846)
		(width 0.14224)
		(layer "In11.Cu")
		(net "DELTA_L_85_5INCH_IN4_DN")
	)
	(segment
		(start 405.211026 6.84276)
		(end 406.57526 6.601714)
		(width 0.14224)
		(layer "In11.Cu")
		(net "DELTA_L_85_5INCH_IN4_DN")
	)
	(segment
		(start 424.908218 7.001002)
		(end 425.02328 6.83641)
		(width 0.14224)
		(layer "In11.Cu")
		(net "DELTA_L_85_5INCH_IN4_DN")
	)
	(segment
		(start 428.870872 7.001256)
		(end 428.985934 6.836664)
		(width 0.14224)
		(layer "In11.Cu")
		(net "DELTA_L_85_5INCH_IN4_DN")
	)
	(segment
		(start 417.326318 10.714482)
		(end 417.575746 10.358374)
		(width 0.14224)
		(layer "In11.Cu")
		(net "DELTA_L_85_5INCH_IN4_DN")
	)
	(segment
		(start 432.834796 7.007098)
		(end 432.949858 6.842506)
		(width 0.14224)
		(layer "In11.Cu")
		(net "DELTA_L_85_5INCH_IN4_DN")
	)
	(segment
		(start 423.652442 10.96391)
		(end 425.246038 10.68197)
		(width 0.14224)
		(layer "In11.Cu")
		(net "DELTA_L_85_5INCH_IN4_DN")
	)
	(segment
		(start 415.376614 10.74674)
		(end 415.732722 10.996168)
		(width 0.14224)
		(layer "In11.Cu")
		(net "DELTA_L_85_5INCH_IN4_DN")
	)
	(segment
		(start 427.613064 10.951718)
		(end 429.20666 10.670032)
		(width 0.14224)
		(layer "In11.Cu")
		(net "DELTA_L_85_5INCH_IN4_DN")
	)
	(segment
		(start 419.690042 10.964164)
		(end 421.283638 10.682478)
		(width 0.14224)
		(layer "In11.Cu")
		(net "DELTA_L_85_5INCH_IN4_DN")
	)
	(segment
		(start 411.412436 10.738104)
		(end 411.768544 10.987532)
		(width 0.14224)
		(layer "In11.Cu")
		(net "DELTA_L_85_5INCH_IN4_DN")
	)
	(segment
		(start 419.333934 10.714736)
		(end 419.690042 10.964164)
		(width 0.14224)
		(layer "In11.Cu")
		(net "DELTA_L_85_5INCH_IN4_DN")
	)
	(segment
		(start 407.453592 10.758678)
		(end 407.8097 11.008106)
		(width 0.14224)
		(layer "In11.Cu")
		(net "DELTA_L_85_5INCH_IN4_DN")
	)
	(segment
		(start 397.760444 10.346436)
		(end 397.173704 7.02564)
		(width 0.14224)
		(layer "In11.Cu")
		(net "DELTA_L_85_5INCH_IN4_DN")
	)
	(segment
		(start 395.91742 10.98423)
		(end 397.511016 10.702544)
		(width 0.14224)
		(layer "In11.Cu")
		(net "DELTA_L_85_5INCH_IN4_DN")
	)
	(segment
		(start 395.299184 9.250172)
		(end 395.561312 10.734802)
		(width 0.14224)
		(layer "In11.Cu")
		(net "DELTA_L_85_5INCH_IN4_DN")
	)
	(segment
		(start 409.652724 10.370312)
		(end 409.057602 7.002018)
		(width 0.14224)
		(layer "In11.Cu")
		(net "DELTA_L_85_5INCH_IN4_DN")
	)
	(segment
		(start 429.456088 10.314432)
		(end 428.870872 7.001256)
		(width 0.14224)
		(layer "In11.Cu")
		(net "DELTA_L_85_5INCH_IN4_DN")
	)
	(segment
		(start 414.667954 6.734048)
		(end 415.376614 10.74674)
		(width 0.14224)
		(layer "In11.Cu")
		(net "DELTA_L_85_5INCH_IN4_DN")
	)
	(segment
		(start 315.791088 0.25273)
		(end 316.44336 0.434594)
		(width 0.12954)
		(layer "F.Cu")
		(net "DELTA_L_85_5INCH_IN3_DP")
	)
	(segment
		(start 365.463074 0.25273)
		(end 364.810802 0.434594)
		(width 0.12954)
		(layer "F.Cu")
		(net "DELTA_L_85_5INCH_IN3_DP")
	)
	(segment
		(start 321.064636 2.047748)
		(end 321.420744 2.297176)
		(width 0.14224)
		(layer "In6.Cu")
		(net "DELTA_L_85_5INCH_IN3_DP")
	)
	(segment
		(start 360.249216 -0.456184)
		(end 361.103672 0.143764)
		(width 0.14224)
		(layer "In6.Cu")
		(net "DELTA_L_85_5INCH_IN3_DP")
	)
	(segment
		(start 354.959412 1.627378)
		(end 354.374196 -1.685798)
		(width 0.14224)
		(layer "In6.Cu")
		(net "DELTA_L_85_5INCH_IN3_DP")
	)
	(segment
		(start 364.519972 0.143764)
		(end 364.810802 0.434594)
		(width 0.14224)
		(layer "In6.Cu")
		(net "DELTA_L_85_5INCH_IN3_DP")
	)
	(segment
		(start 350.526604 -1.850644)
		(end 351.890838 -2.09169)
		(width 0.14224)
		(layer "In6.Cu")
		(net "DELTA_L_85_5INCH_IN3_DP")
	)
	(segment
		(start 336.20456 -1.975866)
		(end 336.91576 2.05105)
		(width 0.14224)
		(layer "In6.Cu")
		(net "DELTA_L_85_5INCH_IN3_DP")
	)
	(segment
		(start 347.931994 -2.069846)
		(end 348.096332 -1.954784)
		(width 0.14224)
		(layer "In6.Cu")
		(net "DELTA_L_85_5INCH_IN3_DP")
	)
	(segment
		(start 338.527644 -1.66243)
		(end 338.642706 -1.827022)
		(width 0.14224)
		(layer "In6.Cu")
		(net "DELTA_L_85_5INCH_IN3_DP")
	)
	(segment
		(start 339.114892 1.662684)
		(end 338.527644 -1.66243)
		(width 0.14224)
		(layer "In6.Cu")
		(net "DELTA_L_85_5INCH_IN3_DP")
	)
	(segment
		(start 335.156048 1.683258)
		(end 334.560926 -1.685036)
		(width 0.14224)
		(layer "In6.Cu")
		(net "DELTA_L_85_5INCH_IN3_DP")
	)
	(segment
		(start 325.027544 2.048764)
		(end 325.383652 2.298192)
		(width 0.14224)
		(layer "In6.Cu")
		(net "DELTA_L_85_5INCH_IN3_DP")
	)
	(segment
		(start 334.675988 -1.849882)
		(end 336.040222 -2.090928)
		(width 0.14224)
		(layer "In6.Cu")
		(net "DELTA_L_85_5INCH_IN3_DP")
	)
	(segment
		(start 358.92232 1.628902)
		(end 358.33812 -1.679956)
		(width 0.14224)
		(layer "In6.Cu")
		(net "DELTA_L_85_5INCH_IN3_DP")
	)
	(segment
		(start 354.374196 -1.685798)
		(end 354.489258 -1.85039)
		(width 0.14224)
		(layer "In6.Cu")
		(net "DELTA_L_85_5INCH_IN3_DP")
	)
	(segment
		(start 347.03639 1.639316)
		(end 346.452698 -1.664208)
		(width 0.14224)
		(layer "In6.Cu")
		(net "DELTA_L_85_5INCH_IN3_DP")
	)
	(segment
		(start 346.56776 -1.8288)
		(end 347.931994 -2.069846)
		(width 0.14224)
		(layer "In6.Cu")
		(net "DELTA_L_85_5INCH_IN3_DP")
	)
	(segment
		(start 323.263768 1.659382)
		(end 322.677028 -1.661414)
		(width 0.14224)
		(layer "In6.Cu")
		(net "DELTA_L_85_5INCH_IN3_DP")
	)
	(segment
		(start 329.344528 2.290064)
		(end 330.938632 2.008378)
		(width 0.14224)
		(layer "In6.Cu")
		(net "DELTA_L_85_5INCH_IN3_DP")
	)
	(segment
		(start 358.453182 -1.844548)
		(end 359.817416 -2.085594)
		(width 0.14224)
		(layer "In6.Cu")
		(net "DELTA_L_85_5INCH_IN3_DP")
	)
	(segment
		(start 336.040222 -2.090928)
		(end 336.20456 -1.975866)
		(width 0.14224)
		(layer "In6.Cu")
		(net "DELTA_L_85_5INCH_IN3_DP")
	)
	(segment
		(start 352.055176 -1.976628)
		(end 352.760026 2.015236)
		(width 0.14224)
		(layer "In6.Cu")
		(net "DELTA_L_85_5INCH_IN3_DP")
	)
	(segment
		(start 337.271868 2.300478)
		(end 338.865464 2.018792)
		(width 0.14224)
		(layer "In6.Cu")
		(net "DELTA_L_85_5INCH_IN3_DP")
	)
	(segment
		(start 348.096332 -1.954784)
		(end 348.799658 2.027428)
		(width 0.14224)
		(layer "In6.Cu")
		(net "DELTA_L_85_5INCH_IN3_DP")
	)
	(segment
		(start 340.00694 -2.068068)
		(end 340.171278 -1.953006)
		(width 0.14224)
		(layer "In6.Cu")
		(net "DELTA_L_85_5INCH_IN3_DP")
	)
	(segment
		(start 336.91576 2.05105)
		(end 337.271868 2.300478)
		(width 0.14224)
		(layer "In6.Cu")
		(net "DELTA_L_85_5INCH_IN3_DP")
	)
	(segment
		(start 324.320662 -1.95199)
		(end 325.027544 2.048764)
		(width 0.14224)
		(layer "In6.Cu")
		(net "DELTA_L_85_5INCH_IN3_DP")
	)
	(segment
		(start 325.383652 2.298192)
		(end 326.977248 2.016506)
		(width 0.14224)
		(layer "In6.Cu")
		(net "DELTA_L_85_5INCH_IN3_DP")
	)
	(segment
		(start 344.837258 2.027682)
		(end 345.193366 2.27711)
		(width 0.14224)
		(layer "In6.Cu")
		(net "DELTA_L_85_5INCH_IN3_DP")
	)
	(segment
		(start 357.079296 2.266696)
		(end 358.672892 1.98501)
		(width 0.14224)
		(layer "In6.Cu")
		(net "DELTA_L_85_5INCH_IN3_DP")
	)
	(segment
		(start 340.171278 -1.953006)
		(end 340.879938 2.059686)
		(width 0.14224)
		(layer "In6.Cu")
		(net "DELTA_L_85_5INCH_IN3_DP")
	)
	(segment
		(start 359.981754 -1.970532)
		(end 360.249216 -0.456184)
		(width 0.14224)
		(layer "In6.Cu")
		(net "DELTA_L_85_5INCH_IN3_DP")
	)
	(segment
		(start 316.44336 0.434594)
		(end 316.73419 0.143764)
		(width 0.14224)
		(layer "In6.Cu")
		(net "DELTA_L_85_5INCH_IN3_DP")
	)
	(segment
		(start 332.956916 2.071624)
		(end 333.313024 2.321052)
		(width 0.14224)
		(layer "In6.Cu")
		(net "DELTA_L_85_5INCH_IN3_DP")
	)
	(segment
		(start 349.155766 2.276856)
		(end 350.749362 1.994916)
		(width 0.14224)
		(layer "In6.Cu")
		(net "DELTA_L_85_5INCH_IN3_DP")
	)
	(segment
		(start 358.672892 1.98501)
		(end 358.92232 1.628902)
		(width 0.14224)
		(layer "In6.Cu")
		(net "DELTA_L_85_5INCH_IN3_DP")
	)
	(segment
		(start 326.63257 -1.702054)
		(end 326.747632 -1.8669)
		(width 0.14224)
		(layer "In6.Cu")
		(net "DELTA_L_85_5INCH_IN3_DP")
	)
	(segment
		(start 321.420744 2.297176)
		(end 323.01434 2.01549)
		(width 0.14224)
		(layer "In6.Cu")
		(net "DELTA_L_85_5INCH_IN3_DP")
	)
	(segment
		(start 316.73419 0.143764)
		(end 320.203576 0.143764)
		(width 0.14224)
		(layer "In6.Cu")
		(net "DELTA_L_85_5INCH_IN3_DP")
	)
	(segment
		(start 351.890838 -2.09169)
		(end 352.055176 -1.976628)
		(width 0.14224)
		(layer "In6.Cu")
		(net "DELTA_L_85_5INCH_IN3_DP")
	)
	(segment
		(start 328.276204 -1.992884)
		(end 328.988928 2.040636)
		(width 0.14224)
		(layer "In6.Cu")
		(net "DELTA_L_85_5INCH_IN3_DP")
	)
	(segment
		(start 350.749362 1.994916)
		(end 350.99879 1.639062)
		(width 0.14224)
		(layer "In6.Cu")
		(net "DELTA_L_85_5INCH_IN3_DP")
	)
	(segment
		(start 326.747632 -1.8669)
		(end 328.111866 -2.107946)
		(width 0.14224)
		(layer "In6.Cu")
		(net "DELTA_L_85_5INCH_IN3_DP")
	)
	(segment
		(start 344.13825 -1.928622)
		(end 344.837258 2.027682)
		(width 0.14224)
		(layer "In6.Cu")
		(net "DELTA_L_85_5INCH_IN3_DP")
	)
	(segment
		(start 358.33812 -1.679956)
		(end 358.453182 -1.844548)
		(width 0.14224)
		(layer "In6.Cu")
		(net "DELTA_L_85_5INCH_IN3_DP")
	)
	(segment
		(start 334.560926 -1.685036)
		(end 334.675988 -1.849882)
		(width 0.14224)
		(layer "In6.Cu")
		(net "DELTA_L_85_5INCH_IN3_DP")
	)
	(segment
		(start 354.489258 -1.85039)
		(end 355.853492 -2.091436)
		(width 0.14224)
		(layer "In6.Cu")
		(net "DELTA_L_85_5INCH_IN3_DP")
	)
	(segment
		(start 331.187806 1.652016)
		(end 330.599288 -1.679448)
		(width 0.14224)
		(layer "In6.Cu")
		(net "DELTA_L_85_5INCH_IN3_DP")
	)
	(segment
		(start 342.829642 2.027428)
		(end 343.07907 1.67132)
		(width 0.14224)
		(layer "In6.Cu")
		(net "DELTA_L_85_5INCH_IN3_DP")
	)
	(segment
		(start 332.242922 -1.970278)
		(end 332.956916 2.071624)
		(width 0.14224)
		(layer "In6.Cu")
		(net "DELTA_L_85_5INCH_IN3_DP")
	)
	(segment
		(start 338.642706 -1.827022)
		(end 340.00694 -2.068068)
		(width 0.14224)
		(layer "In6.Cu")
		(net "DELTA_L_85_5INCH_IN3_DP")
	)
	(segment
		(start 346.786962 1.995424)
		(end 347.03639 1.639316)
		(width 0.14224)
		(layer "In6.Cu")
		(net "DELTA_L_85_5INCH_IN3_DP")
	)
	(segment
		(start 341.236046 2.309114)
		(end 342.829642 2.027428)
		(width 0.14224)
		(layer "In6.Cu")
		(net "DELTA_L_85_5INCH_IN3_DP")
	)
	(segment
		(start 320.203576 0.143764)
		(end 320.802508 0.563118)
		(width 0.14224)
		(layer "In6.Cu")
		(net "DELTA_L_85_5INCH_IN3_DP")
	)
	(segment
		(start 328.988928 2.040636)
		(end 329.344528 2.290064)
		(width 0.14224)
		(layer "In6.Cu")
		(net "DELTA_L_85_5INCH_IN3_DP")
	)
	(segment
		(start 330.71435 -1.844294)
		(end 332.078584 -2.08534)
		(width 0.14224)
		(layer "In6.Cu")
		(net "DELTA_L_85_5INCH_IN3_DP")
	)
	(segment
		(start 326.977248 2.016506)
		(end 327.226676 1.660398)
		(width 0.14224)
		(layer "In6.Cu")
		(net "DELTA_L_85_5INCH_IN3_DP")
	)
	(segment
		(start 338.865464 2.018792)
		(end 339.114892 1.662684)
		(width 0.14224)
		(layer "In6.Cu")
		(net "DELTA_L_85_5INCH_IN3_DP")
	)
	(segment
		(start 359.817416 -2.085594)
		(end 359.981754 -1.970532)
		(width 0.14224)
		(layer "In6.Cu")
		(net "DELTA_L_85_5INCH_IN3_DP")
	)
	(segment
		(start 332.078584 -2.08534)
		(end 332.242922 -1.970278)
		(width 0.14224)
		(layer "In6.Cu")
		(net "DELTA_L_85_5INCH_IN3_DP")
	)
	(segment
		(start 330.938632 2.008378)
		(end 331.187806 1.652016)
		(width 0.14224)
		(layer "In6.Cu")
		(net "DELTA_L_85_5INCH_IN3_DP")
	)
	(segment
		(start 334.90662 2.039366)
		(end 335.156048 1.683258)
		(width 0.14224)
		(layer "In6.Cu")
		(net "DELTA_L_85_5INCH_IN3_DP")
	)
	(segment
		(start 323.01434 2.01549)
		(end 323.263768 1.659382)
		(width 0.14224)
		(layer "In6.Cu")
		(net "DELTA_L_85_5INCH_IN3_DP")
	)
	(segment
		(start 353.116388 2.264664)
		(end 354.709984 1.982978)
		(width 0.14224)
		(layer "In6.Cu")
		(net "DELTA_L_85_5INCH_IN3_DP")
	)
	(segment
		(start 342.494616 -1.638046)
		(end 342.609678 -1.802638)
		(width 0.14224)
		(layer "In6.Cu")
		(net "DELTA_L_85_5INCH_IN3_DP")
	)
	(segment
		(start 342.609678 -1.802638)
		(end 343.973912 -2.043684)
		(width 0.14224)
		(layer "In6.Cu")
		(net "DELTA_L_85_5INCH_IN3_DP")
	)
	(segment
		(start 322.79209 -1.826006)
		(end 324.156324 -2.067052)
		(width 0.14224)
		(layer "In6.Cu")
		(net "DELTA_L_85_5INCH_IN3_DP")
	)
	(segment
		(start 350.99879 1.639062)
		(end 350.411542 -1.686052)
		(width 0.14224)
		(layer "In6.Cu")
		(net "DELTA_L_85_5INCH_IN3_DP")
	)
	(segment
		(start 330.599288 -1.679448)
		(end 330.71435 -1.844294)
		(width 0.14224)
		(layer "In6.Cu")
		(net "DELTA_L_85_5INCH_IN3_DP")
	)
	(segment
		(start 324.156324 -2.067052)
		(end 324.320662 -1.95199)
		(width 0.14224)
		(layer "In6.Cu")
		(net "DELTA_L_85_5INCH_IN3_DP")
	)
	(segment
		(start 352.760026 2.015236)
		(end 353.116388 2.264664)
		(width 0.14224)
		(layer "In6.Cu")
		(net "DELTA_L_85_5INCH_IN3_DP")
	)
	(segment
		(start 350.411542 -1.686052)
		(end 350.526604 -1.850644)
		(width 0.14224)
		(layer "In6.Cu")
		(net "DELTA_L_85_5INCH_IN3_DP")
	)
	(segment
		(start 356.01783 -1.976374)
		(end 356.723188 2.017268)
		(width 0.14224)
		(layer "In6.Cu")
		(net "DELTA_L_85_5INCH_IN3_DP")
	)
	(segment
		(start 354.709984 1.982978)
		(end 354.959412 1.627378)
		(width 0.14224)
		(layer "In6.Cu")
		(net "DELTA_L_85_5INCH_IN3_DP")
	)
	(segment
		(start 348.799658 2.027428)
		(end 349.155766 2.276856)
		(width 0.14224)
		(layer "In6.Cu")
		(net "DELTA_L_85_5INCH_IN3_DP")
	)
	(segment
		(start 345.193366 2.27711)
		(end 346.786962 1.995424)
		(width 0.14224)
		(layer "In6.Cu")
		(net "DELTA_L_85_5INCH_IN3_DP")
	)
	(segment
		(start 333.313024 2.321052)
		(end 334.90662 2.039366)
		(width 0.14224)
		(layer "In6.Cu")
		(net "DELTA_L_85_5INCH_IN3_DP")
	)
	(segment
		(start 343.973912 -2.043684)
		(end 344.13825 -1.928622)
		(width 0.14224)
		(layer "In6.Cu")
		(net "DELTA_L_85_5INCH_IN3_DP")
	)
	(segment
		(start 355.853492 -2.091436)
		(end 356.01783 -1.976374)
		(width 0.14224)
		(layer "In6.Cu")
		(net "DELTA_L_85_5INCH_IN3_DP")
	)
	(segment
		(start 361.103672 0.143764)
		(end 364.519972 0.143764)
		(width 0.14224)
		(layer "In6.Cu")
		(net "DELTA_L_85_5INCH_IN3_DP")
	)
	(segment
		(start 346.452698 -1.664208)
		(end 346.56776 -1.8288)
		(width 0.14224)
		(layer "In6.Cu")
		(net "DELTA_L_85_5INCH_IN3_DP")
	)
	(segment
		(start 320.802508 0.563118)
		(end 321.064636 2.047748)
		(width 0.14224)
		(layer "In6.Cu")
		(net "DELTA_L_85_5INCH_IN3_DP")
	)
	(segment
		(start 322.677028 -1.661414)
		(end 322.79209 -1.826006)
		(width 0.14224)
		(layer "In6.Cu")
		(net "DELTA_L_85_5INCH_IN3_DP")
	)
	(segment
		(start 340.879938 2.059686)
		(end 341.236046 2.309114)
		(width 0.14224)
		(layer "In6.Cu")
		(net "DELTA_L_85_5INCH_IN3_DP")
	)
	(segment
		(start 356.723188 2.017268)
		(end 357.079296 2.266696)
		(width 0.14224)
		(layer "In6.Cu")
		(net "DELTA_L_85_5INCH_IN3_DP")
	)
	(segment
		(start 343.07907 1.67132)
		(end 342.494616 -1.638046)
		(width 0.14224)
		(layer "In6.Cu")
		(net "DELTA_L_85_5INCH_IN3_DP")
	)
	(segment
		(start 328.111866 -2.107946)
		(end 328.276204 -1.992884)
		(width 0.14224)
		(layer "In6.Cu")
		(net "DELTA_L_85_5INCH_IN3_DP")
	)
	(segment
		(start 327.226676 1.660398)
		(end 326.63257 -1.702054)
		(width 0.14224)
		(layer "In6.Cu")
		(net "DELTA_L_85_5INCH_IN3_DP")
	)
	(segment
		(start 365.463074 -0.247142)
		(end 364.810802 -0.429006)
		(width 0.12954)
		(layer "F.Cu")
		(net "DELTA_L_85_5INCH_IN3_DN")
	)
	(segment
		(start 315.791088 -0.247142)
		(end 316.44336 -0.429006)
		(width 0.12954)
		(layer "F.Cu")
		(net "DELTA_L_85_5INCH_IN3_DN")
	)
	(segment
		(start 330.301092 -1.745742)
		(end 330.88961 1.585976)
		(width 0.14224)
		(layer "In6.Cu")
		(net "DELTA_L_85_5INCH_IN3_DN")
	)
	(segment
		(start 325.449692 1.999996)
		(end 325.2851 1.88468)
		(width 0.14224)
		(layer "In6.Cu")
		(net "DELTA_L_85_5INCH_IN3_DN")
	)
	(segment
		(start 350.362266 -2.1082)
		(end 350.113346 -1.752092)
		(width 0.14224)
		(layer "In6.Cu")
		(net "DELTA_L_85_5INCH_IN3_DN")
	)
	(segment
		(start 316.73419 -0.138176)
		(end 316.44336 -0.429006)
		(width 0.14224)
		(layer "In6.Cu")
		(net "DELTA_L_85_5INCH_IN3_DN")
	)
	(segment
		(start 324.222364 -2.365248)
		(end 322.627752 -2.083562)
		(width 0.14224)
		(layer "In6.Cu")
		(net "DELTA_L_85_5INCH_IN3_DN")
	)
	(segment
		(start 350.113346 -1.752092)
		(end 350.700594 1.573022)
		(width 0.14224)
		(layer "In6.Cu")
		(net "DELTA_L_85_5INCH_IN3_DN")
	)
	(segment
		(start 338.478368 -2.084578)
		(end 338.229448 -1.72847)
		(width 0.14224)
		(layer "In6.Cu")
		(net "DELTA_L_85_5INCH_IN3_DN")
	)
	(segment
		(start 320.292476 -0.138176)
		(end 316.73419 -0.138176)
		(width 0.14224)
		(layer "In6.Cu")
		(net "DELTA_L_85_5INCH_IN3_DN")
	)
	(segment
		(start 342.19642 -1.704086)
		(end 342.780874 1.60528)
		(width 0.14224)
		(layer "In6.Cu")
		(net "DELTA_L_85_5INCH_IN3_DN")
	)
	(segment
		(start 340.428834 -2.11709)
		(end 340.07298 -2.366264)
		(width 0.14224)
		(layer "In6.Cu")
		(net "DELTA_L_85_5INCH_IN3_DN")
	)
	(segment
		(start 351.956878 -2.389886)
		(end 350.362266 -2.1082)
		(width 0.14224)
		(layer "In6.Cu")
		(net "DELTA_L_85_5INCH_IN3_DN")
	)
	(segment
		(start 322.965572 1.593342)
		(end 322.850256 1.757934)
		(width 0.14224)
		(layer "In6.Cu")
		(net "DELTA_L_85_5INCH_IN3_DN")
	)
	(segment
		(start 360.506772 -0.620014)
		(end 360.23931 -2.134616)
		(width 0.14224)
		(layer "In6.Cu")
		(net "DELTA_L_85_5INCH_IN3_DN")
	)
	(segment
		(start 348.353888 -2.118868)
		(end 347.998034 -2.368042)
		(width 0.14224)
		(layer "In6.Cu")
		(net "DELTA_L_85_5INCH_IN3_DN")
	)
	(segment
		(start 326.813164 1.75895)
		(end 325.449692 1.999996)
		(width 0.14224)
		(layer "In6.Cu")
		(net "DELTA_L_85_5INCH_IN3_DN")
	)
	(segment
		(start 337.173316 1.886966)
		(end 336.462116 -2.13995)
		(width 0.14224)
		(layer "In6.Cu")
		(net "DELTA_L_85_5INCH_IN3_DN")
	)
	(segment
		(start 342.665558 1.769872)
		(end 341.302086 2.010918)
		(width 0.14224)
		(layer "In6.Cu")
		(net "DELTA_L_85_5INCH_IN3_DN")
	)
	(segment
		(start 345.259406 1.978914)
		(end 345.094814 1.863598)
		(width 0.14224)
		(layer "In6.Cu")
		(net "DELTA_L_85_5INCH_IN3_DN")
	)
	(segment
		(start 322.627752 -2.083562)
		(end 322.378832 -1.727454)
		(width 0.14224)
		(layer "In6.Cu")
		(net "DELTA_L_85_5INCH_IN3_DN")
	)
	(segment
		(start 356.275386 -2.140458)
		(end 355.919532 -2.389632)
		(width 0.14224)
		(layer "In6.Cu")
		(net "DELTA_L_85_5INCH_IN3_DN")
	)
	(segment
		(start 334.742536 1.78181)
		(end 333.379064 2.022856)
		(width 0.14224)
		(layer "In6.Cu")
		(net "DELTA_L_85_5INCH_IN3_DN")
	)
	(segment
		(start 325.2851 1.88468)
		(end 324.578218 -2.116074)
		(width 0.14224)
		(layer "In6.Cu")
		(net "DELTA_L_85_5INCH_IN3_DN")
	)
	(segment
		(start 344.395806 -2.092706)
		(end 344.039952 -2.34188)
		(width 0.14224)
		(layer "In6.Cu")
		(net "DELTA_L_85_5INCH_IN3_DN")
	)
	(segment
		(start 330.88961 1.585976)
		(end 330.774294 1.750822)
		(width 0.14224)
		(layer "In6.Cu")
		(net "DELTA_L_85_5INCH_IN3_DN")
	)
	(segment
		(start 334.857852 1.617218)
		(end 334.742536 1.78181)
		(width 0.14224)
		(layer "In6.Cu")
		(net "DELTA_L_85_5INCH_IN3_DN")
	)
	(segment
		(start 321.486784 1.99898)
		(end 321.322192 1.883664)
		(width 0.14224)
		(layer "In6.Cu")
		(net "DELTA_L_85_5INCH_IN3_DN")
	)
	(segment
		(start 338.816696 1.596644)
		(end 338.70138 1.761236)
		(width 0.14224)
		(layer "In6.Cu")
		(net "DELTA_L_85_5INCH_IN3_DN")
	)
	(segment
		(start 333.379064 2.022856)
		(end 333.214472 1.90754)
		(width 0.14224)
		(layer "In6.Cu")
		(net "DELTA_L_85_5INCH_IN3_DN")
	)
	(segment
		(start 330.550012 -2.10185)
		(end 330.301092 -1.745742)
		(width 0.14224)
		(layer "In6.Cu")
		(net "DELTA_L_85_5INCH_IN3_DN")
	)
	(segment
		(start 352.312732 -2.140712)
		(end 351.956878 -2.389886)
		(width 0.14224)
		(layer "In6.Cu")
		(net "DELTA_L_85_5INCH_IN3_DN")
	)
	(segment
		(start 346.403422 -2.086356)
		(end 346.154502 -1.730248)
		(width 0.14224)
		(layer "In6.Cu")
		(net "DELTA_L_85_5INCH_IN3_DN")
	)
	(segment
		(start 346.154502 -1.730248)
		(end 346.738194 1.573276)
		(width 0.14224)
		(layer "In6.Cu")
		(net "DELTA_L_85_5INCH_IN3_DN")
	)
	(segment
		(start 358.624124 1.562862)
		(end 358.508808 1.727454)
		(width 0.14224)
		(layer "In6.Cu")
		(net "DELTA_L_85_5INCH_IN3_DN")
	)
	(segment
		(start 332.500478 -2.134362)
		(end 332.144624 -2.383536)
		(width 0.14224)
		(layer "In6.Cu")
		(net "DELTA_L_85_5INCH_IN3_DN")
	)
	(segment
		(start 340.07298 -2.366264)
		(end 338.478368 -2.084578)
		(width 0.14224)
		(layer "In6.Cu")
		(net "DELTA_L_85_5INCH_IN3_DN")
	)
	(segment
		(start 324.578218 -2.116074)
		(end 324.222364 -2.365248)
		(width 0.14224)
		(layer "In6.Cu")
		(net "DELTA_L_85_5INCH_IN3_DN")
	)
	(segment
		(start 333.214472 1.90754)
		(end 332.500478 -2.134362)
		(width 0.14224)
		(layer "In6.Cu")
		(net "DELTA_L_85_5INCH_IN3_DN")
	)
	(segment
		(start 353.017582 1.851152)
		(end 352.312732 -2.140712)
		(width 0.14224)
		(layer "In6.Cu")
		(net "DELTA_L_85_5INCH_IN3_DN")
	)
	(segment
		(start 321.322192 1.883664)
		(end 321.060064 0.399034)
		(width 0.14224)
		(layer "In6.Cu")
		(net "DELTA_L_85_5INCH_IN3_DN")
	)
	(segment
		(start 359.086404 -2.243074)
		(end 358.288844 -2.102104)
		(width 0.14224)
		(layer "In6.Cu")
		(net "DELTA_L_85_5INCH_IN3_DN")
	)
	(segment
		(start 355.919532 -2.389632)
		(end 354.32492 -2.107946)
		(width 0.14224)
		(layer "In6.Cu")
		(net "DELTA_L_85_5INCH_IN3_DN")
	)
	(segment
		(start 350.585278 1.73736)
		(end 349.221806 1.97866)
		(width 0.14224)
		(layer "In6.Cu")
		(net "DELTA_L_85_5INCH_IN3_DN")
	)
	(segment
		(start 350.700594 1.573022)
		(end 350.585278 1.73736)
		(width 0.14224)
		(layer "In6.Cu")
		(net "DELTA_L_85_5INCH_IN3_DN")
	)
	(segment
		(start 358.039924 -1.745996)
		(end 358.624124 1.562862)
		(width 0.14224)
		(layer "In6.Cu")
		(net "DELTA_L_85_5INCH_IN3_DN")
	)
	(segment
		(start 364.519972 -0.138176)
		(end 361.192826 -0.138176)
		(width 0.14224)
		(layer "In6.Cu")
		(net "DELTA_L_85_5INCH_IN3_DN")
	)
	(segment
		(start 360.23931 -2.134616)
		(end 359.883456 -2.38379)
		(width 0.14224)
		(layer "In6.Cu")
		(net "DELTA_L_85_5INCH_IN3_DN")
	)
	(segment
		(start 341.137494 1.895602)
		(end 340.428834 -2.11709)
		(width 0.14224)
		(layer "In6.Cu")
		(net "DELTA_L_85_5INCH_IN3_DN")
	)
	(segment
		(start 330.774294 1.750822)
		(end 329.410822 1.991868)
		(width 0.14224)
		(layer "In6.Cu")
		(net "DELTA_L_85_5INCH_IN3_DN")
	)
	(segment
		(start 358.288844 -2.102104)
		(end 358.039924 -1.745996)
		(width 0.14224)
		(layer "In6.Cu")
		(net "DELTA_L_85_5INCH_IN3_DN")
	)
	(segment
		(start 336.106262 -2.389124)
		(end 334.51165 -2.107438)
		(width 0.14224)
		(layer "In6.Cu")
		(net "DELTA_L_85_5INCH_IN3_DN")
	)
	(segment
		(start 346.622878 1.737868)
		(end 345.259406 1.978914)
		(width 0.14224)
		(layer "In6.Cu")
		(net "DELTA_L_85_5INCH_IN3_DN")
	)
	(segment
		(start 334.26273 -1.75133)
		(end 334.857852 1.617218)
		(width 0.14224)
		(layer "In6.Cu")
		(net "DELTA_L_85_5INCH_IN3_DN")
	)
	(segment
		(start 334.51165 -2.107438)
		(end 334.26273 -1.75133)
		(width 0.14224)
		(layer "In6.Cu")
		(net "DELTA_L_85_5INCH_IN3_DN")
	)
	(segment
		(start 354.076 -1.751838)
		(end 354.661216 1.561084)
		(width 0.14224)
		(layer "In6.Cu")
		(net "DELTA_L_85_5INCH_IN3_DN")
	)
	(segment
		(start 356.980744 1.853184)
		(end 356.275386 -2.140458)
		(width 0.14224)
		(layer "In6.Cu")
		(net "DELTA_L_85_5INCH_IN3_DN")
	)
	(segment
		(start 328.53376 -2.156968)
		(end 328.177906 -2.406142)
		(width 0.14224)
		(layer "In6.Cu")
		(net "DELTA_L_85_5INCH_IN3_DN")
	)
	(segment
		(start 342.780874 1.60528)
		(end 342.665558 1.769872)
		(width 0.14224)
		(layer "In6.Cu")
		(net "DELTA_L_85_5INCH_IN3_DN")
	)
	(segment
		(start 326.334374 -1.768348)
		(end 326.92848 1.594358)
		(width 0.14224)
		(layer "In6.Cu")
		(net "DELTA_L_85_5INCH_IN3_DN")
	)
	(segment
		(start 347.998034 -2.368042)
		(end 346.403422 -2.086356)
		(width 0.14224)
		(layer "In6.Cu")
		(net "DELTA_L_85_5INCH_IN3_DN")
	)
	(segment
		(start 338.229448 -1.72847)
		(end 338.816696 1.596644)
		(width 0.14224)
		(layer "In6.Cu")
		(net "DELTA_L_85_5INCH_IN3_DN")
	)
	(segment
		(start 337.337908 2.002282)
		(end 337.173316 1.886966)
		(width 0.14224)
		(layer "In6.Cu")
		(net "DELTA_L_85_5INCH_IN3_DN")
	)
	(segment
		(start 354.661216 1.561084)
		(end 354.5459 1.725422)
		(width 0.14224)
		(layer "In6.Cu")
		(net "DELTA_L_85_5INCH_IN3_DN")
	)
	(segment
		(start 354.5459 1.725422)
		(end 353.182428 1.966468)
		(width 0.14224)
		(layer "In6.Cu")
		(net "DELTA_L_85_5INCH_IN3_DN")
	)
	(segment
		(start 322.378832 -1.727454)
		(end 322.965572 1.593342)
		(width 0.14224)
		(layer "In6.Cu")
		(net "DELTA_L_85_5INCH_IN3_DN")
	)
	(segment
		(start 342.44534 -2.060194)
		(end 342.19642 -1.704086)
		(width 0.14224)
		(layer "In6.Cu")
		(net "DELTA_L_85_5INCH_IN3_DN")
	)
	(segment
		(start 326.583294 -2.124456)
		(end 326.334374 -1.768348)
		(width 0.14224)
		(layer "In6.Cu")
		(net "DELTA_L_85_5INCH_IN3_DN")
	)
	(segment
		(start 328.177906 -2.406142)
		(end 326.583294 -2.124456)
		(width 0.14224)
		(layer "In6.Cu")
		(net "DELTA_L_85_5INCH_IN3_DN")
	)
	(segment
		(start 359.883456 -2.38379)
		(end 359.086404 -2.243074)
		(width 0.14224)
		(layer "In6.Cu")
		(net "DELTA_L_85_5INCH_IN3_DN")
	)
	(segment
		(start 358.508808 1.727454)
		(end 357.145336 1.9685)
		(width 0.14224)
		(layer "In6.Cu")
		(net "DELTA_L_85_5INCH_IN3_DN")
	)
	(segment
		(start 361.192826 -0.138176)
		(end 360.506772 -0.620014)
		(width 0.14224)
		(layer "In6.Cu")
		(net "DELTA_L_85_5INCH_IN3_DN")
	)
	(segment
		(start 341.302086 2.010918)
		(end 341.137494 1.895602)
		(width 0.14224)
		(layer "In6.Cu")
		(net "DELTA_L_85_5INCH_IN3_DN")
	)
	(segment
		(start 338.70138 1.761236)
		(end 337.337908 2.002282)
		(width 0.14224)
		(layer "In6.Cu")
		(net "DELTA_L_85_5INCH_IN3_DN")
	)
	(segment
		(start 321.060064 0.399034)
		(end 320.292476 -0.138176)
		(width 0.14224)
		(layer "In6.Cu")
		(net "DELTA_L_85_5INCH_IN3_DN")
	)
	(segment
		(start 344.039952 -2.34188)
		(end 342.44534 -2.060194)
		(width 0.14224)
		(layer "In6.Cu")
		(net "DELTA_L_85_5INCH_IN3_DN")
	)
	(segment
		(start 329.410822 1.991868)
		(end 329.246484 1.876552)
		(width 0.14224)
		(layer "In6.Cu")
		(net "DELTA_L_85_5INCH_IN3_DN")
	)
	(segment
		(start 357.145336 1.9685)
		(end 356.980744 1.853184)
		(width 0.14224)
		(layer "In6.Cu")
		(net "DELTA_L_85_5INCH_IN3_DN")
	)
	(segment
		(start 345.094814 1.863598)
		(end 344.395806 -2.092706)
		(width 0.14224)
		(layer "In6.Cu")
		(net "DELTA_L_85_5INCH_IN3_DN")
	)
	(segment
		(start 364.810802 -0.429006)
		(end 364.519972 -0.138176)
		(width 0.14224)
		(layer "In6.Cu")
		(net "DELTA_L_85_5INCH_IN3_DN")
	)
	(segment
		(start 332.144624 -2.383536)
		(end 330.550012 -2.10185)
		(width 0.14224)
		(layer "In6.Cu")
		(net "DELTA_L_85_5INCH_IN3_DN")
	)
	(segment
		(start 329.246484 1.876552)
		(end 328.53376 -2.156968)
		(width 0.14224)
		(layer "In6.Cu")
		(net "DELTA_L_85_5INCH_IN3_DN")
	)
	(segment
		(start 353.182428 1.966468)
		(end 353.017582 1.851152)
		(width 0.14224)
		(layer "In6.Cu")
		(net "DELTA_L_85_5INCH_IN3_DN")
	)
	(segment
		(start 326.92848 1.594358)
		(end 326.813164 1.75895)
		(width 0.14224)
		(layer "In6.Cu")
		(net "DELTA_L_85_5INCH_IN3_DN")
	)
	(segment
		(start 322.850256 1.757934)
		(end 321.486784 1.99898)
		(width 0.14224)
		(layer "In6.Cu")
		(net "DELTA_L_85_5INCH_IN3_DN")
	)
	(segment
		(start 349.221806 1.97866)
		(end 349.057214 1.863344)
		(width 0.14224)
		(layer "In6.Cu")
		(net "DELTA_L_85_5INCH_IN3_DN")
	)
	(segment
		(start 346.738194 1.573276)
		(end 346.622878 1.737868)
		(width 0.14224)
		(layer "In6.Cu")
		(net "DELTA_L_85_5INCH_IN3_DN")
	)
	(segment
		(start 336.462116 -2.13995)
		(end 336.106262 -2.389124)
		(width 0.14224)
		(layer "In6.Cu")
		(net "DELTA_L_85_5INCH_IN3_DN")
	)
	(segment
		(start 354.32492 -2.107946)
		(end 354.076 -1.751838)
		(width 0.14224)
		(layer "In6.Cu")
		(net "DELTA_L_85_5INCH_IN3_DN")
	)
	(segment
		(start 349.057214 1.863344)
		(end 348.353888 -2.118868)
		(width 0.14224)
		(layer "In6.Cu")
		(net "DELTA_L_85_5INCH_IN3_DN")
	)
	(segment
		(start 390.287764 6.399784)
		(end 390.940036 6.581648)
		(width 0.12954)
		(layer "F.Cu")
		(net "DELTA_L_85_5INCH_IN2_DP")
	)
	(segment
		(start 439.95975 6.399784)
		(end 439.307478 6.581648)
		(width 0.12954)
		(layer "F.Cu")
		(net "DELTA_L_85_5INCH_IN2_DP")
	)
	(segment
		(start 414.503616 4.078986)
		(end 414.667954 4.194048)
		(width 0.14224)
		(layer "In4.Cu")
		(net "DELTA_L_85_5INCH_IN2_DP")
	)
	(segment
		(start 399.880328 8.445246)
		(end 401.473924 8.16356)
		(width 0.14224)
		(layer "In4.Cu")
		(net "DELTA_L_85_5INCH_IN2_DP")
	)
	(segment
		(start 417.106354 4.344416)
		(end 418.470588 4.10337)
		(width 0.14224)
		(layer "In4.Cu")
		(net "DELTA_L_85_5INCH_IN2_DP")
	)
	(segment
		(start 416.991292 4.509008)
		(end 417.106354 4.344416)
		(width 0.14224)
		(layer "In4.Cu")
		(net "DELTA_L_85_5INCH_IN2_DP")
	)
	(segment
		(start 421.533066 7.78637)
		(end 420.949374 4.482846)
		(width 0.14224)
		(layer "In4.Cu")
		(net "DELTA_L_85_5INCH_IN2_DP")
	)
	(segment
		(start 409.403296 8.18642)
		(end 409.652724 7.830312)
		(width 0.14224)
		(layer "In4.Cu")
		(net "DELTA_L_85_5INCH_IN2_DP")
	)
	(segment
		(start 390.940036 6.581648)
		(end 391.230866 6.290818)
		(width 0.14224)
		(layer "In4.Cu")
		(net "DELTA_L_85_5INCH_IN2_DP")
	)
	(segment
		(start 428.985934 4.296664)
		(end 430.350168 4.055618)
		(width 0.14224)
		(layer "In4.Cu")
		(net "DELTA_L_85_5INCH_IN2_DP")
	)
	(segment
		(start 432.949858 4.302506)
		(end 434.314092 4.06146)
		(width 0.14224)
		(layer "In4.Cu")
		(net "DELTA_L_85_5INCH_IN2_DP")
	)
	(segment
		(start 401.129246 4.445)
		(end 401.244308 4.280154)
		(width 0.14224)
		(layer "In4.Cu")
		(net "DELTA_L_85_5INCH_IN2_DP")
	)
	(segment
		(start 417.575746 7.818374)
		(end 416.991292 4.509008)
		(width 0.14224)
		(layer "In4.Cu")
		(net "DELTA_L_85_5INCH_IN2_DP")
	)
	(segment
		(start 409.172664 4.297172)
		(end 410.536898 4.056126)
		(width 0.14224)
		(layer "In4.Cu")
		(net "DELTA_L_85_5INCH_IN2_DP")
	)
	(segment
		(start 394.700252 6.290818)
		(end 395.299184 6.710172)
		(width 0.14224)
		(layer "In4.Cu")
		(net "DELTA_L_85_5INCH_IN2_DP")
	)
	(segment
		(start 405.684482 7.79907)
		(end 405.095964 4.467606)
		(width 0.14224)
		(layer "In4.Cu")
		(net "DELTA_L_85_5INCH_IN2_DP")
	)
	(segment
		(start 402.77288 4.15417)
		(end 403.485604 8.18769)
		(width 0.14224)
		(layer "In4.Cu")
		(net "DELTA_L_85_5INCH_IN2_DP")
	)
	(segment
		(start 422.593008 4.19227)
		(end 423.296334 8.174482)
		(width 0.14224)
		(layer "In4.Cu")
		(net "DELTA_L_85_5INCH_IN2_DP")
	)
	(segment
		(start 413.02432 4.484624)
		(end 413.139382 4.320032)
		(width 0.14224)
		(layer "In4.Cu")
		(net "DELTA_L_85_5INCH_IN2_DP")
	)
	(segment
		(start 424.908218 4.461002)
		(end 425.02328 4.29641)
		(width 0.14224)
		(layer "In4.Cu")
		(net "DELTA_L_85_5INCH_IN2_DP")
	)
	(segment
		(start 439.016648 6.290818)
		(end 439.307478 6.581648)
		(width 0.14224)
		(layer "In4.Cu")
		(net "DELTA_L_85_5INCH_IN2_DP")
	)
	(segment
		(start 425.495466 7.786116)
		(end 424.908218 4.461002)
		(width 0.14224)
		(layer "In4.Cu")
		(net "DELTA_L_85_5INCH_IN2_DP")
	)
	(segment
		(start 420.949374 4.482846)
		(end 421.064436 4.318254)
		(width 0.14224)
		(layer "In4.Cu")
		(net "DELTA_L_85_5INCH_IN2_DP")
	)
	(segment
		(start 397.288766 4.321048)
		(end 398.653 4.080002)
		(width 0.14224)
		(layer "In4.Cu")
		(net "DELTA_L_85_5INCH_IN2_DP")
	)
	(segment
		(start 405.211026 4.30276)
		(end 406.57526 4.061714)
		(width 0.14224)
		(layer "In4.Cu")
		(net "DELTA_L_85_5INCH_IN2_DP")
	)
	(segment
		(start 399.52422 8.195818)
		(end 399.880328 8.445246)
		(width 0.14224)
		(layer "In4.Cu")
		(net "DELTA_L_85_5INCH_IN2_DP")
	)
	(segment
		(start 401.723352 7.807452)
		(end 401.129246 4.445)
		(width 0.14224)
		(layer "In4.Cu")
		(net "DELTA_L_85_5INCH_IN2_DP")
	)
	(segment
		(start 409.652724 7.830312)
		(end 409.057602 4.462018)
		(width 0.14224)
		(layer "In4.Cu")
		(net "DELTA_L_85_5INCH_IN2_DP")
	)
	(segment
		(start 419.690042 8.424164)
		(end 421.283638 8.142478)
		(width 0.14224)
		(layer "In4.Cu")
		(net "DELTA_L_85_5INCH_IN2_DP")
	)
	(segment
		(start 402.608542 4.039108)
		(end 402.77288 4.15417)
		(width 0.14224)
		(layer "In4.Cu")
		(net "DELTA_L_85_5INCH_IN2_DP")
	)
	(segment
		(start 429.20666 8.130032)
		(end 429.456088 7.774432)
		(width 0.14224)
		(layer "In4.Cu")
		(net "DELTA_L_85_5INCH_IN2_DP")
	)
	(segment
		(start 395.91742 8.44423)
		(end 397.511016 8.162544)
		(width 0.14224)
		(layer "In4.Cu")
		(net "DELTA_L_85_5INCH_IN2_DP")
	)
	(segment
		(start 430.514506 4.17068)
		(end 431.219864 8.164322)
		(width 0.14224)
		(layer "In4.Cu")
		(net "DELTA_L_85_5INCH_IN2_DP")
	)
	(segment
		(start 432.834796 4.467098)
		(end 432.949858 4.302506)
		(width 0.14224)
		(layer "In4.Cu")
		(net "DELTA_L_85_5INCH_IN2_DP")
	)
	(segment
		(start 421.064436 4.318254)
		(end 422.42867 4.077208)
		(width 0.14224)
		(layer "In4.Cu")
		(net "DELTA_L_85_5INCH_IN2_DP")
	)
	(segment
		(start 413.139382 4.320032)
		(end 414.503616 4.078986)
		(width 0.14224)
		(layer "In4.Cu")
		(net "DELTA_L_85_5INCH_IN2_DP")
	)
	(segment
		(start 425.246038 8.14197)
		(end 425.495466 7.786116)
		(width 0.14224)
		(layer "In4.Cu")
		(net "DELTA_L_85_5INCH_IN2_DP")
	)
	(segment
		(start 415.732722 8.456168)
		(end 417.326318 8.174482)
		(width 0.14224)
		(layer "In4.Cu")
		(net "DELTA_L_85_5INCH_IN2_DP")
	)
	(segment
		(start 418.470588 4.10337)
		(end 418.634926 4.218432)
		(width 0.14224)
		(layer "In4.Cu")
		(net "DELTA_L_85_5INCH_IN2_DP")
	)
	(segment
		(start 406.739598 4.176776)
		(end 407.453592 8.218678)
		(width 0.14224)
		(layer "In4.Cu")
		(net "DELTA_L_85_5INCH_IN2_DP")
	)
	(segment
		(start 431.575972 8.41375)
		(end 433.169568 8.132064)
		(width 0.14224)
		(layer "In4.Cu")
		(net "DELTA_L_85_5INCH_IN2_DP")
	)
	(segment
		(start 435.600348 6.290818)
		(end 439.016648 6.290818)
		(width 0.14224)
		(layer "In4.Cu")
		(net "DELTA_L_85_5INCH_IN2_DP")
	)
	(segment
		(start 433.418996 7.775956)
		(end 432.834796 4.467098)
		(width 0.14224)
		(layer "In4.Cu")
		(net "DELTA_L_85_5INCH_IN2_DP")
	)
	(segment
		(start 418.634926 4.218432)
		(end 419.333934 8.174736)
		(width 0.14224)
		(layer "In4.Cu")
		(net "DELTA_L_85_5INCH_IN2_DP")
	)
	(segment
		(start 426.387514 4.055364)
		(end 426.551852 4.170426)
		(width 0.14224)
		(layer "In4.Cu")
		(net "DELTA_L_85_5INCH_IN2_DP")
	)
	(segment
		(start 413.611568 7.809738)
		(end 413.02432 4.484624)
		(width 0.14224)
		(layer "In4.Cu")
		(net "DELTA_L_85_5INCH_IN2_DP")
	)
	(segment
		(start 401.244308 4.280154)
		(end 402.608542 4.039108)
		(width 0.14224)
		(layer "In4.Cu")
		(net "DELTA_L_85_5INCH_IN2_DP")
	)
	(segment
		(start 434.745892 5.69087)
		(end 435.600348 6.290818)
		(width 0.14224)
		(layer "In4.Cu")
		(net "DELTA_L_85_5INCH_IN2_DP")
	)
	(segment
		(start 398.653 4.080002)
		(end 398.817338 4.195064)
		(width 0.14224)
		(layer "In4.Cu")
		(net "DELTA_L_85_5INCH_IN2_DP")
	)
	(segment
		(start 414.667954 4.194048)
		(end 415.376614 8.20674)
		(width 0.14224)
		(layer "In4.Cu")
		(net "DELTA_L_85_5INCH_IN2_DP")
	)
	(segment
		(start 421.283638 8.142478)
		(end 421.533066 7.78637)
		(width 0.14224)
		(layer "In4.Cu")
		(net "DELTA_L_85_5INCH_IN2_DP")
	)
	(segment
		(start 423.652442 8.42391)
		(end 425.246038 8.14197)
		(width 0.14224)
		(layer "In4.Cu")
		(net "DELTA_L_85_5INCH_IN2_DP")
	)
	(segment
		(start 430.350168 4.055618)
		(end 430.514506 4.17068)
		(width 0.14224)
		(layer "In4.Cu")
		(net "DELTA_L_85_5INCH_IN2_DP")
	)
	(segment
		(start 409.057602 4.462018)
		(end 409.172664 4.297172)
		(width 0.14224)
		(layer "In4.Cu")
		(net "DELTA_L_85_5INCH_IN2_DP")
	)
	(segment
		(start 391.230866 6.290818)
		(end 394.700252 6.290818)
		(width 0.14224)
		(layer "In4.Cu")
		(net "DELTA_L_85_5INCH_IN2_DP")
	)
	(segment
		(start 410.536898 4.056126)
		(end 410.701236 4.171188)
		(width 0.14224)
		(layer "In4.Cu")
		(net "DELTA_L_85_5INCH_IN2_DP")
	)
	(segment
		(start 405.095964 4.467606)
		(end 405.211026 4.30276)
		(width 0.14224)
		(layer "In4.Cu")
		(net "DELTA_L_85_5INCH_IN2_DP")
	)
	(segment
		(start 397.173704 4.48564)
		(end 397.288766 4.321048)
		(width 0.14224)
		(layer "In4.Cu")
		(net "DELTA_L_85_5INCH_IN2_DP")
	)
	(segment
		(start 397.760444 7.806436)
		(end 397.173704 4.48564)
		(width 0.14224)
		(layer "In4.Cu")
		(net "DELTA_L_85_5INCH_IN2_DP")
	)
	(segment
		(start 426.551852 4.170426)
		(end 427.256702 8.16229)
		(width 0.14224)
		(layer "In4.Cu")
		(net "DELTA_L_85_5INCH_IN2_DP")
	)
	(segment
		(start 413.36214 8.165846)
		(end 413.611568 7.809738)
		(width 0.14224)
		(layer "In4.Cu")
		(net "DELTA_L_85_5INCH_IN2_DP")
	)
	(segment
		(start 417.326318 8.174482)
		(end 417.575746 7.818374)
		(width 0.14224)
		(layer "In4.Cu")
		(net "DELTA_L_85_5INCH_IN2_DP")
	)
	(segment
		(start 401.473924 8.16356)
		(end 401.723352 7.807452)
		(width 0.14224)
		(layer "In4.Cu")
		(net "DELTA_L_85_5INCH_IN2_DP")
	)
	(segment
		(start 433.169568 8.132064)
		(end 433.418996 7.775956)
		(width 0.14224)
		(layer "In4.Cu")
		(net "DELTA_L_85_5INCH_IN2_DP")
	)
	(segment
		(start 427.256702 8.16229)
		(end 427.613064 8.411718)
		(width 0.14224)
		(layer "In4.Cu")
		(net "DELTA_L_85_5INCH_IN2_DP")
	)
	(segment
		(start 405.435308 8.155432)
		(end 405.684482 7.79907)
		(width 0.14224)
		(layer "In4.Cu")
		(net "DELTA_L_85_5INCH_IN2_DP")
	)
	(segment
		(start 407.453592 8.218678)
		(end 407.8097 8.468106)
		(width 0.14224)
		(layer "In4.Cu")
		(net "DELTA_L_85_5INCH_IN2_DP")
	)
	(segment
		(start 428.870872 4.461256)
		(end 428.985934 4.296664)
		(width 0.14224)
		(layer "In4.Cu")
		(net "DELTA_L_85_5INCH_IN2_DP")
	)
	(segment
		(start 415.376614 8.20674)
		(end 415.732722 8.456168)
		(width 0.14224)
		(layer "In4.Cu")
		(net "DELTA_L_85_5INCH_IN2_DP")
	)
	(segment
		(start 403.841204 8.437118)
		(end 405.435308 8.155432)
		(width 0.14224)
		(layer "In4.Cu")
		(net "DELTA_L_85_5INCH_IN2_DP")
	)
	(segment
		(start 397.511016 8.162544)
		(end 397.760444 7.806436)
		(width 0.14224)
		(layer "In4.Cu")
		(net "DELTA_L_85_5INCH_IN2_DP")
	)
	(segment
		(start 425.02328 4.29641)
		(end 426.387514 4.055364)
		(width 0.14224)
		(layer "In4.Cu")
		(net "DELTA_L_85_5INCH_IN2_DP")
	)
	(segment
		(start 411.412436 8.198104)
		(end 411.768544 8.447532)
		(width 0.14224)
		(layer "In4.Cu")
		(net "DELTA_L_85_5INCH_IN2_DP")
	)
	(segment
		(start 423.296334 8.174482)
		(end 423.652442 8.42391)
		(width 0.14224)
		(layer "In4.Cu")
		(net "DELTA_L_85_5INCH_IN2_DP")
	)
	(segment
		(start 395.299184 6.710172)
		(end 395.561312 8.194802)
		(width 0.14224)
		(layer "In4.Cu")
		(net "DELTA_L_85_5INCH_IN2_DP")
	)
	(segment
		(start 406.57526 4.061714)
		(end 406.739598 4.176776)
		(width 0.14224)
		(layer "In4.Cu")
		(net "DELTA_L_85_5INCH_IN2_DP")
	)
	(segment
		(start 429.456088 7.774432)
		(end 428.870872 4.461256)
		(width 0.14224)
		(layer "In4.Cu")
		(net "DELTA_L_85_5INCH_IN2_DP")
	)
	(segment
		(start 407.8097 8.468106)
		(end 409.403296 8.18642)
		(width 0.14224)
		(layer "In4.Cu")
		(net "DELTA_L_85_5INCH_IN2_DP")
	)
	(segment
		(start 427.613064 8.411718)
		(end 429.20666 8.130032)
		(width 0.14224)
		(layer "In4.Cu")
		(net "DELTA_L_85_5INCH_IN2_DP")
	)
	(segment
		(start 434.47843 4.176522)
		(end 434.745892 5.69087)
		(width 0.14224)
		(layer "In4.Cu")
		(net "DELTA_L_85_5INCH_IN2_DP")
	)
	(segment
		(start 411.768544 8.447532)
		(end 413.36214 8.165846)
		(width 0.14224)
		(layer "In4.Cu")
		(net "DELTA_L_85_5INCH_IN2_DP")
	)
	(segment
		(start 398.817338 4.195064)
		(end 399.52422 8.195818)
		(width 0.14224)
		(layer "In4.Cu")
		(net "DELTA_L_85_5INCH_IN2_DP")
	)
	(segment
		(start 410.701236 4.171188)
		(end 411.412436 8.198104)
		(width 0.14224)
		(layer "In4.Cu")
		(net "DELTA_L_85_5INCH_IN2_DP")
	)
	(segment
		(start 431.219864 8.164322)
		(end 431.575972 8.41375)
		(width 0.14224)
		(layer "In4.Cu")
		(net "DELTA_L_85_5INCH_IN2_DP")
	)
	(segment
		(start 434.314092 4.06146)
		(end 434.47843 4.176522)
		(width 0.14224)
		(layer "In4.Cu")
		(net "DELTA_L_85_5INCH_IN2_DP")
	)
	(segment
		(start 419.333934 8.174736)
		(end 419.690042 8.424164)
		(width 0.14224)
		(layer "In4.Cu")
		(net "DELTA_L_85_5INCH_IN2_DP")
	)
	(segment
		(start 403.485604 8.18769)
		(end 403.841204 8.437118)
		(width 0.14224)
		(layer "In4.Cu")
		(net "DELTA_L_85_5INCH_IN2_DP")
	)
	(segment
		(start 395.561312 8.194802)
		(end 395.91742 8.44423)
		(width 0.14224)
		(layer "In4.Cu")
		(net "DELTA_L_85_5INCH_IN2_DP")
	)
	(segment
		(start 422.42867 4.077208)
		(end 422.593008 4.19227)
		(width 0.14224)
		(layer "In4.Cu")
		(net "DELTA_L_85_5INCH_IN2_DP")
	)
	(segment
		(start 439.95975 5.899912)
		(end 439.307478 5.718048)
		(width 0.12954)
		(layer "F.Cu")
		(net "DELTA_L_85_5INCH_IN2_DN")
	)
	(segment
		(start 390.287764 5.899912)
		(end 390.940036 5.718048)
		(width 0.12954)
		(layer "F.Cu")
		(net "DELTA_L_85_5INCH_IN2_DN")
	)
	(segment
		(start 401.07997 4.022598)
		(end 400.83105 4.378706)
		(width 0.14224)
		(layer "In4.Cu")
		(net "DELTA_L_85_5INCH_IN2_DN")
	)
	(segment
		(start 419.756082 8.125968)
		(end 419.59149 8.010652)
		(width 0.14224)
		(layer "In4.Cu")
		(net "DELTA_L_85_5INCH_IN2_DN")
	)
	(segment
		(start 414.92551 4.029964)
		(end 414.569656 3.78079)
		(width 0.14224)
		(layer "In4.Cu")
		(net "DELTA_L_85_5INCH_IN2_DN")
	)
	(segment
		(start 424.610022 4.394962)
		(end 425.19727 7.720076)
		(width 0.14224)
		(layer "In4.Cu")
		(net "DELTA_L_85_5INCH_IN2_DN")
	)
	(segment
		(start 420.651178 4.416806)
		(end 421.23487 7.72033)
		(width 0.14224)
		(layer "In4.Cu")
		(net "DELTA_L_85_5INCH_IN2_DN")
	)
	(segment
		(start 415.63417 8.042656)
		(end 414.92551 4.029964)
		(width 0.14224)
		(layer "In4.Cu")
		(net "DELTA_L_85_5INCH_IN2_DN")
	)
	(segment
		(start 435.003448 5.52704)
		(end 434.735986 4.012438)
		(width 0.14224)
		(layer "In4.Cu")
		(net "DELTA_L_85_5INCH_IN2_DN")
	)
	(segment
		(start 411.669992 8.03402)
		(end 410.958792 4.007104)
		(width 0.14224)
		(layer "In4.Cu")
		(net "DELTA_L_85_5INCH_IN2_DN")
	)
	(segment
		(start 431.47742 8.000238)
		(end 430.772062 4.006596)
		(width 0.14224)
		(layer "In4.Cu")
		(net "DELTA_L_85_5INCH_IN2_DN")
	)
	(segment
		(start 397.124428 4.063492)
		(end 396.875508 4.4196)
		(width 0.14224)
		(layer "In4.Cu")
		(net "DELTA_L_85_5INCH_IN2_DN")
	)
	(segment
		(start 424.858942 4.038854)
		(end 424.610022 4.394962)
		(width 0.14224)
		(layer "In4.Cu")
		(net "DELTA_L_85_5INCH_IN2_DN")
	)
	(segment
		(start 408.759406 4.395724)
		(end 409.354528 7.764272)
		(width 0.14224)
		(layer "In4.Cu")
		(net "DELTA_L_85_5INCH_IN2_DN")
	)
	(segment
		(start 410.602938 3.75793)
		(end 409.008326 4.039616)
		(width 0.14224)
		(layer "In4.Cu")
		(net "DELTA_L_85_5INCH_IN2_DN")
	)
	(segment
		(start 432.78552 4.04495)
		(end 432.5366 4.401058)
		(width 0.14224)
		(layer "In4.Cu")
		(net "DELTA_L_85_5INCH_IN2_DN")
	)
	(segment
		(start 391.230866 6.008878)
		(end 390.940036 5.718048)
		(width 0.14224)
		(layer "In4.Cu")
		(net "DELTA_L_85_5INCH_IN2_DN")
	)
	(segment
		(start 426.809408 4.006342)
		(end 426.453554 3.757168)
		(width 0.14224)
		(layer "In4.Cu")
		(net "DELTA_L_85_5INCH_IN2_DN")
	)
	(segment
		(start 430.416208 3.757422)
		(end 428.821596 4.039108)
		(width 0.14224)
		(layer "In4.Cu")
		(net "DELTA_L_85_5INCH_IN2_DN")
	)
	(segment
		(start 409.239212 7.928864)
		(end 407.87574 8.16991)
		(width 0.14224)
		(layer "In4.Cu")
		(net "DELTA_L_85_5INCH_IN2_DN")
	)
	(segment
		(start 421.119554 7.884922)
		(end 419.756082 8.125968)
		(width 0.14224)
		(layer "In4.Cu")
		(net "DELTA_L_85_5INCH_IN2_DN")
	)
	(segment
		(start 434.735986 4.012438)
		(end 434.380132 3.763264)
		(width 0.14224)
		(layer "In4.Cu")
		(net "DELTA_L_85_5INCH_IN2_DN")
	)
	(segment
		(start 428.572676 4.395216)
		(end 429.157892 7.708138)
		(width 0.14224)
		(layer "In4.Cu")
		(net "DELTA_L_85_5INCH_IN2_DN")
	)
	(segment
		(start 405.046688 4.045204)
		(end 404.797768 4.401312)
		(width 0.14224)
		(layer "In4.Cu")
		(net "DELTA_L_85_5INCH_IN2_DN")
	)
	(segment
		(start 413.198056 7.90829)
		(end 411.834584 8.149336)
		(width 0.14224)
		(layer "In4.Cu")
		(net "DELTA_L_85_5INCH_IN2_DN")
	)
	(segment
		(start 404.797768 4.401312)
		(end 405.386286 7.73303)
		(width 0.14224)
		(layer "In4.Cu")
		(net "DELTA_L_85_5INCH_IN2_DN")
	)
	(segment
		(start 395.818868 8.030718)
		(end 395.55674 6.546088)
		(width 0.14224)
		(layer "In4.Cu")
		(net "DELTA_L_85_5INCH_IN2_DN")
	)
	(segment
		(start 402.674582 3.740912)
		(end 401.07997 4.022598)
		(width 0.14224)
		(layer "In4.Cu")
		(net "DELTA_L_85_5INCH_IN2_DN")
	)
	(segment
		(start 425.19727 7.720076)
		(end 425.081954 7.884414)
		(width 0.14224)
		(layer "In4.Cu")
		(net "DELTA_L_85_5INCH_IN2_DN")
	)
	(segment
		(start 429.157892 7.708138)
		(end 429.042576 7.872476)
		(width 0.14224)
		(layer "In4.Cu")
		(net "DELTA_L_85_5INCH_IN2_DN")
	)
	(segment
		(start 422.850564 4.028186)
		(end 422.49471 3.779012)
		(width 0.14224)
		(layer "In4.Cu")
		(net "DELTA_L_85_5INCH_IN2_DN")
	)
	(segment
		(start 439.016648 6.008878)
		(end 435.689502 6.008878)
		(width 0.14224)
		(layer "In4.Cu")
		(net "DELTA_L_85_5INCH_IN2_DN")
	)
	(segment
		(start 406.6413 3.763518)
		(end 405.046688 4.045204)
		(width 0.14224)
		(layer "In4.Cu")
		(net "DELTA_L_85_5INCH_IN2_DN")
	)
	(segment
		(start 403.030436 3.990086)
		(end 402.674582 3.740912)
		(width 0.14224)
		(layer "In4.Cu")
		(net "DELTA_L_85_5INCH_IN2_DN")
	)
	(segment
		(start 400.83105 4.378706)
		(end 401.425156 7.741412)
		(width 0.14224)
		(layer "In4.Cu")
		(net "DELTA_L_85_5INCH_IN2_DN")
	)
	(segment
		(start 394.789152 6.008878)
		(end 391.230866 6.008878)
		(width 0.14224)
		(layer "In4.Cu")
		(net "DELTA_L_85_5INCH_IN2_DN")
	)
	(segment
		(start 418.892482 4.054348)
		(end 418.536628 3.805174)
		(width 0.14224)
		(layer "In4.Cu")
		(net "DELTA_L_85_5INCH_IN2_DN")
	)
	(segment
		(start 428.821596 4.039108)
		(end 428.572676 4.395216)
		(width 0.14224)
		(layer "In4.Cu")
		(net "DELTA_L_85_5INCH_IN2_DN")
	)
	(segment
		(start 401.425156 7.741412)
		(end 401.30984 7.906004)
		(width 0.14224)
		(layer "In4.Cu")
		(net "DELTA_L_85_5INCH_IN2_DN")
	)
	(segment
		(start 399.946368 8.14705)
		(end 399.781776 8.031734)
		(width 0.14224)
		(layer "In4.Cu")
		(net "DELTA_L_85_5INCH_IN2_DN")
	)
	(segment
		(start 419.59149 8.010652)
		(end 418.892482 4.054348)
		(width 0.14224)
		(layer "In4.Cu")
		(net "DELTA_L_85_5INCH_IN2_DN")
	)
	(segment
		(start 407.711148 8.054594)
		(end 406.997154 4.012692)
		(width 0.14224)
		(layer "In4.Cu")
		(net "DELTA_L_85_5INCH_IN2_DN")
	)
	(segment
		(start 427.679104 8.113522)
		(end 427.514258 7.998206)
		(width 0.14224)
		(layer "In4.Cu")
		(net "DELTA_L_85_5INCH_IN2_DN")
	)
	(segment
		(start 398.71904 3.781806)
		(end 397.124428 4.063492)
		(width 0.14224)
		(layer "In4.Cu")
		(net "DELTA_L_85_5INCH_IN2_DN")
	)
	(segment
		(start 410.958792 4.007104)
		(end 410.602938 3.75793)
		(width 0.14224)
		(layer "In4.Cu")
		(net "DELTA_L_85_5INCH_IN2_DN")
	)
	(segment
		(start 423.718482 8.125714)
		(end 423.55389 8.010398)
		(width 0.14224)
		(layer "In4.Cu")
		(net "DELTA_L_85_5INCH_IN2_DN")
	)
	(segment
		(start 401.30984 7.906004)
		(end 399.946368 8.14705)
		(width 0.14224)
		(layer "In4.Cu")
		(net "DELTA_L_85_5INCH_IN2_DN")
	)
	(segment
		(start 416.942016 4.08686)
		(end 416.693096 4.442968)
		(width 0.14224)
		(layer "In4.Cu")
		(net "DELTA_L_85_5INCH_IN2_DN")
	)
	(segment
		(start 399.781776 8.031734)
		(end 399.074894 4.03098)
		(width 0.14224)
		(layer "In4.Cu")
		(net "DELTA_L_85_5INCH_IN2_DN")
	)
	(segment
		(start 430.772062 4.006596)
		(end 430.416208 3.757422)
		(width 0.14224)
		(layer "In4.Cu")
		(net "DELTA_L_85_5INCH_IN2_DN")
	)
	(segment
		(start 420.900098 4.060698)
		(end 420.651178 4.416806)
		(width 0.14224)
		(layer "In4.Cu")
		(net "DELTA_L_85_5INCH_IN2_DN")
	)
	(segment
		(start 413.313372 7.743698)
		(end 413.198056 7.90829)
		(width 0.14224)
		(layer "In4.Cu")
		(net "DELTA_L_85_5INCH_IN2_DN")
	)
	(segment
		(start 397.346932 7.904988)
		(end 395.98346 8.146034)
		(width 0.14224)
		(layer "In4.Cu")
		(net "DELTA_L_85_5INCH_IN2_DN")
	)
	(segment
		(start 434.380132 3.763264)
		(end 433.58308 3.90398)
		(width 0.14224)
		(layer "In4.Cu")
		(net "DELTA_L_85_5INCH_IN2_DN")
	)
	(segment
		(start 417.27755 7.752334)
		(end 417.162234 7.916926)
		(width 0.14224)
		(layer "In4.Cu")
		(net "DELTA_L_85_5INCH_IN2_DN")
	)
	(segment
		(start 399.074894 4.03098)
		(end 398.71904 3.781806)
		(width 0.14224)
		(layer "In4.Cu")
		(net "DELTA_L_85_5INCH_IN2_DN")
	)
	(segment
		(start 396.875508 4.4196)
		(end 397.462248 7.740396)
		(width 0.14224)
		(layer "In4.Cu")
		(net "DELTA_L_85_5INCH_IN2_DN")
	)
	(segment
		(start 415.798762 8.157972)
		(end 415.63417 8.042656)
		(width 0.14224)
		(layer "In4.Cu")
		(net "DELTA_L_85_5INCH_IN2_DN")
	)
	(segment
		(start 435.689502 6.008878)
		(end 435.003448 5.52704)
		(width 0.14224)
		(layer "In4.Cu")
		(net "DELTA_L_85_5INCH_IN2_DN")
	)
	(segment
		(start 397.462248 7.740396)
		(end 397.346932 7.904988)
		(width 0.14224)
		(layer "In4.Cu")
		(net "DELTA_L_85_5INCH_IN2_DN")
	)
	(segment
		(start 414.569656 3.78079)
		(end 412.975044 4.062476)
		(width 0.14224)
		(layer "In4.Cu")
		(net "DELTA_L_85_5INCH_IN2_DN")
	)
	(segment
		(start 405.27097 7.897876)
		(end 403.907498 8.138922)
		(width 0.14224)
		(layer "In4.Cu")
		(net "DELTA_L_85_5INCH_IN2_DN")
	)
	(segment
		(start 403.907498 8.138922)
		(end 403.74316 8.023606)
		(width 0.14224)
		(layer "In4.Cu")
		(net "DELTA_L_85_5INCH_IN2_DN")
	)
	(segment
		(start 432.5366 4.401058)
		(end 433.1208 7.709916)
		(width 0.14224)
		(layer "In4.Cu")
		(net "DELTA_L_85_5INCH_IN2_DN")
	)
	(segment
		(start 412.975044 4.062476)
		(end 412.726124 4.418584)
		(width 0.14224)
		(layer "In4.Cu")
		(net "DELTA_L_85_5INCH_IN2_DN")
	)
	(segment
		(start 395.98346 8.146034)
		(end 395.818868 8.030718)
		(width 0.14224)
		(layer "In4.Cu")
		(net "DELTA_L_85_5INCH_IN2_DN")
	)
	(segment
		(start 423.55389 8.010398)
		(end 422.850564 4.028186)
		(width 0.14224)
		(layer "In4.Cu")
		(net "DELTA_L_85_5INCH_IN2_DN")
	)
	(segment
		(start 406.997154 4.012692)
		(end 406.6413 3.763518)
		(width 0.14224)
		(layer "In4.Cu")
		(net "DELTA_L_85_5INCH_IN2_DN")
	)
	(segment
		(start 409.354528 7.764272)
		(end 409.239212 7.928864)
		(width 0.14224)
		(layer "In4.Cu")
		(net "DELTA_L_85_5INCH_IN2_DN")
	)
	(segment
		(start 433.005484 7.874508)
		(end 431.642012 8.115554)
		(width 0.14224)
		(layer "In4.Cu")
		(net "DELTA_L_85_5INCH_IN2_DN")
	)
	(segment
		(start 407.87574 8.16991)
		(end 407.711148 8.054594)
		(width 0.14224)
		(layer "In4.Cu")
		(net "DELTA_L_85_5INCH_IN2_DN")
	)
	(segment
		(start 417.162234 7.916926)
		(end 415.798762 8.157972)
		(width 0.14224)
		(layer "In4.Cu")
		(net "DELTA_L_85_5INCH_IN2_DN")
	)
	(segment
		(start 433.58308 3.90398)
		(end 432.78552 4.04495)
		(width 0.14224)
		(layer "In4.Cu")
		(net "DELTA_L_85_5INCH_IN2_DN")
	)
	(segment
		(start 439.307478 5.718048)
		(end 439.016648 6.008878)
		(width 0.14224)
		(layer "In4.Cu")
		(net "DELTA_L_85_5INCH_IN2_DN")
	)
	(segment
		(start 431.642012 8.115554)
		(end 431.47742 8.000238)
		(width 0.14224)
		(layer "In4.Cu")
		(net "DELTA_L_85_5INCH_IN2_DN")
	)
	(segment
		(start 418.536628 3.805174)
		(end 416.942016 4.08686)
		(width 0.14224)
		(layer "In4.Cu")
		(net "DELTA_L_85_5INCH_IN2_DN")
	)
	(segment
		(start 427.514258 7.998206)
		(end 426.809408 4.006342)
		(width 0.14224)
		(layer "In4.Cu")
		(net "DELTA_L_85_5INCH_IN2_DN")
	)
	(segment
		(start 422.49471 3.779012)
		(end 420.900098 4.060698)
		(width 0.14224)
		(layer "In4.Cu")
		(net "DELTA_L_85_5INCH_IN2_DN")
	)
	(segment
		(start 416.693096 4.442968)
		(end 417.27755 7.752334)
		(width 0.14224)
		(layer "In4.Cu")
		(net "DELTA_L_85_5INCH_IN2_DN")
	)
	(segment
		(start 429.042576 7.872476)
		(end 427.679104 8.113522)
		(width 0.14224)
		(layer "In4.Cu")
		(net "DELTA_L_85_5INCH_IN2_DN")
	)
	(segment
		(start 395.55674 6.546088)
		(end 394.789152 6.008878)
		(width 0.14224)
		(layer "In4.Cu")
		(net "DELTA_L_85_5INCH_IN2_DN")
	)
	(segment
		(start 405.386286 7.73303)
		(end 405.27097 7.897876)
		(width 0.14224)
		(layer "In4.Cu")
		(net "DELTA_L_85_5INCH_IN2_DN")
	)
	(segment
		(start 426.453554 3.757168)
		(end 424.858942 4.038854)
		(width 0.14224)
		(layer "In4.Cu")
		(net "DELTA_L_85_5INCH_IN2_DN")
	)
	(segment
		(start 425.081954 7.884414)
		(end 423.718482 8.125714)
		(width 0.14224)
		(layer "In4.Cu")
		(net "DELTA_L_85_5INCH_IN2_DN")
	)
	(segment
		(start 433.1208 7.709916)
		(end 433.005484 7.874508)
		(width 0.14224)
		(layer "In4.Cu")
		(net "DELTA_L_85_5INCH_IN2_DN")
	)
	(segment
		(start 403.74316 8.023606)
		(end 403.030436 3.990086)
		(width 0.14224)
		(layer "In4.Cu")
		(net "DELTA_L_85_5INCH_IN2_DN")
	)
	(segment
		(start 411.834584 8.149336)
		(end 411.669992 8.03402)
		(width 0.14224)
		(layer "In4.Cu")
		(net "DELTA_L_85_5INCH_IN2_DN")
	)
	(segment
		(start 409.008326 4.039616)
		(end 408.759406 4.395724)
		(width 0.14224)
		(layer "In4.Cu")
		(net "DELTA_L_85_5INCH_IN2_DN")
	)
	(segment
		(start 421.23487 7.72033)
		(end 421.119554 7.884922)
		(width 0.14224)
		(layer "In4.Cu")
		(net "DELTA_L_85_5INCH_IN2_DN")
	)
	(segment
		(start 412.726124 4.418584)
		(end 413.313372 7.743698)
		(width 0.14224)
		(layer "In4.Cu")
		(net "DELTA_L_85_5INCH_IN2_DN")
	)
	(segment
		(start 315.791088 5.33273)
		(end 316.44336 5.514594)
		(width 0.12954)
		(layer "F.Cu")
		(net "DELTA_L_85_5INCH_IN1_DP")
	)
	(segment
		(start 365.463074 5.33273)
		(end 364.810802 5.514594)
		(width 0.12954)
		(layer "F.Cu")
		(net "DELTA_L_85_5INCH_IN1_DP")
	)
	(segment
		(start 333.313024 7.401052)
		(end 334.90662 7.119366)
		(width 0.14224)
		(layer "In2.Cu")
		(net "DELTA_L_85_5INCH_IN1_DP")
	)
	(segment
		(start 330.71435 3.235706)
		(end 332.078584 2.99466)
		(width 0.14224)
		(layer "In2.Cu")
		(net "DELTA_L_85_5INCH_IN1_DP")
	)
	(segment
		(start 353.116388 7.344664)
		(end 354.709984 7.062978)
		(width 0.14224)
		(layer "In2.Cu")
		(net "DELTA_L_85_5INCH_IN1_DP")
	)
	(segment
		(start 359.981754 3.109468)
		(end 360.249216 4.623816)
		(width 0.14224)
		(layer "In2.Cu")
		(net "DELTA_L_85_5INCH_IN1_DP")
	)
	(segment
		(start 340.171278 3.126994)
		(end 340.879938 7.139686)
		(width 0.14224)
		(layer "In2.Cu")
		(net "DELTA_L_85_5INCH_IN1_DP")
	)
	(segment
		(start 355.853492 2.988564)
		(end 356.01783 3.103626)
		(width 0.14224)
		(layer "In2.Cu")
		(net "DELTA_L_85_5INCH_IN1_DP")
	)
	(segment
		(start 325.383652 7.378192)
		(end 326.977248 7.096506)
		(width 0.14224)
		(layer "In2.Cu")
		(net "DELTA_L_85_5INCH_IN1_DP")
	)
	(segment
		(start 346.786962 7.075424)
		(end 347.03639 6.719316)
		(width 0.14224)
		(layer "In2.Cu")
		(net "DELTA_L_85_5INCH_IN1_DP")
	)
	(segment
		(start 339.114892 6.742684)
		(end 338.527644 3.41757)
		(width 0.14224)
		(layer "In2.Cu")
		(net "DELTA_L_85_5INCH_IN1_DP")
	)
	(segment
		(start 323.263768 6.739382)
		(end 322.677028 3.418586)
		(width 0.14224)
		(layer "In2.Cu")
		(net "DELTA_L_85_5INCH_IN1_DP")
	)
	(segment
		(start 348.799658 7.107428)
		(end 349.155766 7.356856)
		(width 0.14224)
		(layer "In2.Cu")
		(net "DELTA_L_85_5INCH_IN1_DP")
	)
	(segment
		(start 357.079296 7.346696)
		(end 358.672892 7.06501)
		(width 0.14224)
		(layer "In2.Cu")
		(net "DELTA_L_85_5INCH_IN1_DP")
	)
	(segment
		(start 342.609678 3.277362)
		(end 343.973912 3.036316)
		(width 0.14224)
		(layer "In2.Cu")
		(net "DELTA_L_85_5INCH_IN1_DP")
	)
	(segment
		(start 356.01783 3.103626)
		(end 356.723188 7.097268)
		(width 0.14224)
		(layer "In2.Cu")
		(net "DELTA_L_85_5INCH_IN1_DP")
	)
	(segment
		(start 324.320662 3.12801)
		(end 325.027544 7.128764)
		(width 0.14224)
		(layer "In2.Cu")
		(net "DELTA_L_85_5INCH_IN1_DP")
	)
	(segment
		(start 343.973912 3.036316)
		(end 344.13825 3.151378)
		(width 0.14224)
		(layer "In2.Cu")
		(net "DELTA_L_85_5INCH_IN1_DP")
	)
	(segment
		(start 327.226676 6.740398)
		(end 326.63257 3.377946)
		(width 0.14224)
		(layer "In2.Cu")
		(net "DELTA_L_85_5INCH_IN1_DP")
	)
	(segment
		(start 334.675988 3.230118)
		(end 336.040222 2.989072)
		(width 0.14224)
		(layer "In2.Cu")
		(net "DELTA_L_85_5INCH_IN1_DP")
	)
	(segment
		(start 336.040222 2.989072)
		(end 336.20456 3.104134)
		(width 0.14224)
		(layer "In2.Cu")
		(net "DELTA_L_85_5INCH_IN1_DP")
	)
	(segment
		(start 346.56776 3.2512)
		(end 347.931994 3.010154)
		(width 0.14224)
		(layer "In2.Cu")
		(net "DELTA_L_85_5INCH_IN1_DP")
	)
	(segment
		(start 338.865464 7.098792)
		(end 339.114892 6.742684)
		(width 0.14224)
		(layer "In2.Cu")
		(net "DELTA_L_85_5INCH_IN1_DP")
	)
	(segment
		(start 352.055176 3.103372)
		(end 352.760026 7.095236)
		(width 0.14224)
		(layer "In2.Cu")
		(net "DELTA_L_85_5INCH_IN1_DP")
	)
	(segment
		(start 326.977248 7.096506)
		(end 327.226676 6.740398)
		(width 0.14224)
		(layer "In2.Cu")
		(net "DELTA_L_85_5INCH_IN1_DP")
	)
	(segment
		(start 364.519972 5.223764)
		(end 364.810802 5.514594)
		(width 0.14224)
		(layer "In2.Cu")
		(net "DELTA_L_85_5INCH_IN1_DP")
	)
	(segment
		(start 341.236046 7.389114)
		(end 342.829642 7.107428)
		(width 0.14224)
		(layer "In2.Cu")
		(net "DELTA_L_85_5INCH_IN1_DP")
	)
	(segment
		(start 345.193366 7.35711)
		(end 346.786962 7.075424)
		(width 0.14224)
		(layer "In2.Cu")
		(net "DELTA_L_85_5INCH_IN1_DP")
	)
	(segment
		(start 332.956916 7.151624)
		(end 333.313024 7.401052)
		(width 0.14224)
		(layer "In2.Cu")
		(net "DELTA_L_85_5INCH_IN1_DP")
	)
	(segment
		(start 361.103672 5.223764)
		(end 364.519972 5.223764)
		(width 0.14224)
		(layer "In2.Cu")
		(net "DELTA_L_85_5INCH_IN1_DP")
	)
	(segment
		(start 356.723188 7.097268)
		(end 357.079296 7.346696)
		(width 0.14224)
		(layer "In2.Cu")
		(net "DELTA_L_85_5INCH_IN1_DP")
	)
	(segment
		(start 359.817416 2.994406)
		(end 359.981754 3.109468)
		(width 0.14224)
		(layer "In2.Cu")
		(net "DELTA_L_85_5INCH_IN1_DP")
	)
	(segment
		(start 316.44336 5.514594)
		(end 316.73419 5.223764)
		(width 0.14224)
		(layer "In2.Cu")
		(net "DELTA_L_85_5INCH_IN1_DP")
	)
	(segment
		(start 350.526604 3.229356)
		(end 351.890838 2.98831)
		(width 0.14224)
		(layer "In2.Cu")
		(net "DELTA_L_85_5INCH_IN1_DP")
	)
	(segment
		(start 348.096332 3.125216)
		(end 348.799658 7.107428)
		(width 0.14224)
		(layer "In2.Cu")
		(net "DELTA_L_85_5INCH_IN1_DP")
	)
	(segment
		(start 320.203576 5.223764)
		(end 320.802508 5.643118)
		(width 0.14224)
		(layer "In2.Cu")
		(net "DELTA_L_85_5INCH_IN1_DP")
	)
	(segment
		(start 340.00694 3.011932)
		(end 340.171278 3.126994)
		(width 0.14224)
		(layer "In2.Cu")
		(net "DELTA_L_85_5INCH_IN1_DP")
	)
	(segment
		(start 342.494616 3.441954)
		(end 342.609678 3.277362)
		(width 0.14224)
		(layer "In2.Cu")
		(net "DELTA_L_85_5INCH_IN1_DP")
	)
	(segment
		(start 334.90662 7.119366)
		(end 335.156048 6.763258)
		(width 0.14224)
		(layer "In2.Cu")
		(net "DELTA_L_85_5INCH_IN1_DP")
	)
	(segment
		(start 322.79209 3.253994)
		(end 324.156324 3.012948)
		(width 0.14224)
		(layer "In2.Cu")
		(net "DELTA_L_85_5INCH_IN1_DP")
	)
	(segment
		(start 342.829642 7.107428)
		(end 343.07907 6.75132)
		(width 0.14224)
		(layer "In2.Cu")
		(net "DELTA_L_85_5INCH_IN1_DP")
	)
	(segment
		(start 334.560926 3.394964)
		(end 334.675988 3.230118)
		(width 0.14224)
		(layer "In2.Cu")
		(net "DELTA_L_85_5INCH_IN1_DP")
	)
	(segment
		(start 358.92232 6.708902)
		(end 358.33812 3.400044)
		(width 0.14224)
		(layer "In2.Cu")
		(net "DELTA_L_85_5INCH_IN1_DP")
	)
	(segment
		(start 316.73419 5.223764)
		(end 320.203576 5.223764)
		(width 0.14224)
		(layer "In2.Cu")
		(net "DELTA_L_85_5INCH_IN1_DP")
	)
	(segment
		(start 354.709984 7.062978)
		(end 354.959412 6.707378)
		(width 0.14224)
		(layer "In2.Cu")
		(net "DELTA_L_85_5INCH_IN1_DP")
	)
	(segment
		(start 321.064636 7.127748)
		(end 321.420744 7.377176)
		(width 0.14224)
		(layer "In2.Cu")
		(net "DELTA_L_85_5INCH_IN1_DP")
	)
	(segment
		(start 336.91576 7.13105)
		(end 337.271868 7.380478)
		(width 0.14224)
		(layer "In2.Cu")
		(net "DELTA_L_85_5INCH_IN1_DP")
	)
	(segment
		(start 328.276204 3.087116)
		(end 328.988928 7.120636)
		(width 0.14224)
		(layer "In2.Cu")
		(net "DELTA_L_85_5INCH_IN1_DP")
	)
	(segment
		(start 347.931994 3.010154)
		(end 348.096332 3.125216)
		(width 0.14224)
		(layer "In2.Cu")
		(net "DELTA_L_85_5INCH_IN1_DP")
	)
	(segment
		(start 349.155766 7.356856)
		(end 350.749362 7.074916)
		(width 0.14224)
		(layer "In2.Cu")
		(net "DELTA_L_85_5INCH_IN1_DP")
	)
	(segment
		(start 321.420744 7.377176)
		(end 323.01434 7.09549)
		(width 0.14224)
		(layer "In2.Cu")
		(net "DELTA_L_85_5INCH_IN1_DP")
	)
	(segment
		(start 343.07907 6.75132)
		(end 342.494616 3.441954)
		(width 0.14224)
		(layer "In2.Cu")
		(net "DELTA_L_85_5INCH_IN1_DP")
	)
	(segment
		(start 344.13825 3.151378)
		(end 344.837258 7.107682)
		(width 0.14224)
		(layer "In2.Cu")
		(net "DELTA_L_85_5INCH_IN1_DP")
	)
	(segment
		(start 358.453182 3.235452)
		(end 359.817416 2.994406)
		(width 0.14224)
		(layer "In2.Cu")
		(net "DELTA_L_85_5INCH_IN1_DP")
	)
	(segment
		(start 331.187806 6.732016)
		(end 330.599288 3.400552)
		(width 0.14224)
		(layer "In2.Cu")
		(net "DELTA_L_85_5INCH_IN1_DP")
	)
	(segment
		(start 344.837258 7.107682)
		(end 345.193366 7.35711)
		(width 0.14224)
		(layer "In2.Cu")
		(net "DELTA_L_85_5INCH_IN1_DP")
	)
	(segment
		(start 337.271868 7.380478)
		(end 338.865464 7.098792)
		(width 0.14224)
		(layer "In2.Cu")
		(net "DELTA_L_85_5INCH_IN1_DP")
	)
	(segment
		(start 326.63257 3.377946)
		(end 326.747632 3.2131)
		(width 0.14224)
		(layer "In2.Cu")
		(net "DELTA_L_85_5INCH_IN1_DP")
	)
	(segment
		(start 322.677028 3.418586)
		(end 322.79209 3.253994)
		(width 0.14224)
		(layer "In2.Cu")
		(net "DELTA_L_85_5INCH_IN1_DP")
	)
	(segment
		(start 325.027544 7.128764)
		(end 325.383652 7.378192)
		(width 0.14224)
		(layer "In2.Cu")
		(net "DELTA_L_85_5INCH_IN1_DP")
	)
	(segment
		(start 332.242922 3.109722)
		(end 332.956916 7.151624)
		(width 0.14224)
		(layer "In2.Cu")
		(net "DELTA_L_85_5INCH_IN1_DP")
	)
	(segment
		(start 360.249216 4.623816)
		(end 361.103672 5.223764)
		(width 0.14224)
		(layer "In2.Cu")
		(net "DELTA_L_85_5INCH_IN1_DP")
	)
	(segment
		(start 330.599288 3.400552)
		(end 330.71435 3.235706)
		(width 0.14224)
		(layer "In2.Cu")
		(net "DELTA_L_85_5INCH_IN1_DP")
	)
	(segment
		(start 354.959412 6.707378)
		(end 354.374196 3.394202)
		(width 0.14224)
		(layer "In2.Cu")
		(net "DELTA_L_85_5INCH_IN1_DP")
	)
	(segment
		(start 330.938632 7.088378)
		(end 331.187806 6.732016)
		(width 0.14224)
		(layer "In2.Cu")
		(net "DELTA_L_85_5INCH_IN1_DP")
	)
	(segment
		(start 347.03639 6.719316)
		(end 346.452698 3.415792)
		(width 0.14224)
		(layer "In2.Cu")
		(net "DELTA_L_85_5INCH_IN1_DP")
	)
	(segment
		(start 351.890838 2.98831)
		(end 352.055176 3.103372)
		(width 0.14224)
		(layer "In2.Cu")
		(net "DELTA_L_85_5INCH_IN1_DP")
	)
	(segment
		(start 338.642706 3.252978)
		(end 340.00694 3.011932)
		(width 0.14224)
		(layer "In2.Cu")
		(net "DELTA_L_85_5INCH_IN1_DP")
	)
	(segment
		(start 335.156048 6.763258)
		(end 334.560926 3.394964)
		(width 0.14224)
		(layer "In2.Cu")
		(net "DELTA_L_85_5INCH_IN1_DP")
	)
	(segment
		(start 358.672892 7.06501)
		(end 358.92232 6.708902)
		(width 0.14224)
		(layer "In2.Cu")
		(net "DELTA_L_85_5INCH_IN1_DP")
	)
	(segment
		(start 358.33812 3.400044)
		(end 358.453182 3.235452)
		(width 0.14224)
		(layer "In2.Cu")
		(net "DELTA_L_85_5INCH_IN1_DP")
	)
	(segment
		(start 350.411542 3.393948)
		(end 350.526604 3.229356)
		(width 0.14224)
		(layer "In2.Cu")
		(net "DELTA_L_85_5INCH_IN1_DP")
	)
	(segment
		(start 350.99879 6.719062)
		(end 350.411542 3.393948)
		(width 0.14224)
		(layer "In2.Cu")
		(net "DELTA_L_85_5INCH_IN1_DP")
	)
	(segment
		(start 326.747632 3.2131)
		(end 328.111866 2.972054)
		(width 0.14224)
		(layer "In2.Cu")
		(net "DELTA_L_85_5INCH_IN1_DP")
	)
	(segment
		(start 354.374196 3.394202)
		(end 354.489258 3.22961)
		(width 0.14224)
		(layer "In2.Cu")
		(net "DELTA_L_85_5INCH_IN1_DP")
	)
	(segment
		(start 329.344528 7.370064)
		(end 330.938632 7.088378)
		(width 0.14224)
		(layer "In2.Cu")
		(net "DELTA_L_85_5INCH_IN1_DP")
	)
	(segment
		(start 332.078584 2.99466)
		(end 332.242922 3.109722)
		(width 0.14224)
		(layer "In2.Cu")
		(net "DELTA_L_85_5INCH_IN1_DP")
	)
	(segment
		(start 336.20456 3.104134)
		(end 336.91576 7.13105)
		(width 0.14224)
		(layer "In2.Cu")
		(net "DELTA_L_85_5INCH_IN1_DP")
	)
	(segment
		(start 354.489258 3.22961)
		(end 355.853492 2.988564)
		(width 0.14224)
		(layer "In2.Cu")
		(net "DELTA_L_85_5INCH_IN1_DP")
	)
	(segment
		(start 352.760026 7.095236)
		(end 353.116388 7.344664)
		(width 0.14224)
		(layer "In2.Cu")
		(net "DELTA_L_85_5INCH_IN1_DP")
	)
	(segment
		(start 328.988928 7.120636)
		(end 329.344528 7.370064)
		(width 0.14224)
		(layer "In2.Cu")
		(net "DELTA_L_85_5INCH_IN1_DP")
	)
	(segment
		(start 340.879938 7.139686)
		(end 341.236046 7.389114)
		(width 0.14224)
		(layer "In2.Cu")
		(net "DELTA_L_85_5INCH_IN1_DP")
	)
	(segment
		(start 338.527644 3.41757)
		(end 338.642706 3.252978)
		(width 0.14224)
		(layer "In2.Cu")
		(net "DELTA_L_85_5INCH_IN1_DP")
	)
	(segment
		(start 350.749362 7.074916)
		(end 350.99879 6.719062)
		(width 0.14224)
		(layer "In2.Cu")
		(net "DELTA_L_85_5INCH_IN1_DP")
	)
	(segment
		(start 324.156324 3.012948)
		(end 324.320662 3.12801)
		(width 0.14224)
		(layer "In2.Cu")
		(net "DELTA_L_85_5INCH_IN1_DP")
	)
	(segment
		(start 320.802508 5.643118)
		(end 321.064636 7.127748)
		(width 0.14224)
		(layer "In2.Cu")
		(net "DELTA_L_85_5INCH_IN1_DP")
	)
	(segment
		(start 346.452698 3.415792)
		(end 346.56776 3.2512)
		(width 0.14224)
		(layer "In2.Cu")
		(net "DELTA_L_85_5INCH_IN1_DP")
	)
	(segment
		(start 328.111866 2.972054)
		(end 328.276204 3.087116)
		(width 0.14224)
		(layer "In2.Cu")
		(net "DELTA_L_85_5INCH_IN1_DP")
	)
	(segment
		(start 323.01434 7.09549)
		(end 323.263768 6.739382)
		(width 0.14224)
		(layer "In2.Cu")
		(net "DELTA_L_85_5INCH_IN1_DP")
	)
	(segment
		(start 365.463074 4.832858)
		(end 364.810802 4.650994)
		(width 0.12954)
		(layer "F.Cu")
		(net "DELTA_L_85_5INCH_IN1_DN")
	)
	(segment
		(start 315.791088 4.832858)
		(end 316.44336 4.650994)
		(width 0.12954)
		(layer "F.Cu")
		(net "DELTA_L_85_5INCH_IN1_DN")
	)
	(segment
		(start 352.312732 2.939288)
		(end 351.956878 2.690114)
		(width 0.14224)
		(layer "In2.Cu")
		(net "DELTA_L_85_5INCH_IN1_DN")
	)
	(segment
		(start 346.154502 3.349752)
		(end 346.738194 6.653276)
		(width 0.14224)
		(layer "In2.Cu")
		(net "DELTA_L_85_5INCH_IN1_DN")
	)
	(segment
		(start 338.478368 2.995422)
		(end 338.229448 3.35153)
		(width 0.14224)
		(layer "In2.Cu")
		(net "DELTA_L_85_5INCH_IN1_DN")
	)
	(segment
		(start 341.137494 6.975602)
		(end 340.428834 2.96291)
		(width 0.14224)
		(layer "In2.Cu")
		(net "DELTA_L_85_5INCH_IN1_DN")
	)
	(segment
		(start 332.144624 2.696464)
		(end 330.550012 2.97815)
		(width 0.14224)
		(layer "In2.Cu")
		(net "DELTA_L_85_5INCH_IN1_DN")
	)
	(segment
		(start 340.07298 2.713736)
		(end 338.478368 2.995422)
		(width 0.14224)
		(layer "In2.Cu")
		(net "DELTA_L_85_5INCH_IN1_DN")
	)
	(segment
		(start 346.738194 6.653276)
		(end 346.622878 6.817868)
		(width 0.14224)
		(layer "In2.Cu")
		(net "DELTA_L_85_5INCH_IN1_DN")
	)
	(segment
		(start 334.26273 3.32867)
		(end 334.857852 6.697218)
		(width 0.14224)
		(layer "In2.Cu")
		(net "DELTA_L_85_5INCH_IN1_DN")
	)
	(segment
		(start 356.275386 2.939542)
		(end 355.919532 2.690368)
		(width 0.14224)
		(layer "In2.Cu")
		(net "DELTA_L_85_5INCH_IN1_DN")
	)
	(segment
		(start 346.403422 2.993644)
		(end 346.154502 3.349752)
		(width 0.14224)
		(layer "In2.Cu")
		(net "DELTA_L_85_5INCH_IN1_DN")
	)
	(segment
		(start 346.622878 6.817868)
		(end 345.259406 7.058914)
		(width 0.14224)
		(layer "In2.Cu")
		(net "DELTA_L_85_5INCH_IN1_DN")
	)
	(segment
		(start 358.624124 6.642862)
		(end 358.508808 6.807454)
		(width 0.14224)
		(layer "In2.Cu")
		(net "DELTA_L_85_5INCH_IN1_DN")
	)
	(segment
		(start 354.32492 2.972054)
		(end 354.076 3.328162)
		(width 0.14224)
		(layer "In2.Cu")
		(net "DELTA_L_85_5INCH_IN1_DN")
	)
	(segment
		(start 324.578218 2.963926)
		(end 324.222364 2.714752)
		(width 0.14224)
		(layer "In2.Cu")
		(net "DELTA_L_85_5INCH_IN1_DN")
	)
	(segment
		(start 345.259406 7.058914)
		(end 345.094814 6.943598)
		(width 0.14224)
		(layer "In2.Cu")
		(net "DELTA_L_85_5INCH_IN1_DN")
	)
	(segment
		(start 330.88961 6.665976)
		(end 330.774294 6.830822)
		(width 0.14224)
		(layer "In2.Cu")
		(net "DELTA_L_85_5INCH_IN1_DN")
	)
	(segment
		(start 326.334374 3.311652)
		(end 326.92848 6.674358)
		(width 0.14224)
		(layer "In2.Cu")
		(net "DELTA_L_85_5INCH_IN1_DN")
	)
	(segment
		(start 350.113346 3.327908)
		(end 350.700594 6.653022)
		(width 0.14224)
		(layer "In2.Cu")
		(net "DELTA_L_85_5INCH_IN1_DN")
	)
	(segment
		(start 316.73419 4.941824)
		(end 316.44336 4.650994)
		(width 0.14224)
		(layer "In2.Cu")
		(net "DELTA_L_85_5INCH_IN1_DN")
	)
	(segment
		(start 321.322192 6.963664)
		(end 321.060064 5.479034)
		(width 0.14224)
		(layer "In2.Cu")
		(net "DELTA_L_85_5INCH_IN1_DN")
	)
	(segment
		(start 364.519972 4.941824)
		(end 361.192826 4.941824)
		(width 0.14224)
		(layer "In2.Cu")
		(net "DELTA_L_85_5INCH_IN1_DN")
	)
	(segment
		(start 322.378832 3.352546)
		(end 322.965572 6.673342)
		(width 0.14224)
		(layer "In2.Cu")
		(net "DELTA_L_85_5INCH_IN1_DN")
	)
	(segment
		(start 322.965572 6.673342)
		(end 322.850256 6.837934)
		(width 0.14224)
		(layer "In2.Cu")
		(net "DELTA_L_85_5INCH_IN1_DN")
	)
	(segment
		(start 320.292476 4.941824)
		(end 316.73419 4.941824)
		(width 0.14224)
		(layer "In2.Cu")
		(net "DELTA_L_85_5INCH_IN1_DN")
	)
	(segment
		(start 330.301092 3.334258)
		(end 330.88961 6.665976)
		(width 0.14224)
		(layer "In2.Cu")
		(net "DELTA_L_85_5INCH_IN1_DN")
	)
	(segment
		(start 358.039924 3.334004)
		(end 358.624124 6.642862)
		(width 0.14224)
		(layer "In2.Cu")
		(net "DELTA_L_85_5INCH_IN1_DN")
	)
	(segment
		(start 321.486784 7.07898)
		(end 321.322192 6.963664)
		(width 0.14224)
		(layer "In2.Cu")
		(net "DELTA_L_85_5INCH_IN1_DN")
	)
	(segment
		(start 334.742536 6.86181)
		(end 333.379064 7.102856)
		(width 0.14224)
		(layer "In2.Cu")
		(net "DELTA_L_85_5INCH_IN1_DN")
	)
	(segment
		(start 350.362266 2.9718)
		(end 350.113346 3.327908)
		(width 0.14224)
		(layer "In2.Cu")
		(net "DELTA_L_85_5INCH_IN1_DN")
	)
	(segment
		(start 336.106262 2.690876)
		(end 334.51165 2.972562)
		(width 0.14224)
		(layer "In2.Cu")
		(net "DELTA_L_85_5INCH_IN1_DN")
	)
	(segment
		(start 328.53376 2.923032)
		(end 328.177906 2.673858)
		(width 0.14224)
		(layer "In2.Cu")
		(net "DELTA_L_85_5INCH_IN1_DN")
	)
	(segment
		(start 351.956878 2.690114)
		(end 350.362266 2.9718)
		(width 0.14224)
		(layer "In2.Cu")
		(net "DELTA_L_85_5INCH_IN1_DN")
	)
	(segment
		(start 364.810802 4.650994)
		(end 364.519972 4.941824)
		(width 0.14224)
		(layer "In2.Cu")
		(net "DELTA_L_85_5INCH_IN1_DN")
	)
	(segment
		(start 332.500478 2.945638)
		(end 332.144624 2.696464)
		(width 0.14224)
		(layer "In2.Cu")
		(net "DELTA_L_85_5INCH_IN1_DN")
	)
	(segment
		(start 354.076 3.328162)
		(end 354.661216 6.641084)
		(width 0.14224)
		(layer "In2.Cu")
		(net "DELTA_L_85_5INCH_IN1_DN")
	)
	(segment
		(start 329.246484 6.956552)
		(end 328.53376 2.923032)
		(width 0.14224)
		(layer "In2.Cu")
		(net "DELTA_L_85_5INCH_IN1_DN")
	)
	(segment
		(start 337.173316 6.966966)
		(end 336.462116 2.94005)
		(width 0.14224)
		(layer "In2.Cu")
		(net "DELTA_L_85_5INCH_IN1_DN")
	)
	(segment
		(start 357.145336 7.0485)
		(end 356.980744 6.933184)
		(width 0.14224)
		(layer "In2.Cu")
		(net "DELTA_L_85_5INCH_IN1_DN")
	)
	(segment
		(start 349.221806 7.05866)
		(end 349.057214 6.943344)
		(width 0.14224)
		(layer "In2.Cu")
		(net "DELTA_L_85_5INCH_IN1_DN")
	)
	(segment
		(start 334.51165 2.972562)
		(end 334.26273 3.32867)
		(width 0.14224)
		(layer "In2.Cu")
		(net "DELTA_L_85_5INCH_IN1_DN")
	)
	(segment
		(start 342.780874 6.68528)
		(end 342.665558 6.849872)
		(width 0.14224)
		(layer "In2.Cu")
		(net "DELTA_L_85_5INCH_IN1_DN")
	)
	(segment
		(start 347.998034 2.711958)
		(end 346.403422 2.993644)
		(width 0.14224)
		(layer "In2.Cu")
		(net "DELTA_L_85_5INCH_IN1_DN")
	)
	(segment
		(start 360.506772 4.459986)
		(end 360.23931 2.945384)
		(width 0.14224)
		(layer "In2.Cu")
		(net "DELTA_L_85_5INCH_IN1_DN")
	)
	(segment
		(start 356.980744 6.933184)
		(end 356.275386 2.939542)
		(width 0.14224)
		(layer "In2.Cu")
		(net "DELTA_L_85_5INCH_IN1_DN")
	)
	(segment
		(start 354.661216 6.641084)
		(end 354.5459 6.805422)
		(width 0.14224)
		(layer "In2.Cu")
		(net "DELTA_L_85_5INCH_IN1_DN")
	)
	(segment
		(start 358.288844 2.977896)
		(end 358.039924 3.334004)
		(width 0.14224)
		(layer "In2.Cu")
		(net "DELTA_L_85_5INCH_IN1_DN")
	)
	(segment
		(start 336.462116 2.94005)
		(end 336.106262 2.690876)
		(width 0.14224)
		(layer "In2.Cu")
		(net "DELTA_L_85_5INCH_IN1_DN")
	)
	(segment
		(start 322.627752 2.996438)
		(end 322.378832 3.352546)
		(width 0.14224)
		(layer "In2.Cu")
		(net "DELTA_L_85_5INCH_IN1_DN")
	)
	(segment
		(start 337.337908 7.082282)
		(end 337.173316 6.966966)
		(width 0.14224)
		(layer "In2.Cu")
		(net "DELTA_L_85_5INCH_IN1_DN")
	)
	(segment
		(start 355.919532 2.690368)
		(end 354.32492 2.972054)
		(width 0.14224)
		(layer "In2.Cu")
		(net "DELTA_L_85_5INCH_IN1_DN")
	)
	(segment
		(start 353.017582 6.931152)
		(end 352.312732 2.939288)
		(width 0.14224)
		(layer "In2.Cu")
		(net "DELTA_L_85_5INCH_IN1_DN")
	)
	(segment
		(start 328.177906 2.673858)
		(end 326.583294 2.955544)
		(width 0.14224)
		(layer "In2.Cu")
		(net "DELTA_L_85_5INCH_IN1_DN")
	)
	(segment
		(start 334.857852 6.697218)
		(end 334.742536 6.86181)
		(width 0.14224)
		(layer "In2.Cu")
		(net "DELTA_L_85_5INCH_IN1_DN")
	)
	(segment
		(start 338.70138 6.841236)
		(end 337.337908 7.082282)
		(width 0.14224)
		(layer "In2.Cu")
		(net "DELTA_L_85_5INCH_IN1_DN")
	)
	(segment
		(start 330.550012 2.97815)
		(end 330.301092 3.334258)
		(width 0.14224)
		(layer "In2.Cu")
		(net "DELTA_L_85_5INCH_IN1_DN")
	)
	(segment
		(start 342.19642 3.375914)
		(end 342.780874 6.68528)
		(width 0.14224)
		(layer "In2.Cu")
		(net "DELTA_L_85_5INCH_IN1_DN")
	)
	(segment
		(start 349.057214 6.943344)
		(end 348.353888 2.961132)
		(width 0.14224)
		(layer "In2.Cu")
		(net "DELTA_L_85_5INCH_IN1_DN")
	)
	(segment
		(start 344.039952 2.73812)
		(end 342.44534 3.019806)
		(width 0.14224)
		(layer "In2.Cu")
		(net "DELTA_L_85_5INCH_IN1_DN")
	)
	(segment
		(start 326.583294 2.955544)
		(end 326.334374 3.311652)
		(width 0.14224)
		(layer "In2.Cu")
		(net "DELTA_L_85_5INCH_IN1_DN")
	)
	(segment
		(start 333.379064 7.102856)
		(end 333.214472 6.98754)
		(width 0.14224)
		(layer "In2.Cu")
		(net "DELTA_L_85_5INCH_IN1_DN")
	)
	(segment
		(start 350.585278 6.81736)
		(end 349.221806 7.05866)
		(width 0.14224)
		(layer "In2.Cu")
		(net "DELTA_L_85_5INCH_IN1_DN")
	)
	(segment
		(start 326.92848 6.674358)
		(end 326.813164 6.83895)
		(width 0.14224)
		(layer "In2.Cu")
		(net "DELTA_L_85_5INCH_IN1_DN")
	)
	(segment
		(start 322.850256 6.837934)
		(end 321.486784 7.07898)
		(width 0.14224)
		(layer "In2.Cu")
		(net "DELTA_L_85_5INCH_IN1_DN")
	)
	(segment
		(start 329.410822 7.071868)
		(end 329.246484 6.956552)
		(width 0.14224)
		(layer "In2.Cu")
		(net "DELTA_L_85_5INCH_IN1_DN")
	)
	(segment
		(start 345.094814 6.943598)
		(end 344.395806 2.987294)
		(width 0.14224)
		(layer "In2.Cu")
		(net "DELTA_L_85_5INCH_IN1_DN")
	)
	(segment
		(start 359.086404 2.836926)
		(end 358.288844 2.977896)
		(width 0.14224)
		(layer "In2.Cu")
		(net "DELTA_L_85_5INCH_IN1_DN")
	)
	(segment
		(start 360.23931 2.945384)
		(end 359.883456 2.69621)
		(width 0.14224)
		(layer "In2.Cu")
		(net "DELTA_L_85_5INCH_IN1_DN")
	)
	(segment
		(start 348.353888 2.961132)
		(end 347.998034 2.711958)
		(width 0.14224)
		(layer "In2.Cu")
		(net "DELTA_L_85_5INCH_IN1_DN")
	)
	(segment
		(start 330.774294 6.830822)
		(end 329.410822 7.071868)
		(width 0.14224)
		(layer "In2.Cu")
		(net "DELTA_L_85_5INCH_IN1_DN")
	)
	(segment
		(start 321.060064 5.479034)
		(end 320.292476 4.941824)
		(width 0.14224)
		(layer "In2.Cu")
		(net "DELTA_L_85_5INCH_IN1_DN")
	)
	(segment
		(start 338.816696 6.676644)
		(end 338.70138 6.841236)
		(width 0.14224)
		(layer "In2.Cu")
		(net "DELTA_L_85_5INCH_IN1_DN")
	)
	(segment
		(start 344.395806 2.987294)
		(end 344.039952 2.73812)
		(width 0.14224)
		(layer "In2.Cu")
		(net "DELTA_L_85_5INCH_IN1_DN")
	)
	(segment
		(start 358.508808 6.807454)
		(end 357.145336 7.0485)
		(width 0.14224)
		(layer "In2.Cu")
		(net "DELTA_L_85_5INCH_IN1_DN")
	)
	(segment
		(start 342.665558 6.849872)
		(end 341.302086 7.090918)
		(width 0.14224)
		(layer "In2.Cu")
		(net "DELTA_L_85_5INCH_IN1_DN")
	)
	(segment
		(start 338.229448 3.35153)
		(end 338.816696 6.676644)
		(width 0.14224)
		(layer "In2.Cu")
		(net "DELTA_L_85_5INCH_IN1_DN")
	)
	(segment
		(start 342.44534 3.019806)
		(end 342.19642 3.375914)
		(width 0.14224)
		(layer "In2.Cu")
		(net "DELTA_L_85_5INCH_IN1_DN")
	)
	(segment
		(start 341.302086 7.090918)
		(end 341.137494 6.975602)
		(width 0.14224)
		(layer "In2.Cu")
		(net "DELTA_L_85_5INCH_IN1_DN")
	)
	(segment
		(start 354.5459 6.805422)
		(end 353.182428 7.046468)
		(width 0.14224)
		(layer "In2.Cu")
		(net "DELTA_L_85_5INCH_IN1_DN")
	)
	(segment
		(start 361.192826 4.941824)
		(end 360.506772 4.459986)
		(width 0.14224)
		(layer "In2.Cu")
		(net "DELTA_L_85_5INCH_IN1_DN")
	)
	(segment
		(start 324.222364 2.714752)
		(end 322.627752 2.996438)
		(width 0.14224)
		(layer "In2.Cu")
		(net "DELTA_L_85_5INCH_IN1_DN")
	)
	(segment
		(start 350.700594 6.653022)
		(end 350.585278 6.81736)
		(width 0.14224)
		(layer "In2.Cu")
		(net "DELTA_L_85_5INCH_IN1_DN")
	)
	(segment
		(start 353.182428 7.046468)
		(end 353.017582 6.931152)
		(width 0.14224)
		(layer "In2.Cu")
		(net "DELTA_L_85_5INCH_IN1_DN")
	)
	(segment
		(start 340.428834 2.96291)
		(end 340.07298 2.713736)
		(width 0.14224)
		(layer "In2.Cu")
		(net "DELTA_L_85_5INCH_IN1_DN")
	)
	(segment
		(start 333.214472 6.98754)
		(end 332.500478 2.945638)
		(width 0.14224)
		(layer "In2.Cu")
		(net "DELTA_L_85_5INCH_IN1_DN")
	)
	(segment
		(start 325.2851 6.96468)
		(end 324.578218 2.963926)
		(width 0.14224)
		(layer "In2.Cu")
		(net "DELTA_L_85_5INCH_IN1_DN")
	)
	(segment
		(start 325.449692 7.079996)
		(end 325.2851 6.96468)
		(width 0.14224)
		(layer "In2.Cu")
		(net "DELTA_L_85_5INCH_IN1_DN")
	)
	(segment
		(start 326.813164 6.83895)
		(end 325.449692 7.079996)
		(width 0.14224)
		(layer "In2.Cu")
		(net "DELTA_L_85_5INCH_IN1_DN")
	)
	(segment
		(start 359.883456 2.69621)
		(end 359.086404 2.836926)
		(width 0.14224)
		(layer "In2.Cu")
		(net "DELTA_L_85_5INCH_IN1_DN")
	)
	(segment
		(start 353.98964 0.783844)
		(end 354.582222 4.137914)
		(width 0.12954)
		(layer "B.Cu")
		(net "DELTA_L_85_5INCH_BOT_DP")
	)
	(segment
		(start 348.921324 4.379976)
		(end 348.21495 0.382016)
		(width 0.12954)
		(layer "B.Cu")
		(net "DELTA_L_85_5INCH_BOT_DP")
	)
	(segment
		(start 344.907362 4.41452)
		(end 344.19667 0.391668)
		(width 0.12954)
		(layer "B.Cu")
		(net "DELTA_L_85_5INCH_BOT_DP")
	)
	(segment
		(start 338.488782 4.071366)
		(end 338.384134 4.220972)
		(width 0.12954)
		(layer "B.Cu")
		(net "DELTA_L_85_5INCH_BOT_DP")
	)
	(segment
		(start 357.119682 4.530852)
		(end 356.970584 4.426458)
		(width 0.12954)
		(layer "B.Cu")
		(net "DELTA_L_85_5INCH_BOT_DP")
	)
	(segment
		(start 328.831194 4.446778)
		(end 328.11466 0.392176)
		(width 0.12954)
		(layer "B.Cu")
		(net "DELTA_L_85_5INCH_BOT_DP")
	)
	(segment
		(start 326.327262 4.245864)
		(end 324.949058 4.48945)
		(width 0.12954)
		(layer "B.Cu")
		(net "DELTA_L_85_5INCH_BOT_DP")
	)
	(segment
		(start 320.93027 4.497324)
		(end 320.781172 4.39293)
		(width 0.12954)
		(layer "B.Cu")
		(net "DELTA_L_85_5INCH_BOT_DP")
	)
	(segment
		(start 315.936884 2.292858)
		(end 315.791088 2.292858)
		(width 0.12954)
		(layer "B.Cu")
		(net "DELTA_L_85_5INCH_BOT_DP")
	)
	(segment
		(start 355.887528 0.124968)
		(end 354.248212 0.415036)
		(width 0.12954)
		(layer "B.Cu")
		(net "DELTA_L_85_5INCH_BOT_DP")
	)
	(segment
		(start 332.990444 4.492498)
		(end 332.841346 4.388104)
		(width 0.12954)
		(layer "B.Cu")
		(net "DELTA_L_85_5INCH_BOT_DP")
	)
	(segment
		(start 330.127356 0.42418)
		(end 329.868784 0.792988)
		(width 0.12954)
		(layer "B.Cu")
		(net "DELTA_L_85_5INCH_BOT_DP")
	)
	(segment
		(start 342.188546 0.423164)
		(end 341.92972 0.791464)
		(width 0.12954)
		(layer "B.Cu")
		(net "DELTA_L_85_5INCH_BOT_DP")
	)
	(segment
		(start 324.79996 4.385056)
		(end 324.093332 0.385064)
		(width 0.12954)
		(layer "B.Cu")
		(net "DELTA_L_85_5INCH_BOT_DP")
	)
	(segment
		(start 341.038688 4.533646)
		(end 340.889336 4.429252)
		(width 0.12954)
		(layer "B.Cu")
		(net "DELTA_L_85_5INCH_BOT_DP")
	)
	(segment
		(start 351.8662 0.120396)
		(end 350.226884 0.410464)
		(width 0.12954)
		(layer "B.Cu")
		(net "DELTA_L_85_5INCH_BOT_DP")
	)
	(segment
		(start 333.88681 0.779526)
		(end 334.473296 4.099306)
		(width 0.12954)
		(layer "B.Cu")
		(net "DELTA_L_85_5INCH_BOT_DP")
	)
	(segment
		(start 329.868784 0.792988)
		(end 330.463398 4.158234)
		(width 0.12954)
		(layer "B.Cu")
		(net "DELTA_L_85_5INCH_BOT_DP")
	)
	(segment
		(start 354.477574 4.28752)
		(end 353.09937 4.531106)
		(width 0.12954)
		(layer "B.Cu")
		(net "DELTA_L_85_5INCH_BOT_DP")
	)
	(segment
		(start 338.384134 4.220972)
		(end 337.00593 4.464558)
		(width 0.12954)
		(layer "B.Cu")
		(net "DELTA_L_85_5INCH_BOT_DP")
	)
	(segment
		(start 353.09937 4.531106)
		(end 352.950272 4.426712)
		(width 0.12954)
		(layer "B.Cu")
		(net "DELTA_L_85_5INCH_BOT_DP")
	)
	(segment
		(start 360.557064 1.971802)
		(end 360.273092 0.363474)
		(width 0.12954)
		(layer "B.Cu")
		(net "DELTA_L_85_5INCH_BOT_DP")
	)
	(segment
		(start 334.368648 4.248912)
		(end 332.990444 4.492498)
		(width 0.12954)
		(layer "B.Cu")
		(net "DELTA_L_85_5INCH_BOT_DP")
	)
	(segment
		(start 328.11466 0.392176)
		(end 327.74636 0.13335)
		(width 0.12954)
		(layer "B.Cu")
		(net "DELTA_L_85_5INCH_BOT_DP")
	)
	(segment
		(start 345.05646 4.518914)
		(end 344.907362 4.41452)
		(width 0.12954)
		(layer "B.Cu")
		(net "DELTA_L_85_5INCH_BOT_DP")
	)
	(segment
		(start 321.826636 0.785368)
		(end 322.413122 4.104386)
		(width 0.12954)
		(layer "B.Cu")
		(net "DELTA_L_85_5INCH_BOT_DP")
	)
	(segment
		(start 352.235008 0.378968)
		(end 351.8662 0.120396)
		(width 0.12954)
		(layer "B.Cu")
		(net "DELTA_L_85_5INCH_BOT_DP")
	)
	(segment
		(start 336.153252 0.379222)
		(end 335.784952 0.120396)
		(width 0.12954)
		(layer "B.Cu")
		(net "DELTA_L_85_5INCH_BOT_DP")
	)
	(segment
		(start 342.52154 4.140708)
		(end 342.416892 4.29006)
		(width 0.12954)
		(layer "B.Cu")
		(net "DELTA_L_85_5INCH_BOT_DP")
	)
	(segment
		(start 337.00593 4.464558)
		(end 336.856832 4.360164)
		(width 0.12954)
		(layer "B.Cu")
		(net "DELTA_L_85_5INCH_BOT_DP")
	)
	(segment
		(start 365.30661 2.292858)
		(end 365.217964 2.381504)
		(width 0.12954)
		(layer "B.Cu")
		(net "DELTA_L_85_5INCH_BOT_DP")
	)
	(segment
		(start 356.256336 0.38354)
		(end 355.887528 0.124968)
		(width 0.12954)
		(layer "B.Cu")
		(net "DELTA_L_85_5INCH_BOT_DP")
	)
	(segment
		(start 336.856832 4.360164)
		(end 336.153252 0.379222)
		(width 0.12954)
		(layer "B.Cu")
		(net "DELTA_L_85_5INCH_BOT_DP")
	)
	(segment
		(start 339.80501 0.120142)
		(end 338.165694 0.41021)
		(width 0.12954)
		(layer "B.Cu")
		(net "DELTA_L_85_5INCH_BOT_DP")
	)
	(segment
		(start 334.145382 0.410718)
		(end 333.88681 0.779526)
		(width 0.12954)
		(layer "B.Cu")
		(net "DELTA_L_85_5INCH_BOT_DP")
	)
	(segment
		(start 349.968312 0.779272)
		(end 350.553528 4.091432)
		(width 0.12954)
		(layer "B.Cu")
		(net "DELTA_L_85_5INCH_BOT_DP")
	)
	(segment
		(start 320.531744 2.981452)
		(end 319.674494 2.381504)
		(width 0.12954)
		(layer "B.Cu")
		(net "DELTA_L_85_5INCH_BOT_DP")
	)
	(segment
		(start 346.539312 4.125722)
		(end 346.434664 4.275328)
		(width 0.12954)
		(layer "B.Cu")
		(net "DELTA_L_85_5INCH_BOT_DP")
	)
	(segment
		(start 322.085208 0.41656)
		(end 321.826636 0.785368)
		(width 0.12954)
		(layer "B.Cu")
		(net "DELTA_L_85_5INCH_BOT_DP")
	)
	(segment
		(start 342.416892 4.29006)
		(end 341.038688 4.533646)
		(width 0.12954)
		(layer "B.Cu")
		(net "DELTA_L_85_5INCH_BOT_DP")
	)
	(segment
		(start 332.841346 4.388104)
		(end 332.13548 0.392684)
		(width 0.12954)
		(layer "B.Cu")
		(net "DELTA_L_85_5INCH_BOT_DP")
	)
	(segment
		(start 344.19667 0.391668)
		(end 343.827354 0.133096)
		(width 0.12954)
		(layer "B.Cu")
		(net "DELTA_L_85_5INCH_BOT_DP")
	)
	(segment
		(start 335.784952 0.120396)
		(end 334.145382 0.410718)
		(width 0.12954)
		(layer "B.Cu")
		(net "DELTA_L_85_5INCH_BOT_DP")
	)
	(segment
		(start 360.273092 0.363474)
		(end 359.886758 0.092202)
		(width 0.12954)
		(layer "B.Cu")
		(net "DELTA_L_85_5INCH_BOT_DP")
	)
	(segment
		(start 349.070676 4.48437)
		(end 348.921324 4.379976)
		(width 0.12954)
		(layer "B.Cu")
		(net "DELTA_L_85_5INCH_BOT_DP")
	)
	(segment
		(start 365.463074 2.292858)
		(end 365.30661 2.292858)
		(width 0.12954)
		(layer "B.Cu")
		(net "DELTA_L_85_5INCH_BOT_DP")
	)
	(segment
		(start 359.886758 0.092202)
		(end 358.277414 0.37719)
		(width 0.12954)
		(layer "B.Cu")
		(net "DELTA_L_85_5INCH_BOT_DP")
	)
	(segment
		(start 322.413122 4.104386)
		(end 322.308474 4.253738)
		(width 0.12954)
		(layer "B.Cu")
		(net "DELTA_L_85_5INCH_BOT_DP")
	)
	(segment
		(start 327.74636 0.13335)
		(end 326.106536 0.423164)
		(width 0.12954)
		(layer "B.Cu")
		(net "DELTA_L_85_5INCH_BOT_DP")
	)
	(segment
		(start 350.44888 4.240784)
		(end 349.070676 4.48437)
		(width 0.12954)
		(layer "B.Cu")
		(net "DELTA_L_85_5INCH_BOT_DP")
	)
	(segment
		(start 356.970584 4.426458)
		(end 356.256336 0.38354)
		(width 0.12954)
		(layer "B.Cu")
		(net "DELTA_L_85_5INCH_BOT_DP")
	)
	(segment
		(start 323.724524 0.126492)
		(end 322.085208 0.41656)
		(width 0.12954)
		(layer "B.Cu")
		(net "DELTA_L_85_5INCH_BOT_DP")
	)
	(segment
		(start 319.674494 2.381504)
		(end 316.02553 2.381504)
		(width 0.12954)
		(layer "B.Cu")
		(net "DELTA_L_85_5INCH_BOT_DP")
	)
	(segment
		(start 331.766672 0.134112)
		(end 330.127356 0.42418)
		(width 0.12954)
		(layer "B.Cu")
		(net "DELTA_L_85_5INCH_BOT_DP")
	)
	(segment
		(start 330.35875 4.307586)
		(end 328.980546 4.551172)
		(width 0.12954)
		(layer "B.Cu")
		(net "DELTA_L_85_5INCH_BOT_DP")
	)
	(segment
		(start 346.20708 0.413512)
		(end 345.948508 0.78232)
		(width 0.12954)
		(layer "B.Cu")
		(net "DELTA_L_85_5INCH_BOT_DP")
	)
	(segment
		(start 330.463398 4.158234)
		(end 330.35875 4.307586)
		(width 0.12954)
		(layer "B.Cu")
		(net "DELTA_L_85_5INCH_BOT_DP")
	)
	(segment
		(start 316.02553 2.381504)
		(end 315.936884 2.292858)
		(width 0.12954)
		(layer "B.Cu")
		(net "DELTA_L_85_5INCH_BOT_DP")
	)
	(segment
		(start 348.21495 0.382016)
		(end 347.84665 0.12319)
		(width 0.12954)
		(layer "B.Cu")
		(net "DELTA_L_85_5INCH_BOT_DP")
	)
	(segment
		(start 358.006396 0.763524)
		(end 358.602534 4.13766)
		(width 0.12954)
		(layer "B.Cu")
		(net "DELTA_L_85_5INCH_BOT_DP")
	)
	(segment
		(start 365.217964 2.381504)
		(end 361.142534 2.381504)
		(width 0.12954)
		(layer "B.Cu")
		(net "DELTA_L_85_5INCH_BOT_DP")
	)
	(segment
		(start 322.308474 4.253738)
		(end 320.93027 4.497324)
		(width 0.12954)
		(layer "B.Cu")
		(net "DELTA_L_85_5INCH_BOT_DP")
	)
	(segment
		(start 354.248212 0.415036)
		(end 353.98964 0.783844)
		(width 0.12954)
		(layer "B.Cu")
		(net "DELTA_L_85_5INCH_BOT_DP")
	)
	(segment
		(start 332.13548 0.392684)
		(end 331.766672 0.134112)
		(width 0.12954)
		(layer "B.Cu")
		(net "DELTA_L_85_5INCH_BOT_DP")
	)
	(segment
		(start 358.602534 4.13766)
		(end 358.497886 4.287266)
		(width 0.12954)
		(layer "B.Cu")
		(net "DELTA_L_85_5INCH_BOT_DP")
	)
	(segment
		(start 320.781172 4.39293)
		(end 320.531744 2.981452)
		(width 0.12954)
		(layer "B.Cu")
		(net "DELTA_L_85_5INCH_BOT_DP")
	)
	(segment
		(start 352.950272 4.426712)
		(end 352.235008 0.378968)
		(width 0.12954)
		(layer "B.Cu")
		(net "DELTA_L_85_5INCH_BOT_DP")
	)
	(segment
		(start 326.106536 0.423164)
		(end 325.848218 0.792734)
		(width 0.12954)
		(layer "B.Cu")
		(net "DELTA_L_85_5INCH_BOT_DP")
	)
	(segment
		(start 341.92972 0.791464)
		(end 342.52154 4.140708)
		(width 0.12954)
		(layer "B.Cu")
		(net "DELTA_L_85_5INCH_BOT_DP")
	)
	(segment
		(start 324.093332 0.385064)
		(end 323.724524 0.126492)
		(width 0.12954)
		(layer "B.Cu")
		(net "DELTA_L_85_5INCH_BOT_DP")
	)
	(segment
		(start 350.226884 0.410464)
		(end 349.968312 0.779272)
		(width 0.12954)
		(layer "B.Cu")
		(net "DELTA_L_85_5INCH_BOT_DP")
	)
	(segment
		(start 361.142534 2.381504)
		(end 360.557064 1.971802)
		(width 0.12954)
		(layer "B.Cu")
		(net "DELTA_L_85_5INCH_BOT_DP")
	)
	(segment
		(start 358.277414 0.37719)
		(end 358.006396 0.763524)
		(width 0.12954)
		(layer "B.Cu")
		(net "DELTA_L_85_5INCH_BOT_DP")
	)
	(segment
		(start 337.907122 0.779018)
		(end 338.488782 4.071366)
		(width 0.12954)
		(layer "B.Cu")
		(net "DELTA_L_85_5INCH_BOT_DP")
	)
	(segment
		(start 326.43191 4.096258)
		(end 326.327262 4.245864)
		(width 0.12954)
		(layer "B.Cu")
		(net "DELTA_L_85_5INCH_BOT_DP")
	)
	(segment
		(start 328.980546 4.551172)
		(end 328.831194 4.446778)
		(width 0.12954)
		(layer "B.Cu")
		(net "DELTA_L_85_5INCH_BOT_DP")
	)
	(segment
		(start 345.948508 0.78232)
		(end 346.539312 4.125722)
		(width 0.12954)
		(layer "B.Cu")
		(net "DELTA_L_85_5INCH_BOT_DP")
	)
	(segment
		(start 347.84665 0.12319)
		(end 346.20708 0.413512)
		(width 0.12954)
		(layer "B.Cu")
		(net "DELTA_L_85_5INCH_BOT_DP")
	)
	(segment
		(start 340.173564 0.378968)
		(end 339.80501 0.120142)
		(width 0.12954)
		(layer "B.Cu")
		(net "DELTA_L_85_5INCH_BOT_DP")
	)
	(segment
		(start 354.582222 4.137914)
		(end 354.477574 4.28752)
		(width 0.12954)
		(layer "B.Cu")
		(net "DELTA_L_85_5INCH_BOT_DP")
	)
	(segment
		(start 358.497886 4.287266)
		(end 357.119682 4.530852)
		(width 0.12954)
		(layer "B.Cu")
		(net "DELTA_L_85_5INCH_BOT_DP")
	)
	(segment
		(start 334.473296 4.099306)
		(end 334.368648 4.248912)
		(width 0.12954)
		(layer "B.Cu")
		(net "DELTA_L_85_5INCH_BOT_DP")
	)
	(segment
		(start 343.827354 0.133096)
		(end 342.188546 0.423164)
		(width 0.12954)
		(layer "B.Cu")
		(net "DELTA_L_85_5INCH_BOT_DP")
	)
	(segment
		(start 346.434664 4.275328)
		(end 345.05646 4.518914)
		(width 0.12954)
		(layer "B.Cu")
		(net "DELTA_L_85_5INCH_BOT_DP")
	)
	(segment
		(start 340.889336 4.429252)
		(end 340.173564 0.378968)
		(width 0.12954)
		(layer "B.Cu")
		(net "DELTA_L_85_5INCH_BOT_DP")
	)
	(segment
		(start 338.165694 0.41021)
		(end 337.907122 0.779018)
		(width 0.12954)
		(layer "B.Cu")
		(net "DELTA_L_85_5INCH_BOT_DP")
	)
	(segment
		(start 350.553528 4.091432)
		(end 350.44888 4.240784)
		(width 0.12954)
		(layer "B.Cu")
		(net "DELTA_L_85_5INCH_BOT_DP")
	)
	(segment
		(start 324.949058 4.48945)
		(end 324.79996 4.385056)
		(width 0.12954)
		(layer "B.Cu")
		(net "DELTA_L_85_5INCH_BOT_DP")
	)
	(segment
		(start 325.848218 0.792734)
		(end 326.43191 4.096258)
		(width 0.12954)
		(layer "B.Cu")
		(net "DELTA_L_85_5INCH_BOT_DP")
	)
	(segment
		(start 344.612722 4.602226)
		(end 343.90203 0.579374)
		(width 0.12954)
		(layer "B.Cu")
		(net "DELTA_L_85_5INCH_BOT_DN")
	)
	(segment
		(start 319.57264 2.704084)
		(end 316.046358 2.704084)
		(width 0.12954)
		(layer "B.Cu")
		(net "DELTA_L_85_5INCH_BOT_DN")
	)
	(segment
		(start 365.302546 2.79273)
		(end 365.2139 2.704084)
		(width 0.12954)
		(layer "B.Cu")
		(net "DELTA_L_85_5INCH_BOT_DN")
	)
	(segment
		(start 322.167758 0.86106)
		(end 322.754244 4.179824)
		(width 0.12954)
		(layer "B.Cu")
		(net "DELTA_L_85_5INCH_BOT_DN")
	)
	(segment
		(start 320.237104 3.169158)
		(end 319.57264 2.704084)
		(width 0.12954)
		(layer "B.Cu")
		(net "DELTA_L_85_5INCH_BOT_DN")
	)
	(segment
		(start 334.814418 4.174744)
		(end 334.556608 4.543552)
		(width 0.12954)
		(layer "B.Cu")
		(net "DELTA_L_85_5INCH_BOT_DN")
	)
	(segment
		(start 324.87362 4.830572)
		(end 324.50532 4.572762)
		(width 0.12954)
		(layer "B.Cu")
		(net "DELTA_L_85_5INCH_BOT_DN")
	)
	(segment
		(start 358.46512 0.67183)
		(end 358.347518 0.839216)
		(width 0.12954)
		(layer "B.Cu")
		(net "DELTA_L_85_5INCH_BOT_DN")
	)
	(segment
		(start 322.272914 0.7112)
		(end 322.167758 0.86106)
		(width 0.12954)
		(layer "B.Cu")
		(net "DELTA_L_85_5INCH_BOT_DN")
	)
	(segment
		(start 330.80452 4.233926)
		(end 330.546456 4.602226)
		(width 0.12954)
		(layer "B.Cu")
		(net "DELTA_L_85_5INCH_BOT_DN")
	)
	(segment
		(start 330.546456 4.602226)
		(end 328.905108 4.892294)
		(width 0.12954)
		(layer "B.Cu")
		(net "DELTA_L_85_5INCH_BOT_DN")
	)
	(segment
		(start 359.978452 0.550926)
		(end 359.811066 0.433324)
		(width 0.12954)
		(layer "B.Cu")
		(net "DELTA_L_85_5INCH_BOT_DN")
	)
	(segment
		(start 354.330762 0.859536)
		(end 354.923344 4.213352)
		(width 0.12954)
		(layer "B.Cu")
		(net "DELTA_L_85_5INCH_BOT_DN")
	)
	(segment
		(start 334.333088 0.705104)
		(end 334.227932 0.855218)
		(width 0.12954)
		(layer "B.Cu")
		(net "DELTA_L_85_5INCH_BOT_DN")
	)
	(segment
		(start 347.92031 0.569468)
		(end 347.770704 0.464312)
		(width 0.12954)
		(layer "B.Cu")
		(net "DELTA_L_85_5INCH_BOT_DN")
	)
	(segment
		(start 322.496434 4.548378)
		(end 320.854832 4.838446)
		(width 0.12954)
		(layer "B.Cu")
		(net "DELTA_L_85_5INCH_BOT_DN")
	)
	(segment
		(start 343.751916 0.474218)
		(end 342.375998 0.717804)
		(width 0.12954)
		(layer "B.Cu")
		(net "DELTA_L_85_5INCH_BOT_DN")
	)
	(segment
		(start 342.604598 4.5847)
		(end 340.96325 4.874768)
		(width 0.12954)
		(layer "B.Cu")
		(net "DELTA_L_85_5INCH_BOT_DN")
	)
	(segment
		(start 357.044244 4.871974)
		(end 356.675944 4.614164)
		(width 0.12954)
		(layer "B.Cu")
		(net "DELTA_L_85_5INCH_BOT_DN")
	)
	(segment
		(start 328.536554 4.634738)
		(end 327.82002 0.579628)
		(width 0.12954)
		(layer "B.Cu")
		(net "DELTA_L_85_5INCH_BOT_DN")
	)
	(segment
		(start 342.862662 4.2164)
		(end 342.604598 4.5847)
		(width 0.12954)
		(layer "B.Cu")
		(net "DELTA_L_85_5INCH_BOT_DN")
	)
	(segment
		(start 326.773032 4.171696)
		(end 326.515222 4.540504)
		(width 0.12954)
		(layer "B.Cu")
		(net "DELTA_L_85_5INCH_BOT_DN")
	)
	(segment
		(start 330.209906 0.86868)
		(end 330.80452 4.233926)
		(width 0.12954)
		(layer "B.Cu")
		(net "DELTA_L_85_5INCH_BOT_DN")
	)
	(segment
		(start 346.622624 4.569968)
		(end 344.981022 4.860036)
		(width 0.12954)
		(layer "B.Cu")
		(net "DELTA_L_85_5INCH_BOT_DN")
	)
	(segment
		(start 358.685846 4.581906)
		(end 357.044244 4.871974)
		(width 0.12954)
		(layer "B.Cu")
		(net "DELTA_L_85_5INCH_BOT_DN")
	)
	(segment
		(start 359.811066 0.433324)
		(end 358.46512 0.67183)
		(width 0.12954)
		(layer "B.Cu")
		(net "DELTA_L_85_5INCH_BOT_DN")
	)
	(segment
		(start 335.709006 0.461518)
		(end 334.333088 0.705104)
		(width 0.12954)
		(layer "B.Cu")
		(net "DELTA_L_85_5INCH_BOT_DN")
	)
	(segment
		(start 350.89465 4.167124)
		(end 350.636586 4.535424)
		(width 0.12954)
		(layer "B.Cu")
		(net "DELTA_L_85_5INCH_BOT_DN")
	)
	(segment
		(start 358.943656 4.213352)
		(end 358.685846 4.581906)
		(width 0.12954)
		(layer "B.Cu")
		(net "DELTA_L_85_5INCH_BOT_DN")
	)
	(segment
		(start 334.556608 4.543552)
		(end 332.915006 4.83362)
		(width 0.12954)
		(layer "B.Cu")
		(net "DELTA_L_85_5INCH_BOT_DN")
	)
	(segment
		(start 340.96325 4.874768)
		(end 340.594696 4.617212)
		(width 0.12954)
		(layer "B.Cu")
		(net "DELTA_L_85_5INCH_BOT_DN")
	)
	(segment
		(start 339.878924 0.56642)
		(end 339.729318 0.461264)
		(width 0.12954)
		(layer "B.Cu")
		(net "DELTA_L_85_5INCH_BOT_DN")
	)
	(segment
		(start 350.636586 4.535424)
		(end 348.995238 4.825492)
		(width 0.12954)
		(layer "B.Cu")
		(net "DELTA_L_85_5INCH_BOT_DN")
	)
	(segment
		(start 334.227932 0.855218)
		(end 334.814418 4.174744)
		(width 0.12954)
		(layer "B.Cu")
		(net "DELTA_L_85_5INCH_BOT_DN")
	)
	(segment
		(start 350.41459 0.705104)
		(end 350.309434 0.854964)
		(width 0.12954)
		(layer "B.Cu")
		(net "DELTA_L_85_5INCH_BOT_DN")
	)
	(segment
		(start 355.811836 0.46609)
		(end 354.435918 0.709676)
		(width 0.12954)
		(layer "B.Cu")
		(net "DELTA_L_85_5INCH_BOT_DN")
	)
	(segment
		(start 326.515222 4.540504)
		(end 324.87362 4.830572)
		(width 0.12954)
		(layer "B.Cu")
		(net "DELTA_L_85_5INCH_BOT_DN")
	)
	(segment
		(start 351.940368 0.566674)
		(end 351.790508 0.461518)
		(width 0.12954)
		(layer "B.Cu")
		(net "DELTA_L_85_5INCH_BOT_DN")
	)
	(segment
		(start 338.248244 0.85471)
		(end 338.829904 4.146804)
		(width 0.12954)
		(layer "B.Cu")
		(net "DELTA_L_85_5INCH_BOT_DN")
	)
	(segment
		(start 346.880434 4.20116)
		(end 346.622624 4.569968)
		(width 0.12954)
		(layer "B.Cu")
		(net "DELTA_L_85_5INCH_BOT_DN")
	)
	(segment
		(start 348.995238 4.825492)
		(end 348.626684 4.567936)
		(width 0.12954)
		(layer "B.Cu")
		(net "DELTA_L_85_5INCH_BOT_DN")
	)
	(segment
		(start 327.82002 0.579628)
		(end 327.670414 0.474472)
		(width 0.12954)
		(layer "B.Cu")
		(net "DELTA_L_85_5INCH_BOT_DN")
	)
	(segment
		(start 342.270842 0.86741)
		(end 342.862662 4.2164)
		(width 0.12954)
		(layer "B.Cu")
		(net "DELTA_L_85_5INCH_BOT_DN")
	)
	(segment
		(start 354.923344 4.213352)
		(end 354.665534 4.58216)
		(width 0.12954)
		(layer "B.Cu")
		(net "DELTA_L_85_5INCH_BOT_DN")
	)
	(segment
		(start 354.665534 4.58216)
		(end 353.023932 4.872228)
		(width 0.12954)
		(layer "B.Cu")
		(net "DELTA_L_85_5INCH_BOT_DN")
	)
	(segment
		(start 335.858612 0.566674)
		(end 335.709006 0.461518)
		(width 0.12954)
		(layer "B.Cu")
		(net "DELTA_L_85_5INCH_BOT_DN")
	)
	(segment
		(start 350.309434 0.854964)
		(end 350.89465 4.167124)
		(width 0.12954)
		(layer "B.Cu")
		(net "DELTA_L_85_5INCH_BOT_DN")
	)
	(segment
		(start 328.905108 4.892294)
		(end 328.536554 4.634738)
		(width 0.12954)
		(layer "B.Cu")
		(net "DELTA_L_85_5INCH_BOT_DN")
	)
	(segment
		(start 351.790508 0.461518)
		(end 350.41459 0.705104)
		(width 0.12954)
		(layer "B.Cu")
		(net "DELTA_L_85_5INCH_BOT_DN")
	)
	(segment
		(start 331.84084 0.58039)
		(end 331.69098 0.475234)
		(width 0.12954)
		(layer "B.Cu")
		(net "DELTA_L_85_5INCH_BOT_DN")
	)
	(segment
		(start 365.2139 2.704084)
		(end 361.04068 2.704084)
		(width 0.12954)
		(layer "B.Cu")
		(net "DELTA_L_85_5INCH_BOT_DN")
	)
	(segment
		(start 346.394786 0.707898)
		(end 346.28963 0.858012)
		(width 0.12954)
		(layer "B.Cu")
		(net "DELTA_L_85_5INCH_BOT_DN")
	)
	(segment
		(start 365.463074 2.79273)
		(end 365.302546 2.79273)
		(width 0.12954)
		(layer "B.Cu")
		(net "DELTA_L_85_5INCH_BOT_DN")
	)
	(segment
		(start 338.3534 0.70485)
		(end 338.248244 0.85471)
		(width 0.12954)
		(layer "B.Cu")
		(net "DELTA_L_85_5INCH_BOT_DN")
	)
	(segment
		(start 346.28963 0.858012)
		(end 346.880434 4.20116)
		(width 0.12954)
		(layer "B.Cu")
		(net "DELTA_L_85_5INCH_BOT_DN")
	)
	(segment
		(start 354.435918 0.709676)
		(end 354.330762 0.859536)
		(width 0.12954)
		(layer "B.Cu")
		(net "DELTA_L_85_5INCH_BOT_DN")
	)
	(segment
		(start 326.294496 0.717804)
		(end 326.18934 0.868172)
		(width 0.12954)
		(layer "B.Cu")
		(net "DELTA_L_85_5INCH_BOT_DN")
	)
	(segment
		(start 338.829904 4.146804)
		(end 338.572094 4.515612)
		(width 0.12954)
		(layer "B.Cu")
		(net "DELTA_L_85_5INCH_BOT_DN")
	)
	(segment
		(start 332.546706 4.57581)
		(end 331.84084 0.58039)
		(width 0.12954)
		(layer "B.Cu")
		(net "DELTA_L_85_5INCH_BOT_DN")
	)
	(segment
		(start 323.798692 0.57277)
		(end 323.648832 0.467614)
		(width 0.12954)
		(layer "B.Cu")
		(net "DELTA_L_85_5INCH_BOT_DN")
	)
	(segment
		(start 353.023932 4.872228)
		(end 352.655632 4.614418)
		(width 0.12954)
		(layer "B.Cu")
		(net "DELTA_L_85_5INCH_BOT_DN")
	)
	(segment
		(start 342.375998 0.717804)
		(end 342.270842 0.86741)
		(width 0.12954)
		(layer "B.Cu")
		(net "DELTA_L_85_5INCH_BOT_DN")
	)
	(segment
		(start 348.626684 4.567936)
		(end 347.92031 0.569468)
		(width 0.12954)
		(layer "B.Cu")
		(net "DELTA_L_85_5INCH_BOT_DN")
	)
	(segment
		(start 355.961696 0.571246)
		(end 355.811836 0.46609)
		(width 0.12954)
		(layer "B.Cu")
		(net "DELTA_L_85_5INCH_BOT_DN")
	)
	(segment
		(start 339.729318 0.461264)
		(end 338.3534 0.70485)
		(width 0.12954)
		(layer "B.Cu")
		(net "DELTA_L_85_5INCH_BOT_DN")
	)
	(segment
		(start 336.562192 4.54787)
		(end 335.858612 0.566674)
		(width 0.12954)
		(layer "B.Cu")
		(net "DELTA_L_85_5INCH_BOT_DN")
	)
	(segment
		(start 322.754244 4.179824)
		(end 322.496434 4.548378)
		(width 0.12954)
		(layer "B.Cu")
		(net "DELTA_L_85_5INCH_BOT_DN")
	)
	(segment
		(start 320.486532 4.580636)
		(end 320.237104 3.169158)
		(width 0.12954)
		(layer "B.Cu")
		(net "DELTA_L_85_5INCH_BOT_DN")
	)
	(segment
		(start 356.675944 4.614164)
		(end 355.961696 0.571246)
		(width 0.12954)
		(layer "B.Cu")
		(net "DELTA_L_85_5INCH_BOT_DN")
	)
	(segment
		(start 330.315062 0.71882)
		(end 330.209906 0.86868)
		(width 0.12954)
		(layer "B.Cu")
		(net "DELTA_L_85_5INCH_BOT_DN")
	)
	(segment
		(start 320.854832 4.838446)
		(end 320.486532 4.580636)
		(width 0.12954)
		(layer "B.Cu")
		(net "DELTA_L_85_5INCH_BOT_DN")
	)
	(segment
		(start 344.981022 4.860036)
		(end 344.612722 4.602226)
		(width 0.12954)
		(layer "B.Cu")
		(net "DELTA_L_85_5INCH_BOT_DN")
	)
	(segment
		(start 327.670414 0.474472)
		(end 326.294496 0.717804)
		(width 0.12954)
		(layer "B.Cu")
		(net "DELTA_L_85_5INCH_BOT_DN")
	)
	(segment
		(start 323.648832 0.467614)
		(end 322.272914 0.7112)
		(width 0.12954)
		(layer "B.Cu")
		(net "DELTA_L_85_5INCH_BOT_DN")
	)
	(segment
		(start 347.770704 0.464312)
		(end 346.394786 0.707898)
		(width 0.12954)
		(layer "B.Cu")
		(net "DELTA_L_85_5INCH_BOT_DN")
	)
	(segment
		(start 360.262424 2.159508)
		(end 359.978452 0.550926)
		(width 0.12954)
		(layer "B.Cu")
		(net "DELTA_L_85_5INCH_BOT_DN")
	)
	(segment
		(start 332.915006 4.83362)
		(end 332.546706 4.57581)
		(width 0.12954)
		(layer "B.Cu")
		(net "DELTA_L_85_5INCH_BOT_DN")
	)
	(segment
		(start 315.957712 2.79273)
		(end 315.791088 2.79273)
		(width 0.12954)
		(layer "B.Cu")
		(net "DELTA_L_85_5INCH_BOT_DN")
	)
	(segment
		(start 336.930492 4.80568)
		(end 336.562192 4.54787)
		(width 0.12954)
		(layer "B.Cu")
		(net "DELTA_L_85_5INCH_BOT_DN")
	)
	(segment
		(start 324.50532 4.572762)
		(end 323.798692 0.57277)
		(width 0.12954)
		(layer "B.Cu")
		(net "DELTA_L_85_5INCH_BOT_DN")
	)
	(segment
		(start 331.69098 0.475234)
		(end 330.315062 0.71882)
		(width 0.12954)
		(layer "B.Cu")
		(net "DELTA_L_85_5INCH_BOT_DN")
	)
	(segment
		(start 352.655632 4.614418)
		(end 351.940368 0.566674)
		(width 0.12954)
		(layer "B.Cu")
		(net "DELTA_L_85_5INCH_BOT_DN")
	)
	(segment
		(start 338.572094 4.515612)
		(end 336.930492 4.80568)
		(width 0.12954)
		(layer "B.Cu")
		(net "DELTA_L_85_5INCH_BOT_DN")
	)
	(segment
		(start 361.04068 2.704084)
		(end 360.262424 2.159508)
		(width 0.12954)
		(layer "B.Cu")
		(net "DELTA_L_85_5INCH_BOT_DN")
	)
	(segment
		(start 340.594696 4.617212)
		(end 339.878924 0.56642)
		(width 0.12954)
		(layer "B.Cu")
		(net "DELTA_L_85_5INCH_BOT_DN")
	)
	(segment
		(start 358.347518 0.839216)
		(end 358.943656 4.213352)
		(width 0.12954)
		(layer "B.Cu")
		(net "DELTA_L_85_5INCH_BOT_DN")
	)
	(segment
		(start 326.18934 0.868172)
		(end 326.773032 4.171696)
		(width 0.12954)
		(layer "B.Cu")
		(net "DELTA_L_85_5INCH_BOT_DN")
	)
	(segment
		(start 316.046358 2.704084)
		(end 315.957712 2.79273)
		(width 0.12954)
		(layer "B.Cu")
		(net "DELTA_L_85_5INCH_BOT_DN")
	)
	(segment
		(start 343.90203 0.579374)
		(end 343.751916 0.474218)
		(width 0.12954)
		(layer "B.Cu")
		(net "DELTA_L_85_5INCH_BOT_DN")
	)
	(segment
		(start 288.696146 2.02565)
		(end 287.31845 2.269236)
		(width 0.12954)
		(layer "F.Cu")
		(net "DELTA_L_85_10INCH_TOP_DP")
	)
	(segment
		(start 218.821762 2.15773)
		(end 218.524328 0.474218)
		(width 0.12954)
		(layer "F.Cu")
		(net "DELTA_L_85_10INCH_TOP_DP")
	)
	(segment
		(start 222.032576 -2.423668)
		(end 221.663768 -2.68224)
		(width 0.12954)
		(layer "F.Cu")
		(net "DELTA_L_85_10INCH_TOP_DP")
	)
	(segment
		(start 269.914116 -2.649474)
		(end 268.2748 -2.359406)
		(width 0.12954)
		(layer "F.Cu")
		(net "DELTA_L_85_10INCH_TOP_DP")
	)
	(segment
		(start 243.09197 2.256282)
		(end 242.942872 2.151888)
		(width 0.12954)
		(layer "F.Cu")
		(net "DELTA_L_85_10INCH_TOP_DP")
	)
	(segment
		(start 252.193552 -2.358644)
		(end 251.93498 -1.989836)
		(width 0.12954)
		(layer "F.Cu")
		(net "DELTA_L_85_10INCH_TOP_DP")
	)
	(segment
		(start 271.2339 2.251202)
		(end 271.084548 2.146554)
		(width 0.12954)
		(layer "F.Cu")
		(net "DELTA_L_85_10INCH_TOP_DP")
	)
	(segment
		(start 240.132362 -2.358136)
		(end 239.873536 -1.989836)
		(width 0.12954)
		(layer "F.Cu")
		(net "DELTA_L_85_10INCH_TOP_DP")
	)
	(segment
		(start 256.631694 1.837944)
		(end 256.527046 1.98755)
		(width 0.12954)
		(layer "F.Cu")
		(net "DELTA_L_85_10INCH_TOP_DP")
	)
	(segment
		(start 239.873536 -1.989836)
		(end 240.554002 1.859534)
		(width 0.12954)
		(layer "F.Cu")
		(net "DELTA_L_85_10INCH_TOP_DP")
	)
	(segment
		(start 281.974798 -2.651506)
		(end 280.335482 -2.361438)
		(width 0.12954)
		(layer "F.Cu")
		(net "DELTA_L_85_10INCH_TOP_DP")
	)
	(segment
		(start 227.010214 2.25552)
		(end 226.861116 2.151126)
		(width 0.12954)
		(layer "F.Cu")
		(net "DELTA_L_85_10INCH_TOP_DP")
	)
	(segment
		(start 260.547612 1.988058)
		(end 259.169408 2.231644)
		(width 0.12954)
		(layer "F.Cu")
		(net "DELTA_L_85_10INCH_TOP_DP")
	)
	(segment
		(start 257.849878 -2.666238)
		(end 256.210816 -2.37617)
		(width 0.12954)
		(layer "F.Cu")
		(net "DELTA_L_85_10INCH_TOP_DP")
	)
	(segment
		(start 232.408984 2.011426)
		(end 231.03078 2.255012)
		(width 0.12954)
		(layer "F.Cu")
		(net "DELTA_L_85_10INCH_TOP_DP")
	)
	(segment
		(start 287.169606 2.164842)
		(end 286.364934 -2.389124)
		(width 0.12954)
		(layer "F.Cu")
		(net "DELTA_L_85_10INCH_TOP_DP")
	)
	(segment
		(start 260.233414 -2.364232)
		(end 259.974842 -1.995424)
		(width 0.12954)
		(layer "F.Cu")
		(net "DELTA_L_85_10INCH_TOP_DP")
	)
	(segment
		(start 237.744508 -2.689352)
		(end 236.104938 -2.399284)
		(width 0.12954)
		(layer "F.Cu")
		(net "DELTA_L_85_10INCH_TOP_DP")
	)
	(segment
		(start 276.31644 -2.356104)
		(end 276.057614 -1.98755)
		(width 0.12954)
		(layer "F.Cu")
		(net "DELTA_L_85_10INCH_TOP_DP")
	)
	(segment
		(start 220.349318 2.018538)
		(end 218.971114 2.262124)
		(width 0.12954)
		(layer "F.Cu")
		(net "DELTA_L_85_10INCH_TOP_DP")
	)
	(segment
		(start 236.531404 1.847596)
		(end 236.426756 1.997202)
		(width 0.12954)
		(layer "F.Cu")
		(net "DELTA_L_85_10INCH_TOP_DP")
	)
	(segment
		(start 290.385754 -2.386584)
		(end 290.016946 -2.645156)
		(width 0.12954)
		(layer "F.Cu")
		(net "DELTA_L_85_10INCH_TOP_DP")
	)
	(segment
		(start 256.210816 -2.37617)
		(end 255.952244 -2.007362)
		(width 0.12954)
		(layer "F.Cu")
		(net "DELTA_L_85_10INCH_TOP_DP")
	)
	(segment
		(start 247.803162 2.140712)
		(end 247.803162 2.140966)
		(width 0.12954)
		(layer "F.Cu")
		(net "DELTA_L_85_10INCH_TOP_DP")
	)
	(segment
		(start 264.255504 -2.354834)
		(end 263.996932 -1.986026)
		(width 0.12954)
		(layer "F.Cu")
		(net "DELTA_L_85_10INCH_TOP_DP")
	)
	(segment
		(start 230.076248 -2.407158)
		(end 229.707694 -2.66573)
		(width 0.12954)
		(layer "F.Cu")
		(net "DELTA_L_85_10INCH_TOP_DP")
	)
	(segment
		(start 236.104938 -2.399284)
		(end 235.846366 -2.030476)
		(width 0.12954)
		(layer "F.Cu")
		(net "DELTA_L_85_10INCH_TOP_DP")
	)
	(segment
		(start 235.846366 -2.030476)
		(end 236.531404 1.847596)
		(width 0.12954)
		(layer "F.Cu")
		(net "DELTA_L_85_10INCH_TOP_DP")
	)
	(segment
		(start 234.0991 -2.39522)
		(end 233.729784 -2.653792)
		(width 0.12954)
		(layer "F.Cu")
		(net "DELTA_L_85_10INCH_TOP_DP")
	)
	(segment
		(start 287.31845 2.269236)
		(end 287.169606 2.164842)
		(width 0.12954)
		(layer "F.Cu")
		(net "DELTA_L_85_10INCH_TOP_DP")
	)
	(segment
		(start 268.696948 1.86182)
		(end 268.5923 2.011426)
		(width 0.12954)
		(layer "F.Cu")
		(net "DELTA_L_85_10INCH_TOP_DP")
	)
	(segment
		(start 238.112808 -2.430526)
		(end 237.744508 -2.689352)
		(width 0.12954)
		(layer "F.Cu")
		(net "DELTA_L_85_10INCH_TOP_DP")
	)
	(segment
		(start 238.921798 2.147824)
		(end 238.112808 -2.430526)
		(width 0.12954)
		(layer "F.Cu")
		(net "DELTA_L_85_10INCH_TOP_DP")
	)
	(segment
		(start 243.896896 -1.972564)
		(end 244.574822 1.863344)
		(width 0.12954)
		(layer "F.Cu")
		(net "DELTA_L_85_10INCH_TOP_DP")
	)
	(segment
		(start 299.555408 -0.247142)
		(end 299.466762 -0.158496)
		(width 0.12954)
		(layer "F.Cu")
		(net "DELTA_L_85_10INCH_TOP_DP")
	)
	(segment
		(start 226.861116 2.151126)
		(end 226.055682 -2.408174)
		(width 0.12954)
		(layer "F.Cu")
		(net "DELTA_L_85_10INCH_TOP_DP")
	)
	(segment
		(start 252.615954 1.865376)
		(end 252.511306 2.014982)
		(width 0.12954)
		(layer "F.Cu")
		(net "DELTA_L_85_10INCH_TOP_DP")
	)
	(segment
		(start 254.999744 2.126742)
		(end 254.201422 -2.39014)
		(width 0.12954)
		(layer "F.Cu")
		(net "DELTA_L_85_10INCH_TOP_DP")
	)
	(segment
		(start 276.636226 2.027936)
		(end 275.258022 2.271522)
		(width 0.12954)
		(layer "F.Cu")
		(net "DELTA_L_85_10INCH_TOP_DP")
	)
	(segment
		(start 268.5923 2.011426)
		(end 267.214096 2.255012)
		(width 0.12954)
		(layer "F.Cu")
		(net "DELTA_L_85_10INCH_TOP_DP")
	)
	(segment
		(start 222.838772 2.137664)
		(end 222.032576 -2.423668)
		(width 0.12954)
		(layer "F.Cu")
		(net "DELTA_L_85_10INCH_TOP_DP")
	)
	(segment
		(start 259.169408 2.231644)
		(end 259.02031 2.12725)
		(width 0.12954)
		(layer "F.Cu")
		(net "DELTA_L_85_10INCH_TOP_DP")
	)
	(segment
		(start 224.36582 1.998472)
		(end 222.98787 2.242058)
		(width 0.12954)
		(layer "F.Cu")
		(net "DELTA_L_85_10INCH_TOP_DP")
	)
	(segment
		(start 247.803162 2.140966)
		(end 247.113806 2.262886)
		(width 0.12954)
		(layer "F.Cu")
		(net "DELTA_L_85_10INCH_TOP_DP")
	)
	(segment
		(start 235.737908 2.118614)
		(end 235.737908 2.118868)
		(width 0.12954)
		(layer "F.Cu")
		(net "DELTA_L_85_10INCH_TOP_DP")
	)
	(segment
		(start 280.07691 -1.99263)
		(end 280.759154 1.867154)
		(width 0.12954)
		(layer "F.Cu")
		(net "DELTA_L_85_10INCH_TOP_DP")
	)
	(segment
		(start 263.996932 -1.986026)
		(end 264.67435 1.848612)
		(width 0.12954)
		(layer "F.Cu")
		(net "DELTA_L_85_10INCH_TOP_DP")
	)
	(segment
		(start 227.809806 -2.006346)
		(end 228.493066 1.862328)
		(width 0.12954)
		(layer "F.Cu")
		(net "DELTA_L_85_10INCH_TOP_DP")
	)
	(segment
		(start 228.493066 1.862328)
		(end 228.388418 2.011934)
		(width 0.12954)
		(layer "F.Cu")
		(net "DELTA_L_85_10INCH_TOP_DP")
	)
	(segment
		(start 240.554002 1.859534)
		(end 240.449354 2.008886)
		(width 0.12954)
		(layer "F.Cu")
		(net "DELTA_L_85_10INCH_TOP_DP")
	)
	(segment
		(start 264.67435 1.848612)
		(end 264.569702 1.998218)
		(width 0.12954)
		(layer "F.Cu")
		(net "DELTA_L_85_10INCH_TOP_DP")
	)
	(segment
		(start 243.781326 2.134362)
		(end 243.09197 2.256282)
		(width 0.12954)
		(layer "F.Cu")
		(net "DELTA_L_85_10INCH_TOP_DP")
	)
	(segment
		(start 277.955502 -2.646172)
		(end 276.31644 -2.356104)
		(width 0.12954)
		(layer "F.Cu")
		(net "DELTA_L_85_10INCH_TOP_DP")
	)
	(segment
		(start 299.466762 -0.158496)
		(end 295.34866 -0.158496)
		(width 0.12954)
		(layer "F.Cu")
		(net "DELTA_L_85_10INCH_TOP_DP")
	)
	(segment
		(start 222.98787 2.242058)
		(end 222.838772 2.137664)
		(width 0.12954)
		(layer "F.Cu")
		(net "DELTA_L_85_10INCH_TOP_DP")
	)
	(segment
		(start 242.942872 2.151888)
		(end 242.140232 -2.389632)
		(width 0.12954)
		(layer "F.Cu")
		(net "DELTA_L_85_10INCH_TOP_DP")
	)
	(segment
		(start 265.895328 -2.644902)
		(end 264.255504 -2.354834)
		(width 0.12954)
		(layer "F.Cu")
		(net "DELTA_L_85_10INCH_TOP_DP")
	)
	(segment
		(start 274.305268 -2.380996)
		(end 273.93646 -2.639568)
		(width 0.12954)
		(layer "F.Cu")
		(net "DELTA_L_85_10INCH_TOP_DP")
	)
	(segment
		(start 254.201422 -2.39014)
		(end 253.832868 -2.648966)
		(width 0.12954)
		(layer "F.Cu")
		(net "DELTA_L_85_10INCH_TOP_DP")
	)
	(segment
		(start 279.127204 2.155952)
		(end 278.32431 -2.3876)
		(width 0.12954)
		(layer "F.Cu")
		(net "DELTA_L_85_10INCH_TOP_DP")
	)
	(segment
		(start 270.282924 -2.390902)
		(end 269.914116 -2.649474)
		(width 0.12954)
		(layer "F.Cu")
		(net "DELTA_L_85_10INCH_TOP_DP")
	)
	(segment
		(start 280.654506 2.01676)
		(end 279.276302 2.260346)
		(width 0.12954)
		(layer "F.Cu")
		(net "DELTA_L_85_10INCH_TOP_DP")
	)
	(segment
		(start 232.090722 -2.363724)
		(end 231.83215 -1.994916)
		(width 0.12954)
		(layer "F.Cu")
		(net "DELTA_L_85_10INCH_TOP_DP")
	)
	(segment
		(start 259.02031 2.12725)
		(end 258.219194 -2.407666)
		(width 0.12954)
		(layer "F.Cu")
		(net "DELTA_L_85_10INCH_TOP_DP")
	)
	(segment
		(start 267.064998 2.150618)
		(end 266.263374 -2.385822)
		(width 0.12954)
		(layer "F.Cu")
		(net "DELTA_L_85_10INCH_TOP_DP")
	)
	(segment
		(start 228.068378 -2.375408)
		(end 227.809806 -2.006346)
		(width 0.12954)
		(layer "F.Cu")
		(net "DELTA_L_85_10INCH_TOP_DP")
	)
	(segment
		(start 276.057614 -1.98755)
		(end 276.740874 1.878584)
		(width 0.12954)
		(layer "F.Cu")
		(net "DELTA_L_85_10INCH_TOP_DP")
	)
	(segment
		(start 246.964708 2.158492)
		(end 246.163846 -2.372868)
		(width 0.12954)
		(layer "F.Cu")
		(net "DELTA_L_85_10INCH_TOP_DP")
	)
	(segment
		(start 220.453712 1.86944)
		(end 220.349318 2.018538)
		(width 0.12954)
		(layer "F.Cu")
		(net "DELTA_L_85_10INCH_TOP_DP")
	)
	(segment
		(start 250.984004 2.154174)
		(end 250.179586 -2.401062)
		(width 0.12954)
		(layer "F.Cu")
		(net "DELTA_L_85_10INCH_TOP_DP")
	)
	(segment
		(start 253.832868 -2.648966)
		(end 252.193552 -2.358644)
		(width 0.12954)
		(layer "F.Cu")
		(net "DELTA_L_85_10INCH_TOP_DP")
	)
	(segment
		(start 251.822458 2.136394)
		(end 251.822458 2.136648)
		(width 0.12954)
		(layer "F.Cu")
		(net "DELTA_L_85_10INCH_TOP_DP")
	)
	(segment
		(start 250.179586 -2.401062)
		(end 249.81027 -2.659634)
		(width 0.12954)
		(layer "F.Cu")
		(net "DELTA_L_85_10INCH_TOP_DP")
	)
	(segment
		(start 218.524328 0.474218)
		(end 217.620342 -0.158496)
		(width 0.12954)
		(layer "F.Cu")
		(net "DELTA_L_85_10INCH_TOP_DP")
	)
	(segment
		(start 234.899454 2.13614)
		(end 234.0991 -2.39522)
		(width 0.12954)
		(layer "F.Cu")
		(net "DELTA_L_85_10INCH_TOP_DP")
	)
	(segment
		(start 235.737908 2.118868)
		(end 235.048552 2.240788)
		(width 0.12954)
		(layer "F.Cu")
		(net "DELTA_L_85_10INCH_TOP_DP")
	)
	(segment
		(start 275.108924 2.167128)
		(end 274.305268 -2.380996)
		(width 0.12954)
		(layer "F.Cu")
		(net "DELTA_L_85_10INCH_TOP_DP")
	)
	(segment
		(start 284.677104 2.02946)
		(end 283.2989 2.273046)
		(width 0.12954)
		(layer "F.Cu")
		(net "DELTA_L_85_10INCH_TOP_DP")
	)
	(segment
		(start 266.263374 -2.385822)
		(end 265.895328 -2.644902)
		(width 0.12954)
		(layer "F.Cu")
		(net "DELTA_L_85_10INCH_TOP_DP")
	)
	(segment
		(start 272.612104 2.007616)
		(end 271.2339 2.251202)
		(width 0.12954)
		(layer "F.Cu")
		(net "DELTA_L_85_10INCH_TOP_DP")
	)
	(segment
		(start 217.620342 -0.158496)
		(end 213.520782 -0.158496)
		(width 0.12954)
		(layer "F.Cu")
		(net "DELTA_L_85_10INCH_TOP_DP")
	)
	(segment
		(start 218.971114 2.262124)
		(end 218.821762 2.15773)
		(width 0.12954)
		(layer "F.Cu")
		(net "DELTA_L_85_10INCH_TOP_DP")
	)
	(segment
		(start 213.432136 -0.247142)
		(end 213.297008 -0.247142)
		(width 0.12954)
		(layer "F.Cu")
		(net "DELTA_L_85_10INCH_TOP_DP")
	)
	(segment
		(start 275.258022 2.271522)
		(end 275.108924 2.167128)
		(width 0.12954)
		(layer "F.Cu")
		(net "DELTA_L_85_10INCH_TOP_DP")
	)
	(segment
		(start 244.155468 -2.341372)
		(end 243.896896 -1.972564)
		(width 0.12954)
		(layer "F.Cu")
		(net "DELTA_L_85_10INCH_TOP_DP")
	)
	(segment
		(start 291.19068 2.16916)
		(end 290.385754 -2.386584)
		(width 0.12954)
		(layer "F.Cu")
		(net "DELTA_L_85_10INCH_TOP_DP")
	)
	(segment
		(start 231.83215 -1.994916)
		(end 232.513632 1.86182)
		(width 0.12954)
		(layer "F.Cu")
		(net "DELTA_L_85_10INCH_TOP_DP")
	)
	(segment
		(start 213.520782 -0.158496)
		(end 213.432136 -0.247142)
		(width 0.12954)
		(layer "F.Cu")
		(net "DELTA_L_85_10INCH_TOP_DP")
	)
	(segment
		(start 259.974842 -1.995424)
		(end 260.65226 1.838452)
		(width 0.12954)
		(layer "F.Cu")
		(net "DELTA_L_85_10INCH_TOP_DP")
	)
	(segment
		(start 272.716752 1.858264)
		(end 272.612104 2.007616)
		(width 0.12954)
		(layer "F.Cu")
		(net "DELTA_L_85_10INCH_TOP_DP")
	)
	(segment
		(start 232.513632 1.86182)
		(end 232.408984 2.011426)
		(width 0.12954)
		(layer "F.Cu")
		(net "DELTA_L_85_10INCH_TOP_DP")
	)
	(segment
		(start 248.171462 -2.369566)
		(end 247.912636 -2.001266)
		(width 0.12954)
		(layer "F.Cu")
		(net "DELTA_L_85_10INCH_TOP_DP")
	)
	(segment
		(start 273.93646 -2.639568)
		(end 272.297144 -2.3495)
		(width 0.12954)
		(layer "F.Cu")
		(net "DELTA_L_85_10INCH_TOP_DP")
	)
	(segment
		(start 288.37763 -2.355088)
		(end 288.119058 -1.98628)
		(width 0.12954)
		(layer "F.Cu")
		(net "DELTA_L_85_10INCH_TOP_DP")
	)
	(segment
		(start 225.686874 -2.666746)
		(end 224.047558 -2.376678)
		(width 0.12954)
		(layer "F.Cu")
		(net "DELTA_L_85_10INCH_TOP_DP")
	)
	(segment
		(start 280.335482 -2.361438)
		(end 280.07691 -1.99263)
		(width 0.12954)
		(layer "F.Cu")
		(net "DELTA_L_85_10INCH_TOP_DP")
	)
	(segment
		(start 244.470174 2.012696)
		(end 243.781326 2.134108)
		(width 0.12954)
		(layer "F.Cu")
		(net "DELTA_L_85_10INCH_TOP_DP")
	)
	(segment
		(start 247.113806 2.262886)
		(end 246.964708 2.158492)
		(width 0.12954)
		(layer "F.Cu")
		(net "DELTA_L_85_10INCH_TOP_DP")
	)
	(segment
		(start 263.191498 2.241804)
		(end 263.0424 2.13741)
		(width 0.12954)
		(layer "F.Cu")
		(net "DELTA_L_85_10INCH_TOP_DP")
	)
	(segment
		(start 245.79453 -2.63144)
		(end 244.155468 -2.341372)
		(width 0.12954)
		(layer "F.Cu")
		(net "DELTA_L_85_10INCH_TOP_DP")
	)
	(segment
		(start 235.048552 2.240788)
		(end 234.899454 2.13614)
		(width 0.12954)
		(layer "F.Cu")
		(net "DELTA_L_85_10INCH_TOP_DP")
	)
	(segment
		(start 292.822376 1.880362)
		(end 292.717728 2.029968)
		(width 0.12954)
		(layer "F.Cu")
		(net "DELTA_L_85_10INCH_TOP_DP")
	)
	(segment
		(start 291.339778 2.273554)
		(end 291.19068 2.16916)
		(width 0.12954)
		(layer "F.Cu")
		(net "DELTA_L_85_10INCH_TOP_DP")
	)
	(segment
		(start 226.055682 -2.408174)
		(end 225.686874 -2.666746)
		(width 0.12954)
		(layer "F.Cu")
		(net "DELTA_L_85_10INCH_TOP_DP")
	)
	(segment
		(start 294.722296 -0.596392)
		(end 294.40124 -2.414524)
		(width 0.12954)
		(layer "F.Cu")
		(net "DELTA_L_85_10INCH_TOP_DP")
	)
	(segment
		(start 258.219194 -2.407666)
		(end 257.849878 -2.666238)
		(width 0.12954)
		(layer "F.Cu")
		(net "DELTA_L_85_10INCH_TOP_DP")
	)
	(segment
		(start 243.781326 2.134108)
		(end 243.781326 2.134362)
		(width 0.12954)
		(layer "F.Cu")
		(net "DELTA_L_85_10INCH_TOP_DP")
	)
	(segment
		(start 220.024452 -2.392172)
		(end 219.76588 -2.023364)
		(width 0.12954)
		(layer "F.Cu")
		(net "DELTA_L_85_10INCH_TOP_DP")
	)
	(segment
		(start 288.801048 1.87579)
		(end 288.696146 2.02565)
		(width 0.12954)
		(layer "F.Cu")
		(net "DELTA_L_85_10INCH_TOP_DP")
	)
	(segment
		(start 267.214096 2.255012)
		(end 267.064998 2.150618)
		(width 0.12954)
		(layer "F.Cu")
		(net "DELTA_L_85_10INCH_TOP_DP")
	)
	(segment
		(start 256.527046 1.98755)
		(end 255.838198 2.108962)
		(width 0.12954)
		(layer "F.Cu")
		(net "DELTA_L_85_10INCH_TOP_DP")
	)
	(segment
		(start 272.038572 -1.980692)
		(end 272.716752 1.858264)
		(width 0.12954)
		(layer "F.Cu")
		(net "DELTA_L_85_10INCH_TOP_DP")
	)
	(segment
		(start 284.098238 -1.98882)
		(end 284.781752 1.879854)
		(width 0.12954)
		(layer "F.Cu")
		(net "DELTA_L_85_10INCH_TOP_DP")
	)
	(segment
		(start 241.771424 -2.648204)
		(end 240.132362 -2.358136)
		(width 0.12954)
		(layer "F.Cu")
		(net "DELTA_L_85_10INCH_TOP_DP")
	)
	(segment
		(start 282.343606 -2.392934)
		(end 281.974798 -2.651506)
		(width 0.12954)
		(layer "F.Cu")
		(net "DELTA_L_85_10INCH_TOP_DP")
	)
	(segment
		(start 268.2748 -2.359406)
		(end 268.016228 -1.990598)
		(width 0.12954)
		(layer "F.Cu")
		(net "DELTA_L_85_10INCH_TOP_DP")
	)
	(segment
		(start 276.740874 1.878584)
		(end 276.636226 2.027936)
		(width 0.12954)
		(layer "F.Cu")
		(net "DELTA_L_85_10INCH_TOP_DP")
	)
	(segment
		(start 283.2989 2.273046)
		(end 283.149802 2.168652)
		(width 0.12954)
		(layer "F.Cu")
		(net "DELTA_L_85_10INCH_TOP_DP")
	)
	(segment
		(start 219.76588 -2.023364)
		(end 220.453712 1.86944)
		(width 0.12954)
		(layer "F.Cu")
		(net "DELTA_L_85_10INCH_TOP_DP")
	)
	(segment
		(start 261.873238 -2.654554)
		(end 260.233414 -2.364232)
		(width 0.12954)
		(layer "F.Cu")
		(net "DELTA_L_85_10INCH_TOP_DP")
	)
	(segment
		(start 248.596658 1.869694)
		(end 248.49201 2.0193)
		(width 0.12954)
		(layer "F.Cu")
		(net "DELTA_L_85_10INCH_TOP_DP")
	)
	(segment
		(start 284.781752 1.879854)
		(end 284.677104 2.02946)
		(width 0.12954)
		(layer "F.Cu")
		(net "DELTA_L_85_10INCH_TOP_DP")
	)
	(segment
		(start 229.707694 -2.66573)
		(end 228.068378 -2.375408)
		(width 0.12954)
		(layer "F.Cu")
		(net "DELTA_L_85_10INCH_TOP_DP")
	)
	(segment
		(start 286.364934 -2.389124)
		(end 285.996126 -2.647696)
		(width 0.12954)
		(layer "F.Cu")
		(net "DELTA_L_85_10INCH_TOP_DP")
	)
	(segment
		(start 264.569702 1.998218)
		(end 263.191498 2.241804)
		(width 0.12954)
		(layer "F.Cu")
		(net "DELTA_L_85_10INCH_TOP_DP")
	)
	(segment
		(start 251.822458 2.136648)
		(end 251.133102 2.258568)
		(width 0.12954)
		(layer "F.Cu")
		(net "DELTA_L_85_10INCH_TOP_DP")
	)
	(segment
		(start 224.047558 -2.376678)
		(end 223.788986 -2.00787)
		(width 0.12954)
		(layer "F.Cu")
		(net "DELTA_L_85_10INCH_TOP_DP")
	)
	(segment
		(start 292.717728 2.029968)
		(end 291.339778 2.273554)
		(width 0.12954)
		(layer "F.Cu")
		(net "DELTA_L_85_10INCH_TOP_DP")
	)
	(segment
		(start 294.032432 -2.673096)
		(end 292.393116 -2.382774)
		(width 0.12954)
		(layer "F.Cu")
		(net "DELTA_L_85_10INCH_TOP_DP")
	)
	(segment
		(start 233.729784 -2.653792)
		(end 232.090722 -2.363724)
		(width 0.12954)
		(layer "F.Cu")
		(net "DELTA_L_85_10INCH_TOP_DP")
	)
	(segment
		(start 255.838198 2.108962)
		(end 255.838198 2.109216)
		(width 0.12954)
		(layer "F.Cu")
		(net "DELTA_L_85_10INCH_TOP_DP")
	)
	(segment
		(start 290.016946 -2.645156)
		(end 288.37763 -2.355088)
		(width 0.12954)
		(layer "F.Cu")
		(net "DELTA_L_85_10INCH_TOP_DP")
	)
	(segment
		(start 240.449354 2.008886)
		(end 239.07115 2.252472)
		(width 0.12954)
		(layer "F.Cu")
		(net "DELTA_L_85_10INCH_TOP_DP")
	)
	(segment
		(start 228.388418 2.011934)
		(end 227.010214 2.25552)
		(width 0.12954)
		(layer "F.Cu")
		(net "DELTA_L_85_10INCH_TOP_DP")
	)
	(segment
		(start 248.49201 2.0193)
		(end 247.803162 2.140712)
		(width 0.12954)
		(layer "F.Cu")
		(net "DELTA_L_85_10INCH_TOP_DP")
	)
	(segment
		(start 230.881682 2.150364)
		(end 230.076248 -2.407158)
		(width 0.12954)
		(layer "F.Cu")
		(net "DELTA_L_85_10INCH_TOP_DP")
	)
	(segment
		(start 249.81027 -2.659634)
		(end 248.171462 -2.369566)
		(width 0.12954)
		(layer "F.Cu")
		(net "DELTA_L_85_10INCH_TOP_DP")
	)
	(segment
		(start 278.32431 -2.3876)
		(end 277.955502 -2.646172)
		(width 0.12954)
		(layer "F.Cu")
		(net "DELTA_L_85_10INCH_TOP_DP")
	)
	(segment
		(start 252.511306 2.014982)
		(end 251.822458 2.136394)
		(width 0.12954)
		(layer "F.Cu")
		(net "DELTA_L_85_10INCH_TOP_DP")
	)
	(segment
		(start 239.07115 2.252472)
		(end 238.921798 2.147824)
		(width 0.12954)
		(layer "F.Cu")
		(net "DELTA_L_85_10INCH_TOP_DP")
	)
	(segment
		(start 236.426756 1.997202)
		(end 235.737908 2.118614)
		(width 0.12954)
		(layer "F.Cu")
		(net "DELTA_L_85_10INCH_TOP_DP")
	)
	(segment
		(start 292.134544 -2.013966)
		(end 292.822376 1.880362)
		(width 0.12954)
		(layer "F.Cu")
		(net "DELTA_L_85_10INCH_TOP_DP")
	)
	(segment
		(start 260.65226 1.838452)
		(end 260.547612 1.988058)
		(width 0.12954)
		(layer "F.Cu")
		(net "DELTA_L_85_10INCH_TOP_DP")
	)
	(segment
		(start 221.663768 -2.68224)
		(end 220.024452 -2.392172)
		(width 0.12954)
		(layer "F.Cu")
		(net "DELTA_L_85_10INCH_TOP_DP")
	)
	(segment
		(start 295.34866 -0.158496)
		(end 294.722296 -0.596392)
		(width 0.12954)
		(layer "F.Cu")
		(net "DELTA_L_85_10INCH_TOP_DP")
	)
	(segment
		(start 262.241284 -2.395474)
		(end 261.873238 -2.654554)
		(width 0.12954)
		(layer "F.Cu")
		(net "DELTA_L_85_10INCH_TOP_DP")
	)
	(segment
		(start 242.140232 -2.389632)
		(end 241.771424 -2.648204)
		(width 0.12954)
		(layer "F.Cu")
		(net "DELTA_L_85_10INCH_TOP_DP")
	)
	(segment
		(start 244.574822 1.863344)
		(end 244.470174 2.012696)
		(width 0.12954)
		(layer "F.Cu")
		(net "DELTA_L_85_10INCH_TOP_DP")
	)
	(segment
		(start 285.996126 -2.647696)
		(end 284.35681 -2.357628)
		(width 0.12954)
		(layer "F.Cu")
		(net "DELTA_L_85_10INCH_TOP_DP")
	)
	(segment
		(start 223.788986 -2.00787)
		(end 224.470468 1.848866)
		(width 0.12954)
		(layer "F.Cu")
		(net "DELTA_L_85_10INCH_TOP_DP")
	)
	(segment
		(start 271.084548 2.146554)
		(end 270.282924 -2.390902)
		(width 0.12954)
		(layer "F.Cu")
		(net "DELTA_L_85_10INCH_TOP_DP")
	)
	(segment
		(start 263.0424 2.13741)
		(end 262.241284 -2.395474)
		(width 0.12954)
		(layer "F.Cu")
		(net "DELTA_L_85_10INCH_TOP_DP")
	)
	(segment
		(start 246.163846 -2.372868)
		(end 245.79453 -2.63144)
		(width 0.12954)
		(layer "F.Cu")
		(net "DELTA_L_85_10INCH_TOP_DP")
	)
	(segment
		(start 299.712888 -0.247142)
		(end 299.555408 -0.247142)
		(width 0.12954)
		(layer "F.Cu")
		(net "DELTA_L_85_10INCH_TOP_DP")
	)
	(segment
		(start 251.133102 2.258568)
		(end 250.984004 2.154174)
		(width 0.12954)
		(layer "F.Cu")
		(net "DELTA_L_85_10INCH_TOP_DP")
	)
	(segment
		(start 279.276302 2.260346)
		(end 279.127204 2.155952)
		(width 0.12954)
		(layer "F.Cu")
		(net "DELTA_L_85_10INCH_TOP_DP")
	)
	(segment
		(start 251.93498 -1.989836)
		(end 252.615954 1.865376)
		(width 0.12954)
		(layer "F.Cu")
		(net "DELTA_L_85_10INCH_TOP_DP")
	)
	(segment
		(start 231.03078 2.255012)
		(end 230.881682 2.150364)
		(width 0.12954)
		(layer "F.Cu")
		(net "DELTA_L_85_10INCH_TOP_DP")
	)
	(segment
		(start 255.838198 2.109216)
		(end 255.148842 2.231136)
		(width 0.12954)
		(layer "F.Cu")
		(net "DELTA_L_85_10INCH_TOP_DP")
	)
	(segment
		(start 255.952244 -2.007362)
		(end 256.631694 1.837944)
		(width 0.12954)
		(layer "F.Cu")
		(net "DELTA_L_85_10INCH_TOP_DP")
	)
	(segment
		(start 247.912636 -2.001266)
		(end 248.596658 1.869694)
		(width 0.12954)
		(layer "F.Cu")
		(net "DELTA_L_85_10INCH_TOP_DP")
	)
	(segment
		(start 272.297144 -2.3495)
		(end 272.038572 -1.980692)
		(width 0.12954)
		(layer "F.Cu")
		(net "DELTA_L_85_10INCH_TOP_DP")
	)
	(segment
		(start 283.149802 2.168652)
		(end 282.343606 -2.392934)
		(width 0.12954)
		(layer "F.Cu")
		(net "DELTA_L_85_10INCH_TOP_DP")
	)
	(segment
		(start 284.35681 -2.357628)
		(end 284.098238 -1.98882)
		(width 0.12954)
		(layer "F.Cu")
		(net "DELTA_L_85_10INCH_TOP_DP")
	)
	(segment
		(start 288.119058 -1.98628)
		(end 288.801048 1.87579)
		(width 0.12954)
		(layer "F.Cu")
		(net "DELTA_L_85_10INCH_TOP_DP")
	)
	(segment
		(start 294.40124 -2.414524)
		(end 294.032432 -2.673096)
		(width 0.12954)
		(layer "F.Cu")
		(net "DELTA_L_85_10INCH_TOP_DP")
	)
	(segment
		(start 280.759154 1.867154)
		(end 280.654506 2.01676)
		(width 0.12954)
		(layer "F.Cu")
		(net "DELTA_L_85_10INCH_TOP_DP")
	)
	(segment
		(start 255.148842 2.231136)
		(end 254.999744 2.126742)
		(width 0.12954)
		(layer "F.Cu")
		(net "DELTA_L_85_10INCH_TOP_DP")
	)
	(segment
		(start 224.470468 1.848866)
		(end 224.36582 1.998472)
		(width 0.12954)
		(layer "F.Cu")
		(net "DELTA_L_85_10INCH_TOP_DP")
	)
	(segment
		(start 292.393116 -2.382774)
		(end 292.134544 -2.013966)
		(width 0.12954)
		(layer "F.Cu")
		(net "DELTA_L_85_10INCH_TOP_DP")
	)
	(segment
		(start 268.016228 -1.990598)
		(end 268.696948 1.86182)
		(width 0.12954)
		(layer "F.Cu")
		(net "DELTA_L_85_10INCH_TOP_DP")
	)
	(segment
		(start 228.150928 -1.930654)
		(end 228.834188 1.937766)
		(width 0.12954)
		(layer "F.Cu")
		(net "DELTA_L_85_10INCH_TOP_DN")
	)
	(segment
		(start 284.865064 2.3241)
		(end 283.223462 2.614168)
		(width 0.12954)
		(layer "F.Cu")
		(net "DELTA_L_85_10INCH_TOP_DN")
	)
	(segment
		(start 285.920434 -2.306574)
		(end 284.544516 -2.062988)
		(width 0.12954)
		(layer "F.Cu")
		(net "DELTA_L_85_10INCH_TOP_DN")
	)
	(segment
		(start 286.874966 2.352548)
		(end 286.070294 -2.201418)
		(width 0.12954)
		(layer "F.Cu")
		(net "DELTA_L_85_10INCH_TOP_DN")
	)
	(segment
		(start 280.523188 -2.066798)
		(end 280.418032 -1.916938)
		(width 0.12954)
		(layer "F.Cu")
		(net "DELTA_L_85_10INCH_TOP_DN")
	)
	(segment
		(start 269.03807 1.937258)
		(end 268.78026 2.306066)
		(width 0.12954)
		(layer "F.Cu")
		(net "DELTA_L_85_10INCH_TOP_DN")
	)
	(segment
		(start 256.398522 -2.08153)
		(end 256.293366 -1.93167)
		(width 0.12954)
		(layer "F.Cu")
		(net "DELTA_L_85_10INCH_TOP_DN")
	)
	(segment
		(start 218.229688 0.661924)
		(end 217.518488 0.164084)
		(width 0.12954)
		(layer "F.Cu")
		(net "DELTA_L_85_10INCH_TOP_DN")
	)
	(segment
		(start 253.757176 -2.307844)
		(end 252.381258 -2.064258)
		(width 0.12954)
		(layer "F.Cu")
		(net "DELTA_L_85_10INCH_TOP_DN")
	)
	(segment
		(start 257.77444 -2.325116)
		(end 256.398522 -2.08153)
		(width 0.12954)
		(layer "F.Cu")
		(net "DELTA_L_85_10INCH_TOP_DN")
	)
	(segment
		(start 222.912432 2.58318)
		(end 222.544132 2.32537)
		(width 0.12954)
		(layer "F.Cu")
		(net "DELTA_L_85_10INCH_TOP_DN")
	)
	(segment
		(start 229.632002 -2.324608)
		(end 228.256084 -2.081022)
		(width 0.12954)
		(layer "F.Cu")
		(net "DELTA_L_85_10INCH_TOP_DN")
	)
	(segment
		(start 263.11606 2.582926)
		(end 262.74776 2.325116)
		(width 0.12954)
		(layer "F.Cu")
		(net "DELTA_L_85_10INCH_TOP_DN")
	)
	(segment
		(start 284.43936 -1.913128)
		(end 285.122874 1.955292)
		(width 0.12954)
		(layer "F.Cu")
		(net "DELTA_L_85_10INCH_TOP_DN")
	)
	(segment
		(start 213.519766 0.164084)
		(end 213.43112 0.25273)
		(width 0.12954)
		(layer "F.Cu")
		(net "DELTA_L_85_10INCH_TOP_DN")
	)
	(segment
		(start 220.107002 -1.947672)
		(end 220.794834 1.945132)
		(width 0.12954)
		(layer "F.Cu")
		(net "DELTA_L_85_10INCH_TOP_DN")
	)
	(segment
		(start 261.946644 -2.208276)
		(end 261.797292 -2.313432)
		(width 0.12954)
		(layer "F.Cu")
		(net "DELTA_L_85_10INCH_TOP_DN")
	)
	(segment
		(start 241.845592 -2.201926)
		(end 241.695732 -2.307082)
		(width 0.12954)
		(layer "F.Cu")
		(net "DELTA_L_85_10INCH_TOP_DN")
	)
	(segment
		(start 232.278428 -2.069084)
		(end 232.173272 -1.919224)
		(width 0.12954)
		(layer "F.Cu")
		(net "DELTA_L_85_10INCH_TOP_DN")
	)
	(segment
		(start 238.995712 2.593594)
		(end 238.627158 2.335784)
		(width 0.12954)
		(layer "F.Cu")
		(net "DELTA_L_85_10INCH_TOP_DN")
	)
	(segment
		(start 229.781608 -2.219452)
		(end 229.632002 -2.324608)
		(width 0.12954)
		(layer "F.Cu")
		(net "DELTA_L_85_10INCH_TOP_DN")
	)
	(segment
		(start 248.679716 2.31394)
		(end 247.038368 2.604008)
		(width 0.12954)
		(layer "F.Cu")
		(net "DELTA_L_85_10INCH_TOP_DN")
	)
	(segment
		(start 242.648232 2.339594)
		(end 241.845592 -2.201926)
		(width 0.12954)
		(layer "F.Cu")
		(net "DELTA_L_85_10INCH_TOP_DN")
	)
	(segment
		(start 290.091114 -2.198878)
		(end 289.941254 -2.304034)
		(width 0.12954)
		(layer "F.Cu")
		(net "DELTA_L_85_10INCH_TOP_DN")
	)
	(segment
		(start 294.427656 -0.408432)
		(end 294.1066 -2.226818)
		(width 0.12954)
		(layer "F.Cu")
		(net "DELTA_L_85_10INCH_TOP_DN")
	)
	(segment
		(start 228.256084 -2.081022)
		(end 228.150928 -1.930654)
		(width 0.12954)
		(layer "F.Cu")
		(net "DELTA_L_85_10INCH_TOP_DN")
	)
	(segment
		(start 293.163498 1.9558)
		(end 292.905688 2.324608)
		(width 0.12954)
		(layer "F.Cu")
		(net "DELTA_L_85_10INCH_TOP_DN")
	)
	(segment
		(start 294.1066 -2.226818)
		(end 293.95674 -2.331974)
		(width 0.12954)
		(layer "F.Cu")
		(net "DELTA_L_85_10INCH_TOP_DN")
	)
	(segment
		(start 248.93778 1.945386)
		(end 248.679716 2.31394)
		(width 0.12954)
		(layer "F.Cu")
		(net "DELTA_L_85_10INCH_TOP_DN")
	)
	(segment
		(start 218.527122 2.34569)
		(end 218.229688 0.661924)
		(width 0.12954)
		(layer "F.Cu")
		(net "DELTA_L_85_10INCH_TOP_DN")
	)
	(segment
		(start 241.695732 -2.307082)
		(end 240.319814 -2.063496)
		(width 0.12954)
		(layer "F.Cu")
		(net "DELTA_L_85_10INCH_TOP_DN")
	)
	(segment
		(start 279.200864 2.601468)
		(end 278.832564 2.343658)
		(width 0.12954)
		(layer "F.Cu")
		(net "DELTA_L_85_10INCH_TOP_DN")
	)
	(segment
		(start 284.544516 -2.062988)
		(end 284.43936 -1.913128)
		(width 0.12954)
		(layer "F.Cu")
		(net "DELTA_L_85_10INCH_TOP_DN")
	)
	(segment
		(start 273.860768 -2.298446)
		(end 272.48485 -2.05486)
		(width 0.12954)
		(layer "F.Cu")
		(net "DELTA_L_85_10INCH_TOP_DN")
	)
	(segment
		(start 218.895676 2.603246)
		(end 218.527122 2.34569)
		(width 0.12954)
		(layer "F.Cu")
		(net "DELTA_L_85_10INCH_TOP_DN")
	)
	(segment
		(start 292.580822 -2.088134)
		(end 292.475666 -1.938274)
		(width 0.12954)
		(layer "F.Cu")
		(net "DELTA_L_85_10INCH_TOP_DN")
	)
	(segment
		(start 233.654346 -2.31267)
		(end 232.278428 -2.069084)
		(width 0.12954)
		(layer "F.Cu")
		(net "DELTA_L_85_10INCH_TOP_DN")
	)
	(segment
		(start 254.705104 2.314448)
		(end 253.906782 -2.202688)
		(width 0.12954)
		(layer "F.Cu")
		(net "DELTA_L_85_10INCH_TOP_DN")
	)
	(segment
		(start 247.038368 2.604008)
		(end 246.670068 2.346198)
		(width 0.12954)
		(layer "F.Cu")
		(net "DELTA_L_85_10INCH_TOP_DN")
	)
	(segment
		(start 299.550328 0.25273)
		(end 299.461682 0.164084)
		(width 0.12954)
		(layer "F.Cu")
		(net "DELTA_L_85_10INCH_TOP_DN")
	)
	(segment
		(start 299.461682 0.164084)
		(end 295.24706 0.164084)
		(width 0.12954)
		(layer "F.Cu")
		(net "DELTA_L_85_10INCH_TOP_DN")
	)
	(segment
		(start 232.854754 1.937258)
		(end 232.596944 2.306066)
		(width 0.12954)
		(layer "F.Cu")
		(net "DELTA_L_85_10INCH_TOP_DN")
	)
	(segment
		(start 252.276102 -1.914144)
		(end 252.957076 1.941068)
		(width 0.12954)
		(layer "F.Cu")
		(net "DELTA_L_85_10INCH_TOP_DN")
	)
	(segment
		(start 265.015472 1.92405)
		(end 264.757662 2.292858)
		(width 0.12954)
		(layer "F.Cu")
		(net "DELTA_L_85_10INCH_TOP_DN")
	)
	(segment
		(start 265.819382 -2.30378)
		(end 264.44321 -2.060194)
		(width 0.12954)
		(layer "F.Cu")
		(net "DELTA_L_85_10INCH_TOP_DN")
	)
	(segment
		(start 236.292644 -2.104644)
		(end 236.187488 -1.954784)
		(width 0.12954)
		(layer "F.Cu")
		(net "DELTA_L_85_10INCH_TOP_DN")
	)
	(segment
		(start 287.242758 2.610358)
		(end 286.874966 2.352548)
		(width 0.12954)
		(layer "F.Cu")
		(net "DELTA_L_85_10INCH_TOP_DN")
	)
	(segment
		(start 255.073404 2.572258)
		(end 254.705104 2.314448)
		(width 0.12954)
		(layer "F.Cu")
		(net "DELTA_L_85_10INCH_TOP_DN")
	)
	(segment
		(start 236.872526 1.923034)
		(end 236.614716 2.291842)
		(width 0.12954)
		(layer "F.Cu")
		(net "DELTA_L_85_10INCH_TOP_DN")
	)
	(segment
		(start 261.797292 -2.313432)
		(end 260.42112 -2.069592)
		(width 0.12954)
		(layer "F.Cu")
		(net "DELTA_L_85_10INCH_TOP_DN")
	)
	(segment
		(start 271.158208 2.592324)
		(end 270.789908 2.33426)
		(width 0.12954)
		(layer "F.Cu")
		(net "DELTA_L_85_10INCH_TOP_DN")
	)
	(segment
		(start 237.818168 -2.243074)
		(end 237.668562 -2.34823)
		(width 0.12954)
		(layer "F.Cu")
		(net "DELTA_L_85_10INCH_TOP_DN")
	)
	(segment
		(start 244.915944 1.938782)
		(end 244.65788 2.307336)
		(width 0.12954)
		(layer "F.Cu")
		(net "DELTA_L_85_10INCH_TOP_DN")
	)
	(segment
		(start 272.379694 -1.905)
		(end 273.057874 1.933956)
		(width 0.12954)
		(layer "F.Cu")
		(net "DELTA_L_85_10INCH_TOP_DN")
	)
	(segment
		(start 244.65788 2.307336)
		(end 243.016532 2.597404)
		(width 0.12954)
		(layer "F.Cu")
		(net "DELTA_L_85_10INCH_TOP_DN")
	)
	(segment
		(start 299.712888 0.25273)
		(end 299.550328 0.25273)
		(width 0.12954)
		(layer "F.Cu")
		(net "DELTA_L_85_10INCH_TOP_DN")
	)
	(segment
		(start 288.46018 -1.910588)
		(end 289.14217 1.951228)
		(width 0.12954)
		(layer "F.Cu")
		(net "DELTA_L_85_10INCH_TOP_DN")
	)
	(segment
		(start 286.070294 -2.201418)
		(end 285.920434 -2.306574)
		(width 0.12954)
		(layer "F.Cu")
		(net "DELTA_L_85_10INCH_TOP_DN")
	)
	(segment
		(start 269.838424 -2.308352)
		(end 268.462506 -2.064766)
		(width 0.12954)
		(layer "F.Cu")
		(net "DELTA_L_85_10INCH_TOP_DN")
	)
	(segment
		(start 249.884946 -2.213356)
		(end 249.734832 -2.318512)
		(width 0.12954)
		(layer "F.Cu")
		(net "DELTA_L_85_10INCH_TOP_DN")
	)
	(segment
		(start 220.537024 2.313178)
		(end 218.895676 2.603246)
		(width 0.12954)
		(layer "F.Cu")
		(net "DELTA_L_85_10INCH_TOP_DN")
	)
	(segment
		(start 236.187488 -1.954784)
		(end 236.872526 1.923034)
		(width 0.12954)
		(layer "F.Cu")
		(net "DELTA_L_85_10INCH_TOP_DN")
	)
	(segment
		(start 248.253758 -1.92532)
		(end 248.93778 1.945386)
		(width 0.12954)
		(layer "F.Cu")
		(net "DELTA_L_85_10INCH_TOP_DN")
	)
	(segment
		(start 230.587042 2.337816)
		(end 229.781608 -2.219452)
		(width 0.12954)
		(layer "F.Cu")
		(net "DELTA_L_85_10INCH_TOP_DN")
	)
	(segment
		(start 291.26434 2.614676)
		(end 290.89604 2.356866)
		(width 0.12954)
		(layer "F.Cu")
		(net "DELTA_L_85_10INCH_TOP_DN")
	)
	(segment
		(start 213.43112 0.25273)
		(end 213.297008 0.25273)
		(width 0.12954)
		(layer "F.Cu")
		(net "DELTA_L_85_10INCH_TOP_DN")
	)
	(segment
		(start 225.611182 -2.325624)
		(end 224.235264 -2.082038)
		(width 0.12954)
		(layer "F.Cu")
		(net "DELTA_L_85_10INCH_TOP_DN")
	)
	(segment
		(start 244.343174 -2.046732)
		(end 244.238018 -1.896872)
		(width 0.12954)
		(layer "F.Cu")
		(net "DELTA_L_85_10INCH_TOP_DN")
	)
	(segment
		(start 230.955088 2.596134)
		(end 230.587042 2.337816)
		(width 0.12954)
		(layer "F.Cu")
		(net "DELTA_L_85_10INCH_TOP_DN")
	)
	(segment
		(start 220.212158 -2.097532)
		(end 220.107002 -1.947672)
		(width 0.12954)
		(layer "F.Cu")
		(net "DELTA_L_85_10INCH_TOP_DN")
	)
	(segment
		(start 221.588076 -2.341118)
		(end 220.212158 -2.097532)
		(width 0.12954)
		(layer "F.Cu")
		(net "DELTA_L_85_10INCH_TOP_DN")
	)
	(segment
		(start 256.293366 -1.93167)
		(end 256.972816 1.913636)
		(width 0.12954)
		(layer "F.Cu")
		(net "DELTA_L_85_10INCH_TOP_DN")
	)
	(segment
		(start 240.214658 -1.91389)
		(end 240.895124 1.935226)
		(width 0.12954)
		(layer "F.Cu")
		(net "DELTA_L_85_10INCH_TOP_DN")
	)
	(segment
		(start 268.462506 -2.064766)
		(end 268.35735 -1.914906)
		(width 0.12954)
		(layer "F.Cu")
		(net "DELTA_L_85_10INCH_TOP_DN")
	)
	(segment
		(start 273.057874 1.933956)
		(end 272.79981 2.302256)
		(width 0.12954)
		(layer "F.Cu")
		(net "DELTA_L_85_10INCH_TOP_DN")
	)
	(segment
		(start 270.789908 2.33426)
		(end 269.988284 -2.203196)
		(width 0.12954)
		(layer "F.Cu")
		(net "DELTA_L_85_10INCH_TOP_DN")
	)
	(segment
		(start 217.518488 0.164084)
		(end 213.519766 0.164084)
		(width 0.12954)
		(layer "F.Cu")
		(net "DELTA_L_85_10INCH_TOP_DN")
	)
	(segment
		(start 278.832564 2.343658)
		(end 278.02967 -2.199894)
		(width 0.12954)
		(layer "F.Cu")
		(net "DELTA_L_85_10INCH_TOP_DN")
	)
	(segment
		(start 275.182584 2.612644)
		(end 274.814284 2.354834)
		(width 0.12954)
		(layer "F.Cu")
		(net "DELTA_L_85_10INCH_TOP_DN")
	)
	(segment
		(start 276.398736 -1.911858)
		(end 277.081996 1.954276)
		(width 0.12954)
		(layer "F.Cu")
		(net "DELTA_L_85_10INCH_TOP_DN")
	)
	(segment
		(start 243.016532 2.597404)
		(end 242.648232 2.339594)
		(width 0.12954)
		(layer "F.Cu")
		(net "DELTA_L_85_10INCH_TOP_DN")
	)
	(segment
		(start 221.737936 -2.235962)
		(end 221.588076 -2.341118)
		(width 0.12954)
		(layer "F.Cu")
		(net "DELTA_L_85_10INCH_TOP_DN")
	)
	(segment
		(start 245.869206 -2.185162)
		(end 245.719092 -2.290318)
		(width 0.12954)
		(layer "F.Cu")
		(net "DELTA_L_85_10INCH_TOP_DN")
	)
	(segment
		(start 228.834188 1.937766)
		(end 228.576378 2.306574)
		(width 0.12954)
		(layer "F.Cu")
		(net "DELTA_L_85_10INCH_TOP_DN")
	)
	(segment
		(start 276.823932 2.322576)
		(end 275.182584 2.612644)
		(width 0.12954)
		(layer "F.Cu")
		(net "DELTA_L_85_10INCH_TOP_DN")
	)
	(segment
		(start 232.173272 -1.919224)
		(end 232.854754 1.937258)
		(width 0.12954)
		(layer "F.Cu")
		(net "DELTA_L_85_10INCH_TOP_DN")
	)
	(segment
		(start 269.988284 -2.203196)
		(end 269.838424 -2.308352)
		(width 0.12954)
		(layer "F.Cu")
		(net "DELTA_L_85_10INCH_TOP_DN")
	)
	(segment
		(start 226.566476 2.338832)
		(end 225.761042 -2.220468)
		(width 0.12954)
		(layer "F.Cu")
		(net "DELTA_L_85_10INCH_TOP_DN")
	)
	(segment
		(start 225.761042 -2.220468)
		(end 225.611182 -2.325624)
		(width 0.12954)
		(layer "F.Cu")
		(net "DELTA_L_85_10INCH_TOP_DN")
	)
	(segment
		(start 280.842466 2.3114)
		(end 279.200864 2.601468)
		(width 0.12954)
		(layer "F.Cu")
		(net "DELTA_L_85_10INCH_TOP_DN")
	)
	(segment
		(start 289.941254 -2.304034)
		(end 288.565336 -2.060448)
		(width 0.12954)
		(layer "F.Cu")
		(net "DELTA_L_85_10INCH_TOP_DN")
	)
	(segment
		(start 234.97286 2.58191)
		(end 234.604814 2.323592)
		(width 0.12954)
		(layer "F.Cu")
		(net "DELTA_L_85_10INCH_TOP_DN")
	)
	(segment
		(start 220.794834 1.945132)
		(end 220.537024 2.313178)
		(width 0.12954)
		(layer "F.Cu")
		(net "DELTA_L_85_10INCH_TOP_DN")
	)
	(segment
		(start 266.770358 2.338324)
		(end 265.968734 -2.198624)
		(width 0.12954)
		(layer "F.Cu")
		(net "DELTA_L_85_10INCH_TOP_DN")
	)
	(segment
		(start 246.670068 2.346198)
		(end 245.869206 -2.185162)
		(width 0.12954)
		(layer "F.Cu")
		(net "DELTA_L_85_10INCH_TOP_DN")
	)
	(segment
		(start 262.74776 2.325116)
		(end 261.946644 -2.208276)
		(width 0.12954)
		(layer "F.Cu")
		(net "DELTA_L_85_10INCH_TOP_DN")
	)
	(segment
		(start 245.719092 -2.290318)
		(end 244.343174 -2.046732)
		(width 0.12954)
		(layer "F.Cu")
		(net "DELTA_L_85_10INCH_TOP_DN")
	)
	(segment
		(start 293.95674 -2.331974)
		(end 292.580822 -2.088134)
		(width 0.12954)
		(layer "F.Cu")
		(net "DELTA_L_85_10INCH_TOP_DN")
	)
	(segment
		(start 292.905688 2.324608)
		(end 291.26434 2.614676)
		(width 0.12954)
		(layer "F.Cu")
		(net "DELTA_L_85_10INCH_TOP_DN")
	)
	(segment
		(start 288.565336 -2.060448)
		(end 288.46018 -1.910588)
		(width 0.12954)
		(layer "F.Cu")
		(net "DELTA_L_85_10INCH_TOP_DN")
	)
	(segment
		(start 267.138658 2.596134)
		(end 266.770358 2.338324)
		(width 0.12954)
		(layer "F.Cu")
		(net "DELTA_L_85_10INCH_TOP_DN")
	)
	(segment
		(start 264.757662 2.292858)
		(end 263.11606 2.582926)
		(width 0.12954)
		(layer "F.Cu")
		(net "DELTA_L_85_10INCH_TOP_DN")
	)
	(segment
		(start 252.699012 2.309622)
		(end 251.057664 2.59969)
		(width 0.12954)
		(layer "F.Cu")
		(net "DELTA_L_85_10INCH_TOP_DN")
	)
	(segment
		(start 224.235264 -2.082038)
		(end 224.130108 -1.932178)
		(width 0.12954)
		(layer "F.Cu")
		(net "DELTA_L_85_10INCH_TOP_DN")
	)
	(segment
		(start 233.80446 -2.207514)
		(end 233.654346 -2.31267)
		(width 0.12954)
		(layer "F.Cu")
		(net "DELTA_L_85_10INCH_TOP_DN")
	)
	(segment
		(start 256.714752 2.28219)
		(end 255.073404 2.572258)
		(width 0.12954)
		(layer "F.Cu")
		(net "DELTA_L_85_10INCH_TOP_DN")
	)
	(segment
		(start 272.48485 -2.05486)
		(end 272.379694 -1.905)
		(width 0.12954)
		(layer "F.Cu")
		(net "DELTA_L_85_10INCH_TOP_DN")
	)
	(segment
		(start 260.42112 -2.069592)
		(end 260.315964 -1.919732)
		(width 0.12954)
		(layer "F.Cu")
		(net "DELTA_L_85_10INCH_TOP_DN")
	)
	(segment
		(start 257.924554 -2.21996)
		(end 257.77444 -2.325116)
		(width 0.12954)
		(layer "F.Cu")
		(net "DELTA_L_85_10INCH_TOP_DN")
	)
	(segment
		(start 249.734832 -2.318512)
		(end 248.358914 -2.074926)
		(width 0.12954)
		(layer "F.Cu")
		(net "DELTA_L_85_10INCH_TOP_DN")
	)
	(segment
		(start 222.544132 2.32537)
		(end 221.737936 -2.235962)
		(width 0.12954)
		(layer "F.Cu")
		(net "DELTA_L_85_10INCH_TOP_DN")
	)
	(segment
		(start 272.79981 2.302256)
		(end 271.158208 2.592324)
		(width 0.12954)
		(layer "F.Cu")
		(net "DELTA_L_85_10INCH_TOP_DN")
	)
	(segment
		(start 224.81159 1.924304)
		(end 224.55378 2.293112)
		(width 0.12954)
		(layer "F.Cu")
		(net "DELTA_L_85_10INCH_TOP_DN")
	)
	(segment
		(start 277.081996 1.954276)
		(end 276.823932 2.322576)
		(width 0.12954)
		(layer "F.Cu")
		(net "DELTA_L_85_10INCH_TOP_DN")
	)
	(segment
		(start 260.993382 1.91389)
		(end 260.735572 2.282698)
		(width 0.12954)
		(layer "F.Cu")
		(net "DELTA_L_85_10INCH_TOP_DN")
	)
	(segment
		(start 234.604814 2.323592)
		(end 233.80446 -2.207514)
		(width 0.12954)
		(layer "F.Cu")
		(net "DELTA_L_85_10INCH_TOP_DN")
	)
	(segment
		(start 278.02967 -2.199894)
		(end 277.87981 -2.30505)
		(width 0.12954)
		(layer "F.Cu")
		(net "DELTA_L_85_10INCH_TOP_DN")
	)
	(segment
		(start 285.122874 1.955292)
		(end 284.865064 2.3241)
		(width 0.12954)
		(layer "F.Cu")
		(net "DELTA_L_85_10INCH_TOP_DN")
	)
	(segment
		(start 288.883852 2.32029)
		(end 287.242758 2.610358)
		(width 0.12954)
		(layer "F.Cu")
		(net "DELTA_L_85_10INCH_TOP_DN")
	)
	(segment
		(start 232.596944 2.306066)
		(end 230.955088 2.596134)
		(width 0.12954)
		(layer "F.Cu")
		(net "DELTA_L_85_10INCH_TOP_DN")
	)
	(segment
		(start 226.934776 2.596642)
		(end 226.566476 2.338832)
		(width 0.12954)
		(layer "F.Cu")
		(net "DELTA_L_85_10INCH_TOP_DN")
	)
	(segment
		(start 265.968734 -2.198624)
		(end 265.819382 -2.30378)
		(width 0.12954)
		(layer "F.Cu")
		(net "DELTA_L_85_10INCH_TOP_DN")
	)
	(segment
		(start 295.24706 0.164084)
		(end 294.427656 -0.408432)
		(width 0.12954)
		(layer "F.Cu")
		(net "DELTA_L_85_10INCH_TOP_DN")
	)
	(segment
		(start 240.895124 1.935226)
		(end 240.63706 2.303526)
		(width 0.12954)
		(layer "F.Cu")
		(net "DELTA_L_85_10INCH_TOP_DN")
	)
	(segment
		(start 277.87981 -2.30505)
		(end 276.503892 -2.061464)
		(width 0.12954)
		(layer "F.Cu")
		(net "DELTA_L_85_10INCH_TOP_DN")
	)
	(segment
		(start 258.72567 2.314956)
		(end 257.924554 -2.21996)
		(width 0.12954)
		(layer "F.Cu")
		(net "DELTA_L_85_10INCH_TOP_DN")
	)
	(segment
		(start 252.957076 1.941068)
		(end 252.699012 2.309622)
		(width 0.12954)
		(layer "F.Cu")
		(net "DELTA_L_85_10INCH_TOP_DN")
	)
	(segment
		(start 281.899106 -2.310384)
		(end 280.523188 -2.066798)
		(width 0.12954)
		(layer "F.Cu")
		(net "DELTA_L_85_10INCH_TOP_DN")
	)
	(segment
		(start 244.238018 -1.896872)
		(end 244.915944 1.938782)
		(width 0.12954)
		(layer "F.Cu")
		(net "DELTA_L_85_10INCH_TOP_DN")
	)
	(segment
		(start 280.418032 -1.916938)
		(end 281.100276 1.942592)
		(width 0.12954)
		(layer "F.Cu")
		(net "DELTA_L_85_10INCH_TOP_DN")
	)
	(segment
		(start 224.55378 2.293112)
		(end 222.912432 2.58318)
		(width 0.12954)
		(layer "F.Cu")
		(net "DELTA_L_85_10INCH_TOP_DN")
	)
	(segment
		(start 259.09397 2.572766)
		(end 258.72567 2.314956)
		(width 0.12954)
		(layer "F.Cu")
		(net "DELTA_L_85_10INCH_TOP_DN")
	)
	(segment
		(start 238.627158 2.335784)
		(end 237.818168 -2.243074)
		(width 0.12954)
		(layer "F.Cu")
		(net "DELTA_L_85_10INCH_TOP_DN")
	)
	(segment
		(start 240.319814 -2.063496)
		(end 240.214658 -1.91389)
		(width 0.12954)
		(layer "F.Cu")
		(net "DELTA_L_85_10INCH_TOP_DN")
	)
	(segment
		(start 248.358914 -2.074926)
		(end 248.253758 -1.92532)
		(width 0.12954)
		(layer "F.Cu")
		(net "DELTA_L_85_10INCH_TOP_DN")
	)
	(segment
		(start 250.689364 2.34188)
		(end 249.884946 -2.213356)
		(width 0.12954)
		(layer "F.Cu")
		(net "DELTA_L_85_10INCH_TOP_DN")
	)
	(segment
		(start 283.223462 2.614168)
		(end 282.855162 2.356358)
		(width 0.12954)
		(layer "F.Cu")
		(net "DELTA_L_85_10INCH_TOP_DN")
	)
	(segment
		(start 276.503892 -2.061464)
		(end 276.398736 -1.911858)
		(width 0.12954)
		(layer "F.Cu")
		(net "DELTA_L_85_10INCH_TOP_DN")
	)
	(segment
		(start 274.814284 2.354834)
		(end 274.010628 -2.19329)
		(width 0.12954)
		(layer "F.Cu")
		(net "DELTA_L_85_10INCH_TOP_DN")
	)
	(segment
		(start 268.78026 2.306066)
		(end 267.138658 2.596134)
		(width 0.12954)
		(layer "F.Cu")
		(net "DELTA_L_85_10INCH_TOP_DN")
	)
	(segment
		(start 253.906782 -2.202688)
		(end 253.757176 -2.307844)
		(width 0.12954)
		(layer "F.Cu")
		(net "DELTA_L_85_10INCH_TOP_DN")
	)
	(segment
		(start 292.475666 -1.938274)
		(end 293.163498 1.9558)
		(width 0.12954)
		(layer "F.Cu")
		(net "DELTA_L_85_10INCH_TOP_DN")
	)
	(segment
		(start 237.668562 -2.34823)
		(end 236.292644 -2.104644)
		(width 0.12954)
		(layer "F.Cu")
		(net "DELTA_L_85_10INCH_TOP_DN")
	)
	(segment
		(start 282.048966 -2.205228)
		(end 281.899106 -2.310384)
		(width 0.12954)
		(layer "F.Cu")
		(net "DELTA_L_85_10INCH_TOP_DN")
	)
	(segment
		(start 224.130108 -1.932178)
		(end 224.81159 1.924304)
		(width 0.12954)
		(layer "F.Cu")
		(net "DELTA_L_85_10INCH_TOP_DN")
	)
	(segment
		(start 264.338054 -1.910334)
		(end 265.015472 1.92405)
		(width 0.12954)
		(layer "F.Cu")
		(net "DELTA_L_85_10INCH_TOP_DN")
	)
	(segment
		(start 240.63706 2.303526)
		(end 238.995712 2.593594)
		(width 0.12954)
		(layer "F.Cu")
		(net "DELTA_L_85_10INCH_TOP_DN")
	)
	(segment
		(start 289.14217 1.951228)
		(end 288.883852 2.32029)
		(width 0.12954)
		(layer "F.Cu")
		(net "DELTA_L_85_10INCH_TOP_DN")
	)
	(segment
		(start 251.057664 2.59969)
		(end 250.689364 2.34188)
		(width 0.12954)
		(layer "F.Cu")
		(net "DELTA_L_85_10INCH_TOP_DN")
	)
	(segment
		(start 282.855162 2.356358)
		(end 282.048966 -2.205228)
		(width 0.12954)
		(layer "F.Cu")
		(net "DELTA_L_85_10INCH_TOP_DN")
	)
	(segment
		(start 236.614716 2.291842)
		(end 234.97286 2.58191)
		(width 0.12954)
		(layer "F.Cu")
		(net "DELTA_L_85_10INCH_TOP_DN")
	)
	(segment
		(start 260.735572 2.282698)
		(end 259.09397 2.572766)
		(width 0.12954)
		(layer "F.Cu")
		(net "DELTA_L_85_10INCH_TOP_DN")
	)
	(segment
		(start 264.44321 -2.060194)
		(end 264.338054 -1.910334)
		(width 0.12954)
		(layer "F.Cu")
		(net "DELTA_L_85_10INCH_TOP_DN")
	)
	(segment
		(start 228.576378 2.306574)
		(end 226.934776 2.596642)
		(width 0.12954)
		(layer "F.Cu")
		(net "DELTA_L_85_10INCH_TOP_DN")
	)
	(segment
		(start 256.972816 1.913636)
		(end 256.714752 2.28219)
		(width 0.12954)
		(layer "F.Cu")
		(net "DELTA_L_85_10INCH_TOP_DN")
	)
	(segment
		(start 290.89604 2.356866)
		(end 290.091114 -2.198878)
		(width 0.12954)
		(layer "F.Cu")
		(net "DELTA_L_85_10INCH_TOP_DN")
	)
	(segment
		(start 274.010628 -2.19329)
		(end 273.860768 -2.298446)
		(width 0.12954)
		(layer "F.Cu")
		(net "DELTA_L_85_10INCH_TOP_DN")
	)
	(segment
		(start 260.315964 -1.919732)
		(end 260.993382 1.91389)
		(width 0.12954)
		(layer "F.Cu")
		(net "DELTA_L_85_10INCH_TOP_DN")
	)
	(segment
		(start 252.381258 -2.064258)
		(end 252.276102 -1.914144)
		(width 0.12954)
		(layer "F.Cu")
		(net "DELTA_L_85_10INCH_TOP_DN")
	)
	(segment
		(start 268.35735 -1.914906)
		(end 269.03807 1.937258)
		(width 0.12954)
		(layer "F.Cu")
		(net "DELTA_L_85_10INCH_TOP_DN")
	)
	(segment
		(start 281.100276 1.942592)
		(end 280.842466 2.3114)
		(width 0.12954)
		(layer "F.Cu")
		(net "DELTA_L_85_10INCH_TOP_DN")
	)
	(segment
		(start 213.297008 2.292858)
		(end 213.94928 2.110994)
		(width 0.12954)
		(layer "B.Cu")
		(net "DELTA_L_85_10INCH_IN6_DP")
	)
	(segment
		(start 299.712888 2.292858)
		(end 299.060616 2.110994)
		(width 0.12954)
		(layer "B.Cu")
		(net "DELTA_L_85_10INCH_IN6_DP")
	)
	(segment
		(start 242.098068 4.766056)
		(end 241.93373 4.650994)
		(width 0.14224)
		(layer "In15.Cu")
		(net "DELTA_L_85_10INCH_IN6_DP")
	)
	(segment
		(start 240.797334 -0.019304)
		(end 239.203738 0.262128)
		(width 0.14224)
		(layer "In15.Cu")
		(net "DELTA_L_85_10INCH_IN6_DP")
	)
	(segment
		(start 283.084778 4.492752)
		(end 281.72029 4.733798)
		(width 0.14224)
		(layer "In15.Cu")
		(net "DELTA_L_85_10INCH_IN6_DP")
	)
	(segment
		(start 220.976952 -0.056134)
		(end 219.383356 0.225298)
		(width 0.14224)
		(layer "In15.Cu")
		(net "DELTA_L_85_10INCH_IN6_DP")
	)
	(segment
		(start 237.193074 0.242316)
		(end 236.836966 -0.007112)
		(width 0.14224)
		(layer "In15.Cu")
		(net "DELTA_L_85_10INCH_IN6_DP")
	)
	(segment
		(start 280.773124 0.18542)
		(end 280.41727 -0.064008)
		(width 0.14224)
		(layer "In15.Cu")
		(net "DELTA_L_85_10INCH_IN6_DP")
	)
	(segment
		(start 243.462556 4.52501)
		(end 242.098068 4.766056)
		(width 0.14224)
		(layer "In15.Cu")
		(net "DELTA_L_85_10INCH_IN6_DP")
	)
	(segment
		(start 270.646144 0.5588)
		(end 271.311624 4.329176)
		(width 0.14224)
		(layer "In15.Cu")
		(net "DELTA_L_85_10INCH_IN6_DP")
	)
	(segment
		(start 262.719566 0.553466)
		(end 263.388602 4.343908)
		(width 0.14224)
		(layer "In15.Cu")
		(net "DELTA_L_85_10INCH_IN6_DP")
	)
	(segment
		(start 269.832074 4.734814)
		(end 269.667736 4.620006)
		(width 0.14224)
		(layer "In15.Cu")
		(net "DELTA_L_85_10INCH_IN6_DP")
	)
	(segment
		(start 230.214424 4.791202)
		(end 230.050086 4.67614)
		(width 0.14224)
		(layer "In15.Cu")
		(net "DELTA_L_85_10INCH_IN6_DP")
	)
	(segment
		(start 266.683744 0.56134)
		(end 267.353034 4.353306)
		(width 0.14224)
		(layer "In15.Cu")
		(net "DELTA_L_85_10INCH_IN6_DP")
	)
	(segment
		(start 284.398466 0.040386)
		(end 282.80487 0.321818)
		(width 0.14224)
		(layer "In15.Cu")
		(net "DELTA_L_85_10INCH_IN6_DP")
	)
	(segment
		(start 294.893238 3.224276)
		(end 295.078404 4.273042)
		(width 0.14224)
		(layer "In15.Cu")
		(net "DELTA_L_85_10INCH_IN6_DP")
	)
	(segment
		(start 259.011928 0.229362)
		(end 258.7625 0.58547)
		(width 0.14224)
		(layer "In15.Cu")
		(net "DELTA_L_85_10INCH_IN6_DP")
	)
	(segment
		(start 273.802856 4.779518)
		(end 273.638518 4.664456)
		(width 0.14224)
		(layer "In15.Cu")
		(net "DELTA_L_85_10INCH_IN6_DP")
	)
	(segment
		(start 275.282406 4.374134)
		(end 275.167344 4.538472)
		(width 0.14224)
		(layer "In15.Cu")
		(net "DELTA_L_85_10INCH_IN6_DP")
	)
	(segment
		(start 253.052834 0.292608)
		(end 252.696726 0.04318)
		(width 0.14224)
		(layer "In15.Cu")
		(net "DELTA_L_85_10INCH_IN6_DP")
	)
	(segment
		(start 278.574246 0.573786)
		(end 279.241504 4.35356)
		(width 0.14224)
		(layer "In15.Cu")
		(net "DELTA_L_85_10INCH_IN6_DP")
	)
	(segment
		(start 290.471606 0.624332)
		(end 291.137594 4.397756)
		(width 0.14224)
		(layer "In15.Cu")
		(net "DELTA_L_85_10INCH_IN6_DP")
	)
	(segment
		(start 292.670484 0.23622)
		(end 292.31463 -0.013208)
		(width 0.14224)
		(layer "In15.Cu")
		(net "DELTA_L_85_10INCH_IN6_DP")
	)
	(segment
		(start 258.7625 0.58547)
		(end 259.423662 4.331462)
		(width 0.14224)
		(layer "In15.Cu")
		(net "DELTA_L_85_10INCH_IN6_DP")
	)
	(segment
		(start 247.543574 4.37769)
		(end 247.428512 4.542028)
		(width 0.14224)
		(layer "In15.Cu")
		(net "DELTA_L_85_10INCH_IN6_DP")
	)
	(segment
		(start 289.493706 4.688078)
		(end 288.70529 0.221996)
		(width 0.14224)
		(layer "In15.Cu")
		(net "DELTA_L_85_10INCH_IN6_DP")
	)
	(segment
		(start 264.56259 -0.084074)
		(end 262.968994 0.197358)
		(width 0.14224)
		(layer "In15.Cu")
		(net "DELTA_L_85_10INCH_IN6_DP")
	)
	(segment
		(start 265.873484 4.75869)
		(end 265.709146 4.643628)
		(width 0.14224)
		(layer "In15.Cu")
		(net "DELTA_L_85_10INCH_IN6_DP")
	)
	(segment
		(start 232.876852 0.009144)
		(end 231.283256 0.290576)
		(width 0.14224)
		(layer "In15.Cu")
		(net "DELTA_L_85_10INCH_IN6_DP")
	)
	(segment
		(start 248.720864 -0.030734)
		(end 247.127268 0.250698)
		(width 0.14224)
		(layer "In15.Cu")
		(net "DELTA_L_85_10INCH_IN6_DP")
	)
	(segment
		(start 287.169352 4.367276)
		(end 287.05429 4.531614)
		(width 0.14224)
		(layer "In15.Cu")
		(net "DELTA_L_85_10INCH_IN6_DP")
	)
	(segment
		(start 250.853702 0.68072)
		(end 251.499116 4.337558)
		(width 0.14224)
		(layer "In15.Cu")
		(net "DELTA_L_85_10INCH_IN6_DP")
	)
	(segment
		(start 255.056894 0.273304)
		(end 254.807466 0.629412)
		(width 0.14224)
		(layer "In15.Cu")
		(net "DELTA_L_85_10INCH_IN6_DP")
	)
	(segment
		(start 251.10313 0.324612)
		(end 250.853702 0.68072)
		(width 0.14224)
		(layer "In15.Cu")
		(net "DELTA_L_85_10INCH_IN6_DP")
	)
	(segment
		(start 223.651572 4.539742)
		(end 222.287084 4.780788)
		(width 0.14224)
		(layer "In15.Cu")
		(net "DELTA_L_85_10INCH_IN6_DP")
	)
	(segment
		(start 218.325446 4.788408)
		(end 218.161108 4.673346)
		(width 0.14224)
		(layer "In15.Cu")
		(net "DELTA_L_85_10INCH_IN6_DP")
	)
	(segment
		(start 284.754574 0.289814)
		(end 284.398466 0.040386)
		(width 0.14224)
		(layer "In15.Cu")
		(net "DELTA_L_85_10INCH_IN6_DP")
	)
	(segment
		(start 294.894254 4.536186)
		(end 293.599362 4.764786)
		(width 0.14224)
		(layer "In15.Cu")
		(net "DELTA_L_85_10INCH_IN6_DP")
	)
	(segment
		(start 235.5342 4.508246)
		(end 234.169712 4.749292)
		(width 0.14224)
		(layer "In15.Cu")
		(net "DELTA_L_85_10INCH_IN6_DP")
	)
	(segment
		(start 238.95431 0.618236)
		(end 239.61852 4.381754)
		(width 0.14224)
		(layer "In15.Cu")
		(net "DELTA_L_85_10INCH_IN6_DP")
	)
	(segment
		(start 278.823674 0.217424)
		(end 278.574246 0.573786)
		(width 0.14224)
		(layer "In15.Cu")
		(net "DELTA_L_85_10INCH_IN6_DP")
	)
	(segment
		(start 221.333314 0.193294)
		(end 220.976952 -0.056134)
		(width 0.14224)
		(layer "In15.Cu")
		(net "DELTA_L_85_10INCH_IN6_DP")
	)
	(segment
		(start 227.728272 4.369562)
		(end 227.61321 4.5339)
		(width 0.14224)
		(layer "In15.Cu")
		(net "DELTA_L_85_10INCH_IN6_DP")
	)
	(segment
		(start 257.006598 0.2413)
		(end 256.65049 -0.008128)
		(width 0.14224)
		(layer "In15.Cu")
		(net "DELTA_L_85_10INCH_IN6_DP")
	)
	(segment
		(start 219.689934 4.547362)
		(end 218.325446 4.788408)
		(width 0.14224)
		(layer "In15.Cu")
		(net "DELTA_L_85_10INCH_IN6_DP")
	)
	(segment
		(start 274.613624 0.585724)
		(end 275.282406 4.374134)
		(width 0.14224)
		(layer "In15.Cu")
		(net "DELTA_L_85_10INCH_IN6_DP")
	)
	(segment
		(start 276.456648 -0.051816)
		(end 274.863052 0.229616)
		(width 0.14224)
		(layer "In15.Cu")
		(net "DELTA_L_85_10INCH_IN6_DP")
	)
	(segment
		(start 244.757956 -0.031496)
		(end 243.16436 0.249936)
		(width 0.14224)
		(layer "In15.Cu")
		(net "DELTA_L_85_10INCH_IN6_DP")
	)
	(segment
		(start 246.87784 0.606806)
		(end 247.543574 4.37769)
		(width 0.14224)
		(layer "In15.Cu")
		(net "DELTA_L_85_10INCH_IN6_DP")
	)
	(segment
		(start 286.75584 0.254)
		(end 286.506412 0.610362)
		(width 0.14224)
		(layer "In15.Cu")
		(net "DELTA_L_85_10INCH_IN6_DP")
	)
	(segment
		(start 214.24011 2.401824)
		(end 213.94928 2.110994)
		(width 0.14224)
		(layer "In15.Cu")
		(net "DELTA_L_85_10INCH_IN6_DP")
	)
	(segment
		(start 296.314876 2.401824)
		(end 295.360344 2.56159)
		(width 0.14224)
		(layer "In15.Cu")
		(net "DELTA_L_85_10INCH_IN6_DP")
	)
	(segment
		(start 289.658044 4.80314)
		(end 289.493706 4.688078)
		(width 0.14224)
		(layer "In15.Cu")
		(net "DELTA_L_85_10INCH_IN6_DP")
	)
	(segment
		(start 283.19984 4.328414)
		(end 283.084778 4.492752)
		(width 0.14224)
		(layer "In15.Cu")
		(net "DELTA_L_85_10INCH_IN6_DP")
	)
	(segment
		(start 291.137594 4.397756)
		(end 291.022532 4.562094)
		(width 0.14224)
		(layer "In15.Cu")
		(net "DELTA_L_85_10INCH_IN6_DP")
	)
	(segment
		(start 279.241504 4.35356)
		(end 279.126442 4.517644)
		(width 0.14224)
		(layer "In15.Cu")
		(net "DELTA_L_85_10INCH_IN6_DP")
	)
	(segment
		(start 234.169712 4.749292)
		(end 234.005374 4.63423)
		(width 0.14224)
		(layer "In15.Cu")
		(net "DELTA_L_85_10INCH_IN6_DP")
	)
	(segment
		(start 237.974886 4.671822)
		(end 237.193074 0.242316)
		(width 0.14224)
		(layer "In15.Cu")
		(net "DELTA_L_85_10INCH_IN6_DP")
	)
	(segment
		(start 255.35509 4.548632)
		(end 253.990602 4.789678)
		(width 0.14224)
		(layer "In15.Cu")
		(net "DELTA_L_85_10INCH_IN6_DP")
	)
	(segment
		(start 234.993942 0.630428)
		(end 235.649262 4.343908)
		(width 0.14224)
		(layer "In15.Cu")
		(net "DELTA_L_85_10INCH_IN6_DP")
	)
	(segment
		(start 267.237972 4.517644)
		(end 265.873484 4.75869)
		(width 0.14224)
		(layer "In15.Cu")
		(net "DELTA_L_85_10INCH_IN6_DP")
	)
	(segment
		(start 273.638518 4.664456)
		(end 272.84553 0.171196)
		(width 0.14224)
		(layer "In15.Cu")
		(net "DELTA_L_85_10INCH_IN6_DP")
	)
	(segment
		(start 226.248722 4.774946)
		(end 226.084384 4.659884)
		(width 0.14224)
		(layer "In15.Cu")
		(net "DELTA_L_85_10INCH_IN6_DP")
	)
	(segment
		(start 254.807466 0.629412)
		(end 255.470152 4.384294)
		(width 0.14224)
		(layer "In15.Cu")
		(net "DELTA_L_85_10INCH_IN6_DP")
	)
	(segment
		(start 295.078404 4.273042)
		(end 294.894254 4.536186)
		(width 0.14224)
		(layer "In15.Cu")
		(net "DELTA_L_85_10INCH_IN6_DP")
	)
	(segment
		(start 247.428512 4.542028)
		(end 246.064024 4.783074)
		(width 0.14224)
		(layer "In15.Cu")
		(net "DELTA_L_85_10INCH_IN6_DP")
	)
	(segment
		(start 276.812756 0.197612)
		(end 276.456648 -0.051816)
		(width 0.14224)
		(layer "In15.Cu")
		(net "DELTA_L_85_10INCH_IN6_DP")
	)
	(segment
		(start 272.84553 0.171196)
		(end 272.489168 -0.078232)
		(width 0.14224)
		(layer "In15.Cu")
		(net "DELTA_L_85_10INCH_IN6_DP")
	)
	(segment
		(start 263.27354 4.508246)
		(end 261.909052 4.749292)
		(width 0.14224)
		(layer "In15.Cu")
		(net "DELTA_L_85_10INCH_IN6_DP")
	)
	(segment
		(start 264.918698 0.165354)
		(end 264.56259 -0.084074)
		(width 0.14224)
		(layer "In15.Cu")
		(net "DELTA_L_85_10INCH_IN6_DP")
	)
	(segment
		(start 245.899686 4.668012)
		(end 245.114064 0.217932)
		(width 0.14224)
		(layer "In15.Cu")
		(net "DELTA_L_85_10INCH_IN6_DP")
	)
	(segment
		(start 225.300032 0.216408)
		(end 224.943924 -0.03302)
		(width 0.14224)
		(layer "In15.Cu")
		(net "DELTA_L_85_10INCH_IN6_DP")
	)
	(segment
		(start 227.61321 4.5339)
		(end 226.248722 4.774946)
		(width 0.14224)
		(layer "In15.Cu")
		(net "DELTA_L_85_10INCH_IN6_DP")
	)
	(segment
		(start 251.499116 4.337558)
		(end 251.384054 4.50215)
		(width 0.14224)
		(layer "In15.Cu")
		(net "DELTA_L_85_10INCH_IN6_DP")
	)
	(segment
		(start 275.167344 4.538472)
		(end 273.802856 4.779518)
		(width 0.14224)
		(layer "In15.Cu")
		(net "DELTA_L_85_10INCH_IN6_DP")
	)
	(segment
		(start 265.709146 4.643628)
		(end 264.918698 0.165354)
		(width 0.14224)
		(layer "In15.Cu")
		(net "DELTA_L_85_10INCH_IN6_DP")
	)
	(segment
		(start 235.24337 0.27432)
		(end 234.993942 0.630428)
		(width 0.14224)
		(layer "In15.Cu")
		(net "DELTA_L_85_10INCH_IN6_DP")
	)
	(segment
		(start 253.990602 4.789678)
		(end 253.826264 4.674616)
		(width 0.14224)
		(layer "In15.Cu")
		(net "DELTA_L_85_10INCH_IN6_DP")
	)
	(segment
		(start 222.122746 4.665726)
		(end 221.333314 0.193294)
		(width 0.14224)
		(layer "In15.Cu")
		(net "DELTA_L_85_10INCH_IN6_DP")
	)
	(segment
		(start 252.696726 0.04318)
		(end 251.10313 0.324612)
		(width 0.14224)
		(layer "In15.Cu")
		(net "DELTA_L_85_10INCH_IN6_DP")
	)
	(segment
		(start 270.895572 0.2032)
		(end 270.646144 0.5588)
		(width 0.14224)
		(layer "In15.Cu")
		(net "DELTA_L_85_10INCH_IN6_DP")
	)
	(segment
		(start 217.84818 2.900172)
		(end 217.135456 2.401824)
		(width 0.14224)
		(layer "In15.Cu")
		(net "DELTA_L_85_10INCH_IN6_DP")
	)
	(segment
		(start 286.506412 0.610362)
		(end 287.169352 4.367276)
		(width 0.14224)
		(layer "In15.Cu")
		(net "DELTA_L_85_10INCH_IN6_DP")
	)
	(segment
		(start 223.350328 0.248412)
		(end 223.1009 0.60452)
		(width 0.14224)
		(layer "In15.Cu")
		(net "DELTA_L_85_10INCH_IN6_DP")
	)
	(segment
		(start 242.914932 0.606044)
		(end 243.577618 4.360672)
		(width 0.14224)
		(layer "In15.Cu")
		(net "DELTA_L_85_10INCH_IN6_DP")
	)
	(segment
		(start 267.353034 4.353306)
		(end 267.237972 4.517644)
		(width 0.14224)
		(layer "In15.Cu")
		(net "DELTA_L_85_10INCH_IN6_DP")
	)
	(segment
		(start 266.933172 0.205232)
		(end 266.683744 0.56134)
		(width 0.14224)
		(layer "In15.Cu")
		(net "DELTA_L_85_10INCH_IN6_DP")
	)
	(segment
		(start 219.383356 0.225298)
		(end 219.133928 0.580898)
		(width 0.14224)
		(layer "In15.Cu")
		(net "DELTA_L_85_10INCH_IN6_DP")
	)
	(segment
		(start 279.126442 4.517644)
		(end 277.761954 4.75869)
		(width 0.14224)
		(layer "In15.Cu")
		(net "DELTA_L_85_10INCH_IN6_DP")
	)
	(segment
		(start 218.161108 4.673346)
		(end 217.84818 2.900172)
		(width 0.14224)
		(layer "In15.Cu")
		(net "DELTA_L_85_10INCH_IN6_DP")
	)
	(segment
		(start 268.526768 -0.0762)
		(end 266.933172 0.205232)
		(width 0.14224)
		(layer "In15.Cu")
		(net "DELTA_L_85_10INCH_IN6_DP")
	)
	(segment
		(start 239.203738 0.262128)
		(end 238.95431 0.618236)
		(width 0.14224)
		(layer "In15.Cu")
		(net "DELTA_L_85_10INCH_IN6_DP")
	)
	(segment
		(start 231.033828 0.646684)
		(end 231.693974 4.386072)
		(width 0.14224)
		(layer "In15.Cu")
		(net "DELTA_L_85_10INCH_IN6_DP")
	)
	(segment
		(start 227.315522 0.262128)
		(end 227.066094 0.618236)
		(width 0.14224)
		(layer "In15.Cu")
		(net "DELTA_L_85_10INCH_IN6_DP")
	)
	(segment
		(start 246.064024 4.783074)
		(end 245.899686 4.668012)
		(width 0.14224)
		(layer "In15.Cu")
		(net "DELTA_L_85_10INCH_IN6_DP")
	)
	(segment
		(start 222.287084 4.780788)
		(end 222.122746 4.665726)
		(width 0.14224)
		(layer "In15.Cu")
		(net "DELTA_L_85_10INCH_IN6_DP")
	)
	(segment
		(start 224.943924 -0.03302)
		(end 223.350328 0.248412)
		(width 0.14224)
		(layer "In15.Cu")
		(net "DELTA_L_85_10INCH_IN6_DP")
	)
	(segment
		(start 262.968994 0.197358)
		(end 262.719566 0.553466)
		(width 0.14224)
		(layer "In15.Cu")
		(net "DELTA_L_85_10INCH_IN6_DP")
	)
	(segment
		(start 249.076972 0.218694)
		(end 248.720864 -0.030734)
		(width 0.14224)
		(layer "In15.Cu")
		(net "DELTA_L_85_10INCH_IN6_DP")
	)
	(segment
		(start 277.761954 4.75869)
		(end 277.597616 4.643628)
		(width 0.14224)
		(layer "In15.Cu")
		(net "DELTA_L_85_10INCH_IN6_DP")
	)
	(segment
		(start 234.005374 4.63423)
		(end 233.23296 0.258572)
		(width 0.14224)
		(layer "In15.Cu")
		(net "DELTA_L_85_10INCH_IN6_DP")
	)
	(segment
		(start 260.961632 0.197358)
		(end 260.605524 -0.05207)
		(width 0.14224)
		(layer "In15.Cu")
		(net "DELTA_L_85_10INCH_IN6_DP")
	)
	(segment
		(start 295.360344 2.56159)
		(end 294.893238 3.224276)
		(width 0.14224)
		(layer "In15.Cu")
		(net "DELTA_L_85_10INCH_IN6_DP")
	)
	(segment
		(start 250.019566 4.743196)
		(end 249.855228 4.628134)
		(width 0.14224)
		(layer "In15.Cu")
		(net "DELTA_L_85_10INCH_IN6_DP")
	)
	(segment
		(start 228.909118 -0.019304)
		(end 227.315522 0.262128)
		(width 0.14224)
		(layer "In15.Cu")
		(net "DELTA_L_85_10INCH_IN6_DP")
	)
	(segment
		(start 256.65049 -0.008128)
		(end 255.056894 0.273304)
		(width 0.14224)
		(layer "In15.Cu")
		(net "DELTA_L_85_10INCH_IN6_DP")
	)
	(segment
		(start 217.135456 2.401824)
		(end 214.24011 2.401824)
		(width 0.14224)
		(layer "In15.Cu")
		(net "DELTA_L_85_10INCH_IN6_DP")
	)
	(segment
		(start 227.066094 0.618236)
		(end 227.728272 4.369562)
		(width 0.14224)
		(layer "In15.Cu")
		(net "DELTA_L_85_10INCH_IN6_DP")
	)
	(segment
		(start 247.127268 0.250698)
		(end 246.87784 0.606806)
		(width 0.14224)
		(layer "In15.Cu")
		(net "DELTA_L_85_10INCH_IN6_DP")
	)
	(segment
		(start 281.72029 4.733798)
		(end 281.555952 4.618736)
		(width 0.14224)
		(layer "In15.Cu")
		(net "DELTA_L_85_10INCH_IN6_DP")
	)
	(segment
		(start 257.779774 4.621784)
		(end 257.006598 0.2413)
		(width 0.14224)
		(layer "In15.Cu")
		(net "DELTA_L_85_10INCH_IN6_DP")
	)
	(segment
		(start 268.882876 0.173228)
		(end 268.526768 -0.0762)
		(width 0.14224)
		(layer "In15.Cu")
		(net "DELTA_L_85_10INCH_IN6_DP")
	)
	(segment
		(start 299.060616 2.110994)
		(end 298.769786 2.401824)
		(width 0.14224)
		(layer "In15.Cu")
		(net "DELTA_L_85_10INCH_IN6_DP")
	)
	(segment
		(start 263.388602 4.343908)
		(end 263.27354 4.508246)
		(width 0.14224)
		(layer "In15.Cu")
		(net "DELTA_L_85_10INCH_IN6_DP")
	)
	(segment
		(start 288.34969 -0.027432)
		(end 286.75584 0.254)
		(width 0.14224)
		(layer "In15.Cu")
		(net "DELTA_L_85_10INCH_IN6_DP")
	)
	(segment
		(start 274.863052 0.229616)
		(end 274.613624 0.585724)
		(width 0.14224)
		(layer "In15.Cu")
		(net "DELTA_L_85_10INCH_IN6_DP")
	)
	(segment
		(start 231.578912 4.550156)
		(end 230.214424 4.791202)
		(width 0.14224)
		(layer "In15.Cu")
		(net "DELTA_L_85_10INCH_IN6_DP")
	)
	(segment
		(start 230.050086 4.67614)
		(end 229.265226 0.230124)
		(width 0.14224)
		(layer "In15.Cu")
		(net "DELTA_L_85_10INCH_IN6_DP")
	)
	(segment
		(start 269.667736 4.620006)
		(end 268.882876 0.173228)
		(width 0.14224)
		(layer "In15.Cu")
		(net "DELTA_L_85_10INCH_IN6_DP")
	)
	(segment
		(start 249.855228 4.628134)
		(end 249.076972 0.218694)
		(width 0.14224)
		(layer "In15.Cu")
		(net "DELTA_L_85_10INCH_IN6_DP")
	)
	(segment
		(start 243.16436 0.249936)
		(end 242.914932 0.606044)
		(width 0.14224)
		(layer "In15.Cu")
		(net "DELTA_L_85_10INCH_IN6_DP")
	)
	(segment
		(start 287.05429 4.531614)
		(end 285.689802 4.77266)
		(width 0.14224)
		(layer "In15.Cu")
		(net "DELTA_L_85_10INCH_IN6_DP")
	)
	(segment
		(start 277.597616 4.643628)
		(end 276.812756 0.197612)
		(width 0.14224)
		(layer "In15.Cu")
		(net "DELTA_L_85_10INCH_IN6_DP")
	)
	(segment
		(start 235.649262 4.343908)
		(end 235.5342 4.508246)
		(width 0.14224)
		(layer "In15.Cu")
		(net "DELTA_L_85_10INCH_IN6_DP")
	)
	(segment
		(start 259.3086 4.4958)
		(end 257.944112 4.736846)
		(width 0.14224)
		(layer "In15.Cu")
		(net "DELTA_L_85_10INCH_IN6_DP")
	)
	(segment
		(start 260.605524 -0.05207)
		(end 259.011928 0.229362)
		(width 0.14224)
		(layer "In15.Cu")
		(net "DELTA_L_85_10INCH_IN6_DP")
	)
	(segment
		(start 285.689802 4.77266)
		(end 285.525464 4.657598)
		(width 0.14224)
		(layer "In15.Cu")
		(net "DELTA_L_85_10INCH_IN6_DP")
	)
	(segment
		(start 231.693974 4.386072)
		(end 231.578912 4.550156)
		(width 0.14224)
		(layer "In15.Cu")
		(net "DELTA_L_85_10INCH_IN6_DP")
	)
	(segment
		(start 236.836966 -0.007112)
		(end 235.24337 0.27432)
		(width 0.14224)
		(layer "In15.Cu")
		(net "DELTA_L_85_10INCH_IN6_DP")
	)
	(segment
		(start 292.31463 -0.013208)
		(end 290.721034 0.268224)
		(width 0.14224)
		(layer "In15.Cu")
		(net "DELTA_L_85_10INCH_IN6_DP")
	)
	(segment
		(start 251.384054 4.50215)
		(end 250.019566 4.743196)
		(width 0.14224)
		(layer "In15.Cu")
		(net "DELTA_L_85_10INCH_IN6_DP")
	)
	(segment
		(start 233.23296 0.258572)
		(end 232.876852 0.009144)
		(width 0.14224)
		(layer "In15.Cu")
		(net "DELTA_L_85_10INCH_IN6_DP")
	)
	(segment
		(start 291.022532 4.562094)
		(end 289.658044 4.80314)
		(width 0.14224)
		(layer "In15.Cu")
		(net "DELTA_L_85_10INCH_IN6_DP")
	)
	(segment
		(start 229.265226 0.230124)
		(end 228.909118 -0.019304)
		(width 0.14224)
		(layer "In15.Cu")
		(net "DELTA_L_85_10INCH_IN6_DP")
	)
	(segment
		(start 290.721034 0.268224)
		(end 290.471606 0.624332)
		(width 0.14224)
		(layer "In15.Cu")
		(net "DELTA_L_85_10INCH_IN6_DP")
	)
	(segment
		(start 245.114064 0.217932)
		(end 244.757956 -0.031496)
		(width 0.14224)
		(layer "In15.Cu")
		(net "DELTA_L_85_10INCH_IN6_DP")
	)
	(segment
		(start 239.503712 4.545838)
		(end 238.139224 4.786884)
		(width 0.14224)
		(layer "In15.Cu")
		(net "DELTA_L_85_10INCH_IN6_DP")
	)
	(segment
		(start 281.555952 4.618736)
		(end 280.773124 0.18542)
		(width 0.14224)
		(layer "In15.Cu")
		(net "DELTA_L_85_10INCH_IN6_DP")
	)
	(segment
		(start 285.525464 4.657598)
		(end 284.754574 0.289814)
		(width 0.14224)
		(layer "In15.Cu")
		(net "DELTA_L_85_10INCH_IN6_DP")
	)
	(segment
		(start 255.470152 4.384294)
		(end 255.35509 4.548632)
		(width 0.14224)
		(layer "In15.Cu")
		(net "DELTA_L_85_10INCH_IN6_DP")
	)
	(segment
		(start 253.826264 4.674616)
		(end 253.052834 0.292608)
		(width 0.14224)
		(layer "In15.Cu")
		(net "DELTA_L_85_10INCH_IN6_DP")
	)
	(segment
		(start 257.944112 4.736846)
		(end 257.779774 4.621784)
		(width 0.14224)
		(layer "In15.Cu")
		(net "DELTA_L_85_10INCH_IN6_DP")
	)
	(segment
		(start 288.70529 0.221996)
		(end 288.34969 -0.027432)
		(width 0.14224)
		(layer "In15.Cu")
		(net "DELTA_L_85_10INCH_IN6_DP")
	)
	(segment
		(start 272.489168 -0.078232)
		(end 270.895572 0.2032)
		(width 0.14224)
		(layer "In15.Cu")
		(net "DELTA_L_85_10INCH_IN6_DP")
	)
	(segment
		(start 282.80487 0.321818)
		(end 282.555442 0.677926)
		(width 0.14224)
		(layer "In15.Cu")
		(net "DELTA_L_85_10INCH_IN6_DP")
	)
	(segment
		(start 243.577618 4.360672)
		(end 243.462556 4.52501)
		(width 0.14224)
		(layer "In15.Cu")
		(net "DELTA_L_85_10INCH_IN6_DP")
	)
	(segment
		(start 223.766634 4.375404)
		(end 223.651572 4.539742)
		(width 0.14224)
		(layer "In15.Cu")
		(net "DELTA_L_85_10INCH_IN6_DP")
	)
	(segment
		(start 226.084384 4.659884)
		(end 225.300032 0.216408)
		(width 0.14224)
		(layer "In15.Cu")
		(net "DELTA_L_85_10INCH_IN6_DP")
	)
	(segment
		(start 219.804996 4.383024)
		(end 219.689934 4.547362)
		(width 0.14224)
		(layer "In15.Cu")
		(net "DELTA_L_85_10INCH_IN6_DP")
	)
	(segment
		(start 238.139224 4.786884)
		(end 237.974886 4.671822)
		(width 0.14224)
		(layer "In15.Cu")
		(net "DELTA_L_85_10INCH_IN6_DP")
	)
	(segment
		(start 271.311624 4.329176)
		(end 271.196562 4.493768)
		(width 0.14224)
		(layer "In15.Cu")
		(net "DELTA_L_85_10INCH_IN6_DP")
	)
	(segment
		(start 280.41727 -0.064008)
		(end 278.823674 0.217424)
		(width 0.14224)
		(layer "In15.Cu")
		(net "DELTA_L_85_10INCH_IN6_DP")
	)
	(segment
		(start 223.1009 0.60452)
		(end 223.766634 4.375404)
		(width 0.14224)
		(layer "In15.Cu")
		(net "DELTA_L_85_10INCH_IN6_DP")
	)
	(segment
		(start 259.423662 4.331462)
		(end 259.3086 4.4958)
		(width 0.14224)
		(layer "In15.Cu")
		(net "DELTA_L_85_10INCH_IN6_DP")
	)
	(segment
		(start 271.196562 4.493768)
		(end 269.832074 4.734814)
		(width 0.14224)
		(layer "In15.Cu")
		(net "DELTA_L_85_10INCH_IN6_DP")
	)
	(segment
		(start 219.133928 0.580898)
		(end 219.804996 4.383024)
		(width 0.14224)
		(layer "In15.Cu")
		(net "DELTA_L_85_10INCH_IN6_DP")
	)
	(segment
		(start 298.769786 2.401824)
		(end 296.314876 2.401824)
		(width 0.14224)
		(layer "In15.Cu")
		(net "DELTA_L_85_10INCH_IN6_DP")
	)
	(segment
		(start 241.93373 4.650994)
		(end 241.153442 0.230124)
		(width 0.14224)
		(layer "In15.Cu")
		(net "DELTA_L_85_10INCH_IN6_DP")
	)
	(segment
		(start 261.744714 4.63423)
		(end 260.961632 0.197358)
		(width 0.14224)
		(layer "In15.Cu")
		(net "DELTA_L_85_10INCH_IN6_DP")
	)
	(segment
		(start 293.451788 4.661916)
		(end 292.670484 0.23622)
		(width 0.14224)
		(layer "In15.Cu")
		(net "DELTA_L_85_10INCH_IN6_DP")
	)
	(segment
		(start 261.909052 4.749292)
		(end 261.744714 4.63423)
		(width 0.14224)
		(layer "In15.Cu")
		(net "DELTA_L_85_10INCH_IN6_DP")
	)
	(segment
		(start 239.61852 4.381754)
		(end 239.503712 4.545838)
		(width 0.14224)
		(layer "In15.Cu")
		(net "DELTA_L_85_10INCH_IN6_DP")
	)
	(segment
		(start 282.555442 0.677926)
		(end 283.19984 4.328414)
		(width 0.14224)
		(layer "In15.Cu")
		(net "DELTA_L_85_10INCH_IN6_DP")
	)
	(segment
		(start 241.153442 0.230124)
		(end 240.797334 -0.019304)
		(width 0.14224)
		(layer "In15.Cu")
		(net "DELTA_L_85_10INCH_IN6_DP")
	)
	(segment
		(start 293.599362 4.764786)
		(end 293.451788 4.661916)
		(width 0.14224)
		(layer "In15.Cu")
		(net "DELTA_L_85_10INCH_IN6_DP")
	)
	(segment
		(start 231.283256 0.290576)
		(end 231.033828 0.646684)
		(width 0.14224)
		(layer "In15.Cu")
		(net "DELTA_L_85_10INCH_IN6_DP")
	)
	(segment
		(start 299.712888 2.79273)
		(end 299.060616 2.974594)
		(width 0.12954)
		(layer "B.Cu")
		(net "DELTA_L_85_10INCH_IN6_DN")
	)
	(segment
		(start 213.297008 2.79273)
		(end 213.94928 2.974594)
		(width 0.12954)
		(layer "B.Cu")
		(net "DELTA_L_85_10INCH_IN6_DN")
	)
	(segment
		(start 271.059656 0.460756)
		(end 272.423128 0.219964)
		(width 0.14224)
		(layer "In15.Cu")
		(net "DELTA_L_85_10INCH_IN6_DN")
	)
	(segment
		(start 256.58445 0.290068)
		(end 256.749042 0.405384)
		(width 0.14224)
		(layer "In15.Cu")
		(net "DELTA_L_85_10INCH_IN6_DN")
	)
	(segment
		(start 298.769786 2.683764)
		(end 299.060616 2.974594)
		(width 0.14224)
		(layer "In15.Cu")
		(net "DELTA_L_85_10INCH_IN6_DN")
	)
	(segment
		(start 276.5552 0.361696)
		(end 277.34006 4.807712)
		(width 0.14224)
		(layer "In15.Cu")
		(net "DELTA_L_85_10INCH_IN6_DN")
	)
	(segment
		(start 252.630686 0.341376)
		(end 252.795278 0.456692)
		(width 0.14224)
		(layer "In15.Cu")
		(net "DELTA_L_85_10INCH_IN6_DN")
	)
	(segment
		(start 243.875814 4.426712)
		(end 243.213128 0.672084)
		(width 0.14224)
		(layer "In15.Cu")
		(net "DELTA_L_85_10INCH_IN6_DN")
	)
	(segment
		(start 261.487158 4.798314)
		(end 261.843012 5.047488)
		(width 0.14224)
		(layer "In15.Cu")
		(net "DELTA_L_85_10INCH_IN6_DN")
	)
	(segment
		(start 291.43579 4.463796)
		(end 290.769802 0.690372)
		(width 0.14224)
		(layer "In15.Cu")
		(net "DELTA_L_85_10INCH_IN6_DN")
	)
	(segment
		(start 221.86519 4.82981)
		(end 222.221044 5.078984)
		(width 0.14224)
		(layer "In15.Cu")
		(net "DELTA_L_85_10INCH_IN6_DN")
	)
	(segment
		(start 225.042476 0.380492)
		(end 225.826828 4.823968)
		(width 0.14224)
		(layer "In15.Cu")
		(net "DELTA_L_85_10INCH_IN6_DN")
	)
	(segment
		(start 278.987758 0.47498)
		(end 280.35123 0.234188)
		(width 0.14224)
		(layer "In15.Cu")
		(net "DELTA_L_85_10INCH_IN6_DN")
	)
	(segment
		(start 283.498036 4.394454)
		(end 282.853638 0.743966)
		(width 0.14224)
		(layer "In15.Cu")
		(net "DELTA_L_85_10INCH_IN6_DN")
	)
	(segment
		(start 244.691916 0.2667)
		(end 244.856508 0.382016)
		(width 0.14224)
		(layer "In15.Cu")
		(net "DELTA_L_85_10INCH_IN6_DN")
	)
	(segment
		(start 261.843012 5.047488)
		(end 263.437624 4.765802)
		(width 0.14224)
		(layer "In15.Cu")
		(net "DELTA_L_85_10INCH_IN6_DN")
	)
	(segment
		(start 293.533576 5.062728)
		(end 295.058338 4.793742)
		(width 0.14224)
		(layer "In15.Cu")
		(net "DELTA_L_85_10INCH_IN6_DN")
	)
	(segment
		(start 259.060696 0.65151)
		(end 259.176012 0.486918)
		(width 0.14224)
		(layer "In15.Cu")
		(net "DELTA_L_85_10INCH_IN6_DN")
	)
	(segment
		(start 220.910912 0.242062)
		(end 221.075758 0.357378)
		(width 0.14224)
		(layer "In15.Cu")
		(net "DELTA_L_85_10INCH_IN6_DN")
	)
	(segment
		(start 292.24859 0.284988)
		(end 292.412928 0.400304)
		(width 0.14224)
		(layer "In15.Cu")
		(net "DELTA_L_85_10INCH_IN6_DN")
	)
	(segment
		(start 285.623762 5.070856)
		(end 287.218374 4.78917)
		(width 0.14224)
		(layer "In15.Cu")
		(net "DELTA_L_85_10INCH_IN6_DN")
	)
	(segment
		(start 228.026468 4.435602)
		(end 227.36429 0.684276)
		(width 0.14224)
		(layer "In15.Cu")
		(net "DELTA_L_85_10INCH_IN6_DN")
	)
	(segment
		(start 260.539484 0.246126)
		(end 260.704076 0.361442)
		(width 0.14224)
		(layer "In15.Cu")
		(net "DELTA_L_85_10INCH_IN6_DN")
	)
	(segment
		(start 280.515568 0.349504)
		(end 281.298396 4.78282)
		(width 0.14224)
		(layer "In15.Cu")
		(net "DELTA_L_85_10INCH_IN6_DN")
	)
	(segment
		(start 224.06483 4.441444)
		(end 223.399096 0.67056)
		(width 0.14224)
		(layer "In15.Cu")
		(net "DELTA_L_85_10INCH_IN6_DN")
	)
	(segment
		(start 251.267214 0.582168)
		(end 252.630686 0.341376)
		(width 0.14224)
		(layer "In15.Cu")
		(net "DELTA_L_85_10INCH_IN6_DN")
	)
	(segment
		(start 232.975404 0.422656)
		(end 233.747818 4.798314)
		(width 0.14224)
		(layer "In15.Cu")
		(net "DELTA_L_85_10INCH_IN6_DN")
	)
	(segment
		(start 282.853638 0.743966)
		(end 282.968954 0.579374)
		(width 0.14224)
		(layer "In15.Cu")
		(net "DELTA_L_85_10INCH_IN6_DN")
	)
	(segment
		(start 235.292138 0.696468)
		(end 235.407454 0.531876)
		(width 0.14224)
		(layer "In15.Cu")
		(net "DELTA_L_85_10INCH_IN6_DN")
	)
	(segment
		(start 281.65425 5.031994)
		(end 283.248862 4.750308)
		(width 0.14224)
		(layer "In15.Cu")
		(net "DELTA_L_85_10INCH_IN6_DN")
	)
	(segment
		(start 281.298396 4.78282)
		(end 281.65425 5.031994)
		(width 0.14224)
		(layer "In15.Cu")
		(net "DELTA_L_85_10INCH_IN6_DN")
	)
	(segment
		(start 290.885118 0.52578)
		(end 292.24859 0.284988)
		(width 0.14224)
		(layer "In15.Cu")
		(net "DELTA_L_85_10INCH_IN6_DN")
	)
	(segment
		(start 253.924562 5.087874)
		(end 255.519174 4.806188)
		(width 0.14224)
		(layer "In15.Cu")
		(net "DELTA_L_85_10INCH_IN6_DN")
	)
	(segment
		(start 243.328444 0.507492)
		(end 244.691916 0.2667)
		(width 0.14224)
		(layer "In15.Cu")
		(net "DELTA_L_85_10INCH_IN6_DN")
	)
	(segment
		(start 260.704076 0.361442)
		(end 261.487158 4.798314)
		(width 0.14224)
		(layer "In15.Cu")
		(net "DELTA_L_85_10INCH_IN6_DN")
	)
	(segment
		(start 239.667796 4.803394)
		(end 239.916716 4.447794)
		(width 0.14224)
		(layer "In15.Cu")
		(net "DELTA_L_85_10INCH_IN6_DN")
	)
	(segment
		(start 236.935518 0.4064)
		(end 237.71733 4.835906)
		(width 0.14224)
		(layer "In15.Cu")
		(net "DELTA_L_85_10INCH_IN6_DN")
	)
	(segment
		(start 286.804608 0.676402)
		(end 286.919924 0.511556)
		(width 0.14224)
		(layer "In15.Cu")
		(net "DELTA_L_85_10INCH_IN6_DN")
	)
	(segment
		(start 245.997984 5.08127)
		(end 247.592596 4.799584)
		(width 0.14224)
		(layer "In15.Cu")
		(net "DELTA_L_85_10INCH_IN6_DN")
	)
	(segment
		(start 272.587974 0.33528)
		(end 273.380962 4.82854)
		(width 0.14224)
		(layer "In15.Cu")
		(net "DELTA_L_85_10INCH_IN6_DN")
	)
	(segment
		(start 272.423128 0.219964)
		(end 272.587974 0.33528)
		(width 0.14224)
		(layer "In15.Cu")
		(net "DELTA_L_85_10INCH_IN6_DN")
	)
	(segment
		(start 284.497018 0.453898)
		(end 285.267908 4.821682)
		(width 0.14224)
		(layer "In15.Cu")
		(net "DELTA_L_85_10INCH_IN6_DN")
	)
	(segment
		(start 234.103672 5.047488)
		(end 235.698284 4.765802)
		(width 0.14224)
		(layer "In15.Cu")
		(net "DELTA_L_85_10INCH_IN6_DN")
	)
	(segment
		(start 228.843078 0.278892)
		(end 229.00767 0.394208)
		(width 0.14224)
		(layer "In15.Cu")
		(net "DELTA_L_85_10INCH_IN6_DN")
	)
	(segment
		(start 247.84177 4.44373)
		(end 247.176036 0.672846)
		(width 0.14224)
		(layer "In15.Cu")
		(net "DELTA_L_85_10INCH_IN6_DN")
	)
	(segment
		(start 291.186616 4.81965)
		(end 291.43579 4.463796)
		(width 0.14224)
		(layer "In15.Cu")
		(net "DELTA_L_85_10INCH_IN6_DN")
	)
	(segment
		(start 238.073184 5.08508)
		(end 239.667796 4.803394)
		(width 0.14224)
		(layer "In15.Cu")
		(net "DELTA_L_85_10INCH_IN6_DN")
	)
	(segment
		(start 253.568708 4.8387)
		(end 253.924562 5.087874)
		(width 0.14224)
		(layer "In15.Cu")
		(net "DELTA_L_85_10INCH_IN6_DN")
	)
	(segment
		(start 257.522218 4.785868)
		(end 257.878072 5.035042)
		(width 0.14224)
		(layer "In15.Cu")
		(net "DELTA_L_85_10INCH_IN6_DN")
	)
	(segment
		(start 237.71733 4.835906)
		(end 238.073184 5.08508)
		(width 0.14224)
		(layer "In15.Cu")
		(net "DELTA_L_85_10INCH_IN6_DN")
	)
	(segment
		(start 256.749042 0.405384)
		(end 257.522218 4.785868)
		(width 0.14224)
		(layer "In15.Cu")
		(net "DELTA_L_85_10INCH_IN6_DN")
	)
	(segment
		(start 277.695914 5.056886)
		(end 279.290526 4.7752)
		(width 0.14224)
		(layer "In15.Cu")
		(net "DELTA_L_85_10INCH_IN6_DN")
	)
	(segment
		(start 289.23615 4.852162)
		(end 289.592004 5.101336)
		(width 0.14224)
		(layer "In15.Cu")
		(net "DELTA_L_85_10INCH_IN6_DN")
	)
	(segment
		(start 217.903552 4.83743)
		(end 218.259406 5.086604)
		(width 0.14224)
		(layer "In15.Cu")
		(net "DELTA_L_85_10INCH_IN6_DN")
	)
	(segment
		(start 273.380962 4.82854)
		(end 273.736816 5.077714)
		(width 0.14224)
		(layer "In15.Cu")
		(net "DELTA_L_85_10INCH_IN6_DN")
	)
	(segment
		(start 223.399096 0.67056)
		(end 223.514412 0.505968)
		(width 0.14224)
		(layer "In15.Cu")
		(net "DELTA_L_85_10INCH_IN6_DN")
	)
	(segment
		(start 278.872442 0.639826)
		(end 278.987758 0.47498)
		(width 0.14224)
		(layer "In15.Cu")
		(net "DELTA_L_85_10INCH_IN6_DN")
	)
	(segment
		(start 240.731294 0.278892)
		(end 240.895886 0.394208)
		(width 0.14224)
		(layer "In15.Cu")
		(net "DELTA_L_85_10INCH_IN6_DN")
	)
	(segment
		(start 275.331428 4.796028)
		(end 275.580602 4.440174)
		(width 0.14224)
		(layer "In15.Cu")
		(net "DELTA_L_85_10INCH_IN6_DN")
	)
	(segment
		(start 287.467548 4.433316)
		(end 286.804608 0.676402)
		(width 0.14224)
		(layer "In15.Cu")
		(net "DELTA_L_85_10INCH_IN6_DN")
	)
	(segment
		(start 267.65123 4.419346)
		(end 266.98194 0.62738)
		(width 0.14224)
		(layer "In15.Cu")
		(net "DELTA_L_85_10INCH_IN6_DN")
	)
	(segment
		(start 230.148384 5.089398)
		(end 231.742996 4.807712)
		(width 0.14224)
		(layer "In15.Cu")
		(net "DELTA_L_85_10INCH_IN6_DN")
	)
	(segment
		(start 229.00767 0.394208)
		(end 229.79253 4.840224)
		(width 0.14224)
		(layer "In15.Cu")
		(net "DELTA_L_85_10INCH_IN6_DN")
	)
	(segment
		(start 288.283396 0.270764)
		(end 288.447734 0.38608)
		(width 0.14224)
		(layer "In15.Cu")
		(net "DELTA_L_85_10INCH_IN6_DN")
	)
	(segment
		(start 285.267908 4.821682)
		(end 285.623762 5.070856)
		(width 0.14224)
		(layer "In15.Cu")
		(net "DELTA_L_85_10INCH_IN6_DN")
	)
	(segment
		(start 257.878072 5.035042)
		(end 259.472684 4.753356)
		(width 0.14224)
		(layer "In15.Cu")
		(net "DELTA_L_85_10INCH_IN6_DN")
	)
	(segment
		(start 233.747818 4.798314)
		(end 234.103672 5.047488)
		(width 0.14224)
		(layer "In15.Cu")
		(net "DELTA_L_85_10INCH_IN6_DN")
	)
	(segment
		(start 249.597672 4.792218)
		(end 249.953526 5.041392)
		(width 0.14224)
		(layer "In15.Cu")
		(net "DELTA_L_85_10INCH_IN6_DN")
	)
	(segment
		(start 296.338498 2.683764)
		(end 298.769786 2.683764)
		(width 0.14224)
		(layer "In15.Cu")
		(net "DELTA_L_85_10INCH_IN6_DN")
	)
	(segment
		(start 286.919924 0.511556)
		(end 288.283396 0.270764)
		(width 0.14224)
		(layer "In15.Cu")
		(net "DELTA_L_85_10INCH_IN6_DN")
	)
	(segment
		(start 265.807444 5.056886)
		(end 267.402056 4.7752)
		(width 0.14224)
		(layer "In15.Cu")
		(net "DELTA_L_85_10INCH_IN6_DN")
	)
	(segment
		(start 251.151898 0.74676)
		(end 251.267214 0.582168)
		(width 0.14224)
		(layer "In15.Cu")
		(net "DELTA_L_85_10INCH_IN6_DN")
	)
	(segment
		(start 295.523158 2.820416)
		(end 296.338498 2.683764)
		(width 0.14224)
		(layer "In15.Cu")
		(net "DELTA_L_85_10INCH_IN6_DN")
	)
	(segment
		(start 275.027136 0.487172)
		(end 276.390608 0.24638)
		(width 0.14224)
		(layer "In15.Cu")
		(net "DELTA_L_85_10INCH_IN6_DN")
	)
	(segment
		(start 231.44734 0.548132)
		(end 232.810812 0.30734)
		(width 0.14224)
		(layer "In15.Cu")
		(net "DELTA_L_85_10INCH_IN6_DN")
	)
	(segment
		(start 248.819416 0.382778)
		(end 249.597672 4.792218)
		(width 0.14224)
		(layer "In15.Cu")
		(net "DELTA_L_85_10INCH_IN6_DN")
	)
	(segment
		(start 267.402056 4.7752)
		(end 267.65123 4.419346)
		(width 0.14224)
		(layer "In15.Cu")
		(net "DELTA_L_85_10INCH_IN6_DN")
	)
	(segment
		(start 259.721858 4.397502)
		(end 259.060696 0.65151)
		(width 0.14224)
		(layer "In15.Cu")
		(net "DELTA_L_85_10INCH_IN6_DN")
	)
	(segment
		(start 218.259406 5.086604)
		(end 219.854018 4.804918)
		(width 0.14224)
		(layer "In15.Cu")
		(net "DELTA_L_85_10INCH_IN6_DN")
	)
	(segment
		(start 223.815656 4.797298)
		(end 224.06483 4.441444)
		(width 0.14224)
		(layer "In15.Cu")
		(net "DELTA_L_85_10INCH_IN6_DN")
	)
	(segment
		(start 236.770926 0.291084)
		(end 236.935518 0.4064)
		(width 0.14224)
		(layer "In15.Cu")
		(net "DELTA_L_85_10INCH_IN6_DN")
	)
	(segment
		(start 231.332024 0.712724)
		(end 231.44734 0.548132)
		(width 0.14224)
		(layer "In15.Cu")
		(net "DELTA_L_85_10INCH_IN6_DN")
	)
	(segment
		(start 263.017762 0.619506)
		(end 263.133078 0.454914)
		(width 0.14224)
		(layer "In15.Cu")
		(net "DELTA_L_85_10INCH_IN6_DN")
	)
	(segment
		(start 219.854018 4.804918)
		(end 220.103192 4.449064)
		(width 0.14224)
		(layer "In15.Cu")
		(net "DELTA_L_85_10INCH_IN6_DN")
	)
	(segment
		(start 220.103192 4.449064)
		(end 219.432124 0.647192)
		(width 0.14224)
		(layer "In15.Cu")
		(net "DELTA_L_85_10INCH_IN6_DN")
	)
	(segment
		(start 275.580602 4.440174)
		(end 274.91182 0.651764)
		(width 0.14224)
		(layer "In15.Cu")
		(net "DELTA_L_85_10INCH_IN6_DN")
	)
	(segment
		(start 244.856508 0.382016)
		(end 245.64213 4.832096)
		(width 0.14224)
		(layer "In15.Cu")
		(net "DELTA_L_85_10INCH_IN6_DN")
	)
	(segment
		(start 245.64213 4.832096)
		(end 245.997984 5.08127)
		(width 0.14224)
		(layer "In15.Cu")
		(net "DELTA_L_85_10INCH_IN6_DN")
	)
	(segment
		(start 292.412928 0.400304)
		(end 293.194486 4.826254)
		(width 0.14224)
		(layer "In15.Cu")
		(net "DELTA_L_85_10INCH_IN6_DN")
	)
	(segment
		(start 263.133078 0.454914)
		(end 264.49655 0.214122)
		(width 0.14224)
		(layer "In15.Cu")
		(net "DELTA_L_85_10INCH_IN6_DN")
	)
	(segment
		(start 283.248862 4.750308)
		(end 283.498036 4.394454)
		(width 0.14224)
		(layer "In15.Cu")
		(net "DELTA_L_85_10INCH_IN6_DN")
	)
	(segment
		(start 217.046556 2.683764)
		(end 217.590624 3.06451)
		(width 0.14224)
		(layer "In15.Cu")
		(net "DELTA_L_85_10INCH_IN6_DN")
	)
	(segment
		(start 293.194486 4.826254)
		(end 293.533576 5.062728)
		(width 0.14224)
		(layer "In15.Cu")
		(net "DELTA_L_85_10INCH_IN6_DN")
	)
	(segment
		(start 219.54744 0.482854)
		(end 220.910912 0.242062)
		(width 0.14224)
		(layer "In15.Cu")
		(net "DELTA_L_85_10INCH_IN6_DN")
	)
	(segment
		(start 287.218374 4.78917)
		(end 287.467548 4.433316)
		(width 0.14224)
		(layer "In15.Cu")
		(net "DELTA_L_85_10INCH_IN6_DN")
	)
	(segment
		(start 280.35123 0.234188)
		(end 280.515568 0.349504)
		(width 0.14224)
		(layer "In15.Cu")
		(net "DELTA_L_85_10INCH_IN6_DN")
	)
	(segment
		(start 242.032028 5.064252)
		(end 243.62664 4.782566)
		(width 0.14224)
		(layer "In15.Cu")
		(net "DELTA_L_85_10INCH_IN6_DN")
	)
	(segment
		(start 255.768348 4.450334)
		(end 255.105662 0.695452)
		(width 0.14224)
		(layer "In15.Cu")
		(net "DELTA_L_85_10INCH_IN6_DN")
	)
	(segment
		(start 247.592596 4.799584)
		(end 247.84177 4.44373)
		(width 0.14224)
		(layer "In15.Cu")
		(net "DELTA_L_85_10INCH_IN6_DN")
	)
	(segment
		(start 222.221044 5.078984)
		(end 223.815656 4.797298)
		(width 0.14224)
		(layer "In15.Cu")
		(net "DELTA_L_85_10INCH_IN6_DN")
	)
	(segment
		(start 270.94434 0.625094)
		(end 271.059656 0.460756)
		(width 0.14224)
		(layer "In15.Cu")
		(net "DELTA_L_85_10INCH_IN6_DN")
	)
	(segment
		(start 263.437624 4.765802)
		(end 263.686798 4.409948)
		(width 0.14224)
		(layer "In15.Cu")
		(net "DELTA_L_85_10INCH_IN6_DN")
	)
	(segment
		(start 268.62532 0.337312)
		(end 269.41018 4.784344)
		(width 0.14224)
		(layer "In15.Cu")
		(net "DELTA_L_85_10INCH_IN6_DN")
	)
	(segment
		(start 276.390608 0.24638)
		(end 276.5552 0.361696)
		(width 0.14224)
		(layer "In15.Cu")
		(net "DELTA_L_85_10INCH_IN6_DN")
	)
	(segment
		(start 217.590624 3.06451)
		(end 217.903552 4.83743)
		(width 0.14224)
		(layer "In15.Cu")
		(net "DELTA_L_85_10INCH_IN6_DN")
	)
	(segment
		(start 288.447734 0.38608)
		(end 289.23615 4.852162)
		(width 0.14224)
		(layer "In15.Cu")
		(net "DELTA_L_85_10INCH_IN6_DN")
	)
	(segment
		(start 231.742996 4.807712)
		(end 231.99217 4.452366)
		(width 0.14224)
		(layer "In15.Cu")
		(net "DELTA_L_85_10INCH_IN6_DN")
	)
	(segment
		(start 239.367822 0.519684)
		(end 240.731294 0.278892)
		(width 0.14224)
		(layer "In15.Cu")
		(net "DELTA_L_85_10INCH_IN6_DN")
	)
	(segment
		(start 279.5397 4.419854)
		(end 278.872442 0.639826)
		(width 0.14224)
		(layer "In15.Cu")
		(net "DELTA_L_85_10INCH_IN6_DN")
	)
	(segment
		(start 279.290526 4.7752)
		(end 279.5397 4.419854)
		(width 0.14224)
		(layer "In15.Cu")
		(net "DELTA_L_85_10INCH_IN6_DN")
	)
	(segment
		(start 227.36429 0.684276)
		(end 227.479606 0.519684)
		(width 0.14224)
		(layer "In15.Cu")
		(net "DELTA_L_85_10INCH_IN6_DN")
	)
	(segment
		(start 271.60982 4.395216)
		(end 270.94434 0.625094)
		(width 0.14224)
		(layer "In15.Cu")
		(net "DELTA_L_85_10INCH_IN6_DN")
	)
	(segment
		(start 240.895886 0.394208)
		(end 241.676174 4.815078)
		(width 0.14224)
		(layer "In15.Cu")
		(net "DELTA_L_85_10INCH_IN6_DN")
	)
	(segment
		(start 221.075758 0.357378)
		(end 221.86519 4.82981)
		(width 0.14224)
		(layer "In15.Cu")
		(net "DELTA_L_85_10INCH_IN6_DN")
	)
	(segment
		(start 266.98194 0.62738)
		(end 267.097256 0.462788)
		(width 0.14224)
		(layer "In15.Cu")
		(net "DELTA_L_85_10INCH_IN6_DN")
	)
	(segment
		(start 274.91182 0.651764)
		(end 275.027136 0.487172)
		(width 0.14224)
		(layer "In15.Cu")
		(net "DELTA_L_85_10INCH_IN6_DN")
	)
	(segment
		(start 255.519174 4.806188)
		(end 255.768348 4.450334)
		(width 0.14224)
		(layer "In15.Cu")
		(net "DELTA_L_85_10INCH_IN6_DN")
	)
	(segment
		(start 235.407454 0.531876)
		(end 236.770926 0.291084)
		(width 0.14224)
		(layer "In15.Cu")
		(net "DELTA_L_85_10INCH_IN6_DN")
	)
	(segment
		(start 259.472684 4.753356)
		(end 259.721858 4.397502)
		(width 0.14224)
		(layer "In15.Cu")
		(net "DELTA_L_85_10INCH_IN6_DN")
	)
	(segment
		(start 227.777294 4.791456)
		(end 228.026468 4.435602)
		(width 0.14224)
		(layer "In15.Cu")
		(net "DELTA_L_85_10INCH_IN6_DN")
	)
	(segment
		(start 289.592004 5.101336)
		(end 291.186616 4.81965)
		(width 0.14224)
		(layer "In15.Cu")
		(net "DELTA_L_85_10INCH_IN6_DN")
	)
	(segment
		(start 251.797312 4.403598)
		(end 251.151898 0.74676)
		(width 0.14224)
		(layer "In15.Cu")
		(net "DELTA_L_85_10INCH_IN6_DN")
	)
	(segment
		(start 277.34006 4.807712)
		(end 277.695914 5.056886)
		(width 0.14224)
		(layer "In15.Cu")
		(net "DELTA_L_85_10INCH_IN6_DN")
	)
	(segment
		(start 231.99217 4.452366)
		(end 231.332024 0.712724)
		(width 0.14224)
		(layer "In15.Cu")
		(net "DELTA_L_85_10INCH_IN6_DN")
	)
	(segment
		(start 239.916716 4.447794)
		(end 239.252506 0.684276)
		(width 0.14224)
		(layer "In15.Cu")
		(net "DELTA_L_85_10INCH_IN6_DN")
	)
	(segment
		(start 255.105662 0.695452)
		(end 255.220978 0.53086)
		(width 0.14224)
		(layer "In15.Cu")
		(net "DELTA_L_85_10INCH_IN6_DN")
	)
	(segment
		(start 267.097256 0.462788)
		(end 268.460728 0.221996)
		(width 0.14224)
		(layer "In15.Cu")
		(net "DELTA_L_85_10INCH_IN6_DN")
	)
	(segment
		(start 255.220978 0.53086)
		(end 256.58445 0.290068)
		(width 0.14224)
		(layer "In15.Cu")
		(net "DELTA_L_85_10INCH_IN6_DN")
	)
	(segment
		(start 214.24011 2.683764)
		(end 217.046556 2.683764)
		(width 0.14224)
		(layer "In15.Cu")
		(net "DELTA_L_85_10INCH_IN6_DN")
	)
	(segment
		(start 213.94928 2.974594)
		(end 214.24011 2.683764)
		(width 0.14224)
		(layer "In15.Cu")
		(net "DELTA_L_85_10INCH_IN6_DN")
	)
	(segment
		(start 232.810812 0.30734)
		(end 232.975404 0.422656)
		(width 0.14224)
		(layer "In15.Cu")
		(net "DELTA_L_85_10INCH_IN6_DN")
	)
	(segment
		(start 224.877884 0.265176)
		(end 225.042476 0.380492)
		(width 0.14224)
		(layer "In15.Cu")
		(net "DELTA_L_85_10INCH_IN6_DN")
	)
	(segment
		(start 295.191434 3.290824)
		(end 295.523158 2.820416)
		(width 0.14224)
		(layer "In15.Cu")
		(net "DELTA_L_85_10INCH_IN6_DN")
	)
	(segment
		(start 226.182682 5.073142)
		(end 227.777294 4.791456)
		(width 0.14224)
		(layer "In15.Cu")
		(net "DELTA_L_85_10INCH_IN6_DN")
	)
	(segment
		(start 223.514412 0.505968)
		(end 224.877884 0.265176)
		(width 0.14224)
		(layer "In15.Cu")
		(net "DELTA_L_85_10INCH_IN6_DN")
	)
	(segment
		(start 247.176036 0.672846)
		(end 247.291352 0.508254)
		(width 0.14224)
		(layer "In15.Cu")
		(net "DELTA_L_85_10INCH_IN6_DN")
	)
	(segment
		(start 229.79253 4.840224)
		(end 230.148384 5.089398)
		(width 0.14224)
		(layer "In15.Cu")
		(net "DELTA_L_85_10INCH_IN6_DN")
	)
	(segment
		(start 259.176012 0.486918)
		(end 260.539484 0.246126)
		(width 0.14224)
		(layer "In15.Cu")
		(net "DELTA_L_85_10INCH_IN6_DN")
	)
	(segment
		(start 284.332426 0.338582)
		(end 284.497018 0.453898)
		(width 0.14224)
		(layer "In15.Cu")
		(net "DELTA_L_85_10INCH_IN6_DN")
	)
	(segment
		(start 243.62664 4.782566)
		(end 243.875814 4.426712)
		(width 0.14224)
		(layer "In15.Cu")
		(net "DELTA_L_85_10INCH_IN6_DN")
	)
	(segment
		(start 265.45159 4.807712)
		(end 265.807444 5.056886)
		(width 0.14224)
		(layer "In15.Cu")
		(net "DELTA_L_85_10INCH_IN6_DN")
	)
	(segment
		(start 295.3766 4.339082)
		(end 295.191434 3.290824)
		(width 0.14224)
		(layer "In15.Cu")
		(net "DELTA_L_85_10INCH_IN6_DN")
	)
	(segment
		(start 219.432124 0.647192)
		(end 219.54744 0.482854)
		(width 0.14224)
		(layer "In15.Cu")
		(net "DELTA_L_85_10INCH_IN6_DN")
	)
	(segment
		(start 235.698284 4.765802)
		(end 235.947458 4.409948)
		(width 0.14224)
		(layer "In15.Cu")
		(net "DELTA_L_85_10INCH_IN6_DN")
	)
	(segment
		(start 282.968954 0.579374)
		(end 284.332426 0.338582)
		(width 0.14224)
		(layer "In15.Cu")
		(net "DELTA_L_85_10INCH_IN6_DN")
	)
	(segment
		(start 249.953526 5.041392)
		(end 251.548392 4.759706)
		(width 0.14224)
		(layer "In15.Cu")
		(net "DELTA_L_85_10INCH_IN6_DN")
	)
	(segment
		(start 239.252506 0.684276)
		(end 239.367822 0.519684)
		(width 0.14224)
		(layer "In15.Cu")
		(net "DELTA_L_85_10INCH_IN6_DN")
	)
	(segment
		(start 247.291352 0.508254)
		(end 248.654824 0.267462)
		(width 0.14224)
		(layer "In15.Cu")
		(net "DELTA_L_85_10INCH_IN6_DN")
	)
	(segment
		(start 252.795278 0.456692)
		(end 253.568708 4.8387)
		(width 0.14224)
		(layer "In15.Cu")
		(net "DELTA_L_85_10INCH_IN6_DN")
	)
	(segment
		(start 268.460728 0.221996)
		(end 268.62532 0.337312)
		(width 0.14224)
		(layer "In15.Cu")
		(net "DELTA_L_85_10INCH_IN6_DN")
	)
	(segment
		(start 225.826828 4.823968)
		(end 226.182682 5.073142)
		(width 0.14224)
		(layer "In15.Cu")
		(net "DELTA_L_85_10INCH_IN6_DN")
	)
	(segment
		(start 264.49655 0.214122)
		(end 264.661142 0.329438)
		(width 0.14224)
		(layer "In15.Cu")
		(net "DELTA_L_85_10INCH_IN6_DN")
	)
	(segment
		(start 241.676174 4.815078)
		(end 242.032028 5.064252)
		(width 0.14224)
		(layer "In15.Cu")
		(net "DELTA_L_85_10INCH_IN6_DN")
	)
	(segment
		(start 264.661142 0.329438)
		(end 265.45159 4.807712)
		(width 0.14224)
		(layer "In15.Cu")
		(net "DELTA_L_85_10INCH_IN6_DN")
	)
	(segment
		(start 269.766288 5.03301)
		(end 271.3609 4.751324)
		(width 0.14224)
		(layer "In15.Cu")
		(net "DELTA_L_85_10INCH_IN6_DN")
	)
	(segment
		(start 227.479606 0.519684)
		(end 228.843078 0.278892)
		(width 0.14224)
		(layer "In15.Cu")
		(net "DELTA_L_85_10INCH_IN6_DN")
	)
	(segment
		(start 271.3609 4.751324)
		(end 271.60982 4.395216)
		(width 0.14224)
		(layer "In15.Cu")
		(net "DELTA_L_85_10INCH_IN6_DN")
	)
	(segment
		(start 290.769802 0.690372)
		(end 290.885118 0.52578)
		(width 0.14224)
		(layer "In15.Cu")
		(net "DELTA_L_85_10INCH_IN6_DN")
	)
	(segment
		(start 295.058338 4.793742)
		(end 295.3766 4.339082)
		(width 0.14224)
		(layer "In15.Cu")
		(net "DELTA_L_85_10INCH_IN6_DN")
	)
	(segment
		(start 263.686798 4.409948)
		(end 263.017762 0.619506)
		(width 0.14224)
		(layer "In15.Cu")
		(net "DELTA_L_85_10INCH_IN6_DN")
	)
	(segment
		(start 235.947458 4.409948)
		(end 235.292138 0.696468)
		(width 0.14224)
		(layer "In15.Cu")
		(net "DELTA_L_85_10INCH_IN6_DN")
	)
	(segment
		(start 248.654824 0.267462)
		(end 248.819416 0.382778)
		(width 0.14224)
		(layer "In15.Cu")
		(net "DELTA_L_85_10INCH_IN6_DN")
	)
	(segment
		(start 273.736816 5.077714)
		(end 275.331428 4.796028)
		(width 0.14224)
		(layer "In15.Cu")
		(net "DELTA_L_85_10INCH_IN6_DN")
	)
	(segment
		(start 251.548392 4.759706)
		(end 251.797312 4.403598)
		(width 0.14224)
		(layer "In15.Cu")
		(net "DELTA_L_85_10INCH_IN6_DN")
	)
	(segment
		(start 243.213128 0.672084)
		(end 243.328444 0.507492)
		(width 0.14224)
		(layer "In15.Cu")
		(net "DELTA_L_85_10INCH_IN6_DN")
	)
	(segment
		(start 269.41018 4.784344)
		(end 269.766288 5.03301)
		(width 0.14224)
		(layer "In15.Cu")
		(net "DELTA_L_85_10INCH_IN6_DN")
	)
	(segment
		(start 185.037222 3.77317)
		(end 184.38495 3.955034)
		(width 0.12954)
		(layer "B.Cu")
		(net "DELTA_L_85_10INCH_IN5_DP")
	)
	(segment
		(start 98.621342 3.77317)
		(end 99.273614 3.955034)
		(width 0.12954)
		(layer "B.Cu")
		(net "DELTA_L_85_10INCH_IN5_DP")
	)
	(segment
		(start 99.273614 3.955034)
		(end 99.564444 3.664204)
		(width 0.14224)
		(layer "In13.Cu")
		(net "DELTA_L_85_10INCH_IN5_DP")
	)
	(segment
		(start 176.760124 5.444236)
		(end 176.094136 1.670812)
		(width 0.14224)
		(layer "In13.Cu")
		(net "DELTA_L_85_10INCH_IN5_DP")
	)
	(segment
		(start 172.791882 5.413756)
		(end 172.128942 1.656842)
		(width 0.14224)
		(layer "In13.Cu")
		(net "DELTA_L_85_10INCH_IN5_DP")
	)
	(segment
		(start 168.293288 1.559814)
		(end 169.65676 1.319022)
		(width 0.14224)
		(layer "In13.Cu")
		(net "DELTA_L_85_10INCH_IN5_DP")
	)
	(segment
		(start 103.58374 6.067044)
		(end 105.178352 5.785358)
		(width 0.14224)
		(layer "In13.Cu")
		(net "DELTA_L_85_10INCH_IN5_DP")
	)
	(segment
		(start 106.235246 1.222502)
		(end 106.400092 1.337818)
		(width 0.14224)
		(layer "In13.Cu")
		(net "DELTA_L_85_10INCH_IN5_DP")
	)
	(segment
		(start 109.13999 5.777738)
		(end 109.389164 5.421884)
		(width 0.14224)
		(layer "In13.Cu")
		(net "DELTA_L_85_10INCH_IN5_DP")
	)
	(segment
		(start 169.65676 1.319022)
		(end 169.821352 1.434338)
		(width 0.14224)
		(layer "In13.Cu")
		(net "DELTA_L_85_10INCH_IN5_DP")
	)
	(segment
		(start 163.020248 6.037326)
		(end 164.61486 5.75564)
		(width 0.14224)
		(layer "In13.Cu")
		(net "DELTA_L_85_10INCH_IN5_DP")
	)
	(segment
		(start 153.949654 1.317752)
		(end 154.734514 5.764784)
		(width 0.14224)
		(layer "In13.Cu")
		(net "DELTA_L_85_10INCH_IN5_DP")
	)
	(segment
		(start 184.09412 3.664204)
		(end 184.38495 3.955034)
		(width 0.14224)
		(layer "In13.Cu")
		(net "DELTA_L_85_10INCH_IN5_DP")
	)
	(segment
		(start 174.916338 6.081776)
		(end 176.51095 5.80009)
		(width 0.14224)
		(layer "In13.Cu")
		(net "DELTA_L_85_10INCH_IN5_DP")
	)
	(segment
		(start 176.51095 5.80009)
		(end 176.760124 5.444236)
		(width 0.14224)
		(layer "In13.Cu")
		(net "DELTA_L_85_10INCH_IN5_DP")
	)
	(segment
		(start 118.135146 1.28778)
		(end 118.299738 1.403096)
		(width 0.14224)
		(layer "In13.Cu")
		(net "DELTA_L_85_10INCH_IN5_DP")
	)
	(segment
		(start 114.167412 1.259332)
		(end 114.332004 1.374648)
		(width 0.14224)
		(layer "In13.Cu")
		(net "DELTA_L_85_10INCH_IN5_DP")
	)
	(segment
		(start 149.985476 1.309878)
		(end 150.775924 5.788152)
		(width 0.14224)
		(layer "In13.Cu")
		(net "DELTA_L_85_10INCH_IN5_DP")
	)
	(segment
		(start 110.202218 1.245616)
		(end 110.36681 1.360932)
		(width 0.14224)
		(layer "In13.Cu")
		(net "DELTA_L_85_10INCH_IN5_DP")
	)
	(segment
		(start 172.244258 1.491996)
		(end 173.60773 1.251204)
		(width 0.14224)
		(layer "In13.Cu")
		(net "DELTA_L_85_10INCH_IN5_DP")
	)
	(segment
		(start 157.747462 1.200404)
		(end 157.912308 1.31572)
		(width 0.14224)
		(layer "In13.Cu")
		(net "DELTA_L_85_10INCH_IN5_DP")
	)
	(segment
		(start 170.948096 6.051296)
		(end 172.542708 5.76961)
		(width 0.14224)
		(layer "In13.Cu")
		(net "DELTA_L_85_10INCH_IN5_DP")
	)
	(segment
		(start 116.656358 1.693164)
		(end 116.771674 1.528572)
		(width 0.14224)
		(layer "In13.Cu")
		(net "DELTA_L_85_10INCH_IN5_DP")
	)
	(segment
		(start 99.564444 3.664204)
		(end 102.37089 3.664204)
		(width 0.14224)
		(layer "In13.Cu")
		(net "DELTA_L_85_10INCH_IN5_DP")
	)
	(segment
		(start 121.271792 5.390388)
		(end 120.616472 1.676908)
		(width 0.14224)
		(layer "In13.Cu")
		(net "DELTA_L_85_10INCH_IN5_DP")
	)
	(segment
		(start 144.500346 1.467358)
		(end 145.863818 1.226566)
		(width 0.14224)
		(layer "In13.Cu")
		(net "DELTA_L_85_10INCH_IN5_DP")
	)
	(segment
		(start 123.041664 5.816346)
		(end 123.397518 6.06552)
		(width 0.14224)
		(layer "In13.Cu")
		(net "DELTA_L_85_10INCH_IN5_DP")
	)
	(segment
		(start 148.342096 1.599946)
		(end 148.457412 1.435354)
		(width 0.14224)
		(layer "In13.Cu")
		(net "DELTA_L_85_10INCH_IN5_DP")
	)
	(segment
		(start 111.507016 6.053582)
		(end 113.101628 5.771896)
		(width 0.14224)
		(layer "In13.Cu")
		(net "DELTA_L_85_10INCH_IN5_DP")
	)
	(segment
		(start 141.908784 1.270508)
		(end 142.073376 1.385824)
		(width 0.14224)
		(layer "In13.Cu")
		(net "DELTA_L_85_10INCH_IN5_DP")
	)
	(segment
		(start 121.022618 5.746242)
		(end 121.271792 5.390388)
		(width 0.14224)
		(layer "In13.Cu")
		(net "DELTA_L_85_10INCH_IN5_DP")
	)
	(segment
		(start 155.090622 6.01345)
		(end 156.685234 5.731764)
		(width 0.14224)
		(layer "In13.Cu")
		(net "DELTA_L_85_10INCH_IN5_DP")
	)
	(segment
		(start 109.389164 5.421884)
		(end 108.72343 1.651)
		(width 0.14224)
		(layer "In13.Cu")
		(net "DELTA_L_85_10INCH_IN5_DP")
	)
	(segment
		(start 180.847492 3.800856)
		(end 181.662832 3.664204)
		(width 0.14224)
		(layer "In13.Cu")
		(net "DELTA_L_85_10INCH_IN5_DP")
	)
	(segment
		(start 115.472718 6.069838)
		(end 117.06733 5.788152)
		(width 0.14224)
		(layer "In13.Cu")
		(net "DELTA_L_85_10INCH_IN5_DP")
	)
	(segment
		(start 145.863818 1.226566)
		(end 146.02841 1.341882)
		(width 0.14224)
		(layer "In13.Cu")
		(net "DELTA_L_85_10INCH_IN5_DP")
	)
	(segment
		(start 161.879534 1.342136)
		(end 162.664394 5.788152)
		(width 0.14224)
		(layer "In13.Cu")
		(net "DELTA_L_85_10INCH_IN5_DP")
	)
	(segment
		(start 140.545312 1.5113)
		(end 141.908784 1.270508)
		(width 0.14224)
		(layer "In13.Cu")
		(net "DELTA_L_85_10INCH_IN5_DP")
	)
	(segment
		(start 102.37089 3.664204)
		(end 102.914958 4.04495)
		(width 0.14224)
		(layer "In13.Cu")
		(net "DELTA_L_85_10INCH_IN5_DP")
	)
	(segment
		(start 149.820884 1.194562)
		(end 149.985476 1.309878)
		(width 0.14224)
		(layer "In13.Cu")
		(net "DELTA_L_85_10INCH_IN5_DP")
	)
	(segment
		(start 180.382672 5.774182)
		(end 180.700934 5.319522)
		(width 0.14224)
		(layer "In13.Cu")
		(net "DELTA_L_85_10INCH_IN5_DP")
	)
	(segment
		(start 166.62273 5.76326)
		(end 166.978584 6.012434)
		(width 0.14224)
		(layer "In13.Cu")
		(net "DELTA_L_85_10INCH_IN5_DP")
	)
	(segment
		(start 173.772068 1.36652)
		(end 174.560484 5.832602)
		(width 0.14224)
		(layer "In13.Cu")
		(net "DELTA_L_85_10INCH_IN5_DP")
	)
	(segment
		(start 107.189524 5.81025)
		(end 107.545378 6.059424)
		(width 0.14224)
		(layer "In13.Cu")
		(net "DELTA_L_85_10INCH_IN5_DP")
	)
	(segment
		(start 138.893042 5.81914)
		(end 139.248896 6.068314)
		(width 0.14224)
		(layer "In13.Cu")
		(net "DELTA_L_85_10INCH_IN5_DP")
	)
	(segment
		(start 149.011132 5.390388)
		(end 148.342096 1.599946)
		(width 0.14224)
		(layer "In13.Cu")
		(net "DELTA_L_85_10INCH_IN5_DP")
	)
	(segment
		(start 147.167346 6.027928)
		(end 148.761958 5.746242)
		(width 0.14224)
		(layer "In13.Cu")
		(net "DELTA_L_85_10INCH_IN5_DP")
	)
	(segment
		(start 127.356362 6.044692)
		(end 128.950974 5.763006)
		(width 0.14224)
		(layer "In13.Cu")
		(net "DELTA_L_85_10INCH_IN5_DP")
	)
	(segment
		(start 132.50037 1.653286)
		(end 132.615686 1.488694)
		(width 0.14224)
		(layer "In13.Cu")
		(net "DELTA_L_85_10INCH_IN5_DP")
	)
	(segment
		(start 178.51882 5.806694)
		(end 178.85791 6.043168)
		(width 0.14224)
		(layer "In13.Cu")
		(net "DELTA_L_85_10INCH_IN5_DP")
	)
	(segment
		(start 164.196776 1.620266)
		(end 164.312092 1.45542)
		(width 0.14224)
		(layer "In13.Cu")
		(net "DELTA_L_85_10INCH_IN5_DP")
	)
	(segment
		(start 166.978584 6.012434)
		(end 168.573196 5.730748)
		(width 0.14224)
		(layer "In13.Cu")
		(net "DELTA_L_85_10INCH_IN5_DP")
	)
	(segment
		(start 103.227886 5.81787)
		(end 103.58374 6.067044)
		(width 0.14224)
		(layer "In13.Cu")
		(net "DELTA_L_85_10INCH_IN5_DP")
	)
	(segment
		(start 144.38503 1.63195)
		(end 144.500346 1.467358)
		(width 0.14224)
		(layer "In13.Cu")
		(net "DELTA_L_85_10INCH_IN5_DP")
	)
	(segment
		(start 113.350802 5.416042)
		(end 112.688624 1.664716)
		(width 0.14224)
		(layer "In13.Cu")
		(net "DELTA_L_85_10INCH_IN5_DP")
	)
	(segment
		(start 148.457412 1.435354)
		(end 149.820884 1.194562)
		(width 0.14224)
		(layer "In13.Cu")
		(net "DELTA_L_85_10INCH_IN5_DP")
	)
	(segment
		(start 156.268674 1.605534)
		(end 156.38399 1.441196)
		(width 0.14224)
		(layer "In13.Cu")
		(net "DELTA_L_85_10INCH_IN5_DP")
	)
	(segment
		(start 170.592242 5.802122)
		(end 170.948096 6.051296)
		(width 0.14224)
		(layer "In13.Cu")
		(net "DELTA_L_85_10INCH_IN5_DP")
	)
	(segment
		(start 126.22022 1.374648)
		(end 127.000508 5.795518)
		(width 0.14224)
		(layer "In13.Cu")
		(net "DELTA_L_85_10INCH_IN5_DP")
	)
	(segment
		(start 106.400092 1.337818)
		(end 107.189524 5.81025)
		(width 0.14224)
		(layer "In13.Cu")
		(net "DELTA_L_85_10INCH_IN5_DP")
	)
	(segment
		(start 159.06115 6.058154)
		(end 160.655762 5.776468)
		(width 0.14224)
		(layer "In13.Cu")
		(net "DELTA_L_85_10INCH_IN5_DP")
	)
	(segment
		(start 119.072152 5.778754)
		(end 119.428006 6.027928)
		(width 0.14224)
		(layer "In13.Cu")
		(net "DELTA_L_85_10INCH_IN5_DP")
	)
	(segment
		(start 120.616472 1.676908)
		(end 120.731788 1.512316)
		(width 0.14224)
		(layer "In13.Cu")
		(net "DELTA_L_85_10INCH_IN5_DP")
	)
	(segment
		(start 122.09526 1.271524)
		(end 122.259852 1.38684)
		(width 0.14224)
		(layer "In13.Cu")
		(net "DELTA_L_85_10INCH_IN5_DP")
	)
	(segment
		(start 120.731788 1.512316)
		(end 122.09526 1.271524)
		(width 0.14224)
		(layer "In13.Cu")
		(net "DELTA_L_85_10INCH_IN5_DP")
	)
	(segment
		(start 124.57684 1.664716)
		(end 124.692156 1.500124)
		(width 0.14224)
		(layer "In13.Cu")
		(net "DELTA_L_85_10INCH_IN5_DP")
	)
	(segment
		(start 130.180842 1.362456)
		(end 130.966464 5.812536)
		(width 0.14224)
		(layer "In13.Cu")
		(net "DELTA_L_85_10INCH_IN5_DP")
	)
	(segment
		(start 118.299738 1.403096)
		(end 119.072152 5.778754)
		(width 0.14224)
		(layer "In13.Cu")
		(net "DELTA_L_85_10INCH_IN5_DP")
	)
	(segment
		(start 107.545378 6.059424)
		(end 109.13999 5.777738)
		(width 0.14224)
		(layer "In13.Cu")
		(net "DELTA_L_85_10INCH_IN5_DP")
	)
	(segment
		(start 168.82237 5.374894)
		(end 168.177972 1.724406)
		(width 0.14224)
		(layer "In13.Cu")
		(net "DELTA_L_85_10INCH_IN5_DP")
	)
	(segment
		(start 157.912308 1.31572)
		(end 158.705296 5.80898)
		(width 0.14224)
		(layer "In13.Cu")
		(net "DELTA_L_85_10INCH_IN5_DP")
	)
	(segment
		(start 176.209452 1.50622)
		(end 177.572924 1.265428)
		(width 0.14224)
		(layer "In13.Cu")
		(net "DELTA_L_85_10INCH_IN5_DP")
	)
	(segment
		(start 142.073376 1.385824)
		(end 142.846552 5.766308)
		(width 0.14224)
		(layer "In13.Cu")
		(net "DELTA_L_85_10INCH_IN5_DP")
	)
	(segment
		(start 111.151162 5.804408)
		(end 111.507016 6.053582)
		(width 0.14224)
		(layer "In13.Cu")
		(net "DELTA_L_85_10INCH_IN5_DP")
	)
	(segment
		(start 146.811492 5.778754)
		(end 147.167346 6.027928)
		(width 0.14224)
		(layer "In13.Cu")
		(net "DELTA_L_85_10INCH_IN5_DP")
	)
	(segment
		(start 162.664394 5.788152)
		(end 163.020248 6.037326)
		(width 0.14224)
		(layer "In13.Cu")
		(net "DELTA_L_85_10INCH_IN5_DP")
	)
	(segment
		(start 108.838746 1.486408)
		(end 110.202218 1.245616)
		(width 0.14224)
		(layer "In13.Cu")
		(net "DELTA_L_85_10INCH_IN5_DP")
	)
	(segment
		(start 156.934154 5.375656)
		(end 156.268674 1.605534)
		(width 0.14224)
		(layer "In13.Cu")
		(net "DELTA_L_85_10INCH_IN5_DP")
	)
	(segment
		(start 174.560484 5.832602)
		(end 174.916338 6.081776)
		(width 0.14224)
		(layer "In13.Cu")
		(net "DELTA_L_85_10INCH_IN5_DP")
	)
	(segment
		(start 165.675564 1.214628)
		(end 165.839902 1.329944)
		(width 0.14224)
		(layer "In13.Cu")
		(net "DELTA_L_85_10INCH_IN5_DP")
	)
	(segment
		(start 146.02841 1.341882)
		(end 146.811492 5.778754)
		(width 0.14224)
		(layer "In13.Cu")
		(net "DELTA_L_85_10INCH_IN5_DP")
	)
	(segment
		(start 138.119612 1.437132)
		(end 138.893042 5.81914)
		(width 0.14224)
		(layer "In13.Cu")
		(net "DELTA_L_85_10INCH_IN5_DP")
	)
	(segment
		(start 124.99213 5.783834)
		(end 125.24105 5.428234)
		(width 0.14224)
		(layer "In13.Cu")
		(net "DELTA_L_85_10INCH_IN5_DP")
	)
	(segment
		(start 172.128942 1.656842)
		(end 172.244258 1.491996)
		(width 0.14224)
		(layer "In13.Cu")
		(net "DELTA_L_85_10INCH_IN5_DP")
	)
	(segment
		(start 129.200148 5.407152)
		(end 128.537462 1.652524)
		(width 0.14224)
		(layer "In13.Cu")
		(net "DELTA_L_85_10INCH_IN5_DP")
	)
	(segment
		(start 105.427526 5.429504)
		(end 104.756458 1.627632)
		(width 0.14224)
		(layer "In13.Cu")
		(net "DELTA_L_85_10INCH_IN5_DP")
	)
	(segment
		(start 140.429996 1.675892)
		(end 140.545312 1.5113)
		(width 0.14224)
		(layer "In13.Cu")
		(net "DELTA_L_85_10INCH_IN5_DP")
	)
	(segment
		(start 119.428006 6.027928)
		(end 121.022618 5.746242)
		(width 0.14224)
		(layer "In13.Cu")
		(net "DELTA_L_85_10INCH_IN5_DP")
	)
	(segment
		(start 140.843508 5.786628)
		(end 141.092682 5.430774)
		(width 0.14224)
		(layer "In13.Cu")
		(net "DELTA_L_85_10INCH_IN5_DP")
	)
	(segment
		(start 165.839902 1.329944)
		(end 166.62273 5.76326)
		(width 0.14224)
		(layer "In13.Cu")
		(net "DELTA_L_85_10INCH_IN5_DP")
	)
	(segment
		(start 180.700934 5.319522)
		(end 180.515768 4.271264)
		(width 0.14224)
		(layer "In13.Cu")
		(net "DELTA_L_85_10INCH_IN5_DP")
	)
	(segment
		(start 137.95502 1.321816)
		(end 138.119612 1.437132)
		(width 0.14224)
		(layer "In13.Cu")
		(net "DELTA_L_85_10INCH_IN5_DP")
	)
	(segment
		(start 115.116864 5.820664)
		(end 115.472718 6.069838)
		(width 0.14224)
		(layer "In13.Cu")
		(net "DELTA_L_85_10INCH_IN5_DP")
	)
	(segment
		(start 152.42159 1.443228)
		(end 153.785062 1.202436)
		(width 0.14224)
		(layer "In13.Cu")
		(net "DELTA_L_85_10INCH_IN5_DP")
	)
	(segment
		(start 177.572924 1.265428)
		(end 177.737262 1.380744)
		(width 0.14224)
		(layer "In13.Cu")
		(net "DELTA_L_85_10INCH_IN5_DP")
	)
	(segment
		(start 168.573196 5.730748)
		(end 168.82237 5.374894)
		(width 0.14224)
		(layer "In13.Cu")
		(net "DELTA_L_85_10INCH_IN5_DP")
	)
	(segment
		(start 133.979158 1.247902)
		(end 134.14375 1.363218)
		(width 0.14224)
		(layer "In13.Cu")
		(net "DELTA_L_85_10INCH_IN5_DP")
	)
	(segment
		(start 156.38399 1.441196)
		(end 157.747462 1.200404)
		(width 0.14224)
		(layer "In13.Cu")
		(net "DELTA_L_85_10INCH_IN5_DP")
	)
	(segment
		(start 113.101628 5.771896)
		(end 113.350802 5.416042)
		(width 0.14224)
		(layer "In13.Cu")
		(net "DELTA_L_85_10INCH_IN5_DP")
	)
	(segment
		(start 160.655762 5.776468)
		(end 160.904936 5.420614)
		(width 0.14224)
		(layer "In13.Cu")
		(net "DELTA_L_85_10INCH_IN5_DP")
	)
	(segment
		(start 152.306274 1.60782)
		(end 152.42159 1.443228)
		(width 0.14224)
		(layer "In13.Cu")
		(net "DELTA_L_85_10INCH_IN5_DP")
	)
	(segment
		(start 136.476232 1.7272)
		(end 136.591548 1.562608)
		(width 0.14224)
		(layer "In13.Cu")
		(net "DELTA_L_85_10INCH_IN5_DP")
	)
	(segment
		(start 126.055628 1.259332)
		(end 126.22022 1.374648)
		(width 0.14224)
		(layer "In13.Cu")
		(net "DELTA_L_85_10INCH_IN5_DP")
	)
	(segment
		(start 152.72639 5.75564)
		(end 152.975564 5.399786)
		(width 0.14224)
		(layer "In13.Cu")
		(net "DELTA_L_85_10INCH_IN5_DP")
	)
	(segment
		(start 150.775924 5.788152)
		(end 151.131778 6.037326)
		(width 0.14224)
		(layer "In13.Cu")
		(net "DELTA_L_85_10INCH_IN5_DP")
	)
	(segment
		(start 164.61486 5.75564)
		(end 164.864034 5.400294)
		(width 0.14224)
		(layer "In13.Cu")
		(net "DELTA_L_85_10INCH_IN5_DP")
	)
	(segment
		(start 131.322318 6.06171)
		(end 132.91693 5.780024)
		(width 0.14224)
		(layer "In13.Cu")
		(net "DELTA_L_85_10INCH_IN5_DP")
	)
	(segment
		(start 168.177972 1.724406)
		(end 168.293288 1.559814)
		(width 0.14224)
		(layer "In13.Cu")
		(net "DELTA_L_85_10INCH_IN5_DP")
	)
	(segment
		(start 123.397518 6.06552)
		(end 124.99213 5.783834)
		(width 0.14224)
		(layer "In13.Cu")
		(net "DELTA_L_85_10INCH_IN5_DP")
	)
	(segment
		(start 181.662832 3.664204)
		(end 184.09412 3.664204)
		(width 0.14224)
		(layer "In13.Cu")
		(net "DELTA_L_85_10INCH_IN5_DP")
	)
	(segment
		(start 169.821352 1.434338)
		(end 170.592242 5.802122)
		(width 0.14224)
		(layer "In13.Cu")
		(net "DELTA_L_85_10INCH_IN5_DP")
	)
	(segment
		(start 172.542708 5.76961)
		(end 172.791882 5.413756)
		(width 0.14224)
		(layer "In13.Cu")
		(net "DELTA_L_85_10INCH_IN5_DP")
	)
	(segment
		(start 102.914958 4.04495)
		(end 103.227886 5.81787)
		(width 0.14224)
		(layer "In13.Cu")
		(net "DELTA_L_85_10INCH_IN5_DP")
	)
	(segment
		(start 128.537462 1.652524)
		(end 128.652778 1.487932)
		(width 0.14224)
		(layer "In13.Cu")
		(net "DELTA_L_85_10INCH_IN5_DP")
	)
	(segment
		(start 135.27786 6.021832)
		(end 136.872726 5.740146)
		(width 0.14224)
		(layer "In13.Cu")
		(net "DELTA_L_85_10INCH_IN5_DP")
	)
	(segment
		(start 152.975564 5.399786)
		(end 152.306274 1.60782)
		(width 0.14224)
		(layer "In13.Cu")
		(net "DELTA_L_85_10INCH_IN5_DP")
	)
	(segment
		(start 122.259852 1.38684)
		(end 123.041664 5.816346)
		(width 0.14224)
		(layer "In13.Cu")
		(net "DELTA_L_85_10INCH_IN5_DP")
	)
	(segment
		(start 110.36681 1.360932)
		(end 111.151162 5.804408)
		(width 0.14224)
		(layer "In13.Cu")
		(net "DELTA_L_85_10INCH_IN5_DP")
	)
	(segment
		(start 117.06733 5.788152)
		(end 117.316504 5.432806)
		(width 0.14224)
		(layer "In13.Cu")
		(net "DELTA_L_85_10INCH_IN5_DP")
	)
	(segment
		(start 105.178352 5.785358)
		(end 105.427526 5.429504)
		(width 0.14224)
		(layer "In13.Cu")
		(net "DELTA_L_85_10INCH_IN5_DP")
	)
	(segment
		(start 141.092682 5.430774)
		(end 140.429996 1.675892)
		(width 0.14224)
		(layer "In13.Cu")
		(net "DELTA_L_85_10INCH_IN5_DP")
	)
	(segment
		(start 160.236154 1.632204)
		(end 160.35147 1.467612)
		(width 0.14224)
		(layer "In13.Cu")
		(net "DELTA_L_85_10INCH_IN5_DP")
	)
	(segment
		(start 112.80394 1.500124)
		(end 114.167412 1.259332)
		(width 0.14224)
		(layer "In13.Cu")
		(net "DELTA_L_85_10INCH_IN5_DP")
	)
	(segment
		(start 142.846552 5.766308)
		(end 143.202406 6.015482)
		(width 0.14224)
		(layer "In13.Cu")
		(net "DELTA_L_85_10INCH_IN5_DP")
	)
	(segment
		(start 164.312092 1.45542)
		(end 165.675564 1.214628)
		(width 0.14224)
		(layer "In13.Cu")
		(net "DELTA_L_85_10INCH_IN5_DP")
	)
	(segment
		(start 137.121646 5.384038)
		(end 136.476232 1.7272)
		(width 0.14224)
		(layer "In13.Cu")
		(net "DELTA_L_85_10INCH_IN5_DP")
	)
	(segment
		(start 125.24105 5.428234)
		(end 124.57684 1.664716)
		(width 0.14224)
		(layer "In13.Cu")
		(net "DELTA_L_85_10INCH_IN5_DP")
	)
	(segment
		(start 145.046192 5.377942)
		(end 144.38503 1.63195)
		(width 0.14224)
		(layer "In13.Cu")
		(net "DELTA_L_85_10INCH_IN5_DP")
	)
	(segment
		(start 124.692156 1.500124)
		(end 126.055628 1.259332)
		(width 0.14224)
		(layer "In13.Cu")
		(net "DELTA_L_85_10INCH_IN5_DP")
	)
	(segment
		(start 130.01625 1.24714)
		(end 130.180842 1.362456)
		(width 0.14224)
		(layer "In13.Cu")
		(net "DELTA_L_85_10INCH_IN5_DP")
	)
	(segment
		(start 127.000508 5.795518)
		(end 127.356362 6.044692)
		(width 0.14224)
		(layer "In13.Cu")
		(net "DELTA_L_85_10INCH_IN5_DP")
	)
	(segment
		(start 112.688624 1.664716)
		(end 112.80394 1.500124)
		(width 0.14224)
		(layer "In13.Cu")
		(net "DELTA_L_85_10INCH_IN5_DP")
	)
	(segment
		(start 134.922006 5.772658)
		(end 135.27786 6.021832)
		(width 0.14224)
		(layer "In13.Cu")
		(net "DELTA_L_85_10INCH_IN5_DP")
	)
	(segment
		(start 180.515768 4.271264)
		(end 180.847492 3.800856)
		(width 0.14224)
		(layer "In13.Cu")
		(net "DELTA_L_85_10INCH_IN5_DP")
	)
	(segment
		(start 134.14375 1.363218)
		(end 134.922006 5.772658)
		(width 0.14224)
		(layer "In13.Cu")
		(net "DELTA_L_85_10INCH_IN5_DP")
	)
	(segment
		(start 154.734514 5.764784)
		(end 155.090622 6.01345)
		(width 0.14224)
		(layer "In13.Cu")
		(net "DELTA_L_85_10INCH_IN5_DP")
	)
	(segment
		(start 161.714942 1.22682)
		(end 161.879534 1.342136)
		(width 0.14224)
		(layer "In13.Cu")
		(net "DELTA_L_85_10INCH_IN5_DP")
	)
	(segment
		(start 133.166104 5.42417)
		(end 132.50037 1.653286)
		(width 0.14224)
		(layer "In13.Cu")
		(net "DELTA_L_85_10INCH_IN5_DP")
	)
	(segment
		(start 143.202406 6.015482)
		(end 144.797018 5.733796)
		(width 0.14224)
		(layer "In13.Cu")
		(net "DELTA_L_85_10INCH_IN5_DP")
	)
	(segment
		(start 128.950974 5.763006)
		(end 129.200148 5.407152)
		(width 0.14224)
		(layer "In13.Cu")
		(net "DELTA_L_85_10INCH_IN5_DP")
	)
	(segment
		(start 114.332004 1.374648)
		(end 115.116864 5.820664)
		(width 0.14224)
		(layer "In13.Cu")
		(net "DELTA_L_85_10INCH_IN5_DP")
	)
	(segment
		(start 116.771674 1.528572)
		(end 118.135146 1.28778)
		(width 0.14224)
		(layer "In13.Cu")
		(net "DELTA_L_85_10INCH_IN5_DP")
	)
	(segment
		(start 160.904936 5.420614)
		(end 160.236154 1.632204)
		(width 0.14224)
		(layer "In13.Cu")
		(net "DELTA_L_85_10INCH_IN5_DP")
	)
	(segment
		(start 104.871774 1.463294)
		(end 106.235246 1.222502)
		(width 0.14224)
		(layer "In13.Cu")
		(net "DELTA_L_85_10INCH_IN5_DP")
	)
	(segment
		(start 160.35147 1.467612)
		(end 161.714942 1.22682)
		(width 0.14224)
		(layer "In13.Cu")
		(net "DELTA_L_85_10INCH_IN5_DP")
	)
	(segment
		(start 144.797018 5.733796)
		(end 145.046192 5.377942)
		(width 0.14224)
		(layer "In13.Cu")
		(net "DELTA_L_85_10INCH_IN5_DP")
	)
	(segment
		(start 136.591548 1.562608)
		(end 137.95502 1.321816)
		(width 0.14224)
		(layer "In13.Cu")
		(net "DELTA_L_85_10INCH_IN5_DP")
	)
	(segment
		(start 136.872726 5.740146)
		(end 137.121646 5.384038)
		(width 0.14224)
		(layer "In13.Cu")
		(net "DELTA_L_85_10INCH_IN5_DP")
	)
	(segment
		(start 117.316504 5.432806)
		(end 116.656358 1.693164)
		(width 0.14224)
		(layer "In13.Cu")
		(net "DELTA_L_85_10INCH_IN5_DP")
	)
	(segment
		(start 164.864034 5.400294)
		(end 164.196776 1.620266)
		(width 0.14224)
		(layer "In13.Cu")
		(net "DELTA_L_85_10INCH_IN5_DP")
	)
	(segment
		(start 148.761958 5.746242)
		(end 149.011132 5.390388)
		(width 0.14224)
		(layer "In13.Cu")
		(net "DELTA_L_85_10INCH_IN5_DP")
	)
	(segment
		(start 104.756458 1.627632)
		(end 104.871774 1.463294)
		(width 0.14224)
		(layer "In13.Cu")
		(net "DELTA_L_85_10INCH_IN5_DP")
	)
	(segment
		(start 177.737262 1.380744)
		(end 178.51882 5.806694)
		(width 0.14224)
		(layer "In13.Cu")
		(net "DELTA_L_85_10INCH_IN5_DP")
	)
	(segment
		(start 158.705296 5.80898)
		(end 159.06115 6.058154)
		(width 0.14224)
		(layer "In13.Cu")
		(net "DELTA_L_85_10INCH_IN5_DP")
	)
	(segment
		(start 130.966464 5.812536)
		(end 131.322318 6.06171)
		(width 0.14224)
		(layer "In13.Cu")
		(net "DELTA_L_85_10INCH_IN5_DP")
	)
	(segment
		(start 178.85791 6.043168)
		(end 180.382672 5.774182)
		(width 0.14224)
		(layer "In13.Cu")
		(net "DELTA_L_85_10INCH_IN5_DP")
	)
	(segment
		(start 176.094136 1.670812)
		(end 176.209452 1.50622)
		(width 0.14224)
		(layer "In13.Cu")
		(net "DELTA_L_85_10INCH_IN5_DP")
	)
	(segment
		(start 151.131778 6.037326)
		(end 152.72639 5.75564)
		(width 0.14224)
		(layer "In13.Cu")
		(net "DELTA_L_85_10INCH_IN5_DP")
	)
	(segment
		(start 156.685234 5.731764)
		(end 156.934154 5.375656)
		(width 0.14224)
		(layer "In13.Cu")
		(net "DELTA_L_85_10INCH_IN5_DP")
	)
	(segment
		(start 173.60773 1.251204)
		(end 173.772068 1.36652)
		(width 0.14224)
		(layer "In13.Cu")
		(net "DELTA_L_85_10INCH_IN5_DP")
	)
	(segment
		(start 132.615686 1.488694)
		(end 133.979158 1.247902)
		(width 0.14224)
		(layer "In13.Cu")
		(net "DELTA_L_85_10INCH_IN5_DP")
	)
	(segment
		(start 108.72343 1.651)
		(end 108.838746 1.486408)
		(width 0.14224)
		(layer "In13.Cu")
		(net "DELTA_L_85_10INCH_IN5_DP")
	)
	(segment
		(start 132.91693 5.780024)
		(end 133.166104 5.42417)
		(width 0.14224)
		(layer "In13.Cu")
		(net "DELTA_L_85_10INCH_IN5_DP")
	)
	(segment
		(start 139.248896 6.068314)
		(end 140.843508 5.786628)
		(width 0.14224)
		(layer "In13.Cu")
		(net "DELTA_L_85_10INCH_IN5_DP")
	)
	(segment
		(start 128.652778 1.487932)
		(end 130.01625 1.24714)
		(width 0.14224)
		(layer "In13.Cu")
		(net "DELTA_L_85_10INCH_IN5_DP")
	)
	(segment
		(start 153.785062 1.202436)
		(end 153.949654 1.317752)
		(width 0.14224)
		(layer "In13.Cu")
		(net "DELTA_L_85_10INCH_IN5_DP")
	)
	(segment
		(start 185.037222 3.273298)
		(end 184.38495 3.091434)
		(width 0.12954)
		(layer "B.Cu")
		(net "DELTA_L_85_10INCH_IN5_DN")
	)
	(segment
		(start 98.621342 3.273298)
		(end 99.273614 3.091434)
		(width 0.12954)
		(layer "B.Cu")
		(net "DELTA_L_85_10INCH_IN5_DN")
	)
	(segment
		(start 138.02106 1.02362)
		(end 136.427464 1.305052)
		(width 0.14224)
		(layer "In13.Cu")
		(net "DELTA_L_85_10INCH_IN5_DN")
	)
	(segment
		(start 181.63921 3.382264)
		(end 180.684678 3.54203)
		(width 0.14224)
		(layer "In13.Cu")
		(net "DELTA_L_85_10INCH_IN5_DN")
	)
	(segment
		(start 140.794486 5.364734)
		(end 140.679424 5.529072)
		(width 0.14224)
		(layer "In13.Cu")
		(net "DELTA_L_85_10INCH_IN5_DN")
	)
	(segment
		(start 138.377168 1.273048)
		(end 138.02106 1.02362)
		(width 0.14224)
		(layer "In13.Cu")
		(net "DELTA_L_85_10INCH_IN5_DN")
	)
	(segment
		(start 140.1318 1.609852)
		(end 140.794486 5.364734)
		(width 0.14224)
		(layer "In13.Cu")
		(net "DELTA_L_85_10INCH_IN5_DN")
	)
	(segment
		(start 148.0439 1.533906)
		(end 148.712936 5.324348)
		(width 0.14224)
		(layer "In13.Cu")
		(net "DELTA_L_85_10INCH_IN5_DN")
	)
	(segment
		(start 148.597874 5.488686)
		(end 147.233386 5.729732)
		(width 0.14224)
		(layer "In13.Cu")
		(net "DELTA_L_85_10INCH_IN5_DN")
	)
	(segment
		(start 160.491678 5.518912)
		(end 159.12719 5.759958)
		(width 0.14224)
		(layer "In13.Cu")
		(net "DELTA_L_85_10INCH_IN5_DN")
	)
	(segment
		(start 168.129204 1.302258)
		(end 167.879776 1.658366)
		(width 0.14224)
		(layer "In13.Cu")
		(net "DELTA_L_85_10INCH_IN5_DN")
	)
	(segment
		(start 120.858534 5.488686)
		(end 119.494046 5.729732)
		(width 0.14224)
		(layer "In13.Cu")
		(net "DELTA_L_85_10INCH_IN5_DN")
	)
	(segment
		(start 165.741604 0.916432)
		(end 164.148008 1.197864)
		(width 0.14224)
		(layer "In13.Cu")
		(net "DELTA_L_85_10INCH_IN5_DN")
	)
	(segment
		(start 147.069048 5.61467)
		(end 146.285966 1.177798)
		(width 0.14224)
		(layer "In13.Cu")
		(net "DELTA_L_85_10INCH_IN5_DN")
	)
	(segment
		(start 143.104108 5.602224)
		(end 142.330932 1.22174)
		(width 0.14224)
		(layer "In13.Cu")
		(net "DELTA_L_85_10INCH_IN5_DN")
	)
	(segment
		(start 144.086834 1.56591)
		(end 144.747996 5.311902)
		(width 0.14224)
		(layer "In13.Cu")
		(net "DELTA_L_85_10INCH_IN5_DN")
	)
	(segment
		(start 128.488694 1.230376)
		(end 128.239266 1.586484)
		(width 0.14224)
		(layer "In13.Cu")
		(net "DELTA_L_85_10INCH_IN5_DN")
	)
	(segment
		(start 122.517408 1.222756)
		(end 122.1613 0.973328)
		(width 0.14224)
		(layer "In13.Cu")
		(net "DELTA_L_85_10INCH_IN5_DN")
	)
	(segment
		(start 142.330932 1.22174)
		(end 141.974824 0.972312)
		(width 0.14224)
		(layer "In13.Cu")
		(net "DELTA_L_85_10INCH_IN5_DN")
	)
	(segment
		(start 176.346866 5.542534)
		(end 174.982378 5.78358)
		(width 0.14224)
		(layer "In13.Cu")
		(net "DELTA_L_85_10INCH_IN5_DN")
	)
	(segment
		(start 156.635958 5.309616)
		(end 156.520896 5.474208)
		(width 0.14224)
		(layer "In13.Cu")
		(net "DELTA_L_85_10INCH_IN5_DN")
	)
	(segment
		(start 156.219906 1.18364)
		(end 155.970478 1.53924)
		(width 0.14224)
		(layer "In13.Cu")
		(net "DELTA_L_85_10INCH_IN5_DN")
	)
	(segment
		(start 102.45979 3.382264)
		(end 99.564444 3.382264)
		(width 0.14224)
		(layer "In13.Cu")
		(net "DELTA_L_85_10INCH_IN5_DN")
	)
	(segment
		(start 106.657648 1.173734)
		(end 106.301286 0.924306)
		(width 0.14224)
		(layer "In13.Cu")
		(net "DELTA_L_85_10INCH_IN5_DN")
	)
	(segment
		(start 152.562306 5.498084)
		(end 151.197818 5.73913)
		(width 0.14224)
		(layer "In13.Cu")
		(net "DELTA_L_85_10INCH_IN5_DN")
	)
	(segment
		(start 112.639856 1.242568)
		(end 112.390428 1.598676)
		(width 0.14224)
		(layer "In13.Cu")
		(net "DELTA_L_85_10INCH_IN5_DN")
	)
	(segment
		(start 168.524174 5.308854)
		(end 168.409112 5.473192)
		(width 0.14224)
		(layer "In13.Cu")
		(net "DELTA_L_85_10INCH_IN5_DN")
	)
	(segment
		(start 143.268446 5.717286)
		(end 143.104108 5.602224)
		(width 0.14224)
		(layer "In13.Cu")
		(net "DELTA_L_85_10INCH_IN5_DN")
	)
	(segment
		(start 158.962852 5.644896)
		(end 158.169864 1.151636)
		(width 0.14224)
		(layer "In13.Cu")
		(net "DELTA_L_85_10INCH_IN5_DN")
	)
	(segment
		(start 160.60674 5.354574)
		(end 160.491678 5.518912)
		(width 0.14224)
		(layer "In13.Cu")
		(net "DELTA_L_85_10INCH_IN5_DN")
	)
	(segment
		(start 107.44708 5.646166)
		(end 106.657648 1.173734)
		(width 0.14224)
		(layer "In13.Cu")
		(net "DELTA_L_85_10INCH_IN5_DN")
	)
	(segment
		(start 180.217572 4.204716)
		(end 180.402738 5.253482)
		(width 0.14224)
		(layer "In13.Cu")
		(net "DELTA_L_85_10INCH_IN5_DN")
	)
	(segment
		(start 144.747996 5.311902)
		(end 144.632934 5.47624)
		(width 0.14224)
		(layer "In13.Cu")
		(net "DELTA_L_85_10INCH_IN5_DN")
	)
	(segment
		(start 170.078908 1.270254)
		(end 169.7228 1.020826)
		(width 0.14224)
		(layer "In13.Cu")
		(net "DELTA_L_85_10INCH_IN5_DN")
	)
	(segment
		(start 132.451602 1.231138)
		(end 132.202174 1.587246)
		(width 0.14224)
		(layer "In13.Cu")
		(net "DELTA_L_85_10INCH_IN5_DN")
	)
	(segment
		(start 111.408718 5.640324)
		(end 110.624366 1.196848)
		(width 0.14224)
		(layer "In13.Cu")
		(net "DELTA_L_85_10INCH_IN5_DN")
	)
	(segment
		(start 136.427464 1.305052)
		(end 136.178036 1.66116)
		(width 0.14224)
		(layer "In13.Cu")
		(net "DELTA_L_85_10INCH_IN5_DN")
	)
	(segment
		(start 126.121668 0.961136)
		(end 124.528072 1.242568)
		(width 0.14224)
		(layer "In13.Cu")
		(net "DELTA_L_85_10INCH_IN5_DN")
	)
	(segment
		(start 172.493686 5.347716)
		(end 172.378624 5.512054)
		(width 0.14224)
		(layer "In13.Cu")
		(net "DELTA_L_85_10INCH_IN5_DN")
	)
	(segment
		(start 164.450776 5.498084)
		(end 163.086288 5.73913)
		(width 0.14224)
		(layer "In13.Cu")
		(net "DELTA_L_85_10INCH_IN5_DN")
	)
	(segment
		(start 124.278644 1.598676)
		(end 124.942854 5.362194)
		(width 0.14224)
		(layer "In13.Cu")
		(net "DELTA_L_85_10INCH_IN5_DN")
	)
	(segment
		(start 119.329708 5.61467)
		(end 118.557294 1.239012)
		(width 0.14224)
		(layer "In13.Cu")
		(net "DELTA_L_85_10INCH_IN5_DN")
	)
	(segment
		(start 167.879776 1.658366)
		(end 168.524174 5.308854)
		(width 0.14224)
		(layer "In13.Cu")
		(net "DELTA_L_85_10INCH_IN5_DN")
	)
	(segment
		(start 132.752846 5.522468)
		(end 131.388358 5.763514)
		(width 0.14224)
		(layer "In13.Cu")
		(net "DELTA_L_85_10INCH_IN5_DN")
	)
	(segment
		(start 166.880286 5.599176)
		(end 166.097458 1.16586)
		(width 0.14224)
		(layer "In13.Cu")
		(net "DELTA_L_85_10INCH_IN5_DN")
	)
	(segment
		(start 180.402738 5.253482)
		(end 180.218588 5.516626)
		(width 0.14224)
		(layer "In13.Cu")
		(net "DELTA_L_85_10INCH_IN5_DN")
	)
	(segment
		(start 146.285966 1.177798)
		(end 145.929858 0.92837)
		(width 0.14224)
		(layer "In13.Cu")
		(net "DELTA_L_85_10INCH_IN5_DN")
	)
	(segment
		(start 184.38495 3.091434)
		(end 184.09412 3.382264)
		(width 0.14224)
		(layer "In13.Cu")
		(net "DELTA_L_85_10INCH_IN5_DN")
	)
	(segment
		(start 136.82345 5.317998)
		(end 136.708388 5.48259)
		(width 0.14224)
		(layer "In13.Cu")
		(net "DELTA_L_85_10INCH_IN5_DN")
	)
	(segment
		(start 180.684678 3.54203)
		(end 180.217572 4.204716)
		(width 0.14224)
		(layer "In13.Cu")
		(net "DELTA_L_85_10INCH_IN5_DN")
	)
	(segment
		(start 171.830746 1.590802)
		(end 172.493686 5.347716)
		(width 0.14224)
		(layer "In13.Cu")
		(net "DELTA_L_85_10INCH_IN5_DN")
	)
	(segment
		(start 108.674662 1.228852)
		(end 108.425234 1.58496)
		(width 0.14224)
		(layer "In13.Cu")
		(net "DELTA_L_85_10INCH_IN5_DN")
	)
	(segment
		(start 176.045368 1.248664)
		(end 175.79594 1.604772)
		(width 0.14224)
		(layer "In13.Cu")
		(net "DELTA_L_85_10INCH_IN5_DN")
	)
	(segment
		(start 166.097458 1.16586)
		(end 165.741604 0.916432)
		(width 0.14224)
		(layer "In13.Cu")
		(net "DELTA_L_85_10INCH_IN5_DN")
	)
	(segment
		(start 111.573056 5.755386)
		(end 111.408718 5.640324)
		(width 0.14224)
		(layer "In13.Cu")
		(net "DELTA_L_85_10INCH_IN5_DN")
	)
	(segment
		(start 173.674024 0.953008)
		(end 172.080174 1.23444)
		(width 0.14224)
		(layer "In13.Cu")
		(net "DELTA_L_85_10INCH_IN5_DN")
	)
	(segment
		(start 148.293328 1.177798)
		(end 148.0439 1.533906)
		(width 0.14224)
		(layer "In13.Cu")
		(net "DELTA_L_85_10INCH_IN5_DN")
	)
	(segment
		(start 130.08229 0.948944)
		(end 128.488694 1.230376)
		(width 0.14224)
		(layer "In13.Cu")
		(net "DELTA_L_85_10INCH_IN5_DN")
	)
	(segment
		(start 161.780982 0.928624)
		(end 160.187386 1.210056)
		(width 0.14224)
		(layer "In13.Cu")
		(net "DELTA_L_85_10INCH_IN5_DN")
	)
	(segment
		(start 159.937958 1.566164)
		(end 160.60674 5.354574)
		(width 0.14224)
		(layer "In13.Cu")
		(net "DELTA_L_85_10INCH_IN5_DN")
	)
	(segment
		(start 150.243032 1.145794)
		(end 149.886924 0.896366)
		(width 0.14224)
		(layer "In13.Cu")
		(net "DELTA_L_85_10INCH_IN5_DN")
	)
	(segment
		(start 131.22402 5.648452)
		(end 130.438398 1.198372)
		(width 0.14224)
		(layer "In13.Cu")
		(net "DELTA_L_85_10INCH_IN5_DN")
	)
	(segment
		(start 144.632934 5.47624)
		(end 143.268446 5.717286)
		(width 0.14224)
		(layer "In13.Cu")
		(net "DELTA_L_85_10INCH_IN5_DN")
	)
	(segment
		(start 184.09412 3.382264)
		(end 181.63921 3.382264)
		(width 0.14224)
		(layer "In13.Cu")
		(net "DELTA_L_85_10INCH_IN5_DN")
	)
	(segment
		(start 136.178036 1.66116)
		(end 136.82345 5.317998)
		(width 0.14224)
		(layer "In13.Cu")
		(net "DELTA_L_85_10INCH_IN5_DN")
	)
	(segment
		(start 108.425234 1.58496)
		(end 109.090968 5.355844)
		(width 0.14224)
		(layer "In13.Cu")
		(net "DELTA_L_85_10INCH_IN5_DN")
	)
	(segment
		(start 134.045198 0.949706)
		(end 132.451602 1.231138)
		(width 0.14224)
		(layer "In13.Cu")
		(net "DELTA_L_85_10INCH_IN5_DN")
	)
	(segment
		(start 127.258064 5.631434)
		(end 126.477776 1.210564)
		(width 0.14224)
		(layer "In13.Cu")
		(net "DELTA_L_85_10INCH_IN5_DN")
	)
	(segment
		(start 147.233386 5.729732)
		(end 147.069048 5.61467)
		(width 0.14224)
		(layer "In13.Cu")
		(net "DELTA_L_85_10INCH_IN5_DN")
	)
	(segment
		(start 172.080174 1.23444)
		(end 171.830746 1.590802)
		(width 0.14224)
		(layer "In13.Cu")
		(net "DELTA_L_85_10INCH_IN5_DN")
	)
	(segment
		(start 119.494046 5.729732)
		(end 119.329708 5.61467)
		(width 0.14224)
		(layer "In13.Cu")
		(net "DELTA_L_85_10INCH_IN5_DN")
	)
	(segment
		(start 105.12933 5.363464)
		(end 105.014268 5.527802)
		(width 0.14224)
		(layer "In13.Cu")
		(net "DELTA_L_85_10INCH_IN5_DN")
	)
	(segment
		(start 135.3439 5.723636)
		(end 135.179562 5.608574)
		(width 0.14224)
		(layer "In13.Cu")
		(net "DELTA_L_85_10INCH_IN5_DN")
	)
	(segment
		(start 99.564444 3.382264)
		(end 99.273614 3.091434)
		(width 0.14224)
		(layer "In13.Cu")
		(net "DELTA_L_85_10INCH_IN5_DN")
	)
	(segment
		(start 151.03348 5.624068)
		(end 150.243032 1.145794)
		(width 0.14224)
		(layer "In13.Cu")
		(net "DELTA_L_85_10INCH_IN5_DN")
	)
	(segment
		(start 124.528072 1.242568)
		(end 124.278644 1.598676)
		(width 0.14224)
		(layer "In13.Cu")
		(net "DELTA_L_85_10INCH_IN5_DN")
	)
	(segment
		(start 130.438398 1.198372)
		(end 130.08229 0.948944)
		(width 0.14224)
		(layer "In13.Cu")
		(net "DELTA_L_85_10INCH_IN5_DN")
	)
	(segment
		(start 115.538758 5.771642)
		(end 115.37442 5.65658)
		(width 0.14224)
		(layer "In13.Cu")
		(net "DELTA_L_85_10INCH_IN5_DN")
	)
	(segment
		(start 175.79594 1.604772)
		(end 176.461928 5.378196)
		(width 0.14224)
		(layer "In13.Cu")
		(net "DELTA_L_85_10INCH_IN5_DN")
	)
	(segment
		(start 162.92195 5.624068)
		(end 162.13709 1.178052)
		(width 0.14224)
		(layer "In13.Cu")
		(net "DELTA_L_85_10INCH_IN5_DN")
	)
	(segment
		(start 162.13709 1.178052)
		(end 161.780982 0.928624)
		(width 0.14224)
		(layer "In13.Cu")
		(net "DELTA_L_85_10INCH_IN5_DN")
	)
	(segment
		(start 160.187386 1.210056)
		(end 159.937958 1.566164)
		(width 0.14224)
		(layer "In13.Cu")
		(net "DELTA_L_85_10INCH_IN5_DN")
	)
	(segment
		(start 107.611418 5.761228)
		(end 107.44708 5.646166)
		(width 0.14224)
		(layer "In13.Cu")
		(net "DELTA_L_85_10INCH_IN5_DN")
	)
	(segment
		(start 112.390428 1.598676)
		(end 113.052606 5.350002)
		(width 0.14224)
		(layer "In13.Cu")
		(net "DELTA_L_85_10INCH_IN5_DN")
	)
	(segment
		(start 163.89858 1.554226)
		(end 164.565838 5.334)
		(width 0.14224)
		(layer "In13.Cu")
		(net "DELTA_L_85_10INCH_IN5_DN")
	)
	(segment
		(start 154.20721 1.153668)
		(end 153.851102 0.90424)
		(width 0.14224)
		(layer "In13.Cu")
		(net "DELTA_L_85_10INCH_IN5_DN")
	)
	(segment
		(start 117.018308 5.366512)
		(end 116.903246 5.530596)
		(width 0.14224)
		(layer "In13.Cu")
		(net "DELTA_L_85_10INCH_IN5_DN")
	)
	(segment
		(start 141.974824 0.972312)
		(end 140.381228 1.253744)
		(width 0.14224)
		(layer "In13.Cu")
		(net "DELTA_L_85_10INCH_IN5_DN")
	)
	(segment
		(start 103.485442 5.653786)
		(end 103.172514 3.880612)
		(width 0.14224)
		(layer "In13.Cu")
		(net "DELTA_L_85_10INCH_IN5_DN")
	)
	(segment
		(start 177.994818 1.21666)
		(end 177.638964 0.967232)
		(width 0.14224)
		(layer "In13.Cu")
		(net "DELTA_L_85_10INCH_IN5_DN")
	)
	(segment
		(start 112.937544 5.51434)
		(end 111.573056 5.755386)
		(width 0.14224)
		(layer "In13.Cu")
		(net "DELTA_L_85_10INCH_IN5_DN")
	)
	(segment
		(start 164.565838 5.334)
		(end 164.450776 5.498084)
		(width 0.14224)
		(layer "In13.Cu")
		(net "DELTA_L_85_10INCH_IN5_DN")
	)
	(segment
		(start 152.257506 1.185672)
		(end 152.008078 1.54178)
		(width 0.14224)
		(layer "In13.Cu")
		(net "DELTA_L_85_10INCH_IN5_DN")
	)
	(segment
		(start 171.014136 5.7531)
		(end 170.849798 5.638038)
		(width 0.14224)
		(layer "In13.Cu")
		(net "DELTA_L_85_10INCH_IN5_DN")
	)
	(segment
		(start 139.150598 5.655056)
		(end 138.377168 1.273048)
		(width 0.14224)
		(layer "In13.Cu")
		(net "DELTA_L_85_10INCH_IN5_DN")
	)
	(segment
		(start 144.336262 1.209802)
		(end 144.086834 1.56591)
		(width 0.14224)
		(layer "In13.Cu")
		(net "DELTA_L_85_10INCH_IN5_DN")
	)
	(segment
		(start 128.239266 1.586484)
		(end 128.901952 5.341112)
		(width 0.14224)
		(layer "In13.Cu")
		(net "DELTA_L_85_10INCH_IN5_DN")
	)
	(segment
		(start 131.388358 5.763514)
		(end 131.22402 5.648452)
		(width 0.14224)
		(layer "In13.Cu")
		(net "DELTA_L_85_10INCH_IN5_DN")
	)
	(segment
		(start 135.179562 5.608574)
		(end 134.401306 1.199134)
		(width 0.14224)
		(layer "In13.Cu")
		(net "DELTA_L_85_10INCH_IN5_DN")
	)
	(segment
		(start 152.008078 1.54178)
		(end 152.677368 5.333746)
		(width 0.14224)
		(layer "In13.Cu")
		(net "DELTA_L_85_10INCH_IN5_DN")
	)
	(segment
		(start 157.813502 0.902208)
		(end 156.219906 1.18364)
		(width 0.14224)
		(layer "In13.Cu")
		(net "DELTA_L_85_10INCH_IN5_DN")
	)
	(segment
		(start 104.458262 1.561338)
		(end 105.12933 5.363464)
		(width 0.14224)
		(layer "In13.Cu")
		(net "DELTA_L_85_10INCH_IN5_DN")
	)
	(segment
		(start 145.929858 0.92837)
		(end 144.336262 1.209802)
		(width 0.14224)
		(layer "In13.Cu")
		(net "DELTA_L_85_10INCH_IN5_DN")
	)
	(segment
		(start 151.197818 5.73913)
		(end 151.03348 5.624068)
		(width 0.14224)
		(layer "In13.Cu")
		(net "DELTA_L_85_10INCH_IN5_DN")
	)
	(segment
		(start 132.202174 1.587246)
		(end 132.867908 5.35813)
		(width 0.14224)
		(layer "In13.Cu")
		(net "DELTA_L_85_10INCH_IN5_DN")
	)
	(segment
		(start 106.301286 0.924306)
		(end 104.70769 1.205738)
		(width 0.14224)
		(layer "In13.Cu")
		(net "DELTA_L_85_10INCH_IN5_DN")
	)
	(segment
		(start 174.029624 1.202436)
		(end 173.674024 0.953008)
		(width 0.14224)
		(layer "In13.Cu")
		(net "DELTA_L_85_10INCH_IN5_DN")
	)
	(segment
		(start 155.970478 1.53924)
		(end 156.635958 5.309616)
		(width 0.14224)
		(layer "In13.Cu")
		(net "DELTA_L_85_10INCH_IN5_DN")
	)
	(segment
		(start 114.58956 1.210564)
		(end 114.233452 0.961136)
		(width 0.14224)
		(layer "In13.Cu")
		(net "DELTA_L_85_10INCH_IN5_DN")
	)
	(segment
		(start 120.567704 1.25476)
		(end 120.318276 1.610868)
		(width 0.14224)
		(layer "In13.Cu")
		(net "DELTA_L_85_10INCH_IN5_DN")
	)
	(segment
		(start 132.867908 5.35813)
		(end 132.752846 5.522468)
		(width 0.14224)
		(layer "In13.Cu")
		(net "DELTA_L_85_10INCH_IN5_DN")
	)
	(segment
		(start 153.851102 0.90424)
		(end 152.257506 1.185672)
		(width 0.14224)
		(layer "In13.Cu")
		(net "DELTA_L_85_10INCH_IN5_DN")
	)
	(segment
		(start 174.982378 5.78358)
		(end 174.81804 5.668518)
		(width 0.14224)
		(layer "In13.Cu")
		(net "DELTA_L_85_10INCH_IN5_DN")
	)
	(segment
		(start 128.78689 5.50545)
		(end 127.422402 5.746496)
		(width 0.14224)
		(layer "In13.Cu")
		(net "DELTA_L_85_10INCH_IN5_DN")
	)
	(segment
		(start 122.1613 0.973328)
		(end 120.567704 1.25476)
		(width 0.14224)
		(layer "In13.Cu")
		(net "DELTA_L_85_10INCH_IN5_DN")
	)
	(segment
		(start 120.318276 1.610868)
		(end 120.973596 5.324348)
		(width 0.14224)
		(layer "In13.Cu")
		(net "DELTA_L_85_10INCH_IN5_DN")
	)
	(segment
		(start 118.557294 1.239012)
		(end 118.201186 0.989584)
		(width 0.14224)
		(layer "In13.Cu")
		(net "DELTA_L_85_10INCH_IN5_DN")
	)
	(segment
		(start 140.381228 1.253744)
		(end 140.1318 1.609852)
		(width 0.14224)
		(layer "In13.Cu")
		(net "DELTA_L_85_10INCH_IN5_DN")
	)
	(segment
		(start 127.422402 5.746496)
		(end 127.258064 5.631434)
		(width 0.14224)
		(layer "In13.Cu")
		(net "DELTA_L_85_10INCH_IN5_DN")
	)
	(segment
		(start 180.218588 5.516626)
		(end 178.923696 5.745226)
		(width 0.14224)
		(layer "In13.Cu")
		(net "DELTA_L_85_10INCH_IN5_DN")
	)
	(segment
		(start 154.99207 5.600446)
		(end 154.20721 1.153668)
		(width 0.14224)
		(layer "In13.Cu")
		(net "DELTA_L_85_10INCH_IN5_DN")
	)
	(segment
		(start 164.148008 1.197864)
		(end 163.89858 1.554226)
		(width 0.14224)
		(layer "In13.Cu")
		(net "DELTA_L_85_10INCH_IN5_DN")
	)
	(segment
		(start 124.942854 5.362194)
		(end 124.828046 5.526278)
		(width 0.14224)
		(layer "In13.Cu")
		(net "DELTA_L_85_10INCH_IN5_DN")
	)
	(segment
		(start 167.044624 5.714238)
		(end 166.880286 5.599176)
		(width 0.14224)
		(layer "In13.Cu")
		(net "DELTA_L_85_10INCH_IN5_DN")
	)
	(segment
		(start 152.677368 5.333746)
		(end 152.562306 5.498084)
		(width 0.14224)
		(layer "In13.Cu")
		(net "DELTA_L_85_10INCH_IN5_DN")
	)
	(segment
		(start 176.461928 5.378196)
		(end 176.346866 5.542534)
		(width 0.14224)
		(layer "In13.Cu")
		(net "DELTA_L_85_10INCH_IN5_DN")
	)
	(segment
		(start 170.849798 5.638038)
		(end 170.078908 1.270254)
		(width 0.14224)
		(layer "In13.Cu")
		(net "DELTA_L_85_10INCH_IN5_DN")
	)
	(segment
		(start 128.901952 5.341112)
		(end 128.78689 5.50545)
		(width 0.14224)
		(layer "In13.Cu")
		(net "DELTA_L_85_10INCH_IN5_DN")
	)
	(segment
		(start 136.708388 5.48259)
		(end 135.3439 5.723636)
		(width 0.14224)
		(layer "In13.Cu")
		(net "DELTA_L_85_10INCH_IN5_DN")
	)
	(segment
		(start 109.090968 5.355844)
		(end 108.975906 5.520182)
		(width 0.14224)
		(layer "In13.Cu")
		(net "DELTA_L_85_10INCH_IN5_DN")
	)
	(segment
		(start 140.679424 5.529072)
		(end 139.314936 5.770118)
		(width 0.14224)
		(layer "In13.Cu")
		(net "DELTA_L_85_10INCH_IN5_DN")
	)
	(segment
		(start 118.201186 0.989584)
		(end 116.60759 1.271016)
		(width 0.14224)
		(layer "In13.Cu")
		(net "DELTA_L_85_10INCH_IN5_DN")
	)
	(segment
		(start 120.973596 5.324348)
		(end 120.858534 5.488686)
		(width 0.14224)
		(layer "In13.Cu")
		(net "DELTA_L_85_10INCH_IN5_DN")
	)
	(segment
		(start 168.409112 5.473192)
		(end 167.044624 5.714238)
		(width 0.14224)
		(layer "In13.Cu")
		(net "DELTA_L_85_10INCH_IN5_DN")
	)
	(segment
		(start 174.81804 5.668518)
		(end 174.029624 1.202436)
		(width 0.14224)
		(layer "In13.Cu")
		(net "DELTA_L_85_10INCH_IN5_DN")
	)
	(segment
		(start 124.828046 5.526278)
		(end 123.463558 5.767324)
		(width 0.14224)
		(layer "In13.Cu")
		(net "DELTA_L_85_10INCH_IN5_DN")
	)
	(segment
		(start 177.638964 0.967232)
		(end 176.045368 1.248664)
		(width 0.14224)
		(layer "In13.Cu")
		(net "DELTA_L_85_10INCH_IN5_DN")
	)
	(segment
		(start 123.463558 5.767324)
		(end 123.29922 5.652262)
		(width 0.14224)
		(layer "In13.Cu")
		(net "DELTA_L_85_10INCH_IN5_DN")
	)
	(segment
		(start 178.776122 5.642356)
		(end 177.994818 1.21666)
		(width 0.14224)
		(layer "In13.Cu")
		(net "DELTA_L_85_10INCH_IN5_DN")
	)
	(segment
		(start 104.70769 1.205738)
		(end 104.458262 1.561338)
		(width 0.14224)
		(layer "In13.Cu")
		(net "DELTA_L_85_10INCH_IN5_DN")
	)
	(segment
		(start 139.314936 5.770118)
		(end 139.150598 5.655056)
		(width 0.14224)
		(layer "In13.Cu")
		(net "DELTA_L_85_10INCH_IN5_DN")
	)
	(segment
		(start 158.169864 1.151636)
		(end 157.813502 0.902208)
		(width 0.14224)
		(layer "In13.Cu")
		(net "DELTA_L_85_10INCH_IN5_DN")
	)
	(segment
		(start 156.520896 5.474208)
		(end 155.156408 5.715254)
		(width 0.14224)
		(layer "In13.Cu")
		(net "DELTA_L_85_10INCH_IN5_DN")
	)
	(segment
		(start 114.233452 0.961136)
		(end 112.639856 1.242568)
		(width 0.14224)
		(layer "In13.Cu")
		(net "DELTA_L_85_10INCH_IN5_DN")
	)
	(segment
		(start 134.401306 1.199134)
		(end 134.045198 0.949706)
		(width 0.14224)
		(layer "In13.Cu")
		(net "DELTA_L_85_10INCH_IN5_DN")
	)
	(segment
		(start 172.378624 5.512054)
		(end 171.014136 5.7531)
		(width 0.14224)
		(layer "In13.Cu")
		(net "DELTA_L_85_10INCH_IN5_DN")
	)
	(segment
		(start 116.903246 5.530596)
		(end 115.538758 5.771642)
		(width 0.14224)
		(layer "In13.Cu")
		(net "DELTA_L_85_10INCH_IN5_DN")
	)
	(segment
		(start 115.37442 5.65658)
		(end 114.58956 1.210564)
		(width 0.14224)
		(layer "In13.Cu")
		(net "DELTA_L_85_10INCH_IN5_DN")
	)
	(segment
		(start 163.086288 5.73913)
		(end 162.92195 5.624068)
		(width 0.14224)
		(layer "In13.Cu")
		(net "DELTA_L_85_10INCH_IN5_DN")
	)
	(segment
		(start 123.29922 5.652262)
		(end 122.517408 1.222756)
		(width 0.14224)
		(layer "In13.Cu")
		(net "DELTA_L_85_10INCH_IN5_DN")
	)
	(segment
		(start 116.358162 1.627124)
		(end 117.018308 5.366512)
		(width 0.14224)
		(layer "In13.Cu")
		(net "DELTA_L_85_10INCH_IN5_DN")
	)
	(segment
		(start 103.172514 3.880612)
		(end 102.45979 3.382264)
		(width 0.14224)
		(layer "In13.Cu")
		(net "DELTA_L_85_10INCH_IN5_DN")
	)
	(segment
		(start 110.624366 1.196848)
		(end 110.268258 0.94742)
		(width 0.14224)
		(layer "In13.Cu")
		(net "DELTA_L_85_10INCH_IN5_DN")
	)
	(segment
		(start 155.156408 5.715254)
		(end 154.99207 5.600446)
		(width 0.14224)
		(layer "In13.Cu")
		(net "DELTA_L_85_10INCH_IN5_DN")
	)
	(segment
		(start 113.052606 5.350002)
		(end 112.937544 5.51434)
		(width 0.14224)
		(layer "In13.Cu")
		(net "DELTA_L_85_10INCH_IN5_DN")
	)
	(segment
		(start 110.268258 0.94742)
		(end 108.674662 1.228852)
		(width 0.14224)
		(layer "In13.Cu")
		(net "DELTA_L_85_10INCH_IN5_DN")
	)
	(segment
		(start 105.014268 5.527802)
		(end 103.64978 5.768848)
		(width 0.14224)
		(layer "In13.Cu")
		(net "DELTA_L_85_10INCH_IN5_DN")
	)
	(segment
		(start 178.923696 5.745226)
		(end 178.776122 5.642356)
		(width 0.14224)
		(layer "In13.Cu")
		(net "DELTA_L_85_10INCH_IN5_DN")
	)
	(segment
		(start 149.886924 0.896366)
		(end 148.293328 1.177798)
		(width 0.14224)
		(layer "In13.Cu")
		(net "DELTA_L_85_10INCH_IN5_DN")
	)
	(segment
		(start 169.7228 1.020826)
		(end 168.129204 1.302258)
		(width 0.14224)
		(layer "In13.Cu")
		(net "DELTA_L_85_10INCH_IN5_DN")
	)
	(segment
		(start 148.712936 5.324348)
		(end 148.597874 5.488686)
		(width 0.14224)
		(layer "In13.Cu")
		(net "DELTA_L_85_10INCH_IN5_DN")
	)
	(segment
		(start 103.64978 5.768848)
		(end 103.485442 5.653786)
		(width 0.14224)
		(layer "In13.Cu")
		(net "DELTA_L_85_10INCH_IN5_DN")
	)
	(segment
		(start 126.477776 1.210564)
		(end 126.121668 0.961136)
		(width 0.14224)
		(layer "In13.Cu")
		(net "DELTA_L_85_10INCH_IN5_DN")
	)
	(segment
		(start 159.12719 5.759958)
		(end 158.962852 5.644896)
		(width 0.14224)
		(layer "In13.Cu")
		(net "DELTA_L_85_10INCH_IN5_DN")
	)
	(segment
		(start 116.60759 1.271016)
		(end 116.358162 1.627124)
		(width 0.14224)
		(layer "In13.Cu")
		(net "DELTA_L_85_10INCH_IN5_DN")
	)
	(segment
		(start 108.975906 5.520182)
		(end 107.611418 5.761228)
		(width 0.14224)
		(layer "In13.Cu")
		(net "DELTA_L_85_10INCH_IN5_DN")
	)
	(segment
		(start 299.712888 -2.28727)
		(end 299.060616 -2.105406)
		(width 0.12954)
		(layer "B.Cu")
		(net "DELTA_L_85_10INCH_IN4_DP")
	)
	(segment
		(start 213.297008 -2.28727)
		(end 213.94928 -2.105406)
		(width 0.12954)
		(layer "B.Cu")
		(net "DELTA_L_85_10INCH_IN4_DP")
	)
	(segment
		(start 291.43579 -0.616204)
		(end 290.769802 -4.389628)
		(width 0.14224)
		(layer "In11.Cu")
		(net "DELTA_L_85_10INCH_IN4_DP")
	)
	(segment
		(start 223.399096 -4.40944)
		(end 223.514412 -4.574032)
		(width 0.14224)
		(layer "In11.Cu")
		(net "DELTA_L_85_10INCH_IN4_DP")
	)
	(segment
		(start 247.84177 -0.63627)
		(end 247.176036 -4.407154)
		(width 0.14224)
		(layer "In11.Cu")
		(net "DELTA_L_85_10INCH_IN4_DP")
	)
	(segment
		(start 255.105662 -4.384548)
		(end 255.220978 -4.54914)
		(width 0.14224)
		(layer "In11.Cu")
		(net "DELTA_L_85_10INCH_IN4_DP")
	)
	(segment
		(start 233.747818 -0.281686)
		(end 234.103672 -0.032512)
		(width 0.14224)
		(layer "In11.Cu")
		(net "DELTA_L_85_10INCH_IN4_DP")
	)
	(segment
		(start 228.026468 -0.644398)
		(end 227.36429 -4.395724)
		(width 0.14224)
		(layer "In11.Cu")
		(net "DELTA_L_85_10INCH_IN4_DP")
	)
	(segment
		(start 283.498036 -0.685546)
		(end 282.853638 -4.336034)
		(width 0.14224)
		(layer "In11.Cu")
		(net "DELTA_L_85_10INCH_IN4_DP")
	)
	(segment
		(start 227.777294 -0.288544)
		(end 228.026468 -0.644398)
		(width 0.14224)
		(layer "In11.Cu")
		(net "DELTA_L_85_10INCH_IN4_DP")
	)
	(segment
		(start 247.176036 -4.407154)
		(end 247.291352 -4.571746)
		(width 0.14224)
		(layer "In11.Cu")
		(net "DELTA_L_85_10INCH_IN4_DP")
	)
	(segment
		(start 235.698284 -0.314198)
		(end 235.947458 -0.670052)
		(width 0.14224)
		(layer "In11.Cu")
		(net "DELTA_L_85_10INCH_IN4_DP")
	)
	(segment
		(start 253.924562 0.007874)
		(end 255.519174 -0.273812)
		(width 0.14224)
		(layer "In11.Cu")
		(net "DELTA_L_85_10INCH_IN4_DP")
	)
	(segment
		(start 275.580602 -0.639826)
		(end 274.91182 -4.428236)
		(width 0.14224)
		(layer "In11.Cu")
		(net "DELTA_L_85_10INCH_IN4_DP")
	)
	(segment
		(start 218.259406 0.006604)
		(end 219.854018 -0.275082)
		(width 0.14224)
		(layer "In11.Cu")
		(net "DELTA_L_85_10INCH_IN4_DP")
	)
	(segment
		(start 285.623762 -0.009144)
		(end 287.218374 -0.29083)
		(width 0.14224)
		(layer "In11.Cu")
		(net "DELTA_L_85_10INCH_IN4_DP")
	)
	(segment
		(start 286.804608 -4.403598)
		(end 286.919924 -4.568444)
		(width 0.14224)
		(layer "In11.Cu")
		(net "DELTA_L_85_10INCH_IN4_DP")
	)
	(segment
		(start 224.06483 -0.638556)
		(end 223.399096 -4.40944)
		(width 0.14224)
		(layer "In11.Cu")
		(net "DELTA_L_85_10INCH_IN4_DP")
	)
	(segment
		(start 286.919924 -4.568444)
		(end 288.283396 -4.809236)
		(width 0.14224)
		(layer "In11.Cu")
		(net "DELTA_L_85_10INCH_IN4_DP")
	)
	(segment
		(start 255.519174 -0.273812)
		(end 255.768348 -0.629666)
		(width 0.14224)
		(layer "In11.Cu")
		(net "DELTA_L_85_10INCH_IN4_DP")
	)
	(segment
		(start 271.3609 -0.328676)
		(end 271.60982 -0.684784)
		(width 0.14224)
		(layer "In11.Cu")
		(net "DELTA_L_85_10INCH_IN4_DP")
	)
	(segment
		(start 256.58445 -4.789932)
		(end 256.749042 -4.674616)
		(width 0.14224)
		(layer "In11.Cu")
		(net "DELTA_L_85_10INCH_IN4_DP")
	)
	(segment
		(start 244.856508 -4.697984)
		(end 245.64213 -0.247904)
		(width 0.14224)
		(layer "In11.Cu")
		(net "DELTA_L_85_10INCH_IN4_DP")
	)
	(segment
		(start 284.497018 -4.626102)
		(end 285.267908 -0.258318)
		(width 0.14224)
		(layer "In11.Cu")
		(net "DELTA_L_85_10INCH_IN4_DP")
	)
	(segment
		(start 222.221044 -0.001016)
		(end 223.815656 -0.282702)
		(width 0.14224)
		(layer "In11.Cu")
		(net "DELTA_L_85_10INCH_IN4_DP")
	)
	(segment
		(start 295.523158 -2.259584)
		(end 296.338498 -2.396236)
		(width 0.14224)
		(layer "In11.Cu")
		(net "DELTA_L_85_10INCH_IN4_DP")
	)
	(segment
		(start 243.62664 -0.297434)
		(end 243.875814 -0.653288)
		(width 0.14224)
		(layer "In11.Cu")
		(net "DELTA_L_85_10INCH_IN4_DP")
	)
	(segment
		(start 292.412928 -4.679696)
		(end 293.194486 -0.253746)
		(width 0.14224)
		(layer "In11.Cu")
		(net "DELTA_L_85_10INCH_IN4_DP")
	)
	(segment
		(start 229.79253 -0.239776)
		(end 230.148384 0.009398)
		(width 0.14224)
		(layer "In11.Cu")
		(net "DELTA_L_85_10INCH_IN4_DP")
	)
	(segment
		(start 267.097256 -4.617212)
		(end 268.460728 -4.858004)
		(width 0.14224)
		(layer "In11.Cu")
		(net "DELTA_L_85_10INCH_IN4_DP")
	)
	(segment
		(start 225.042476 -4.699508)
		(end 225.826828 -0.256032)
		(width 0.14224)
		(layer "In11.Cu")
		(net "DELTA_L_85_10INCH_IN4_DP")
	)
	(segment
		(start 281.65425 -0.048006)
		(end 283.248862 -0.329692)
		(width 0.14224)
		(layer "In11.Cu")
		(net "DELTA_L_85_10INCH_IN4_DP")
	)
	(segment
		(start 252.630686 -4.738624)
		(end 252.795278 -4.623308)
		(width 0.14224)
		(layer "In11.Cu")
		(net "DELTA_L_85_10INCH_IN4_DP")
	)
	(segment
		(start 239.252506 -4.395724)
		(end 239.367822 -4.560316)
		(width 0.14224)
		(layer "In11.Cu")
		(net "DELTA_L_85_10INCH_IN4_DP")
	)
	(segment
		(start 239.667796 -0.276606)
		(end 239.916716 -0.632206)
		(width 0.14224)
		(layer "In11.Cu")
		(net "DELTA_L_85_10INCH_IN4_DP")
	)
	(segment
		(start 295.3766 -0.740918)
		(end 295.191434 -1.789176)
		(width 0.14224)
		(layer "In11.Cu")
		(net "DELTA_L_85_10INCH_IN4_DP")
	)
	(segment
		(start 236.935518 -4.6736)
		(end 237.71733 -0.244094)
		(width 0.14224)
		(layer "In11.Cu")
		(net "DELTA_L_85_10INCH_IN4_DP")
	)
	(segment
		(start 231.44734 -4.531868)
		(end 232.810812 -4.77266)
		(width 0.14224)
		(layer "In11.Cu")
		(net "DELTA_L_85_10INCH_IN4_DP")
	)
	(segment
		(start 279.5397 -0.660146)
		(end 278.872442 -4.440174)
		(width 0.14224)
		(layer "In11.Cu")
		(net "DELTA_L_85_10INCH_IN4_DP")
	)
	(segment
		(start 291.186616 -0.26035)
		(end 291.43579 -0.616204)
		(width 0.14224)
		(layer "In11.Cu")
		(net "DELTA_L_85_10INCH_IN4_DP")
	)
	(segment
		(start 281.298396 -0.29718)
		(end 281.65425 -0.048006)
		(width 0.14224)
		(layer "In11.Cu")
		(net "DELTA_L_85_10INCH_IN4_DP")
	)
	(segment
		(start 247.592596 -0.280416)
		(end 247.84177 -0.63627)
		(width 0.14224)
		(layer "In11.Cu")
		(net "DELTA_L_85_10INCH_IN4_DP")
	)
	(segment
		(start 219.432124 -4.432808)
		(end 219.54744 -4.597146)
		(width 0.14224)
		(layer "In11.Cu")
		(net "DELTA_L_85_10INCH_IN4_DP")
	)
	(segment
		(start 271.60982 -0.684784)
		(end 270.94434 -4.454906)
		(width 0.14224)
		(layer "In11.Cu")
		(net "DELTA_L_85_10INCH_IN4_DP")
	)
	(segment
		(start 251.548392 -0.320294)
		(end 251.797312 -0.676402)
		(width 0.14224)
		(layer "In11.Cu")
		(net "DELTA_L_85_10INCH_IN4_DP")
	)
	(segment
		(start 265.45159 -0.272288)
		(end 265.807444 -0.023114)
		(width 0.14224)
		(layer "In11.Cu")
		(net "DELTA_L_85_10INCH_IN4_DP")
	)
	(segment
		(start 255.768348 -0.629666)
		(end 255.105662 -4.384548)
		(width 0.14224)
		(layer "In11.Cu")
		(net "DELTA_L_85_10INCH_IN4_DP")
	)
	(segment
		(start 231.332024 -4.367276)
		(end 231.44734 -4.531868)
		(width 0.14224)
		(layer "In11.Cu")
		(net "DELTA_L_85_10INCH_IN4_DP")
	)
	(segment
		(start 234.103672 -0.032512)
		(end 235.698284 -0.314198)
		(width 0.14224)
		(layer "In11.Cu")
		(net "DELTA_L_85_10INCH_IN4_DP")
	)
	(segment
		(start 268.62532 -4.742688)
		(end 269.41018 -0.295656)
		(width 0.14224)
		(layer "In11.Cu")
		(net "DELTA_L_85_10INCH_IN4_DP")
	)
	(segment
		(start 253.568708 -0.2413)
		(end 253.924562 0.007874)
		(width 0.14224)
		(layer "In11.Cu")
		(net "DELTA_L_85_10INCH_IN4_DP")
	)
	(segment
		(start 273.736816 -0.002286)
		(end 275.331428 -0.283972)
		(width 0.14224)
		(layer "In11.Cu")
		(net "DELTA_L_85_10INCH_IN4_DP")
	)
	(segment
		(start 219.54744 -4.597146)
		(end 220.910912 -4.837938)
		(width 0.14224)
		(layer "In11.Cu")
		(net "DELTA_L_85_10INCH_IN4_DP")
	)
	(segment
		(start 280.515568 -4.730496)
		(end 281.298396 -0.29718)
		(width 0.14224)
		(layer "In11.Cu")
		(net "DELTA_L_85_10INCH_IN4_DP")
	)
	(segment
		(start 276.5552 -4.718304)
		(end 277.34006 -0.272288)
		(width 0.14224)
		(layer "In11.Cu")
		(net "DELTA_L_85_10INCH_IN4_DP")
	)
	(segment
		(start 251.797312 -0.676402)
		(end 251.151898 -4.33324)
		(width 0.14224)
		(layer "In11.Cu")
		(net "DELTA_L_85_10INCH_IN4_DP")
	)
	(segment
		(start 235.407454 -4.548124)
		(end 236.770926 -4.788916)
		(width 0.14224)
		(layer "In11.Cu")
		(net "DELTA_L_85_10INCH_IN4_DP")
	)
	(segment
		(start 227.36429 -4.395724)
		(end 227.479606 -4.560316)
		(width 0.14224)
		(layer "In11.Cu")
		(net "DELTA_L_85_10INCH_IN4_DP")
	)
	(segment
		(start 261.487158 -0.281686)
		(end 261.843012 -0.032512)
		(width 0.14224)
		(layer "In11.Cu")
		(net "DELTA_L_85_10INCH_IN4_DP")
	)
	(segment
		(start 232.810812 -4.77266)
		(end 232.975404 -4.657344)
		(width 0.14224)
		(layer "In11.Cu")
		(net "DELTA_L_85_10INCH_IN4_DP")
	)
	(segment
		(start 284.332426 -4.741418)
		(end 284.497018 -4.626102)
		(width 0.14224)
		(layer "In11.Cu")
		(net "DELTA_L_85_10INCH_IN4_DP")
	)
	(segment
		(start 226.182682 -0.006858)
		(end 227.777294 -0.288544)
		(width 0.14224)
		(layer "In11.Cu")
		(net "DELTA_L_85_10INCH_IN4_DP")
	)
	(segment
		(start 283.248862 -0.329692)
		(end 283.498036 -0.685546)
		(width 0.14224)
		(layer "In11.Cu")
		(net "DELTA_L_85_10INCH_IN4_DP")
	)
	(segment
		(start 269.41018 -0.295656)
		(end 269.766288 -0.04699)
		(width 0.14224)
		(layer "In11.Cu")
		(net "DELTA_L_85_10INCH_IN4_DP")
	)
	(segment
		(start 231.99217 -0.627634)
		(end 231.332024 -4.367276)
		(width 0.14224)
		(layer "In11.Cu")
		(net "DELTA_L_85_10INCH_IN4_DP")
	)
	(segment
		(start 275.331428 -0.283972)
		(end 275.580602 -0.639826)
		(width 0.14224)
		(layer "In11.Cu")
		(net "DELTA_L_85_10INCH_IN4_DP")
	)
	(segment
		(start 223.815656 -0.282702)
		(end 224.06483 -0.638556)
		(width 0.14224)
		(layer "In11.Cu")
		(net "DELTA_L_85_10INCH_IN4_DP")
	)
	(segment
		(start 223.514412 -4.574032)
		(end 224.877884 -4.814824)
		(width 0.14224)
		(layer "In11.Cu")
		(net "DELTA_L_85_10INCH_IN4_DP")
	)
	(segment
		(start 242.032028 -0.015748)
		(end 243.62664 -0.297434)
		(width 0.14224)
		(layer "In11.Cu")
		(net "DELTA_L_85_10INCH_IN4_DP")
	)
	(segment
		(start 228.843078 -4.801108)
		(end 229.00767 -4.685792)
		(width 0.14224)
		(layer "In11.Cu")
		(net "DELTA_L_85_10INCH_IN4_DP")
	)
	(segment
		(start 238.073184 0.00508)
		(end 239.667796 -0.276606)
		(width 0.14224)
		(layer "In11.Cu")
		(net "DELTA_L_85_10INCH_IN4_DP")
	)
	(segment
		(start 287.467548 -0.646684)
		(end 286.804608 -4.403598)
		(width 0.14224)
		(layer "In11.Cu")
		(net "DELTA_L_85_10INCH_IN4_DP")
	)
	(segment
		(start 259.472684 -0.326644)
		(end 259.721858 -0.682498)
		(width 0.14224)
		(layer "In11.Cu")
		(net "DELTA_L_85_10INCH_IN4_DP")
	)
	(segment
		(start 276.390608 -4.83362)
		(end 276.5552 -4.718304)
		(width 0.14224)
		(layer "In11.Cu")
		(net "DELTA_L_85_10INCH_IN4_DP")
	)
	(segment
		(start 263.133078 -4.625086)
		(end 264.49655 -4.865878)
		(width 0.14224)
		(layer "In11.Cu")
		(net "DELTA_L_85_10INCH_IN4_DP")
	)
	(segment
		(start 255.220978 -4.54914)
		(end 256.58445 -4.789932)
		(width 0.14224)
		(layer "In11.Cu")
		(net "DELTA_L_85_10INCH_IN4_DP")
	)
	(segment
		(start 263.686798 -0.670052)
		(end 263.017762 -4.460494)
		(width 0.14224)
		(layer "In11.Cu")
		(net "DELTA_L_85_10INCH_IN4_DP")
	)
	(segment
		(start 275.027136 -4.592828)
		(end 276.390608 -4.83362)
		(width 0.14224)
		(layer "In11.Cu")
		(net "DELTA_L_85_10INCH_IN4_DP")
	)
	(segment
		(start 270.94434 -4.454906)
		(end 271.059656 -4.619244)
		(width 0.14224)
		(layer "In11.Cu")
		(net "DELTA_L_85_10INCH_IN4_DP")
	)
	(segment
		(start 231.742996 -0.272288)
		(end 231.99217 -0.627634)
		(width 0.14224)
		(layer "In11.Cu")
		(net "DELTA_L_85_10INCH_IN4_DP")
	)
	(segment
		(start 221.075758 -4.722622)
		(end 221.86519 -0.25019)
		(width 0.14224)
		(layer "In11.Cu")
		(net "DELTA_L_85_10INCH_IN4_DP")
	)
	(segment
		(start 257.522218 -0.294132)
		(end 257.878072 -0.044958)
		(width 0.14224)
		(layer "In11.Cu")
		(net "DELTA_L_85_10INCH_IN4_DP")
	)
	(segment
		(start 259.176012 -4.593082)
		(end 260.539484 -4.833874)
		(width 0.14224)
		(layer "In11.Cu")
		(net "DELTA_L_85_10INCH_IN4_DP")
	)
	(segment
		(start 285.267908 -0.258318)
		(end 285.623762 -0.009144)
		(width 0.14224)
		(layer "In11.Cu")
		(net "DELTA_L_85_10INCH_IN4_DP")
	)
	(segment
		(start 213.94928 -2.105406)
		(end 214.24011 -2.396236)
		(width 0.14224)
		(layer "In11.Cu")
		(net "DELTA_L_85_10INCH_IN4_DP")
	)
	(segment
		(start 260.704076 -4.718558)
		(end 261.487158 -0.281686)
		(width 0.14224)
		(layer "In11.Cu")
		(net "DELTA_L_85_10INCH_IN4_DP")
	)
	(segment
		(start 278.872442 -4.440174)
		(end 278.987758 -4.60502)
		(width 0.14224)
		(layer "In11.Cu")
		(net "DELTA_L_85_10INCH_IN4_DP")
	)
	(segment
		(start 235.292138 -4.383532)
		(end 235.407454 -4.548124)
		(width 0.14224)
		(layer "In11.Cu")
		(net "DELTA_L_85_10INCH_IN4_DP")
	)
	(segment
		(start 273.380962 -0.25146)
		(end 273.736816 -0.002286)
		(width 0.14224)
		(layer "In11.Cu")
		(net "DELTA_L_85_10INCH_IN4_DP")
	)
	(segment
		(start 295.191434 -1.789176)
		(end 295.523158 -2.259584)
		(width 0.14224)
		(layer "In11.Cu")
		(net "DELTA_L_85_10INCH_IN4_DP")
	)
	(segment
		(start 224.877884 -4.814824)
		(end 225.042476 -4.699508)
		(width 0.14224)
		(layer "In11.Cu")
		(net "DELTA_L_85_10INCH_IN4_DP")
	)
	(segment
		(start 295.058338 -0.286258)
		(end 295.3766 -0.740918)
		(width 0.14224)
		(layer "In11.Cu")
		(net "DELTA_L_85_10INCH_IN4_DP")
	)
	(segment
		(start 241.676174 -0.264922)
		(end 242.032028 -0.015748)
		(width 0.14224)
		(layer "In11.Cu")
		(net "DELTA_L_85_10INCH_IN4_DP")
	)
	(segment
		(start 267.65123 -0.660654)
		(end 266.98194 -4.45262)
		(width 0.14224)
		(layer "In11.Cu")
		(net "DELTA_L_85_10INCH_IN4_DP")
	)
	(segment
		(start 296.338498 -2.396236)
		(end 298.769786 -2.396236)
		(width 0.14224)
		(layer "In11.Cu")
		(net "DELTA_L_85_10INCH_IN4_DP")
	)
	(segment
		(start 240.731294 -4.801108)
		(end 240.895886 -4.685792)
		(width 0.14224)
		(layer "In11.Cu")
		(net "DELTA_L_85_10INCH_IN4_DP")
	)
	(segment
		(start 248.819416 -4.697222)
		(end 249.597672 -0.287782)
		(width 0.14224)
		(layer "In11.Cu")
		(net "DELTA_L_85_10INCH_IN4_DP")
	)
	(segment
		(start 263.017762 -4.460494)
		(end 263.133078 -4.625086)
		(width 0.14224)
		(layer "In11.Cu")
		(net "DELTA_L_85_10INCH_IN4_DP")
	)
	(segment
		(start 274.91182 -4.428236)
		(end 275.027136 -4.592828)
		(width 0.14224)
		(layer "In11.Cu")
		(net "DELTA_L_85_10INCH_IN4_DP")
	)
	(segment
		(start 245.64213 -0.247904)
		(end 245.997984 0.00127)
		(width 0.14224)
		(layer "In11.Cu")
		(net "DELTA_L_85_10INCH_IN4_DP")
	)
	(segment
		(start 290.885118 -4.55422)
		(end 292.24859 -4.795012)
		(width 0.14224)
		(layer "In11.Cu")
		(net "DELTA_L_85_10INCH_IN4_DP")
	)
	(segment
		(start 243.328444 -4.572508)
		(end 244.691916 -4.8133)
		(width 0.14224)
		(layer "In11.Cu")
		(net "DELTA_L_85_10INCH_IN4_DP")
	)
	(segment
		(start 239.916716 -0.632206)
		(end 239.252506 -4.395724)
		(width 0.14224)
		(layer "In11.Cu")
		(net "DELTA_L_85_10INCH_IN4_DP")
	)
	(segment
		(start 227.479606 -4.560316)
		(end 228.843078 -4.801108)
		(width 0.14224)
		(layer "In11.Cu")
		(net "DELTA_L_85_10INCH_IN4_DP")
	)
	(segment
		(start 214.24011 -2.396236)
		(end 217.046556 -2.396236)
		(width 0.14224)
		(layer "In11.Cu")
		(net "DELTA_L_85_10INCH_IN4_DP")
	)
	(segment
		(start 249.597672 -0.287782)
		(end 249.953526 -0.038608)
		(width 0.14224)
		(layer "In11.Cu")
		(net "DELTA_L_85_10INCH_IN4_DP")
	)
	(segment
		(start 235.947458 -0.670052)
		(end 235.292138 -4.383532)
		(width 0.14224)
		(layer "In11.Cu")
		(net "DELTA_L_85_10INCH_IN4_DP")
	)
	(segment
		(start 279.290526 -0.3048)
		(end 279.5397 -0.660146)
		(width 0.14224)
		(layer "In11.Cu")
		(net "DELTA_L_85_10INCH_IN4_DP")
	)
	(segment
		(start 288.447734 -4.69392)
		(end 289.23615 -0.227838)
		(width 0.14224)
		(layer "In11.Cu")
		(net "DELTA_L_85_10INCH_IN4_DP")
	)
	(segment
		(start 239.367822 -4.560316)
		(end 240.731294 -4.801108)
		(width 0.14224)
		(layer "In11.Cu")
		(net "DELTA_L_85_10INCH_IN4_DP")
	)
	(segment
		(start 272.587974 -4.74472)
		(end 273.380962 -0.25146)
		(width 0.14224)
		(layer "In11.Cu")
		(net "DELTA_L_85_10INCH_IN4_DP")
	)
	(segment
		(start 290.769802 -4.389628)
		(end 290.885118 -4.55422)
		(width 0.14224)
		(layer "In11.Cu")
		(net "DELTA_L_85_10INCH_IN4_DP")
	)
	(segment
		(start 267.402056 -0.3048)
		(end 267.65123 -0.660654)
		(width 0.14224)
		(layer "In11.Cu")
		(net "DELTA_L_85_10INCH_IN4_DP")
	)
	(segment
		(start 280.35123 -4.845812)
		(end 280.515568 -4.730496)
		(width 0.14224)
		(layer "In11.Cu")
		(net "DELTA_L_85_10INCH_IN4_DP")
	)
	(segment
		(start 256.749042 -4.674616)
		(end 257.522218 -0.294132)
		(width 0.14224)
		(layer "In11.Cu")
		(net "DELTA_L_85_10INCH_IN4_DP")
	)
	(segment
		(start 263.437624 -0.314198)
		(end 263.686798 -0.670052)
		(width 0.14224)
		(layer "In11.Cu")
		(net "DELTA_L_85_10INCH_IN4_DP")
	)
	(segment
		(start 229.00767 -4.685792)
		(end 229.79253 -0.239776)
		(width 0.14224)
		(layer "In11.Cu")
		(net "DELTA_L_85_10INCH_IN4_DP")
	)
	(segment
		(start 272.423128 -4.860036)
		(end 272.587974 -4.74472)
		(width 0.14224)
		(layer "In11.Cu")
		(net "DELTA_L_85_10INCH_IN4_DP")
	)
	(segment
		(start 298.769786 -2.396236)
		(end 299.060616 -2.105406)
		(width 0.14224)
		(layer "In11.Cu")
		(net "DELTA_L_85_10INCH_IN4_DP")
	)
	(segment
		(start 251.151898 -4.33324)
		(end 251.267214 -4.497832)
		(width 0.14224)
		(layer "In11.Cu")
		(net "DELTA_L_85_10INCH_IN4_DP")
	)
	(segment
		(start 245.997984 0.00127)
		(end 247.592596 -0.280416)
		(width 0.14224)
		(layer "In11.Cu")
		(net "DELTA_L_85_10INCH_IN4_DP")
	)
	(segment
		(start 265.807444 -0.023114)
		(end 267.402056 -0.3048)
		(width 0.14224)
		(layer "In11.Cu")
		(net "DELTA_L_85_10INCH_IN4_DP")
	)
	(segment
		(start 266.98194 -4.45262)
		(end 267.097256 -4.617212)
		(width 0.14224)
		(layer "In11.Cu")
		(net "DELTA_L_85_10INCH_IN4_DP")
	)
	(segment
		(start 261.843012 -0.032512)
		(end 263.437624 -0.314198)
		(width 0.14224)
		(layer "In11.Cu")
		(net "DELTA_L_85_10INCH_IN4_DP")
	)
	(segment
		(start 278.987758 -4.60502)
		(end 280.35123 -4.845812)
		(width 0.14224)
		(layer "In11.Cu")
		(net "DELTA_L_85_10INCH_IN4_DP")
	)
	(segment
		(start 264.661142 -4.750562)
		(end 265.45159 -0.272288)
		(width 0.14224)
		(layer "In11.Cu")
		(net "DELTA_L_85_10INCH_IN4_DP")
	)
	(segment
		(start 287.218374 -0.29083)
		(end 287.467548 -0.646684)
		(width 0.14224)
		(layer "In11.Cu")
		(net "DELTA_L_85_10INCH_IN4_DP")
	)
	(segment
		(start 293.194486 -0.253746)
		(end 293.533576 -0.017272)
		(width 0.14224)
		(layer "In11.Cu")
		(net "DELTA_L_85_10INCH_IN4_DP")
	)
	(segment
		(start 282.853638 -4.336034)
		(end 282.968954 -4.500626)
		(width 0.14224)
		(layer "In11.Cu")
		(net "DELTA_L_85_10INCH_IN4_DP")
	)
	(segment
		(start 259.721858 -0.682498)
		(end 259.060696 -4.42849)
		(width 0.14224)
		(layer "In11.Cu")
		(net "DELTA_L_85_10INCH_IN4_DP")
	)
	(segment
		(start 236.770926 -4.788916)
		(end 236.935518 -4.6736)
		(width 0.14224)
		(layer "In11.Cu")
		(net "DELTA_L_85_10INCH_IN4_DP")
	)
	(segment
		(start 257.878072 -0.044958)
		(end 259.472684 -0.326644)
		(width 0.14224)
		(layer "In11.Cu")
		(net "DELTA_L_85_10INCH_IN4_DP")
	)
	(segment
		(start 219.854018 -0.275082)
		(end 220.103192 -0.630936)
		(width 0.14224)
		(layer "In11.Cu")
		(net "DELTA_L_85_10INCH_IN4_DP")
	)
	(segment
		(start 217.590624 -2.01549)
		(end 217.903552 -0.24257)
		(width 0.14224)
		(layer "In11.Cu")
		(net "DELTA_L_85_10INCH_IN4_DP")
	)
	(segment
		(start 232.975404 -4.657344)
		(end 233.747818 -0.281686)
		(width 0.14224)
		(layer "In11.Cu")
		(net "DELTA_L_85_10INCH_IN4_DP")
	)
	(segment
		(start 288.283396 -4.809236)
		(end 288.447734 -4.69392)
		(width 0.14224)
		(layer "In11.Cu")
		(net "DELTA_L_85_10INCH_IN4_DP")
	)
	(segment
		(start 237.71733 -0.244094)
		(end 238.073184 0.00508)
		(width 0.14224)
		(layer "In11.Cu")
		(net "DELTA_L_85_10INCH_IN4_DP")
	)
	(segment
		(start 248.654824 -4.812538)
		(end 248.819416 -4.697222)
		(width 0.14224)
		(layer "In11.Cu")
		(net "DELTA_L_85_10INCH_IN4_DP")
	)
	(segment
		(start 289.592004 0.021336)
		(end 291.186616 -0.26035)
		(width 0.14224)
		(layer "In11.Cu")
		(net "DELTA_L_85_10INCH_IN4_DP")
	)
	(segment
		(start 244.691916 -4.8133)
		(end 244.856508 -4.697984)
		(width 0.14224)
		(layer "In11.Cu")
		(net "DELTA_L_85_10INCH_IN4_DP")
	)
	(segment
		(start 251.267214 -4.497832)
		(end 252.630686 -4.738624)
		(width 0.14224)
		(layer "In11.Cu")
		(net "DELTA_L_85_10INCH_IN4_DP")
	)
	(segment
		(start 230.148384 0.009398)
		(end 231.742996 -0.272288)
		(width 0.14224)
		(layer "In11.Cu")
		(net "DELTA_L_85_10INCH_IN4_DP")
	)
	(segment
		(start 282.968954 -4.500626)
		(end 284.332426 -4.741418)
		(width 0.14224)
		(layer "In11.Cu")
		(net "DELTA_L_85_10INCH_IN4_DP")
	)
	(segment
		(start 293.533576 -0.017272)
		(end 295.058338 -0.286258)
		(width 0.14224)
		(layer "In11.Cu")
		(net "DELTA_L_85_10INCH_IN4_DP")
	)
	(segment
		(start 221.86519 -0.25019)
		(end 222.221044 -0.001016)
		(width 0.14224)
		(layer "In11.Cu")
		(net "DELTA_L_85_10INCH_IN4_DP")
	)
	(segment
		(start 240.895886 -4.685792)
		(end 241.676174 -0.264922)
		(width 0.14224)
		(layer "In11.Cu")
		(net "DELTA_L_85_10INCH_IN4_DP")
	)
	(segment
		(start 243.875814 -0.653288)
		(end 243.213128 -4.407916)
		(width 0.14224)
		(layer "In11.Cu")
		(net "DELTA_L_85_10INCH_IN4_DP")
	)
	(segment
		(start 220.910912 -4.837938)
		(end 221.075758 -4.722622)
		(width 0.14224)
		(layer "In11.Cu")
		(net "DELTA_L_85_10INCH_IN4_DP")
	)
	(segment
		(start 217.903552 -0.24257)
		(end 218.259406 0.006604)
		(width 0.14224)
		(layer "In11.Cu")
		(net "DELTA_L_85_10INCH_IN4_DP")
	)
	(segment
		(start 271.059656 -4.619244)
		(end 272.423128 -4.860036)
		(width 0.14224)
		(layer "In11.Cu")
		(net "DELTA_L_85_10INCH_IN4_DP")
	)
	(segment
		(start 264.49655 -4.865878)
		(end 264.661142 -4.750562)
		(width 0.14224)
		(layer "In11.Cu")
		(net "DELTA_L_85_10INCH_IN4_DP")
	)
	(segment
		(start 225.826828 -0.256032)
		(end 226.182682 -0.006858)
		(width 0.14224)
		(layer "In11.Cu")
		(net "DELTA_L_85_10INCH_IN4_DP")
	)
	(segment
		(start 260.539484 -4.833874)
		(end 260.704076 -4.718558)
		(width 0.14224)
		(layer "In11.Cu")
		(net "DELTA_L_85_10INCH_IN4_DP")
	)
	(segment
		(start 243.213128 -4.407916)
		(end 243.328444 -4.572508)
		(width 0.14224)
		(layer "In11.Cu")
		(net "DELTA_L_85_10INCH_IN4_DP")
	)
	(segment
		(start 268.460728 -4.858004)
		(end 268.62532 -4.742688)
		(width 0.14224)
		(layer "In11.Cu")
		(net "DELTA_L_85_10INCH_IN4_DP")
	)
	(segment
		(start 259.060696 -4.42849)
		(end 259.176012 -4.593082)
		(width 0.14224)
		(layer "In11.Cu")
		(net "DELTA_L_85_10INCH_IN4_DP")
	)
	(segment
		(start 277.695914 -0.023114)
		(end 279.290526 -0.3048)
		(width 0.14224)
		(layer "In11.Cu")
		(net "DELTA_L_85_10INCH_IN4_DP")
	)
	(segment
		(start 269.766288 -0.04699)
		(end 271.3609 -0.328676)
		(width 0.14224)
		(layer "In11.Cu")
		(net "DELTA_L_85_10INCH_IN4_DP")
	)
	(segment
		(start 277.34006 -0.272288)
		(end 277.695914 -0.023114)
		(width 0.14224)
		(layer "In11.Cu")
		(net "DELTA_L_85_10INCH_IN4_DP")
	)
	(segment
		(start 289.23615 -0.227838)
		(end 289.592004 0.021336)
		(width 0.14224)
		(layer "In11.Cu")
		(net "DELTA_L_85_10INCH_IN4_DP")
	)
	(segment
		(start 249.953526 -0.038608)
		(end 251.548392 -0.320294)
		(width 0.14224)
		(layer "In11.Cu")
		(net "DELTA_L_85_10INCH_IN4_DP")
	)
	(segment
		(start 292.24859 -4.795012)
		(end 292.412928 -4.679696)
		(width 0.14224)
		(layer "In11.Cu")
		(net "DELTA_L_85_10INCH_IN4_DP")
	)
	(segment
		(start 220.103192 -0.630936)
		(end 219.432124 -4.432808)
		(width 0.14224)
		(layer "In11.Cu")
		(net "DELTA_L_85_10INCH_IN4_DP")
	)
	(segment
		(start 217.046556 -2.396236)
		(end 217.590624 -2.01549)
		(width 0.14224)
		(layer "In11.Cu")
		(net "DELTA_L_85_10INCH_IN4_DP")
	)
	(segment
		(start 252.795278 -4.623308)
		(end 253.568708 -0.2413)
		(width 0.14224)
		(layer "In11.Cu")
		(net "DELTA_L_85_10INCH_IN4_DP")
	)
	(segment
		(start 247.291352 -4.571746)
		(end 248.654824 -4.812538)
		(width 0.14224)
		(layer "In11.Cu")
		(net "DELTA_L_85_10INCH_IN4_DP")
	)
	(segment
		(start 299.712888 -2.787142)
		(end 299.060616 -2.969006)
		(width 0.12954)
		(layer "B.Cu")
		(net "DELTA_L_85_10INCH_IN4_DN")
	)
	(segment
		(start 213.297008 -2.787142)
		(end 213.94928 -2.969006)
		(width 0.12954)
		(layer "B.Cu")
		(net "DELTA_L_85_10INCH_IN4_DN")
	)
	(segment
		(start 281.555952 -0.461264)
		(end 280.773124 -4.89458)
		(width 0.14224)
		(layer "In11.Cu")
		(net "DELTA_L_85_10INCH_IN4_DN")
	)
	(segment
		(start 218.325446 -0.291592)
		(end 218.161108 -0.406654)
		(width 0.14224)
		(layer "In11.Cu")
		(net "DELTA_L_85_10INCH_IN4_DN")
	)
	(segment
		(start 287.169352 -0.712724)
		(end 287.05429 -0.548386)
		(width 0.14224)
		(layer "In11.Cu")
		(net "DELTA_L_85_10INCH_IN4_DN")
	)
	(segment
		(start 226.248722 -0.305054)
		(end 226.084384 -0.420116)
		(width 0.14224)
		(layer "In11.Cu")
		(net "DELTA_L_85_10INCH_IN4_DN")
	)
	(segment
		(start 262.968994 -4.882642)
		(end 262.719566 -4.526534)
		(width 0.14224)
		(layer "In11.Cu")
		(net "DELTA_L_85_10INCH_IN4_DN")
	)
	(segment
		(start 295.078404 -0.806958)
		(end 294.894254 -0.543814)
		(width 0.14224)
		(layer "In11.Cu")
		(net "DELTA_L_85_10INCH_IN4_DN")
	)
	(segment
		(start 237.974886 -0.408178)
		(end 237.193074 -4.837684)
		(width 0.14224)
		(layer "In11.Cu")
		(net "DELTA_L_85_10INCH_IN4_DN")
	)
	(segment
		(start 275.167344 -0.541528)
		(end 273.802856 -0.300482)
		(width 0.14224)
		(layer "In11.Cu")
		(net "DELTA_L_85_10INCH_IN4_DN")
	)
	(segment
		(start 242.914932 -4.473956)
		(end 243.577618 -0.719328)
		(width 0.14224)
		(layer "In11.Cu")
		(net "DELTA_L_85_10INCH_IN4_DN")
	)
	(segment
		(start 299.060616 -2.969006)
		(end 298.769786 -2.678176)
		(width 0.14224)
		(layer "In11.Cu")
		(net "DELTA_L_85_10INCH_IN4_DN")
	)
	(segment
		(start 243.16436 -4.830064)
		(end 242.914932 -4.473956)
		(width 0.14224)
		(layer "In11.Cu")
		(net "DELTA_L_85_10INCH_IN4_DN")
	)
	(segment
		(start 257.944112 -0.343154)
		(end 257.779774 -0.458216)
		(width 0.14224)
		(layer "In11.Cu")
		(net "DELTA_L_85_10INCH_IN4_DN")
	)
	(segment
		(start 289.658044 -0.27686)
		(end 289.493706 -0.391922)
		(width 0.14224)
		(layer "In11.Cu")
		(net "DELTA_L_85_10INCH_IN4_DN")
	)
	(segment
		(start 270.646144 -4.5212)
		(end 271.311624 -0.750824)
		(width 0.14224)
		(layer "In11.Cu")
		(net "DELTA_L_85_10INCH_IN4_DN")
	)
	(segment
		(start 219.689934 -0.532638)
		(end 218.325446 -0.291592)
		(width 0.14224)
		(layer "In11.Cu")
		(net "DELTA_L_85_10INCH_IN4_DN")
	)
	(segment
		(start 227.61321 -0.5461)
		(end 226.248722 -0.305054)
		(width 0.14224)
		(layer "In11.Cu")
		(net "DELTA_L_85_10INCH_IN4_DN")
	)
	(segment
		(start 248.720864 -5.110734)
		(end 247.127268 -4.829302)
		(width 0.14224)
		(layer "In11.Cu")
		(net "DELTA_L_85_10INCH_IN4_DN")
	)
	(segment
		(start 217.135456 -2.678176)
		(end 214.24011 -2.678176)
		(width 0.14224)
		(layer "In11.Cu")
		(net "DELTA_L_85_10INCH_IN4_DN")
	)
	(segment
		(start 223.651572 -0.540258)
		(end 222.287084 -0.299212)
		(width 0.14224)
		(layer "In11.Cu")
		(net "DELTA_L_85_10INCH_IN4_DN")
	)
	(segment
		(start 238.95431 -4.461764)
		(end 239.61852 -0.698246)
		(width 0.14224)
		(layer "In11.Cu")
		(net "DELTA_L_85_10INCH_IN4_DN")
	)
	(segment
		(start 231.578912 -0.529844)
		(end 230.214424 -0.288798)
		(width 0.14224)
		(layer "In11.Cu")
		(net "DELTA_L_85_10INCH_IN4_DN")
	)
	(segment
		(start 234.993942 -4.449572)
		(end 235.649262 -0.736092)
		(width 0.14224)
		(layer "In11.Cu")
		(net "DELTA_L_85_10INCH_IN4_DN")
	)
	(segment
		(start 240.797334 -5.099304)
		(end 239.203738 -4.817872)
		(width 0.14224)
		(layer "In11.Cu")
		(net "DELTA_L_85_10INCH_IN4_DN")
	)
	(segment
		(start 267.237972 -0.562356)
		(end 265.873484 -0.32131)
		(width 0.14224)
		(layer "In11.Cu")
		(net "DELTA_L_85_10INCH_IN4_DN")
	)
	(segment
		(start 251.499116 -0.742442)
		(end 251.384054 -0.57785)
		(width 0.14224)
		(layer "In11.Cu")
		(net "DELTA_L_85_10INCH_IN4_DN")
	)
	(segment
		(start 278.823674 -4.862576)
		(end 278.574246 -4.506214)
		(width 0.14224)
		(layer "In11.Cu")
		(net "DELTA_L_85_10INCH_IN4_DN")
	)
	(segment
		(start 284.398466 -5.039614)
		(end 282.80487 -4.758182)
		(width 0.14224)
		(layer "In11.Cu")
		(net "DELTA_L_85_10INCH_IN4_DN")
	)
	(segment
		(start 264.56259 -5.164074)
		(end 262.968994 -4.882642)
		(width 0.14224)
		(layer "In11.Cu")
		(net "DELTA_L_85_10INCH_IN4_DN")
	)
	(segment
		(start 241.93373 -0.429006)
		(end 241.153442 -4.849876)
		(width 0.14224)
		(layer "In11.Cu")
		(net "DELTA_L_85_10INCH_IN4_DN")
	)
	(segment
		(start 269.667736 -0.459994)
		(end 268.882876 -4.906772)
		(width 0.14224)
		(layer "In11.Cu")
		(net "DELTA_L_85_10INCH_IN4_DN")
	)
	(segment
		(start 282.555442 -4.402074)
		(end 283.19984 -0.751586)
		(width 0.14224)
		(layer "In11.Cu")
		(net "DELTA_L_85_10INCH_IN4_DN")
	)
	(segment
		(start 225.300032 -4.863592)
		(end 224.943924 -5.11302)
		(width 0.14224)
		(layer "In11.Cu")
		(net "DELTA_L_85_10INCH_IN4_DN")
	)
	(segment
		(start 249.076972 -4.861306)
		(end 248.720864 -5.110734)
		(width 0.14224)
		(layer "In11.Cu")
		(net "DELTA_L_85_10INCH_IN4_DN")
	)
	(segment
		(start 238.139224 -0.293116)
		(end 237.974886 -0.408178)
		(width 0.14224)
		(layer "In11.Cu")
		(net "DELTA_L_85_10INCH_IN4_DN")
	)
	(segment
		(start 277.597616 -0.436372)
		(end 276.812756 -4.882388)
		(width 0.14224)
		(layer "In11.Cu")
		(net "DELTA_L_85_10INCH_IN4_DN")
	)
	(segment
		(start 289.493706 -0.391922)
		(end 288.70529 -4.858004)
		(width 0.14224)
		(layer "In11.Cu")
		(net "DELTA_L_85_10INCH_IN4_DN")
	)
	(segment
		(start 274.613624 -4.494276)
		(end 275.282406 -0.705866)
		(width 0.14224)
		(layer "In11.Cu")
		(net "DELTA_L_85_10INCH_IN4_DN")
	)
	(segment
		(start 231.283256 -4.789424)
		(end 231.033828 -4.433316)
		(width 0.14224)
		(layer "In11.Cu")
		(net "DELTA_L_85_10INCH_IN4_DN")
	)
	(segment
		(start 275.282406 -0.705866)
		(end 275.167344 -0.541528)
		(width 0.14224)
		(layer "In11.Cu")
		(net "DELTA_L_85_10INCH_IN4_DN")
	)
	(segment
		(start 226.084384 -0.420116)
		(end 225.300032 -4.863592)
		(width 0.14224)
		(layer "In11.Cu")
		(net "DELTA_L_85_10INCH_IN4_DN")
	)
	(segment
		(start 236.836966 -5.087112)
		(end 235.24337 -4.80568)
		(width 0.14224)
		(layer "In11.Cu")
		(net "DELTA_L_85_10INCH_IN4_DN")
	)
	(segment
		(start 247.428512 -0.537972)
		(end 246.064024 -0.296926)
		(width 0.14224)
		(layer "In11.Cu")
		(net "DELTA_L_85_10INCH_IN4_DN")
	)
	(segment
		(start 217.84818 -2.179828)
		(end 217.135456 -2.678176)
		(width 0.14224)
		(layer "In11.Cu")
		(net "DELTA_L_85_10INCH_IN4_DN")
	)
	(segment
		(start 279.126442 -0.562356)
		(end 277.761954 -0.32131)
		(width 0.14224)
		(layer "In11.Cu")
		(net "DELTA_L_85_10INCH_IN4_DN")
	)
	(segment
		(start 294.894254 -0.543814)
		(end 293.599362 -0.315214)
		(width 0.14224)
		(layer "In11.Cu")
		(net "DELTA_L_85_10INCH_IN4_DN")
	)
	(segment
		(start 285.525464 -0.422402)
		(end 284.754574 -4.790186)
		(width 0.14224)
		(layer "In11.Cu")
		(net "DELTA_L_85_10INCH_IN4_DN")
	)
	(segment
		(start 278.574246 -4.506214)
		(end 279.241504 -0.72644)
		(width 0.14224)
		(layer "In11.Cu")
		(net "DELTA_L_85_10INCH_IN4_DN")
	)
	(segment
		(start 280.773124 -4.89458)
		(end 280.41727 -5.144008)
		(width 0.14224)
		(layer "In11.Cu")
		(net "DELTA_L_85_10INCH_IN4_DN")
	)
	(segment
		(start 228.909118 -5.099304)
		(end 227.315522 -4.817872)
		(width 0.14224)
		(layer "In11.Cu")
		(net "DELTA_L_85_10INCH_IN4_DN")
	)
	(segment
		(start 250.853702 -4.39928)
		(end 251.499116 -0.742442)
		(width 0.14224)
		(layer "In11.Cu")
		(net "DELTA_L_85_10INCH_IN4_DN")
	)
	(segment
		(start 221.333314 -4.886706)
		(end 220.976952 -5.136134)
		(width 0.14224)
		(layer "In11.Cu")
		(net "DELTA_L_85_10INCH_IN4_DN")
	)
	(segment
		(start 259.3086 -0.5842)
		(end 257.944112 -0.343154)
		(width 0.14224)
		(layer "In11.Cu")
		(net "DELTA_L_85_10INCH_IN4_DN")
	)
	(segment
		(start 270.895572 -4.8768)
		(end 270.646144 -4.5212)
		(width 0.14224)
		(layer "In11.Cu")
		(net "DELTA_L_85_10INCH_IN4_DN")
	)
	(segment
		(start 259.011928 -4.850638)
		(end 258.7625 -4.49453)
		(width 0.14224)
		(layer "In11.Cu")
		(net "DELTA_L_85_10INCH_IN4_DN")
	)
	(segment
		(start 290.721034 -4.811776)
		(end 290.471606 -4.455668)
		(width 0.14224)
		(layer "In11.Cu")
		(net "DELTA_L_85_10INCH_IN4_DN")
	)
	(segment
		(start 235.5342 -0.571754)
		(end 234.169712 -0.330708)
		(width 0.14224)
		(layer "In11.Cu")
		(net "DELTA_L_85_10INCH_IN4_DN")
	)
	(segment
		(start 222.122746 -0.414274)
		(end 221.333314 -4.886706)
		(width 0.14224)
		(layer "In11.Cu")
		(net "DELTA_L_85_10INCH_IN4_DN")
	)
	(segment
		(start 219.133928 -4.499102)
		(end 219.804996 -0.696976)
		(width 0.14224)
		(layer "In11.Cu")
		(net "DELTA_L_85_10INCH_IN4_DN")
	)
	(segment
		(start 227.066094 -4.461764)
		(end 227.728272 -0.710438)
		(width 0.14224)
		(layer "In11.Cu")
		(net "DELTA_L_85_10INCH_IN4_DN")
	)
	(segment
		(start 223.1009 -4.47548)
		(end 223.766634 -0.704596)
		(width 0.14224)
		(layer "In11.Cu")
		(net "DELTA_L_85_10INCH_IN4_DN")
	)
	(segment
		(start 261.909052 -0.330708)
		(end 261.744714 -0.44577)
		(width 0.14224)
		(layer "In11.Cu")
		(net "DELTA_L_85_10INCH_IN4_DN")
	)
	(segment
		(start 292.670484 -4.84378)
		(end 292.31463 -5.093208)
		(width 0.14224)
		(layer "In11.Cu")
		(net "DELTA_L_85_10INCH_IN4_DN")
	)
	(segment
		(start 286.75584 -4.826)
		(end 286.506412 -4.469638)
		(width 0.14224)
		(layer "In11.Cu")
		(net "DELTA_L_85_10INCH_IN4_DN")
	)
	(segment
		(start 234.169712 -0.330708)
		(end 234.005374 -0.44577)
		(width 0.14224)
		(layer "In11.Cu")
		(net "DELTA_L_85_10INCH_IN4_DN")
	)
	(segment
		(start 227.315522 -4.817872)
		(end 227.066094 -4.461764)
		(width 0.14224)
		(layer "In11.Cu")
		(net "DELTA_L_85_10INCH_IN4_DN")
	)
	(segment
		(start 269.832074 -0.345186)
		(end 269.667736 -0.459994)
		(width 0.14224)
		(layer "In11.Cu")
		(net "DELTA_L_85_10INCH_IN4_DN")
	)
	(segment
		(start 239.61852 -0.698246)
		(end 239.503712 -0.534162)
		(width 0.14224)
		(layer "In11.Cu")
		(net "DELTA_L_85_10INCH_IN4_DN")
	)
	(segment
		(start 293.599362 -0.315214)
		(end 293.451788 -0.418084)
		(width 0.14224)
		(layer "In11.Cu")
		(net "DELTA_L_85_10INCH_IN4_DN")
	)
	(segment
		(start 245.899686 -0.411988)
		(end 245.114064 -4.862068)
		(width 0.14224)
		(layer "In11.Cu")
		(net "DELTA_L_85_10INCH_IN4_DN")
	)
	(segment
		(start 298.769786 -2.678176)
		(end 296.314876 -2.678176)
		(width 0.14224)
		(layer "In11.Cu")
		(net "DELTA_L_85_10INCH_IN4_DN")
	)
	(segment
		(start 219.804996 -0.696976)
		(end 219.689934 -0.532638)
		(width 0.14224)
		(layer "In11.Cu")
		(net "DELTA_L_85_10INCH_IN4_DN")
	)
	(segment
		(start 219.383356 -4.854702)
		(end 219.133928 -4.499102)
		(width 0.14224)
		(layer "In11.Cu")
		(net "DELTA_L_85_10INCH_IN4_DN")
	)
	(segment
		(start 281.72029 -0.346202)
		(end 281.555952 -0.461264)
		(width 0.14224)
		(layer "In11.Cu")
		(net "DELTA_L_85_10INCH_IN4_DN")
	)
	(segment
		(start 242.098068 -0.313944)
		(end 241.93373 -0.429006)
		(width 0.14224)
		(layer "In11.Cu")
		(net "DELTA_L_85_10INCH_IN4_DN")
	)
	(segment
		(start 257.006598 -4.8387)
		(end 256.65049 -5.088128)
		(width 0.14224)
		(layer "In11.Cu")
		(net "DELTA_L_85_10INCH_IN4_DN")
	)
	(segment
		(start 247.127268 -4.829302)
		(end 246.87784 -4.473194)
		(width 0.14224)
		(layer "In11.Cu")
		(net "DELTA_L_85_10INCH_IN4_DN")
	)
	(segment
		(start 251.384054 -0.57785)
		(end 250.019566 -0.336804)
		(width 0.14224)
		(layer "In11.Cu")
		(net "DELTA_L_85_10INCH_IN4_DN")
	)
	(segment
		(start 231.693974 -0.693928)
		(end 231.578912 -0.529844)
		(width 0.14224)
		(layer "In11.Cu")
		(net "DELTA_L_85_10INCH_IN4_DN")
	)
	(segment
		(start 266.683744 -4.51866)
		(end 267.353034 -0.726694)
		(width 0.14224)
		(layer "In11.Cu")
		(net "DELTA_L_85_10INCH_IN4_DN")
	)
	(segment
		(start 254.807466 -4.450588)
		(end 255.470152 -0.695706)
		(width 0.14224)
		(layer "In11.Cu")
		(net "DELTA_L_85_10INCH_IN4_DN")
	)
	(segment
		(start 265.709146 -0.436372)
		(end 264.918698 -4.914646)
		(width 0.14224)
		(layer "In11.Cu")
		(net "DELTA_L_85_10INCH_IN4_DN")
	)
	(segment
		(start 253.990602 -0.290322)
		(end 253.826264 -0.405384)
		(width 0.14224)
		(layer "In11.Cu")
		(net "DELTA_L_85_10INCH_IN4_DN")
	)
	(segment
		(start 283.084778 -0.587248)
		(end 281.72029 -0.346202)
		(width 0.14224)
		(layer "In11.Cu")
		(net "DELTA_L_85_10INCH_IN4_DN")
	)
	(segment
		(start 223.350328 -4.831588)
		(end 223.1009 -4.47548)
		(width 0.14224)
		(layer "In11.Cu")
		(net "DELTA_L_85_10INCH_IN4_DN")
	)
	(segment
		(start 272.84553 -4.908804)
		(end 272.489168 -5.158232)
		(width 0.14224)
		(layer "In11.Cu")
		(net "DELTA_L_85_10INCH_IN4_DN")
	)
	(segment
		(start 295.360344 -2.51841)
		(end 294.893238 -1.855724)
		(width 0.14224)
		(layer "In11.Cu")
		(net "DELTA_L_85_10INCH_IN4_DN")
	)
	(segment
		(start 252.696726 -5.03682)
		(end 251.10313 -4.755388)
		(width 0.14224)
		(layer "In11.Cu")
		(net "DELTA_L_85_10INCH_IN4_DN")
	)
	(segment
		(start 244.757956 -5.111496)
		(end 243.16436 -4.830064)
		(width 0.14224)
		(layer "In11.Cu")
		(net "DELTA_L_85_10INCH_IN4_DN")
	)
	(segment
		(start 255.35509 -0.531368)
		(end 253.990602 -0.290322)
		(width 0.14224)
		(layer "In11.Cu")
		(net "DELTA_L_85_10INCH_IN4_DN")
	)
	(segment
		(start 292.31463 -5.093208)
		(end 290.721034 -4.811776)
		(width 0.14224)
		(layer "In11.Cu")
		(net "DELTA_L_85_10INCH_IN4_DN")
	)
	(segment
		(start 243.577618 -0.719328)
		(end 243.462556 -0.55499)
		(width 0.14224)
		(layer "In11.Cu")
		(net "DELTA_L_85_10INCH_IN4_DN")
	)
	(segment
		(start 259.423662 -0.748538)
		(end 259.3086 -0.5842)
		(width 0.14224)
		(layer "In11.Cu")
		(net "DELTA_L_85_10INCH_IN4_DN")
	)
	(segment
		(start 239.503712 -0.534162)
		(end 238.139224 -0.293116)
		(width 0.14224)
		(layer "In11.Cu")
		(net "DELTA_L_85_10INCH_IN4_DN")
	)
	(segment
		(start 288.34969 -5.107432)
		(end 286.75584 -4.826)
		(width 0.14224)
		(layer "In11.Cu")
		(net "DELTA_L_85_10INCH_IN4_DN")
	)
	(segment
		(start 285.689802 -0.30734)
		(end 285.525464 -0.422402)
		(width 0.14224)
		(layer "In11.Cu")
		(net "DELTA_L_85_10INCH_IN4_DN")
	)
	(segment
		(start 263.388602 -0.736092)
		(end 263.27354 -0.571754)
		(width 0.14224)
		(layer "In11.Cu")
		(net "DELTA_L_85_10INCH_IN4_DN")
	)
	(segment
		(start 284.754574 -4.790186)
		(end 284.398466 -5.039614)
		(width 0.14224)
		(layer "In11.Cu")
		(net "DELTA_L_85_10INCH_IN4_DN")
	)
	(segment
		(start 271.196562 -0.586232)
		(end 269.832074 -0.345186)
		(width 0.14224)
		(layer "In11.Cu")
		(net "DELTA_L_85_10INCH_IN4_DN")
	)
	(segment
		(start 235.649262 -0.736092)
		(end 235.5342 -0.571754)
		(width 0.14224)
		(layer "In11.Cu")
		(net "DELTA_L_85_10INCH_IN4_DN")
	)
	(segment
		(start 251.10313 -4.755388)
		(end 250.853702 -4.39928)
		(width 0.14224)
		(layer "In11.Cu")
		(net "DELTA_L_85_10INCH_IN4_DN")
	)
	(segment
		(start 274.863052 -4.850384)
		(end 274.613624 -4.494276)
		(width 0.14224)
		(layer "In11.Cu")
		(net "DELTA_L_85_10INCH_IN4_DN")
	)
	(segment
		(start 268.526768 -5.1562)
		(end 266.933172 -4.874768)
		(width 0.14224)
		(layer "In11.Cu")
		(net "DELTA_L_85_10INCH_IN4_DN")
	)
	(segment
		(start 282.80487 -4.758182)
		(end 282.555442 -4.402074)
		(width 0.14224)
		(layer "In11.Cu")
		(net "DELTA_L_85_10INCH_IN4_DN")
	)
	(segment
		(start 290.471606 -4.455668)
		(end 291.137594 -0.682244)
		(width 0.14224)
		(layer "In11.Cu")
		(net "DELTA_L_85_10INCH_IN4_DN")
	)
	(segment
		(start 279.241504 -0.72644)
		(end 279.126442 -0.562356)
		(width 0.14224)
		(layer "In11.Cu")
		(net "DELTA_L_85_10INCH_IN4_DN")
	)
	(segment
		(start 288.70529 -4.858004)
		(end 288.34969 -5.107432)
		(width 0.14224)
		(layer "In11.Cu")
		(net "DELTA_L_85_10INCH_IN4_DN")
	)
	(segment
		(start 296.314876 -2.678176)
		(end 295.360344 -2.51841)
		(width 0.14224)
		(layer "In11.Cu")
		(net "DELTA_L_85_10INCH_IN4_DN")
	)
	(segment
		(start 260.605524 -5.13207)
		(end 259.011928 -4.850638)
		(width 0.14224)
		(layer "In11.Cu")
		(net "DELTA_L_85_10INCH_IN4_DN")
	)
	(segment
		(start 286.506412 -4.469638)
		(end 287.169352 -0.712724)
		(width 0.14224)
		(layer "In11.Cu")
		(net "DELTA_L_85_10INCH_IN4_DN")
	)
	(segment
		(start 247.543574 -0.70231)
		(end 247.428512 -0.537972)
		(width 0.14224)
		(layer "In11.Cu")
		(net "DELTA_L_85_10INCH_IN4_DN")
	)
	(segment
		(start 261.744714 -0.44577)
		(end 260.961632 -4.882642)
		(width 0.14224)
		(layer "In11.Cu")
		(net "DELTA_L_85_10INCH_IN4_DN")
	)
	(segment
		(start 264.918698 -4.914646)
		(end 264.56259 -5.164074)
		(width 0.14224)
		(layer "In11.Cu")
		(net "DELTA_L_85_10INCH_IN4_DN")
	)
	(segment
		(start 267.353034 -0.726694)
		(end 267.237972 -0.562356)
		(width 0.14224)
		(layer "In11.Cu")
		(net "DELTA_L_85_10INCH_IN4_DN")
	)
	(segment
		(start 230.050086 -0.40386)
		(end 229.265226 -4.849876)
		(width 0.14224)
		(layer "In11.Cu")
		(net "DELTA_L_85_10INCH_IN4_DN")
	)
	(segment
		(start 218.161108 -0.406654)
		(end 217.84818 -2.179828)
		(width 0.14224)
		(layer "In11.Cu")
		(net "DELTA_L_85_10INCH_IN4_DN")
	)
	(segment
		(start 223.766634 -0.704596)
		(end 223.651572 -0.540258)
		(width 0.14224)
		(layer "In11.Cu")
		(net "DELTA_L_85_10INCH_IN4_DN")
	)
	(segment
		(start 232.876852 -5.070856)
		(end 231.283256 -4.789424)
		(width 0.14224)
		(layer "In11.Cu")
		(net "DELTA_L_85_10INCH_IN4_DN")
	)
	(segment
		(start 222.287084 -0.299212)
		(end 222.122746 -0.414274)
		(width 0.14224)
		(layer "In11.Cu")
		(net "DELTA_L_85_10INCH_IN4_DN")
	)
	(segment
		(start 220.976952 -5.136134)
		(end 219.383356 -4.854702)
		(width 0.14224)
		(layer "In11.Cu")
		(net "DELTA_L_85_10INCH_IN4_DN")
	)
	(segment
		(start 256.65049 -5.088128)
		(end 255.056894 -4.806696)
		(width 0.14224)
		(layer "In11.Cu")
		(net "DELTA_L_85_10INCH_IN4_DN")
	)
	(segment
		(start 253.826264 -0.405384)
		(end 253.052834 -4.787392)
		(width 0.14224)
		(layer "In11.Cu")
		(net "DELTA_L_85_10INCH_IN4_DN")
	)
	(segment
		(start 258.7625 -4.49453)
		(end 259.423662 -0.748538)
		(width 0.14224)
		(layer "In11.Cu")
		(net "DELTA_L_85_10INCH_IN4_DN")
	)
	(segment
		(start 291.137594 -0.682244)
		(end 291.022532 -0.517906)
		(width 0.14224)
		(layer "In11.Cu")
		(net "DELTA_L_85_10INCH_IN4_DN")
	)
	(segment
		(start 214.24011 -2.678176)
		(end 213.94928 -2.969006)
		(width 0.14224)
		(layer "In11.Cu")
		(net "DELTA_L_85_10INCH_IN4_DN")
	)
	(segment
		(start 234.005374 -0.44577)
		(end 233.23296 -4.821428)
		(width 0.14224)
		(layer "In11.Cu")
		(net "DELTA_L_85_10INCH_IN4_DN")
	)
	(segment
		(start 294.893238 -1.855724)
		(end 295.078404 -0.806958)
		(width 0.14224)
		(layer "In11.Cu")
		(net "DELTA_L_85_10INCH_IN4_DN")
	)
	(segment
		(start 268.882876 -4.906772)
		(end 268.526768 -5.1562)
		(width 0.14224)
		(layer "In11.Cu")
		(net "DELTA_L_85_10INCH_IN4_DN")
	)
	(segment
		(start 276.812756 -4.882388)
		(end 276.456648 -5.131816)
		(width 0.14224)
		(layer "In11.Cu")
		(net "DELTA_L_85_10INCH_IN4_DN")
	)
	(segment
		(start 233.23296 -4.821428)
		(end 232.876852 -5.070856)
		(width 0.14224)
		(layer "In11.Cu")
		(net "DELTA_L_85_10INCH_IN4_DN")
	)
	(segment
		(start 260.961632 -4.882642)
		(end 260.605524 -5.13207)
		(width 0.14224)
		(layer "In11.Cu")
		(net "DELTA_L_85_10INCH_IN4_DN")
	)
	(segment
		(start 276.456648 -5.131816)
		(end 274.863052 -4.850384)
		(width 0.14224)
		(layer "In11.Cu")
		(net "DELTA_L_85_10INCH_IN4_DN")
	)
	(segment
		(start 287.05429 -0.548386)
		(end 285.689802 -0.30734)
		(width 0.14224)
		(layer "In11.Cu")
		(net "DELTA_L_85_10INCH_IN4_DN")
	)
	(segment
		(start 237.193074 -4.837684)
		(end 236.836966 -5.087112)
		(width 0.14224)
		(layer "In11.Cu")
		(net "DELTA_L_85_10INCH_IN4_DN")
	)
	(segment
		(start 266.933172 -4.874768)
		(end 266.683744 -4.51866)
		(width 0.14224)
		(layer "In11.Cu")
		(net "DELTA_L_85_10INCH_IN4_DN")
	)
	(segment
		(start 265.873484 -0.32131)
		(end 265.709146 -0.436372)
		(width 0.14224)
		(layer "In11.Cu")
		(net "DELTA_L_85_10INCH_IN4_DN")
	)
	(segment
		(start 230.214424 -0.288798)
		(end 230.050086 -0.40386)
		(width 0.14224)
		(layer "In11.Cu")
		(net "DELTA_L_85_10INCH_IN4_DN")
	)
	(segment
		(start 273.638518 -0.415544)
		(end 272.84553 -4.908804)
		(width 0.14224)
		(layer "In11.Cu")
		(net "DELTA_L_85_10INCH_IN4_DN")
	)
	(segment
		(start 224.943924 -5.11302)
		(end 223.350328 -4.831588)
		(width 0.14224)
		(layer "In11.Cu")
		(net "DELTA_L_85_10INCH_IN4_DN")
	)
	(segment
		(start 257.779774 -0.458216)
		(end 257.006598 -4.8387)
		(width 0.14224)
		(layer "In11.Cu")
		(net "DELTA_L_85_10INCH_IN4_DN")
	)
	(segment
		(start 293.451788 -0.418084)
		(end 292.670484 -4.84378)
		(width 0.14224)
		(layer "In11.Cu")
		(net "DELTA_L_85_10INCH_IN4_DN")
	)
	(segment
		(start 255.470152 -0.695706)
		(end 255.35509 -0.531368)
		(width 0.14224)
		(layer "In11.Cu")
		(net "DELTA_L_85_10INCH_IN4_DN")
	)
	(segment
		(start 291.022532 -0.517906)
		(end 289.658044 -0.27686)
		(width 0.14224)
		(layer "In11.Cu")
		(net "DELTA_L_85_10INCH_IN4_DN")
	)
	(segment
		(start 246.87784 -4.473194)
		(end 247.543574 -0.70231)
		(width 0.14224)
		(layer "In11.Cu")
		(net "DELTA_L_85_10INCH_IN4_DN")
	)
	(segment
		(start 231.033828 -4.433316)
		(end 231.693974 -0.693928)
		(width 0.14224)
		(layer "In11.Cu")
		(net "DELTA_L_85_10INCH_IN4_DN")
	)
	(segment
		(start 227.728272 -0.710438)
		(end 227.61321 -0.5461)
		(width 0.14224)
		(layer "In11.Cu")
		(net "DELTA_L_85_10INCH_IN4_DN")
	)
	(segment
		(start 246.064024 -0.296926)
		(end 245.899686 -0.411988)
		(width 0.14224)
		(layer "In11.Cu")
		(net "DELTA_L_85_10INCH_IN4_DN")
	)
	(segment
		(start 253.052834 -4.787392)
		(end 252.696726 -5.03682)
		(width 0.14224)
		(layer "In11.Cu")
		(net "DELTA_L_85_10INCH_IN4_DN")
	)
	(segment
		(start 249.855228 -0.451866)
		(end 249.076972 -4.861306)
		(width 0.14224)
		(layer "In11.Cu")
		(net "DELTA_L_85_10INCH_IN4_DN")
	)
	(segment
		(start 245.114064 -4.862068)
		(end 244.757956 -5.111496)
		(width 0.14224)
		(layer "In11.Cu")
		(net "DELTA_L_85_10INCH_IN4_DN")
	)
	(segment
		(start 241.153442 -4.849876)
		(end 240.797334 -5.099304)
		(width 0.14224)
		(layer "In11.Cu")
		(net "DELTA_L_85_10INCH_IN4_DN")
	)
	(segment
		(start 283.19984 -0.751586)
		(end 283.084778 -0.587248)
		(width 0.14224)
		(layer "In11.Cu")
		(net "DELTA_L_85_10INCH_IN4_DN")
	)
	(segment
		(start 280.41727 -5.144008)
		(end 278.823674 -4.862576)
		(width 0.14224)
		(layer "In11.Cu")
		(net "DELTA_L_85_10INCH_IN4_DN")
	)
	(segment
		(start 250.019566 -0.336804)
		(end 249.855228 -0.451866)
		(width 0.14224)
		(layer "In11.Cu")
		(net "DELTA_L_85_10INCH_IN4_DN")
	)
	(segment
		(start 229.265226 -4.849876)
		(end 228.909118 -5.099304)
		(width 0.14224)
		(layer "In11.Cu")
		(net "DELTA_L_85_10INCH_IN4_DN")
	)
	(segment
		(start 239.203738 -4.817872)
		(end 238.95431 -4.461764)
		(width 0.14224)
		(layer "In11.Cu")
		(net "DELTA_L_85_10INCH_IN4_DN")
	)
	(segment
		(start 263.27354 -0.571754)
		(end 261.909052 -0.330708)
		(width 0.14224)
		(layer "In11.Cu")
		(net "DELTA_L_85_10INCH_IN4_DN")
	)
	(segment
		(start 273.802856 -0.300482)
		(end 273.638518 -0.415544)
		(width 0.14224)
		(layer "In11.Cu")
		(net "DELTA_L_85_10INCH_IN4_DN")
	)
	(segment
		(start 255.056894 -4.806696)
		(end 254.807466 -4.450588)
		(width 0.14224)
		(layer "In11.Cu")
		(net "DELTA_L_85_10INCH_IN4_DN")
	)
	(segment
		(start 271.311624 -0.750824)
		(end 271.196562 -0.586232)
		(width 0.14224)
		(layer "In11.Cu")
		(net "DELTA_L_85_10INCH_IN4_DN")
	)
	(segment
		(start 235.24337 -4.80568)
		(end 234.993942 -4.449572)
		(width 0.14224)
		(layer "In11.Cu")
		(net "DELTA_L_85_10INCH_IN4_DN")
	)
	(segment
		(start 262.719566 -4.526534)
		(end 263.388602 -0.736092)
		(width 0.14224)
		(layer "In11.Cu")
		(net "DELTA_L_85_10INCH_IN4_DN")
	)
	(segment
		(start 272.489168 -5.158232)
		(end 270.895572 -4.8768)
		(width 0.14224)
		(layer "In11.Cu")
		(net "DELTA_L_85_10INCH_IN4_DN")
	)
	(segment
		(start 243.462556 -0.55499)
		(end 242.098068 -0.313944)
		(width 0.14224)
		(layer "In11.Cu")
		(net "DELTA_L_85_10INCH_IN4_DN")
	)
	(segment
		(start 277.761954 -0.32131)
		(end 277.597616 -0.436372)
		(width 0.14224)
		(layer "In11.Cu")
		(net "DELTA_L_85_10INCH_IN4_DN")
	)
	(segment
		(start 299.712888 4.832858)
		(end 299.060616 4.650994)
		(width 0.12954)
		(layer "F.Cu")
		(net "DELTA_L_85_10INCH_IN3_DP")
	)
	(segment
		(start 213.297008 4.832858)
		(end 213.94928 4.650994)
		(width 0.12954)
		(layer "F.Cu")
		(net "DELTA_L_85_10INCH_IN3_DP")
	)
	(segment
		(start 280.773124 2.72542)
		(end 280.41727 2.475992)
		(width 0.14224)
		(layer "In6.Cu")
		(net "DELTA_L_85_10INCH_IN3_DP")
	)
	(segment
		(start 234.169712 7.289292)
		(end 234.005374 7.17423)
		(width 0.14224)
		(layer "In6.Cu")
		(net "DELTA_L_85_10INCH_IN3_DP")
	)
	(segment
		(start 281.555952 7.158736)
		(end 280.773124 2.72542)
		(width 0.14224)
		(layer "In6.Cu")
		(net "DELTA_L_85_10INCH_IN3_DP")
	)
	(segment
		(start 266.683744 3.10134)
		(end 267.353034 6.893306)
		(width 0.14224)
		(layer "In6.Cu")
		(net "DELTA_L_85_10INCH_IN3_DP")
	)
	(segment
		(start 220.976952 2.483866)
		(end 219.383356 2.765298)
		(width 0.14224)
		(layer "In6.Cu")
		(net "DELTA_L_85_10INCH_IN3_DP")
	)
	(segment
		(start 292.670484 2.77622)
		(end 292.31463 2.526792)
		(width 0.14224)
		(layer "In6.Cu")
		(net "DELTA_L_85_10INCH_IN3_DP")
	)
	(segment
		(start 260.961632 2.737358)
		(end 260.605524 2.48793)
		(width 0.14224)
		(layer "In6.Cu")
		(net "DELTA_L_85_10INCH_IN3_DP")
	)
	(segment
		(start 251.499116 6.877558)
		(end 251.384054 7.04215)
		(width 0.14224)
		(layer "In6.Cu")
		(net "DELTA_L_85_10INCH_IN3_DP")
	)
	(segment
		(start 276.456648 2.488184)
		(end 274.863052 2.769616)
		(width 0.14224)
		(layer "In6.Cu")
		(net "DELTA_L_85_10INCH_IN3_DP")
	)
	(segment
		(start 294.894254 7.076186)
		(end 293.599362 7.304786)
		(width 0.14224)
		(layer "In6.Cu")
		(net "DELTA_L_85_10INCH_IN3_DP")
	)
	(segment
		(start 282.555442 3.217926)
		(end 283.19984 6.868414)
		(width 0.14224)
		(layer "In6.Cu")
		(net "DELTA_L_85_10INCH_IN3_DP")
	)
	(segment
		(start 245.899686 7.208012)
		(end 245.114064 2.757932)
		(width 0.14224)
		(layer "In6.Cu")
		(net "DELTA_L_85_10INCH_IN3_DP")
	)
	(segment
		(start 283.084778 7.032752)
		(end 281.72029 7.273798)
		(width 0.14224)
		(layer "In6.Cu")
		(net "DELTA_L_85_10INCH_IN3_DP")
	)
	(segment
		(start 275.282406 6.914134)
		(end 275.167344 7.078472)
		(width 0.14224)
		(layer "In6.Cu")
		(net "DELTA_L_85_10INCH_IN3_DP")
	)
	(segment
		(start 277.761954 7.29869)
		(end 277.597616 7.183628)
		(width 0.14224)
		(layer "In6.Cu")
		(net "DELTA_L_85_10INCH_IN3_DP")
	)
	(segment
		(start 226.248722 7.314946)
		(end 226.084384 7.199884)
		(width 0.14224)
		(layer "In6.Cu")
		(net "DELTA_L_85_10INCH_IN3_DP")
	)
	(segment
		(start 235.649262 6.883908)
		(end 235.5342 7.048246)
		(width 0.14224)
		(layer "In6.Cu")
		(net "DELTA_L_85_10INCH_IN3_DP")
	)
	(segment
		(start 240.797334 2.520696)
		(end 239.203738 2.802128)
		(width 0.14224)
		(layer "In6.Cu")
		(net "DELTA_L_85_10INCH_IN3_DP")
	)
	(segment
		(start 264.56259 2.455926)
		(end 262.968994 2.737358)
		(width 0.14224)
		(layer "In6.Cu")
		(net "DELTA_L_85_10INCH_IN3_DP")
	)
	(segment
		(start 249.076972 2.758694)
		(end 248.720864 2.509266)
		(width 0.14224)
		(layer "In6.Cu")
		(net "DELTA_L_85_10INCH_IN3_DP")
	)
	(segment
		(start 262.968994 2.737358)
		(end 262.719566 3.093466)
		(width 0.14224)
		(layer "In6.Cu")
		(net "DELTA_L_85_10INCH_IN3_DP")
	)
	(segment
		(start 273.802856 7.319518)
		(end 273.638518 7.204456)
		(width 0.14224)
		(layer "In6.Cu")
		(net "DELTA_L_85_10INCH_IN3_DP")
	)
	(segment
		(start 229.265226 2.770124)
		(end 228.909118 2.520696)
		(width 0.14224)
		(layer "In6.Cu")
		(net "DELTA_L_85_10INCH_IN3_DP")
	)
	(segment
		(start 233.23296 2.798572)
		(end 232.876852 2.549144)
		(width 0.14224)
		(layer "In6.Cu")
		(net "DELTA_L_85_10INCH_IN3_DP")
	)
	(segment
		(start 241.153442 2.770124)
		(end 240.797334 2.520696)
		(width 0.14224)
		(layer "In6.Cu")
		(net "DELTA_L_85_10INCH_IN3_DP")
	)
	(segment
		(start 267.237972 7.057644)
		(end 265.873484 7.29869)
		(width 0.14224)
		(layer "In6.Cu")
		(net "DELTA_L_85_10INCH_IN3_DP")
	)
	(segment
		(start 255.35509 7.088632)
		(end 253.990602 7.329678)
		(width 0.14224)
		(layer "In6.Cu")
		(net "DELTA_L_85_10INCH_IN3_DP")
	)
	(segment
		(start 279.126442 7.057644)
		(end 277.761954 7.29869)
		(width 0.14224)
		(layer "In6.Cu")
		(net "DELTA_L_85_10INCH_IN3_DP")
	)
	(segment
		(start 292.31463 2.526792)
		(end 290.721034 2.808224)
		(width 0.14224)
		(layer "In6.Cu")
		(net "DELTA_L_85_10INCH_IN3_DP")
	)
	(segment
		(start 227.728272 6.909562)
		(end 227.61321 7.0739)
		(width 0.14224)
		(layer "In6.Cu")
		(net "DELTA_L_85_10INCH_IN3_DP")
	)
	(segment
		(start 269.667736 7.160006)
		(end 268.882876 2.713228)
		(width 0.14224)
		(layer "In6.Cu")
		(net "DELTA_L_85_10INCH_IN3_DP")
	)
	(segment
		(start 291.022532 7.102094)
		(end 289.658044 7.34314)
		(width 0.14224)
		(layer "In6.Cu")
		(net "DELTA_L_85_10INCH_IN3_DP")
	)
	(segment
		(start 289.493706 7.228078)
		(end 288.70529 2.761996)
		(width 0.14224)
		(layer "In6.Cu")
		(net "DELTA_L_85_10INCH_IN3_DP")
	)
	(segment
		(start 237.974886 7.211822)
		(end 237.193074 2.782316)
		(width 0.14224)
		(layer "In6.Cu")
		(net "DELTA_L_85_10INCH_IN3_DP")
	)
	(segment
		(start 253.990602 7.329678)
		(end 253.826264 7.214616)
		(width 0.14224)
		(layer "In6.Cu")
		(net "DELTA_L_85_10INCH_IN3_DP")
	)
	(segment
		(start 286.506412 3.150362)
		(end 287.169352 6.907276)
		(width 0.14224)
		(layer "In6.Cu")
		(net "DELTA_L_85_10INCH_IN3_DP")
	)
	(segment
		(start 276.812756 2.737612)
		(end 276.456648 2.488184)
		(width 0.14224)
		(layer "In6.Cu")
		(net "DELTA_L_85_10INCH_IN3_DP")
	)
	(segment
		(start 217.84818 5.440172)
		(end 217.135456 4.941824)
		(width 0.14224)
		(layer "In6.Cu")
		(net "DELTA_L_85_10INCH_IN3_DP")
	)
	(segment
		(start 259.3086 7.0358)
		(end 257.944112 7.276846)
		(width 0.14224)
		(layer "In6.Cu")
		(net "DELTA_L_85_10INCH_IN3_DP")
	)
	(segment
		(start 287.169352 6.907276)
		(end 287.05429 7.071614)
		(width 0.14224)
		(layer "In6.Cu")
		(net "DELTA_L_85_10INCH_IN3_DP")
	)
	(segment
		(start 296.314876 4.941824)
		(end 295.360344 5.10159)
		(width 0.14224)
		(layer "In6.Cu")
		(net "DELTA_L_85_10INCH_IN3_DP")
	)
	(segment
		(start 227.066094 3.158236)
		(end 227.728272 6.909562)
		(width 0.14224)
		(layer "In6.Cu")
		(net "DELTA_L_85_10INCH_IN3_DP")
	)
	(segment
		(start 236.836966 2.532888)
		(end 235.24337 2.81432)
		(width 0.14224)
		(layer "In6.Cu")
		(net "DELTA_L_85_10INCH_IN3_DP")
	)
	(segment
		(start 273.638518 7.204456)
		(end 272.84553 2.711196)
		(width 0.14224)
		(layer "In6.Cu")
		(net "DELTA_L_85_10INCH_IN3_DP")
	)
	(segment
		(start 242.914932 3.146044)
		(end 243.577618 6.900672)
		(width 0.14224)
		(layer "In6.Cu")
		(net "DELTA_L_85_10INCH_IN3_DP")
	)
	(segment
		(start 261.909052 7.289292)
		(end 261.744714 7.17423)
		(width 0.14224)
		(layer "In6.Cu")
		(net "DELTA_L_85_10INCH_IN3_DP")
	)
	(segment
		(start 217.135456 4.941824)
		(end 214.24011 4.941824)
		(width 0.14224)
		(layer "In6.Cu")
		(net "DELTA_L_85_10INCH_IN3_DP")
	)
	(segment
		(start 226.084384 7.199884)
		(end 225.300032 2.756408)
		(width 0.14224)
		(layer "In6.Cu")
		(net "DELTA_L_85_10INCH_IN3_DP")
	)
	(segment
		(start 268.882876 2.713228)
		(end 268.526768 2.4638)
		(width 0.14224)
		(layer "In6.Cu")
		(net "DELTA_L_85_10INCH_IN3_DP")
	)
	(segment
		(start 257.779774 7.161784)
		(end 257.006598 2.7813)
		(width 0.14224)
		(layer "In6.Cu")
		(net "DELTA_L_85_10INCH_IN3_DP")
	)
	(segment
		(start 274.863052 2.769616)
		(end 274.613624 3.125724)
		(width 0.14224)
		(layer "In6.Cu")
		(net "DELTA_L_85_10INCH_IN3_DP")
	)
	(segment
		(start 262.719566 3.093466)
		(end 263.388602 6.883908)
		(width 0.14224)
		(layer "In6.Cu")
		(net "DELTA_L_85_10INCH_IN3_DP")
	)
	(segment
		(start 244.757956 2.508504)
		(end 243.16436 2.789936)
		(width 0.14224)
		(layer "In6.Cu")
		(net "DELTA_L_85_10INCH_IN3_DP")
	)
	(segment
		(start 258.7625 3.12547)
		(end 259.423662 6.871462)
		(width 0.14224)
		(layer "In6.Cu")
		(net "DELTA_L_85_10INCH_IN3_DP")
	)
	(segment
		(start 232.876852 2.549144)
		(end 231.283256 2.830576)
		(width 0.14224)
		(layer "In6.Cu")
		(net "DELTA_L_85_10INCH_IN3_DP")
	)
	(segment
		(start 256.65049 2.531872)
		(end 255.056894 2.813304)
		(width 0.14224)
		(layer "In6.Cu")
		(net "DELTA_L_85_10INCH_IN3_DP")
	)
	(segment
		(start 248.720864 2.509266)
		(end 247.127268 2.790698)
		(width 0.14224)
		(layer "In6.Cu")
		(net "DELTA_L_85_10INCH_IN3_DP")
	)
	(segment
		(start 270.895572 2.7432)
		(end 270.646144 3.0988)
		(width 0.14224)
		(layer "In6.Cu")
		(net "DELTA_L_85_10INCH_IN3_DP")
	)
	(segment
		(start 290.471606 3.164332)
		(end 291.137594 6.937756)
		(width 0.14224)
		(layer "In6.Cu")
		(net "DELTA_L_85_10INCH_IN3_DP")
	)
	(segment
		(start 298.769786 4.941824)
		(end 296.314876 4.941824)
		(width 0.14224)
		(layer "In6.Cu")
		(net "DELTA_L_85_10INCH_IN3_DP")
	)
	(segment
		(start 227.61321 7.0739)
		(end 226.248722 7.314946)
		(width 0.14224)
		(layer "In6.Cu")
		(net "DELTA_L_85_10INCH_IN3_DP")
	)
	(segment
		(start 278.574246 3.113786)
		(end 279.241504 6.89356)
		(width 0.14224)
		(layer "In6.Cu")
		(net "DELTA_L_85_10INCH_IN3_DP")
	)
	(segment
		(start 283.19984 6.868414)
		(end 283.084778 7.032752)
		(width 0.14224)
		(layer "In6.Cu")
		(net "DELTA_L_85_10INCH_IN3_DP")
	)
	(segment
		(start 254.807466 3.169412)
		(end 255.470152 6.924294)
		(width 0.14224)
		(layer "In6.Cu")
		(net "DELTA_L_85_10INCH_IN3_DP")
	)
	(segment
		(start 253.826264 7.214616)
		(end 253.052834 2.832608)
		(width 0.14224)
		(layer "In6.Cu")
		(net "DELTA_L_85_10INCH_IN3_DP")
	)
	(segment
		(start 224.943924 2.50698)
		(end 223.350328 2.788412)
		(width 0.14224)
		(layer "In6.Cu")
		(net "DELTA_L_85_10INCH_IN3_DP")
	)
	(segment
		(start 249.855228 7.168134)
		(end 249.076972 2.758694)
		(width 0.14224)
		(layer "In6.Cu")
		(net "DELTA_L_85_10INCH_IN3_DP")
	)
	(segment
		(start 238.95431 3.158236)
		(end 239.61852 6.921754)
		(width 0.14224)
		(layer "In6.Cu")
		(net "DELTA_L_85_10INCH_IN3_DP")
	)
	(segment
		(start 219.689934 7.087362)
		(end 218.325446 7.328408)
		(width 0.14224)
		(layer "In6.Cu")
		(net "DELTA_L_85_10INCH_IN3_DP")
	)
	(segment
		(start 260.605524 2.48793)
		(end 259.011928 2.769362)
		(width 0.14224)
		(layer "In6.Cu")
		(net "DELTA_L_85_10INCH_IN3_DP")
	)
	(segment
		(start 271.196562 7.033768)
		(end 269.832074 7.274814)
		(width 0.14224)
		(layer "In6.Cu")
		(net "DELTA_L_85_10INCH_IN3_DP")
	)
	(segment
		(start 266.933172 2.745232)
		(end 266.683744 3.10134)
		(width 0.14224)
		(layer "In6.Cu")
		(net "DELTA_L_85_10INCH_IN3_DP")
	)
	(segment
		(start 231.283256 2.830576)
		(end 231.033828 3.186684)
		(width 0.14224)
		(layer "In6.Cu")
		(net "DELTA_L_85_10INCH_IN3_DP")
	)
	(segment
		(start 261.744714 7.17423)
		(end 260.961632 2.737358)
		(width 0.14224)
		(layer "In6.Cu")
		(net "DELTA_L_85_10INCH_IN3_DP")
	)
	(segment
		(start 214.24011 4.941824)
		(end 213.94928 4.650994)
		(width 0.14224)
		(layer "In6.Cu")
		(net "DELTA_L_85_10INCH_IN3_DP")
	)
	(segment
		(start 228.909118 2.520696)
		(end 227.315522 2.802128)
		(width 0.14224)
		(layer "In6.Cu")
		(net "DELTA_L_85_10INCH_IN3_DP")
	)
	(segment
		(start 288.34969 2.512568)
		(end 286.75584 2.794)
		(width 0.14224)
		(layer "In6.Cu")
		(net "DELTA_L_85_10INCH_IN3_DP")
	)
	(segment
		(start 221.333314 2.733294)
		(end 220.976952 2.483866)
		(width 0.14224)
		(layer "In6.Cu")
		(net "DELTA_L_85_10INCH_IN3_DP")
	)
	(segment
		(start 270.646144 3.0988)
		(end 271.311624 6.869176)
		(width 0.14224)
		(layer "In6.Cu")
		(net "DELTA_L_85_10INCH_IN3_DP")
	)
	(segment
		(start 284.754574 2.829814)
		(end 284.398466 2.580386)
		(width 0.14224)
		(layer "In6.Cu")
		(net "DELTA_L_85_10INCH_IN3_DP")
	)
	(segment
		(start 223.651572 7.079742)
		(end 222.287084 7.320788)
		(width 0.14224)
		(layer "In6.Cu")
		(net "DELTA_L_85_10INCH_IN3_DP")
	)
	(segment
		(start 274.613624 3.125724)
		(end 275.282406 6.914134)
		(width 0.14224)
		(layer "In6.Cu")
		(net "DELTA_L_85_10INCH_IN3_DP")
	)
	(segment
		(start 218.161108 7.213346)
		(end 217.84818 5.440172)
		(width 0.14224)
		(layer "In6.Cu")
		(net "DELTA_L_85_10INCH_IN3_DP")
	)
	(segment
		(start 230.214424 7.331202)
		(end 230.050086 7.21614)
		(width 0.14224)
		(layer "In6.Cu")
		(net "DELTA_L_85_10INCH_IN3_DP")
	)
	(segment
		(start 287.05429 7.071614)
		(end 285.689802 7.31266)
		(width 0.14224)
		(layer "In6.Cu")
		(net "DELTA_L_85_10INCH_IN3_DP")
	)
	(segment
		(start 295.078404 6.813042)
		(end 294.894254 7.076186)
		(width 0.14224)
		(layer "In6.Cu")
		(net "DELTA_L_85_10INCH_IN3_DP")
	)
	(segment
		(start 239.61852 6.921754)
		(end 239.503712 7.085838)
		(width 0.14224)
		(layer "In6.Cu")
		(net "DELTA_L_85_10INCH_IN3_DP")
	)
	(segment
		(start 281.72029 7.273798)
		(end 281.555952 7.158736)
		(width 0.14224)
		(layer "In6.Cu")
		(net "DELTA_L_85_10INCH_IN3_DP")
	)
	(segment
		(start 272.489168 2.461768)
		(end 270.895572 2.7432)
		(width 0.14224)
		(layer "In6.Cu")
		(net "DELTA_L_85_10INCH_IN3_DP")
	)
	(segment
		(start 223.1009 3.14452)
		(end 223.766634 6.915404)
		(width 0.14224)
		(layer "In6.Cu")
		(net "DELTA_L_85_10INCH_IN3_DP")
	)
	(segment
		(start 282.80487 2.861818)
		(end 282.555442 3.217926)
		(width 0.14224)
		(layer "In6.Cu")
		(net "DELTA_L_85_10INCH_IN3_DP")
	)
	(segment
		(start 219.133928 3.120898)
		(end 219.804996 6.923024)
		(width 0.14224)
		(layer "In6.Cu")
		(net "DELTA_L_85_10INCH_IN3_DP")
	)
	(segment
		(start 219.804996 6.923024)
		(end 219.689934 7.087362)
		(width 0.14224)
		(layer "In6.Cu")
		(net "DELTA_L_85_10INCH_IN3_DP")
	)
	(segment
		(start 251.384054 7.04215)
		(end 250.019566 7.283196)
		(width 0.14224)
		(layer "In6.Cu")
		(net "DELTA_L_85_10INCH_IN3_DP")
	)
	(segment
		(start 280.41727 2.475992)
		(end 278.823674 2.757424)
		(width 0.14224)
		(layer "In6.Cu")
		(net "DELTA_L_85_10INCH_IN3_DP")
	)
	(segment
		(start 257.006598 2.7813)
		(end 256.65049 2.531872)
		(width 0.14224)
		(layer "In6.Cu")
		(net "DELTA_L_85_10INCH_IN3_DP")
	)
	(segment
		(start 237.193074 2.782316)
		(end 236.836966 2.532888)
		(width 0.14224)
		(layer "In6.Cu")
		(net "DELTA_L_85_10INCH_IN3_DP")
	)
	(segment
		(start 293.451788 7.201916)
		(end 292.670484 2.77622)
		(width 0.14224)
		(layer "In6.Cu")
		(net "DELTA_L_85_10INCH_IN3_DP")
	)
	(segment
		(start 245.114064 2.757932)
		(end 244.757956 2.508504)
		(width 0.14224)
		(layer "In6.Cu")
		(net "DELTA_L_85_10INCH_IN3_DP")
	)
	(segment
		(start 250.019566 7.283196)
		(end 249.855228 7.168134)
		(width 0.14224)
		(layer "In6.Cu")
		(net "DELTA_L_85_10INCH_IN3_DP")
	)
	(segment
		(start 218.325446 7.328408)
		(end 218.161108 7.213346)
		(width 0.14224)
		(layer "In6.Cu")
		(net "DELTA_L_85_10INCH_IN3_DP")
	)
	(segment
		(start 275.167344 7.078472)
		(end 273.802856 7.319518)
		(width 0.14224)
		(layer "In6.Cu")
		(net "DELTA_L_85_10INCH_IN3_DP")
	)
	(segment
		(start 290.721034 2.808224)
		(end 290.471606 3.164332)
		(width 0.14224)
		(layer "In6.Cu")
		(net "DELTA_L_85_10INCH_IN3_DP")
	)
	(segment
		(start 247.428512 7.082028)
		(end 246.064024 7.323074)
		(width 0.14224)
		(layer "In6.Cu")
		(net "DELTA_L_85_10INCH_IN3_DP")
	)
	(segment
		(start 222.122746 7.205726)
		(end 221.333314 2.733294)
		(width 0.14224)
		(layer "In6.Cu")
		(net "DELTA_L_85_10INCH_IN3_DP")
	)
	(segment
		(start 235.5342 7.048246)
		(end 234.169712 7.289292)
		(width 0.14224)
		(layer "In6.Cu")
		(net "DELTA_L_85_10INCH_IN3_DP")
	)
	(segment
		(start 271.311624 6.869176)
		(end 271.196562 7.033768)
		(width 0.14224)
		(layer "In6.Cu")
		(net "DELTA_L_85_10INCH_IN3_DP")
	)
	(segment
		(start 263.388602 6.883908)
		(end 263.27354 7.048246)
		(width 0.14224)
		(layer "In6.Cu")
		(net "DELTA_L_85_10INCH_IN3_DP")
	)
	(segment
		(start 223.766634 6.915404)
		(end 223.651572 7.079742)
		(width 0.14224)
		(layer "In6.Cu")
		(net "DELTA_L_85_10INCH_IN3_DP")
	)
	(segment
		(start 243.16436 2.789936)
		(end 242.914932 3.146044)
		(width 0.14224)
		(layer "In6.Cu")
		(net "DELTA_L_85_10INCH_IN3_DP")
	)
	(segment
		(start 247.543574 6.91769)
		(end 247.428512 7.082028)
		(width 0.14224)
		(layer "In6.Cu")
		(net "DELTA_L_85_10INCH_IN3_DP")
	)
	(segment
		(start 284.398466 2.580386)
		(end 282.80487 2.861818)
		(width 0.14224)
		(layer "In6.Cu")
		(net "DELTA_L_85_10INCH_IN3_DP")
	)
	(segment
		(start 239.203738 2.802128)
		(end 238.95431 3.158236)
		(width 0.14224)
		(layer "In6.Cu")
		(net "DELTA_L_85_10INCH_IN3_DP")
	)
	(segment
		(start 247.127268 2.790698)
		(end 246.87784 3.146806)
		(width 0.14224)
		(layer "In6.Cu")
		(net "DELTA_L_85_10INCH_IN3_DP")
	)
	(segment
		(start 286.75584 2.794)
		(end 286.506412 3.150362)
		(width 0.14224)
		(layer "In6.Cu")
		(net "DELTA_L_85_10INCH_IN3_DP")
	)
	(segment
		(start 263.27354 7.048246)
		(end 261.909052 7.289292)
		(width 0.14224)
		(layer "In6.Cu")
		(net "DELTA_L_85_10INCH_IN3_DP")
	)
	(segment
		(start 231.578912 7.090156)
		(end 230.214424 7.331202)
		(width 0.14224)
		(layer "In6.Cu")
		(net "DELTA_L_85_10INCH_IN3_DP")
	)
	(segment
		(start 289.658044 7.34314)
		(end 289.493706 7.228078)
		(width 0.14224)
		(layer "In6.Cu")
		(net "DELTA_L_85_10INCH_IN3_DP")
	)
	(segment
		(start 251.10313 2.864612)
		(end 250.853702 3.22072)
		(width 0.14224)
		(layer "In6.Cu")
		(net "DELTA_L_85_10INCH_IN3_DP")
	)
	(segment
		(start 243.577618 6.900672)
		(end 243.462556 7.06501)
		(width 0.14224)
		(layer "In6.Cu")
		(net "DELTA_L_85_10INCH_IN3_DP")
	)
	(segment
		(start 239.503712 7.085838)
		(end 238.139224 7.326884)
		(width 0.14224)
		(layer "In6.Cu")
		(net "DELTA_L_85_10INCH_IN3_DP")
	)
	(segment
		(start 219.383356 2.765298)
		(end 219.133928 3.120898)
		(width 0.14224)
		(layer "In6.Cu")
		(net "DELTA_L_85_10INCH_IN3_DP")
	)
	(segment
		(start 255.470152 6.924294)
		(end 255.35509 7.088632)
		(width 0.14224)
		(layer "In6.Cu")
		(net "DELTA_L_85_10INCH_IN3_DP")
	)
	(segment
		(start 231.693974 6.926072)
		(end 231.578912 7.090156)
		(width 0.14224)
		(layer "In6.Cu")
		(net "DELTA_L_85_10INCH_IN3_DP")
	)
	(segment
		(start 225.300032 2.756408)
		(end 224.943924 2.50698)
		(width 0.14224)
		(layer "In6.Cu")
		(net "DELTA_L_85_10INCH_IN3_DP")
	)
	(segment
		(start 299.060616 4.650994)
		(end 298.769786 4.941824)
		(width 0.14224)
		(layer "In6.Cu")
		(net "DELTA_L_85_10INCH_IN3_DP")
	)
	(segment
		(start 259.011928 2.769362)
		(end 258.7625 3.12547)
		(width 0.14224)
		(layer "In6.Cu")
		(net "DELTA_L_85_10INCH_IN3_DP")
	)
	(segment
		(start 267.353034 6.893306)
		(end 267.237972 7.057644)
		(width 0.14224)
		(layer "In6.Cu")
		(net "DELTA_L_85_10INCH_IN3_DP")
	)
	(segment
		(start 246.064024 7.323074)
		(end 245.899686 7.208012)
		(width 0.14224)
		(layer "In6.Cu")
		(net "DELTA_L_85_10INCH_IN3_DP")
	)
	(segment
		(start 241.93373 7.190994)
		(end 241.153442 2.770124)
		(width 0.14224)
		(layer "In6.Cu")
		(net "DELTA_L_85_10INCH_IN3_DP")
	)
	(segment
		(start 235.24337 2.81432)
		(end 234.993942 3.170428)
		(width 0.14224)
		(layer "In6.Cu")
		(net "DELTA_L_85_10INCH_IN3_DP")
	)
	(segment
		(start 285.525464 7.197598)
		(end 284.754574 2.829814)
		(width 0.14224)
		(layer "In6.Cu")
		(net "DELTA_L_85_10INCH_IN3_DP")
	)
	(segment
		(start 269.832074 7.274814)
		(end 269.667736 7.160006)
		(width 0.14224)
		(layer "In6.Cu")
		(net "DELTA_L_85_10INCH_IN3_DP")
	)
	(segment
		(start 294.893238 5.764276)
		(end 295.078404 6.813042)
		(width 0.14224)
		(layer "In6.Cu")
		(net "DELTA_L_85_10INCH_IN3_DP")
	)
	(segment
		(start 291.137594 6.937756)
		(end 291.022532 7.102094)
		(width 0.14224)
		(layer "In6.Cu")
		(net "DELTA_L_85_10INCH_IN3_DP")
	)
	(segment
		(start 246.87784 3.146806)
		(end 247.543574 6.91769)
		(width 0.14224)
		(layer "In6.Cu")
		(net "DELTA_L_85_10INCH_IN3_DP")
	)
	(segment
		(start 253.052834 2.832608)
		(end 252.696726 2.58318)
		(width 0.14224)
		(layer "In6.Cu")
		(net "DELTA_L_85_10INCH_IN3_DP")
	)
	(segment
		(start 230.050086 7.21614)
		(end 229.265226 2.770124)
		(width 0.14224)
		(layer "In6.Cu")
		(net "DELTA_L_85_10INCH_IN3_DP")
	)
	(segment
		(start 250.853702 3.22072)
		(end 251.499116 6.877558)
		(width 0.14224)
		(layer "In6.Cu")
		(net "DELTA_L_85_10INCH_IN3_DP")
	)
	(segment
		(start 252.696726 2.58318)
		(end 251.10313 2.864612)
		(width 0.14224)
		(layer "In6.Cu")
		(net "DELTA_L_85_10INCH_IN3_DP")
	)
	(segment
		(start 277.597616 7.183628)
		(end 276.812756 2.737612)
		(width 0.14224)
		(layer "In6.Cu")
		(net "DELTA_L_85_10INCH_IN3_DP")
	)
	(segment
		(start 278.823674 2.757424)
		(end 278.574246 3.113786)
		(width 0.14224)
		(layer "In6.Cu")
		(net "DELTA_L_85_10INCH_IN3_DP")
	)
	(segment
		(start 257.944112 7.276846)
		(end 257.779774 7.161784)
		(width 0.14224)
		(layer "In6.Cu")
		(net "DELTA_L_85_10INCH_IN3_DP")
	)
	(segment
		(start 264.918698 2.705354)
		(end 264.56259 2.455926)
		(width 0.14224)
		(layer "In6.Cu")
		(net "DELTA_L_85_10INCH_IN3_DP")
	)
	(segment
		(start 231.033828 3.186684)
		(end 231.693974 6.926072)
		(width 0.14224)
		(layer "In6.Cu")
		(net "DELTA_L_85_10INCH_IN3_DP")
	)
	(segment
		(start 288.70529 2.761996)
		(end 288.34969 2.512568)
		(width 0.14224)
		(layer "In6.Cu")
		(net "DELTA_L_85_10INCH_IN3_DP")
	)
	(segment
		(start 285.689802 7.31266)
		(end 285.525464 7.197598)
		(width 0.14224)
		(layer "In6.Cu")
		(net "DELTA_L_85_10INCH_IN3_DP")
	)
	(segment
		(start 265.873484 7.29869)
		(end 265.709146 7.183628)
		(width 0.14224)
		(layer "In6.Cu")
		(net "DELTA_L_85_10INCH_IN3_DP")
	)
	(segment
		(start 255.056894 2.813304)
		(end 254.807466 3.169412)
		(width 0.14224)
		(layer "In6.Cu")
		(net "DELTA_L_85_10INCH_IN3_DP")
	)
	(segment
		(start 243.462556 7.06501)
		(end 242.098068 7.306056)
		(width 0.14224)
		(layer "In6.Cu")
		(net "DELTA_L_85_10INCH_IN3_DP")
	)
	(segment
		(start 293.599362 7.304786)
		(end 293.451788 7.201916)
		(width 0.14224)
		(layer "In6.Cu")
		(net "DELTA_L_85_10INCH_IN3_DP")
	)
	(segment
		(start 295.360344 5.10159)
		(end 294.893238 5.764276)
		(width 0.14224)
		(layer "In6.Cu")
		(net "DELTA_L_85_10INCH_IN3_DP")
	)
	(segment
		(start 234.005374 7.17423)
		(end 233.23296 2.798572)
		(width 0.14224)
		(layer "In6.Cu")
		(net "DELTA_L_85_10INCH_IN3_DP")
	)
	(segment
		(start 259.423662 6.871462)
		(end 259.3086 7.0358)
		(width 0.14224)
		(layer "In6.Cu")
		(net "DELTA_L_85_10INCH_IN3_DP")
	)
	(segment
		(start 238.139224 7.326884)
		(end 237.974886 7.211822)
		(width 0.14224)
		(layer "In6.Cu")
		(net "DELTA_L_85_10INCH_IN3_DP")
	)
	(segment
		(start 279.241504 6.89356)
		(end 279.126442 7.057644)
		(width 0.14224)
		(layer "In6.Cu")
		(net "DELTA_L_85_10INCH_IN3_DP")
	)
	(segment
		(start 223.350328 2.788412)
		(end 223.1009 3.14452)
		(width 0.14224)
		(layer "In6.Cu")
		(net "DELTA_L_85_10INCH_IN3_DP")
	)
	(segment
		(start 222.287084 7.320788)
		(end 222.122746 7.205726)
		(width 0.14224)
		(layer "In6.Cu")
		(net "DELTA_L_85_10INCH_IN3_DP")
	)
	(segment
		(start 227.315522 2.802128)
		(end 227.066094 3.158236)
		(width 0.14224)
		(layer "In6.Cu")
		(net "DELTA_L_85_10INCH_IN3_DP")
	)
	(segment
		(start 272.84553 2.711196)
		(end 272.489168 2.461768)
		(width 0.14224)
		(layer "In6.Cu")
		(net "DELTA_L_85_10INCH_IN3_DP")
	)
	(segment
		(start 242.098068 7.306056)
		(end 241.93373 7.190994)
		(width 0.14224)
		(layer "In6.Cu")
		(net "DELTA_L_85_10INCH_IN3_DP")
	)
	(segment
		(start 268.526768 2.4638)
		(end 266.933172 2.745232)
		(width 0.14224)
		(layer "In6.Cu")
		(net "DELTA_L_85_10INCH_IN3_DP")
	)
	(segment
		(start 265.709146 7.183628)
		(end 264.918698 2.705354)
		(width 0.14224)
		(layer "In6.Cu")
		(net "DELTA_L_85_10INCH_IN3_DP")
	)
	(segment
		(start 234.993942 3.170428)
		(end 235.649262 6.883908)
		(width 0.14224)
		(layer "In6.Cu")
		(net "DELTA_L_85_10INCH_IN3_DP")
	)
	(segment
		(start 299.712888 5.33273)
		(end 299.060616 5.514594)
		(width 0.12954)
		(layer "F.Cu")
		(net "DELTA_L_85_10INCH_IN3_DN")
	)
	(segment
		(start 213.297008 5.33273)
		(end 213.94928 5.514594)
		(width 0.12954)
		(layer "F.Cu")
		(net "DELTA_L_85_10INCH_IN3_DN")
	)
	(segment
		(start 263.437624 7.305802)
		(end 263.686798 6.949948)
		(width 0.14224)
		(layer "In6.Cu")
		(net "DELTA_L_85_10INCH_IN3_DN")
	)
	(segment
		(start 264.49655 2.754122)
		(end 264.661142 2.869438)
		(width 0.14224)
		(layer "In6.Cu")
		(net "DELTA_L_85_10INCH_IN3_DN")
	)
	(segment
		(start 239.667796 7.343394)
		(end 239.916716 6.987794)
		(width 0.14224)
		(layer "In6.Cu")
		(net "DELTA_L_85_10INCH_IN3_DN")
	)
	(segment
		(start 223.514412 3.045968)
		(end 224.877884 2.805176)
		(width 0.14224)
		(layer "In6.Cu")
		(net "DELTA_L_85_10INCH_IN3_DN")
	)
	(segment
		(start 249.953526 7.581392)
		(end 251.548392 7.299706)
		(width 0.14224)
		(layer "In6.Cu")
		(net "DELTA_L_85_10INCH_IN3_DN")
	)
	(segment
		(start 235.947458 6.949948)
		(end 235.292138 3.236468)
		(width 0.14224)
		(layer "In6.Cu")
		(net "DELTA_L_85_10INCH_IN3_DN")
	)
	(segment
		(start 249.597672 7.332218)
		(end 249.953526 7.581392)
		(width 0.14224)
		(layer "In6.Cu")
		(net "DELTA_L_85_10INCH_IN3_DN")
	)
	(segment
		(start 244.691916 2.8067)
		(end 244.856508 2.922016)
		(width 0.14224)
		(layer "In6.Cu")
		(net "DELTA_L_85_10INCH_IN3_DN")
	)
	(segment
		(start 247.176036 3.212846)
		(end 247.291352 3.048254)
		(width 0.14224)
		(layer "In6.Cu")
		(net "DELTA_L_85_10INCH_IN3_DN")
	)
	(segment
		(start 221.075758 2.897378)
		(end 221.86519 7.36981)
		(width 0.14224)
		(layer "In6.Cu")
		(net "DELTA_L_85_10INCH_IN3_DN")
	)
	(segment
		(start 243.62664 7.322566)
		(end 243.875814 6.966712)
		(width 0.14224)
		(layer "In6.Cu")
		(net "DELTA_L_85_10INCH_IN3_DN")
	)
	(segment
		(start 256.58445 2.830068)
		(end 256.749042 2.945384)
		(width 0.14224)
		(layer "In6.Cu")
		(net "DELTA_L_85_10INCH_IN3_DN")
	)
	(segment
		(start 282.853638 3.283966)
		(end 282.968954 3.119374)
		(width 0.14224)
		(layer "In6.Cu")
		(net "DELTA_L_85_10INCH_IN3_DN")
	)
	(segment
		(start 233.747818 7.338314)
		(end 234.103672 7.587488)
		(width 0.14224)
		(layer "In6.Cu")
		(net "DELTA_L_85_10INCH_IN3_DN")
	)
	(segment
		(start 218.259406 7.626604)
		(end 219.854018 7.344918)
		(width 0.14224)
		(layer "In6.Cu")
		(net "DELTA_L_85_10INCH_IN3_DN")
	)
	(segment
		(start 289.23615 7.392162)
		(end 289.592004 7.641336)
		(width 0.14224)
		(layer "In6.Cu")
		(net "DELTA_L_85_10INCH_IN3_DN")
	)
	(segment
		(start 264.661142 2.869438)
		(end 265.45159 7.347712)
		(width 0.14224)
		(layer "In6.Cu")
		(net "DELTA_L_85_10INCH_IN3_DN")
	)
	(segment
		(start 252.630686 2.881376)
		(end 252.795278 2.996692)
		(width 0.14224)
		(layer "In6.Cu")
		(net "DELTA_L_85_10INCH_IN3_DN")
	)
	(segment
		(start 236.935518 2.9464)
		(end 237.71733 7.375906)
		(width 0.14224)
		(layer "In6.Cu")
		(net "DELTA_L_85_10INCH_IN3_DN")
	)
	(segment
		(start 222.221044 7.618984)
		(end 223.815656 7.337298)
		(width 0.14224)
		(layer "In6.Cu")
		(net "DELTA_L_85_10INCH_IN3_DN")
	)
	(segment
		(start 229.79253 7.380224)
		(end 230.148384 7.629398)
		(width 0.14224)
		(layer "In6.Cu")
		(net "DELTA_L_85_10INCH_IN3_DN")
	)
	(segment
		(start 285.267908 7.361682)
		(end 285.623762 7.610856)
		(width 0.14224)
		(layer "In6.Cu")
		(net "DELTA_L_85_10INCH_IN3_DN")
	)
	(segment
		(start 235.698284 7.305802)
		(end 235.947458 6.949948)
		(width 0.14224)
		(layer "In6.Cu")
		(net "DELTA_L_85_10INCH_IN3_DN")
	)
	(segment
		(start 267.402056 7.3152)
		(end 267.65123 6.959346)
		(width 0.14224)
		(layer "In6.Cu")
		(net "DELTA_L_85_10INCH_IN3_DN")
	)
	(segment
		(start 273.380962 7.36854)
		(end 273.736816 7.617714)
		(width 0.14224)
		(layer "In6.Cu")
		(net "DELTA_L_85_10INCH_IN3_DN")
	)
	(segment
		(start 287.218374 7.32917)
		(end 287.467548 6.973316)
		(width 0.14224)
		(layer "In6.Cu")
		(net "DELTA_L_85_10INCH_IN3_DN")
	)
	(segment
		(start 259.176012 3.026918)
		(end 260.539484 2.786126)
		(width 0.14224)
		(layer "In6.Cu")
		(net "DELTA_L_85_10INCH_IN3_DN")
	)
	(segment
		(start 295.058338 7.333742)
		(end 295.3766 6.879082)
		(width 0.14224)
		(layer "In6.Cu")
		(net "DELTA_L_85_10INCH_IN3_DN")
	)
	(segment
		(start 267.097256 3.002788)
		(end 268.460728 2.761996)
		(width 0.14224)
		(layer "In6.Cu")
		(net "DELTA_L_85_10INCH_IN3_DN")
	)
	(segment
		(start 255.220978 3.07086)
		(end 256.58445 2.830068)
		(width 0.14224)
		(layer "In6.Cu")
		(net "DELTA_L_85_10INCH_IN3_DN")
	)
	(segment
		(start 230.148384 7.629398)
		(end 231.742996 7.347712)
		(width 0.14224)
		(layer "In6.Cu")
		(net "DELTA_L_85_10INCH_IN3_DN")
	)
	(segment
		(start 243.328444 3.047492)
		(end 244.691916 2.8067)
		(width 0.14224)
		(layer "In6.Cu")
		(net "DELTA_L_85_10INCH_IN3_DN")
	)
	(segment
		(start 256.749042 2.945384)
		(end 257.522218 7.325868)
		(width 0.14224)
		(layer "In6.Cu")
		(net "DELTA_L_85_10INCH_IN3_DN")
	)
	(segment
		(start 278.987758 3.01498)
		(end 280.35123 2.774188)
		(width 0.14224)
		(layer "In6.Cu")
		(net "DELTA_L_85_10INCH_IN3_DN")
	)
	(segment
		(start 232.810812 2.84734)
		(end 232.975404 2.962656)
		(width 0.14224)
		(layer "In6.Cu")
		(net "DELTA_L_85_10INCH_IN3_DN")
	)
	(segment
		(start 243.875814 6.966712)
		(end 243.213128 3.212084)
		(width 0.14224)
		(layer "In6.Cu")
		(net "DELTA_L_85_10INCH_IN3_DN")
	)
	(segment
		(start 217.903552 7.37743)
		(end 218.259406 7.626604)
		(width 0.14224)
		(layer "In6.Cu")
		(net "DELTA_L_85_10INCH_IN3_DN")
	)
	(segment
		(start 268.460728 2.761996)
		(end 268.62532 2.877312)
		(width 0.14224)
		(layer "In6.Cu")
		(net "DELTA_L_85_10INCH_IN3_DN")
	)
	(segment
		(start 269.41018 7.324344)
		(end 269.766288 7.57301)
		(width 0.14224)
		(layer "In6.Cu")
		(net "DELTA_L_85_10INCH_IN3_DN")
	)
	(segment
		(start 275.331428 7.336028)
		(end 275.580602 6.980174)
		(width 0.14224)
		(layer "In6.Cu")
		(net "DELTA_L_85_10INCH_IN3_DN")
	)
	(segment
		(start 247.84177 6.98373)
		(end 247.176036 3.212846)
		(width 0.14224)
		(layer "In6.Cu")
		(net "DELTA_L_85_10INCH_IN3_DN")
	)
	(segment
		(start 228.843078 2.818892)
		(end 229.00767 2.934208)
		(width 0.14224)
		(layer "In6.Cu")
		(net "DELTA_L_85_10INCH_IN3_DN")
	)
	(segment
		(start 268.62532 2.877312)
		(end 269.41018 7.324344)
		(width 0.14224)
		(layer "In6.Cu")
		(net "DELTA_L_85_10INCH_IN3_DN")
	)
	(segment
		(start 251.548392 7.299706)
		(end 251.797312 6.943598)
		(width 0.14224)
		(layer "In6.Cu")
		(net "DELTA_L_85_10INCH_IN3_DN")
	)
	(segment
		(start 255.105662 3.235452)
		(end 255.220978 3.07086)
		(width 0.14224)
		(layer "In6.Cu")
		(net "DELTA_L_85_10INCH_IN3_DN")
	)
	(segment
		(start 227.479606 3.059684)
		(end 228.843078 2.818892)
		(width 0.14224)
		(layer "In6.Cu")
		(net "DELTA_L_85_10INCH_IN3_DN")
	)
	(segment
		(start 219.54744 3.022854)
		(end 220.910912 2.782062)
		(width 0.14224)
		(layer "In6.Cu")
		(net "DELTA_L_85_10INCH_IN3_DN")
	)
	(segment
		(start 240.731294 2.818892)
		(end 240.895886 2.934208)
		(width 0.14224)
		(layer "In6.Cu")
		(net "DELTA_L_85_10INCH_IN3_DN")
	)
	(segment
		(start 221.86519 7.36981)
		(end 222.221044 7.618984)
		(width 0.14224)
		(layer "In6.Cu")
		(net "DELTA_L_85_10INCH_IN3_DN")
	)
	(segment
		(start 225.042476 2.920492)
		(end 225.826828 7.363968)
		(width 0.14224)
		(layer "In6.Cu")
		(net "DELTA_L_85_10INCH_IN3_DN")
	)
	(segment
		(start 226.182682 7.613142)
		(end 227.777294 7.331456)
		(width 0.14224)
		(layer "In6.Cu")
		(net "DELTA_L_85_10INCH_IN3_DN")
	)
	(segment
		(start 296.338498 5.223764)
		(end 298.769786 5.223764)
		(width 0.14224)
		(layer "In6.Cu")
		(net "DELTA_L_85_10INCH_IN3_DN")
	)
	(segment
		(start 277.34006 7.347712)
		(end 277.695914 7.596886)
		(width 0.14224)
		(layer "In6.Cu")
		(net "DELTA_L_85_10INCH_IN3_DN")
	)
	(segment
		(start 255.519174 7.346188)
		(end 255.768348 6.990334)
		(width 0.14224)
		(layer "In6.Cu")
		(net "DELTA_L_85_10INCH_IN3_DN")
	)
	(segment
		(start 267.65123 6.959346)
		(end 266.98194 3.16738)
		(width 0.14224)
		(layer "In6.Cu")
		(net "DELTA_L_85_10INCH_IN3_DN")
	)
	(segment
		(start 237.71733 7.375906)
		(end 238.073184 7.62508)
		(width 0.14224)
		(layer "In6.Cu")
		(net "DELTA_L_85_10INCH_IN3_DN")
	)
	(segment
		(start 280.35123 2.774188)
		(end 280.515568 2.889504)
		(width 0.14224)
		(layer "In6.Cu")
		(net "DELTA_L_85_10INCH_IN3_DN")
	)
	(segment
		(start 276.5552 2.901696)
		(end 277.34006 7.347712)
		(width 0.14224)
		(layer "In6.Cu")
		(net "DELTA_L_85_10INCH_IN3_DN")
	)
	(segment
		(start 219.432124 3.187192)
		(end 219.54744 3.022854)
		(width 0.14224)
		(layer "In6.Cu")
		(net "DELTA_L_85_10INCH_IN3_DN")
	)
	(segment
		(start 279.290526 7.3152)
		(end 279.5397 6.959854)
		(width 0.14224)
		(layer "In6.Cu")
		(net "DELTA_L_85_10INCH_IN3_DN")
	)
	(segment
		(start 244.856508 2.922016)
		(end 245.64213 7.372096)
		(width 0.14224)
		(layer "In6.Cu")
		(net "DELTA_L_85_10INCH_IN3_DN")
	)
	(segment
		(start 290.885118 3.06578)
		(end 292.24859 2.824988)
		(width 0.14224)
		(layer "In6.Cu")
		(net "DELTA_L_85_10INCH_IN3_DN")
	)
	(segment
		(start 259.060696 3.19151)
		(end 259.176012 3.026918)
		(width 0.14224)
		(layer "In6.Cu")
		(net "DELTA_L_85_10INCH_IN3_DN")
	)
	(segment
		(start 290.769802 3.230372)
		(end 290.885118 3.06578)
		(width 0.14224)
		(layer "In6.Cu")
		(net "DELTA_L_85_10INCH_IN3_DN")
	)
	(segment
		(start 248.654824 2.807462)
		(end 248.819416 2.922778)
		(width 0.14224)
		(layer "In6.Cu")
		(net "DELTA_L_85_10INCH_IN3_DN")
	)
	(segment
		(start 292.412928 2.940304)
		(end 293.194486 7.366254)
		(width 0.14224)
		(layer "In6.Cu")
		(net "DELTA_L_85_10INCH_IN3_DN")
	)
	(segment
		(start 240.895886 2.934208)
		(end 241.676174 7.355078)
		(width 0.14224)
		(layer "In6.Cu")
		(net "DELTA_L_85_10INCH_IN3_DN")
	)
	(segment
		(start 286.804608 3.216402)
		(end 286.919924 3.051556)
		(width 0.14224)
		(layer "In6.Cu")
		(net "DELTA_L_85_10INCH_IN3_DN")
	)
	(segment
		(start 272.423128 2.759964)
		(end 272.587974 2.87528)
		(width 0.14224)
		(layer "In6.Cu")
		(net "DELTA_L_85_10INCH_IN3_DN")
	)
	(segment
		(start 223.815656 7.337298)
		(end 224.06483 6.981444)
		(width 0.14224)
		(layer "In6.Cu")
		(net "DELTA_L_85_10INCH_IN3_DN")
	)
	(segment
		(start 213.94928 5.514594)
		(end 214.24011 5.223764)
		(width 0.14224)
		(layer "In6.Cu")
		(net "DELTA_L_85_10INCH_IN3_DN")
	)
	(segment
		(start 260.539484 2.786126)
		(end 260.704076 2.901442)
		(width 0.14224)
		(layer "In6.Cu")
		(net "DELTA_L_85_10INCH_IN3_DN")
	)
	(segment
		(start 228.026468 6.975602)
		(end 227.36429 3.224276)
		(width 0.14224)
		(layer "In6.Cu")
		(net "DELTA_L_85_10INCH_IN3_DN")
	)
	(segment
		(start 281.298396 7.32282)
		(end 281.65425 7.571994)
		(width 0.14224)
		(layer "In6.Cu")
		(net "DELTA_L_85_10INCH_IN3_DN")
	)
	(segment
		(start 270.94434 3.165094)
		(end 271.059656 3.000756)
		(width 0.14224)
		(layer "In6.Cu")
		(net "DELTA_L_85_10INCH_IN3_DN")
	)
	(segment
		(start 214.24011 5.223764)
		(end 217.046556 5.223764)
		(width 0.14224)
		(layer "In6.Cu")
		(net "DELTA_L_85_10INCH_IN3_DN")
	)
	(segment
		(start 259.721858 6.937502)
		(end 259.060696 3.19151)
		(width 0.14224)
		(layer "In6.Cu")
		(net "DELTA_L_85_10INCH_IN3_DN")
	)
	(segment
		(start 277.695914 7.596886)
		(end 279.290526 7.3152)
		(width 0.14224)
		(layer "In6.Cu")
		(net "DELTA_L_85_10INCH_IN3_DN")
	)
	(segment
		(start 282.968954 3.119374)
		(end 284.332426 2.878582)
		(width 0.14224)
		(layer "In6.Cu")
		(net "DELTA_L_85_10INCH_IN3_DN")
	)
	(segment
		(start 231.742996 7.347712)
		(end 231.99217 6.992366)
		(width 0.14224)
		(layer "In6.Cu")
		(net "DELTA_L_85_10INCH_IN3_DN")
	)
	(segment
		(start 291.186616 7.35965)
		(end 291.43579 7.003796)
		(width 0.14224)
		(layer "In6.Cu")
		(net "DELTA_L_85_10INCH_IN3_DN")
	)
	(segment
		(start 217.046556 5.223764)
		(end 217.590624 5.60451)
		(width 0.14224)
		(layer "In6.Cu")
		(net "DELTA_L_85_10INCH_IN3_DN")
	)
	(segment
		(start 259.472684 7.293356)
		(end 259.721858 6.937502)
		(width 0.14224)
		(layer "In6.Cu")
		(net "DELTA_L_85_10INCH_IN3_DN")
	)
	(segment
		(start 224.877884 2.805176)
		(end 225.042476 2.920492)
		(width 0.14224)
		(layer "In6.Cu")
		(net "DELTA_L_85_10INCH_IN3_DN")
	)
	(segment
		(start 227.36429 3.224276)
		(end 227.479606 3.059684)
		(width 0.14224)
		(layer "In6.Cu")
		(net "DELTA_L_85_10INCH_IN3_DN")
	)
	(segment
		(start 275.027136 3.027172)
		(end 276.390608 2.78638)
		(width 0.14224)
		(layer "In6.Cu")
		(net "DELTA_L_85_10INCH_IN3_DN")
	)
	(segment
		(start 245.997984 7.62127)
		(end 247.592596 7.339584)
		(width 0.14224)
		(layer "In6.Cu")
		(net "DELTA_L_85_10INCH_IN3_DN")
	)
	(segment
		(start 224.06483 6.981444)
		(end 223.399096 3.21056)
		(width 0.14224)
		(layer "In6.Cu")
		(net "DELTA_L_85_10INCH_IN3_DN")
	)
	(segment
		(start 263.017762 3.159506)
		(end 263.133078 2.994914)
		(width 0.14224)
		(layer "In6.Cu")
		(net "DELTA_L_85_10INCH_IN3_DN")
	)
	(segment
		(start 257.878072 7.575042)
		(end 259.472684 7.293356)
		(width 0.14224)
		(layer "In6.Cu")
		(net "DELTA_L_85_10INCH_IN3_DN")
	)
	(segment
		(start 251.797312 6.943598)
		(end 251.151898 3.28676)
		(width 0.14224)
		(layer "In6.Cu")
		(net "DELTA_L_85_10INCH_IN3_DN")
	)
	(segment
		(start 288.283396 2.810764)
		(end 288.447734 2.92608)
		(width 0.14224)
		(layer "In6.Cu")
		(net "DELTA_L_85_10INCH_IN3_DN")
	)
	(segment
		(start 252.795278 2.996692)
		(end 253.568708 7.3787)
		(width 0.14224)
		(layer "In6.Cu")
		(net "DELTA_L_85_10INCH_IN3_DN")
	)
	(segment
		(start 253.568708 7.3787)
		(end 253.924562 7.627874)
		(width 0.14224)
		(layer "In6.Cu")
		(net "DELTA_L_85_10INCH_IN3_DN")
	)
	(segment
		(start 239.916716 6.987794)
		(end 239.252506 3.224276)
		(width 0.14224)
		(layer "In6.Cu")
		(net "DELTA_L_85_10INCH_IN3_DN")
	)
	(segment
		(start 239.367822 3.059684)
		(end 240.731294 2.818892)
		(width 0.14224)
		(layer "In6.Cu")
		(net "DELTA_L_85_10INCH_IN3_DN")
	)
	(segment
		(start 295.3766 6.879082)
		(end 295.191434 5.830824)
		(width 0.14224)
		(layer "In6.Cu")
		(net "DELTA_L_85_10INCH_IN3_DN")
	)
	(segment
		(start 265.45159 7.347712)
		(end 265.807444 7.596886)
		(width 0.14224)
		(layer "In6.Cu")
		(net "DELTA_L_85_10INCH_IN3_DN")
	)
	(segment
		(start 245.64213 7.372096)
		(end 245.997984 7.62127)
		(width 0.14224)
		(layer "In6.Cu")
		(net "DELTA_L_85_10INCH_IN3_DN")
	)
	(segment
		(start 241.676174 7.355078)
		(end 242.032028 7.604252)
		(width 0.14224)
		(layer "In6.Cu")
		(net "DELTA_L_85_10INCH_IN3_DN")
	)
	(segment
		(start 235.292138 3.236468)
		(end 235.407454 3.071876)
		(width 0.14224)
		(layer "In6.Cu")
		(net "DELTA_L_85_10INCH_IN3_DN")
	)
	(segment
		(start 289.592004 7.641336)
		(end 291.186616 7.35965)
		(width 0.14224)
		(layer "In6.Cu")
		(net "DELTA_L_85_10INCH_IN3_DN")
	)
	(segment
		(start 247.592596 7.339584)
		(end 247.84177 6.98373)
		(width 0.14224)
		(layer "In6.Cu")
		(net "DELTA_L_85_10INCH_IN3_DN")
	)
	(segment
		(start 251.151898 3.28676)
		(end 251.267214 3.122168)
		(width 0.14224)
		(layer "In6.Cu")
		(net "DELTA_L_85_10INCH_IN3_DN")
	)
	(segment
		(start 231.99217 6.992366)
		(end 231.332024 3.252724)
		(width 0.14224)
		(layer "In6.Cu")
		(net "DELTA_L_85_10INCH_IN3_DN")
	)
	(segment
		(start 285.623762 7.610856)
		(end 287.218374 7.32917)
		(width 0.14224)
		(layer "In6.Cu")
		(net "DELTA_L_85_10INCH_IN3_DN")
	)
	(segment
		(start 263.686798 6.949948)
		(end 263.017762 3.159506)
		(width 0.14224)
		(layer "In6.Cu")
		(net "DELTA_L_85_10INCH_IN3_DN")
	)
	(segment
		(start 234.103672 7.587488)
		(end 235.698284 7.305802)
		(width 0.14224)
		(layer "In6.Cu")
		(net "DELTA_L_85_10INCH_IN3_DN")
	)
	(segment
		(start 263.133078 2.994914)
		(end 264.49655 2.754122)
		(width 0.14224)
		(layer "In6.Cu")
		(net "DELTA_L_85_10INCH_IN3_DN")
	)
	(segment
		(start 298.769786 5.223764)
		(end 299.060616 5.514594)
		(width 0.14224)
		(layer "In6.Cu")
		(net "DELTA_L_85_10INCH_IN3_DN")
	)
	(segment
		(start 239.252506 3.224276)
		(end 239.367822 3.059684)
		(width 0.14224)
		(layer "In6.Cu")
		(net "DELTA_L_85_10INCH_IN3_DN")
	)
	(segment
		(start 236.770926 2.831084)
		(end 236.935518 2.9464)
		(width 0.14224)
		(layer "In6.Cu")
		(net "DELTA_L_85_10INCH_IN3_DN")
	)
	(segment
		(start 286.919924 3.051556)
		(end 288.283396 2.810764)
		(width 0.14224)
		(layer "In6.Cu")
		(net "DELTA_L_85_10INCH_IN3_DN")
	)
	(segment
		(start 232.975404 2.962656)
		(end 233.747818 7.338314)
		(width 0.14224)
		(layer "In6.Cu")
		(net "DELTA_L_85_10INCH_IN3_DN")
	)
	(segment
		(start 227.777294 7.331456)
		(end 228.026468 6.975602)
		(width 0.14224)
		(layer "In6.Cu")
		(net "DELTA_L_85_10INCH_IN3_DN")
	)
	(segment
		(start 273.736816 7.617714)
		(end 275.331428 7.336028)
		(width 0.14224)
		(layer "In6.Cu")
		(net "DELTA_L_85_10INCH_IN3_DN")
	)
	(segment
		(start 229.00767 2.934208)
		(end 229.79253 7.380224)
		(width 0.14224)
		(layer "In6.Cu")
		(net "DELTA_L_85_10INCH_IN3_DN")
	)
	(segment
		(start 220.910912 2.782062)
		(end 221.075758 2.897378)
		(width 0.14224)
		(layer "In6.Cu")
		(net "DELTA_L_85_10INCH_IN3_DN")
	)
	(segment
		(start 248.819416 2.922778)
		(end 249.597672 7.332218)
		(width 0.14224)
		(layer "In6.Cu")
		(net "DELTA_L_85_10INCH_IN3_DN")
	)
	(segment
		(start 251.267214 3.122168)
		(end 252.630686 2.881376)
		(width 0.14224)
		(layer "In6.Cu")
		(net "DELTA_L_85_10INCH_IN3_DN")
	)
	(segment
		(start 271.3609 7.291324)
		(end 271.60982 6.935216)
		(width 0.14224)
		(layer "In6.Cu")
		(net "DELTA_L_85_10INCH_IN3_DN")
	)
	(segment
		(start 235.407454 3.071876)
		(end 236.770926 2.831084)
		(width 0.14224)
		(layer "In6.Cu")
		(net "DELTA_L_85_10INCH_IN3_DN")
	)
	(segment
		(start 225.826828 7.363968)
		(end 226.182682 7.613142)
		(width 0.14224)
		(layer "In6.Cu")
		(net "DELTA_L_85_10INCH_IN3_DN")
	)
	(segment
		(start 278.872442 3.179826)
		(end 278.987758 3.01498)
		(width 0.14224)
		(layer "In6.Cu")
		(net "DELTA_L_85_10INCH_IN3_DN")
	)
	(segment
		(start 217.590624 5.60451)
		(end 217.903552 7.37743)
		(width 0.14224)
		(layer "In6.Cu")
		(net "DELTA_L_85_10INCH_IN3_DN")
	)
	(segment
		(start 288.447734 2.92608)
		(end 289.23615 7.392162)
		(width 0.14224)
		(layer "In6.Cu")
		(net "DELTA_L_85_10INCH_IN3_DN")
	)
	(segment
		(start 261.843012 7.587488)
		(end 263.437624 7.305802)
		(width 0.14224)
		(layer "In6.Cu")
		(net "DELTA_L_85_10INCH_IN3_DN")
	)
	(segment
		(start 220.103192 6.989064)
		(end 219.432124 3.187192)
		(width 0.14224)
		(layer "In6.Cu")
		(net "DELTA_L_85_10INCH_IN3_DN")
	)
	(segment
		(start 280.515568 2.889504)
		(end 281.298396 7.32282)
		(width 0.14224)
		(layer "In6.Cu")
		(net "DELTA_L_85_10INCH_IN3_DN")
	)
	(segment
		(start 279.5397 6.959854)
		(end 278.872442 3.179826)
		(width 0.14224)
		(layer "In6.Cu")
		(net "DELTA_L_85_10INCH_IN3_DN")
	)
	(segment
		(start 284.332426 2.878582)
		(end 284.497018 2.993898)
		(width 0.14224)
		(layer "In6.Cu")
		(net "DELTA_L_85_10INCH_IN3_DN")
	)
	(segment
		(start 271.60982 6.935216)
		(end 270.94434 3.165094)
		(width 0.14224)
		(layer "In6.Cu")
		(net "DELTA_L_85_10INCH_IN3_DN")
	)
	(segment
		(start 292.24859 2.824988)
		(end 292.412928 2.940304)
		(width 0.14224)
		(layer "In6.Cu")
		(net "DELTA_L_85_10INCH_IN3_DN")
	)
	(segment
		(start 243.213128 3.212084)
		(end 243.328444 3.047492)
		(width 0.14224)
		(layer "In6.Cu")
		(net "DELTA_L_85_10INCH_IN3_DN")
	)
	(segment
		(start 219.854018 7.344918)
		(end 220.103192 6.989064)
		(width 0.14224)
		(layer "In6.Cu")
		(net "DELTA_L_85_10INCH_IN3_DN")
	)
	(segment
		(start 284.497018 2.993898)
		(end 285.267908 7.361682)
		(width 0.14224)
		(layer "In6.Cu")
		(net "DELTA_L_85_10INCH_IN3_DN")
	)
	(segment
		(start 261.487158 7.338314)
		(end 261.843012 7.587488)
		(width 0.14224)
		(layer "In6.Cu")
		(net "DELTA_L_85_10INCH_IN3_DN")
	)
	(segment
		(start 295.523158 5.360416)
		(end 296.338498 5.223764)
		(width 0.14224)
		(layer "In6.Cu")
		(net "DELTA_L_85_10INCH_IN3_DN")
	)
	(segment
		(start 271.059656 3.000756)
		(end 272.423128 2.759964)
		(width 0.14224)
		(layer "In6.Cu")
		(net "DELTA_L_85_10INCH_IN3_DN")
	)
	(segment
		(start 274.91182 3.191764)
		(end 275.027136 3.027172)
		(width 0.14224)
		(layer "In6.Cu")
		(net "DELTA_L_85_10INCH_IN3_DN")
	)
	(segment
		(start 293.194486 7.366254)
		(end 293.533576 7.602728)
		(width 0.14224)
		(layer "In6.Cu")
		(net "DELTA_L_85_10INCH_IN3_DN")
	)
	(segment
		(start 223.399096 3.21056)
		(end 223.514412 3.045968)
		(width 0.14224)
		(layer "In6.Cu")
		(net "DELTA_L_85_10INCH_IN3_DN")
	)
	(segment
		(start 276.390608 2.78638)
		(end 276.5552 2.901696)
		(width 0.14224)
		(layer "In6.Cu")
		(net "DELTA_L_85_10INCH_IN3_DN")
	)
	(segment
		(start 247.291352 3.048254)
		(end 248.654824 2.807462)
		(width 0.14224)
		(layer "In6.Cu")
		(net "DELTA_L_85_10INCH_IN3_DN")
	)
	(segment
		(start 255.768348 6.990334)
		(end 255.105662 3.235452)
		(width 0.14224)
		(layer "In6.Cu")
		(net "DELTA_L_85_10INCH_IN3_DN")
	)
	(segment
		(start 257.522218 7.325868)
		(end 257.878072 7.575042)
		(width 0.14224)
		(layer "In6.Cu")
		(net "DELTA_L_85_10INCH_IN3_DN")
	)
	(segment
		(start 266.98194 3.16738)
		(end 267.097256 3.002788)
		(width 0.14224)
		(layer "In6.Cu")
		(net "DELTA_L_85_10INCH_IN3_DN")
	)
	(segment
		(start 291.43579 7.003796)
		(end 290.769802 3.230372)
		(width 0.14224)
		(layer "In6.Cu")
		(net "DELTA_L_85_10INCH_IN3_DN")
	)
	(segment
		(start 231.44734 3.088132)
		(end 232.810812 2.84734)
		(width 0.14224)
		(layer "In6.Cu")
		(net "DELTA_L_85_10INCH_IN3_DN")
	)
	(segment
		(start 293.533576 7.602728)
		(end 295.058338 7.333742)
		(width 0.14224)
		(layer "In6.Cu")
		(net "DELTA_L_85_10INCH_IN3_DN")
	)
	(segment
		(start 260.704076 2.901442)
		(end 261.487158 7.338314)
		(width 0.14224)
		(layer "In6.Cu")
		(net "DELTA_L_85_10INCH_IN3_DN")
	)
	(segment
		(start 283.498036 6.934454)
		(end 282.853638 3.283966)
		(width 0.14224)
		(layer "In6.Cu")
		(net "DELTA_L_85_10INCH_IN3_DN")
	)
	(segment
		(start 275.580602 6.980174)
		(end 274.91182 3.191764)
		(width 0.14224)
		(layer "In6.Cu")
		(net "DELTA_L_85_10INCH_IN3_DN")
	)
	(segment
		(start 253.924562 7.627874)
		(end 255.519174 7.346188)
		(width 0.14224)
		(layer "In6.Cu")
		(net "DELTA_L_85_10INCH_IN3_DN")
	)
	(segment
		(start 281.65425 7.571994)
		(end 283.248862 7.290308)
		(width 0.14224)
		(layer "In6.Cu")
		(net "DELTA_L_85_10INCH_IN3_DN")
	)
	(segment
		(start 242.032028 7.604252)
		(end 243.62664 7.322566)
		(width 0.14224)
		(layer "In6.Cu")
		(net "DELTA_L_85_10INCH_IN3_DN")
	)
	(segment
		(start 238.073184 7.62508)
		(end 239.667796 7.343394)
		(width 0.14224)
		(layer "In6.Cu")
		(net "DELTA_L_85_10INCH_IN3_DN")
	)
	(segment
		(start 283.248862 7.290308)
		(end 283.498036 6.934454)
		(width 0.14224)
		(layer "In6.Cu")
		(net "DELTA_L_85_10INCH_IN3_DN")
	)
	(segment
		(start 287.467548 6.973316)
		(end 286.804608 3.216402)
		(width 0.14224)
		(layer "In6.Cu")
		(net "DELTA_L_85_10INCH_IN3_DN")
	)
	(segment
		(start 231.332024 3.252724)
		(end 231.44734 3.088132)
		(width 0.14224)
		(layer "In6.Cu")
		(net "DELTA_L_85_10INCH_IN3_DN")
	)
	(segment
		(start 272.587974 2.87528)
		(end 273.380962 7.36854)
		(width 0.14224)
		(layer "In6.Cu")
		(net "DELTA_L_85_10INCH_IN3_DN")
	)
	(segment
		(start 265.807444 7.596886)
		(end 267.402056 7.3152)
		(width 0.14224)
		(layer "In6.Cu")
		(net "DELTA_L_85_10INCH_IN3_DN")
	)
	(segment
		(start 269.766288 7.57301)
		(end 271.3609 7.291324)
		(width 0.14224)
		(layer "In6.Cu")
		(net "DELTA_L_85_10INCH_IN3_DN")
	)
	(segment
		(start 295.191434 5.830824)
		(end 295.523158 5.360416)
		(width 0.14224)
		(layer "In6.Cu")
		(net "DELTA_L_85_10INCH_IN3_DN")
	)
	(segment
		(start 213.297008 -5.327142)
		(end 213.94928 -5.509006)
		(width 0.12954)
		(layer "F.Cu")
		(net "DELTA_L_85_10INCH_IN2_DP")
	)
	(segment
		(start 299.712888 -5.327142)
		(end 299.060616 -5.509006)
		(width 0.12954)
		(layer "F.Cu")
		(net "DELTA_L_85_10INCH_IN2_DP")
	)
	(segment
		(start 249.076972 -7.401306)
		(end 248.720864 -7.650734)
		(width 0.14224)
		(layer "In4.Cu")
		(net "DELTA_L_85_10INCH_IN2_DP")
	)
	(segment
		(start 217.84818 -4.719828)
		(end 217.135456 -5.218176)
		(width 0.14224)
		(layer "In4.Cu")
		(net "DELTA_L_85_10INCH_IN2_DP")
	)
	(segment
		(start 234.993942 -6.989572)
		(end 235.649262 -3.276092)
		(width 0.14224)
		(layer "In4.Cu")
		(net "DELTA_L_85_10INCH_IN2_DP")
	)
	(segment
		(start 246.064024 -2.836926)
		(end 245.899686 -2.951988)
		(width 0.14224)
		(layer "In4.Cu")
		(net "DELTA_L_85_10INCH_IN2_DP")
	)
	(segment
		(start 287.169352 -3.252724)
		(end 287.05429 -3.088386)
		(width 0.14224)
		(layer "In4.Cu")
		(net "DELTA_L_85_10INCH_IN2_DP")
	)
	(segment
		(start 255.470152 -3.235706)
		(end 255.35509 -3.071368)
		(width 0.14224)
		(layer "In4.Cu")
		(net "DELTA_L_85_10INCH_IN2_DP")
	)
	(segment
		(start 275.282406 -3.245866)
		(end 275.167344 -3.081528)
		(width 0.14224)
		(layer "In4.Cu")
		(net "DELTA_L_85_10INCH_IN2_DP")
	)
	(segment
		(start 273.638518 -2.955544)
		(end 272.84553 -7.448804)
		(width 0.14224)
		(layer "In4.Cu")
		(net "DELTA_L_85_10INCH_IN2_DP")
	)
	(segment
		(start 268.882876 -7.446772)
		(end 268.526768 -7.6962)
		(width 0.14224)
		(layer "In4.Cu")
		(net "DELTA_L_85_10INCH_IN2_DP")
	)
	(segment
		(start 281.555952 -3.001264)
		(end 280.773124 -7.43458)
		(width 0.14224)
		(layer "In4.Cu")
		(net "DELTA_L_85_10INCH_IN2_DP")
	)
	(segment
		(start 271.311624 -3.290824)
		(end 271.196562 -3.126232)
		(width 0.14224)
		(layer "In4.Cu")
		(net "DELTA_L_85_10INCH_IN2_DP")
	)
	(segment
		(start 268.526768 -7.6962)
		(end 266.933172 -7.414768)
		(width 0.14224)
		(layer "In4.Cu")
		(net "DELTA_L_85_10INCH_IN2_DP")
	)
	(segment
		(start 247.543574 -3.24231)
		(end 247.428512 -3.077972)
		(width 0.14224)
		(layer "In4.Cu")
		(net "DELTA_L_85_10INCH_IN2_DP")
	)
	(segment
		(start 253.990602 -2.830322)
		(end 253.826264 -2.945384)
		(width 0.14224)
		(layer "In4.Cu")
		(net "DELTA_L_85_10INCH_IN2_DP")
	)
	(segment
		(start 227.315522 -7.357872)
		(end 227.066094 -7.001764)
		(width 0.14224)
		(layer "In4.Cu")
		(net "DELTA_L_85_10INCH_IN2_DP")
	)
	(segment
		(start 231.283256 -7.329424)
		(end 231.033828 -6.973316)
		(width 0.14224)
		(layer "In4.Cu")
		(net "DELTA_L_85_10INCH_IN2_DP")
	)
	(segment
		(start 227.61321 -3.0861)
		(end 226.248722 -2.845054)
		(width 0.14224)
		(layer "In4.Cu")
		(net "DELTA_L_85_10INCH_IN2_DP")
	)
	(segment
		(start 259.3086 -3.1242)
		(end 257.944112 -2.883154)
		(width 0.14224)
		(layer "In4.Cu")
		(net "DELTA_L_85_10INCH_IN2_DP")
	)
	(segment
		(start 299.060616 -5.509006)
		(end 298.769786 -5.218176)
		(width 0.14224)
		(layer "In4.Cu")
		(net "DELTA_L_85_10INCH_IN2_DP")
	)
	(segment
		(start 282.555442 -6.942074)
		(end 283.19984 -3.291586)
		(width 0.14224)
		(layer "In4.Cu")
		(net "DELTA_L_85_10INCH_IN2_DP")
	)
	(segment
		(start 257.944112 -2.883154)
		(end 257.779774 -2.998216)
		(width 0.14224)
		(layer "In4.Cu")
		(net "DELTA_L_85_10INCH_IN2_DP")
	)
	(segment
		(start 247.428512 -3.077972)
		(end 246.064024 -2.836926)
		(width 0.14224)
		(layer "In4.Cu")
		(net "DELTA_L_85_10INCH_IN2_DP")
	)
	(segment
		(start 222.122746 -2.954274)
		(end 221.333314 -7.426706)
		(width 0.14224)
		(layer "In4.Cu")
		(net "DELTA_L_85_10INCH_IN2_DP")
	)
	(segment
		(start 263.27354 -3.111754)
		(end 261.909052 -2.870708)
		(width 0.14224)
		(layer "In4.Cu")
		(net "DELTA_L_85_10INCH_IN2_DP")
	)
	(segment
		(start 240.797334 -7.639304)
		(end 239.203738 -7.357872)
		(width 0.14224)
		(layer "In4.Cu")
		(net "DELTA_L_85_10INCH_IN2_DP")
	)
	(segment
		(start 254.807466 -6.990588)
		(end 255.470152 -3.235706)
		(width 0.14224)
		(layer "In4.Cu")
		(net "DELTA_L_85_10INCH_IN2_DP")
	)
	(segment
		(start 229.265226 -7.389876)
		(end 228.909118 -7.639304)
		(width 0.14224)
		(layer "In4.Cu")
		(net "DELTA_L_85_10INCH_IN2_DP")
	)
	(segment
		(start 241.93373 -2.969006)
		(end 241.153442 -7.389876)
		(width 0.14224)
		(layer "In4.Cu")
		(net "DELTA_L_85_10INCH_IN2_DP")
	)
	(segment
		(start 278.823674 -7.402576)
		(end 278.574246 -7.046214)
		(width 0.14224)
		(layer "In4.Cu")
		(net "DELTA_L_85_10INCH_IN2_DP")
	)
	(segment
		(start 292.31463 -7.633208)
		(end 290.721034 -7.351776)
		(width 0.14224)
		(layer "In4.Cu")
		(net "DELTA_L_85_10INCH_IN2_DP")
	)
	(segment
		(start 243.462556 -3.09499)
		(end 242.098068 -2.853944)
		(width 0.14224)
		(layer "In4.Cu")
		(net "DELTA_L_85_10INCH_IN2_DP")
	)
	(segment
		(start 221.333314 -7.426706)
		(end 220.976952 -7.676134)
		(width 0.14224)
		(layer "In4.Cu")
		(net "DELTA_L_85_10INCH_IN2_DP")
	)
	(segment
		(start 238.139224 -2.833116)
		(end 237.974886 -2.948178)
		(width 0.14224)
		(layer "In4.Cu")
		(net "DELTA_L_85_10INCH_IN2_DP")
	)
	(segment
		(start 266.933172 -7.414768)
		(end 266.683744 -7.05866)
		(width 0.14224)
		(layer "In4.Cu")
		(net "DELTA_L_85_10INCH_IN2_DP")
	)
	(segment
		(start 225.300032 -7.403592)
		(end 224.943924 -7.65302)
		(width 0.14224)
		(layer "In4.Cu")
		(net "DELTA_L_85_10INCH_IN2_DP")
	)
	(segment
		(start 295.360344 -5.05841)
		(end 294.893238 -4.395724)
		(width 0.14224)
		(layer "In4.Cu")
		(net "DELTA_L_85_10INCH_IN2_DP")
	)
	(segment
		(start 265.709146 -2.976372)
		(end 264.918698 -7.454646)
		(width 0.14224)
		(layer "In4.Cu")
		(net "DELTA_L_85_10INCH_IN2_DP")
	)
	(segment
		(start 249.855228 -2.991866)
		(end 249.076972 -7.401306)
		(width 0.14224)
		(layer "In4.Cu")
		(net "DELTA_L_85_10INCH_IN2_DP")
	)
	(segment
		(start 243.577618 -3.259328)
		(end 243.462556 -3.09499)
		(width 0.14224)
		(layer "In4.Cu")
		(net "DELTA_L_85_10INCH_IN2_DP")
	)
	(segment
		(start 283.084778 -3.127248)
		(end 281.72029 -2.886202)
		(width 0.14224)
		(layer "In4.Cu")
		(net "DELTA_L_85_10INCH_IN2_DP")
	)
	(segment
		(start 234.169712 -2.870708)
		(end 234.005374 -2.98577)
		(width 0.14224)
		(layer "In4.Cu")
		(net "DELTA_L_85_10INCH_IN2_DP")
	)
	(segment
		(start 274.613624 -7.034276)
		(end 275.282406 -3.245866)
		(width 0.14224)
		(layer "In4.Cu")
		(net "DELTA_L_85_10INCH_IN2_DP")
	)
	(segment
		(start 266.683744 -7.05866)
		(end 267.353034 -3.266694)
		(width 0.14224)
		(layer "In4.Cu")
		(net "DELTA_L_85_10INCH_IN2_DP")
	)
	(segment
		(start 260.961632 -7.422642)
		(end 260.605524 -7.67207)
		(width 0.14224)
		(layer "In4.Cu")
		(net "DELTA_L_85_10INCH_IN2_DP")
	)
	(segment
		(start 273.802856 -2.840482)
		(end 273.638518 -2.955544)
		(width 0.14224)
		(layer "In4.Cu")
		(net "DELTA_L_85_10INCH_IN2_DP")
	)
	(segment
		(start 223.350328 -7.371588)
		(end 223.1009 -7.01548)
		(width 0.14224)
		(layer "In4.Cu")
		(net "DELTA_L_85_10INCH_IN2_DP")
	)
	(segment
		(start 258.7625 -7.03453)
		(end 259.423662 -3.288538)
		(width 0.14224)
		(layer "In4.Cu")
		(net "DELTA_L_85_10INCH_IN2_DP")
	)
	(segment
		(start 250.853702 -6.93928)
		(end 251.499116 -3.282442)
		(width 0.14224)
		(layer "In4.Cu")
		(net "DELTA_L_85_10INCH_IN2_DP")
	)
	(segment
		(start 288.34969 -7.647432)
		(end 286.75584 -7.366)
		(width 0.14224)
		(layer "In4.Cu")
		(net "DELTA_L_85_10INCH_IN2_DP")
	)
	(segment
		(start 257.779774 -2.998216)
		(end 257.006598 -7.3787)
		(width 0.14224)
		(layer "In4.Cu")
		(net "DELTA_L_85_10INCH_IN2_DP")
	)
	(segment
		(start 219.689934 -3.072638)
		(end 218.325446 -2.831592)
		(width 0.14224)
		(layer "In4.Cu")
		(net "DELTA_L_85_10INCH_IN2_DP")
	)
	(segment
		(start 253.826264 -2.945384)
		(end 253.052834 -7.327392)
		(width 0.14224)
		(layer "In4.Cu")
		(net "DELTA_L_85_10INCH_IN2_DP")
	)
	(segment
		(start 257.006598 -7.3787)
		(end 256.65049 -7.628128)
		(width 0.14224)
		(layer "In4.Cu")
		(net "DELTA_L_85_10INCH_IN2_DP")
	)
	(segment
		(start 234.005374 -2.98577)
		(end 233.23296 -7.361428)
		(width 0.14224)
		(layer "In4.Cu")
		(net "DELTA_L_85_10INCH_IN2_DP")
	)
	(segment
		(start 280.773124 -7.43458)
		(end 280.41727 -7.684008)
		(width 0.14224)
		(layer "In4.Cu")
		(net "DELTA_L_85_10INCH_IN2_DP")
	)
	(segment
		(start 219.804996 -3.236976)
		(end 219.689934 -3.072638)
		(width 0.14224)
		(layer "In4.Cu")
		(net "DELTA_L_85_10INCH_IN2_DP")
	)
	(segment
		(start 235.24337 -7.34568)
		(end 234.993942 -6.989572)
		(width 0.14224)
		(layer "In4.Cu")
		(net "DELTA_L_85_10INCH_IN2_DP")
	)
	(segment
		(start 251.499116 -3.282442)
		(end 251.384054 -3.11785)
		(width 0.14224)
		(layer "In4.Cu")
		(net "DELTA_L_85_10INCH_IN2_DP")
	)
	(segment
		(start 267.353034 -3.266694)
		(end 267.237972 -3.102356)
		(width 0.14224)
		(layer "In4.Cu")
		(net "DELTA_L_85_10INCH_IN2_DP")
	)
	(segment
		(start 223.766634 -3.244596)
		(end 223.651572 -3.080258)
		(width 0.14224)
		(layer "In4.Cu")
		(net "DELTA_L_85_10INCH_IN2_DP")
	)
	(segment
		(start 245.114064 -7.402068)
		(end 244.757956 -7.651496)
		(width 0.14224)
		(layer "In4.Cu")
		(net "DELTA_L_85_10INCH_IN2_DP")
	)
	(segment
		(start 224.943924 -7.65302)
		(end 223.350328 -7.371588)
		(width 0.14224)
		(layer "In4.Cu")
		(net "DELTA_L_85_10INCH_IN2_DP")
	)
	(segment
		(start 251.384054 -3.11785)
		(end 250.019566 -2.876804)
		(width 0.14224)
		(layer "In4.Cu")
		(net "DELTA_L_85_10INCH_IN2_DP")
	)
	(segment
		(start 218.325446 -2.831592)
		(end 218.161108 -2.946654)
		(width 0.14224)
		(layer "In4.Cu")
		(net "DELTA_L_85_10INCH_IN2_DP")
	)
	(segment
		(start 235.649262 -3.276092)
		(end 235.5342 -3.111754)
		(width 0.14224)
		(layer "In4.Cu")
		(net "DELTA_L_85_10INCH_IN2_DP")
	)
	(segment
		(start 286.506412 -7.009638)
		(end 287.169352 -3.252724)
		(width 0.14224)
		(layer "In4.Cu")
		(net "DELTA_L_85_10INCH_IN2_DP")
	)
	(segment
		(start 237.974886 -2.948178)
		(end 237.193074 -7.377684)
		(width 0.14224)
		(layer "In4.Cu")
		(net "DELTA_L_85_10INCH_IN2_DP")
	)
	(segment
		(start 271.196562 -3.126232)
		(end 269.832074 -2.885186)
		(width 0.14224)
		(layer "In4.Cu")
		(net "DELTA_L_85_10INCH_IN2_DP")
	)
	(segment
		(start 261.744714 -2.98577)
		(end 260.961632 -7.422642)
		(width 0.14224)
		(layer "In4.Cu")
		(net "DELTA_L_85_10INCH_IN2_DP")
	)
	(segment
		(start 293.451788 -2.958084)
		(end 292.670484 -7.38378)
		(width 0.14224)
		(layer "In4.Cu")
		(net "DELTA_L_85_10INCH_IN2_DP")
	)
	(segment
		(start 256.65049 -7.628128)
		(end 255.056894 -7.346696)
		(width 0.14224)
		(layer "In4.Cu")
		(net "DELTA_L_85_10INCH_IN2_DP")
	)
	(segment
		(start 282.80487 -7.298182)
		(end 282.555442 -6.942074)
		(width 0.14224)
		(layer "In4.Cu")
		(net "DELTA_L_85_10INCH_IN2_DP")
	)
	(segment
		(start 261.909052 -2.870708)
		(end 261.744714 -2.98577)
		(width 0.14224)
		(layer "In4.Cu")
		(net "DELTA_L_85_10INCH_IN2_DP")
	)
	(segment
		(start 288.70529 -7.398004)
		(end 288.34969 -7.647432)
		(width 0.14224)
		(layer "In4.Cu")
		(net "DELTA_L_85_10INCH_IN2_DP")
	)
	(segment
		(start 279.126442 -3.102356)
		(end 277.761954 -2.86131)
		(width 0.14224)
		(layer "In4.Cu")
		(net "DELTA_L_85_10INCH_IN2_DP")
	)
	(segment
		(start 264.56259 -7.704074)
		(end 262.968994 -7.422642)
		(width 0.14224)
		(layer "In4.Cu")
		(net "DELTA_L_85_10INCH_IN2_DP")
	)
	(segment
		(start 259.011928 -7.390638)
		(end 258.7625 -7.03453)
		(width 0.14224)
		(layer "In4.Cu")
		(net "DELTA_L_85_10INCH_IN2_DP")
	)
	(segment
		(start 247.127268 -7.369302)
		(end 246.87784 -7.013194)
		(width 0.14224)
		(layer "In4.Cu")
		(net "DELTA_L_85_10INCH_IN2_DP")
	)
	(segment
		(start 223.651572 -3.080258)
		(end 222.287084 -2.839212)
		(width 0.14224)
		(layer "In4.Cu")
		(net "DELTA_L_85_10INCH_IN2_DP")
	)
	(segment
		(start 233.23296 -7.361428)
		(end 232.876852 -7.610856)
		(width 0.14224)
		(layer "In4.Cu")
		(net "DELTA_L_85_10INCH_IN2_DP")
	)
	(segment
		(start 278.574246 -7.046214)
		(end 279.241504 -3.26644)
		(width 0.14224)
		(layer "In4.Cu")
		(net "DELTA_L_85_10INCH_IN2_DP")
	)
	(segment
		(start 267.237972 -3.102356)
		(end 265.873484 -2.86131)
		(width 0.14224)
		(layer "In4.Cu")
		(net "DELTA_L_85_10INCH_IN2_DP")
	)
	(segment
		(start 270.646144 -7.0612)
		(end 271.311624 -3.290824)
		(width 0.14224)
		(layer "In4.Cu")
		(net "DELTA_L_85_10INCH_IN2_DP")
	)
	(segment
		(start 294.893238 -4.395724)
		(end 295.078404 -3.346958)
		(width 0.14224)
		(layer "In4.Cu")
		(net "DELTA_L_85_10INCH_IN2_DP")
	)
	(segment
		(start 292.670484 -7.38378)
		(end 292.31463 -7.633208)
		(width 0.14224)
		(layer "In4.Cu")
		(net "DELTA_L_85_10INCH_IN2_DP")
	)
	(segment
		(start 290.721034 -7.351776)
		(end 290.471606 -6.995668)
		(width 0.14224)
		(layer "In4.Cu")
		(net "DELTA_L_85_10INCH_IN2_DP")
	)
	(segment
		(start 241.153442 -7.389876)
		(end 240.797334 -7.639304)
		(width 0.14224)
		(layer "In4.Cu")
		(net "DELTA_L_85_10INCH_IN2_DP")
	)
	(segment
		(start 239.61852 -3.238246)
		(end 239.503712 -3.074162)
		(width 0.14224)
		(layer "In4.Cu")
		(net "DELTA_L_85_10INCH_IN2_DP")
	)
	(segment
		(start 238.95431 -7.001764)
		(end 239.61852 -3.238246)
		(width 0.14224)
		(layer "In4.Cu")
		(net "DELTA_L_85_10INCH_IN2_DP")
	)
	(segment
		(start 217.135456 -5.218176)
		(end 214.24011 -5.218176)
		(width 0.14224)
		(layer "In4.Cu")
		(net "DELTA_L_85_10INCH_IN2_DP")
	)
	(segment
		(start 242.914932 -7.013956)
		(end 243.577618 -3.259328)
		(width 0.14224)
		(layer "In4.Cu")
		(net "DELTA_L_85_10INCH_IN2_DP")
	)
	(segment
		(start 293.599362 -2.855214)
		(end 293.451788 -2.958084)
		(width 0.14224)
		(layer "In4.Cu")
		(net "DELTA_L_85_10INCH_IN2_DP")
	)
	(segment
		(start 244.757956 -7.651496)
		(end 243.16436 -7.370064)
		(width 0.14224)
		(layer "In4.Cu")
		(net "DELTA_L_85_10INCH_IN2_DP")
	)
	(segment
		(start 232.876852 -7.610856)
		(end 231.283256 -7.329424)
		(width 0.14224)
		(layer "In4.Cu")
		(net "DELTA_L_85_10INCH_IN2_DP")
	)
	(segment
		(start 265.873484 -2.86131)
		(end 265.709146 -2.976372)
		(width 0.14224)
		(layer "In4.Cu")
		(net "DELTA_L_85_10INCH_IN2_DP")
	)
	(segment
		(start 286.75584 -7.366)
		(end 286.506412 -7.009638)
		(width 0.14224)
		(layer "In4.Cu")
		(net "DELTA_L_85_10INCH_IN2_DP")
	)
	(segment
		(start 269.667736 -2.999994)
		(end 268.882876 -7.446772)
		(width 0.14224)
		(layer "In4.Cu")
		(net "DELTA_L_85_10INCH_IN2_DP")
	)
	(segment
		(start 284.754574 -7.330186)
		(end 284.398466 -7.579614)
		(width 0.14224)
		(layer "In4.Cu")
		(net "DELTA_L_85_10INCH_IN2_DP")
	)
	(segment
		(start 291.022532 -3.057906)
		(end 289.658044 -2.81686)
		(width 0.14224)
		(layer "In4.Cu")
		(net "DELTA_L_85_10INCH_IN2_DP")
	)
	(segment
		(start 239.503712 -3.074162)
		(end 238.139224 -2.833116)
		(width 0.14224)
		(layer "In4.Cu")
		(net "DELTA_L_85_10INCH_IN2_DP")
	)
	(segment
		(start 250.019566 -2.876804)
		(end 249.855228 -2.991866)
		(width 0.14224)
		(layer "In4.Cu")
		(net "DELTA_L_85_10INCH_IN2_DP")
	)
	(segment
		(start 218.161108 -2.946654)
		(end 217.84818 -4.719828)
		(width 0.14224)
		(layer "In4.Cu")
		(net "DELTA_L_85_10INCH_IN2_DP")
	)
	(segment
		(start 280.41727 -7.684008)
		(end 278.823674 -7.402576)
		(width 0.14224)
		(layer "In4.Cu")
		(net "DELTA_L_85_10INCH_IN2_DP")
	)
	(segment
		(start 223.1009 -7.01548)
		(end 223.766634 -3.244596)
		(width 0.14224)
		(layer "In4.Cu")
		(net "DELTA_L_85_10INCH_IN2_DP")
	)
	(segment
		(start 253.052834 -7.327392)
		(end 252.696726 -7.57682)
		(width 0.14224)
		(layer "In4.Cu")
		(net "DELTA_L_85_10INCH_IN2_DP")
	)
	(segment
		(start 226.248722 -2.845054)
		(end 226.084384 -2.960116)
		(width 0.14224)
		(layer "In4.Cu")
		(net "DELTA_L_85_10INCH_IN2_DP")
	)
	(segment
		(start 246.87784 -7.013194)
		(end 247.543574 -3.24231)
		(width 0.14224)
		(layer "In4.Cu")
		(net "DELTA_L_85_10INCH_IN2_DP")
	)
	(segment
		(start 262.968994 -7.422642)
		(end 262.719566 -7.066534)
		(width 0.14224)
		(layer "In4.Cu")
		(net "DELTA_L_85_10INCH_IN2_DP")
	)
	(segment
		(start 275.167344 -3.081528)
		(end 273.802856 -2.840482)
		(width 0.14224)
		(layer "In4.Cu")
		(net "DELTA_L_85_10INCH_IN2_DP")
	)
	(segment
		(start 294.894254 -3.083814)
		(end 293.599362 -2.855214)
		(width 0.14224)
		(layer "In4.Cu")
		(net "DELTA_L_85_10INCH_IN2_DP")
	)
	(segment
		(start 290.471606 -6.995668)
		(end 291.137594 -3.222244)
		(width 0.14224)
		(layer "In4.Cu")
		(net "DELTA_L_85_10INCH_IN2_DP")
	)
	(segment
		(start 219.383356 -7.394702)
		(end 219.133928 -7.039102)
		(width 0.14224)
		(layer "In4.Cu")
		(net "DELTA_L_85_10INCH_IN2_DP")
	)
	(segment
		(start 289.658044 -2.81686)
		(end 289.493706 -2.931922)
		(width 0.14224)
		(layer "In4.Cu")
		(net "DELTA_L_85_10INCH_IN2_DP")
	)
	(segment
		(start 245.899686 -2.951988)
		(end 245.114064 -7.402068)
		(width 0.14224)
		(layer "In4.Cu")
		(net "DELTA_L_85_10INCH_IN2_DP")
	)
	(segment
		(start 252.696726 -7.57682)
		(end 251.10313 -7.295388)
		(width 0.14224)
		(layer "In4.Cu")
		(net "DELTA_L_85_10INCH_IN2_DP")
	)
	(segment
		(start 227.728272 -3.250438)
		(end 227.61321 -3.0861)
		(width 0.14224)
		(layer "In4.Cu")
		(net "DELTA_L_85_10INCH_IN2_DP")
	)
	(segment
		(start 259.423662 -3.288538)
		(end 259.3086 -3.1242)
		(width 0.14224)
		(layer "In4.Cu")
		(net "DELTA_L_85_10INCH_IN2_DP")
	)
	(segment
		(start 270.895572 -7.4168)
		(end 270.646144 -7.0612)
		(width 0.14224)
		(layer "In4.Cu")
		(net "DELTA_L_85_10INCH_IN2_DP")
	)
	(segment
		(start 276.812756 -7.422388)
		(end 276.456648 -7.671816)
		(width 0.14224)
		(layer "In4.Cu")
		(net "DELTA_L_85_10INCH_IN2_DP")
	)
	(segment
		(start 219.133928 -7.039102)
		(end 219.804996 -3.236976)
		(width 0.14224)
		(layer "In4.Cu")
		(net "DELTA_L_85_10INCH_IN2_DP")
	)
	(segment
		(start 272.489168 -7.698232)
		(end 270.895572 -7.4168)
		(width 0.14224)
		(layer "In4.Cu")
		(net "DELTA_L_85_10INCH_IN2_DP")
	)
	(segment
		(start 251.10313 -7.295388)
		(end 250.853702 -6.93928)
		(width 0.14224)
		(layer "In4.Cu")
		(net "DELTA_L_85_10INCH_IN2_DP")
	)
	(segment
		(start 289.493706 -2.931922)
		(end 288.70529 -7.398004)
		(width 0.14224)
		(layer "In4.Cu")
		(net "DELTA_L_85_10INCH_IN2_DP")
	)
	(segment
		(start 248.720864 -7.650734)
		(end 247.127268 -7.369302)
		(width 0.14224)
		(layer "In4.Cu")
		(net "DELTA_L_85_10INCH_IN2_DP")
	)
	(segment
		(start 242.098068 -2.853944)
		(end 241.93373 -2.969006)
		(width 0.14224)
		(layer "In4.Cu")
		(net "DELTA_L_85_10INCH_IN2_DP")
	)
	(segment
		(start 296.314876 -5.218176)
		(end 295.360344 -5.05841)
		(width 0.14224)
		(layer "In4.Cu")
		(net "DELTA_L_85_10INCH_IN2_DP")
	)
	(segment
		(start 236.836966 -7.627112)
		(end 235.24337 -7.34568)
		(width 0.14224)
		(layer "In4.Cu")
		(net "DELTA_L_85_10INCH_IN2_DP")
	)
	(segment
		(start 298.769786 -5.218176)
		(end 296.314876 -5.218176)
		(width 0.14224)
		(layer "In4.Cu")
		(net "DELTA_L_85_10INCH_IN2_DP")
	)
	(segment
		(start 262.719566 -7.066534)
		(end 263.388602 -3.276092)
		(width 0.14224)
		(layer "In4.Cu")
		(net "DELTA_L_85_10INCH_IN2_DP")
	)
	(segment
		(start 231.693974 -3.233928)
		(end 231.578912 -3.069844)
		(width 0.14224)
		(layer "In4.Cu")
		(net "DELTA_L_85_10INCH_IN2_DP")
	)
	(segment
		(start 272.84553 -7.448804)
		(end 272.489168 -7.698232)
		(width 0.14224)
		(layer "In4.Cu")
		(net "DELTA_L_85_10INCH_IN2_DP")
	)
	(segment
		(start 274.863052 -7.390384)
		(end 274.613624 -7.034276)
		(width 0.14224)
		(layer "In4.Cu")
		(net "DELTA_L_85_10INCH_IN2_DP")
	)
	(segment
		(start 230.214424 -2.828798)
		(end 230.050086 -2.94386)
		(width 0.14224)
		(layer "In4.Cu")
		(net "DELTA_L_85_10INCH_IN2_DP")
	)
	(segment
		(start 277.761954 -2.86131)
		(end 277.597616 -2.976372)
		(width 0.14224)
		(layer "In4.Cu")
		(net "DELTA_L_85_10INCH_IN2_DP")
	)
	(segment
		(start 231.033828 -6.973316)
		(end 231.693974 -3.233928)
		(width 0.14224)
		(layer "In4.Cu")
		(net "DELTA_L_85_10INCH_IN2_DP")
	)
	(segment
		(start 235.5342 -3.111754)
		(end 234.169712 -2.870708)
		(width 0.14224)
		(layer "In4.Cu")
		(net "DELTA_L_85_10INCH_IN2_DP")
	)
	(segment
		(start 239.203738 -7.357872)
		(end 238.95431 -7.001764)
		(width 0.14224)
		(layer "In4.Cu")
		(net "DELTA_L_85_10INCH_IN2_DP")
	)
	(segment
		(start 276.456648 -7.671816)
		(end 274.863052 -7.390384)
		(width 0.14224)
		(layer "In4.Cu")
		(net "DELTA_L_85_10INCH_IN2_DP")
	)
	(segment
		(start 214.24011 -5.218176)
		(end 213.94928 -5.509006)
		(width 0.14224)
		(layer "In4.Cu")
		(net "DELTA_L_85_10INCH_IN2_DP")
	)
	(segment
		(start 226.084384 -2.960116)
		(end 225.300032 -7.403592)
		(width 0.14224)
		(layer "In4.Cu")
		(net "DELTA_L_85_10INCH_IN2_DP")
	)
	(segment
		(start 269.832074 -2.885186)
		(end 269.667736 -2.999994)
		(width 0.14224)
		(layer "In4.Cu")
		(net "DELTA_L_85_10INCH_IN2_DP")
	)
	(segment
		(start 228.909118 -7.639304)
		(end 227.315522 -7.357872)
		(width 0.14224)
		(layer "In4.Cu")
		(net "DELTA_L_85_10INCH_IN2_DP")
	)
	(segment
		(start 227.066094 -7.001764)
		(end 227.728272 -3.250438)
		(width 0.14224)
		(layer "In4.Cu")
		(net "DELTA_L_85_10INCH_IN2_DP")
	)
	(segment
		(start 222.287084 -2.839212)
		(end 222.122746 -2.954274)
		(width 0.14224)
		(layer "In4.Cu")
		(net "DELTA_L_85_10INCH_IN2_DP")
	)
	(segment
		(start 255.056894 -7.346696)
		(end 254.807466 -6.990588)
		(width 0.14224)
		(layer "In4.Cu")
		(net "DELTA_L_85_10INCH_IN2_DP")
	)
	(segment
		(start 264.918698 -7.454646)
		(end 264.56259 -7.704074)
		(width 0.14224)
		(layer "In4.Cu")
		(net "DELTA_L_85_10INCH_IN2_DP")
	)
	(segment
		(start 243.16436 -7.370064)
		(end 242.914932 -7.013956)
		(width 0.14224)
		(layer "In4.Cu")
		(net "DELTA_L_85_10INCH_IN2_DP")
	)
	(segment
		(start 237.193074 -7.377684)
		(end 236.836966 -7.627112)
		(width 0.14224)
		(layer "In4.Cu")
		(net "DELTA_L_85_10INCH_IN2_DP")
	)
	(segment
		(start 281.72029 -2.886202)
		(end 281.555952 -3.001264)
		(width 0.14224)
		(layer "In4.Cu")
		(net "DELTA_L_85_10INCH_IN2_DP")
	)
	(segment
		(start 287.05429 -3.088386)
		(end 285.689802 -2.84734)
		(width 0.14224)
		(layer "In4.Cu")
		(net "DELTA_L_85_10INCH_IN2_DP")
	)
	(segment
		(start 285.525464 -2.962402)
		(end 284.754574 -7.330186)
		(width 0.14224)
		(layer "In4.Cu")
		(net "DELTA_L_85_10INCH_IN2_DP")
	)
	(segment
		(start 284.398466 -7.579614)
		(end 282.80487 -7.298182)
		(width 0.14224)
		(layer "In4.Cu")
		(net "DELTA_L_85_10INCH_IN2_DP")
	)
	(segment
		(start 279.241504 -3.26644)
		(end 279.126442 -3.102356)
		(width 0.14224)
		(layer "In4.Cu")
		(net "DELTA_L_85_10INCH_IN2_DP")
	)
	(segment
		(start 295.078404 -3.346958)
		(end 294.894254 -3.083814)
		(width 0.14224)
		(layer "In4.Cu")
		(net "DELTA_L_85_10INCH_IN2_DP")
	)
	(segment
		(start 291.137594 -3.222244)
		(end 291.022532 -3.057906)
		(width 0.14224)
		(layer "In4.Cu")
		(net "DELTA_L_85_10INCH_IN2_DP")
	)
	(segment
		(start 255.35509 -3.071368)
		(end 253.990602 -2.830322)
		(width 0.14224)
		(layer "In4.Cu")
		(net "DELTA_L_85_10INCH_IN2_DP")
	)
	(segment
		(start 231.578912 -3.069844)
		(end 230.214424 -2.828798)
		(width 0.14224)
		(layer "In4.Cu")
		(net "DELTA_L_85_10INCH_IN2_DP")
	)
	(segment
		(start 283.19984 -3.291586)
		(end 283.084778 -3.127248)
		(width 0.14224)
		(layer "In4.Cu")
		(net "DELTA_L_85_10INCH_IN2_DP")
	)
	(segment
		(start 220.976952 -7.676134)
		(end 219.383356 -7.394702)
		(width 0.14224)
		(layer "In4.Cu")
		(net "DELTA_L_85_10INCH_IN2_DP")
	)
	(segment
		(start 260.605524 -7.67207)
		(end 259.011928 -7.390638)
		(width 0.14224)
		(layer "In4.Cu")
		(net "DELTA_L_85_10INCH_IN2_DP")
	)
	(segment
		(start 277.597616 -2.976372)
		(end 276.812756 -7.422388)
		(width 0.14224)
		(layer "In4.Cu")
		(net "DELTA_L_85_10INCH_IN2_DP")
	)
	(segment
		(start 230.050086 -2.94386)
		(end 229.265226 -7.389876)
		(width 0.14224)
		(layer "In4.Cu")
		(net "DELTA_L_85_10INCH_IN2_DP")
	)
	(segment
		(start 263.388602 -3.276092)
		(end 263.27354 -3.111754)
		(width 0.14224)
		(layer "In4.Cu")
		(net "DELTA_L_85_10INCH_IN2_DP")
	)
	(segment
		(start 285.689802 -2.84734)
		(end 285.525464 -2.962402)
		(width 0.14224)
		(layer "In4.Cu")
		(net "DELTA_L_85_10INCH_IN2_DP")
	)
	(segment
		(start 299.712888 -4.82727)
		(end 299.060616 -4.645406)
		(width 0.12954)
		(layer "F.Cu")
		(net "DELTA_L_85_10INCH_IN2_DN")
	)
	(segment
		(start 213.297008 -4.82727)
		(end 213.94928 -4.645406)
		(width 0.12954)
		(layer "F.Cu")
		(net "DELTA_L_85_10INCH_IN2_DN")
	)
	(segment
		(start 231.99217 -3.167634)
		(end 231.332024 -6.907276)
		(width 0.14224)
		(layer "In4.Cu")
		(net "DELTA_L_85_10INCH_IN2_DN")
	)
	(segment
		(start 272.587974 -7.28472)
		(end 273.380962 -2.79146)
		(width 0.14224)
		(layer "In4.Cu")
		(net "DELTA_L_85_10INCH_IN2_DN")
	)
	(segment
		(start 239.916716 -3.172206)
		(end 239.252506 -6.935724)
		(width 0.14224)
		(layer "In4.Cu")
		(net "DELTA_L_85_10INCH_IN2_DN")
	)
	(segment
		(start 244.691916 -7.3533)
		(end 244.856508 -7.237984)
		(width 0.14224)
		(layer "In4.Cu")
		(net "DELTA_L_85_10INCH_IN2_DN")
	)
	(segment
		(start 251.151898 -6.87324)
		(end 251.267214 -7.037832)
		(width 0.14224)
		(layer "In4.Cu")
		(net "DELTA_L_85_10INCH_IN2_DN")
	)
	(segment
		(start 263.017762 -7.000494)
		(end 263.133078 -7.165086)
		(width 0.14224)
		(layer "In4.Cu")
		(net "DELTA_L_85_10INCH_IN2_DN")
	)
	(segment
		(start 269.41018 -2.835656)
		(end 269.766288 -2.58699)
		(width 0.14224)
		(layer "In4.Cu")
		(net "DELTA_L_85_10INCH_IN2_DN")
	)
	(segment
		(start 239.667796 -2.816606)
		(end 239.916716 -3.172206)
		(width 0.14224)
		(layer "In4.Cu")
		(net "DELTA_L_85_10INCH_IN2_DN")
	)
	(segment
		(start 235.407454 -7.088124)
		(end 236.770926 -7.328916)
		(width 0.14224)
		(layer "In4.Cu")
		(net "DELTA_L_85_10INCH_IN2_DN")
	)
	(segment
		(start 219.854018 -2.815082)
		(end 220.103192 -3.170936)
		(width 0.14224)
		(layer "In4.Cu")
		(net "DELTA_L_85_10INCH_IN2_DN")
	)
	(segment
		(start 276.390608 -7.37362)
		(end 276.5552 -7.258304)
		(width 0.14224)
		(layer "In4.Cu")
		(net "DELTA_L_85_10INCH_IN2_DN")
	)
	(segment
		(start 221.075758 -7.262622)
		(end 221.86519 -2.79019)
		(width 0.14224)
		(layer "In4.Cu")
		(net "DELTA_L_85_10INCH_IN2_DN")
	)
	(segment
		(start 264.661142 -7.290562)
		(end 265.45159 -2.812288)
		(width 0.14224)
		(layer "In4.Cu")
		(net "DELTA_L_85_10INCH_IN2_DN")
	)
	(segment
		(start 217.903552 -2.78257)
		(end 218.259406 -2.533396)
		(width 0.14224)
		(layer "In4.Cu")
		(net "DELTA_L_85_10INCH_IN2_DN")
	)
	(segment
		(start 264.49655 -7.405878)
		(end 264.661142 -7.290562)
		(width 0.14224)
		(layer "In4.Cu")
		(net "DELTA_L_85_10INCH_IN2_DN")
	)
	(segment
		(start 282.853638 -6.876034)
		(end 282.968954 -7.040626)
		(width 0.14224)
		(layer "In4.Cu")
		(net "DELTA_L_85_10INCH_IN2_DN")
	)
	(segment
		(start 245.997984 -2.53873)
		(end 247.592596 -2.820416)
		(width 0.14224)
		(layer "In4.Cu")
		(net "DELTA_L_85_10INCH_IN2_DN")
	)
	(segment
		(start 233.747818 -2.821686)
		(end 234.103672 -2.572512)
		(width 0.14224)
		(layer "In4.Cu")
		(net "DELTA_L_85_10INCH_IN2_DN")
	)
	(segment
		(start 282.968954 -7.040626)
		(end 284.332426 -7.281418)
		(width 0.14224)
		(layer "In4.Cu")
		(net "DELTA_L_85_10INCH_IN2_DN")
	)
	(segment
		(start 219.432124 -6.972808)
		(end 219.54744 -7.137146)
		(width 0.14224)
		(layer "In4.Cu")
		(net "DELTA_L_85_10INCH_IN2_DN")
	)
	(segment
		(start 268.62532 -7.282688)
		(end 269.41018 -2.835656)
		(width 0.14224)
		(layer "In4.Cu")
		(net "DELTA_L_85_10INCH_IN2_DN")
	)
	(segment
		(start 257.878072 -2.584958)
		(end 259.472684 -2.866644)
		(width 0.14224)
		(layer "In4.Cu")
		(net "DELTA_L_85_10INCH_IN2_DN")
	)
	(segment
		(start 249.953526 -2.578608)
		(end 251.548392 -2.860294)
		(width 0.14224)
		(layer "In4.Cu")
		(net "DELTA_L_85_10INCH_IN2_DN")
	)
	(segment
		(start 228.843078 -7.341108)
		(end 229.00767 -7.225792)
		(width 0.14224)
		(layer "In4.Cu")
		(net "DELTA_L_85_10INCH_IN2_DN")
	)
	(segment
		(start 234.103672 -2.572512)
		(end 235.698284 -2.854198)
		(width 0.14224)
		(layer "In4.Cu")
		(net "DELTA_L_85_10INCH_IN2_DN")
	)
	(segment
		(start 265.807444 -2.563114)
		(end 267.402056 -2.8448)
		(width 0.14224)
		(layer "In4.Cu")
		(net "DELTA_L_85_10INCH_IN2_DN")
	)
	(segment
		(start 255.519174 -2.813812)
		(end 255.768348 -3.169666)
		(width 0.14224)
		(layer "In4.Cu")
		(net "DELTA_L_85_10INCH_IN2_DN")
	)
	(segment
		(start 259.176012 -7.133082)
		(end 260.539484 -7.373874)
		(width 0.14224)
		(layer "In4.Cu")
		(net "DELTA_L_85_10INCH_IN2_DN")
	)
	(segment
		(start 288.447734 -7.23392)
		(end 289.23615 -2.767838)
		(width 0.14224)
		(layer "In4.Cu")
		(net "DELTA_L_85_10INCH_IN2_DN")
	)
	(segment
		(start 229.79253 -2.779776)
		(end 230.148384 -2.530602)
		(width 0.14224)
		(layer "In4.Cu")
		(net "DELTA_L_85_10INCH_IN2_DN")
	)
	(segment
		(start 220.103192 -3.170936)
		(end 219.432124 -6.972808)
		(width 0.14224)
		(layer "In4.Cu")
		(net "DELTA_L_85_10INCH_IN2_DN")
	)
	(segment
		(start 217.590624 -4.55549)
		(end 217.903552 -2.78257)
		(width 0.14224)
		(layer "In4.Cu")
		(net "DELTA_L_85_10INCH_IN2_DN")
	)
	(segment
		(start 256.58445 -7.329932)
		(end 256.749042 -7.214616)
		(width 0.14224)
		(layer "In4.Cu")
		(net "DELTA_L_85_10INCH_IN2_DN")
	)
	(segment
		(start 236.935518 -7.2136)
		(end 237.71733 -2.784094)
		(width 0.14224)
		(layer "In4.Cu")
		(net "DELTA_L_85_10INCH_IN2_DN")
	)
	(segment
		(start 271.059656 -7.159244)
		(end 272.423128 -7.400036)
		(width 0.14224)
		(layer "In4.Cu")
		(net "DELTA_L_85_10INCH_IN2_DN")
	)
	(segment
		(start 272.423128 -7.400036)
		(end 272.587974 -7.28472)
		(width 0.14224)
		(layer "In4.Cu")
		(net "DELTA_L_85_10INCH_IN2_DN")
	)
	(segment
		(start 222.221044 -2.541016)
		(end 223.815656 -2.822702)
		(width 0.14224)
		(layer "In4.Cu")
		(net "DELTA_L_85_10INCH_IN2_DN")
	)
	(segment
		(start 281.65425 -2.588006)
		(end 283.248862 -2.869692)
		(width 0.14224)
		(layer "In4.Cu")
		(net "DELTA_L_85_10INCH_IN2_DN")
	)
	(segment
		(start 277.34006 -2.812288)
		(end 277.695914 -2.563114)
		(width 0.14224)
		(layer "In4.Cu")
		(net "DELTA_L_85_10INCH_IN2_DN")
	)
	(segment
		(start 275.580602 -3.179826)
		(end 274.91182 -6.968236)
		(width 0.14224)
		(layer "In4.Cu")
		(net "DELTA_L_85_10INCH_IN2_DN")
	)
	(segment
		(start 281.298396 -2.83718)
		(end 281.65425 -2.588006)
		(width 0.14224)
		(layer "In4.Cu")
		(net "DELTA_L_85_10INCH_IN2_DN")
	)
	(segment
		(start 283.248862 -2.869692)
		(end 283.498036 -3.225546)
		(width 0.14224)
		(layer "In4.Cu")
		(net "DELTA_L_85_10INCH_IN2_DN")
	)
	(segment
		(start 243.213128 -6.947916)
		(end 243.328444 -7.112508)
		(width 0.14224)
		(layer "In4.Cu")
		(net "DELTA_L_85_10INCH_IN2_DN")
	)
	(segment
		(start 293.194486 -2.793746)
		(end 293.533576 -2.557272)
		(width 0.14224)
		(layer "In4.Cu")
		(net "DELTA_L_85_10INCH_IN2_DN")
	)
	(segment
		(start 259.060696 -6.96849)
		(end 259.176012 -7.133082)
		(width 0.14224)
		(layer "In4.Cu")
		(net "DELTA_L_85_10INCH_IN2_DN")
	)
	(segment
		(start 292.412928 -7.219696)
		(end 293.194486 -2.793746)
		(width 0.14224)
		(layer "In4.Cu")
		(net "DELTA_L_85_10INCH_IN2_DN")
	)
	(segment
		(start 263.686798 -3.210052)
		(end 263.017762 -7.000494)
		(width 0.14224)
		(layer "In4.Cu")
		(net "DELTA_L_85_10INCH_IN2_DN")
	)
	(segment
		(start 277.695914 -2.563114)
		(end 279.290526 -2.8448)
		(width 0.14224)
		(layer "In4.Cu")
		(net "DELTA_L_85_10INCH_IN2_DN")
	)
	(segment
		(start 289.23615 -2.767838)
		(end 289.592004 -2.518664)
		(width 0.14224)
		(layer "In4.Cu")
		(net "DELTA_L_85_10INCH_IN2_DN")
	)
	(segment
		(start 247.84177 -3.17627)
		(end 247.176036 -6.947154)
		(width 0.14224)
		(layer "In4.Cu")
		(net "DELTA_L_85_10INCH_IN2_DN")
	)
	(segment
		(start 292.24859 -7.335012)
		(end 292.412928 -7.219696)
		(width 0.14224)
		(layer "In4.Cu")
		(net "DELTA_L_85_10INCH_IN2_DN")
	)
	(segment
		(start 295.523158 -4.799584)
		(end 296.338498 -4.936236)
		(width 0.14224)
		(layer "In4.Cu")
		(net "DELTA_L_85_10INCH_IN2_DN")
	)
	(segment
		(start 293.533576 -2.557272)
		(end 295.058338 -2.826258)
		(width 0.14224)
		(layer "In4.Cu")
		(net "DELTA_L_85_10INCH_IN2_DN")
	)
	(segment
		(start 291.186616 -2.80035)
		(end 291.43579 -3.156204)
		(width 0.14224)
		(layer "In4.Cu")
		(net "DELTA_L_85_10INCH_IN2_DN")
	)
	(segment
		(start 257.522218 -2.834132)
		(end 257.878072 -2.584958)
		(width 0.14224)
		(layer "In4.Cu")
		(net "DELTA_L_85_10INCH_IN2_DN")
	)
	(segment
		(start 266.98194 -6.99262)
		(end 267.097256 -7.157212)
		(width 0.14224)
		(layer "In4.Cu")
		(net "DELTA_L_85_10INCH_IN2_DN")
	)
	(segment
		(start 231.742996 -2.812288)
		(end 231.99217 -3.167634)
		(width 0.14224)
		(layer "In4.Cu")
		(net "DELTA_L_85_10INCH_IN2_DN")
	)
	(segment
		(start 280.515568 -7.270496)
		(end 281.298396 -2.83718)
		(width 0.14224)
		(layer "In4.Cu")
		(net "DELTA_L_85_10INCH_IN2_DN")
	)
	(segment
		(start 244.856508 -7.237984)
		(end 245.64213 -2.787904)
		(width 0.14224)
		(layer "In4.Cu")
		(net "DELTA_L_85_10INCH_IN2_DN")
	)
	(segment
		(start 280.35123 -7.385812)
		(end 280.515568 -7.270496)
		(width 0.14224)
		(layer "In4.Cu")
		(net "DELTA_L_85_10INCH_IN2_DN")
	)
	(segment
		(start 252.795278 -7.163308)
		(end 253.568708 -2.7813)
		(width 0.14224)
		(layer "In4.Cu")
		(net "DELTA_L_85_10INCH_IN2_DN")
	)
	(segment
		(start 225.042476 -7.239508)
		(end 225.826828 -2.796032)
		(width 0.14224)
		(layer "In4.Cu")
		(net "DELTA_L_85_10INCH_IN2_DN")
	)
	(segment
		(start 253.568708 -2.7813)
		(end 253.924562 -2.532126)
		(width 0.14224)
		(layer "In4.Cu")
		(net "DELTA_L_85_10INCH_IN2_DN")
	)
	(segment
		(start 227.479606 -7.100316)
		(end 228.843078 -7.341108)
		(width 0.14224)
		(layer "In4.Cu")
		(net "DELTA_L_85_10INCH_IN2_DN")
	)
	(segment
		(start 260.539484 -7.373874)
		(end 260.704076 -7.258558)
		(width 0.14224)
		(layer "In4.Cu")
		(net "DELTA_L_85_10INCH_IN2_DN")
	)
	(segment
		(start 223.399096 -6.94944)
		(end 223.514412 -7.114032)
		(width 0.14224)
		(layer "In4.Cu")
		(net "DELTA_L_85_10INCH_IN2_DN")
	)
	(segment
		(start 251.797312 -3.216402)
		(end 251.151898 -6.87324)
		(width 0.14224)
		(layer "In4.Cu")
		(net "DELTA_L_85_10INCH_IN2_DN")
	)
	(segment
		(start 221.86519 -2.79019)
		(end 222.221044 -2.541016)
		(width 0.14224)
		(layer "In4.Cu")
		(net "DELTA_L_85_10INCH_IN2_DN")
	)
	(segment
		(start 231.332024 -6.907276)
		(end 231.44734 -7.071868)
		(width 0.14224)
		(layer "In4.Cu")
		(net "DELTA_L_85_10INCH_IN2_DN")
	)
	(segment
		(start 283.498036 -3.225546)
		(end 282.853638 -6.876034)
		(width 0.14224)
		(layer "In4.Cu")
		(net "DELTA_L_85_10INCH_IN2_DN")
	)
	(segment
		(start 253.924562 -2.532126)
		(end 255.519174 -2.813812)
		(width 0.14224)
		(layer "In4.Cu")
		(net "DELTA_L_85_10INCH_IN2_DN")
	)
	(segment
		(start 248.819416 -7.237222)
		(end 249.597672 -2.827782)
		(width 0.14224)
		(layer "In4.Cu")
		(net "DELTA_L_85_10INCH_IN2_DN")
	)
	(segment
		(start 252.630686 -7.278624)
		(end 252.795278 -7.163308)
		(width 0.14224)
		(layer "In4.Cu")
		(net "DELTA_L_85_10INCH_IN2_DN")
	)
	(segment
		(start 235.698284 -2.854198)
		(end 235.947458 -3.210052)
		(width 0.14224)
		(layer "In4.Cu")
		(net "DELTA_L_85_10INCH_IN2_DN")
	)
	(segment
		(start 224.877884 -7.354824)
		(end 225.042476 -7.239508)
		(width 0.14224)
		(layer "In4.Cu")
		(net "DELTA_L_85_10INCH_IN2_DN")
	)
	(segment
		(start 279.5397 -3.200146)
		(end 278.872442 -6.980174)
		(width 0.14224)
		(layer "In4.Cu")
		(net "DELTA_L_85_10INCH_IN2_DN")
	)
	(segment
		(start 265.45159 -2.812288)
		(end 265.807444 -2.563114)
		(width 0.14224)
		(layer "In4.Cu")
		(net "DELTA_L_85_10INCH_IN2_DN")
	)
	(segment
		(start 278.987758 -7.14502)
		(end 280.35123 -7.385812)
		(width 0.14224)
		(layer "In4.Cu")
		(net "DELTA_L_85_10INCH_IN2_DN")
	)
	(segment
		(start 295.3766 -3.280918)
		(end 295.191434 -4.329176)
		(width 0.14224)
		(layer "In4.Cu")
		(net "DELTA_L_85_10INCH_IN2_DN")
	)
	(segment
		(start 286.919924 -7.108444)
		(end 288.283396 -7.349236)
		(width 0.14224)
		(layer "In4.Cu")
		(net "DELTA_L_85_10INCH_IN2_DN")
	)
	(segment
		(start 248.654824 -7.352538)
		(end 248.819416 -7.237222)
		(width 0.14224)
		(layer "In4.Cu")
		(net "DELTA_L_85_10INCH_IN2_DN")
	)
	(segment
		(start 267.402056 -2.8448)
		(end 267.65123 -3.200654)
		(width 0.14224)
		(layer "In4.Cu")
		(net "DELTA_L_85_10INCH_IN2_DN")
	)
	(segment
		(start 285.267908 -2.798318)
		(end 285.623762 -2.549144)
		(width 0.14224)
		(layer "In4.Cu")
		(net "DELTA_L_85_10INCH_IN2_DN")
	)
	(segment
		(start 240.895886 -7.225792)
		(end 241.676174 -2.804922)
		(width 0.14224)
		(layer "In4.Cu")
		(net "DELTA_L_85_10INCH_IN2_DN")
	)
	(segment
		(start 284.332426 -7.281418)
		(end 284.497018 -7.166102)
		(width 0.14224)
		(layer "In4.Cu")
		(net "DELTA_L_85_10INCH_IN2_DN")
	)
	(segment
		(start 290.769802 -6.929628)
		(end 290.885118 -7.09422)
		(width 0.14224)
		(layer "In4.Cu")
		(net "DELTA_L_85_10INCH_IN2_DN")
	)
	(segment
		(start 217.046556 -4.936236)
		(end 217.590624 -4.55549)
		(width 0.14224)
		(layer "In4.Cu")
		(net "DELTA_L_85_10INCH_IN2_DN")
	)
	(segment
		(start 255.105662 -6.924548)
		(end 255.220978 -7.08914)
		(width 0.14224)
		(layer "In4.Cu")
		(net "DELTA_L_85_10INCH_IN2_DN")
	)
	(segment
		(start 273.380962 -2.79146)
		(end 273.736816 -2.542286)
		(width 0.14224)
		(layer "In4.Cu")
		(net "DELTA_L_85_10INCH_IN2_DN")
	)
	(segment
		(start 279.290526 -2.8448)
		(end 279.5397 -3.200146)
		(width 0.14224)
		(layer "In4.Cu")
		(net "DELTA_L_85_10INCH_IN2_DN")
	)
	(segment
		(start 237.71733 -2.784094)
		(end 238.073184 -2.53492)
		(width 0.14224)
		(layer "In4.Cu")
		(net "DELTA_L_85_10INCH_IN2_DN")
	)
	(segment
		(start 247.592596 -2.820416)
		(end 247.84177 -3.17627)
		(width 0.14224)
		(layer "In4.Cu")
		(net "DELTA_L_85_10INCH_IN2_DN")
	)
	(segment
		(start 230.148384 -2.530602)
		(end 231.742996 -2.812288)
		(width 0.14224)
		(layer "In4.Cu")
		(net "DELTA_L_85_10INCH_IN2_DN")
	)
	(segment
		(start 273.736816 -2.542286)
		(end 275.331428 -2.823972)
		(width 0.14224)
		(layer "In4.Cu")
		(net "DELTA_L_85_10INCH_IN2_DN")
	)
	(segment
		(start 296.338498 -4.936236)
		(end 298.769786 -4.936236)
		(width 0.14224)
		(layer "In4.Cu")
		(net "DELTA_L_85_10INCH_IN2_DN")
	)
	(segment
		(start 249.597672 -2.827782)
		(end 249.953526 -2.578608)
		(width 0.14224)
		(layer "In4.Cu")
		(net "DELTA_L_85_10INCH_IN2_DN")
	)
	(segment
		(start 276.5552 -7.258304)
		(end 277.34006 -2.812288)
		(width 0.14224)
		(layer "In4.Cu")
		(net "DELTA_L_85_10INCH_IN2_DN")
	)
	(segment
		(start 278.872442 -6.980174)
		(end 278.987758 -7.14502)
		(width 0.14224)
		(layer "In4.Cu")
		(net "DELTA_L_85_10INCH_IN2_DN")
	)
	(segment
		(start 263.133078 -7.165086)
		(end 264.49655 -7.405878)
		(width 0.14224)
		(layer "In4.Cu")
		(net "DELTA_L_85_10INCH_IN2_DN")
	)
	(segment
		(start 245.64213 -2.787904)
		(end 245.997984 -2.53873)
		(width 0.14224)
		(layer "In4.Cu")
		(net "DELTA_L_85_10INCH_IN2_DN")
	)
	(segment
		(start 256.749042 -7.214616)
		(end 257.522218 -2.834132)
		(width 0.14224)
		(layer "In4.Cu")
		(net "DELTA_L_85_10INCH_IN2_DN")
	)
	(segment
		(start 298.769786 -4.936236)
		(end 299.060616 -4.645406)
		(width 0.14224)
		(layer "In4.Cu")
		(net "DELTA_L_85_10INCH_IN2_DN")
	)
	(segment
		(start 259.721858 -3.222498)
		(end 259.060696 -6.96849)
		(width 0.14224)
		(layer "In4.Cu")
		(net "DELTA_L_85_10INCH_IN2_DN")
	)
	(segment
		(start 286.804608 -6.943598)
		(end 286.919924 -7.108444)
		(width 0.14224)
		(layer "In4.Cu")
		(net "DELTA_L_85_10INCH_IN2_DN")
	)
	(segment
		(start 218.259406 -2.533396)
		(end 219.854018 -2.815082)
		(width 0.14224)
		(layer "In4.Cu")
		(net "DELTA_L_85_10INCH_IN2_DN")
	)
	(segment
		(start 235.947458 -3.210052)
		(end 235.292138 -6.923532)
		(width 0.14224)
		(layer "In4.Cu")
		(net "DELTA_L_85_10INCH_IN2_DN")
	)
	(segment
		(start 225.826828 -2.796032)
		(end 226.182682 -2.546858)
		(width 0.14224)
		(layer "In4.Cu")
		(net "DELTA_L_85_10INCH_IN2_DN")
	)
	(segment
		(start 270.94434 -6.994906)
		(end 271.059656 -7.159244)
		(width 0.14224)
		(layer "In4.Cu")
		(net "DELTA_L_85_10INCH_IN2_DN")
	)
	(segment
		(start 227.777294 -2.828544)
		(end 228.026468 -3.184398)
		(width 0.14224)
		(layer "In4.Cu")
		(net "DELTA_L_85_10INCH_IN2_DN")
	)
	(segment
		(start 285.623762 -2.549144)
		(end 287.218374 -2.83083)
		(width 0.14224)
		(layer "In4.Cu")
		(net "DELTA_L_85_10INCH_IN2_DN")
	)
	(segment
		(start 290.885118 -7.09422)
		(end 292.24859 -7.335012)
		(width 0.14224)
		(layer "In4.Cu")
		(net "DELTA_L_85_10INCH_IN2_DN")
	)
	(segment
		(start 287.218374 -2.83083)
		(end 287.467548 -3.186684)
		(width 0.14224)
		(layer "In4.Cu")
		(net "DELTA_L_85_10INCH_IN2_DN")
	)
	(segment
		(start 231.44734 -7.071868)
		(end 232.810812 -7.31266)
		(width 0.14224)
		(layer "In4.Cu")
		(net "DELTA_L_85_10INCH_IN2_DN")
	)
	(segment
		(start 259.472684 -2.866644)
		(end 259.721858 -3.222498)
		(width 0.14224)
		(layer "In4.Cu")
		(net "DELTA_L_85_10INCH_IN2_DN")
	)
	(segment
		(start 267.65123 -3.200654)
		(end 266.98194 -6.99262)
		(width 0.14224)
		(layer "In4.Cu")
		(net "DELTA_L_85_10INCH_IN2_DN")
	)
	(segment
		(start 241.676174 -2.804922)
		(end 242.032028 -2.555748)
		(width 0.14224)
		(layer "In4.Cu")
		(net "DELTA_L_85_10INCH_IN2_DN")
	)
	(segment
		(start 223.815656 -2.822702)
		(end 224.06483 -3.178556)
		(width 0.14224)
		(layer "In4.Cu")
		(net "DELTA_L_85_10INCH_IN2_DN")
	)
	(segment
		(start 255.220978 -7.08914)
		(end 256.58445 -7.329932)
		(width 0.14224)
		(layer "In4.Cu")
		(net "DELTA_L_85_10INCH_IN2_DN")
	)
	(segment
		(start 243.328444 -7.112508)
		(end 244.691916 -7.3533)
		(width 0.14224)
		(layer "In4.Cu")
		(net "DELTA_L_85_10INCH_IN2_DN")
	)
	(segment
		(start 242.032028 -2.555748)
		(end 243.62664 -2.837434)
		(width 0.14224)
		(layer "In4.Cu")
		(net "DELTA_L_85_10INCH_IN2_DN")
	)
	(segment
		(start 219.54744 -7.137146)
		(end 220.910912 -7.377938)
		(width 0.14224)
		(layer "In4.Cu")
		(net "DELTA_L_85_10INCH_IN2_DN")
	)
	(segment
		(start 295.191434 -4.329176)
		(end 295.523158 -4.799584)
		(width 0.14224)
		(layer "In4.Cu")
		(net "DELTA_L_85_10INCH_IN2_DN")
	)
	(segment
		(start 220.910912 -7.377938)
		(end 221.075758 -7.262622)
		(width 0.14224)
		(layer "In4.Cu")
		(net "DELTA_L_85_10INCH_IN2_DN")
	)
	(segment
		(start 243.62664 -2.837434)
		(end 243.875814 -3.193288)
		(width 0.14224)
		(layer "In4.Cu")
		(net "DELTA_L_85_10INCH_IN2_DN")
	)
	(segment
		(start 239.252506 -6.935724)
		(end 239.367822 -7.100316)
		(width 0.14224)
		(layer "In4.Cu")
		(net "DELTA_L_85_10INCH_IN2_DN")
	)
	(segment
		(start 291.43579 -3.156204)
		(end 290.769802 -6.929628)
		(width 0.14224)
		(layer "In4.Cu")
		(net "DELTA_L_85_10INCH_IN2_DN")
	)
	(segment
		(start 228.026468 -3.184398)
		(end 227.36429 -6.935724)
		(width 0.14224)
		(layer "In4.Cu")
		(net "DELTA_L_85_10INCH_IN2_DN")
	)
	(segment
		(start 236.770926 -7.328916)
		(end 236.935518 -7.2136)
		(width 0.14224)
		(layer "In4.Cu")
		(net "DELTA_L_85_10INCH_IN2_DN")
	)
	(segment
		(start 239.367822 -7.100316)
		(end 240.731294 -7.341108)
		(width 0.14224)
		(layer "In4.Cu")
		(net "DELTA_L_85_10INCH_IN2_DN")
	)
	(segment
		(start 247.291352 -7.111746)
		(end 248.654824 -7.352538)
		(width 0.14224)
		(layer "In4.Cu")
		(net "DELTA_L_85_10INCH_IN2_DN")
	)
	(segment
		(start 229.00767 -7.225792)
		(end 229.79253 -2.779776)
		(width 0.14224)
		(layer "In4.Cu")
		(net "DELTA_L_85_10INCH_IN2_DN")
	)
	(segment
		(start 261.843012 -2.572512)
		(end 263.437624 -2.854198)
		(width 0.14224)
		(layer "In4.Cu")
		(net "DELTA_L_85_10INCH_IN2_DN")
	)
	(segment
		(start 275.331428 -2.823972)
		(end 275.580602 -3.179826)
		(width 0.14224)
		(layer "In4.Cu")
		(net "DELTA_L_85_10INCH_IN2_DN")
	)
	(segment
		(start 243.875814 -3.193288)
		(end 243.213128 -6.947916)
		(width 0.14224)
		(layer "In4.Cu")
		(net "DELTA_L_85_10INCH_IN2_DN")
	)
	(segment
		(start 269.766288 -2.58699)
		(end 271.3609 -2.868676)
		(width 0.14224)
		(layer "In4.Cu")
		(net "DELTA_L_85_10INCH_IN2_DN")
	)
	(segment
		(start 271.60982 -3.224784)
		(end 270.94434 -6.994906)
		(width 0.14224)
		(layer "In4.Cu")
		(net "DELTA_L_85_10INCH_IN2_DN")
	)
	(segment
		(start 227.36429 -6.935724)
		(end 227.479606 -7.100316)
		(width 0.14224)
		(layer "In4.Cu")
		(net "DELTA_L_85_10INCH_IN2_DN")
	)
	(segment
		(start 271.3609 -2.868676)
		(end 271.60982 -3.224784)
		(width 0.14224)
		(layer "In4.Cu")
		(net "DELTA_L_85_10INCH_IN2_DN")
	)
	(segment
		(start 213.94928 -4.645406)
		(end 214.24011 -4.936236)
		(width 0.14224)
		(layer "In4.Cu")
		(net "DELTA_L_85_10INCH_IN2_DN")
	)
	(segment
		(start 284.497018 -7.166102)
		(end 285.267908 -2.798318)
		(width 0.14224)
		(layer "In4.Cu")
		(net "DELTA_L_85_10INCH_IN2_DN")
	)
	(segment
		(start 288.283396 -7.349236)
		(end 288.447734 -7.23392)
		(width 0.14224)
		(layer "In4.Cu")
		(net "DELTA_L_85_10INCH_IN2_DN")
	)
	(segment
		(start 232.975404 -7.197344)
		(end 233.747818 -2.821686)
		(width 0.14224)
		(layer "In4.Cu")
		(net "DELTA_L_85_10INCH_IN2_DN")
	)
	(segment
		(start 223.514412 -7.114032)
		(end 224.877884 -7.354824)
		(width 0.14224)
		(layer "In4.Cu")
		(net "DELTA_L_85_10INCH_IN2_DN")
	)
	(segment
		(start 224.06483 -3.178556)
		(end 223.399096 -6.94944)
		(width 0.14224)
		(layer "In4.Cu")
		(net "DELTA_L_85_10INCH_IN2_DN")
	)
	(segment
		(start 240.731294 -7.341108)
		(end 240.895886 -7.225792)
		(width 0.14224)
		(layer "In4.Cu")
		(net "DELTA_L_85_10INCH_IN2_DN")
	)
	(segment
		(start 287.467548 -3.186684)
		(end 286.804608 -6.943598)
		(width 0.14224)
		(layer "In4.Cu")
		(net "DELTA_L_85_10INCH_IN2_DN")
	)
	(segment
		(start 260.704076 -7.258558)
		(end 261.487158 -2.821686)
		(width 0.14224)
		(layer "In4.Cu")
		(net "DELTA_L_85_10INCH_IN2_DN")
	)
	(segment
		(start 267.097256 -7.157212)
		(end 268.460728 -7.398004)
		(width 0.14224)
		(layer "In4.Cu")
		(net "DELTA_L_85_10INCH_IN2_DN")
	)
	(segment
		(start 289.592004 -2.518664)
		(end 291.186616 -2.80035)
		(width 0.14224)
		(layer "In4.Cu")
		(net "DELTA_L_85_10INCH_IN2_DN")
	)
	(segment
		(start 251.267214 -7.037832)
		(end 252.630686 -7.278624)
		(width 0.14224)
		(layer "In4.Cu")
		(net "DELTA_L_85_10INCH_IN2_DN")
	)
	(segment
		(start 274.91182 -6.968236)
		(end 275.027136 -7.132828)
		(width 0.14224)
		(layer "In4.Cu")
		(net "DELTA_L_85_10INCH_IN2_DN")
	)
	(segment
		(start 214.24011 -4.936236)
		(end 217.046556 -4.936236)
		(width 0.14224)
		(layer "In4.Cu")
		(net "DELTA_L_85_10INCH_IN2_DN")
	)
	(segment
		(start 268.460728 -7.398004)
		(end 268.62532 -7.282688)
		(width 0.14224)
		(layer "In4.Cu")
		(net "DELTA_L_85_10INCH_IN2_DN")
	)
	(segment
		(start 295.058338 -2.826258)
		(end 295.3766 -3.280918)
		(width 0.14224)
		(layer "In4.Cu")
		(net "DELTA_L_85_10INCH_IN2_DN")
	)
	(segment
		(start 255.768348 -3.169666)
		(end 255.105662 -6.924548)
		(width 0.14224)
		(layer "In4.Cu")
		(net "DELTA_L_85_10INCH_IN2_DN")
	)
	(segment
		(start 226.182682 -2.546858)
		(end 227.777294 -2.828544)
		(width 0.14224)
		(layer "In4.Cu")
		(net "DELTA_L_85_10INCH_IN2_DN")
	)
	(segment
		(start 238.073184 -2.53492)
		(end 239.667796 -2.816606)
		(width 0.14224)
		(layer "In4.Cu")
		(net "DELTA_L_85_10INCH_IN2_DN")
	)
	(segment
		(start 232.810812 -7.31266)
		(end 232.975404 -7.197344)
		(width 0.14224)
		(layer "In4.Cu")
		(net "DELTA_L_85_10INCH_IN2_DN")
	)
	(segment
		(start 275.027136 -7.132828)
		(end 276.390608 -7.37362)
		(width 0.14224)
		(layer "In4.Cu")
		(net "DELTA_L_85_10INCH_IN2_DN")
	)
	(segment
		(start 235.292138 -6.923532)
		(end 235.407454 -7.088124)
		(width 0.14224)
		(layer "In4.Cu")
		(net "DELTA_L_85_10INCH_IN2_DN")
	)
	(segment
		(start 247.176036 -6.947154)
		(end 247.291352 -7.111746)
		(width 0.14224)
		(layer "In4.Cu")
		(net "DELTA_L_85_10INCH_IN2_DN")
	)
	(segment
		(start 261.487158 -2.821686)
		(end 261.843012 -2.572512)
		(width 0.14224)
		(layer "In4.Cu")
		(net "DELTA_L_85_10INCH_IN2_DN")
	)
	(segment
		(start 251.548392 -2.860294)
		(end 251.797312 -3.216402)
		(width 0.14224)
		(layer "In4.Cu")
		(net "DELTA_L_85_10INCH_IN2_DN")
	)
	(segment
		(start 263.437624 -2.854198)
		(end 263.686798 -3.210052)
		(width 0.14224)
		(layer "In4.Cu")
		(net "DELTA_L_85_10INCH_IN2_DN")
	)
	(segment
		(start 185.037222 5.813298)
		(end 184.38495 5.631434)
		(width 0.12954)
		(layer "F.Cu")
		(net "DELTA_L_85_10INCH_IN1_DP")
	)
	(segment
		(start 98.621342 5.813298)
		(end 99.273614 5.631434)
		(width 0.12954)
		(layer "F.Cu")
		(net "DELTA_L_85_10INCH_IN1_DP")
	)
	(segment
		(start 164.450776 8.038084)
		(end 163.086288 8.27913)
		(width 0.14224)
		(layer "In2.Cu")
		(net "DELTA_L_85_10INCH_IN1_DP")
	)
	(segment
		(start 130.08229 3.488944)
		(end 128.488694 3.770376)
		(width 0.14224)
		(layer "In2.Cu")
		(net "DELTA_L_85_10INCH_IN1_DP")
	)
	(segment
		(start 120.567704 3.79476)
		(end 120.318276 4.150868)
		(width 0.14224)
		(layer "In2.Cu")
		(net "DELTA_L_85_10INCH_IN1_DP")
	)
	(segment
		(start 114.233452 3.501136)
		(end 112.639856 3.782568)
		(width 0.14224)
		(layer "In2.Cu")
		(net "DELTA_L_85_10INCH_IN1_DP")
	)
	(segment
		(start 167.879776 4.198366)
		(end 168.524174 7.848854)
		(width 0.14224)
		(layer "In2.Cu")
		(net "DELTA_L_85_10INCH_IN1_DP")
	)
	(segment
		(start 171.830746 4.130802)
		(end 172.493686 7.887716)
		(width 0.14224)
		(layer "In2.Cu")
		(net "DELTA_L_85_10INCH_IN1_DP")
	)
	(segment
		(start 99.564444 5.922264)
		(end 99.273614 5.631434)
		(width 0.14224)
		(layer "In2.Cu")
		(net "DELTA_L_85_10INCH_IN1_DP")
	)
	(segment
		(start 131.388358 8.303514)
		(end 131.22402 8.188452)
		(width 0.14224)
		(layer "In2.Cu")
		(net "DELTA_L_85_10INCH_IN1_DP")
	)
	(segment
		(start 180.402738 7.793482)
		(end 180.218588 8.056626)
		(width 0.14224)
		(layer "In2.Cu")
		(net "DELTA_L_85_10INCH_IN1_DP")
	)
	(segment
		(start 128.488694 3.770376)
		(end 128.239266 4.126484)
		(width 0.14224)
		(layer "In2.Cu")
		(net "DELTA_L_85_10INCH_IN1_DP")
	)
	(segment
		(start 128.901952 7.881112)
		(end 128.78689 8.04545)
		(width 0.14224)
		(layer "In2.Cu")
		(net "DELTA_L_85_10INCH_IN1_DP")
	)
	(segment
		(start 132.867908 7.89813)
		(end 132.752846 8.062468)
		(width 0.14224)
		(layer "In2.Cu")
		(net "DELTA_L_85_10INCH_IN1_DP")
	)
	(segment
		(start 184.09412 5.922264)
		(end 181.63921 5.922264)
		(width 0.14224)
		(layer "In2.Cu")
		(net "DELTA_L_85_10INCH_IN1_DP")
	)
	(segment
		(start 160.187386 3.750056)
		(end 159.937958 4.106164)
		(width 0.14224)
		(layer "In2.Cu")
		(net "DELTA_L_85_10INCH_IN1_DP")
	)
	(segment
		(start 152.562306 8.038084)
		(end 151.197818 8.27913)
		(width 0.14224)
		(layer "In2.Cu")
		(net "DELTA_L_85_10INCH_IN1_DP")
	)
	(segment
		(start 169.7228 3.560826)
		(end 168.129204 3.842258)
		(width 0.14224)
		(layer "In2.Cu")
		(net "DELTA_L_85_10INCH_IN1_DP")
	)
	(segment
		(start 140.1318 4.149852)
		(end 140.794486 7.904734)
		(width 0.14224)
		(layer "In2.Cu")
		(net "DELTA_L_85_10INCH_IN1_DP")
	)
	(segment
		(start 105.014268 8.067802)
		(end 103.64978 8.308848)
		(width 0.14224)
		(layer "In2.Cu")
		(net "DELTA_L_85_10INCH_IN1_DP")
	)
	(segment
		(start 124.528072 3.782568)
		(end 124.278644 4.138676)
		(width 0.14224)
		(layer "In2.Cu")
		(net "DELTA_L_85_10INCH_IN1_DP")
	)
	(segment
		(start 172.493686 7.887716)
		(end 172.378624 8.052054)
		(width 0.14224)
		(layer "In2.Cu")
		(net "DELTA_L_85_10INCH_IN1_DP")
	)
	(segment
		(start 172.080174 3.77444)
		(end 171.830746 4.130802)
		(width 0.14224)
		(layer "In2.Cu")
		(net "DELTA_L_85_10INCH_IN1_DP")
	)
	(segment
		(start 163.89858 4.094226)
		(end 164.565838 7.874)
		(width 0.14224)
		(layer "In2.Cu")
		(net "DELTA_L_85_10INCH_IN1_DP")
	)
	(segment
		(start 145.929858 3.46837)
		(end 144.336262 3.749802)
		(width 0.14224)
		(layer "In2.Cu")
		(net "DELTA_L_85_10INCH_IN1_DP")
	)
	(segment
		(start 158.169864 3.691636)
		(end 157.813502 3.442208)
		(width 0.14224)
		(layer "In2.Cu")
		(net "DELTA_L_85_10INCH_IN1_DP")
	)
	(segment
		(start 176.045368 3.788664)
		(end 175.79594 4.144772)
		(width 0.14224)
		(layer "In2.Cu")
		(net "DELTA_L_85_10INCH_IN1_DP")
	)
	(segment
		(start 152.677368 7.873746)
		(end 152.562306 8.038084)
		(width 0.14224)
		(layer "In2.Cu")
		(net "DELTA_L_85_10INCH_IN1_DP")
	)
	(segment
		(start 104.458262 4.101338)
		(end 105.12933 7.903464)
		(width 0.14224)
		(layer "In2.Cu")
		(net "DELTA_L_85_10INCH_IN1_DP")
	)
	(segment
		(start 143.104108 8.142224)
		(end 142.330932 3.76174)
		(width 0.14224)
		(layer "In2.Cu")
		(net "DELTA_L_85_10INCH_IN1_DP")
	)
	(segment
		(start 132.752846 8.062468)
		(end 131.388358 8.303514)
		(width 0.14224)
		(layer "In2.Cu")
		(net "DELTA_L_85_10INCH_IN1_DP")
	)
	(segment
		(start 154.20721 3.693668)
		(end 153.851102 3.44424)
		(width 0.14224)
		(layer "In2.Cu")
		(net "DELTA_L_85_10INCH_IN1_DP")
	)
	(segment
		(start 112.937544 8.05434)
		(end 111.573056 8.295386)
		(width 0.14224)
		(layer "In2.Cu")
		(net "DELTA_L_85_10INCH_IN1_DP")
	)
	(segment
		(start 161.780982 3.468624)
		(end 160.187386 3.750056)
		(width 0.14224)
		(layer "In2.Cu")
		(net "DELTA_L_85_10INCH_IN1_DP")
	)
	(segment
		(start 178.923696 8.285226)
		(end 178.776122 8.182356)
		(width 0.14224)
		(layer "In2.Cu")
		(net "DELTA_L_85_10INCH_IN1_DP")
	)
	(segment
		(start 156.219906 3.72364)
		(end 155.970478 4.07924)
		(width 0.14224)
		(layer "In2.Cu")
		(net "DELTA_L_85_10INCH_IN1_DP")
	)
	(segment
		(start 176.346866 8.082534)
		(end 174.982378 8.32358)
		(width 0.14224)
		(layer "In2.Cu")
		(net "DELTA_L_85_10INCH_IN1_DP")
	)
	(segment
		(start 112.639856 3.782568)
		(end 112.390428 4.138676)
		(width 0.14224)
		(layer "In2.Cu")
		(net "DELTA_L_85_10INCH_IN1_DP")
	)
	(segment
		(start 127.258064 8.171434)
		(end 126.477776 3.750564)
		(width 0.14224)
		(layer "In2.Cu")
		(net "DELTA_L_85_10INCH_IN1_DP")
	)
	(segment
		(start 116.60759 3.811016)
		(end 116.358162 4.167124)
		(width 0.14224)
		(layer "In2.Cu")
		(net "DELTA_L_85_10INCH_IN1_DP")
	)
	(segment
		(start 144.632934 8.01624)
		(end 143.268446 8.257286)
		(width 0.14224)
		(layer "In2.Cu")
		(net "DELTA_L_85_10INCH_IN1_DP")
	)
	(segment
		(start 146.285966 3.717798)
		(end 145.929858 3.46837)
		(width 0.14224)
		(layer "In2.Cu")
		(net "DELTA_L_85_10INCH_IN1_DP")
	)
	(segment
		(start 136.708388 8.02259)
		(end 135.3439 8.263636)
		(width 0.14224)
		(layer "In2.Cu")
		(net "DELTA_L_85_10INCH_IN1_DP")
	)
	(segment
		(start 106.657648 3.713734)
		(end 106.301286 3.464306)
		(width 0.14224)
		(layer "In2.Cu")
		(net "DELTA_L_85_10INCH_IN1_DP")
	)
	(segment
		(start 165.741604 3.456432)
		(end 164.148008 3.737864)
		(width 0.14224)
		(layer "In2.Cu")
		(net "DELTA_L_85_10INCH_IN1_DP")
	)
	(segment
		(start 123.463558 8.307324)
		(end 123.29922 8.192262)
		(width 0.14224)
		(layer "In2.Cu")
		(net "DELTA_L_85_10INCH_IN1_DP")
	)
	(segment
		(start 148.293328 3.717798)
		(end 148.0439 4.073906)
		(width 0.14224)
		(layer "In2.Cu")
		(net "DELTA_L_85_10INCH_IN1_DP")
	)
	(segment
		(start 142.330932 3.76174)
		(end 141.974824 3.512312)
		(width 0.14224)
		(layer "In2.Cu")
		(net "DELTA_L_85_10INCH_IN1_DP")
	)
	(segment
		(start 111.408718 8.180324)
		(end 110.624366 3.736848)
		(width 0.14224)
		(layer "In2.Cu")
		(net "DELTA_L_85_10INCH_IN1_DP")
	)
	(segment
		(start 148.0439 4.073906)
		(end 148.712936 7.864348)
		(width 0.14224)
		(layer "In2.Cu")
		(net "DELTA_L_85_10INCH_IN1_DP")
	)
	(segment
		(start 110.624366 3.736848)
		(end 110.268258 3.48742)
		(width 0.14224)
		(layer "In2.Cu")
		(net "DELTA_L_85_10INCH_IN1_DP")
	)
	(segment
		(start 114.58956 3.750564)
		(end 114.233452 3.501136)
		(width 0.14224)
		(layer "In2.Cu")
		(net "DELTA_L_85_10INCH_IN1_DP")
	)
	(segment
		(start 162.13709 3.718052)
		(end 161.780982 3.468624)
		(width 0.14224)
		(layer "In2.Cu")
		(net "DELTA_L_85_10INCH_IN1_DP")
	)
	(segment
		(start 104.70769 3.745738)
		(end 104.458262 4.101338)
		(width 0.14224)
		(layer "In2.Cu")
		(net "DELTA_L_85_10INCH_IN1_DP")
	)
	(segment
		(start 115.538758 8.311642)
		(end 115.37442 8.19658)
		(width 0.14224)
		(layer "In2.Cu")
		(net "DELTA_L_85_10INCH_IN1_DP")
	)
	(segment
		(start 144.747996 7.851902)
		(end 144.632934 8.01624)
		(width 0.14224)
		(layer "In2.Cu")
		(net "DELTA_L_85_10INCH_IN1_DP")
	)
	(segment
		(start 180.218588 8.056626)
		(end 178.923696 8.285226)
		(width 0.14224)
		(layer "In2.Cu")
		(net "DELTA_L_85_10INCH_IN1_DP")
	)
	(segment
		(start 177.994818 3.75666)
		(end 177.638964 3.507232)
		(width 0.14224)
		(layer "In2.Cu")
		(net "DELTA_L_85_10INCH_IN1_DP")
	)
	(segment
		(start 102.45979 5.922264)
		(end 99.564444 5.922264)
		(width 0.14224)
		(layer "In2.Cu")
		(net "DELTA_L_85_10INCH_IN1_DP")
	)
	(segment
		(start 109.090968 7.895844)
		(end 108.975906 8.060182)
		(width 0.14224)
		(layer "In2.Cu")
		(net "DELTA_L_85_10INCH_IN1_DP")
	)
	(segment
		(start 144.336262 3.749802)
		(end 144.086834 4.10591)
		(width 0.14224)
		(layer "In2.Cu")
		(net "DELTA_L_85_10INCH_IN1_DP")
	)
	(segment
		(start 180.684678 6.08203)
		(end 180.217572 6.744716)
		(width 0.14224)
		(layer "In2.Cu")
		(net "DELTA_L_85_10INCH_IN1_DP")
	)
	(segment
		(start 148.712936 7.864348)
		(end 148.597874 8.028686)
		(width 0.14224)
		(layer "In2.Cu")
		(net "DELTA_L_85_10INCH_IN1_DP")
	)
	(segment
		(start 174.81804 8.208518)
		(end 174.029624 3.742436)
		(width 0.14224)
		(layer "In2.Cu")
		(net "DELTA_L_85_10INCH_IN1_DP")
	)
	(segment
		(start 171.014136 8.2931)
		(end 170.849798 8.178038)
		(width 0.14224)
		(layer "In2.Cu")
		(net "DELTA_L_85_10INCH_IN1_DP")
	)
	(segment
		(start 173.674024 3.493008)
		(end 172.080174 3.77444)
		(width 0.14224)
		(layer "In2.Cu")
		(net "DELTA_L_85_10INCH_IN1_DP")
	)
	(segment
		(start 138.377168 3.813048)
		(end 138.02106 3.56362)
		(width 0.14224)
		(layer "In2.Cu")
		(net "DELTA_L_85_10INCH_IN1_DP")
	)
	(segment
		(start 105.12933 7.903464)
		(end 105.014268 8.067802)
		(width 0.14224)
		(layer "In2.Cu")
		(net "DELTA_L_85_10INCH_IN1_DP")
	)
	(segment
		(start 166.097458 3.70586)
		(end 165.741604 3.456432)
		(width 0.14224)
		(layer "In2.Cu")
		(net "DELTA_L_85_10INCH_IN1_DP")
	)
	(segment
		(start 126.477776 3.750564)
		(end 126.121668 3.501136)
		(width 0.14224)
		(layer "In2.Cu")
		(net "DELTA_L_85_10INCH_IN1_DP")
	)
	(segment
		(start 127.422402 8.286496)
		(end 127.258064 8.171434)
		(width 0.14224)
		(layer "In2.Cu")
		(net "DELTA_L_85_10INCH_IN1_DP")
	)
	(segment
		(start 159.937958 4.106164)
		(end 160.60674 7.894574)
		(width 0.14224)
		(layer "In2.Cu")
		(net "DELTA_L_85_10INCH_IN1_DP")
	)
	(segment
		(start 136.178036 4.20116)
		(end 136.82345 7.857998)
		(width 0.14224)
		(layer "In2.Cu")
		(net "DELTA_L_85_10INCH_IN1_DP")
	)
	(segment
		(start 135.3439 8.263636)
		(end 135.179562 8.148574)
		(width 0.14224)
		(layer "In2.Cu")
		(net "DELTA_L_85_10INCH_IN1_DP")
	)
	(segment
		(start 136.82345 7.857998)
		(end 136.708388 8.02259)
		(width 0.14224)
		(layer "In2.Cu")
		(net "DELTA_L_85_10INCH_IN1_DP")
	)
	(segment
		(start 175.79594 4.144772)
		(end 176.461928 7.918196)
		(width 0.14224)
		(layer "In2.Cu")
		(net "DELTA_L_85_10INCH_IN1_DP")
	)
	(segment
		(start 151.197818 8.27913)
		(end 151.03348 8.164068)
		(width 0.14224)
		(layer "In2.Cu")
		(net "DELTA_L_85_10INCH_IN1_DP")
	)
	(segment
		(start 119.494046 8.269732)
		(end 119.329708 8.15467)
		(width 0.14224)
		(layer "In2.Cu")
		(net "DELTA_L_85_10INCH_IN1_DP")
	)
	(segment
		(start 160.491678 8.058912)
		(end 159.12719 8.299958)
		(width 0.14224)
		(layer "In2.Cu")
		(net "DELTA_L_85_10INCH_IN1_DP")
	)
	(segment
		(start 143.268446 8.257286)
		(end 143.104108 8.142224)
		(width 0.14224)
		(layer "In2.Cu")
		(net "DELTA_L_85_10INCH_IN1_DP")
	)
	(segment
		(start 108.674662 3.768852)
		(end 108.425234 4.12496)
		(width 0.14224)
		(layer "In2.Cu")
		(net "DELTA_L_85_10INCH_IN1_DP")
	)
	(segment
		(start 162.92195 8.164068)
		(end 162.13709 3.718052)
		(width 0.14224)
		(layer "In2.Cu")
		(net "DELTA_L_85_10INCH_IN1_DP")
	)
	(segment
		(start 150.243032 3.685794)
		(end 149.886924 3.436366)
		(width 0.14224)
		(layer "In2.Cu")
		(net "DELTA_L_85_10INCH_IN1_DP")
	)
	(segment
		(start 159.12719 8.299958)
		(end 158.962852 8.184896)
		(width 0.14224)
		(layer "In2.Cu")
		(net "DELTA_L_85_10INCH_IN1_DP")
	)
	(segment
		(start 116.903246 8.070596)
		(end 115.538758 8.311642)
		(width 0.14224)
		(layer "In2.Cu")
		(net "DELTA_L_85_10INCH_IN1_DP")
	)
	(segment
		(start 144.086834 4.10591)
		(end 144.747996 7.851902)
		(width 0.14224)
		(layer "In2.Cu")
		(net "DELTA_L_85_10INCH_IN1_DP")
	)
	(segment
		(start 176.461928 7.918196)
		(end 176.346866 8.082534)
		(width 0.14224)
		(layer "In2.Cu")
		(net "DELTA_L_85_10INCH_IN1_DP")
	)
	(segment
		(start 147.233386 8.269732)
		(end 147.069048 8.15467)
		(width 0.14224)
		(layer "In2.Cu")
		(net "DELTA_L_85_10INCH_IN1_DP")
	)
	(segment
		(start 128.239266 4.126484)
		(end 128.901952 7.881112)
		(width 0.14224)
		(layer "In2.Cu")
		(net "DELTA_L_85_10INCH_IN1_DP")
	)
	(segment
		(start 139.314936 8.310118)
		(end 139.150598 8.195056)
		(width 0.14224)
		(layer "In2.Cu")
		(net "DELTA_L_85_10INCH_IN1_DP")
	)
	(segment
		(start 181.63921 5.922264)
		(end 180.684678 6.08203)
		(width 0.14224)
		(layer "In2.Cu")
		(net "DELTA_L_85_10INCH_IN1_DP")
	)
	(segment
		(start 155.156408 8.255254)
		(end 154.99207 8.140446)
		(width 0.14224)
		(layer "In2.Cu")
		(net "DELTA_L_85_10INCH_IN1_DP")
	)
	(segment
		(start 124.278644 4.138676)
		(end 124.942854 7.902194)
		(width 0.14224)
		(layer "In2.Cu")
		(net "DELTA_L_85_10INCH_IN1_DP")
	)
	(segment
		(start 153.851102 3.44424)
		(end 152.257506 3.725672)
		(width 0.14224)
		(layer "In2.Cu")
		(net "DELTA_L_85_10INCH_IN1_DP")
	)
	(segment
		(start 174.982378 8.32358)
		(end 174.81804 8.208518)
		(width 0.14224)
		(layer "In2.Cu")
		(net "DELTA_L_85_10INCH_IN1_DP")
	)
	(segment
		(start 164.565838 7.874)
		(end 164.450776 8.038084)
		(width 0.14224)
		(layer "In2.Cu")
		(net "DELTA_L_85_10INCH_IN1_DP")
	)
	(segment
		(start 122.1613 3.513328)
		(end 120.567704 3.79476)
		(width 0.14224)
		(layer "In2.Cu")
		(net "DELTA_L_85_10INCH_IN1_DP")
	)
	(segment
		(start 168.409112 8.013192)
		(end 167.044624 8.254238)
		(width 0.14224)
		(layer "In2.Cu")
		(net "DELTA_L_85_10INCH_IN1_DP")
	)
	(segment
		(start 111.573056 8.295386)
		(end 111.408718 8.180324)
		(width 0.14224)
		(layer "In2.Cu")
		(net "DELTA_L_85_10INCH_IN1_DP")
	)
	(segment
		(start 132.451602 3.771138)
		(end 132.202174 4.127246)
		(width 0.14224)
		(layer "In2.Cu")
		(net "DELTA_L_85_10INCH_IN1_DP")
	)
	(segment
		(start 134.045198 3.489706)
		(end 132.451602 3.771138)
		(width 0.14224)
		(layer "In2.Cu")
		(net "DELTA_L_85_10INCH_IN1_DP")
	)
	(segment
		(start 107.611418 8.301228)
		(end 107.44708 8.186166)
		(width 0.14224)
		(layer "In2.Cu")
		(net "DELTA_L_85_10INCH_IN1_DP")
	)
	(segment
		(start 110.268258 3.48742)
		(end 108.674662 3.768852)
		(width 0.14224)
		(layer "In2.Cu")
		(net "DELTA_L_85_10INCH_IN1_DP")
	)
	(segment
		(start 141.974824 3.512312)
		(end 140.381228 3.793744)
		(width 0.14224)
		(layer "In2.Cu")
		(net "DELTA_L_85_10INCH_IN1_DP")
	)
	(segment
		(start 177.638964 3.507232)
		(end 176.045368 3.788664)
		(width 0.14224)
		(layer "In2.Cu")
		(net "DELTA_L_85_10INCH_IN1_DP")
	)
	(segment
		(start 160.60674 7.894574)
		(end 160.491678 8.058912)
		(width 0.14224)
		(layer "In2.Cu")
		(net "DELTA_L_85_10INCH_IN1_DP")
	)
	(segment
		(start 168.129204 3.842258)
		(end 167.879776 4.198366)
		(width 0.14224)
		(layer "In2.Cu")
		(net "DELTA_L_85_10INCH_IN1_DP")
	)
	(segment
		(start 131.22402 8.188452)
		(end 130.438398 3.738372)
		(width 0.14224)
		(layer "In2.Cu")
		(net "DELTA_L_85_10INCH_IN1_DP")
	)
	(segment
		(start 147.069048 8.15467)
		(end 146.285966 3.717798)
		(width 0.14224)
		(layer "In2.Cu")
		(net "DELTA_L_85_10INCH_IN1_DP")
	)
	(segment
		(start 113.052606 7.890002)
		(end 112.937544 8.05434)
		(width 0.14224)
		(layer "In2.Cu")
		(net "DELTA_L_85_10INCH_IN1_DP")
	)
	(segment
		(start 167.044624 8.254238)
		(end 166.880286 8.139176)
		(width 0.14224)
		(layer "In2.Cu")
		(net "DELTA_L_85_10INCH_IN1_DP")
	)
	(segment
		(start 135.179562 8.148574)
		(end 134.401306 3.739134)
		(width 0.14224)
		(layer "In2.Cu")
		(net "DELTA_L_85_10INCH_IN1_DP")
	)
	(segment
		(start 138.02106 3.56362)
		(end 136.427464 3.845052)
		(width 0.14224)
		(layer "In2.Cu")
		(net "DELTA_L_85_10INCH_IN1_DP")
	)
	(segment
		(start 140.794486 7.904734)
		(end 140.679424 8.069072)
		(width 0.14224)
		(layer "In2.Cu")
		(net "DELTA_L_85_10INCH_IN1_DP")
	)
	(segment
		(start 132.202174 4.127246)
		(end 132.867908 7.89813)
		(width 0.14224)
		(layer "In2.Cu")
		(net "DELTA_L_85_10INCH_IN1_DP")
	)
	(segment
		(start 108.425234 4.12496)
		(end 109.090968 7.895844)
		(width 0.14224)
		(layer "In2.Cu")
		(net "DELTA_L_85_10INCH_IN1_DP")
	)
	(segment
		(start 170.078908 3.810254)
		(end 169.7228 3.560826)
		(width 0.14224)
		(layer "In2.Cu")
		(net "DELTA_L_85_10INCH_IN1_DP")
	)
	(segment
		(start 170.849798 8.178038)
		(end 170.078908 3.810254)
		(width 0.14224)
		(layer "In2.Cu")
		(net "DELTA_L_85_10INCH_IN1_DP")
	)
	(segment
		(start 180.217572 6.744716)
		(end 180.402738 7.793482)
		(width 0.14224)
		(layer "In2.Cu")
		(net "DELTA_L_85_10INCH_IN1_DP")
	)
	(segment
		(start 118.557294 3.779012)
		(end 118.201186 3.529584)
		(width 0.14224)
		(layer "In2.Cu")
		(net "DELTA_L_85_10INCH_IN1_DP")
	)
	(segment
		(start 156.520896 8.014208)
		(end 155.156408 8.255254)
		(width 0.14224)
		(layer "In2.Cu")
		(net "DELTA_L_85_10INCH_IN1_DP")
	)
	(segment
		(start 115.37442 8.19658)
		(end 114.58956 3.750564)
		(width 0.14224)
		(layer "In2.Cu")
		(net "DELTA_L_85_10INCH_IN1_DP")
	)
	(segment
		(start 103.64978 8.308848)
		(end 103.485442 8.193786)
		(width 0.14224)
		(layer "In2.Cu")
		(net "DELTA_L_85_10INCH_IN1_DP")
	)
	(segment
		(start 120.318276 4.150868)
		(end 120.973596 7.864348)
		(width 0.14224)
		(layer "In2.Cu")
		(net "DELTA_L_85_10INCH_IN1_DP")
	)
	(segment
		(start 120.858534 8.028686)
		(end 119.494046 8.269732)
		(width 0.14224)
		(layer "In2.Cu")
		(net "DELTA_L_85_10INCH_IN1_DP")
	)
	(segment
		(start 134.401306 3.739134)
		(end 134.045198 3.489706)
		(width 0.14224)
		(layer "In2.Cu")
		(net "DELTA_L_85_10INCH_IN1_DP")
	)
	(segment
		(start 128.78689 8.04545)
		(end 127.422402 8.286496)
		(width 0.14224)
		(layer "In2.Cu")
		(net "DELTA_L_85_10INCH_IN1_DP")
	)
	(segment
		(start 118.201186 3.529584)
		(end 116.60759 3.811016)
		(width 0.14224)
		(layer "In2.Cu")
		(net "DELTA_L_85_10INCH_IN1_DP")
	)
	(segment
		(start 126.121668 3.501136)
		(end 124.528072 3.782568)
		(width 0.14224)
		(layer "In2.Cu")
		(net "DELTA_L_85_10INCH_IN1_DP")
	)
	(segment
		(start 139.150598 8.195056)
		(end 138.377168 3.813048)
		(width 0.14224)
		(layer "In2.Cu")
		(net "DELTA_L_85_10INCH_IN1_DP")
	)
	(segment
		(start 108.975906 8.060182)
		(end 107.611418 8.301228)
		(width 0.14224)
		(layer "In2.Cu")
		(net "DELTA_L_85_10INCH_IN1_DP")
	)
	(segment
		(start 172.378624 8.052054)
		(end 171.014136 8.2931)
		(width 0.14224)
		(layer "In2.Cu")
		(net "DELTA_L_85_10INCH_IN1_DP")
	)
	(segment
		(start 103.172514 6.420612)
		(end 102.45979 5.922264)
		(width 0.14224)
		(layer "In2.Cu")
		(net "DELTA_L_85_10INCH_IN1_DP")
	)
	(segment
		(start 130.438398 3.738372)
		(end 130.08229 3.488944)
		(width 0.14224)
		(layer "In2.Cu")
		(net "DELTA_L_85_10INCH_IN1_DP")
	)
	(segment
		(start 140.679424 8.069072)
		(end 139.314936 8.310118)
		(width 0.14224)
		(layer "In2.Cu")
		(net "DELTA_L_85_10INCH_IN1_DP")
	)
	(segment
		(start 152.008078 4.08178)
		(end 152.677368 7.873746)
		(width 0.14224)
		(layer "In2.Cu")
		(net "DELTA_L_85_10INCH_IN1_DP")
	)
	(segment
		(start 152.257506 3.725672)
		(end 152.008078 4.08178)
		(width 0.14224)
		(layer "In2.Cu")
		(net "DELTA_L_85_10INCH_IN1_DP")
	)
	(segment
		(start 178.776122 8.182356)
		(end 177.994818 3.75666)
		(width 0.14224)
		(layer "In2.Cu")
		(net "DELTA_L_85_10INCH_IN1_DP")
	)
	(segment
		(start 163.086288 8.27913)
		(end 162.92195 8.164068)
		(width 0.14224)
		(layer "In2.Cu")
		(net "DELTA_L_85_10INCH_IN1_DP")
	)
	(segment
		(start 120.973596 7.864348)
		(end 120.858534 8.028686)
		(width 0.14224)
		(layer "In2.Cu")
		(net "DELTA_L_85_10INCH_IN1_DP")
	)
	(segment
		(start 157.813502 3.442208)
		(end 156.219906 3.72364)
		(width 0.14224)
		(layer "In2.Cu")
		(net "DELTA_L_85_10INCH_IN1_DP")
	)
	(segment
		(start 112.390428 4.138676)
		(end 113.052606 7.890002)
		(width 0.14224)
		(layer "In2.Cu")
		(net "DELTA_L_85_10INCH_IN1_DP")
	)
	(segment
		(start 117.018308 7.906512)
		(end 116.903246 8.070596)
		(width 0.14224)
		(layer "In2.Cu")
		(net "DELTA_L_85_10INCH_IN1_DP")
	)
	(segment
		(start 123.29922 8.192262)
		(end 122.517408 3.762756)
		(width 0.14224)
		(layer "In2.Cu")
		(net "DELTA_L_85_10INCH_IN1_DP")
	)
	(segment
		(start 119.329708 8.15467)
		(end 118.557294 3.779012)
		(width 0.14224)
		(layer "In2.Cu")
		(net "DELTA_L_85_10INCH_IN1_DP")
	)
	(segment
		(start 122.517408 3.762756)
		(end 122.1613 3.513328)
		(width 0.14224)
		(layer "In2.Cu")
		(net "DELTA_L_85_10INCH_IN1_DP")
	)
	(segment
		(start 124.942854 7.902194)
		(end 124.828046 8.066278)
		(width 0.14224)
		(layer "In2.Cu")
		(net "DELTA_L_85_10INCH_IN1_DP")
	)
	(segment
		(start 116.358162 4.167124)
		(end 117.018308 7.906512)
		(width 0.14224)
		(layer "In2.Cu")
		(net "DELTA_L_85_10INCH_IN1_DP")
	)
	(segment
		(start 168.524174 7.848854)
		(end 168.409112 8.013192)
		(width 0.14224)
		(layer "In2.Cu")
		(net "DELTA_L_85_10INCH_IN1_DP")
	)
	(segment
		(start 148.597874 8.028686)
		(end 147.233386 8.269732)
		(width 0.14224)
		(layer "In2.Cu")
		(net "DELTA_L_85_10INCH_IN1_DP")
	)
	(segment
		(start 174.029624 3.742436)
		(end 173.674024 3.493008)
		(width 0.14224)
		(layer "In2.Cu")
		(net "DELTA_L_85_10INCH_IN1_DP")
	)
	(segment
		(start 103.485442 8.193786)
		(end 103.172514 6.420612)
		(width 0.14224)
		(layer "In2.Cu")
		(net "DELTA_L_85_10INCH_IN1_DP")
	)
	(segment
		(start 149.886924 3.436366)
		(end 148.293328 3.717798)
		(width 0.14224)
		(layer "In2.Cu")
		(net "DELTA_L_85_10INCH_IN1_DP")
	)
	(segment
		(start 154.99207 8.140446)
		(end 154.20721 3.693668)
		(width 0.14224)
		(layer "In2.Cu")
		(net "DELTA_L_85_10INCH_IN1_DP")
	)
	(segment
		(start 158.962852 8.184896)
		(end 158.169864 3.691636)
		(width 0.14224)
		(layer "In2.Cu")
		(net "DELTA_L_85_10INCH_IN1_DP")
	)
	(segment
		(start 136.427464 3.845052)
		(end 136.178036 4.20116)
		(width 0.14224)
		(layer "In2.Cu")
		(net "DELTA_L_85_10INCH_IN1_DP")
	)
	(segment
		(start 151.03348 8.164068)
		(end 150.243032 3.685794)
		(width 0.14224)
		(layer "In2.Cu")
		(net "DELTA_L_85_10INCH_IN1_DP")
	)
	(segment
		(start 184.38495 5.631434)
		(end 184.09412 5.922264)
		(width 0.14224)
		(layer "In2.Cu")
		(net "DELTA_L_85_10INCH_IN1_DP")
	)
	(segment
		(start 140.381228 3.793744)
		(end 140.1318 4.149852)
		(width 0.14224)
		(layer "In2.Cu")
		(net "DELTA_L_85_10INCH_IN1_DP")
	)
	(segment
		(start 124.828046 8.066278)
		(end 123.463558 8.307324)
		(width 0.14224)
		(layer "In2.Cu")
		(net "DELTA_L_85_10INCH_IN1_DP")
	)
	(segment
		(start 164.148008 3.737864)
		(end 163.89858 4.094226)
		(width 0.14224)
		(layer "In2.Cu")
		(net "DELTA_L_85_10INCH_IN1_DP")
	)
	(segment
		(start 107.44708 8.186166)
		(end 106.657648 3.713734)
		(width 0.14224)
		(layer "In2.Cu")
		(net "DELTA_L_85_10INCH_IN1_DP")
	)
	(segment
		(start 155.970478 4.07924)
		(end 156.635958 7.849616)
		(width 0.14224)
		(layer "In2.Cu")
		(net "DELTA_L_85_10INCH_IN1_DP")
	)
	(segment
		(start 106.301286 3.464306)
		(end 104.70769 3.745738)
		(width 0.14224)
		(layer "In2.Cu")
		(net "DELTA_L_85_10INCH_IN1_DP")
	)
	(segment
		(start 166.880286 8.139176)
		(end 166.097458 3.70586)
		(width 0.14224)
		(layer "In2.Cu")
		(net "DELTA_L_85_10INCH_IN1_DP")
	)
	(segment
		(start 156.635958 7.849616)
		(end 156.520896 8.014208)
		(width 0.14224)
		(layer "In2.Cu")
		(net "DELTA_L_85_10INCH_IN1_DP")
	)
	(segment
		(start 185.037222 6.31317)
		(end 184.38495 6.495034)
		(width 0.12954)
		(layer "F.Cu")
		(net "DELTA_L_85_10INCH_IN1_DN")
	)
	(segment
		(start 98.621342 6.31317)
		(end 99.273614 6.495034)
		(width 0.12954)
		(layer "F.Cu")
		(net "DELTA_L_85_10INCH_IN1_DN")
	)
	(segment
		(start 149.820884 3.734562)
		(end 149.985476 3.849878)
		(width 0.14224)
		(layer "In2.Cu")
		(net "DELTA_L_85_10INCH_IN1_DN")
	)
	(segment
		(start 178.51882 8.346694)
		(end 178.85791 8.583168)
		(width 0.14224)
		(layer "In2.Cu")
		(net "DELTA_L_85_10INCH_IN1_DN")
	)
	(segment
		(start 176.51095 8.34009)
		(end 176.760124 7.984236)
		(width 0.14224)
		(layer "In2.Cu")
		(net "DELTA_L_85_10INCH_IN1_DN")
	)
	(segment
		(start 140.545312 4.0513)
		(end 141.908784 3.810508)
		(width 0.14224)
		(layer "In2.Cu")
		(net "DELTA_L_85_10INCH_IN1_DN")
	)
	(segment
		(start 128.950974 8.303006)
		(end 129.200148 7.947152)
		(width 0.14224)
		(layer "In2.Cu")
		(net "DELTA_L_85_10INCH_IN1_DN")
	)
	(segment
		(start 165.675564 3.754628)
		(end 165.839902 3.869944)
		(width 0.14224)
		(layer "In2.Cu")
		(net "DELTA_L_85_10INCH_IN1_DN")
	)
	(segment
		(start 172.542708 8.30961)
		(end 172.791882 7.953756)
		(width 0.14224)
		(layer "In2.Cu")
		(net "DELTA_L_85_10INCH_IN1_DN")
	)
	(segment
		(start 122.09526 3.811524)
		(end 122.259852 3.92684)
		(width 0.14224)
		(layer "In2.Cu")
		(net "DELTA_L_85_10INCH_IN1_DN")
	)
	(segment
		(start 160.236154 4.172204)
		(end 160.35147 4.007612)
		(width 0.14224)
		(layer "In2.Cu")
		(net "DELTA_L_85_10INCH_IN1_DN")
	)
	(segment
		(start 176.760124 7.984236)
		(end 176.094136 4.210812)
		(width 0.14224)
		(layer "In2.Cu")
		(net "DELTA_L_85_10INCH_IN1_DN")
	)
	(segment
		(start 152.975564 7.939786)
		(end 152.306274 4.14782)
		(width 0.14224)
		(layer "In2.Cu")
		(net "DELTA_L_85_10INCH_IN1_DN")
	)
	(segment
		(start 169.65676 3.859022)
		(end 169.821352 3.974338)
		(width 0.14224)
		(layer "In2.Cu")
		(net "DELTA_L_85_10INCH_IN1_DN")
	)
	(segment
		(start 133.979158 3.787902)
		(end 134.14375 3.903218)
		(width 0.14224)
		(layer "In2.Cu")
		(net "DELTA_L_85_10INCH_IN1_DN")
	)
	(segment
		(start 146.02841 3.881882)
		(end 146.811492 8.318754)
		(width 0.14224)
		(layer "In2.Cu")
		(net "DELTA_L_85_10INCH_IN1_DN")
	)
	(segment
		(start 156.38399 3.981196)
		(end 157.747462 3.740404)
		(width 0.14224)
		(layer "In2.Cu")
		(net "DELTA_L_85_10INCH_IN1_DN")
	)
	(segment
		(start 118.135146 3.82778)
		(end 118.299738 3.943096)
		(width 0.14224)
		(layer "In2.Cu")
		(net "DELTA_L_85_10INCH_IN1_DN")
	)
	(segment
		(start 157.912308 3.85572)
		(end 158.705296 8.34898)
		(width 0.14224)
		(layer "In2.Cu")
		(net "DELTA_L_85_10INCH_IN1_DN")
	)
	(segment
		(start 123.397518 8.60552)
		(end 124.99213 8.323834)
		(width 0.14224)
		(layer "In2.Cu")
		(net "DELTA_L_85_10INCH_IN1_DN")
	)
	(segment
		(start 110.202218 3.785616)
		(end 110.36681 3.900932)
		(width 0.14224)
		(layer "In2.Cu")
		(net "DELTA_L_85_10INCH_IN1_DN")
	)
	(segment
		(start 129.200148 7.947152)
		(end 128.537462 4.192524)
		(width 0.14224)
		(layer "In2.Cu")
		(net "DELTA_L_85_10INCH_IN1_DN")
	)
	(segment
		(start 107.545378 8.599424)
		(end 109.13999 8.317738)
		(width 0.14224)
		(layer "In2.Cu")
		(net "DELTA_L_85_10INCH_IN1_DN")
	)
	(segment
		(start 116.656358 4.233164)
		(end 116.771674 4.068572)
		(width 0.14224)
		(layer "In2.Cu")
		(net "DELTA_L_85_10INCH_IN1_DN")
	)
	(segment
		(start 158.705296 8.34898)
		(end 159.06115 8.598154)
		(width 0.14224)
		(layer "In2.Cu")
		(net "DELTA_L_85_10INCH_IN1_DN")
	)
	(segment
		(start 172.244258 4.031996)
		(end 173.60773 3.791204)
		(width 0.14224)
		(layer "In2.Cu")
		(net "DELTA_L_85_10INCH_IN1_DN")
	)
	(segment
		(start 141.908784 3.810508)
		(end 142.073376 3.925824)
		(width 0.14224)
		(layer "In2.Cu")
		(net "DELTA_L_85_10INCH_IN1_DN")
	)
	(segment
		(start 121.271792 7.930388)
		(end 120.616472 4.216908)
		(width 0.14224)
		(layer "In2.Cu")
		(net "DELTA_L_85_10INCH_IN1_DN")
	)
	(segment
		(start 128.537462 4.192524)
		(end 128.652778 4.027932)
		(width 0.14224)
		(layer "In2.Cu")
		(net "DELTA_L_85_10INCH_IN1_DN")
	)
	(segment
		(start 149.985476 3.849878)
		(end 150.775924 8.328152)
		(width 0.14224)
		(layer "In2.Cu")
		(net "DELTA_L_85_10INCH_IN1_DN")
	)
	(segment
		(start 131.322318 8.60171)
		(end 132.91693 8.320024)
		(width 0.14224)
		(layer "In2.Cu")
		(net "DELTA_L_85_10INCH_IN1_DN")
	)
	(segment
		(start 99.564444 6.204204)
		(end 102.37089 6.204204)
		(width 0.14224)
		(layer "In2.Cu")
		(net "DELTA_L_85_10INCH_IN1_DN")
	)
	(segment
		(start 104.756458 4.167632)
		(end 104.871774 4.003294)
		(width 0.14224)
		(layer "In2.Cu")
		(net "DELTA_L_85_10INCH_IN1_DN")
	)
	(segment
		(start 138.119612 3.977132)
		(end 138.893042 8.35914)
		(width 0.14224)
		(layer "In2.Cu")
		(net "DELTA_L_85_10INCH_IN1_DN")
	)
	(segment
		(start 174.916338 8.621776)
		(end 176.51095 8.34009)
		(width 0.14224)
		(layer "In2.Cu")
		(net "DELTA_L_85_10INCH_IN1_DN")
	)
	(segment
		(start 144.500346 4.007358)
		(end 145.863818 3.766566)
		(width 0.14224)
		(layer "In2.Cu")
		(net "DELTA_L_85_10INCH_IN1_DN")
	)
	(segment
		(start 153.949654 3.857752)
		(end 154.734514 8.304784)
		(width 0.14224)
		(layer "In2.Cu")
		(net "DELTA_L_85_10INCH_IN1_DN")
	)
	(segment
		(start 168.177972 4.264406)
		(end 168.293288 4.099814)
		(width 0.14224)
		(layer "In2.Cu")
		(net "DELTA_L_85_10INCH_IN1_DN")
	)
	(segment
		(start 107.189524 8.35025)
		(end 107.545378 8.599424)
		(width 0.14224)
		(layer "In2.Cu")
		(net "DELTA_L_85_10INCH_IN1_DN")
	)
	(segment
		(start 145.863818 3.766566)
		(end 146.02841 3.881882)
		(width 0.14224)
		(layer "In2.Cu")
		(net "DELTA_L_85_10INCH_IN1_DN")
	)
	(segment
		(start 130.01625 3.78714)
		(end 130.180842 3.902456)
		(width 0.14224)
		(layer "In2.Cu")
		(net "DELTA_L_85_10INCH_IN1_DN")
	)
	(segment
		(start 127.356362 8.584692)
		(end 128.950974 8.303006)
		(width 0.14224)
		(layer "In2.Cu")
		(net "DELTA_L_85_10INCH_IN1_DN")
	)
	(segment
		(start 113.101628 8.311896)
		(end 113.350802 7.956042)
		(width 0.14224)
		(layer "In2.Cu")
		(net "DELTA_L_85_10INCH_IN1_DN")
	)
	(segment
		(start 114.167412 3.799332)
		(end 114.332004 3.914648)
		(width 0.14224)
		(layer "In2.Cu")
		(net "DELTA_L_85_10INCH_IN1_DN")
	)
	(segment
		(start 108.838746 4.026408)
		(end 110.202218 3.785616)
		(width 0.14224)
		(layer "In2.Cu")
		(net "DELTA_L_85_10INCH_IN1_DN")
	)
	(segment
		(start 102.914958 6.58495)
		(end 103.227886 8.35787)
		(width 0.14224)
		(layer "In2.Cu")
		(net "DELTA_L_85_10INCH_IN1_DN")
	)
	(segment
		(start 180.382672 8.314182)
		(end 180.700934 7.859522)
		(width 0.14224)
		(layer "In2.Cu")
		(net "DELTA_L_85_10INCH_IN1_DN")
	)
	(segment
		(start 164.312092 3.99542)
		(end 165.675564 3.754628)
		(width 0.14224)
		(layer "In2.Cu")
		(net "DELTA_L_85_10INCH_IN1_DN")
	)
	(segment
		(start 99.273614 6.495034)
		(end 99.564444 6.204204)
		(width 0.14224)
		(layer "In2.Cu")
		(net "DELTA_L_85_10INCH_IN1_DN")
	)
	(segment
		(start 156.268674 4.145534)
		(end 156.38399 3.981196)
		(width 0.14224)
		(layer "In2.Cu")
		(net "DELTA_L_85_10INCH_IN1_DN")
	)
	(segment
		(start 119.428006 8.567928)
		(end 121.022618 8.286242)
		(width 0.14224)
		(layer "In2.Cu")
		(net "DELTA_L_85_10INCH_IN1_DN")
	)
	(segment
		(start 168.293288 4.099814)
		(end 169.65676 3.859022)
		(width 0.14224)
		(layer "In2.Cu")
		(net "DELTA_L_85_10INCH_IN1_DN")
	)
	(segment
		(start 164.864034 7.940294)
		(end 164.196776 4.160266)
		(width 0.14224)
		(layer "In2.Cu")
		(net "DELTA_L_85_10INCH_IN1_DN")
	)
	(segment
		(start 161.879534 3.882136)
		(end 162.664394 8.328152)
		(width 0.14224)
		(layer "In2.Cu")
		(net "DELTA_L_85_10INCH_IN1_DN")
	)
	(segment
		(start 117.316504 7.972806)
		(end 116.656358 4.233164)
		(width 0.14224)
		(layer "In2.Cu")
		(net "DELTA_L_85_10INCH_IN1_DN")
	)
	(segment
		(start 173.772068 3.90652)
		(end 174.560484 8.372602)
		(width 0.14224)
		(layer "In2.Cu")
		(net "DELTA_L_85_10INCH_IN1_DN")
	)
	(segment
		(start 114.332004 3.914648)
		(end 115.116864 8.360664)
		(width 0.14224)
		(layer "In2.Cu")
		(net "DELTA_L_85_10INCH_IN1_DN")
	)
	(segment
		(start 111.507016 8.593582)
		(end 113.101628 8.311896)
		(width 0.14224)
		(layer "In2.Cu")
		(net "DELTA_L_85_10INCH_IN1_DN")
	)
	(segment
		(start 105.427526 7.969504)
		(end 104.756458 4.167632)
		(width 0.14224)
		(layer "In2.Cu")
		(net "DELTA_L_85_10INCH_IN1_DN")
	)
	(segment
		(start 119.072152 8.318754)
		(end 119.428006 8.567928)
		(width 0.14224)
		(layer "In2.Cu")
		(net "DELTA_L_85_10INCH_IN1_DN")
	)
	(segment
		(start 162.664394 8.328152)
		(end 163.020248 8.577326)
		(width 0.14224)
		(layer "In2.Cu")
		(net "DELTA_L_85_10INCH_IN1_DN")
	)
	(segment
		(start 134.14375 3.903218)
		(end 134.922006 8.312658)
		(width 0.14224)
		(layer "In2.Cu")
		(net "DELTA_L_85_10INCH_IN1_DN")
	)
	(segment
		(start 127.000508 8.335518)
		(end 127.356362 8.584692)
		(width 0.14224)
		(layer "In2.Cu")
		(net "DELTA_L_85_10INCH_IN1_DN")
	)
	(segment
		(start 136.591548 4.102608)
		(end 137.95502 3.861816)
		(width 0.14224)
		(layer "In2.Cu")
		(net "DELTA_L_85_10INCH_IN1_DN")
	)
	(segment
		(start 145.046192 7.917942)
		(end 144.38503 4.17195)
		(width 0.14224)
		(layer "In2.Cu")
		(net "DELTA_L_85_10INCH_IN1_DN")
	)
	(segment
		(start 134.922006 8.312658)
		(end 135.27786 8.561832)
		(width 0.14224)
		(layer "In2.Cu")
		(net "DELTA_L_85_10INCH_IN1_DN")
	)
	(segment
		(start 117.06733 8.328152)
		(end 117.316504 7.972806)
		(width 0.14224)
		(layer "In2.Cu")
		(net "DELTA_L_85_10INCH_IN1_DN")
	)
	(segment
		(start 176.209452 4.04622)
		(end 177.572924 3.805428)
		(width 0.14224)
		(layer "In2.Cu")
		(net "DELTA_L_85_10INCH_IN1_DN")
	)
	(segment
		(start 177.572924 3.805428)
		(end 177.737262 3.920744)
		(width 0.14224)
		(layer "In2.Cu")
		(net "DELTA_L_85_10INCH_IN1_DN")
	)
	(segment
		(start 152.42159 3.983228)
		(end 153.785062 3.742436)
		(width 0.14224)
		(layer "In2.Cu")
		(net "DELTA_L_85_10INCH_IN1_DN")
	)
	(segment
		(start 151.131778 8.577326)
		(end 152.72639 8.29564)
		(width 0.14224)
		(layer "In2.Cu")
		(net "DELTA_L_85_10INCH_IN1_DN")
	)
	(segment
		(start 113.350802 7.956042)
		(end 112.688624 4.204716)
		(width 0.14224)
		(layer "In2.Cu")
		(net "DELTA_L_85_10INCH_IN1_DN")
	)
	(segment
		(start 172.128942 4.196842)
		(end 172.244258 4.031996)
		(width 0.14224)
		(layer "In2.Cu")
		(net "DELTA_L_85_10INCH_IN1_DN")
	)
	(segment
		(start 153.785062 3.742436)
		(end 153.949654 3.857752)
		(width 0.14224)
		(layer "In2.Cu")
		(net "DELTA_L_85_10INCH_IN1_DN")
	)
	(segment
		(start 126.22022 3.914648)
		(end 127.000508 8.335518)
		(width 0.14224)
		(layer "In2.Cu")
		(net "DELTA_L_85_10INCH_IN1_DN")
	)
	(segment
		(start 112.688624 4.204716)
		(end 112.80394 4.040124)
		(width 0.14224)
		(layer "In2.Cu")
		(net "DELTA_L_85_10INCH_IN1_DN")
	)
	(segment
		(start 148.342096 4.139946)
		(end 148.457412 3.975354)
		(width 0.14224)
		(layer "In2.Cu")
		(net "DELTA_L_85_10INCH_IN1_DN")
	)
	(segment
		(start 106.400092 3.877818)
		(end 107.189524 8.35025)
		(width 0.14224)
		(layer "In2.Cu")
		(net "DELTA_L_85_10INCH_IN1_DN")
	)
	(segment
		(start 147.167346 8.567928)
		(end 148.761958 8.286242)
		(width 0.14224)
		(layer "In2.Cu")
		(net "DELTA_L_85_10INCH_IN1_DN")
	)
	(segment
		(start 128.652778 4.027932)
		(end 130.01625 3.78714)
		(width 0.14224)
		(layer "In2.Cu")
		(net "DELTA_L_85_10INCH_IN1_DN")
	)
	(segment
		(start 132.615686 4.028694)
		(end 133.979158 3.787902)
		(width 0.14224)
		(layer "In2.Cu")
		(net "DELTA_L_85_10INCH_IN1_DN")
	)
	(segment
		(start 154.734514 8.304784)
		(end 155.090622 8.55345)
		(width 0.14224)
		(layer "In2.Cu")
		(net "DELTA_L_85_10INCH_IN1_DN")
	)
	(segment
		(start 136.872726 8.280146)
		(end 137.121646 7.924038)
		(width 0.14224)
		(layer "In2.Cu")
		(net "DELTA_L_85_10INCH_IN1_DN")
	)
	(segment
		(start 181.662832 6.204204)
		(end 184.09412 6.204204)
		(width 0.14224)
		(layer "In2.Cu")
		(net "DELTA_L_85_10INCH_IN1_DN")
	)
	(segment
		(start 132.91693 8.320024)
		(end 133.166104 7.96417)
		(width 0.14224)
		(layer "In2.Cu")
		(net "DELTA_L_85_10INCH_IN1_DN")
	)
	(segment
		(start 135.27786 8.561832)
		(end 136.872726 8.280146)
		(width 0.14224)
		(layer "In2.Cu")
		(net "DELTA_L_85_10INCH_IN1_DN")
	)
	(segment
		(start 122.259852 3.92684)
		(end 123.041664 8.356346)
		(width 0.14224)
		(layer "In2.Cu")
		(net "DELTA_L_85_10INCH_IN1_DN")
	)
	(segment
		(start 108.72343 4.191)
		(end 108.838746 4.026408)
		(width 0.14224)
		(layer "In2.Cu")
		(net "DELTA_L_85_10INCH_IN1_DN")
	)
	(segment
		(start 115.116864 8.360664)
		(end 115.472718 8.609838)
		(width 0.14224)
		(layer "In2.Cu")
		(net "DELTA_L_85_10INCH_IN1_DN")
	)
	(segment
		(start 105.178352 8.325358)
		(end 105.427526 7.969504)
		(width 0.14224)
		(layer "In2.Cu")
		(net "DELTA_L_85_10INCH_IN1_DN")
	)
	(segment
		(start 137.95502 3.861816)
		(end 138.119612 3.977132)
		(width 0.14224)
		(layer "In2.Cu")
		(net "DELTA_L_85_10INCH_IN1_DN")
	)
	(segment
		(start 174.560484 8.372602)
		(end 174.916338 8.621776)
		(width 0.14224)
		(layer "In2.Cu")
		(net "DELTA_L_85_10INCH_IN1_DN")
	)
	(segment
		(start 141.092682 7.970774)
		(end 140.429996 4.215892)
		(width 0.14224)
		(layer "In2.Cu")
		(net "DELTA_L_85_10INCH_IN1_DN")
	)
	(segment
		(start 124.57684 4.204716)
		(end 124.692156 4.040124)
		(width 0.14224)
		(layer "In2.Cu")
		(net "DELTA_L_85_10INCH_IN1_DN")
	)
	(segment
		(start 138.893042 8.35914)
		(end 139.248896 8.608314)
		(width 0.14224)
		(layer "In2.Cu")
		(net "DELTA_L_85_10INCH_IN1_DN")
	)
	(segment
		(start 156.934154 7.915656)
		(end 156.268674 4.145534)
		(width 0.14224)
		(layer "In2.Cu")
		(net "DELTA_L_85_10INCH_IN1_DN")
	)
	(segment
		(start 166.62273 8.30326)
		(end 166.978584 8.552434)
		(width 0.14224)
		(layer "In2.Cu")
		(net "DELTA_L_85_10INCH_IN1_DN")
	)
	(segment
		(start 106.235246 3.762502)
		(end 106.400092 3.877818)
		(width 0.14224)
		(layer "In2.Cu")
		(net "DELTA_L_85_10INCH_IN1_DN")
	)
	(segment
		(start 110.36681 3.900932)
		(end 111.151162 8.344408)
		(width 0.14224)
		(layer "In2.Cu")
		(net "DELTA_L_85_10INCH_IN1_DN")
	)
	(segment
		(start 102.37089 6.204204)
		(end 102.914958 6.58495)
		(width 0.14224)
		(layer "In2.Cu")
		(net "DELTA_L_85_10INCH_IN1_DN")
	)
	(segment
		(start 104.871774 4.003294)
		(end 106.235246 3.762502)
		(width 0.14224)
		(layer "In2.Cu")
		(net "DELTA_L_85_10INCH_IN1_DN")
	)
	(segment
		(start 144.38503 4.17195)
		(end 144.500346 4.007358)
		(width 0.14224)
		(layer "In2.Cu")
		(net "DELTA_L_85_10INCH_IN1_DN")
	)
	(segment
		(start 112.80394 4.040124)
		(end 114.167412 3.799332)
		(width 0.14224)
		(layer "In2.Cu")
		(net "DELTA_L_85_10INCH_IN1_DN")
	)
	(segment
		(start 142.073376 3.925824)
		(end 142.846552 8.306308)
		(width 0.14224)
		(layer "In2.Cu")
		(net "DELTA_L_85_10INCH_IN1_DN")
	)
	(segment
		(start 155.090622 8.55345)
		(end 156.685234 8.271764)
		(width 0.14224)
		(layer "In2.Cu")
		(net "DELTA_L_85_10INCH_IN1_DN")
	)
	(segment
		(start 133.166104 7.96417)
		(end 132.50037 4.193286)
		(width 0.14224)
		(layer "In2.Cu")
		(net "DELTA_L_85_10INCH_IN1_DN")
	)
	(segment
		(start 118.299738 3.943096)
		(end 119.072152 8.318754)
		(width 0.14224)
		(layer "In2.Cu")
		(net "DELTA_L_85_10INCH_IN1_DN")
	)
	(segment
		(start 152.72639 8.29564)
		(end 152.975564 7.939786)
		(width 0.14224)
		(layer "In2.Cu")
		(net "DELTA_L_85_10INCH_IN1_DN")
	)
	(segment
		(start 109.389164 7.961884)
		(end 108.72343 4.191)
		(width 0.14224)
		(layer "In2.Cu")
		(net "DELTA_L_85_10INCH_IN1_DN")
	)
	(segment
		(start 170.592242 8.342122)
		(end 170.948096 8.591296)
		(width 0.14224)
		(layer "In2.Cu")
		(net "DELTA_L_85_10INCH_IN1_DN")
	)
	(segment
		(start 140.843508 8.326628)
		(end 141.092682 7.970774)
		(width 0.14224)
		(layer "In2.Cu")
		(net "DELTA_L_85_10INCH_IN1_DN")
	)
	(segment
		(start 116.771674 4.068572)
		(end 118.135146 3.82778)
		(width 0.14224)
		(layer "In2.Cu")
		(net "DELTA_L_85_10INCH_IN1_DN")
	)
	(segment
		(start 103.58374 8.607044)
		(end 105.178352 8.325358)
		(width 0.14224)
		(layer "In2.Cu")
		(net "DELTA_L_85_10INCH_IN1_DN")
	)
	(segment
		(start 178.85791 8.583168)
		(end 180.382672 8.314182)
		(width 0.14224)
		(layer "In2.Cu")
		(net "DELTA_L_85_10INCH_IN1_DN")
	)
	(segment
		(start 160.655762 8.316468)
		(end 160.904936 7.960614)
		(width 0.14224)
		(layer "In2.Cu")
		(net "DELTA_L_85_10INCH_IN1_DN")
	)
	(segment
		(start 144.797018 8.273796)
		(end 145.046192 7.917942)
		(width 0.14224)
		(layer "In2.Cu")
		(net "DELTA_L_85_10INCH_IN1_DN")
	)
	(segment
		(start 160.35147 4.007612)
		(end 161.714942 3.76682)
		(width 0.14224)
		(layer "In2.Cu")
		(net "DELTA_L_85_10INCH_IN1_DN")
	)
	(segment
		(start 146.811492 8.318754)
		(end 147.167346 8.567928)
		(width 0.14224)
		(layer "In2.Cu")
		(net "DELTA_L_85_10INCH_IN1_DN")
	)
	(segment
		(start 103.227886 8.35787)
		(end 103.58374 8.607044)
		(width 0.14224)
		(layer "In2.Cu")
		(net "DELTA_L_85_10INCH_IN1_DN")
	)
	(segment
		(start 184.09412 6.204204)
		(end 184.38495 6.495034)
		(width 0.14224)
		(layer "In2.Cu")
		(net "DELTA_L_85_10INCH_IN1_DN")
	)
	(segment
		(start 163.020248 8.577326)
		(end 164.61486 8.29564)
		(width 0.14224)
		(layer "In2.Cu")
		(net "DELTA_L_85_10INCH_IN1_DN")
	)
	(segment
		(start 149.011132 7.930388)
		(end 148.342096 4.139946)
		(width 0.14224)
		(layer "In2.Cu")
		(net "DELTA_L_85_10INCH_IN1_DN")
	)
	(segment
		(start 152.306274 4.14782)
		(end 152.42159 3.983228)
		(width 0.14224)
		(layer "In2.Cu")
		(net "DELTA_L_85_10INCH_IN1_DN")
	)
	(segment
		(start 139.248896 8.608314)
		(end 140.843508 8.326628)
		(width 0.14224)
		(layer "In2.Cu")
		(net "DELTA_L_85_10INCH_IN1_DN")
	)
	(segment
		(start 168.82237 7.914894)
		(end 168.177972 4.264406)
		(width 0.14224)
		(layer "In2.Cu")
		(net "DELTA_L_85_10INCH_IN1_DN")
	)
	(segment
		(start 123.041664 8.356346)
		(end 123.397518 8.60552)
		(width 0.14224)
		(layer "In2.Cu")
		(net "DELTA_L_85_10INCH_IN1_DN")
	)
	(segment
		(start 120.731788 4.052316)
		(end 122.09526 3.811524)
		(width 0.14224)
		(layer "In2.Cu")
		(net "DELTA_L_85_10INCH_IN1_DN")
	)
	(segment
		(start 159.06115 8.598154)
		(end 160.655762 8.316468)
		(width 0.14224)
		(layer "In2.Cu")
		(net "DELTA_L_85_10INCH_IN1_DN")
	)
	(segment
		(start 132.50037 4.193286)
		(end 132.615686 4.028694)
		(width 0.14224)
		(layer "In2.Cu")
		(net "DELTA_L_85_10INCH_IN1_DN")
	)
	(segment
		(start 111.151162 8.344408)
		(end 111.507016 8.593582)
		(width 0.14224)
		(layer "In2.Cu")
		(net "DELTA_L_85_10INCH_IN1_DN")
	)
	(segment
		(start 148.761958 8.286242)
		(end 149.011132 7.930388)
		(width 0.14224)
		(layer "In2.Cu")
		(net "DELTA_L_85_10INCH_IN1_DN")
	)
	(segment
		(start 136.476232 4.2672)
		(end 136.591548 4.102608)
		(width 0.14224)
		(layer "In2.Cu")
		(net "DELTA_L_85_10INCH_IN1_DN")
	)
	(segment
		(start 140.429996 4.215892)
		(end 140.545312 4.0513)
		(width 0.14224)
		(layer "In2.Cu")
		(net "DELTA_L_85_10INCH_IN1_DN")
	)
	(segment
		(start 109.13999 8.317738)
		(end 109.389164 7.961884)
		(width 0.14224)
		(layer "In2.Cu")
		(net "DELTA_L_85_10INCH_IN1_DN")
	)
	(segment
		(start 173.60773 3.791204)
		(end 173.772068 3.90652)
		(width 0.14224)
		(layer "In2.Cu")
		(net "DELTA_L_85_10INCH_IN1_DN")
	)
	(segment
		(start 157.747462 3.740404)
		(end 157.912308 3.85572)
		(width 0.14224)
		(layer "In2.Cu")
		(net "DELTA_L_85_10INCH_IN1_DN")
	)
	(segment
		(start 177.737262 3.920744)
		(end 178.51882 8.346694)
		(width 0.14224)
		(layer "In2.Cu")
		(net "DELTA_L_85_10INCH_IN1_DN")
	)
	(segment
		(start 124.692156 4.040124)
		(end 126.055628 3.799332)
		(width 0.14224)
		(layer "In2.Cu")
		(net "DELTA_L_85_10INCH_IN1_DN")
	)
	(segment
		(start 172.791882 7.953756)
		(end 172.128942 4.196842)
		(width 0.14224)
		(layer "In2.Cu")
		(net "DELTA_L_85_10INCH_IN1_DN")
	)
	(segment
		(start 164.61486 8.29564)
		(end 164.864034 7.940294)
		(width 0.14224)
		(layer "In2.Cu")
		(net "DELTA_L_85_10INCH_IN1_DN")
	)
	(segment
		(start 168.573196 8.270748)
		(end 168.82237 7.914894)
		(width 0.14224)
		(layer "In2.Cu")
		(net "DELTA_L_85_10INCH_IN1_DN")
	)
	(segment
		(start 170.948096 8.591296)
		(end 172.542708 8.30961)
		(width 0.14224)
		(layer "In2.Cu")
		(net "DELTA_L_85_10INCH_IN1_DN")
	)
	(segment
		(start 120.616472 4.216908)
		(end 120.731788 4.052316)
		(width 0.14224)
		(layer "In2.Cu")
		(net "DELTA_L_85_10INCH_IN1_DN")
	)
	(segment
		(start 176.094136 4.210812)
		(end 176.209452 4.04622)
		(width 0.14224)
		(layer "In2.Cu")
		(net "DELTA_L_85_10INCH_IN1_DN")
	)
	(segment
		(start 165.839902 3.869944)
		(end 166.62273 8.30326)
		(width 0.14224)
		(layer "In2.Cu")
		(net "DELTA_L_85_10INCH_IN1_DN")
	)
	(segment
		(start 115.472718 8.609838)
		(end 117.06733 8.328152)
		(width 0.14224)
		(layer "In2.Cu")
		(net "DELTA_L_85_10INCH_IN1_DN")
	)
	(segment
		(start 180.700934 7.859522)
		(end 180.515768 6.811264)
		(width 0.14224)
		(layer "In2.Cu")
		(net "DELTA_L_85_10INCH_IN1_DN")
	)
	(segment
		(start 130.180842 3.902456)
		(end 130.966464 8.352536)
		(width 0.14224)
		(layer "In2.Cu")
		(net "DELTA_L_85_10INCH_IN1_DN")
	)
	(segment
		(start 160.904936 7.960614)
		(end 160.236154 4.172204)
		(width 0.14224)
		(layer "In2.Cu")
		(net "DELTA_L_85_10INCH_IN1_DN")
	)
	(segment
		(start 161.714942 3.76682)
		(end 161.879534 3.882136)
		(width 0.14224)
		(layer "In2.Cu")
		(net "DELTA_L_85_10INCH_IN1_DN")
	)
	(segment
		(start 124.99213 8.323834)
		(end 125.24105 7.968234)
		(width 0.14224)
		(layer "In2.Cu")
		(net "DELTA_L_85_10INCH_IN1_DN")
	)
	(segment
		(start 180.847492 6.340856)
		(end 181.662832 6.204204)
		(width 0.14224)
		(layer "In2.Cu")
		(net "DELTA_L_85_10INCH_IN1_DN")
	)
	(segment
		(start 169.821352 3.974338)
		(end 170.592242 8.342122)
		(width 0.14224)
		(layer "In2.Cu")
		(net "DELTA_L_85_10INCH_IN1_DN")
	)
	(segment
		(start 156.685234 8.271764)
		(end 156.934154 7.915656)
		(width 0.14224)
		(layer "In2.Cu")
		(net "DELTA_L_85_10INCH_IN1_DN")
	)
	(segment
		(start 150.775924 8.328152)
		(end 151.131778 8.577326)
		(width 0.14224)
		(layer "In2.Cu")
		(net "DELTA_L_85_10INCH_IN1_DN")
	)
	(segment
		(start 125.24105 7.968234)
		(end 124.57684 4.204716)
		(width 0.14224)
		(layer "In2.Cu")
		(net "DELTA_L_85_10INCH_IN1_DN")
	)
	(segment
		(start 164.196776 4.160266)
		(end 164.312092 3.99542)
		(width 0.14224)
		(layer "In2.Cu")
		(net "DELTA_L_85_10INCH_IN1_DN")
	)
	(segment
		(start 143.202406 8.555482)
		(end 144.797018 8.273796)
		(width 0.14224)
		(layer "In2.Cu")
		(net "DELTA_L_85_10INCH_IN1_DN")
	)
	(segment
		(start 142.846552 8.306308)
		(end 143.202406 8.555482)
		(width 0.14224)
		(layer "In2.Cu")
		(net "DELTA_L_85_10INCH_IN1_DN")
	)
	(segment
		(start 166.978584 8.552434)
		(end 168.573196 8.270748)
		(width 0.14224)
		(layer "In2.Cu")
		(net "DELTA_L_85_10INCH_IN1_DN")
	)
	(segment
		(start 137.121646 7.924038)
		(end 136.476232 4.2672)
		(width 0.14224)
		(layer "In2.Cu")
		(net "DELTA_L_85_10INCH_IN1_DN")
	)
	(segment
		(start 126.055628 3.799332)
		(end 126.22022 3.914648)
		(width 0.14224)
		(layer "In2.Cu")
		(net "DELTA_L_85_10INCH_IN1_DN")
	)
	(segment
		(start 148.457412 3.975354)
		(end 149.820884 3.734562)
		(width 0.14224)
		(layer "In2.Cu")
		(net "DELTA_L_85_10INCH_IN1_DN")
	)
	(segment
		(start 130.966464 8.352536)
		(end 131.322318 8.60171)
		(width 0.14224)
		(layer "In2.Cu")
		(net "DELTA_L_85_10INCH_IN1_DN")
	)
	(segment
		(start 121.022618 8.286242)
		(end 121.271792 7.930388)
		(width 0.14224)
		(layer "In2.Cu")
		(net "DELTA_L_85_10INCH_IN1_DN")
	)
	(segment
		(start 180.515768 6.811264)
		(end 180.847492 6.340856)
		(width 0.14224)
		(layer "In2.Cu")
		(net "DELTA_L_85_10INCH_IN1_DN")
	)
	(segment
		(start 295.24706 7.784084)
		(end 294.427656 7.211568)
		(width 0.12954)
		(layer "B.Cu")
		(net "DELTA_L_85_10INCH_BOT_DP")
	)
	(segment
		(start 283.223462 10.234168)
		(end 282.855162 9.976358)
		(width 0.12954)
		(layer "B.Cu")
		(net "DELTA_L_85_10INCH_BOT_DP")
	)
	(segment
		(start 289.941254 5.315966)
		(end 288.565336 5.559552)
		(width 0.12954)
		(layer "B.Cu")
		(net "DELTA_L_85_10INCH_BOT_DP")
	)
	(segment
		(start 244.343174 5.573268)
		(end 244.238018 5.723128)
		(width 0.12954)
		(layer "B.Cu")
		(net "DELTA_L_85_10INCH_BOT_DP")
	)
	(segment
		(start 261.946644 5.411724)
		(end 261.797292 5.306568)
		(width 0.12954)
		(layer "B.Cu")
		(net "DELTA_L_85_10INCH_BOT_DP")
	)
	(segment
		(start 237.818168 5.376926)
		(end 237.668562 5.27177)
		(width 0.12954)
		(layer "B.Cu")
		(net "DELTA_L_85_10INCH_BOT_DP")
	)
	(segment
		(start 277.87981 5.31495)
		(end 276.503892 5.558536)
		(width 0.12954)
		(layer "B.Cu")
		(net "DELTA_L_85_10INCH_BOT_DP")
	)
	(segment
		(start 284.865064 9.9441)
		(end 283.223462 10.234168)
		(width 0.12954)
		(layer "B.Cu")
		(net "DELTA_L_85_10INCH_BOT_DP")
	)
	(segment
		(start 247.038368 10.224008)
		(end 246.670068 9.966198)
		(width 0.12954)
		(layer "B.Cu")
		(net "DELTA_L_85_10INCH_BOT_DP")
	)
	(segment
		(start 240.63706 9.923526)
		(end 238.995712 10.213594)
		(width 0.12954)
		(layer "B.Cu")
		(net "DELTA_L_85_10INCH_BOT_DP")
	)
	(segment
		(start 232.173272 5.700776)
		(end 232.854754 9.557258)
		(width 0.12954)
		(layer "B.Cu")
		(net "DELTA_L_85_10INCH_BOT_DP")
	)
	(segment
		(start 240.895124 9.555226)
		(end 240.63706 9.923526)
		(width 0.12954)
		(layer "B.Cu")
		(net "DELTA_L_85_10INCH_BOT_DP")
	)
	(segment
		(start 245.869206 5.434838)
		(end 245.719092 5.329682)
		(width 0.12954)
		(layer "B.Cu")
		(net "DELTA_L_85_10INCH_BOT_DP")
	)
	(segment
		(start 259.09397 10.192766)
		(end 258.72567 9.934956)
		(width 0.12954)
		(layer "B.Cu")
		(net "DELTA_L_85_10INCH_BOT_DP")
	)
	(segment
		(start 243.016532 10.217404)
		(end 242.648232 9.959594)
		(width 0.12954)
		(layer "B.Cu")
		(net "DELTA_L_85_10INCH_BOT_DP")
	)
	(segment
		(start 224.55378 9.913112)
		(end 222.912432 10.20318)
		(width 0.12954)
		(layer "B.Cu")
		(net "DELTA_L_85_10INCH_BOT_DP")
	)
	(segment
		(start 292.905688 9.944608)
		(end 291.26434 10.234676)
		(width 0.12954)
		(layer "B.Cu")
		(net "DELTA_L_85_10INCH_BOT_DP")
	)
	(segment
		(start 268.78026 9.926066)
		(end 267.138658 10.216134)
		(width 0.12954)
		(layer "B.Cu")
		(net "DELTA_L_85_10INCH_BOT_DP")
	)
	(segment
		(start 285.122874 9.575292)
		(end 284.865064 9.9441)
		(width 0.12954)
		(layer "B.Cu")
		(net "DELTA_L_85_10INCH_BOT_DP")
	)
	(segment
		(start 220.794834 9.565132)
		(end 220.537024 9.933178)
		(width 0.12954)
		(layer "B.Cu")
		(net "DELTA_L_85_10INCH_BOT_DP")
	)
	(segment
		(start 270.789908 9.95426)
		(end 269.988284 5.416804)
		(width 0.12954)
		(layer "B.Cu")
		(net "DELTA_L_85_10INCH_BOT_DP")
	)
	(segment
		(start 271.158208 10.212324)
		(end 270.789908 9.95426)
		(width 0.12954)
		(layer "B.Cu")
		(net "DELTA_L_85_10INCH_BOT_DP")
	)
	(segment
		(start 281.899106 5.309616)
		(end 280.523188 5.553202)
		(width 0.12954)
		(layer "B.Cu")
		(net "DELTA_L_85_10INCH_BOT_DP")
	)
	(segment
		(start 229.781608 5.400548)
		(end 229.632002 5.295392)
		(width 0.12954)
		(layer "B.Cu")
		(net "DELTA_L_85_10INCH_BOT_DP")
	)
	(segment
		(start 228.150928 5.689346)
		(end 228.834188 9.557766)
		(width 0.12954)
		(layer "B.Cu")
		(net "DELTA_L_85_10INCH_BOT_DP")
	)
	(segment
		(start 282.855162 9.976358)
		(end 282.048966 5.414772)
		(width 0.12954)
		(layer "B.Cu")
		(net "DELTA_L_85_10INCH_BOT_DP")
	)
	(segment
		(start 256.398522 5.53847)
		(end 256.293366 5.68833)
		(width 0.12954)
		(layer "B.Cu")
		(net "DELTA_L_85_10INCH_BOT_DP")
	)
	(segment
		(start 236.872526 9.543034)
		(end 236.614716 9.911842)
		(width 0.12954)
		(layer "B.Cu")
		(net "DELTA_L_85_10INCH_BOT_DP")
	)
	(segment
		(start 282.048966 5.414772)
		(end 281.899106 5.309616)
		(width 0.12954)
		(layer "B.Cu")
		(net "DELTA_L_85_10INCH_BOT_DP")
	)
	(segment
		(start 274.010628 5.42671)
		(end 273.860768 5.321554)
		(width 0.12954)
		(layer "B.Cu")
		(net "DELTA_L_85_10INCH_BOT_DP")
	)
	(segment
		(start 273.860768 5.321554)
		(end 272.48485 5.56514)
		(width 0.12954)
		(layer "B.Cu")
		(net "DELTA_L_85_10INCH_BOT_DP")
	)
	(segment
		(start 232.596944 9.926066)
		(end 230.955088 10.216134)
		(width 0.12954)
		(layer "B.Cu")
		(net "DELTA_L_85_10INCH_BOT_DP")
	)
	(segment
		(start 234.604814 9.943592)
		(end 233.80446 5.412486)
		(width 0.12954)
		(layer "B.Cu")
		(net "DELTA_L_85_10INCH_BOT_DP")
	)
	(segment
		(start 246.670068 9.966198)
		(end 245.869206 5.434838)
		(width 0.12954)
		(layer "B.Cu")
		(net "DELTA_L_85_10INCH_BOT_DP")
	)
	(segment
		(start 256.293366 5.68833)
		(end 256.972816 9.533636)
		(width 0.12954)
		(layer "B.Cu")
		(net "DELTA_L_85_10INCH_BOT_DP")
	)
	(segment
		(start 263.11606 10.202926)
		(end 262.74776 9.945116)
		(width 0.12954)
		(layer "B.Cu")
		(net "DELTA_L_85_10INCH_BOT_DP")
	)
	(segment
		(start 258.72567 9.934956)
		(end 257.924554 5.40004)
		(width 0.12954)
		(layer "B.Cu")
		(net "DELTA_L_85_10INCH_BOT_DP")
	)
	(segment
		(start 292.475666 5.681726)
		(end 293.163498 9.5758)
		(width 0.12954)
		(layer "B.Cu")
		(net "DELTA_L_85_10INCH_BOT_DP")
	)
	(segment
		(start 218.229688 8.281924)
		(end 217.518488 7.784084)
		(width 0.12954)
		(layer "B.Cu")
		(net "DELTA_L_85_10INCH_BOT_DP")
	)
	(segment
		(start 286.874966 9.972548)
		(end 286.070294 5.418582)
		(width 0.12954)
		(layer "B.Cu")
		(net "DELTA_L_85_10INCH_BOT_DP")
	)
	(segment
		(start 233.80446 5.412486)
		(end 233.654346 5.30733)
		(width 0.12954)
		(layer "B.Cu")
		(net "DELTA_L_85_10INCH_BOT_DP")
	)
	(segment
		(start 269.03807 9.557258)
		(end 268.78026 9.926066)
		(width 0.12954)
		(layer "B.Cu")
		(net "DELTA_L_85_10INCH_BOT_DP")
	)
	(segment
		(start 265.015472 9.54405)
		(end 264.757662 9.912858)
		(width 0.12954)
		(layer "B.Cu")
		(net "DELTA_L_85_10INCH_BOT_DP")
	)
	(segment
		(start 294.427656 7.211568)
		(end 294.1066 5.393182)
		(width 0.12954)
		(layer "B.Cu")
		(net "DELTA_L_85_10INCH_BOT_DP")
	)
	(segment
		(start 240.319814 5.556504)
		(end 240.214658 5.70611)
		(width 0.12954)
		(layer "B.Cu")
		(net "DELTA_L_85_10INCH_BOT_DP")
	)
	(segment
		(start 220.212158 5.522468)
		(end 220.107002 5.672328)
		(width 0.12954)
		(layer "B.Cu")
		(net "DELTA_L_85_10INCH_BOT_DP")
	)
	(segment
		(start 238.627158 9.955784)
		(end 237.818168 5.376926)
		(width 0.12954)
		(layer "B.Cu")
		(net "DELTA_L_85_10INCH_BOT_DP")
	)
	(segment
		(start 222.544132 9.94537)
		(end 221.737936 5.384038)
		(width 0.12954)
		(layer "B.Cu")
		(net "DELTA_L_85_10INCH_BOT_DP")
	)
	(segment
		(start 218.527122 9.96569)
		(end 218.229688 8.281924)
		(width 0.12954)
		(layer "B.Cu")
		(net "DELTA_L_85_10INCH_BOT_DP")
	)
	(segment
		(start 252.957076 9.561068)
		(end 252.699012 9.929622)
		(width 0.12954)
		(layer "B.Cu")
		(net "DELTA_L_85_10INCH_BOT_DP")
	)
	(segment
		(start 299.712888 7.87273)
		(end 299.550328 7.87273)
		(width 0.12954)
		(layer "B.Cu")
		(net "DELTA_L_85_10INCH_BOT_DP")
	)
	(segment
		(start 266.770358 9.958324)
		(end 265.968734 5.421376)
		(width 0.12954)
		(layer "B.Cu")
		(net "DELTA_L_85_10INCH_BOT_DP")
	)
	(segment
		(start 294.1066 5.393182)
		(end 293.95674 5.288026)
		(width 0.12954)
		(layer "B.Cu")
		(net "DELTA_L_85_10INCH_BOT_DP")
	)
	(segment
		(start 279.200864 10.221468)
		(end 278.832564 9.963658)
		(width 0.12954)
		(layer "B.Cu")
		(net "DELTA_L_85_10INCH_BOT_DP")
	)
	(segment
		(start 241.695732 5.312918)
		(end 240.319814 5.556504)
		(width 0.12954)
		(layer "B.Cu")
		(net "DELTA_L_85_10INCH_BOT_DP")
	)
	(segment
		(start 256.972816 9.533636)
		(end 256.714752 9.90219)
		(width 0.12954)
		(layer "B.Cu")
		(net "DELTA_L_85_10INCH_BOT_DP")
	)
	(segment
		(start 226.934776 10.216642)
		(end 226.566476 9.958832)
		(width 0.12954)
		(layer "B.Cu")
		(net "DELTA_L_85_10INCH_BOT_DP")
	)
	(segment
		(start 281.100276 9.562592)
		(end 280.842466 9.9314)
		(width 0.12954)
		(layer "B.Cu")
		(net "DELTA_L_85_10INCH_BOT_DP")
	)
	(segment
		(start 232.854754 9.557258)
		(end 232.596944 9.926066)
		(width 0.12954)
		(layer "B.Cu")
		(net "DELTA_L_85_10INCH_BOT_DP")
	)
	(segment
		(start 251.057664 10.21969)
		(end 250.689364 9.96188)
		(width 0.12954)
		(layer "B.Cu")
		(net "DELTA_L_85_10INCH_BOT_DP")
	)
	(segment
		(start 229.632002 5.295392)
		(end 228.256084 5.538978)
		(width 0.12954)
		(layer "B.Cu")
		(net "DELTA_L_85_10INCH_BOT_DP")
	)
	(segment
		(start 276.503892 5.558536)
		(end 276.398736 5.708142)
		(width 0.12954)
		(layer "B.Cu")
		(net "DELTA_L_85_10INCH_BOT_DP")
	)
	(segment
		(start 272.48485 5.56514)
		(end 272.379694 5.715)
		(width 0.12954)
		(layer "B.Cu")
		(net "DELTA_L_85_10INCH_BOT_DP")
	)
	(segment
		(start 268.462506 5.555234)
		(end 268.35735 5.705094)
		(width 0.12954)
		(layer "B.Cu")
		(net "DELTA_L_85_10INCH_BOT_DP")
	)
	(segment
		(start 248.93778 9.565386)
		(end 248.679716 9.93394)
		(width 0.12954)
		(layer "B.Cu")
		(net "DELTA_L_85_10INCH_BOT_DP")
	)
	(segment
		(start 236.292644 5.515356)
		(end 236.187488 5.665216)
		(width 0.12954)
		(layer "B.Cu")
		(net "DELTA_L_85_10INCH_BOT_DP")
	)
	(segment
		(start 288.565336 5.559552)
		(end 288.46018 5.709412)
		(width 0.12954)
		(layer "B.Cu")
		(net "DELTA_L_85_10INCH_BOT_DP")
	)
	(segment
		(start 248.679716 9.93394)
		(end 247.038368 10.224008)
		(width 0.12954)
		(layer "B.Cu")
		(net "DELTA_L_85_10INCH_BOT_DP")
	)
	(segment
		(start 221.737936 5.384038)
		(end 221.588076 5.278882)
		(width 0.12954)
		(layer "B.Cu")
		(net "DELTA_L_85_10INCH_BOT_DP")
	)
	(segment
		(start 293.95674 5.288026)
		(end 292.580822 5.531866)
		(width 0.12954)
		(layer "B.Cu")
		(net "DELTA_L_85_10INCH_BOT_DP")
	)
	(segment
		(start 280.842466 9.9314)
		(end 279.200864 10.221468)
		(width 0.12954)
		(layer "B.Cu")
		(net "DELTA_L_85_10INCH_BOT_DP")
	)
	(segment
		(start 292.580822 5.531866)
		(end 292.475666 5.681726)
		(width 0.12954)
		(layer "B.Cu")
		(net "DELTA_L_85_10INCH_BOT_DP")
	)
	(segment
		(start 226.566476 9.958832)
		(end 225.761042 5.399532)
		(width 0.12954)
		(layer "B.Cu")
		(net "DELTA_L_85_10INCH_BOT_DP")
	)
	(segment
		(start 228.256084 5.538978)
		(end 228.150928 5.689346)
		(width 0.12954)
		(layer "B.Cu")
		(net "DELTA_L_85_10INCH_BOT_DP")
	)
	(segment
		(start 286.070294 5.418582)
		(end 285.920434 5.313426)
		(width 0.12954)
		(layer "B.Cu")
		(net "DELTA_L_85_10INCH_BOT_DP")
	)
	(segment
		(start 242.648232 9.959594)
		(end 241.845592 5.418074)
		(width 0.12954)
		(layer "B.Cu")
		(net "DELTA_L_85_10INCH_BOT_DP")
	)
	(segment
		(start 221.588076 5.278882)
		(end 220.212158 5.522468)
		(width 0.12954)
		(layer "B.Cu")
		(net "DELTA_L_85_10INCH_BOT_DP")
	)
	(segment
		(start 290.89604 9.976866)
		(end 290.091114 5.421122)
		(width 0.12954)
		(layer "B.Cu")
		(net "DELTA_L_85_10INCH_BOT_DP")
	)
	(segment
		(start 264.757662 9.912858)
		(end 263.11606 10.202926)
		(width 0.12954)
		(layer "B.Cu")
		(net "DELTA_L_85_10INCH_BOT_DP")
	)
	(segment
		(start 272.79981 9.922256)
		(end 271.158208 10.212324)
		(width 0.12954)
		(layer "B.Cu")
		(net "DELTA_L_85_10INCH_BOT_DP")
	)
	(segment
		(start 228.834188 9.557766)
		(end 228.576378 9.926574)
		(width 0.12954)
		(layer "B.Cu")
		(net "DELTA_L_85_10INCH_BOT_DP")
	)
	(segment
		(start 240.214658 5.70611)
		(end 240.895124 9.555226)
		(width 0.12954)
		(layer "B.Cu")
		(net "DELTA_L_85_10INCH_BOT_DP")
	)
	(segment
		(start 284.544516 5.557012)
		(end 284.43936 5.706872)
		(width 0.12954)
		(layer "B.Cu")
		(net "DELTA_L_85_10INCH_BOT_DP")
	)
	(segment
		(start 287.242758 10.230358)
		(end 286.874966 9.972548)
		(width 0.12954)
		(layer "B.Cu")
		(net "DELTA_L_85_10INCH_BOT_DP")
	)
	(segment
		(start 236.614716 9.911842)
		(end 234.97286 10.20191)
		(width 0.12954)
		(layer "B.Cu")
		(net "DELTA_L_85_10INCH_BOT_DP")
	)
	(segment
		(start 220.537024 9.933178)
		(end 218.895676 10.223246)
		(width 0.12954)
		(layer "B.Cu")
		(net "DELTA_L_85_10INCH_BOT_DP")
	)
	(segment
		(start 218.895676 10.223246)
		(end 218.527122 9.96569)
		(width 0.12954)
		(layer "B.Cu")
		(net "DELTA_L_85_10INCH_BOT_DP")
	)
	(segment
		(start 260.735572 9.902698)
		(end 259.09397 10.192766)
		(width 0.12954)
		(layer "B.Cu")
		(net "DELTA_L_85_10INCH_BOT_DP")
	)
	(segment
		(start 245.719092 5.329682)
		(end 244.343174 5.573268)
		(width 0.12954)
		(layer "B.Cu")
		(net "DELTA_L_85_10INCH_BOT_DP")
	)
	(segment
		(start 244.238018 5.723128)
		(end 244.915944 9.558782)
		(width 0.12954)
		(layer "B.Cu")
		(net "DELTA_L_85_10INCH_BOT_DP")
	)
	(segment
		(start 213.43112 7.87273)
		(end 213.297008 7.87273)
		(width 0.12954)
		(layer "B.Cu")
		(net "DELTA_L_85_10INCH_BOT_DP")
	)
	(segment
		(start 230.955088 10.216134)
		(end 230.587042 9.957816)
		(width 0.12954)
		(layer "B.Cu")
		(net "DELTA_L_85_10INCH_BOT_DP")
	)
	(segment
		(start 225.611182 5.294376)
		(end 224.235264 5.537962)
		(width 0.12954)
		(layer "B.Cu")
		(net "DELTA_L_85_10INCH_BOT_DP")
	)
	(segment
		(start 244.915944 9.558782)
		(end 244.65788 9.927336)
		(width 0.12954)
		(layer "B.Cu")
		(net "DELTA_L_85_10INCH_BOT_DP")
	)
	(segment
		(start 299.550328 7.87273)
		(end 299.461682 7.784084)
		(width 0.12954)
		(layer "B.Cu")
		(net "DELTA_L_85_10INCH_BOT_DP")
	)
	(segment
		(start 253.757176 5.312156)
		(end 252.381258 5.555742)
		(width 0.12954)
		(layer "B.Cu")
		(net "DELTA_L_85_10INCH_BOT_DP")
	)
	(segment
		(start 269.838424 5.311648)
		(end 268.462506 5.555234)
		(width 0.12954)
		(layer "B.Cu")
		(net "DELTA_L_85_10INCH_BOT_DP")
	)
	(segment
		(start 225.761042 5.399532)
		(end 225.611182 5.294376)
		(width 0.12954)
		(layer "B.Cu")
		(net "DELTA_L_85_10INCH_BOT_DP")
	)
	(segment
		(start 248.358914 5.545074)
		(end 248.253758 5.69468)
		(width 0.12954)
		(layer "B.Cu")
		(net "DELTA_L_85_10INCH_BOT_DP")
	)
	(segment
		(start 280.418032 5.703062)
		(end 281.100276 9.562592)
		(width 0.12954)
		(layer "B.Cu")
		(net "DELTA_L_85_10INCH_BOT_DP")
	)
	(segment
		(start 274.814284 9.974834)
		(end 274.010628 5.42671)
		(width 0.12954)
		(layer "B.Cu")
		(net "DELTA_L_85_10INCH_BOT_DP")
	)
	(segment
		(start 252.381258 5.555742)
		(end 252.276102 5.705856)
		(width 0.12954)
		(layer "B.Cu")
		(net "DELTA_L_85_10INCH_BOT_DP")
	)
	(segment
		(start 233.654346 5.30733)
		(end 232.278428 5.550916)
		(width 0.12954)
		(layer "B.Cu")
		(net "DELTA_L_85_10INCH_BOT_DP")
	)
	(segment
		(start 276.823932 9.942576)
		(end 275.182584 10.232644)
		(width 0.12954)
		(layer "B.Cu")
		(net "DELTA_L_85_10INCH_BOT_DP")
	)
	(segment
		(start 249.884946 5.406644)
		(end 249.734832 5.301488)
		(width 0.12954)
		(layer "B.Cu")
		(net "DELTA_L_85_10INCH_BOT_DP")
	)
	(segment
		(start 241.845592 5.418074)
		(end 241.695732 5.312918)
		(width 0.12954)
		(layer "B.Cu")
		(net "DELTA_L_85_10INCH_BOT_DP")
	)
	(segment
		(start 213.519766 7.784084)
		(end 213.43112 7.87273)
		(width 0.12954)
		(layer "B.Cu")
		(net "DELTA_L_85_10INCH_BOT_DP")
	)
	(segment
		(start 264.338054 5.709666)
		(end 265.015472 9.54405)
		(width 0.12954)
		(layer "B.Cu")
		(net "DELTA_L_85_10INCH_BOT_DP")
	)
	(segment
		(start 288.46018 5.709412)
		(end 289.14217 9.571228)
		(width 0.12954)
		(layer "B.Cu")
		(net "DELTA_L_85_10INCH_BOT_DP")
	)
	(segment
		(start 257.924554 5.40004)
		(end 257.77444 5.294884)
		(width 0.12954)
		(layer "B.Cu")
		(net "DELTA_L_85_10INCH_BOT_DP")
	)
	(segment
		(start 278.832564 9.963658)
		(end 278.02967 5.420106)
		(width 0.12954)
		(layer "B.Cu")
		(net "DELTA_L_85_10INCH_BOT_DP")
	)
	(segment
		(start 267.138658 10.216134)
		(end 266.770358 9.958324)
		(width 0.12954)
		(layer "B.Cu")
		(net "DELTA_L_85_10INCH_BOT_DP")
	)
	(segment
		(start 224.235264 5.537962)
		(end 224.130108 5.687822)
		(width 0.12954)
		(layer "B.Cu")
		(net "DELTA_L_85_10INCH_BOT_DP")
	)
	(segment
		(start 273.057874 9.553956)
		(end 272.79981 9.922256)
		(width 0.12954)
		(layer "B.Cu")
		(net "DELTA_L_85_10INCH_BOT_DP")
	)
	(segment
		(start 217.518488 7.784084)
		(end 213.519766 7.784084)
		(width 0.12954)
		(layer "B.Cu")
		(net "DELTA_L_85_10INCH_BOT_DP")
	)
	(segment
		(start 253.906782 5.417312)
		(end 253.757176 5.312156)
		(width 0.12954)
		(layer "B.Cu")
		(net "DELTA_L_85_10INCH_BOT_DP")
	)
	(segment
		(start 269.988284 5.416804)
		(end 269.838424 5.311648)
		(width 0.12954)
		(layer "B.Cu")
		(net "DELTA_L_85_10INCH_BOT_DP")
	)
	(segment
		(start 238.995712 10.213594)
		(end 238.627158 9.955784)
		(width 0.12954)
		(layer "B.Cu")
		(net "DELTA_L_85_10INCH_BOT_DP")
	)
	(segment
		(start 260.993382 9.53389)
		(end 260.735572 9.902698)
		(width 0.12954)
		(layer "B.Cu")
		(net "DELTA_L_85_10INCH_BOT_DP")
	)
	(segment
		(start 236.187488 5.665216)
		(end 236.872526 9.543034)
		(width 0.12954)
		(layer "B.Cu")
		(net "DELTA_L_85_10INCH_BOT_DP")
	)
	(segment
		(start 290.091114 5.421122)
		(end 289.941254 5.315966)
		(width 0.12954)
		(layer "B.Cu")
		(net "DELTA_L_85_10INCH_BOT_DP")
	)
	(segment
		(start 275.182584 10.232644)
		(end 274.814284 9.974834)
		(width 0.12954)
		(layer "B.Cu")
		(net "DELTA_L_85_10INCH_BOT_DP")
	)
	(segment
		(start 285.920434 5.313426)
		(end 284.544516 5.557012)
		(width 0.12954)
		(layer "B.Cu")
		(net "DELTA_L_85_10INCH_BOT_DP")
	)
	(segment
		(start 224.130108 5.687822)
		(end 224.81159 9.544304)
		(width 0.12954)
		(layer "B.Cu")
		(net "DELTA_L_85_10INCH_BOT_DP")
	)
	(segment
		(start 299.461682 7.784084)
		(end 295.24706 7.784084)
		(width 0.12954)
		(layer "B.Cu")
		(net "DELTA_L_85_10INCH_BOT_DP")
	)
	(segment
		(start 280.523188 5.553202)
		(end 280.418032 5.703062)
		(width 0.12954)
		(layer "B.Cu")
		(net "DELTA_L_85_10INCH_BOT_DP")
	)
	(segment
		(start 278.02967 5.420106)
		(end 277.87981 5.31495)
		(width 0.12954)
		(layer "B.Cu")
		(net "DELTA_L_85_10INCH_BOT_DP")
	)
	(segment
		(start 252.699012 9.929622)
		(end 251.057664 10.21969)
		(width 0.12954)
		(layer "B.Cu")
		(net "DELTA_L_85_10INCH_BOT_DP")
	)
	(segment
		(start 232.278428 5.550916)
		(end 232.173272 5.700776)
		(width 0.12954)
		(layer "B.Cu")
		(net "DELTA_L_85_10INCH_BOT_DP")
	)
	(segment
		(start 272.379694 5.715)
		(end 273.057874 9.553956)
		(width 0.12954)
		(layer "B.Cu")
		(net "DELTA_L_85_10INCH_BOT_DP")
	)
	(segment
		(start 222.912432 10.20318)
		(end 222.544132 9.94537)
		(width 0.12954)
		(layer "B.Cu")
		(net "DELTA_L_85_10INCH_BOT_DP")
	)
	(segment
		(start 257.77444 5.294884)
		(end 256.398522 5.53847)
		(width 0.12954)
		(layer "B.Cu")
		(net "DELTA_L_85_10INCH_BOT_DP")
	)
	(segment
		(start 234.97286 10.20191)
		(end 234.604814 9.943592)
		(width 0.12954)
		(layer "B.Cu")
		(net "DELTA_L_85_10INCH_BOT_DP")
	)
	(segment
		(start 261.797292 5.306568)
		(end 260.42112 5.550408)
		(width 0.12954)
		(layer "B.Cu")
		(net "DELTA_L_85_10INCH_BOT_DP")
	)
	(segment
		(start 288.883852 9.94029)
		(end 287.242758 10.230358)
		(width 0.12954)
		(layer "B.Cu")
		(net "DELTA_L_85_10INCH_BOT_DP")
	)
	(segment
		(start 248.253758 5.69468)
		(end 248.93778 9.565386)
		(width 0.12954)
		(layer "B.Cu")
		(net "DELTA_L_85_10INCH_BOT_DP")
	)
	(segment
		(start 277.081996 9.574276)
		(end 276.823932 9.942576)
		(width 0.12954)
		(layer "B.Cu")
		(net "DELTA_L_85_10INCH_BOT_DP")
	)
	(segment
		(start 255.073404 10.192258)
		(end 254.705104 9.934448)
		(width 0.12954)
		(layer "B.Cu")
		(net "DELTA_L_85_10INCH_BOT_DP")
	)
	(segment
		(start 284.43936 5.706872)
		(end 285.122874 9.575292)
		(width 0.12954)
		(layer "B.Cu")
		(net "DELTA_L_85_10INCH_BOT_DP")
	)
	(segment
		(start 291.26434 10.234676)
		(end 290.89604 9.976866)
		(width 0.12954)
		(layer "B.Cu")
		(net "DELTA_L_85_10INCH_BOT_DP")
	)
	(segment
		(start 249.734832 5.301488)
		(end 248.358914 5.545074)
		(width 0.12954)
		(layer "B.Cu")
		(net "DELTA_L_85_10INCH_BOT_DP")
	)
	(segment
		(start 256.714752 9.90219)
		(end 255.073404 10.192258)
		(width 0.12954)
		(layer "B.Cu")
		(net "DELTA_L_85_10INCH_BOT_DP")
	)
	(segment
		(start 289.14217 9.571228)
		(end 288.883852 9.94029)
		(width 0.12954)
		(layer "B.Cu")
		(net "DELTA_L_85_10INCH_BOT_DP")
	)
	(segment
		(start 276.398736 5.708142)
		(end 277.081996 9.574276)
		(width 0.12954)
		(layer "B.Cu")
		(net "DELTA_L_85_10INCH_BOT_DP")
	)
	(segment
		(start 268.35735 5.705094)
		(end 269.03807 9.557258)
		(width 0.12954)
		(layer "B.Cu")
		(net "DELTA_L_85_10INCH_BOT_DP")
	)
	(segment
		(start 264.44321 5.559806)
		(end 264.338054 5.709666)
		(width 0.12954)
		(layer "B.Cu")
		(net "DELTA_L_85_10INCH_BOT_DP")
	)
	(segment
		(start 224.81159 9.544304)
		(end 224.55378 9.913112)
		(width 0.12954)
		(layer "B.Cu")
		(net "DELTA_L_85_10INCH_BOT_DP")
	)
	(segment
		(start 220.107002 5.672328)
		(end 220.794834 9.565132)
		(width 0.12954)
		(layer "B.Cu")
		(net "DELTA_L_85_10INCH_BOT_DP")
	)
	(segment
		(start 262.74776 9.945116)
		(end 261.946644 5.411724)
		(width 0.12954)
		(layer "B.Cu")
		(net "DELTA_L_85_10INCH_BOT_DP")
	)
	(segment
		(start 265.968734 5.421376)
		(end 265.819382 5.31622)
		(width 0.12954)
		(layer "B.Cu")
		(net "DELTA_L_85_10INCH_BOT_DP")
	)
	(segment
		(start 260.315964 5.700268)
		(end 260.993382 9.53389)
		(width 0.12954)
		(layer "B.Cu")
		(net "DELTA_L_85_10INCH_BOT_DP")
	)
	(segment
		(start 228.576378 9.926574)
		(end 226.934776 10.216642)
		(width 0.12954)
		(layer "B.Cu")
		(net "DELTA_L_85_10INCH_BOT_DP")
	)
	(segment
		(start 237.668562 5.27177)
		(end 236.292644 5.515356)
		(width 0.12954)
		(layer "B.Cu")
		(net "DELTA_L_85_10INCH_BOT_DP")
	)
	(segment
		(start 244.65788 9.927336)
		(end 243.016532 10.217404)
		(width 0.12954)
		(layer "B.Cu")
		(net "DELTA_L_85_10INCH_BOT_DP")
	)
	(segment
		(start 230.587042 9.957816)
		(end 229.781608 5.400548)
		(width 0.12954)
		(layer "B.Cu")
		(net "DELTA_L_85_10INCH_BOT_DP")
	)
	(segment
		(start 254.705104 9.934448)
		(end 253.906782 5.417312)
		(width 0.12954)
		(layer "B.Cu")
		(net "DELTA_L_85_10INCH_BOT_DP")
	)
	(segment
		(start 265.819382 5.31622)
		(end 264.44321 5.559806)
		(width 0.12954)
		(layer "B.Cu")
		(net "DELTA_L_85_10INCH_BOT_DP")
	)
	(segment
		(start 250.689364 9.96188)
		(end 249.884946 5.406644)
		(width 0.12954)
		(layer "B.Cu")
		(net "DELTA_L_85_10INCH_BOT_DP")
	)
	(segment
		(start 260.42112 5.550408)
		(end 260.315964 5.700268)
		(width 0.12954)
		(layer "B.Cu")
		(net "DELTA_L_85_10INCH_BOT_DP")
	)
	(segment
		(start 252.276102 5.705856)
		(end 252.957076 9.561068)
		(width 0.12954)
		(layer "B.Cu")
		(net "DELTA_L_85_10INCH_BOT_DP")
	)
	(segment
		(start 293.163498 9.5758)
		(end 292.905688 9.944608)
		(width 0.12954)
		(layer "B.Cu")
		(net "DELTA_L_85_10INCH_BOT_DP")
	)
	(segment
		(start 251.93498 5.630164)
		(end 252.615954 9.485376)
		(width 0.12954)
		(layer "B.Cu")
		(net "DELTA_L_85_10INCH_BOT_DN")
	)
	(segment
		(start 252.615954 9.485376)
		(end 252.511306 9.634982)
		(width 0.12954)
		(layer "B.Cu")
		(net "DELTA_L_85_10INCH_BOT_DN")
	)
	(segment
		(start 265.895328 4.975098)
		(end 264.255504 5.265166)
		(width 0.12954)
		(layer "B.Cu")
		(net "DELTA_L_85_10INCH_BOT_DN")
	)
	(segment
		(start 279.276302 9.880346)
		(end 279.127204 9.775952)
		(width 0.12954)
		(layer "B.Cu")
		(net "DELTA_L_85_10INCH_BOT_DN")
	)
	(segment
		(start 284.781752 9.499854)
		(end 284.677104 9.64946)
		(width 0.12954)
		(layer "B.Cu")
		(net "DELTA_L_85_10INCH_BOT_DN")
	)
	(segment
		(start 294.722296 7.023608)
		(end 294.40124 5.205476)
		(width 0.12954)
		(layer "B.Cu")
		(net "DELTA_L_85_10INCH_BOT_DN")
	)
	(segment
		(start 239.07115 9.872472)
		(end 238.921798 9.767824)
		(width 0.12954)
		(layer "B.Cu")
		(net "DELTA_L_85_10INCH_BOT_DN")
	)
	(segment
		(start 261.873238 4.965446)
		(end 260.233414 5.255768)
		(width 0.12954)
		(layer "B.Cu")
		(net "DELTA_L_85_10INCH_BOT_DN")
	)
	(segment
		(start 284.35681 5.262372)
		(end 284.098238 5.63118)
		(width 0.12954)
		(layer "B.Cu")
		(net "DELTA_L_85_10INCH_BOT_DN")
	)
	(segment
		(start 232.090722 5.256276)
		(end 231.83215 5.625084)
		(width 0.12954)
		(layer "B.Cu")
		(net "DELTA_L_85_10INCH_BOT_DN")
	)
	(segment
		(start 263.996932 5.633974)
		(end 264.67435 9.468612)
		(width 0.12954)
		(layer "B.Cu")
		(net "DELTA_L_85_10INCH_BOT_DN")
	)
	(segment
		(start 263.0424 9.75741)
		(end 262.241284 5.224526)
		(width 0.12954)
		(layer "B.Cu")
		(net "DELTA_L_85_10INCH_BOT_DN")
	)
	(segment
		(start 220.024452 5.227828)
		(end 219.76588 5.596636)
		(width 0.12954)
		(layer "B.Cu")
		(net "DELTA_L_85_10INCH_BOT_DN")
	)
	(segment
		(start 235.846366 5.589524)
		(end 236.531404 9.467596)
		(width 0.12954)
		(layer "B.Cu")
		(net "DELTA_L_85_10INCH_BOT_DN")
	)
	(segment
		(start 256.631694 9.457944)
		(end 256.527046 9.60755)
		(width 0.12954)
		(layer "B.Cu")
		(net "DELTA_L_85_10INCH_BOT_DN")
	)
	(segment
		(start 290.016946 4.974844)
		(end 288.37763 5.264912)
		(width 0.12954)
		(layer "B.Cu")
		(net "DELTA_L_85_10INCH_BOT_DN")
	)
	(segment
		(start 259.02031 9.74725)
		(end 258.219194 5.212334)
		(width 0.12954)
		(layer "B.Cu")
		(net "DELTA_L_85_10INCH_BOT_DN")
	)
	(segment
		(start 271.084548 9.766554)
		(end 270.282924 5.229098)
		(width 0.12954)
		(layer "B.Cu")
		(net "DELTA_L_85_10INCH_BOT_DN")
	)
	(segment
		(start 264.67435 9.468612)
		(end 264.569702 9.618218)
		(width 0.12954)
		(layer "B.Cu")
		(net "DELTA_L_85_10INCH_BOT_DN")
	)
	(segment
		(start 240.132362 5.261864)
		(end 239.873536 5.630164)
		(width 0.12954)
		(layer "B.Cu")
		(net "DELTA_L_85_10INCH_BOT_DN")
	)
	(segment
		(start 286.364934 5.230876)
		(end 285.996126 4.972304)
		(width 0.12954)
		(layer "B.Cu")
		(net "DELTA_L_85_10INCH_BOT_DN")
	)
	(segment
		(start 213.432136 7.372858)
		(end 213.297008 7.372858)
		(width 0.12954)
		(layer "B.Cu")
		(net "DELTA_L_85_10INCH_BOT_DN")
	)
	(segment
		(start 217.620342 7.461504)
		(end 213.520782 7.461504)
		(width 0.12954)
		(layer "B.Cu")
		(net "DELTA_L_85_10INCH_BOT_DN")
	)
	(segment
		(start 277.955502 4.973828)
		(end 276.31644 5.263896)
		(width 0.12954)
		(layer "B.Cu")
		(net "DELTA_L_85_10INCH_BOT_DN")
	)
	(segment
		(start 219.76588 5.596636)
		(end 220.453712 9.48944)
		(width 0.12954)
		(layer "B.Cu")
		(net "DELTA_L_85_10INCH_BOT_DN")
	)
	(segment
		(start 282.343606 5.227066)
		(end 281.974798 4.968494)
		(width 0.12954)
		(layer "B.Cu")
		(net "DELTA_L_85_10INCH_BOT_DN")
	)
	(segment
		(start 240.554002 9.479534)
		(end 240.449354 9.628886)
		(width 0.12954)
		(layer "B.Cu")
		(net "DELTA_L_85_10INCH_BOT_DN")
	)
	(segment
		(start 272.716752 9.478264)
		(end 272.612104 9.627616)
		(width 0.12954)
		(layer "B.Cu")
		(net "DELTA_L_85_10INCH_BOT_DN")
	)
	(segment
		(start 294.032432 4.946904)
		(end 292.393116 5.237226)
		(width 0.12954)
		(layer "B.Cu")
		(net "DELTA_L_85_10INCH_BOT_DN")
	)
	(segment
		(start 291.19068 9.78916)
		(end 290.385754 5.233416)
		(width 0.12954)
		(layer "B.Cu")
		(net "DELTA_L_85_10INCH_BOT_DN")
	)
	(segment
		(start 268.5923 9.631426)
		(end 267.214096 9.875012)
		(width 0.12954)
		(layer "B.Cu")
		(net "DELTA_L_85_10INCH_BOT_DN")
	)
	(segment
		(start 228.493066 9.482328)
		(end 228.388418 9.631934)
		(width 0.12954)
		(layer "B.Cu")
		(net "DELTA_L_85_10INCH_BOT_DN")
	)
	(segment
		(start 224.047558 5.243322)
		(end 223.788986 5.61213)
		(width 0.12954)
		(layer "B.Cu")
		(net "DELTA_L_85_10INCH_BOT_DN")
	)
	(segment
		(start 240.449354 9.628886)
		(end 239.07115 9.872472)
		(width 0.12954)
		(layer "B.Cu")
		(net "DELTA_L_85_10INCH_BOT_DN")
	)
	(segment
		(start 292.717728 9.649968)
		(end 291.339778 9.893554)
		(width 0.12954)
		(layer "B.Cu")
		(net "DELTA_L_85_10INCH_BOT_DN")
	)
	(segment
		(start 213.520782 7.461504)
		(end 213.432136 7.372858)
		(width 0.12954)
		(layer "B.Cu")
		(net "DELTA_L_85_10INCH_BOT_DN")
	)
	(segment
		(start 299.466762 7.461504)
		(end 295.34866 7.461504)
		(width 0.12954)
		(layer "B.Cu")
		(net "DELTA_L_85_10INCH_BOT_DN")
	)
	(segment
		(start 239.873536 5.630164)
		(end 240.554002 9.479534)
		(width 0.12954)
		(layer "B.Cu")
		(net "DELTA_L_85_10INCH_BOT_DN")
	)
	(segment
		(start 226.055682 5.211826)
		(end 225.686874 4.953254)
		(width 0.12954)
		(layer "B.Cu")
		(net "DELTA_L_85_10INCH_BOT_DN")
	)
	(segment
		(start 280.654506 9.63676)
		(end 279.276302 9.880346)
		(width 0.12954)
		(layer "B.Cu")
		(net "DELTA_L_85_10INCH_BOT_DN")
	)
	(segment
		(start 276.636226 9.647936)
		(end 275.258022 9.891522)
		(width 0.12954)
		(layer "B.Cu")
		(net "DELTA_L_85_10INCH_BOT_DN")
	)
	(segment
		(start 222.838772 9.757664)
		(end 222.032576 5.196332)
		(width 0.12954)
		(layer "B.Cu")
		(net "DELTA_L_85_10INCH_BOT_DN")
	)
	(segment
		(start 218.971114 9.882124)
		(end 218.821762 9.77773)
		(width 0.12954)
		(layer "B.Cu")
		(net "DELTA_L_85_10INCH_BOT_DN")
	)
	(segment
		(start 236.104938 5.220716)
		(end 235.846366 5.589524)
		(width 0.12954)
		(layer "B.Cu")
		(net "DELTA_L_85_10INCH_BOT_DN")
	)
	(segment
		(start 243.781326 9.754362)
		(end 243.09197 9.876282)
		(width 0.12954)
		(layer "B.Cu")
		(net "DELTA_L_85_10INCH_BOT_DN")
	)
	(segment
		(start 230.881682 9.770364)
		(end 230.076248 5.212842)
		(width 0.12954)
		(layer "B.Cu")
		(net "DELTA_L_85_10INCH_BOT_DN")
	)
	(segment
		(start 229.707694 4.95427)
		(end 228.068378 5.244592)
		(width 0.12954)
		(layer "B.Cu")
		(net "DELTA_L_85_10INCH_BOT_DN")
	)
	(segment
		(start 232.408984 9.631426)
		(end 231.03078 9.875012)
		(width 0.12954)
		(layer "B.Cu")
		(net "DELTA_L_85_10INCH_BOT_DN")
	)
	(segment
		(start 269.914116 4.970526)
		(end 268.2748 5.260594)
		(width 0.12954)
		(layer "B.Cu")
		(net "DELTA_L_85_10INCH_BOT_DN")
	)
	(segment
		(start 227.809806 5.613654)
		(end 228.493066 9.482328)
		(width 0.12954)
		(layer "B.Cu")
		(net "DELTA_L_85_10INCH_BOT_DN")
	)
	(segment
		(start 273.93646 4.980432)
		(end 272.297144 5.2705)
		(width 0.12954)
		(layer "B.Cu")
		(net "DELTA_L_85_10INCH_BOT_DN")
	)
	(segment
		(start 244.155468 5.278628)
		(end 243.896896 5.647436)
		(width 0.12954)
		(layer "B.Cu")
		(net "DELTA_L_85_10INCH_BOT_DN")
	)
	(segment
		(start 256.527046 9.60755)
		(end 255.838198 9.728962)
		(width 0.12954)
		(layer "B.Cu")
		(net "DELTA_L_85_10INCH_BOT_DN")
	)
	(segment
		(start 228.388418 9.631934)
		(end 227.010214 9.87552)
		(width 0.12954)
		(layer "B.Cu")
		(net "DELTA_L_85_10INCH_BOT_DN")
	)
	(segment
		(start 278.32431 5.2324)
		(end 277.955502 4.973828)
		(width 0.12954)
		(layer "B.Cu")
		(net "DELTA_L_85_10INCH_BOT_DN")
	)
	(segment
		(start 247.803162 9.760966)
		(end 247.113806 9.882886)
		(width 0.12954)
		(layer "B.Cu")
		(net "DELTA_L_85_10INCH_BOT_DN")
	)
	(segment
		(start 255.148842 9.851136)
		(end 254.999744 9.746742)
		(width 0.12954)
		(layer "B.Cu")
		(net "DELTA_L_85_10INCH_BOT_DN")
	)
	(segment
		(start 253.832868 4.971034)
		(end 252.193552 5.261356)
		(width 0.12954)
		(layer "B.Cu")
		(net "DELTA_L_85_10INCH_BOT_DN")
	)
	(segment
		(start 224.36582 9.618472)
		(end 222.98787 9.862058)
		(width 0.12954)
		(layer "B.Cu")
		(net "DELTA_L_85_10INCH_BOT_DN")
	)
	(segment
		(start 299.712888 7.372858)
		(end 299.555408 7.372858)
		(width 0.12954)
		(layer "B.Cu")
		(net "DELTA_L_85_10INCH_BOT_DN")
	)
	(segment
		(start 255.952244 5.612638)
		(end 256.631694 9.457944)
		(width 0.12954)
		(layer "B.Cu")
		(net "DELTA_L_85_10INCH_BOT_DN")
	)
	(segment
		(start 248.171462 5.250434)
		(end 247.912636 5.618734)
		(width 0.12954)
		(layer "B.Cu")
		(net "DELTA_L_85_10INCH_BOT_DN")
	)
	(segment
		(start 222.98787 9.862058)
		(end 222.838772 9.757664)
		(width 0.12954)
		(layer "B.Cu")
		(net "DELTA_L_85_10INCH_BOT_DN")
	)
	(segment
		(start 291.339778 9.893554)
		(end 291.19068 9.78916)
		(width 0.12954)
		(layer "B.Cu")
		(net "DELTA_L_85_10INCH_BOT_DN")
	)
	(segment
		(start 218.821762 9.77773)
		(end 218.524328 8.094218)
		(width 0.12954)
		(layer "B.Cu")
		(net "DELTA_L_85_10INCH_BOT_DN")
	)
	(segment
		(start 284.098238 5.63118)
		(end 284.781752 9.499854)
		(width 0.12954)
		(layer "B.Cu")
		(net "DELTA_L_85_10INCH_BOT_DN")
	)
	(segment
		(start 292.393116 5.237226)
		(end 292.134544 5.606034)
		(width 0.12954)
		(layer "B.Cu")
		(net "DELTA_L_85_10INCH_BOT_DN")
	)
	(segment
		(start 222.032576 5.196332)
		(end 221.663768 4.93776)
		(width 0.12954)
		(layer "B.Cu")
		(net "DELTA_L_85_10INCH_BOT_DN")
	)
	(segment
		(start 246.163846 5.247132)
		(end 245.79453 4.98856)
		(width 0.12954)
		(layer "B.Cu")
		(net "DELTA_L_85_10INCH_BOT_DN")
	)
	(segment
		(start 237.744508 4.930648)
		(end 236.104938 5.220716)
		(width 0.12954)
		(layer "B.Cu")
		(net "DELTA_L_85_10INCH_BOT_DN")
	)
	(segment
		(start 268.2748 5.260594)
		(end 268.016228 5.629402)
		(width 0.12954)
		(layer "B.Cu")
		(net "DELTA_L_85_10INCH_BOT_DN")
	)
	(segment
		(start 275.108924 9.787128)
		(end 274.305268 5.239004)
		(width 0.12954)
		(layer "B.Cu")
		(net "DELTA_L_85_10INCH_BOT_DN")
	)
	(segment
		(start 263.191498 9.861804)
		(end 263.0424 9.75741)
		(width 0.12954)
		(layer "B.Cu")
		(net "DELTA_L_85_10INCH_BOT_DN")
	)
	(segment
		(start 243.09197 9.876282)
		(end 242.942872 9.771888)
		(width 0.12954)
		(layer "B.Cu")
		(net "DELTA_L_85_10INCH_BOT_DN")
	)
	(segment
		(start 272.612104 9.627616)
		(end 271.2339 9.871202)
		(width 0.12954)
		(layer "B.Cu")
		(net "DELTA_L_85_10INCH_BOT_DN")
	)
	(segment
		(start 266.263374 5.234178)
		(end 265.895328 4.975098)
		(width 0.12954)
		(layer "B.Cu")
		(net "DELTA_L_85_10INCH_BOT_DN")
	)
	(segment
		(start 244.470174 9.632696)
		(end 243.781326 9.754108)
		(width 0.12954)
		(layer "B.Cu")
		(net "DELTA_L_85_10INCH_BOT_DN")
	)
	(segment
		(start 274.305268 5.239004)
		(end 273.93646 4.980432)
		(width 0.12954)
		(layer "B.Cu")
		(net "DELTA_L_85_10INCH_BOT_DN")
	)
	(segment
		(start 283.2989 9.893046)
		(end 283.149802 9.788652)
		(width 0.12954)
		(layer "B.Cu")
		(net "DELTA_L_85_10INCH_BOT_DN")
	)
	(segment
		(start 238.112808 5.189474)
		(end 237.744508 4.930648)
		(width 0.12954)
		(layer "B.Cu")
		(net "DELTA_L_85_10INCH_BOT_DN")
	)
	(segment
		(start 242.942872 9.771888)
		(end 242.140232 5.230368)
		(width 0.12954)
		(layer "B.Cu")
		(net "DELTA_L_85_10INCH_BOT_DN")
	)
	(segment
		(start 251.822458 9.756648)
		(end 251.133102 9.878568)
		(width 0.12954)
		(layer "B.Cu")
		(net "DELTA_L_85_10INCH_BOT_DN")
	)
	(segment
		(start 283.149802 9.788652)
		(end 282.343606 5.227066)
		(width 0.12954)
		(layer "B.Cu")
		(net "DELTA_L_85_10INCH_BOT_DN")
	)
	(segment
		(start 236.426756 9.617202)
		(end 235.737908 9.738614)
		(width 0.12954)
		(layer "B.Cu")
		(net "DELTA_L_85_10INCH_BOT_DN")
	)
	(segment
		(start 247.803162 9.760712)
		(end 247.803162 9.760966)
		(width 0.12954)
		(layer "B.Cu")
		(net "DELTA_L_85_10INCH_BOT_DN")
	)
	(segment
		(start 255.838198 9.729216)
		(end 255.148842 9.851136)
		(width 0.12954)
		(layer "B.Cu")
		(net "DELTA_L_85_10INCH_BOT_DN")
	)
	(segment
		(start 258.219194 5.212334)
		(end 257.849878 4.953762)
		(width 0.12954)
		(layer "B.Cu")
		(net "DELTA_L_85_10INCH_BOT_DN")
	)
	(segment
		(start 279.127204 9.775952)
		(end 278.32431 5.2324)
		(width 0.12954)
		(layer "B.Cu")
		(net "DELTA_L_85_10INCH_BOT_DN")
	)
	(segment
		(start 260.65226 9.458452)
		(end 260.547612 9.608058)
		(width 0.12954)
		(layer "B.Cu")
		(net "DELTA_L_85_10INCH_BOT_DN")
	)
	(segment
		(start 290.385754 5.233416)
		(end 290.016946 4.974844)
		(width 0.12954)
		(layer "B.Cu")
		(net "DELTA_L_85_10INCH_BOT_DN")
	)
	(segment
		(start 252.193552 5.261356)
		(end 251.93498 5.630164)
		(width 0.12954)
		(layer "B.Cu")
		(net "DELTA_L_85_10INCH_BOT_DN")
	)
	(segment
		(start 280.335482 5.258562)
		(end 280.07691 5.62737)
		(width 0.12954)
		(layer "B.Cu")
		(net "DELTA_L_85_10INCH_BOT_DN")
	)
	(segment
		(start 244.574822 9.483344)
		(end 244.470174 9.632696)
		(width 0.12954)
		(layer "B.Cu")
		(net "DELTA_L_85_10INCH_BOT_DN")
	)
	(segment
		(start 285.996126 4.972304)
		(end 284.35681 5.262372)
		(width 0.12954)
		(layer "B.Cu")
		(net "DELTA_L_85_10INCH_BOT_DN")
	)
	(segment
		(start 254.999744 9.746742)
		(end 254.201422 5.22986)
		(width 0.12954)
		(layer "B.Cu")
		(net "DELTA_L_85_10INCH_BOT_DN")
	)
	(segment
		(start 251.133102 9.878568)
		(end 250.984004 9.774174)
		(width 0.12954)
		(layer "B.Cu")
		(net "DELTA_L_85_10INCH_BOT_DN")
	)
	(segment
		(start 224.470468 9.468866)
		(end 224.36582 9.618472)
		(width 0.12954)
		(layer "B.Cu")
		(net "DELTA_L_85_10INCH_BOT_DN")
	)
	(segment
		(start 295.34866 7.461504)
		(end 294.722296 7.023608)
		(width 0.12954)
		(layer "B.Cu")
		(net "DELTA_L_85_10INCH_BOT_DN")
	)
	(segment
		(start 294.40124 5.205476)
		(end 294.032432 4.946904)
		(width 0.12954)
		(layer "B.Cu")
		(net "DELTA_L_85_10INCH_BOT_DN")
	)
	(segment
		(start 220.453712 9.48944)
		(end 220.349318 9.638538)
		(width 0.12954)
		(layer "B.Cu")
		(net "DELTA_L_85_10INCH_BOT_DN")
	)
	(segment
		(start 292.134544 5.606034)
		(end 292.822376 9.500362)
		(width 0.12954)
		(layer "B.Cu")
		(net "DELTA_L_85_10INCH_BOT_DN")
	)
	(segment
		(start 248.49201 9.6393)
		(end 247.803162 9.760712)
		(width 0.12954)
		(layer "B.Cu")
		(net "DELTA_L_85_10INCH_BOT_DN")
	)
	(segment
		(start 287.31845 9.889236)
		(end 287.169606 9.784842)
		(width 0.12954)
		(layer "B.Cu")
		(net "DELTA_L_85_10INCH_BOT_DN")
	)
	(segment
		(start 259.169408 9.851644)
		(end 259.02031 9.74725)
		(width 0.12954)
		(layer "B.Cu")
		(net "DELTA_L_85_10INCH_BOT_DN")
	)
	(segment
		(start 228.068378 5.244592)
		(end 227.809806 5.613654)
		(width 0.12954)
		(layer "B.Cu")
		(net "DELTA_L_85_10INCH_BOT_DN")
	)
	(segment
		(start 284.677104 9.64946)
		(end 283.2989 9.893046)
		(width 0.12954)
		(layer "B.Cu")
		(net "DELTA_L_85_10INCH_BOT_DN")
	)
	(segment
		(start 276.057614 5.63245)
		(end 276.740874 9.498584)
		(width 0.12954)
		(layer "B.Cu")
		(net "DELTA_L_85_10INCH_BOT_DN")
	)
	(segment
		(start 223.788986 5.61213)
		(end 224.470468 9.468866)
		(width 0.12954)
		(layer "B.Cu")
		(net "DELTA_L_85_10INCH_BOT_DN")
	)
	(segment
		(start 250.984004 9.774174)
		(end 250.179586 5.218938)
		(width 0.12954)
		(layer "B.Cu")
		(net "DELTA_L_85_10INCH_BOT_DN")
	)
	(segment
		(start 267.214096 9.875012)
		(end 267.064998 9.770618)
		(width 0.12954)
		(layer "B.Cu")
		(net "DELTA_L_85_10INCH_BOT_DN")
	)
	(segment
		(start 233.729784 4.966208)
		(end 232.090722 5.256276)
		(width 0.12954)
		(layer "B.Cu")
		(net "DELTA_L_85_10INCH_BOT_DN")
	)
	(segment
		(start 281.974798 4.968494)
		(end 280.335482 5.258562)
		(width 0.12954)
		(layer "B.Cu")
		(net "DELTA_L_85_10INCH_BOT_DN")
	)
	(segment
		(start 267.064998 9.770618)
		(end 266.263374 5.234178)
		(width 0.12954)
		(layer "B.Cu")
		(net "DELTA_L_85_10INCH_BOT_DN")
	)
	(segment
		(start 280.07691 5.62737)
		(end 280.759154 9.487154)
		(width 0.12954)
		(layer "B.Cu")
		(net "DELTA_L_85_10INCH_BOT_DN")
	)
	(segment
		(start 252.511306 9.634982)
		(end 251.822458 9.756394)
		(width 0.12954)
		(layer "B.Cu")
		(net "DELTA_L_85_10INCH_BOT_DN")
	)
	(segment
		(start 275.258022 9.891522)
		(end 275.108924 9.787128)
		(width 0.12954)
		(layer "B.Cu")
		(net "DELTA_L_85_10INCH_BOT_DN")
	)
	(segment
		(start 225.686874 4.953254)
		(end 224.047558 5.243322)
		(width 0.12954)
		(layer "B.Cu")
		(net "DELTA_L_85_10INCH_BOT_DN")
	)
	(segment
		(start 288.696146 9.64565)
		(end 287.31845 9.889236)
		(width 0.12954)
		(layer "B.Cu")
		(net "DELTA_L_85_10INCH_BOT_DN")
	)
	(segment
		(start 264.255504 5.265166)
		(end 263.996932 5.633974)
		(width 0.12954)
		(layer "B.Cu")
		(net "DELTA_L_85_10INCH_BOT_DN")
	)
	(segment
		(start 231.83215 5.625084)
		(end 232.513632 9.48182)
		(width 0.12954)
		(layer "B.Cu")
		(net "DELTA_L_85_10INCH_BOT_DN")
	)
	(segment
		(start 292.822376 9.500362)
		(end 292.717728 9.649968)
		(width 0.12954)
		(layer "B.Cu")
		(net "DELTA_L_85_10INCH_BOT_DN")
	)
	(segment
		(start 260.233414 5.255768)
		(end 259.974842 5.624576)
		(width 0.12954)
		(layer "B.Cu")
		(net "DELTA_L_85_10INCH_BOT_DN")
	)
	(segment
		(start 254.201422 5.22986)
		(end 253.832868 4.971034)
		(width 0.12954)
		(layer "B.Cu")
		(net "DELTA_L_85_10INCH_BOT_DN")
	)
	(segment
		(start 227.010214 9.87552)
		(end 226.861116 9.771126)
		(width 0.12954)
		(layer "B.Cu")
		(net "DELTA_L_85_10INCH_BOT_DN")
	)
	(segment
		(start 299.555408 7.372858)
		(end 299.466762 7.461504)
		(width 0.12954)
		(layer "B.Cu")
		(net "DELTA_L_85_10INCH_BOT_DN")
	)
	(segment
		(start 243.781326 9.754108)
		(end 243.781326 9.754362)
		(width 0.12954)
		(layer "B.Cu")
		(net "DELTA_L_85_10INCH_BOT_DN")
	)
	(segment
		(start 256.210816 5.24383)
		(end 255.952244 5.612638)
		(width 0.12954)
		(layer "B.Cu")
		(net "DELTA_L_85_10INCH_BOT_DN")
	)
	(segment
		(start 262.241284 5.224526)
		(end 261.873238 4.965446)
		(width 0.12954)
		(layer "B.Cu")
		(net "DELTA_L_85_10INCH_BOT_DN")
	)
	(segment
		(start 235.737908 9.738868)
		(end 235.048552 9.860788)
		(width 0.12954)
		(layer "B.Cu")
		(net "DELTA_L_85_10INCH_BOT_DN")
	)
	(segment
		(start 220.349318 9.638538)
		(end 218.971114 9.882124)
		(width 0.12954)
		(layer "B.Cu")
		(net "DELTA_L_85_10INCH_BOT_DN")
	)
	(segment
		(start 276.31644 5.263896)
		(end 276.057614 5.63245)
		(width 0.12954)
		(layer "B.Cu")
		(net "DELTA_L_85_10INCH_BOT_DN")
	)
	(segment
		(start 272.297144 5.2705)
		(end 272.038572 5.639308)
		(width 0.12954)
		(layer "B.Cu")
		(net "DELTA_L_85_10INCH_BOT_DN")
	)
	(segment
		(start 276.740874 9.498584)
		(end 276.636226 9.647936)
		(width 0.12954)
		(layer "B.Cu")
		(net "DELTA_L_85_10INCH_BOT_DN")
	)
	(segment
		(start 235.737908 9.738614)
		(end 235.737908 9.738868)
		(width 0.12954)
		(layer "B.Cu")
		(net "DELTA_L_85_10INCH_BOT_DN")
	)
	(segment
		(start 268.016228 5.629402)
		(end 268.696948 9.48182)
		(width 0.12954)
		(layer "B.Cu")
		(net "DELTA_L_85_10INCH_BOT_DN")
	)
	(segment
		(start 247.113806 9.882886)
		(end 246.964708 9.778492)
		(width 0.12954)
		(layer "B.Cu")
		(net "DELTA_L_85_10INCH_BOT_DN")
	)
	(segment
		(start 260.547612 9.608058)
		(end 259.169408 9.851644)
		(width 0.12954)
		(layer "B.Cu")
		(net "DELTA_L_85_10INCH_BOT_DN")
	)
	(segment
		(start 221.663768 4.93776)
		(end 220.024452 5.227828)
		(width 0.12954)
		(layer "B.Cu")
		(net "DELTA_L_85_10INCH_BOT_DN")
	)
	(segment
		(start 250.179586 5.218938)
		(end 249.81027 4.960366)
		(width 0.12954)
		(layer "B.Cu")
		(net "DELTA_L_85_10INCH_BOT_DN")
	)
	(segment
		(start 230.076248 5.212842)
		(end 229.707694 4.95427)
		(width 0.12954)
		(layer "B.Cu")
		(net "DELTA_L_85_10INCH_BOT_DN")
	)
	(segment
		(start 248.596658 9.489694)
		(end 248.49201 9.6393)
		(width 0.12954)
		(layer "B.Cu")
		(net "DELTA_L_85_10INCH_BOT_DN")
	)
	(segment
		(start 272.038572 5.639308)
		(end 272.716752 9.478264)
		(width 0.12954)
		(layer "B.Cu")
		(net "DELTA_L_85_10INCH_BOT_DN")
	)
	(segment
		(start 241.771424 4.971796)
		(end 240.132362 5.261864)
		(width 0.12954)
		(layer "B.Cu")
		(net "DELTA_L_85_10INCH_BOT_DN")
	)
	(segment
		(start 264.569702 9.618218)
		(end 263.191498 9.861804)
		(width 0.12954)
		(layer "B.Cu")
		(net "DELTA_L_85_10INCH_BOT_DN")
	)
	(segment
		(start 236.531404 9.467596)
		(end 236.426756 9.617202)
		(width 0.12954)
		(layer "B.Cu")
		(net "DELTA_L_85_10INCH_BOT_DN")
	)
	(segment
		(start 255.838198 9.728962)
		(end 255.838198 9.729216)
		(width 0.12954)
		(layer "B.Cu")
		(net "DELTA_L_85_10INCH_BOT_DN")
	)
	(segment
		(start 280.759154 9.487154)
		(end 280.654506 9.63676)
		(width 0.12954)
		(layer "B.Cu")
		(net "DELTA_L_85_10INCH_BOT_DN")
	)
	(segment
		(start 226.861116 9.771126)
		(end 226.055682 5.211826)
		(width 0.12954)
		(layer "B.Cu")
		(net "DELTA_L_85_10INCH_BOT_DN")
	)
	(segment
		(start 234.0991 5.22478)
		(end 233.729784 4.966208)
		(width 0.12954)
		(layer "B.Cu")
		(net "DELTA_L_85_10INCH_BOT_DN")
	)
	(segment
		(start 288.37763 5.264912)
		(end 288.119058 5.63372)
		(width 0.12954)
		(layer "B.Cu")
		(net "DELTA_L_85_10INCH_BOT_DN")
	)
	(segment
		(start 247.912636 5.618734)
		(end 248.596658 9.489694)
		(width 0.12954)
		(layer "B.Cu")
		(net "DELTA_L_85_10INCH_BOT_DN")
	)
	(segment
		(start 242.140232 5.230368)
		(end 241.771424 4.971796)
		(width 0.12954)
		(layer "B.Cu")
		(net "DELTA_L_85_10INCH_BOT_DN")
	)
	(segment
		(start 288.801048 9.49579)
		(end 288.696146 9.64565)
		(width 0.12954)
		(layer "B.Cu")
		(net "DELTA_L_85_10INCH_BOT_DN")
	)
	(segment
		(start 288.119058 5.63372)
		(end 288.801048 9.49579)
		(width 0.12954)
		(layer "B.Cu")
		(net "DELTA_L_85_10INCH_BOT_DN")
	)
	(segment
		(start 246.964708 9.778492)
		(end 246.163846 5.247132)
		(width 0.12954)
		(layer "B.Cu")
		(net "DELTA_L_85_10INCH_BOT_DN")
	)
	(segment
		(start 271.2339 9.871202)
		(end 271.084548 9.766554)
		(width 0.12954)
		(layer "B.Cu")
		(net "DELTA_L_85_10INCH_BOT_DN")
	)
	(segment
		(start 235.048552 9.860788)
		(end 234.899454 9.75614)
		(width 0.12954)
		(layer "B.Cu")
		(net "DELTA_L_85_10INCH_BOT_DN")
	)
	(segment
		(start 232.513632 9.48182)
		(end 232.408984 9.631426)
		(width 0.12954)
		(layer "B.Cu")
		(net "DELTA_L_85_10INCH_BOT_DN")
	)
	(segment
		(start 249.81027 4.960366)
		(end 248.171462 5.250434)
		(width 0.12954)
		(layer "B.Cu")
		(net "DELTA_L_85_10INCH_BOT_DN")
	)
	(segment
		(start 218.524328 8.094218)
		(end 217.620342 7.461504)
		(width 0.12954)
		(layer "B.Cu")
		(net "DELTA_L_85_10INCH_BOT_DN")
	)
	(segment
		(start 257.849878 4.953762)
		(end 256.210816 5.24383)
		(width 0.12954)
		(layer "B.Cu")
		(net "DELTA_L_85_10INCH_BOT_DN")
	)
	(segment
		(start 243.896896 5.647436)
		(end 244.574822 9.483344)
		(width 0.12954)
		(layer "B.Cu")
		(net "DELTA_L_85_10INCH_BOT_DN")
	)
	(segment
		(start 245.79453 4.98856)
		(end 244.155468 5.278628)
		(width 0.12954)
		(layer "B.Cu")
		(net "DELTA_L_85_10INCH_BOT_DN")
	)
	(segment
		(start 231.03078 9.875012)
		(end 230.881682 9.770364)
		(width 0.12954)
		(layer "B.Cu")
		(net "DELTA_L_85_10INCH_BOT_DN")
	)
	(segment
		(start 238.921798 9.767824)
		(end 238.112808 5.189474)
		(width 0.12954)
		(layer "B.Cu")
		(net "DELTA_L_85_10INCH_BOT_DN")
	)
	(segment
		(start 270.282924 5.229098)
		(end 269.914116 4.970526)
		(width 0.12954)
		(layer "B.Cu")
		(net "DELTA_L_85_10INCH_BOT_DN")
	)
	(segment
		(start 259.974842 5.624576)
		(end 260.65226 9.458452)
		(width 0.12954)
		(layer "B.Cu")
		(net "DELTA_L_85_10INCH_BOT_DN")
	)
	(segment
		(start 287.169606 9.784842)
		(end 286.364934 5.230876)
		(width 0.12954)
		(layer "B.Cu")
		(net "DELTA_L_85_10INCH_BOT_DN")
	)
	(segment
		(start 251.822458 9.756394)
		(end 251.822458 9.756648)
		(width 0.12954)
		(layer "B.Cu")
		(net "DELTA_L_85_10INCH_BOT_DN")
	)
	(segment
		(start 268.696948 9.48182)
		(end 268.5923 9.631426)
		(width 0.12954)
		(layer "B.Cu")
		(net "DELTA_L_85_10INCH_BOT_DN")
	)
	(segment
		(start 234.899454 9.75614)
		(end 234.0991 5.22478)
		(width 0.12954)
		(layer "B.Cu")
		(net "DELTA_L_85_10INCH_BOT_DN")
	)
	(segment
		(start 149.500336 -314.47105)
		(end 149.603714 -314.574428)
		(width 0.10668)
		(layer "B.Cu")
		(net "XTAL_CPU1_X48M_X2_R")
	)
	(segment
		(start 149.603714 -314.574428)
		(end 149.603714 -315.540136)
		(width 0.10668)
		(layer "B.Cu")
		(net "XTAL_CPU1_X48M_X2_R")
	)
	(segment
		(start 149.500336 -313.45505)
		(end 149.500336 -314.47105)
		(width 0.10668)
		(layer "B.Cu")
		(net "XTAL_CPU1_X48M_X2_R")
	)
	(segment
		(start 149.603714 -315.540136)
		(end 150.147528 -316.08395)
		(width 0.10668)
		(layer "B.Cu")
		(net "XTAL_CPU1_X48M_X2_R")
	)
	(segment
		(start 148.522436 -313.45505)
		(end 149.500336 -313.45505)
		(width 0.10668)
		(layer "B.Cu")
		(net "XTAL_CPU1_X48M_X2_R")
	)
	(segment
		(start 397.430752 -314.572396)
		(end 398.392904 -315.534548)
		(width 0.10668)
		(layer "B.Cu")
		(net "XTAL_CPU0_X48M_X2_R")
	)
	(segment
		(start 396.558008 -313.477148)
		(end 397.535908 -313.477148)
		(width 0.10668)
		(layer "B.Cu")
		(net "XTAL_CPU0_X48M_X2_R")
	)
	(segment
		(start 397.535908 -313.477148)
		(end 397.430752 -313.582304)
		(width 0.10668)
		(layer "B.Cu")
		(net "XTAL_CPU0_X48M_X2_R")
	)
	(segment
		(start 398.392904 -315.534548)
		(end 398.392904 -315.852048)
		(width 0.10668)
		(layer "B.Cu")
		(net "XTAL_CPU0_X48M_X2_R")
	)
	(segment
		(start 397.430752 -313.582304)
		(end 397.430752 -314.366148)
		(width 0.10668)
		(layer "B.Cu")
		(net "XTAL_CPU0_X48M_X2_R")
	)
	(segment
		(start 397.430752 -314.366148)
		(end 397.430752 -314.572396)
		(width 0.10668)
		(layer "B.Cu")
		(net "XTAL_CPU0_X48M_X2_R")
	)
	(segment
		(start 418.257482 -122.130312)
		(end 414.619186 -113.346484)
		(width 0.12954)
		(layer "F.Cu")
		(net "USB2_CPU0_P11_DP")
	)
	(segment
		(start 414.619186 -113.346484)
		(end 407.834592 -79.238094)
		(width 0.12954)
		(layer "F.Cu")
		(net "USB2_CPU0_P11_DP")
	)
	(segment
		(start 339.337904 -294.88003)
		(end 338.871052 -295.145968)
		(width 0.12954)
		(layer "F.Cu")
		(net "USB2_CPU0_P11_DP")
	)
	(segment
		(start 428.512986 -132.385816)
		(end 418.257482 -122.130312)
		(width 0.12954)
		(layer "F.Cu")
		(net "USB2_CPU0_P11_DP")
	)
	(segment
		(start 407.834592 -79.238094)
		(end 407.834592 -74.431652)
		(width 0.12954)
		(layer "F.Cu")
		(net "USB2_CPU0_P11_DP")
	)
	(segment
		(start 409.915868 -56.766206)
		(end 400.810476 -34.783776)
		(width 0.12954)
		(layer "F.Cu")
		(net "USB2_CPU0_P11_DP")
	)
	(segment
		(start 400.810476 -34.783776)
		(end 390.166606 -24.139906)
		(width 0.12954)
		(layer "F.Cu")
		(net "USB2_CPU0_P11_DP")
	)
	(segment
		(start 428.512986 -146.88947)
		(end 428.512986 -132.385816)
		(width 0.12954)
		(layer "F.Cu")
		(net "USB2_CPU0_P11_DP")
	)
	(segment
		(start 390.166606 -23.535894)
		(end 390.513316 -23.189184)
		(width 0.12954)
		(layer "F.Cu")
		(net "USB2_CPU0_P11_DP")
	)
	(segment
		(start 407.834592 -74.431652)
		(end 409.915868 -72.350376)
		(width 0.12954)
		(layer "F.Cu")
		(net "USB2_CPU0_P11_DP")
	)
	(segment
		(start 432.878484 -157.428946)
		(end 428.512986 -146.88947)
		(width 0.12954)
		(layer "F.Cu")
		(net "USB2_CPU0_P11_DP")
	)
	(segment
		(start 409.915868 -72.350376)
		(end 409.915868 -56.766206)
		(width 0.12954)
		(layer "F.Cu")
		(net "USB2_CPU0_P11_DP")
	)
	(segment
		(start 390.166606 -24.139906)
		(end 390.166606 -23.535894)
		(width 0.12954)
		(layer "F.Cu")
		(net "USB2_CPU0_P11_DP")
	)
	(segment
		(start 432.878484 -163.382706)
		(end 432.878484 -157.428946)
		(width 0.12954)
		(layer "F.Cu")
		(net "USB2_CPU0_P11_DP")
	)
	(segment
		(start 433.212494 -163.716716)
		(end 432.878484 -163.382706)
		(width 0.12954)
		(layer "F.Cu")
		(net "USB2_CPU0_P11_DP")
	)
	(via
		(at 338.871052 -295.145968)
		(size 0.4064)
		(drill 0.2032)
		(layers "F.Cu" "B.Cu")
		(net "USB2_CPU0_P11_DP")
	)
	(via
		(at 433.212494 -163.716716)
		(size 0.508)
		(drill 0.254)
		(layers "F.Cu" "B.Cu")
		(net "USB2_CPU0_P11_DP")
	)
	(segment
		(start 338.710016 -296.469054)
		(end 338.710016 -296.450004)
		(width 0.0762)
		(layer "B.Cu")
		(net "USB2_CPU0_P11_DP")
	)
	(segment
		(start 409.21305 -336.70494)
		(end 387.48462 -336.70494)
		(width 0.12954)
		(layer "B.Cu")
		(net "USB2_CPU0_P11_DP")
	)
	(segment
		(start 348.319852 -297.546522)
		(end 344.253312 -297.546522)
		(width 0.12954)
		(layer "B.Cu")
		(net "USB2_CPU0_P11_DP")
	)
	(segment
		(start 387.48462 -336.70494)
		(end 364.437422 -313.657742)
		(width 0.12954)
		(layer "B.Cu")
		(net "USB2_CPU0_P11_DP")
	)
	(segment
		(start 421.68953 -189.71895)
		(end 411.054042 -189.71895)
		(width 0.12954)
		(layer "B.Cu")
		(net "USB2_CPU0_P11_DP")
	)
	(segment
		(start 364.431072 -313.657742)
		(end 348.319852 -297.546522)
		(width 0.12954)
		(layer "B.Cu")
		(net "USB2_CPU0_P11_DP")
	)
	(segment
		(start 410.346398 -190.012066)
		(end 408.315922 -192.042796)
		(width 0.12954)
		(layer "B.Cu")
		(net "USB2_CPU0_P11_DP")
	)
	(segment
		(start 341.012526 -297.071542)
		(end 338.977478 -297.071542)
		(width 0.12954)
		(layer "B.Cu")
		(net "USB2_CPU0_P11_DP")
	)
	(segment
		(start 364.437422 -313.657742)
		(end 364.431072 -313.657742)
		(width 0.12954)
		(layer "B.Cu")
		(net "USB2_CPU0_P11_DP")
	)
	(segment
		(start 344.253312 -297.546522)
		(end 343.314274 -296.607484)
		(width 0.12954)
		(layer "B.Cu")
		(net "USB2_CPU0_P11_DP")
	)
	(segment
		(start 339.00491 -295.50106)
		(end 339.02777 -295.41597)
		(width 0.0762)
		(layer "B.Cu")
		(net "USB2_CPU0_P11_DP")
	)
	(segment
		(start 407.806144 -194.30365)
		(end 408.464004 -199.273922)
		(width 0.12954)
		(layer "B.Cu")
		(net "USB2_CPU0_P11_DP")
	)
	(segment
		(start 341.476584 -296.607484)
		(end 341.012526 -297.071542)
		(width 0.12954)
		(layer "B.Cu")
		(net "USB2_CPU0_P11_DP")
	)
	(segment
		(start 411.01518 -314.715906)
		(end 411.01518 -334.90281)
		(width 0.12954)
		(layer "B.Cu")
		(net "USB2_CPU0_P11_DP")
	)
	(segment
		(start 338.776056 -296.383964)
		(end 338.776056 -295.956228)
		(width 0.0762)
		(layer "B.Cu")
		(net "USB2_CPU0_P11_DP")
	)
	(segment
		(start 411.01518 -334.90281)
		(end 409.21305 -336.70494)
		(width 0.12954)
		(layer "B.Cu")
		(net "USB2_CPU0_P11_DP")
	)
	(segment
		(start 408.464004 -199.77608)
		(end 411.01518 -314.715906)
		(width 0.12954)
		(layer "B.Cu")
		(net "USB2_CPU0_P11_DP")
	)
	(segment
		(start 411.054042 -189.71895)
		(end 410.346398 -190.012066)
		(width 0.12954)
		(layer "B.Cu")
		(net "USB2_CPU0_P11_DP")
	)
	(segment
		(start 432.878484 -178.529996)
		(end 421.68953 -189.71895)
		(width 0.12954)
		(layer "B.Cu")
		(net "USB2_CPU0_P11_DP")
	)
	(segment
		(start 339.02777 -295.41597)
		(end 338.871052 -295.145968)
		(width 0.0762)
		(layer "B.Cu")
		(net "USB2_CPU0_P11_DP")
	)
	(segment
		(start 338.977478 -297.071542)
		(end 338.710016 -296.80408)
		(width 0.12954)
		(layer "B.Cu")
		(net "USB2_CPU0_P11_DP")
	)
	(segment
		(start 407.857198 -193.363088)
		(end 407.806144 -194.30365)
		(width 0.12954)
		(layer "B.Cu")
		(net "USB2_CPU0_P11_DP")
	)
	(segment
		(start 338.710016 -296.450004)
		(end 338.776056 -296.383964)
		(width 0.0762)
		(layer "B.Cu")
		(net "USB2_CPU0_P11_DP")
	)
	(segment
		(start 407.997914 -192.788794)
		(end 407.857198 -193.363088)
		(width 0.12954)
		(layer "B.Cu")
		(net "USB2_CPU0_P11_DP")
	)
	(segment
		(start 432.878484 -164.050726)
		(end 432.878484 -178.529996)
		(width 0.12954)
		(layer "B.Cu")
		(net "USB2_CPU0_P11_DP")
	)
	(segment
		(start 338.776056 -295.956228)
		(end 338.775802 -295.955974)
		(width 0.0762)
		(layer "B.Cu")
		(net "USB2_CPU0_P11_DP")
	)
	(segment
		(start 408.315922 -192.042796)
		(end 407.997914 -192.788794)
		(width 0.12954)
		(layer "B.Cu")
		(net "USB2_CPU0_P11_DP")
	)
	(segment
		(start 433.212494 -163.716716)
		(end 432.878484 -164.050726)
		(width 0.12954)
		(layer "B.Cu")
		(net "USB2_CPU0_P11_DP")
	)
	(segment
		(start 408.464004 -199.273922)
		(end 408.464004 -199.77608)
		(width 0.12954)
		(layer "B.Cu")
		(net "USB2_CPU0_P11_DP")
	)
	(segment
		(start 343.314274 -296.607484)
		(end 341.476584 -296.607484)
		(width 0.12954)
		(layer "B.Cu")
		(net "USB2_CPU0_P11_DP")
	)
	(segment
		(start 338.710016 -296.80408)
		(end 338.710016 -296.469054)
		(width 0.12954)
		(layer "B.Cu")
		(net "USB2_CPU0_P11_DP")
	)
	(arc
		(start 338.984844 -295.516554)
		(mid 338.994789 -295.508693)
		(end 339.00491 -295.50106)
		(width 0.0762)
		(layer "B.Cu")
		(net "USB2_CPU0_P11_DP")
	)
	(arc
		(start 338.775802 -295.955974)
		(mid 338.830614 -295.712612)
		(end 338.984844 -295.516554)
		(width 0.0762)
		(layer "B.Cu")
		(net "USB2_CPU0_P11_DP")
	)
	(segment
		(start 409.593288 -56.830468)
		(end 400.536918 -34.966656)
		(width 0.12954)
		(layer "F.Cu")
		(net "USB2_CPU0_P11_DN")
	)
	(segment
		(start 432.221894 -163.716716)
		(end 432.555904 -163.382706)
		(width 0.12954)
		(layer "F.Cu")
		(net "USB2_CPU0_P11_DN")
	)
	(segment
		(start 389.844026 -24.273764)
		(end 389.844026 -23.535894)
		(width 0.12954)
		(layer "F.Cu")
		(net "USB2_CPU0_P11_DN")
	)
	(segment
		(start 428.190406 -146.953732)
		(end 428.190406 -132.519674)
		(width 0.12954)
		(layer "F.Cu")
		(net "USB2_CPU0_P11_DN")
	)
	(segment
		(start 407.512012 -79.270098)
		(end 407.512012 -74.297794)
		(width 0.12954)
		(layer "F.Cu")
		(net "USB2_CPU0_P11_DN")
	)
	(segment
		(start 409.593288 -72.216518)
		(end 409.593288 -56.830468)
		(width 0.12954)
		(layer "F.Cu")
		(net "USB2_CPU0_P11_DN")
	)
	(segment
		(start 414.308798 -113.440718)
		(end 407.512012 -79.270098)
		(width 0.12954)
		(layer "F.Cu")
		(net "USB2_CPU0_P11_DN")
	)
	(segment
		(start 339.808058 -295.690036)
		(end 339.341206 -295.955974)
		(width 0.12954)
		(layer "F.Cu")
		(net "USB2_CPU0_P11_DN")
	)
	(segment
		(start 432.555904 -163.382706)
		(end 432.555904 -157.493208)
		(width 0.12954)
		(layer "F.Cu")
		(net "USB2_CPU0_P11_DN")
	)
	(segment
		(start 407.512012 -74.297794)
		(end 409.593288 -72.216518)
		(width 0.12954)
		(layer "F.Cu")
		(net "USB2_CPU0_P11_DN")
	)
	(segment
		(start 428.190406 -132.519674)
		(end 417.983924 -122.313192)
		(width 0.12954)
		(layer "F.Cu")
		(net "USB2_CPU0_P11_DN")
	)
	(segment
		(start 400.536918 -34.966656)
		(end 389.844026 -24.273764)
		(width 0.12954)
		(layer "F.Cu")
		(net "USB2_CPU0_P11_DN")
	)
	(segment
		(start 417.983924 -122.313192)
		(end 414.308798 -113.440718)
		(width 0.12954)
		(layer "F.Cu")
		(net "USB2_CPU0_P11_DN")
	)
	(segment
		(start 432.555904 -157.493208)
		(end 428.190406 -146.953732)
		(width 0.12954)
		(layer "F.Cu")
		(net "USB2_CPU0_P11_DN")
	)
	(segment
		(start 389.844026 -23.535894)
		(end 389.497316 -23.189184)
		(width 0.12954)
		(layer "F.Cu")
		(net "USB2_CPU0_P11_DN")
	)
	(via
		(at 432.221894 -163.716716)
		(size 0.508)
		(drill 0.254)
		(layers "F.Cu" "B.Cu")
		(net "USB2_CPU0_P11_DN")
	)
	(via
		(at 339.341206 -295.955974)
		(size 0.4064)
		(drill 0.2032)
		(layers "F.Cu" "B.Cu")
		(net "USB2_CPU0_P11_DN")
	)
	(segment
		(start 389.427974 -336.19186)
		(end 389.041894 -336.19186)
		(width 0.12954)
		(layer "B.Cu")
		(net "USB2_CPU0_P11_DN")
	)
	(segment
		(start 407.482294 -194.316096)
		(end 408.141424 -199.295258)
		(width 0.12954)
		(layer "B.Cu")
		(net "USB2_CPU0_P11_DN")
	)
	(segment
		(start 344.802714 -297.223942)
		(end 344.38717 -297.223942)
		(width 0.12954)
		(layer "B.Cu")
		(net "USB2_CPU0_P11_DN")
	)
	(segment
		(start 421.555672 -189.39637)
		(end 410.98978 -189.39637)
		(width 0.12954)
		(layer "B.Cu")
		(net "USB2_CPU0_P11_DN")
	)
	(segment
		(start 393.308586 -336.19186)
		(end 392.922506 -336.19186)
		(width 0.12954)
		(layer "B.Cu")
		(net "USB2_CPU0_P11_DN")
	)
	(segment
		(start 408.141424 -199.295258)
		(end 408.141424 -199.77989)
		(width 0.12954)
		(layer "B.Cu")
		(net "USB2_CPU0_P11_DN")
	)
	(segment
		(start 339.105494 -295.665144)
		(end 339.184488 -295.685972)
		(width 0.0762)
		(layer "B.Cu")
		(net "USB2_CPU0_P11_DN")
	)
	(segment
		(start 393.885166 -336.38236)
		(end 393.499086 -336.38236)
		(width 0.12954)
		(layer "B.Cu")
		(net "USB2_CPU0_P11_DN")
	)
	(segment
		(start 346.225114 -297.223942)
		(end 345.569794 -297.223942)
		(width 0.12954)
		(layer "B.Cu")
		(net "USB2_CPU0_P11_DN")
	)
	(segment
		(start 364.56493 -313.335162)
		(end 348.45371 -297.223942)
		(width 0.12954)
		(layer "B.Cu")
		(net "USB2_CPU0_P11_DN")
	)
	(segment
		(start 339.032596 -296.469054)
		(end 339.032596 -296.450004)
		(width 0.0762)
		(layer "B.Cu")
		(net "USB2_CPU0_P11_DN")
	)
	(segment
		(start 394.461746 -336.19186)
		(end 394.075666 -336.19186)
		(width 0.12954)
		(layer "B.Cu")
		(net "USB2_CPU0_P11_DN")
	)
	(segment
		(start 408.04338 -191.858646)
		(end 407.690828 -192.686432)
		(width 0.12954)
		(layer "B.Cu")
		(net "USB2_CPU0_P11_DN")
	)
	(segment
		(start 390.23163 -336.19186)
		(end 390.04113 -336.38236)
		(width 0.12954)
		(layer "B.Cu")
		(net "USB2_CPU0_P11_DN")
	)
	(segment
		(start 410.6926 -334.768952)
		(end 409.079192 -336.38236)
		(width 0.12954)
		(layer "B.Cu")
		(net "USB2_CPU0_P11_DN")
	)
	(segment
		(start 410.6926 -314.719716)
		(end 410.6926 -333.04226)
		(width 0.12954)
		(layer "B.Cu")
		(net "USB2_CPU0_P11_DN")
	)
	(segment
		(start 364.57128 -313.335162)
		(end 364.56493 -313.335162)
		(width 0.12954)
		(layer "B.Cu")
		(net "USB2_CPU0_P11_DN")
	)
	(segment
		(start 410.6926 -333.04226)
		(end 410.5021 -333.23276)
		(width 0.12954)
		(layer "B.Cu")
		(net "USB2_CPU0_P11_DN")
	)
	(segment
		(start 344.993214 -297.033442)
		(end 344.802714 -297.223942)
		(width 0.12954)
		(layer "B.Cu")
		(net "USB2_CPU0_P11_DN")
	)
	(segment
		(start 392.345926 -336.38236)
		(end 392.155426 -336.19186)
		(width 0.12954)
		(layer "B.Cu")
		(net "USB2_CPU0_P11_DN")
	)
	(segment
		(start 394.652246 -336.38236)
		(end 394.461746 -336.19186)
		(width 0.12954)
		(layer "B.Cu")
		(net "USB2_CPU0_P11_DN")
	)
	(segment
		(start 345.569794 -297.223942)
		(end 345.379294 -297.033442)
		(width 0.12954)
		(layer "B.Cu")
		(net "USB2_CPU0_P11_DN")
	)
	(segment
		(start 387.618478 -336.38236)
		(end 364.57128 -313.335162)
		(width 0.12954)
		(layer "B.Cu")
		(net "USB2_CPU0_P11_DN")
	)
	(segment
		(start 341.342726 -296.284904)
		(end 340.878668 -296.748962)
		(width 0.12954)
		(layer "B.Cu")
		(net "USB2_CPU0_P11_DN")
	)
	(segment
		(start 391.578846 -336.38236)
		(end 390.80821 -336.38236)
		(width 0.12954)
		(layer "B.Cu")
		(net "USB2_CPU0_P11_DN")
	)
	(segment
		(start 343.448132 -296.284904)
		(end 341.342726 -296.284904)
		(width 0.12954)
		(layer "B.Cu")
		(net "USB2_CPU0_P11_DN")
	)
	(segment
		(start 339.032596 -296.450004)
		(end 338.966556 -296.383964)
		(width 0.0762)
		(layer "B.Cu")
		(net "USB2_CPU0_P11_DN")
	)
	(segment
		(start 339.111336 -296.748962)
		(end 339.032596 -296.670222)
		(width 0.12954)
		(layer "B.Cu")
		(net "USB2_CPU0_P11_DN")
	)
	(segment
		(start 339.032596 -296.670222)
		(end 339.032596 -296.469054)
		(width 0.12954)
		(layer "B.Cu")
		(net "USB2_CPU0_P11_DN")
	)
	(segment
		(start 407.53665 -193.31559)
		(end 407.482294 -194.316096)
		(width 0.12954)
		(layer "B.Cu")
		(net "USB2_CPU0_P11_DN")
	)
	(segment
		(start 432.555904 -164.050726)
		(end 432.555904 -178.396138)
		(width 0.12954)
		(layer "B.Cu")
		(net "USB2_CPU0_P11_DN")
	)
	(segment
		(start 346.415614 -297.033442)
		(end 346.225114 -297.223942)
		(width 0.12954)
		(layer "B.Cu")
		(net "USB2_CPU0_P11_DN")
	)
	(segment
		(start 392.155426 -336.19186)
		(end 391.769346 -336.19186)
		(width 0.12954)
		(layer "B.Cu")
		(net "USB2_CPU0_P11_DN")
	)
	(segment
		(start 410.98978 -189.39637)
		(end 410.163518 -189.738508)
		(width 0.12954)
		(layer "B.Cu")
		(net "USB2_CPU0_P11_DN")
	)
	(segment
		(start 432.555904 -178.396138)
		(end 421.555672 -189.39637)
		(width 0.12954)
		(layer "B.Cu")
		(net "USB2_CPU0_P11_DN")
	)
	(segment
		(start 410.5021 -333.23276)
		(end 410.5021 -333.61884)
		(width 0.12954)
		(layer "B.Cu")
		(net "USB2_CPU0_P11_DN")
	)
	(segment
		(start 388.851394 -336.38236)
		(end 387.618478 -336.38236)
		(width 0.12954)
		(layer "B.Cu")
		(net "USB2_CPU0_P11_DN")
	)
	(segment
		(start 410.5021 -333.61884)
		(end 410.6926 -333.80934)
		(width 0.12954)
		(layer "B.Cu")
		(net "USB2_CPU0_P11_DN")
	)
	(segment
		(start 432.221894 -163.716716)
		(end 432.555904 -164.050726)
		(width 0.12954)
		(layer "B.Cu")
		(net "USB2_CPU0_P11_DN")
	)
	(segment
		(start 339.184488 -295.685972)
		(end 339.341206 -295.955974)
		(width 0.0762)
		(layer "B.Cu")
		(net "USB2_CPU0_P11_DN")
	)
	(segment
		(start 344.38717 -297.223942)
		(end 343.448132 -296.284904)
		(width 0.12954)
		(layer "B.Cu")
		(net "USB2_CPU0_P11_DN")
	)
	(segment
		(start 346.992194 -297.223942)
		(end 346.801694 -297.033442)
		(width 0.12954)
		(layer "B.Cu")
		(net "USB2_CPU0_P11_DN")
	)
	(segment
		(start 390.80821 -336.38236)
		(end 390.61771 -336.19186)
		(width 0.12954)
		(layer "B.Cu")
		(net "USB2_CPU0_P11_DN")
	)
	(segment
		(start 390.04113 -336.38236)
		(end 389.618474 -336.38236)
		(width 0.12954)
		(layer "B.Cu")
		(net "USB2_CPU0_P11_DN")
	)
	(segment
		(start 338.966556 -296.383964)
		(end 338.966556 -295.955974)
		(width 0.0762)
		(layer "B.Cu")
		(net "USB2_CPU0_P11_DN")
	)
	(segment
		(start 407.690828 -192.686432)
		(end 407.53665 -193.31559)
		(width 0.12954)
		(layer "B.Cu")
		(net "USB2_CPU0_P11_DN")
	)
	(segment
		(start 393.499086 -336.38236)
		(end 393.308586 -336.19186)
		(width 0.12954)
		(layer "B.Cu")
		(net "USB2_CPU0_P11_DN")
	)
	(segment
		(start 394.075666 -336.19186)
		(end 393.885166 -336.38236)
		(width 0.12954)
		(layer "B.Cu")
		(net "USB2_CPU0_P11_DN")
	)
	(segment
		(start 391.769346 -336.19186)
		(end 391.578846 -336.38236)
		(width 0.12954)
		(layer "B.Cu")
		(net "USB2_CPU0_P11_DN")
	)
	(segment
		(start 346.801694 -297.033442)
		(end 346.415614 -297.033442)
		(width 0.12954)
		(layer "B.Cu")
		(net "USB2_CPU0_P11_DN")
	)
	(segment
		(start 340.878668 -296.748962)
		(end 339.111336 -296.748962)
		(width 0.12954)
		(layer "B.Cu")
		(net "USB2_CPU0_P11_DN")
	)
	(segment
		(start 345.379294 -297.033442)
		(end 344.993214 -297.033442)
		(width 0.12954)
		(layer "B.Cu")
		(net "USB2_CPU0_P11_DN")
	)
	(segment
		(start 410.163518 -189.738508)
		(end 408.04338 -191.858646)
		(width 0.12954)
		(layer "B.Cu")
		(net "USB2_CPU0_P11_DN")
	)
	(segment
		(start 389.041894 -336.19186)
		(end 388.851394 -336.38236)
		(width 0.12954)
		(layer "B.Cu")
		(net "USB2_CPU0_P11_DN")
	)
	(segment
		(start 348.45371 -297.223942)
		(end 346.992194 -297.223942)
		(width 0.12954)
		(layer "B.Cu")
		(net "USB2_CPU0_P11_DN")
	)
	(segment
		(start 390.61771 -336.19186)
		(end 390.23163 -336.19186)
		(width 0.12954)
		(layer "B.Cu")
		(net "USB2_CPU0_P11_DN")
	)
	(segment
		(start 389.618474 -336.38236)
		(end 389.427974 -336.19186)
		(width 0.12954)
		(layer "B.Cu")
		(net "USB2_CPU0_P11_DN")
	)
	(segment
		(start 408.141424 -199.77989)
		(end 410.6926 -314.719716)
		(width 0.12954)
		(layer "B.Cu")
		(net "USB2_CPU0_P11_DN")
	)
	(segment
		(start 410.6926 -333.80934)
		(end 410.6926 -334.768952)
		(width 0.12954)
		(layer "B.Cu")
		(net "USB2_CPU0_P11_DN")
	)
	(segment
		(start 392.922506 -336.19186)
		(end 392.732006 -336.38236)
		(width 0.12954)
		(layer "B.Cu")
		(net "USB2_CPU0_P11_DN")
	)
	(segment
		(start 392.732006 -336.38236)
		(end 392.345926 -336.38236)
		(width 0.12954)
		(layer "B.Cu")
		(net "USB2_CPU0_P11_DN")
	)
	(segment
		(start 409.079192 -336.38236)
		(end 394.652246 -336.38236)
		(width 0.12954)
		(layer "B.Cu")
		(net "USB2_CPU0_P11_DN")
	)
	(arc
		(start 338.966556 -295.955974)
		(mid 339.003108 -295.794821)
		(end 339.105494 -295.665144)
		(width 0.0762)
		(layer "B.Cu")
		(net "USB2_CPU0_P11_DN")
	)
	(segment
		(start 192.322196 -117.052852)
		(end 192.712086 -117.442742)
		(width 0.10668)
		(layer "F.Cu")
		(net "SWB_HSC_PWRGD_ISO_R")
	)
	(via
		(at 192.712086 -117.442742)
		(size 0.4572)
		(drill 0.254)
		(layers "F.Cu" "B.Cu")
		(net "SWB_HSC_PWRGD_ISO_R")
	)
	(via
		(at 199.074786 -121.753376)
		(size 0.762)
		(drill 0.254)
		(layers "F.Cu" "B.Cu")
		(net "SWB_HSC_PWRGD_ISO_R")
	)
	(segment
		(start 200.552558 -121.385076)
		(end 200.552558 -121.753376)
		(width 0.10668)
		(layer "B.Cu")
		(net "SWB_HSC_PWRGD_ISO_R")
	)
	(segment
		(start 200.372726 -121.205244)
		(end 200.552558 -121.385076)
		(width 0.10668)
		(layer "B.Cu")
		(net "SWB_HSC_PWRGD_ISO_R")
	)
	(segment
		(start 199.074786 -121.753376)
		(end 199.622918 -121.205244)
		(width 0.10668)
		(layer "B.Cu")
		(net "SWB_HSC_PWRGD_ISO_R")
	)
	(segment
		(start 199.622918 -121.205244)
		(end 200.372726 -121.205244)
		(width 0.10668)
		(layer "B.Cu")
		(net "SWB_HSC_PWRGD_ISO_R")
	)
	(segment
		(start 199.936862 -118.2116)
		(end 197.53326 -118.2116)
		(width 0.11684)
		(layer "In4.Cu")
		(net "SWB_HSC_PWRGD_ISO_R")
	)
	(segment
		(start 197.53326 -118.2116)
		(end 197.380352 -118.058692)
		(width 0.11684)
		(layer "In4.Cu")
		(net "SWB_HSC_PWRGD_ISO_R")
	)
	(segment
		(start 194.23507 -117.442742)
		(end 192.712086 -117.442742)
		(width 0.11684)
		(layer "In4.Cu")
		(net "SWB_HSC_PWRGD_ISO_R")
	)
	(segment
		(start 199.074786 -121.753376)
		(end 199.625204 -121.202958)
		(width 0.11684)
		(layer "In4.Cu")
		(net "SWB_HSC_PWRGD_ISO_R")
	)
	(segment
		(start 194.85102 -118.058692)
		(end 194.23507 -117.442742)
		(width 0.11684)
		(layer "In4.Cu")
		(net "SWB_HSC_PWRGD_ISO_R")
	)
	(segment
		(start 200.472294 -118.747032)
		(end 199.936862 -118.2116)
		(width 0.11684)
		(layer "In4.Cu")
		(net "SWB_HSC_PWRGD_ISO_R")
	)
	(segment
		(start 197.380352 -118.058692)
		(end 194.85102 -118.058692)
		(width 0.11684)
		(layer "In4.Cu")
		(net "SWB_HSC_PWRGD_ISO_R")
	)
	(segment
		(start 200.355454 -121.202958)
		(end 200.472294 -121.086118)
		(width 0.11684)
		(layer "In4.Cu")
		(net "SWB_HSC_PWRGD_ISO_R")
	)
	(segment
		(start 200.472294 -121.086118)
		(end 200.472294 -118.747032)
		(width 0.11684)
		(layer "In4.Cu")
		(net "SWB_HSC_PWRGD_ISO_R")
	)
	(segment
		(start 199.625204 -121.202958)
		(end 200.355454 -121.202958)
		(width 0.11684)
		(layer "In4.Cu")
		(net "SWB_HSC_PWRGD_ISO_R")
	)
	(segment
		(start 192.322196 -116.252752)
		(end 192.712086 -116.642642)
		(width 0.10668)
		(layer "F.Cu")
		(net "SWB_HSC_EN_R")
	)
	(via
		(at 192.712086 -116.642642)
		(size 0.4572)
		(drill 0.254)
		(layers "F.Cu" "B.Cu")
		(net "SWB_HSC_EN_R")
	)
	(segment
		(start 195.803774 -118.655592)
		(end 195.803774 -118.099332)
		(width 0.10668)
		(layer "B.Cu")
		(net "SWB_HSC_EN_R")
	)
	(segment
		(start 195.803774 -118.099332)
		(end 194.347084 -116.642642)
		(width 0.10668)
		(layer "B.Cu")
		(net "SWB_HSC_EN_R")
	)
	(segment
		(start 196.869558 -119.721376)
		(end 195.803774 -118.655592)
		(width 0.10668)
		(layer "B.Cu")
		(net "SWB_HSC_EN_R")
	)
	(segment
		(start 194.347084 -116.642642)
		(end 192.712086 -116.642642)
		(width 0.10668)
		(layer "B.Cu")
		(net "SWB_HSC_EN_R")
	)
	(segment
		(start 308.087014 -74.947018)
		(end 309.649622 -74.947018)
		(width 0.10668)
		(layer "F.Cu")
		(net "SCM_SYS_PWROK_R2")
	)
	(segment
		(start 305.437032 -86.721696)
		(end 305.437032 -84.99348)
		(width 0.10668)
		(layer "F.Cu")
		(net "SCM_SYS_PWROK_R2")
	)
	(segment
		(start 305.437032 -84.99348)
		(end 304.840894 -84.397342)
		(width 0.10668)
		(layer "F.Cu")
		(net "SCM_SYS_PWROK_R2")
	)
	(segment
		(start 309.649622 -74.947018)
		(end 310.411876 -74.184764)
		(width 0.10668)
		(layer "F.Cu")
		(net "SCM_SYS_PWROK_R2")
	)
	(segment
		(start 304.840894 -84.397342)
		(end 304.840894 -78.193138)
		(width 0.10668)
		(layer "F.Cu")
		(net "SCM_SYS_PWROK_R2")
	)
	(segment
		(start 304.840894 -78.193138)
		(end 308.087014 -74.947018)
		(width 0.10668)
		(layer "F.Cu")
		(net "SCM_SYS_PWROK_R2")
	)
	(via
		(at 305.437032 -86.721696)
		(size 0.508)
		(drill 0.254)
		(layers "F.Cu" "B.Cu")
		(net "SCM_SYS_PWROK_R2")
	)
	(via
		(at 310.411876 -74.184764)
		(size 0.762)
		(drill 0.254)
		(layers "F.Cu" "B.Cu")
		(net "SCM_SYS_PWROK_R2")
	)
	(via
		(at 212.829648 -101.99243)
		(size 0.508)
		(drill 0.254)
		(layers "F.Cu" "B.Cu")
		(net "SCM_SYS_PWROK_R2")
	)
	(segment
		(start 310.411876 -73.861422)
		(end 310.73852 -73.534778)
		(width 0.10668)
		(layer "B.Cu")
		(net "SCM_SYS_PWROK_R2")
	)
	(segment
		(start 157.913832 -110.014258)
		(end 158.640526 -110.014258)
		(width 0.10668)
		(layer "B.Cu")
		(net "SCM_SYS_PWROK_R2")
	)
	(segment
		(start 166.660576 -92.66682)
		(end 168.509188 -90.818208)
		(width 0.10668)
		(layer "B.Cu")
		(net "SCM_SYS_PWROK_R2")
	)
	(segment
		(start 310.411876 -74.184764)
		(end 310.411876 -73.861422)
		(width 0.10668)
		(layer "B.Cu")
		(net "SCM_SYS_PWROK_R2")
	)
	(segment
		(start 161.73577 -118.428008)
		(end 161.24936 -118.428008)
		(width 0.10668)
		(layer "B.Cu")
		(net "SCM_SYS_PWROK_R2")
	)
	(segment
		(start 168.509188 -90.818208)
		(end 188.48197 -90.818208)
		(width 0.10668)
		(layer "B.Cu")
		(net "SCM_SYS_PWROK_R2")
	)
	(segment
		(start 157.41904 -110.50905)
		(end 157.913832 -110.014258)
		(width 0.10668)
		(layer "B.Cu")
		(net "SCM_SYS_PWROK_R2")
	)
	(segment
		(start 190.00089 -89.299288)
		(end 204.885798 -89.299288)
		(width 0.10668)
		(layer "B.Cu")
		(net "SCM_SYS_PWROK_R2")
	)
	(segment
		(start 188.48197 -90.818208)
		(end 190.00089 -89.299288)
		(width 0.10668)
		(layer "B.Cu")
		(net "SCM_SYS_PWROK_R2")
	)
	(segment
		(start 210.032092 -99.194874)
		(end 212.829648 -101.99243)
		(width 0.10668)
		(layer "B.Cu")
		(net "SCM_SYS_PWROK_R2")
	)
	(segment
		(start 310.73852 -73.534778)
		(end 311.194704 -73.534778)
		(width 0.10668)
		(layer "B.Cu")
		(net "SCM_SYS_PWROK_R2")
	)
	(segment
		(start 163.67252 -120.364758)
		(end 161.73577 -118.428008)
		(width 0.10668)
		(layer "B.Cu")
		(net "SCM_SYS_PWROK_R2")
	)
	(segment
		(start 163.67252 -121.038874)
		(end 163.662868 -121.048526)
		(width 0.10668)
		(layer "B.Cu")
		(net "SCM_SYS_PWROK_R2")
	)
	(segment
		(start 161.730944 -107.49026)
		(end 166.660576 -102.560628)
		(width 0.10668)
		(layer "B.Cu")
		(net "SCM_SYS_PWROK_R2")
	)
	(segment
		(start 157.41904 -114.597688)
		(end 157.41904 -110.50905)
		(width 0.10668)
		(layer "B.Cu")
		(net "SCM_SYS_PWROK_R2")
	)
	(segment
		(start 163.662868 -121.048526)
		(end 163.662868 -121.701814)
		(width 0.10668)
		(layer "B.Cu")
		(net "SCM_SYS_PWROK_R2")
	)
	(segment
		(start 210.032092 -94.445582)
		(end 210.032092 -99.194874)
		(width 0.10668)
		(layer "B.Cu")
		(net "SCM_SYS_PWROK_R2")
	)
	(segment
		(start 158.640526 -110.014258)
		(end 161.164524 -107.49026)
		(width 0.10668)
		(layer "B.Cu")
		(net "SCM_SYS_PWROK_R2")
	)
	(segment
		(start 204.885798 -89.299288)
		(end 210.032092 -94.445582)
		(width 0.10668)
		(layer "B.Cu")
		(net "SCM_SYS_PWROK_R2")
	)
	(segment
		(start 161.164524 -107.49026)
		(end 161.730944 -107.49026)
		(width 0.10668)
		(layer "B.Cu")
		(net "SCM_SYS_PWROK_R2")
	)
	(segment
		(start 163.67252 -120.364758)
		(end 163.67252 -121.038874)
		(width 0.10668)
		(layer "B.Cu")
		(net "SCM_SYS_PWROK_R2")
	)
	(segment
		(start 161.24936 -118.428008)
		(end 157.41904 -114.597688)
		(width 0.10668)
		(layer "B.Cu")
		(net "SCM_SYS_PWROK_R2")
	)
	(segment
		(start 166.660576 -102.560628)
		(end 166.660576 -92.66682)
		(width 0.10668)
		(layer "B.Cu")
		(net "SCM_SYS_PWROK_R2")
	)
	(segment
		(start 247.577102 -86.821772)
		(end 305.336956 -86.821772)
		(width 0.11684)
		(layer "In15.Cu")
		(net "SCM_SYS_PWROK_R2")
	)
	(segment
		(start 213.437978 -101.3841)
		(end 216.25052 -101.3841)
		(width 0.11684)
		(layer "In15.Cu")
		(net "SCM_SYS_PWROK_R2")
	)
	(segment
		(start 216.65184 -101.78542)
		(end 232.613454 -101.78542)
		(width 0.11684)
		(layer "In15.Cu")
		(net "SCM_SYS_PWROK_R2")
	)
	(segment
		(start 232.613454 -101.78542)
		(end 247.577102 -86.821772)
		(width 0.11684)
		(layer "In15.Cu")
		(net "SCM_SYS_PWROK_R2")
	)
	(segment
		(start 212.829648 -101.99243)
		(end 213.437978 -101.3841)
		(width 0.11684)
		(layer "In15.Cu")
		(net "SCM_SYS_PWROK_R2")
	)
	(segment
		(start 216.25052 -101.3841)
		(end 216.65184 -101.78542)
		(width 0.11684)
		(layer "In15.Cu")
		(net "SCM_SYS_PWROK_R2")
	)
	(segment
		(start 305.336956 -86.821772)
		(end 305.437032 -86.721696)
		(width 0.11684)
		(layer "In15.Cu")
		(net "SCM_SYS_PWROK_R2")
	)
	(segment
		(start 142.947136 -13.599922)
		(end 142.947136 -12.418314)
		(width 0.10668)
		(layer "F.Cu")
		(net "SCM_SYS_PWROK_R1")
	)
	(segment
		(start 142.947136 -12.418314)
		(end 142.832074 -12.303252)
		(width 0.10668)
		(layer "F.Cu")
		(net "SCM_SYS_PWROK_R1")
	)
	(via
		(at 161.45256 -117.921278)
		(size 0.508)
		(drill 0.254)
		(layers "F.Cu" "B.Cu")
		(net "SCM_SYS_PWROK_R1")
	)
	(via
		(at 142.832074 -12.303252)
		(size 0.508)
		(drill 0.254)
		(layers "F.Cu" "B.Cu")
		(net "SCM_SYS_PWROK_R1")
	)
	(via
		(at 147.65909 -119.9134)
		(size 0.508)
		(drill 0.254)
		(layers "F.Cu" "B.Cu")
		(net "SCM_SYS_PWROK_R1")
	)
	(segment
		(start 162.248088 -117.921278)
		(end 161.45256 -117.921278)
		(width 0.10668)
		(layer "B.Cu")
		(net "SCM_SYS_PWROK_R1")
	)
	(segment
		(start 163.662868 -119.336058)
		(end 162.248088 -117.921278)
		(width 0.10668)
		(layer "B.Cu")
		(net "SCM_SYS_PWROK_R1")
	)
	(segment
		(start 159.042608 -117.921278)
		(end 155.978606 -120.98528)
		(width 0.11684)
		(layer "In2.Cu")
		(net "SCM_SYS_PWROK_R1")
	)
	(segment
		(start 149.000972 -120.98528)
		(end 147.929092 -119.9134)
		(width 0.11684)
		(layer "In2.Cu")
		(net "SCM_SYS_PWROK_R1")
	)
	(segment
		(start 147.929092 -119.9134)
		(end 147.65909 -119.9134)
		(width 0.11684)
		(layer "In2.Cu")
		(net "SCM_SYS_PWROK_R1")
	)
	(segment
		(start 155.978606 -120.98528)
		(end 149.000972 -120.98528)
		(width 0.11684)
		(layer "In2.Cu")
		(net "SCM_SYS_PWROK_R1")
	)
	(segment
		(start 161.45256 -117.921278)
		(end 159.042608 -117.921278)
		(width 0.11684)
		(layer "In2.Cu")
		(net "SCM_SYS_PWROK_R1")
	)
	(segment
		(start 131.345432 -33.082992)
		(end 135.482076 -33.082992)
		(width 0.11684)
		(layer "In4.Cu")
		(net "SCM_SYS_PWROK_R1")
	)
	(segment
		(start 135.482076 -33.082992)
		(end 137.53592 -31.029148)
		(width 0.11684)
		(layer "In4.Cu")
		(net "SCM_SYS_PWROK_R1")
	)
	(segment
		(start 105.09504 -52.921408)
		(end 107.236768 -50.77968)
		(width 0.11684)
		(layer "In4.Cu")
		(net "SCM_SYS_PWROK_R1")
	)
	(segment
		(start 139.44727 -110.392464)
		(end 139.44727 -109.79404)
		(width 0.11684)
		(layer "In4.Cu")
		(net "SCM_SYS_PWROK_R1")
	)
	(segment
		(start 142.832074 -13.975334)
		(end 142.832074 -12.303252)
		(width 0.11684)
		(layer "In4.Cu")
		(net "SCM_SYS_PWROK_R1")
	)
	(segment
		(start 107.236768 -50.77968)
		(end 117.93474 -50.77968)
		(width 0.11684)
		(layer "In4.Cu")
		(net "SCM_SYS_PWROK_R1")
	)
	(segment
		(start 145.559018 -119.9134)
		(end 141.070584 -115.424966)
		(width 0.11684)
		(layer "In4.Cu")
		(net "SCM_SYS_PWROK_R1")
	)
	(segment
		(start 137.53592 -31.029148)
		(end 137.53592 -27.131264)
		(width 0.11684)
		(layer "In4.Cu")
		(net "SCM_SYS_PWROK_R1")
	)
	(segment
		(start 142.341092 -15.43177)
		(end 142.341092 -14.466316)
		(width 0.11684)
		(layer "In4.Cu")
		(net "SCM_SYS_PWROK_R1")
	)
	(segment
		(start 141.070584 -112.015778)
		(end 139.44727 -110.392464)
		(width 0.11684)
		(layer "In4.Cu")
		(net "SCM_SYS_PWROK_R1")
	)
	(segment
		(start 117.93474 -50.77968)
		(end 129.062734 -39.651686)
		(width 0.11684)
		(layer "In4.Cu")
		(net "SCM_SYS_PWROK_R1")
	)
	(segment
		(start 120.06707 -91.012264)
		(end 120.06707 -89.795858)
		(width 0.11684)
		(layer "In4.Cu")
		(net "SCM_SYS_PWROK_R1")
	)
	(segment
		(start 143.242792 -16.33347)
		(end 142.341092 -15.43177)
		(width 0.11684)
		(layer "In4.Cu")
		(net "SCM_SYS_PWROK_R1")
	)
	(segment
		(start 143.242792 -21.424392)
		(end 143.242792 -16.33347)
		(width 0.11684)
		(layer "In4.Cu")
		(net "SCM_SYS_PWROK_R1")
	)
	(segment
		(start 105.09504 -58.33364)
		(end 105.09504 -52.921408)
		(width 0.11684)
		(layer "In4.Cu")
		(net "SCM_SYS_PWROK_R1")
	)
	(segment
		(start 136.446768 -105.22458)
		(end 134.279386 -105.22458)
		(width 0.11684)
		(layer "In4.Cu")
		(net "SCM_SYS_PWROK_R1")
	)
	(segment
		(start 138.009122 -106.786934)
		(end 136.446768 -105.22458)
		(width 0.11684)
		(layer "In4.Cu")
		(net "SCM_SYS_PWROK_R1")
	)
	(segment
		(start 137.53592 -27.131264)
		(end 143.242792 -21.424392)
		(width 0.11684)
		(layer "In4.Cu")
		(net "SCM_SYS_PWROK_R1")
	)
	(segment
		(start 110.00486 -79.733648)
		(end 110.00486 -76.186284)
		(width 0.11684)
		(layer "In4.Cu")
		(net "SCM_SYS_PWROK_R1")
	)
	(segment
		(start 104.01554 -70.196964)
		(end 104.01554 -59.41314)
		(width 0.11684)
		(layer "In4.Cu")
		(net "SCM_SYS_PWROK_R1")
	)
	(segment
		(start 120.06707 -89.795858)
		(end 110.00486 -79.733648)
		(width 0.11684)
		(layer "In4.Cu")
		(net "SCM_SYS_PWROK_R1")
	)
	(segment
		(start 142.341092 -14.466316)
		(end 142.832074 -13.975334)
		(width 0.11684)
		(layer "In4.Cu")
		(net "SCM_SYS_PWROK_R1")
	)
	(segment
		(start 134.279386 -105.22458)
		(end 120.06707 -91.012264)
		(width 0.11684)
		(layer "In4.Cu")
		(net "SCM_SYS_PWROK_R1")
	)
	(segment
		(start 147.65909 -119.9134)
		(end 145.559018 -119.9134)
		(width 0.11684)
		(layer "In4.Cu")
		(net "SCM_SYS_PWROK_R1")
	)
	(segment
		(start 129.062734 -39.651686)
		(end 129.062734 -35.36569)
		(width 0.11684)
		(layer "In4.Cu")
		(net "SCM_SYS_PWROK_R1")
	)
	(segment
		(start 138.009122 -108.355892)
		(end 138.009122 -106.786934)
		(width 0.11684)
		(layer "In4.Cu")
		(net "SCM_SYS_PWROK_R1")
	)
	(segment
		(start 129.062734 -35.36569)
		(end 131.345432 -33.082992)
		(width 0.11684)
		(layer "In4.Cu")
		(net "SCM_SYS_PWROK_R1")
	)
	(segment
		(start 104.01554 -59.41314)
		(end 105.09504 -58.33364)
		(width 0.11684)
		(layer "In4.Cu")
		(net "SCM_SYS_PWROK_R1")
	)
	(segment
		(start 141.070584 -115.424966)
		(end 141.070584 -112.015778)
		(width 0.11684)
		(layer "In4.Cu")
		(net "SCM_SYS_PWROK_R1")
	)
	(segment
		(start 139.44727 -109.79404)
		(end 138.009122 -108.355892)
		(width 0.11684)
		(layer "In4.Cu")
		(net "SCM_SYS_PWROK_R1")
	)
	(segment
		(start 110.00486 -76.186284)
		(end 104.01554 -70.196964)
		(width 0.11684)
		(layer "In4.Cu")
		(net "SCM_SYS_PWROK_R1")
	)
	(segment
		(start 83.622134 -39.65448)
		(end 83.622134 -40.67048)
		(width 0.10668)
		(layer "F.Cu")
		(net "RST_PERST_OCP_V3_2_BUF2_N")
	)
	(segment
		(start 83.622134 -41.88968)
		(end 83.622134 -43.47718)
		(width 0.10668)
		(layer "F.Cu")
		(net "RST_PERST_OCP_V3_2_BUF2_N")
	)
	(segment
		(start 83.622134 -37.36848)
		(end 83.622134 -38.63848)
		(width 0.10668)
		(layer "F.Cu")
		(net "RST_PERST_OCP_V3_2_BUF2_N")
	)
	(segment
		(start 83.622134 -38.63848)
		(end 83.622134 -39.65448)
		(width 0.10668)
		(layer "F.Cu")
		(net "RST_PERST_OCP_V3_2_BUF2_N")
	)
	(segment
		(start 83.622134 -41.88968)
		(end 83.622134 -40.67048)
		(width 0.10668)
		(layer "F.Cu")
		(net "RST_PERST_OCP_V3_2_BUF2_N")
	)
	(via
		(at 83.622134 -41.88968)
		(size 0.762)
		(drill 0.381)
		(layers "F.Cu" "B.Cu")
		(net "RST_PERST_OCP_V3_2_BUF2_N")
	)
	(segment
		(start 211.42325 -123.569984)
		(end 212.149944 -122.84329)
		(width 0.10668)
		(layer "F.Cu")
		(net "RST_PERST_OCP_SFF_BUF2_N")
	)
	(segment
		(start 213.528148 -122.46991)
		(end 213.51875 -122.460512)
		(width 0.10668)
		(layer "F.Cu")
		(net "RST_PERST_OCP_SFF_BUF2_N")
	)
	(segment
		(start 213.519004 -124.604018)
		(end 213.528148 -124.594874)
		(width 0.10668)
		(layer "F.Cu")
		(net "RST_PERST_OCP_SFF_BUF2_N")
	)
	(segment
		(start 212.532722 -122.460512)
		(end 213.51875 -122.460512)
		(width 0.10668)
		(layer "F.Cu")
		(net "RST_PERST_OCP_SFF_BUF2_N")
	)
	(segment
		(start 213.519004 -125.614684)
		(end 213.519004 -124.604018)
		(width 0.10668)
		(layer "F.Cu")
		(net "RST_PERST_OCP_SFF_BUF2_N")
	)
	(segment
		(start 213.489794 -125.643894)
		(end 213.519004 -125.614684)
		(width 0.10668)
		(layer "F.Cu")
		(net "RST_PERST_OCP_SFF_BUF2_N")
	)
	(segment
		(start 212.149944 -122.84329)
		(end 212.532722 -122.460512)
		(width 0.10668)
		(layer "F.Cu")
		(net "RST_PERST_OCP_SFF_BUF2_N")
	)
	(segment
		(start 213.528148 -123.565412)
		(end 213.528148 -122.46991)
		(width 0.10668)
		(layer "F.Cu")
		(net "RST_PERST_OCP_SFF_BUF2_N")
	)
	(segment
		(start 213.528148 -124.594874)
		(end 213.528148 -123.565412)
		(width 0.10668)
		(layer "F.Cu")
		(net "RST_PERST_OCP_SFF_BUF2_N")
	)
	(segment
		(start 210.573112 -123.569984)
		(end 211.42325 -123.569984)
		(width 0.10668)
		(layer "F.Cu")
		(net "RST_PERST_OCP_SFF_BUF2_N")
	)
	(via
		(at 212.149944 -122.84329)
		(size 0.762)
		(drill 0.381)
		(layers "F.Cu" "B.Cu")
		(net "RST_PERST_OCP_SFF_BUF2_N")
	)
	(segment
		(start 189.92215 -117.852952)
		(end 190.31204 -118.242842)
		(width 0.10668)
		(layer "F.Cu")
		(net "RST_BMC_FROM_SWB_ISO_R_N")
	)
	(segment
		(start 197.400164 -127.363982)
		(end 197.400164 -128.137158)
		(width 0.10668)
		(layer "F.Cu")
		(net "RST_BMC_FROM_SWB_ISO_R_N")
	)
	(segment
		(start 196.869558 -126.833376)
		(end 197.400164 -127.363982)
		(width 0.10668)
		(layer "F.Cu")
		(net "RST_BMC_FROM_SWB_ISO_R_N")
	)
	(via
		(at 197.400164 -128.137158)
		(size 0.508)
		(drill 0.254)
		(layers "F.Cu" "B.Cu")
		(net "RST_BMC_FROM_SWB_ISO_R_N")
	)
	(via
		(at 190.31204 -118.242842)
		(size 0.4572)
		(drill 0.254)
		(layers "F.Cu" "B.Cu")
		(net "RST_BMC_FROM_SWB_ISO_R_N")
	)
	(segment
		(start 190.909702 -121.054114)
		(end 192.073022 -121.054114)
		(width 0.11684)
		(layer "In6.Cu")
		(net "RST_BMC_FROM_SWB_ISO_R_N")
	)
	(segment
		(start 189.903608 -118.651274)
		(end 189.903608 -120.051576)
		(width 0.11684)
		(layer "In6.Cu")
		(net "RST_BMC_FROM_SWB_ISO_R_N")
	)
	(segment
		(start 190.57112 -120.254014)
		(end 190.706248 -120.389142)
		(width 0.11684)
		(layer "In6.Cu")
		(net "RST_BMC_FROM_SWB_ISO_R_N")
	)
	(segment
		(start 190.706248 -120.85066)
		(end 190.909702 -121.054114)
		(width 0.11684)
		(layer "In6.Cu")
		(net "RST_BMC_FROM_SWB_ISO_R_N")
	)
	(segment
		(start 192.300606 -121.281698)
		(end 192.300606 -123.253754)
		(width 0.11684)
		(layer "In6.Cu")
		(net "RST_BMC_FROM_SWB_ISO_R_N")
	)
	(segment
		(start 190.106808 -120.254776)
		(end 190.150242 -120.254776)
		(width 0.11684)
		(layer "In6.Cu")
		(net "RST_BMC_FROM_SWB_ISO_R_N")
	)
	(segment
		(start 190.150242 -120.254776)
		(end 190.151004 -120.254014)
		(width 0.11684)
		(layer "In6.Cu")
		(net "RST_BMC_FROM_SWB_ISO_R_N")
	)
	(segment
		(start 196.058282 -127.01143)
		(end 196.058282 -127.683514)
		(width 0.11684)
		(layer "In6.Cu")
		(net "RST_BMC_FROM_SWB_ISO_R_N")
	)
	(segment
		(start 196.511926 -128.137158)
		(end 197.400164 -128.137158)
		(width 0.11684)
		(layer "In6.Cu")
		(net "RST_BMC_FROM_SWB_ISO_R_N")
	)
	(segment
		(start 190.31204 -118.242842)
		(end 189.903608 -118.651274)
		(width 0.11684)
		(layer "In6.Cu")
		(net "RST_BMC_FROM_SWB_ISO_R_N")
	)
	(segment
		(start 189.903608 -120.051576)
		(end 190.106808 -120.254776)
		(width 0.11684)
		(layer "In6.Cu")
		(net "RST_BMC_FROM_SWB_ISO_R_N")
	)
	(segment
		(start 190.706248 -120.389142)
		(end 190.706248 -120.85066)
		(width 0.11684)
		(layer "In6.Cu")
		(net "RST_BMC_FROM_SWB_ISO_R_N")
	)
	(segment
		(start 196.058282 -127.683514)
		(end 196.511926 -128.137158)
		(width 0.11684)
		(layer "In6.Cu")
		(net "RST_BMC_FROM_SWB_ISO_R_N")
	)
	(segment
		(start 192.073022 -121.054114)
		(end 192.300606 -121.281698)
		(width 0.11684)
		(layer "In6.Cu")
		(net "RST_BMC_FROM_SWB_ISO_R_N")
	)
	(segment
		(start 190.151004 -120.254014)
		(end 190.57112 -120.254014)
		(width 0.11684)
		(layer "In6.Cu")
		(net "RST_BMC_FROM_SWB_ISO_R_N")
	)
	(segment
		(start 192.300606 -123.253754)
		(end 196.058282 -127.01143)
		(width 0.11684)
		(layer "In6.Cu")
		(net "RST_BMC_FROM_SWB_ISO_R_N")
	)
	(segment
		(start 191.522096 -112.25276)
		(end 191.911986 -111.86287)
		(width 0.10668)
		(layer "F.Cu")
		(net "PWRGD_P3V3_AUX_R")
	)
	(segment
		(start 200.491598 -109.609636)
		(end 199.090534 -109.609636)
		(width 0.10668)
		(layer "F.Cu")
		(net "PWRGD_P3V3_AUX_R")
	)
	(segment
		(start 200.539858 -109.561376)
		(end 200.491598 -109.609636)
		(width 0.10668)
		(layer "F.Cu")
		(net "PWRGD_P3V3_AUX_R")
	)
	(via
		(at 199.090534 -109.609636)
		(size 0.508)
		(drill 0.254)
		(layers "F.Cu" "B.Cu")
		(net "PWRGD_P3V3_AUX_R")
	)
	(via
		(at 191.911986 -111.86287)
		(size 0.4572)
		(drill 0.254)
		(layers "F.Cu" "B.Cu")
		(net "PWRGD_P3V3_AUX_R")
	)
	(segment
		(start 195.987162 -109.76864)
		(end 195.623434 -110.132368)
		(width 0.11684)
		(layer "In4.Cu")
		(net "PWRGD_P3V3_AUX_R")
	)
	(segment
		(start 195.623434 -110.132368)
		(end 194.959732 -110.132368)
		(width 0.11684)
		(layer "In4.Cu")
		(net "PWRGD_P3V3_AUX_R")
	)
	(segment
		(start 194.959732 -110.132368)
		(end 193.625724 -111.466376)
		(width 0.11684)
		(layer "In4.Cu")
		(net "PWRGD_P3V3_AUX_R")
	)
	(segment
		(start 198.500492 -109.014768)
		(end 198.142352 -109.014768)
		(width 0.11684)
		(layer "In4.Cu")
		(net "PWRGD_P3V3_AUX_R")
	)
	(segment
		(start 193.625724 -111.466376)
		(end 192.265808 -111.466376)
		(width 0.11684)
		(layer "In4.Cu")
		(net "PWRGD_P3V3_AUX_R")
	)
	(segment
		(start 191.911986 -111.820198)
		(end 191.911986 -111.86287)
		(width 0.11684)
		(layer "In4.Cu")
		(net "PWRGD_P3V3_AUX_R")
	)
	(segment
		(start 198.142352 -109.014768)
		(end 197.38848 -109.76864)
		(width 0.11684)
		(layer "In4.Cu")
		(net "PWRGD_P3V3_AUX_R")
	)
	(segment
		(start 192.265808 -111.466376)
		(end 191.911986 -111.820198)
		(width 0.11684)
		(layer "In4.Cu")
		(net "PWRGD_P3V3_AUX_R")
	)
	(segment
		(start 199.090534 -109.60481)
		(end 198.500492 -109.014768)
		(width 0.11684)
		(layer "In4.Cu")
		(net "PWRGD_P3V3_AUX_R")
	)
	(segment
		(start 199.090534 -109.609636)
		(end 199.090534 -109.60481)
		(width 0.11684)
		(layer "In4.Cu")
		(net "PWRGD_P3V3_AUX_R")
	)
	(segment
		(start 197.38848 -109.76864)
		(end 195.987162 -109.76864)
		(width 0.11684)
		(layer "In4.Cu")
		(net "PWRGD_P3V3_AUX_R")
	)
	(segment
		(start 319.754758 -77.436472)
		(end 319.754758 -73.95591)
		(width 0.10668)
		(layer "F.Cu")
		(net "PWRGD_P1V8_AUX_R")
	)
	(segment
		(start 192.322196 -112.25276)
		(end 192.712086 -111.86287)
		(width 0.10668)
		(layer "F.Cu")
		(net "PWRGD_P1V8_AUX_R")
	)
	(segment
		(start 306.977796 -78.471776)
		(end 318.719454 -78.471776)
		(width 0.10668)
		(layer "F.Cu")
		(net "PWRGD_P1V8_AUX_R")
	)
	(segment
		(start 216.199466 -128.335786)
		(end 216.801954 -128.335786)
		(width 0.10668)
		(layer "F.Cu")
		(net "PWRGD_P1V8_AUX_R")
	)
	(segment
		(start 319.754758 -73.95591)
		(end 320.571876 -73.138792)
		(width 0.10668)
		(layer "F.Cu")
		(net "PWRGD_P1V8_AUX_R")
	)
	(segment
		(start 158.82874 -45.385736)
		(end 158.82874 -45.863764)
		(width 0.10668)
		(layer "F.Cu")
		(net "PWRGD_P1V8_AUX_R")
	)
	(segment
		(start 158.82874 -45.863764)
		(end 159.213296 -46.24832)
		(width 0.10668)
		(layer "F.Cu")
		(net "PWRGD_P1V8_AUX_R")
	)
	(segment
		(start 215.730328 -128.804924)
		(end 216.199466 -128.335786)
		(width 0.10668)
		(layer "F.Cu")
		(net "PWRGD_P1V8_AUX_R")
	)
	(segment
		(start 318.719454 -78.471776)
		(end 319.754758 -77.436472)
		(width 0.10668)
		(layer "F.Cu")
		(net "PWRGD_P1V8_AUX_R")
	)
	(segment
		(start 306.22875 -79.694532)
		(end 306.22875 -79.220822)
		(width 0.10668)
		(layer "F.Cu")
		(net "PWRGD_P1V8_AUX_R")
	)
	(segment
		(start 216.801954 -128.335786)
		(end 217.296238 -128.83007)
		(width 0.10668)
		(layer "F.Cu")
		(net "PWRGD_P1V8_AUX_R")
	)
	(segment
		(start 306.22875 -79.220822)
		(end 306.977796 -78.471776)
		(width 0.10668)
		(layer "F.Cu")
		(net "PWRGD_P1V8_AUX_R")
	)
	(via
		(at 251.353828 -77.105002)
		(size 0.508)
		(drill 0.254)
		(layers "F.Cu" "B.Cu")
		(net "PWRGD_P1V8_AUX_R")
	)
	(via
		(at 159.213296 -46.24832)
		(size 0.508)
		(drill 0.254)
		(layers "F.Cu" "B.Cu")
		(net "PWRGD_P1V8_AUX_R")
	)
	(via
		(at 306.22875 -79.694532)
		(size 0.508)
		(drill 0.254)
		(layers "F.Cu" "B.Cu")
		(net "PWRGD_P1V8_AUX_R")
	)
	(via
		(at 151.6507 -71.6153)
		(size 0.508)
		(drill 0.254)
		(layers "F.Cu" "B.Cu")
		(net "PWRGD_P1V8_AUX_R")
	)
	(via
		(at 217.296238 -128.83007)
		(size 0.508)
		(drill 0.254)
		(layers "F.Cu" "B.Cu")
		(net "PWRGD_P1V8_AUX_R")
	)
	(via
		(at 320.571876 -73.138792)
		(size 0.762)
		(drill 0.254)
		(layers "F.Cu" "B.Cu")
		(net "PWRGD_P1V8_AUX_R")
	)
	(via
		(at 218.305126 -108.024422)
		(size 0.508)
		(drill 0.254)
		(layers "F.Cu" "B.Cu")
		(net "PWRGD_P1V8_AUX_R")
	)
	(via
		(at 252.579886 -88.852502)
		(size 0.508)
		(drill 0.254)
		(layers "F.Cu" "B.Cu")
		(net "PWRGD_P1V8_AUX_R")
	)
	(via
		(at 236.760766 -62.002162)
		(size 0.508)
		(drill 0.254)
		(layers "F.Cu" "B.Cu")
		(net "PWRGD_P1V8_AUX_R")
	)
	(via
		(at 192.712086 -111.86287)
		(size 0.4572)
		(drill 0.254)
		(layers "F.Cu" "B.Cu")
		(net "PWRGD_P1V8_AUX_R")
	)
	(segment
		(start 122.221244 -70.066916)
		(end 134.288276 -70.066916)
		(width 0.10668)
		(layer "B.Cu")
		(net "PWRGD_P1V8_AUX_R")
	)
	(segment
		(start 136.17956 -71.9582)
		(end 151.3078 -71.9582)
		(width 0.10668)
		(layer "B.Cu")
		(net "PWRGD_P1V8_AUX_R")
	)
	(segment
		(start 320.81343 -73.534778)
		(end 321.222624 -73.534778)
		(width 0.10668)
		(layer "B.Cu")
		(net "PWRGD_P1V8_AUX_R")
	)
	(segment
		(start 121.410222 -70.877938)
		(end 122.221244 -70.066916)
		(width 0.10668)
		(layer "B.Cu")
		(net "PWRGD_P1V8_AUX_R")
	)
	(segment
		(start 320.571876 -73.293224)
		(end 320.81343 -73.534778)
		(width 0.10668)
		(layer "B.Cu")
		(net "PWRGD_P1V8_AUX_R")
	)
	(segment
		(start 249.913394 -75.664568)
		(end 251.353828 -77.105002)
		(width 0.10668)
		(layer "B.Cu")
		(net "PWRGD_P1V8_AUX_R")
	)
	(segment
		(start 236.760766 -62.002162)
		(end 238.482124 -63.72352)
		(width 0.10668)
		(layer "B.Cu")
		(net "PWRGD_P1V8_AUX_R")
	)
	(segment
		(start 151.3078 -71.9582)
		(end 151.6507 -71.6153)
		(width 0.10668)
		(layer "B.Cu")
		(net "PWRGD_P1V8_AUX_R")
	)
	(segment
		(start 134.288276 -70.066916)
		(end 136.17956 -71.9582)
		(width 0.10668)
		(layer "B.Cu")
		(net "PWRGD_P1V8_AUX_R")
	)
	(segment
		(start 121.410222 -71.397622)
		(end 121.410222 -70.877938)
		(width 0.10668)
		(layer "B.Cu")
		(net "PWRGD_P1V8_AUX_R")
	)
	(segment
		(start 238.482124 -65.343532)
		(end 248.80316 -75.664568)
		(width 0.10668)
		(layer "B.Cu")
		(net "PWRGD_P1V8_AUX_R")
	)
	(segment
		(start 121.410222 -72.566022)
		(end 121.410222 -71.397622)
		(width 0.10668)
		(layer "B.Cu")
		(net "PWRGD_P1V8_AUX_R")
	)
	(segment
		(start 238.482124 -63.72352)
		(end 238.482124 -65.343532)
		(width 0.10668)
		(layer "B.Cu")
		(net "PWRGD_P1V8_AUX_R")
	)
	(segment
		(start 248.80316 -75.664568)
		(end 249.913394 -75.664568)
		(width 0.10668)
		(layer "B.Cu")
		(net "PWRGD_P1V8_AUX_R")
	)
	(segment
		(start 320.571876 -73.138792)
		(end 320.571876 -73.293224)
		(width 0.10668)
		(layer "B.Cu")
		(net "PWRGD_P1V8_AUX_R")
	)
	(segment
		(start 252.579886 -78.33106)
		(end 251.353828 -77.105002)
		(width 0.11684)
		(layer "In4.Cu")
		(net "PWRGD_P1V8_AUX_R")
	)
	(segment
		(start 252.579886 -88.852502)
		(end 252.579886 -78.33106)
		(width 0.11684)
		(layer "In4.Cu")
		(net "PWRGD_P1V8_AUX_R")
	)
	(segment
		(start 219.008452 -116.324888)
		(end 217.294968 -114.611404)
		(width 0.11684)
		(layer "In11.Cu")
		(net "PWRGD_P1V8_AUX_R")
	)
	(segment
		(start 154.65298 -71.6153)
		(end 151.6507 -71.6153)
		(width 0.11684)
		(layer "In11.Cu")
		(net "PWRGD_P1V8_AUX_R")
	)
	(segment
		(start 217.294968 -114.611404)
		(end 217.294968 -109.03458)
		(width 0.11684)
		(layer "In11.Cu")
		(net "PWRGD_P1V8_AUX_R")
	)
	(segment
		(start 217.294968 -109.03458)
		(end 218.305126 -108.024422)
		(width 0.11684)
		(layer "In11.Cu")
		(net "PWRGD_P1V8_AUX_R")
	)
	(segment
		(start 219.008452 -125.05055)
		(end 219.008452 -116.324888)
		(width 0.11684)
		(layer "In11.Cu")
		(net "PWRGD_P1V8_AUX_R")
	)
	(segment
		(start 158.50362 -46.957996)
		(end 158.50362 -54.72938)
		(width 0.11684)
		(layer "In11.Cu")
		(net "PWRGD_P1V8_AUX_R")
	)
	(segment
		(start 158.98622 -67.28206)
		(end 154.65298 -71.6153)
		(width 0.11684)
		(layer "In11.Cu")
		(net "PWRGD_P1V8_AUX_R")
	)
	(segment
		(start 159.213296 -46.24832)
		(end 158.50362 -46.957996)
		(width 0.11684)
		(layer "In11.Cu")
		(net "PWRGD_P1V8_AUX_R")
	)
	(segment
		(start 217.296238 -128.83007)
		(end 217.296238 -126.762764)
		(width 0.11684)
		(layer "In11.Cu")
		(net "PWRGD_P1V8_AUX_R")
	)
	(segment
		(start 158.50362 -54.72938)
		(end 158.98622 -55.21198)
		(width 0.11684)
		(layer "In11.Cu")
		(net "PWRGD_P1V8_AUX_R")
	)
	(segment
		(start 158.98622 -55.21198)
		(end 158.98622 -67.28206)
		(width 0.11684)
		(layer "In11.Cu")
		(net "PWRGD_P1V8_AUX_R")
	)
	(segment
		(start 217.296238 -126.762764)
		(end 219.008452 -125.05055)
		(width 0.11684)
		(layer "In11.Cu")
		(net "PWRGD_P1V8_AUX_R")
	)
	(segment
		(start 193.692272 -111.86287)
		(end 197.557898 -107.997244)
		(width 0.11684)
		(layer "In15.Cu")
		(net "PWRGD_P1V8_AUX_R")
	)
	(segment
		(start 181.172866 -41.256204)
		(end 203.58862 -63.671958)
		(width 0.11684)
		(layer "In15.Cu")
		(net "PWRGD_P1V8_AUX_R")
	)
	(segment
		(start 161.43605 -46.24832)
		(end 164.65169 -43.03268)
		(width 0.11684)
		(layer "In15.Cu")
		(net "PWRGD_P1V8_AUX_R")
	)
	(segment
		(start 255.700784 -81.451958)
		(end 251.353828 -77.105002)
		(width 0.11684)
		(layer "In15.Cu")
		(net "PWRGD_P1V8_AUX_R")
	)
	(segment
		(start 233.54665 -107.039664)
		(end 249.149108 -91.437206)
		(width 0.11684)
		(layer "In15.Cu")
		(net "PWRGD_P1V8_AUX_R")
	)
	(segment
		(start 304.471324 -81.451958)
		(end 255.700784 -81.451958)
		(width 0.11684)
		(layer "In15.Cu")
		(net "PWRGD_P1V8_AUX_R")
	)
	(segment
		(start 249.149108 -90.500454)
		(end 250.69546 -88.954102)
		(width 0.11684)
		(layer "In15.Cu")
		(net "PWRGD_P1V8_AUX_R")
	)
	(segment
		(start 203.854558 -107.997244)
		(end 205.057248 -106.794554)
		(width 0.11684)
		(layer "In15.Cu")
		(net "PWRGD_P1V8_AUX_R")
	)
	(segment
		(start 206.665576 -106.794554)
		(end 207.266286 -107.395264)
		(width 0.11684)
		(layer "In15.Cu")
		(net "PWRGD_P1V8_AUX_R")
	)
	(segment
		(start 197.557898 -107.997244)
		(end 203.854558 -107.997244)
		(width 0.11684)
		(layer "In15.Cu")
		(net "PWRGD_P1V8_AUX_R")
	)
	(segment
		(start 306.22875 -79.694532)
		(end 304.471324 -81.451958)
		(width 0.11684)
		(layer "In15.Cu")
		(net "PWRGD_P1V8_AUX_R")
	)
	(segment
		(start 250.69546 -88.954102)
		(end 252.478286 -88.954102)
		(width 0.11684)
		(layer "In15.Cu")
		(net "PWRGD_P1V8_AUX_R")
	)
	(segment
		(start 208.529174 -107.395264)
		(end 208.8642 -107.060238)
		(width 0.11684)
		(layer "In15.Cu")
		(net "PWRGD_P1V8_AUX_R")
	)
	(segment
		(start 219.289884 -107.039664)
		(end 233.54665 -107.039664)
		(width 0.11684)
		(layer "In15.Cu")
		(net "PWRGD_P1V8_AUX_R")
	)
	(segment
		(start 210.811364 -107.060238)
		(end 210.97621 -106.895392)
		(width 0.11684)
		(layer "In15.Cu")
		(net "PWRGD_P1V8_AUX_R")
	)
	(segment
		(start 252.478286 -88.954102)
		(end 252.579886 -88.852502)
		(width 0.11684)
		(layer "In15.Cu")
		(net "PWRGD_P1V8_AUX_R")
	)
	(segment
		(start 215.070944 -106.895392)
		(end 216.199974 -108.024422)
		(width 0.11684)
		(layer "In15.Cu")
		(net "PWRGD_P1V8_AUX_R")
	)
	(segment
		(start 168.800272 -43.03268)
		(end 170.576748 -41.256204)
		(width 0.11684)
		(layer "In15.Cu")
		(net "PWRGD_P1V8_AUX_R")
	)
	(segment
		(start 170.576748 -41.256204)
		(end 181.172866 -41.256204)
		(width 0.11684)
		(layer "In15.Cu")
		(net "PWRGD_P1V8_AUX_R")
	)
	(segment
		(start 203.58862 -63.671958)
		(end 235.09097 -63.671958)
		(width 0.11684)
		(layer "In15.Cu")
		(net "PWRGD_P1V8_AUX_R")
	)
	(segment
		(start 208.8642 -107.060238)
		(end 210.811364 -107.060238)
		(width 0.11684)
		(layer "In15.Cu")
		(net "PWRGD_P1V8_AUX_R")
	)
	(segment
		(start 249.149108 -91.437206)
		(end 249.149108 -90.500454)
		(width 0.11684)
		(layer "In15.Cu")
		(net "PWRGD_P1V8_AUX_R")
	)
	(segment
		(start 207.266286 -107.395264)
		(end 208.529174 -107.395264)
		(width 0.11684)
		(layer "In15.Cu")
		(net "PWRGD_P1V8_AUX_R")
	)
	(segment
		(start 205.057248 -106.794554)
		(end 206.665576 -106.794554)
		(width 0.11684)
		(layer "In15.Cu")
		(net "PWRGD_P1V8_AUX_R")
	)
	(segment
		(start 164.65169 -43.03268)
		(end 168.800272 -43.03268)
		(width 0.11684)
		(layer "In15.Cu")
		(net "PWRGD_P1V8_AUX_R")
	)
	(segment
		(start 210.97621 -106.895392)
		(end 215.070944 -106.895392)
		(width 0.11684)
		(layer "In15.Cu")
		(net "PWRGD_P1V8_AUX_R")
	)
	(segment
		(start 159.213296 -46.24832)
		(end 161.43605 -46.24832)
		(width 0.11684)
		(layer "In15.Cu")
		(net "PWRGD_P1V8_AUX_R")
	)
	(segment
		(start 216.199974 -108.024422)
		(end 218.305126 -108.024422)
		(width 0.11684)
		(layer "In15.Cu")
		(net "PWRGD_P1V8_AUX_R")
	)
	(segment
		(start 235.09097 -63.671958)
		(end 236.760766 -62.002162)
		(width 0.11684)
		(layer "In15.Cu")
		(net "PWRGD_P1V8_AUX_R")
	)
	(segment
		(start 218.305126 -108.024422)
		(end 219.289884 -107.039664)
		(width 0.11684)
		(layer "In15.Cu")
		(net "PWRGD_P1V8_AUX_R")
	)
	(segment
		(start 192.712086 -111.86287)
		(end 193.692272 -111.86287)
		(width 0.11684)
		(layer "In15.Cu")
		(net "PWRGD_P1V8_AUX_R")
	)
	(segment
		(start 186.722004 -121.052844)
		(end 187.111894 -121.442734)
		(width 0.10668)
		(layer "F.Cu")
		(net "PWRGD_P12V_MEM_R")
	)
	(segment
		(start 97.074736 -118.453154)
		(end 97.074736 -119.069104)
		(width 0.10668)
		(layer "F.Cu")
		(net "PWRGD_P12V_MEM_R")
	)
	(segment
		(start 97.074736 -119.069104)
		(end 96.058736 -119.069104)
		(width 0.10668)
		(layer "F.Cu")
		(net "PWRGD_P12V_MEM_R")
	)
	(via
		(at 97.074736 -118.453154)
		(size 0.508)
		(drill 0.254)
		(layers "F.Cu" "B.Cu")
		(net "PWRGD_P12V_MEM_R")
	)
	(via
		(at 187.111894 -121.442734)
		(size 0.4572)
		(drill 0.254)
		(layers "F.Cu" "B.Cu")
		(net "PWRGD_P12V_MEM_R")
	)
	(via
		(at 165.929564 -121.692924)
		(size 0.508)
		(drill 0.254)
		(layers "F.Cu" "B.Cu")
		(net "PWRGD_P12V_MEM_R")
	)
	(segment
		(start 158.535116 -122.185938)
		(end 158.98622 -122.637042)
		(width 0.10668)
		(layer "B.Cu")
		(net "PWRGD_P12V_MEM_R")
	)
	(segment
		(start 135.000746 -117.60327)
		(end 135.990584 -118.593108)
		(width 0.10668)
		(layer "B.Cu")
		(net "PWRGD_P12V_MEM_R")
	)
	(segment
		(start 153.577798 -122.185938)
		(end 158.535116 -122.185938)
		(width 0.10668)
		(layer "B.Cu")
		(net "PWRGD_P12V_MEM_R")
	)
	(segment
		(start 164.883338 -122.637042)
		(end 165.827456 -121.692924)
		(width 0.10668)
		(layer "B.Cu")
		(net "PWRGD_P12V_MEM_R")
	)
	(segment
		(start 158.98622 -122.637042)
		(end 164.883338 -122.637042)
		(width 0.10668)
		(layer "B.Cu")
		(net "PWRGD_P12V_MEM_R")
	)
	(segment
		(start 144.109948 -118.593108)
		(end 149.089364 -123.572524)
		(width 0.10668)
		(layer "B.Cu")
		(net "PWRGD_P12V_MEM_R")
	)
	(segment
		(start 135.990584 -118.593108)
		(end 144.109948 -118.593108)
		(width 0.10668)
		(layer "B.Cu")
		(net "PWRGD_P12V_MEM_R")
	)
	(segment
		(start 97.074736 -118.453154)
		(end 97.243138 -118.453154)
		(width 0.10668)
		(layer "B.Cu")
		(net "PWRGD_P12V_MEM_R")
	)
	(segment
		(start 152.191212 -123.572524)
		(end 153.577798 -122.185938)
		(width 0.10668)
		(layer "B.Cu")
		(net "PWRGD_P12V_MEM_R")
	)
	(segment
		(start 97.243138 -118.453154)
		(end 98.093022 -117.60327)
		(width 0.10668)
		(layer "B.Cu")
		(net "PWRGD_P12V_MEM_R")
	)
	(segment
		(start 165.827456 -121.692924)
		(end 165.929564 -121.692924)
		(width 0.10668)
		(layer "B.Cu")
		(net "PWRGD_P12V_MEM_R")
	)
	(segment
		(start 149.089364 -123.572524)
		(end 152.191212 -123.572524)
		(width 0.10668)
		(layer "B.Cu")
		(net "PWRGD_P12V_MEM_R")
	)
	(segment
		(start 98.093022 -117.60327)
		(end 135.000746 -117.60327)
		(width 0.10668)
		(layer "B.Cu")
		(net "PWRGD_P12V_MEM_R")
	)
	(segment
		(start 187.111894 -121.442734)
		(end 187.05703 -121.442734)
		(width 0.11684)
		(layer "In6.Cu")
		(net "PWRGD_P12V_MEM_R")
	)
	(segment
		(start 187.05703 -121.442734)
		(end 186.65317 -121.846594)
		(width 0.11684)
		(layer "In6.Cu")
		(net "PWRGD_P12V_MEM_R")
	)
	(segment
		(start 166.083234 -121.846594)
		(end 165.929564 -121.692924)
		(width 0.11684)
		(layer "In6.Cu")
		(net "PWRGD_P12V_MEM_R")
	)
	(segment
		(start 186.65317 -121.846594)
		(end 166.083234 -121.846594)
		(width 0.11684)
		(layer "In6.Cu")
		(net "PWRGD_P12V_MEM_R")
	)
	(segment
		(start 97.69475 -124.728478)
		(end 97.69475 -125.54839)
		(width 0.10668)
		(layer "F.Cu")
		(net "PWRGD_P12V_MEM_CPU1_R")
	)
	(segment
		(start 97.69475 -125.54839)
		(end 97.074736 -126.168404)
		(width 0.10668)
		(layer "F.Cu")
		(net "PWRGD_P12V_MEM_CPU1_R")
	)
	(segment
		(start 97.074736 -127.387604)
		(end 97.074736 -126.168404)
		(width 0.10668)
		(layer "F.Cu")
		(net "PWRGD_P12V_MEM_CPU1_R")
	)
	(via
		(at 97.074736 -126.168404)
		(size 0.762)
		(drill 0.381)
		(layers "F.Cu" "B.Cu")
		(net "PWRGD_P12V_MEM_CPU1_R")
	)
	(segment
		(start 106.160062 -123.341892)
		(end 105.809796 -123.341892)
		(width 0.10668)
		(layer "F.Cu")
		(net "PWRGD_P12V_MEM_CPU1_EN_N")
	)
	(segment
		(start 105.659936 -123.192032)
		(end 105.659936 -122.686318)
		(width 0.10668)
		(layer "F.Cu")
		(net "PWRGD_P12V_MEM_CPU1_EN_N")
	)
	(segment
		(start 106.309922 -123.192032)
		(end 106.160062 -123.341892)
		(width 0.10668)
		(layer "F.Cu")
		(net "PWRGD_P12V_MEM_CPU1_EN_N")
	)
	(segment
		(start 105.659936 -119.879618)
		(end 105.659936 -121.098818)
		(width 0.10668)
		(layer "F.Cu")
		(net "PWRGD_P12V_MEM_CPU1_EN_N")
	)
	(segment
		(start 106.309922 -122.686318)
		(end 106.309922 -123.192032)
		(width 0.10668)
		(layer "F.Cu")
		(net "PWRGD_P12V_MEM_CPU1_EN_N")
	)
	(segment
		(start 105.659936 -121.098818)
		(end 105.659936 -122.686318)
		(width 0.10668)
		(layer "F.Cu")
		(net "PWRGD_P12V_MEM_CPU1_EN_N")
	)
	(segment
		(start 105.809796 -123.341892)
		(end 105.659936 -123.192032)
		(width 0.10668)
		(layer "F.Cu")
		(net "PWRGD_P12V_MEM_CPU1_EN_N")
	)
	(via
		(at 105.659936 -121.098818)
		(size 0.762)
		(drill 0.381)
		(layers "F.Cu" "B.Cu")
		(net "PWRGD_P12V_MEM_CPU1_EN_N")
	)
	(segment
		(start 105.659936 -126.148846)
		(end 105.659936 -127.368046)
		(width 0.10668)
		(layer "F.Cu")
		(net "PWRGD_P12V_MEM_CPU1_EN")
	)
	(segment
		(start 105.659936 -126.148846)
		(end 105.659936 -124.561346)
		(width 0.10668)
		(layer "F.Cu")
		(net "PWRGD_P12V_MEM_CPU1_EN")
	)
	(segment
		(start 105.659936 -127.368046)
		(end 106.675936 -127.368046)
		(width 0.10668)
		(layer "F.Cu")
		(net "PWRGD_P12V_MEM_CPU1_EN")
	)
	(via
		(at 105.659936 -126.148846)
		(size 0.762)
		(drill 0.381)
		(layers "F.Cu" "B.Cu")
		(net "PWRGD_P12V_MEM_CPU1_EN")
	)
	(segment
		(start 104.389936 -127.368046)
		(end 104.389936 -126.148846)
		(width 0.10668)
		(layer "F.Cu")
		(net "PWRGD_P12V_MEM_CPU1")
	)
	(segment
		(start 104.389936 -126.148846)
		(end 105.00995 -125.528832)
		(width 0.10668)
		(layer "F.Cu")
		(net "PWRGD_P12V_MEM_CPU1")
	)
	(segment
		(start 105.00995 -125.528832)
		(end 105.00995 -124.561346)
		(width 0.10668)
		(layer "F.Cu")
		(net "PWRGD_P12V_MEM_CPU1")
	)
	(segment
		(start 97.074736 -128.187704)
		(end 97.074736 -128.803654)
		(width 0.10668)
		(layer "F.Cu")
		(net "PWRGD_P12V_MEM_CPU1")
	)
	(via
		(at 97.074736 -128.803654)
		(size 0.508)
		(drill 0.254)
		(layers "F.Cu" "B.Cu")
		(net "PWRGD_P12V_MEM_CPU1")
	)
	(via
		(at 104.389936 -126.148846)
		(size 0.508)
		(drill 0.254)
		(layers "F.Cu" "B.Cu")
		(net "PWRGD_P12V_MEM_CPU1")
	)
	(segment
		(start 104.149906 -126.148846)
		(end 102.907846 -127.390906)
		(width 0.11684)
		(layer "In11.Cu")
		(net "PWRGD_P12V_MEM_CPU1")
	)
	(segment
		(start 102.907846 -127.390906)
		(end 98.487484 -127.390906)
		(width 0.11684)
		(layer "In11.Cu")
		(net "PWRGD_P12V_MEM_CPU1")
	)
	(segment
		(start 98.487484 -127.390906)
		(end 97.074736 -128.803654)
		(width 0.11684)
		(layer "In11.Cu")
		(net "PWRGD_P12V_MEM_CPU1")
	)
	(segment
		(start 104.389936 -126.148846)
		(end 104.149906 -126.148846)
		(width 0.11684)
		(layer "In11.Cu")
		(net "PWRGD_P12V_MEM_CPU1")
	)
	(segment
		(start 98.994722 -124.728478)
		(end 98.994722 -125.54839)
		(width 0.10668)
		(layer "F.Cu")
		(net "PWRGD_P12V_MEM_CPU0_R")
	)
	(segment
		(start 99.614736 -127.387604)
		(end 99.614736 -126.168404)
		(width 0.10668)
		(layer "F.Cu")
		(net "PWRGD_P12V_MEM_CPU0_R")
	)
	(segment
		(start 98.994722 -125.54839)
		(end 99.614736 -126.168404)
		(width 0.10668)
		(layer "F.Cu")
		(net "PWRGD_P12V_MEM_CPU0_R")
	)
	(via
		(at 99.614736 -126.168404)
		(size 0.762)
		(drill 0.381)
		(layers "F.Cu" "B.Cu")
		(net "PWRGD_P12V_MEM_CPU0_R")
	)
	(segment
		(start 102.154736 -121.118376)
		(end 102.154736 -122.705876)
		(width 0.10668)
		(layer "F.Cu")
		(net "PWRGD_P12V_MEM_CPU0_EN_N")
	)
	(segment
		(start 102.154736 -119.899176)
		(end 102.154736 -121.118376)
		(width 0.10668)
		(layer "F.Cu")
		(net "PWRGD_P12V_MEM_CPU0_EN_N")
	)
	(segment
		(start 102.154736 -123.21159)
		(end 102.154736 -122.705876)
		(width 0.10668)
		(layer "F.Cu")
		(net "PWRGD_P12V_MEM_CPU0_EN_N")
	)
	(segment
		(start 102.304596 -123.36145)
		(end 102.154736 -123.21159)
		(width 0.10668)
		(layer "F.Cu")
		(net "PWRGD_P12V_MEM_CPU0_EN_N")
	)
	(segment
		(start 102.654862 -123.36145)
		(end 102.304596 -123.36145)
		(width 0.10668)
		(layer "F.Cu")
		(net "PWRGD_P12V_MEM_CPU0_EN_N")
	)
	(segment
		(start 102.804722 -122.705876)
		(end 102.804722 -123.21159)
		(width 0.10668)
		(layer "F.Cu")
		(net "PWRGD_P12V_MEM_CPU0_EN_N")
	)
	(segment
		(start 102.804722 -123.21159)
		(end 102.654862 -123.36145)
		(width 0.10668)
		(layer "F.Cu")
		(net "PWRGD_P12V_MEM_CPU0_EN_N")
	)
	(via
		(at 102.154736 -121.118376)
		(size 0.762)
		(drill 0.381)
		(layers "F.Cu" "B.Cu")
		(net "PWRGD_P12V_MEM_CPU0_EN_N")
	)
	(segment
		(start 102.154736 -126.168404)
		(end 102.154736 -127.387604)
		(width 0.10668)
		(layer "F.Cu")
		(net "PWRGD_P12V_MEM_CPU0_EN")
	)
	(segment
		(start 102.154736 -127.387604)
		(end 103.170736 -127.387604)
		(width 0.10668)
		(layer "F.Cu")
		(net "PWRGD_P12V_MEM_CPU0_EN")
	)
	(segment
		(start 102.154736 -126.168404)
		(end 102.154736 -124.580904)
		(width 0.10668)
		(layer "F.Cu")
		(net "PWRGD_P12V_MEM_CPU0_EN")
	)
	(via
		(at 102.154736 -126.168404)
		(size 0.762)
		(drill 0.381)
		(layers "F.Cu" "B.Cu")
		(net "PWRGD_P12V_MEM_CPU0_EN")
	)
	(segment
		(start 101.50475 -125.54839)
		(end 101.50475 -124.580904)
		(width 0.10668)
		(layer "F.Cu")
		(net "PWRGD_P12V_MEM_CPU0")
	)
	(segment
		(start 100.884736 -127.387604)
		(end 100.884736 -126.168404)
		(width 0.10668)
		(layer "F.Cu")
		(net "PWRGD_P12V_MEM_CPU0")
	)
	(segment
		(start 100.414836 -127.387604)
		(end 99.614736 -128.187704)
		(width 0.10668)
		(layer "F.Cu")
		(net "PWRGD_P12V_MEM_CPU0")
	)
	(segment
		(start 100.884736 -126.168404)
		(end 101.50475 -125.54839)
		(width 0.10668)
		(layer "F.Cu")
		(net "PWRGD_P12V_MEM_CPU0")
	)
	(segment
		(start 100.884736 -127.387604)
		(end 100.414836 -127.387604)
		(width 0.10668)
		(layer "F.Cu")
		(net "PWRGD_P12V_MEM_CPU0")
	)
	(via
		(at 100.884736 -126.168404)
		(size 0.762)
		(drill 0.381)
		(layers "F.Cu" "B.Cu")
		(net "PWRGD_P12V_MEM_CPU0")
	)
	(segment
		(start 97.074736 -121.088404)
		(end 97.69475 -121.708418)
		(width 0.10668)
		(layer "F.Cu")
		(net "PWRGD_P12V_MEM")
	)
	(segment
		(start 96.058736 -119.869204)
		(end 96.058736 -120.607836)
		(width 0.10668)
		(layer "F.Cu")
		(net "PWRGD_P12V_MEM")
	)
	(segment
		(start 96.058736 -120.607836)
		(end 96.539304 -121.088404)
		(width 0.10668)
		(layer "F.Cu")
		(net "PWRGD_P12V_MEM")
	)
	(segment
		(start 96.539304 -121.088404)
		(end 97.074736 -121.088404)
		(width 0.10668)
		(layer "F.Cu")
		(net "PWRGD_P12V_MEM")
	)
	(segment
		(start 97.69475 -121.708418)
		(end 97.69475 -122.52833)
		(width 0.10668)
		(layer "F.Cu")
		(net "PWRGD_P12V_MEM")
	)
	(via
		(at 97.074736 -121.088404)
		(size 0.762)
		(drill 0.381)
		(layers "F.Cu" "B.Cu")
		(net "PWRGD_P12V_MEM")
	)
	(segment
		(start 196.2912 -128.880362)
		(end 196.76491 -129.354072)
		(width 0.10668)
		(layer "F.Cu")
		(net "PU_SPI_PLD_CS_N")
	)
	(segment
		(start 196.2912 -126.562358)
		(end 196.2912 -128.880362)
		(width 0.10668)
		(layer "F.Cu")
		(net "PU_SPI_PLD_CS_N")
	)
	(segment
		(start 196.76491 -129.354072)
		(end 197.117462 -129.354072)
		(width 0.10668)
		(layer "F.Cu")
		(net "PU_SPI_PLD_CS_N")
	)
	(segment
		(start 197.9676 -130.20421)
		(end 197.9676 -135.35152)
		(width 0.10668)
		(layer "F.Cu")
		(net "PU_SPI_PLD_CS_N")
	)
	(segment
		(start 197.86092 -135.4582)
		(end 197.2056 -135.4582)
		(width 0.10668)
		(layer "F.Cu")
		(net "PU_SPI_PLD_CS_N")
	)
	(segment
		(start 195.543424 -125.814582)
		(end 196.2912 -126.562358)
		(width 0.10668)
		(layer "F.Cu")
		(net "PU_SPI_PLD_CS_N")
	)
	(segment
		(start 196.6976 -133.74878)
		(end 196.117718 -133.168898)
		(width 0.10668)
		(layer "F.Cu")
		(net "PU_SPI_PLD_CS_N")
	)
	(segment
		(start 197.117462 -129.354072)
		(end 197.9676 -130.20421)
		(width 0.10668)
		(layer "F.Cu")
		(net "PU_SPI_PLD_CS_N")
	)
	(segment
		(start 196.117718 -133.168898)
		(end 196.088 -133.168898)
		(width 0.10668)
		(layer "F.Cu")
		(net "PU_SPI_PLD_CS_N")
	)
	(segment
		(start 197.9676 -135.35152)
		(end 197.86092 -135.4582)
		(width 0.10668)
		(layer "F.Cu")
		(net "PU_SPI_PLD_CS_N")
	)
	(segment
		(start 193.922142 -122.65279)
		(end 195.543424 -124.274072)
		(width 0.10668)
		(layer "F.Cu")
		(net "PU_SPI_PLD_CS_N")
	)
	(segment
		(start 196.6976 -134.9502)
		(end 196.6976 -133.74878)
		(width 0.10668)
		(layer "F.Cu")
		(net "PU_SPI_PLD_CS_N")
	)
	(segment
		(start 195.543424 -124.274072)
		(end 195.543424 -125.814582)
		(width 0.10668)
		(layer "F.Cu")
		(net "PU_SPI_PLD_CS_N")
	)
	(segment
		(start 197.2056 -135.4582)
		(end 196.6976 -134.9502)
		(width 0.10668)
		(layer "F.Cu")
		(net "PU_SPI_PLD_CS_N")
	)
	(via
		(at 197.2056 -135.4582)
		(size 0.762)
		(drill 0.381)
		(layers "F.Cu" "B.Cu")
		(net "PU_SPI_PLD_CS_N")
	)
	(segment
		(start 411.870144 -139.58316)
		(end 411.521148 -139.58316)
		(width 0.10668)
		(layer "F.Cu")
		(net "P5V_AUX_EN")
	)
	(segment
		(start 409.655264 -137.334498)
		(end 407.841958 -137.334498)
		(width 0.10668)
		(layer "F.Cu")
		(net "P5V_AUX_EN")
	)
	(segment
		(start 409.878276 -137.55751)
		(end 409.655264 -137.334498)
		(width 0.10668)
		(layer "F.Cu")
		(net "P5V_AUX_EN")
	)
	(segment
		(start 409.878276 -137.940288)
		(end 409.878276 -137.854182)
		(width 0.10668)
		(layer "F.Cu")
		(net "P5V_AUX_EN")
	)
	(segment
		(start 409.878276 -137.854182)
		(end 409.878276 -137.55751)
		(width 0.10668)
		(layer "F.Cu")
		(net "P5V_AUX_EN")
	)
	(segment
		(start 411.521148 -139.58316)
		(end 409.878276 -137.940288)
		(width 0.10668)
		(layer "F.Cu")
		(net "P5V_AUX_EN")
	)
	(segment
		(start 407.841958 -137.334498)
		(end 407.731214 -137.445242)
		(width 0.10668)
		(layer "F.Cu")
		(net "P5V_AUX_EN")
	)
	(via
		(at 407.731214 -137.445242)
		(size 0.762)
		(drill 0.381)
		(layers "F.Cu" "B.Cu")
		(net "P5V_AUX_EN")
	)
	(segment
		(start 306.941474 -32.701992)
		(end 307.728874 -32.701992)
		(width 0.508)
		(layer "F.Cu")
		(net "P3V3_STBY_R")
	)
	(segment
		(start 306.154074 -32.701992)
		(end 306.941474 -32.701992)
		(width 0.508)
		(layer "F.Cu")
		(net "P3V3_STBY_R")
	)
	(via
		(at 306.941474 -32.701992)
		(size 0.508)
		(drill 0.254)
		(layers "F.Cu" "B.Cu")
		(net "P3V3_STBY_R")
	)
	(segment
		(start 324.094856 -24.226266)
		(end 324.094856 -23.039324)
		(width 0.10668)
		(layer "F.Cu")
		(net "P3V3_RTC_AUX_R")
	)
	(segment
		(start 324.094856 -23.039324)
		(end 324.099174 -23.035006)
		(width 0.10668)
		(layer "F.Cu")
		(net "P3V3_RTC_AUX_R")
	)
	(segment
		(start 325.314056 -24.226266)
		(end 324.094856 -24.226266)
		(width 0.10668)
		(layer "F.Cu")
		(net "P3V3_RTC_AUX_R")
	)
	(via
		(at 324.094856 -24.226266)
		(size 0.762)
		(drill 0.381)
		(layers "F.Cu" "B.Cu")
		(net "P3V3_RTC_AUX_R")
	)
	(segment
		(start 326.330056 -22.417786)
		(end 326.00011 -22.08784)
		(width 0.10668)
		(layer "F.Cu")
		(net "P1V5_BAT_OUT_R")
	)
	(segment
		(start 326.330056 -23.426166)
		(end 326.330056 -22.417786)
		(width 0.10668)
		(layer "F.Cu")
		(net "P1V5_BAT_OUT_R")
	)
	(segment
		(start 326.330056 -23.426166)
		(end 325.314056 -23.426166)
		(width 0.10668)
		(layer "F.Cu")
		(net "P1V5_BAT_OUT_R")
	)
	(segment
		(start 326.495918 -21.592032)
		(end 326.00011 -22.08784)
		(width 0.10668)
		(layer "F.Cu")
		(net "P1V5_BAT_OUT_R")
	)
	(segment
		(start 328.07529 -21.592032)
		(end 326.495918 -21.592032)
		(width 0.10668)
		(layer "F.Cu")
		(net "P1V5_BAT_OUT_R")
	)
	(segment
		(start 330.057506 -23.574248)
		(end 328.07529 -21.592032)
		(width 0.10668)
		(layer "F.Cu")
		(net "P1V5_BAT_OUT_R")
	)
	(via
		(at 326.00011 -22.08784)
		(size 0.762)
		(drill 0.381)
		(layers "F.Cu" "B.Cu")
		(net "P1V5_BAT_OUT_R")
	)
	(segment
		(start 299.79112 -25.601422)
		(end 300.253654 -25.601422)
		(width 0.10668)
		(layer "F.Cu")
		(net "P1V5_BAT_IN")
	)
	(segment
		(start 299.622464 -25.432766)
		(end 299.79112 -25.601422)
		(width 0.10668)
		(layer "F.Cu")
		(net "P1V5_BAT_IN")
	)
	(segment
		(start 300.253654 -25.601422)
		(end 300.5328 -25.322276)
		(width 0.10668)
		(layer "F.Cu")
		(net "P1V5_BAT_IN")
	)
	(segment
		(start 297.650916 -22.747224)
		(end 297.650916 -23.763224)
		(width 0.10668)
		(layer "F.Cu")
		(net "P1V5_BAT_IN")
	)
	(segment
		(start 297.650916 -21.205952)
		(end 297.650916 -22.747224)
		(width 0.10668)
		(layer "F.Cu")
		(net "P1V5_BAT_IN")
	)
	(segment
		(start 301.943008 -26.272236)
		(end 300.993048 -25.322276)
		(width 0.10668)
		(layer "F.Cu")
		(net "P1V5_BAT_IN")
	)
	(segment
		(start 297.650916 -24.172164)
		(end 297.650916 -23.763224)
		(width 0.10668)
		(layer "F.Cu")
		(net "P1V5_BAT_IN")
	)
	(segment
		(start 300.5328 -25.322276)
		(end 300.993048 -25.322276)
		(width 0.10668)
		(layer "F.Cu")
		(net "P1V5_BAT_IN")
	)
	(segment
		(start 299.622464 -24.349456)
		(end 299.622464 -25.432766)
		(width 0.10668)
		(layer "F.Cu")
		(net "P1V5_BAT_IN")
	)
	(segment
		(start 299.622464 -24.349456)
		(end 297.828208 -24.349456)
		(width 0.10668)
		(layer "F.Cu")
		(net "P1V5_BAT_IN")
	)
	(segment
		(start 303.831498 -26.272236)
		(end 301.943008 -26.272236)
		(width 0.10668)
		(layer "F.Cu")
		(net "P1V5_BAT_IN")
	)
	(segment
		(start 297.828208 -24.349456)
		(end 297.650916 -24.172164)
		(width 0.10668)
		(layer "F.Cu")
		(net "P1V5_BAT_IN")
	)
	(via
		(at 299.79112 -25.601422)
		(size 0.762)
		(drill 0.381)
		(layers "F.Cu" "B.Cu")
		(net "P1V5_BAT_IN")
	)
	(segment
		(start 176.072038 -192.235328)
		(end 177.215038 -192.235328)
		(width 0.4572)
		(layer "F.Cu")
		(net "P12V_MEM_CPU1")
	)
	(segment
		(start 59.428126 -192.235328)
		(end 60.571126 -192.235328)
		(width 0.4572)
		(layer "F.Cu")
		(net "P12V_MEM_CPU1")
	)
	(segment
		(start 179.516024 -193.085212)
		(end 178.373024 -193.085212)
		(width 0.4572)
		(layer "F.Cu")
		(net "P12V_MEM_CPU1")
	)
	(segment
		(start 164.427916 -193.085212)
		(end 163.284916 -193.085212)
		(width 0.4572)
		(layer "F.Cu")
		(net "P12V_MEM_CPU1")
	)
	(segment
		(start 25.152096 -192.235328)
		(end 24.009096 -192.235328)
		(width 0.4572)
		(layer "F.Cu")
		(net "P12V_MEM_CPU1")
	)
	(segment
		(start 55.328058 -192.235328)
		(end 54.185058 -192.235328)
		(width 0.4572)
		(layer "F.Cu")
		(net "P12V_MEM_CPU1")
	)
	(segment
		(start 206.248 -192.235328)
		(end 207.391 -192.235328)
		(width 0.4572)
		(layer "F.Cu")
		(net "P12V_MEM_CPU1")
	)
	(segment
		(start 40.23995 -193.085212)
		(end 39.09695 -193.085212)
		(width 0.4572)
		(layer "F.Cu")
		(net "P12V_MEM_CPU1")
	)
	(segment
		(start 194.604132 -193.085212)
		(end 193.461132 -193.085212)
		(width 0.4572)
		(layer "F.Cu")
		(net "P12V_MEM_CPU1")
	)
	(segment
		(start 44.340018 -192.235328)
		(end 45.483018 -192.235328)
		(width 0.4572)
		(layer "F.Cu")
		(net "P12V_MEM_CPU1")
	)
	(segment
		(start 171.97197 -193.085212)
		(end 170.82897 -193.085212)
		(width 0.4572)
		(layer "F.Cu")
		(net "P12V_MEM_CPU1")
	)
	(segment
		(start 51.884072 -192.235328)
		(end 53.027072 -192.235328)
		(width 0.4572)
		(layer "F.Cu")
		(net "P12V_MEM_CPU1")
	)
	(segment
		(start 168.527984 -192.235328)
		(end 169.670984 -192.235328)
		(width 0.4572)
		(layer "F.Cu")
		(net "P12V_MEM_CPU1")
	)
	(segment
		(start 17.608042 -193.085212)
		(end 16.465042 -193.085212)
		(width 0.4572)
		(layer "F.Cu")
		(net "P12V_MEM_CPU1")
	)
	(segment
		(start 202.147932 -192.235328)
		(end 201.004932 -192.235328)
		(width 0.4572)
		(layer "F.Cu")
		(net "P12V_MEM_CPU1")
	)
	(segment
		(start 32.695896 -192.235328)
		(end 31.552896 -192.235328)
		(width 0.4572)
		(layer "F.Cu")
		(net "P12V_MEM_CPU1")
	)
	(segment
		(start 191.160146 -192.235328)
		(end 192.303146 -192.235328)
		(width 0.4572)
		(layer "F.Cu")
		(net "P12V_MEM_CPU1")
	)
	(segment
		(start 47.784004 -193.085212)
		(end 46.641004 -193.085212)
		(width 0.4572)
		(layer "F.Cu")
		(net "P12V_MEM_CPU1")
	)
	(segment
		(start 25.152096 -193.085212)
		(end 24.009096 -193.085212)
		(width 0.4572)
		(layer "F.Cu")
		(net "P12V_MEM_CPU1")
	)
	(segment
		(start 29.252164 -192.235328)
		(end 30.395164 -192.235328)
		(width 0.4572)
		(layer "F.Cu")
		(net "P12V_MEM_CPU1")
	)
	(segment
		(start 199.8472 -192.235328)
		(end 198.7042 -192.235328)
		(width 0.4572)
		(layer "F.Cu")
		(net "P12V_MEM_CPU1")
	)
	(segment
		(start 183.616092 -192.235328)
		(end 184.759092 -192.235328)
		(width 0.4572)
		(layer "F.Cu")
		(net "P12V_MEM_CPU1")
	)
	(segment
		(start 55.328058 -193.085212)
		(end 54.185058 -193.085212)
		(width 0.4572)
		(layer "F.Cu")
		(net "P12V_MEM_CPU1")
	)
	(segment
		(start 21.70811 -192.235328)
		(end 22.85111 -192.235328)
		(width 0.4572)
		(layer "F.Cu")
		(net "P12V_MEM_CPU1")
	)
	(segment
		(start 171.97197 -192.235328)
		(end 170.82897 -192.235328)
		(width 0.4572)
		(layer "F.Cu")
		(net "P12V_MEM_CPU1")
	)
	(segment
		(start 179.516024 -192.235328)
		(end 178.373024 -192.235328)
		(width 0.4572)
		(layer "F.Cu")
		(net "P12V_MEM_CPU1")
	)
	(segment
		(start 36.795964 -192.235328)
		(end 37.938964 -192.235328)
		(width 0.4572)
		(layer "F.Cu")
		(net "P12V_MEM_CPU1")
	)
	(segment
		(start 17.608042 -192.235328)
		(end 16.465042 -192.235328)
		(width 0.4572)
		(layer "F.Cu")
		(net "P12V_MEM_CPU1")
	)
	(segment
		(start 106.675936 -128.168146)
		(end 106.675936 -129.032)
		(width 0.4572)
		(layer "F.Cu")
		(net "P12V_MEM_CPU1")
	)
	(segment
		(start 164.427916 -192.235328)
		(end 163.284916 -192.235328)
		(width 0.4572)
		(layer "F.Cu")
		(net "P12V_MEM_CPU1")
	)
	(segment
		(start 194.604132 -192.235328)
		(end 193.461132 -192.235328)
		(width 0.4572)
		(layer "F.Cu")
		(net "P12V_MEM_CPU1")
	)
	(segment
		(start 202.147932 -193.085212)
		(end 201.004932 -193.085212)
		(width 0.4572)
		(layer "F.Cu")
		(net "P12V_MEM_CPU1")
	)
	(segment
		(start 32.695896 -193.085212)
		(end 31.552896 -193.085212)
		(width 0.4572)
		(layer "F.Cu")
		(net "P12V_MEM_CPU1")
	)
	(segment
		(start 47.784004 -192.235328)
		(end 46.641004 -192.235328)
		(width 0.4572)
		(layer "F.Cu")
		(net "P12V_MEM_CPU1")
	)
	(segment
		(start 187.060078 -193.085212)
		(end 185.917078 -193.085212)
		(width 0.4572)
		(layer "F.Cu")
		(net "P12V_MEM_CPU1")
	)
	(segment
		(start 187.060078 -192.235328)
		(end 185.917078 -192.235328)
		(width 0.4572)
		(layer "F.Cu")
		(net "P12V_MEM_CPU1")
	)
	(segment
		(start 40.23995 -192.235328)
		(end 39.09695 -192.235328)
		(width 0.4572)
		(layer "F.Cu")
		(net "P12V_MEM_CPU1")
	)
	(via
		(at 22.85111 -192.235328)
		(size 0.4826)
		(drill 0.254)
		(layers "F.Cu" "B.Cu")
		(net "P12V_MEM_CPU1")
	)
	(via
		(at 177.215038 -192.235328)
		(size 0.4826)
		(drill 0.254)
		(layers "F.Cu" "B.Cu")
		(net "P12V_MEM_CPU1")
	)
	(via
		(at 201.004932 -192.235328)
		(size 0.4826)
		(drill 0.254)
		(layers "F.Cu" "B.Cu")
		(net "P12V_MEM_CPU1")
	)
	(via
		(at 31.49092 -182.87492)
		(size 0.508)
		(drill 0.254)
		(layers "F.Cu" "B.Cu")
		(net "P12V_MEM_CPU1")
	)
	(via
		(at 30.85592 -181.60492)
		(size 0.508)
		(drill 0.254)
		(layers "F.Cu" "B.Cu")
		(net "P12V_MEM_CPU1")
	)
	(via
		(at 54.185058 -192.235328)
		(size 0.4826)
		(drill 0.254)
		(layers "F.Cu" "B.Cu")
		(net "P12V_MEM_CPU1")
	)
	(via
		(at 112.888014 -143.649446)
		(size 0.508)
		(drill 0.254)
		(layers "F.Cu" "B.Cu")
		(net "P12V_MEM_CPU1")
	)
	(via
		(at 170.82897 -193.085212)
		(size 0.4826)
		(drill 0.254)
		(layers "F.Cu" "B.Cu")
		(net "P12V_MEM_CPU1")
	)
	(via
		(at 30.85592 -183.50992)
		(size 0.508)
		(drill 0.254)
		(layers "F.Cu" "B.Cu")
		(net "P12V_MEM_CPU1")
	)
	(via
		(at 31.49092 -183.50992)
		(size 0.508)
		(drill 0.254)
		(layers "F.Cu" "B.Cu")
		(net "P12V_MEM_CPU1")
	)
	(via
		(at 30.395164 -192.235328)
		(size 0.4826)
		(drill 0.254)
		(layers "F.Cu" "B.Cu")
		(net "P12V_MEM_CPU1")
	)
	(via
		(at 30.22092 -182.23992)
		(size 0.508)
		(drill 0.254)
		(layers "F.Cu" "B.Cu")
		(net "P12V_MEM_CPU1")
	)
	(via
		(at 199.8472 -192.235328)
		(size 0.4826)
		(drill 0.254)
		(layers "F.Cu" "B.Cu")
		(net "P12V_MEM_CPU1")
	)
	(via
		(at 29.58592 -182.23992)
		(size 0.508)
		(drill 0.254)
		(layers "F.Cu" "B.Cu")
		(net "P12V_MEM_CPU1")
	)
	(via
		(at 54.185058 -193.085212)
		(size 0.4826)
		(drill 0.254)
		(layers "F.Cu" "B.Cu")
		(net "P12V_MEM_CPU1")
	)
	(via
		(at 193.461132 -192.235328)
		(size 0.4826)
		(drill 0.254)
		(layers "F.Cu" "B.Cu")
		(net "P12V_MEM_CPU1")
	)
	(via
		(at 39.09695 -192.235328)
		(size 0.4826)
		(drill 0.254)
		(layers "F.Cu" "B.Cu")
		(net "P12V_MEM_CPU1")
	)
	(via
		(at 30.22092 -182.87492)
		(size 0.508)
		(drill 0.254)
		(layers "F.Cu" "B.Cu")
		(net "P12V_MEM_CPU1")
	)
	(via
		(at 46.641004 -193.085212)
		(size 0.4826)
		(drill 0.254)
		(layers "F.Cu" "B.Cu")
		(net "P12V_MEM_CPU1")
	)
	(via
		(at 163.284916 -193.085212)
		(size 0.4826)
		(drill 0.254)
		(layers "F.Cu" "B.Cu")
		(net "P12V_MEM_CPU1")
	)
	(via
		(at 178.373024 -193.085212)
		(size 0.4826)
		(drill 0.254)
		(layers "F.Cu" "B.Cu")
		(net "P12V_MEM_CPU1")
	)
	(via
		(at 30.22092 -183.50992)
		(size 0.508)
		(drill 0.254)
		(layers "F.Cu" "B.Cu")
		(net "P12V_MEM_CPU1")
	)
	(via
		(at 29.58592 -181.60492)
		(size 0.508)
		(drill 0.254)
		(layers "F.Cu" "B.Cu")
		(net "P12V_MEM_CPU1")
	)
	(via
		(at 193.461132 -193.085212)
		(size 0.4826)
		(drill 0.254)
		(layers "F.Cu" "B.Cu")
		(net "P12V_MEM_CPU1")
	)
	(via
		(at 192.303146 -192.235328)
		(size 0.4826)
		(drill 0.254)
		(layers "F.Cu" "B.Cu")
		(net "P12V_MEM_CPU1")
	)
	(via
		(at 28.95092 -182.87492)
		(size 0.508)
		(drill 0.254)
		(layers "F.Cu" "B.Cu")
		(net "P12V_MEM_CPU1")
	)
	(via
		(at 30.85592 -182.23992)
		(size 0.508)
		(drill 0.254)
		(layers "F.Cu" "B.Cu")
		(net "P12V_MEM_CPU1")
	)
	(via
		(at 163.284916 -192.235328)
		(size 0.4826)
		(drill 0.254)
		(layers "F.Cu" "B.Cu")
		(net "P12V_MEM_CPU1")
	)
	(via
		(at 170.82897 -192.235328)
		(size 0.4826)
		(drill 0.254)
		(layers "F.Cu" "B.Cu")
		(net "P12V_MEM_CPU1")
	)
	(via
		(at 31.49092 -182.23992)
		(size 0.508)
		(drill 0.254)
		(layers "F.Cu" "B.Cu")
		(net "P12V_MEM_CPU1")
	)
	(via
		(at 30.22092 -181.60492)
		(size 0.508)
		(drill 0.254)
		(layers "F.Cu" "B.Cu")
		(net "P12V_MEM_CPU1")
	)
	(via
		(at 28.95092 -182.23992)
		(size 0.508)
		(drill 0.254)
		(layers "F.Cu" "B.Cu")
		(net "P12V_MEM_CPU1")
	)
	(via
		(at 37.938964 -192.235328)
		(size 0.4826)
		(drill 0.254)
		(layers "F.Cu" "B.Cu")
		(net "P12V_MEM_CPU1")
	)
	(via
		(at 46.641004 -192.235328)
		(size 0.4826)
		(drill 0.254)
		(layers "F.Cu" "B.Cu")
		(net "P12V_MEM_CPU1")
	)
	(via
		(at 45.483018 -192.235328)
		(size 0.4826)
		(drill 0.254)
		(layers "F.Cu" "B.Cu")
		(net "P12V_MEM_CPU1")
	)
	(via
		(at 185.917078 -192.235328)
		(size 0.4826)
		(drill 0.254)
		(layers "F.Cu" "B.Cu")
		(net "P12V_MEM_CPU1")
	)
	(via
		(at 185.917078 -193.085212)
		(size 0.4826)
		(drill 0.254)
		(layers "F.Cu" "B.Cu")
		(net "P12V_MEM_CPU1")
	)
	(via
		(at 169.670984 -192.235328)
		(size 0.4826)
		(drill 0.254)
		(layers "F.Cu" "B.Cu")
		(net "P12V_MEM_CPU1")
	)
	(via
		(at 24.009096 -192.235328)
		(size 0.4826)
		(drill 0.254)
		(layers "F.Cu" "B.Cu")
		(net "P12V_MEM_CPU1")
	)
	(via
		(at 30.85592 -182.87492)
		(size 0.508)
		(drill 0.254)
		(layers "F.Cu" "B.Cu")
		(net "P12V_MEM_CPU1")
	)
	(via
		(at 178.373024 -192.235328)
		(size 0.4826)
		(drill 0.254)
		(layers "F.Cu" "B.Cu")
		(net "P12V_MEM_CPU1")
	)
	(via
		(at 16.465042 -193.085212)
		(size 0.4826)
		(drill 0.254)
		(layers "F.Cu" "B.Cu")
		(net "P12V_MEM_CPU1")
	)
	(via
		(at 29.58592 -183.50992)
		(size 0.508)
		(drill 0.254)
		(layers "F.Cu" "B.Cu")
		(net "P12V_MEM_CPU1")
	)
	(via
		(at 39.09695 -193.085212)
		(size 0.4826)
		(drill 0.254)
		(layers "F.Cu" "B.Cu")
		(net "P12V_MEM_CPU1")
	)
	(via
		(at 184.759092 -192.235328)
		(size 0.4826)
		(drill 0.254)
		(layers "F.Cu" "B.Cu")
		(net "P12V_MEM_CPU1")
	)
	(via
		(at 16.465042 -192.235328)
		(size 0.4826)
		(drill 0.254)
		(layers "F.Cu" "B.Cu")
		(net "P12V_MEM_CPU1")
	)
	(via
		(at 31.552896 -192.235328)
		(size 0.4826)
		(drill 0.254)
		(layers "F.Cu" "B.Cu")
		(net "P12V_MEM_CPU1")
	)
	(via
		(at 201.004932 -193.085212)
		(size 0.4826)
		(drill 0.254)
		(layers "F.Cu" "B.Cu")
		(net "P12V_MEM_CPU1")
	)
	(via
		(at 28.95092 -183.50992)
		(size 0.508)
		(drill 0.254)
		(layers "F.Cu" "B.Cu")
		(net "P12V_MEM_CPU1")
	)
	(via
		(at 31.49092 -181.60492)
		(size 0.508)
		(drill 0.254)
		(layers "F.Cu" "B.Cu")
		(net "P12V_MEM_CPU1")
	)
	(via
		(at 24.009096 -193.085212)
		(size 0.4826)
		(drill 0.254)
		(layers "F.Cu" "B.Cu")
		(net "P12V_MEM_CPU1")
	)
	(via
		(at 29.58592 -182.87492)
		(size 0.508)
		(drill 0.254)
		(layers "F.Cu" "B.Cu")
		(net "P12V_MEM_CPU1")
	)
	(via
		(at 28.95092 -181.60492)
		(size 0.508)
		(drill 0.254)
		(layers "F.Cu" "B.Cu")
		(net "P12V_MEM_CPU1")
	)
	(via
		(at 106.675936 -129.032)
		(size 0.508)
		(drill 0.254)
		(layers "F.Cu" "B.Cu")
		(net "P12V_MEM_CPU1")
	)
	(via
		(at 60.571126 -192.235328)
		(size 0.4826)
		(drill 0.254)
		(layers "F.Cu" "B.Cu")
		(net "P12V_MEM_CPU1")
	)
	(via
		(at 53.027072 -192.235328)
		(size 0.4826)
		(drill 0.254)
		(layers "F.Cu" "B.Cu")
		(net "P12V_MEM_CPU1")
	)
	(via
		(at 207.391 -192.235328)
		(size 0.4826)
		(drill 0.254)
		(layers "F.Cu" "B.Cu")
		(net "P12V_MEM_CPU1")
	)
	(via
		(at 31.552896 -193.085212)
		(size 0.4826)
		(drill 0.254)
		(layers "F.Cu" "B.Cu")
		(net "P12V_MEM_CPU1")
	)
	(segment
		(start 112.888014 -143.649446)
		(end 112.888014 -135.73379)
		(width 0.4572)
		(layer "In4.Cu")
		(net "P12V_MEM_CPU1")
	)
	(segment
		(start 106.675936 -129.521712)
		(end 106.675936 -129.032)
		(width 0.4572)
		(layer "In4.Cu")
		(net "P12V_MEM_CPU1")
	)
	(segment
		(start 112.888014 -135.73379)
		(end 106.675936 -129.521712)
		(width 0.4572)
		(layer "In4.Cu")
		(net "P12V_MEM_CPU1")
	)
	(segment
		(start 435.000146 -192.235074)
		(end 433.857146 -192.235074)
		(width 0.4572)
		(layer "F.Cu")
		(net "P12V_MEM_CPU0")
	)
	(segment
		(start 431.55616 -192.235074)
		(end 432.69916 -192.235074)
		(width 0.4572)
		(layer "F.Cu")
		(net "P12V_MEM_CPU0")
	)
	(segment
		(start 454.188068 -192.235074)
		(end 455.331068 -192.235074)
		(width 0.4572)
		(layer "F.Cu")
		(net "P12V_MEM_CPU0")
	)
	(segment
		(start 419.912038 -192.235074)
		(end 418.769038 -192.235074)
		(width 0.4572)
		(layer "F.Cu")
		(net "P12V_MEM_CPU0")
	)
	(segment
		(start 103.170736 -128.187704)
		(end 103.170736 -129.0066)
		(width 0.4572)
		(layer "F.Cu")
		(net "P12V_MEM_CPU0")
	)
	(segment
		(start 265.54811 -192.235074)
		(end 264.40511 -192.235074)
		(width 0.4572)
		(layer "F.Cu")
		(net "P12V_MEM_CPU0")
	)
	(segment
		(start 303.268126 -192.235074)
		(end 302.125126 -192.235074)
		(width 0.4572)
		(layer "F.Cu")
		(net "P12V_MEM_CPU0")
	)
	(segment
		(start 299.82414 -192.235074)
		(end 300.96714 -192.235074)
		(width 0.4572)
		(layer "F.Cu")
		(net "P12V_MEM_CPU0")
	)
	(segment
		(start 412.367984 -192.235074)
		(end 411.224984 -192.235074)
		(width 0.4572)
		(layer "F.Cu")
		(net "P12V_MEM_CPU0")
	)
	(segment
		(start 308.050946 -192.235074)
		(end 307.368194 -192.235074)
		(width 0.4572)
		(layer "F.Cu")
		(net "P12V_MEM_CPU0")
	)
	(segment
		(start 412.367984 -193.084958)
		(end 411.224984 -193.084958)
		(width 0.4572)
		(layer "F.Cu")
		(net "P12V_MEM_CPU0")
	)
	(segment
		(start 284.736032 -192.235074)
		(end 285.879032 -192.235074)
		(width 0.4572)
		(layer "F.Cu")
		(net "P12V_MEM_CPU0")
	)
	(segment
		(start 303.268126 -193.084958)
		(end 302.125126 -193.084958)
		(width 0.4572)
		(layer "F.Cu")
		(net "P12V_MEM_CPU0")
	)
	(segment
		(start 269.648178 -192.235074)
		(end 270.791178 -192.235074)
		(width 0.4572)
		(layer "F.Cu")
		(net "P12V_MEM_CPU0")
	)
	(segment
		(start 280.635964 -192.235074)
		(end 279.492964 -192.235074)
		(width 0.4572)
		(layer "F.Cu")
		(net "P12V_MEM_CPU0")
	)
	(segment
		(start 416.468052 -192.235074)
		(end 417.611052 -192.235074)
		(width 0.4572)
		(layer "F.Cu")
		(net "P12V_MEM_CPU0")
	)
	(segment
		(start 277.192232 -192.235074)
		(end 278.335232 -192.235074)
		(width 0.4572)
		(layer "F.Cu")
		(net "P12V_MEM_CPU0")
	)
	(segment
		(start 280.635964 -193.084958)
		(end 279.492964 -193.084958)
		(width 0.4572)
		(layer "F.Cu")
		(net "P12V_MEM_CPU0")
	)
	(segment
		(start 450.088 -192.235074)
		(end 448.945 -192.235074)
		(width 0.4572)
		(layer "F.Cu")
		(net "P12V_MEM_CPU0")
	)
	(segment
		(start 288.180018 -193.084958)
		(end 287.037018 -193.084958)
		(width 0.4572)
		(layer "F.Cu")
		(net "P12V_MEM_CPU0")
	)
	(segment
		(start 427.456092 -193.084958)
		(end 426.313092 -193.084958)
		(width 0.4572)
		(layer "F.Cu")
		(net "P12V_MEM_CPU0")
	)
	(segment
		(start 273.092164 -193.084958)
		(end 271.949164 -193.084958)
		(width 0.4572)
		(layer "F.Cu")
		(net "P12V_MEM_CPU0")
	)
	(segment
		(start 295.724072 -193.084958)
		(end 294.581072 -193.084958)
		(width 0.4572)
		(layer "F.Cu")
		(net "P12V_MEM_CPU0")
	)
	(segment
		(start 442.5442 -193.084958)
		(end 441.4012 -193.084958)
		(width 0.4572)
		(layer "F.Cu")
		(net "P12V_MEM_CPU0")
	)
	(segment
		(start 273.092164 -192.235074)
		(end 271.949164 -192.235074)
		(width 0.4572)
		(layer "F.Cu")
		(net "P12V_MEM_CPU0")
	)
	(segment
		(start 450.088 -193.084958)
		(end 448.945 -193.084958)
		(width 0.4572)
		(layer "F.Cu")
		(net "P12V_MEM_CPU0")
	)
	(segment
		(start 442.5442 -192.235074)
		(end 441.4012 -192.235074)
		(width 0.4572)
		(layer "F.Cu")
		(net "P12V_MEM_CPU0")
	)
	(segment
		(start 295.724072 -192.235074)
		(end 294.581072 -192.235074)
		(width 0.4572)
		(layer "F.Cu")
		(net "P12V_MEM_CPU0")
	)
	(segment
		(start 288.180018 -192.235074)
		(end 287.037018 -192.235074)
		(width 0.4572)
		(layer "F.Cu")
		(net "P12V_MEM_CPU0")
	)
	(segment
		(start 435.000146 -193.084958)
		(end 433.857146 -193.084958)
		(width 0.4572)
		(layer "F.Cu")
		(net "P12V_MEM_CPU0")
	)
	(segment
		(start 424.012106 -192.235074)
		(end 425.155106 -192.235074)
		(width 0.4572)
		(layer "F.Cu")
		(net "P12V_MEM_CPU0")
	)
	(segment
		(start 308.5084 -192.928748)
		(end 308.5084 -192.692528)
		(width 0.4572)
		(layer "F.Cu")
		(net "P12V_MEM_CPU0")
	)
	(segment
		(start 439.100214 -192.235074)
		(end 440.243214 -192.235074)
		(width 0.4572)
		(layer "F.Cu")
		(net "P12V_MEM_CPU0")
	)
	(segment
		(start 419.912038 -193.084958)
		(end 418.769038 -193.084958)
		(width 0.4572)
		(layer "F.Cu")
		(net "P12V_MEM_CPU0")
	)
	(segment
		(start 427.456092 -192.235074)
		(end 426.313092 -192.235074)
		(width 0.4572)
		(layer "F.Cu")
		(net "P12V_MEM_CPU0")
	)
	(segment
		(start 446.644268 -192.235074)
		(end 447.787268 -192.235074)
		(width 0.4572)
		(layer "F.Cu")
		(net "P12V_MEM_CPU0")
	)
	(segment
		(start 292.280086 -192.235074)
		(end 293.423086 -192.235074)
		(width 0.4572)
		(layer "F.Cu")
		(net "P12V_MEM_CPU0")
	)
	(segment
		(start 308.5084 -192.692528)
		(end 308.050946 -192.235074)
		(width 0.4572)
		(layer "F.Cu")
		(net "P12V_MEM_CPU0")
	)
	(segment
		(start 265.54811 -193.084958)
		(end 264.40511 -193.084958)
		(width 0.4572)
		(layer "F.Cu")
		(net "P12V_MEM_CPU0")
	)
	(via
		(at 279.492964 -192.235074)
		(size 0.4826)
		(drill 0.254)
		(layers "F.Cu" "B.Cu")
		(net "P12V_MEM_CPU0")
	)
	(via
		(at 444.24346 -180.05806)
		(size 0.508)
		(drill 0.254)
		(layers "F.Cu" "B.Cu")
		(net "P12V_MEM_CPU0")
	)
	(via
		(at 442.97346 -180.69306)
		(size 0.508)
		(drill 0.254)
		(layers "F.Cu" "B.Cu")
		(net "P12V_MEM_CPU0")
	)
	(via
		(at 444.87846 -179.42306)
		(size 0.508)
		(drill 0.254)
		(layers "F.Cu" "B.Cu")
		(net "P12V_MEM_CPU0")
	)
	(via
		(at 300.96714 -192.235074)
		(size 0.4826)
		(drill 0.254)
		(layers "F.Cu" "B.Cu")
		(net "P12V_MEM_CPU0")
	)
	(via
		(at 279.492964 -193.084958)
		(size 0.4826)
		(drill 0.254)
		(layers "F.Cu" "B.Cu")
		(net "P12V_MEM_CPU0")
	)
	(via
		(at 445.51346 -181.32806)
		(size 0.508)
		(drill 0.254)
		(layers "F.Cu" "B.Cu")
		(net "P12V_MEM_CPU0")
	)
	(via
		(at 442.97346 -180.05806)
		(size 0.508)
		(drill 0.254)
		(layers "F.Cu" "B.Cu")
		(net "P12V_MEM_CPU0")
	)
	(via
		(at 287.037018 -193.084958)
		(size 0.4826)
		(drill 0.254)
		(layers "F.Cu" "B.Cu")
		(net "P12V_MEM_CPU0")
	)
	(via
		(at 285.879032 -192.235074)
		(size 0.4826)
		(drill 0.254)
		(layers "F.Cu" "B.Cu")
		(net "P12V_MEM_CPU0")
	)
	(via
		(at 443.60846 -180.05806)
		(size 0.508)
		(drill 0.254)
		(layers "F.Cu" "B.Cu")
		(net "P12V_MEM_CPU0")
	)
	(via
		(at 411.224984 -193.084958)
		(size 0.4826)
		(drill 0.254)
		(layers "F.Cu" "B.Cu")
		(net "P12V_MEM_CPU0")
	)
	(via
		(at 433.857146 -192.235074)
		(size 0.4826)
		(drill 0.254)
		(layers "F.Cu" "B.Cu")
		(net "P12V_MEM_CPU0")
	)
	(via
		(at 443.60846 -181.32806)
		(size 0.508)
		(drill 0.254)
		(layers "F.Cu" "B.Cu")
		(net "P12V_MEM_CPU0")
	)
	(via
		(at 455.331068 -192.235074)
		(size 0.4826)
		(drill 0.254)
		(layers "F.Cu" "B.Cu")
		(net "P12V_MEM_CPU0")
	)
	(via
		(at 302.125126 -192.235074)
		(size 0.4826)
		(drill 0.254)
		(layers "F.Cu" "B.Cu")
		(net "P12V_MEM_CPU0")
	)
	(via
		(at 294.581072 -192.235074)
		(size 0.4826)
		(drill 0.254)
		(layers "F.Cu" "B.Cu")
		(net "P12V_MEM_CPU0")
	)
	(via
		(at 447.787268 -192.235074)
		(size 0.4826)
		(drill 0.254)
		(layers "F.Cu" "B.Cu")
		(net "P12V_MEM_CPU0")
	)
	(via
		(at 300.293024 -160.621472)
		(size 0.508)
		(drill 0.254)
		(layers "F.Cu" "B.Cu")
		(net "P12V_MEM_CPU0")
	)
	(via
		(at 308.5084 -192.928748)
		(size 0.4826)
		(drill 0.254)
		(layers "F.Cu" "B.Cu")
		(net "P12V_MEM_CPU0")
	)
	(via
		(at 271.949164 -192.235074)
		(size 0.4826)
		(drill 0.254)
		(layers "F.Cu" "B.Cu")
		(net "P12V_MEM_CPU0")
	)
	(via
		(at 264.40511 -193.084958)
		(size 0.4826)
		(drill 0.254)
		(layers "F.Cu" "B.Cu")
		(net "P12V_MEM_CPU0")
	)
	(via
		(at 418.769038 -193.084958)
		(size 0.4826)
		(drill 0.254)
		(layers "F.Cu" "B.Cu")
		(net "P12V_MEM_CPU0")
	)
	(via
		(at 432.69916 -192.235074)
		(size 0.4826)
		(drill 0.254)
		(layers "F.Cu" "B.Cu")
		(net "P12V_MEM_CPU0")
	)
	(via
		(at 441.4012 -193.084958)
		(size 0.4826)
		(drill 0.254)
		(layers "F.Cu" "B.Cu")
		(net "P12V_MEM_CPU0")
	)
	(via
		(at 444.24346 -181.32806)
		(size 0.508)
		(drill 0.254)
		(layers "F.Cu" "B.Cu")
		(net "P12V_MEM_CPU0")
	)
	(via
		(at 302.125126 -193.084958)
		(size 0.4826)
		(drill 0.254)
		(layers "F.Cu" "B.Cu")
		(net "P12V_MEM_CPU0")
	)
	(via
		(at 278.335232 -192.235074)
		(size 0.4826)
		(drill 0.254)
		(layers "F.Cu" "B.Cu")
		(net "P12V_MEM_CPU0")
	)
	(via
		(at 443.60846 -179.42306)
		(size 0.508)
		(drill 0.254)
		(layers "F.Cu" "B.Cu")
		(net "P12V_MEM_CPU0")
	)
	(via
		(at 444.24346 -179.42306)
		(size 0.508)
		(drill 0.254)
		(layers "F.Cu" "B.Cu")
		(net "P12V_MEM_CPU0")
	)
	(via
		(at 425.155106 -192.235074)
		(size 0.4826)
		(drill 0.254)
		(layers "F.Cu" "B.Cu")
		(net "P12V_MEM_CPU0")
	)
	(via
		(at 444.87846 -181.32806)
		(size 0.508)
		(drill 0.254)
		(layers "F.Cu" "B.Cu")
		(net "P12V_MEM_CPU0")
	)
	(via
		(at 441.4012 -192.235074)
		(size 0.4826)
		(drill 0.254)
		(layers "F.Cu" "B.Cu")
		(net "P12V_MEM_CPU0")
	)
	(via
		(at 448.945 -193.084958)
		(size 0.4826)
		(drill 0.254)
		(layers "F.Cu" "B.Cu")
		(net "P12V_MEM_CPU0")
	)
	(via
		(at 287.037018 -192.235074)
		(size 0.4826)
		(drill 0.254)
		(layers "F.Cu" "B.Cu")
		(net "P12V_MEM_CPU0")
	)
	(via
		(at 426.313092 -193.084958)
		(size 0.4826)
		(drill 0.254)
		(layers "F.Cu" "B.Cu")
		(net "P12V_MEM_CPU0")
	)
	(via
		(at 444.87846 -180.05806)
		(size 0.508)
		(drill 0.254)
		(layers "F.Cu" "B.Cu")
		(net "P12V_MEM_CPU0")
	)
	(via
		(at 445.51346 -180.69306)
		(size 0.508)
		(drill 0.254)
		(layers "F.Cu" "B.Cu")
		(net "P12V_MEM_CPU0")
	)
	(via
		(at 417.611052 -192.235074)
		(size 0.4826)
		(drill 0.254)
		(layers "F.Cu" "B.Cu")
		(net "P12V_MEM_CPU0")
	)
	(via
		(at 271.949164 -193.084958)
		(size 0.4826)
		(drill 0.254)
		(layers "F.Cu" "B.Cu")
		(net "P12V_MEM_CPU0")
	)
	(via
		(at 294.581072 -193.084958)
		(size 0.4826)
		(drill 0.254)
		(layers "F.Cu" "B.Cu")
		(net "P12V_MEM_CPU0")
	)
	(via
		(at 103.170736 -129.0066)
		(size 0.508)
		(drill 0.254)
		(layers "F.Cu" "B.Cu")
		(net "P12V_MEM_CPU0")
	)
	(via
		(at 411.224984 -192.235074)
		(size 0.4826)
		(drill 0.254)
		(layers "F.Cu" "B.Cu")
		(net "P12V_MEM_CPU0")
	)
	(via
		(at 445.51346 -179.42306)
		(size 0.508)
		(drill 0.254)
		(layers "F.Cu" "B.Cu")
		(net "P12V_MEM_CPU0")
	)
	(via
		(at 426.313092 -192.235074)
		(size 0.4826)
		(drill 0.254)
		(layers "F.Cu" "B.Cu")
		(net "P12V_MEM_CPU0")
	)
	(via
		(at 445.51346 -180.05806)
		(size 0.508)
		(drill 0.254)
		(layers "F.Cu" "B.Cu")
		(net "P12V_MEM_CPU0")
	)
	(via
		(at 293.423086 -192.235074)
		(size 0.4826)
		(drill 0.254)
		(layers "F.Cu" "B.Cu")
		(net "P12V_MEM_CPU0")
	)
	(via
		(at 433.857146 -193.084958)
		(size 0.4826)
		(drill 0.254)
		(layers "F.Cu" "B.Cu")
		(net "P12V_MEM_CPU0")
	)
	(via
		(at 270.791178 -192.235074)
		(size 0.4826)
		(drill 0.254)
		(layers "F.Cu" "B.Cu")
		(net "P12V_MEM_CPU0")
	)
	(via
		(at 442.97346 -179.42306)
		(size 0.508)
		(drill 0.254)
		(layers "F.Cu" "B.Cu")
		(net "P12V_MEM_CPU0")
	)
	(via
		(at 444.24346 -180.69306)
		(size 0.508)
		(drill 0.254)
		(layers "F.Cu" "B.Cu")
		(net "P12V_MEM_CPU0")
	)
	(via
		(at 418.769038 -192.235074)
		(size 0.4826)
		(drill 0.254)
		(layers "F.Cu" "B.Cu")
		(net "P12V_MEM_CPU0")
	)
	(via
		(at 448.945 -192.235074)
		(size 0.4826)
		(drill 0.254)
		(layers "F.Cu" "B.Cu")
		(net "P12V_MEM_CPU0")
	)
	(via
		(at 444.87846 -180.69306)
		(size 0.508)
		(drill 0.254)
		(layers "F.Cu" "B.Cu")
		(net "P12V_MEM_CPU0")
	)
	(via
		(at 440.243214 -192.235074)
		(size 0.4826)
		(drill 0.254)
		(layers "F.Cu" "B.Cu")
		(net "P12V_MEM_CPU0")
	)
	(via
		(at 442.97346 -181.32806)
		(size 0.508)
		(drill 0.254)
		(layers "F.Cu" "B.Cu")
		(net "P12V_MEM_CPU0")
	)
	(via
		(at 443.60846 -180.69306)
		(size 0.508)
		(drill 0.254)
		(layers "F.Cu" "B.Cu")
		(net "P12V_MEM_CPU0")
	)
	(via
		(at 264.40511 -192.235074)
		(size 0.4826)
		(drill 0.254)
		(layers "F.Cu" "B.Cu")
		(net "P12V_MEM_CPU0")
	)
	(segment
		(start 210.779868 -158.6992)
		(end 207.478122 -162.000946)
		(width 0.508)
		(layer "In6.Cu")
		(net "P12V_MEM_CPU0")
	)
	(segment
		(start 295.019222 -160.21558)
		(end 281.234388 -160.21558)
		(width 0.508)
		(layer "In6.Cu")
		(net "P12V_MEM_CPU0")
	)
	(segment
		(start 108.984542 -131.68884)
		(end 104.131364 -131.68884)
		(width 0.508)
		(layer "In6.Cu")
		(net "P12V_MEM_CPU0")
	)
	(segment
		(start 171.767246 -150.913846)
		(end 166.997634 -150.913846)
		(width 0.508)
		(layer "In6.Cu")
		(net "P12V_MEM_CPU0")
	)
	(segment
		(start 228.444298 -161.0741)
		(end 226.069398 -158.6992)
		(width 0.508)
		(layer "In6.Cu")
		(net "P12V_MEM_CPU0")
	)
	(segment
		(start 179.147724 -154.586686)
		(end 175.440086 -154.586686)
		(width 0.508)
		(layer "In6.Cu")
		(net "P12V_MEM_CPU0")
	)
	(segment
		(start 280.649426 -160.800542)
		(end 269.747746 -160.800542)
		(width 0.508)
		(layer "In6.Cu")
		(net "P12V_MEM_CPU0")
	)
	(segment
		(start 113.180876 -135.885174)
		(end 108.984542 -131.68884)
		(width 0.508)
		(layer "In6.Cu")
		(net "P12V_MEM_CPU0")
	)
	(segment
		(start 187.718954 -157.220666)
		(end 181.781704 -157.220666)
		(width 0.508)
		(layer "In6.Cu")
		(net "P12V_MEM_CPU0")
	)
	(segment
		(start 269.747746 -160.800542)
		(end 268.473428 -162.07486)
		(width 0.508)
		(layer "In6.Cu")
		(net "P12V_MEM_CPU0")
	)
	(segment
		(start 164.352986 -153.558494)
		(end 158.005018 -153.558494)
		(width 0.508)
		(layer "In6.Cu")
		(net "P12V_MEM_CPU0")
	)
	(segment
		(start 166.997634 -150.913846)
		(end 164.352986 -153.558494)
		(width 0.508)
		(layer "In6.Cu")
		(net "P12V_MEM_CPU0")
	)
	(segment
		(start 233.81462 -161.0741)
		(end 228.444298 -161.0741)
		(width 0.508)
		(layer "In6.Cu")
		(net "P12V_MEM_CPU0")
	)
	(segment
		(start 234.81538 -162.07486)
		(end 233.81462 -161.0741)
		(width 0.508)
		(layer "In6.Cu")
		(net "P12V_MEM_CPU0")
	)
	(segment
		(start 268.473428 -162.07486)
		(end 234.81538 -162.07486)
		(width 0.508)
		(layer "In6.Cu")
		(net "P12V_MEM_CPU0")
	)
	(segment
		(start 104.131364 -131.68884)
		(end 103.170736 -130.728212)
		(width 0.508)
		(layer "In6.Cu")
		(net "P12V_MEM_CPU0")
	)
	(segment
		(start 181.781704 -157.220666)
		(end 179.147724 -154.586686)
		(width 0.508)
		(layer "In6.Cu")
		(net "P12V_MEM_CPU0")
	)
	(segment
		(start 295.425114 -160.621472)
		(end 295.019222 -160.21558)
		(width 0.508)
		(layer "In6.Cu")
		(net "P12V_MEM_CPU0")
	)
	(segment
		(start 281.234388 -160.21558)
		(end 280.649426 -160.800542)
		(width 0.508)
		(layer "In6.Cu")
		(net "P12V_MEM_CPU0")
	)
	(segment
		(start 300.293024 -160.621472)
		(end 295.425114 -160.621472)
		(width 0.508)
		(layer "In6.Cu")
		(net "P12V_MEM_CPU0")
	)
	(segment
		(start 158.005018 -153.558494)
		(end 140.331698 -135.885174)
		(width 0.508)
		(layer "In6.Cu")
		(net "P12V_MEM_CPU0")
	)
	(segment
		(start 140.331698 -135.885174)
		(end 113.180876 -135.885174)
		(width 0.508)
		(layer "In6.Cu")
		(net "P12V_MEM_CPU0")
	)
	(segment
		(start 226.069398 -158.6992)
		(end 210.779868 -158.6992)
		(width 0.508)
		(layer "In6.Cu")
		(net "P12V_MEM_CPU0")
	)
	(segment
		(start 192.499234 -162.000946)
		(end 187.718954 -157.220666)
		(width 0.508)
		(layer "In6.Cu")
		(net "P12V_MEM_CPU0")
	)
	(segment
		(start 103.170736 -130.728212)
		(end 103.170736 -129.0066)
		(width 0.508)
		(layer "In6.Cu")
		(net "P12V_MEM_CPU0")
	)
	(segment
		(start 207.478122 -162.000946)
		(end 192.499234 -162.000946)
		(width 0.508)
		(layer "In6.Cu")
		(net "P12V_MEM_CPU0")
	)
	(segment
		(start 175.440086 -154.586686)
		(end 171.767246 -150.913846)
		(width 0.508)
		(layer "In6.Cu")
		(net "P12V_MEM_CPU0")
	)
	(segment
		(start 312.443876 -70.573392)
		(end 312.443876 -71.868792)
		(width 0.10668)
		(layer "F.Cu")
		(net "LED_PWRGD_SYS_PWROK_R_D")
	)
	(via
		(at 312.443876 -71.868792)
		(size 0.762)
		(drill 0.254)
		(layers "F.Cu" "B.Cu")
		(net "LED_PWRGD_SYS_PWROK_R_D")
	)
	(segment
		(start 312.443876 -72.234044)
		(end 312.443876 -71.868792)
		(width 0.10668)
		(layer "B.Cu")
		(net "LED_PWRGD_SYS_PWROK_R_D")
	)
	(segment
		(start 313.094624 -72.884792)
		(end 312.443876 -72.234044)
		(width 0.10668)
		(layer "B.Cu")
		(net "LED_PWRGD_SYS_PWROK_R_D")
	)
	(segment
		(start 312.443876 -68.328032)
		(end 312.443876 -69.623432)
		(width 0.10668)
		(layer "F.Cu")
		(net "LED_PWRGD_SYS_PWROK_R")
	)
	(via
		(at 312.443876 -68.328032)
		(size 0.508)
		(drill 0.254)
		(layers "F.Cu" "B.Cu")
		(net "LED_PWRGD_SYS_PWROK_R")
	)
	(segment
		(start 312.443876 -67.108832)
		(end 312.443876 -68.328032)
		(width 0.10668)
		(layer "B.Cu")
		(net "LED_PWRGD_SYS_PWROK_R")
	)
	(segment
		(start 318.539876 -70.573392)
		(end 318.539876 -71.868792)
		(width 0.10668)
		(layer "F.Cu")
		(net "LED_PWRGD_P1V8_AUX_D")
	)
	(via
		(at 318.539876 -71.868792)
		(size 0.762)
		(drill 0.254)
		(layers "F.Cu" "B.Cu")
		(net "LED_PWRGD_P1V8_AUX_D")
	)
	(segment
		(start 319.430146 -71.868792)
		(end 319.878456 -72.317102)
		(width 0.10668)
		(layer "B.Cu")
		(net "LED_PWRGD_P1V8_AUX_D")
	)
	(segment
		(start 318.539876 -71.868792)
		(end 319.430146 -71.868792)
		(width 0.10668)
		(layer "B.Cu")
		(net "LED_PWRGD_P1V8_AUX_D")
	)
	(segment
		(start 319.878456 -72.317102)
		(end 319.878456 -74.063352)
		(width 0.10668)
		(layer "B.Cu")
		(net "LED_PWRGD_P1V8_AUX_D")
	)
	(segment
		(start 319.757044 -74.184764)
		(end 319.322704 -74.184764)
		(width 0.10668)
		(layer "B.Cu")
		(net "LED_PWRGD_P1V8_AUX_D")
	)
	(segment
		(start 319.878456 -74.063352)
		(end 319.757044 -74.184764)
		(width 0.10668)
		(layer "B.Cu")
		(net "LED_PWRGD_P1V8_AUX_D")
	)
	(segment
		(start 318.539876 -69.623432)
		(end 318.539876 -68.328032)
		(width 0.10668)
		(layer "F.Cu")
		(net "LED_PWRGD_P1V8_AUX")
	)
	(via
		(at 318.539876 -68.328032)
		(size 0.508)
		(drill 0.254)
		(layers "F.Cu" "B.Cu")
		(net "LED_PWRGD_P1V8_AUX")
	)
	(segment
		(start 318.539876 -67.108832)
		(end 318.539876 -68.328032)
		(width 0.10668)
		(layer "B.Cu")
		(net "LED_PWRGD_P1V8_AUX")
	)
	(segment
		(start 177.534316 -110.264956)
		(end 177.922174 -110.652814)
		(width 0.10668)
		(layer "F.Cu")
		(net "IRQ_HSC_FAULT_BUF_R_N")
	)
	(segment
		(start 175.07458 -111.33328)
		(end 176.206912 -110.200948)
		(width 0.10668)
		(layer "F.Cu")
		(net "IRQ_HSC_FAULT_BUF_R_N")
	)
	(segment
		(start 176.637442 -110.264956)
		(end 177.534316 -110.264956)
		(width 0.10668)
		(layer "F.Cu")
		(net "IRQ_HSC_FAULT_BUF_R_N")
	)
	(segment
		(start 172.975524 -111.33328)
		(end 173.5582 -111.33328)
		(width 0.10668)
		(layer "F.Cu")
		(net "IRQ_HSC_FAULT_BUF_R_N")
	)
	(segment
		(start 176.573434 -110.200948)
		(end 176.637442 -110.264956)
		(width 0.10668)
		(layer "F.Cu")
		(net "IRQ_HSC_FAULT_BUF_R_N")
	)
	(segment
		(start 171.59605 -110.200948)
		(end 171.843192 -110.200948)
		(width 0.10668)
		(layer "F.Cu")
		(net "IRQ_HSC_FAULT_BUF_R_N")
	)
	(segment
		(start 173.5582 -111.33328)
		(end 175.07458 -111.33328)
		(width 0.10668)
		(layer "F.Cu")
		(net "IRQ_HSC_FAULT_BUF_R_N")
	)
	(segment
		(start 171.843192 -110.200948)
		(end 172.975524 -111.33328)
		(width 0.10668)
		(layer "F.Cu")
		(net "IRQ_HSC_FAULT_BUF_R_N")
	)
	(segment
		(start 176.206912 -110.200948)
		(end 176.573434 -110.200948)
		(width 0.10668)
		(layer "F.Cu")
		(net "IRQ_HSC_FAULT_BUF_R_N")
	)
	(via
		(at 173.5582 -111.33328)
		(size 0.762)
		(drill 0.381)
		(layers "F.Cu" "B.Cu")
		(net "IRQ_HSC_FAULT_BUF_R_N")
	)
	(segment
		(start 189.12205 -115.452906)
		(end 189.51194 -115.842796)
		(width 0.10668)
		(layer "F.Cu")
		(net "HPDB_HSC_PWRGD_ISO_R")
	)
	(segment
		(start 204.814932 -116.673376)
		(end 203.899008 -116.673376)
		(width 0.10668)
		(layer "F.Cu")
		(net "HPDB_HSC_PWRGD_ISO_R")
	)
	(via
		(at 203.899008 -116.673376)
		(size 0.508)
		(drill 0.254)
		(layers "F.Cu" "B.Cu")
		(net "HPDB_HSC_PWRGD_ISO_R")
	)
	(via
		(at 189.51194 -115.842796)
		(size 0.4572)
		(drill 0.254)
		(layers "F.Cu" "B.Cu")
		(net "HPDB_HSC_PWRGD_ISO_R")
	)
	(segment
		(start 203.899008 -116.673376)
		(end 203.39558 -116.169948)
		(width 0.11684)
		(layer "In15.Cu")
		(net "HPDB_HSC_PWRGD_ISO_R")
	)
	(segment
		(start 189.51194 -115.601496)
		(end 189.51194 -115.842796)
		(width 0.11684)
		(layer "In15.Cu")
		(net "HPDB_HSC_PWRGD_ISO_R")
	)
	(segment
		(start 198.69404 -115.215162)
		(end 189.898274 -115.215162)
		(width 0.11684)
		(layer "In15.Cu")
		(net "HPDB_HSC_PWRGD_ISO_R")
	)
	(segment
		(start 189.898274 -115.215162)
		(end 189.51194 -115.601496)
		(width 0.11684)
		(layer "In15.Cu")
		(net "HPDB_HSC_PWRGD_ISO_R")
	)
	(segment
		(start 203.39558 -116.169948)
		(end 199.648826 -116.169948)
		(width 0.11684)
		(layer "In15.Cu")
		(net "HPDB_HSC_PWRGD_ISO_R")
	)
	(segment
		(start 199.648826 -116.169948)
		(end 198.69404 -115.215162)
		(width 0.11684)
		(layer "In15.Cu")
		(net "HPDB_HSC_PWRGD_ISO_R")
	)
	(segment
		(start 189.92215 -116.252752)
		(end 190.31204 -116.642642)
		(width 0.10668)
		(layer "F.Cu")
		(net "HGX_DETECT_N_R")
	)
	(segment
		(start 204.759306 -114.249708)
		(end 203.843382 -114.249708)
		(width 0.10668)
		(layer "F.Cu")
		(net "HGX_DETECT_N_R")
	)
	(via
		(at 190.31204 -116.642642)
		(size 0.4572)
		(drill 0.254)
		(layers "F.Cu" "B.Cu")
		(net "HGX_DETECT_N_R")
	)
	(via
		(at 203.843382 -114.249708)
		(size 0.508)
		(drill 0.254)
		(layers "F.Cu" "B.Cu")
		(net "HGX_DETECT_N_R")
	)
	(segment
		(start 190.556896 -116.238528)
		(end 196.007736 -116.238528)
		(width 0.11684)
		(layer "In6.Cu")
		(net "HGX_DETECT_N_R")
	)
	(segment
		(start 190.31204 -116.642642)
		(end 190.31204 -116.483384)
		(width 0.11684)
		(layer "In6.Cu")
		(net "HGX_DETECT_N_R")
	)
	(segment
		(start 196.007736 -116.238528)
		(end 197.125336 -115.120928)
		(width 0.11684)
		(layer "In6.Cu")
		(net "HGX_DETECT_N_R")
	)
	(segment
		(start 202.972162 -115.120928)
		(end 203.843382 -114.249708)
		(width 0.11684)
		(layer "In6.Cu")
		(net "HGX_DETECT_N_R")
	)
	(segment
		(start 190.31204 -116.483384)
		(end 190.556896 -116.238528)
		(width 0.11684)
		(layer "In6.Cu")
		(net "HGX_DETECT_N_R")
	)
	(segment
		(start 197.125336 -115.120928)
		(end 202.972162 -115.120928)
		(width 0.11684)
		(layer "In6.Cu")
		(net "HGX_DETECT_N_R")
	)
	(segment
		(start 191.522096 -117.852952)
		(end 191.911986 -118.242842)
		(width 0.10668)
		(layer "F.Cu")
		(net "GPU_WP_HW_CTRL_R_N")
	)
	(via
		(at 191.911986 -118.242842)
		(size 0.4572)
		(drill 0.254)
		(layers "F.Cu" "B.Cu")
		(net "GPU_WP_HW_CTRL_R_N")
	)
	(via
		(at 195.603876 -121.548144)
		(size 0.6604)
		(drill 0.3302)
		(layers "F.Cu" "B.Cu")
		(net "GPU_WP_HW_CTRL_R_N")
	)
	(segment
		(start 197.555358 -122.769376)
		(end 196.825108 -122.769376)
		(width 0.10668)
		(layer "B.Cu")
		(net "GPU_WP_HW_CTRL_R_N")
	)
	(segment
		(start 196.825108 -122.769376)
		(end 195.603876 -121.548144)
		(width 0.10668)
		(layer "B.Cu")
		(net "GPU_WP_HW_CTRL_R_N")
	)
	(segment
		(start 194.729354 -118.899178)
		(end 194.469258 -118.639082)
		(width 0.10668)
		(layer "B.Cu")
		(net "GPU_WP_HW_CTRL_R_N")
	)
	(segment
		(start 192.308226 -118.639082)
		(end 191.911986 -118.242842)
		(width 0.10668)
		(layer "B.Cu")
		(net "GPU_WP_HW_CTRL_R_N")
	)
	(segment
		(start 195.603876 -121.548144)
		(end 195.244212 -121.18848)
		(width 0.10668)
		(layer "B.Cu")
		(net "GPU_WP_HW_CTRL_R_N")
	)
	(segment
		(start 195.244212 -121.18848)
		(end 195.244212 -120.499632)
		(width 0.10668)
		(layer "B.Cu")
		(net "GPU_WP_HW_CTRL_R_N")
	)
	(segment
		(start 194.729354 -119.984774)
		(end 194.729354 -118.899178)
		(width 0.10668)
		(layer "B.Cu")
		(net "GPU_WP_HW_CTRL_R_N")
	)
	(segment
		(start 195.244212 -120.499632)
		(end 194.729354 -119.984774)
		(width 0.10668)
		(layer "B.Cu")
		(net "GPU_WP_HW_CTRL_R_N")
	)
	(segment
		(start 194.469258 -118.639082)
		(end 192.308226 -118.639082)
		(width 0.10668)
		(layer "B.Cu")
		(net "GPU_WP_HW_CTRL_R_N")
	)
	(segment
		(start 167.937688 -118.880636)
		(end 168.148 -119.090948)
		(width 0.10668)
		(layer "F.Cu")
		(net "GPU_PRSNT_N_ISO_R")
	)
	(segment
		(start 164.138864 -119.345202)
		(end 165.358064 -119.345202)
		(width 0.10668)
		(layer "F.Cu")
		(net "GPU_PRSNT_N_ISO_R")
	)
	(segment
		(start 193.922142 -118.652798)
		(end 194.312032 -119.042688)
		(width 0.10668)
		(layer "F.Cu")
		(net "GPU_PRSNT_N_ISO_R")
	)
	(segment
		(start 165.82263 -118.880636)
		(end 167.937688 -118.880636)
		(width 0.10668)
		(layer "F.Cu")
		(net "GPU_PRSNT_N_ISO_R")
	)
	(segment
		(start 168.148 -119.090948)
		(end 168.148 -119.344948)
		(width 0.10668)
		(layer "F.Cu")
		(net "GPU_PRSNT_N_ISO_R")
	)
	(segment
		(start 165.358064 -119.345202)
		(end 165.82263 -118.880636)
		(width 0.10668)
		(layer "F.Cu")
		(net "GPU_PRSNT_N_ISO_R")
	)
	(via
		(at 168.148 -119.344948)
		(size 0.508)
		(drill 0.254)
		(layers "F.Cu" "B.Cu")
		(net "GPU_PRSNT_N_ISO_R")
	)
	(via
		(at 194.312032 -119.042688)
		(size 0.4572)
		(drill 0.254)
		(layers "F.Cu" "B.Cu")
		(net "GPU_PRSNT_N_ISO_R")
	)
	(via
		(at 165.358064 -119.345202)
		(size 0.762)
		(drill 0.381)
		(layers "F.Cu" "B.Cu")
		(net "GPU_PRSNT_N_ISO_R")
	)
	(segment
		(start 177.333148 -117.846856)
		(end 177.07864 -117.592348)
		(width 0.11684)
		(layer "In2.Cu")
		(net "GPU_PRSNT_N_ISO_R")
	)
	(segment
		(start 180.335428 -117.211856)
		(end 180.335428 -117.605556)
		(width 0.11684)
		(layer "In2.Cu")
		(net "GPU_PRSNT_N_ISO_R")
	)
	(segment
		(start 180.094128 -117.846856)
		(end 177.333148 -117.846856)
		(width 0.11684)
		(layer "In2.Cu")
		(net "GPU_PRSNT_N_ISO_R")
	)
	(segment
		(start 180.335428 -117.605556)
		(end 180.094128 -117.846856)
		(width 0.11684)
		(layer "In2.Cu")
		(net "GPU_PRSNT_N_ISO_R")
	)
	(segment
		(start 171.748958 -117.709188)
		(end 170.59148 -118.866666)
		(width 0.11684)
		(layer "In2.Cu")
		(net "GPU_PRSNT_N_ISO_R")
	)
	(segment
		(start 192.316608 -117.663976)
		(end 192.316608 -117.206776)
		(width 0.11684)
		(layer "In2.Cu")
		(net "GPU_PRSNT_N_ISO_R")
	)
	(segment
		(start 173.5963 -117.592348)
		(end 173.47946 -117.709188)
		(width 0.11684)
		(layer "In2.Cu")
		(net "GPU_PRSNT_N_ISO_R")
	)
	(segment
		(start 192.316608 -117.206776)
		(end 192.148968 -117.039136)
		(width 0.11684)
		(layer "In2.Cu")
		(net "GPU_PRSNT_N_ISO_R")
	)
	(segment
		(start 170.59148 -118.866666)
		(end 168.626282 -118.866666)
		(width 0.11684)
		(layer "In2.Cu")
		(net "GPU_PRSNT_N_ISO_R")
	)
	(segment
		(start 193.672968 -117.846856)
		(end 192.499488 -117.846856)
		(width 0.11684)
		(layer "In2.Cu")
		(net "GPU_PRSNT_N_ISO_R")
	)
	(segment
		(start 193.919348 -118.093236)
		(end 193.672968 -117.846856)
		(width 0.11684)
		(layer "In2.Cu")
		(net "GPU_PRSNT_N_ISO_R")
	)
	(segment
		(start 192.499488 -117.846856)
		(end 192.316608 -117.663976)
		(width 0.11684)
		(layer "In2.Cu")
		(net "GPU_PRSNT_N_ISO_R")
	)
	(segment
		(start 193.919348 -118.650004)
		(end 193.919348 -118.093236)
		(width 0.11684)
		(layer "In2.Cu")
		(net "GPU_PRSNT_N_ISO_R")
	)
	(segment
		(start 168.626282 -118.866666)
		(end 168.148 -119.344948)
		(width 0.11684)
		(layer "In2.Cu")
		(net "GPU_PRSNT_N_ISO_R")
	)
	(segment
		(start 194.312032 -119.042688)
		(end 193.919348 -118.650004)
		(width 0.11684)
		(layer "In2.Cu")
		(net "GPU_PRSNT_N_ISO_R")
	)
	(segment
		(start 173.47946 -117.709188)
		(end 171.748958 -117.709188)
		(width 0.11684)
		(layer "In2.Cu")
		(net "GPU_PRSNT_N_ISO_R")
	)
	(segment
		(start 177.07864 -117.592348)
		(end 173.5963 -117.592348)
		(width 0.11684)
		(layer "In2.Cu")
		(net "GPU_PRSNT_N_ISO_R")
	)
	(segment
		(start 192.148968 -117.039136)
		(end 180.508148 -117.039136)
		(width 0.11684)
		(layer "In2.Cu")
		(net "GPU_PRSNT_N_ISO_R")
	)
	(segment
		(start 180.508148 -117.039136)
		(end 180.335428 -117.211856)
		(width 0.11684)
		(layer "In2.Cu")
		(net "GPU_PRSNT_N_ISO_R")
	)
	(segment
		(start 196.488812 -102.342442)
		(end 194.75196 -104.079294)
		(width 0.10668)
		(layer "F.Cu")
		(net "GPU_NVS_PWR_BRAKE_R_N")
	)
	(segment
		(start 195.01358 -106.661204)
		(end 194.221862 -107.452922)
		(width 0.10668)
		(layer "F.Cu")
		(net "GPU_NVS_PWR_BRAKE_R_N")
	)
	(segment
		(start 196.488812 -101.183186)
		(end 196.488812 -102.342442)
		(width 0.10668)
		(layer "F.Cu")
		(net "GPU_NVS_PWR_BRAKE_R_N")
	)
	(segment
		(start 194.75196 -104.079294)
		(end 194.75196 -105.066338)
		(width 0.10668)
		(layer "F.Cu")
		(net "GPU_NVS_PWR_BRAKE_R_N")
	)
	(segment
		(start 194.751706 -105.0671)
		(end 194.55765 -105.261156)
		(width 0.10668)
		(layer "F.Cu")
		(net "GPU_NVS_PWR_BRAKE_R_N")
	)
	(segment
		(start 195.01358 -105.90657)
		(end 195.01358 -106.661204)
		(width 0.10668)
		(layer "F.Cu")
		(net "GPU_NVS_PWR_BRAKE_R_N")
	)
	(segment
		(start 194.221862 -107.452922)
		(end 193.922142 -107.452922)
		(width 0.10668)
		(layer "F.Cu")
		(net "GPU_NVS_PWR_BRAKE_R_N")
	)
	(segment
		(start 194.55765 -105.261156)
		(end 194.55765 -105.45064)
		(width 0.10668)
		(layer "F.Cu")
		(net "GPU_NVS_PWR_BRAKE_R_N")
	)
	(segment
		(start 194.75196 -105.066338)
		(end 194.751706 -105.0671)
		(width 0.10668)
		(layer "F.Cu")
		(net "GPU_NVS_PWR_BRAKE_R_N")
	)
	(segment
		(start 196.977 -100.694998)
		(end 196.488812 -101.183186)
		(width 0.10668)
		(layer "F.Cu")
		(net "GPU_NVS_PWR_BRAKE_R_N")
	)
	(segment
		(start 194.55765 -105.45064)
		(end 195.01358 -105.90657)
		(width 0.10668)
		(layer "F.Cu")
		(net "GPU_NVS_PWR_BRAKE_R_N")
	)
	(via
		(at 194.55765 -105.261156)
		(size 0.508)
		(drill 0.254)
		(layers "F.Cu" "B.Cu")
		(net "GPU_NVS_PWR_BRAKE_R_N")
	)
	(segment
		(start 193.122042 -117.852952)
		(end 193.511932 -118.242842)
		(width 0.10668)
		(layer "F.Cu")
		(net "GPU_HMC_PRSNT_ISO_R_N")
	)
	(segment
		(start 208.478882 -117.748812)
		(end 207.264 -117.748812)
		(width 0.10668)
		(layer "F.Cu")
		(net "GPU_HMC_PRSNT_ISO_R_N")
	)
	(via
		(at 207.264 -117.748812)
		(size 0.762)
		(drill 0.254)
		(layers "F.Cu" "B.Cu")
		(net "GPU_HMC_PRSNT_ISO_R_N")
	)
	(via
		(at 193.511932 -118.242842)
		(size 0.4572)
		(drill 0.254)
		(layers "F.Cu" "B.Cu")
		(net "GPU_HMC_PRSNT_ISO_R_N")
	)
	(segment
		(start 206.645256 -118.367556)
		(end 207.264 -117.748812)
		(width 0.11684)
		(layer "In6.Cu")
		(net "GPU_HMC_PRSNT_ISO_R_N")
	)
	(segment
		(start 200.276968 -118.367556)
		(end 206.645256 -118.367556)
		(width 0.11684)
		(layer "In6.Cu")
		(net "GPU_HMC_PRSNT_ISO_R_N")
	)
	(segment
		(start 193.511932 -118.267226)
		(end 193.896234 -118.651528)
		(width 0.11684)
		(layer "In6.Cu")
		(net "GPU_HMC_PRSNT_ISO_R_N")
	)
	(segment
		(start 197.154038 -118.651528)
		(end 197.657974 -119.155464)
		(width 0.11684)
		(layer "In6.Cu")
		(net "GPU_HMC_PRSNT_ISO_R_N")
	)
	(segment
		(start 199.48906 -119.155464)
		(end 200.276968 -118.367556)
		(width 0.11684)
		(layer "In6.Cu")
		(net "GPU_HMC_PRSNT_ISO_R_N")
	)
	(segment
		(start 193.896234 -118.651528)
		(end 197.154038 -118.651528)
		(width 0.11684)
		(layer "In6.Cu")
		(net "GPU_HMC_PRSNT_ISO_R_N")
	)
	(segment
		(start 193.511932 -118.242842)
		(end 193.511932 -118.267226)
		(width 0.11684)
		(layer "In6.Cu")
		(net "GPU_HMC_PRSNT_ISO_R_N")
	)
	(segment
		(start 197.657974 -119.155464)
		(end 199.48906 -119.155464)
		(width 0.11684)
		(layer "In6.Cu")
		(net "GPU_HMC_PRSNT_ISO_R_N")
	)
	(segment
		(start 191.522096 -117.052852)
		(end 191.911986 -117.442742)
		(width 0.10668)
		(layer "F.Cu")
		(net "GPU_FPGA_THERM_OVERT_ISO_R_N")
	)
	(via
		(at 191.911986 -117.442742)
		(size 0.4572)
		(drill 0.254)
		(layers "F.Cu" "B.Cu")
		(net "GPU_FPGA_THERM_OVERT_ISO_R_N")
	)
	(via
		(at 195.044314 -118.414546)
		(size 0.6604)
		(drill 0.3302)
		(layers "F.Cu" "B.Cu")
		(net "GPU_FPGA_THERM_OVERT_ISO_R_N")
	)
	(segment
		(start 196.313298 -121.197116)
		(end 196.005958 -121.197116)
		(width 0.10668)
		(layer "B.Cu")
		(net "GPU_FPGA_THERM_OVERT_ISO_R_N")
	)
	(segment
		(start 196.869558 -121.753376)
		(end 196.313298 -121.197116)
		(width 0.10668)
		(layer "B.Cu")
		(net "GPU_FPGA_THERM_OVERT_ISO_R_N")
	)
	(segment
		(start 194.97675 -118.48211)
		(end 195.044314 -118.414546)
		(width 0.10668)
		(layer "B.Cu")
		(net "GPU_FPGA_THERM_OVERT_ISO_R_N")
	)
	(segment
		(start 194.46875 -117.838982)
		(end 195.044314 -118.414546)
		(width 0.10668)
		(layer "B.Cu")
		(net "GPU_FPGA_THERM_OVERT_ISO_R_N")
	)
	(segment
		(start 195.736718 -120.927876)
		(end 195.736718 -120.664732)
		(width 0.10668)
		(layer "B.Cu")
		(net "GPU_FPGA_THERM_OVERT_ISO_R_N")
	)
	(segment
		(start 195.736718 -120.664732)
		(end 194.97675 -119.904764)
		(width 0.10668)
		(layer "B.Cu")
		(net "GPU_FPGA_THERM_OVERT_ISO_R_N")
	)
	(segment
		(start 192.308226 -117.838982)
		(end 194.46875 -117.838982)
		(width 0.10668)
		(layer "B.Cu")
		(net "GPU_FPGA_THERM_OVERT_ISO_R_N")
	)
	(segment
		(start 194.97675 -119.904764)
		(end 194.97675 -118.48211)
		(width 0.10668)
		(layer "B.Cu")
		(net "GPU_FPGA_THERM_OVERT_ISO_R_N")
	)
	(segment
		(start 196.005958 -121.197116)
		(end 195.736718 -120.927876)
		(width 0.10668)
		(layer "B.Cu")
		(net "GPU_FPGA_THERM_OVERT_ISO_R_N")
	)
	(segment
		(start 191.911986 -117.442742)
		(end 192.308226 -117.838982)
		(width 0.10668)
		(layer "B.Cu")
		(net "GPU_FPGA_THERM_OVERT_ISO_R_N")
	)
	(segment
		(start 208.494376 -114.249708)
		(end 207.291686 -114.249708)
		(width 0.10668)
		(layer "F.Cu")
		(net "GPU_FPGA_RST_N")
	)
	(segment
		(start 190.721996 -111.452914)
		(end 191.111886 -111.063024)
		(width 0.10668)
		(layer "F.Cu")
		(net "GPU_FPGA_RST_N")
	)
	(via
		(at 207.291686 -114.249708)
		(size 0.762)
		(drill 0.254)
		(layers "F.Cu" "B.Cu")
		(net "GPU_FPGA_RST_N")
	)
	(via
		(at 191.111886 -111.063024)
		(size 0.4572)
		(drill 0.254)
		(layers "F.Cu" "B.Cu")
		(net "GPU_FPGA_RST_N")
	)
	(segment
		(start 191.623696 -111.46282)
		(end 191.2239 -111.063024)
		(width 0.11684)
		(layer "In2.Cu")
		(net "GPU_FPGA_RST_N")
	)
	(segment
		(start 201.679556 -113.117376)
		(end 200.55078 -111.9886)
		(width 0.11684)
		(layer "In2.Cu")
		(net "GPU_FPGA_RST_N")
	)
	(segment
		(start 198.0565 -111.9886)
		(end 197.199504 -112.845596)
		(width 0.11684)
		(layer "In2.Cu")
		(net "GPU_FPGA_RST_N")
	)
	(segment
		(start 197.199504 -112.845596)
		(end 195.481956 -112.845596)
		(width 0.11684)
		(layer "In2.Cu")
		(net "GPU_FPGA_RST_N")
	)
	(segment
		(start 194.860672 -112.224312)
		(end 194.449192 -112.224312)
		(width 0.11684)
		(layer "In2.Cu")
		(net "GPU_FPGA_RST_N")
	)
	(segment
		(start 194.449192 -112.224312)
		(end 193.6877 -111.46282)
		(width 0.11684)
		(layer "In2.Cu")
		(net "GPU_FPGA_RST_N")
	)
	(segment
		(start 206.605378 -113.5634)
		(end 203.389992 -113.5634)
		(width 0.11684)
		(layer "In2.Cu")
		(net "GPU_FPGA_RST_N")
	)
	(segment
		(start 202.943968 -113.117376)
		(end 201.679556 -113.117376)
		(width 0.11684)
		(layer "In2.Cu")
		(net "GPU_FPGA_RST_N")
	)
	(segment
		(start 203.389992 -113.5634)
		(end 202.943968 -113.117376)
		(width 0.11684)
		(layer "In2.Cu")
		(net "GPU_FPGA_RST_N")
	)
	(segment
		(start 193.6877 -111.46282)
		(end 191.623696 -111.46282)
		(width 0.11684)
		(layer "In2.Cu")
		(net "GPU_FPGA_RST_N")
	)
	(segment
		(start 191.2239 -111.063024)
		(end 191.111886 -111.063024)
		(width 0.11684)
		(layer "In2.Cu")
		(net "GPU_FPGA_RST_N")
	)
	(segment
		(start 195.481956 -112.845596)
		(end 194.860672 -112.224312)
		(width 0.11684)
		(layer "In2.Cu")
		(net "GPU_FPGA_RST_N")
	)
	(segment
		(start 207.291686 -114.249708)
		(end 206.605378 -113.5634)
		(width 0.11684)
		(layer "In2.Cu")
		(net "GPU_FPGA_RST_N")
	)
	(segment
		(start 200.55078 -111.9886)
		(end 198.0565 -111.9886)
		(width 0.11684)
		(layer "In2.Cu")
		(net "GPU_FPGA_RST_N")
	)
	(segment
		(start 198.157846 -123.313952)
		(end 197.61327 -122.769376)
		(width 0.10668)
		(layer "F.Cu")
		(net "GPU_FPGA_READY_ISO_R")
	)
	(segment
		(start 200.682098 -122.798332)
		(end 200.166478 -123.313952)
		(width 0.10668)
		(layer "F.Cu")
		(net "GPU_FPGA_READY_ISO_R")
	)
	(segment
		(start 197.47611 -122.769376)
		(end 195.638674 -122.769376)
		(width 0.10668)
		(layer "F.Cu")
		(net "GPU_FPGA_READY_ISO_R")
	)
	(segment
		(start 197.61327 -122.769376)
		(end 197.47611 -122.769376)
		(width 0.10668)
		(layer "F.Cu")
		(net "GPU_FPGA_READY_ISO_R")
	)
	(segment
		(start 200.166478 -123.313952)
		(end 198.157846 -123.313952)
		(width 0.10668)
		(layer "F.Cu")
		(net "GPU_FPGA_READY_ISO_R")
	)
	(segment
		(start 195.638674 -122.769376)
		(end 193.922142 -121.052844)
		(width 0.10668)
		(layer "F.Cu")
		(net "GPU_FPGA_READY_ISO_R")
	)
	(via
		(at 197.47611 -122.769376)
		(size 0.762)
		(drill 0.381)
		(layers "F.Cu" "B.Cu")
		(net "GPU_FPGA_READY_ISO_R")
	)
	(segment
		(start 192.322196 -117.852952)
		(end 192.712086 -118.242842)
		(width 0.10668)
		(layer "F.Cu")
		(net "GPU_FPGA_OVERT_ISO_R_N")
	)
	(via
		(at 192.712086 -118.242842)
		(size 0.4572)
		(drill 0.254)
		(layers "F.Cu" "B.Cu")
		(net "GPU_FPGA_OVERT_ISO_R_N")
	)
	(via
		(at 199.734932 -122.825764)
		(size 0.508)
		(drill 0.254)
		(layers "F.Cu" "B.Cu")
		(net "GPU_FPGA_OVERT_ISO_R_N")
	)
	(segment
		(start 199.79132 -122.769376)
		(end 199.734932 -122.825764)
		(width 0.10668)
		(layer "B.Cu")
		(net "GPU_FPGA_OVERT_ISO_R_N")
	)
	(segment
		(start 200.552558 -122.769376)
		(end 199.79132 -122.769376)
		(width 0.10668)
		(layer "B.Cu")
		(net "GPU_FPGA_OVERT_ISO_R_N")
	)
	(segment
		(start 194.50431 -119.441976)
		(end 193.307208 -119.441976)
		(width 0.11684)
		(layer "In2.Cu")
		(net "GPU_FPGA_OVERT_ISO_R_N")
	)
	(segment
		(start 193.104008 -118.634764)
		(end 192.712086 -118.242842)
		(width 0.11684)
		(layer "In2.Cu")
		(net "GPU_FPGA_OVERT_ISO_R_N")
	)
	(segment
		(start 193.104008 -119.238776)
		(end 193.104008 -118.634764)
		(width 0.11684)
		(layer "In2.Cu")
		(net "GPU_FPGA_OVERT_ISO_R_N")
	)
	(segment
		(start 195.678044 -120.850406)
		(end 195.678044 -120.61571)
		(width 0.11684)
		(layer "In2.Cu")
		(net "GPU_FPGA_OVERT_ISO_R_N")
	)
	(segment
		(start 193.307208 -119.441976)
		(end 193.104008 -119.238776)
		(width 0.11684)
		(layer "In2.Cu")
		(net "GPU_FPGA_OVERT_ISO_R_N")
	)
	(segment
		(start 195.678044 -120.61571)
		(end 194.50431 -119.441976)
		(width 0.11684)
		(layer "In2.Cu")
		(net "GPU_FPGA_OVERT_ISO_R_N")
	)
	(segment
		(start 197.154038 -122.3264)
		(end 195.678044 -120.850406)
		(width 0.11684)
		(layer "In2.Cu")
		(net "GPU_FPGA_OVERT_ISO_R_N")
	)
	(segment
		(start 199.235568 -122.3264)
		(end 197.154038 -122.3264)
		(width 0.11684)
		(layer "In2.Cu")
		(net "GPU_FPGA_OVERT_ISO_R_N")
	)
	(segment
		(start 199.734932 -122.825764)
		(end 199.235568 -122.3264)
		(width 0.11684)
		(layer "In2.Cu")
		(net "GPU_FPGA_OVERT_ISO_R_N")
	)
	(segment
		(start 193.122042 -109.052868)
		(end 193.511932 -108.662978)
		(width 0.10668)
		(layer "F.Cu")
		(net "GPU_FPGA_EROT_RST_R_N")
	)
	(segment
		(start 199.931274 -110.577376)
		(end 199.897746 -110.610904)
		(width 0.10668)
		(layer "F.Cu")
		(net "GPU_FPGA_EROT_RST_R_N")
	)
	(segment
		(start 200.552558 -110.577376)
		(end 199.931274 -110.577376)
		(width 0.10668)
		(layer "F.Cu")
		(net "GPU_FPGA_EROT_RST_R_N")
	)
	(via
		(at 199.897746 -110.610904)
		(size 0.508)
		(drill 0.254)
		(layers "F.Cu" "B.Cu")
		(net "GPU_FPGA_EROT_RST_R_N")
	)
	(via
		(at 193.511932 -108.662978)
		(size 0.4572)
		(drill 0.254)
		(layers "F.Cu" "B.Cu")
		(net "GPU_FPGA_EROT_RST_R_N")
	)
	(segment
		(start 199.897746 -110.610904)
		(end 199.897746 -110.565184)
		(width 0.11684)
		(layer "In6.Cu")
		(net "GPU_FPGA_EROT_RST_R_N")
	)
	(segment
		(start 199.897746 -110.565184)
		(end 199.480678 -110.148116)
		(width 0.11684)
		(layer "In6.Cu")
		(net "GPU_FPGA_EROT_RST_R_N")
	)
	(segment
		(start 195.74002 -108.91393)
		(end 195.648326 -108.822236)
		(width 0.11684)
		(layer "In6.Cu")
		(net "GPU_FPGA_EROT_RST_R_N")
	)
	(segment
		(start 196.43471 -108.91393)
		(end 195.74002 -108.91393)
		(width 0.11684)
		(layer "In6.Cu")
		(net "GPU_FPGA_EROT_RST_R_N")
	)
	(segment
		(start 193.922142 -109.073188)
		(end 193.511932 -108.662978)
		(width 0.11684)
		(layer "In6.Cu")
		(net "GPU_FPGA_EROT_RST_R_N")
	)
	(segment
		(start 195.074032 -108.822236)
		(end 194.82308 -109.073188)
		(width 0.11684)
		(layer "In6.Cu")
		(net "GPU_FPGA_EROT_RST_R_N")
	)
	(segment
		(start 194.82308 -109.073188)
		(end 193.922142 -109.073188)
		(width 0.11684)
		(layer "In6.Cu")
		(net "GPU_FPGA_EROT_RST_R_N")
	)
	(segment
		(start 197.668896 -110.148116)
		(end 196.43471 -108.91393)
		(width 0.11684)
		(layer "In6.Cu")
		(net "GPU_FPGA_EROT_RST_R_N")
	)
	(segment
		(start 199.480678 -110.148116)
		(end 197.668896 -110.148116)
		(width 0.11684)
		(layer "In6.Cu")
		(net "GPU_FPGA_EROT_RST_R_N")
	)
	(segment
		(start 195.648326 -108.822236)
		(end 195.074032 -108.822236)
		(width 0.11684)
		(layer "In6.Cu")
		(net "GPU_FPGA_EROT_RST_R_N")
	)
	(segment
		(start 203.841604 -110.649512)
		(end 203.77658 -110.584488)
		(width 0.10668)
		(layer "F.Cu")
		(net "GPU_FPGA_EROT_RECOV_R_N")
	)
	(segment
		(start 193.122042 -109.852968)
		(end 193.511932 -109.463078)
		(width 0.10668)
		(layer "F.Cu")
		(net "GPU_FPGA_EROT_RECOV_R_N")
	)
	(segment
		(start 204.834236 -110.649512)
		(end 203.841604 -110.649512)
		(width 0.10668)
		(layer "F.Cu")
		(net "GPU_FPGA_EROT_RECOV_R_N")
	)
	(via
		(at 193.511932 -109.463078)
		(size 0.4572)
		(drill 0.254)
		(layers "F.Cu" "B.Cu")
		(net "GPU_FPGA_EROT_RECOV_R_N")
	)
	(via
		(at 203.77658 -110.584488)
		(size 0.508)
		(drill 0.254)
		(layers "F.Cu" "B.Cu")
		(net "GPU_FPGA_EROT_RECOV_R_N")
	)
	(segment
		(start 203.208636 -109.010196)
		(end 195.947792 -109.010196)
		(width 0.11684)
		(layer "In2.Cu")
		(net "GPU_FPGA_EROT_RECOV_R_N")
	)
	(segment
		(start 203.77658 -110.584488)
		(end 203.77658 -109.57814)
		(width 0.11684)
		(layer "In2.Cu")
		(net "GPU_FPGA_EROT_RECOV_R_N")
	)
	(segment
		(start 195.947792 -109.010196)
		(end 195.759832 -108.822236)
		(width 0.11684)
		(layer "In2.Cu")
		(net "GPU_FPGA_EROT_RECOV_R_N")
	)
	(segment
		(start 195.759832 -108.822236)
		(end 194.873372 -108.822236)
		(width 0.11684)
		(layer "In2.Cu")
		(net "GPU_FPGA_EROT_RECOV_R_N")
	)
	(segment
		(start 194.873372 -108.822236)
		(end 194.637152 -109.058456)
		(width 0.11684)
		(layer "In2.Cu")
		(net "GPU_FPGA_EROT_RECOV_R_N")
	)
	(segment
		(start 203.77658 -109.57814)
		(end 203.208636 -109.010196)
		(width 0.11684)
		(layer "In2.Cu")
		(net "GPU_FPGA_EROT_RECOV_R_N")
	)
	(segment
		(start 193.916554 -109.058456)
		(end 193.511932 -109.463078)
		(width 0.11684)
		(layer "In2.Cu")
		(net "GPU_FPGA_EROT_RECOV_R_N")
	)
	(segment
		(start 194.637152 -109.058456)
		(end 193.916554 -109.058456)
		(width 0.11684)
		(layer "In2.Cu")
		(net "GPU_FPGA_EROT_RECOV_R_N")
	)
	(segment
		(start 193.122042 -118.652798)
		(end 193.511932 -119.042688)
		(width 0.10668)
		(layer "F.Cu")
		(net "GPU_FPGA_EROT_FATALERR_ISO_R_N")
	)
	(segment
		(start 208.478882 -118.762272)
		(end 207.367886 -118.762272)
		(width 0.10668)
		(layer "F.Cu")
		(net "GPU_FPGA_EROT_FATALERR_ISO_R_N")
	)
	(via
		(at 207.367886 -118.762272)
		(size 0.508)
		(drill 0.254)
		(layers "F.Cu" "B.Cu")
		(net "GPU_FPGA_EROT_FATALERR_ISO_R_N")
	)
	(via
		(at 193.511932 -119.042688)
		(size 0.4572)
		(drill 0.254)
		(layers "F.Cu" "B.Cu")
		(net "GPU_FPGA_EROT_FATALERR_ISO_R_N")
	)
	(segment
		(start 198.009256 -120.232932)
		(end 200.522586 -120.232932)
		(width 0.11684)
		(layer "In6.Cu")
		(net "GPU_FPGA_EROT_FATALERR_ISO_R_N")
	)
	(segment
		(start 201.993246 -118.762272)
		(end 207.367886 -118.762272)
		(width 0.11684)
		(layer "In6.Cu")
		(net "GPU_FPGA_EROT_FATALERR_ISO_R_N")
	)
	(segment
		(start 193.511932 -119.149876)
		(end 193.80327 -119.441214)
		(width 0.11684)
		(layer "In6.Cu")
		(net "GPU_FPGA_EROT_FATALERR_ISO_R_N")
	)
	(segment
		(start 196.896228 -119.119904)
		(end 198.009256 -120.232932)
		(width 0.11684)
		(layer "In6.Cu")
		(net "GPU_FPGA_EROT_FATALERR_ISO_R_N")
	)
	(segment
		(start 200.522586 -120.232932)
		(end 201.993246 -118.762272)
		(width 0.11684)
		(layer "In6.Cu")
		(net "GPU_FPGA_EROT_FATALERR_ISO_R_N")
	)
	(segment
		(start 195.297044 -119.119904)
		(end 196.896228 -119.119904)
		(width 0.11684)
		(layer "In6.Cu")
		(net "GPU_FPGA_EROT_FATALERR_ISO_R_N")
	)
	(segment
		(start 194.975734 -119.441214)
		(end 195.297044 -119.119904)
		(width 0.11684)
		(layer "In6.Cu")
		(net "GPU_FPGA_EROT_FATALERR_ISO_R_N")
	)
	(segment
		(start 193.80327 -119.441214)
		(end 194.975734 -119.441214)
		(width 0.11684)
		(layer "In6.Cu")
		(net "GPU_FPGA_EROT_FATALERR_ISO_R_N")
	)
	(segment
		(start 193.511932 -119.042688)
		(end 193.511932 -119.149876)
		(width 0.11684)
		(layer "In6.Cu")
		(net "GPU_FPGA_EROT_FATALERR_ISO_R_N")
	)
	(segment
		(start 194.328796 -133.168898)
		(end 194.183 -133.168898)
		(width 0.10668)
		(layer "F.Cu")
		(net "GPU_FPGA_BOOT_EN_R")
	)
	(segment
		(start 194.691 -131.806188)
		(end 194.691 -132.806694)
		(width 0.10668)
		(layer "F.Cu")
		(net "GPU_FPGA_BOOT_EN_R")
	)
	(segment
		(start 194.2084 -131.323588)
		(end 194.691 -131.806188)
		(width 0.10668)
		(layer "F.Cu")
		(net "GPU_FPGA_BOOT_EN_R")
	)
	(segment
		(start 194.691 -132.806694)
		(end 194.328796 -133.168898)
		(width 0.10668)
		(layer "F.Cu")
		(net "GPU_FPGA_BOOT_EN_R")
	)
	(segment
		(start 189.12205 -117.852952)
		(end 189.51194 -118.242842)
		(width 0.10668)
		(layer "F.Cu")
		(net "GPU_FPGA_BOOT_EN_R")
	)
	(via
		(at 189.51194 -118.242842)
		(size 0.4572)
		(drill 0.254)
		(layers "F.Cu" "B.Cu")
		(net "GPU_FPGA_BOOT_EN_R")
	)
	(via
		(at 194.2084 -131.323588)
		(size 0.762)
		(drill 0.254)
		(layers "F.Cu" "B.Cu")
		(net "GPU_FPGA_BOOT_EN_R")
	)
	(segment
		(start 192.319148 -121.227596)
		(end 192.138808 -121.047256)
		(width 0.11684)
		(layer "In2.Cu")
		(net "GPU_FPGA_BOOT_EN_R")
	)
	(segment
		(start 191.379348 -119.447056)
		(end 190.871348 -119.447056)
		(width 0.11684)
		(layer "In2.Cu")
		(net "GPU_FPGA_BOOT_EN_R")
	)
	(segment
		(start 191.684148 -121.047256)
		(end 191.513968 -120.877076)
		(width 0.11684)
		(layer "In2.Cu")
		(net "GPU_FPGA_BOOT_EN_R")
	)
	(segment
		(start 190.716408 -119.292116)
		(end 190.716408 -118.857776)
		(width 0.11684)
		(layer "In2.Cu")
		(net "GPU_FPGA_BOOT_EN_R")
	)
	(segment
		(start 191.513968 -119.581676)
		(end 191.379348 -119.447056)
		(width 0.11684)
		(layer "In2.Cu")
		(net "GPU_FPGA_BOOT_EN_R")
	)
	(segment
		(start 192.138808 -121.047256)
		(end 191.684148 -121.047256)
		(width 0.11684)
		(layer "In2.Cu")
		(net "GPU_FPGA_BOOT_EN_R")
	)
	(segment
		(start 190.716408 -118.857776)
		(end 190.490348 -118.631716)
		(width 0.11684)
		(layer "In2.Cu")
		(net "GPU_FPGA_BOOT_EN_R")
	)
	(segment
		(start 193.600832 -123.695714)
		(end 192.319148 -122.41403)
		(width 0.11684)
		(layer "In2.Cu")
		(net "GPU_FPGA_BOOT_EN_R")
	)
	(segment
		(start 190.490348 -118.631716)
		(end 189.900814 -118.631716)
		(width 0.11684)
		(layer "In2.Cu")
		(net "GPU_FPGA_BOOT_EN_R")
	)
	(segment
		(start 192.319148 -122.41403)
		(end 192.319148 -121.227596)
		(width 0.11684)
		(layer "In2.Cu")
		(net "GPU_FPGA_BOOT_EN_R")
	)
	(segment
		(start 194.833748 -125.772672)
		(end 193.600832 -124.539756)
		(width 0.11684)
		(layer "In2.Cu")
		(net "GPU_FPGA_BOOT_EN_R")
	)
	(segment
		(start 194.833748 -130.69824)
		(end 194.833748 -125.772672)
		(width 0.11684)
		(layer "In2.Cu")
		(net "GPU_FPGA_BOOT_EN_R")
	)
	(segment
		(start 189.900814 -118.631716)
		(end 189.51194 -118.242842)
		(width 0.11684)
		(layer "In2.Cu")
		(net "GPU_FPGA_BOOT_EN_R")
	)
	(segment
		(start 193.600832 -124.539756)
		(end 193.600832 -123.695714)
		(width 0.11684)
		(layer "In2.Cu")
		(net "GPU_FPGA_BOOT_EN_R")
	)
	(segment
		(start 191.513968 -120.877076)
		(end 191.513968 -119.581676)
		(width 0.11684)
		(layer "In2.Cu")
		(net "GPU_FPGA_BOOT_EN_R")
	)
	(segment
		(start 190.871348 -119.447056)
		(end 190.716408 -119.292116)
		(width 0.11684)
		(layer "In2.Cu")
		(net "GPU_FPGA_BOOT_EN_R")
	)
	(segment
		(start 194.2084 -131.323588)
		(end 194.833748 -130.69824)
		(width 0.11684)
		(layer "In2.Cu")
		(net "GPU_FPGA_BOOT_EN_R")
	)
	(segment
		(start 200.135744 -119.241824)
		(end 199.4916 -119.241824)
		(width 0.10668)
		(layer "F.Cu")
		(net "PRSNT_CABLE_GPU_A1_ISO_R_N")
	)
	(segment
		(start 199.4916 -119.241824)
		(end 199.10933 -119.624094)
		(width 0.10668)
		(layer "F.Cu")
		(net "PRSNT_CABLE_GPU_A1_ISO_R_N")
	)
	(segment
		(start 194.361308 -117.448076)
		(end 193.517266 -117.448076)
		(width 0.10668)
		(layer "F.Cu")
		(net "PRSNT_CABLE_GPU_A1_ISO_R_N")
	)
	(segment
		(start 193.517266 -117.448076)
		(end 193.122042 -117.052852)
		(width 0.10668)
		(layer "F.Cu")
		(net "PRSNT_CABLE_GPU_A1_ISO_R_N")
	)
	(segment
		(start 198.23684 -119.624094)
		(end 198.147432 -119.534686)
		(width 0.10668)
		(layer "F.Cu")
		(net "PRSNT_CABLE_GPU_A1_ISO_R_N")
	)
	(segment
		(start 200.595484 -118.782084)
		(end 200.135744 -119.241824)
		(width 0.10668)
		(layer "F.Cu")
		(net "PRSNT_CABLE_GPU_A1_ISO_R_N")
	)
	(segment
		(start 198.147432 -119.534686)
		(end 196.447918 -119.534686)
		(width 0.10668)
		(layer "F.Cu")
		(net "PRSNT_CABLE_GPU_A1_ISO_R_N")
	)
	(segment
		(start 196.447918 -119.534686)
		(end 194.361308 -117.448076)
		(width 0.10668)
		(layer "F.Cu")
		(net "PRSNT_CABLE_GPU_A1_ISO_R_N")
	)
	(segment
		(start 199.10933 -119.624094)
		(end 198.23684 -119.624094)
		(width 0.10668)
		(layer "F.Cu")
		(net "PRSNT_CABLE_GPU_A1_ISO_R_N")
	)
	(via
		(at 199.10933 -119.624094)
		(size 0.762)
		(drill 0.381)
		(layers "F.Cu" "B.Cu")
		(net "PRSNT_CABLE_GPU_A1_ISO_R_N")
	)
	(segment
		(start 192.322196 -121.052844)
		(end 192.712086 -121.442734)
		(width 0.10668)
		(layer "F.Cu")
		(net "GPU_BASE_STBY_EN_R")
	)
	(segment
		(start 196.869558 -125.817376)
		(end 196.196458 -125.817376)
		(width 0.10668)
		(layer "F.Cu")
		(net "GPU_BASE_STBY_EN_R")
	)
	(via
		(at 196.196458 -125.817376)
		(size 0.508)
		(drill 0.254)
		(layers "F.Cu" "B.Cu")
		(net "GPU_BASE_STBY_EN_R")
	)
	(via
		(at 192.712086 -121.442734)
		(size 0.4572)
		(drill 0.254)
		(layers "F.Cu" "B.Cu")
		(net "GPU_BASE_STBY_EN_R")
	)
	(segment
		(start 195.08851 -123.82373)
		(end 195.08851 -124.709428)
		(width 0.11684)
		(layer "In6.Cu")
		(net "GPU_BASE_STBY_EN_R")
	)
	(segment
		(start 192.712086 -121.442734)
		(end 193.104008 -121.834656)
		(width 0.11684)
		(layer "In6.Cu")
		(net "GPU_BASE_STBY_EN_R")
	)
	(segment
		(start 193.104008 -121.834656)
		(end 193.104008 -122.82424)
		(width 0.11684)
		(layer "In6.Cu")
		(net "GPU_BASE_STBY_EN_R")
	)
	(segment
		(start 194.620896 -123.356116)
		(end 195.08851 -123.82373)
		(width 0.11684)
		(layer "In6.Cu")
		(net "GPU_BASE_STBY_EN_R")
	)
	(segment
		(start 193.635884 -123.356116)
		(end 194.620896 -123.356116)
		(width 0.11684)
		(layer "In6.Cu")
		(net "GPU_BASE_STBY_EN_R")
	)
	(segment
		(start 193.104008 -122.82424)
		(end 193.635884 -123.356116)
		(width 0.11684)
		(layer "In6.Cu")
		(net "GPU_BASE_STBY_EN_R")
	)
	(segment
		(start 195.08851 -124.709428)
		(end 196.196458 -125.817376)
		(width 0.11684)
		(layer "In6.Cu")
		(net "GPU_BASE_STBY_EN_R")
	)
	(segment
		(start 204.715618 -117.682772)
		(end 203.594208 -117.682772)
		(width 0.10668)
		(layer "F.Cu")
		(net "GPU_BASE_HMC_READY_ISO_R")
	)
	(segment
		(start 204.781658 -117.748812)
		(end 204.715618 -117.682772)
		(width 0.10668)
		(layer "F.Cu")
		(net "GPU_BASE_HMC_READY_ISO_R")
	)
	(segment
		(start 193.922142 -117.852952)
		(end 194.312032 -118.242842)
		(width 0.10668)
		(layer "F.Cu")
		(net "GPU_BASE_HMC_READY_ISO_R")
	)
	(via
		(at 203.594208 -117.682772)
		(size 0.762)
		(drill 0.254)
		(layers "F.Cu" "B.Cu")
		(net "GPU_BASE_HMC_READY_ISO_R")
	)
	(via
		(at 194.312032 -118.242842)
		(size 0.4572)
		(drill 0.254)
		(layers "F.Cu" "B.Cu")
		(net "GPU_BASE_HMC_READY_ISO_R")
	)
	(segment
		(start 203.116688 -117.205252)
		(end 200.658984 -117.205252)
		(width 0.11684)
		(layer "In6.Cu")
		(net "GPU_BASE_HMC_READY_ISO_R")
	)
	(segment
		(start 199.695562 -118.168674)
		(end 194.3862 -118.168674)
		(width 0.11684)
		(layer "In6.Cu")
		(net "GPU_BASE_HMC_READY_ISO_R")
	)
	(segment
		(start 203.594208 -117.682772)
		(end 203.116688 -117.205252)
		(width 0.11684)
		(layer "In6.Cu")
		(net "GPU_BASE_HMC_READY_ISO_R")
	)
	(segment
		(start 200.658984 -117.205252)
		(end 199.695562 -118.168674)
		(width 0.11684)
		(layer "In6.Cu")
		(net "GPU_BASE_HMC_READY_ISO_R")
	)
	(segment
		(start 194.3862 -118.168674)
		(end 194.312032 -118.242842)
		(width 0.11684)
		(layer "In6.Cu")
		(net "GPU_BASE_HMC_READY_ISO_R")
	)
	(segment
		(start 194.476624 -117.052852)
		(end 193.922142 -117.052852)
		(width 0.10668)
		(layer "F.Cu")
		(net "GPU_3V3IO_RSVD5_FFU_ISO_R")
	)
	(segment
		(start 199.568816 -118.25859)
		(end 198.605648 -119.221758)
		(width 0.10668)
		(layer "F.Cu")
		(net "GPU_3V3IO_RSVD5_FFU_ISO_R")
	)
	(segment
		(start 199.802496 -118.25859)
		(end 199.568816 -118.25859)
		(width 0.10668)
		(layer "F.Cu")
		(net "GPU_3V3IO_RSVD5_FFU_ISO_R")
	)
	(segment
		(start 198.605648 -119.221758)
		(end 196.64553 -119.221758)
		(width 0.10668)
		(layer "F.Cu")
		(net "GPU_3V3IO_RSVD5_FFU_ISO_R")
	)
	(segment
		(start 200.552558 -117.689376)
		(end 200.37171 -117.689376)
		(width 0.10668)
		(layer "F.Cu")
		(net "GPU_3V3IO_RSVD5_FFU_ISO_R")
	)
	(segment
		(start 200.37171 -117.689376)
		(end 199.802496 -118.25859)
		(width 0.10668)
		(layer "F.Cu")
		(net "GPU_3V3IO_RSVD5_FFU_ISO_R")
	)
	(segment
		(start 196.64553 -119.221758)
		(end 194.476624 -117.052852)
		(width 0.10668)
		(layer "F.Cu")
		(net "GPU_3V3IO_RSVD5_FFU_ISO_R")
	)
	(via
		(at 199.802496 -118.25859)
		(size 0.762)
		(drill 0.381)
		(layers "F.Cu" "B.Cu")
		(net "GPU_3V3IO_RSVD5_FFU_ISO_R")
	)
	(segment
		(start 190.721996 -116.252752)
		(end 191.111886 -116.642642)
		(width 0.10668)
		(layer "F.Cu")
		(net "GPU_3V3IO_RSVD4_ISO_R")
	)
	(segment
		(start 200.552558 -114.641376)
		(end 199.869298 -114.641376)
		(width 0.10668)
		(layer "F.Cu")
		(net "GPU_3V3IO_RSVD4_ISO_R")
	)
	(via
		(at 199.869298 -114.641376)
		(size 0.508)
		(drill 0.254)
		(layers "F.Cu" "B.Cu")
		(net "GPU_3V3IO_RSVD4_ISO_R")
	)
	(via
		(at 191.111886 -116.642642)
		(size 0.4572)
		(drill 0.254)
		(layers "F.Cu" "B.Cu")
		(net "GPU_3V3IO_RSVD4_ISO_R")
	)
	(segment
		(start 191.111886 -116.51234)
		(end 191.111886 -116.642642)
		(width 0.11684)
		(layer "In4.Cu")
		(net "GPU_3V3IO_RSVD4_ISO_R")
	)
	(segment
		(start 199.869298 -114.804444)
		(end 198.43877 -116.234972)
		(width 0.11684)
		(layer "In4.Cu")
		(net "GPU_3V3IO_RSVD4_ISO_R")
	)
	(segment
		(start 199.869298 -114.641376)
		(end 199.869298 -114.804444)
		(width 0.11684)
		(layer "In4.Cu")
		(net "GPU_3V3IO_RSVD4_ISO_R")
	)
	(segment
		(start 198.43877 -116.234972)
		(end 191.389254 -116.234972)
		(width 0.11684)
		(layer "In4.Cu")
		(net "GPU_3V3IO_RSVD4_ISO_R")
	)
	(segment
		(start 191.389254 -116.234972)
		(end 191.111886 -116.51234)
		(width 0.11684)
		(layer "In4.Cu")
		(net "GPU_3V3IO_RSVD4_ISO_R")
	)
	(segment
		(start 196.869558 -120.991376)
		(end 196.450458 -120.991376)
		(width 0.10668)
		(layer "F.Cu")
		(net "PRSNT_CABLE_GPU_A2_ISO_R_N")
	)
	(segment
		(start 190.721996 -117.052852)
		(end 191.111886 -117.442742)
		(width 0.10668)
		(layer "F.Cu")
		(net "PRSNT_CABLE_GPU_A2_ISO_R_N")
	)
	(segment
		(start 196.450458 -120.991376)
		(end 196.196458 -120.737376)
		(width 0.10668)
		(layer "F.Cu")
		(net "PRSNT_CABLE_GPU_A2_ISO_R_N")
	)
	(via
		(at 196.196458 -120.737376)
		(size 0.508)
		(drill 0.254)
		(layers "F.Cu" "B.Cu")
		(net "PRSNT_CABLE_GPU_A2_ISO_R_N")
	)
	(via
		(at 191.111886 -117.442742)
		(size 0.4572)
		(drill 0.254)
		(layers "F.Cu" "B.Cu")
		(net "PRSNT_CABLE_GPU_A2_ISO_R_N")
	)
	(segment
		(start 192.316608 -118.857776)
		(end 192.113408 -118.654576)
		(width 0.11684)
		(layer "In4.Cu")
		(net "PRSNT_CABLE_GPU_A2_ISO_R_N")
	)
	(segment
		(start 196.196458 -120.737376)
		(end 195.095368 -120.737376)
		(width 0.11684)
		(layer "In4.Cu")
		(net "PRSNT_CABLE_GPU_A2_ISO_R_N")
	)
	(segment
		(start 191.75095 -118.654068)
		(end 191.750442 -118.654576)
		(width 0.11684)
		(layer "In4.Cu")
		(net "PRSNT_CABLE_GPU_A2_ISO_R_N")
	)
	(segment
		(start 192.073022 -118.654068)
		(end 191.75095 -118.654068)
		(width 0.11684)
		(layer "In4.Cu")
		(net "PRSNT_CABLE_GPU_A2_ISO_R_N")
	)
	(segment
		(start 192.569846 -120.254014)
		(end 192.316608 -120.000776)
		(width 0.11684)
		(layer "In4.Cu")
		(net "PRSNT_CABLE_GPU_A2_ISO_R_N")
	)
	(segment
		(start 194.47383 -120.254776)
		(end 194.473068 -120.254014)
		(width 0.11684)
		(layer "In4.Cu")
		(net "PRSNT_CABLE_GPU_A2_ISO_R_N")
	)
	(segment
		(start 191.503808 -117.834664)
		(end 191.111886 -117.442742)
		(width 0.11684)
		(layer "In4.Cu")
		(net "PRSNT_CABLE_GPU_A2_ISO_R_N")
	)
	(segment
		(start 191.656208 -118.654576)
		(end 191.503808 -118.502176)
		(width 0.11684)
		(layer "In4.Cu")
		(net "PRSNT_CABLE_GPU_A2_ISO_R_N")
	)
	(segment
		(start 194.473068 -120.254014)
		(end 192.569846 -120.254014)
		(width 0.11684)
		(layer "In4.Cu")
		(net "PRSNT_CABLE_GPU_A2_ISO_R_N")
	)
	(segment
		(start 195.095368 -120.737376)
		(end 194.612768 -120.254776)
		(width 0.11684)
		(layer "In4.Cu")
		(net "PRSNT_CABLE_GPU_A2_ISO_R_N")
	)
	(segment
		(start 192.113408 -118.654576)
		(end 192.07353 -118.654576)
		(width 0.11684)
		(layer "In4.Cu")
		(net "PRSNT_CABLE_GPU_A2_ISO_R_N")
	)
	(segment
		(start 194.612768 -120.254776)
		(end 194.47383 -120.254776)
		(width 0.11684)
		(layer "In4.Cu")
		(net "PRSNT_CABLE_GPU_A2_ISO_R_N")
	)
	(segment
		(start 191.750442 -118.654576)
		(end 191.656208 -118.654576)
		(width 0.11684)
		(layer "In4.Cu")
		(net "PRSNT_CABLE_GPU_A2_ISO_R_N")
	)
	(segment
		(start 192.07353 -118.654576)
		(end 192.073022 -118.654068)
		(width 0.11684)
		(layer "In4.Cu")
		(net "PRSNT_CABLE_GPU_A2_ISO_R_N")
	)
	(segment
		(start 191.503808 -118.502176)
		(end 191.503808 -117.834664)
		(width 0.11684)
		(layer "In4.Cu")
		(net "PRSNT_CABLE_GPU_A2_ISO_R_N")
	)
	(segment
		(start 192.316608 -120.000776)
		(end 192.316608 -118.857776)
		(width 0.11684)
		(layer "In4.Cu")
		(net "PRSNT_CABLE_GPU_A2_ISO_R_N")
	)
	(segment
		(start 198.857616 -116.102638)
		(end 196.996558 -116.102638)
		(width 0.10668)
		(layer "F.Cu")
		(net "GPU_3V3IO_RSVD3_ISO_R")
	)
	(segment
		(start 199.084184 -115.87607)
		(end 198.857616 -116.102638)
		(width 0.10668)
		(layer "F.Cu")
		(net "GPU_3V3IO_RSVD3_ISO_R")
	)
	(segment
		(start 193.509392 -115.065556)
		(end 193.122042 -115.452906)
		(width 0.10668)
		(layer "F.Cu")
		(net "GPU_3V3IO_RSVD3_ISO_R")
	)
	(segment
		(start 196.869558 -115.975638)
		(end 196.869558 -115.657376)
		(width 0.10668)
		(layer "F.Cu")
		(net "GPU_3V3IO_RSVD3_ISO_R")
	)
	(segment
		(start 195.542408 -115.657376)
		(end 194.950588 -115.065556)
		(width 0.10668)
		(layer "F.Cu")
		(net "GPU_3V3IO_RSVD3_ISO_R")
	)
	(segment
		(start 196.869558 -115.657376)
		(end 195.542408 -115.657376)
		(width 0.10668)
		(layer "F.Cu")
		(net "GPU_3V3IO_RSVD3_ISO_R")
	)
	(segment
		(start 196.996558 -116.102638)
		(end 196.869558 -115.975638)
		(width 0.10668)
		(layer "F.Cu")
		(net "GPU_3V3IO_RSVD3_ISO_R")
	)
	(segment
		(start 194.950588 -115.065556)
		(end 193.509392 -115.065556)
		(width 0.10668)
		(layer "F.Cu")
		(net "GPU_3V3IO_RSVD3_ISO_R")
	)
	(via
		(at 199.084184 -115.87607)
		(size 0.762)
		(drill 0.381)
		(layers "F.Cu" "B.Cu")
		(net "GPU_3V3IO_RSVD3_ISO_R")
	)
	(segment
		(start 204.843634 -121.960386)
		(end 203.899008 -121.960386)
		(width 0.10668)
		(layer "F.Cu")
		(net "GPU_3V3IO_RSVD3_FFU_ISO_R")
	)
	(segment
		(start 181.122066 -115.452906)
		(end 180.732176 -115.842796)
		(width 0.10668)
		(layer "F.Cu")
		(net "GPU_3V3IO_RSVD3_FFU_ISO_R")
	)
	(via
		(at 203.899008 -121.960386)
		(size 0.508)
		(drill 0.254)
		(layers "F.Cu" "B.Cu")
		(net "GPU_3V3IO_RSVD3_FFU_ISO_R")
	)
	(via
		(at 180.732176 -115.842796)
		(size 0.4572)
		(drill 0.254)
		(layers "F.Cu" "B.Cu")
		(net "GPU_3V3IO_RSVD3_FFU_ISO_R")
	)
	(segment
		(start 194.776598 -114.997992)
		(end 197.337172 -117.558566)
		(width 0.11684)
		(layer "In2.Cu")
		(net "GPU_3V3IO_RSVD3_FFU_ISO_R")
	)
	(segment
		(start 198.04253 -119.17807)
		(end 200.851008 -119.17807)
		(width 0.11684)
		(layer "In2.Cu")
		(net "GPU_3V3IO_RSVD3_FFU_ISO_R")
	)
	(segment
		(start 180.732176 -115.842796)
		(end 180.732176 -115.679474)
		(width 0.11684)
		(layer "In2.Cu")
		(net "GPU_3V3IO_RSVD3_FFU_ISO_R")
	)
	(segment
		(start 190.505334 -114.997992)
		(end 194.776598 -114.997992)
		(width 0.11684)
		(layer "In2.Cu")
		(net "GPU_3V3IO_RSVD3_FFU_ISO_R")
	)
	(segment
		(start 202.118214 -120.445276)
		(end 204.11694 -120.445276)
		(width 0.11684)
		(layer "In2.Cu")
		(net "GPU_3V3IO_RSVD3_FFU_ISO_R")
	)
	(segment
		(start 204.365098 -120.693434)
		(end 204.365098 -121.494296)
		(width 0.11684)
		(layer "In2.Cu")
		(net "GPU_3V3IO_RSVD3_FFU_ISO_R")
	)
	(segment
		(start 204.11694 -120.445276)
		(end 204.365098 -120.693434)
		(width 0.11684)
		(layer "In2.Cu")
		(net "GPU_3V3IO_RSVD3_FFU_ISO_R")
	)
	(segment
		(start 204.365098 -121.494296)
		(end 203.899008 -121.960386)
		(width 0.11684)
		(layer "In2.Cu")
		(net "GPU_3V3IO_RSVD3_FFU_ISO_R")
	)
	(segment
		(start 197.337172 -118.472712)
		(end 198.04253 -119.17807)
		(width 0.11684)
		(layer "In2.Cu")
		(net "GPU_3V3IO_RSVD3_FFU_ISO_R")
	)
	(segment
		(start 181.152292 -115.259358)
		(end 190.243968 -115.259358)
		(width 0.11684)
		(layer "In2.Cu")
		(net "GPU_3V3IO_RSVD3_FFU_ISO_R")
	)
	(segment
		(start 200.851008 -119.17807)
		(end 202.118214 -120.445276)
		(width 0.11684)
		(layer "In2.Cu")
		(net "GPU_3V3IO_RSVD3_FFU_ISO_R")
	)
	(segment
		(start 180.732176 -115.679474)
		(end 181.152292 -115.259358)
		(width 0.11684)
		(layer "In2.Cu")
		(net "GPU_3V3IO_RSVD3_FFU_ISO_R")
	)
	(segment
		(start 197.337172 -117.558566)
		(end 197.337172 -118.472712)
		(width 0.11684)
		(layer "In2.Cu")
		(net "GPU_3V3IO_RSVD3_FFU_ISO_R")
	)
	(segment
		(start 190.243968 -115.259358)
		(end 190.505334 -114.997992)
		(width 0.11684)
		(layer "In2.Cu")
		(net "GPU_3V3IO_RSVD3_FFU_ISO_R")
	)
	(segment
		(start 181.922166 -115.452906)
		(end 181.532276 -115.842796)
		(width 0.10668)
		(layer "F.Cu")
		(net "PRSNT_CABLE_GPU_B3_ISO_R_N")
	)
	(segment
		(start 174.57674 -128.977898)
		(end 174.57674 -127.115062)
		(width 0.10668)
		(layer "F.Cu")
		(net "PRSNT_CABLE_GPU_B3_ISO_R_N")
	)
	(via
		(at 174.57674 -127.115062)
		(size 0.508)
		(drill 0.254)
		(layers "F.Cu" "B.Cu")
		(net "PRSNT_CABLE_GPU_B3_ISO_R_N")
	)
	(via
		(at 181.532276 -115.842796)
		(size 0.4572)
		(drill 0.254)
		(layers "F.Cu" "B.Cu")
		(net "PRSNT_CABLE_GPU_B3_ISO_R_N")
	)
	(segment
		(start 180.340508 -120.457976)
		(end 180.340508 -126.132082)
		(width 0.11684)
		(layer "In11.Cu")
		(net "PRSNT_CABLE_GPU_B3_ISO_R_N")
	)
	(segment
		(start 180.962046 -120.237504)
		(end 180.56098 -120.237504)
		(width 0.11684)
		(layer "In11.Cu")
		(net "PRSNT_CABLE_GPU_B3_ISO_R_N")
	)
	(segment
		(start 181.13375 -119.555006)
		(end 181.13375 -120.0658)
		(width 0.11684)
		(layer "In11.Cu")
		(net "PRSNT_CABLE_GPU_B3_ISO_R_N")
	)
	(segment
		(start 180.340508 -126.132082)
		(end 178.694842 -127.777748)
		(width 0.11684)
		(layer "In11.Cu")
		(net "PRSNT_CABLE_GPU_B3_ISO_R_N")
	)
	(segment
		(start 181.532276 -115.842796)
		(end 181.780434 -115.842796)
		(width 0.11684)
		(layer "In11.Cu")
		(net "PRSNT_CABLE_GPU_B3_ISO_R_N")
	)
	(segment
		(start 181.257448 -119.431308)
		(end 181.13375 -119.555006)
		(width 0.11684)
		(layer "In11.Cu")
		(net "PRSNT_CABLE_GPU_B3_ISO_R_N")
	)
	(segment
		(start 181.920896 -119.294656)
		(end 181.784244 -119.431308)
		(width 0.11684)
		(layer "In11.Cu")
		(net "PRSNT_CABLE_GPU_B3_ISO_R_N")
	)
	(segment
		(start 181.920896 -115.983258)
		(end 181.920896 -119.294656)
		(width 0.11684)
		(layer "In11.Cu")
		(net "PRSNT_CABLE_GPU_B3_ISO_R_N")
	)
	(segment
		(start 178.694842 -127.777748)
		(end 175.239426 -127.777748)
		(width 0.11684)
		(layer "In11.Cu")
		(net "PRSNT_CABLE_GPU_B3_ISO_R_N")
	)
	(segment
		(start 181.784244 -119.431308)
		(end 181.257448 -119.431308)
		(width 0.11684)
		(layer "In11.Cu")
		(net "PRSNT_CABLE_GPU_B3_ISO_R_N")
	)
	(segment
		(start 181.780434 -115.842796)
		(end 181.920896 -115.983258)
		(width 0.11684)
		(layer "In11.Cu")
		(net "PRSNT_CABLE_GPU_B3_ISO_R_N")
	)
	(segment
		(start 180.56098 -120.237504)
		(end 180.340508 -120.457976)
		(width 0.11684)
		(layer "In11.Cu")
		(net "PRSNT_CABLE_GPU_B3_ISO_R_N")
	)
	(segment
		(start 181.13375 -120.0658)
		(end 180.962046 -120.237504)
		(width 0.11684)
		(layer "In11.Cu")
		(net "PRSNT_CABLE_GPU_B3_ISO_R_N")
	)
	(segment
		(start 175.239426 -127.777748)
		(end 174.57674 -127.115062)
		(width 0.11684)
		(layer "In11.Cu")
		(net "PRSNT_CABLE_GPU_B3_ISO_R_N")
	)
	(segment
		(start 193.922142 -115.452906)
		(end 194.312032 -115.842796)
		(width 0.10668)
		(layer "F.Cu")
		(net "GPU_3V3IO_RSVD1_ISO_R")
	)
	(via
		(at 196.672454 -116.532152)
		(size 0.6604)
		(drill 0.3302)
		(layers "F.Cu" "B.Cu")
		(net "GPU_3V3IO_RSVD1_ISO_R")
	)
	(via
		(at 194.312032 -115.842796)
		(size 0.4572)
		(drill 0.254)
		(layers "F.Cu" "B.Cu")
		(net "GPU_3V3IO_RSVD1_ISO_R")
	)
	(segment
		(start 194.973448 -115.842796)
		(end 195.285868 -116.155216)
		(width 0.10668)
		(layer "B.Cu")
		(net "GPU_3V3IO_RSVD1_ISO_R")
	)
	(segment
		(start 196.295518 -116.155216)
		(end 196.672454 -116.532152)
		(width 0.10668)
		(layer "B.Cu")
		(net "GPU_3V3IO_RSVD1_ISO_R")
	)
	(segment
		(start 195.285868 -116.155216)
		(end 196.295518 -116.155216)
		(width 0.10668)
		(layer "B.Cu")
		(net "GPU_3V3IO_RSVD1_ISO_R")
	)
	(segment
		(start 194.312032 -115.842796)
		(end 194.973448 -115.842796)
		(width 0.10668)
		(layer "B.Cu")
		(net "GPU_3V3IO_RSVD1_ISO_R")
	)
	(segment
		(start 196.869558 -116.729256)
		(end 196.869558 -117.689376)
		(width 0.10668)
		(layer "B.Cu")
		(net "GPU_3V3IO_RSVD1_ISO_R")
	)
	(segment
		(start 196.672454 -116.532152)
		(end 196.869558 -116.729256)
		(width 0.10668)
		(layer "B.Cu")
		(net "GPU_3V3IO_RSVD1_ISO_R")
	)
	(segment
		(start 204.843634 -120.944386)
		(end 202.555602 -120.944386)
		(width 0.10668)
		(layer "F.Cu")
		(net "GPU_3V3IO_RSVD1_FFU_ISO_R")
	)
	(segment
		(start 189.12205 -116.252752)
		(end 189.51194 -116.642642)
		(width 0.10668)
		(layer "F.Cu")
		(net "GPU_3V3IO_RSVD1_FFU_ISO_R")
	)
	(via
		(at 189.51194 -116.642642)
		(size 0.4572)
		(drill 0.254)
		(layers "F.Cu" "B.Cu")
		(net "GPU_3V3IO_RSVD1_FFU_ISO_R")
	)
	(via
		(at 202.555602 -120.944386)
		(size 0.508)
		(drill 0.254)
		(layers "F.Cu" "B.Cu")
		(net "GPU_3V3IO_RSVD1_FFU_ISO_R")
	)
	(segment
		(start 200.276206 -120.197118)
		(end 201.023474 -120.944386)
		(width 0.11684)
		(layer "In2.Cu")
		(net "GPU_3V3IO_RSVD1_FFU_ISO_R")
	)
	(segment
		(start 189.51194 -116.642642)
		(end 189.903608 -116.250974)
		(width 0.11684)
		(layer "In2.Cu")
		(net "GPU_3V3IO_RSVD1_FFU_ISO_R")
	)
	(segment
		(start 196.331332 -118.232682)
		(end 197.598538 -119.499888)
		(width 0.11684)
		(layer "In2.Cu")
		(net "GPU_3V3IO_RSVD1_FFU_ISO_R")
	)
	(segment
		(start 190.891668 -115.454176)
		(end 193.332608 -115.454176)
		(width 0.11684)
		(layer "In2.Cu")
		(net "GPU_3V3IO_RSVD1_FFU_ISO_R")
	)
	(segment
		(start 197.598538 -119.499888)
		(end 197.598538 -119.883428)
		(width 0.11684)
		(layer "In2.Cu")
		(net "GPU_3V3IO_RSVD1_FFU_ISO_R")
	)
	(segment
		(start 201.023474 -120.944386)
		(end 202.555602 -120.944386)
		(width 0.11684)
		(layer "In2.Cu")
		(net "GPU_3V3IO_RSVD1_FFU_ISO_R")
	)
	(segment
		(start 193.332608 -115.454176)
		(end 196.111114 -118.232682)
		(width 0.11684)
		(layer "In2.Cu")
		(net "GPU_3V3IO_RSVD1_FFU_ISO_R")
	)
	(segment
		(start 190.453518 -116.250974)
		(end 190.70066 -116.003832)
		(width 0.11684)
		(layer "In2.Cu")
		(net "GPU_3V3IO_RSVD1_FFU_ISO_R")
	)
	(segment
		(start 190.70066 -116.003832)
		(end 190.70066 -115.645184)
		(width 0.11684)
		(layer "In2.Cu")
		(net "GPU_3V3IO_RSVD1_FFU_ISO_R")
	)
	(segment
		(start 189.903608 -116.250974)
		(end 190.453518 -116.250974)
		(width 0.11684)
		(layer "In2.Cu")
		(net "GPU_3V3IO_RSVD1_FFU_ISO_R")
	)
	(segment
		(start 196.111114 -118.232682)
		(end 196.331332 -118.232682)
		(width 0.11684)
		(layer "In2.Cu")
		(net "GPU_3V3IO_RSVD1_FFU_ISO_R")
	)
	(segment
		(start 190.70066 -115.645184)
		(end 190.891668 -115.454176)
		(width 0.11684)
		(layer "In2.Cu")
		(net "GPU_3V3IO_RSVD1_FFU_ISO_R")
	)
	(segment
		(start 197.912228 -120.197118)
		(end 200.276206 -120.197118)
		(width 0.11684)
		(layer "In2.Cu")
		(net "GPU_3V3IO_RSVD1_FFU_ISO_R")
	)
	(segment
		(start 197.598538 -119.883428)
		(end 197.912228 -120.197118)
		(width 0.11684)
		(layer "In2.Cu")
		(net "GPU_3V3IO_RSVD1_FFU_ISO_R")
	)
	(segment
		(start 191.522096 -116.252752)
		(end 191.911986 -116.642642)
		(width 0.10668)
		(layer "F.Cu")
		(net "GPU_3V3IO_RSVD0_FFU_ISO_R")
	)
	(via
		(at 193.957448 -117.341142)
		(size 0.6604)
		(drill 0.3302)
		(layers "F.Cu" "B.Cu")
		(net "GPU_3V3IO_RSVD0_FFU_ISO_R")
	)
	(via
		(at 191.911986 -116.642642)
		(size 0.4572)
		(drill 0.254)
		(layers "F.Cu" "B.Cu")
		(net "GPU_3V3IO_RSVD0_FFU_ISO_R")
	)
	(segment
		(start 195.58 -120.181116)
		(end 195.205604 -119.80672)
		(width 0.10668)
		(layer "B.Cu")
		(net "GPU_3V3IO_RSVD0_FFU_ISO_R")
	)
	(segment
		(start 195.205604 -119.80672)
		(end 195.205604 -119.195088)
		(width 0.10668)
		(layer "B.Cu")
		(net "GPU_3V3IO_RSVD0_FFU_ISO_R")
	)
	(segment
		(start 195.551044 -118.849648)
		(end 195.551044 -118.163086)
		(width 0.10668)
		(layer "B.Cu")
		(net "GPU_3V3IO_RSVD0_FFU_ISO_R")
	)
	(segment
		(start 195.551044 -118.163086)
		(end 194.7291 -117.341142)
		(width 0.10668)
		(layer "B.Cu")
		(net "GPU_3V3IO_RSVD0_FFU_ISO_R")
	)
	(segment
		(start 194.7291 -117.341142)
		(end 193.957448 -117.341142)
		(width 0.10668)
		(layer "B.Cu")
		(net "GPU_3V3IO_RSVD0_FFU_ISO_R")
	)
	(segment
		(start 196.869558 -120.737376)
		(end 196.313298 -120.181116)
		(width 0.10668)
		(layer "B.Cu")
		(net "GPU_3V3IO_RSVD0_FFU_ISO_R")
	)
	(segment
		(start 193.655188 -117.038882)
		(end 192.308226 -117.038882)
		(width 0.10668)
		(layer "B.Cu")
		(net "GPU_3V3IO_RSVD0_FFU_ISO_R")
	)
	(segment
		(start 192.308226 -117.038882)
		(end 191.911986 -116.642642)
		(width 0.10668)
		(layer "B.Cu")
		(net "GPU_3V3IO_RSVD0_FFU_ISO_R")
	)
	(segment
		(start 195.205604 -119.195088)
		(end 195.551044 -118.849648)
		(width 0.10668)
		(layer "B.Cu")
		(net "GPU_3V3IO_RSVD0_FFU_ISO_R")
	)
	(segment
		(start 193.957448 -117.341142)
		(end 193.655188 -117.038882)
		(width 0.10668)
		(layer "B.Cu")
		(net "GPU_3V3IO_RSVD0_FFU_ISO_R")
	)
	(segment
		(start 196.313298 -120.181116)
		(end 195.58 -120.181116)
		(width 0.10668)
		(layer "B.Cu")
		(net "GPU_3V3IO_RSVD0_FFU_ISO_R")
	)
	(segment
		(start 167.53205 -109.184948)
		(end 167.94099 -109.184948)
		(width 0.10668)
		(layer "F.Cu")
		(net "FM_UV_ADR_TRIGGER_R_N")
	)
	(segment
		(start 167.945562 -109.180376)
		(end 168.148 -109.180376)
		(width 0.10668)
		(layer "F.Cu")
		(net "FM_UV_ADR_TRIGGER_R_N")
	)
	(segment
		(start 177.122074 -111.452914)
		(end 176.732184 -111.063024)
		(width 0.10668)
		(layer "F.Cu")
		(net "FM_UV_ADR_TRIGGER_R_N")
	)
	(segment
		(start 167.94099 -109.184948)
		(end 167.945562 -109.180376)
		(width 0.10668)
		(layer "F.Cu")
		(net "FM_UV_ADR_TRIGGER_R_N")
	)
	(via
		(at 176.732184 -111.063024)
		(size 0.4572)
		(drill 0.254)
		(layers "F.Cu" "B.Cu")
		(net "FM_UV_ADR_TRIGGER_R_N")
	)
	(via
		(at 168.148 -109.180376)
		(size 0.508)
		(drill 0.254)
		(layers "F.Cu" "B.Cu")
		(net "FM_UV_ADR_TRIGGER_R_N")
	)
	(segment
		(start 176.464976 -111.063024)
		(end 175.106584 -109.704632)
		(width 0.11684)
		(layer "In2.Cu")
		(net "FM_UV_ADR_TRIGGER_R_N")
	)
	(segment
		(start 175.106584 -109.704632)
		(end 168.672256 -109.704632)
		(width 0.11684)
		(layer "In2.Cu")
		(net "FM_UV_ADR_TRIGGER_R_N")
	)
	(segment
		(start 168.672256 -109.704632)
		(end 168.148 -109.180376)
		(width 0.11684)
		(layer "In2.Cu")
		(net "FM_UV_ADR_TRIGGER_R_N")
	)
	(segment
		(start 176.732184 -111.063024)
		(end 176.464976 -111.063024)
		(width 0.11684)
		(layer "In2.Cu")
		(net "FM_UV_ADR_TRIGGER_R_N")
	)
	(segment
		(start 195.377308 -102.68712)
		(end 195.964048 -102.10038)
		(width 0.10668)
		(layer "F.Cu")
		(net "FM_SWB_PWR_EN")
	)
	(segment
		(start 194.7926 -106.422444)
		(end 194.150488 -107.064556)
		(width 0.10668)
		(layer "F.Cu")
		(net "FM_SWB_PWR_EN")
	)
	(segment
		(start 194.146678 -105.857802)
		(end 194.467734 -105.857802)
		(width 0.10668)
		(layer "F.Cu")
		(net "FM_SWB_PWR_EN")
	)
	(segment
		(start 194.7926 -106.182668)
		(end 194.7926 -106.422444)
		(width 0.10668)
		(layer "F.Cu")
		(net "FM_SWB_PWR_EN")
	)
	(segment
		(start 194.6402 -102.68712)
		(end 194.010788 -103.316532)
		(width 0.10668)
		(layer "F.Cu")
		(net "FM_SWB_PWR_EN")
	)
	(segment
		(start 194.467734 -105.857802)
		(end 194.7926 -106.182668)
		(width 0.10668)
		(layer "F.Cu")
		(net "FM_SWB_PWR_EN")
	)
	(segment
		(start 195.961 -101.104192)
		(end 195.961 -100.694998)
		(width 0.10668)
		(layer "F.Cu")
		(net "FM_SWB_PWR_EN")
	)
	(segment
		(start 194.150488 -107.064556)
		(end 193.510408 -107.064556)
		(width 0.10668)
		(layer "F.Cu")
		(net "FM_SWB_PWR_EN")
	)
	(segment
		(start 194.010788 -105.721912)
		(end 194.146678 -105.857802)
		(width 0.10668)
		(layer "F.Cu")
		(net "FM_SWB_PWR_EN")
	)
	(segment
		(start 193.510408 -107.064556)
		(end 193.122042 -107.452922)
		(width 0.10668)
		(layer "F.Cu")
		(net "FM_SWB_PWR_EN")
	)
	(segment
		(start 194.6402 -102.68712)
		(end 195.377308 -102.68712)
		(width 0.10668)
		(layer "F.Cu")
		(net "FM_SWB_PWR_EN")
	)
	(segment
		(start 194.010788 -103.316532)
		(end 194.010788 -105.721912)
		(width 0.10668)
		(layer "F.Cu")
		(net "FM_SWB_PWR_EN")
	)
	(segment
		(start 195.964048 -102.10038)
		(end 195.964048 -101.10724)
		(width 0.10668)
		(layer "F.Cu")
		(net "FM_SWB_PWR_EN")
	)
	(segment
		(start 195.964048 -101.10724)
		(end 195.961 -101.104192)
		(width 0.10668)
		(layer "F.Cu")
		(net "FM_SWB_PWR_EN")
	)
	(via
		(at 194.6402 -102.68712)
		(size 0.762)
		(drill 0.381)
		(layers "F.Cu" "B.Cu")
		(net "FM_SWB_PWR_EN")
	)
	(segment
		(start 193.922142 -120.252744)
		(end 194.312032 -120.642634)
		(width 0.10668)
		(layer "F.Cu")
		(net "FM_SWB_PWRGD_ISO_R")
	)
	(segment
		(start 204.832458 -124.801376)
		(end 203.645262 -124.801376)
		(width 0.10668)
		(layer "F.Cu")
		(net "FM_SWB_PWRGD_ISO_R")
	)
	(via
		(at 194.312032 -120.642634)
		(size 0.4572)
		(drill 0.254)
		(layers "F.Cu" "B.Cu")
		(net "FM_SWB_PWRGD_ISO_R")
	)
	(via
		(at 203.645262 -124.801376)
		(size 0.508)
		(drill 0.254)
		(layers "F.Cu" "B.Cu")
		(net "FM_SWB_PWRGD_ISO_R")
	)
	(segment
		(start 197.46595 -123.893072)
		(end 194.312032 -120.739154)
		(width 0.11684)
		(layer "In2.Cu")
		(net "FM_SWB_PWRGD_ISO_R")
	)
	(segment
		(start 194.312032 -120.739154)
		(end 194.312032 -120.642634)
		(width 0.11684)
		(layer "In2.Cu")
		(net "FM_SWB_PWRGD_ISO_R")
	)
	(segment
		(start 201.647806 -125.265434)
		(end 199.155558 -125.265434)
		(width 0.11684)
		(layer "In2.Cu")
		(net "FM_SWB_PWRGD_ISO_R")
	)
	(segment
		(start 203.645262 -124.801376)
		(end 202.111864 -124.801376)
		(width 0.11684)
		(layer "In2.Cu")
		(net "FM_SWB_PWRGD_ISO_R")
	)
	(segment
		(start 202.111864 -124.801376)
		(end 201.647806 -125.265434)
		(width 0.11684)
		(layer "In2.Cu")
		(net "FM_SWB_PWRGD_ISO_R")
	)
	(segment
		(start 197.46595 -124.278644)
		(end 197.46595 -123.893072)
		(width 0.11684)
		(layer "In2.Cu")
		(net "FM_SWB_PWRGD_ISO_R")
	)
	(segment
		(start 198.052182 -124.864876)
		(end 197.46595 -124.278644)
		(width 0.11684)
		(layer "In2.Cu")
		(net "FM_SWB_PWRGD_ISO_R")
	)
	(segment
		(start 199.155558 -125.265434)
		(end 198.755 -124.864876)
		(width 0.11684)
		(layer "In2.Cu")
		(net "FM_SWB_PWRGD_ISO_R")
	)
	(segment
		(start 198.755 -124.864876)
		(end 198.052182 -124.864876)
		(width 0.11684)
		(layer "In2.Cu")
		(net "FM_SWB_PWRGD_ISO_R")
	)
	(segment
		(start 193.922142 -119.452898)
		(end 194.312032 -119.842788)
		(width 0.10668)
		(layer "F.Cu")
		(net "FM_SWB_BIC_READY_ISO_R_N")
	)
	(segment
		(start 204.814932 -123.785376)
		(end 203.899008 -123.785376)
		(width 0.10668)
		(layer "F.Cu")
		(net "FM_SWB_BIC_READY_ISO_R_N")
	)
	(via
		(at 203.899008 -123.785376)
		(size 0.508)
		(drill 0.254)
		(layers "F.Cu" "B.Cu")
		(net "FM_SWB_BIC_READY_ISO_R_N")
	)
	(via
		(at 194.312032 -119.842788)
		(size 0.4572)
		(drill 0.254)
		(layers "F.Cu" "B.Cu")
		(net "FM_SWB_BIC_READY_ISO_R_N")
	)
	(segment
		(start 198.49084 -123.632468)
		(end 197.820026 -123.632468)
		(width 0.11684)
		(layer "In2.Cu")
		(net "FM_SWB_BIC_READY_ISO_R_N")
	)
	(segment
		(start 198.960994 -124.102622)
		(end 198.49084 -123.632468)
		(width 0.11684)
		(layer "In2.Cu")
		(net "FM_SWB_BIC_READY_ISO_R_N")
	)
	(segment
		(start 201.185272 -124.102622)
		(end 198.960994 -124.102622)
		(width 0.11684)
		(layer "In2.Cu")
		(net "FM_SWB_BIC_READY_ISO_R_N")
	)
	(segment
		(start 203.461366 -123.785376)
		(end 202.882754 -124.363988)
		(width 0.11684)
		(layer "In2.Cu")
		(net "FM_SWB_BIC_READY_ISO_R_N")
	)
	(segment
		(start 195.293488 -121.10593)
		(end 195.293488 -120.824244)
		(width 0.11684)
		(layer "In2.Cu")
		(net "FM_SWB_BIC_READY_ISO_R_N")
	)
	(segment
		(start 197.820026 -123.632468)
		(end 195.293488 -121.10593)
		(width 0.11684)
		(layer "In2.Cu")
		(net "FM_SWB_BIC_READY_ISO_R_N")
	)
	(segment
		(start 201.446638 -124.363988)
		(end 201.185272 -124.102622)
		(width 0.11684)
		(layer "In2.Cu")
		(net "FM_SWB_BIC_READY_ISO_R_N")
	)
	(segment
		(start 202.882754 -124.363988)
		(end 201.446638 -124.363988)
		(width 0.11684)
		(layer "In2.Cu")
		(net "FM_SWB_BIC_READY_ISO_R_N")
	)
	(segment
		(start 203.899008 -123.785376)
		(end 203.461366 -123.785376)
		(width 0.11684)
		(layer "In2.Cu")
		(net "FM_SWB_BIC_READY_ISO_R_N")
	)
	(segment
		(start 195.293488 -120.824244)
		(end 194.312032 -119.842788)
		(width 0.11684)
		(layer "In2.Cu")
		(net "FM_SWB_BIC_READY_ISO_R_N")
	)
	(segment
		(start 192.322196 -120.252744)
		(end 192.712086 -120.642634)
		(width 0.10668)
		(layer "F.Cu")
		(net "FM_SMB_2_ALERT_GPU_ISO_R_N")
	)
	(segment
		(start 196.869558 -123.785376)
		(end 196.196458 -123.785376)
		(width 0.10668)
		(layer "F.Cu")
		(net "FM_SMB_2_ALERT_GPU_ISO_R_N")
	)
	(via
		(at 196.196458 -123.785376)
		(size 0.508)
		(drill 0.254)
		(layers "F.Cu" "B.Cu")
		(net "FM_SMB_2_ALERT_GPU_ISO_R_N")
	)
	(via
		(at 192.712086 -120.642634)
		(size 0.4572)
		(drill 0.254)
		(layers "F.Cu" "B.Cu")
		(net "FM_SMB_2_ALERT_GPU_ISO_R_N")
	)
	(segment
		(start 195.50507 -123.093988)
		(end 194.035172 -123.093988)
		(width 0.11684)
		(layer "In6.Cu")
		(net "FM_SMB_2_ALERT_GPU_ISO_R_N")
	)
	(segment
		(start 193.114422 -121.04497)
		(end 192.712086 -120.642634)
		(width 0.11684)
		(layer "In6.Cu")
		(net "FM_SMB_2_ALERT_GPU_ISO_R_N")
	)
	(segment
		(start 194.035172 -123.093988)
		(end 193.908172 -122.966988)
		(width 0.11684)
		(layer "In6.Cu")
		(net "FM_SMB_2_ALERT_GPU_ISO_R_N")
	)
	(segment
		(start 193.908172 -122.966988)
		(end 193.908172 -121.25071)
		(width 0.11684)
		(layer "In6.Cu")
		(net "FM_SMB_2_ALERT_GPU_ISO_R_N")
	)
	(segment
		(start 193.908172 -121.25071)
		(end 193.702432 -121.04497)
		(width 0.11684)
		(layer "In6.Cu")
		(net "FM_SMB_2_ALERT_GPU_ISO_R_N")
	)
	(segment
		(start 193.702432 -121.04497)
		(end 193.114422 -121.04497)
		(width 0.11684)
		(layer "In6.Cu")
		(net "FM_SMB_2_ALERT_GPU_ISO_R_N")
	)
	(segment
		(start 196.196458 -123.785376)
		(end 195.50507 -123.093988)
		(width 0.11684)
		(layer "In6.Cu")
		(net "FM_SMB_2_ALERT_GPU_ISO_R_N")
	)
	(segment
		(start 193.122042 -119.452898)
		(end 193.511932 -119.842788)
		(width 0.10668)
		(layer "F.Cu")
		(net "FM_SMB_1_ALERT_GPU_ISO_R_N")
	)
	(segment
		(start 204.814932 -119.721376)
		(end 203.675996 -119.721376)
		(width 0.10668)
		(layer "F.Cu")
		(net "FM_SMB_1_ALERT_GPU_ISO_R_N")
	)
	(via
		(at 203.675996 -119.721376)
		(size 0.508)
		(drill 0.254)
		(layers "F.Cu" "B.Cu")
		(net "FM_SMB_1_ALERT_GPU_ISO_R_N")
	)
	(via
		(at 193.511932 -119.842788)
		(size 0.4572)
		(drill 0.254)
		(layers "F.Cu" "B.Cu")
		(net "FM_SMB_1_ALERT_GPU_ISO_R_N")
	)
	(segment
		(start 202.941174 -120.241568)
		(end 193.792602 -120.241568)
		(width 0.11684)
		(layer "In13.Cu")
		(net "FM_SMB_1_ALERT_GPU_ISO_R_N")
	)
	(segment
		(start 203.461366 -119.721376)
		(end 202.941174 -120.241568)
		(width 0.11684)
		(layer "In13.Cu")
		(net "FM_SMB_1_ALERT_GPU_ISO_R_N")
	)
	(segment
		(start 193.792602 -120.241568)
		(end 193.511932 -119.960898)
		(width 0.11684)
		(layer "In13.Cu")
		(net "FM_SMB_1_ALERT_GPU_ISO_R_N")
	)
	(segment
		(start 193.511932 -119.960898)
		(end 193.511932 -119.842788)
		(width 0.11684)
		(layer "In13.Cu")
		(net "FM_SMB_1_ALERT_GPU_ISO_R_N")
	)
	(segment
		(start 203.675996 -119.721376)
		(end 203.461366 -119.721376)
		(width 0.11684)
		(layer "In13.Cu")
		(net "FM_SMB_1_ALERT_GPU_ISO_R_N")
	)
	(segment
		(start 191.522096 -110.652814)
		(end 191.911986 -110.262924)
		(width 0.10668)
		(layer "F.Cu")
		(net "FM_GPU_PWR_EN")
	)
	(segment
		(start 208.526634 -111.576866)
		(end 207.323944 -111.576866)
		(width 0.10668)
		(layer "F.Cu")
		(net "FM_GPU_PWR_EN")
	)
	(via
		(at 191.911986 -110.262924)
		(size 0.4572)
		(drill 0.254)
		(layers "F.Cu" "B.Cu")
		(net "FM_GPU_PWR_EN")
	)
	(via
		(at 207.323944 -111.576866)
		(size 0.762)
		(drill 0.254)
		(layers "F.Cu" "B.Cu")
		(net "FM_GPU_PWR_EN")
	)
	(segment
		(start 202.428602 -111.075724)
		(end 196.061584 -111.075724)
		(width 0.11684)
		(layer "In2.Cu")
		(net "FM_GPU_PWR_EN")
	)
	(segment
		(start 192.300606 -109.874304)
		(end 191.911986 -110.262924)
		(width 0.11684)
		(layer "In2.Cu")
		(net "FM_GPU_PWR_EN")
	)
	(segment
		(start 195.22186 -110.236)
		(end 193.234818 -110.236)
		(width 0.11684)
		(layer "In2.Cu")
		(net "FM_GPU_PWR_EN")
	)
	(segment
		(start 202.929744 -111.576866)
		(end 202.428602 -111.075724)
		(width 0.11684)
		(layer "In2.Cu")
		(net "FM_GPU_PWR_EN")
	)
	(segment
		(start 192.873122 -109.874304)
		(end 192.300606 -109.874304)
		(width 0.11684)
		(layer "In2.Cu")
		(net "FM_GPU_PWR_EN")
	)
	(segment
		(start 193.234818 -110.236)
		(end 192.873122 -109.874304)
		(width 0.11684)
		(layer "In2.Cu")
		(net "FM_GPU_PWR_EN")
	)
	(segment
		(start 207.323944 -111.576866)
		(end 202.929744 -111.576866)
		(width 0.11684)
		(layer "In2.Cu")
		(net "FM_GPU_PWR_EN")
	)
	(segment
		(start 196.061584 -111.075724)
		(end 195.22186 -110.236)
		(width 0.11684)
		(layer "In2.Cu")
		(net "FM_GPU_PWR_EN")
	)
	(segment
		(start 193.122042 -120.252744)
		(end 193.511932 -120.642634)
		(width 0.10668)
		(layer "F.Cu")
		(net "FM_GPU_PWRGD_ISO_R")
	)
	(segment
		(start 208.478882 -119.721376)
		(end 207.291686 -119.721376)
		(width 0.10668)
		(layer "F.Cu")
		(net "FM_GPU_PWRGD_ISO_R")
	)
	(via
		(at 193.511932 -120.642634)
		(size 0.4572)
		(drill 0.254)
		(layers "F.Cu" "B.Cu")
		(net "FM_GPU_PWRGD_ISO_R")
	)
	(via
		(at 207.291686 -119.721376)
		(size 0.762)
		(drill 0.254)
		(layers "F.Cu" "B.Cu")
		(net "FM_GPU_PWRGD_ISO_R")
	)
	(segment
		(start 201.736452 -120.325134)
		(end 202.905868 -120.325134)
		(width 0.11684)
		(layer "In6.Cu")
		(net "FM_GPU_PWRGD_ISO_R")
	)
	(segment
		(start 200.85939 -121.202196)
		(end 201.736452 -120.325134)
		(width 0.11684)
		(layer "In6.Cu")
		(net "FM_GPU_PWRGD_ISO_R")
	)
	(segment
		(start 193.511932 -120.642634)
		(end 193.760852 -120.642634)
		(width 0.11684)
		(layer "In6.Cu")
		(net "FM_GPU_PWRGD_ISO_R")
	)
	(segment
		(start 203.265786 -119.183912)
		(end 206.754222 -119.183912)
		(width 0.11684)
		(layer "In6.Cu")
		(net "FM_GPU_PWRGD_ISO_R")
	)
	(segment
		(start 193.760852 -120.642634)
		(end 194.320414 -121.202196)
		(width 0.11684)
		(layer "In6.Cu")
		(net "FM_GPU_PWRGD_ISO_R")
	)
	(segment
		(start 203.032868 -119.41683)
		(end 203.265786 -119.183912)
		(width 0.11684)
		(layer "In6.Cu")
		(net "FM_GPU_PWRGD_ISO_R")
	)
	(segment
		(start 206.754222 -119.183912)
		(end 207.291686 -119.721376)
		(width 0.11684)
		(layer "In6.Cu")
		(net "FM_GPU_PWRGD_ISO_R")
	)
	(segment
		(start 203.032868 -120.198134)
		(end 203.032868 -119.41683)
		(width 0.11684)
		(layer "In6.Cu")
		(net "FM_GPU_PWRGD_ISO_R")
	)
	(segment
		(start 194.320414 -121.202196)
		(end 200.85939 -121.202196)
		(width 0.11684)
		(layer "In6.Cu")
		(net "FM_GPU_PWRGD_ISO_R")
	)
	(segment
		(start 202.905868 -120.325134)
		(end 203.032868 -120.198134)
		(width 0.11684)
		(layer "In6.Cu")
		(net "FM_GPU_PWRGD_ISO_R")
	)
	(segment
		(start 165.387528 -110.875318)
		(end 165.045898 -111.216948)
		(width 0.10668)
		(layer "F.Cu")
		(net "E1S_0_PERST1_CLKREQ_R_N")
	)
	(segment
		(start 173.01718 -111.92764)
		(end 171.80306 -110.71352)
		(width 0.10668)
		(layer "F.Cu")
		(net "E1S_0_PERST1_CLKREQ_R_N")
	)
	(segment
		(start 160.993582 -111.767112)
		(end 163.552886 -111.767112)
		(width 0.10668)
		(layer "F.Cu")
		(net "E1S_0_PERST1_CLKREQ_R_N")
	)
	(segment
		(start 176.432718 -110.652814)
		(end 175.157892 -111.92764)
		(width 0.10668)
		(layer "F.Cu")
		(net "E1S_0_PERST1_CLKREQ_R_N")
	)
	(segment
		(start 165.045898 -111.216948)
		(end 164.10305 -111.216948)
		(width 0.10668)
		(layer "F.Cu")
		(net "E1S_0_PERST1_CLKREQ_R_N")
	)
	(segment
		(start 175.157892 -111.92764)
		(end 173.01718 -111.92764)
		(width 0.10668)
		(layer "F.Cu")
		(net "E1S_0_PERST1_CLKREQ_R_N")
	)
	(segment
		(start 160.674812 -111.448342)
		(end 160.993582 -111.767112)
		(width 0.10668)
		(layer "F.Cu")
		(net "E1S_0_PERST1_CLKREQ_R_N")
	)
	(segment
		(start 171.80306 -110.71352)
		(end 165.549326 -110.71352)
		(width 0.10668)
		(layer "F.Cu")
		(net "E1S_0_PERST1_CLKREQ_R_N")
	)
	(segment
		(start 160.674812 -111.221774)
		(end 160.674812 -111.448342)
		(width 0.10668)
		(layer "F.Cu")
		(net "E1S_0_PERST1_CLKREQ_R_N")
	)
	(segment
		(start 165.549326 -110.71352)
		(end 165.387528 -110.875318)
		(width 0.10668)
		(layer "F.Cu")
		(net "E1S_0_PERST1_CLKREQ_R_N")
	)
	(segment
		(start 177.122074 -110.652814)
		(end 176.432718 -110.652814)
		(width 0.10668)
		(layer "F.Cu")
		(net "E1S_0_PERST1_CLKREQ_R_N")
	)
	(segment
		(start 163.552886 -111.767112)
		(end 164.10305 -111.216948)
		(width 0.10668)
		(layer "F.Cu")
		(net "E1S_0_PERST1_CLKREQ_R_N")
	)
	(via
		(at 165.387528 -110.875318)
		(size 0.762)
		(drill 0.381)
		(layers "F.Cu" "B.Cu")
		(net "E1S_0_PERST1_CLKREQ_R_N")
	)
	(segment
		(start 388.217918 -294.88003)
		(end 388.68477 -295.145968)
		(width 0.10668)
		(layer "F.Cu")
		(net "CPU0_RTC_LDO_SELECT")
	)
	(via
		(at 388.68477 -295.145968)
		(size 0.4064)
		(drill 0.2032)
		(layers "F.Cu" "B.Cu")
		(net "CPU0_RTC_LDO_SELECT")
	)
	(via
		(at 409.599638 -326.26554)
		(size 0.6604)
		(drill 0.3302)
		(layers "F.Cu" "B.Cu")
		(net "CPU0_RTC_LDO_SELECT")
	)
	(segment
		(start 409.599638 -314.8203)
		(end 409.599638 -326.26554)
		(width 0.10668)
		(layer "B.Cu")
		(net "CPU0_RTC_LDO_SELECT")
	)
	(segment
		(start 393.606274 -294.733218)
		(end 393.619736 -294.741092)
		(width 0.10668)
		(layer "B.Cu")
		(net "CPU0_RTC_LDO_SELECT")
	)
	(segment
		(start 391.739628 -294.741092)
		(end 391.74928 -294.74668)
		(width 0.10668)
		(layer "B.Cu")
		(net "CPU0_RTC_LDO_SELECT")
	)
	(segment
		(start 389.018526 -295.145968)
		(end 389.46455 -294.699944)
		(width 0.10668)
		(layer "B.Cu")
		(net "CPU0_RTC_LDO_SELECT")
	)
	(segment
		(start 394.90269 -295.150286)
		(end 394.90269 -297.196002)
		(width 0.10668)
		(layer "B.Cu")
		(net "CPU0_RTC_LDO_SELECT")
	)
	(segment
		(start 408.597608 -329.587352)
		(end 408.597608 -328.266552)
		(width 0.10668)
		(layer "B.Cu")
		(net "CPU0_RTC_LDO_SELECT")
	)
	(segment
		(start 398.410176 -300.703488)
		(end 398.410176 -303.630838)
		(width 0.10668)
		(layer "B.Cu")
		(net "CPU0_RTC_LDO_SELECT")
	)
	(segment
		(start 392.679174 -294.741092)
		(end 392.688826 -294.74668)
		(width 0.10668)
		(layer "B.Cu")
		(net "CPU0_RTC_LDO_SELECT")
	)
	(segment
		(start 389.859774 -294.741092)
		(end 389.869426 -294.74668)
		(width 0.10668)
		(layer "B.Cu")
		(net "CPU0_RTC_LDO_SELECT")
	)
	(segment
		(start 409.599638 -326.26554)
		(end 409.599638 -327.264522)
		(width 0.10668)
		(layer "B.Cu")
		(net "CPU0_RTC_LDO_SELECT")
	)
	(segment
		(start 388.68477 -295.145968)
		(end 389.018526 -295.145968)
		(width 0.10668)
		(layer "B.Cu")
		(net "CPU0_RTC_LDO_SELECT")
	)
	(segment
		(start 389.46455 -294.699944)
		(end 389.859774 -294.741092)
		(width 0.10668)
		(layer "B.Cu")
		(net "CPU0_RTC_LDO_SELECT")
	)
	(segment
		(start 409.599638 -327.264522)
		(end 408.597608 -328.266552)
		(width 0.10668)
		(layer "B.Cu")
		(net "CPU0_RTC_LDO_SELECT")
	)
	(segment
		(start 393.854686 -294.804338)
		(end 394.556742 -294.804338)
		(width 0.10668)
		(layer "B.Cu")
		(net "CPU0_RTC_LDO_SELECT")
	)
	(segment
		(start 398.410176 -303.630838)
		(end 409.599638 -314.8203)
		(width 0.10668)
		(layer "B.Cu")
		(net "CPU0_RTC_LDO_SELECT")
	)
	(segment
		(start 394.556742 -294.804338)
		(end 394.90269 -295.150286)
		(width 0.10668)
		(layer "B.Cu")
		(net "CPU0_RTC_LDO_SELECT")
	)
	(segment
		(start 394.90269 -297.196002)
		(end 398.410176 -300.703488)
		(width 0.10668)
		(layer "B.Cu")
		(net "CPU0_RTC_LDO_SELECT")
	)
	(arc
		(start 392.209274 -294.741092)
		(mid 392.444224 -294.677859)
		(end 392.679174 -294.741092)
		(width 0.10668)
		(layer "B.Cu")
		(net "CPU0_RTC_LDO_SELECT")
	)
	(arc
		(start 393.149328 -294.741092)
		(mid 393.376768 -294.677672)
		(end 393.606274 -294.733218)
		(width 0.10668)
		(layer "B.Cu")
		(net "CPU0_RTC_LDO_SELECT")
	)
	(arc
		(start 389.869426 -294.74668)
		(mid 390.100411 -294.804381)
		(end 390.329928 -294.741092)
		(width 0.10668)
		(layer "B.Cu")
		(net "CPU0_RTC_LDO_SELECT")
	)
	(arc
		(start 390.329928 -294.741092)
		(mid 390.564878 -294.677859)
		(end 390.799828 -294.741092)
		(width 0.10668)
		(layer "B.Cu")
		(net "CPU0_RTC_LDO_SELECT")
	)
	(arc
		(start 391.74928 -294.74668)
		(mid 391.980011 -294.804259)
		(end 392.209274 -294.741092)
		(width 0.10668)
		(layer "B.Cu")
		(net "CPU0_RTC_LDO_SELECT")
	)
	(arc
		(start 393.619736 -294.741092)
		(mid 393.733031 -294.78824)
		(end 393.854686 -294.804338)
		(width 0.10668)
		(layer "B.Cu")
		(net "CPU0_RTC_LDO_SELECT")
	)
	(arc
		(start 392.688826 -294.74668)
		(mid 392.919811 -294.804381)
		(end 393.149328 -294.741092)
		(width 0.10668)
		(layer "B.Cu")
		(net "CPU0_RTC_LDO_SELECT")
	)
	(arc
		(start 391.269728 -294.741092)
		(mid 391.504678 -294.677859)
		(end 391.739628 -294.741092)
		(width 0.10668)
		(layer "B.Cu")
		(net "CPU0_RTC_LDO_SELECT")
	)
	(arc
		(start 390.799828 -294.741092)
		(mid 391.034778 -294.804291)
		(end 391.269728 -294.741092)
		(width 0.10668)
		(layer "B.Cu")
		(net "CPU0_RTC_LDO_SELECT")
	)
	(segment
		(start 208.494376 -110.649512)
		(end 207.396842 -110.649512)
		(width 0.10668)
		(layer "F.Cu")
		(net "BMC_MONITER")
	)
	(segment
		(start 207.396842 -110.649512)
		(end 207.324706 -110.577376)
		(width 0.10668)
		(layer "F.Cu")
		(net "BMC_MONITER")
	)
	(segment
		(start 193.922142 -109.852968)
		(end 194.312032 -109.463078)
		(width 0.10668)
		(layer "F.Cu")
		(net "BMC_MONITER")
	)
	(via
		(at 194.312032 -109.463078)
		(size 0.4572)
		(drill 0.254)
		(layers "F.Cu" "B.Cu")
		(net "BMC_MONITER")
	)
	(via
		(at 207.324706 -110.577376)
		(size 0.508)
		(drill 0.254)
		(layers "F.Cu" "B.Cu")
		(net "BMC_MONITER")
	)
	(segment
		(start 197.93204 -110.08614)
		(end 197.53834 -109.69244)
		(width 0.11684)
		(layer "In2.Cu")
		(net "BMC_MONITER")
	)
	(segment
		(start 206.898494 -111.075724)
		(end 203.44892 -111.075724)
		(width 0.11684)
		(layer "In2.Cu")
		(net "BMC_MONITER")
	)
	(segment
		(start 207.324706 -110.649512)
		(end 206.898494 -111.075724)
		(width 0.11684)
		(layer "In2.Cu")
		(net "BMC_MONITER")
	)
	(segment
		(start 197.53834 -109.69244)
		(end 196.23024 -109.69244)
		(width 0.11684)
		(layer "In2.Cu")
		(net "BMC_MONITER")
	)
	(segment
		(start 196.23024 -109.69244)
		(end 195.97878 -109.9439)
		(width 0.11684)
		(layer "In2.Cu")
		(net "BMC_MONITER")
	)
	(segment
		(start 203.44892 -111.075724)
		(end 202.459336 -110.08614)
		(width 0.11684)
		(layer "In2.Cu")
		(net "BMC_MONITER")
	)
	(segment
		(start 202.459336 -110.08614)
		(end 197.93204 -110.08614)
		(width 0.11684)
		(layer "In2.Cu")
		(net "BMC_MONITER")
	)
	(segment
		(start 207.324706 -110.577376)
		(end 207.324706 -110.649512)
		(width 0.11684)
		(layer "In2.Cu")
		(net "BMC_MONITER")
	)
	(segment
		(start 194.792854 -109.9439)
		(end 194.312032 -109.463078)
		(width 0.11684)
		(layer "In2.Cu")
		(net "BMC_MONITER")
	)
	(segment
		(start 195.97878 -109.9439)
		(end 194.792854 -109.9439)
		(width 0.11684)
		(layer "In2.Cu")
		(net "BMC_MONITER")
	)
	(segment
		(start 190.721996 -117.852952)
		(end 191.111886 -118.242842)
		(width 0.10668)
		(layer "F.Cu")
		(net "BIC_MONITER_ISO_R")
	)
	(via
		(at 191.111886 -118.242842)
		(size 0.4572)
		(drill 0.254)
		(layers "F.Cu" "B.Cu")
		(net "BIC_MONITER_ISO_R")
	)
	(via
		(at 198.511414 -123.651518)
		(size 0.6604)
		(drill 0.3302)
		(layers "F.Cu" "B.Cu")
		(net "BIC_MONITER_ISO_R")
	)
	(segment
		(start 193.680588 -119.446548)
		(end 193.914776 -119.680736)
		(width 0.10668)
		(layer "B.Cu")
		(net "BIC_MONITER_ISO_R")
	)
	(segment
		(start 194.56654 -120.241568)
		(end 194.708272 -120.3833)
		(width 0.10668)
		(layer "B.Cu")
		(net "BIC_MONITER_ISO_R")
	)
	(segment
		(start 196.523864 -123.09221)
		(end 196.826124 -123.39447)
		(width 0.10668)
		(layer "B.Cu")
		(net "BIC_MONITER_ISO_R")
	)
	(segment
		(start 191.755268 -119.446548)
		(end 193.680588 -119.446548)
		(width 0.10668)
		(layer "B.Cu")
		(net "BIC_MONITER_ISO_R")
	)
	(segment
		(start 194.708272 -120.3833)
		(end 194.708272 -121.861072)
		(width 0.10668)
		(layer "B.Cu")
		(net "BIC_MONITER_ISO_R")
	)
	(segment
		(start 198.511414 -123.651518)
		(end 198.690992 -123.831096)
		(width 0.10668)
		(layer "B.Cu")
		(net "BIC_MONITER_ISO_R")
	)
	(segment
		(start 191.515746 -118.646702)
		(end 191.515746 -119.207026)
		(width 0.10668)
		(layer "B.Cu")
		(net "BIC_MONITER_ISO_R")
	)
	(segment
		(start 193.914776 -119.680736)
		(end 193.914776 -120.134888)
		(width 0.10668)
		(layer "B.Cu")
		(net "BIC_MONITER_ISO_R")
	)
	(segment
		(start 191.111886 -118.242842)
		(end 191.515746 -118.646702)
		(width 0.10668)
		(layer "B.Cu")
		(net "BIC_MONITER_ISO_R")
	)
	(segment
		(start 198.254366 -123.39447)
		(end 198.511414 -123.651518)
		(width 0.10668)
		(layer "B.Cu")
		(net "BIC_MONITER_ISO_R")
	)
	(segment
		(start 193.914776 -120.134888)
		(end 194.021456 -120.241568)
		(width 0.10668)
		(layer "B.Cu")
		(net "BIC_MONITER_ISO_R")
	)
	(segment
		(start 195.93941 -123.09221)
		(end 196.523864 -123.09221)
		(width 0.10668)
		(layer "B.Cu")
		(net "BIC_MONITER_ISO_R")
	)
	(segment
		(start 191.515746 -119.207026)
		(end 191.755268 -119.446548)
		(width 0.10668)
		(layer "B.Cu")
		(net "BIC_MONITER_ISO_R")
	)
	(segment
		(start 194.021456 -120.241568)
		(end 194.56654 -120.241568)
		(width 0.10668)
		(layer "B.Cu")
		(net "BIC_MONITER_ISO_R")
	)
	(segment
		(start 196.826124 -123.39447)
		(end 198.254366 -123.39447)
		(width 0.10668)
		(layer "B.Cu")
		(net "BIC_MONITER_ISO_R")
	)
	(segment
		(start 194.708272 -121.861072)
		(end 195.93941 -123.09221)
		(width 0.10668)
		(layer "B.Cu")
		(net "BIC_MONITER_ISO_R")
	)
	(segment
		(start 198.690992 -123.831096)
		(end 199.623172 -123.831096)
		(width 0.10668)
		(layer "B.Cu")
		(net "BIC_MONITER_ISO_R")
	)
	(segment
		(start 186.26201 -18.54327)
		(end 185.893456 -18.911824)
		(width 0.10668)
		(layer "F.Cu")
		(net "UART_CPU0_SCM_LVC3_UART1_R1_TX")
	)
	(segment
		(start 185.893456 -18.911824)
		(end 185.893456 -19.035522)
		(width 0.10668)
		(layer "F.Cu")
		(net "UART_CPU0_SCM_LVC3_UART1_R1_TX")
	)
	(segment
		(start 186.26201 -16.549878)
		(end 186.26201 -18.54327)
		(width 0.10668)
		(layer "F.Cu")
		(net "UART_CPU0_SCM_LVC3_UART1_R1_TX")
	)
	(segment
		(start 185.26252 -19.035522)
		(end 185.893456 -19.035522)
		(width 0.10668)
		(layer "F.Cu")
		(net "UART_CPU0_SCM_LVC3_UART1_R1_TX")
	)
	(via
		(at 185.893456 -19.035522)
		(size 0.508)
		(drill 0.254)
		(layers "F.Cu" "B.Cu")
		(net "UART_CPU0_SCM_LVC3_UART1_R1_TX")
	)
	(segment
		(start 307.494178 -42.176954)
		(end 307.805328 -42.488104)
		(width 0.10668)
		(layer "F.Cu")
		(net "TP_ADC128_INT")
	)
	(segment
		(start 307.805328 -42.488104)
		(end 309.925212 -42.488104)
		(width 0.10668)
		(layer "F.Cu")
		(net "TP_ADC128_INT")
	)
	(via
		(at 307.494178 -42.176954)
		(size 0.762)
		(drill 0.381)
		(layers "F.Cu" "B.Cu")
		(net "TP_ADC128_INT")
	)
	(segment
		(start 306.219098 -46.021498)
		(end 307.100986 -46.021498)
		(width 0.10668)
		(layer "F.Cu")
		(net "SMB_SEN_TIC_3V3AUX_SDA")
	)
	(segment
		(start 308.125622 -46.021498)
		(end 309.058818 -45.088302)
		(width 0.10668)
		(layer "F.Cu")
		(net "SMB_SEN_TIC_3V3AUX_SDA")
	)
	(segment
		(start 307.100986 -46.021498)
		(end 308.125622 -46.021498)
		(width 0.10668)
		(layer "F.Cu")
		(net "SMB_SEN_TIC_3V3AUX_SDA")
	)
	(segment
		(start 309.058818 -45.088302)
		(end 309.925212 -45.088302)
		(width 0.10668)
		(layer "F.Cu")
		(net "SMB_SEN_TIC_3V3AUX_SDA")
	)
	(via
		(at 307.100986 -46.021498)
		(size 0.762)
		(drill 0.381)
		(layers "F.Cu" "B.Cu")
		(net "SMB_SEN_TIC_3V3AUX_SDA")
	)
	(segment
		(start 307.891434 -45.005498)
		(end 306.219098 -45.005498)
		(width 0.10668)
		(layer "F.Cu")
		(net "SMB_SEN_TIC_3V3AUX_SCL")
	)
	(segment
		(start 309.925212 -44.438316)
		(end 308.458616 -44.438316)
		(width 0.10668)
		(layer "F.Cu")
		(net "SMB_SEN_TIC_3V3AUX_SCL")
	)
	(segment
		(start 308.458616 -44.438316)
		(end 308.073552 -44.82338)
		(width 0.10668)
		(layer "F.Cu")
		(net "SMB_SEN_TIC_3V3AUX_SCL")
	)
	(segment
		(start 308.073552 -44.82338)
		(end 307.891434 -45.005498)
		(width 0.10668)
		(layer "F.Cu")
		(net "SMB_SEN_TIC_3V3AUX_SCL")
	)
	(via
		(at 308.073552 -44.82338)
		(size 0.762)
		(drill 0.381)
		(layers "F.Cu" "B.Cu")
		(net "SMB_SEN_TIC_3V3AUX_SCL")
	)
	(segment
		(start 329.817476 -36.05911)
		(end 332.966314 -36.05911)
		(width 0.10668)
		(layer "F.Cu")
		(net "SMB_SCM_2_R4_SDA")
	)
	(segment
		(start 390.614662 -142.49654)
		(end 389.337296 -141.219174)
		(width 0.10668)
		(layer "F.Cu")
		(net "SMB_SCM_2_R4_SDA")
	)
	(segment
		(start 332.966314 -36.05911)
		(end 333.504794 -35.52063)
		(width 0.10668)
		(layer "F.Cu")
		(net "SMB_SCM_2_R4_SDA")
	)
	(segment
		(start 390.614662 -142.923006)
		(end 390.614662 -142.49654)
		(width 0.10668)
		(layer "F.Cu")
		(net "SMB_SCM_2_R4_SDA")
	)
	(segment
		(start 305.418998 -46.021498)
		(end 304.803048 -46.021498)
		(width 0.10668)
		(layer "F.Cu")
		(net "SMB_SCM_2_R4_SDA")
	)
	(segment
		(start 329.760072 -36.001706)
		(end 329.817476 -36.05911)
		(width 0.10668)
		(layer "F.Cu")
		(net "SMB_SCM_2_R4_SDA")
	)
	(via
		(at 413.296608 -42.90568)
		(size 0.508)
		(drill 0.254)
		(layers "F.Cu" "B.Cu")
		(net "SMB_SCM_2_R4_SDA")
	)
	(via
		(at 333.504794 -35.52063)
		(size 0.508)
		(drill 0.254)
		(layers "F.Cu" "B.Cu")
		(net "SMB_SCM_2_R4_SDA")
	)
	(via
		(at 304.803048 -46.021498)
		(size 0.508)
		(drill 0.254)
		(layers "F.Cu" "B.Cu")
		(net "SMB_SCM_2_R4_SDA")
	)
	(via
		(at 389.337296 -141.219174)
		(size 0.508)
		(drill 0.254)
		(layers "F.Cu" "B.Cu")
		(net "SMB_SCM_2_R4_SDA")
	)
	(segment
		(start 413.25546 -42.946828)
		(end 413.296608 -42.90568)
		(width 0.10668)
		(layer "B.Cu")
		(net "SMB_SCM_2_R4_SDA")
	)
	(segment
		(start 333.504794 -35.52063)
		(end 367.545874 -35.52063)
		(width 0.10668)
		(layer "B.Cu")
		(net "SMB_SCM_2_R4_SDA")
	)
	(segment
		(start 373.358918 -41.333674)
		(end 411.245558 -41.333674)
		(width 0.10668)
		(layer "B.Cu")
		(net "SMB_SCM_2_R4_SDA")
	)
	(segment
		(start 412.858712 -42.946828)
		(end 413.25546 -42.946828)
		(width 0.10668)
		(layer "B.Cu")
		(net "SMB_SCM_2_R4_SDA")
	)
	(segment
		(start 411.245558 -41.333674)
		(end 412.858712 -42.946828)
		(width 0.10668)
		(layer "B.Cu")
		(net "SMB_SCM_2_R4_SDA")
	)
	(segment
		(start 367.545874 -35.52063)
		(end 373.358918 -41.333674)
		(width 0.10668)
		(layer "B.Cu")
		(net "SMB_SCM_2_R4_SDA")
	)
	(segment
		(start 312.762646 -40.65016)
		(end 312.879486 -40.53332)
		(width 0.11684)
		(layer "In2.Cu")
		(net "SMB_SCM_2_R4_SDA")
	)
	(segment
		(start 310.82107 -39.799768)
		(end 311.490106 -39.799768)
		(width 0.11684)
		(layer "In2.Cu")
		(net "SMB_SCM_2_R4_SDA")
	)
	(segment
		(start 311.723786 -40.65016)
		(end 311.914286 -40.65016)
		(width 0.11684)
		(layer "In2.Cu")
		(net "SMB_SCM_2_R4_SDA")
	)
	(segment
		(start 311.490106 -39.799768)
		(end 311.606946 -39.916608)
		(width 0.11684)
		(layer "In2.Cu")
		(net "SMB_SCM_2_R4_SDA")
	)
	(segment
		(start 333.039974 -35.05581)
		(end 333.504794 -35.52063)
		(width 0.11684)
		(layer "In2.Cu")
		(net "SMB_SCM_2_R4_SDA")
	)
	(segment
		(start 312.031126 -40.53332)
		(end 312.031126 -39.916608)
		(width 0.11684)
		(layer "In2.Cu")
		(net "SMB_SCM_2_R4_SDA")
	)
	(segment
		(start 304.803048 -45.81779)
		(end 310.82107 -39.799768)
		(width 0.11684)
		(layer "In2.Cu")
		(net "SMB_SCM_2_R4_SDA")
	)
	(segment
		(start 318.229996 -39.799768)
		(end 327.079864 -30.9499)
		(width 0.11684)
		(layer "In2.Cu")
		(net "SMB_SCM_2_R4_SDA")
	)
	(segment
		(start 333.039974 -32.120332)
		(end 333.039974 -35.05581)
		(width 0.11684)
		(layer "In2.Cu")
		(net "SMB_SCM_2_R4_SDA")
	)
	(segment
		(start 312.031126 -39.916608)
		(end 312.147966 -39.799768)
		(width 0.11684)
		(layer "In2.Cu")
		(net "SMB_SCM_2_R4_SDA")
	)
	(segment
		(start 312.338466 -39.799768)
		(end 312.455306 -39.916608)
		(width 0.11684)
		(layer "In2.Cu")
		(net "SMB_SCM_2_R4_SDA")
	)
	(segment
		(start 312.147966 -39.799768)
		(end 312.338466 -39.799768)
		(width 0.11684)
		(layer "In2.Cu")
		(net "SMB_SCM_2_R4_SDA")
	)
	(segment
		(start 311.606946 -39.916608)
		(end 311.606946 -40.53332)
		(width 0.11684)
		(layer "In2.Cu")
		(net "SMB_SCM_2_R4_SDA")
	)
	(segment
		(start 304.803048 -46.021498)
		(end 304.803048 -45.81779)
		(width 0.11684)
		(layer "In2.Cu")
		(net "SMB_SCM_2_R4_SDA")
	)
	(segment
		(start 327.079864 -30.9499)
		(end 331.869542 -30.9499)
		(width 0.11684)
		(layer "In2.Cu")
		(net "SMB_SCM_2_R4_SDA")
	)
	(segment
		(start 311.606946 -40.53332)
		(end 311.723786 -40.65016)
		(width 0.11684)
		(layer "In2.Cu")
		(net "SMB_SCM_2_R4_SDA")
	)
	(segment
		(start 331.869542 -30.9499)
		(end 333.039974 -32.120332)
		(width 0.11684)
		(layer "In2.Cu")
		(net "SMB_SCM_2_R4_SDA")
	)
	(segment
		(start 312.572146 -40.65016)
		(end 312.762646 -40.65016)
		(width 0.11684)
		(layer "In2.Cu")
		(net "SMB_SCM_2_R4_SDA")
	)
	(segment
		(start 312.455306 -40.53332)
		(end 312.572146 -40.65016)
		(width 0.11684)
		(layer "In2.Cu")
		(net "SMB_SCM_2_R4_SDA")
	)
	(segment
		(start 311.914286 -40.65016)
		(end 312.031126 -40.53332)
		(width 0.11684)
		(layer "In2.Cu")
		(net "SMB_SCM_2_R4_SDA")
	)
	(segment
		(start 312.455306 -39.916608)
		(end 312.455306 -40.53332)
		(width 0.11684)
		(layer "In2.Cu")
		(net "SMB_SCM_2_R4_SDA")
	)
	(segment
		(start 312.996326 -39.799768)
		(end 318.229996 -39.799768)
		(width 0.11684)
		(layer "In2.Cu")
		(net "SMB_SCM_2_R4_SDA")
	)
	(segment
		(start 312.879486 -40.53332)
		(end 312.879486 -39.916608)
		(width 0.11684)
		(layer "In2.Cu")
		(net "SMB_SCM_2_R4_SDA")
	)
	(segment
		(start 312.879486 -39.916608)
		(end 312.996326 -39.799768)
		(width 0.11684)
		(layer "In2.Cu")
		(net "SMB_SCM_2_R4_SDA")
	)
	(segment
		(start 408.280616 -58.336942)
		(end 414.143952 -52.473606)
		(width 0.11684)
		(layer "In4.Cu")
		(net "SMB_SCM_2_R4_SDA")
	)
	(segment
		(start 414.143952 -52.473606)
		(end 414.143952 -43.31589)
		(width 0.11684)
		(layer "In4.Cu")
		(net "SMB_SCM_2_R4_SDA")
	)
	(segment
		(start 414.143952 -43.31589)
		(end 413.733742 -42.90568)
		(width 0.11684)
		(layer "In4.Cu")
		(net "SMB_SCM_2_R4_SDA")
	)
	(segment
		(start 413.733742 -42.90568)
		(end 413.296608 -42.90568)
		(width 0.11684)
		(layer "In4.Cu")
		(net "SMB_SCM_2_R4_SDA")
	)
	(segment
		(start 389.337296 -141.219174)
		(end 389.337296 -134.558786)
		(width 0.11684)
		(layer "In4.Cu")
		(net "SMB_SCM_2_R4_SDA")
	)
	(segment
		(start 390.565894 -133.330188)
		(end 406.564338 -133.330188)
		(width 0.11684)
		(layer "In4.Cu")
		(net "SMB_SCM_2_R4_SDA")
	)
	(segment
		(start 389.337296 -134.558786)
		(end 390.565894 -133.330188)
		(width 0.11684)
		(layer "In4.Cu")
		(net "SMB_SCM_2_R4_SDA")
	)
	(segment
		(start 408.280616 -131.61391)
		(end 408.280616 -58.336942)
		(width 0.11684)
		(layer "In4.Cu")
		(net "SMB_SCM_2_R4_SDA")
	)
	(segment
		(start 406.564338 -133.330188)
		(end 408.280616 -131.61391)
		(width 0.11684)
		(layer "In4.Cu")
		(net "SMB_SCM_2_R4_SDA")
	)
	(segment
		(start 333.017368 -34.985706)
		(end 329.760072 -34.985706)
		(width 0.10668)
		(layer "F.Cu")
		(net "SMB_SCM_2_R4_SCL")
	)
	(segment
		(start 333.504794 -34.49828)
		(end 333.017368 -34.985706)
		(width 0.10668)
		(layer "F.Cu")
		(net "SMB_SCM_2_R4_SCL")
	)
	(segment
		(start 388.074662 -142.923006)
		(end 388.074662 -142.307056)
		(width 0.10668)
		(layer "F.Cu")
		(net "SMB_SCM_2_R4_SCL")
	)
	(segment
		(start 305.418998 -45.005498)
		(end 304.809398 -45.005498)
		(width 0.10668)
		(layer "F.Cu")
		(net "SMB_SCM_2_R4_SCL")
	)
	(via
		(at 388.074662 -142.307056)
		(size 0.508)
		(drill 0.254)
		(layers "F.Cu" "B.Cu")
		(net "SMB_SCM_2_R4_SCL")
	)
	(via
		(at 414.38957 -42.64025)
		(size 0.508)
		(drill 0.254)
		(layers "F.Cu" "B.Cu")
		(net "SMB_SCM_2_R4_SCL")
	)
	(via
		(at 333.504794 -34.49828)
		(size 0.508)
		(drill 0.254)
		(layers "F.Cu" "B.Cu")
		(net "SMB_SCM_2_R4_SCL")
	)
	(via
		(at 304.809398 -45.005498)
		(size 0.508)
		(drill 0.254)
		(layers "F.Cu" "B.Cu")
		(net "SMB_SCM_2_R4_SCL")
	)
	(segment
		(start 373.202962 -40.311324)
		(end 410.991558 -40.311324)
		(width 0.10668)
		(layer "B.Cu")
		(net "SMB_SCM_2_R4_SCL")
	)
	(segment
		(start 414.061656 -42.312336)
		(end 414.38957 -42.64025)
		(width 0.10668)
		(layer "B.Cu")
		(net "SMB_SCM_2_R4_SCL")
	)
	(segment
		(start 410.991558 -40.311324)
		(end 412.99257 -42.312336)
		(width 0.10668)
		(layer "B.Cu")
		(net "SMB_SCM_2_R4_SCL")
	)
	(segment
		(start 412.99257 -42.312336)
		(end 414.061656 -42.312336)
		(width 0.10668)
		(layer "B.Cu")
		(net "SMB_SCM_2_R4_SCL")
	)
	(segment
		(start 367.861088 -34.96945)
		(end 373.202962 -40.311324)
		(width 0.10668)
		(layer "B.Cu")
		(net "SMB_SCM_2_R4_SCL")
	)
	(segment
		(start 333.975964 -34.96945)
		(end 367.861088 -34.96945)
		(width 0.10668)
		(layer "B.Cu")
		(net "SMB_SCM_2_R4_SCL")
	)
	(segment
		(start 333.504794 -34.49828)
		(end 333.975964 -34.96945)
		(width 0.10668)
		(layer "B.Cu")
		(net "SMB_SCM_2_R4_SCL")
	)
	(segment
		(start 326.905112 -30.52826)
		(end 332.044294 -30.52826)
		(width 0.11684)
		(layer "In2.Cu")
		(net "SMB_SCM_2_R4_SCL")
	)
	(segment
		(start 304.809398 -45.005498)
		(end 305.229514 -44.585382)
		(width 0.11684)
		(layer "In2.Cu")
		(net "SMB_SCM_2_R4_SCL")
	)
	(segment
		(start 305.37785 -44.585382)
		(end 310.585104 -39.378128)
		(width 0.11684)
		(layer "In2.Cu")
		(net "SMB_SCM_2_R4_SCL")
	)
	(segment
		(start 333.504794 -31.98876)
		(end 333.504794 -34.49828)
		(width 0.11684)
		(layer "In2.Cu")
		(net "SMB_SCM_2_R4_SCL")
	)
	(segment
		(start 305.229514 -44.585382)
		(end 305.37785 -44.585382)
		(width 0.11684)
		(layer "In2.Cu")
		(net "SMB_SCM_2_R4_SCL")
	)
	(segment
		(start 332.044294 -30.52826)
		(end 333.504794 -31.98876)
		(width 0.11684)
		(layer "In2.Cu")
		(net "SMB_SCM_2_R4_SCL")
	)
	(segment
		(start 310.585104 -39.378128)
		(end 318.055244 -39.378128)
		(width 0.11684)
		(layer "In2.Cu")
		(net "SMB_SCM_2_R4_SCL")
	)
	(segment
		(start 318.055244 -39.378128)
		(end 326.905112 -30.52826)
		(width 0.11684)
		(layer "In2.Cu")
		(net "SMB_SCM_2_R4_SCL")
	)
	(segment
		(start 408.723846 -130.256534)
		(end 408.723846 -130.447034)
		(width 0.11684)
		(layer "In4.Cu")
		(net "SMB_SCM_2_R4_SCL")
	)
	(segment
		(start 408.840686 -129.715514)
		(end 409.55976 -129.715514)
		(width 0.11684)
		(layer "In4.Cu")
		(net "SMB_SCM_2_R4_SCL")
	)
	(segment
		(start 408.723846 -131.104894)
		(end 408.723846 -131.915916)
		(width 0.11684)
		(layer "In4.Cu")
		(net "SMB_SCM_2_R4_SCL")
	)
	(segment
		(start 409.55976 -130.563874)
		(end 409.6766 -130.680714)
		(width 0.11684)
		(layer "In4.Cu")
		(net "SMB_SCM_2_R4_SCL")
	)
	(segment
		(start 390.996678 -133.865874)
		(end 390.053322 -134.80923)
		(width 0.11684)
		(layer "In4.Cu")
		(net "SMB_SCM_2_R4_SCL")
	)
	(segment
		(start 409.6766 -130.022854)
		(end 409.55976 -130.139694)
		(width 0.11684)
		(layer "In4.Cu")
		(net "SMB_SCM_2_R4_SCL")
	)
	(segment
		(start 408.840686 -130.139694)
		(end 408.723846 -130.256534)
		(width 0.11684)
		(layer "In4.Cu")
		(net "SMB_SCM_2_R4_SCL")
	)
	(segment
		(start 409.55976 -130.988054)
		(end 408.840686 -130.988054)
		(width 0.11684)
		(layer "In4.Cu")
		(net "SMB_SCM_2_R4_SCL")
	)
	(segment
		(start 408.723846 -129.598674)
		(end 408.840686 -129.715514)
		(width 0.11684)
		(layer "In4.Cu")
		(net "SMB_SCM_2_R4_SCL")
	)
	(segment
		(start 409.6766 -130.680714)
		(end 409.6766 -130.871214)
		(width 0.11684)
		(layer "In4.Cu")
		(net "SMB_SCM_2_R4_SCL")
	)
	(segment
		(start 408.723846 -131.915916)
		(end 406.773888 -133.865874)
		(width 0.11684)
		(layer "In4.Cu")
		(net "SMB_SCM_2_R4_SCL")
	)
	(segment
		(start 409.55976 -130.139694)
		(end 408.840686 -130.139694)
		(width 0.11684)
		(layer "In4.Cu")
		(net "SMB_SCM_2_R4_SCL")
	)
	(segment
		(start 389.726678 -141.74343)
		(end 388.638288 -141.74343)
		(width 0.11684)
		(layer "In4.Cu")
		(net "SMB_SCM_2_R4_SCL")
	)
	(segment
		(start 409.6766 -129.832354)
		(end 409.6766 -130.022854)
		(width 0.11684)
		(layer "In4.Cu")
		(net "SMB_SCM_2_R4_SCL")
	)
	(segment
		(start 388.638288 -141.74343)
		(end 388.074662 -142.307056)
		(width 0.11684)
		(layer "In4.Cu")
		(net "SMB_SCM_2_R4_SCL")
	)
	(segment
		(start 390.053322 -141.416786)
		(end 389.726678 -141.74343)
		(width 0.11684)
		(layer "In4.Cu")
		(net "SMB_SCM_2_R4_SCL")
	)
	(segment
		(start 406.773888 -133.865874)
		(end 390.996678 -133.865874)
		(width 0.11684)
		(layer "In4.Cu")
		(net "SMB_SCM_2_R4_SCL")
	)
	(segment
		(start 409.55976 -129.715514)
		(end 409.6766 -129.832354)
		(width 0.11684)
		(layer "In4.Cu")
		(net "SMB_SCM_2_R4_SCL")
	)
	(segment
		(start 408.723846 -130.447034)
		(end 408.840686 -130.563874)
		(width 0.11684)
		(layer "In4.Cu")
		(net "SMB_SCM_2_R4_SCL")
	)
	(segment
		(start 414.38957 -42.64025)
		(end 414.587182 -42.837862)
		(width 0.11684)
		(layer "In4.Cu")
		(net "SMB_SCM_2_R4_SCL")
	)
	(segment
		(start 414.587182 -52.657248)
		(end 408.723846 -58.520584)
		(width 0.11684)
		(layer "In4.Cu")
		(net "SMB_SCM_2_R4_SCL")
	)
	(segment
		(start 408.840686 -130.988054)
		(end 408.723846 -131.104894)
		(width 0.11684)
		(layer "In4.Cu")
		(net "SMB_SCM_2_R4_SCL")
	)
	(segment
		(start 414.587182 -42.837862)
		(end 414.587182 -52.657248)
		(width 0.11684)
		(layer "In4.Cu")
		(net "SMB_SCM_2_R4_SCL")
	)
	(segment
		(start 408.840686 -130.563874)
		(end 409.55976 -130.563874)
		(width 0.11684)
		(layer "In4.Cu")
		(net "SMB_SCM_2_R4_SCL")
	)
	(segment
		(start 390.053322 -134.80923)
		(end 390.053322 -141.416786)
		(width 0.11684)
		(layer "In4.Cu")
		(net "SMB_SCM_2_R4_SCL")
	)
	(segment
		(start 409.6766 -130.871214)
		(end 409.55976 -130.988054)
		(width 0.11684)
		(layer "In4.Cu")
		(net "SMB_SCM_2_R4_SCL")
	)
	(segment
		(start 408.723846 -58.520584)
		(end 408.723846 -129.598674)
		(width 0.11684)
		(layer "In4.Cu")
		(net "SMB_SCM_2_R4_SCL")
	)
	(segment
		(start 374.715278 -134.786624)
		(end 373.73433 -133.805676)
		(width 0.10668)
		(layer "F.Cu")
		(net "SMB_SCM_2_R3_SDA")
	)
	(segment
		(start 390.614662 -143.723106)
		(end 390.387586 -143.49603)
		(width 0.10668)
		(layer "F.Cu")
		(net "SMB_SCM_2_R3_SDA")
	)
	(segment
		(start 390.614662 -147.022566)
		(end 391.255758 -147.663662)
		(width 0.10668)
		(layer "F.Cu")
		(net "SMB_SCM_2_R3_SDA")
	)
	(segment
		(start 390.387586 -143.49603)
		(end 389.77951 -143.49603)
		(width 0.10668)
		(layer "F.Cu")
		(net "SMB_SCM_2_R3_SDA")
	)
	(segment
		(start 390.614662 -143.723106)
		(end 390.614662 -147.022566)
		(width 0.10668)
		(layer "F.Cu")
		(net "SMB_SCM_2_R3_SDA")
	)
	(segment
		(start 252.173486 -121.71045)
		(end 250.88977 -121.71045)
		(width 0.10668)
		(layer "F.Cu")
		(net "SMB_SCM_2_R3_SDA")
	)
	(segment
		(start 250.88977 -121.71045)
		(end 250.64466 -121.95556)
		(width 0.10668)
		(layer "F.Cu")
		(net "SMB_SCM_2_R3_SDA")
	)
	(segment
		(start 373.73433 -133.805676)
		(end 373.73433 -123.845828)
		(width 0.10668)
		(layer "F.Cu")
		(net "SMB_SCM_2_R3_SDA")
	)
	(via
		(at 373.73433 -123.845828)
		(size 0.508)
		(drill 0.254)
		(layers "F.Cu" "B.Cu")
		(net "SMB_SCM_2_R3_SDA")
	)
	(via
		(at 250.64466 -121.95556)
		(size 0.508)
		(drill 0.254)
		(layers "F.Cu" "B.Cu")
		(net "SMB_SCM_2_R3_SDA")
	)
	(via
		(at 374.715278 -134.786624)
		(size 0.508)
		(drill 0.254)
		(layers "F.Cu" "B.Cu")
		(net "SMB_SCM_2_R3_SDA")
	)
	(via
		(at 389.77951 -143.49603)
		(size 0.508)
		(drill 0.254)
		(layers "F.Cu" "B.Cu")
		(net "SMB_SCM_2_R3_SDA")
	)
	(segment
		(start 377.253246 -135.52424)
		(end 375.388378 -137.389108)
		(width 0.10668)
		(layer "B.Cu")
		(net "SMB_SCM_2_R3_SDA")
	)
	(segment
		(start 389.77951 -143.49603)
		(end 387.73608 -143.49603)
		(width 0.10668)
		(layer "B.Cu")
		(net "SMB_SCM_2_R3_SDA")
	)
	(segment
		(start 386.90931 -136.40435)
		(end 386.0292 -135.52424)
		(width 0.10668)
		(layer "B.Cu")
		(net "SMB_SCM_2_R3_SDA")
	)
	(segment
		(start 387.73608 -143.49603)
		(end 386.90931 -142.66926)
		(width 0.10668)
		(layer "B.Cu")
		(net "SMB_SCM_2_R3_SDA")
	)
	(segment
		(start 374.715278 -137.389108)
		(end 374.715278 -134.786624)
		(width 0.10668)
		(layer "B.Cu")
		(net "SMB_SCM_2_R3_SDA")
	)
	(segment
		(start 375.388378 -137.389108)
		(end 374.715278 -137.389108)
		(width 0.10668)
		(layer "B.Cu")
		(net "SMB_SCM_2_R3_SDA")
	)
	(segment
		(start 386.90931 -142.66926)
		(end 386.90931 -136.40435)
		(width 0.10668)
		(layer "B.Cu")
		(net "SMB_SCM_2_R3_SDA")
	)
	(segment
		(start 386.0292 -135.52424)
		(end 377.253246 -135.52424)
		(width 0.10668)
		(layer "B.Cu")
		(net "SMB_SCM_2_R3_SDA")
	)
	(segment
		(start 321.374262 -119.000778)
		(end 369.587018 -119.000778)
		(width 0.11684)
		(layer "In6.Cu")
		(net "SMB_SCM_2_R3_SDA")
	)
	(segment
		(start 264.50544 -119.6086)
		(end 268.503908 -123.607068)
		(width 0.11684)
		(layer "In6.Cu")
		(net "SMB_SCM_2_R3_SDA")
	)
	(segment
		(start 255.7399 -116.16182)
		(end 259.18668 -119.6086)
		(width 0.11684)
		(layer "In6.Cu")
		(net "SMB_SCM_2_R3_SDA")
	)
	(segment
		(start 290.467288 -123.7869)
		(end 292.006528 -122.24766)
		(width 0.11684)
		(layer "In6.Cu")
		(net "SMB_SCM_2_R3_SDA")
	)
	(segment
		(start 268.503908 -123.607068)
		(end 272.532602 -123.607068)
		(width 0.11684)
		(layer "In6.Cu")
		(net "SMB_SCM_2_R3_SDA")
	)
	(segment
		(start 250.64466 -121.95556)
		(end 249.57532 -120.88622)
		(width 0.11684)
		(layer "In6.Cu")
		(net "SMB_SCM_2_R3_SDA")
	)
	(segment
		(start 292.006528 -122.24766)
		(end 294.26662 -122.24766)
		(width 0.11684)
		(layer "In6.Cu")
		(net "SMB_SCM_2_R3_SDA")
	)
	(segment
		(start 254.70866 -116.16182)
		(end 255.7399 -116.16182)
		(width 0.11684)
		(layer "In6.Cu")
		(net "SMB_SCM_2_R3_SDA")
	)
	(segment
		(start 318.647572 -121.727468)
		(end 321.374262 -119.000778)
		(width 0.11684)
		(layer "In6.Cu")
		(net "SMB_SCM_2_R3_SDA")
	)
	(segment
		(start 273.427952 -124.502418)
		(end 275.379942 -124.502418)
		(width 0.11684)
		(layer "In6.Cu")
		(net "SMB_SCM_2_R3_SDA")
	)
	(segment
		(start 253.9365 -115.38966)
		(end 254.70866 -116.16182)
		(width 0.11684)
		(layer "In6.Cu")
		(net "SMB_SCM_2_R3_SDA")
	)
	(segment
		(start 294.786812 -121.727468)
		(end 318.647572 -121.727468)
		(width 0.11684)
		(layer "In6.Cu")
		(net "SMB_SCM_2_R3_SDA")
	)
	(segment
		(start 369.587018 -119.000778)
		(end 373.73433 -123.14809)
		(width 0.11684)
		(layer "In6.Cu")
		(net "SMB_SCM_2_R3_SDA")
	)
	(segment
		(start 373.73433 -123.14809)
		(end 373.73433 -123.845828)
		(width 0.11684)
		(layer "In6.Cu")
		(net "SMB_SCM_2_R3_SDA")
	)
	(segment
		(start 249.57532 -120.88622)
		(end 249.57532 -117.14988)
		(width 0.11684)
		(layer "In6.Cu")
		(net "SMB_SCM_2_R3_SDA")
	)
	(segment
		(start 249.57532 -117.14988)
		(end 251.33554 -115.38966)
		(width 0.11684)
		(layer "In6.Cu")
		(net "SMB_SCM_2_R3_SDA")
	)
	(segment
		(start 259.18668 -119.6086)
		(end 264.50544 -119.6086)
		(width 0.11684)
		(layer "In6.Cu")
		(net "SMB_SCM_2_R3_SDA")
	)
	(segment
		(start 276.09546 -123.7869)
		(end 290.467288 -123.7869)
		(width 0.11684)
		(layer "In6.Cu")
		(net "SMB_SCM_2_R3_SDA")
	)
	(segment
		(start 251.33554 -115.38966)
		(end 253.9365 -115.38966)
		(width 0.11684)
		(layer "In6.Cu")
		(net "SMB_SCM_2_R3_SDA")
	)
	(segment
		(start 294.26662 -122.24766)
		(end 294.786812 -121.727468)
		(width 0.11684)
		(layer "In6.Cu")
		(net "SMB_SCM_2_R3_SDA")
	)
	(segment
		(start 272.532602 -123.607068)
		(end 273.427952 -124.502418)
		(width 0.11684)
		(layer "In6.Cu")
		(net "SMB_SCM_2_R3_SDA")
	)
	(segment
		(start 275.379942 -124.502418)
		(end 276.09546 -123.7869)
		(width 0.11684)
		(layer "In6.Cu")
		(net "SMB_SCM_2_R3_SDA")
	)
	(segment
		(start 372.321328 -123.956826)
		(end 372.21033 -123.845828)
		(width 0.10668)
		(layer "F.Cu")
		(net "SMB_SCM_2_R3_SCL")
	)
	(segment
		(start 372.321328 -134.786624)
		(end 372.321328 -123.956826)
		(width 0.10668)
		(layer "F.Cu")
		(net "SMB_SCM_2_R3_SCL")
	)
	(segment
		(start 251.1171 -119.60098)
		(end 251.1171 -118.19001)
		(width 0.10668)
		(layer "F.Cu")
		(net "SMB_SCM_2_R3_SCL")
	)
	(segment
		(start 251.82957 -120.31345)
		(end 251.1171 -119.60098)
		(width 0.10668)
		(layer "F.Cu")
		(net "SMB_SCM_2_R3_SCL")
	)
	(segment
		(start 388.808722 -142.989046)
		(end 389.31342 -142.989046)
		(width 0.10668)
		(layer "F.Cu")
		(net "SMB_SCM_2_R3_SCL")
	)
	(segment
		(start 388.074662 -147.022566)
		(end 388.715758 -147.663662)
		(width 0.10668)
		(layer "F.Cu")
		(net "SMB_SCM_2_R3_SCL")
	)
	(segment
		(start 388.074662 -143.723106)
		(end 388.074662 -147.022566)
		(width 0.10668)
		(layer "F.Cu")
		(net "SMB_SCM_2_R3_SCL")
	)
	(segment
		(start 388.074662 -143.723106)
		(end 388.808722 -142.989046)
		(width 0.10668)
		(layer "F.Cu")
		(net "SMB_SCM_2_R3_SCL")
	)
	(segment
		(start 252.173486 -120.31345)
		(end 251.82957 -120.31345)
		(width 0.10668)
		(layer "F.Cu")
		(net "SMB_SCM_2_R3_SCL")
	)
	(via
		(at 251.1171 -118.19001)
		(size 0.508)
		(drill 0.254)
		(layers "F.Cu" "B.Cu")
		(net "SMB_SCM_2_R3_SCL")
	)
	(via
		(at 372.321328 -134.786624)
		(size 0.508)
		(drill 0.254)
		(layers "F.Cu" "B.Cu")
		(net "SMB_SCM_2_R3_SCL")
	)
	(via
		(at 389.31342 -142.989046)
		(size 0.508)
		(drill 0.254)
		(layers "F.Cu" "B.Cu")
		(net "SMB_SCM_2_R3_SCL")
	)
	(via
		(at 372.21033 -123.845828)
		(size 0.508)
		(drill 0.254)
		(layers "F.Cu" "B.Cu")
		(net "SMB_SCM_2_R3_SCL")
	)
	(segment
		(start 376.626374 -133.691376)
		(end 374.639586 -133.691376)
		(width 0.10668)
		(layer "B.Cu")
		(net "SMB_SCM_2_R3_SCL")
	)
	(segment
		(start 374.0404 -135.904986)
		(end 373.337328 -136.608058)
		(width 0.10668)
		(layer "B.Cu")
		(net "SMB_SCM_2_R3_SCL")
	)
	(segment
		(start 372.429278 -134.786624)
		(end 372.321328 -134.786624)
		(width 0.10668)
		(layer "B.Cu")
		(net "SMB_SCM_2_R3_SCL")
	)
	(segment
		(start 374.639586 -133.691376)
		(end 374.0404 -134.290562)
		(width 0.10668)
		(layer "B.Cu")
		(net "SMB_SCM_2_R3_SCL")
	)
	(segment
		(start 378.118878 -135.18388)
		(end 376.626374 -133.691376)
		(width 0.10668)
		(layer "B.Cu")
		(net "SMB_SCM_2_R3_SCL")
	)
	(segment
		(start 373.337328 -136.608058)
		(end 373.337328 -135.694674)
		(width 0.10668)
		(layer "B.Cu")
		(net "SMB_SCM_2_R3_SCL")
	)
	(segment
		(start 387.351524 -142.610586)
		(end 387.351524 -136.276334)
		(width 0.10668)
		(layer "B.Cu")
		(net "SMB_SCM_2_R3_SCL")
	)
	(segment
		(start 374.0404 -134.290562)
		(end 374.0404 -135.904986)
		(width 0.10668)
		(layer "B.Cu")
		(net "SMB_SCM_2_R3_SCL")
	)
	(segment
		(start 389.31342 -142.989046)
		(end 387.729984 -142.989046)
		(width 0.10668)
		(layer "B.Cu")
		(net "SMB_SCM_2_R3_SCL")
	)
	(segment
		(start 386.25907 -135.18388)
		(end 378.118878 -135.18388)
		(width 0.10668)
		(layer "B.Cu")
		(net "SMB_SCM_2_R3_SCL")
	)
	(segment
		(start 387.729984 -142.989046)
		(end 387.351524 -142.610586)
		(width 0.10668)
		(layer "B.Cu")
		(net "SMB_SCM_2_R3_SCL")
	)
	(segment
		(start 373.337328 -135.694674)
		(end 372.429278 -134.786624)
		(width 0.10668)
		(layer "B.Cu")
		(net "SMB_SCM_2_R3_SCL")
	)
	(segment
		(start 387.351524 -136.276334)
		(end 386.25907 -135.18388)
		(width 0.10668)
		(layer "B.Cu")
		(net "SMB_SCM_2_R3_SCL")
	)
	(segment
		(start 261.64159 -121.32818)
		(end 261.83209 -121.32818)
		(width 0.11684)
		(layer "In6.Cu")
		(net "SMB_SCM_2_R3_SCL")
	)
	(segment
		(start 265.43 -121.32818)
		(end 268.130528 -124.028708)
		(width 0.11684)
		(layer "In6.Cu")
		(net "SMB_SCM_2_R3_SCL")
	)
	(segment
		(start 261.94893 -122.12828)
		(end 262.06577 -122.24512)
		(width 0.11684)
		(layer "In6.Cu")
		(net "SMB_SCM_2_R3_SCL")
	)
	(segment
		(start 261.94893 -121.44502)
		(end 261.94893 -122.12828)
		(width 0.11684)
		(layer "In6.Cu")
		(net "SMB_SCM_2_R3_SCL")
	)
	(segment
		(start 261.10057 -121.44502)
		(end 261.10057 -122.12828)
		(width 0.11684)
		(layer "In6.Cu")
		(net "SMB_SCM_2_R3_SCL")
	)
	(segment
		(start 257.468624 -118.486936)
		(end 257.468624 -120.316244)
		(width 0.11684)
		(layer "In6.Cu")
		(net "SMB_SCM_2_R3_SCL")
	)
	(segment
		(start 262.25627 -122.24512)
		(end 262.37311 -122.12828)
		(width 0.11684)
		(layer "In6.Cu")
		(net "SMB_SCM_2_R3_SCL")
	)
	(segment
		(start 372.21033 -123.14047)
		(end 372.21033 -123.845828)
		(width 0.11684)
		(layer "In6.Cu")
		(net "SMB_SCM_2_R3_SCL")
	)
	(segment
		(start 289.91306 -124.93752)
		(end 291.77488 -123.0757)
		(width 0.11684)
		(layer "In6.Cu")
		(net "SMB_SCM_2_R3_SCL")
	)
	(segment
		(start 271.44218 -124.93752)
		(end 289.91306 -124.93752)
		(width 0.11684)
		(layer "In6.Cu")
		(net "SMB_SCM_2_R3_SCL")
	)
	(segment
		(start 256.454148 -117.47246)
		(end 257.468624 -118.486936)
		(width 0.11684)
		(layer "In6.Cu")
		(net "SMB_SCM_2_R3_SCL")
	)
	(segment
		(start 261.52475 -122.12828)
		(end 261.52475 -121.44502)
		(width 0.11684)
		(layer "In6.Cu")
		(net "SMB_SCM_2_R3_SCL")
	)
	(segment
		(start 291.77488 -123.0757)
		(end 308.41188 -123.0757)
		(width 0.11684)
		(layer "In6.Cu")
		(net "SMB_SCM_2_R3_SCL")
	)
	(segment
		(start 261.10057 -122.12828)
		(end 261.21741 -122.24512)
		(width 0.11684)
		(layer "In6.Cu")
		(net "SMB_SCM_2_R3_SCL")
	)
	(segment
		(start 262.37311 -121.44502)
		(end 262.48995 -121.32818)
		(width 0.11684)
		(layer "In6.Cu")
		(net "SMB_SCM_2_R3_SCL")
	)
	(segment
		(start 309.30342 -122.18416)
		(end 318.787272 -122.18416)
		(width 0.11684)
		(layer "In6.Cu")
		(net "SMB_SCM_2_R3_SCL")
	)
	(segment
		(start 262.06577 -122.24512)
		(end 262.25627 -122.24512)
		(width 0.11684)
		(layer "In6.Cu")
		(net "SMB_SCM_2_R3_SCL")
	)
	(segment
		(start 318.787272 -122.18416)
		(end 321.549014 -119.422418)
		(width 0.11684)
		(layer "In6.Cu")
		(net "SMB_SCM_2_R3_SCL")
	)
	(segment
		(start 252.50013 -116.80698)
		(end 253.92126 -116.80698)
		(width 0.11684)
		(layer "In6.Cu")
		(net "SMB_SCM_2_R3_SCL")
	)
	(segment
		(start 253.92126 -116.80698)
		(end 254.58674 -117.47246)
		(width 0.11684)
		(layer "In6.Cu")
		(net "SMB_SCM_2_R3_SCL")
	)
	(segment
		(start 260.98373 -121.32818)
		(end 261.10057 -121.44502)
		(width 0.11684)
		(layer "In6.Cu")
		(net "SMB_SCM_2_R3_SCL")
	)
	(segment
		(start 262.37311 -122.12828)
		(end 262.37311 -121.44502)
		(width 0.11684)
		(layer "In6.Cu")
		(net "SMB_SCM_2_R3_SCL")
	)
	(segment
		(start 261.21741 -122.24512)
		(end 261.40791 -122.24512)
		(width 0.11684)
		(layer "In6.Cu")
		(net "SMB_SCM_2_R3_SCL")
	)
	(segment
		(start 261.83209 -121.32818)
		(end 261.94893 -121.44502)
		(width 0.11684)
		(layer "In6.Cu")
		(net "SMB_SCM_2_R3_SCL")
	)
	(segment
		(start 270.533368 -124.028708)
		(end 271.44218 -124.93752)
		(width 0.11684)
		(layer "In6.Cu")
		(net "SMB_SCM_2_R3_SCL")
	)
	(segment
		(start 251.1171 -118.19001)
		(end 252.50013 -116.80698)
		(width 0.11684)
		(layer "In6.Cu")
		(net "SMB_SCM_2_R3_SCL")
	)
	(segment
		(start 261.40791 -122.24512)
		(end 261.52475 -122.12828)
		(width 0.11684)
		(layer "In6.Cu")
		(net "SMB_SCM_2_R3_SCL")
	)
	(segment
		(start 268.130528 -124.028708)
		(end 270.533368 -124.028708)
		(width 0.11684)
		(layer "In6.Cu")
		(net "SMB_SCM_2_R3_SCL")
	)
	(segment
		(start 262.48995 -121.32818)
		(end 265.43 -121.32818)
		(width 0.11684)
		(layer "In6.Cu")
		(net "SMB_SCM_2_R3_SCL")
	)
	(segment
		(start 258.48056 -121.32818)
		(end 260.98373 -121.32818)
		(width 0.11684)
		(layer "In6.Cu")
		(net "SMB_SCM_2_R3_SCL")
	)
	(segment
		(start 308.41188 -123.0757)
		(end 309.30342 -122.18416)
		(width 0.11684)
		(layer "In6.Cu")
		(net "SMB_SCM_2_R3_SCL")
	)
	(segment
		(start 261.52475 -121.44502)
		(end 261.64159 -121.32818)
		(width 0.11684)
		(layer "In6.Cu")
		(net "SMB_SCM_2_R3_SCL")
	)
	(segment
		(start 368.492278 -119.422418)
		(end 372.21033 -123.14047)
		(width 0.11684)
		(layer "In6.Cu")
		(net "SMB_SCM_2_R3_SCL")
	)
	(segment
		(start 257.468624 -120.316244)
		(end 258.48056 -121.32818)
		(width 0.11684)
		(layer "In6.Cu")
		(net "SMB_SCM_2_R3_SCL")
	)
	(segment
		(start 254.58674 -117.47246)
		(end 256.454148 -117.47246)
		(width 0.11684)
		(layer "In6.Cu")
		(net "SMB_SCM_2_R3_SCL")
	)
	(segment
		(start 321.549014 -119.422418)
		(end 368.492278 -119.422418)
		(width 0.11684)
		(layer "In6.Cu")
		(net "SMB_SCM_2_R3_SCL")
	)
	(segment
		(start 193.122042 -121.052844)
		(end 193.511932 -121.442734)
		(width 0.10668)
		(layer "F.Cu")
		(net "RST_PERST_OCP_V3_2_N")
	)
	(segment
		(start 75.064366 -61.75883)
		(end 75.255882 -61.567314)
		(width 0.10668)
		(layer "F.Cu")
		(net "RST_PERST_OCP_V3_2_N")
	)
	(segment
		(start 74.693526 -63.369444)
		(end 75.064366 -62.998604)
		(width 0.10668)
		(layer "F.Cu")
		(net "RST_PERST_OCP_V3_2_N")
	)
	(segment
		(start 75.064366 -62.998604)
		(end 75.064366 -61.75883)
		(width 0.10668)
		(layer "F.Cu")
		(net "RST_PERST_OCP_V3_2_N")
	)
	(segment
		(start 74.409046 -63.369444)
		(end 74.693526 -63.369444)
		(width 0.10668)
		(layer "F.Cu")
		(net "RST_PERST_OCP_V3_2_N")
	)
	(via
		(at 87.625936 -50.621946)
		(size 0.508)
		(drill 0.254)
		(layers "F.Cu" "B.Cu")
		(net "RST_PERST_OCP_V3_2_N")
	)
	(via
		(at 172.866304 -52.60467)
		(size 0.508)
		(drill 0.254)
		(layers "F.Cu" "B.Cu")
		(net "RST_PERST_OCP_V3_2_N")
	)
	(via
		(at 75.255882 -61.567314)
		(size 0.508)
		(drill 0.254)
		(layers "F.Cu" "B.Cu")
		(net "RST_PERST_OCP_V3_2_N")
	)
	(via
		(at 193.511932 -121.442734)
		(size 0.4572)
		(drill 0.254)
		(layers "F.Cu" "B.Cu")
		(net "RST_PERST_OCP_V3_2_N")
	)
	(segment
		(start 75.255882 -61.155072)
		(end 75.255882 -61.567314)
		(width 0.11684)
		(layer "In2.Cu")
		(net "RST_PERST_OCP_V3_2_N")
	)
	(segment
		(start 87.625936 -50.621946)
		(end 85.789008 -50.621946)
		(width 0.11684)
		(layer "In2.Cu")
		(net "RST_PERST_OCP_V3_2_N")
	)
	(segment
		(start 85.789008 -50.621946)
		(end 75.255882 -61.155072)
		(width 0.11684)
		(layer "In2.Cu")
		(net "RST_PERST_OCP_V3_2_N")
	)
	(segment
		(start 124.366528 -52.825396)
		(end 126.270004 -52.825396)
		(width 0.11684)
		(layer "In6.Cu")
		(net "RST_PERST_OCP_V3_2_N")
	)
	(segment
		(start 88.794336 -51.790346)
		(end 102.527862 -51.790346)
		(width 0.11684)
		(layer "In6.Cu")
		(net "RST_PERST_OCP_V3_2_N")
	)
	(segment
		(start 161.443924 -50.85207)
		(end 162.248596 -50.047398)
		(width 0.11684)
		(layer "In6.Cu")
		(net "RST_PERST_OCP_V3_2_N")
	)
	(segment
		(start 126.270004 -52.825396)
		(end 126.4158 -52.6796)
		(width 0.11684)
		(layer "In6.Cu")
		(net "RST_PERST_OCP_V3_2_N")
	)
	(segment
		(start 87.625936 -50.621946)
		(end 88.794336 -51.790346)
		(width 0.11684)
		(layer "In6.Cu")
		(net "RST_PERST_OCP_V3_2_N")
	)
	(segment
		(start 168.619678 -50.047398)
		(end 171.17695 -52.60467)
		(width 0.11684)
		(layer "In6.Cu")
		(net "RST_PERST_OCP_V3_2_N")
	)
	(segment
		(start 126.4158 -52.6796)
		(end 126.8984 -52.6796)
		(width 0.11684)
		(layer "In6.Cu")
		(net "RST_PERST_OCP_V3_2_N")
	)
	(segment
		(start 162.248596 -50.047398)
		(end 168.619678 -50.047398)
		(width 0.11684)
		(layer "In6.Cu")
		(net "RST_PERST_OCP_V3_2_N")
	)
	(segment
		(start 122.860054 -54.33187)
		(end 124.366528 -52.825396)
		(width 0.11684)
		(layer "In6.Cu")
		(net "RST_PERST_OCP_V3_2_N")
	)
	(segment
		(start 149.593554 -50.85207)
		(end 161.443924 -50.85207)
		(width 0.11684)
		(layer "In6.Cu")
		(net "RST_PERST_OCP_V3_2_N")
	)
	(segment
		(start 120.850914 -54.33187)
		(end 122.860054 -54.33187)
		(width 0.11684)
		(layer "In6.Cu")
		(net "RST_PERST_OCP_V3_2_N")
	)
	(segment
		(start 126.8984 -52.6796)
		(end 127.347472 -53.128672)
		(width 0.11684)
		(layer "In6.Cu")
		(net "RST_PERST_OCP_V3_2_N")
	)
	(segment
		(start 103.536496 -52.79898)
		(end 119.318024 -52.79898)
		(width 0.11684)
		(layer "In6.Cu")
		(net "RST_PERST_OCP_V3_2_N")
	)
	(segment
		(start 131.779772 -51.989228)
		(end 148.456396 -51.989228)
		(width 0.11684)
		(layer "In6.Cu")
		(net "RST_PERST_OCP_V3_2_N")
	)
	(segment
		(start 127.347472 -53.128672)
		(end 130.640328 -53.128672)
		(width 0.11684)
		(layer "In6.Cu")
		(net "RST_PERST_OCP_V3_2_N")
	)
	(segment
		(start 130.640328 -53.128672)
		(end 131.779772 -51.989228)
		(width 0.11684)
		(layer "In6.Cu")
		(net "RST_PERST_OCP_V3_2_N")
	)
	(segment
		(start 148.456396 -51.989228)
		(end 149.593554 -50.85207)
		(width 0.11684)
		(layer "In6.Cu")
		(net "RST_PERST_OCP_V3_2_N")
	)
	(segment
		(start 119.318024 -52.79898)
		(end 120.850914 -54.33187)
		(width 0.11684)
		(layer "In6.Cu")
		(net "RST_PERST_OCP_V3_2_N")
	)
	(segment
		(start 171.17695 -52.60467)
		(end 172.866304 -52.60467)
		(width 0.11684)
		(layer "In6.Cu")
		(net "RST_PERST_OCP_V3_2_N")
	)
	(segment
		(start 102.527862 -51.790346)
		(end 103.536496 -52.79898)
		(width 0.11684)
		(layer "In6.Cu")
		(net "RST_PERST_OCP_V3_2_N")
	)
	(segment
		(start 193.467228 -91.634056)
		(end 192.5955 -90.762328)
		(width 0.11684)
		(layer "In11.Cu")
		(net "RST_PERST_OCP_V3_2_N")
	)
	(segment
		(start 187.12942 -87.907114)
		(end 183.832246 -84.60994)
		(width 0.11684)
		(layer "In11.Cu")
		(net "RST_PERST_OCP_V3_2_N")
	)
	(segment
		(start 194.919092 -106.614468)
		(end 195.51904 -106.01452)
		(width 0.11684)
		(layer "In11.Cu")
		(net "RST_PERST_OCP_V3_2_N")
	)
	(segment
		(start 195.086224 -103.366316)
		(end 196.44868 -102.00386)
		(width 0.11684)
		(layer "In11.Cu")
		(net "RST_PERST_OCP_V3_2_N")
	)
	(segment
		(start 195.086224 -104.764332)
		(end 195.086224 -103.366316)
		(width 0.11684)
		(layer "In11.Cu")
		(net "RST_PERST_OCP_V3_2_N")
	)
	(segment
		(start 172.549312 -77.192886)
		(end 172.549312 -61.264546)
		(width 0.11684)
		(layer "In11.Cu")
		(net "RST_PERST_OCP_V3_2_N")
	)
	(segment
		(start 194.454526 -110.70971)
		(end 194.919092 -110.245144)
		(width 0.11684)
		(layer "In11.Cu")
		(net "RST_PERST_OCP_V3_2_N")
	)
	(segment
		(start 193.90614 -113.319052)
		(end 194.454526 -112.770666)
		(width 0.11684)
		(layer "In11.Cu")
		(net "RST_PERST_OCP_V3_2_N")
	)
	(segment
		(start 183.832246 -84.60994)
		(end 181.157118 -84.60994)
		(width 0.11684)
		(layer "In11.Cu")
		(net "RST_PERST_OCP_V3_2_N")
	)
	(segment
		(start 193.90614 -121.048526)
		(end 193.90614 -113.319052)
		(width 0.11684)
		(layer "In11.Cu")
		(net "RST_PERST_OCP_V3_2_N")
	)
	(segment
		(start 195.0847 -97.252028)
		(end 193.467228 -95.634556)
		(width 0.11684)
		(layer "In11.Cu")
		(net "RST_PERST_OCP_V3_2_N")
	)
	(segment
		(start 196.44868 -97.968308)
		(end 195.7324 -97.252028)
		(width 0.11684)
		(layer "In11.Cu")
		(net "RST_PERST_OCP_V3_2_N")
	)
	(segment
		(start 195.51904 -105.197148)
		(end 195.086224 -104.764332)
		(width 0.11684)
		(layer "In11.Cu")
		(net "RST_PERST_OCP_V3_2_N")
	)
	(segment
		(start 181.157118 -84.60994)
		(end 177.755296 -81.208118)
		(width 0.11684)
		(layer "In11.Cu")
		(net "RST_PERST_OCP_V3_2_N")
	)
	(segment
		(start 176.564544 -81.208118)
		(end 172.549312 -77.192886)
		(width 0.11684)
		(layer "In11.Cu")
		(net "RST_PERST_OCP_V3_2_N")
	)
	(segment
		(start 193.467228 -95.634556)
		(end 193.467228 -91.634056)
		(width 0.11684)
		(layer "In11.Cu")
		(net "RST_PERST_OCP_V3_2_N")
	)
	(segment
		(start 187.89142 -89.691718)
		(end 187.12942 -88.929718)
		(width 0.11684)
		(layer "In11.Cu")
		(net "RST_PERST_OCP_V3_2_N")
	)
	(segment
		(start 175.74387 -58.069988)
		(end 175.74387 -55.199788)
		(width 0.11684)
		(layer "In11.Cu")
		(net "RST_PERST_OCP_V3_2_N")
	)
	(segment
		(start 194.919092 -110.245144)
		(end 194.919092 -106.614468)
		(width 0.11684)
		(layer "In11.Cu")
		(net "RST_PERST_OCP_V3_2_N")
	)
	(segment
		(start 187.12942 -88.929718)
		(end 187.12942 -87.907114)
		(width 0.11684)
		(layer "In11.Cu")
		(net "RST_PERST_OCP_V3_2_N")
	)
	(segment
		(start 195.51904 -106.01452)
		(end 195.51904 -105.197148)
		(width 0.11684)
		(layer "In11.Cu")
		(net "RST_PERST_OCP_V3_2_N")
	)
	(segment
		(start 175.74387 -55.199788)
		(end 173.148752 -52.60467)
		(width 0.11684)
		(layer "In11.Cu")
		(net "RST_PERST_OCP_V3_2_N")
	)
	(segment
		(start 195.7324 -97.252028)
		(end 195.0847 -97.252028)
		(width 0.11684)
		(layer "In11.Cu")
		(net "RST_PERST_OCP_V3_2_N")
	)
	(segment
		(start 177.755296 -81.208118)
		(end 176.564544 -81.208118)
		(width 0.11684)
		(layer "In11.Cu")
		(net "RST_PERST_OCP_V3_2_N")
	)
	(segment
		(start 193.511932 -121.442734)
		(end 193.90614 -121.048526)
		(width 0.11684)
		(layer "In11.Cu")
		(net "RST_PERST_OCP_V3_2_N")
	)
	(segment
		(start 190.010542 -89.691718)
		(end 187.89142 -89.691718)
		(width 0.11684)
		(layer "In11.Cu")
		(net "RST_PERST_OCP_V3_2_N")
	)
	(segment
		(start 192.5955 -90.762328)
		(end 190.010542 -89.691718)
		(width 0.11684)
		(layer "In11.Cu")
		(net "RST_PERST_OCP_V3_2_N")
	)
	(segment
		(start 172.549312 -61.264546)
		(end 175.74387 -58.069988)
		(width 0.11684)
		(layer "In11.Cu")
		(net "RST_PERST_OCP_V3_2_N")
	)
	(segment
		(start 196.44868 -102.00386)
		(end 196.44868 -97.968308)
		(width 0.11684)
		(layer "In11.Cu")
		(net "RST_PERST_OCP_V3_2_N")
	)
	(segment
		(start 173.148752 -52.60467)
		(end 172.866304 -52.60467)
		(width 0.11684)
		(layer "In11.Cu")
		(net "RST_PERST_OCP_V3_2_N")
	)
	(segment
		(start 194.454526 -112.770666)
		(end 194.454526 -110.70971)
		(width 0.11684)
		(layer "In11.Cu")
		(net "RST_PERST_OCP_V3_2_N")
	)
	(segment
		(start 397.619982 -136.928098)
		(end 403.53742 -136.928098)
		(width 0.10668)
		(layer "F.Cu")
		(net "PWRGD_P5V_AUX_R2")
	)
	(segment
		(start 209.294476 -106.513376)
		(end 210.144614 -106.513376)
		(width 0.10668)
		(layer "F.Cu")
		(net "PWRGD_P5V_AUX_R2")
	)
	(segment
		(start 395.782292 -123.644914)
		(end 395.782292 -135.090408)
		(width 0.10668)
		(layer "F.Cu")
		(net "PWRGD_P5V_AUX_R2")
	)
	(segment
		(start 405.459946 -136.231376)
		(end 406.075896 -136.231376)
		(width 0.10668)
		(layer "F.Cu")
		(net "PWRGD_P5V_AUX_R2")
	)
	(segment
		(start 403.963378 -136.50214)
		(end 403.963378 -136.231376)
		(width 0.10668)
		(layer "F.Cu")
		(net "PWRGD_P5V_AUX_R2")
	)
	(segment
		(start 403.53742 -136.928098)
		(end 403.963378 -136.50214)
		(width 0.10668)
		(layer "F.Cu")
		(net "PWRGD_P5V_AUX_R2")
	)
	(segment
		(start 403.963378 -136.231376)
		(end 405.459946 -136.231376)
		(width 0.10668)
		(layer "F.Cu")
		(net "PWRGD_P5V_AUX_R2")
	)
	(segment
		(start 395.782292 -135.090408)
		(end 397.619982 -136.928098)
		(width 0.10668)
		(layer "F.Cu")
		(net "PWRGD_P5V_AUX_R2")
	)
	(via
		(at 210.144614 -106.513376)
		(size 0.508)
		(drill 0.254)
		(layers "F.Cu" "B.Cu")
		(net "PWRGD_P5V_AUX_R2")
	)
	(via
		(at 395.782292 -123.644914)
		(size 0.508)
		(drill 0.254)
		(layers "F.Cu" "B.Cu")
		(net "PWRGD_P5V_AUX_R2")
	)
	(via
		(at 405.459946 -136.231376)
		(size 0.508)
		(drill 0.254)
		(layers "F.Cu" "B.Cu")
		(net "PWRGD_P5V_AUX_R2")
	)
	(segment
		(start 263.224518 -102.754684)
		(end 260.978904 -105.000298)
		(width 0.11684)
		(layer "In6.Cu")
		(net "PWRGD_P5V_AUX_R2")
	)
	(segment
		(start 382.763776 -122.442986)
		(end 382.763776 -120.923812)
		(width 0.11684)
		(layer "In6.Cu")
		(net "PWRGD_P5V_AUX_R2")
	)
	(segment
		(start 383.965704 -123.644914)
		(end 382.763776 -122.442986)
		(width 0.11684)
		(layer "In6.Cu")
		(net "PWRGD_P5V_AUX_R2")
	)
	(segment
		(start 273.92503 -102.754684)
		(end 263.224518 -102.754684)
		(width 0.11684)
		(layer "In6.Cu")
		(net "PWRGD_P5V_AUX_R2")
	)
	(segment
		(start 322.103242 -111.999776)
		(end 314.065158 -103.961692)
		(width 0.11684)
		(layer "In6.Cu")
		(net "PWRGD_P5V_AUX_R2")
	)
	(segment
		(start 218.413838 -105.000298)
		(end 217.406474 -103.992934)
		(width 0.11684)
		(layer "In6.Cu")
		(net "PWRGD_P5V_AUX_R2")
	)
	(segment
		(start 215.995758 -103.992934)
		(end 213.475316 -106.513376)
		(width 0.11684)
		(layer "In6.Cu")
		(net "PWRGD_P5V_AUX_R2")
	)
	(segment
		(start 395.782292 -123.644914)
		(end 383.965704 -123.644914)
		(width 0.11684)
		(layer "In6.Cu")
		(net "PWRGD_P5V_AUX_R2")
	)
	(segment
		(start 217.406474 -103.992934)
		(end 215.995758 -103.992934)
		(width 0.11684)
		(layer "In6.Cu")
		(net "PWRGD_P5V_AUX_R2")
	)
	(segment
		(start 213.475316 -106.513376)
		(end 210.144614 -106.513376)
		(width 0.11684)
		(layer "In6.Cu")
		(net "PWRGD_P5V_AUX_R2")
	)
	(segment
		(start 373.911622 -112.435132)
		(end 369.325906 -112.435132)
		(width 0.11684)
		(layer "In6.Cu")
		(net "PWRGD_P5V_AUX_R2")
	)
	(segment
		(start 220.66758 -105.000298)
		(end 218.413838 -105.000298)
		(width 0.11684)
		(layer "In6.Cu")
		(net "PWRGD_P5V_AUX_R2")
	)
	(segment
		(start 368.89055 -111.999776)
		(end 322.103242 -111.999776)
		(width 0.11684)
		(layer "In6.Cu")
		(net "PWRGD_P5V_AUX_R2")
	)
	(segment
		(start 222.170498 -105.4608)
		(end 221.128082 -105.4608)
		(width 0.11684)
		(layer "In6.Cu")
		(net "PWRGD_P5V_AUX_R2")
	)
	(segment
		(start 382.763776 -120.923812)
		(end 381.189738 -119.349774)
		(width 0.11684)
		(layer "In6.Cu")
		(net "PWRGD_P5V_AUX_R2")
	)
	(segment
		(start 221.128082 -105.4608)
		(end 220.66758 -105.000298)
		(width 0.11684)
		(layer "In6.Cu")
		(net "PWRGD_P5V_AUX_R2")
	)
	(segment
		(start 314.065158 -103.961692)
		(end 275.132038 -103.961692)
		(width 0.11684)
		(layer "In6.Cu")
		(net "PWRGD_P5V_AUX_R2")
	)
	(segment
		(start 380.826264 -119.349774)
		(end 373.911622 -112.435132)
		(width 0.11684)
		(layer "In6.Cu")
		(net "PWRGD_P5V_AUX_R2")
	)
	(segment
		(start 369.325906 -112.435132)
		(end 368.89055 -111.999776)
		(width 0.11684)
		(layer "In6.Cu")
		(net "PWRGD_P5V_AUX_R2")
	)
	(segment
		(start 275.132038 -103.961692)
		(end 273.92503 -102.754684)
		(width 0.11684)
		(layer "In6.Cu")
		(net "PWRGD_P5V_AUX_R2")
	)
	(segment
		(start 381.189738 -119.349774)
		(end 380.826264 -119.349774)
		(width 0.11684)
		(layer "In6.Cu")
		(net "PWRGD_P5V_AUX_R2")
	)
	(segment
		(start 260.978904 -105.000298)
		(end 222.631 -105.000298)
		(width 0.11684)
		(layer "In6.Cu")
		(net "PWRGD_P5V_AUX_R2")
	)
	(segment
		(start 222.631 -105.000298)
		(end 222.170498 -105.4608)
		(width 0.11684)
		(layer "In6.Cu")
		(net "PWRGD_P5V_AUX_R2")
	)
	(segment
		(start 402.063458 -134.931404)
		(end 400.795236 -134.931404)
		(width 0.10668)
		(layer "F.Cu")
		(net "PWRGD_P5V_AUX_R1")
	)
	(segment
		(start 402.063458 -134.931404)
		(end 402.063458 -135.58139)
		(width 0.10668)
		(layer "F.Cu")
		(net "PWRGD_P5V_AUX_R1")
	)
	(segment
		(start 399.598896 -134.931404)
		(end 399.597372 -134.92988)
		(width 0.10668)
		(layer "F.Cu")
		(net "PWRGD_P5V_AUX_R1")
	)
	(segment
		(start 400.795236 -134.931404)
		(end 399.598896 -134.931404)
		(width 0.10668)
		(layer "F.Cu")
		(net "PWRGD_P5V_AUX_R1")
	)
	(via
		(at 400.795236 -134.931404)
		(size 0.762)
		(drill 0.381)
		(layers "F.Cu" "B.Cu")
		(net "PWRGD_P5V_AUX_R1")
	)
	(segment
		(start 186.387994 -133.137148)
		(end 186.387994 -132.706364)
		(width 0.10668)
		(layer "F.Cu")
		(net "PWRGD_P3V3_R2")
	)
	(segment
		(start 185.922158 -118.652798)
		(end 186.312048 -119.042688)
		(width 0.10668)
		(layer "F.Cu")
		(net "PWRGD_P3V3_R2")
	)
	(segment
		(start 186.387994 -132.706364)
		(end 186.055 -132.37337)
		(width 0.10668)
		(layer "F.Cu")
		(net "PWRGD_P3V3_R2")
	)
	(segment
		(start 187.908184 -127.825754)
		(end 187.908184 -129.706878)
		(width 0.10668)
		(layer "F.Cu")
		(net "PWRGD_P3V3_R2")
	)
	(segment
		(start 187.198 -130.417062)
		(end 187.198 -130.541268)
		(width 0.10668)
		(layer "F.Cu")
		(net "PWRGD_P3V3_R2")
	)
	(segment
		(start 188.034422 -127.699516)
		(end 187.908184 -127.825754)
		(width 0.10668)
		(layer "F.Cu")
		(net "PWRGD_P3V3_R2")
	)
	(segment
		(start 187.908184 -129.706878)
		(end 187.198 -130.417062)
		(width 0.10668)
		(layer "F.Cu")
		(net "PWRGD_P3V3_R2")
	)
	(segment
		(start 186.055 -131.684268)
		(end 187.030106 -130.709162)
		(width 0.10668)
		(layer "F.Cu")
		(net "PWRGD_P3V3_R2")
	)
	(segment
		(start 186.055 -132.37337)
		(end 186.055 -131.684268)
		(width 0.10668)
		(layer "F.Cu")
		(net "PWRGD_P3V3_R2")
	)
	(segment
		(start 187.198 -130.541268)
		(end 187.030106 -130.709162)
		(width 0.10668)
		(layer "F.Cu")
		(net "PWRGD_P3V3_R2")
	)
	(segment
		(start 187.622688 -125.588776)
		(end 188.034422 -126.00051)
		(width 0.10668)
		(layer "F.Cu")
		(net "PWRGD_P3V3_R2")
	)
	(segment
		(start 188.034422 -126.00051)
		(end 188.034422 -127.699516)
		(width 0.10668)
		(layer "F.Cu")
		(net "PWRGD_P3V3_R2")
	)
	(via
		(at 186.312048 -119.042688)
		(size 0.4572)
		(drill 0.254)
		(layers "F.Cu" "B.Cu")
		(net "PWRGD_P3V3_R2")
	)
	(via
		(at 187.622688 -125.588776)
		(size 0.508)
		(drill 0.254)
		(layers "F.Cu" "B.Cu")
		(net "PWRGD_P3V3_R2")
	)
	(via
		(at 187.030106 -130.709162)
		(size 0.762)
		(drill 0.381)
		(layers "F.Cu" "B.Cu")
		(net "PWRGD_P3V3_R2")
	)
	(segment
		(start 186.449208 -119.042688)
		(end 186.312048 -119.042688)
		(width 0.11684)
		(layer "In4.Cu")
		(net "PWRGD_P3V3_R2")
	)
	(segment
		(start 186.70524 -124.671328)
		(end 186.70524 -119.29872)
		(width 0.11684)
		(layer "In4.Cu")
		(net "PWRGD_P3V3_R2")
	)
	(segment
		(start 186.70524 -119.29872)
		(end 186.449208 -119.042688)
		(width 0.11684)
		(layer "In4.Cu")
		(net "PWRGD_P3V3_R2")
	)
	(segment
		(start 187.622688 -125.588776)
		(end 186.70524 -124.671328)
		(width 0.11684)
		(layer "In4.Cu")
		(net "PWRGD_P3V3_R2")
	)
	(segment
		(start 107.895136 -127.348488)
		(end 107.895136 -126.129288)
		(width 0.10668)
		(layer "F.Cu")
		(net "PWRGD_P3V3_R1")
	)
	(segment
		(start 107.895136 -126.129288)
		(end 108.51515 -125.509274)
		(width 0.10668)
		(layer "F.Cu")
		(net "PWRGD_P3V3_R1")
	)
	(segment
		(start 186.055 -134.584948)
		(end 186.055 -134.270242)
		(width 0.10668)
		(layer "F.Cu")
		(net "PWRGD_P3V3_R1")
	)
	(segment
		(start 108.51515 -125.509274)
		(end 108.51515 -124.541788)
		(width 0.10668)
		(layer "F.Cu")
		(net "PWRGD_P3V3_R1")
	)
	(segment
		(start 186.055 -134.270242)
		(end 186.387994 -133.937248)
		(width 0.10668)
		(layer "F.Cu")
		(net "PWRGD_P3V3_R1")
	)
	(via
		(at 107.895136 -126.129288)
		(size 0.508)
		(drill 0.254)
		(layers "F.Cu" "B.Cu")
		(net "PWRGD_P3V3_R1")
	)
	(via
		(at 154.201114 -134.154672)
		(size 0.508)
		(drill 0.254)
		(layers "F.Cu" "B.Cu")
		(net "PWRGD_P3V3_R1")
	)
	(via
		(at 186.055 -134.584948)
		(size 0.508)
		(drill 0.254)
		(layers "F.Cu" "B.Cu")
		(net "PWRGD_P3V3_R1")
	)
	(segment
		(start 148.662136 -128.615694)
		(end 114.738658 -128.615694)
		(width 0.10668)
		(layer "B.Cu")
		(net "PWRGD_P3V3_R1")
	)
	(segment
		(start 112.903508 -126.780544)
		(end 108.546392 -126.780544)
		(width 0.10668)
		(layer "B.Cu")
		(net "PWRGD_P3V3_R1")
	)
	(segment
		(start 154.201114 -134.154672)
		(end 148.662136 -128.615694)
		(width 0.10668)
		(layer "B.Cu")
		(net "PWRGD_P3V3_R1")
	)
	(segment
		(start 108.546392 -126.780544)
		(end 107.895136 -126.129288)
		(width 0.10668)
		(layer "B.Cu")
		(net "PWRGD_P3V3_R1")
	)
	(segment
		(start 114.738658 -128.615694)
		(end 112.903508 -126.780544)
		(width 0.10668)
		(layer "B.Cu")
		(net "PWRGD_P3V3_R1")
	)
	(segment
		(start 185.59018 -134.826248)
		(end 185.83148 -134.584948)
		(width 0.11684)
		(layer "In2.Cu")
		(net "PWRGD_P3V3_R1")
	)
	(segment
		(start 154.201114 -134.154672)
		(end 154.82697 -134.154672)
		(width 0.11684)
		(layer "In2.Cu")
		(net "PWRGD_P3V3_R1")
	)
	(segment
		(start 185.83148 -134.584948)
		(end 186.055 -134.584948)
		(width 0.11684)
		(layer "In2.Cu")
		(net "PWRGD_P3V3_R1")
	)
	(segment
		(start 157.75559 -137.083292)
		(end 157.75559 -140.988034)
		(width 0.11684)
		(layer "In2.Cu")
		(net "PWRGD_P3V3_R1")
	)
	(segment
		(start 186.550554 -140.637768)
		(end 186.550554 -138.114278)
		(width 0.11684)
		(layer "In2.Cu")
		(net "PWRGD_P3V3_R1")
	)
	(segment
		(start 186.550554 -138.114278)
		(end 185.59018 -137.153904)
		(width 0.11684)
		(layer "In2.Cu")
		(net "PWRGD_P3V3_R1")
	)
	(segment
		(start 154.82697 -134.154672)
		(end 157.75559 -137.083292)
		(width 0.11684)
		(layer "In2.Cu")
		(net "PWRGD_P3V3_R1")
	)
	(segment
		(start 185.212736 -141.975586)
		(end 186.550554 -140.637768)
		(width 0.11684)
		(layer "In2.Cu")
		(net "PWRGD_P3V3_R1")
	)
	(segment
		(start 157.75559 -140.988034)
		(end 158.743142 -141.975586)
		(width 0.11684)
		(layer "In2.Cu")
		(net "PWRGD_P3V3_R1")
	)
	(segment
		(start 158.743142 -141.975586)
		(end 185.212736 -141.975586)
		(width 0.11684)
		(layer "In2.Cu")
		(net "PWRGD_P3V3_R1")
	)
	(segment
		(start 185.59018 -137.153904)
		(end 185.59018 -134.826248)
		(width 0.11684)
		(layer "In2.Cu")
		(net "PWRGD_P3V3_R1")
	)
	(segment
		(start 109.815122 -123.172474)
		(end 109.665262 -123.322334)
		(width 0.10668)
		(layer "F.Cu")
		(net "PWRGD_P3V3_EN_N")
	)
	(segment
		(start 109.815122 -122.66676)
		(end 109.815122 -123.172474)
		(width 0.10668)
		(layer "F.Cu")
		(net "PWRGD_P3V3_EN_N")
	)
	(segment
		(start 109.165136 -122.66676)
		(end 109.165136 -121.07926)
		(width 0.10668)
		(layer "F.Cu")
		(net "PWRGD_P3V3_EN_N")
	)
	(segment
		(start 109.165136 -123.172474)
		(end 109.165136 -122.66676)
		(width 0.10668)
		(layer "F.Cu")
		(net "PWRGD_P3V3_EN_N")
	)
	(segment
		(start 109.165136 -119.86006)
		(end 109.165136 -121.07926)
		(width 0.10668)
		(layer "F.Cu")
		(net "PWRGD_P3V3_EN_N")
	)
	(segment
		(start 109.665262 -123.322334)
		(end 109.314996 -123.322334)
		(width 0.10668)
		(layer "F.Cu")
		(net "PWRGD_P3V3_EN_N")
	)
	(segment
		(start 109.314996 -123.322334)
		(end 109.165136 -123.172474)
		(width 0.10668)
		(layer "F.Cu")
		(net "PWRGD_P3V3_EN_N")
	)
	(via
		(at 109.165136 -121.07926)
		(size 0.762)
		(drill 0.381)
		(layers "F.Cu" "B.Cu")
		(net "PWRGD_P3V3_EN_N")
	)
	(segment
		(start 111.633 -126.13005)
		(end 109.165898 -126.13005)
		(width 0.10668)
		(layer "F.Cu")
		(net "PWRGD_P3V3_EN")
	)
	(segment
		(start 109.165136 -126.129288)
		(end 109.165136 -124.541788)
		(width 0.10668)
		(layer "F.Cu")
		(net "PWRGD_P3V3_EN")
	)
	(segment
		(start 109.165898 -126.13005)
		(end 109.165136 -126.129288)
		(width 0.10668)
		(layer "F.Cu")
		(net "PWRGD_P3V3_EN")
	)
	(via
		(at 109.165136 -126.129288)
		(size 0.762)
		(drill 0.381)
		(layers "F.Cu" "B.Cu")
		(net "PWRGD_P3V3_EN")
	)
	(segment
		(start 147.877022 -21.906992)
		(end 148.527008 -21.906992)
		(width 0.10668)
		(layer "F.Cu")
		(net "PU_JTAG_DBP_BMC_PRDY_N")
	)
	(segment
		(start 141.746986 -13.599922)
		(end 141.746986 -10.984484)
		(width 0.10668)
		(layer "F.Cu")
		(net "PU_JTAG_DBP_BMC_PRDY_N")
	)
	(segment
		(start 141.746986 -10.984484)
		(end 141.313154 -10.550652)
		(width 0.10668)
		(layer "F.Cu")
		(net "PU_JTAG_DBP_BMC_PRDY_N")
	)
	(via
		(at 148.527008 -21.906992)
		(size 0.508)
		(drill 0.254)
		(layers "F.Cu" "B.Cu")
		(net "PU_JTAG_DBP_BMC_PRDY_N")
	)
	(via
		(at 141.313154 -10.550652)
		(size 0.508)
		(drill 0.254)
		(layers "F.Cu" "B.Cu")
		(net "PU_JTAG_DBP_BMC_PRDY_N")
	)
	(segment
		(start 146.511264 -19.055334)
		(end 147.701 -20.24507)
		(width 0.10668)
		(layer "B.Cu")
		(net "PU_JTAG_DBP_BMC_PRDY_N")
	)
	(segment
		(start 143.92783 -19.055334)
		(end 146.511264 -19.055334)
		(width 0.10668)
		(layer "B.Cu")
		(net "PU_JTAG_DBP_BMC_PRDY_N")
	)
	(segment
		(start 143.503396 -18.6309)
		(end 143.92783 -19.055334)
		(width 0.10668)
		(layer "B.Cu")
		(net "PU_JTAG_DBP_BMC_PRDY_N")
	)
	(segment
		(start 141.746986 -12.368022)
		(end 140.915136 -13.199872)
		(width 0.10668)
		(layer "B.Cu")
		(net "PU_JTAG_DBP_BMC_PRDY_N")
	)
	(segment
		(start 140.915136 -14.823186)
		(end 143.503396 -17.411446)
		(width 0.10668)
		(layer "B.Cu")
		(net "PU_JTAG_DBP_BMC_PRDY_N")
	)
	(segment
		(start 140.915136 -13.199872)
		(end 140.915136 -14.823186)
		(width 0.10668)
		(layer "B.Cu")
		(net "PU_JTAG_DBP_BMC_PRDY_N")
	)
	(segment
		(start 147.701 -20.24507)
		(end 147.701 -21.080984)
		(width 0.10668)
		(layer "B.Cu")
		(net "PU_JTAG_DBP_BMC_PRDY_N")
	)
	(segment
		(start 143.503396 -17.411446)
		(end 143.503396 -18.6309)
		(width 0.10668)
		(layer "B.Cu")
		(net "PU_JTAG_DBP_BMC_PRDY_N")
	)
	(segment
		(start 141.313154 -10.550652)
		(end 141.746986 -10.984484)
		(width 0.10668)
		(layer "B.Cu")
		(net "PU_JTAG_DBP_BMC_PRDY_N")
	)
	(segment
		(start 141.746986 -10.984484)
		(end 141.746986 -12.368022)
		(width 0.10668)
		(layer "B.Cu")
		(net "PU_JTAG_DBP_BMC_PRDY_N")
	)
	(segment
		(start 147.701 -21.080984)
		(end 148.527008 -21.906992)
		(width 0.10668)
		(layer "B.Cu")
		(net "PU_JTAG_DBP_BMC_PRDY_N")
	)
	(segment
		(start 319.032128 -44.208954)
		(end 318.289178 -44.208954)
		(width 0.10668)
		(layer "F.Cu")
		(net "P5V_ADC_TIC")
	)
	(segment
		(start 321.749166 -43.573954)
		(end 321.114166 -44.208954)
		(width 0.10668)
		(layer "F.Cu")
		(net "P5V_ADC_TIC")
	)
	(segment
		(start 322.436998 -43.573954)
		(end 321.749166 -43.573954)
		(width 0.10668)
		(layer "F.Cu")
		(net "P5V_ADC_TIC")
	)
	(segment
		(start 321.114166 -44.208954)
		(end 320.048128 -44.208954)
		(width 0.10668)
		(layer "F.Cu")
		(net "P5V_ADC_TIC")
	)
	(segment
		(start 316.765178 -44.208954)
		(end 316.344554 -43.78833)
		(width 0.10668)
		(layer "F.Cu")
		(net "P5V_ADC_TIC")
	)
	(segment
		(start 316.344554 -43.78833)
		(end 315.525404 -43.78833)
		(width 0.10668)
		(layer "F.Cu")
		(net "P5V_ADC_TIC")
	)
	(segment
		(start 318.289178 -44.208954)
		(end 316.765178 -44.208954)
		(width 0.10668)
		(layer "F.Cu")
		(net "P5V_ADC_TIC")
	)
	(segment
		(start 320.048128 -44.208954)
		(end 319.540128 -43.700954)
		(width 0.10668)
		(layer "F.Cu")
		(net "P5V_ADC_TIC")
	)
	(segment
		(start 319.540128 -43.700954)
		(end 319.032128 -44.208954)
		(width 0.10668)
		(layer "F.Cu")
		(net "P5V_ADC_TIC")
	)
	(via
		(at 318.289178 -44.208954)
		(size 0.762)
		(drill 0.381)
		(layers "F.Cu" "B.Cu")
		(net "P5V_ADC_TIC")
	)
	(segment
		(start 316.374526 -31.63316)
		(end 316.171072 -31.429706)
		(width 0.10668)
		(layer "F.Cu")
		(net "P5V_ADC_MAM")
	)
	(segment
		(start 318.438022 -31.683706)
		(end 319.152778 -32.398462)
		(width 0.10668)
		(layer "F.Cu")
		(net "P5V_ADC_MAM")
	)
	(segment
		(start 324.037198 -43.573954)
		(end 324.646798 -43.573954)
		(width 0.10668)
		(layer "F.Cu")
		(net "P5V_ADC_MAM")
	)
	(segment
		(start 318.184022 -31.683706)
		(end 318.438022 -31.683706)
		(width 0.10668)
		(layer "F.Cu")
		(net "P5V_ADC_MAM")
	)
	(segment
		(start 319.152778 -32.398462)
		(end 319.99809 -32.398462)
		(width 0.10668)
		(layer "F.Cu")
		(net "P5V_ADC_MAM")
	)
	(segment
		(start 318.133476 -31.63316)
		(end 316.374526 -31.63316)
		(width 0.10668)
		(layer "F.Cu")
		(net "P5V_ADC_MAM")
	)
	(segment
		(start 318.184022 -31.683706)
		(end 318.133476 -31.63316)
		(width 0.10668)
		(layer "F.Cu")
		(net "P5V_ADC_MAM")
	)
	(via
		(at 318.184022 -31.683706)
		(size 0.508)
		(drill 0.254)
		(layers "F.Cu" "B.Cu")
		(net "P5V_ADC_MAM")
	)
	(via
		(at 324.646798 -43.573954)
		(size 0.508)
		(drill 0.254)
		(layers "F.Cu" "B.Cu")
		(net "P5V_ADC_MAM")
	)
	(segment
		(start 323.84746 -30.368748)
		(end 323.84746 -42.774616)
		(width 0.11684)
		(layer "In4.Cu")
		(net "P5V_ADC_MAM")
	)
	(segment
		(start 318.184022 -31.683706)
		(end 320.9544 -28.913328)
		(width 0.11684)
		(layer "In4.Cu")
		(net "P5V_ADC_MAM")
	)
	(segment
		(start 323.84746 -42.774616)
		(end 324.646798 -43.573954)
		(width 0.11684)
		(layer "In4.Cu")
		(net "P5V_ADC_MAM")
	)
	(segment
		(start 320.9544 -28.913328)
		(end 322.39204 -28.913328)
		(width 0.11684)
		(layer "In4.Cu")
		(net "P5V_ADC_MAM")
	)
	(segment
		(start 322.39204 -28.913328)
		(end 323.84746 -30.368748)
		(width 0.11684)
		(layer "In4.Cu")
		(net "P5V_ADC_MAM")
	)
	(segment
		(start 326.836532 -43.82897)
		(end 327.166732 -44.15917)
		(width 0.10668)
		(layer "F.Cu")
		(net "P5V_ADC")
	)
	(segment
		(start 327.166732 -44.15917)
		(end 328.826876 -44.15917)
		(width 0.10668)
		(layer "F.Cu")
		(net "P5V_ADC")
	)
	(segment
		(start 323.237098 -43.573954)
		(end 323.237098 -43.905424)
		(width 0.10668)
		(layer "F.Cu")
		(net "P5V_ADC")
	)
	(segment
		(start 326.779128 -43.573954)
		(end 326.355964 -43.573954)
		(width 0.10668)
		(layer "F.Cu")
		(net "P5V_ADC")
	)
	(segment
		(start 325.293736 -44.113704)
		(end 325.320914 -44.140882)
		(width 0.10668)
		(layer "F.Cu")
		(net "P5V_ADC")
	)
	(segment
		(start 326.779128 -43.573954)
		(end 326.836532 -43.631358)
		(width 0.10668)
		(layer "F.Cu")
		(net "P5V_ADC")
	)
	(segment
		(start 329.192128 -43.793918)
		(end 329.192128 -43.573954)
		(width 0.10668)
		(layer "F.Cu")
		(net "P5V_ADC")
	)
	(segment
		(start 323.445378 -44.113704)
		(end 325.293736 -44.113704)
		(width 0.10668)
		(layer "F.Cu")
		(net "P5V_ADC")
	)
	(segment
		(start 323.237098 -43.905424)
		(end 323.445378 -44.113704)
		(width 0.10668)
		(layer "F.Cu")
		(net "P5V_ADC")
	)
	(segment
		(start 328.826876 -44.15917)
		(end 329.192128 -43.793918)
		(width 0.10668)
		(layer "F.Cu")
		(net "P5V_ADC")
	)
	(segment
		(start 325.789036 -44.140882)
		(end 325.320914 -44.140882)
		(width 0.10668)
		(layer "F.Cu")
		(net "P5V_ADC")
	)
	(segment
		(start 326.836532 -43.631358)
		(end 326.836532 -43.82897)
		(width 0.10668)
		(layer "F.Cu")
		(net "P5V_ADC")
	)
	(segment
		(start 326.355964 -43.573954)
		(end 325.789036 -44.140882)
		(width 0.10668)
		(layer "F.Cu")
		(net "P5V_ADC")
	)
	(via
		(at 325.320914 -44.140882)
		(size 0.762)
		(drill 0.381)
		(layers "F.Cu" "B.Cu")
		(net "P5V_ADC")
	)
	(segment
		(start 322.436998 -40.144954)
		(end 321.435222 -41.14673)
		(width 0.10668)
		(layer "F.Cu")
		(net "P3V3_PDB_AUX_ADC_TIC")
	)
	(segment
		(start 318.651128 -41.541954)
		(end 317.273178 -41.541954)
		(width 0.10668)
		(layer "F.Cu")
		(net "P3V3_PDB_AUX_ADC_TIC")
	)
	(segment
		(start 321.435222 -41.14673)
		(end 320.033904 -41.14673)
		(width 0.10668)
		(layer "F.Cu")
		(net "P3V3_PDB_AUX_ADC_TIC")
	)
	(segment
		(start 316.638178 -41.541954)
		(end 316.342014 -41.838118)
		(width 0.10668)
		(layer "F.Cu")
		(net "P3V3_PDB_AUX_ADC_TIC")
	)
	(segment
		(start 319.540128 -40.652954)
		(end 318.651128 -41.541954)
		(width 0.10668)
		(layer "F.Cu")
		(net "P3V3_PDB_AUX_ADC_TIC")
	)
	(segment
		(start 320.033904 -41.14673)
		(end 319.540128 -40.652954)
		(width 0.10668)
		(layer "F.Cu")
		(net "P3V3_PDB_AUX_ADC_TIC")
	)
	(segment
		(start 317.273178 -41.541954)
		(end 316.638178 -41.541954)
		(width 0.10668)
		(layer "F.Cu")
		(net "P3V3_PDB_AUX_ADC_TIC")
	)
	(segment
		(start 316.342014 -41.838118)
		(end 315.525404 -41.838118)
		(width 0.10668)
		(layer "F.Cu")
		(net "P3V3_PDB_AUX_ADC_TIC")
	)
	(via
		(at 317.273178 -41.541954)
		(size 0.762)
		(drill 0.381)
		(layers "F.Cu" "B.Cu")
		(net "P3V3_PDB_AUX_ADC_TIC")
	)
	(segment
		(start 324.15226 -40.144954)
		(end 324.665594 -39.63162)
		(width 0.10668)
		(layer "F.Cu")
		(net "P3V3_PDB_AUX_ADC_MAM")
	)
	(segment
		(start 327.419716 -33.4264)
		(end 326.37984 -33.4264)
		(width 0.10668)
		(layer "F.Cu")
		(net "P3V3_PDB_AUX_ADC_MAM")
	)
	(segment
		(start 324.037198 -40.144954)
		(end 324.15226 -40.144954)
		(width 0.10668)
		(layer "F.Cu")
		(net "P3V3_PDB_AUX_ADC_MAM")
	)
	(segment
		(start 327.709022 -33.715706)
		(end 327.419716 -33.4264)
		(width 0.10668)
		(layer "F.Cu")
		(net "P3V3_PDB_AUX_ADC_MAM")
	)
	(segment
		(start 328.959972 -33.969706)
		(end 327.963022 -33.969706)
		(width 0.10668)
		(layer "F.Cu")
		(net "P3V3_PDB_AUX_ADC_MAM")
	)
	(segment
		(start 327.963022 -33.969706)
		(end 327.709022 -33.715706)
		(width 0.10668)
		(layer "F.Cu")
		(net "P3V3_PDB_AUX_ADC_MAM")
	)
	(segment
		(start 331.493114 -33.4645)
		(end 329.465178 -33.4645)
		(width 0.10668)
		(layer "F.Cu")
		(net "P3V3_PDB_AUX_ADC_MAM")
	)
	(segment
		(start 326.137778 -33.668462)
		(end 325.308214 -33.668462)
		(width 0.10668)
		(layer "F.Cu")
		(net "P3V3_PDB_AUX_ADC_MAM")
	)
	(segment
		(start 329.465178 -33.4645)
		(end 328.959972 -33.969706)
		(width 0.10668)
		(layer "F.Cu")
		(net "P3V3_PDB_AUX_ADC_MAM")
	)
	(segment
		(start 326.37984 -33.4264)
		(end 326.137778 -33.668462)
		(width 0.10668)
		(layer "F.Cu")
		(net "P3V3_PDB_AUX_ADC_MAM")
	)
	(via
		(at 331.493114 -33.4645)
		(size 0.508)
		(drill 0.254)
		(layers "F.Cu" "B.Cu")
		(net "P3V3_PDB_AUX_ADC_MAM")
	)
	(via
		(at 324.665594 -39.63162)
		(size 0.508)
		(drill 0.254)
		(layers "F.Cu" "B.Cu")
		(net "P3V3_PDB_AUX_ADC_MAM")
	)
	(via
		(at 327.709022 -33.715706)
		(size 0.762)
		(drill 0.381)
		(layers "F.Cu" "B.Cu")
		(net "P3V3_PDB_AUX_ADC_MAM")
	)
	(segment
		(start 327.95972 -36.337494)
		(end 327.95972 -32.516318)
		(width 0.11684)
		(layer "In4.Cu")
		(net "P3V3_PDB_AUX_ADC_MAM")
	)
	(segment
		(start 324.665594 -39.63162)
		(end 327.95972 -36.337494)
		(width 0.11684)
		(layer "In4.Cu")
		(net "P3V3_PDB_AUX_ADC_MAM")
	)
	(segment
		(start 331.818488 -30.62986)
		(end 332.277974 -31.089346)
		(width 0.11684)
		(layer "In4.Cu")
		(net "P3V3_PDB_AUX_ADC_MAM")
	)
	(segment
		(start 332.277974 -31.089346)
		(end 332.277974 -32.67964)
		(width 0.11684)
		(layer "In4.Cu")
		(net "P3V3_PDB_AUX_ADC_MAM")
	)
	(segment
		(start 327.95972 -32.516318)
		(end 329.846178 -30.62986)
		(width 0.11684)
		(layer "In4.Cu")
		(net "P3V3_PDB_AUX_ADC_MAM")
	)
	(segment
		(start 332.277974 -32.67964)
		(end 331.493114 -33.4645)
		(width 0.11684)
		(layer "In4.Cu")
		(net "P3V3_PDB_AUX_ADC_MAM")
	)
	(segment
		(start 329.846178 -30.62986)
		(end 331.818488 -30.62986)
		(width 0.11684)
		(layer "In4.Cu")
		(net "P3V3_PDB_AUX_ADC_MAM")
	)
	(segment
		(start 59.33313 -38.606984)
		(end 59.970416 -38.606984)
		(width 0.10668)
		(layer "F.Cu")
		(net "P3V3_OCP_V3_2_EN_R")
	)
	(segment
		(start 98.467418 -72.99198)
		(end 99.283774 -72.175624)
		(width 0.10668)
		(layer "F.Cu")
		(net "P3V3_OCP_V3_2_EN_R")
	)
	(segment
		(start 153.249376 -35.97656)
		(end 153.249376 -35.339274)
		(width 0.10668)
		(layer "F.Cu")
		(net "P3V3_OCP_V3_2_EN_R")
	)
	(segment
		(start 97.577402 -72.99198)
		(end 98.467418 -72.99198)
		(width 0.10668)
		(layer "F.Cu")
		(net "P3V3_OCP_V3_2_EN_R")
	)
	(segment
		(start 190.721996 -119.452898)
		(end 191.111886 -119.842788)
		(width 0.10668)
		(layer "F.Cu")
		(net "P3V3_OCP_V3_2_EN_R")
	)
	(via
		(at 194.945 -98.262948)
		(size 0.508)
		(drill 0.254)
		(layers "F.Cu" "B.Cu")
		(net "P3V3_OCP_V3_2_EN_R")
	)
	(via
		(at 153.249376 -35.339274)
		(size 0.508)
		(drill 0.254)
		(layers "F.Cu" "B.Cu")
		(net "P3V3_OCP_V3_2_EN_R")
	)
	(via
		(at 59.970416 -38.606984)
		(size 0.508)
		(drill 0.254)
		(layers "F.Cu" "B.Cu")
		(net "P3V3_OCP_V3_2_EN_R")
	)
	(via
		(at 194.31 -47.371)
		(size 0.508)
		(drill 0.254)
		(layers "F.Cu" "B.Cu")
		(net "P3V3_OCP_V3_2_EN_R")
	)
	(via
		(at 99.283774 -72.175624)
		(size 0.508)
		(drill 0.254)
		(layers "F.Cu" "B.Cu")
		(net "P3V3_OCP_V3_2_EN_R")
	)
	(via
		(at 191.111886 -119.842788)
		(size 0.4572)
		(drill 0.254)
		(layers "F.Cu" "B.Cu")
		(net "P3V3_OCP_V3_2_EN_R")
	)
	(segment
		(start 194.945 -97.519998)
		(end 194.945 -98.262948)
		(width 0.10668)
		(layer "B.Cu")
		(net "P3V3_OCP_V3_2_EN_R")
	)
	(segment
		(start 125.857 -53.8226)
		(end 125.5268 -53.4924)
		(width 0.11684)
		(layer "In2.Cu")
		(net "P3V3_OCP_V3_2_EN_R")
	)
	(segment
		(start 130.033014 -54.3052)
		(end 127.7366 -54.3052)
		(width 0.11684)
		(layer "In2.Cu")
		(net "P3V3_OCP_V3_2_EN_R")
	)
	(segment
		(start 150.830788 -35.339274)
		(end 131.418076 -54.751986)
		(width 0.11684)
		(layer "In2.Cu")
		(net "P3V3_OCP_V3_2_EN_R")
	)
	(segment
		(start 122.997214 -54.751986)
		(end 115.493292 -54.751986)
		(width 0.11684)
		(layer "In2.Cu")
		(net "P3V3_OCP_V3_2_EN_R")
	)
	(segment
		(start 127.7366 -54.3052)
		(end 127.289814 -54.751986)
		(width 0.11684)
		(layer "In2.Cu")
		(net "P3V3_OCP_V3_2_EN_R")
	)
	(segment
		(start 105.16362 -62.56782)
		(end 104.279192 -63.452248)
		(width 0.11684)
		(layer "In2.Cu")
		(net "P3V3_OCP_V3_2_EN_R")
	)
	(segment
		(start 127.289814 -54.751986)
		(end 126.4158 -54.751986)
		(width 0.11684)
		(layer "In2.Cu")
		(net "P3V3_OCP_V3_2_EN_R")
	)
	(segment
		(start 104.279192 -67.180206)
		(end 99.283774 -72.175624)
		(width 0.11684)
		(layer "In2.Cu")
		(net "P3V3_OCP_V3_2_EN_R")
	)
	(segment
		(start 114.51336 -54.75224)
		(end 114.230912 -55.034688)
		(width 0.11684)
		(layer "In2.Cu")
		(net "P3V3_OCP_V3_2_EN_R")
	)
	(segment
		(start 124.2568 -53.4924)
		(end 122.997214 -54.751986)
		(width 0.11684)
		(layer "In2.Cu")
		(net "P3V3_OCP_V3_2_EN_R")
	)
	(segment
		(start 125.857 -54.193186)
		(end 125.857 -53.8226)
		(width 0.11684)
		(layer "In2.Cu")
		(net "P3V3_OCP_V3_2_EN_R")
	)
	(segment
		(start 115.493292 -54.751986)
		(end 115.493038 -54.75224)
		(width 0.11684)
		(layer "In2.Cu")
		(net "P3V3_OCP_V3_2_EN_R")
	)
	(segment
		(start 107.677458 -62.56782)
		(end 105.16362 -62.56782)
		(width 0.11684)
		(layer "In2.Cu")
		(net "P3V3_OCP_V3_2_EN_R")
	)
	(segment
		(start 104.279192 -63.452248)
		(end 104.279192 -67.180206)
		(width 0.11684)
		(layer "In2.Cu")
		(net "P3V3_OCP_V3_2_EN_R")
	)
	(segment
		(start 125.5268 -53.4924)
		(end 124.2568 -53.4924)
		(width 0.11684)
		(layer "In2.Cu")
		(net "P3V3_OCP_V3_2_EN_R")
	)
	(segment
		(start 130.4798 -54.751986)
		(end 130.033014 -54.3052)
		(width 0.11684)
		(layer "In2.Cu")
		(net "P3V3_OCP_V3_2_EN_R")
	)
	(segment
		(start 126.4158 -54.751986)
		(end 125.857 -54.193186)
		(width 0.11684)
		(layer "In2.Cu")
		(net "P3V3_OCP_V3_2_EN_R")
	)
	(segment
		(start 114.230912 -56.014366)
		(end 107.677458 -62.56782)
		(width 0.11684)
		(layer "In2.Cu")
		(net "P3V3_OCP_V3_2_EN_R")
	)
	(segment
		(start 115.493038 -54.75224)
		(end 114.51336 -54.75224)
		(width 0.11684)
		(layer "In2.Cu")
		(net "P3V3_OCP_V3_2_EN_R")
	)
	(segment
		(start 114.230912 -55.034688)
		(end 114.230912 -56.014366)
		(width 0.11684)
		(layer "In2.Cu")
		(net "P3V3_OCP_V3_2_EN_R")
	)
	(segment
		(start 153.249376 -35.339274)
		(end 150.830788 -35.339274)
		(width 0.11684)
		(layer "In2.Cu")
		(net "P3V3_OCP_V3_2_EN_R")
	)
	(segment
		(start 131.418076 -54.751986)
		(end 130.4798 -54.751986)
		(width 0.11684)
		(layer "In2.Cu")
		(net "P3V3_OCP_V3_2_EN_R")
	)
	(segment
		(start 196.59473 -82.696558)
		(end 196.59473 -85.001354)
		(width 0.11684)
		(layer "In4.Cu")
		(net "P3V3_OCP_V3_2_EN_R")
	)
	(segment
		(start 196.59473 -85.001354)
		(end 195.614036 -85.982048)
		(width 0.11684)
		(layer "In4.Cu")
		(net "P3V3_OCP_V3_2_EN_R")
	)
	(segment
		(start 195.614036 -85.982048)
		(end 195.614036 -91.586558)
		(width 0.11684)
		(layer "In4.Cu")
		(net "P3V3_OCP_V3_2_EN_R")
	)
	(segment
		(start 195.875402 -95.419926)
		(end 194.945 -96.350328)
		(width 0.11684)
		(layer "In4.Cu")
		(net "P3V3_OCP_V3_2_EN_R")
	)
	(segment
		(start 195.269104 -60.014104)
		(end 195.269104 -65.955672)
		(width 0.11684)
		(layer "In4.Cu")
		(net "P3V3_OCP_V3_2_EN_R")
	)
	(segment
		(start 194.31 -47.371)
		(end 194.31 -47.479966)
		(width 0.11684)
		(layer "In4.Cu")
		(net "P3V3_OCP_V3_2_EN_R")
	)
	(segment
		(start 194.437 -59.182)
		(end 195.269104 -60.014104)
		(width 0.11684)
		(layer "In4.Cu")
		(net "P3V3_OCP_V3_2_EN_R")
	)
	(segment
		(start 195.269104 -48.43907)
		(end 195.269104 -55.118)
		(width 0.11684)
		(layer "In4.Cu")
		(net "P3V3_OCP_V3_2_EN_R")
	)
	(segment
		(start 200.11644 -74.503788)
		(end 200.11644 -79.174848)
		(width 0.11684)
		(layer "In4.Cu")
		(net "P3V3_OCP_V3_2_EN_R")
	)
	(segment
		(start 200.11644 -79.174848)
		(end 196.59473 -82.696558)
		(width 0.11684)
		(layer "In4.Cu")
		(net "P3V3_OCP_V3_2_EN_R")
	)
	(segment
		(start 195.269104 -65.955672)
		(end 196.81952 -67.506088)
		(width 0.11684)
		(layer "In4.Cu")
		(net "P3V3_OCP_V3_2_EN_R")
	)
	(segment
		(start 195.269104 -55.118)
		(end 194.437 -55.950104)
		(width 0.11684)
		(layer "In4.Cu")
		(net "P3V3_OCP_V3_2_EN_R")
	)
	(segment
		(start 196.81952 -71.206868)
		(end 200.11644 -74.503788)
		(width 0.11684)
		(layer "In4.Cu")
		(net "P3V3_OCP_V3_2_EN_R")
	)
	(segment
		(start 195.614036 -91.586558)
		(end 195.875402 -91.847924)
		(width 0.11684)
		(layer "In4.Cu")
		(net "P3V3_OCP_V3_2_EN_R")
	)
	(segment
		(start 195.875402 -91.847924)
		(end 195.875402 -95.419926)
		(width 0.11684)
		(layer "In4.Cu")
		(net "P3V3_OCP_V3_2_EN_R")
	)
	(segment
		(start 194.31 -47.479966)
		(end 195.269104 -48.43907)
		(width 0.11684)
		(layer "In4.Cu")
		(net "P3V3_OCP_V3_2_EN_R")
	)
	(segment
		(start 194.945 -96.350328)
		(end 194.945 -98.262948)
		(width 0.11684)
		(layer "In4.Cu")
		(net "P3V3_OCP_V3_2_EN_R")
	)
	(segment
		(start 196.81952 -67.506088)
		(end 196.81952 -71.206868)
		(width 0.11684)
		(layer "In4.Cu")
		(net "P3V3_OCP_V3_2_EN_R")
	)
	(segment
		(start 194.437 -55.950104)
		(end 194.437 -59.182)
		(width 0.11684)
		(layer "In4.Cu")
		(net "P3V3_OCP_V3_2_EN_R")
	)
	(segment
		(start 88.025732 -53.17236)
		(end 98.210624 -53.17236)
		(width 0.11684)
		(layer "In6.Cu")
		(net "P3V3_OCP_V3_2_EN_R")
	)
	(segment
		(start 100.603812 -70.855586)
		(end 99.283774 -72.175624)
		(width 0.11684)
		(layer "In6.Cu")
		(net "P3V3_OCP_V3_2_EN_R")
	)
	(segment
		(start 77.36332 -42.509948)
		(end 88.025732 -53.17236)
		(width 0.11684)
		(layer "In6.Cu")
		(net "P3V3_OCP_V3_2_EN_R")
	)
	(segment
		(start 100.603812 -55.565548)
		(end 100.603812 -70.855586)
		(width 0.11684)
		(layer "In6.Cu")
		(net "P3V3_OCP_V3_2_EN_R")
	)
	(segment
		(start 62.870588 -39.799768)
		(end 64.65062 -41.5798)
		(width 0.11684)
		(layer "In6.Cu")
		(net "P3V3_OCP_V3_2_EN_R")
	)
	(segment
		(start 59.970416 -38.606984)
		(end 61.1632 -39.799768)
		(width 0.11684)
		(layer "In6.Cu")
		(net "P3V3_OCP_V3_2_EN_R")
	)
	(segment
		(start 73.37806 -42.509948)
		(end 77.36332 -42.509948)
		(width 0.11684)
		(layer "In6.Cu")
		(net "P3V3_OCP_V3_2_EN_R")
	)
	(segment
		(start 72.447912 -41.5798)
		(end 73.37806 -42.509948)
		(width 0.11684)
		(layer "In6.Cu")
		(net "P3V3_OCP_V3_2_EN_R")
	)
	(segment
		(start 61.1632 -39.799768)
		(end 62.870588 -39.799768)
		(width 0.11684)
		(layer "In6.Cu")
		(net "P3V3_OCP_V3_2_EN_R")
	)
	(segment
		(start 98.210624 -53.17236)
		(end 100.603812 -55.565548)
		(width 0.11684)
		(layer "In6.Cu")
		(net "P3V3_OCP_V3_2_EN_R")
	)
	(segment
		(start 64.65062 -41.5798)
		(end 72.447912 -41.5798)
		(width 0.11684)
		(layer "In6.Cu")
		(net "P3V3_OCP_V3_2_EN_R")
	)
	(segment
		(start 192.9511 -113.07064)
		(end 193.900552 -112.121188)
		(width 0.11684)
		(layer "In11.Cu")
		(net "P3V3_OCP_V3_2_EN_R")
	)
	(segment
		(start 191.50711 -115.44935)
		(end 192.31102 -114.64544)
		(width 0.11684)
		(layer "In11.Cu")
		(net "P3V3_OCP_V3_2_EN_R")
	)
	(segment
		(start 193.900552 -112.121188)
		(end 193.900552 -106.072432)
		(width 0.11684)
		(layer "In11.Cu")
		(net "P3V3_OCP_V3_2_EN_R")
	)
	(segment
		(start 193.9163 -100.174298)
		(end 194.447414 -99.643184)
		(width 0.11684)
		(layer "In11.Cu")
		(net "P3V3_OCP_V3_2_EN_R")
	)
	(segment
		(start 191.111886 -119.842788)
		(end 191.280542 -119.842788)
		(width 0.11684)
		(layer "In11.Cu")
		(net "P3V3_OCP_V3_2_EN_R")
	)
	(segment
		(start 192.31102 -114.64544)
		(end 192.31102 -113.25352)
		(width 0.11684)
		(layer "In11.Cu")
		(net "P3V3_OCP_V3_2_EN_R")
	)
	(segment
		(start 193.900552 -106.072432)
		(end 193.39306 -105.56494)
		(width 0.11684)
		(layer "In11.Cu")
		(net "P3V3_OCP_V3_2_EN_R")
	)
	(segment
		(start 193.9163 -103.7971)
		(end 193.9163 -100.174298)
		(width 0.11684)
		(layer "In11.Cu")
		(net "P3V3_OCP_V3_2_EN_R")
	)
	(segment
		(start 192.31102 -113.25352)
		(end 192.4939 -113.07064)
		(width 0.11684)
		(layer "In11.Cu")
		(net "P3V3_OCP_V3_2_EN_R")
	)
	(segment
		(start 194.704208 -98.262948)
		(end 194.945 -98.262948)
		(width 0.11684)
		(layer "In11.Cu")
		(net "P3V3_OCP_V3_2_EN_R")
	)
	(segment
		(start 192.4939 -113.07064)
		(end 192.9511 -113.07064)
		(width 0.11684)
		(layer "In11.Cu")
		(net "P3V3_OCP_V3_2_EN_R")
	)
	(segment
		(start 194.447414 -99.643184)
		(end 194.447414 -98.519742)
		(width 0.11684)
		(layer "In11.Cu")
		(net "P3V3_OCP_V3_2_EN_R")
	)
	(segment
		(start 191.280542 -119.842788)
		(end 191.50711 -119.61622)
		(width 0.11684)
		(layer "In11.Cu")
		(net "P3V3_OCP_V3_2_EN_R")
	)
	(segment
		(start 191.50711 -119.61622)
		(end 191.50711 -115.44935)
		(width 0.11684)
		(layer "In11.Cu")
		(net "P3V3_OCP_V3_2_EN_R")
	)
	(segment
		(start 193.39306 -105.56494)
		(end 193.39306 -104.32034)
		(width 0.11684)
		(layer "In11.Cu")
		(net "P3V3_OCP_V3_2_EN_R")
	)
	(segment
		(start 193.39306 -104.32034)
		(end 193.9163 -103.7971)
		(width 0.11684)
		(layer "In11.Cu")
		(net "P3V3_OCP_V3_2_EN_R")
	)
	(segment
		(start 194.447414 -98.519742)
		(end 194.704208 -98.262948)
		(width 0.11684)
		(layer "In11.Cu")
		(net "P3V3_OCP_V3_2_EN_R")
	)
	(segment
		(start 191.897 -44.958)
		(end 194.31 -47.371)
		(width 0.11684)
		(layer "In15.Cu")
		(net "P3V3_OCP_V3_2_EN_R")
	)
	(segment
		(start 163.939728 -40.491156)
		(end 185.085228 -40.491156)
		(width 0.11684)
		(layer "In15.Cu")
		(net "P3V3_OCP_V3_2_EN_R")
	)
	(segment
		(start 185.085228 -40.491156)
		(end 189.552072 -44.958)
		(width 0.11684)
		(layer "In15.Cu")
		(net "P3V3_OCP_V3_2_EN_R")
	)
	(segment
		(start 162.833558 -39.384986)
		(end 163.939728 -40.491156)
		(width 0.11684)
		(layer "In15.Cu")
		(net "P3V3_OCP_V3_2_EN_R")
	)
	(segment
		(start 157.295088 -39.384986)
		(end 162.833558 -39.384986)
		(width 0.11684)
		(layer "In15.Cu")
		(net "P3V3_OCP_V3_2_EN_R")
	)
	(segment
		(start 153.249376 -35.339274)
		(end 157.295088 -39.384986)
		(width 0.11684)
		(layer "In15.Cu")
		(net "P3V3_OCP_V3_2_EN_R")
	)
	(segment
		(start 189.552072 -44.958)
		(end 191.897 -44.958)
		(width 0.11684)
		(layer "In15.Cu")
		(net "P3V3_OCP_V3_2_EN_R")
	)
	(via
		(at 327.074022 -37.144706)
		(size 0.762)
		(drill 0.381)
		(layers "F.Cu" "B.Cu")
		(net "P3V3_MAX11617_VDD")
	)
	(segment
		(start 320.048128 -42.176954)
		(end 319.540128 -41.668954)
		(width 0.10668)
		(layer "F.Cu")
		(net "P3V3_AUX_ADC_TIC")
	)
	(segment
		(start 321.420998 -42.176954)
		(end 320.048128 -42.176954)
		(width 0.10668)
		(layer "F.Cu")
		(net "P3V3_AUX_ADC_TIC")
	)
	(segment
		(start 318.720978 -42.488104)
		(end 319.540128 -41.668954)
		(width 0.10668)
		(layer "F.Cu")
		(net "P3V3_AUX_ADC_TIC")
	)
	(segment
		(start 315.525404 -42.488104)
		(end 318.289178 -42.488104)
		(width 0.10668)
		(layer "F.Cu")
		(net "P3V3_AUX_ADC_TIC")
	)
	(segment
		(start 322.436998 -41.160954)
		(end 321.420998 -42.176954)
		(width 0.10668)
		(layer "F.Cu")
		(net "P3V3_AUX_ADC_TIC")
	)
	(segment
		(start 318.289178 -42.488104)
		(end 318.720978 -42.488104)
		(width 0.10668)
		(layer "F.Cu")
		(net "P3V3_AUX_ADC_TIC")
	)
	(via
		(at 318.289178 -42.488104)
		(size 0.762)
		(drill 0.381)
		(layers "F.Cu" "B.Cu")
		(net "P3V3_AUX_ADC_TIC")
	)
	(segment
		(start 326.105266 -33.033462)
		(end 325.308214 -33.033462)
		(width 0.10668)
		(layer "F.Cu")
		(net "P3V3_AUX_ADC_MAM")
	)
	(segment
		(start 324.40626 -41.160954)
		(end 324.665594 -40.90162)
		(width 0.10668)
		(layer "F.Cu")
		(net "P3V3_AUX_ADC_MAM")
	)
	(segment
		(start 324.037198 -41.160954)
		(end 324.40626 -41.160954)
		(width 0.10668)
		(layer "F.Cu")
		(net "P3V3_AUX_ADC_MAM")
	)
	(segment
		(start 329.444858 -32.46882)
		(end 328.959972 -32.953706)
		(width 0.10668)
		(layer "F.Cu")
		(net "P3V3_AUX_ADC_MAM")
	)
	(segment
		(start 327.074022 -32.572706)
		(end 326.566022 -32.572706)
		(width 0.10668)
		(layer "F.Cu")
		(net "P3V3_AUX_ADC_MAM")
	)
	(segment
		(start 326.566022 -32.572706)
		(end 326.105266 -33.033462)
		(width 0.10668)
		(layer "F.Cu")
		(net "P3V3_AUX_ADC_MAM")
	)
	(segment
		(start 328.959972 -32.953706)
		(end 328.578972 -32.572706)
		(width 0.10668)
		(layer "F.Cu")
		(net "P3V3_AUX_ADC_MAM")
	)
	(segment
		(start 331.493114 -32.46882)
		(end 329.444858 -32.46882)
		(width 0.10668)
		(layer "F.Cu")
		(net "P3V3_AUX_ADC_MAM")
	)
	(segment
		(start 328.578972 -32.572706)
		(end 327.074022 -32.572706)
		(width 0.10668)
		(layer "F.Cu")
		(net "P3V3_AUX_ADC_MAM")
	)
	(via
		(at 327.074022 -32.572706)
		(size 0.762)
		(drill 0.381)
		(layers "F.Cu" "B.Cu")
		(net "P3V3_AUX_ADC_MAM")
	)
	(via
		(at 331.493114 -32.46882)
		(size 0.508)
		(drill 0.254)
		(layers "F.Cu" "B.Cu")
		(net "P3V3_AUX_ADC_MAM")
	)
	(via
		(at 324.665594 -40.90162)
		(size 0.508)
		(drill 0.254)
		(layers "F.Cu" "B.Cu")
		(net "P3V3_AUX_ADC_MAM")
	)
	(segment
		(start 328.361548 -32.658812)
		(end 330.07046 -30.9499)
		(width 0.11684)
		(layer "In4.Cu")
		(net "P3V3_AUX_ADC_MAM")
	)
	(segment
		(start 324.665594 -40.90162)
		(end 324.665594 -40.28948)
		(width 0.11684)
		(layer "In4.Cu")
		(net "P3V3_AUX_ADC_MAM")
	)
	(segment
		(start 324.665594 -40.28948)
		(end 328.361548 -36.593526)
		(width 0.11684)
		(layer "In4.Cu")
		(net "P3V3_AUX_ADC_MAM")
	)
	(segment
		(start 330.07046 -30.9499)
		(end 331.6859 -30.9499)
		(width 0.11684)
		(layer "In4.Cu")
		(net "P3V3_AUX_ADC_MAM")
	)
	(segment
		(start 331.6859 -30.9499)
		(end 331.957934 -31.221934)
		(width 0.11684)
		(layer "In4.Cu")
		(net "P3V3_AUX_ADC_MAM")
	)
	(segment
		(start 328.361548 -36.593526)
		(end 328.361548 -32.658812)
		(width 0.11684)
		(layer "In4.Cu")
		(net "P3V3_AUX_ADC_MAM")
	)
	(segment
		(start 331.957934 -31.221934)
		(end 331.957934 -32.004)
		(width 0.11684)
		(layer "In4.Cu")
		(net "P3V3_AUX_ADC_MAM")
	)
	(segment
		(start 331.957934 -32.004)
		(end 331.493114 -32.46882)
		(width 0.11684)
		(layer "In4.Cu")
		(net "P3V3_AUX_ADC_MAM")
	)
	(segment
		(start 328.720958 -41.632124)
		(end 327.250298 -41.632124)
		(width 0.10668)
		(layer "F.Cu")
		(net "P3V3_AUX_ADC")
	)
	(segment
		(start 329.192128 -41.160954)
		(end 328.720958 -41.632124)
		(width 0.10668)
		(layer "F.Cu")
		(net "P3V3_AUX_ADC")
	)
	(segment
		(start 323.237098 -41.160954)
		(end 323.708268 -41.632124)
		(width 0.10668)
		(layer "F.Cu")
		(net "P3V3_AUX_ADC")
	)
	(segment
		(start 327.250298 -41.632124)
		(end 326.779128 -41.160954)
		(width 0.10668)
		(layer "F.Cu")
		(net "P3V3_AUX_ADC")
	)
	(segment
		(start 323.708268 -41.632124)
		(end 324.875652 -41.632124)
		(width 0.10668)
		(layer "F.Cu")
		(net "P3V3_AUX_ADC")
	)
	(segment
		(start 326.779128 -41.160954)
		(end 326.719438 -41.101264)
		(width 0.10668)
		(layer "F.Cu")
		(net "P3V3_AUX_ADC")
	)
	(segment
		(start 324.875652 -41.632124)
		(end 325.406512 -41.101264)
		(width 0.10668)
		(layer "F.Cu")
		(net "P3V3_AUX_ADC")
	)
	(segment
		(start 326.719438 -41.101264)
		(end 325.406512 -41.101264)
		(width 0.10668)
		(layer "F.Cu")
		(net "P3V3_AUX_ADC")
	)
	(via
		(at 325.406512 -41.101264)
		(size 0.762)
		(drill 0.381)
		(layers "F.Cu" "B.Cu")
		(net "P3V3_AUX_ADC")
	)
	(segment
		(start 322.436998 -42.176954)
		(end 322.436998 -42.684954)
		(width 0.10668)
		(layer "F.Cu")
		(net "P3V3_ADC_TIC")
	)
	(segment
		(start 316.638178 -43.319954)
		(end 316.456314 -43.13809)
		(width 0.10668)
		(layer "F.Cu")
		(net "P3V3_ADC_TIC")
	)
	(segment
		(start 320.067178 -43.192954)
		(end 319.559178 -42.684954)
		(width 0.10668)
		(layer "F.Cu")
		(net "P3V3_ADC_TIC")
	)
	(segment
		(start 319.540128 -42.684954)
		(end 318.905128 -43.319954)
		(width 0.10668)
		(layer "F.Cu")
		(net "P3V3_ADC_TIC")
	)
	(segment
		(start 322.436998 -42.684954)
		(end 321.928998 -43.192954)
		(width 0.10668)
		(layer "F.Cu")
		(net "P3V3_ADC_TIC")
	)
	(segment
		(start 316.456314 -43.13809)
		(end 315.525404 -43.13809)
		(width 0.10668)
		(layer "F.Cu")
		(net "P3V3_ADC_TIC")
	)
	(segment
		(start 321.928998 -43.192954)
		(end 320.067178 -43.192954)
		(width 0.10668)
		(layer "F.Cu")
		(net "P3V3_ADC_TIC")
	)
	(segment
		(start 318.905128 -43.319954)
		(end 317.273178 -43.319954)
		(width 0.10668)
		(layer "F.Cu")
		(net "P3V3_ADC_TIC")
	)
	(segment
		(start 317.273178 -43.319954)
		(end 316.638178 -43.319954)
		(width 0.10668)
		(layer "F.Cu")
		(net "P3V3_ADC_TIC")
	)
	(segment
		(start 319.559178 -42.684954)
		(end 319.540128 -42.684954)
		(width 0.10668)
		(layer "F.Cu")
		(net "P3V3_ADC_TIC")
	)
	(via
		(at 317.273178 -43.319954)
		(size 0.762)
		(drill 0.381)
		(layers "F.Cu" "B.Cu")
		(net "P3V3_ADC_TIC")
	)
	(segment
		(start 329.482958 -31.41472)
		(end 328.959972 -31.937706)
		(width 0.10668)
		(layer "F.Cu")
		(net "P3V3_ADC_MAM")
	)
	(segment
		(start 328.451972 -31.429706)
		(end 326.662542 -31.429706)
		(width 0.10668)
		(layer "F.Cu")
		(net "P3V3_ADC_MAM")
	)
	(segment
		(start 326.286622 -31.923482)
		(end 325.811642 -32.398462)
		(width 0.10668)
		(layer "F.Cu")
		(net "P3V3_ADC_MAM")
	)
	(segment
		(start 325.811642 -32.398462)
		(end 325.308214 -32.398462)
		(width 0.10668)
		(layer "F.Cu")
		(net "P3V3_ADC_MAM")
	)
	(segment
		(start 328.959972 -31.937706)
		(end 328.451972 -31.429706)
		(width 0.10668)
		(layer "F.Cu")
		(net "P3V3_ADC_MAM")
	)
	(segment
		(start 324.037198 -42.176954)
		(end 324.646798 -42.176954)
		(width 0.10668)
		(layer "F.Cu")
		(net "P3V3_ADC_MAM")
	)
	(segment
		(start 331.493114 -31.41472)
		(end 329.482958 -31.41472)
		(width 0.10668)
		(layer "F.Cu")
		(net "P3V3_ADC_MAM")
	)
	(segment
		(start 326.286622 -31.053786)
		(end 326.286622 -31.923482)
		(width 0.10668)
		(layer "F.Cu")
		(net "P3V3_ADC_MAM")
	)
	(segment
		(start 326.662542 -31.429706)
		(end 326.286622 -31.053786)
		(width 0.10668)
		(layer "F.Cu")
		(net "P3V3_ADC_MAM")
	)
	(via
		(at 326.286622 -31.053786)
		(size 0.762)
		(drill 0.381)
		(layers "F.Cu" "B.Cu")
		(net "P3V3_ADC_MAM")
	)
	(via
		(at 331.493114 -31.41472)
		(size 0.508)
		(drill 0.254)
		(layers "F.Cu" "B.Cu")
		(net "P3V3_ADC_MAM")
	)
	(via
		(at 324.646798 -42.176954)
		(size 0.508)
		(drill 0.254)
		(layers "F.Cu" "B.Cu")
		(net "P3V3_ADC_MAM")
	)
	(segment
		(start 330.235052 -31.41472)
		(end 331.493114 -31.41472)
		(width 0.11684)
		(layer "In4.Cu")
		(net "P3V3_ADC_MAM")
	)
	(segment
		(start 328.87412 -36.721288)
		(end 328.87412 -32.775652)
		(width 0.11684)
		(layer "In4.Cu")
		(net "P3V3_ADC_MAM")
	)
	(segment
		(start 325.19874 -41.625012)
		(end 325.19874 -40.396668)
		(width 0.11684)
		(layer "In4.Cu")
		(net "P3V3_ADC_MAM")
	)
	(segment
		(start 324.646798 -42.176954)
		(end 325.19874 -41.625012)
		(width 0.11684)
		(layer "In4.Cu")
		(net "P3V3_ADC_MAM")
	)
	(segment
		(start 328.87412 -32.775652)
		(end 330.235052 -31.41472)
		(width 0.11684)
		(layer "In4.Cu")
		(net "P3V3_ADC_MAM")
	)
	(segment
		(start 325.19874 -40.396668)
		(end 328.87412 -36.721288)
		(width 0.11684)
		(layer "In4.Cu")
		(net "P3V3_ADC_MAM")
	)
	(via
		(at 307.519578 -43.446954)
		(size 0.762)
		(drill 0.381)
		(layers "F.Cu" "B.Cu")
		(net "P3V3_ADC128_VCC")
	)
	(segment
		(start 325.70166 -42.773854)
		(end 326.261984 -42.21353)
		(width 0.10668)
		(layer "F.Cu")
		(net "P3V3_ADC")
	)
	(segment
		(start 325.348854 -42.773854)
		(end 325.70166 -42.773854)
		(width 0.10668)
		(layer "F.Cu")
		(net "P3V3_ADC")
	)
	(segment
		(start 323.237098 -42.176954)
		(end 323.237098 -42.492422)
		(width 0.10668)
		(layer "F.Cu")
		(net "P3V3_ADC")
	)
	(segment
		(start 329.192128 -42.407332)
		(end 328.849228 -42.750232)
		(width 0.10668)
		(layer "F.Cu")
		(net "P3V3_ADC")
	)
	(segment
		(start 323.237098 -42.492422)
		(end 323.596762 -42.852086)
		(width 0.10668)
		(layer "F.Cu")
		(net "P3V3_ADC")
	)
	(segment
		(start 326.742552 -42.21353)
		(end 326.779128 -42.176954)
		(width 0.10668)
		(layer "F.Cu")
		(net "P3V3_ADC")
	)
	(segment
		(start 323.596762 -42.852086)
		(end 325.270622 -42.852086)
		(width 0.10668)
		(layer "F.Cu")
		(net "P3V3_ADC")
	)
	(segment
		(start 326.261984 -42.21353)
		(end 326.742552 -42.21353)
		(width 0.10668)
		(layer "F.Cu")
		(net "P3V3_ADC")
	)
	(segment
		(start 325.270622 -42.852086)
		(end 325.348854 -42.773854)
		(width 0.10668)
		(layer "F.Cu")
		(net "P3V3_ADC")
	)
	(segment
		(start 327.072244 -42.750232)
		(end 326.779128 -42.457116)
		(width 0.10668)
		(layer "F.Cu")
		(net "P3V3_ADC")
	)
	(segment
		(start 328.849228 -42.750232)
		(end 327.072244 -42.750232)
		(width 0.10668)
		(layer "F.Cu")
		(net "P3V3_ADC")
	)
	(segment
		(start 326.779128 -42.457116)
		(end 326.779128 -42.176954)
		(width 0.10668)
		(layer "F.Cu")
		(net "P3V3_ADC")
	)
	(segment
		(start 329.192128 -42.176954)
		(end 329.192128 -42.407332)
		(width 0.10668)
		(layer "F.Cu")
		(net "P3V3_ADC")
	)
	(via
		(at 325.348854 -42.773854)
		(size 0.762)
		(drill 0.381)
		(layers "F.Cu" "B.Cu")
		(net "P3V3_ADC")
	)
	(segment
		(start 323.224144 -38.10762)
		(end 321.973194 -38.10762)
		(width 0.10668)
		(layer "F.Cu")
		(net "P1V581_PDB_ADC")
	)
	(segment
		(start 323.237098 -40.144954)
		(end 323.237098 -39.136574)
		(width 0.10668)
		(layer "F.Cu")
		(net "P1V581_PDB_ADC")
	)
	(segment
		(start 322.264278 -39.12362)
		(end 323.224144 -39.12362)
		(width 0.10668)
		(layer "F.Cu")
		(net "P1V581_PDB_ADC")
	)
	(segment
		(start 321.973194 -38.832536)
		(end 322.264278 -39.12362)
		(width 0.10668)
		(layer "F.Cu")
		(net "P1V581_PDB_ADC")
	)
	(segment
		(start 321.973194 -38.10762)
		(end 321.973194 -38.832536)
		(width 0.10668)
		(layer "F.Cu")
		(net "P1V581_PDB_ADC")
	)
	(segment
		(start 323.237098 -39.136574)
		(end 323.224144 -39.12362)
		(width 0.10668)
		(layer "F.Cu")
		(net "P1V581_PDB_ADC")
	)
	(via
		(at 321.973194 -38.10762)
		(size 0.762)
		(drill 0.381)
		(layers "F.Cu" "B.Cu")
		(net "P1V581_PDB_ADC")
	)
	(segment
		(start 317.273178 -44.970954)
		(end 316.978538 -44.970954)
		(width 0.254)
		(layer "F.Cu")
		(net "P12V_OCP_V3_2_ISENSE_TIC")
	)
	(segment
		(start 322.983098 -45.267626)
		(end 320.038476 -45.267626)
		(width 0.254)
		(layer "F.Cu")
		(net "P12V_OCP_V3_2_ISENSE_TIC")
	)
	(segment
		(start 316.4459 -44.438316)
		(end 315.525404 -44.438316)
		(width 0.254)
		(layer "F.Cu")
		(net "P12V_OCP_V3_2_ISENSE_TIC")
	)
	(segment
		(start 319.540128 -44.769278)
		(end 319.540128 -44.716954)
		(width 0.254)
		(layer "F.Cu")
		(net "P12V_OCP_V3_2_ISENSE_TIC")
	)
	(segment
		(start 323.237098 -45.013626)
		(end 322.983098 -45.267626)
		(width 0.254)
		(layer "F.Cu")
		(net "P12V_OCP_V3_2_ISENSE_TIC")
	)
	(segment
		(start 320.038476 -45.267626)
		(end 319.540128 -44.769278)
		(width 0.254)
		(layer "F.Cu")
		(net "P12V_OCP_V3_2_ISENSE_TIC")
	)
	(segment
		(start 317.273178 -44.970954)
		(end 319.286128 -44.970954)
		(width 0.254)
		(layer "F.Cu")
		(net "P12V_OCP_V3_2_ISENSE_TIC")
	)
	(segment
		(start 316.978538 -44.970954)
		(end 316.4459 -44.438316)
		(width 0.254)
		(layer "F.Cu")
		(net "P12V_OCP_V3_2_ISENSE_TIC")
	)
	(segment
		(start 323.237098 -44.716954)
		(end 323.237098 -45.013626)
		(width 0.254)
		(layer "F.Cu")
		(net "P12V_OCP_V3_2_ISENSE_TIC")
	)
	(segment
		(start 319.286128 -44.970954)
		(end 319.540128 -44.716954)
		(width 0.254)
		(layer "F.Cu")
		(net "P12V_OCP_V3_2_ISENSE_TIC")
	)
	(via
		(at 317.273178 -44.970954)
		(size 0.762)
		(drill 0.381)
		(layers "F.Cu" "B.Cu")
		(net "P12V_OCP_V3_2_ISENSE_TIC")
	)
	(segment
		(start 317.422022 -32.826706)
		(end 318.692022 -32.826706)
		(width 0.254)
		(layer "F.Cu")
		(net "P12V_OCP_V3_2_ISENSE_MAM")
	)
	(segment
		(start 318.898778 -33.033462)
		(end 319.99809 -33.033462)
		(width 0.254)
		(layer "F.Cu")
		(net "P12V_OCP_V3_2_ISENSE_MAM")
	)
	(segment
		(start 315.849508 -32.001206)
		(end 316.171072 -32.32277)
		(width 0.254)
		(layer "F.Cu")
		(net "P12V_OCP_V3_2_ISENSE_MAM")
	)
	(segment
		(start 311.941972 -32.255206)
		(end 312.195972 -32.001206)
		(width 0.254)
		(layer "F.Cu")
		(net "P12V_OCP_V3_2_ISENSE_MAM")
	)
	(segment
		(start 311.941972 -32.572706)
		(end 311.941972 -32.255206)
		(width 0.254)
		(layer "F.Cu")
		(net "P12V_OCP_V3_2_ISENSE_MAM")
	)
	(segment
		(start 316.425072 -32.826706)
		(end 316.171072 -32.572706)
		(width 0.254)
		(layer "F.Cu")
		(net "P12V_OCP_V3_2_ISENSE_MAM")
	)
	(segment
		(start 318.692022 -32.826706)
		(end 318.898778 -33.033462)
		(width 0.254)
		(layer "F.Cu")
		(net "P12V_OCP_V3_2_ISENSE_MAM")
	)
	(segment
		(start 316.171072 -32.32277)
		(end 316.171072 -32.572706)
		(width 0.254)
		(layer "F.Cu")
		(net "P12V_OCP_V3_2_ISENSE_MAM")
	)
	(segment
		(start 312.195972 -32.001206)
		(end 315.849508 -32.001206)
		(width 0.254)
		(layer "F.Cu")
		(net "P12V_OCP_V3_2_ISENSE_MAM")
	)
	(segment
		(start 317.422022 -32.826706)
		(end 316.425072 -32.826706)
		(width 0.254)
		(layer "F.Cu")
		(net "P12V_OCP_V3_2_ISENSE_MAM")
	)
	(via
		(at 317.422022 -32.826706)
		(size 0.762)
		(drill 0.381)
		(layers "F.Cu" "B.Cu")
		(net "P12V_OCP_V3_2_ISENSE_MAM")
	)
	(segment
		(start 65.172844 -35.784028)
		(end 65.172844 -35.146742)
		(width 0.10668)
		(layer "F.Cu")
		(net "P12V_OCP_V3_2_EN_R")
	)
	(segment
		(start 70.052438 -32.916114)
		(end 70.051422 -32.91713)
		(width 0.10668)
		(layer "F.Cu")
		(net "P12V_OCP_V3_2_EN_R")
	)
	(segment
		(start 52.40274 -42.35069)
		(end 59.595512 -42.35069)
		(width 0.10668)
		(layer "F.Cu")
		(net "P12V_OCP_V3_2_EN_R")
	)
	(segment
		(start 204.862176 -125.817376)
		(end 203.647548 -125.817376)
		(width 0.10668)
		(layer "F.Cu")
		(net "P12V_OCP_V3_2_EN_R")
	)
	(segment
		(start 52.0446 -41.99255)
		(end 52.40274 -42.35069)
		(width 0.10668)
		(layer "F.Cu")
		(net "P12V_OCP_V3_2_EN_R")
	)
	(segment
		(start 50.472594 -41.99255)
		(end 52.0446 -41.99255)
		(width 0.10668)
		(layer "F.Cu")
		(net "P12V_OCP_V3_2_EN_R")
	)
	(segment
		(start 70.052438 -32.287972)
		(end 70.052438 -32.916114)
		(width 0.10668)
		(layer "F.Cu")
		(net "P12V_OCP_V3_2_EN_R")
	)
	(segment
		(start 193.122042 -121.852944)
		(end 193.511932 -122.242834)
		(width 0.10668)
		(layer "F.Cu")
		(net "P12V_OCP_V3_2_EN_R")
	)
	(via
		(at 59.595512 -42.35069)
		(size 0.508)
		(drill 0.254)
		(layers "F.Cu" "B.Cu")
		(net "P12V_OCP_V3_2_EN_R")
	)
	(via
		(at 193.511932 -122.242834)
		(size 0.4572)
		(drill 0.254)
		(layers "F.Cu" "B.Cu")
		(net "P12V_OCP_V3_2_EN_R")
	)
	(via
		(at 70.051422 -32.91713)
		(size 0.508)
		(drill 0.254)
		(layers "F.Cu" "B.Cu")
		(net "P12V_OCP_V3_2_EN_R")
	)
	(via
		(at 158.94177 -42.904918)
		(size 0.508)
		(drill 0.254)
		(layers "F.Cu" "B.Cu")
		(net "P12V_OCP_V3_2_EN_R")
	)
	(via
		(at 203.647548 -125.817376)
		(size 0.508)
		(drill 0.254)
		(layers "F.Cu" "B.Cu")
		(net "P12V_OCP_V3_2_EN_R")
	)
	(via
		(at 65.172844 -35.146742)
		(size 0.508)
		(drill 0.254)
		(layers "F.Cu" "B.Cu")
		(net "P12V_OCP_V3_2_EN_R")
	)
	(via
		(at 172.546264 -53.304694)
		(size 0.508)
		(drill 0.254)
		(layers "F.Cu" "B.Cu")
		(net "P12V_OCP_V3_2_EN_R")
	)
	(segment
		(start 172.546264 -53.304694)
		(end 172.546264 -53.313076)
		(width 0.10668)
		(layer "B.Cu")
		(net "P12V_OCP_V3_2_EN_R")
	)
	(segment
		(start 170.39971 -54.58841)
		(end 163.58362 -54.58841)
		(width 0.10668)
		(layer "B.Cu")
		(net "P12V_OCP_V3_2_EN_R")
	)
	(segment
		(start 172.546264 -53.313076)
		(end 171.590208 -54.269132)
		(width 0.10668)
		(layer "B.Cu")
		(net "P12V_OCP_V3_2_EN_R")
	)
	(segment
		(start 157.99181 -48.9966)
		(end 157.99181 -43.854878)
		(width 0.10668)
		(layer "B.Cu")
		(net "P12V_OCP_V3_2_EN_R")
	)
	(segment
		(start 171.590208 -54.269132)
		(end 170.718988 -54.269132)
		(width 0.10668)
		(layer "B.Cu")
		(net "P12V_OCP_V3_2_EN_R")
	)
	(segment
		(start 170.718988 -54.269132)
		(end 170.39971 -54.58841)
		(width 0.10668)
		(layer "B.Cu")
		(net "P12V_OCP_V3_2_EN_R")
	)
	(segment
		(start 157.99181 -43.854878)
		(end 158.94177 -42.904918)
		(width 0.10668)
		(layer "B.Cu")
		(net "P12V_OCP_V3_2_EN_R")
	)
	(segment
		(start 163.58362 -54.58841)
		(end 157.99181 -48.9966)
		(width 0.10668)
		(layer "B.Cu")
		(net "P12V_OCP_V3_2_EN_R")
	)
	(segment
		(start 194.740784 -123.371356)
		(end 193.612262 -122.242834)
		(width 0.11684)
		(layer "In2.Cu")
		(net "P12V_OCP_V3_2_EN_R")
	)
	(segment
		(start 203.647548 -125.817376)
		(end 202.698604 -126.76632)
		(width 0.11684)
		(layer "In2.Cu")
		(net "P12V_OCP_V3_2_EN_R")
	)
	(segment
		(start 202.698604 -126.76632)
		(end 200.68667 -126.76632)
		(width 0.11684)
		(layer "In2.Cu")
		(net "P12V_OCP_V3_2_EN_R")
	)
	(segment
		(start 193.612262 -122.242834)
		(end 193.511932 -122.242834)
		(width 0.11684)
		(layer "In2.Cu")
		(net "P12V_OCP_V3_2_EN_R")
	)
	(segment
		(start 194.740784 -124.562362)
		(end 194.740784 -123.371356)
		(width 0.11684)
		(layer "In2.Cu")
		(net "P12V_OCP_V3_2_EN_R")
	)
	(segment
		(start 65.172844 -38.510972)
		(end 61.333126 -42.35069)
		(width 0.11684)
		(layer "In2.Cu")
		(net "P12V_OCP_V3_2_EN_R")
	)
	(segment
		(start 200.16216 -127.29083)
		(end 198.15683 -127.29083)
		(width 0.11684)
		(layer "In2.Cu")
		(net "P12V_OCP_V3_2_EN_R")
	)
	(segment
		(start 195.910454 -126.357126)
		(end 195.504562 -125.951234)
		(width 0.11684)
		(layer "In2.Cu")
		(net "P12V_OCP_V3_2_EN_R")
	)
	(segment
		(start 65.172844 -35.146742)
		(end 65.172844 -38.510972)
		(width 0.11684)
		(layer "In2.Cu")
		(net "P12V_OCP_V3_2_EN_R")
	)
	(segment
		(start 198.15683 -127.29083)
		(end 197.223126 -126.357126)
		(width 0.11684)
		(layer "In2.Cu")
		(net "P12V_OCP_V3_2_EN_R")
	)
	(segment
		(start 61.333126 -42.35069)
		(end 59.595512 -42.35069)
		(width 0.11684)
		(layer "In2.Cu")
		(net "P12V_OCP_V3_2_EN_R")
	)
	(segment
		(start 197.223126 -126.357126)
		(end 195.910454 -126.357126)
		(width 0.11684)
		(layer "In2.Cu")
		(net "P12V_OCP_V3_2_EN_R")
	)
	(segment
		(start 200.68667 -126.76632)
		(end 200.16216 -127.29083)
		(width 0.11684)
		(layer "In2.Cu")
		(net "P12V_OCP_V3_2_EN_R")
	)
	(segment
		(start 195.504562 -125.951234)
		(end 195.504562 -125.32614)
		(width 0.11684)
		(layer "In2.Cu")
		(net "P12V_OCP_V3_2_EN_R")
	)
	(segment
		(start 195.504562 -125.32614)
		(end 194.740784 -124.562362)
		(width 0.11684)
		(layer "In2.Cu")
		(net "P12V_OCP_V3_2_EN_R")
	)
	(segment
		(start 66.545206 -35.146742)
		(end 68.819268 -32.87268)
		(width 0.11684)
		(layer "In4.Cu")
		(net "P12V_OCP_V3_2_EN_R")
	)
	(segment
		(start 68.819268 -32.87268)
		(end 70.006972 -32.87268)
		(width 0.11684)
		(layer "In4.Cu")
		(net "P12V_OCP_V3_2_EN_R")
	)
	(segment
		(start 70.006972 -32.87268)
		(end 70.051422 -32.91713)
		(width 0.11684)
		(layer "In4.Cu")
		(net "P12V_OCP_V3_2_EN_R")
	)
	(segment
		(start 65.172844 -35.146742)
		(end 66.545206 -35.146742)
		(width 0.11684)
		(layer "In4.Cu")
		(net "P12V_OCP_V3_2_EN_R")
	)
	(segment
		(start 88.537034 -38.36797)
		(end 84.887562 -34.718498)
		(width 0.11684)
		(layer "In6.Cu")
		(net "P12V_OCP_V3_2_EN_R")
	)
	(segment
		(start 104.141524 -39.923466)
		(end 100.385626 -38.36797)
		(width 0.11684)
		(layer "In6.Cu")
		(net "P12V_OCP_V3_2_EN_R")
	)
	(segment
		(start 114.479324 -44.43222)
		(end 109.441488 -44.43222)
		(width 0.11684)
		(layer "In6.Cu")
		(net "P12V_OCP_V3_2_EN_R")
	)
	(segment
		(start 73.904348 -32.842708)
		(end 70.125844 -32.842708)
		(width 0.11684)
		(layer "In6.Cu")
		(net "P12V_OCP_V3_2_EN_R")
	)
	(segment
		(start 104.932734 -39.923466)
		(end 104.141524 -39.923466)
		(width 0.11684)
		(layer "In6.Cu")
		(net "P12V_OCP_V3_2_EN_R")
	)
	(segment
		(start 78.432914 -34.718498)
		(end 73.904348 -32.842708)
		(width 0.11684)
		(layer "In6.Cu")
		(net "P12V_OCP_V3_2_EN_R")
	)
	(segment
		(start 157.7975 -44.049188)
		(end 152.06218 -44.049188)
		(width 0.11684)
		(layer "In6.Cu")
		(net "P12V_OCP_V3_2_EN_R")
	)
	(segment
		(start 152.06218 -44.049188)
		(end 150.48992 -42.476928)
		(width 0.11684)
		(layer "In6.Cu")
		(net "P12V_OCP_V3_2_EN_R")
	)
	(segment
		(start 145.588228 -43.86072)
		(end 129.475484 -43.86072)
		(width 0.11684)
		(layer "In6.Cu")
		(net "P12V_OCP_V3_2_EN_R")
	)
	(segment
		(start 84.887562 -34.718498)
		(end 78.432914 -34.718498)
		(width 0.11684)
		(layer "In6.Cu")
		(net "P12V_OCP_V3_2_EN_R")
	)
	(segment
		(start 150.48992 -42.476928)
		(end 146.97202 -42.476928)
		(width 0.11684)
		(layer "In6.Cu")
		(net "P12V_OCP_V3_2_EN_R")
	)
	(segment
		(start 129.047748 -43.432984)
		(end 115.47856 -43.432984)
		(width 0.11684)
		(layer "In6.Cu")
		(net "P12V_OCP_V3_2_EN_R")
	)
	(segment
		(start 100.385626 -38.36797)
		(end 88.537034 -38.36797)
		(width 0.11684)
		(layer "In6.Cu")
		(net "P12V_OCP_V3_2_EN_R")
	)
	(segment
		(start 158.94177 -42.904918)
		(end 157.7975 -44.049188)
		(width 0.11684)
		(layer "In6.Cu")
		(net "P12V_OCP_V3_2_EN_R")
	)
	(segment
		(start 146.97202 -42.476928)
		(end 145.588228 -43.86072)
		(width 0.11684)
		(layer "In6.Cu")
		(net "P12V_OCP_V3_2_EN_R")
	)
	(segment
		(start 70.125844 -32.842708)
		(end 70.051422 -32.91713)
		(width 0.11684)
		(layer "In6.Cu")
		(net "P12V_OCP_V3_2_EN_R")
	)
	(segment
		(start 115.47856 -43.432984)
		(end 114.479324 -44.43222)
		(width 0.11684)
		(layer "In6.Cu")
		(net "P12V_OCP_V3_2_EN_R")
	)
	(segment
		(start 109.441488 -44.43222)
		(end 104.932734 -39.923466)
		(width 0.11684)
		(layer "In6.Cu")
		(net "P12V_OCP_V3_2_EN_R")
	)
	(segment
		(start 129.475484 -43.86072)
		(end 129.047748 -43.432984)
		(width 0.11684)
		(layer "In6.Cu")
		(net "P12V_OCP_V3_2_EN_R")
	)
	(segment
		(start 195.1863 -97.793048)
		(end 194.8053 -97.793048)
		(width 0.11684)
		(layer "In11.Cu")
		(net "P12V_OCP_V3_2_EN_R")
	)
	(segment
		(start 180.969158 -85.03158)
		(end 177.576734 -81.639156)
		(width 0.11684)
		(layer "In11.Cu")
		(net "P12V_OCP_V3_2_EN_R")
	)
	(segment
		(start 172.075348 -61.068204)
		(end 175.269906 -57.873646)
		(width 0.11684)
		(layer "In11.Cu")
		(net "P12V_OCP_V3_2_EN_R")
	)
	(segment
		(start 194.07505 -104.35717)
		(end 194.583558 -103.848662)
		(width 0.11684)
		(layer "In11.Cu")
		(net "P12V_OCP_V3_2_EN_R")
	)
	(segment
		(start 192.90792 -91.703144)
		(end 192.416684 -91.211908)
		(width 0.11684)
		(layer "In11.Cu")
		(net "P12V_OCP_V3_2_EN_R")
	)
	(segment
		(start 185.738262 -88.418416)
		(end 185.738262 -87.483188)
		(width 0.11684)
		(layer "In11.Cu")
		(net "P12V_OCP_V3_2_EN_R")
	)
	(segment
		(start 190.175388 -90.283538)
		(end 187.603384 -90.283538)
		(width 0.11684)
		(layer "In11.Cu")
		(net "P12V_OCP_V3_2_EN_R")
	)
	(segment
		(start 193.11874 -121.849642)
		(end 193.11874 -113.306352)
		(width 0.11684)
		(layer "In11.Cu")
		(net "P12V_OCP_V3_2_EN_R")
	)
	(segment
		(start 194.166236 -110.461806)
		(end 194.700652 -109.92739)
		(width 0.11684)
		(layer "In11.Cu")
		(net "P12V_OCP_V3_2_EN_R")
	)
	(segment
		(start 183.286654 -85.03158)
		(end 180.969158 -85.03158)
		(width 0.11684)
		(layer "In11.Cu")
		(net "P12V_OCP_V3_2_EN_R")
	)
	(segment
		(start 172.075348 -77.328776)
		(end 172.075348 -61.068204)
		(width 0.11684)
		(layer "In11.Cu")
		(net "P12V_OCP_V3_2_EN_R")
	)
	(segment
		(start 194.8053 -97.793048)
		(end 192.435988 -95.423736)
		(width 0.11684)
		(layer "In11.Cu")
		(net "P12V_OCP_V3_2_EN_R")
	)
	(segment
		(start 177.576734 -81.639156)
		(end 176.385728 -81.639156)
		(width 0.11684)
		(layer "In11.Cu")
		(net "P12V_OCP_V3_2_EN_R")
	)
	(segment
		(start 194.07505 -105.476294)
		(end 194.07505 -104.35717)
		(width 0.11684)
		(layer "In11.Cu")
		(net "P12V_OCP_V3_2_EN_R")
	)
	(segment
		(start 194.583558 -103.848662)
		(end 194.583558 -103.12527)
		(width 0.11684)
		(layer "In11.Cu")
		(net "P12V_OCP_V3_2_EN_R")
	)
	(segment
		(start 175.269906 -57.873646)
		(end 175.269906 -55.401718)
		(width 0.11684)
		(layer "In11.Cu")
		(net "P12V_OCP_V3_2_EN_R")
	)
	(segment
		(start 194.700652 -106.101896)
		(end 194.07505 -105.476294)
		(width 0.11684)
		(layer "In11.Cu")
		(net "P12V_OCP_V3_2_EN_R")
	)
	(segment
		(start 193.511932 -122.242834)
		(end 193.11874 -121.849642)
		(width 0.11684)
		(layer "In11.Cu")
		(net "P12V_OCP_V3_2_EN_R")
	)
	(segment
		(start 192.435988 -94.73438)
		(end 192.90792 -94.262448)
		(width 0.11684)
		(layer "In11.Cu")
		(net "P12V_OCP_V3_2_EN_R")
	)
	(segment
		(start 185.738262 -87.483188)
		(end 183.286654 -85.03158)
		(width 0.11684)
		(layer "In11.Cu")
		(net "P12V_OCP_V3_2_EN_R")
	)
	(segment
		(start 192.416684 -91.211908)
		(end 190.175388 -90.283538)
		(width 0.11684)
		(layer "In11.Cu")
		(net "P12V_OCP_V3_2_EN_R")
	)
	(segment
		(start 194.700652 -109.92739)
		(end 194.700652 -106.101896)
		(width 0.11684)
		(layer "In11.Cu")
		(net "P12V_OCP_V3_2_EN_R")
	)
	(segment
		(start 192.435988 -95.423736)
		(end 192.435988 -94.73438)
		(width 0.11684)
		(layer "In11.Cu")
		(net "P12V_OCP_V3_2_EN_R")
	)
	(segment
		(start 194.166236 -112.258856)
		(end 194.166236 -110.461806)
		(width 0.11684)
		(layer "In11.Cu")
		(net "P12V_OCP_V3_2_EN_R")
	)
	(segment
		(start 175.269906 -55.401718)
		(end 173.172882 -53.304694)
		(width 0.11684)
		(layer "In11.Cu")
		(net "P12V_OCP_V3_2_EN_R")
	)
	(segment
		(start 193.11874 -113.306352)
		(end 194.166236 -112.258856)
		(width 0.11684)
		(layer "In11.Cu")
		(net "P12V_OCP_V3_2_EN_R")
	)
	(segment
		(start 194.583558 -103.12527)
		(end 195.4403 -102.268528)
		(width 0.11684)
		(layer "In11.Cu")
		(net "P12V_OCP_V3_2_EN_R")
	)
	(segment
		(start 195.4403 -98.047048)
		(end 195.1863 -97.793048)
		(width 0.11684)
		(layer "In11.Cu")
		(net "P12V_OCP_V3_2_EN_R")
	)
	(segment
		(start 173.172882 -53.304694)
		(end 172.546264 -53.304694)
		(width 0.11684)
		(layer "In11.Cu")
		(net "P12V_OCP_V3_2_EN_R")
	)
	(segment
		(start 192.90792 -94.262448)
		(end 192.90792 -91.703144)
		(width 0.11684)
		(layer "In11.Cu")
		(net "P12V_OCP_V3_2_EN_R")
	)
	(segment
		(start 195.4403 -102.268528)
		(end 195.4403 -98.047048)
		(width 0.11684)
		(layer "In11.Cu")
		(net "P12V_OCP_V3_2_EN_R")
	)
	(segment
		(start 176.385728 -81.639156)
		(end 172.075348 -77.328776)
		(width 0.11684)
		(layer "In11.Cu")
		(net "P12V_OCP_V3_2_EN_R")
	)
	(segment
		(start 187.603384 -90.283538)
		(end 185.738262 -88.418416)
		(width 0.11684)
		(layer "In11.Cu")
		(net "P12V_OCP_V3_2_EN_R")
	)
	(segment
		(start 317.146432 -45.859954)
		(end 316.37478 -45.088302)
		(width 0.254)
		(layer "F.Cu")
		(net "P12V_OCP_SFF_ISENSE_TIC")
	)
	(segment
		(start 323.237098 -46.116494)
		(end 322.926456 -46.427136)
		(width 0.254)
		(layer "F.Cu")
		(net "P12V_OCP_SFF_ISENSE_TIC")
	)
	(segment
		(start 318.289178 -45.859954)
		(end 319.540128 -45.859954)
		(width 0.254)
		(layer "F.Cu")
		(net "P12V_OCP_SFF_ISENSE_TIC")
	)
	(segment
		(start 319.794382 -46.427136)
		(end 319.540128 -46.172882)
		(width 0.254)
		(layer "F.Cu")
		(net "P12V_OCP_SFF_ISENSE_TIC")
	)
	(segment
		(start 316.37478 -45.088302)
		(end 315.525404 -45.088302)
		(width 0.254)
		(layer "F.Cu")
		(net "P12V_OCP_SFF_ISENSE_TIC")
	)
	(segment
		(start 323.237098 -45.86351)
		(end 323.237098 -46.116494)
		(width 0.254)
		(layer "F.Cu")
		(net "P12V_OCP_SFF_ISENSE_TIC")
	)
	(segment
		(start 322.926456 -46.427136)
		(end 319.794382 -46.427136)
		(width 0.254)
		(layer "F.Cu")
		(net "P12V_OCP_SFF_ISENSE_TIC")
	)
	(segment
		(start 318.289178 -45.859954)
		(end 317.146432 -45.859954)
		(width 0.254)
		(layer "F.Cu")
		(net "P12V_OCP_SFF_ISENSE_TIC")
	)
	(segment
		(start 319.540128 -46.172882)
		(end 319.540128 -45.859954)
		(width 0.254)
		(layer "F.Cu")
		(net "P12V_OCP_SFF_ISENSE_TIC")
	)
	(via
		(at 318.289178 -45.859954)
		(size 0.762)
		(drill 0.381)
		(layers "F.Cu" "B.Cu")
		(net "P12V_OCP_SFF_ISENSE_TIC")
	)
	(segment
		(start 312.195972 -33.144206)
		(end 315.849508 -33.144206)
		(width 0.254)
		(layer "F.Cu")
		(net "P12V_OCP_SFF_ISENSE_MAM")
	)
	(segment
		(start 311.941972 -33.398206)
		(end 312.195972 -33.144206)
		(width 0.254)
		(layer "F.Cu")
		(net "P12V_OCP_SFF_ISENSE_MAM")
	)
	(segment
		(start 315.849508 -33.144206)
		(end 316.171072 -33.46577)
		(width 0.254)
		(layer "F.Cu")
		(net "P12V_OCP_SFF_ISENSE_MAM")
	)
	(segment
		(start 319.120266 -33.668462)
		(end 319.99809 -33.668462)
		(width 0.254)
		(layer "F.Cu")
		(net "P12V_OCP_SFF_ISENSE_MAM")
	)
	(segment
		(start 316.376812 -33.921446)
		(end 316.171072 -33.715706)
		(width 0.254)
		(layer "F.Cu")
		(net "P12V_OCP_SFF_ISENSE_MAM")
	)
	(segment
		(start 311.941972 -33.715706)
		(end 311.941972 -33.398206)
		(width 0.254)
		(layer "F.Cu")
		(net "P12V_OCP_SFF_ISENSE_MAM")
	)
	(segment
		(start 316.171072 -33.46577)
		(end 316.171072 -33.715706)
		(width 0.254)
		(layer "F.Cu")
		(net "P12V_OCP_SFF_ISENSE_MAM")
	)
	(segment
		(start 318.184022 -33.921446)
		(end 318.867282 -33.921446)
		(width 0.254)
		(layer "F.Cu")
		(net "P12V_OCP_SFF_ISENSE_MAM")
	)
	(segment
		(start 318.184022 -33.921446)
		(end 316.376812 -33.921446)
		(width 0.254)
		(layer "F.Cu")
		(net "P12V_OCP_SFF_ISENSE_MAM")
	)
	(segment
		(start 318.867282 -33.921446)
		(end 319.120266 -33.668462)
		(width 0.254)
		(layer "F.Cu")
		(net "P12V_OCP_SFF_ISENSE_MAM")
	)
	(via
		(at 318.184022 -33.921446)
		(size 0.762)
		(drill 0.381)
		(layers "F.Cu" "B.Cu")
		(net "P12V_OCP_SFF_ISENSE_MAM")
	)
	(segment
		(start 316.949836 -40.600376)
		(end 317.96355 -39.586662)
		(width 0.254)
		(layer "F.Cu")
		(net "P12V_E1S_0_ISENSE_TIC")
	)
	(segment
		(start 316.333632 -41.21658)
		(end 316.949836 -40.600376)
		(width 0.254)
		(layer "F.Cu")
		(net "P12V_E1S_0_ISENSE_TIC")
	)
	(segment
		(start 319.508886 -39.586662)
		(end 319.540128 -39.55542)
		(width 0.254)
		(layer "F.Cu")
		(net "P12V_E1S_0_ISENSE_TIC")
	)
	(segment
		(start 317.96355 -39.586662)
		(end 319.508886 -39.586662)
		(width 0.254)
		(layer "F.Cu")
		(net "P12V_E1S_0_ISENSE_TIC")
	)
	(segment
		(start 315.553852 -41.21658)
		(end 316.333632 -41.21658)
		(width 0.254)
		(layer "F.Cu")
		(net "P12V_E1S_0_ISENSE_TIC")
	)
	(segment
		(start 315.525404 -41.188132)
		(end 315.553852 -41.21658)
		(width 0.254)
		(layer "F.Cu")
		(net "P12V_E1S_0_ISENSE_TIC")
	)
	(via
		(at 316.949836 -40.600376)
		(size 0.508)
		(drill 0.254)
		(layers "F.Cu" "B.Cu")
		(net "P12V_E1S_0_ISENSE_TIC")
	)
	(segment
		(start 316.812422 -40.73779)
		(end 316.949836 -40.600376)
		(width 0.254)
		(layer "B.Cu")
		(net "P12V_E1S_0_ISENSE_TIC")
	)
	(segment
		(start 315.585094 -40.73779)
		(end 316.812422 -40.73779)
		(width 0.254)
		(layer "B.Cu")
		(net "P12V_E1S_0_ISENSE_TIC")
	)
	(segment
		(start 327.021444 -34.07791)
		(end 326.554592 -34.07791)
		(width 0.254)
		(layer "F.Cu")
		(net "P12V_E1S_0_ISENSE_MAM")
	)
	(segment
		(start 326.32904 -34.303462)
		(end 325.308214 -34.303462)
		(width 0.254)
		(layer "F.Cu")
		(net "P12V_E1S_0_ISENSE_MAM")
	)
	(segment
		(start 326.554592 -34.07791)
		(end 326.32904 -34.303462)
		(width 0.254)
		(layer "F.Cu")
		(net "P12V_E1S_0_ISENSE_MAM")
	)
	(via
		(at 327.021444 -34.07791)
		(size 0.508)
		(drill 0.254)
		(layers "F.Cu" "B.Cu")
		(net "P12V_E1S_0_ISENSE_MAM")
	)
	(segment
		(start 325.635112 -34.251392)
		(end 326.809608 -34.251392)
		(width 0.254)
		(layer "B.Cu")
		(net "P12V_E1S_0_ISENSE_MAM")
	)
	(segment
		(start 326.98309 -34.07791)
		(end 327.021444 -34.07791)
		(width 0.254)
		(layer "B.Cu")
		(net "P12V_E1S_0_ISENSE_MAM")
	)
	(segment
		(start 327.08342 -34.139886)
		(end 327.021444 -34.07791)
		(width 0.254)
		(layer "B.Cu")
		(net "P12V_E1S_0_ISENSE_MAM")
	)
	(segment
		(start 326.809608 -34.251392)
		(end 326.98309 -34.07791)
		(width 0.254)
		(layer "B.Cu")
		(net "P12V_E1S_0_ISENSE_MAM")
	)
	(segment
		(start 328.5236 -34.139886)
		(end 327.08342 -34.139886)
		(width 0.254)
		(layer "B.Cu")
		(net "P12V_E1S_0_ISENSE_MAM")
	)
	(segment
		(start 319.540128 -47.237904)
		(end 319.540128 -47.002954)
		(width 0.10668)
		(layer "F.Cu")
		(net "P12V_AUX_ADC_TIC")
	)
	(segment
		(start 316.262766 -45.738288)
		(end 315.525404 -45.738288)
		(width 0.10668)
		(layer "F.Cu")
		(net "P12V_AUX_ADC_TIC")
	)
	(segment
		(start 319.540128 -47.002954)
		(end 319.131188 -47.002954)
		(width 0.10668)
		(layer "F.Cu")
		(net "P12V_AUX_ADC_TIC")
	)
	(segment
		(start 319.131188 -47.002954)
		(end 318.877188 -46.748954)
		(width 0.10668)
		(layer "F.Cu")
		(net "P12V_AUX_ADC_TIC")
	)
	(segment
		(start 317.273178 -46.748954)
		(end 317.273178 -46.7487)
		(width 0.10668)
		(layer "F.Cu")
		(net "P12V_AUX_ADC_TIC")
	)
	(segment
		(start 322.436998 -46.986698)
		(end 321.785742 -47.637954)
		(width 0.10668)
		(layer "F.Cu")
		(net "P12V_AUX_ADC_TIC")
	)
	(segment
		(start 318.877188 -46.748954)
		(end 317.273178 -46.748954)
		(width 0.10668)
		(layer "F.Cu")
		(net "P12V_AUX_ADC_TIC")
	)
	(segment
		(start 317.273178 -46.7487)
		(end 316.262766 -45.738288)
		(width 0.10668)
		(layer "F.Cu")
		(net "P12V_AUX_ADC_TIC")
	)
	(segment
		(start 319.940178 -47.637954)
		(end 319.540128 -47.237904)
		(width 0.10668)
		(layer "F.Cu")
		(net "P12V_AUX_ADC_TIC")
	)
	(segment
		(start 321.785742 -47.637954)
		(end 319.940178 -47.637954)
		(width 0.10668)
		(layer "F.Cu")
		(net "P12V_AUX_ADC_TIC")
	)
	(via
		(at 317.273178 -46.748954)
		(size 0.762)
		(drill 0.381)
		(layers "F.Cu" "B.Cu")
		(net "P12V_AUX_ADC_TIC")
	)
	(segment
		(start 317.355474 -34.985706)
		(end 316.298072 -34.985706)
		(width 0.10668)
		(layer "F.Cu")
		(net "P12V_AUX_ADC_MAM")
	)
	(segment
		(start 319.99809 -34.303462)
		(end 318.643254 -34.303462)
		(width 0.10668)
		(layer "F.Cu")
		(net "P12V_AUX_ADC_MAM")
	)
	(segment
		(start 324.037198 -46.986698)
		(end 324.646798 -46.986698)
		(width 0.10668)
		(layer "F.Cu")
		(net "P12V_AUX_ADC_MAM")
	)
	(segment
		(start 317.96101 -34.985706)
		(end 317.355474 -34.985706)
		(width 0.10668)
		(layer "F.Cu")
		(net "P12V_AUX_ADC_MAM")
	)
	(segment
		(start 318.643254 -34.303462)
		(end 317.96101 -34.985706)
		(width 0.10668)
		(layer "F.Cu")
		(net "P12V_AUX_ADC_MAM")
	)
	(segment
		(start 316.298072 -34.985706)
		(end 316.171072 -34.858706)
		(width 0.10668)
		(layer "F.Cu")
		(net "P12V_AUX_ADC_MAM")
	)
	(via
		(at 317.355474 -34.985706)
		(size 0.508)
		(drill 0.254)
		(layers "F.Cu" "B.Cu")
		(net "P12V_AUX_ADC_MAM")
	)
	(via
		(at 324.646798 -46.986698)
		(size 0.508)
		(drill 0.254)
		(layers "F.Cu" "B.Cu")
		(net "P12V_AUX_ADC_MAM")
	)
	(segment
		(start 320.8909 -47.645828)
		(end 323.548248 -47.645828)
		(width 0.11684)
		(layer "In4.Cu")
		(net "P12V_AUX_ADC_MAM")
	)
	(segment
		(start 320.37528 -38.867588)
		(end 320.37528 -47.130208)
		(width 0.11684)
		(layer "In4.Cu")
		(net "P12V_AUX_ADC_MAM")
	)
	(segment
		(start 317.355474 -35.847782)
		(end 320.37528 -38.867588)
		(width 0.11684)
		(layer "In4.Cu")
		(net "P12V_AUX_ADC_MAM")
	)
	(segment
		(start 324.207378 -46.986698)
		(end 324.646798 -46.986698)
		(width 0.11684)
		(layer "In4.Cu")
		(net "P12V_AUX_ADC_MAM")
	)
	(segment
		(start 323.548248 -47.645828)
		(end 324.207378 -46.986698)
		(width 0.11684)
		(layer "In4.Cu")
		(net "P12V_AUX_ADC_MAM")
	)
	(segment
		(start 317.355474 -34.985706)
		(end 317.355474 -35.847782)
		(width 0.11684)
		(layer "In4.Cu")
		(net "P12V_AUX_ADC_MAM")
	)
	(segment
		(start 320.37528 -47.130208)
		(end 320.8909 -47.645828)
		(width 0.11684)
		(layer "In4.Cu")
		(net "P12V_AUX_ADC_MAM")
	)
	(segment
		(start 323.496178 -47.510954)
		(end 324.874128 -47.510954)
		(width 0.10668)
		(layer "F.Cu")
		(net "P12V_AUX_ADC")
	)
	(segment
		(start 326.779128 -46.748954)
		(end 325.636128 -46.748954)
		(width 0.10668)
		(layer "F.Cu")
		(net "P12V_AUX_ADC")
	)
	(segment
		(start 323.237098 -47.251874)
		(end 323.496178 -47.510954)
		(width 0.10668)
		(layer "F.Cu")
		(net "P12V_AUX_ADC")
	)
	(segment
		(start 324.874128 -47.510954)
		(end 325.51878 -46.866302)
		(width 0.10668)
		(layer "F.Cu")
		(net "P12V_AUX_ADC")
	)
	(segment
		(start 328.712322 -47.22876)
		(end 327.233534 -47.22876)
		(width 0.10668)
		(layer "F.Cu")
		(net "P12V_AUX_ADC")
	)
	(segment
		(start 326.779128 -46.774354)
		(end 326.779128 -46.748954)
		(width 0.10668)
		(layer "F.Cu")
		(net "P12V_AUX_ADC")
	)
	(segment
		(start 329.192128 -46.748954)
		(end 328.712322 -47.22876)
		(width 0.10668)
		(layer "F.Cu")
		(net "P12V_AUX_ADC")
	)
	(segment
		(start 323.237098 -46.986698)
		(end 323.237098 -47.251874)
		(width 0.10668)
		(layer "F.Cu")
		(net "P12V_AUX_ADC")
	)
	(segment
		(start 325.636128 -46.748954)
		(end 325.51878 -46.866302)
		(width 0.10668)
		(layer "F.Cu")
		(net "P12V_AUX_ADC")
	)
	(segment
		(start 327.233534 -47.22876)
		(end 326.779128 -46.774354)
		(width 0.10668)
		(layer "F.Cu")
		(net "P12V_AUX_ADC")
	)
	(via
		(at 325.51878 -46.866302)
		(size 0.762)
		(drill 0.381)
		(layers "F.Cu" "B.Cu")
		(net "P12V_AUX_ADC")
	)
	(segment
		(start 317.422022 -36.843462)
		(end 316.218316 -36.843462)
		(width 0.10668)
		(layer "F.Cu")
		(net "MAX11617_VREF_R")
	)
	(segment
		(start 319.99809 -36.843462)
		(end 317.422022 -36.843462)
		(width 0.10668)
		(layer "F.Cu")
		(net "MAX11617_VREF_R")
	)
	(segment
		(start 316.218316 -36.843462)
		(end 316.171072 -36.890706)
		(width 0.10668)
		(layer "F.Cu")
		(net "MAX11617_VREF_R")
	)
	(via
		(at 317.422022 -36.843462)
		(size 0.762)
		(drill 0.381)
		(layers "F.Cu" "B.Cu")
		(net "MAX11617_VREF_R")
	)
	(segment
		(start 313.504072 -36.890706)
		(end 313.504072 -37.887656)
		(width 0.10668)
		(layer "F.Cu")
		(net "MAX11617_VREF")
	)
	(segment
		(start 312.596022 -38.160706)
		(end 311.199022 -38.160706)
		(width 0.10668)
		(layer "F.Cu")
		(net "MAX11617_VREF")
	)
	(segment
		(start 313.231022 -38.160706)
		(end 312.596022 -38.160706)
		(width 0.10668)
		(layer "F.Cu")
		(net "MAX11617_VREF")
	)
	(segment
		(start 313.504072 -37.887656)
		(end 313.231022 -38.160706)
		(width 0.10668)
		(layer "F.Cu")
		(net "MAX11617_VREF")
	)
	(segment
		(start 310.945022 -37.906706)
		(end 310.945022 -37.017706)
		(width 0.10668)
		(layer "F.Cu")
		(net "MAX11617_VREF")
	)
	(segment
		(start 313.504072 -36.890706)
		(end 315.370972 -36.890706)
		(width 0.10668)
		(layer "F.Cu")
		(net "MAX11617_VREF")
	)
	(segment
		(start 311.199022 -38.160706)
		(end 310.945022 -37.906706)
		(width 0.10668)
		(layer "F.Cu")
		(net "MAX11617_VREF")
	)
	(via
		(at 312.596022 -38.160706)
		(size 0.762)
		(drill 0.381)
		(layers "F.Cu" "B.Cu")
		(net "MAX11617_VREF")
	)
	(segment
		(start 164.144706 -41.112948)
		(end 163.5252 -41.112948)
		(width 0.10668)
		(layer "F.Cu")
		(net "M2_0_PEWAKE_R_N")
	)
	(segment
		(start 158.16707 -74.35342)
		(end 158.16707 -72.46747)
		(width 0.10668)
		(layer "F.Cu")
		(net "M2_0_PEWAKE_R_N")
	)
	(via
		(at 158.16707 -72.46747)
		(size 0.508)
		(drill 0.254)
		(layers "F.Cu" "B.Cu")
		(net "M2_0_PEWAKE_R_N")
	)
	(via
		(at 163.5252 -41.112948)
		(size 0.508)
		(drill 0.254)
		(layers "F.Cu" "B.Cu")
		(net "M2_0_PEWAKE_R_N")
	)
	(segment
		(start 159.64789 -51.04511)
		(end 159.64789 -72.660256)
		(width 0.11684)
		(layer "In15.Cu")
		(net "M2_0_PEWAKE_R_N")
	)
	(segment
		(start 159.405828 -41.627298)
		(end 158.33852 -42.694606)
		(width 0.11684)
		(layer "In15.Cu")
		(net "M2_0_PEWAKE_R_N")
	)
	(segment
		(start 159.375856 -72.93229)
		(end 158.63189 -72.93229)
		(width 0.11684)
		(layer "In15.Cu")
		(net "M2_0_PEWAKE_R_N")
	)
	(segment
		(start 158.33852 -42.694606)
		(end 158.33852 -49.73574)
		(width 0.11684)
		(layer "In15.Cu")
		(net "M2_0_PEWAKE_R_N")
	)
	(segment
		(start 158.33852 -49.73574)
		(end 159.64789 -51.04511)
		(width 0.11684)
		(layer "In15.Cu")
		(net "M2_0_PEWAKE_R_N")
	)
	(segment
		(start 159.64789 -72.660256)
		(end 159.375856 -72.93229)
		(width 0.11684)
		(layer "In15.Cu")
		(net "M2_0_PEWAKE_R_N")
	)
	(segment
		(start 158.63189 -72.93229)
		(end 158.16707 -72.46747)
		(width 0.11684)
		(layer "In15.Cu")
		(net "M2_0_PEWAKE_R_N")
	)
	(segment
		(start 163.5252 -41.112948)
		(end 163.01085 -41.627298)
		(width 0.11684)
		(layer "In15.Cu")
		(net "M2_0_PEWAKE_R_N")
	)
	(segment
		(start 163.01085 -41.627298)
		(end 159.405828 -41.627298)
		(width 0.11684)
		(layer "In15.Cu")
		(net "M2_0_PEWAKE_R_N")
	)
	(segment
		(start 185.122058 -106.652822)
		(end 184.732168 -106.262932)
		(width 0.10668)
		(layer "F.Cu")
		(net "LED_HDD_ACTIVITY_B_PLD_N")
	)
	(segment
		(start 185.801 -93.074998)
		(end 185.801 -93.690948)
		(width 0.10668)
		(layer "F.Cu")
		(net "LED_HDD_ACTIVITY_B_PLD_N")
	)
	(via
		(at 185.801 -93.690948)
		(size 0.508)
		(drill 0.254)
		(layers "F.Cu" "B.Cu")
		(net "LED_HDD_ACTIVITY_B_PLD_N")
	)
	(via
		(at 184.732168 -106.262932)
		(size 0.4572)
		(drill 0.254)
		(layers "F.Cu" "B.Cu")
		(net "LED_HDD_ACTIVITY_B_PLD_N")
	)
	(segment
		(start 184.25922 -98.916998)
		(end 184.25922 -99.62388)
		(width 0.11684)
		(layer "In11.Cu")
		(net "LED_HDD_ACTIVITY_B_PLD_N")
	)
	(segment
		(start 183.8198 -100.0633)
		(end 183.8198 -103.100886)
		(width 0.11684)
		(layer "In11.Cu")
		(net "LED_HDD_ACTIVITY_B_PLD_N")
	)
	(segment
		(start 184.3024 -97.665794)
		(end 184.3024 -98.873818)
		(width 0.11684)
		(layer "In11.Cu")
		(net "LED_HDD_ACTIVITY_B_PLD_N")
	)
	(segment
		(start 184.3024 -98.873818)
		(end 184.25922 -98.916998)
		(width 0.11684)
		(layer "In11.Cu")
		(net "LED_HDD_ACTIVITY_B_PLD_N")
	)
	(segment
		(start 185.22188 -96.746314)
		(end 184.3024 -97.665794)
		(width 0.11684)
		(layer "In11.Cu")
		(net "LED_HDD_ACTIVITY_B_PLD_N")
	)
	(segment
		(start 183.8198 -103.100886)
		(end 184.732168 -104.013254)
		(width 0.11684)
		(layer "In11.Cu")
		(net "LED_HDD_ACTIVITY_B_PLD_N")
	)
	(segment
		(start 184.732168 -104.013254)
		(end 184.732168 -106.262932)
		(width 0.11684)
		(layer "In11.Cu")
		(net "LED_HDD_ACTIVITY_B_PLD_N")
	)
	(segment
		(start 185.22188 -94.270068)
		(end 185.22188 -96.746314)
		(width 0.11684)
		(layer "In11.Cu")
		(net "LED_HDD_ACTIVITY_B_PLD_N")
	)
	(segment
		(start 185.801 -93.690948)
		(end 185.22188 -94.270068)
		(width 0.11684)
		(layer "In11.Cu")
		(net "LED_HDD_ACTIVITY_B_PLD_N")
	)
	(segment
		(start 184.25922 -99.62388)
		(end 183.8198 -100.0633)
		(width 0.11684)
		(layer "In11.Cu")
		(net "LED_HDD_ACTIVITY_B_PLD_N")
	)
	(segment
		(start 153.856944 -13.599922)
		(end 153.856944 -11.272012)
		(width 0.10668)
		(layer "F.Cu")
		(net "JTAG_SCM_TDO_R")
	)
	(segment
		(start 153.856944 -11.272012)
		(end 154.07259 -11.056366)
		(width 0.10668)
		(layer "F.Cu")
		(net "JTAG_SCM_TDO_R")
	)
	(via
		(at 154.07259 -11.056366)
		(size 0.508)
		(drill 0.254)
		(layers "F.Cu" "B.Cu")
		(net "JTAG_SCM_TDO_R")
	)
	(via
		(at 131.397756 -50.914046)
		(size 0.508)
		(drill 0.254)
		(layers "F.Cu" "B.Cu")
		(net "JTAG_SCM_TDO_R")
	)
	(segment
		(start 130.657092 -50.702972)
		(end 131.17957 -50.702972)
		(width 0.10668)
		(layer "B.Cu")
		(net "JTAG_SCM_TDO_R")
	)
	(segment
		(start 131.17957 -50.702972)
		(end 131.390644 -50.914046)
		(width 0.10668)
		(layer "B.Cu")
		(net "JTAG_SCM_TDO_R")
	)
	(segment
		(start 154.577288 -10.551668)
		(end 154.07259 -11.056366)
		(width 0.10668)
		(layer "B.Cu")
		(net "JTAG_SCM_TDO_R")
	)
	(segment
		(start 131.390644 -50.914046)
		(end 131.397756 -50.914046)
		(width 0.10668)
		(layer "B.Cu")
		(net "JTAG_SCM_TDO_R")
	)
	(segment
		(start 154.577288 -9.8806)
		(end 154.577288 -10.551668)
		(width 0.10668)
		(layer "B.Cu")
		(net "JTAG_SCM_TDO_R")
	)
	(segment
		(start 145.699988 -17.754346)
		(end 145.699988 -28.480512)
		(width 0.11684)
		(layer "In4.Cu")
		(net "JTAG_SCM_TDO_R")
	)
	(segment
		(start 145.085054 -44.671996)
		(end 133.401054 -46.996096)
		(width 0.11684)
		(layer "In4.Cu")
		(net "JTAG_SCM_TDO_R")
	)
	(segment
		(start 154.07259 -12.521946)
		(end 153.116788 -13.477748)
		(width 0.11684)
		(layer "In4.Cu")
		(net "JTAG_SCM_TDO_R")
	)
	(segment
		(start 153.116788 -13.477748)
		(end 149.976586 -13.477748)
		(width 0.11684)
		(layer "In4.Cu")
		(net "JTAG_SCM_TDO_R")
	)
	(segment
		(start 146.23542 -43.52163)
		(end 145.085054 -44.671996)
		(width 0.11684)
		(layer "In4.Cu")
		(net "JTAG_SCM_TDO_R")
	)
	(segment
		(start 131.10845 -48.410876)
		(end 131.10845 -50.62474)
		(width 0.11684)
		(layer "In4.Cu")
		(net "JTAG_SCM_TDO_R")
	)
	(segment
		(start 131.10845 -50.62474)
		(end 131.397756 -50.914046)
		(width 0.11684)
		(layer "In4.Cu")
		(net "JTAG_SCM_TDO_R")
	)
	(segment
		(start 142.98549 -32.799528)
		(end 146.23542 -36.049458)
		(width 0.11684)
		(layer "In4.Cu")
		(net "JTAG_SCM_TDO_R")
	)
	(segment
		(start 142.98549 -31.19501)
		(end 142.98549 -32.799528)
		(width 0.11684)
		(layer "In4.Cu")
		(net "JTAG_SCM_TDO_R")
	)
	(segment
		(start 149.976586 -13.477748)
		(end 145.699988 -17.754346)
		(width 0.11684)
		(layer "In4.Cu")
		(net "JTAG_SCM_TDO_R")
	)
	(segment
		(start 154.07259 -11.056366)
		(end 154.07259 -12.521946)
		(width 0.11684)
		(layer "In4.Cu")
		(net "JTAG_SCM_TDO_R")
	)
	(segment
		(start 146.23542 -36.049458)
		(end 146.23542 -43.52163)
		(width 0.11684)
		(layer "In4.Cu")
		(net "JTAG_SCM_TDO_R")
	)
	(segment
		(start 145.699988 -28.480512)
		(end 142.98549 -31.19501)
		(width 0.11684)
		(layer "In4.Cu")
		(net "JTAG_SCM_TDO_R")
	)
	(segment
		(start 133.401054 -46.996096)
		(end 131.902708 -47.616618)
		(width 0.11684)
		(layer "In4.Cu")
		(net "JTAG_SCM_TDO_R")
	)
	(segment
		(start 131.902708 -47.616618)
		(end 131.10845 -48.410876)
		(width 0.11684)
		(layer "In4.Cu")
		(net "JTAG_SCM_TDO_R")
	)
	(segment
		(start 153.869136 -8.599678)
		(end 153.628598 -8.35914)
		(width 0.10668)
		(layer "F.Cu")
		(net "JTAG_SCM_TDI_R")
	)
	(segment
		(start 153.628598 -8.35914)
		(end 153.120598 -8.35914)
		(width 0.10668)
		(layer "F.Cu")
		(net "JTAG_SCM_TDI_R")
	)
	(segment
		(start 153.869136 -9.645904)
		(end 153.869136 -8.599678)
		(width 0.10668)
		(layer "F.Cu")
		(net "JTAG_SCM_TDI_R")
	)
	(segment
		(start 154.68473 -10.461498)
		(end 153.869136 -9.645904)
		(width 0.10668)
		(layer "F.Cu")
		(net "JTAG_SCM_TDI_R")
	)
	(segment
		(start 154.456892 -12.297918)
		(end 154.68473 -12.07008)
		(width 0.10668)
		(layer "F.Cu")
		(net "JTAG_SCM_TDI_R")
	)
	(segment
		(start 154.68473 -12.07008)
		(end 154.68473 -10.461498)
		(width 0.10668)
		(layer "F.Cu")
		(net "JTAG_SCM_TDI_R")
	)
	(segment
		(start 154.456892 -13.599922)
		(end 154.456892 -12.297918)
		(width 0.10668)
		(layer "F.Cu")
		(net "JTAG_SCM_TDI_R")
	)
	(via
		(at 131.747514 -48.728884)
		(size 0.508)
		(drill 0.254)
		(layers "F.Cu" "B.Cu")
		(net "JTAG_SCM_TDI_R")
	)
	(via
		(at 153.120598 -8.35914)
		(size 0.508)
		(drill 0.254)
		(layers "F.Cu" "B.Cu")
		(net "JTAG_SCM_TDI_R")
	)
	(segment
		(start 153.120598 -8.35914)
		(end 153.199338 -8.2804)
		(width 0.10668)
		(layer "B.Cu")
		(net "JTAG_SCM_TDI_R")
	)
	(segment
		(start 130.657092 -49.102772)
		(end 131.373626 -49.102772)
		(width 0.10668)
		(layer "B.Cu")
		(net "JTAG_SCM_TDI_R")
	)
	(segment
		(start 153.199338 -8.2804)
		(end 154.577288 -8.2804)
		(width 0.10668)
		(layer "B.Cu")
		(net "JTAG_SCM_TDI_R")
	)
	(segment
		(start 131.373626 -49.102772)
		(end 131.747514 -48.728884)
		(width 0.10668)
		(layer "B.Cu")
		(net "JTAG_SCM_TDI_R")
	)
	(segment
		(start 146.149568 -18.006568)
		(end 146.149568 -27.734768)
		(width 0.11684)
		(layer "In4.Cu")
		(net "JTAG_SCM_TDI_R")
	)
	(segment
		(start 153.120598 -8.35914)
		(end 158.247334 -8.35914)
		(width 0.11684)
		(layer "In4.Cu")
		(net "JTAG_SCM_TDI_R")
	)
	(segment
		(start 158.247334 -8.35914)
		(end 158.951676 -9.063482)
		(width 0.11684)
		(layer "In4.Cu")
		(net "JTAG_SCM_TDI_R")
	)
	(segment
		(start 158.951676 -9.063482)
		(end 158.951676 -9.979152)
		(width 0.11684)
		(layer "In4.Cu")
		(net "JTAG_SCM_TDI_R")
	)
	(segment
		(start 158.007304 -10.923524)
		(end 158.007304 -13.03401)
		(width 0.11684)
		(layer "In4.Cu")
		(net "JTAG_SCM_TDI_R")
	)
	(segment
		(start 146.149568 -27.734768)
		(end 147.23618 -28.82138)
		(width 0.11684)
		(layer "In4.Cu")
		(net "JTAG_SCM_TDI_R")
	)
	(segment
		(start 147.23618 -28.82138)
		(end 147.23618 -32.476186)
		(width 0.11684)
		(layer "In4.Cu")
		(net "JTAG_SCM_TDI_R")
	)
	(segment
		(start 134.341616 -47.320962)
		(end 132.316474 -48.159924)
		(width 0.11684)
		(layer "In4.Cu")
		(net "JTAG_SCM_TDI_R")
	)
	(segment
		(start 145.396712 -45.122084)
		(end 134.341616 -47.320962)
		(width 0.11684)
		(layer "In4.Cu")
		(net "JTAG_SCM_TDI_R")
	)
	(segment
		(start 146.685 -43.833796)
		(end 145.396712 -45.122084)
		(width 0.11684)
		(layer "In4.Cu")
		(net "JTAG_SCM_TDI_R")
	)
	(segment
		(start 146.685 -33.027366)
		(end 146.685 -43.833796)
		(width 0.11684)
		(layer "In4.Cu")
		(net "JTAG_SCM_TDI_R")
	)
	(segment
		(start 158.007304 -13.03401)
		(end 156.993336 -14.047978)
		(width 0.11684)
		(layer "In4.Cu")
		(net "JTAG_SCM_TDI_R")
	)
	(segment
		(start 147.23618 -32.476186)
		(end 146.685 -33.027366)
		(width 0.11684)
		(layer "In4.Cu")
		(net "JTAG_SCM_TDI_R")
	)
	(segment
		(start 158.951676 -9.979152)
		(end 158.007304 -10.923524)
		(width 0.11684)
		(layer "In4.Cu")
		(net "JTAG_SCM_TDI_R")
	)
	(segment
		(start 132.316474 -48.159924)
		(end 131.747514 -48.728884)
		(width 0.11684)
		(layer "In4.Cu")
		(net "JTAG_SCM_TDI_R")
	)
	(segment
		(start 156.993336 -14.047978)
		(end 150.108158 -14.047978)
		(width 0.11684)
		(layer "In4.Cu")
		(net "JTAG_SCM_TDI_R")
	)
	(segment
		(start 150.108158 -14.047978)
		(end 146.149568 -18.006568)
		(width 0.11684)
		(layer "In4.Cu")
		(net "JTAG_SCM_TDI_R")
	)
	(segment
		(start 101.10978 -34.516314)
		(end 101.10978 -36.71062)
		(width 0.10668)
		(layer "F.Cu")
		(net "IRQ_OCP_V3_2_WAKE_BUF_N")
	)
	(segment
		(start 101.341174 -34.28492)
		(end 101.10978 -34.516314)
		(width 0.10668)
		(layer "F.Cu")
		(net "IRQ_OCP_V3_2_WAKE_BUF_N")
	)
	(segment
		(start 101.10978 -36.71062)
		(end 100.47986 -37.34054)
		(width 0.10668)
		(layer "F.Cu")
		(net "IRQ_OCP_V3_2_WAKE_BUF_N")
	)
	(segment
		(start 157.15107 -74.35342)
		(end 157.15107 -72.46747)
		(width 0.10668)
		(layer "F.Cu")
		(net "IRQ_OCP_V3_2_WAKE_BUF_N")
	)
	(via
		(at 157.15107 -72.46747)
		(size 0.508)
		(drill 0.254)
		(layers "F.Cu" "B.Cu")
		(net "IRQ_OCP_V3_2_WAKE_BUF_N")
	)
	(via
		(at 100.47986 -37.34054)
		(size 0.508)
		(drill 0.254)
		(layers "F.Cu" "B.Cu")
		(net "IRQ_OCP_V3_2_WAKE_BUF_N")
	)
	(segment
		(start 107.8738 -41.930574)
		(end 103.961946 -38.01872)
		(width 0.10668)
		(layer "B.Cu")
		(net "IRQ_OCP_V3_2_WAKE_BUF_N")
	)
	(segment
		(start 149.832822 -53.769768)
		(end 148.627592 -53.769768)
		(width 0.10668)
		(layer "B.Cu")
		(net "IRQ_OCP_V3_2_WAKE_BUF_N")
	)
	(segment
		(start 121.967752 -44.74972)
		(end 109.95406 -44.74972)
		(width 0.10668)
		(layer "B.Cu")
		(net "IRQ_OCP_V3_2_WAKE_BUF_N")
	)
	(segment
		(start 147.834604 -52.97678)
		(end 138.087608 -52.97678)
		(width 0.10668)
		(layer "B.Cu")
		(net "IRQ_OCP_V3_2_WAKE_BUF_N")
	)
	(segment
		(start 123.753372 -46.53534)
		(end 121.967752 -44.74972)
		(width 0.10668)
		(layer "B.Cu")
		(net "IRQ_OCP_V3_2_WAKE_BUF_N")
	)
	(segment
		(start 103.36784 -38.01872)
		(end 103.01224 -38.37432)
		(width 0.10668)
		(layer "B.Cu")
		(net "IRQ_OCP_V3_2_WAKE_BUF_N")
	)
	(segment
		(start 109.95406 -44.74972)
		(end 107.8738 -42.66946)
		(width 0.10668)
		(layer "B.Cu")
		(net "IRQ_OCP_V3_2_WAKE_BUF_N")
	)
	(segment
		(start 101.51364 -38.37432)
		(end 100.47986 -37.34054)
		(width 0.10668)
		(layer "B.Cu")
		(net "IRQ_OCP_V3_2_WAKE_BUF_N")
	)
	(segment
		(start 103.01224 -38.37432)
		(end 101.51364 -38.37432)
		(width 0.10668)
		(layer "B.Cu")
		(net "IRQ_OCP_V3_2_WAKE_BUF_N")
	)
	(segment
		(start 128.937004 -47.293784)
		(end 128.17856 -46.53534)
		(width 0.10668)
		(layer "B.Cu")
		(net "IRQ_OCP_V3_2_WAKE_BUF_N")
	)
	(segment
		(start 148.627592 -53.769768)
		(end 147.834604 -52.97678)
		(width 0.10668)
		(layer "B.Cu")
		(net "IRQ_OCP_V3_2_WAKE_BUF_N")
	)
	(segment
		(start 157.15107 -61.088016)
		(end 149.832822 -53.769768)
		(width 0.10668)
		(layer "B.Cu")
		(net "IRQ_OCP_V3_2_WAKE_BUF_N")
	)
	(segment
		(start 107.8738 -42.66946)
		(end 107.8738 -41.930574)
		(width 0.10668)
		(layer "B.Cu")
		(net "IRQ_OCP_V3_2_WAKE_BUF_N")
	)
	(segment
		(start 103.961946 -38.01872)
		(end 103.36784 -38.01872)
		(width 0.10668)
		(layer "B.Cu")
		(net "IRQ_OCP_V3_2_WAKE_BUF_N")
	)
	(segment
		(start 138.087608 -52.97678)
		(end 132.404612 -47.293784)
		(width 0.10668)
		(layer "B.Cu")
		(net "IRQ_OCP_V3_2_WAKE_BUF_N")
	)
	(segment
		(start 128.17856 -46.53534)
		(end 123.753372 -46.53534)
		(width 0.10668)
		(layer "B.Cu")
		(net "IRQ_OCP_V3_2_WAKE_BUF_N")
	)
	(segment
		(start 132.404612 -47.293784)
		(end 128.937004 -47.293784)
		(width 0.10668)
		(layer "B.Cu")
		(net "IRQ_OCP_V3_2_WAKE_BUF_N")
	)
	(segment
		(start 157.15107 -72.46747)
		(end 157.15107 -61.088016)
		(width 0.10668)
		(layer "B.Cu")
		(net "IRQ_OCP_V3_2_WAKE_BUF_N")
	)
	(segment
		(start 164.142674 -39.777416)
		(end 162.815524 -41.104566)
		(width 0.10668)
		(layer "F.Cu")
		(net "IRQ_OCP_SFF_WAKE_BUF_N")
	)
	(segment
		(start 159.18307 -74.35342)
		(end 159.18307 -72.46747)
		(width 0.10668)
		(layer "F.Cu")
		(net "IRQ_OCP_SFF_WAKE_BUF_N")
	)
	(segment
		(start 164.142674 -38.894004)
		(end 164.142674 -39.777416)
		(width 0.10668)
		(layer "F.Cu")
		(net "IRQ_OCP_SFF_WAKE_BUF_N")
	)
	(via
		(at 159.18307 -72.46747)
		(size 0.762)
		(drill 0.254)
		(layers "F.Cu" "B.Cu")
		(net "IRQ_OCP_SFF_WAKE_BUF_N")
	)
	(via
		(at 162.815524 -41.104566)
		(size 0.508)
		(drill 0.254)
		(layers "F.Cu" "B.Cu")
		(net "IRQ_OCP_SFF_WAKE_BUF_N")
	)
	(segment
		(start 159.321246 -41.104566)
		(end 157.90037 -42.525442)
		(width 0.11684)
		(layer "In15.Cu")
		(net "IRQ_OCP_SFF_WAKE_BUF_N")
	)
	(segment
		(start 157.90037 -49.916334)
		(end 159.18307 -51.199034)
		(width 0.11684)
		(layer "In15.Cu")
		(net "IRQ_OCP_SFF_WAKE_BUF_N")
	)
	(segment
		(start 162.815524 -41.104566)
		(end 159.321246 -41.104566)
		(width 0.11684)
		(layer "In15.Cu")
		(net "IRQ_OCP_SFF_WAKE_BUF_N")
	)
	(segment
		(start 157.90037 -42.525442)
		(end 157.90037 -49.916334)
		(width 0.11684)
		(layer "In15.Cu")
		(net "IRQ_OCP_SFF_WAKE_BUF_N")
	)
	(segment
		(start 159.18307 -51.199034)
		(end 159.18307 -72.46747)
		(width 0.11684)
		(layer "In15.Cu")
		(net "IRQ_OCP_SFF_WAKE_BUF_N")
	)
	(segment
		(start 192.545208 -23.691342)
		(end 192.325752 -23.471886)
		(width 0.10668)
		(layer "F.Cu")
		(net "HP_LVC3_SCM_HSC_PWRGD")
	)
	(segment
		(start 192.325752 -23.471886)
		(end 192.325752 -23.324566)
		(width 0.10668)
		(layer "F.Cu")
		(net "HP_LVC3_SCM_HSC_PWRGD")
	)
	(segment
		(start 193.089022 -22.694392)
		(end 193.089022 -23.691342)
		(width 0.10668)
		(layer "F.Cu")
		(net "HP_LVC3_SCM_HSC_PWRGD")
	)
	(segment
		(start 209.294476 -109.561376)
		(end 209.924396 -109.561376)
		(width 0.10668)
		(layer "F.Cu")
		(net "HP_LVC3_SCM_HSC_PWRGD")
	)
	(segment
		(start 193.089022 -23.691342)
		(end 192.545208 -23.691342)
		(width 0.10668)
		(layer "F.Cu")
		(net "HP_LVC3_SCM_HSC_PWRGD")
	)
	(via
		(at 174.117 -31.496)
		(size 0.508)
		(drill 0.254)
		(layers "F.Cu" "B.Cu")
		(net "HP_LVC3_SCM_HSC_PWRGD")
	)
	(via
		(at 192.325752 -23.324566)
		(size 0.508)
		(drill 0.254)
		(layers "F.Cu" "B.Cu")
		(net "HP_LVC3_SCM_HSC_PWRGD")
	)
	(via
		(at 192.024 -36.957)
		(size 0.508)
		(drill 0.254)
		(layers "F.Cu" "B.Cu")
		(net "HP_LVC3_SCM_HSC_PWRGD")
	)
	(via
		(at 209.924396 -109.561376)
		(size 0.508)
		(drill 0.254)
		(layers "F.Cu" "B.Cu")
		(net "HP_LVC3_SCM_HSC_PWRGD")
	)
	(segment
		(start 173.62805 -30.49905)
		(end 174.117 -30.988)
		(width 0.10668)
		(layer "B.Cu")
		(net "HP_LVC3_SCM_HSC_PWRGD")
	)
	(segment
		(start 174.117 -30.988)
		(end 174.117 -31.496)
		(width 0.10668)
		(layer "B.Cu")
		(net "HP_LVC3_SCM_HSC_PWRGD")
	)
	(segment
		(start 173.101 -30.49905)
		(end 173.62805 -30.49905)
		(width 0.10668)
		(layer "B.Cu")
		(net "HP_LVC3_SCM_HSC_PWRGD")
	)
	(segment
		(start 199.096376 -85.543136)
		(end 199.096376 -87.197438)
		(width 0.11684)
		(layer "In11.Cu")
		(net "HP_LVC3_SCM_HSC_PWRGD")
	)
	(segment
		(start 189.463426 -27.779218)
		(end 188.917834 -28.32481)
		(width 0.11684)
		(layer "In11.Cu")
		(net "HP_LVC3_SCM_HSC_PWRGD")
	)
	(segment
		(start 197.350126 -83.796886)
		(end 199.096376 -85.543136)
		(width 0.11684)
		(layer "In11.Cu")
		(net "HP_LVC3_SCM_HSC_PWRGD")
	)
	(segment
		(start 209.924396 -108.493052)
		(end 209.924396 -109.561376)
		(width 0.11684)
		(layer "In11.Cu")
		(net "HP_LVC3_SCM_HSC_PWRGD")
	)
	(segment
		(start 207.22717 -92.565474)
		(end 207.22717 -96.959166)
		(width 0.11684)
		(layer "In11.Cu")
		(net "HP_LVC3_SCM_HSC_PWRGD")
	)
	(segment
		(start 193.504058 -78.917292)
		(end 196.759576 -78.917292)
		(width 0.11684)
		(layer "In11.Cu")
		(net "HP_LVC3_SCM_HSC_PWRGD")
	)
	(segment
		(start 208.93024 -103.593646)
		(end 209.20329 -103.866696)
		(width 0.11684)
		(layer "In11.Cu")
		(net "HP_LVC3_SCM_HSC_PWRGD")
	)
	(segment
		(start 190.13043 -21.864066)
		(end 189.463426 -22.53107)
		(width 0.11684)
		(layer "In11.Cu")
		(net "HP_LVC3_SCM_HSC_PWRGD")
	)
	(segment
		(start 191.044068 -76.457302)
		(end 193.504058 -78.917292)
		(width 0.11684)
		(layer "In11.Cu")
		(net "HP_LVC3_SCM_HSC_PWRGD")
	)
	(segment
		(start 192.621408 -42.515536)
		(end 191.802766 -43.334178)
		(width 0.11684)
		(layer "In11.Cu")
		(net "HP_LVC3_SCM_HSC_PWRGD")
	)
	(segment
		(start 191.802766 -43.334178)
		(end 191.802766 -44.161456)
		(width 0.11684)
		(layer "In11.Cu")
		(net "HP_LVC3_SCM_HSC_PWRGD")
	)
	(segment
		(start 207.22717 -96.959166)
		(end 208.264506 -97.996502)
		(width 0.11684)
		(layer "In11.Cu")
		(net "HP_LVC3_SCM_HSC_PWRGD")
	)
	(segment
		(start 209.20329 -107.771946)
		(end 209.924396 -108.493052)
		(width 0.11684)
		(layer "In11.Cu")
		(net "HP_LVC3_SCM_HSC_PWRGD")
	)
	(segment
		(start 208.93024 -102.780846)
		(end 208.93024 -103.593646)
		(width 0.11684)
		(layer "In11.Cu")
		(net "HP_LVC3_SCM_HSC_PWRGD")
	)
	(segment
		(start 209.20329 -103.866696)
		(end 209.20329 -107.771946)
		(width 0.11684)
		(layer "In11.Cu")
		(net "HP_LVC3_SCM_HSC_PWRGD")
	)
	(segment
		(start 192.024 -33.558734)
		(end 192.024 -36.957)
		(width 0.11684)
		(layer "In11.Cu")
		(net "HP_LVC3_SCM_HSC_PWRGD")
	)
	(segment
		(start 209.17027 -100.496878)
		(end 209.17027 -102.540816)
		(width 0.11684)
		(layer "In11.Cu")
		(net "HP_LVC3_SCM_HSC_PWRGD")
	)
	(segment
		(start 190.865252 -21.864066)
		(end 190.13043 -21.864066)
		(width 0.11684)
		(layer "In11.Cu")
		(net "HP_LVC3_SCM_HSC_PWRGD")
	)
	(segment
		(start 200.888854 -88.989916)
		(end 203.651612 -88.989916)
		(width 0.11684)
		(layer "In11.Cu")
		(net "HP_LVC3_SCM_HSC_PWRGD")
	)
	(segment
		(start 189.980062 -74.467212)
		(end 191.044068 -76.457302)
		(width 0.11684)
		(layer "In11.Cu")
		(net "HP_LVC3_SCM_HSC_PWRGD")
	)
	(segment
		(start 192.024 -36.957)
		(end 192.621408 -37.554408)
		(width 0.11684)
		(layer "In11.Cu")
		(net "HP_LVC3_SCM_HSC_PWRGD")
	)
	(segment
		(start 197.350126 -79.507842)
		(end 197.350126 -83.796886)
		(width 0.11684)
		(layer "In11.Cu")
		(net "HP_LVC3_SCM_HSC_PWRGD")
	)
	(segment
		(start 188.917834 -30.452568)
		(end 192.024 -33.558734)
		(width 0.11684)
		(layer "In11.Cu")
		(net "HP_LVC3_SCM_HSC_PWRGD")
	)
	(segment
		(start 208.264506 -97.996502)
		(end 208.264506 -99.591114)
		(width 0.11684)
		(layer "In11.Cu")
		(net "HP_LVC3_SCM_HSC_PWRGD")
	)
	(segment
		(start 192.325752 -23.324566)
		(end 190.865252 -21.864066)
		(width 0.11684)
		(layer "In11.Cu")
		(net "HP_LVC3_SCM_HSC_PWRGD")
	)
	(segment
		(start 196.759576 -78.917292)
		(end 197.350126 -79.507842)
		(width 0.11684)
		(layer "In11.Cu")
		(net "HP_LVC3_SCM_HSC_PWRGD")
	)
	(segment
		(start 199.096376 -87.197438)
		(end 200.888854 -88.989916)
		(width 0.11684)
		(layer "In11.Cu")
		(net "HP_LVC3_SCM_HSC_PWRGD")
	)
	(segment
		(start 192.621408 -37.554408)
		(end 192.621408 -42.515536)
		(width 0.11684)
		(layer "In11.Cu")
		(net "HP_LVC3_SCM_HSC_PWRGD")
	)
	(segment
		(start 209.17027 -102.540816)
		(end 208.93024 -102.780846)
		(width 0.11684)
		(layer "In11.Cu")
		(net "HP_LVC3_SCM_HSC_PWRGD")
	)
	(segment
		(start 189.463426 -22.53107)
		(end 189.463426 -27.779218)
		(width 0.11684)
		(layer "In11.Cu")
		(net "HP_LVC3_SCM_HSC_PWRGD")
	)
	(segment
		(start 203.651612 -88.989916)
		(end 207.22717 -92.565474)
		(width 0.11684)
		(layer "In11.Cu")
		(net "HP_LVC3_SCM_HSC_PWRGD")
	)
	(segment
		(start 188.917834 -28.32481)
		(end 188.917834 -30.452568)
		(width 0.11684)
		(layer "In11.Cu")
		(net "HP_LVC3_SCM_HSC_PWRGD")
	)
	(segment
		(start 189.980062 -45.98416)
		(end 189.980062 -74.467212)
		(width 0.11684)
		(layer "In11.Cu")
		(net "HP_LVC3_SCM_HSC_PWRGD")
	)
	(segment
		(start 191.802766 -44.161456)
		(end 189.980062 -45.98416)
		(width 0.11684)
		(layer "In11.Cu")
		(net "HP_LVC3_SCM_HSC_PWRGD")
	)
	(segment
		(start 208.264506 -99.591114)
		(end 209.17027 -100.496878)
		(width 0.11684)
		(layer "In11.Cu")
		(net "HP_LVC3_SCM_HSC_PWRGD")
	)
	(segment
		(start 176.011078 -31.862522)
		(end 176.011078 -32.245046)
		(width 0.11684)
		(layer "In15.Cu")
		(net "HP_LVC3_SCM_HSC_PWRGD")
	)
	(segment
		(start 185.921904 -36.383468)
		(end 186.495436 -36.957)
		(width 0.11684)
		(layer "In15.Cu")
		(net "HP_LVC3_SCM_HSC_PWRGD")
	)
	(segment
		(start 175.644556 -31.496)
		(end 176.011078 -31.862522)
		(width 0.11684)
		(layer "In15.Cu")
		(net "HP_LVC3_SCM_HSC_PWRGD")
	)
	(segment
		(start 186.495436 -36.957)
		(end 192.024 -36.957)
		(width 0.11684)
		(layer "In15.Cu")
		(net "HP_LVC3_SCM_HSC_PWRGD")
	)
	(segment
		(start 176.011078 -32.245046)
		(end 180.1495 -36.383468)
		(width 0.11684)
		(layer "In15.Cu")
		(net "HP_LVC3_SCM_HSC_PWRGD")
	)
	(segment
		(start 174.117 -31.496)
		(end 175.644556 -31.496)
		(width 0.11684)
		(layer "In15.Cu")
		(net "HP_LVC3_SCM_HSC_PWRGD")
	)
	(segment
		(start 180.1495 -36.383468)
		(end 185.921904 -36.383468)
		(width 0.11684)
		(layer "In15.Cu")
		(net "HP_LVC3_SCM_HSC_PWRGD")
	)
	(segment
		(start 185.122058 -108.252768)
		(end 184.732168 -107.862878)
		(width 0.10668)
		(layer "F.Cu")
		(net "FM_THERMAL_ALERT_R_N")
	)
	(segment
		(start 183.71566 -93.074998)
		(end 183.141874 -93.648784)
		(width 0.10668)
		(layer "F.Cu")
		(net "FM_THERMAL_ALERT_R_N")
	)
	(segment
		(start 183.769 -93.074998)
		(end 183.71566 -93.074998)
		(width 0.10668)
		(layer "F.Cu")
		(net "FM_THERMAL_ALERT_R_N")
	)
	(segment
		(start 183.141874 -93.648784)
		(end 182.795164 -93.648784)
		(width 0.10668)
		(layer "F.Cu")
		(net "FM_THERMAL_ALERT_R_N")
	)
	(segment
		(start 182.795164 -93.648784)
		(end 182.753 -93.690948)
		(width 0.10668)
		(layer "F.Cu")
		(net "FM_THERMAL_ALERT_R_N")
	)
	(via
		(at 184.732168 -107.862878)
		(size 0.4572)
		(drill 0.254)
		(layers "F.Cu" "B.Cu")
		(net "FM_THERMAL_ALERT_R_N")
	)
	(via
		(at 182.753 -93.690948)
		(size 0.508)
		(drill 0.254)
		(layers "F.Cu" "B.Cu")
		(net "FM_THERMAL_ALERT_R_N")
	)
	(segment
		(start 183.2102 -103.19258)
		(end 184.3405 -104.32288)
		(width 0.11684)
		(layer "In11.Cu")
		(net "FM_THERMAL_ALERT_R_N")
	)
	(segment
		(start 182.753 -93.690948)
		(end 182.753 -94.140782)
		(width 0.11684)
		(layer "In11.Cu")
		(net "FM_THERMAL_ALERT_R_N")
	)
	(segment
		(start 183.237124 -95.67545)
		(end 182.940198 -95.972376)
		(width 0.11684)
		(layer "In11.Cu")
		(net "FM_THERMAL_ALERT_R_N")
	)
	(segment
		(start 183.279542 -100.04552)
		(end 183.2102 -100.114862)
		(width 0.11684)
		(layer "In11.Cu")
		(net "FM_THERMAL_ALERT_R_N")
	)
	(segment
		(start 183.237124 -94.624906)
		(end 183.237124 -95.67545)
		(width 0.11684)
		(layer "In11.Cu")
		(net "FM_THERMAL_ALERT_R_N")
	)
	(segment
		(start 184.3405 -107.48264)
		(end 184.720738 -107.862878)
		(width 0.11684)
		(layer "In11.Cu")
		(net "FM_THERMAL_ALERT_R_N")
	)
	(segment
		(start 182.940198 -95.972376)
		(end 182.940198 -97.616518)
		(width 0.11684)
		(layer "In11.Cu")
		(net "FM_THERMAL_ALERT_R_N")
	)
	(segment
		(start 182.753 -94.140782)
		(end 183.237124 -94.624906)
		(width 0.11684)
		(layer "In11.Cu")
		(net "FM_THERMAL_ALERT_R_N")
	)
	(segment
		(start 183.279542 -97.955862)
		(end 183.279542 -100.04552)
		(width 0.11684)
		(layer "In11.Cu")
		(net "FM_THERMAL_ALERT_R_N")
	)
	(segment
		(start 182.940198 -97.616518)
		(end 183.279542 -97.955862)
		(width 0.11684)
		(layer "In11.Cu")
		(net "FM_THERMAL_ALERT_R_N")
	)
	(segment
		(start 183.2102 -100.114862)
		(end 183.2102 -103.19258)
		(width 0.11684)
		(layer "In11.Cu")
		(net "FM_THERMAL_ALERT_R_N")
	)
	(segment
		(start 184.3405 -104.32288)
		(end 184.3405 -107.48264)
		(width 0.11684)
		(layer "In11.Cu")
		(net "FM_THERMAL_ALERT_R_N")
	)
	(segment
		(start 184.720738 -107.862878)
		(end 184.732168 -107.862878)
		(width 0.11684)
		(layer "In11.Cu")
		(net "FM_THERMAL_ALERT_R_N")
	)
	(segment
		(start 187.833 -95.703898)
		(end 187.833 -95.087948)
		(width 0.10668)
		(layer "F.Cu")
		(net "FM_SMB_RST_E1S_0_R_N")
	)
	(segment
		(start 250.065286 -75.092814)
		(end 250.065286 -77.120242)
		(width 0.10668)
		(layer "F.Cu")
		(net "FM_SMB_RST_E1S_0_R_N")
	)
	(via
		(at 233.684572 -92.170758)
		(size 0.508)
		(drill 0.254)
		(layers "F.Cu" "B.Cu")
		(net "FM_SMB_RST_E1S_0_R_N")
	)
	(via
		(at 187.833 -95.087948)
		(size 0.508)
		(drill 0.254)
		(layers "F.Cu" "B.Cu")
		(net "FM_SMB_RST_E1S_0_R_N")
	)
	(via
		(at 250.065286 -77.120242)
		(size 0.508)
		(drill 0.254)
		(layers "F.Cu" "B.Cu")
		(net "FM_SMB_RST_E1S_0_R_N")
	)
	(segment
		(start 233.684572 -91.866974)
		(end 242.823492 -82.728054)
		(width 0.11684)
		(layer "In4.Cu")
		(net "FM_SMB_RST_E1S_0_R_N")
	)
	(segment
		(start 249.44705 -76.502006)
		(end 250.065286 -77.120242)
		(width 0.11684)
		(layer "In4.Cu")
		(net "FM_SMB_RST_E1S_0_R_N")
	)
	(segment
		(start 247.691148 -76.502006)
		(end 249.44705 -76.502006)
		(width 0.11684)
		(layer "In4.Cu")
		(net "FM_SMB_RST_E1S_0_R_N")
	)
	(segment
		(start 242.823492 -82.728054)
		(end 242.823492 -81.369662)
		(width 0.11684)
		(layer "In4.Cu")
		(net "FM_SMB_RST_E1S_0_R_N")
	)
	(segment
		(start 233.684572 -92.170758)
		(end 233.684572 -91.866974)
		(width 0.11684)
		(layer "In4.Cu")
		(net "FM_SMB_RST_E1S_0_R_N")
	)
	(segment
		(start 242.823492 -81.369662)
		(end 247.691148 -76.502006)
		(width 0.11684)
		(layer "In4.Cu")
		(net "FM_SMB_RST_E1S_0_R_N")
	)
	(segment
		(start 188.310774 -93.274388)
		(end 188.310774 -94.026228)
		(width 0.11684)
		(layer "In15.Cu")
		(net "FM_SMB_RST_E1S_0_R_N")
	)
	(segment
		(start 193.082926 -92.295726)
		(end 189.289436 -92.295726)
		(width 0.11684)
		(layer "In15.Cu")
		(net "FM_SMB_RST_E1S_0_R_N")
	)
	(segment
		(start 203.198222 -94.178628)
		(end 202.920092 -93.900498)
		(width 0.11684)
		(layer "In15.Cu")
		(net "FM_SMB_RST_E1S_0_R_N")
	)
	(segment
		(start 193.735452 -91.6432)
		(end 193.082926 -92.295726)
		(width 0.11684)
		(layer "In15.Cu")
		(net "FM_SMB_RST_E1S_0_R_N")
	)
	(segment
		(start 204.653134 -94.178628)
		(end 203.198222 -94.178628)
		(width 0.11684)
		(layer "In15.Cu")
		(net "FM_SMB_RST_E1S_0_R_N")
	)
	(segment
		(start 233.596688 -92.082874)
		(end 206.748888 -92.082874)
		(width 0.11684)
		(layer "In15.Cu")
		(net "FM_SMB_RST_E1S_0_R_N")
	)
	(segment
		(start 206.748888 -92.082874)
		(end 204.653134 -94.178628)
		(width 0.11684)
		(layer "In15.Cu")
		(net "FM_SMB_RST_E1S_0_R_N")
	)
	(segment
		(start 202.920092 -93.900498)
		(end 197.964552 -93.900498)
		(width 0.11684)
		(layer "In15.Cu")
		(net "FM_SMB_RST_E1S_0_R_N")
	)
	(segment
		(start 233.684572 -92.170758)
		(end 233.596688 -92.082874)
		(width 0.11684)
		(layer "In15.Cu")
		(net "FM_SMB_RST_E1S_0_R_N")
	)
	(segment
		(start 187.833 -94.504002)
		(end 187.833 -95.087948)
		(width 0.11684)
		(layer "In15.Cu")
		(net "FM_SMB_RST_E1S_0_R_N")
	)
	(segment
		(start 189.289436 -92.295726)
		(end 188.310774 -93.274388)
		(width 0.11684)
		(layer "In15.Cu")
		(net "FM_SMB_RST_E1S_0_R_N")
	)
	(segment
		(start 195.707254 -91.6432)
		(end 193.735452 -91.6432)
		(width 0.11684)
		(layer "In15.Cu")
		(net "FM_SMB_RST_E1S_0_R_N")
	)
	(segment
		(start 188.310774 -94.026228)
		(end 187.833 -94.504002)
		(width 0.11684)
		(layer "In15.Cu")
		(net "FM_SMB_RST_E1S_0_R_N")
	)
	(segment
		(start 197.964552 -93.900498)
		(end 195.707254 -91.6432)
		(width 0.11684)
		(layer "In15.Cu")
		(net "FM_SMB_RST_E1S_0_R_N")
	)
	(segment
		(start 181.122066 -109.052868)
		(end 180.732176 -108.662978)
		(width 0.10668)
		(layer "F.Cu")
		(net "FM_BMC_READY_R_N")
	)
	(via
		(at 180.732176 -108.662978)
		(size 0.4572)
		(drill 0.254)
		(layers "F.Cu" "B.Cu")
		(net "FM_BMC_READY_R_N")
	)
	(via
		(at 179.235608 -104.638348)
		(size 0.6604)
		(drill 0.3302)
		(layers "F.Cu" "B.Cu")
		(net "FM_BMC_READY_R_N")
	)
	(segment
		(start 179.53609 -108.027216)
		(end 179.767992 -108.259118)
		(width 0.10668)
		(layer "B.Cu")
		(net "FM_BMC_READY_R_N")
	)
	(segment
		(start 179.235608 -104.638348)
		(end 179.235608 -105.310432)
		(width 0.10668)
		(layer "B.Cu")
		(net "FM_BMC_READY_R_N")
	)
	(segment
		(start 180.089048 -108.259118)
		(end 180.492908 -108.662978)
		(width 0.10668)
		(layer "B.Cu")
		(net "FM_BMC_READY_R_N")
	)
	(segment
		(start 179.05984 -107.2134)
		(end 179.53609 -107.68965)
		(width 0.10668)
		(layer "B.Cu")
		(net "FM_BMC_READY_R_N")
	)
	(segment
		(start 179.235608 -104.638348)
		(end 178.193192 -103.595932)
		(width 0.10668)
		(layer "B.Cu")
		(net "FM_BMC_READY_R_N")
	)
	(segment
		(start 179.53609 -107.68965)
		(end 179.53609 -108.027216)
		(width 0.10668)
		(layer "B.Cu")
		(net "FM_BMC_READY_R_N")
	)
	(segment
		(start 179.235608 -105.310432)
		(end 179.05984 -105.4862)
		(width 0.10668)
		(layer "B.Cu")
		(net "FM_BMC_READY_R_N")
	)
	(segment
		(start 178.193192 -103.126286)
		(end 176.657 -101.590094)
		(width 0.10668)
		(layer "B.Cu")
		(net "FM_BMC_READY_R_N")
	)
	(segment
		(start 180.492908 -108.662978)
		(end 180.732176 -108.662978)
		(width 0.10668)
		(layer "B.Cu")
		(net "FM_BMC_READY_R_N")
	)
	(segment
		(start 179.767992 -108.259118)
		(end 180.089048 -108.259118)
		(width 0.10668)
		(layer "B.Cu")
		(net "FM_BMC_READY_R_N")
	)
	(segment
		(start 179.05984 -105.4862)
		(end 179.05984 -107.2134)
		(width 0.10668)
		(layer "B.Cu")
		(net "FM_BMC_READY_R_N")
	)
	(segment
		(start 176.657 -101.590094)
		(end 176.657 -100.694998)
		(width 0.10668)
		(layer "B.Cu")
		(net "FM_BMC_READY_R_N")
	)
	(segment
		(start 178.193192 -103.595932)
		(end 178.193192 -103.126286)
		(width 0.10668)
		(layer "B.Cu")
		(net "FM_BMC_READY_R_N")
	)
	(segment
		(start 190.31077 -96.503998)
		(end 191.722502 -95.092266)
		(width 0.10668)
		(layer "F.Cu")
		(net "FM_PDB_BUF_EN_N")
	)
	(segment
		(start 189.12205 -109.852968)
		(end 189.51194 -109.463078)
		(width 0.10668)
		(layer "F.Cu")
		(net "FM_PDB_BUF_EN_N")
	)
	(segment
		(start 189.865 -96.503998)
		(end 190.31077 -96.503998)
		(width 0.10668)
		(layer "F.Cu")
		(net "FM_PDB_BUF_EN_N")
	)
	(segment
		(start 191.722502 -95.092266)
		(end 191.722502 -95.087948)
		(width 0.10668)
		(layer "F.Cu")
		(net "FM_PDB_BUF_EN_N")
	)
	(via
		(at 189.51194 -109.463078)
		(size 0.4572)
		(drill 0.254)
		(layers "F.Cu" "B.Cu")
		(net "FM_PDB_BUF_EN_N")
	)
	(via
		(at 191.722502 -95.087948)
		(size 0.508)
		(drill 0.254)
		(layers "F.Cu" "B.Cu")
		(net "FM_PDB_BUF_EN_N")
	)
	(segment
		(start 191.393572 -99.9236)
		(end 191.393572 -95.416878)
		(width 0.11684)
		(layer "In4.Cu")
		(net "FM_PDB_BUF_EN_N")
	)
	(segment
		(start 189.901322 -105.883202)
		(end 191.86398 -103.920544)
		(width 0.11684)
		(layer "In4.Cu")
		(net "FM_PDB_BUF_EN_N")
	)
	(segment
		(start 191.393572 -95.416878)
		(end 191.722502 -95.087948)
		(width 0.11684)
		(layer "In4.Cu")
		(net "FM_PDB_BUF_EN_N")
	)
	(segment
		(start 191.86398 -100.394008)
		(end 191.393572 -99.9236)
		(width 0.11684)
		(layer "In4.Cu")
		(net "FM_PDB_BUF_EN_N")
	)
	(segment
		(start 189.901322 -109.162088)
		(end 189.901322 -105.883202)
		(width 0.11684)
		(layer "In4.Cu")
		(net "FM_PDB_BUF_EN_N")
	)
	(segment
		(start 189.51194 -109.463078)
		(end 189.600332 -109.463078)
		(width 0.11684)
		(layer "In4.Cu")
		(net "FM_PDB_BUF_EN_N")
	)
	(segment
		(start 189.600332 -109.463078)
		(end 189.901322 -109.162088)
		(width 0.11684)
		(layer "In4.Cu")
		(net "FM_PDB_BUF_EN_N")
	)
	(segment
		(start 191.86398 -103.920544)
		(end 191.86398 -100.394008)
		(width 0.11684)
		(layer "In4.Cu")
		(net "FM_PDB_BUF_EN_N")
	)
	(segment
		(start 306.226972 -47.991268)
		(end 306.226972 -47.553372)
		(width 0.10668)
		(layer "F.Cu")
		(net "ADC128_VREF")
	)
	(segment
		(start 306.226972 -47.553372)
		(end 306.219098 -47.037498)
		(width 0.10668)
		(layer "F.Cu")
		(net "ADC128_VREF")
	)
	(segment
		(start 309.334154 -45.738288)
		(end 309.925212 -45.738288)
		(width 0.10668)
		(layer "F.Cu")
		(net "ADC128_VREF")
	)
	(segment
		(start 307.894228 -47.037498)
		(end 308.034944 -47.037498)
		(width 0.10668)
		(layer "F.Cu")
		(net "ADC128_VREF")
	)
	(segment
		(start 308.034944 -47.037498)
		(end 309.334154 -45.738288)
		(width 0.10668)
		(layer "F.Cu")
		(net "ADC128_VREF")
	)
	(segment
		(start 306.219098 -47.037498)
		(end 307.894228 -47.037498)
		(width 0.10668)
		(layer "F.Cu")
		(net "ADC128_VREF")
	)
	(via
		(at 307.894228 -47.037498)
		(size 0.762)
		(drill 0.381)
		(layers "F.Cu" "B.Cu")
		(net "ADC128_VREF")
	)
	(segment
		(start 306.219098 -40.890698)
		(end 307.218842 -39.890954)
		(width 0.10668)
		(layer "F.Cu")
		(net "ADC128_A1")
	)
	(segment
		(start 305.473354 -40.144954)
		(end 304.346102 -40.144954)
		(width 0.10668)
		(layer "F.Cu")
		(net "ADC128_A1")
	)
	(segment
		(start 306.219098 -40.890698)
		(end 305.473354 -40.144954)
		(width 0.10668)
		(layer "F.Cu")
		(net "ADC128_A1")
	)
	(segment
		(start 304.346102 -40.144954)
		(end 303.600358 -40.890698)
		(width 0.10668)
		(layer "F.Cu")
		(net "ADC128_A1")
	)
	(segment
		(start 309.172356 -41.188132)
		(end 309.925212 -41.188132)
		(width 0.10668)
		(layer "F.Cu")
		(net "ADC128_A1")
	)
	(segment
		(start 307.494178 -39.890954)
		(end 307.875178 -39.890954)
		(width 0.10668)
		(layer "F.Cu")
		(net "ADC128_A1")
	)
	(segment
		(start 307.218842 -39.890954)
		(end 307.494178 -39.890954)
		(width 0.10668)
		(layer "F.Cu")
		(net "ADC128_A1")
	)
	(segment
		(start 307.875178 -39.890954)
		(end 309.172356 -41.188132)
		(width 0.10668)
		(layer "F.Cu")
		(net "ADC128_A1")
	)
	(via
		(at 307.494178 -39.890954)
		(size 0.762)
		(drill 0.381)
		(layers "F.Cu" "B.Cu")
		(net "ADC128_A1")
	)
	(segment
		(start 305.727354 -41.414954)
		(end 304.092102 -41.414954)
		(width 0.10668)
		(layer "F.Cu")
		(net "ADC128_A0")
	)
	(segment
		(start 306.219098 -41.906698)
		(end 307.091842 -41.033954)
		(width 0.10668)
		(layer "F.Cu")
		(net "ADC128_A0")
	)
	(segment
		(start 306.219098 -41.906698)
		(end 305.727354 -41.414954)
		(width 0.10668)
		(layer "F.Cu")
		(net "ADC128_A0")
	)
	(segment
		(start 304.092102 -41.414954)
		(end 303.600358 -41.906698)
		(width 0.10668)
		(layer "F.Cu")
		(net "ADC128_A0")
	)
	(segment
		(start 308.129178 -41.033954)
		(end 308.933342 -41.838118)
		(width 0.10668)
		(layer "F.Cu")
		(net "ADC128_A0")
	)
	(segment
		(start 307.091842 -41.033954)
		(end 308.129178 -41.033954)
		(width 0.10668)
		(layer "F.Cu")
		(net "ADC128_A0")
	)
	(segment
		(start 308.933342 -41.838118)
		(end 309.925212 -41.838118)
		(width 0.10668)
		(layer "F.Cu")
		(net "ADC128_A0")
	)
	(via
		(at 308.129178 -41.033954)
		(size 0.762)
		(drill 0.381)
		(layers "F.Cu" "B.Cu")
		(net "ADC128_A0")
	)
	(segment
		(start 203.476606 -340.255098)
		(end 202.254104 -340.255098)
		(width 0.1778)
		(layer "F.Cu")
		(net "PVDD_33_S5_MODE")
	)
	(segment
		(start 203.609956 -340.121748)
		(end 203.476606 -340.255098)
		(width 0.2032)
		(layer "F.Cu")
		(net "PVDD_33_S5_MODE")
	)
	(via
		(at 203.609956 -340.121748)
		(size 0.508)
		(drill 0.254)
		(layers "F.Cu" "B.Cu")
		(net "PVDD_33_S5_MODE")
	)
	(segment
		(start 203.609956 -340.121748)
		(end 204.297534 -340.809326)
		(width 0.10668)
		(layer "B.Cu")
		(net "PVDD_33_S5_MODE")
	)
	(segment
		(start 204.297534 -340.809326)
		(end 204.297534 -341.853012)
		(width 0.10668)
		(layer "B.Cu")
		(net "PVDD_33_S5_MODE")
	)
	(segment
		(start 183.522112 -122.65279)
		(end 183.132222 -123.04268)
		(width 0.10668)
		(layer "F.Cu")
		(net "TP_SLOT2_CLKREQ_0_R_N")
	)
	(via
		(at 183.132222 -123.04268)
		(size 0.4572)
		(drill 0.254)
		(layers "F.Cu" "B.Cu")
		(net "TP_SLOT2_CLKREQ_0_R_N")
	)
	(segment
		(start 181.122066 -120.252744)
		(end 180.732176 -120.642634)
		(width 0.10668)
		(layer "F.Cu")
		(net "TP_SLOT1_CLKREQ_0_R_N")
	)
	(via
		(at 180.732176 -120.642634)
		(size 0.4572)
		(drill 0.254)
		(layers "F.Cu" "B.Cu")
		(net "TP_SLOT1_CLKREQ_0_R_N")
	)
	(segment
		(start 190.721996 -121.052844)
		(end 191.111886 -121.442734)
		(width 0.10668)
		(layer "F.Cu")
		(net "TP_FM_CLK_BUFFER_EN_R")
	)
	(via
		(at 191.111886 -121.442734)
		(size 0.4572)
		(drill 0.254)
		(layers "F.Cu" "B.Cu")
		(net "TP_FM_CLK_BUFFER_EN_R")
	)
	(segment
		(start 143.740632 -101.244146)
		(end 143.054832 -101.244146)
		(width 0.10668)
		(layer "F.Cu")
		(net "RST_PERST_M2_0_N")
	)
	(segment
		(start 199.866758 -119.721376)
		(end 200.552558 -119.721376)
		(width 0.10668)
		(layer "F.Cu")
		(net "RST_PERST_M2_0_N")
	)
	(segment
		(start 197.669658 -119.975376)
		(end 197.875398 -120.181116)
		(width 0.10668)
		(layer "F.Cu")
		(net "RST_PERST_M2_0_N")
	)
	(segment
		(start 200.552558 -120.074436)
		(end 200.552558 -119.721376)
		(width 0.10668)
		(layer "F.Cu")
		(net "RST_PERST_M2_0_N")
	)
	(segment
		(start 200.445878 -120.181116)
		(end 200.552558 -120.074436)
		(width 0.10668)
		(layer "F.Cu")
		(net "RST_PERST_M2_0_N")
	)
	(segment
		(start 197.875398 -120.181116)
		(end 200.445878 -120.181116)
		(width 0.10668)
		(layer "F.Cu")
		(net "RST_PERST_M2_0_N")
	)
	(segment
		(start 143.054832 -101.244146)
		(end 142.800832 -100.990146)
		(width 0.10668)
		(layer "F.Cu")
		(net "RST_PERST_M2_0_N")
	)
	(via
		(at 142.800832 -100.990146)
		(size 0.508)
		(drill 0.254)
		(layers "F.Cu" "B.Cu")
		(net "RST_PERST_M2_0_N")
	)
	(via
		(at 166.835328 -146.61007)
		(size 0.508)
		(drill 0.254)
		(layers "F.Cu" "B.Cu")
		(net "RST_PERST_M2_0_N")
	)
	(via
		(at 199.866758 -119.721376)
		(size 0.508)
		(drill 0.254)
		(layers "F.Cu" "B.Cu")
		(net "RST_PERST_M2_0_N")
	)
	(via
		(at 197.549516 -141.91996)
		(size 0.508)
		(drill 0.254)
		(layers "F.Cu" "B.Cu")
		(net "RST_PERST_M2_0_N")
	)
	(segment
		(start 197.281038 -142.188438)
		(end 192.006728 -142.188438)
		(width 0.11684)
		(layer "In2.Cu")
		(net "RST_PERST_M2_0_N")
	)
	(segment
		(start 170.750738 -144.82953)
		(end 168.970198 -146.61007)
		(width 0.11684)
		(layer "In2.Cu")
		(net "RST_PERST_M2_0_N")
	)
	(segment
		(start 186.809888 -143.78178)
		(end 182.338218 -143.78178)
		(width 0.11684)
		(layer "In2.Cu")
		(net "RST_PERST_M2_0_N")
	)
	(segment
		(start 197.549516 -141.91996)
		(end 197.281038 -142.188438)
		(width 0.11684)
		(layer "In2.Cu")
		(net "RST_PERST_M2_0_N")
	)
	(segment
		(start 187.235338 -143.35633)
		(end 186.809888 -143.78178)
		(width 0.11684)
		(layer "In2.Cu")
		(net "RST_PERST_M2_0_N")
	)
	(segment
		(start 192.006728 -142.188438)
		(end 190.838836 -143.35633)
		(width 0.11684)
		(layer "In2.Cu")
		(net "RST_PERST_M2_0_N")
	)
	(segment
		(start 182.338218 -143.78178)
		(end 181.290468 -144.82953)
		(width 0.11684)
		(layer "In2.Cu")
		(net "RST_PERST_M2_0_N")
	)
	(segment
		(start 181.290468 -144.82953)
		(end 170.750738 -144.82953)
		(width 0.11684)
		(layer "In2.Cu")
		(net "RST_PERST_M2_0_N")
	)
	(segment
		(start 190.838836 -143.35633)
		(end 187.235338 -143.35633)
		(width 0.11684)
		(layer "In2.Cu")
		(net "RST_PERST_M2_0_N")
	)
	(segment
		(start 168.970198 -146.61007)
		(end 166.835328 -146.61007)
		(width 0.11684)
		(layer "In2.Cu")
		(net "RST_PERST_M2_0_N")
	)
	(segment
		(start 196.85381 -121.085356)
		(end 196.85381 -126.624842)
		(width 0.11684)
		(layer "In4.Cu")
		(net "RST_PERST_M2_0_N")
	)
	(segment
		(start 199.32269 -120.197118)
		(end 197.742048 -120.197118)
		(width 0.11684)
		(layer "In4.Cu")
		(net "RST_PERST_M2_0_N")
	)
	(segment
		(start 198.3105 -128.081532)
		(end 198.3105 -129.477516)
		(width 0.11684)
		(layer "In4.Cu")
		(net "RST_PERST_M2_0_N")
	)
	(segment
		(start 199.798432 -119.721376)
		(end 199.32269 -120.197118)
		(width 0.11684)
		(layer "In4.Cu")
		(net "RST_PERST_M2_0_N")
	)
	(segment
		(start 196.85381 -126.624842)
		(end 198.3105 -128.081532)
		(width 0.11684)
		(layer "In4.Cu")
		(net "RST_PERST_M2_0_N")
	)
	(segment
		(start 199.866758 -119.721376)
		(end 199.798432 -119.721376)
		(width 0.11684)
		(layer "In4.Cu")
		(net "RST_PERST_M2_0_N")
	)
	(segment
		(start 198.3105 -129.477516)
		(end 199.094852 -130.261868)
		(width 0.11684)
		(layer "In4.Cu")
		(net "RST_PERST_M2_0_N")
	)
	(segment
		(start 199.094852 -140.374624)
		(end 197.549516 -141.91996)
		(width 0.11684)
		(layer "In4.Cu")
		(net "RST_PERST_M2_0_N")
	)
	(segment
		(start 199.094852 -130.261868)
		(end 199.094852 -140.374624)
		(width 0.11684)
		(layer "In4.Cu")
		(net "RST_PERST_M2_0_N")
	)
	(segment
		(start 197.742048 -120.197118)
		(end 196.85381 -121.085356)
		(width 0.11684)
		(layer "In4.Cu")
		(net "RST_PERST_M2_0_N")
	)
	(segment
		(start 147.528026 -115.283742)
		(end 147.528026 -112.150398)
		(width 0.11684)
		(layer "In15.Cu")
		(net "RST_PERST_M2_0_N")
	)
	(segment
		(start 147.528026 -112.150398)
		(end 148.62556 -111.052864)
		(width 0.11684)
		(layer "In15.Cu")
		(net "RST_PERST_M2_0_N")
	)
	(segment
		(start 166.835328 -146.61007)
		(end 166.032434 -145.807176)
		(width 0.11684)
		(layer "In15.Cu")
		(net "RST_PERST_M2_0_N")
	)
	(segment
		(start 147.19427 -118.862602)
		(end 147.327112 -118.72976)
		(width 0.11684)
		(layer "In15.Cu")
		(net "RST_PERST_M2_0_N")
	)
	(segment
		(start 144.628362 -100.942394)
		(end 142.848584 -100.942394)
		(width 0.11684)
		(layer "In15.Cu")
		(net "RST_PERST_M2_0_N")
	)
	(segment
		(start 166.032434 -145.807176)
		(end 166.032434 -143.168624)
		(width 0.11684)
		(layer "In15.Cu")
		(net "RST_PERST_M2_0_N")
	)
	(segment
		(start 148.62556 -111.052864)
		(end 148.62556 -104.939592)
		(width 0.11684)
		(layer "In15.Cu")
		(net "RST_PERST_M2_0_N")
	)
	(segment
		(start 166.032434 -143.168624)
		(end 147.19427 -124.33046)
		(width 0.11684)
		(layer "In15.Cu")
		(net "RST_PERST_M2_0_N")
	)
	(segment
		(start 147.19427 -124.33046)
		(end 147.19427 -118.862602)
		(width 0.11684)
		(layer "In15.Cu")
		(net "RST_PERST_M2_0_N")
	)
	(segment
		(start 148.62556 -104.939592)
		(end 144.628362 -100.942394)
		(width 0.11684)
		(layer "In15.Cu")
		(net "RST_PERST_M2_0_N")
	)
	(segment
		(start 147.327112 -115.484656)
		(end 147.528026 -115.283742)
		(width 0.11684)
		(layer "In15.Cu")
		(net "RST_PERST_M2_0_N")
	)
	(segment
		(start 142.848584 -100.942394)
		(end 142.800832 -100.990146)
		(width 0.11684)
		(layer "In15.Cu")
		(net "RST_PERST_M2_0_N")
	)
	(segment
		(start 147.327112 -118.72976)
		(end 147.327112 -115.484656)
		(width 0.11684)
		(layer "In15.Cu")
		(net "RST_PERST_M2_0_N")
	)
	(segment
		(start 239.90808 -48.019208)
		(end 239.90808 -48.936656)
		(width 0.10668)
		(layer "F.Cu")
		(net "RST_PERST_E1S_0_N")
	)
	(segment
		(start 200.552558 -116.673376)
		(end 199.897746 -116.673376)
		(width 0.10668)
		(layer "F.Cu")
		(net "RST_PERST_E1S_0_N")
	)
	(segment
		(start 199.897746 -116.673376)
		(end 199.85355 -116.717572)
		(width 0.10668)
		(layer "F.Cu")
		(net "RST_PERST_E1S_0_N")
	)
	(segment
		(start 197.669658 -117.689376)
		(end 198.120254 -118.139972)
		(width 0.10668)
		(layer "F.Cu")
		(net "RST_PERST_E1S_0_N")
	)
	(segment
		(start 198.960486 -118.139972)
		(end 199.85355 -117.246908)
		(width 0.10668)
		(layer "F.Cu")
		(net "RST_PERST_E1S_0_N")
	)
	(segment
		(start 239.90808 -48.936656)
		(end 240.06048 -49.089056)
		(width 0.10668)
		(layer "F.Cu")
		(net "RST_PERST_E1S_0_N")
	)
	(segment
		(start 198.120254 -118.139972)
		(end 198.960486 -118.139972)
		(width 0.10668)
		(layer "F.Cu")
		(net "RST_PERST_E1S_0_N")
	)
	(segment
		(start 199.85355 -117.246908)
		(end 199.85355 -116.717572)
		(width 0.10668)
		(layer "F.Cu")
		(net "RST_PERST_E1S_0_N")
	)
	(via
		(at 199.85355 -116.717572)
		(size 0.508)
		(drill 0.254)
		(layers "F.Cu" "B.Cu")
		(net "RST_PERST_E1S_0_N")
	)
	(via
		(at 240.06048 -49.089056)
		(size 0.508)
		(drill 0.254)
		(layers "F.Cu" "B.Cu")
		(net "RST_PERST_E1S_0_N")
	)
	(via
		(at 243.594382 -123.771406)
		(size 0.508)
		(drill 0.254)
		(layers "F.Cu" "B.Cu")
		(net "RST_PERST_E1S_0_N")
	)
	(segment
		(start 241.185954 -50.21453)
		(end 241.185954 -64.879474)
		(width 0.11684)
		(layer "In11.Cu")
		(net "RST_PERST_E1S_0_N")
	)
	(segment
		(start 242.86083 -123.037854)
		(end 243.594382 -123.771406)
		(width 0.11684)
		(layer "In11.Cu")
		(net "RST_PERST_E1S_0_N")
	)
	(segment
		(start 242.86083 -79.171292)
		(end 242.86083 -123.037854)
		(width 0.11684)
		(layer "In11.Cu")
		(net "RST_PERST_E1S_0_N")
	)
	(segment
		(start 238.90732 -70.940168)
		(end 239.56772 -71.600568)
		(width 0.11684)
		(layer "In11.Cu")
		(net "RST_PERST_E1S_0_N")
	)
	(segment
		(start 239.56772 -71.600568)
		(end 239.56772 -75.878182)
		(width 0.11684)
		(layer "In11.Cu")
		(net "RST_PERST_E1S_0_N")
	)
	(segment
		(start 238.90732 -67.158108)
		(end 238.90732 -70.940168)
		(width 0.11684)
		(layer "In11.Cu")
		(net "RST_PERST_E1S_0_N")
	)
	(segment
		(start 241.185954 -64.879474)
		(end 238.90732 -67.158108)
		(width 0.11684)
		(layer "In11.Cu")
		(net "RST_PERST_E1S_0_N")
	)
	(segment
		(start 240.06048 -49.089056)
		(end 241.185954 -50.21453)
		(width 0.11684)
		(layer "In11.Cu")
		(net "RST_PERST_E1S_0_N")
	)
	(segment
		(start 239.56772 -75.878182)
		(end 242.86083 -79.171292)
		(width 0.11684)
		(layer "In11.Cu")
		(net "RST_PERST_E1S_0_N")
	)
	(segment
		(start 226.322382 -121.806462)
		(end 227.41255 -122.89663)
		(width 0.11684)
		(layer "In15.Cu")
		(net "RST_PERST_E1S_0_N")
	)
	(segment
		(start 202.833224 -119.227092)
		(end 207.653636 -119.227092)
		(width 0.11684)
		(layer "In15.Cu")
		(net "RST_PERST_E1S_0_N")
	)
	(segment
		(start 227.41255 -122.89663)
		(end 242.719606 -122.89663)
		(width 0.11684)
		(layer "In15.Cu")
		(net "RST_PERST_E1S_0_N")
	)
	(segment
		(start 217.93962 -121.806462)
		(end 226.322382 -121.806462)
		(width 0.11684)
		(layer "In15.Cu")
		(net "RST_PERST_E1S_0_N")
	)
	(segment
		(start 216.494614 -120.361456)
		(end 217.93962 -121.806462)
		(width 0.11684)
		(layer "In15.Cu")
		(net "RST_PERST_E1S_0_N")
	)
	(segment
		(start 199.85355 -116.717572)
		(end 200.323704 -116.717572)
		(width 0.11684)
		(layer "In15.Cu")
		(net "RST_PERST_E1S_0_N")
	)
	(segment
		(start 200.323704 -116.717572)
		(end 202.833224 -119.227092)
		(width 0.11684)
		(layer "In15.Cu")
		(net "RST_PERST_E1S_0_N")
	)
	(segment
		(start 208.788 -120.361456)
		(end 216.494614 -120.361456)
		(width 0.11684)
		(layer "In15.Cu")
		(net "RST_PERST_E1S_0_N")
	)
	(segment
		(start 207.653636 -119.227092)
		(end 208.788 -120.361456)
		(width 0.11684)
		(layer "In15.Cu")
		(net "RST_PERST_E1S_0_N")
	)
	(segment
		(start 242.719606 -122.89663)
		(end 243.594382 -123.771406)
		(width 0.11684)
		(layer "In15.Cu")
		(net "RST_PERST_E1S_0_N")
	)
	(via
		(at 316.93739 -75.020678)
		(size 0.6604)
		(drill 0.3302)
		(layers "F.Cu" "B.Cu")
		(net "PWRGD_PS_PWROK_PLD_N")
	)
	(segment
		(start 316.93739 -75.020678)
		(end 316.93739 -76.239878)
		(width 0.10668)
		(layer "B.Cu")
		(net "PWRGD_PS_PWROK_PLD_N")
	)
	(segment
		(start 315.80455 -76.889864)
		(end 315.80455 -76.239878)
		(width 0.10668)
		(layer "B.Cu")
		(net "PWRGD_PS_PWROK_PLD_N")
	)
	(segment
		(start 316.33033 -75.020678)
		(end 315.80455 -75.546458)
		(width 0.10668)
		(layer "B.Cu")
		(net "PWRGD_PS_PWROK_PLD_N")
	)
	(segment
		(start 316.93739 -75.020678)
		(end 316.33033 -75.020678)
		(width 0.10668)
		(layer "B.Cu")
		(net "PWRGD_PS_PWROK_PLD_N")
	)
	(segment
		(start 315.80455 -75.546458)
		(end 315.80455 -76.239878)
		(width 0.10668)
		(layer "B.Cu")
		(net "PWRGD_PS_PWROK_PLD_N")
	)
	(segment
		(start 181.122066 -112.25276)
		(end 180.732176 -111.86287)
		(width 0.10668)
		(layer "F.Cu")
		(net "PWRGD_PS_PWROK_PLD_ISO_R")
	)
	(via
		(at 311.427876 -79.810864)
		(size 0.762)
		(drill 0.254)
		(layers "F.Cu" "B.Cu")
		(net "PWRGD_PS_PWROK_PLD_ISO_R")
	)
	(via
		(at 176.179734 -87.926926)
		(size 0.508)
		(drill 0.254)
		(layers "F.Cu" "B.Cu")
		(net "PWRGD_PS_PWROK_PLD_ISO_R")
	)
	(via
		(at 180.732176 -111.86287)
		(size 0.4572)
		(drill 0.254)
		(layers "F.Cu" "B.Cu")
		(net "PWRGD_PS_PWROK_PLD_ISO_R")
	)
	(segment
		(start 311.427876 -79.175864)
		(end 311.427876 -79.810864)
		(width 0.10668)
		(layer "B.Cu")
		(net "PWRGD_PS_PWROK_PLD_ISO_R")
	)
	(segment
		(start 201.803762 -88.42375)
		(end 205.575916 -92.195904)
		(width 0.11684)
		(layer "In6.Cu")
		(net "PWRGD_PS_PWROK_PLD_ISO_R")
	)
	(segment
		(start 232.455466 -92.195904)
		(end 233.31678 -93.057218)
		(width 0.11684)
		(layer "In6.Cu")
		(net "PWRGD_PS_PWROK_PLD_ISO_R")
	)
	(segment
		(start 247.76684 -93.057218)
		(end 248.942098 -91.88196)
		(width 0.11684)
		(layer "In6.Cu")
		(net "PWRGD_PS_PWROK_PLD_ISO_R")
	)
	(segment
		(start 187.950856 -87.120476)
		(end 189.25413 -88.42375)
		(width 0.11684)
		(layer "In6.Cu")
		(net "PWRGD_PS_PWROK_PLD_ISO_R")
	)
	(segment
		(start 189.25413 -88.42375)
		(end 201.803762 -88.42375)
		(width 0.11684)
		(layer "In6.Cu")
		(net "PWRGD_PS_PWROK_PLD_ISO_R")
	)
	(segment
		(start 258.889246 -90.762582)
		(end 260.855968 -88.79586)
		(width 0.11684)
		(layer "In6.Cu")
		(net "PWRGD_PS_PWROK_PLD_ISO_R")
	)
	(segment
		(start 176.540922 -88.288114)
		(end 179.510436 -88.288114)
		(width 0.11684)
		(layer "In6.Cu")
		(net "PWRGD_PS_PWROK_PLD_ISO_R")
	)
	(segment
		(start 180.678074 -87.120476)
		(end 187.950856 -87.120476)
		(width 0.11684)
		(layer "In6.Cu")
		(net "PWRGD_PS_PWROK_PLD_ISO_R")
	)
	(segment
		(start 310.912256 -80.326484)
		(end 311.427876 -79.810864)
		(width 0.11684)
		(layer "In6.Cu")
		(net "PWRGD_PS_PWROK_PLD_ISO_R")
	)
	(segment
		(start 248.942098 -91.88196)
		(end 254.904748 -91.88196)
		(width 0.11684)
		(layer "In6.Cu")
		(net "PWRGD_PS_PWROK_PLD_ISO_R")
	)
	(segment
		(start 179.510436 -88.288114)
		(end 180.678074 -87.120476)
		(width 0.11684)
		(layer "In6.Cu")
		(net "PWRGD_PS_PWROK_PLD_ISO_R")
	)
	(segment
		(start 296.508424 -80.326484)
		(end 310.912256 -80.326484)
		(width 0.11684)
		(layer "In6.Cu")
		(net "PWRGD_PS_PWROK_PLD_ISO_R")
	)
	(segment
		(start 288.039048 -88.79586)
		(end 296.508424 -80.326484)
		(width 0.11684)
		(layer "In6.Cu")
		(net "PWRGD_PS_PWROK_PLD_ISO_R")
	)
	(segment
		(start 176.179734 -87.926926)
		(end 176.540922 -88.288114)
		(width 0.11684)
		(layer "In6.Cu")
		(net "PWRGD_PS_PWROK_PLD_ISO_R")
	)
	(segment
		(start 205.575916 -92.195904)
		(end 232.455466 -92.195904)
		(width 0.11684)
		(layer "In6.Cu")
		(net "PWRGD_PS_PWROK_PLD_ISO_R")
	)
	(segment
		(start 233.31678 -93.057218)
		(end 247.76684 -93.057218)
		(width 0.11684)
		(layer "In6.Cu")
		(net "PWRGD_PS_PWROK_PLD_ISO_R")
	)
	(segment
		(start 254.904748 -91.88196)
		(end 256.024126 -90.762582)
		(width 0.11684)
		(layer "In6.Cu")
		(net "PWRGD_PS_PWROK_PLD_ISO_R")
	)
	(segment
		(start 256.024126 -90.762582)
		(end 258.889246 -90.762582)
		(width 0.11684)
		(layer "In6.Cu")
		(net "PWRGD_PS_PWROK_PLD_ISO_R")
	)
	(segment
		(start 260.855968 -88.79586)
		(end 288.039048 -88.79586)
		(width 0.11684)
		(layer "In6.Cu")
		(net "PWRGD_PS_PWROK_PLD_ISO_R")
	)
	(segment
		(start 175.161702 -98.460052)
		(end 175.161702 -93.088968)
		(width 0.11684)
		(layer "In11.Cu")
		(net "PWRGD_PS_PWROK_PLD_ISO_R")
	)
	(segment
		(start 176.179734 -89.548462)
		(end 176.179734 -87.926926)
		(width 0.11684)
		(layer "In11.Cu")
		(net "PWRGD_PS_PWROK_PLD_ISO_R")
	)
	(segment
		(start 178.721512 -106.519472)
		(end 177.796698 -105.594658)
		(width 0.11684)
		(layer "In11.Cu")
		(net "PWRGD_PS_PWROK_PLD_ISO_R")
	)
	(segment
		(start 177.796698 -102.329488)
		(end 175.716946 -100.249736)
		(width 0.11684)
		(layer "In11.Cu")
		(net "PWRGD_PS_PWROK_PLD_ISO_R")
	)
	(segment
		(start 180.23332 -111.45774)
		(end 179.73802 -111.45774)
		(width 0.11684)
		(layer "In11.Cu")
		(net "PWRGD_PS_PWROK_PLD_ISO_R")
	)
	(segment
		(start 175.161702 -93.088968)
		(end 174.637192 -92.564458)
		(width 0.11684)
		(layer "In11.Cu")
		(net "PWRGD_PS_PWROK_PLD_ISO_R")
	)
	(segment
		(start 174.637192 -91.091004)
		(end 176.179734 -89.548462)
		(width 0.11684)
		(layer "In11.Cu")
		(net "PWRGD_PS_PWROK_PLD_ISO_R")
	)
	(segment
		(start 175.716946 -100.249736)
		(end 175.716946 -99.015296)
		(width 0.11684)
		(layer "In11.Cu")
		(net "PWRGD_PS_PWROK_PLD_ISO_R")
	)
	(segment
		(start 175.716946 -99.015296)
		(end 175.161702 -98.460052)
		(width 0.11684)
		(layer "In11.Cu")
		(net "PWRGD_PS_PWROK_PLD_ISO_R")
	)
	(segment
		(start 177.796698 -105.594658)
		(end 177.796698 -102.329488)
		(width 0.11684)
		(layer "In11.Cu")
		(net "PWRGD_PS_PWROK_PLD_ISO_R")
	)
	(segment
		(start 180.63845 -111.86287)
		(end 180.23332 -111.45774)
		(width 0.11684)
		(layer "In11.Cu")
		(net "PWRGD_PS_PWROK_PLD_ISO_R")
	)
	(segment
		(start 179.52974 -111.24946)
		(end 179.52974 -110.899194)
		(width 0.11684)
		(layer "In11.Cu")
		(net "PWRGD_PS_PWROK_PLD_ISO_R")
	)
	(segment
		(start 174.637192 -92.564458)
		(end 174.637192 -91.091004)
		(width 0.11684)
		(layer "In11.Cu")
		(net "PWRGD_PS_PWROK_PLD_ISO_R")
	)
	(segment
		(start 180.732176 -111.86287)
		(end 180.63845 -111.86287)
		(width 0.11684)
		(layer "In11.Cu")
		(net "PWRGD_PS_PWROK_PLD_ISO_R")
	)
	(segment
		(start 179.52974 -110.899194)
		(end 179.304442 -110.673896)
		(width 0.11684)
		(layer "In11.Cu")
		(net "PWRGD_PS_PWROK_PLD_ISO_R")
	)
	(segment
		(start 179.304442 -110.673896)
		(end 178.955446 -110.673896)
		(width 0.11684)
		(layer "In11.Cu")
		(net "PWRGD_PS_PWROK_PLD_ISO_R")
	)
	(segment
		(start 179.73802 -111.45774)
		(end 179.52974 -111.24946)
		(width 0.11684)
		(layer "In11.Cu")
		(net "PWRGD_PS_PWROK_PLD_ISO_R")
	)
	(segment
		(start 178.955446 -110.673896)
		(end 178.721512 -110.439962)
		(width 0.11684)
		(layer "In11.Cu")
		(net "PWRGD_PS_PWROK_PLD_ISO_R")
	)
	(segment
		(start 178.721512 -110.439962)
		(end 178.721512 -106.519472)
		(width 0.11684)
		(layer "In11.Cu")
		(net "PWRGD_PS_PWROK_PLD_ISO_R")
	)
	(via
		(at 312.596276 -78.375764)
		(size 0.6604)
		(drill 0.3302)
		(layers "F.Cu" "B.Cu")
		(net "PWRGD_PS_PWROK_PLD_ISO")
	)
	(segment
		(start 313.43219 -77.53985)
		(end 313.90463 -77.53985)
		(width 0.10668)
		(layer "B.Cu")
		(net "PWRGD_PS_PWROK_PLD_ISO")
	)
	(segment
		(start 310.411876 -78.375764)
		(end 311.427876 -78.375764)
		(width 0.10668)
		(layer "B.Cu")
		(net "PWRGD_PS_PWROK_PLD_ISO")
	)
	(segment
		(start 312.596276 -78.375764)
		(end 313.43219 -77.53985)
		(width 0.10668)
		(layer "B.Cu")
		(net "PWRGD_PS_PWROK_PLD_ISO")
	)
	(segment
		(start 311.427876 -78.375764)
		(end 312.596276 -78.375764)
		(width 0.10668)
		(layer "B.Cu")
		(net "PWRGD_PS_PWROK_PLD_ISO")
	)
	(via
		(at 312.596276 -76.889864)
		(size 0.6604)
		(drill 0.3302)
		(layers "F.Cu" "B.Cu")
		(net "PWRGD_PS_PWROK_PLD")
	)
	(segment
		(start 312.596276 -76.889864)
		(end 313.90463 -76.889864)
		(width 0.10668)
		(layer "B.Cu")
		(net "PWRGD_PS_PWROK_PLD")
	)
	(segment
		(start 315.135768 -74.96937)
		(end 316.57036 -73.534778)
		(width 0.10668)
		(layer "B.Cu")
		(net "PWRGD_PS_PWROK_PLD")
	)
	(segment
		(start 315.135768 -76.340462)
		(end 315.135768 -74.96937)
		(width 0.10668)
		(layer "B.Cu")
		(net "PWRGD_PS_PWROK_PLD")
	)
	(segment
		(start 316.57036 -73.534778)
		(end 319.322704 -73.534778)
		(width 0.10668)
		(layer "B.Cu")
		(net "PWRGD_PS_PWROK_PLD")
	)
	(segment
		(start 314.586366 -76.889864)
		(end 315.135768 -76.340462)
		(width 0.10668)
		(layer "B.Cu")
		(net "PWRGD_PS_PWROK_PLD")
	)
	(segment
		(start 311.427876 -76.889864)
		(end 312.596276 -76.889864)
		(width 0.10668)
		(layer "B.Cu")
		(net "PWRGD_PS_PWROK_PLD")
	)
	(segment
		(start 313.90463 -76.889864)
		(end 314.586366 -76.889864)
		(width 0.10668)
		(layer "B.Cu")
		(net "PWRGD_PS_PWROK_PLD")
	)
	(via
		(at 310.411876 -77.524864)
		(size 0.762)
		(drill 0.254)
		(layers "F.Cu" "B.Cu")
		(net "PWRGD_PS_PWROK")
	)
	(via
		(at 112.09528 -80.30718)
		(size 0.508)
		(drill 0.254)
		(layers "F.Cu" "B.Cu")
		(net "PWRGD_PS_PWROK")
	)
	(via
		(at 145.735802 -14.906752)
		(size 0.508)
		(drill 0.254)
		(layers "F.Cu" "B.Cu")
		(net "PWRGD_PS_PWROK")
	)
	(segment
		(start 145.3388 -14.610334)
		(end 145.635218 -14.906752)
		(width 0.10668)
		(layer "B.Cu")
		(net "PWRGD_PS_PWROK")
	)
	(segment
		(start 145.635218 -14.906752)
		(end 145.735802 -14.906752)
		(width 0.10668)
		(layer "B.Cu")
		(net "PWRGD_PS_PWROK")
	)
	(segment
		(start 145.3388 -14.162278)
		(end 145.3388 -14.610334)
		(width 0.10668)
		(layer "B.Cu")
		(net "PWRGD_PS_PWROK")
	)
	(segment
		(start 310.411876 -76.889864)
		(end 310.411876 -77.524864)
		(width 0.10668)
		(layer "B.Cu")
		(net "PWRGD_PS_PWROK")
	)
	(segment
		(start 158.315406 -83.007454)
		(end 166.802816 -83.007454)
		(width 0.11684)
		(layer "In2.Cu")
		(net "PWRGD_PS_PWROK")
	)
	(segment
		(start 182.528464 -82.215228)
		(end 183.46674 -83.153504)
		(width 0.11684)
		(layer "In2.Cu")
		(net "PWRGD_PS_PWROK")
	)
	(segment
		(start 224.756218 -80.919066)
		(end 226.34448 -79.330804)
		(width 0.11684)
		(layer "In2.Cu")
		(net "PWRGD_PS_PWROK")
	)
	(segment
		(start 285.176214 -81.976468)
		(end 302.779176 -81.976468)
		(width 0.11684)
		(layer "In2.Cu")
		(net "PWRGD_PS_PWROK")
	)
	(segment
		(start 167.595042 -82.215228)
		(end 182.528464 -82.215228)
		(width 0.11684)
		(layer "In2.Cu")
		(net "PWRGD_PS_PWROK")
	)
	(segment
		(start 234.804712 -75.826874)
		(end 256.065782 -75.826874)
		(width 0.11684)
		(layer "In2.Cu")
		(net "PWRGD_PS_PWROK")
	)
	(segment
		(start 257.071622 -76.832714)
		(end 280.03246 -76.832714)
		(width 0.11684)
		(layer "In2.Cu")
		(net "PWRGD_PS_PWROK")
	)
	(segment
		(start 226.34448 -79.330804)
		(end 234.804712 -75.826874)
		(width 0.11684)
		(layer "In2.Cu")
		(net "PWRGD_PS_PWROK")
	)
	(segment
		(start 156.84627 -84.47659)
		(end 158.315406 -83.007454)
		(width 0.11684)
		(layer "In2.Cu")
		(net "PWRGD_PS_PWROK")
	)
	(segment
		(start 183.46674 -83.153504)
		(end 193.427096 -83.153504)
		(width 0.11684)
		(layer "In2.Cu")
		(net "PWRGD_PS_PWROK")
	)
	(segment
		(start 116.26469 -84.47659)
		(end 156.84627 -84.47659)
		(width 0.11684)
		(layer "In2.Cu")
		(net "PWRGD_PS_PWROK")
	)
	(segment
		(start 302.779176 -81.976468)
		(end 307.23078 -77.524864)
		(width 0.11684)
		(layer "In2.Cu")
		(net "PWRGD_PS_PWROK")
	)
	(segment
		(start 194.479164 -82.101436)
		(end 212.880448 -82.101436)
		(width 0.11684)
		(layer "In2.Cu")
		(net "PWRGD_PS_PWROK")
	)
	(segment
		(start 193.427096 -83.153504)
		(end 194.479164 -82.101436)
		(width 0.11684)
		(layer "In2.Cu")
		(net "PWRGD_PS_PWROK")
	)
	(segment
		(start 307.23078 -77.524864)
		(end 310.411876 -77.524864)
		(width 0.11684)
		(layer "In2.Cu")
		(net "PWRGD_PS_PWROK")
	)
	(segment
		(start 112.09528 -80.30718)
		(end 116.26469 -84.47659)
		(width 0.11684)
		(layer "In2.Cu")
		(net "PWRGD_PS_PWROK")
	)
	(segment
		(start 214.062818 -80.919066)
		(end 224.756218 -80.919066)
		(width 0.11684)
		(layer "In2.Cu")
		(net "PWRGD_PS_PWROK")
	)
	(segment
		(start 212.880448 -82.101436)
		(end 214.062818 -80.919066)
		(width 0.11684)
		(layer "In2.Cu")
		(net "PWRGD_PS_PWROK")
	)
	(segment
		(start 166.802816 -83.007454)
		(end 167.595042 -82.215228)
		(width 0.11684)
		(layer "In2.Cu")
		(net "PWRGD_PS_PWROK")
	)
	(segment
		(start 256.065782 -75.826874)
		(end 257.071622 -76.832714)
		(width 0.11684)
		(layer "In2.Cu")
		(net "PWRGD_PS_PWROK")
	)
	(segment
		(start 280.03246 -76.832714)
		(end 285.176214 -81.976468)
		(width 0.11684)
		(layer "In2.Cu")
		(net "PWRGD_PS_PWROK")
	)
	(segment
		(start 129.9972 -35.69716)
		(end 131.699 -33.99536)
		(width 0.11684)
		(layer "In4.Cu")
		(net "PWRGD_PS_PWROK")
	)
	(segment
		(start 144.165574 -17.065752)
		(end 145.735802 -15.495524)
		(width 0.11684)
		(layer "In4.Cu")
		(net "PWRGD_PS_PWROK")
	)
	(segment
		(start 139.5476 -27.524456)
		(end 139.5476 -26.521156)
		(width 0.11684)
		(layer "In4.Cu")
		(net "PWRGD_PS_PWROK")
	)
	(segment
		(start 125.50394 -46.101)
		(end 129.9972 -41.60774)
		(width 0.11684)
		(layer "In4.Cu")
		(net "PWRGD_PS_PWROK")
	)
	(segment
		(start 139.5476 -31.1912)
		(end 139.5476 -29.721302)
		(width 0.11684)
		(layer "In4.Cu")
		(net "PWRGD_PS_PWROK")
	)
	(segment
		(start 105.9942 -70.435216)
		(end 105.9942 -53.38826)
		(width 0.11684)
		(layer "In4.Cu")
		(net "PWRGD_PS_PWROK")
	)
	(segment
		(start 129.9972 -41.60774)
		(end 129.9972 -35.69716)
		(width 0.11684)
		(layer "In4.Cu")
		(net "PWRGD_PS_PWROK")
	)
	(segment
		(start 131.699 -33.99536)
		(end 136.74344 -33.99536)
		(width 0.11684)
		(layer "In4.Cu")
		(net "PWRGD_PS_PWROK")
	)
	(segment
		(start 123.95454 -46.101)
		(end 125.50394 -46.101)
		(width 0.11684)
		(layer "In4.Cu")
		(net "PWRGD_PS_PWROK")
	)
	(segment
		(start 111.229902 -75.670918)
		(end 105.9942 -70.435216)
		(width 0.11684)
		(layer "In4.Cu")
		(net "PWRGD_PS_PWROK")
	)
	(segment
		(start 136.74344 -33.99536)
		(end 139.5476 -31.1912)
		(width 0.11684)
		(layer "In4.Cu")
		(net "PWRGD_PS_PWROK")
	)
	(segment
		(start 139.5476 -26.521156)
		(end 144.165574 -21.903182)
		(width 0.11684)
		(layer "In4.Cu")
		(net "PWRGD_PS_PWROK")
	)
	(segment
		(start 139.5476 -29.721302)
		(end 139.30757 -29.481272)
		(width 0.11684)
		(layer "In4.Cu")
		(net "PWRGD_PS_PWROK")
	)
	(segment
		(start 144.165574 -21.903182)
		(end 144.165574 -17.065752)
		(width 0.11684)
		(layer "In4.Cu")
		(net "PWRGD_PS_PWROK")
	)
	(segment
		(start 139.30757 -29.481272)
		(end 139.30757 -27.764486)
		(width 0.11684)
		(layer "In4.Cu")
		(net "PWRGD_PS_PWROK")
	)
	(segment
		(start 145.735802 -15.495524)
		(end 145.735802 -14.906752)
		(width 0.11684)
		(layer "In4.Cu")
		(net "PWRGD_PS_PWROK")
	)
	(segment
		(start 106.85526 -52.5272)
		(end 109.8042 -52.5272)
		(width 0.11684)
		(layer "In4.Cu")
		(net "PWRGD_PS_PWROK")
	)
	(segment
		(start 109.8042 -52.5272)
		(end 110.555278 -51.776122)
		(width 0.11684)
		(layer "In4.Cu")
		(net "PWRGD_PS_PWROK")
	)
	(segment
		(start 139.30757 -27.764486)
		(end 139.5476 -27.524456)
		(width 0.11684)
		(layer "In4.Cu")
		(net "PWRGD_PS_PWROK")
	)
	(segment
		(start 105.9942 -53.38826)
		(end 106.85526 -52.5272)
		(width 0.11684)
		(layer "In4.Cu")
		(net "PWRGD_PS_PWROK")
	)
	(segment
		(start 118.279418 -51.776122)
		(end 123.95454 -46.101)
		(width 0.11684)
		(layer "In4.Cu")
		(net "PWRGD_PS_PWROK")
	)
	(segment
		(start 111.229902 -79.441802)
		(end 111.229902 -75.670918)
		(width 0.11684)
		(layer "In4.Cu")
		(net "PWRGD_PS_PWROK")
	)
	(segment
		(start 110.555278 -51.776122)
		(end 118.279418 -51.776122)
		(width 0.11684)
		(layer "In4.Cu")
		(net "PWRGD_PS_PWROK")
	)
	(segment
		(start 112.09528 -80.30718)
		(end 111.229902 -79.441802)
		(width 0.11684)
		(layer "In4.Cu")
		(net "PWRGD_PS_PWROK")
	)
	(segment
		(start 184.801256 -96.503998)
		(end 184.801256 -98.246692)
		(width 0.10668)
		(layer "F.Cu")
		(net "PWRGD_OCP_SFF_PWR_GOOD")
	)
	(segment
		(start 184.801256 -98.246692)
		(end 184.785 -98.262948)
		(width 0.10668)
		(layer "F.Cu")
		(net "PWRGD_OCP_SFF_PWR_GOOD")
	)
	(segment
		(start 186.722004 -109.052868)
		(end 187.111894 -108.662978)
		(width 0.10668)
		(layer "F.Cu")
		(net "PWRGD_OCP_SFF_PWR_GOOD")
	)
	(via
		(at 187.111894 -108.662978)
		(size 0.4572)
		(drill 0.254)
		(layers "F.Cu" "B.Cu")
		(net "PWRGD_OCP_SFF_PWR_GOOD")
	)
	(via
		(at 184.785 -98.262948)
		(size 0.508)
		(drill 0.254)
		(layers "F.Cu" "B.Cu")
		(net "PWRGD_OCP_SFF_PWR_GOOD")
	)
	(segment
		(start 184.981342 -98.262948)
		(end 185.3184 -98.600006)
		(width 0.11684)
		(layer "In11.Cu")
		(net "PWRGD_OCP_SFF_PWR_GOOD")
	)
	(segment
		(start 184.4802 -100.50526)
		(end 184.4802 -103.1621)
		(width 0.11684)
		(layer "In11.Cu")
		(net "PWRGD_OCP_SFF_PWR_GOOD")
	)
	(segment
		(start 185.948066 -108.268516)
		(end 186.717432 -108.268516)
		(width 0.11684)
		(layer "In11.Cu")
		(net "PWRGD_OCP_SFF_PWR_GOOD")
	)
	(segment
		(start 184.4802 -103.1621)
		(end 185.3184 -104.0003)
		(width 0.11684)
		(layer "In11.Cu")
		(net "PWRGD_OCP_SFF_PWR_GOOD")
	)
	(segment
		(start 185.3184 -107.63885)
		(end 185.948066 -108.268516)
		(width 0.11684)
		(layer "In11.Cu")
		(net "PWRGD_OCP_SFF_PWR_GOOD")
	)
	(segment
		(start 184.785 -98.262948)
		(end 184.981342 -98.262948)
		(width 0.11684)
		(layer "In11.Cu")
		(net "PWRGD_OCP_SFF_PWR_GOOD")
	)
	(segment
		(start 185.3184 -98.600006)
		(end 185.3184 -99.66706)
		(width 0.11684)
		(layer "In11.Cu")
		(net "PWRGD_OCP_SFF_PWR_GOOD")
	)
	(segment
		(start 186.717432 -108.268516)
		(end 187.111894 -108.662978)
		(width 0.11684)
		(layer "In11.Cu")
		(net "PWRGD_OCP_SFF_PWR_GOOD")
	)
	(segment
		(start 185.3184 -104.0003)
		(end 185.3184 -107.63885)
		(width 0.11684)
		(layer "In11.Cu")
		(net "PWRGD_OCP_SFF_PWR_GOOD")
	)
	(segment
		(start 185.3184 -99.66706)
		(end 184.4802 -100.50526)
		(width 0.11684)
		(layer "In11.Cu")
		(net "PWRGD_OCP_SFF_PWR_GOOD")
	)
	(segment
		(start 421.1574 -37.277548)
		(end 422.3766 -37.277548)
		(width 0.10668)
		(layer "F.Cu")
		(net "PU_FPGA_DEBUG_SW_SPARE")
	)
	(segment
		(start 422.3766 -37.277548)
		(end 423.9514 -37.277548)
		(width 0.10668)
		(layer "F.Cu")
		(net "PU_FPGA_DEBUG_SW_SPARE")
	)
	(via
		(at 422.3766 -37.277548)
		(size 0.762)
		(drill 0.381)
		(layers "F.Cu" "B.Cu")
		(net "PU_FPGA_DEBUG_SW_SPARE")
	)
	(segment
		(start 423.9514 -30.927548)
		(end 424.9674 -30.927548)
		(width 0.10668)
		(layer "F.Cu")
		(net "PU_FPGA_DEBUG_LED_CTRL")
	)
	(via
		(at 424.9674 -30.927548)
		(size 0.508)
		(drill 0.254)
		(layers "F.Cu" "B.Cu")
		(net "PU_FPGA_DEBUG_LED_CTRL")
	)
	(segment
		(start 424.9674 -30.927548)
		(end 426.1358 -30.927548)
		(width 0.10668)
		(layer "B.Cu")
		(net "PU_FPGA_DEBUG_LED_CTRL")
	)
	(segment
		(start 193.122042 -108.252768)
		(end 193.511932 -107.862878)
		(width 0.10668)
		(layer "F.Cu")
		(net "PRSNT_OCP_SFF_N")
	)
	(segment
		(start 207.716374 -108.545376)
		(end 207.644238 -108.47324)
		(width 0.10668)
		(layer "F.Cu")
		(net "PRSNT_OCP_SFF_N")
	)
	(segment
		(start 208.494376 -108.545376)
		(end 207.716374 -108.545376)
		(width 0.10668)
		(layer "F.Cu")
		(net "PRSNT_OCP_SFF_N")
	)
	(via
		(at 193.511932 -107.862878)
		(size 0.4572)
		(drill 0.254)
		(layers "F.Cu" "B.Cu")
		(net "PRSNT_OCP_SFF_N")
	)
	(via
		(at 207.644238 -108.47324)
		(size 0.508)
		(drill 0.254)
		(layers "F.Cu" "B.Cu")
		(net "PRSNT_OCP_SFF_N")
	)
	(segment
		(start 194.006216 -107.348782)
		(end 194.438778 -107.348782)
		(width 0.11684)
		(layer "In2.Cu")
		(net "PRSNT_OCP_SFF_N")
	)
	(segment
		(start 193.511932 -107.843066)
		(end 194.006216 -107.348782)
		(width 0.11684)
		(layer "In2.Cu")
		(net "PRSNT_OCP_SFF_N")
	)
	(segment
		(start 195.49364 -106.29392)
		(end 197.319646 -106.29392)
		(width 0.11684)
		(layer "In2.Cu")
		(net "PRSNT_OCP_SFF_N")
	)
	(segment
		(start 207.043274 -107.872276)
		(end 207.644238 -108.47324)
		(width 0.11684)
		(layer "In2.Cu")
		(net "PRSNT_OCP_SFF_N")
	)
	(segment
		(start 197.319646 -106.29392)
		(end 197.60819 -106.005376)
		(width 0.11684)
		(layer "In2.Cu")
		(net "PRSNT_OCP_SFF_N")
	)
	(segment
		(start 204.386434 -106.005376)
		(end 206.253334 -107.872276)
		(width 0.11684)
		(layer "In2.Cu")
		(net "PRSNT_OCP_SFF_N")
	)
	(segment
		(start 193.511932 -107.862878)
		(end 193.511932 -107.843066)
		(width 0.11684)
		(layer "In2.Cu")
		(net "PRSNT_OCP_SFF_N")
	)
	(segment
		(start 194.438778 -107.348782)
		(end 195.49364 -106.29392)
		(width 0.11684)
		(layer "In2.Cu")
		(net "PRSNT_OCP_SFF_N")
	)
	(segment
		(start 197.60819 -106.005376)
		(end 204.386434 -106.005376)
		(width 0.11684)
		(layer "In2.Cu")
		(net "PRSNT_OCP_SFF_N")
	)
	(segment
		(start 206.253334 -107.872276)
		(end 207.043274 -107.872276)
		(width 0.11684)
		(layer "In2.Cu")
		(net "PRSNT_OCP_SFF_N")
	)
	(segment
		(start 225.298762 -68.791328)
		(end 225.171762 -68.918328)
		(width 0.10668)
		(layer "F.Cu")
		(net "P3V3_E1S_PWRGD_0_R")
	)
	(segment
		(start 225.552 -82.78495)
		(end 225.552 -74.422)
		(width 0.10668)
		(layer "F.Cu")
		(net "P3V3_E1S_PWRGD_0_R")
	)
	(segment
		(start 225.171762 -68.918328)
		(end 224.537016 -68.918328)
		(width 0.10668)
		(layer "F.Cu")
		(net "P3V3_E1S_PWRGD_0_R")
	)
	(segment
		(start 225.298762 -67.921378)
		(end 225.298762 -68.791328)
		(width 0.10668)
		(layer "F.Cu")
		(net "P3V3_E1S_PWRGD_0_R")
	)
	(segment
		(start 225.57105 -82.804)
		(end 225.552 -82.78495)
		(width 0.10668)
		(layer "F.Cu")
		(net "P3V3_E1S_PWRGD_0_R")
	)
	(segment
		(start 189.92215 -114.652806)
		(end 190.31204 -114.262916)
		(width 0.10668)
		(layer "F.Cu")
		(net "P3V3_E1S_PWRGD_0_R")
	)
	(via
		(at 224.537016 -68.918328)
		(size 0.508)
		(drill 0.254)
		(layers "F.Cu" "B.Cu")
		(net "P3V3_E1S_PWRGD_0_R")
	)
	(via
		(at 225.552 -74.422)
		(size 0.508)
		(drill 0.254)
		(layers "F.Cu" "B.Cu")
		(net "P3V3_E1S_PWRGD_0_R")
	)
	(via
		(at 197.461632 -65.188592)
		(size 0.508)
		(drill 0.254)
		(layers "F.Cu" "B.Cu")
		(net "P3V3_E1S_PWRGD_0_R")
	)
	(via
		(at 190.31204 -114.262916)
		(size 0.4572)
		(drill 0.254)
		(layers "F.Cu" "B.Cu")
		(net "P3V3_E1S_PWRGD_0_R")
	)
	(segment
		(start 224.747328 -68.918328)
		(end 226.06 -70.231)
		(width 0.10668)
		(layer "B.Cu")
		(net "P3V3_E1S_PWRGD_0_R")
	)
	(segment
		(start 226.06 -73.914)
		(end 225.552 -74.422)
		(width 0.10668)
		(layer "B.Cu")
		(net "P3V3_E1S_PWRGD_0_R")
	)
	(segment
		(start 226.06 -70.231)
		(end 226.06 -73.914)
		(width 0.10668)
		(layer "B.Cu")
		(net "P3V3_E1S_PWRGD_0_R")
	)
	(segment
		(start 224.537016 -68.918328)
		(end 224.747328 -68.918328)
		(width 0.10668)
		(layer "B.Cu")
		(net "P3V3_E1S_PWRGD_0_R")
	)
	(segment
		(start 218.877896 -65.803526)
		(end 201.712576 -65.803526)
		(width 0.11684)
		(layer "In2.Cu")
		(net "P3V3_E1S_PWRGD_0_R")
	)
	(segment
		(start 219.676472 -68.457318)
		(end 219.426282 -68.207128)
		(width 0.11684)
		(layer "In2.Cu")
		(net "P3V3_E1S_PWRGD_0_R")
	)
	(segment
		(start 219.426282 -66.351912)
		(end 218.877896 -65.803526)
		(width 0.11684)
		(layer "In2.Cu")
		(net "P3V3_E1S_PWRGD_0_R")
	)
	(segment
		(start 224.537016 -68.918328)
		(end 221.704916 -68.918328)
		(width 0.11684)
		(layer "In2.Cu")
		(net "P3V3_E1S_PWRGD_0_R")
	)
	(segment
		(start 201.524108 -65.615058)
		(end 197.888098 -65.615058)
		(width 0.11684)
		(layer "In2.Cu")
		(net "P3V3_E1S_PWRGD_0_R")
	)
	(segment
		(start 221.243906 -68.457318)
		(end 219.676472 -68.457318)
		(width 0.11684)
		(layer "In2.Cu")
		(net "P3V3_E1S_PWRGD_0_R")
	)
	(segment
		(start 201.712576 -65.803526)
		(end 201.524108 -65.615058)
		(width 0.11684)
		(layer "In2.Cu")
		(net "P3V3_E1S_PWRGD_0_R")
	)
	(segment
		(start 197.888098 -65.615058)
		(end 197.461632 -65.188592)
		(width 0.11684)
		(layer "In2.Cu")
		(net "P3V3_E1S_PWRGD_0_R")
	)
	(segment
		(start 219.426282 -68.207128)
		(end 219.426282 -66.351912)
		(width 0.11684)
		(layer "In2.Cu")
		(net "P3V3_E1S_PWRGD_0_R")
	)
	(segment
		(start 221.704916 -68.918328)
		(end 221.243906 -68.457318)
		(width 0.11684)
		(layer "In2.Cu")
		(net "P3V3_E1S_PWRGD_0_R")
	)
	(segment
		(start 190.31204 -114.262916)
		(end 190.354204 -114.262916)
		(width 0.11684)
		(layer "In4.Cu")
		(net "P3V3_E1S_PWRGD_0_R")
	)
	(segment
		(start 197.770242 -99.739958)
		(end 197.770242 -92.105988)
		(width 0.11684)
		(layer "In4.Cu")
		(net "P3V3_E1S_PWRGD_0_R")
	)
	(segment
		(start 196.515736 -100.994464)
		(end 197.770242 -99.739958)
		(width 0.11684)
		(layer "In4.Cu")
		(net "P3V3_E1S_PWRGD_0_R")
	)
	(segment
		(start 193.981578 -101.830378)
		(end 194.817492 -100.994464)
		(width 0.11684)
		(layer "In4.Cu")
		(net "P3V3_E1S_PWRGD_0_R")
	)
	(segment
		(start 196.98208 -85.262212)
		(end 197.130416 -85.113876)
		(width 0.11684)
		(layer "In4.Cu")
		(net "P3V3_E1S_PWRGD_0_R")
	)
	(segment
		(start 193.981578 -104.521762)
		(end 193.981578 -101.830378)
		(width 0.11684)
		(layer "In4.Cu")
		(net "P3V3_E1S_PWRGD_0_R")
	)
	(segment
		(start 193.36766 -105.13568)
		(end 193.981578 -104.521762)
		(width 0.11684)
		(layer "In4.Cu")
		(net "P3V3_E1S_PWRGD_0_R")
	)
	(segment
		(start 191.506348 -105.925874)
		(end 192.296542 -105.13568)
		(width 0.11684)
		(layer "In4.Cu")
		(net "P3V3_E1S_PWRGD_0_R")
	)
	(segment
		(start 196.98208 -91.317826)
		(end 196.98208 -85.262212)
		(width 0.11684)
		(layer "In4.Cu")
		(net "P3V3_E1S_PWRGD_0_R")
	)
	(segment
		(start 191.506348 -109.681518)
		(end 191.506348 -105.925874)
		(width 0.11684)
		(layer "In4.Cu")
		(net "P3V3_E1S_PWRGD_0_R")
	)
	(segment
		(start 197.936866 -65.663826)
		(end 197.461632 -65.188592)
		(width 0.11684)
		(layer "In4.Cu")
		(net "P3V3_E1S_PWRGD_0_R")
	)
	(segment
		(start 200.545954 -72.722994)
		(end 197.936866 -70.113906)
		(width 0.11684)
		(layer "In4.Cu")
		(net "P3V3_E1S_PWRGD_0_R")
	)
	(segment
		(start 191.316864 -109.871002)
		(end 191.506348 -109.681518)
		(width 0.11684)
		(layer "In4.Cu")
		(net "P3V3_E1S_PWRGD_0_R")
	)
	(segment
		(start 194.817492 -100.994464)
		(end 196.515736 -100.994464)
		(width 0.11684)
		(layer "In4.Cu")
		(net "P3V3_E1S_PWRGD_0_R")
	)
	(segment
		(start 190.89243 -109.871002)
		(end 191.316864 -109.871002)
		(width 0.11684)
		(layer "In4.Cu")
		(net "P3V3_E1S_PWRGD_0_R")
	)
	(segment
		(start 197.936866 -70.113906)
		(end 197.936866 -65.663826)
		(width 0.11684)
		(layer "In4.Cu")
		(net "P3V3_E1S_PWRGD_0_R")
	)
	(segment
		(start 190.716408 -110.047024)
		(end 190.89243 -109.871002)
		(width 0.11684)
		(layer "In4.Cu")
		(net "P3V3_E1S_PWRGD_0_R")
	)
	(segment
		(start 192.296542 -105.13568)
		(end 193.36766 -105.13568)
		(width 0.11684)
		(layer "In4.Cu")
		(net "P3V3_E1S_PWRGD_0_R")
	)
	(segment
		(start 200.545954 -79.451454)
		(end 200.545954 -72.722994)
		(width 0.11684)
		(layer "In4.Cu")
		(net "P3V3_E1S_PWRGD_0_R")
	)
	(segment
		(start 197.130416 -85.113876)
		(end 197.130416 -82.866992)
		(width 0.11684)
		(layer "In4.Cu")
		(net "P3V3_E1S_PWRGD_0_R")
	)
	(segment
		(start 197.130416 -82.866992)
		(end 200.545954 -79.451454)
		(width 0.11684)
		(layer "In4.Cu")
		(net "P3V3_E1S_PWRGD_0_R")
	)
	(segment
		(start 197.770242 -92.105988)
		(end 196.98208 -91.317826)
		(width 0.11684)
		(layer "In4.Cu")
		(net "P3V3_E1S_PWRGD_0_R")
	)
	(segment
		(start 190.716408 -113.900712)
		(end 190.716408 -110.047024)
		(width 0.11684)
		(layer "In4.Cu")
		(net "P3V3_E1S_PWRGD_0_R")
	)
	(segment
		(start 190.354204 -114.262916)
		(end 190.716408 -113.900712)
		(width 0.11684)
		(layer "In4.Cu")
		(net "P3V3_E1S_PWRGD_0_R")
	)
	(segment
		(start 250.95962 -68.946522)
		(end 250.95962 -69.962522)
		(width 0.10668)
		(layer "F.Cu")
		(net "P3V3_E1S_EN_0_R")
	)
	(segment
		(start 253.413006 -68.946522)
		(end 252.17882 -68.946522)
		(width 0.10668)
		(layer "F.Cu")
		(net "P3V3_E1S_EN_0_R")
	)
	(segment
		(start 252.17882 -68.946522)
		(end 250.95962 -68.946522)
		(width 0.10668)
		(layer "F.Cu")
		(net "P3V3_E1S_EN_0_R")
	)
	(via
		(at 252.17882 -68.946522)
		(size 0.762)
		(drill 0.381)
		(layers "F.Cu" "B.Cu")
		(net "P3V3_E1S_EN_0_R")
	)
	(segment
		(start 438.257442 -429.318674)
		(end 438.257442 -429.934624)
		(width 0.381)
		(layer "F.Cu")
		(net "P1V8_AUX")
	)
	(segment
		(start 400.933158 -93.30436)
		(end 392.721846 -101.515672)
		(width 0.508)
		(layer "F.Cu")
		(net "P1V8_AUX")
	)
	(segment
		(start 83.478116 -143.785844)
		(end 82.460338 -143.785844)
		(width 0.4572)
		(layer "F.Cu")
		(net "P1V8_AUX")
	)
	(segment
		(start 108.585 -129.680462)
		(end 107.895136 -128.990598)
		(width 0.4064)
		(layer "F.Cu")
		(net "P1V8_AUX")
	)
	(segment
		(start 181.71033 -92.272358)
		(end 181.71033 -91.685618)
		(width 0.4572)
		(layer "F.Cu")
		(net "P1V8_AUX")
	)
	(segment
		(start 154.60726 -111.681006)
		(end 154.686254 -111.76)
		(width 0.381)
		(layer "F.Cu")
		(net "P1V8_AUX")
	)
	(segment
		(start 264.319004 -169.784014)
		(end 264.319004 -185.494422)
		(width 0.381)
		(layer "F.Cu")
		(net "P1V8_AUX")
	)
	(segment
		(start 179.71643 -92.264484)
		(end 179.71643 -91.704414)
		(width 0.4572)
		(layer "F.Cu")
		(net "P1V8_AUX")
	)
	(segment
		(start 234.185206 -333.34706)
		(end 235.73994 -333.34706)
		(width 0.381)
		(layer "F.Cu")
		(net "P1V8_AUX")
	)
	(segment
		(start 347.499686 -27.065986)
		(end 347.499686 -25.529286)
		(width 0.508)
		(layer "F.Cu")
		(net "P1V8_AUX")
	)
	(segment
		(start 181.122066 -121.852944)
		(end 180.732176 -122.242834)
		(width 0.254)
		(layer "F.Cu")
		(net "P1V8_AUX")
	)
	(segment
		(start 179.71643 -91.704414)
		(end 179.817522 -91.603322)
		(width 0.4572)
		(layer "F.Cu")
		(net "P1V8_AUX")
	)
	(segment
		(start 391.83945 -141.02461)
		(end 391.83945 -142.74546)
		(width 0.3556)
		(layer "F.Cu")
		(net "P1V8_AUX")
	)
	(segment
		(start 185.922158 -117.852952)
		(end 186.312048 -118.242842)
		(width 0.254)
		(layer "F.Cu")
		(net "P1V8_AUX")
	)
	(segment
		(start 183.522112 -117.852952)
		(end 183.132222 -118.242842)
		(width 0.254)
		(layer "F.Cu")
		(net "P1V8_AUX")
	)
	(segment
		(start 83.40725 -142.308834)
		(end 83.40725 -143.714978)
		(width 0.4572)
		(layer "F.Cu")
		(net "P1V8_AUX")
	)
	(segment
		(start 143.129762 -74.609452)
		(end 143.129762 -73.623932)
		(width 0.254)
		(layer "F.Cu")
		(net "P1V8_AUX")
	)
	(segment
		(start 99.005136 -119.62257)
		(end 99.005136 -120.92178)
		(width 0.381)
		(layer "F.Cu")
		(net "P1V8_AUX")
	)
	(segment
		(start 262.896604 -190.238126)
		(end 262.896604 -192.026286)
		(width 0.381)
		(layer "F.Cu")
		(net "P1V8_AUX")
	)
	(segment
		(start 239.375696 -331.978)
		(end 240.000282 -331.353414)
		(width 0.381)
		(layer "F.Cu")
		(net "P1V8_AUX")
	)
	(segment
		(start 391.845038 -142.751048)
		(end 392.680698 -142.751048)
		(width 0.4572)
		(layer "F.Cu")
		(net "P1V8_AUX")
	)
	(segment
		(start 152.366218 -72.600058)
		(end 145.204434 -72.600058)
		(width 0.254)
		(layer "F.Cu")
		(net "P1V8_AUX")
	)
	(segment
		(start 98.344736 -120.92178)
		(end 98.344736 -122.52833)
		(width 0.4064)
		(layer "F.Cu")
		(net "P1V8_AUX")
	)
	(segment
		(start 347.499686 -25.529286)
		(end 347.499686 -24.892)
		(width 0.4572)
		(layer "F.Cu")
		(net "P1V8_AUX")
	)
	(segment
		(start 155.42895 -111.76)
		(end 155.42895 -110.998)
		(width 0.381)
		(layer "F.Cu")
		(net "P1V8_AUX")
	)
	(segment
		(start 422.129712 -57.847738)
		(end 422.129712 -58.463688)
		(width 0.4572)
		(layer "F.Cu")
		(net "P1V8_AUX")
	)
	(segment
		(start 420.3573 -38.547548)
		(end 419.74135 -38.547548)
		(width 0.4572)
		(layer "F.Cu")
		(net "P1V8_AUX")
	)
	(segment
		(start 190.721996 -121.852944)
		(end 191.111886 -122.242834)
		(width 0.254)
		(layer "F.Cu")
		(net "P1V8_AUX")
	)
	(segment
		(start 99.470718 -119.156988)
		(end 99.005136 -119.62257)
		(width 0.381)
		(layer "F.Cu")
		(net "P1V8_AUX")
	)
	(segment
		(start 99.005136 -120.92178)
		(end 98.344736 -120.92178)
		(width 0.4064)
		(layer "F.Cu")
		(net "P1V8_AUX")
	)
	(segment
		(start 235.73994 -333.34706)
		(end 237.109 -331.978)
		(width 0.381)
		(layer "F.Cu")
		(net "P1V8_AUX")
	)
	(segment
		(start 154.686254 -111.76)
		(end 155.42895 -111.76)
		(width 0.381)
		(layer "F.Cu")
		(net "P1V8_AUX")
	)
	(segment
		(start 107.895136 -128.990598)
		(end 107.895136 -128.148588)
		(width 0.4064)
		(layer "F.Cu")
		(net "P1V8_AUX")
	)
	(segment
		(start 144.18056 -73.623932)
		(end 143.129762 -73.623932)
		(width 0.254)
		(layer "F.Cu")
		(net "P1V8_AUX")
	)
	(segment
		(start 175.11776 -92.122498)
		(end 175.636936 -91.603322)
		(width 0.381)
		(layer "F.Cu")
		(net "P1V8_AUX")
	)
	(segment
		(start 99.917504 -119.156988)
		(end 99.470718 -119.156988)
		(width 0.381)
		(layer "F.Cu")
		(net "P1V8_AUX")
	)
	(segment
		(start 184.322212 -117.852952)
		(end 183.932322 -118.242842)
		(width 0.254)
		(layer "F.Cu")
		(net "P1V8_AUX")
	)
	(segment
		(start 231.894634 -332.620366)
		(end 233.458512 -332.620366)
		(width 0.381)
		(layer "F.Cu")
		(net "P1V8_AUX")
	)
	(segment
		(start 152.729692 -73.589134)
		(end 152.729692 -72.963532)
		(width 0.254)
		(layer "F.Cu")
		(net "P1V8_AUX")
	)
	(segment
		(start 152.729692 -72.963532)
		(end 152.366218 -72.600058)
		(width 0.254)
		(layer "F.Cu")
		(net "P1V8_AUX")
	)
	(segment
		(start 263.736328 -189.398402)
		(end 262.896604 -190.238126)
		(width 0.381)
		(layer "F.Cu")
		(net "P1V8_AUX")
	)
	(segment
		(start 263.736328 -186.077098)
		(end 263.736328 -189.398402)
		(width 0.381)
		(layer "F.Cu")
		(net "P1V8_AUX")
	)
	(segment
		(start 186.722004 -117.852952)
		(end 187.111894 -118.242842)
		(width 0.254)
		(layer "F.Cu")
		(net "P1V8_AUX")
	)
	(segment
		(start 104.389936 -129.612136)
		(end 104.389936 -128.168146)
		(width 0.4064)
		(layer "F.Cu")
		(net "P1V8_AUX")
	)
	(segment
		(start 400.933158 -73.91273)
		(end 400.933158 -93.30436)
		(width 0.508)
		(layer "F.Cu")
		(net "P1V8_AUX")
	)
	(segment
		(start 153.541476 -111.681006)
		(end 154.60726 -111.681006)
		(width 0.381)
		(layer "F.Cu")
		(net "P1V8_AUX")
	)
	(segment
		(start 231.775 -332.74)
		(end 231.894634 -332.620366)
		(width 0.381)
		(layer "F.Cu")
		(net "P1V8_AUX")
	)
	(segment
		(start 405.760174 -69.085714)
		(end 400.933158 -73.91273)
		(width 0.508)
		(layer "F.Cu")
		(net "P1V8_AUX")
	)
	(segment
		(start 104.521 -129.7432)
		(end 104.389936 -129.612136)
		(width 0.4064)
		(layer "F.Cu")
		(net "P1V8_AUX")
	)
	(segment
		(start 178.69408 -92.285566)
		(end 179.695348 -92.285566)
		(width 0.381)
		(layer "F.Cu")
		(net "P1V8_AUX")
	)
	(segment
		(start 100.884736 -128.803654)
		(end 100.884736 -128.187704)
		(width 0.4064)
		(layer "F.Cu")
		(net "P1V8_AUX")
	)
	(segment
		(start 20.575524 -404.68931)
		(end 20.575524 -405.468328)
		(width 0.381)
		(layer "F.Cu")
		(net "P1V8_AUX")
	)
	(segment
		(start 233.458512 -332.620366)
		(end 234.185206 -333.34706)
		(width 0.381)
		(layer "F.Cu")
		(net "P1V8_AUX")
	)
	(segment
		(start 187.522104 -117.852952)
		(end 187.911994 -118.242842)
		(width 0.254)
		(layer "F.Cu")
		(net "P1V8_AUX")
	)
	(segment
		(start 184.322212 -112.25276)
		(end 183.932322 -111.86287)
		(width 0.254)
		(layer "F.Cu")
		(net "P1V8_AUX")
	)
	(segment
		(start 185.922158 -120.252744)
		(end 186.312048 -120.642634)
		(width 0.254)
		(layer "F.Cu")
		(net "P1V8_AUX")
	)
	(segment
		(start 420.3573 -41.087548)
		(end 419.74135 -41.087548)
		(width 0.4572)
		(layer "F.Cu")
		(net "P1V8_AUX")
	)
	(segment
		(start 181.71033 -91.685618)
		(end 181.737 -91.658948)
		(width 0.4572)
		(layer "F.Cu")
		(net "P1V8_AUX")
	)
	(segment
		(start 147.452842 -110.731046)
		(end 148.094192 -110.731046)
		(width 0.4064)
		(layer "F.Cu")
		(net "P1V8_AUX")
	)
	(segment
		(start 148.241512 -43.03141)
		(end 147.625562 -43.03141)
		(width 0.381)
		(layer "F.Cu")
		(net "P1V8_AUX")
	)
	(segment
		(start 183.522112 -112.25276)
		(end 183.132222 -111.86287)
		(width 0.254)
		(layer "F.Cu")
		(net "P1V8_AUX")
	)
	(segment
		(start 151.181562 -43.93565)
		(end 149.909276 -43.93565)
		(width 0.3556)
		(layer "F.Cu")
		(net "P1V8_AUX")
	)
	(segment
		(start 149.401276 -44.44365)
		(end 148.76399 -44.44365)
		(width 0.4064)
		(layer "F.Cu")
		(net "P1V8_AUX")
	)
	(segment
		(start 181.122066 -108.252768)
		(end 180.732176 -107.862878)
		(width 0.254)
		(layer "F.Cu")
		(net "P1V8_AUX")
	)
	(segment
		(start 149.909276 -43.93565)
		(end 149.401276 -44.44365)
		(width 0.3556)
		(layer "F.Cu")
		(net "P1V8_AUX")
	)
	(segment
		(start 237.109 -331.978)
		(end 239.375696 -331.978)
		(width 0.381)
		(layer "F.Cu")
		(net "P1V8_AUX")
	)
	(segment
		(start 264.319004 -185.494422)
		(end 263.736328 -186.077098)
		(width 0.381)
		(layer "F.Cu")
		(net "P1V8_AUX")
	)
	(segment
		(start 185.122058 -117.852952)
		(end 184.732168 -118.242842)
		(width 0.254)
		(layer "F.Cu")
		(net "P1V8_AUX")
	)
	(segment
		(start 148.241512 -41.746424)
		(end 147.625562 -41.746424)
		(width 0.381)
		(layer "F.Cu")
		(net "P1V8_AUX")
	)
	(segment
		(start 179.695348 -92.285566)
		(end 179.71643 -92.264484)
		(width 0.381)
		(layer "F.Cu")
		(net "P1V8_AUX")
	)
	(segment
		(start 175.11776 -92.285566)
		(end 175.11776 -92.122498)
		(width 0.381)
		(layer "F.Cu")
		(net "P1V8_AUX")
	)
	(segment
		(start 392.721846 -101.515672)
		(end 392.721846 -137.456926)
		(width 0.508)
		(layer "F.Cu")
		(net "P1V8_AUX")
	)
	(segment
		(start 429.006 -58.82005)
		(end 429.006 -59.436)
		(width 0.4572)
		(layer "F.Cu")
		(net "P1V8_AUX")
	)
	(segment
		(start 145.204434 -72.600058)
		(end 144.18056 -73.623932)
		(width 0.254)
		(layer "F.Cu")
		(net "P1V8_AUX")
	)
	(segment
		(start 240.000282 -331.353414)
		(end 240.251488 -331.353414)
		(width 0.381)
		(layer "F.Cu")
		(net "P1V8_AUX")
	)
	(segment
		(start 83.40725 -143.714978)
		(end 83.478116 -143.785844)
		(width 0.4572)
		(layer "F.Cu")
		(net "P1V8_AUX")
	)
	(segment
		(start 391.83945 -142.74546)
		(end 391.845038 -142.751048)
		(width 0.3556)
		(layer "F.Cu")
		(net "P1V8_AUX")
	)
	(via
		(at 263.541764 -265.97229)
		(size 0.508)
		(drill 0.254)
		(layers "F.Cu" "B.Cu")
		(net "P1V8_AUX")
	)
	(via
		(at 154.888692 -79.79283)
		(size 0.508)
		(drill 0.254)
		(layers "F.Cu" "B.Cu")
		(net "P1V8_AUX")
	)
	(via
		(at 153.986992 -73.589134)
		(size 0.508)
		(drill 0.254)
		(layers "F.Cu" "B.Cu")
		(net "P1V8_AUX")
	)
	(via
		(at 154.888692 -81.8388)
		(size 0.508)
		(drill 0.254)
		(layers "F.Cu" "B.Cu")
		(net "P1V8_AUX")
	)
	(via
		(at 249.428 -332.105)
		(size 0.508)
		(drill 0.254)
		(layers "F.Cu" "B.Cu")
		(net "P1V8_AUX")
	)
	(via
		(at 254.78486 -263.481566)
		(size 0.508)
		(drill 0.254)
		(layers "F.Cu" "B.Cu")
		(net "P1V8_AUX")
	)
	(via
		(at 108.585 -129.680462)
		(size 0.508)
		(drill 0.254)
		(layers "F.Cu" "B.Cu")
		(net "P1V8_AUX")
	)
	(via
		(at 427.97095 -42.357548)
		(size 0.508)
		(drill 0.254)
		(layers "F.Cu" "B.Cu")
		(net "P1V8_AUX")
	)
	(via
		(at 183.132222 -118.242842)
		(size 0.4572)
		(drill 0.254)
		(layers "F.Cu" "B.Cu")
		(net "P1V8_AUX")
	)
	(via
		(at 183.932322 -111.86287)
		(size 0.4572)
		(drill 0.254)
		(layers "F.Cu" "B.Cu")
		(net "P1V8_AUX")
	)
	(via
		(at 438.257442 -429.934624)
		(size 0.508)
		(drill 0.254)
		(layers "F.Cu" "B.Cu")
		(net "P1V8_AUX")
	)
	(via
		(at 427.97095 -32.197548)
		(size 0.508)
		(drill 0.254)
		(layers "F.Cu" "B.Cu")
		(net "P1V8_AUX")
	)
	(via
		(at 147.625562 -43.03141)
		(size 0.508)
		(drill 0.254)
		(layers "F.Cu" "B.Cu")
		(net "P1V8_AUX")
	)
	(via
		(at 347.499686 -24.892)
		(size 0.508)
		(drill 0.254)
		(layers "F.Cu" "B.Cu")
		(net "P1V8_AUX")
	)
	(via
		(at 392.721846 -137.456926)
		(size 0.508)
		(drill 0.254)
		(layers "F.Cu" "B.Cu")
		(net "P1V8_AUX")
	)
	(via
		(at 100.884736 -128.803654)
		(size 0.508)
		(drill 0.254)
		(layers "F.Cu" "B.Cu")
		(net "P1V8_AUX")
	)
	(via
		(at 447.027046 -329.520296)
		(size 0.508)
		(drill 0.254)
		(layers "F.Cu" "B.Cu")
		(net "P1V8_AUX")
	)
	(via
		(at 179.817522 -91.603322)
		(size 0.508)
		(drill 0.254)
		(layers "F.Cu" "B.Cu")
		(net "P1V8_AUX")
	)
	(via
		(at 180.732176 -107.862878)
		(size 0.4572)
		(drill 0.254)
		(layers "F.Cu" "B.Cu")
		(net "P1V8_AUX")
	)
	(via
		(at 152.964642 -81.8388)
		(size 0.508)
		(drill 0.254)
		(layers "F.Cu" "B.Cu")
		(net "P1V8_AUX")
	)
	(via
		(at 147.625562 -41.746424)
		(size 0.508)
		(drill 0.254)
		(layers "F.Cu" "B.Cu")
		(net "P1V8_AUX")
	)
	(via
		(at 186.312048 -120.642634)
		(size 0.4572)
		(drill 0.254)
		(layers "F.Cu" "B.Cu")
		(net "P1V8_AUX")
	)
	(via
		(at 153.605992 -79.79283)
		(size 0.508)
		(drill 0.254)
		(layers "F.Cu" "B.Cu")
		(net "P1V8_AUX")
	)
	(via
		(at 465.655152 -373.288306)
		(size 0.508)
		(drill 0.254)
		(layers "F.Cu" "B.Cu")
		(net "P1V8_AUX")
	)
	(via
		(at 154.247342 -79.79283)
		(size 0.508)
		(drill 0.254)
		(layers "F.Cu" "B.Cu")
		(net "P1V8_AUX")
	)
	(via
		(at 152.964642 -75.70089)
		(size 0.508)
		(drill 0.254)
		(layers "F.Cu" "B.Cu")
		(net "P1V8_AUX")
	)
	(via
		(at 147.452842 -110.731046)
		(size 0.508)
		(drill 0.254)
		(layers "F.Cu" "B.Cu")
		(net "P1V8_AUX")
	)
	(via
		(at 170.161966 -103.631746)
		(size 0.508)
		(drill 0.254)
		(layers "F.Cu" "B.Cu")
		(net "P1V8_AUX")
	)
	(via
		(at 154.888692 -75.70089)
		(size 0.508)
		(drill 0.254)
		(layers "F.Cu" "B.Cu")
		(net "P1V8_AUX")
	)
	(via
		(at 99.005136 -120.92178)
		(size 0.508)
		(drill 0.254)
		(layers "F.Cu" "B.Cu")
		(net "P1V8_AUX")
	)
	(via
		(at 154.247342 -75.70089)
		(size 0.508)
		(drill 0.254)
		(layers "F.Cu" "B.Cu")
		(net "P1V8_AUX")
	)
	(via
		(at 244.884956 -140.894816)
		(size 0.508)
		(drill 0.254)
		(layers "F.Cu" "B.Cu")
		(net "P1V8_AUX")
	)
	(via
		(at 187.911994 -118.242842)
		(size 0.4572)
		(drill 0.254)
		(layers "F.Cu" "B.Cu")
		(net "P1V8_AUX")
	)
	(via
		(at 392.680698 -142.751048)
		(size 0.508)
		(drill 0.254)
		(layers "F.Cu" "B.Cu")
		(net "P1V8_AUX")
	)
	(via
		(at 152.964642 -79.79283)
		(size 0.508)
		(drill 0.254)
		(layers "F.Cu" "B.Cu")
		(net "P1V8_AUX")
	)
	(via
		(at 239.016794 -322.452746)
		(size 0.508)
		(drill 0.254)
		(layers "F.Cu" "B.Cu")
		(net "P1V8_AUX")
	)
	(via
		(at 154.628342 -73.589134)
		(size 0.508)
		(drill 0.254)
		(layers "F.Cu" "B.Cu")
		(net "P1V8_AUX")
	)
	(via
		(at 163.100512 -92.272866)
		(size 0.508)
		(drill 0.254)
		(layers "F.Cu" "B.Cu")
		(net "P1V8_AUX")
	)
	(via
		(at 427.97095 -36.007548)
		(size 0.508)
		(drill 0.254)
		(layers "F.Cu" "B.Cu")
		(net "P1V8_AUX")
	)
	(via
		(at 262.896604 -192.026286)
		(size 0.508)
		(drill 0.254)
		(layers "F.Cu" "B.Cu")
		(net "P1V8_AUX")
	)
	(via
		(at 264.319004 -169.784014)
		(size 0.508)
		(drill 0.254)
		(layers "F.Cu" "B.Cu")
		(net "P1V8_AUX")
	)
	(via
		(at 153.605992 -75.70089)
		(size 0.508)
		(drill 0.254)
		(layers "F.Cu" "B.Cu")
		(net "P1V8_AUX")
	)
	(via
		(at 431.17262 -161.637726)
		(size 0.508)
		(drill 0.254)
		(layers "F.Cu" "B.Cu")
		(net "P1V8_AUX")
	)
	(via
		(at 307.860954 -142.196058)
		(size 0.508)
		(drill 0.254)
		(layers "F.Cu" "B.Cu")
		(net "P1V8_AUX")
	)
	(via
		(at 216.2556 -331.596746)
		(size 0.508)
		(drill 0.254)
		(layers "F.Cu" "B.Cu")
		(net "P1V8_AUX")
	)
	(via
		(at 82.460338 -143.785844)
		(size 0.508)
		(drill 0.254)
		(layers "F.Cu" "B.Cu")
		(net "P1V8_AUX")
	)
	(via
		(at 181.737 -91.658948)
		(size 0.508)
		(drill 0.254)
		(layers "F.Cu" "B.Cu")
		(net "P1V8_AUX")
	)
	(via
		(at 226.568 -332.105)
		(size 0.508)
		(drill 0.254)
		(layers "F.Cu" "B.Cu")
		(net "P1V8_AUX")
	)
	(via
		(at 187.111894 -118.242842)
		(size 0.4572)
		(drill 0.254)
		(layers "F.Cu" "B.Cu")
		(net "P1V8_AUX")
	)
	(via
		(at 20.575524 -404.68931)
		(size 0.508)
		(drill 0.254)
		(layers "F.Cu" "B.Cu")
		(net "P1V8_AUX")
	)
	(via
		(at 229.203758 -369.94211)
		(size 0.508)
		(drill 0.254)
		(layers "F.Cu" "B.Cu")
		(net "P1V8_AUX")
	)
	(via
		(at 154.247342 -81.8388)
		(size 0.508)
		(drill 0.254)
		(layers "F.Cu" "B.Cu")
		(net "P1V8_AUX")
	)
	(via
		(at 427.55185 -30.673548)
		(size 0.508)
		(drill 0.254)
		(layers "F.Cu" "B.Cu")
		(net "P1V8_AUX")
	)
	(via
		(at 253.8349 -332.867)
		(size 0.508)
		(drill 0.254)
		(layers "F.Cu" "B.Cu")
		(net "P1V8_AUX")
	)
	(via
		(at 400.916394 -342.550242)
		(size 0.508)
		(drill 0.254)
		(layers "F.Cu" "B.Cu")
		(net "P1V8_AUX")
	)
	(via
		(at 429.006 -59.436)
		(size 0.508)
		(drill 0.254)
		(layers "F.Cu" "B.Cu")
		(net "P1V8_AUX")
	)
	(via
		(at 240.251488 -330.581)
		(size 0.508)
		(drill 0.254)
		(layers "F.Cu" "B.Cu")
		(net "P1V8_AUX")
	)
	(via
		(at 175.636936 -91.603322)
		(size 0.508)
		(drill 0.254)
		(layers "F.Cu" "B.Cu")
		(net "P1V8_AUX")
	)
	(via
		(at 184.732168 -118.242842)
		(size 0.4572)
		(drill 0.254)
		(layers "F.Cu" "B.Cu")
		(net "P1V8_AUX")
	)
	(via
		(at 422.129712 -58.463688)
		(size 0.508)
		(drill 0.254)
		(layers "F.Cu" "B.Cu")
		(net "P1V8_AUX")
	)
	(via
		(at 148.76399 -44.44365)
		(size 0.508)
		(drill 0.254)
		(layers "F.Cu" "B.Cu")
		(net "P1V8_AUX")
	)
	(via
		(at 187.738512 -143.926306)
		(size 0.508)
		(drill 0.254)
		(layers "F.Cu" "B.Cu")
		(net "P1V8_AUX")
	)
	(via
		(at 399.457672 -204.921612)
		(size 0.508)
		(drill 0.254)
		(layers "F.Cu" "B.Cu")
		(net "P1V8_AUX")
	)
	(via
		(at 211.078572 -148.101304)
		(size 0.508)
		(drill 0.254)
		(layers "F.Cu" "B.Cu")
		(net "P1V8_AUX")
	)
	(via
		(at 419.74135 -38.547548)
		(size 0.508)
		(drill 0.254)
		(layers "F.Cu" "B.Cu")
		(net "P1V8_AUX")
	)
	(via
		(at 231.775 -332.74)
		(size 0.508)
		(drill 0.254)
		(layers "F.Cu" "B.Cu")
		(net "P1V8_AUX")
	)
	(via
		(at 405.760174 -69.085714)
		(size 0.508)
		(drill 0.254)
		(layers "F.Cu" "B.Cu")
		(net "P1V8_AUX")
	)
	(via
		(at 427.97095 -40.071548)
		(size 0.508)
		(drill 0.254)
		(layers "F.Cu" "B.Cu")
		(net "P1V8_AUX")
	)
	(via
		(at 153.345642 -73.589134)
		(size 0.508)
		(drill 0.254)
		(layers "F.Cu" "B.Cu")
		(net "P1V8_AUX")
	)
	(via
		(at 186.312048 -118.242842)
		(size 0.4572)
		(drill 0.254)
		(layers "F.Cu" "B.Cu")
		(net "P1V8_AUX")
	)
	(via
		(at 211.582 -127.889)
		(size 0.508)
		(drill 0.254)
		(layers "F.Cu" "B.Cu")
		(net "P1V8_AUX")
	)
	(via
		(at 134.805166 -101.253036)
		(size 0.508)
		(drill 0.254)
		(layers "F.Cu" "B.Cu")
		(net "P1V8_AUX")
	)
	(via
		(at 183.932322 -118.242842)
		(size 0.4572)
		(drill 0.254)
		(layers "F.Cu" "B.Cu")
		(net "P1V8_AUX")
	)
	(via
		(at 400.81708 -341.572342)
		(size 0.508)
		(drill 0.254)
		(layers "F.Cu" "B.Cu")
		(net "P1V8_AUX")
	)
	(via
		(at 104.521 -129.7432)
		(size 0.508)
		(drill 0.254)
		(layers "F.Cu" "B.Cu")
		(net "P1V8_AUX")
	)
	(via
		(at 300.687994 -162.733228)
		(size 0.508)
		(drill 0.254)
		(layers "F.Cu" "B.Cu")
		(net "P1V8_AUX")
	)
	(via
		(at 153.605992 -81.8388)
		(size 0.508)
		(drill 0.254)
		(layers "F.Cu" "B.Cu")
		(net "P1V8_AUX")
	)
	(via
		(at 191.111886 -122.242834)
		(size 0.4572)
		(drill 0.254)
		(layers "F.Cu" "B.Cu")
		(net "P1V8_AUX")
	)
	(via
		(at 216.281 -330.708)
		(size 0.508)
		(drill 0.254)
		(layers "F.Cu" "B.Cu")
		(net "P1V8_AUX")
	)
	(via
		(at 240.251488 -331.353414)
		(size 0.508)
		(drill 0.254)
		(layers "F.Cu" "B.Cu")
		(net "P1V8_AUX")
	)
	(via
		(at 32.78378 -408.517852)
		(size 0.508)
		(drill 0.254)
		(layers "F.Cu" "B.Cu")
		(net "P1V8_AUX")
	)
	(via
		(at 155.42895 -110.998)
		(size 0.508)
		(drill 0.254)
		(layers "F.Cu" "B.Cu")
		(net "P1V8_AUX")
	)
	(via
		(at 180.732176 -122.242834)
		(size 0.4572)
		(drill 0.254)
		(layers "F.Cu" "B.Cu")
		(net "P1V8_AUX")
	)
	(via
		(at 190.279274 -144.86636)
		(size 0.508)
		(drill 0.254)
		(layers "F.Cu" "B.Cu")
		(net "P1V8_AUX")
	)
	(via
		(at 419.74135 -41.087548)
		(size 0.508)
		(drill 0.254)
		(layers "F.Cu" "B.Cu")
		(net "P1V8_AUX")
	)
	(via
		(at 183.132222 -111.86287)
		(size 0.4572)
		(drill 0.254)
		(layers "F.Cu" "B.Cu")
		(net "P1V8_AUX")
	)
	(segment
		(start 216.9033 -330.708)
		(end 216.281 -330.708)
		(width 0.381)
		(layer "B.Cu")
		(net "P1V8_AUX")
	)
	(segment
		(start 172.931328 -367.19002)
		(end 171.92117 -366.179862)
		(width 0.4572)
		(layer "B.Cu")
		(net "P1V8_AUX")
	)
	(segment
		(start 137.490962 -99.597972)
		(end 146.672554 -99.597972)
		(width 0.508)
		(layer "B.Cu")
		(net "P1V8_AUX")
	)
	(segment
		(start 180.634132 -369.992402)
		(end 177.83175 -367.19002)
		(width 0.4572)
		(layer "B.Cu")
		(net "P1V8_AUX")
	)
	(segment
		(start 43.920918 -366.179862)
		(end 40.064436 -370.036344)
		(width 0.4572)
		(layer "B.Cu")
		(net "P1V8_AUX")
	)
	(segment
		(start 184.732168 -118.242842)
		(end 185.132218 -118.642892)
		(width 0.254)
		(layer "B.Cu")
		(net "P1V8_AUX")
	)
	(segment
		(start 147.29714 -100.222558)
		(end 152.231344 -100.222558)
		(width 0.508)
		(layer "B.Cu")
		(net "P1V8_AUX")
	)
	(segment
		(start 404.52929 -204.921612)
		(end 399.457672 -204.921612)
		(width 0.4064)
		(layer "B.Cu")
		(net "P1V8_AUX")
	)
	(segment
		(start 428.5869 -32.197548)
		(end 427.97095 -32.197548)
		(width 0.4064)
		(layer "B.Cu")
		(net "P1V8_AUX")
	)
	(segment
		(start 40.3606 -393.799314)
		(end 39.711122 -394.448792)
		(width 0.4572)
		(layer "B.Cu")
		(net "P1V8_AUX")
	)
	(segment
		(start 161.205926 -94.046548)
		(end 162.073844 -94.046548)
		(width 0.508)
		(layer "B.Cu")
		(net "P1V8_AUX")
	)
	(segment
		(start 183.932322 -111.771176)
		(end 183.62422 -111.463074)
		(width 0.254)
		(layer "B.Cu")
		(net "P1V8_AUX")
	)
	(segment
		(start 154.449018 -94.944438)
		(end 156.416502 -92.976954)
		(width 0.508)
		(layer "B.Cu")
		(net "P1V8_AUX")
	)
	(segment
		(start 186.711844 -117.843046)
		(end 186.312048 -118.242842)
		(width 0.254)
		(layer "B.Cu")
		(net "P1V8_AUX")
	)
	(segment
		(start 40.064436 -370.036344)
		(end 40.064436 -378.616464)
		(width 0.4572)
		(layer "B.Cu")
		(net "P1V8_AUX")
	)
	(segment
		(start 177.83175 -367.19002)
		(end 172.931328 -367.19002)
		(width 0.4572)
		(layer "B.Cu")
		(net "P1V8_AUX")
	)
	(segment
		(start 186.906408 -144.58823)
		(end 187.738512 -144.58823)
		(width 0.4572)
		(layer "B.Cu")
		(net "P1V8_AUX")
	)
	(segment
		(start 217.467688 -369.729258)
		(end 216.95283 -370.244116)
		(width 0.4572)
		(layer "B.Cu")
		(net "P1V8_AUX")
	)
	(segment
		(start 170.184572 -103.102156)
		(end 170.184572 -103.60914)
		(width 0.4572)
		(layer "B.Cu")
		(net "P1V8_AUX")
	)
	(segment
		(start 182.732172 -111.463074)
		(end 182.811674 -111.463074)
		(width 0.254)
		(layer "B.Cu")
		(net "P1V8_AUX")
	)
	(segment
		(start 39.711122 -394.448792)
		(end 39.711122 -400.2913)
		(width 0.4572)
		(layer "B.Cu")
		(net "P1V8_AUX")
	)
	(segment
		(start 183.255158 -118.242842)
		(end 183.132222 -118.242842)
		(width 0.254)
		(layer "B.Cu")
		(net "P1V8_AUX")
	)
	(segment
		(start 261.40537 -218.799156)
		(end 263.541764 -220.93555)
		(width 0.4572)
		(layer "B.Cu")
		(net "P1V8_AUX")
	)
	(segment
		(start 183.532526 -117.842792)
		(end 183.532526 -117.843046)
		(width 0.254)
		(layer "B.Cu")
		(net "P1V8_AUX")
	)
	(segment
		(start 229.203758 -369.94211)
		(end 223.52381 -369.94211)
		(width 0.4572)
		(layer "B.Cu")
		(net "P1V8_AUX")
	)
	(segment
		(start 185.132218 -118.642892)
		(end 185.458608 -118.642892)
		(width 0.254)
		(layer "B.Cu")
		(net "P1V8_AUX")
	)
	(segment
		(start 183.932322 -118.242842)
		(end 183.932322 -118.374922)
		(width 0.254)
		(layer "B.Cu")
		(net "P1V8_AUX")
	)
	(segment
		(start 40.3606 -390.176004)
		(end 40.3606 -393.799314)
		(width 0.4572)
		(layer "B.Cu")
		(net "P1V8_AUX")
	)
	(segment
		(start 183.932322 -111.774478)
		(end 183.932322 -111.86287)
		(width 0.254)
		(layer "B.Cu")
		(net "P1V8_AUX")
	)
	(segment
		(start 187.51169 -117.843046)
		(end 187.111894 -118.242842)
		(width 0.254)
		(layer "B.Cu")
		(net "P1V8_AUX")
	)
	(segment
		(start 183.456326 -111.463074)
		(end 183.132222 -111.787178)
		(width 0.254)
		(layer "B.Cu")
		(net "P1V8_AUX")
	)
	(segment
		(start 427.29785 -30.927548)
		(end 427.55185 -30.673548)
		(width 0.381)
		(layer "B.Cu")
		(net "P1V8_AUX")
	)
	(segment
		(start 263.541764 -220.93555)
		(end 263.541764 -265.97229)
		(width 0.4572)
		(layer "B.Cu")
		(net "P1V8_AUX")
	)
	(segment
		(start 401.554696 -341.572342)
		(end 400.81708 -341.572342)
		(width 0.4572)
		(layer "B.Cu")
		(net "P1V8_AUX")
	)
	(segment
		(start 190.279274 -145.585434)
		(end 190.279274 -144.86636)
		(width 0.4572)
		(layer "B.Cu")
		(net "P1V8_AUX")
	)
	(segment
		(start 428.5869 -36.007548)
		(end 427.97095 -36.007548)
		(width 0.4064)
		(layer "B.Cu")
		(net "P1V8_AUX")
	)
	(segment
		(start 37.072062 -406.93721)
		(end 35.49142 -408.517852)
		(width 0.4572)
		(layer "B.Cu")
		(net "P1V8_AUX")
	)
	(segment
		(start 403.250654 -341.572342)
		(end 401.554696 -341.572342)
		(width 0.4572)
		(layer "B.Cu")
		(net "P1V8_AUX")
	)
	(segment
		(start 226.083114 -333.271114)
		(end 225.9457 -333.1337)
		(width 0.254)
		(layer "B.Cu")
		(net "P1V8_AUX")
	)
	(segment
		(start 240.873788 -330.581)
		(end 240.251488 -330.581)
		(width 0.381)
		(layer "B.Cu")
		(net "P1V8_AUX")
	)
	(segment
		(start 254.3683 -332.867)
		(end 253.8349 -332.867)
		(width 0.254)
		(layer "B.Cu")
		(net "P1V8_AUX")
	)
	(segment
		(start 40.064436 -378.616464)
		(end 39.147496 -379.533404)
		(width 0.4572)
		(layer "B.Cu")
		(net "P1V8_AUX")
	)
	(segment
		(start 262.896604 -194.083178)
		(end 261.40537 -195.574412)
		(width 0.4572)
		(layer "B.Cu")
		(net "P1V8_AUX")
	)
	(segment
		(start 185.911998 -118.642892)
		(end 186.312048 -118.242842)
		(width 0.254)
		(layer "B.Cu")
		(net "P1V8_AUX")
	)
	(segment
		(start 39.147496 -388.9629)
		(end 40.3606 -390.176004)
		(width 0.4572)
		(layer "B.Cu")
		(net "P1V8_AUX")
	)
	(segment
		(start 183.62422 -111.463074)
		(end 183.551068 -111.463074)
		(width 0.254)
		(layer "B.Cu")
		(net "P1V8_AUX")
	)
	(segment
		(start 35.49142 -408.517852)
		(end 32.78378 -408.517852)
		(width 0.4572)
		(layer "B.Cu")
		(net "P1V8_AUX")
	)
	(segment
		(start 184.332372 -118.642892)
		(end 184.477914 -118.642892)
		(width 0.254)
		(layer "B.Cu")
		(net "P1V8_AUX")
	)
	(segment
		(start 39.711122 -400.2913)
		(end 37.072062 -402.93036)
		(width 0.4572)
		(layer "B.Cu")
		(net "P1V8_AUX")
	)
	(segment
		(start 163.100512 -93.01988)
		(end 163.100512 -92.272866)
		(width 0.508)
		(layer "B.Cu")
		(net "P1V8_AUX")
	)
	(segment
		(start 426.9359 -30.927548)
		(end 427.29785 -30.927548)
		(width 0.381)
		(layer "B.Cu")
		(net "P1V8_AUX")
	)
	(segment
		(start 152.231344 -100.222558)
		(end 154.449018 -98.004884)
		(width 0.508)
		(layer "B.Cu")
		(net "P1V8_AUX")
	)
	(segment
		(start 170.184572 -103.60914)
		(end 170.161966 -103.631746)
		(width 0.4572)
		(layer "B.Cu")
		(net "P1V8_AUX")
	)
	(segment
		(start 186.711844 -117.843046)
		(end 186.712098 -117.843046)
		(width 0.254)
		(layer "B.Cu")
		(net "P1V8_AUX")
	)
	(segment
		(start 184.477914 -118.642892)
		(end 184.732168 -118.388638)
		(width 0.254)
		(layer "B.Cu")
		(net "P1V8_AUX")
	)
	(segment
		(start 187.738512 -144.58823)
		(end 187.738512 -143.926306)
		(width 0.4572)
		(layer "B.Cu")
		(net "P1V8_AUX")
	)
	(segment
		(start 154.449018 -98.004884)
		(end 154.449018 -94.944438)
		(width 0.508)
		(layer "B.Cu")
		(net "P1V8_AUX")
	)
	(segment
		(start 39.147496 -379.533404)
		(end 39.147496 -388.9629)
		(width 0.4572)
		(layer "B.Cu")
		(net "P1V8_AUX")
	)
	(segment
		(start 171.92117 -366.179862)
		(end 43.920918 -366.179862)
		(width 0.4572)
		(layer "B.Cu")
		(net "P1V8_AUX")
	)
	(segment
		(start 182.811674 -111.463074)
		(end 183.132222 -111.783622)
		(width 0.254)
		(layer "B.Cu")
		(net "P1V8_AUX")
	)
	(segment
		(start 183.532526 -117.843046)
		(end 183.932322 -118.242842)
		(width 0.254)
		(layer "B.Cu")
		(net "P1V8_AUX")
	)
	(segment
		(start 187.511944 -117.843046)
		(end 187.512198 -117.843046)
		(width 0.254)
		(layer "B.Cu")
		(net "P1V8_AUX")
	)
	(segment
		(start 428.5869 -40.071548)
		(end 427.97095 -40.071548)
		(width 0.4064)
		(layer "B.Cu")
		(net "P1V8_AUX")
	)
	(segment
		(start 186.712098 -117.843046)
		(end 187.111894 -118.242842)
		(width 0.254)
		(layer "B.Cu")
		(net "P1V8_AUX")
	)
	(segment
		(start 186.717178 -144.399)
		(end 186.906408 -144.58823)
		(width 0.4572)
		(layer "B.Cu")
		(net "P1V8_AUX")
	)
	(segment
		(start 135.835898 -101.253036)
		(end 137.490962 -99.597972)
		(width 0.508)
		(layer "B.Cu")
		(net "P1V8_AUX")
	)
	(segment
		(start 227.11029 -333.271114)
		(end 226.083114 -333.271114)
		(width 0.254)
		(layer "B.Cu")
		(net "P1V8_AUX")
	)
	(segment
		(start 184.732168 -118.388638)
		(end 184.732168 -118.242842)
		(width 0.254)
		(layer "B.Cu")
		(net "P1V8_AUX")
	)
	(segment
		(start 180.0352 -107.11053)
		(end 180.0352 -107.165902)
		(width 0.254)
		(layer "B.Cu")
		(net "P1V8_AUX")
	)
	(segment
		(start 187.511944 -117.843046)
		(end 187.51169 -117.843046)
		(width 0.254)
		(layer "B.Cu")
		(net "P1V8_AUX")
	)
	(segment
		(start 180.0352 -107.165902)
		(end 180.732176 -107.862878)
		(width 0.254)
		(layer "B.Cu")
		(net "P1V8_AUX")
	)
	(segment
		(start 160.136332 -92.976954)
		(end 161.205926 -94.046548)
		(width 0.508)
		(layer "B.Cu")
		(net "P1V8_AUX")
	)
	(segment
		(start 188.549534 -369.361466)
		(end 187.31865 -369.361466)
		(width 0.4572)
		(layer "B.Cu")
		(net "P1V8_AUX")
	)
	(segment
		(start 216.9033 -331.724)
		(end 216.776046 -331.596746)
		(width 0.381)
		(layer "B.Cu")
		(net "P1V8_AUX")
	)
	(segment
		(start 183.932322 -111.774478)
		(end 183.932322 -111.771176)
		(width 0.254)
		(layer "B.Cu")
		(net "P1V8_AUX")
	)
	(segment
		(start 184.332372 -111.463074)
		(end 184.243726 -111.463074)
		(width 0.254)
		(layer "B.Cu")
		(net "P1V8_AUX")
	)
	(segment
		(start 405.22017 -204.230732)
		(end 404.52929 -204.921612)
		(width 0.4064)
		(layer "B.Cu")
		(net "P1V8_AUX")
	)
	(segment
		(start 134.805166 -101.253036)
		(end 135.835898 -101.253036)
		(width 0.508)
		(layer "B.Cu")
		(net "P1V8_AUX")
	)
	(segment
		(start 186.687714 -369.992402)
		(end 180.634132 -369.992402)
		(width 0.4572)
		(layer "B.Cu")
		(net "P1V8_AUX")
	)
	(segment
		(start 248.943114 -333.271114)
		(end 248.8057 -333.1337)
		(width 0.254)
		(layer "B.Cu")
		(net "P1V8_AUX")
	)
	(segment
		(start 183.532526 -117.843046)
		(end 183.532526 -117.965474)
		(width 0.254)
		(layer "B.Cu")
		(net "P1V8_AUX")
	)
	(segment
		(start 216.776046 -331.596746)
		(end 216.2556 -331.596746)
		(width 0.381)
		(layer "B.Cu")
		(net "P1V8_AUX")
	)
	(segment
		(start 184.243726 -111.463074)
		(end 183.932322 -111.774478)
		(width 0.254)
		(layer "B.Cu")
		(net "P1V8_AUX")
	)
	(segment
		(start 185.73496 -144.399)
		(end 186.717178 -144.399)
		(width 0.4572)
		(layer "B.Cu")
		(net "P1V8_AUX")
	)
	(segment
		(start 170.795442 -102.780084)
		(end 170.506644 -102.780084)
		(width 0.4572)
		(layer "B.Cu")
		(net "P1V8_AUX")
	)
	(segment
		(start 225.9457 -332.105)
		(end 226.568 -332.105)
		(width 0.254)
		(layer "B.Cu")
		(net "P1V8_AUX")
	)
	(segment
		(start 240.495074 -331.597)
		(end 240.251488 -331.353414)
		(width 0.381)
		(layer "B.Cu")
		(net "P1V8_AUX")
	)
	(segment
		(start 187.31865 -369.361466)
		(end 186.687714 -369.992402)
		(width 0.4572)
		(layer "B.Cu")
		(net "P1V8_AUX")
	)
	(segment
		(start 185.458608 -118.642892)
		(end 185.911998 -118.642892)
		(width 0.254)
		(layer "B.Cu")
		(net "P1V8_AUX")
	)
	(segment
		(start 262.896604 -192.026286)
		(end 262.896604 -194.083178)
		(width 0.4572)
		(layer "B.Cu")
		(net "P1V8_AUX")
	)
	(segment
		(start 156.416502 -92.976954)
		(end 160.136332 -92.976954)
		(width 0.508)
		(layer "B.Cu")
		(net "P1V8_AUX")
	)
	(segment
		(start 250.064778 -333.271114)
		(end 248.943114 -333.271114)
		(width 0.254)
		(layer "B.Cu")
		(net "P1V8_AUX")
	)
	(segment
		(start 231.1527 -332.74)
		(end 231.775 -332.74)
		(width 0.254)
		(layer "B.Cu")
		(net "P1V8_AUX")
	)
	(segment
		(start 223.310958 -369.729258)
		(end 217.467688 -369.729258)
		(width 0.4572)
		(layer "B.Cu")
		(net "P1V8_AUX")
	)
	(segment
		(start 183.551068 -111.463074)
		(end 183.456326 -111.463074)
		(width 0.254)
		(layer "B.Cu")
		(net "P1V8_AUX")
	)
	(segment
		(start 189.432184 -370.244116)
		(end 188.549534 -369.361466)
		(width 0.4572)
		(layer "B.Cu")
		(net "P1V8_AUX")
	)
	(segment
		(start 401.201128 -203.450444)
		(end 400.23923 -203.450444)
		(width 0.4064)
		(layer "B.Cu")
		(net "P1V8_AUX")
	)
	(segment
		(start 428.5869 -42.357548)
		(end 427.97095 -42.357548)
		(width 0.4064)
		(layer "B.Cu")
		(net "P1V8_AUX")
	)
	(segment
		(start 216.95283 -370.244116)
		(end 189.432184 -370.244116)
		(width 0.4572)
		(layer "B.Cu")
		(net "P1V8_AUX")
	)
	(segment
		(start 187.512198 -117.843046)
		(end 187.911994 -118.242842)
		(width 0.254)
		(layer "B.Cu")
		(net "P1V8_AUX")
	)
	(segment
		(start 183.132222 -111.787178)
		(end 183.132222 -111.86287)
		(width 0.254)
		(layer "B.Cu")
		(net "P1V8_AUX")
	)
	(segment
		(start 183.532526 -117.965474)
		(end 183.255158 -118.242842)
		(width 0.254)
		(layer "B.Cu")
		(net "P1V8_AUX")
	)
	(segment
		(start 240.873788 -331.597)
		(end 240.495074 -331.597)
		(width 0.381)
		(layer "B.Cu")
		(net "P1V8_AUX")
	)
	(segment
		(start 162.073844 -94.046548)
		(end 163.100512 -93.01988)
		(width 0.508)
		(layer "B.Cu")
		(net "P1V8_AUX")
	)
	(segment
		(start 248.8057 -332.105)
		(end 249.428 -332.105)
		(width 0.254)
		(layer "B.Cu")
		(net "P1V8_AUX")
	)
	(segment
		(start 261.40537 -195.574412)
		(end 261.40537 -218.799156)
		(width 0.4572)
		(layer "B.Cu")
		(net "P1V8_AUX")
	)
	(segment
		(start 184.200292 -118.642892)
		(end 184.332372 -118.642892)
		(width 0.254)
		(layer "B.Cu")
		(net "P1V8_AUX")
	)
	(segment
		(start 170.506644 -102.780084)
		(end 170.184572 -103.102156)
		(width 0.4572)
		(layer "B.Cu")
		(net "P1V8_AUX")
	)
	(segment
		(start 238.958374 -322.511166)
		(end 239.016794 -322.452746)
		(width 0.381)
		(layer "B.Cu")
		(net "P1V8_AUX")
	)
	(segment
		(start 399.457672 -204.921612)
		(end 399.457672 -204.232002)
		(width 0.4064)
		(layer "B.Cu")
		(net "P1V8_AUX")
	)
	(segment
		(start 405.22017 -203.291186)
		(end 405.22017 -204.230732)
		(width 0.4064)
		(layer "B.Cu")
		(net "P1V8_AUX")
	)
	(segment
		(start 183.132222 -111.783622)
		(end 183.132222 -111.787178)
		(width 0.254)
		(layer "B.Cu")
		(net "P1V8_AUX")
	)
	(segment
		(start 225.9457 -333.1337)
		(end 225.9457 -332.105)
		(width 0.254)
		(layer "B.Cu")
		(net "P1V8_AUX")
	)
	(segment
		(start 401.554696 -342.550242)
		(end 400.916394 -342.550242)
		(width 0.4572)
		(layer "B.Cu")
		(net "P1V8_AUX")
	)
	(segment
		(start 400.23923 -203.450444)
		(end 399.457672 -204.232002)
		(width 0.4064)
		(layer "B.Cu")
		(net "P1V8_AUX")
	)
	(segment
		(start 223.52381 -369.94211)
		(end 223.310958 -369.729258)
		(width 0.4572)
		(layer "B.Cu")
		(net "P1V8_AUX")
	)
	(segment
		(start 248.8057 -333.1337)
		(end 248.8057 -332.105)
		(width 0.254)
		(layer "B.Cu")
		(net "P1V8_AUX")
	)
	(segment
		(start 238.296704 -322.511166)
		(end 238.958374 -322.511166)
		(width 0.381)
		(layer "B.Cu")
		(net "P1V8_AUX")
	)
	(segment
		(start 146.672554 -99.597972)
		(end 147.29714 -100.222558)
		(width 0.508)
		(layer "B.Cu")
		(net "P1V8_AUX")
	)
	(segment
		(start 183.932322 -118.374922)
		(end 184.200292 -118.642892)
		(width 0.254)
		(layer "B.Cu")
		(net "P1V8_AUX")
	)
	(segment
		(start 37.072062 -402.93036)
		(end 37.072062 -406.93721)
		(width 0.4572)
		(layer "B.Cu")
		(net "P1V8_AUX")
	)
	(segment
		(start 405.459692 -337.990942)
		(end 405.459692 -335.570576)
		(width 0.508)
		(layer "In2.Cu")
		(net "P1V8_AUX")
	)
	(segment
		(start 458.328776 -427.785022)
		(end 462.186782 -423.927016)
		(width 0.508)
		(layer "In2.Cu")
		(net "P1V8_AUX")
	)
	(segment
		(start 427.90364 -32.264858)
		(end 427.97095 -32.197548)
		(width 0.508)
		(layer "In2.Cu")
		(net "P1V8_AUX")
	)
	(segment
		(start 438.257442 -430.085246)
		(end 439.9026 -431.730404)
		(width 0.508)
		(layer "In2.Cu")
		(net "P1V8_AUX")
	)
	(segment
		(start 422.109646 -41.11879)
		(end 421.266366 -40.27551)
		(width 0.508)
		(layer "In2.Cu")
		(net "P1V8_AUX")
	)
	(segment
		(start 426.903388 -31.07817)
		(end 426.903388 -31.936944)
		(width 0.508)
		(layer "In2.Cu")
		(net "P1V8_AUX")
	)
	(segment
		(start 128.214882 -120.054116)
		(end 128.214882 -105.331768)
		(width 0.508)
		(layer "In2.Cu")
		(net "P1V8_AUX")
	)
	(segment
		(start 427.97095 -42.357548)
		(end 424.81627 -42.357548)
		(width 0.508)
		(layer "In2.Cu")
		(net "P1V8_AUX")
	)
	(segment
		(start 428.595028 -36.007548)
		(end 428.980346 -35.62223)
		(width 0.508)
		(layer "In2.Cu")
		(net "P1V8_AUX")
	)
	(segment
		(start 419.74135 -41.087548)
		(end 419.74135 -54.178454)
		(width 0.508)
		(layer "In2.Cu")
		(net "P1V8_AUX")
	)
	(segment
		(start 448.804792 -431.730404)
		(end 458.328776 -427.785022)
		(width 0.508)
		(layer "In2.Cu")
		(net "P1V8_AUX")
	)
	(segment
		(start 163.100512 -92.272866)
		(end 163.770056 -91.603322)
		(width 0.508)
		(layer "In2.Cu")
		(net "P1V8_AUX")
	)
	(segment
		(start 374.264682 -23.629874)
		(end 381.993902 -31.359094)
		(width 0.508)
		(layer "In2.Cu")
		(net "P1V8_AUX")
	)
	(segment
		(start 107.241848 -127.61087)
		(end 107.895136 -128.264158)
		(width 0.508)
		(layer "In2.Cu")
		(net "P1V8_AUX")
	)
	(segment
		(start 462.186782 -423.927016)
		(end 462.186782 -405.240744)
		(width 0.508)
		(layer "In2.Cu")
		(net "P1V8_AUX")
	)
	(segment
		(start 104.013 -130.2512)
		(end 104.521 -129.7432)
		(width 0.508)
		(layer "In2.Cu")
		(net "P1V8_AUX")
	)
	(segment
		(start 427.985428 -40.05707)
		(end 427.97095 -40.071548)
		(width 0.508)
		(layer "In2.Cu")
		(net "P1V8_AUX")
	)
	(segment
		(start 427.97095 -36.007548)
		(end 428.595028 -36.007548)
		(width 0.508)
		(layer "In2.Cu")
		(net "P1V8_AUX")
	)
	(segment
		(start 107.895136 -128.990598)
		(end 108.585 -129.680462)
		(width 0.508)
		(layer "In2.Cu")
		(net "P1V8_AUX")
	)
	(segment
		(start 108.585 -129.680462)
		(end 110.890304 -129.680462)
		(width 0.508)
		(layer "In2.Cu")
		(net "P1V8_AUX")
	)
	(segment
		(start 423.577512 -41.11879)
		(end 422.109646 -41.11879)
		(width 0.508)
		(layer "In2.Cu")
		(net "P1V8_AUX")
	)
	(segment
		(start 216.2556 -330.7334)
		(end 216.281 -330.708)
		(width 0.4572)
		(layer "In2.Cu")
		(net "P1V8_AUX")
	)
	(segment
		(start 99.005136 -120.92178)
		(end 99.005136 -123.260612)
		(width 0.508)
		(layer "In2.Cu")
		(net "P1V8_AUX")
	)
	(segment
		(start 428.964852 -40.384984)
		(end 428.636938 -40.05707)
		(width 0.508)
		(layer "In2.Cu")
		(net "P1V8_AUX")
	)
	(segment
		(start 172.26915 -91.603322)
		(end 172.523912 -91.34856)
		(width 0.508)
		(layer "In2.Cu")
		(net "P1V8_AUX")
	)
	(segment
		(start 428.980346 -32.882332)
		(end 428.472346 -32.374332)
		(width 0.508)
		(layer "In2.Cu")
		(net "P1V8_AUX")
	)
	(segment
		(start 422.343834 -58.249566)
		(end 422.129712 -58.463688)
		(width 0.508)
		(layer "In2.Cu")
		(net "P1V8_AUX")
	)
	(segment
		(start 428.472346 -32.374332)
		(end 428.147734 -32.374332)
		(width 0.508)
		(layer "In2.Cu")
		(net "P1V8_AUX")
	)
	(segment
		(start 419.74135 -38.547548)
		(end 419.74135 -41.087548)
		(width 0.508)
		(layer "In2.Cu")
		(net "P1V8_AUX")
	)
	(segment
		(start 400.916394 -341.671656)
		(end 400.81708 -341.572342)
		(width 0.508)
		(layer "In2.Cu")
		(net "P1V8_AUX")
	)
	(segment
		(start 427.30801 -30.673548)
		(end 426.903388 -31.07817)
		(width 0.508)
		(layer "In2.Cu")
		(net "P1V8_AUX")
	)
	(segment
		(start 216.281 -330.708)
		(end 225.171 -330.708)
		(width 0.4572)
		(layer "In2.Cu")
		(net "P1V8_AUX")
	)
	(segment
		(start 461.667098 -395.00937)
		(end 465.829142 -395.00937)
		(width 0.508)
		(layer "In2.Cu")
		(net "P1V8_AUX")
	)
	(segment
		(start 427.121066 -40.071548)
		(end 426.761656 -39.712138)
		(width 0.508)
		(layer "In2.Cu")
		(net "P1V8_AUX")
	)
	(segment
		(start 427.97095 -40.071548)
		(end 427.121066 -40.071548)
		(width 0.508)
		(layer "In2.Cu")
		(net "P1V8_AUX")
	)
	(segment
		(start 177.385726 -91.4781)
		(end 177.510948 -91.603322)
		(width 0.508)
		(layer "In2.Cu")
		(net "P1V8_AUX")
	)
	(segment
		(start 466.69579 -394.142722)
		(end 466.69579 -374.328944)
		(width 0.508)
		(layer "In2.Cu")
		(net "P1V8_AUX")
	)
	(segment
		(start 173.336712 -91.34856)
		(end 173.591474 -91.603322)
		(width 0.508)
		(layer "In2.Cu")
		(net "P1V8_AUX")
	)
	(segment
		(start 226.568 -332.105)
		(end 231.14 -332.105)
		(width 0.4572)
		(layer "In2.Cu")
		(net "P1V8_AUX")
	)
	(segment
		(start 104.521 -129.7432)
		(end 104.521 -128.11887)
		(width 0.508)
		(layer "In2.Cu")
		(net "P1V8_AUX")
	)
	(segment
		(start 122.859038 -125.40996)
		(end 128.214882 -120.054116)
		(width 0.508)
		(layer "In2.Cu")
		(net "P1V8_AUX")
	)
	(segment
		(start 231.14 -332.105)
		(end 231.775 -332.74)
		(width 0.4572)
		(layer "In2.Cu")
		(net "P1V8_AUX")
	)
	(segment
		(start 419.74135 -54.178454)
		(end 422.343834 -56.780938)
		(width 0.508)
		(layer "In2.Cu")
		(net "P1V8_AUX")
	)
	(segment
		(start 100.884736 -129.168906)
		(end 101.96703 -130.2512)
		(width 0.508)
		(layer "In2.Cu")
		(net "P1V8_AUX")
	)
	(segment
		(start 172.523912 -91.34856)
		(end 173.336712 -91.34856)
		(width 0.508)
		(layer "In2.Cu")
		(net "P1V8_AUX")
	)
	(segment
		(start 422.343834 -56.780938)
		(end 422.343834 -58.249566)
		(width 0.508)
		(layer "In2.Cu")
		(net "P1V8_AUX")
	)
	(segment
		(start 111.889794 -128.680972)
		(end 111.889794 -126.85395)
		(width 0.508)
		(layer "In2.Cu")
		(net "P1V8_AUX")
	)
	(segment
		(start 401.878292 -341.572342)
		(end 405.459692 -337.990942)
		(width 0.508)
		(layer "In2.Cu")
		(net "P1V8_AUX")
	)
	(segment
		(start 465.829142 -395.00937)
		(end 466.69579 -394.142722)
		(width 0.508)
		(layer "In2.Cu")
		(net "P1V8_AUX")
	)
	(segment
		(start 406.291034 -31.359094)
		(end 412.537402 -37.605462)
		(width 0.508)
		(layer "In2.Cu")
		(net "P1V8_AUX")
	)
	(segment
		(start 414.911032 -60.434728)
		(end 420.158672 -60.434728)
		(width 0.508)
		(layer "In2.Cu")
		(net "P1V8_AUX")
	)
	(segment
		(start 427.231302 -32.264858)
		(end 427.90364 -32.264858)
		(width 0.508)
		(layer "In2.Cu")
		(net "P1V8_AUX")
	)
	(segment
		(start 163.770056 -91.603322)
		(end 172.26915 -91.603322)
		(width 0.508)
		(layer "In2.Cu")
		(net "P1V8_AUX")
	)
	(segment
		(start 216.2556 -331.596746)
		(end 216.2556 -330.7334)
		(width 0.4572)
		(layer "In2.Cu")
		(net "P1V8_AUX")
	)
	(segment
		(start 176.226978 -91.4781)
		(end 177.385726 -91.4781)
		(width 0.508)
		(layer "In2.Cu")
		(net "P1V8_AUX")
	)
	(segment
		(start 100.884736 -128.803654)
		(end 100.884736 -129.168906)
		(width 0.508)
		(layer "In2.Cu")
		(net "P1V8_AUX")
	)
	(segment
		(start 175.636936 -91.603322)
		(end 176.101756 -91.603322)
		(width 0.508)
		(layer "In2.Cu")
		(net "P1V8_AUX")
	)
	(segment
		(start 100.884736 -125.140212)
		(end 100.884736 -128.803654)
		(width 0.508)
		(layer "In2.Cu")
		(net "P1V8_AUX")
	)
	(segment
		(start 173.591474 -91.603322)
		(end 175.636936 -91.603322)
		(width 0.508)
		(layer "In2.Cu")
		(net "P1V8_AUX")
	)
	(segment
		(start 107.895136 -128.264158)
		(end 107.895136 -128.990598)
		(width 0.508)
		(layer "In2.Cu")
		(net "P1V8_AUX")
	)
	(segment
		(start 347.499686 -24.892)
		(end 347.499686 -24.051514)
		(width 0.508)
		(layer "In2.Cu")
		(net "P1V8_AUX")
	)
	(segment
		(start 426.761656 -36.92779)
		(end 427.681898 -36.007548)
		(width 0.508)
		(layer "In2.Cu")
		(net "P1V8_AUX")
	)
	(segment
		(start 347.499686 -24.051514)
		(end 347.921326 -23.629874)
		(width 0.508)
		(layer "In2.Cu")
		(net "P1V8_AUX")
	)
	(segment
		(start 426.761656 -39.712138)
		(end 426.761656 -36.92779)
		(width 0.508)
		(layer "In2.Cu")
		(net "P1V8_AUX")
	)
	(segment
		(start 459.911196 -402.965158)
		(end 459.911196 -396.765272)
		(width 0.508)
		(layer "In2.Cu")
		(net "P1V8_AUX")
	)
	(segment
		(start 421.266366 -38.964108)
		(end 420.985188 -38.68293)
		(width 0.508)
		(layer "In2.Cu")
		(net "P1V8_AUX")
	)
	(segment
		(start 412.537402 -37.605462)
		(end 412.537402 -58.061098)
		(width 0.508)
		(layer "In2.Cu")
		(net "P1V8_AUX")
	)
	(segment
		(start 427.97095 -42.357548)
		(end 428.44466 -42.357548)
		(width 0.508)
		(layer "In2.Cu")
		(net "P1V8_AUX")
	)
	(segment
		(start 428.147734 -32.374332)
		(end 427.97095 -32.197548)
		(width 0.508)
		(layer "In2.Cu")
		(net "P1V8_AUX")
	)
	(segment
		(start 462.186782 -405.240744)
		(end 459.911196 -402.965158)
		(width 0.508)
		(layer "In2.Cu")
		(net "P1V8_AUX")
	)
	(segment
		(start 445.98971 -328.48296)
		(end 447.027046 -329.520296)
		(width 0.508)
		(layer "In2.Cu")
		(net "P1V8_AUX")
	)
	(segment
		(start 439.9026 -431.730404)
		(end 448.804792 -431.730404)
		(width 0.508)
		(layer "In2.Cu")
		(net "P1V8_AUX")
	)
	(segment
		(start 427.55185 -30.673548)
		(end 427.30801 -30.673548)
		(width 0.508)
		(layer "In2.Cu")
		(net "P1V8_AUX")
	)
	(segment
		(start 420.985188 -38.68293)
		(end 419.876732 -38.68293)
		(width 0.508)
		(layer "In2.Cu")
		(net "P1V8_AUX")
	)
	(segment
		(start 412.537402 -58.061098)
		(end 414.911032 -60.434728)
		(width 0.508)
		(layer "In2.Cu")
		(net "P1V8_AUX")
	)
	(segment
		(start 405.459692 -335.570576)
		(end 408.360118 -332.67015)
		(width 0.508)
		(layer "In2.Cu")
		(net "P1V8_AUX")
	)
	(segment
		(start 428.44466 -42.357548)
		(end 428.964852 -41.837356)
		(width 0.508)
		(layer "In2.Cu")
		(net "P1V8_AUX")
	)
	(segment
		(start 128.214882 -105.331768)
		(end 132.293614 -101.253036)
		(width 0.508)
		(layer "In2.Cu")
		(net "P1V8_AUX")
	)
	(segment
		(start 176.101756 -91.603322)
		(end 176.226978 -91.4781)
		(width 0.508)
		(layer "In2.Cu")
		(net "P1V8_AUX")
	)
	(segment
		(start 428.636938 -40.05707)
		(end 427.985428 -40.05707)
		(width 0.508)
		(layer "In2.Cu")
		(net "P1V8_AUX")
	)
	(segment
		(start 110.890304 -129.680462)
		(end 111.889794 -128.680972)
		(width 0.508)
		(layer "In2.Cu")
		(net "P1V8_AUX")
	)
	(segment
		(start 111.889794 -126.85395)
		(end 113.333784 -125.40996)
		(width 0.508)
		(layer "In2.Cu")
		(net "P1V8_AUX")
	)
	(segment
		(start 132.293614 -101.253036)
		(end 134.805166 -101.253036)
		(width 0.508)
		(layer "In2.Cu")
		(net "P1V8_AUX")
	)
	(segment
		(start 424.81627 -42.357548)
		(end 423.577512 -41.11879)
		(width 0.508)
		(layer "In2.Cu")
		(net "P1V8_AUX")
	)
	(segment
		(start 101.96703 -130.2512)
		(end 104.013 -130.2512)
		(width 0.508)
		(layer "In2.Cu")
		(net "P1V8_AUX")
	)
	(segment
		(start 421.266366 -40.27551)
		(end 421.266366 -38.964108)
		(width 0.508)
		(layer "In2.Cu")
		(net "P1V8_AUX")
	)
	(segment
		(start 347.921326 -23.629874)
		(end 374.264682 -23.629874)
		(width 0.508)
		(layer "In2.Cu")
		(net "P1V8_AUX")
	)
	(segment
		(start 428.964852 -41.837356)
		(end 428.964852 -40.384984)
		(width 0.508)
		(layer "In2.Cu")
		(net "P1V8_AUX")
	)
	(segment
		(start 408.360118 -332.67015)
		(end 412.03245 -331.148944)
		(width 0.508)
		(layer "In2.Cu")
		(net "P1V8_AUX")
	)
	(segment
		(start 438.257442 -429.934624)
		(end 438.257442 -430.085246)
		(width 0.508)
		(layer "In2.Cu")
		(net "P1V8_AUX")
	)
	(segment
		(start 400.916394 -342.550242)
		(end 400.916394 -341.671656)
		(width 0.508)
		(layer "In2.Cu")
		(net "P1V8_AUX")
	)
	(segment
		(start 381.993902 -31.359094)
		(end 406.291034 -31.359094)
		(width 0.508)
		(layer "In2.Cu")
		(net "P1V8_AUX")
	)
	(segment
		(start 428.980346 -35.62223)
		(end 428.980346 -32.882332)
		(width 0.508)
		(layer "In2.Cu")
		(net "P1V8_AUX")
	)
	(segment
		(start 105.029 -127.61087)
		(end 107.241848 -127.61087)
		(width 0.508)
		(layer "In2.Cu")
		(net "P1V8_AUX")
	)
	(segment
		(start 420.158672 -60.434728)
		(end 422.129712 -58.463688)
		(width 0.508)
		(layer "In2.Cu")
		(net "P1V8_AUX")
	)
	(segment
		(start 459.911196 -396.765272)
		(end 461.667098 -395.00937)
		(width 0.508)
		(layer "In2.Cu")
		(net "P1V8_AUX")
	)
	(segment
		(start 104.521 -128.11887)
		(end 105.029 -127.61087)
		(width 0.508)
		(layer "In2.Cu")
		(net "P1V8_AUX")
	)
	(segment
		(start 225.171 -330.708)
		(end 226.568 -332.105)
		(width 0.4572)
		(layer "In2.Cu")
		(net "P1V8_AUX")
	)
	(segment
		(start 99.005136 -123.260612)
		(end 100.884736 -125.140212)
		(width 0.508)
		(layer "In2.Cu")
		(net "P1V8_AUX")
	)
	(segment
		(start 412.03245 -331.148944)
		(end 414.698434 -328.48296)
		(width 0.508)
		(layer "In2.Cu")
		(net "P1V8_AUX")
	)
	(segment
		(start 427.681898 -36.007548)
		(end 427.97095 -36.007548)
		(width 0.508)
		(layer "In2.Cu")
		(net "P1V8_AUX")
	)
	(segment
		(start 113.333784 -125.40996)
		(end 122.859038 -125.40996)
		(width 0.508)
		(layer "In2.Cu")
		(net "P1V8_AUX")
	)
	(segment
		(start 419.876732 -38.68293)
		(end 419.74135 -38.547548)
		(width 0.508)
		(layer "In2.Cu")
		(net "P1V8_AUX")
	)
	(segment
		(start 466.69579 -374.328944)
		(end 465.655152 -373.288306)
		(width 0.508)
		(layer "In2.Cu")
		(net "P1V8_AUX")
	)
	(segment
		(start 177.510948 -91.603322)
		(end 179.817522 -91.603322)
		(width 0.508)
		(layer "In2.Cu")
		(net "P1V8_AUX")
	)
	(segment
		(start 426.903388 -31.936944)
		(end 427.231302 -32.264858)
		(width 0.508)
		(layer "In2.Cu")
		(net "P1V8_AUX")
	)
	(segment
		(start 414.698434 -328.48296)
		(end 445.98971 -328.48296)
		(width 0.508)
		(layer "In2.Cu")
		(net "P1V8_AUX")
	)
	(segment
		(start 400.81708 -341.572342)
		(end 401.878292 -341.572342)
		(width 0.508)
		(layer "In2.Cu")
		(net "P1V8_AUX")
	)
	(segment
		(start 211.582 -127.889)
		(end 210.125818 -129.345182)
		(width 0.4572)
		(layer "In4.Cu")
		(net "P1V8_AUX")
	)
	(segment
		(start 393.923774 -142.836646)
		(end 392.766296 -142.836646)
		(width 0.508)
		(layer "In4.Cu")
		(net "P1V8_AUX")
	)
	(segment
		(start 232.65638 -368.082576)
		(end 232.65638 -359.774236)
		(width 0.4572)
		(layer "In4.Cu")
		(net "P1V8_AUX")
	)
	(segment
		(start 253.0729 -332.105)
		(end 253.8349 -332.867)
		(width 0.4572)
		(layer "In4.Cu")
		(net "P1V8_AUX")
	)
	(segment
		(start 392.766296 -142.836646)
		(end 392.680698 -142.751048)
		(width 0.508)
		(layer "In4.Cu")
		(net "P1V8_AUX")
	)
	(segment
		(start 229.203758 -369.94211)
		(end 229.900226 -369.245642)
		(width 0.4572)
		(layer "In4.Cu")
		(net "P1V8_AUX")
	)
	(segment
		(start 158.064454 -108.907072)
		(end 159.069024 -108.907072)
		(width 0.508)
		(layer "In4.Cu")
		(net "P1V8_AUX")
	)
	(segment
		(start 394.283184 -138.057636)
		(end 394.283184 -142.477236)
		(width 0.508)
		(layer "In4.Cu")
		(net "P1V8_AUX")
	)
	(segment
		(start 232.65638 -359.774236)
		(end 230.98125 -358.099106)
		(width 0.4572)
		(layer "In4.Cu")
		(net "P1V8_AUX")
	)
	(segment
		(start 300.687994 -162.733228)
		(end 302.449992 -160.97123)
		(width 0.508)
		(layer "In4.Cu")
		(net "P1V8_AUX")
	)
	(segment
		(start 249.428 -332.105)
		(end 253.0729 -332.105)
		(width 0.4572)
		(layer "In4.Cu")
		(net "P1V8_AUX")
	)
	(segment
		(start 302.449992 -160.97123)
		(end 302.449992 -153.53284)
		(width 0.508)
		(layer "In4.Cu")
		(net "P1V8_AUX")
	)
	(segment
		(start 210.125818 -131.711446)
		(end 211.078572 -132.6642)
		(width 0.4572)
		(layer "In4.Cu")
		(net "P1V8_AUX")
	)
	(segment
		(start 252.39345 -324.352666)
		(end 252.39345 -322.2371)
		(width 0.4572)
		(layer "In4.Cu")
		(net "P1V8_AUX")
	)
	(segment
		(start 241.54765 -329.284838)
		(end 240.251488 -330.581)
		(width 0.4572)
		(layer "In4.Cu")
		(net "P1V8_AUX")
	)
	(segment
		(start 255.416558 -264.113264)
		(end 254.78486 -263.481566)
		(width 0.4572)
		(layer "In4.Cu")
		(net "P1V8_AUX")
	)
	(segment
		(start 249.428 -332.105)
		(end 249.428 -327.318116)
		(width 0.4572)
		(layer "In4.Cu")
		(net "P1V8_AUX")
	)
	(segment
		(start 454.659746 -320.675)
		(end 448.818 -320.675)
		(width 0.508)
		(layer "In4.Cu")
		(net "P1V8_AUX")
	)
	(segment
		(start 159.069024 -108.907072)
		(end 163.947856 -104.02824)
		(width 0.508)
		(layer "In4.Cu")
		(net "P1V8_AUX")
	)
	(segment
		(start 239.786668 -322.452746)
		(end 241.54765 -324.213728)
		(width 0.4572)
		(layer "In4.Cu")
		(net "P1V8_AUX")
	)
	(segment
		(start 155.973526 -110.998)
		(end 158.064454 -108.907072)
		(width 0.508)
		(layer "In4.Cu")
		(net "P1V8_AUX")
	)
	(segment
		(start 302.449992 -153.53284)
		(end 305.448462 -150.53437)
		(width 0.508)
		(layer "In4.Cu")
		(net "P1V8_AUX")
	)
	(segment
		(start 448.818 -320.675)
		(end 447.167 -322.326)
		(width 0.508)
		(layer "In4.Cu")
		(net "P1V8_AUX")
	)
	(segment
		(start 211.078572 -132.6642)
		(end 211.078572 -148.101304)
		(width 0.4572)
		(layer "In4.Cu")
		(net "P1V8_AUX")
	)
	(segment
		(start 148.238718 -111.516922)
		(end 150.583646 -111.516922)
		(width 0.508)
		(layer "In4.Cu")
		(net "P1V8_AUX")
	)
	(segment
		(start 147.452842 -110.731046)
		(end 148.238718 -111.516922)
		(width 0.508)
		(layer "In4.Cu")
		(net "P1V8_AUX")
	)
	(segment
		(start 163.947856 -104.02824)
		(end 163.947856 -97.722436)
		(width 0.508)
		(layer "In4.Cu")
		(net "P1V8_AUX")
	)
	(segment
		(start 230.98125 -358.099106)
		(end 230.98125 -344.998548)
		(width 0.4572)
		(layer "In4.Cu")
		(net "P1V8_AUX")
	)
	(segment
		(start 241.54765 -324.213728)
		(end 241.54765 -329.284838)
		(width 0.4572)
		(layer "In4.Cu")
		(net "P1V8_AUX")
	)
	(segment
		(start 305.448462 -150.53437)
		(end 305.448462 -144.60855)
		(width 0.508)
		(layer "In4.Cu")
		(net "P1V8_AUX")
	)
	(segment
		(start 231.493314 -369.245642)
		(end 232.65638 -368.082576)
		(width 0.4572)
		(layer "In4.Cu")
		(net "P1V8_AUX")
	)
	(segment
		(start 239.016794 -322.452746)
		(end 239.786668 -322.452746)
		(width 0.4572)
		(layer "In4.Cu")
		(net "P1V8_AUX")
	)
	(segment
		(start 252.39345 -322.2371)
		(end 255.416558 -319.213992)
		(width 0.4572)
		(layer "In4.Cu")
		(net "P1V8_AUX")
	)
	(segment
		(start 249.428 -327.318116)
		(end 252.39345 -324.352666)
		(width 0.4572)
		(layer "In4.Cu")
		(net "P1V8_AUX")
	)
	(segment
		(start 447.167 -329.380342)
		(end 447.027046 -329.520296)
		(width 0.508)
		(layer "In4.Cu")
		(net "P1V8_AUX")
	)
	(segment
		(start 155.42895 -110.998)
		(end 155.973526 -110.998)
		(width 0.508)
		(layer "In4.Cu")
		(net "P1V8_AUX")
	)
	(segment
		(start 451.606666 -172.395896)
		(end 451.606666 -183.15305)
		(width 0.508)
		(layer "In4.Cu")
		(net "P1V8_AUX")
	)
	(segment
		(start 431.696622 -161.637726)
		(end 433.27447 -160.059878)
		(width 0.508)
		(layer "In4.Cu")
		(net "P1V8_AUX")
	)
	(segment
		(start 255.416558 -319.213992)
		(end 255.416558 -264.113264)
		(width 0.4572)
		(layer "In4.Cu")
		(net "P1V8_AUX")
	)
	(segment
		(start 436.897018 -160.059878)
		(end 438.98947 -162.15233)
		(width 0.508)
		(layer "In4.Cu")
		(net "P1V8_AUX")
	)
	(segment
		(start 456.461622 -188.008006)
		(end 456.461622 -318.873124)
		(width 0.508)
		(layer "In4.Cu")
		(net "P1V8_AUX")
	)
	(segment
		(start 210.125818 -129.345182)
		(end 210.125818 -131.711446)
		(width 0.4572)
		(layer "In4.Cu")
		(net "P1V8_AUX")
	)
	(segment
		(start 305.448462 -144.60855)
		(end 307.860954 -142.196058)
		(width 0.508)
		(layer "In4.Cu")
		(net "P1V8_AUX")
	)
	(segment
		(start 392.721846 -137.456926)
		(end 393.682474 -137.456926)
		(width 0.508)
		(layer "In4.Cu")
		(net "P1V8_AUX")
	)
	(segment
		(start 433.27447 -160.059878)
		(end 436.897018 -160.059878)
		(width 0.508)
		(layer "In4.Cu")
		(net "P1V8_AUX")
	)
	(segment
		(start 394.283184 -142.477236)
		(end 393.923774 -142.836646)
		(width 0.508)
		(layer "In4.Cu")
		(net "P1V8_AUX")
	)
	(segment
		(start 438.98947 -162.15233)
		(end 441.3631 -162.15233)
		(width 0.508)
		(layer "In4.Cu")
		(net "P1V8_AUX")
	)
	(segment
		(start 229.900226 -369.245642)
		(end 231.493314 -369.245642)
		(width 0.4572)
		(layer "In4.Cu")
		(net "P1V8_AUX")
	)
	(segment
		(start 230.98125 -344.998548)
		(end 231.420924 -344.558874)
		(width 0.4572)
		(layer "In4.Cu")
		(net "P1V8_AUX")
	)
	(segment
		(start 151.102568 -110.998)
		(end 155.42895 -110.998)
		(width 0.508)
		(layer "In4.Cu")
		(net "P1V8_AUX")
	)
	(segment
		(start 231.420924 -344.558874)
		(end 231.420924 -333.094076)
		(width 0.4572)
		(layer "In4.Cu")
		(net "P1V8_AUX")
	)
	(segment
		(start 447.167 -322.326)
		(end 447.167 -329.380342)
		(width 0.508)
		(layer "In4.Cu")
		(net "P1V8_AUX")
	)
	(segment
		(start 451.606666 -183.15305)
		(end 456.461622 -188.008006)
		(width 0.508)
		(layer "In4.Cu")
		(net "P1V8_AUX")
	)
	(segment
		(start 393.682474 -137.456926)
		(end 394.283184 -138.057636)
		(width 0.508)
		(layer "In4.Cu")
		(net "P1V8_AUX")
	)
	(segment
		(start 231.420924 -333.094076)
		(end 231.775 -332.74)
		(width 0.4572)
		(layer "In4.Cu")
		(net "P1V8_AUX")
	)
	(segment
		(start 431.17262 -161.637726)
		(end 431.696622 -161.637726)
		(width 0.508)
		(layer "In4.Cu")
		(net "P1V8_AUX")
	)
	(segment
		(start 150.583646 -111.516922)
		(end 151.102568 -110.998)
		(width 0.508)
		(layer "In4.Cu")
		(net "P1V8_AUX")
	)
	(segment
		(start 163.100512 -96.875092)
		(end 163.100512 -92.272866)
		(width 0.508)
		(layer "In4.Cu")
		(net "P1V8_AUX")
	)
	(segment
		(start 163.947856 -97.722436)
		(end 163.100512 -96.875092)
		(width 0.508)
		(layer "In4.Cu")
		(net "P1V8_AUX")
	)
	(segment
		(start 456.461622 -318.873124)
		(end 454.659746 -320.675)
		(width 0.508)
		(layer "In4.Cu")
		(net "P1V8_AUX")
	)
	(segment
		(start 441.3631 -162.15233)
		(end 451.606666 -172.395896)
		(width 0.508)
		(layer "In4.Cu")
		(net "P1V8_AUX")
	)
	(segment
		(start 412.662116 -69.085714)
		(end 422.156128 -59.591702)
		(width 0.508)
		(layer "In6.Cu")
		(net "P1V8_AUX")
	)
	(segment
		(start 307.860954 -136.222994)
		(end 312.102246 -131.981702)
		(width 0.508)
		(layer "In6.Cu")
		(net "P1V8_AUX")
	)
	(segment
		(start 82.460338 -143.785844)
		(end 82.460338 -142.807944)
		(width 0.508)
		(layer "In6.Cu")
		(net "P1V8_AUX")
	)
	(segment
		(start 347.523054 -134.074662)
		(end 347.666564 -134.074662)
		(width 0.508)
		(layer "In6.Cu")
		(net "P1V8_AUX")
	)
	(segment
		(start 193.489326 -144.86636)
		(end 202.431396 -148.570442)
		(width 0.4572)
		(layer "In6.Cu")
		(net "P1V8_AUX")
	)
	(segment
		(start 202.431396 -148.570442)
		(end 210.08213 -148.570442)
		(width 0.4572)
		(layer "In6.Cu")
		(net "P1V8_AUX")
	)
	(segment
		(start 210.08213 -148.570442)
		(end 210.551268 -148.101304)
		(width 0.4572)
		(layer "In6.Cu")
		(net "P1V8_AUX")
	)
	(segment
		(start 342.406732 -128.95834)
		(end 347.523054 -134.074662)
		(width 0.508)
		(layer "In6.Cu")
		(net "P1V8_AUX")
	)
	(segment
		(start 187.738512 -144.575784)
		(end 187.738512 -143.926306)
		(width 0.4572)
		(layer "In6.Cu")
		(net "P1V8_AUX")
	)
	(segment
		(start 188.029088 -144.86636)
		(end 187.738512 -144.575784)
		(width 0.4572)
		(layer "In6.Cu")
		(net "P1V8_AUX")
	)
	(segment
		(start 92.862146 -132.670804)
		(end 94.45498 -131.07797)
		(width 0.508)
		(layer "In6.Cu")
		(net "P1V8_AUX")
	)
	(segment
		(start 239.325404 -135.887714)
		(end 244.332506 -140.894816)
		(width 0.508)
		(layer "In6.Cu")
		(net "P1V8_AUX")
	)
	(segment
		(start 348.310454 -134.718552)
		(end 360.021124 -134.718552)
		(width 0.508)
		(layer "In6.Cu")
		(net "P1V8_AUX")
	)
	(segment
		(start 82.460338 -142.807944)
		(end 84.82076 -140.447522)
		(width 0.508)
		(layer "In6.Cu")
		(net "P1V8_AUX")
	)
	(segment
		(start 213.70925 -130.01625)
		(end 218.90863 -130.01625)
		(width 0.508)
		(layer "In6.Cu")
		(net "P1V8_AUX")
	)
	(segment
		(start 360.021124 -134.718552)
		(end 361.131866 -133.60781)
		(width 0.508)
		(layer "In6.Cu")
		(net "P1V8_AUX")
	)
	(segment
		(start 211.582 -127.889)
		(end 213.70925 -130.01625)
		(width 0.508)
		(layer "In6.Cu")
		(net "P1V8_AUX")
	)
	(segment
		(start 390.715246 -133.60781)
		(end 392.721846 -135.61441)
		(width 0.508)
		(layer "In6.Cu")
		(net "P1V8_AUX")
	)
	(segment
		(start 98.61042 -131.07797)
		(end 100.884736 -128.803654)
		(width 0.508)
		(layer "In6.Cu")
		(net "P1V8_AUX")
	)
	(segment
		(start 323.71792 -128.95834)
		(end 342.406732 -128.95834)
		(width 0.508)
		(layer "In6.Cu")
		(net "P1V8_AUX")
	)
	(segment
		(start 86.58479 -140.447522)
		(end 87.10041 -139.931902)
		(width 0.508)
		(layer "In6.Cu")
		(net "P1V8_AUX")
	)
	(segment
		(start 218.90863 -130.01625)
		(end 224.780094 -135.887714)
		(width 0.508)
		(layer "In6.Cu")
		(net "P1V8_AUX")
	)
	(segment
		(start 320.713354 -131.8895)
		(end 320.78676 -131.8895)
		(width 0.508)
		(layer "In6.Cu")
		(net "P1V8_AUX")
	)
	(segment
		(start 429.006 -57.960768)
		(end 428.249588 -57.204356)
		(width 0.4572)
		(layer "In6.Cu")
		(net "P1V8_AUX")
	)
	(segment
		(start 87.10041 -133.841744)
		(end 88.27135 -132.670804)
		(width 0.508)
		(layer "In6.Cu")
		(net "P1V8_AUX")
	)
	(segment
		(start 422.156128 -58.490104)
		(end 422.129712 -58.463688)
		(width 0.508)
		(layer "In6.Cu")
		(net "P1V8_AUX")
	)
	(segment
		(start 190.279274 -144.86636)
		(end 188.029088 -144.86636)
		(width 0.4572)
		(layer "In6.Cu")
		(net "P1V8_AUX")
	)
	(segment
		(start 429.006 -59.436)
		(end 429.006 -57.960768)
		(width 0.4572)
		(layer "In6.Cu")
		(net "P1V8_AUX")
	)
	(segment
		(start 84.82076 -140.447522)
		(end 86.58479 -140.447522)
		(width 0.508)
		(layer "In6.Cu")
		(net "P1V8_AUX")
	)
	(segment
		(start 428.249588 -57.204356)
		(end 423.389044 -57.204356)
		(width 0.4572)
		(layer "In6.Cu")
		(net "P1V8_AUX")
	)
	(segment
		(start 190.279274 -144.86636)
		(end 193.489326 -144.86636)
		(width 0.4572)
		(layer "In6.Cu")
		(net "P1V8_AUX")
	)
	(segment
		(start 224.780094 -135.887714)
		(end 239.325404 -135.887714)
		(width 0.508)
		(layer "In6.Cu")
		(net "P1V8_AUX")
	)
	(segment
		(start 87.10041 -139.931902)
		(end 87.10041 -133.841744)
		(width 0.508)
		(layer "In6.Cu")
		(net "P1V8_AUX")
	)
	(segment
		(start 392.721846 -135.61441)
		(end 392.721846 -137.456926)
		(width 0.508)
		(layer "In6.Cu")
		(net "P1V8_AUX")
	)
	(segment
		(start 422.156128 -59.591702)
		(end 422.156128 -58.490104)
		(width 0.508)
		(layer "In6.Cu")
		(net "P1V8_AUX")
	)
	(segment
		(start 210.551268 -148.101304)
		(end 211.078572 -148.101304)
		(width 0.4572)
		(layer "In6.Cu")
		(net "P1V8_AUX")
	)
	(segment
		(start 88.27135 -132.670804)
		(end 92.862146 -132.670804)
		(width 0.508)
		(layer "In6.Cu")
		(net "P1V8_AUX")
	)
	(segment
		(start 361.131866 -133.60781)
		(end 390.715246 -133.60781)
		(width 0.508)
		(layer "In6.Cu")
		(net "P1V8_AUX")
	)
	(segment
		(start 312.102246 -131.981702)
		(end 320.621152 -131.981702)
		(width 0.508)
		(layer "In6.Cu")
		(net "P1V8_AUX")
	)
	(segment
		(start 94.45498 -131.07797)
		(end 98.61042 -131.07797)
		(width 0.508)
		(layer "In6.Cu")
		(net "P1V8_AUX")
	)
	(segment
		(start 320.621152 -131.981702)
		(end 320.713354 -131.8895)
		(width 0.508)
		(layer "In6.Cu")
		(net "P1V8_AUX")
	)
	(segment
		(start 347.666564 -134.074662)
		(end 348.310454 -134.718552)
		(width 0.508)
		(layer "In6.Cu")
		(net "P1V8_AUX")
	)
	(segment
		(start 423.389044 -57.204356)
		(end 422.129712 -58.463688)
		(width 0.4572)
		(layer "In6.Cu")
		(net "P1V8_AUX")
	)
	(segment
		(start 405.760174 -69.085714)
		(end 412.662116 -69.085714)
		(width 0.508)
		(layer "In6.Cu")
		(net "P1V8_AUX")
	)
	(segment
		(start 244.332506 -140.894816)
		(end 244.884956 -140.894816)
		(width 0.508)
		(layer "In6.Cu")
		(net "P1V8_AUX")
	)
	(segment
		(start 307.860954 -142.196058)
		(end 307.860954 -136.222994)
		(width 0.508)
		(layer "In6.Cu")
		(net "P1V8_AUX")
	)
	(segment
		(start 320.78676 -131.8895)
		(end 323.71792 -128.95834)
		(width 0.508)
		(layer "In6.Cu")
		(net "P1V8_AUX")
	)
	(segment
		(start 414.585912 -190.647828)
		(end 409.93314 -190.647828)
		(width 0.4572)
		(layer "In11.Cu")
		(net "P1V8_AUX")
	)
	(segment
		(start 134.409434 -99.679252)
		(end 134.409434 -64.973962)
		(width 0.508)
		(layer "In11.Cu")
		(net "P1V8_AUX")
	)
	(segment
		(start 244.470682 -167.133778)
		(end 247.120918 -169.784014)
		(width 0.508)
		(layer "In11.Cu")
		(net "P1V8_AUX")
	)
	(segment
		(start 431.17262 -161.637726)
		(end 427.480984 -157.94609)
		(width 0.4572)
		(layer "In11.Cu")
		(net "P1V8_AUX")
	)
	(segment
		(start 134.805166 -101.253036)
		(end 134.805166 -100.074984)
		(width 0.508)
		(layer "In11.Cu")
		(net "P1V8_AUX")
	)
	(segment
		(start 134.805166 -100.074984)
		(end 134.409434 -99.679252)
		(width 0.508)
		(layer "In11.Cu")
		(net "P1V8_AUX")
	)
	(segment
		(start 400.70278 -199.878188)
		(end 400.70278 -203.676504)
		(width 0.4572)
		(layer "In11.Cu")
		(net "P1V8_AUX")
	)
	(segment
		(start 147.625562 -41.746424)
		(end 147.625562 -43.03141)
		(width 0.508)
		(layer "In11.Cu")
		(net "P1V8_AUX")
	)
	(segment
		(start 271.44599 -173.020736)
		(end 294.111426 -173.020736)
		(width 0.508)
		(layer "In11.Cu")
		(net "P1V8_AUX")
	)
	(segment
		(start 418.03447 -157.94609)
		(end 416.613848 -156.525468)
		(width 0.4572)
		(layer "In11.Cu")
		(net "P1V8_AUX")
	)
	(segment
		(start 244.884956 -140.894816)
		(end 244.835172 -140.894816)
		(width 0.508)
		(layer "In11.Cu")
		(net "P1V8_AUX")
	)
	(segment
		(start 268.209268 -169.784014)
		(end 271.44599 -173.020736)
		(width 0.508)
		(layer "In11.Cu")
		(net "P1V8_AUX")
	)
	(segment
		(start 453.68972 -322.13042)
		(end 454.730104 -323.170804)
		(width 0.4572)
		(layer "In11.Cu")
		(net "P1V8_AUX")
	)
	(segment
		(start 133.337046 -52.096162)
		(end 134.055104 -51.378104)
		(width 0.508)
		(layer "In11.Cu")
		(net "P1V8_AUX")
	)
	(segment
		(start 134.409434 -64.973962)
		(end 133.337046 -63.901574)
		(width 0.508)
		(layer "In11.Cu")
		(net "P1V8_AUX")
	)
	(segment
		(start 247.120918 -169.784014)
		(end 264.319004 -169.784014)
		(width 0.508)
		(layer "In11.Cu")
		(net "P1V8_AUX")
	)
	(segment
		(start 409.93314 -190.647828)
		(end 400.70278 -199.878188)
		(width 0.4572)
		(layer "In11.Cu")
		(net "P1V8_AUX")
	)
	(segment
		(start 134.055104 -51.378104)
		(end 137.534904 -51.378104)
		(width 0.508)
		(layer "In11.Cu")
		(net "P1V8_AUX")
	)
	(segment
		(start 294.111426 -173.020736)
		(end 300.687994 -166.444168)
		(width 0.508)
		(layer "In11.Cu")
		(net "P1V8_AUX")
	)
	(segment
		(start 454.730104 -362.363258)
		(end 465.655152 -373.288306)
		(width 0.4572)
		(layer "In11.Cu")
		(net "P1V8_AUX")
	)
	(segment
		(start 449.224146 -322.13042)
		(end 453.68972 -322.13042)
		(width 0.4572)
		(layer "In11.Cu")
		(net "P1V8_AUX")
	)
	(segment
		(start 147.851114 -43.03141)
		(end 148.76399 -43.944286)
		(width 0.508)
		(layer "In11.Cu")
		(net "P1V8_AUX")
	)
	(segment
		(start 447.027046 -324.32752)
		(end 449.224146 -322.13042)
		(width 0.4572)
		(layer "In11.Cu")
		(net "P1V8_AUX")
	)
	(segment
		(start 427.480984 -157.94609)
		(end 418.03447 -157.94609)
		(width 0.4572)
		(layer "In11.Cu")
		(net "P1V8_AUX")
	)
	(segment
		(start 454.730104 -323.170804)
		(end 454.730104 -362.363258)
		(width 0.4572)
		(layer "In11.Cu")
		(net "P1V8_AUX")
	)
	(segment
		(start 431.17262 -161.637726)
		(end 430.89576 -161.914586)
		(width 0.4572)
		(layer "In11.Cu")
		(net "P1V8_AUX")
	)
	(segment
		(start 148.76399 -43.944286)
		(end 148.76399 -44.44365)
		(width 0.508)
		(layer "In11.Cu")
		(net "P1V8_AUX")
	)
	(segment
		(start 244.470682 -141.259306)
		(end 244.470682 -167.133778)
		(width 0.508)
		(layer "In11.Cu")
		(net "P1V8_AUX")
	)
	(segment
		(start 430.89576 -161.914586)
		(end 430.89576 -174.33798)
		(width 0.4572)
		(layer "In11.Cu")
		(net "P1V8_AUX")
	)
	(segment
		(start 447.027046 -329.520296)
		(end 447.027046 -324.32752)
		(width 0.4572)
		(layer "In11.Cu")
		(net "P1V8_AUX")
	)
	(segment
		(start 395.13002 -144.112742)
		(end 393.768326 -142.751048)
		(width 0.4572)
		(layer "In11.Cu")
		(net "P1V8_AUX")
	)
	(segment
		(start 144.1958 -52.1716)
		(end 145.0086 -51.3588)
		(width 0.508)
		(layer "In11.Cu")
		(net "P1V8_AUX")
	)
	(segment
		(start 147.625562 -43.03141)
		(end 147.851114 -43.03141)
		(width 0.508)
		(layer "In11.Cu")
		(net "P1V8_AUX")
	)
	(segment
		(start 264.319004 -169.784014)
		(end 268.209268 -169.784014)
		(width 0.508)
		(layer "In11.Cu")
		(net "P1V8_AUX")
	)
	(segment
		(start 133.337046 -63.901574)
		(end 133.337046 -52.096162)
		(width 0.508)
		(layer "In11.Cu")
		(net "P1V8_AUX")
	)
	(segment
		(start 137.534904 -51.378104)
		(end 138.3284 -52.1716)
		(width 0.508)
		(layer "In11.Cu")
		(net "P1V8_AUX")
	)
	(segment
		(start 395.13002 -149.073108)
		(end 395.13002 -144.112742)
		(width 0.4572)
		(layer "In11.Cu")
		(net "P1V8_AUX")
	)
	(segment
		(start 402.58238 -156.525468)
		(end 395.13002 -149.073108)
		(width 0.4572)
		(layer "In11.Cu")
		(net "P1V8_AUX")
	)
	(segment
		(start 430.89576 -174.33798)
		(end 414.585912 -190.647828)
		(width 0.4572)
		(layer "In11.Cu")
		(net "P1V8_AUX")
	)
	(segment
		(start 244.835172 -140.894816)
		(end 244.470682 -141.259306)
		(width 0.508)
		(layer "In11.Cu")
		(net "P1V8_AUX")
	)
	(segment
		(start 400.70278 -203.676504)
		(end 399.457672 -204.921612)
		(width 0.4572)
		(layer "In11.Cu")
		(net "P1V8_AUX")
	)
	(segment
		(start 138.3284 -52.1716)
		(end 144.1958 -52.1716)
		(width 0.508)
		(layer "In11.Cu")
		(net "P1V8_AUX")
	)
	(segment
		(start 393.768326 -142.751048)
		(end 392.680698 -142.751048)
		(width 0.4572)
		(layer "In11.Cu")
		(net "P1V8_AUX")
	)
	(segment
		(start 147.01647 -43.03141)
		(end 147.625562 -43.03141)
		(width 0.508)
		(layer "In11.Cu")
		(net "P1V8_AUX")
	)
	(segment
		(start 145.0086 -45.03928)
		(end 147.01647 -43.03141)
		(width 0.508)
		(layer "In11.Cu")
		(net "P1V8_AUX")
	)
	(segment
		(start 145.0086 -51.3588)
		(end 145.0086 -45.03928)
		(width 0.508)
		(layer "In11.Cu")
		(net "P1V8_AUX")
	)
	(segment
		(start 416.613848 -156.525468)
		(end 402.58238 -156.525468)
		(width 0.4572)
		(layer "In11.Cu")
		(net "P1V8_AUX")
	)
	(segment
		(start 300.687994 -166.444168)
		(end 300.687994 -162.733228)
		(width 0.508)
		(layer "In11.Cu")
		(net "P1V8_AUX")
	)
	(segment
		(start 246.273828 -331.389736)
		(end 246.066564 -331.597)
		(width 0.4572)
		(layer "In13.Cu")
		(net "P1V8_AUX")
	)
	(segment
		(start 240.495074 -331.597)
		(end 240.251488 -331.353414)
		(width 0.4572)
		(layer "In13.Cu")
		(net "P1V8_AUX")
	)
	(segment
		(start 262.793988 -265.97229)
		(end 263.541764 -265.97229)
		(width 0.4572)
		(layer "In13.Cu")
		(net "P1V8_AUX")
	)
	(segment
		(start 240.251488 -331.353414)
		(end 240.251488 -330.581)
		(width 0.4572)
		(layer "In13.Cu")
		(net "P1V8_AUX")
	)
	(segment
		(start 248.712736 -331.389736)
		(end 246.273828 -331.389736)
		(width 0.4572)
		(layer "In13.Cu")
		(net "P1V8_AUX")
	)
	(segment
		(start 260.303264 -263.481566)
		(end 262.793988 -265.97229)
		(width 0.4572)
		(layer "In13.Cu")
		(net "P1V8_AUX")
	)
	(segment
		(start 246.066564 -331.597)
		(end 240.495074 -331.597)
		(width 0.4572)
		(layer "In13.Cu")
		(net "P1V8_AUX")
	)
	(segment
		(start 249.428 -332.105)
		(end 248.712736 -331.389736)
		(width 0.4572)
		(layer "In13.Cu")
		(net "P1V8_AUX")
	)
	(segment
		(start 254.78486 -263.481566)
		(end 260.303264 -263.481566)
		(width 0.4572)
		(layer "In13.Cu")
		(net "P1V8_AUX")
	)
	(segment
		(start 20.575524 -406.145238)
		(end 22.59965 -408.169364)
		(width 0.4572)
		(layer "In15.Cu")
		(net "P1V8_AUX")
	)
	(segment
		(start 32.435292 -408.169364)
		(end 32.78378 -408.517852)
		(width 0.4572)
		(layer "In15.Cu")
		(net "P1V8_AUX")
	)
	(segment
		(start 20.575524 -404.68931)
		(end 20.575524 -406.145238)
		(width 0.4572)
		(layer "In15.Cu")
		(net "P1V8_AUX")
	)
	(segment
		(start 22.59965 -408.169364)
		(end 32.435292 -408.169364)
		(width 0.4572)
		(layer "In15.Cu")
		(net "P1V8_AUX")
	)
	(segment
		(start 208.494376 -105.497376)
		(end 207.644238 -105.497376)
		(width 0.10668)
		(layer "F.Cu")
		(net "P12V_OCP_V3_1_PWRGD")
	)
	(segment
		(start 191.522096 -107.452922)
		(end 191.911986 -107.063032)
		(width 0.10668)
		(layer "F.Cu")
		(net "P12V_OCP_V3_1_PWRGD")
	)
	(via
		(at 207.644238 -105.497376)
		(size 0.508)
		(drill 0.254)
		(layers "F.Cu" "B.Cu")
		(net "P12V_OCP_V3_1_PWRGD")
	)
	(via
		(at 191.911986 -107.063032)
		(size 0.4572)
		(drill 0.254)
		(layers "F.Cu" "B.Cu")
		(net "P12V_OCP_V3_1_PWRGD")
	)
	(segment
		(start 191.911986 -106.872024)
		(end 191.911986 -107.063032)
		(width 0.11684)
		(layer "In2.Cu")
		(net "P12V_OCP_V3_1_PWRGD")
	)
	(segment
		(start 204.432662 -104.483408)
		(end 197.997572 -104.483408)
		(width 0.11684)
		(layer "In2.Cu")
		(net "P12V_OCP_V3_1_PWRGD")
	)
	(segment
		(start 197.63486 -104.84612)
		(end 195.853304 -104.84612)
		(width 0.11684)
		(layer "In2.Cu")
		(net "P12V_OCP_V3_1_PWRGD")
	)
	(segment
		(start 192.113916 -106.670094)
		(end 191.911986 -106.872024)
		(width 0.11684)
		(layer "In2.Cu")
		(net "P12V_OCP_V3_1_PWRGD")
	)
	(segment
		(start 195.853304 -104.84612)
		(end 194.857624 -105.8418)
		(width 0.11684)
		(layer "In2.Cu")
		(net "P12V_OCP_V3_1_PWRGD")
	)
	(segment
		(start 194.0306 -105.8418)
		(end 193.9036 -105.9688)
		(width 0.11684)
		(layer "In2.Cu")
		(net "P12V_OCP_V3_1_PWRGD")
	)
	(segment
		(start 193.9036 -105.9688)
		(end 193.9036 -106.42346)
		(width 0.11684)
		(layer "In2.Cu")
		(net "P12V_OCP_V3_1_PWRGD")
	)
	(segment
		(start 205.44663 -105.497376)
		(end 204.432662 -104.483408)
		(width 0.11684)
		(layer "In2.Cu")
		(net "P12V_OCP_V3_1_PWRGD")
	)
	(segment
		(start 193.9036 -106.42346)
		(end 193.656966 -106.670094)
		(width 0.11684)
		(layer "In2.Cu")
		(net "P12V_OCP_V3_1_PWRGD")
	)
	(segment
		(start 197.997572 -104.483408)
		(end 197.63486 -104.84612)
		(width 0.11684)
		(layer "In2.Cu")
		(net "P12V_OCP_V3_1_PWRGD")
	)
	(segment
		(start 194.857624 -105.8418)
		(end 194.0306 -105.8418)
		(width 0.11684)
		(layer "In2.Cu")
		(net "P12V_OCP_V3_1_PWRGD")
	)
	(segment
		(start 207.644238 -105.497376)
		(end 205.44663 -105.497376)
		(width 0.11684)
		(layer "In2.Cu")
		(net "P12V_OCP_V3_1_PWRGD")
	)
	(segment
		(start 193.656966 -106.670094)
		(end 192.113916 -106.670094)
		(width 0.11684)
		(layer "In2.Cu")
		(net "P12V_OCP_V3_1_PWRGD")
	)
	(segment
		(start 468.227664 -37.080698)
		(end 462.918302 -37.080698)
		(width 0.10668)
		(layer "F.Cu")
		(net "P12V_OCP_SFF_EN_R")
	)
	(segment
		(start 461.502252 -35.664648)
		(end 448.065144 -35.664648)
		(width 0.10668)
		(layer "F.Cu")
		(net "P12V_OCP_SFF_EN_R")
	)
	(segment
		(start 446.857882 -33.829244)
		(end 445.602106 -32.573468)
		(width 0.10668)
		(layer "F.Cu")
		(net "P12V_OCP_SFF_EN_R")
	)
	(segment
		(start 164.10305 -110.200948)
		(end 164.62629 -110.200948)
		(width 0.10668)
		(layer "F.Cu")
		(net "P12V_OCP_SFF_EN_R")
	)
	(segment
		(start 469.357964 -42.121836)
		(end 469.9127 -41.5671)
		(width 0.10668)
		(layer "F.Cu")
		(net "P12V_OCP_SFF_EN_R")
	)
	(segment
		(start 157.066996 -108.456222)
		(end 157.090364 -108.432854)
		(width 0.10668)
		(layer "F.Cu")
		(net "P12V_OCP_SFF_EN_R")
	)
	(segment
		(start 164.62629 -110.200948)
		(end 164.71011 -110.117128)
		(width 0.10668)
		(layer "F.Cu")
		(net "P12V_OCP_SFF_EN_R")
	)
	(segment
		(start 165.547548 -110.200948)
		(end 166.73195 -110.200948)
		(width 0.10668)
		(layer "F.Cu")
		(net "P12V_OCP_SFF_EN_R")
	)
	(segment
		(start 448.065144 -35.664648)
		(end 446.857882 -34.457386)
		(width 0.10668)
		(layer "F.Cu")
		(net "P12V_OCP_SFF_EN_R")
	)
	(segment
		(start 469.9127 -38.765734)
		(end 468.227664 -37.080698)
		(width 0.10668)
		(layer "F.Cu")
		(net "P12V_OCP_SFF_EN_R")
	)
	(segment
		(start 469.9127 -41.5671)
		(end 469.9127 -38.765734)
		(width 0.10668)
		(layer "F.Cu")
		(net "P12V_OCP_SFF_EN_R")
	)
	(segment
		(start 157.066996 -109.802422)
		(end 157.066996 -108.456222)
		(width 0.10668)
		(layer "F.Cu")
		(net "P12V_OCP_SFF_EN_R")
	)
	(segment
		(start 444.733172 -32.573468)
		(end 445.602106 -32.573468)
		(width 0.10668)
		(layer "F.Cu")
		(net "P12V_OCP_SFF_EN_R")
	)
	(segment
		(start 164.71011 -110.117128)
		(end 165.463728 -110.117128)
		(width 0.10668)
		(layer "F.Cu")
		(net "P12V_OCP_SFF_EN_R")
	)
	(segment
		(start 165.463728 -110.117128)
		(end 165.547548 -110.200948)
		(width 0.10668)
		(layer "F.Cu")
		(net "P12V_OCP_SFF_EN_R")
	)
	(segment
		(start 462.918302 -37.080698)
		(end 461.502252 -35.664648)
		(width 0.10668)
		(layer "F.Cu")
		(net "P12V_OCP_SFF_EN_R")
	)
	(segment
		(start 158.038038 -110.773464)
		(end 157.066996 -109.802422)
		(width 0.10668)
		(layer "F.Cu")
		(net "P12V_OCP_SFF_EN_R")
	)
	(segment
		(start 446.857882 -34.457386)
		(end 446.857882 -33.829244)
		(width 0.10668)
		(layer "F.Cu")
		(net "P12V_OCP_SFF_EN_R")
	)
	(via
		(at 165.463728 -110.117128)
		(size 0.508)
		(drill 0.254)
		(layers "F.Cu" "B.Cu")
		(net "P12V_OCP_SFF_EN_R")
	)
	(via
		(at 445.602106 -32.573468)
		(size 0.508)
		(drill 0.254)
		(layers "F.Cu" "B.Cu")
		(net "P12V_OCP_SFF_EN_R")
	)
	(via
		(at 164.97173 -97.819972)
		(size 0.508)
		(drill 0.254)
		(layers "F.Cu" "B.Cu")
		(net "P12V_OCP_SFF_EN_R")
	)
	(via
		(at 158.038038 -110.773464)
		(size 0.508)
		(drill 0.254)
		(layers "F.Cu" "B.Cu")
		(net "P12V_OCP_SFF_EN_R")
	)
	(segment
		(start 164.807392 -110.773464)
		(end 158.038038 -110.773464)
		(width 0.10668)
		(layer "B.Cu")
		(net "P12V_OCP_SFF_EN_R")
	)
	(segment
		(start 165.463728 -110.117128)
		(end 164.807392 -110.773464)
		(width 0.10668)
		(layer "B.Cu")
		(net "P12V_OCP_SFF_EN_R")
	)
	(segment
		(start 197.662292 -84.455508)
		(end 197.038722 -83.831938)
		(width 0.11684)
		(layer "In6.Cu")
		(net "P12V_OCP_SFF_EN_R")
	)
	(segment
		(start 174.871634 -87.384636)
		(end 174.871634 -88.552782)
		(width 0.11684)
		(layer "In6.Cu")
		(net "P12V_OCP_SFF_EN_R")
	)
	(segment
		(start 308.86527 -51.529234)
		(end 305.531774 -51.529234)
		(width 0.11684)
		(layer "In6.Cu")
		(net "P12V_OCP_SFF_EN_R")
	)
	(segment
		(start 171.622212 -91.78671)
		(end 171.622212 -91.802204)
		(width 0.11684)
		(layer "In6.Cu")
		(net "P12V_OCP_SFF_EN_R")
	)
	(segment
		(start 247.090692 -79.610966)
		(end 238.269272 -88.432386)
		(width 0.11684)
		(layer "In6.Cu")
		(net "P12V_OCP_SFF_EN_R")
	)
	(segment
		(start 192.559178 -84.988908)
		(end 177.267362 -84.988908)
		(width 0.11684)
		(layer "In6.Cu")
		(net "P12V_OCP_SFF_EN_R")
	)
	(segment
		(start 171.622212 -91.802204)
		(end 171.070016 -92.3544)
		(width 0.11684)
		(layer "In6.Cu")
		(net "P12V_OCP_SFF_EN_R")
	)
	(segment
		(start 438.32272 -32.573468)
		(end 433.22494 -27.475688)
		(width 0.11684)
		(layer "In6.Cu")
		(net "P12V_OCP_SFF_EN_R")
	)
	(segment
		(start 277.347934 -67.241166)
		(end 274.74799 -69.84111)
		(width 0.11684)
		(layer "In6.Cu")
		(net "P12V_OCP_SFF_EN_R")
	)
	(segment
		(start 174.871634 -88.552782)
		(end 172.403516 -91.0209)
		(width 0.11684)
		(layer "In6.Cu")
		(net "P12V_OCP_SFF_EN_R")
	)
	(segment
		(start 309.511446 -50.883058)
		(end 308.86527 -51.529234)
		(width 0.11684)
		(layer "In6.Cu")
		(net "P12V_OCP_SFF_EN_R")
	)
	(segment
		(start 269.790926 -69.84111)
		(end 260.02107 -79.610966)
		(width 0.11684)
		(layer "In6.Cu")
		(net "P12V_OCP_SFF_EN_R")
	)
	(segment
		(start 197.038722 -83.831938)
		(end 193.716148 -83.831938)
		(width 0.11684)
		(layer "In6.Cu")
		(net "P12V_OCP_SFF_EN_R")
	)
	(segment
		(start 170.437302 -92.3544)
		(end 164.97173 -97.819972)
		(width 0.11684)
		(layer "In6.Cu")
		(net "P12V_OCP_SFF_EN_R")
	)
	(segment
		(start 177.267362 -84.988908)
		(end 174.871634 -87.384636)
		(width 0.11684)
		(layer "In6.Cu")
		(net "P12V_OCP_SFF_EN_R")
	)
	(segment
		(start 193.716148 -83.831938)
		(end 192.559178 -84.988908)
		(width 0.11684)
		(layer "In6.Cu")
		(net "P12V_OCP_SFF_EN_R")
	)
	(segment
		(start 277.347934 -64.223138)
		(end 277.347934 -67.241166)
		(width 0.11684)
		(layer "In6.Cu")
		(net "P12V_OCP_SFF_EN_R")
	)
	(segment
		(start 172.388022 -91.0209)
		(end 171.622212 -91.78671)
		(width 0.11684)
		(layer "In6.Cu")
		(net "P12V_OCP_SFF_EN_R")
	)
	(segment
		(start 305.531774 -51.529234)
		(end 304.79111 -50.78857)
		(width 0.11684)
		(layer "In6.Cu")
		(net "P12V_OCP_SFF_EN_R")
	)
	(segment
		(start 304.79111 -50.78857)
		(end 290.782502 -50.78857)
		(width 0.11684)
		(layer "In6.Cu")
		(net "P12V_OCP_SFF_EN_R")
	)
	(segment
		(start 274.74799 -69.84111)
		(end 269.790926 -69.84111)
		(width 0.11684)
		(layer "In6.Cu")
		(net "P12V_OCP_SFF_EN_R")
	)
	(segment
		(start 290.782502 -50.78857)
		(end 277.347934 -64.223138)
		(width 0.11684)
		(layer "In6.Cu")
		(net "P12V_OCP_SFF_EN_R")
	)
	(segment
		(start 172.403516 -91.0209)
		(end 172.388022 -91.0209)
		(width 0.11684)
		(layer "In6.Cu")
		(net "P12V_OCP_SFF_EN_R")
	)
	(segment
		(start 213.265766 -88.432386)
		(end 212.095334 -87.263986)
		(width 0.11684)
		(layer "In6.Cu")
		(net "P12V_OCP_SFF_EN_R")
	)
	(segment
		(start 212.095334 -87.263986)
		(end 209.286856 -84.455508)
		(width 0.11684)
		(layer "In6.Cu")
		(net "P12V_OCP_SFF_EN_R")
	)
	(segment
		(start 238.269272 -88.432386)
		(end 213.265766 -88.432386)
		(width 0.11684)
		(layer "In6.Cu")
		(net "P12V_OCP_SFF_EN_R")
	)
	(segment
		(start 445.602106 -32.573468)
		(end 438.32272 -32.573468)
		(width 0.11684)
		(layer "In6.Cu")
		(net "P12V_OCP_SFF_EN_R")
	)
	(segment
		(start 379.17247 -50.883058)
		(end 309.511446 -50.883058)
		(width 0.11684)
		(layer "In6.Cu")
		(net "P12V_OCP_SFF_EN_R")
	)
	(segment
		(start 209.286856 -84.455508)
		(end 197.662292 -84.455508)
		(width 0.11684)
		(layer "In6.Cu")
		(net "P12V_OCP_SFF_EN_R")
	)
	(segment
		(start 402.57984 -27.475688)
		(end 379.17247 -50.883058)
		(width 0.11684)
		(layer "In6.Cu")
		(net "P12V_OCP_SFF_EN_R")
	)
	(segment
		(start 260.02107 -79.610966)
		(end 247.090692 -79.610966)
		(width 0.11684)
		(layer "In6.Cu")
		(net "P12V_OCP_SFF_EN_R")
	)
	(segment
		(start 433.22494 -27.475688)
		(end 402.57984 -27.475688)
		(width 0.11684)
		(layer "In6.Cu")
		(net "P12V_OCP_SFF_EN_R")
	)
	(segment
		(start 171.070016 -92.3544)
		(end 170.437302 -92.3544)
		(width 0.11684)
		(layer "In6.Cu")
		(net "P12V_OCP_SFF_EN_R")
	)
	(segment
		(start 160.671002 -101.979984)
		(end 158.038038 -104.612948)
		(width 0.11684)
		(layer "In15.Cu")
		(net "P12V_OCP_SFF_EN_R")
	)
	(segment
		(start 162.626548 -97.819972)
		(end 160.671002 -99.775518)
		(width 0.11684)
		(layer "In15.Cu")
		(net "P12V_OCP_SFF_EN_R")
	)
	(segment
		(start 160.671002 -99.775518)
		(end 160.671002 -101.979984)
		(width 0.11684)
		(layer "In15.Cu")
		(net "P12V_OCP_SFF_EN_R")
	)
	(segment
		(start 158.038038 -104.612948)
		(end 158.038038 -110.773464)
		(width 0.11684)
		(layer "In15.Cu")
		(net "P12V_OCP_SFF_EN_R")
	)
	(segment
		(start 164.97173 -97.819972)
		(end 162.626548 -97.819972)
		(width 0.11684)
		(layer "In15.Cu")
		(net "P12V_OCP_SFF_EN_R")
	)
	(segment
		(start 189.92215 -113.85296)
		(end 190.31204 -113.46307)
		(width 0.10668)
		(layer "F.Cu")
		(net "P12V_E1S_0_PWRGD")
	)
	(via
		(at 197.779386 -115.111022)
		(size 0.6604)
		(drill 0.3302)
		(layers "F.Cu" "B.Cu")
		(net "P12V_E1S_0_PWRGD")
	)
	(via
		(at 190.31204 -113.46307)
		(size 0.4572)
		(drill 0.254)
		(layers "F.Cu" "B.Cu")
		(net "P12V_E1S_0_PWRGD")
	)
	(segment
		(start 198.124318 -116.158518)
		(end 197.779386 -115.813586)
		(width 0.10668)
		(layer "B.Cu")
		(net "P12V_E1S_0_PWRGD")
	)
	(segment
		(start 199.142096 -116.536216)
		(end 198.764398 -116.158518)
		(width 0.10668)
		(layer "B.Cu")
		(net "P12V_E1S_0_PWRGD")
	)
	(segment
		(start 197.779386 -115.813586)
		(end 197.779386 -115.111022)
		(width 0.10668)
		(layer "B.Cu")
		(net "P12V_E1S_0_PWRGD")
	)
	(segment
		(start 191.066674 -115.176046)
		(end 190.71336 -114.822732)
		(width 0.10668)
		(layer "B.Cu")
		(net "P12V_E1S_0_PWRGD")
	)
	(segment
		(start 189.913768 -114.544602)
		(end 189.913768 -113.861342)
		(width 0.10668)
		(layer "B.Cu")
		(net "P12V_E1S_0_PWRGD")
	)
	(segment
		(start 197.779386 -115.111022)
		(end 197.495668 -115.39474)
		(width 0.10668)
		(layer "B.Cu")
		(net "P12V_E1S_0_PWRGD")
	)
	(segment
		(start 189.913768 -113.861342)
		(end 190.31204 -113.46307)
		(width 0.10668)
		(layer "B.Cu")
		(net "P12V_E1S_0_PWRGD")
	)
	(segment
		(start 195.27774 -115.39474)
		(end 195.059046 -115.176046)
		(width 0.10668)
		(layer "B.Cu")
		(net "P12V_E1S_0_PWRGD")
	)
	(segment
		(start 199.142096 -116.561362)
		(end 199.142096 -116.536216)
		(width 0.10668)
		(layer "B.Cu")
		(net "P12V_E1S_0_PWRGD")
	)
	(segment
		(start 190.71336 -114.822732)
		(end 190.191898 -114.822732)
		(width 0.10668)
		(layer "B.Cu")
		(net "P12V_E1S_0_PWRGD")
	)
	(segment
		(start 197.495668 -115.39474)
		(end 195.27774 -115.39474)
		(width 0.10668)
		(layer "B.Cu")
		(net "P12V_E1S_0_PWRGD")
	)
	(segment
		(start 199.129396 -116.574062)
		(end 199.142096 -116.561362)
		(width 0.10668)
		(layer "B.Cu")
		(net "P12V_E1S_0_PWRGD")
	)
	(segment
		(start 190.191898 -114.822732)
		(end 189.913768 -114.544602)
		(width 0.10668)
		(layer "B.Cu")
		(net "P12V_E1S_0_PWRGD")
	)
	(segment
		(start 198.764398 -116.158518)
		(end 198.124318 -116.158518)
		(width 0.10668)
		(layer "B.Cu")
		(net "P12V_E1S_0_PWRGD")
	)
	(segment
		(start 195.059046 -115.176046)
		(end 191.066674 -115.176046)
		(width 0.10668)
		(layer "B.Cu")
		(net "P12V_E1S_0_PWRGD")
	)
	(segment
		(start 320.571876 -70.573392)
		(end 320.571876 -71.868792)
		(width 0.10668)
		(layer "F.Cu")
		(net "LED_PWRGD_PS_PWROK_PLD_D")
	)
	(via
		(at 320.571876 -71.868792)
		(size 0.762)
		(drill 0.254)
		(layers "F.Cu" "B.Cu")
		(net "LED_PWRGD_PS_PWROK_PLD_D")
	)
	(segment
		(start 321.222624 -72.884792)
		(end 320.571876 -72.234044)
		(width 0.10668)
		(layer "B.Cu")
		(net "LED_PWRGD_PS_PWROK_PLD_D")
	)
	(segment
		(start 320.571876 -72.234044)
		(end 320.571876 -71.868792)
		(width 0.10668)
		(layer "B.Cu")
		(net "LED_PWRGD_PS_PWROK_PLD_D")
	)
	(segment
		(start 320.571876 -69.623432)
		(end 320.571876 -68.328032)
		(width 0.10668)
		(layer "F.Cu")
		(net "LED_PWRGD_PS_PWROK_PLD")
	)
	(via
		(at 320.571876 -68.328032)
		(size 0.508)
		(drill 0.254)
		(layers "F.Cu" "B.Cu")
		(net "LED_PWRGD_PS_PWROK_PLD")
	)
	(segment
		(start 320.571876 -67.108832)
		(end 320.571876 -68.328032)
		(width 0.10668)
		(layer "B.Cu")
		(net "LED_PWRGD_PS_PWROK_PLD")
	)
	(segment
		(start 314.475876 -69.623432)
		(end 314.475876 -68.328032)
		(width 0.10668)
		(layer "F.Cu")
		(net "LED_P5V")
	)
	(via
		(at 314.475876 -68.328032)
		(size 0.508)
		(drill 0.254)
		(layers "F.Cu" "B.Cu")
		(net "LED_P5V")
	)
	(segment
		(start 314.475876 -67.108832)
		(end 314.475876 -68.328032)
		(width 0.10668)
		(layer "B.Cu")
		(net "LED_P5V")
	)
	(segment
		(start 316.507876 -69.623432)
		(end 316.507876 -68.328032)
		(width 0.10668)
		(layer "F.Cu")
		(net "LED_P3V3")
	)
	(via
		(at 316.507876 -68.328032)
		(size 0.508)
		(drill 0.254)
		(layers "F.Cu" "B.Cu")
		(net "LED_P3V3")
	)
	(segment
		(start 316.507876 -67.108832)
		(end 316.507876 -68.328032)
		(width 0.10668)
		(layer "B.Cu")
		(net "LED_P3V3")
	)
	(segment
		(start 381.638048 -294.88003)
		(end 382.1049 -295.145968)
		(width 0.10668)
		(layer "F.Cu")
		(net "IRQ_TPM_SPI_R_N")
	)
	(segment
		(start 180.9242 -95.703898)
		(end 180.9242 -95.291148)
		(width 0.10668)
		(layer "F.Cu")
		(net "IRQ_TPM_SPI_R_N")
	)
	(segment
		(start 180.9242 -95.291148)
		(end 180.721 -95.087948)
		(width 0.10668)
		(layer "F.Cu")
		(net "IRQ_TPM_SPI_R_N")
	)
	(via
		(at 238.661702 -142.755874)
		(size 0.508)
		(drill 0.254)
		(layers "F.Cu" "B.Cu")
		(net "IRQ_TPM_SPI_R_N")
	)
	(via
		(at 400.829526 -319.033144)
		(size 0.6604)
		(drill 0.3302)
		(layers "F.Cu" "B.Cu")
		(net "IRQ_TPM_SPI_R_N")
	)
	(via
		(at 382.1049 -295.145968)
		(size 0.4064)
		(drill 0.2032)
		(layers "F.Cu" "B.Cu")
		(net "IRQ_TPM_SPI_R_N")
	)
	(via
		(at 180.721 -95.087948)
		(size 0.508)
		(drill 0.254)
		(layers "F.Cu" "B.Cu")
		(net "IRQ_TPM_SPI_R_N")
	)
	(via
		(at 392.55192 -316.25286)
		(size 0.508)
		(drill 0.254)
		(layers "F.Cu" "B.Cu")
		(net "IRQ_TPM_SPI_R_N")
	)
	(via
		(at 239.804448 -98.194622)
		(size 0.508)
		(drill 0.254)
		(layers "F.Cu" "B.Cu")
		(net "IRQ_TPM_SPI_R_N")
	)
	(segment
		(start 391.398252 -315.62421)
		(end 389.03275 -315.62421)
		(width 0.10668)
		(layer "B.Cu")
		(net "IRQ_TPM_SPI_R_N")
	)
	(segment
		(start 380.80188 -295.52646)
		(end 381.54102 -295.52646)
		(width 0.10668)
		(layer "B.Cu")
		(net "IRQ_TPM_SPI_R_N")
	)
	(segment
		(start 400.829526 -319.033144)
		(end 401.75688 -319.033144)
		(width 0.10668)
		(layer "B.Cu")
		(net "IRQ_TPM_SPI_R_N")
	)
	(segment
		(start 400.622262 -318.82588)
		(end 395.521688 -318.82588)
		(width 0.10668)
		(layer "B.Cu")
		(net "IRQ_TPM_SPI_R_N")
	)
	(segment
		(start 389.03275 -315.62421)
		(end 388.712202 -315.303662)
		(width 0.10668)
		(layer "B.Cu")
		(net "IRQ_TPM_SPI_R_N")
	)
	(segment
		(start 392.55192 -316.25286)
		(end 392.294364 -315.995304)
		(width 0.10668)
		(layer "B.Cu")
		(net "IRQ_TPM_SPI_R_N")
	)
	(segment
		(start 377.84024 -294.88384)
		(end 377.99264 -294.73144)
		(width 0.10668)
		(layer "B.Cu")
		(net "IRQ_TPM_SPI_R_N")
	)
	(segment
		(start 395.521688 -318.82588)
		(end 395.261846 -318.718184)
		(width 0.10668)
		(layer "B.Cu")
		(net "IRQ_TPM_SPI_R_N")
	)
	(segment
		(start 381.54102 -295.52646)
		(end 381.921512 -295.145968)
		(width 0.10668)
		(layer "B.Cu")
		(net "IRQ_TPM_SPI_R_N")
	)
	(segment
		(start 380.00686 -294.73144)
		(end 380.80188 -295.52646)
		(width 0.10668)
		(layer "B.Cu")
		(net "IRQ_TPM_SPI_R_N")
	)
	(segment
		(start 395.261846 -318.718184)
		(end 392.796522 -316.25286)
		(width 0.10668)
		(layer "B.Cu")
		(net "IRQ_TPM_SPI_R_N")
	)
	(segment
		(start 388.322566 -315.303662)
		(end 380.812294 -307.79339)
		(width 0.10668)
		(layer "B.Cu")
		(net "IRQ_TPM_SPI_R_N")
	)
	(segment
		(start 377.345448 -295.821862)
		(end 377.84024 -295.32707)
		(width 0.10668)
		(layer "B.Cu")
		(net "IRQ_TPM_SPI_R_N")
	)
	(segment
		(start 380.812294 -307.79339)
		(end 380.812294 -304.983134)
		(width 0.10668)
		(layer "B.Cu")
		(net "IRQ_TPM_SPI_R_N")
	)
	(segment
		(start 388.712202 -315.303662)
		(end 388.322566 -315.303662)
		(width 0.10668)
		(layer "B.Cu")
		(net "IRQ_TPM_SPI_R_N")
	)
	(segment
		(start 377.84024 -295.32707)
		(end 377.84024 -294.88384)
		(width 0.10668)
		(layer "B.Cu")
		(net "IRQ_TPM_SPI_R_N")
	)
	(segment
		(start 400.829526 -319.033144)
		(end 400.622262 -318.82588)
		(width 0.10668)
		(layer "B.Cu")
		(net "IRQ_TPM_SPI_R_N")
	)
	(segment
		(start 401.75688 -319.033144)
		(end 401.922488 -319.198752)
		(width 0.10668)
		(layer "B.Cu")
		(net "IRQ_TPM_SPI_R_N")
	)
	(segment
		(start 377.99264 -294.73144)
		(end 380.00686 -294.73144)
		(width 0.10668)
		(layer "B.Cu")
		(net "IRQ_TPM_SPI_R_N")
	)
	(segment
		(start 380.812294 -304.983134)
		(end 377.345448 -296.612564)
		(width 0.10668)
		(layer "B.Cu")
		(net "IRQ_TPM_SPI_R_N")
	)
	(segment
		(start 392.796522 -316.25286)
		(end 392.55192 -316.25286)
		(width 0.10668)
		(layer "B.Cu")
		(net "IRQ_TPM_SPI_R_N")
	)
	(segment
		(start 377.345448 -296.612564)
		(end 377.345448 -295.821862)
		(width 0.10668)
		(layer "B.Cu")
		(net "IRQ_TPM_SPI_R_N")
	)
	(segment
		(start 401.922488 -319.198752)
		(end 401.922488 -320.189352)
		(width 0.10668)
		(layer "B.Cu")
		(net "IRQ_TPM_SPI_R_N")
	)
	(segment
		(start 381.921512 -295.145968)
		(end 382.1049 -295.145968)
		(width 0.10668)
		(layer "B.Cu")
		(net "IRQ_TPM_SPI_R_N")
	)
	(segment
		(start 392.294364 -315.995304)
		(end 391.398252 -315.62421)
		(width 0.10668)
		(layer "B.Cu")
		(net "IRQ_TPM_SPI_R_N")
	)
	(segment
		(start 238.571532 -142.665704)
		(end 238.661702 -142.755874)
		(width 0.11684)
		(layer "In4.Cu")
		(net "IRQ_TPM_SPI_R_N")
	)
	(segment
		(start 238.571532 -99.427538)
		(end 238.571532 -142.665704)
		(width 0.11684)
		(layer "In4.Cu")
		(net "IRQ_TPM_SPI_R_N")
	)
	(segment
		(start 239.804448 -98.194622)
		(end 238.571532 -99.427538)
		(width 0.11684)
		(layer "In4.Cu")
		(net "IRQ_TPM_SPI_R_N")
	)
	(segment
		(start 459.969616 -319.06337)
		(end 453.397366 -325.63562)
		(width 0.11684)
		(layer "In6.Cu")
		(net "IRQ_TPM_SPI_R_N")
	)
	(segment
		(start 243.746274 -147.102576)
		(end 250.088146 -153.444448)
		(width 0.11684)
		(layer "In6.Cu")
		(net "IRQ_TPM_SPI_R_N")
	)
	(segment
		(start 265.104626 -153.444448)
		(end 268.62151 -149.927564)
		(width 0.11684)
		(layer "In6.Cu")
		(net "IRQ_TPM_SPI_R_N")
	)
	(segment
		(start 448.353942 -177.249582)
		(end 459.969616 -188.865256)
		(width 0.11684)
		(layer "In6.Cu")
		(net "IRQ_TPM_SPI_R_N")
	)
	(segment
		(start 406.470612 -319.16878)
		(end 395.46784 -319.16878)
		(width 0.11684)
		(layer "In6.Cu")
		(net "IRQ_TPM_SPI_R_N")
	)
	(segment
		(start 292.26256 -143.660368)
		(end 304.558446 -131.364482)
		(width 0.11684)
		(layer "In6.Cu")
		(net "IRQ_TPM_SPI_R_N")
	)
	(segment
		(start 453.397366 -325.63562)
		(end 412.937452 -325.63562)
		(width 0.11684)
		(layer "In6.Cu")
		(net "IRQ_TPM_SPI_R_N")
	)
	(segment
		(start 412.937452 -325.63562)
		(end 406.470612 -319.16878)
		(width 0.11684)
		(layer "In6.Cu")
		(net "IRQ_TPM_SPI_R_N")
	)
	(segment
		(start 415.157412 -131.9911)
		(end 430.735486 -147.569174)
		(width 0.11684)
		(layer "In6.Cu")
		(net "IRQ_TPM_SPI_R_N")
	)
	(segment
		(start 238.661702 -142.755874)
		(end 239.265206 -142.755874)
		(width 0.11684)
		(layer "In6.Cu")
		(net "IRQ_TPM_SPI_R_N")
	)
	(segment
		(start 347.544898 -133.223508)
		(end 360.066844 -133.223508)
		(width 0.11684)
		(layer "In6.Cu")
		(net "IRQ_TPM_SPI_R_N")
	)
	(segment
		(start 361.299252 -131.9911)
		(end 415.157412 -131.9911)
		(width 0.11684)
		(layer "In6.Cu")
		(net "IRQ_TPM_SPI_R_N")
	)
	(segment
		(start 268.62151 -149.573488)
		(end 274.53463 -143.660368)
		(width 0.11684)
		(layer "In6.Cu")
		(net "IRQ_TPM_SPI_R_N")
	)
	(segment
		(start 243.611908 -147.102576)
		(end 243.746274 -147.102576)
		(width 0.11684)
		(layer "In6.Cu")
		(net "IRQ_TPM_SPI_R_N")
	)
	(segment
		(start 430.735486 -154.71775)
		(end 439.236104 -163.218368)
		(width 0.11684)
		(layer "In6.Cu")
		(net "IRQ_TPM_SPI_R_N")
	)
	(segment
		(start 250.088146 -153.444448)
		(end 265.104626 -153.444448)
		(width 0.11684)
		(layer "In6.Cu")
		(net "IRQ_TPM_SPI_R_N")
	)
	(segment
		(start 342.66251 -128.34112)
		(end 347.544898 -133.223508)
		(width 0.11684)
		(layer "In6.Cu")
		(net "IRQ_TPM_SPI_R_N")
	)
	(segment
		(start 304.558446 -131.364482)
		(end 320.365374 -131.364482)
		(width 0.11684)
		(layer "In6.Cu")
		(net "IRQ_TPM_SPI_R_N")
	)
	(segment
		(start 430.735486 -147.569174)
		(end 430.735486 -154.71775)
		(width 0.11684)
		(layer "In6.Cu")
		(net "IRQ_TPM_SPI_R_N")
	)
	(segment
		(start 320.365374 -131.364482)
		(end 323.388736 -128.34112)
		(width 0.11684)
		(layer "In6.Cu")
		(net "IRQ_TPM_SPI_R_N")
	)
	(segment
		(start 239.265206 -142.755874)
		(end 243.611908 -147.102576)
		(width 0.11684)
		(layer "In6.Cu")
		(net "IRQ_TPM_SPI_R_N")
	)
	(segment
		(start 459.969616 -188.865256)
		(end 459.969616 -319.06337)
		(width 0.11684)
		(layer "In6.Cu")
		(net "IRQ_TPM_SPI_R_N")
	)
	(segment
		(start 395.46784 -319.16878)
		(end 392.55192 -316.25286)
		(width 0.11684)
		(layer "In6.Cu")
		(net "IRQ_TPM_SPI_R_N")
	)
	(segment
		(start 439.236104 -163.218368)
		(end 441.40374 -163.218368)
		(width 0.11684)
		(layer "In6.Cu")
		(net "IRQ_TPM_SPI_R_N")
	)
	(segment
		(start 360.066844 -133.223508)
		(end 361.299252 -131.9911)
		(width 0.11684)
		(layer "In6.Cu")
		(net "IRQ_TPM_SPI_R_N")
	)
	(segment
		(start 268.62151 -149.927564)
		(end 268.62151 -149.573488)
		(width 0.11684)
		(layer "In6.Cu")
		(net "IRQ_TPM_SPI_R_N")
	)
	(segment
		(start 274.53463 -143.660368)
		(end 292.26256 -143.660368)
		(width 0.11684)
		(layer "In6.Cu")
		(net "IRQ_TPM_SPI_R_N")
	)
	(segment
		(start 448.353942 -170.16857)
		(end 448.353942 -177.249582)
		(width 0.11684)
		(layer "In6.Cu")
		(net "IRQ_TPM_SPI_R_N")
	)
	(segment
		(start 323.388736 -128.34112)
		(end 342.66251 -128.34112)
		(width 0.11684)
		(layer "In6.Cu")
		(net "IRQ_TPM_SPI_R_N")
	)
	(segment
		(start 441.40374 -163.218368)
		(end 448.353942 -170.16857)
		(width 0.11684)
		(layer "In6.Cu")
		(net "IRQ_TPM_SPI_R_N")
	)
	(segment
		(start 181.243732 -95.941388)
		(end 181.245764 -95.941388)
		(width 0.11684)
		(layer "In15.Cu")
		(net "IRQ_TPM_SPI_R_N")
	)
	(segment
		(start 181.245764 -95.941388)
		(end 183.288686 -97.98431)
		(width 0.11684)
		(layer "In15.Cu")
		(net "IRQ_TPM_SPI_R_N")
	)
	(segment
		(start 200.257664 -104.596184)
		(end 210.949286 -104.596184)
		(width 0.11684)
		(layer "In15.Cu")
		(net "IRQ_TPM_SPI_R_N")
	)
	(segment
		(start 183.288686 -99.616768)
		(end 183.59755 -99.925632)
		(width 0.11684)
		(layer "In15.Cu")
		(net "IRQ_TPM_SPI_R_N")
	)
	(segment
		(start 215.463374 -104.06126)
		(end 233.497882 -104.06126)
		(width 0.11684)
		(layer "In15.Cu")
		(net "IRQ_TPM_SPI_R_N")
	)
	(segment
		(start 180.721 -95.418656)
		(end 181.243732 -95.941388)
		(width 0.11684)
		(layer "In15.Cu")
		(net "IRQ_TPM_SPI_R_N")
	)
	(segment
		(start 199.370442 -103.016304)
		(end 199.370442 -103.708962)
		(width 0.11684)
		(layer "In15.Cu")
		(net "IRQ_TPM_SPI_R_N")
	)
	(segment
		(start 210.949286 -104.596184)
		(end 211.252562 -104.89946)
		(width 0.11684)
		(layer "In15.Cu")
		(net "IRQ_TPM_SPI_R_N")
	)
	(segment
		(start 199.370442 -103.708962)
		(end 200.257664 -104.596184)
		(width 0.11684)
		(layer "In15.Cu")
		(net "IRQ_TPM_SPI_R_N")
	)
	(segment
		(start 196.27977 -99.925632)
		(end 199.370442 -103.016304)
		(width 0.11684)
		(layer "In15.Cu")
		(net "IRQ_TPM_SPI_R_N")
	)
	(segment
		(start 233.497882 -104.06126)
		(end 239.36452 -98.194622)
		(width 0.11684)
		(layer "In15.Cu")
		(net "IRQ_TPM_SPI_R_N")
	)
	(segment
		(start 214.625174 -104.89946)
		(end 215.463374 -104.06126)
		(width 0.11684)
		(layer "In15.Cu")
		(net "IRQ_TPM_SPI_R_N")
	)
	(segment
		(start 183.59755 -99.925632)
		(end 196.27977 -99.925632)
		(width 0.11684)
		(layer "In15.Cu")
		(net "IRQ_TPM_SPI_R_N")
	)
	(segment
		(start 183.288686 -97.98431)
		(end 183.288686 -99.616768)
		(width 0.11684)
		(layer "In15.Cu")
		(net "IRQ_TPM_SPI_R_N")
	)
	(segment
		(start 239.36452 -98.194622)
		(end 239.804448 -98.194622)
		(width 0.11684)
		(layer "In15.Cu")
		(net "IRQ_TPM_SPI_R_N")
	)
	(segment
		(start 180.721 -95.087948)
		(end 180.721 -95.418656)
		(width 0.11684)
		(layer "In15.Cu")
		(net "IRQ_TPM_SPI_R_N")
	)
	(segment
		(start 211.252562 -104.89946)
		(end 214.625174 -104.89946)
		(width 0.11684)
		(layer "In15.Cu")
		(net "IRQ_TPM_SPI_R_N")
	)
	(segment
		(start 380.697994 -294.88003)
		(end 381.164846 -295.145968)
		(width 0.10668)
		(layer "F.Cu")
		(net "IRQ_SMI_ACTIVE_N")
	)
	(via
		(at 220.308424 -141.913356)
		(size 0.508)
		(drill 0.254)
		(layers "F.Cu" "B.Cu")
		(net "IRQ_SMI_ACTIVE_N")
	)
	(via
		(at 400.71802 -321.162172)
		(size 0.6604)
		(drill 0.3302)
		(layers "F.Cu" "B.Cu")
		(net "IRQ_SMI_ACTIVE_N")
	)
	(via
		(at 216.96426 -102.62489)
		(size 0.508)
		(drill 0.254)
		(layers "F.Cu" "B.Cu")
		(net "IRQ_SMI_ACTIVE_N")
	)
	(via
		(at 381.164846 -295.145968)
		(size 0.4064)
		(drill 0.2032)
		(layers "F.Cu" "B.Cu")
		(net "IRQ_SMI_ACTIVE_N")
	)
	(via
		(at 402.353272 -322.884292)
		(size 0.508)
		(drill 0.254)
		(layers "F.Cu" "B.Cu")
		(net "IRQ_SMI_ACTIVE_N")
	)
	(segment
		(start 376.891296 -296.592498)
		(end 376.891296 -294.896794)
		(width 0.10668)
		(layer "B.Cu")
		(net "IRQ_SMI_ACTIVE_N")
	)
	(segment
		(start 395.531086 -319.234058)
		(end 395.03731 -319.029588)
		(width 0.10668)
		(layer "B.Cu")
		(net "IRQ_SMI_ACTIVE_N")
	)
	(segment
		(start 380.390654 -307.947568)
		(end 380.390654 -305.041808)
		(width 0.10668)
		(layer "B.Cu")
		(net "IRQ_SMI_ACTIVE_N")
	)
	(segment
		(start 381.19558 -295.115234)
		(end 381.164846 -295.145968)
		(width 0.10668)
		(layer "B.Cu")
		(net "IRQ_SMI_ACTIVE_N")
	)
	(segment
		(start 184.312814 -93.293438)
		(end 184.312814 -95.205296)
		(width 0.10668)
		(layer "B.Cu")
		(net "IRQ_SMI_ACTIVE_N")
	)
	(segment
		(start 402.353272 -322.601336)
		(end 401.922488 -322.170552)
		(width 0.10668)
		(layer "B.Cu")
		(net "IRQ_SMI_ACTIVE_N")
	)
	(segment
		(start 400.71802 -321.162172)
		(end 400.71802 -319.975484)
		(width 0.10668)
		(layer "B.Cu")
		(net "IRQ_SMI_ACTIVE_N")
	)
	(segment
		(start 391.629138 -316.568836)
		(end 391.4775 -316.720474)
		(width 0.10668)
		(layer "B.Cu")
		(net "IRQ_SMI_ACTIVE_N")
	)
	(segment
		(start 392.905996 -316.898274)
		(end 392.110468 -316.568836)
		(width 0.10668)
		(layer "B.Cu")
		(net "IRQ_SMI_ACTIVE_N")
	)
	(segment
		(start 401.904708 -321.162172)
		(end 401.922488 -321.179952)
		(width 0.10668)
		(layer "B.Cu")
		(net "IRQ_SMI_ACTIVE_N")
	)
	(segment
		(start 216.837768 -102.498398)
		(end 211.776056 -102.498398)
		(width 0.10668)
		(layer "B.Cu")
		(net "IRQ_SMI_ACTIVE_N")
	)
	(segment
		(start 380.390654 -305.041808)
		(end 376.891296 -296.592498)
		(width 0.10668)
		(layer "B.Cu")
		(net "IRQ_SMI_ACTIVE_N")
	)
	(segment
		(start 376.891296 -294.896794)
		(end 377.046998 -294.741092)
		(width 0.10668)
		(layer "B.Cu")
		(net "IRQ_SMI_ACTIVE_N")
	)
	(segment
		(start 185.05805 -95.950532)
		(end 185.05805 -96.738948)
		(width 0.10668)
		(layer "B.Cu")
		(net "IRQ_SMI_ACTIVE_N")
	)
	(segment
		(start 388.107428 -315.664342)
		(end 380.390654 -307.947568)
		(width 0.10668)
		(layer "B.Cu")
		(net "IRQ_SMI_ACTIVE_N")
	)
	(segment
		(start 184.503568 -93.102684)
		(end 184.312814 -93.293438)
		(width 0.10668)
		(layer "B.Cu")
		(net "IRQ_SMI_ACTIVE_N")
	)
	(segment
		(start 377.31446 -294.10914)
		(end 377.48464 -293.93896)
		(width 0.10668)
		(layer "B.Cu")
		(net "IRQ_SMI_ACTIVE_N")
	)
	(segment
		(start 211.776056 -102.498398)
		(end 208.302606 -99.024948)
		(width 0.10668)
		(layer "B.Cu")
		(net "IRQ_SMI_ACTIVE_N")
	)
	(segment
		(start 395.03731 -319.029588)
		(end 392.905996 -316.898274)
		(width 0.10668)
		(layer "B.Cu")
		(net "IRQ_SMI_ACTIVE_N")
	)
	(segment
		(start 202.325478 -90.020648)
		(end 190.300356 -90.020648)
		(width 0.10668)
		(layer "B.Cu")
		(net "IRQ_SMI_ACTIVE_N")
	)
	(segment
		(start 400.71802 -319.975484)
		(end 399.976594 -319.234058)
		(width 0.10668)
		(layer "B.Cu")
		(net "IRQ_SMI_ACTIVE_N")
	)
	(segment
		(start 381.19558 -294.12184)
		(end 381.19558 -295.115234)
		(width 0.10668)
		(layer "B.Cu")
		(net "IRQ_SMI_ACTIVE_N")
	)
	(segment
		(start 399.976594 -319.234058)
		(end 395.531086 -319.234058)
		(width 0.10668)
		(layer "B.Cu")
		(net "IRQ_SMI_ACTIVE_N")
	)
	(segment
		(start 402.353272 -322.884292)
		(end 402.353272 -322.601336)
		(width 0.10668)
		(layer "B.Cu")
		(net "IRQ_SMI_ACTIVE_N")
	)
	(segment
		(start 184.312814 -95.205296)
		(end 185.05805 -95.950532)
		(width 0.10668)
		(layer "B.Cu")
		(net "IRQ_SMI_ACTIVE_N")
	)
	(segment
		(start 185.739278 -93.102684)
		(end 184.503568 -93.102684)
		(width 0.10668)
		(layer "B.Cu")
		(net "IRQ_SMI_ACTIVE_N")
	)
	(segment
		(start 392.110468 -316.568836)
		(end 391.629138 -316.568836)
		(width 0.10668)
		(layer "B.Cu")
		(net "IRQ_SMI_ACTIVE_N")
	)
	(segment
		(start 208.302606 -99.024948)
		(end 208.302606 -95.997776)
		(width 0.10668)
		(layer "B.Cu")
		(net "IRQ_SMI_ACTIVE_N")
	)
	(segment
		(start 377.48464 -293.93896)
		(end 381.0127 -293.93896)
		(width 0.10668)
		(layer "B.Cu")
		(net "IRQ_SMI_ACTIVE_N")
	)
	(segment
		(start 377.046998 -294.741092)
		(end 377.31446 -294.488616)
		(width 0.10668)
		(layer "B.Cu")
		(net "IRQ_SMI_ACTIVE_N")
	)
	(segment
		(start 208.302606 -95.997776)
		(end 202.325478 -90.020648)
		(width 0.10668)
		(layer "B.Cu")
		(net "IRQ_SMI_ACTIVE_N")
	)
	(segment
		(start 216.96426 -102.62489)
		(end 216.837768 -102.498398)
		(width 0.10668)
		(layer "B.Cu")
		(net "IRQ_SMI_ACTIVE_N")
	)
	(segment
		(start 391.4775 -316.720474)
		(end 389.41248 -316.720474)
		(width 0.10668)
		(layer "B.Cu")
		(net "IRQ_SMI_ACTIVE_N")
	)
	(segment
		(start 388.356348 -315.664342)
		(end 388.107428 -315.664342)
		(width 0.10668)
		(layer "B.Cu")
		(net "IRQ_SMI_ACTIVE_N")
	)
	(segment
		(start 389.41248 -316.720474)
		(end 388.356348 -315.664342)
		(width 0.10668)
		(layer "B.Cu")
		(net "IRQ_SMI_ACTIVE_N")
	)
	(segment
		(start 381.0127 -293.93896)
		(end 381.19558 -294.12184)
		(width 0.10668)
		(layer "B.Cu")
		(net "IRQ_SMI_ACTIVE_N")
	)
	(segment
		(start 186.29249 -92.549472)
		(end 185.739278 -93.102684)
		(width 0.10668)
		(layer "B.Cu")
		(net "IRQ_SMI_ACTIVE_N")
	)
	(segment
		(start 401.922488 -322.170552)
		(end 401.922488 -321.179952)
		(width 0.10668)
		(layer "B.Cu")
		(net "IRQ_SMI_ACTIVE_N")
	)
	(segment
		(start 377.31446 -294.488616)
		(end 377.31446 -294.10914)
		(width 0.10668)
		(layer "B.Cu")
		(net "IRQ_SMI_ACTIVE_N")
	)
	(segment
		(start 187.771532 -92.549472)
		(end 186.29249 -92.549472)
		(width 0.10668)
		(layer "B.Cu")
		(net "IRQ_SMI_ACTIVE_N")
	)
	(segment
		(start 190.300356 -90.020648)
		(end 187.771532 -92.549472)
		(width 0.10668)
		(layer "B.Cu")
		(net "IRQ_SMI_ACTIVE_N")
	)
	(segment
		(start 400.71802 -321.162172)
		(end 401.904708 -321.162172)
		(width 0.10668)
		(layer "B.Cu")
		(net "IRQ_SMI_ACTIVE_N")
	)
	(segment
		(start 222.340678 -113.338102)
		(end 222.553022 -113.550446)
		(width 0.11684)
		(layer "In4.Cu")
		(net "IRQ_SMI_ACTIVE_N")
	)
	(segment
		(start 222.340678 -106.702352)
		(end 222.340678 -113.338102)
		(width 0.11684)
		(layer "In4.Cu")
		(net "IRQ_SMI_ACTIVE_N")
	)
	(segment
		(start 220.176344 -137.653268)
		(end 220.176344 -141.781276)
		(width 0.11684)
		(layer "In4.Cu")
		(net "IRQ_SMI_ACTIVE_N")
	)
	(segment
		(start 218.713304 -102.62489)
		(end 220.84792 -104.759506)
		(width 0.11684)
		(layer "In4.Cu")
		(net "IRQ_SMI_ACTIVE_N")
	)
	(segment
		(start 220.84792 -105.209594)
		(end 222.340678 -106.702352)
		(width 0.11684)
		(layer "In4.Cu")
		(net "IRQ_SMI_ACTIVE_N")
	)
	(segment
		(start 220.176344 -141.781276)
		(end 220.308424 -141.913356)
		(width 0.11684)
		(layer "In4.Cu")
		(net "IRQ_SMI_ACTIVE_N")
	)
	(segment
		(start 222.553022 -135.27659)
		(end 220.176344 -137.653268)
		(width 0.11684)
		(layer "In4.Cu")
		(net "IRQ_SMI_ACTIVE_N")
	)
	(segment
		(start 220.84792 -104.759506)
		(end 220.84792 -105.209594)
		(width 0.11684)
		(layer "In4.Cu")
		(net "IRQ_SMI_ACTIVE_N")
	)
	(segment
		(start 216.96426 -102.62489)
		(end 218.713304 -102.62489)
		(width 0.11684)
		(layer "In4.Cu")
		(net "IRQ_SMI_ACTIVE_N")
	)
	(segment
		(start 222.553022 -113.550446)
		(end 222.553022 -135.27659)
		(width 0.11684)
		(layer "In4.Cu")
		(net "IRQ_SMI_ACTIVE_N")
	)
	(segment
		(start 273.321272 -142.817088)
		(end 291.913056 -142.817088)
		(width 0.11684)
		(layer "In6.Cu")
		(net "IRQ_SMI_ACTIVE_N")
	)
	(segment
		(start 243.961412 -146.259296)
		(end 244.095778 -146.259296)
		(width 0.11684)
		(layer "In6.Cu")
		(net "IRQ_SMI_ACTIVE_N")
	)
	(segment
		(start 449.197222 -169.819066)
		(end 449.197222 -176.900078)
		(width 0.11684)
		(layer "In6.Cu")
		(net "IRQ_SMI_ACTIVE_N")
	)
	(segment
		(start 454.53173 -326.4789)
		(end 412.169102 -326.4789)
		(width 0.11684)
		(layer "In6.Cu")
		(net "IRQ_SMI_ACTIVE_N")
	)
	(segment
		(start 412.169102 -326.4789)
		(end 409.99029 -324.300088)
		(width 0.11684)
		(layer "In6.Cu")
		(net "IRQ_SMI_ACTIVE_N")
	)
	(segment
		(start 291.913056 -142.817088)
		(end 304.208942 -130.521202)
		(width 0.11684)
		(layer "In6.Cu")
		(net "IRQ_SMI_ACTIVE_N")
	)
	(segment
		(start 431.578766 -154.368246)
		(end 439.585608 -162.375088)
		(width 0.11684)
		(layer "In6.Cu")
		(net "IRQ_SMI_ACTIVE_N")
	)
	(segment
		(start 220.461078 -141.760702)
		(end 239.462818 -141.760702)
		(width 0.11684)
		(layer "In6.Cu")
		(net "IRQ_SMI_ACTIVE_N")
	)
	(segment
		(start 347.894402 -132.380228)
		(end 359.71734 -132.380228)
		(width 0.11684)
		(layer "In6.Cu")
		(net "IRQ_SMI_ACTIVE_N")
	)
	(segment
		(start 263.537192 -152.601168)
		(end 273.321272 -142.817088)
		(width 0.11684)
		(layer "In6.Cu")
		(net "IRQ_SMI_ACTIVE_N")
	)
	(segment
		(start 320.01587 -130.521202)
		(end 323.039232 -127.49784)
		(width 0.11684)
		(layer "In6.Cu")
		(net "IRQ_SMI_ACTIVE_N")
	)
	(segment
		(start 359.71734 -132.380228)
		(end 360.949748 -131.14782)
		(width 0.11684)
		(layer "In6.Cu")
		(net "IRQ_SMI_ACTIVE_N")
	)
	(segment
		(start 449.197222 -176.900078)
		(end 460.812896 -188.515752)
		(width 0.11684)
		(layer "In6.Cu")
		(net "IRQ_SMI_ACTIVE_N")
	)
	(segment
		(start 415.506916 -131.14782)
		(end 431.578766 -147.21967)
		(width 0.11684)
		(layer "In6.Cu")
		(net "IRQ_SMI_ACTIVE_N")
	)
	(segment
		(start 250.43765 -152.601168)
		(end 263.537192 -152.601168)
		(width 0.11684)
		(layer "In6.Cu")
		(net "IRQ_SMI_ACTIVE_N")
	)
	(segment
		(start 441.753244 -162.375088)
		(end 449.197222 -169.819066)
		(width 0.11684)
		(layer "In6.Cu")
		(net "IRQ_SMI_ACTIVE_N")
	)
	(segment
		(start 460.812896 -188.515752)
		(end 460.812896 -320.197734)
		(width 0.11684)
		(layer "In6.Cu")
		(net "IRQ_SMI_ACTIVE_N")
	)
	(segment
		(start 244.095778 -146.259296)
		(end 250.43765 -152.601168)
		(width 0.11684)
		(layer "In6.Cu")
		(net "IRQ_SMI_ACTIVE_N")
	)
	(segment
		(start 360.949748 -131.14782)
		(end 415.506916 -131.14782)
		(width 0.11684)
		(layer "In6.Cu")
		(net "IRQ_SMI_ACTIVE_N")
	)
	(segment
		(start 402.353272 -323.323712)
		(end 402.353272 -322.884292)
		(width 0.11684)
		(layer "In6.Cu")
		(net "IRQ_SMI_ACTIVE_N")
	)
	(segment
		(start 304.208942 -130.521202)
		(end 320.01587 -130.521202)
		(width 0.11684)
		(layer "In6.Cu")
		(net "IRQ_SMI_ACTIVE_N")
	)
	(segment
		(start 343.012014 -127.49784)
		(end 347.894402 -132.380228)
		(width 0.11684)
		(layer "In6.Cu")
		(net "IRQ_SMI_ACTIVE_N")
	)
	(segment
		(start 439.585608 -162.375088)
		(end 441.753244 -162.375088)
		(width 0.11684)
		(layer "In6.Cu")
		(net "IRQ_SMI_ACTIVE_N")
	)
	(segment
		(start 431.578766 -147.21967)
		(end 431.578766 -154.368246)
		(width 0.11684)
		(layer "In6.Cu")
		(net "IRQ_SMI_ACTIVE_N")
	)
	(segment
		(start 239.462818 -141.760702)
		(end 243.961412 -146.259296)
		(width 0.11684)
		(layer "In6.Cu")
		(net "IRQ_SMI_ACTIVE_N")
	)
	(segment
		(start 403.329648 -324.300088)
		(end 402.353272 -323.323712)
		(width 0.11684)
		(layer "In6.Cu")
		(net "IRQ_SMI_ACTIVE_N")
	)
	(segment
		(start 220.308424 -141.913356)
		(end 220.461078 -141.760702)
		(width 0.11684)
		(layer "In6.Cu")
		(net "IRQ_SMI_ACTIVE_N")
	)
	(segment
		(start 323.039232 -127.49784)
		(end 343.012014 -127.49784)
		(width 0.11684)
		(layer "In6.Cu")
		(net "IRQ_SMI_ACTIVE_N")
	)
	(segment
		(start 409.99029 -324.300088)
		(end 403.329648 -324.300088)
		(width 0.11684)
		(layer "In6.Cu")
		(net "IRQ_SMI_ACTIVE_N")
	)
	(segment
		(start 460.812896 -320.197734)
		(end 454.53173 -326.4789)
		(width 0.11684)
		(layer "In6.Cu")
		(net "IRQ_SMI_ACTIVE_N")
	)
	(segment
		(start 179.9082 -95.291148)
		(end 179.705 -95.087948)
		(width 0.10668)
		(layer "F.Cu")
		(net "IRQ_CPU_BMC_NMI_N")
	)
	(segment
		(start 179.9082 -95.703898)
		(end 179.9082 -95.291148)
		(width 0.10668)
		(layer "F.Cu")
		(net "IRQ_CPU_BMC_NMI_N")
	)
	(segment
		(start 110.1979 -293.260272)
		(end 109.731048 -293.52621)
		(width 0.10668)
		(layer "F.Cu")
		(net "IRQ_CPU_BMC_NMI_N")
	)
	(via
		(at 161.304732 -101.5238)
		(size 0.508)
		(drill 0.254)
		(layers "F.Cu" "B.Cu")
		(net "IRQ_CPU_BMC_NMI_N")
	)
	(via
		(at 179.705 -95.087948)
		(size 0.508)
		(drill 0.254)
		(layers "F.Cu" "B.Cu")
		(net "IRQ_CPU_BMC_NMI_N")
	)
	(via
		(at 109.731048 -293.52621)
		(size 0.4064)
		(drill 0.2032)
		(layers "F.Cu" "B.Cu")
		(net "IRQ_CPU_BMC_NMI_N")
	)
	(segment
		(start 93.495368 -303.096422)
		(end 92.827094 -303.764696)
		(width 0.10668)
		(layer "B.Cu")
		(net "IRQ_CPU_BMC_NMI_N")
	)
	(segment
		(start 109.3343 -295.917874)
		(end 101.557582 -303.694592)
		(width 0.10668)
		(layer "B.Cu")
		(net "IRQ_CPU_BMC_NMI_N")
	)
	(segment
		(start 157.216602 -107.174284)
		(end 160.292034 -104.098852)
		(width 0.10668)
		(layer "B.Cu")
		(net "IRQ_CPU_BMC_NMI_N")
	)
	(segment
		(start 94.08795 -301.716948)
		(end 93.706442 -301.716948)
		(width 0.10668)
		(layer "B.Cu")
		(net "IRQ_CPU_BMC_NMI_N")
	)
	(segment
		(start 152.98547 -107.174284)
		(end 157.216602 -107.174284)
		(width 0.10668)
		(layer "B.Cu")
		(net "IRQ_CPU_BMC_NMI_N")
	)
	(segment
		(start 101.557582 -303.694592)
		(end 96.520254 -303.694592)
		(width 0.10668)
		(layer "B.Cu")
		(net "IRQ_CPU_BMC_NMI_N")
	)
	(segment
		(start 12.233656 -187.06592)
		(end 32.684212 -166.615364)
		(width 0.10668)
		(layer "B.Cu")
		(net "IRQ_CPU_BMC_NMI_N")
	)
	(segment
		(start 151.300434 -111.113062)
		(end 151.300434 -108.85932)
		(width 0.10668)
		(layer "B.Cu")
		(net "IRQ_CPU_BMC_NMI_N")
	)
	(segment
		(start 150.583392 -111.830104)
		(end 151.300434 -111.113062)
		(width 0.10668)
		(layer "B.Cu")
		(net "IRQ_CPU_BMC_NMI_N")
	)
	(segment
		(start 41.11117 -144.519396)
		(end 69.122544 -116.508022)
		(width 0.10668)
		(layer "B.Cu")
		(net "IRQ_CPU_BMC_NMI_N")
	)
	(segment
		(start 96.520254 -303.694592)
		(end 95.631254 -302.805592)
		(width 0.10668)
		(layer "B.Cu")
		(net "IRQ_CPU_BMC_NMI_N")
	)
	(segment
		(start 92.609924 -305.623722)
		(end 92.609924 -309.45201)
		(width 0.10668)
		(layer "B.Cu")
		(net "IRQ_CPU_BMC_NMI_N")
	)
	(segment
		(start 57.175146 -322.310506)
		(end 18.15719 -322.310506)
		(width 0.10668)
		(layer "B.Cu")
		(net "IRQ_CPU_BMC_NMI_N")
	)
	(segment
		(start 160.292034 -104.098852)
		(end 161.519108 -104.098852)
		(width 0.10668)
		(layer "B.Cu")
		(net "IRQ_CPU_BMC_NMI_N")
	)
	(segment
		(start 109.731048 -294.476678)
		(end 109.3343 -294.873426)
		(width 0.10668)
		(layer "B.Cu")
		(net "IRQ_CPU_BMC_NMI_N")
	)
	(segment
		(start 41.11117 -158.208218)
		(end 41.11117 -144.519396)
		(width 0.10668)
		(layer "B.Cu")
		(net "IRQ_CPU_BMC_NMI_N")
	)
	(segment
		(start 38.078664 -161.22142)
		(end 38.097968 -161.22142)
		(width 0.10668)
		(layer "B.Cu")
		(net "IRQ_CPU_BMC_NMI_N")
	)
	(segment
		(start 94.08795 -301.716948)
		(end 94.08795 -302.023018)
		(width 0.10668)
		(layer "B.Cu")
		(net "IRQ_CPU_BMC_NMI_N")
	)
	(segment
		(start 162.437826 -103.180134)
		(end 162.437826 -102.656894)
		(width 0.10668)
		(layer "B.Cu")
		(net "IRQ_CPU_BMC_NMI_N")
	)
	(segment
		(start 151.300434 -108.85932)
		(end 152.98547 -107.174284)
		(width 0.10668)
		(layer "B.Cu")
		(net "IRQ_CPU_BMC_NMI_N")
	)
	(segment
		(start 38.097968 -161.22142)
		(end 41.11117 -158.208218)
		(width 0.10668)
		(layer "B.Cu")
		(net "IRQ_CPU_BMC_NMI_N")
	)
	(segment
		(start 161.519108 -104.098852)
		(end 162.437826 -103.180134)
		(width 0.10668)
		(layer "B.Cu")
		(net "IRQ_CPU_BMC_NMI_N")
	)
	(segment
		(start 93.706442 -301.716948)
		(end 93.495368 -301.928022)
		(width 0.10668)
		(layer "B.Cu")
		(net "IRQ_CPU_BMC_NMI_N")
	)
	(segment
		(start 147.15617 -112.908334)
		(end 148.2344 -111.830104)
		(width 0.10668)
		(layer "B.Cu")
		(net "IRQ_CPU_BMC_NMI_N")
	)
	(segment
		(start 95.631254 -302.805592)
		(end 94.870524 -302.805592)
		(width 0.10668)
		(layer "B.Cu")
		(net "IRQ_CPU_BMC_NMI_N")
	)
	(segment
		(start 91.341448 -310.720486)
		(end 68.765166 -310.720486)
		(width 0.10668)
		(layer "B.Cu")
		(net "IRQ_CPU_BMC_NMI_N")
	)
	(segment
		(start 109.731048 -293.52621)
		(end 109.731048 -294.476678)
		(width 0.10668)
		(layer "B.Cu")
		(net "IRQ_CPU_BMC_NMI_N")
	)
	(segment
		(start 141.85392 -116.508022)
		(end 145.453608 -112.908334)
		(width 0.10668)
		(layer "B.Cu")
		(net "IRQ_CPU_BMC_NMI_N")
	)
	(segment
		(start 92.827094 -305.406552)
		(end 92.609924 -305.623722)
		(width 0.10668)
		(layer "B.Cu")
		(net "IRQ_CPU_BMC_NMI_N")
	)
	(segment
		(start 32.68472 -166.615364)
		(end 38.078664 -161.22142)
		(width 0.10668)
		(layer "B.Cu")
		(net "IRQ_CPU_BMC_NMI_N")
	)
	(segment
		(start 145.453608 -112.908334)
		(end 147.15617 -112.908334)
		(width 0.10668)
		(layer "B.Cu")
		(net "IRQ_CPU_BMC_NMI_N")
	)
	(segment
		(start 92.827094 -303.764696)
		(end 92.827094 -305.406552)
		(width 0.10668)
		(layer "B.Cu")
		(net "IRQ_CPU_BMC_NMI_N")
	)
	(segment
		(start 94.08795 -302.023018)
		(end 94.870524 -302.805592)
		(width 0.10668)
		(layer "B.Cu")
		(net "IRQ_CPU_BMC_NMI_N")
	)
	(segment
		(start 148.2344 -111.830104)
		(end 150.583392 -111.830104)
		(width 0.10668)
		(layer "B.Cu")
		(net "IRQ_CPU_BMC_NMI_N")
	)
	(segment
		(start 14.27226 -324.572884)
		(end 12.233656 -322.53428)
		(width 0.10668)
		(layer "B.Cu")
		(net "IRQ_CPU_BMC_NMI_N")
	)
	(segment
		(start 12.233656 -322.53428)
		(end 12.233656 -187.06592)
		(width 0.10668)
		(layer "B.Cu")
		(net "IRQ_CPU_BMC_NMI_N")
	)
	(segment
		(start 32.684212 -166.615364)
		(end 32.68472 -166.615364)
		(width 0.10668)
		(layer "B.Cu")
		(net "IRQ_CPU_BMC_NMI_N")
	)
	(segment
		(start 69.122544 -116.508022)
		(end 141.85392 -116.508022)
		(width 0.10668)
		(layer "B.Cu")
		(net "IRQ_CPU_BMC_NMI_N")
	)
	(segment
		(start 18.15719 -322.310506)
		(end 15.894812 -324.572884)
		(width 0.10668)
		(layer "B.Cu")
		(net "IRQ_CPU_BMC_NMI_N")
	)
	(segment
		(start 93.495368 -301.928022)
		(end 93.495368 -303.096422)
		(width 0.10668)
		(layer "B.Cu")
		(net "IRQ_CPU_BMC_NMI_N")
	)
	(segment
		(start 92.609924 -309.45201)
		(end 91.341448 -310.720486)
		(width 0.10668)
		(layer "B.Cu")
		(net "IRQ_CPU_BMC_NMI_N")
	)
	(segment
		(start 109.3343 -294.873426)
		(end 109.3343 -295.917874)
		(width 0.10668)
		(layer "B.Cu")
		(net "IRQ_CPU_BMC_NMI_N")
	)
	(segment
		(start 162.437826 -102.656894)
		(end 161.304732 -101.5238)
		(width 0.10668)
		(layer "B.Cu")
		(net "IRQ_CPU_BMC_NMI_N")
	)
	(segment
		(start 68.765166 -310.720486)
		(end 57.175146 -322.310506)
		(width 0.10668)
		(layer "B.Cu")
		(net "IRQ_CPU_BMC_NMI_N")
	)
	(segment
		(start 15.894812 -324.572884)
		(end 14.27226 -324.572884)
		(width 0.10668)
		(layer "B.Cu")
		(net "IRQ_CPU_BMC_NMI_N")
	)
	(segment
		(start 161.615628 -101.834696)
		(end 161.304732 -101.5238)
		(width 0.11684)
		(layer "In2.Cu")
		(net "IRQ_CPU_BMC_NMI_N")
	)
	(segment
		(start 179.705 -95.087948)
		(end 178.619912 -96.173036)
		(width 0.11684)
		(layer "In2.Cu")
		(net "IRQ_CPU_BMC_NMI_N")
	)
	(segment
		(start 163.797996 -100.731066)
		(end 163.797996 -101.003608)
		(width 0.11684)
		(layer "In2.Cu")
		(net "IRQ_CPU_BMC_NMI_N")
	)
	(segment
		(start 175.544226 -96.173036)
		(end 174.132494 -97.584768)
		(width 0.11684)
		(layer "In2.Cu")
		(net "IRQ_CPU_BMC_NMI_N")
	)
	(segment
		(start 174.132494 -97.584768)
		(end 170.273726 -97.584768)
		(width 0.11684)
		(layer "In2.Cu")
		(net "IRQ_CPU_BMC_NMI_N")
	)
	(segment
		(start 163.797996 -101.003608)
		(end 162.966908 -101.834696)
		(width 0.11684)
		(layer "In2.Cu")
		(net "IRQ_CPU_BMC_NMI_N")
	)
	(segment
		(start 178.619912 -96.173036)
		(end 175.544226 -96.173036)
		(width 0.11684)
		(layer "In2.Cu")
		(net "IRQ_CPU_BMC_NMI_N")
	)
	(segment
		(start 166.596314 -99.076256)
		(end 165.452806 -99.076256)
		(width 0.11684)
		(layer "In2.Cu")
		(net "IRQ_CPU_BMC_NMI_N")
	)
	(segment
		(start 170.052238 -97.36328)
		(end 168.30929 -97.36328)
		(width 0.11684)
		(layer "In2.Cu")
		(net "IRQ_CPU_BMC_NMI_N")
	)
	(segment
		(start 162.966908 -101.834696)
		(end 161.615628 -101.834696)
		(width 0.11684)
		(layer "In2.Cu")
		(net "IRQ_CPU_BMC_NMI_N")
	)
	(segment
		(start 170.273726 -97.584768)
		(end 170.052238 -97.36328)
		(width 0.11684)
		(layer "In2.Cu")
		(net "IRQ_CPU_BMC_NMI_N")
	)
	(segment
		(start 165.452806 -99.076256)
		(end 163.797996 -100.731066)
		(width 0.11684)
		(layer "In2.Cu")
		(net "IRQ_CPU_BMC_NMI_N")
	)
	(segment
		(start 168.30929 -97.36328)
		(end 166.596314 -99.076256)
		(width 0.11684)
		(layer "In2.Cu")
		(net "IRQ_CPU_BMC_NMI_N")
	)
	(segment
		(start 358.607868 -292.450012)
		(end 358.141016 -292.71595)
		(width 0.10668)
		(layer "F.Cu")
		(net "IRQ_BMC_SMI_N")
	)
	(via
		(at 234.014772 -139.536678)
		(size 0.508)
		(drill 0.254)
		(layers "F.Cu" "B.Cu")
		(net "IRQ_BMC_SMI_N")
	)
	(via
		(at 406.147778 -332.679548)
		(size 0.508)
		(drill 0.254)
		(layers "F.Cu" "B.Cu")
		(net "IRQ_BMC_SMI_N")
	)
	(via
		(at 234.014772 -94.60865)
		(size 0.508)
		(drill 0.254)
		(layers "F.Cu" "B.Cu")
		(net "IRQ_BMC_SMI_N")
	)
	(via
		(at 358.141016 -292.71595)
		(size 0.4064)
		(drill 0.2032)
		(layers "F.Cu" "B.Cu")
		(net "IRQ_BMC_SMI_N")
	)
	(via
		(at 207.71612 -93.19387)
		(size 0.508)
		(drill 0.254)
		(layers "F.Cu" "B.Cu")
		(net "IRQ_BMC_SMI_N")
	)
	(via
		(at 361.197398 -302.983392)
		(size 0.6604)
		(drill 0.3302)
		(layers "F.Cu" "B.Cu")
		(net "IRQ_BMC_SMI_N")
	)
	(segment
		(start 174.64786 -98.52914)
		(end 174.64786 -95.063564)
		(width 0.10668)
		(layer "B.Cu")
		(net "IRQ_BMC_SMI_N")
	)
	(segment
		(start 175.160432 -99.374706)
		(end 175.160432 -99.041712)
		(width 0.10668)
		(layer "B.Cu")
		(net "IRQ_BMC_SMI_N")
	)
	(segment
		(start 361.197398 -303.953926)
		(end 370.628418 -313.384946)
		(width 0.10668)
		(layer "B.Cu")
		(net "IRQ_BMC_SMI_N")
	)
	(segment
		(start 406.298908 -329.123548)
		(end 405.662892 -329.759564)
		(width 0.10668)
		(layer "B.Cu")
		(net "IRQ_BMC_SMI_N")
	)
	(segment
		(start 406.736804 -331.496416)
		(end 406.317704 -331.077316)
		(width 0.10668)
		(layer "B.Cu")
		(net "IRQ_BMC_SMI_N")
	)
	(segment
		(start 360.830622 -302.622204)
		(end 360.83621 -302.622204)
		(width 0.10668)
		(layer "B.Cu")
		(net "IRQ_BMC_SMI_N")
	)
	(segment
		(start 206.577184 -93.19387)
		(end 207.71612 -93.19387)
		(width 0.10668)
		(layer "B.Cu")
		(net "IRQ_BMC_SMI_N")
	)
	(segment
		(start 390.531096 -335.05775)
		(end 403.769576 -335.05775)
		(width 0.10668)
		(layer "B.Cu")
		(net "IRQ_BMC_SMI_N")
	)
	(segment
		(start 184.44718 -92.31503)
		(end 184.93867 -91.82354)
		(width 0.10668)
		(layer "B.Cu")
		(net "IRQ_BMC_SMI_N")
	)
	(segment
		(start 177.328068 -93.168978)
		(end 178.182016 -92.31503)
		(width 0.10668)
		(layer "B.Cu")
		(net "IRQ_BMC_SMI_N")
	)
	(segment
		(start 359.708958 -293.913814)
		(end 359.708958 -301.50054)
		(width 0.10668)
		(layer "B.Cu")
		(net "IRQ_BMC_SMI_N")
	)
	(segment
		(start 188.631576 -91.178888)
		(end 190.150496 -89.659968)
		(width 0.10668)
		(layer "B.Cu")
		(net "IRQ_BMC_SMI_N")
	)
	(segment
		(start 190.150496 -89.659968)
		(end 203.043282 -89.659968)
		(width 0.10668)
		(layer "B.Cu")
		(net "IRQ_BMC_SMI_N")
	)
	(segment
		(start 403.769576 -335.05775)
		(end 406.147778 -332.679548)
		(width 0.10668)
		(layer "B.Cu")
		(net "IRQ_BMC_SMI_N")
	)
	(segment
		(start 405.662892 -329.759564)
		(end 405.662892 -330.280518)
		(width 0.10668)
		(layer "B.Cu")
		(net "IRQ_BMC_SMI_N")
	)
	(segment
		(start 174.64786 -95.063564)
		(end 176.542446 -93.168978)
		(width 0.10668)
		(layer "B.Cu")
		(net "IRQ_BMC_SMI_N")
	)
	(segment
		(start 175.160432 -99.041712)
		(end 174.64786 -98.52914)
		(width 0.10668)
		(layer "B.Cu")
		(net "IRQ_BMC_SMI_N")
	)
	(segment
		(start 358.141016 -292.71595)
		(end 358.511094 -292.71595)
		(width 0.10668)
		(layer "B.Cu")
		(net "IRQ_BMC_SMI_N")
	)
	(segment
		(start 406.147778 -332.679548)
		(end 406.736804 -332.090522)
		(width 0.10668)
		(layer "B.Cu")
		(net "IRQ_BMC_SMI_N")
	)
	(segment
		(start 406.298908 -328.926952)
		(end 406.298908 -329.123548)
		(width 0.10668)
		(layer "B.Cu")
		(net "IRQ_BMC_SMI_N")
	)
	(segment
		(start 358.511094 -292.71595)
		(end 359.708958 -293.913814)
		(width 0.10668)
		(layer "B.Cu")
		(net "IRQ_BMC_SMI_N")
	)
	(segment
		(start 370.628418 -313.384946)
		(end 370.628418 -315.155072)
		(width 0.10668)
		(layer "B.Cu")
		(net "IRQ_BMC_SMI_N")
	)
	(segment
		(start 203.043282 -89.659968)
		(end 206.577184 -93.19387)
		(width 0.10668)
		(layer "B.Cu")
		(net "IRQ_BMC_SMI_N")
	)
	(segment
		(start 184.93867 -91.317572)
		(end 185.077354 -91.178888)
		(width 0.10668)
		(layer "B.Cu")
		(net "IRQ_BMC_SMI_N")
	)
	(segment
		(start 360.83621 -302.622204)
		(end 361.197398 -302.983392)
		(width 0.10668)
		(layer "B.Cu")
		(net "IRQ_BMC_SMI_N")
	)
	(segment
		(start 176.542446 -93.168978)
		(end 177.328068 -93.168978)
		(width 0.10668)
		(layer "B.Cu")
		(net "IRQ_BMC_SMI_N")
	)
	(segment
		(start 178.182016 -92.31503)
		(end 184.44718 -92.31503)
		(width 0.10668)
		(layer "B.Cu")
		(net "IRQ_BMC_SMI_N")
	)
	(segment
		(start 184.93867 -91.82354)
		(end 184.93867 -91.317572)
		(width 0.10668)
		(layer "B.Cu")
		(net "IRQ_BMC_SMI_N")
	)
	(segment
		(start 370.628418 -315.155072)
		(end 390.531096 -335.05775)
		(width 0.10668)
		(layer "B.Cu")
		(net "IRQ_BMC_SMI_N")
	)
	(segment
		(start 406.317704 -331.077316)
		(end 406.317704 -330.93533)
		(width 0.10668)
		(layer "B.Cu")
		(net "IRQ_BMC_SMI_N")
	)
	(segment
		(start 185.077354 -91.178888)
		(end 188.631576 -91.178888)
		(width 0.10668)
		(layer "B.Cu")
		(net "IRQ_BMC_SMI_N")
	)
	(segment
		(start 361.197398 -302.983392)
		(end 361.197398 -303.953926)
		(width 0.10668)
		(layer "B.Cu")
		(net "IRQ_BMC_SMI_N")
	)
	(segment
		(start 406.736804 -332.090522)
		(end 406.736804 -331.496416)
		(width 0.10668)
		(layer "B.Cu")
		(net "IRQ_BMC_SMI_N")
	)
	(segment
		(start 359.708958 -301.50054)
		(end 360.830622 -302.622204)
		(width 0.10668)
		(layer "B.Cu")
		(net "IRQ_BMC_SMI_N")
	)
	(segment
		(start 174.64024 -99.894898)
		(end 175.160432 -99.374706)
		(width 0.10668)
		(layer "B.Cu")
		(net "IRQ_BMC_SMI_N")
	)
	(segment
		(start 405.662892 -330.280518)
		(end 406.317704 -330.93533)
		(width 0.10668)
		(layer "B.Cu")
		(net "IRQ_BMC_SMI_N")
	)
	(segment
		(start 234.014772 -94.60865)
		(end 234.014772 -95.665036)
		(width 0.11684)
		(layer "In4.Cu")
		(net "IRQ_BMC_SMI_N")
	)
	(segment
		(start 233.173524 -96.506284)
		(end 233.173524 -138.69543)
		(width 0.11684)
		(layer "In4.Cu")
		(net "IRQ_BMC_SMI_N")
	)
	(segment
		(start 233.173524 -138.69543)
		(end 234.014772 -139.536678)
		(width 0.11684)
		(layer "In4.Cu")
		(net "IRQ_BMC_SMI_N")
	)
	(segment
		(start 234.014772 -95.665036)
		(end 233.173524 -96.506284)
		(width 0.11684)
		(layer "In4.Cu")
		(net "IRQ_BMC_SMI_N")
	)
	(segment
		(start 416.380676 -129.03962)
		(end 433.686966 -146.34591)
		(width 0.11684)
		(layer "In6.Cu")
		(net "IRQ_BMC_SMI_N")
	)
	(segment
		(start 348.768162 -130.272028)
		(end 358.84358 -130.272028)
		(width 0.11684)
		(layer "In6.Cu")
		(net "IRQ_BMC_SMI_N")
	)
	(segment
		(start 291.03955 -140.708634)
		(end 303.335182 -128.413002)
		(width 0.11684)
		(layer "In6.Cu")
		(net "IRQ_BMC_SMI_N")
	)
	(segment
		(start 462.921096 -187.62218)
		(end 462.921096 -321.071494)
		(width 0.11684)
		(layer "In6.Cu")
		(net "IRQ_BMC_SMI_N")
	)
	(segment
		(start 442.088524 -159.728408)
		(end 451.843902 -169.483786)
		(width 0.11684)
		(layer "In6.Cu")
		(net "IRQ_BMC_SMI_N")
	)
	(segment
		(start 439.920888 -159.728408)
		(end 442.088524 -159.728408)
		(width 0.11684)
		(layer "In6.Cu")
		(net "IRQ_BMC_SMI_N")
	)
	(segment
		(start 433.686966 -146.34591)
		(end 433.686966 -153.494486)
		(width 0.11684)
		(layer "In6.Cu")
		(net "IRQ_BMC_SMI_N")
	)
	(segment
		(start 262.663432 -150.492968)
		(end 272.447766 -140.708634)
		(width 0.11684)
		(layer "In6.Cu")
		(net "IRQ_BMC_SMI_N")
	)
	(segment
		(start 207.71612 -93.19387)
		(end 232.599992 -93.19387)
		(width 0.11684)
		(layer "In6.Cu")
		(net "IRQ_BMC_SMI_N")
	)
	(segment
		(start 232.599992 -93.19387)
		(end 234.014772 -94.60865)
		(width 0.11684)
		(layer "In6.Cu")
		(net "IRQ_BMC_SMI_N")
	)
	(segment
		(start 407.503376 -334.035146)
		(end 406.147778 -332.679548)
		(width 0.11684)
		(layer "In6.Cu")
		(net "IRQ_BMC_SMI_N")
	)
	(segment
		(start 360.075988 -129.03962)
		(end 416.380676 -129.03962)
		(width 0.11684)
		(layer "In6.Cu")
		(net "IRQ_BMC_SMI_N")
	)
	(segment
		(start 451.843902 -176.544986)
		(end 462.921096 -187.62218)
		(width 0.11684)
		(layer "In6.Cu")
		(net "IRQ_BMC_SMI_N")
	)
	(segment
		(start 251.31141 -150.492968)
		(end 262.663432 -150.492968)
		(width 0.11684)
		(layer "In6.Cu")
		(net "IRQ_BMC_SMI_N")
	)
	(segment
		(start 244.969538 -144.151096)
		(end 251.31141 -150.492968)
		(width 0.11684)
		(layer "In6.Cu")
		(net "IRQ_BMC_SMI_N")
	)
	(segment
		(start 451.843902 -169.483786)
		(end 451.843902 -176.544986)
		(width 0.11684)
		(layer "In6.Cu")
		(net "IRQ_BMC_SMI_N")
	)
	(segment
		(start 433.686966 -153.494486)
		(end 439.920888 -159.728408)
		(width 0.11684)
		(layer "In6.Cu")
		(net "IRQ_BMC_SMI_N")
	)
	(segment
		(start 244.835172 -144.151096)
		(end 244.969538 -144.151096)
		(width 0.11684)
		(layer "In6.Cu")
		(net "IRQ_BMC_SMI_N")
	)
	(segment
		(start 462.921096 -321.071494)
		(end 455.184002 -328.808588)
		(width 0.11684)
		(layer "In6.Cu")
		(net "IRQ_BMC_SMI_N")
	)
	(segment
		(start 272.447766 -140.708634)
		(end 291.03955 -140.708634)
		(width 0.11684)
		(layer "In6.Cu")
		(net "IRQ_BMC_SMI_N")
	)
	(segment
		(start 358.84358 -130.272028)
		(end 360.075988 -129.03962)
		(width 0.11684)
		(layer "In6.Cu")
		(net "IRQ_BMC_SMI_N")
	)
	(segment
		(start 413.953452 -328.808588)
		(end 408.726894 -334.035146)
		(width 0.11684)
		(layer "In6.Cu")
		(net "IRQ_BMC_SMI_N")
	)
	(segment
		(start 343.885774 -125.38964)
		(end 348.768162 -130.272028)
		(width 0.11684)
		(layer "In6.Cu")
		(net "IRQ_BMC_SMI_N")
	)
	(segment
		(start 234.014772 -139.536678)
		(end 240.220754 -139.536678)
		(width 0.11684)
		(layer "In6.Cu")
		(net "IRQ_BMC_SMI_N")
	)
	(segment
		(start 455.184002 -328.808588)
		(end 413.953452 -328.808588)
		(width 0.11684)
		(layer "In6.Cu")
		(net "IRQ_BMC_SMI_N")
	)
	(segment
		(start 408.726894 -334.035146)
		(end 407.503376 -334.035146)
		(width 0.11684)
		(layer "In6.Cu")
		(net "IRQ_BMC_SMI_N")
	)
	(segment
		(start 240.220754 -139.536678)
		(end 244.835172 -144.151096)
		(width 0.11684)
		(layer "In6.Cu")
		(net "IRQ_BMC_SMI_N")
	)
	(segment
		(start 319.141856 -128.413002)
		(end 322.165218 -125.38964)
		(width 0.11684)
		(layer "In6.Cu")
		(net "IRQ_BMC_SMI_N")
	)
	(segment
		(start 303.335182 -128.413002)
		(end 319.141856 -128.413002)
		(width 0.11684)
		(layer "In6.Cu")
		(net "IRQ_BMC_SMI_N")
	)
	(segment
		(start 322.165218 -125.38964)
		(end 343.885774 -125.38964)
		(width 0.11684)
		(layer "In6.Cu")
		(net "IRQ_BMC_SMI_N")
	)
	(segment
		(start 209.294476 -112.662208)
		(end 210.493356 -112.662208)
		(width 0.10668)
		(layer "F.Cu")
		(net "FPGA_DEBUG_SW_SPARE")
	)
	(segment
		(start 431.5714 -37.277548)
		(end 430.5554 -37.277548)
		(width 0.10668)
		(layer "F.Cu")
		(net "FPGA_DEBUG_SW_SPARE")
	)
	(via
		(at 430.5554 -37.277548)
		(size 0.508)
		(drill 0.254)
		(layers "F.Cu" "B.Cu")
		(net "FPGA_DEBUG_SW_SPARE")
	)
	(via
		(at 210.493356 -112.662208)
		(size 0.508)
		(drill 0.254)
		(layers "F.Cu" "B.Cu")
		(net "FPGA_DEBUG_SW_SPARE")
	)
	(via
		(at 209.99831 -90.508836)
		(size 0.508)
		(drill 0.254)
		(layers "F.Cu" "B.Cu")
		(net "FPGA_DEBUG_SW_SPARE")
	)
	(segment
		(start 429.387 -38.039548)
		(end 429.7934 -38.039548)
		(width 0.10668)
		(layer "B.Cu")
		(net "FPGA_DEBUG_SW_SPARE")
	)
	(segment
		(start 429.7934 -38.039548)
		(end 430.5554 -37.277548)
		(width 0.10668)
		(layer "B.Cu")
		(net "FPGA_DEBUG_SW_SPARE")
	)
	(segment
		(start 210.493356 -112.662208)
		(end 210.233006 -112.662208)
		(width 0.11684)
		(layer "In4.Cu")
		(net "FPGA_DEBUG_SW_SPARE")
	)
	(segment
		(start 209.907378 -112.33658)
		(end 209.907378 -111.445548)
		(width 0.11684)
		(layer "In4.Cu")
		(net "FPGA_DEBUG_SW_SPARE")
	)
	(segment
		(start 209.907378 -111.445548)
		(end 210.63966 -110.713266)
		(width 0.11684)
		(layer "In4.Cu")
		(net "FPGA_DEBUG_SW_SPARE")
	)
	(segment
		(start 210.63966 -104.147366)
		(end 211.318602 -103.468424)
		(width 0.11684)
		(layer "In4.Cu")
		(net "FPGA_DEBUG_SW_SPARE")
	)
	(segment
		(start 211.318602 -103.468424)
		(end 211.318602 -100.458778)
		(width 0.11684)
		(layer "In4.Cu")
		(net "FPGA_DEBUG_SW_SPARE")
	)
	(segment
		(start 211.318602 -100.458778)
		(end 209.99831 -99.138486)
		(width 0.11684)
		(layer "In4.Cu")
		(net "FPGA_DEBUG_SW_SPARE")
	)
	(segment
		(start 210.233006 -112.662208)
		(end 209.907378 -112.33658)
		(width 0.11684)
		(layer "In4.Cu")
		(net "FPGA_DEBUG_SW_SPARE")
	)
	(segment
		(start 210.63966 -110.713266)
		(end 210.63966 -104.147366)
		(width 0.11684)
		(layer "In4.Cu")
		(net "FPGA_DEBUG_SW_SPARE")
	)
	(segment
		(start 209.99831 -99.138486)
		(end 209.99831 -90.508836)
		(width 0.11684)
		(layer "In4.Cu")
		(net "FPGA_DEBUG_SW_SPARE")
	)
	(segment
		(start 330.025756 -54.767988)
		(end 330.012548 -54.75478)
		(width 0.11684)
		(layer "In6.Cu")
		(net "FPGA_DEBUG_SW_SPARE")
	)
	(segment
		(start 210.43519 -90.945716)
		(end 209.99831 -90.508836)
		(width 0.11684)
		(layer "In6.Cu")
		(net "FPGA_DEBUG_SW_SPARE")
	)
	(segment
		(start 307.941472 -54.056788)
		(end 305.06289 -56.93537)
		(width 0.11684)
		(layer "In6.Cu")
		(net "FPGA_DEBUG_SW_SPARE")
	)
	(segment
		(start 279.674574 -68.20535)
		(end 274.798028 -73.081896)
		(width 0.11684)
		(layer "In6.Cu")
		(net "FPGA_DEBUG_SW_SPARE")
	)
	(segment
		(start 274.798028 -73.081896)
		(end 269.840964 -73.081896)
		(width 0.11684)
		(layer "In6.Cu")
		(net "FPGA_DEBUG_SW_SPARE")
	)
	(segment
		(start 269.840964 -73.081896)
		(end 259.816854 -83.106006)
		(width 0.11684)
		(layer "In6.Cu")
		(net "FPGA_DEBUG_SW_SPARE")
	)
	(segment
		(start 287.926526 -56.93537)
		(end 279.674574 -65.187322)
		(width 0.11684)
		(layer "In6.Cu")
		(net "FPGA_DEBUG_SW_SPARE")
	)
	(segment
		(start 279.674574 -65.187322)
		(end 279.674574 -68.20535)
		(width 0.11684)
		(layer "In6.Cu")
		(net "FPGA_DEBUG_SW_SPARE")
	)
	(segment
		(start 305.06289 -56.93537)
		(end 287.926526 -56.93537)
		(width 0.11684)
		(layer "In6.Cu")
		(net "FPGA_DEBUG_SW_SPARE")
	)
	(segment
		(start 330.012548 -54.75478)
		(end 324.60692 -54.75478)
		(width 0.11684)
		(layer "In6.Cu")
		(net "FPGA_DEBUG_SW_SPARE")
	)
	(segment
		(start 430.5554 -37.277548)
		(end 430.276 -37.556948)
		(width 0.11684)
		(layer "In6.Cu")
		(net "FPGA_DEBUG_SW_SPARE")
	)
	(segment
		(start 242.157758 -90.945716)
		(end 210.43519 -90.945716)
		(width 0.11684)
		(layer "In6.Cu")
		(net "FPGA_DEBUG_SW_SPARE")
	)
	(segment
		(start 380.518416 -54.767988)
		(end 330.025756 -54.767988)
		(width 0.11684)
		(layer "In6.Cu")
		(net "FPGA_DEBUG_SW_SPARE")
	)
	(segment
		(start 422.8084 -37.556948)
		(end 421.259 -39.106348)
		(width 0.11684)
		(layer "In6.Cu")
		(net "FPGA_DEBUG_SW_SPARE")
	)
	(segment
		(start 324.60692 -54.75478)
		(end 323.908928 -54.056788)
		(width 0.11684)
		(layer "In6.Cu")
		(net "FPGA_DEBUG_SW_SPARE")
	)
	(segment
		(start 323.908928 -54.056788)
		(end 307.941472 -54.056788)
		(width 0.11684)
		(layer "In6.Cu")
		(net "FPGA_DEBUG_SW_SPARE")
	)
	(segment
		(start 259.816854 -83.106006)
		(end 249.997468 -83.106006)
		(width 0.11684)
		(layer "In6.Cu")
		(net "FPGA_DEBUG_SW_SPARE")
	)
	(segment
		(start 396.180056 -39.106348)
		(end 380.518416 -54.767988)
		(width 0.11684)
		(layer "In6.Cu")
		(net "FPGA_DEBUG_SW_SPARE")
	)
	(segment
		(start 421.259 -39.106348)
		(end 396.180056 -39.106348)
		(width 0.11684)
		(layer "In6.Cu")
		(net "FPGA_DEBUG_SW_SPARE")
	)
	(segment
		(start 249.997468 -83.106006)
		(end 242.157758 -90.945716)
		(width 0.11684)
		(layer "In6.Cu")
		(net "FPGA_DEBUG_SW_SPARE")
	)
	(segment
		(start 430.276 -37.556948)
		(end 422.8084 -37.556948)
		(width 0.11684)
		(layer "In6.Cu")
		(net "FPGA_DEBUG_SW_SPARE")
	)
	(segment
		(start 179.959 -138.032998)
		(end 179.959 -141.084554)
		(width 0.10668)
		(layer "F.Cu")
		(net "FPGA_DEBUG_LED_CTRL")
	)
	(segment
		(start 431.5714 -30.927548)
		(end 430.5554 -30.927548)
		(width 0.10668)
		(layer "F.Cu")
		(net "FPGA_DEBUG_LED_CTRL")
	)
	(via
		(at 166.185342 -106.489754)
		(size 0.508)
		(drill 0.254)
		(layers "F.Cu" "B.Cu")
		(net "FPGA_DEBUG_LED_CTRL")
	)
	(via
		(at 430.5554 -30.927548)
		(size 0.508)
		(drill 0.254)
		(layers "F.Cu" "B.Cu")
		(net "FPGA_DEBUG_LED_CTRL")
	)
	(via
		(at 144.760442 -124.644404)
		(size 0.508)
		(drill 0.254)
		(layers "F.Cu" "B.Cu")
		(net "FPGA_DEBUG_LED_CTRL")
	)
	(via
		(at 158.678372 -140.570712)
		(size 0.508)
		(drill 0.254)
		(layers "F.Cu" "B.Cu")
		(net "FPGA_DEBUG_LED_CTRL")
	)
	(via
		(at 179.959 -141.084554)
		(size 0.508)
		(drill 0.254)
		(layers "F.Cu" "B.Cu")
		(net "FPGA_DEBUG_LED_CTRL")
	)
	(segment
		(start 430.5554 -30.533594)
		(end 430.187354 -30.165548)
		(width 0.10668)
		(layer "B.Cu")
		(net "FPGA_DEBUG_LED_CTRL")
	)
	(segment
		(start 430.187354 -30.165548)
		(end 429.387 -30.165548)
		(width 0.10668)
		(layer "B.Cu")
		(net "FPGA_DEBUG_LED_CTRL")
	)
	(segment
		(start 430.5554 -30.927548)
		(end 430.5554 -30.533594)
		(width 0.10668)
		(layer "B.Cu")
		(net "FPGA_DEBUG_LED_CTRL")
	)
	(segment
		(start 147.37461 -116.036852)
		(end 141.859762 -116.036852)
		(width 0.11684)
		(layer "In2.Cu")
		(net "FPGA_DEBUG_LED_CTRL")
	)
	(segment
		(start 160.708848 -112.857534)
		(end 157.220666 -112.857534)
		(width 0.11684)
		(layer "In2.Cu")
		(net "FPGA_DEBUG_LED_CTRL")
	)
	(segment
		(start 158.816294 -140.708634)
		(end 158.678372 -140.570712)
		(width 0.11684)
		(layer "In2.Cu")
		(net "FPGA_DEBUG_LED_CTRL")
	)
	(segment
		(start 138.256772 -119.639842)
		(end 138.256772 -120.722136)
		(width 0.11684)
		(layer "In2.Cu")
		(net "FPGA_DEBUG_LED_CTRL")
	)
	(segment
		(start 157.220666 -112.857534)
		(end 155.947618 -114.130582)
		(width 0.11684)
		(layer "In2.Cu")
		(net "FPGA_DEBUG_LED_CTRL")
	)
	(segment
		(start 179.959 -141.084554)
		(end 179.58308 -140.708634)
		(width 0.11684)
		(layer "In2.Cu")
		(net "FPGA_DEBUG_LED_CTRL")
	)
	(segment
		(start 138.256772 -120.722136)
		(end 142.17904 -124.644404)
		(width 0.11684)
		(layer "In2.Cu")
		(net "FPGA_DEBUG_LED_CTRL")
	)
	(segment
		(start 165.209982 -107.465114)
		(end 165.209982 -109.323886)
		(width 0.11684)
		(layer "In2.Cu")
		(net "FPGA_DEBUG_LED_CTRL")
	)
	(segment
		(start 165.209982 -109.323886)
		(end 162.751262 -111.782606)
		(width 0.11684)
		(layer "In2.Cu")
		(net "FPGA_DEBUG_LED_CTRL")
	)
	(segment
		(start 149.28088 -114.130582)
		(end 147.37461 -116.036852)
		(width 0.11684)
		(layer "In2.Cu")
		(net "FPGA_DEBUG_LED_CTRL")
	)
	(segment
		(start 162.751262 -111.782606)
		(end 161.783776 -111.782606)
		(width 0.11684)
		(layer "In2.Cu")
		(net "FPGA_DEBUG_LED_CTRL")
	)
	(segment
		(start 179.58308 -140.708634)
		(end 158.816294 -140.708634)
		(width 0.11684)
		(layer "In2.Cu")
		(net "FPGA_DEBUG_LED_CTRL")
	)
	(segment
		(start 142.17904 -124.644404)
		(end 144.760442 -124.644404)
		(width 0.11684)
		(layer "In2.Cu")
		(net "FPGA_DEBUG_LED_CTRL")
	)
	(segment
		(start 141.859762 -116.036852)
		(end 138.256772 -119.639842)
		(width 0.11684)
		(layer "In2.Cu")
		(net "FPGA_DEBUG_LED_CTRL")
	)
	(segment
		(start 166.185342 -106.489754)
		(end 165.209982 -107.465114)
		(width 0.11684)
		(layer "In2.Cu")
		(net "FPGA_DEBUG_LED_CTRL")
	)
	(segment
		(start 155.947618 -114.130582)
		(end 149.28088 -114.130582)
		(width 0.11684)
		(layer "In2.Cu")
		(net "FPGA_DEBUG_LED_CTRL")
	)
	(segment
		(start 161.783776 -111.782606)
		(end 160.708848 -112.857534)
		(width 0.11684)
		(layer "In2.Cu")
		(net "FPGA_DEBUG_LED_CTRL")
	)
	(segment
		(start 158.678372 -137.769854)
		(end 145.552922 -124.644404)
		(width 0.11684)
		(layer "In4.Cu")
		(net "FPGA_DEBUG_LED_CTRL")
	)
	(segment
		(start 145.552922 -124.644404)
		(end 144.760442 -124.644404)
		(width 0.11684)
		(layer "In4.Cu")
		(net "FPGA_DEBUG_LED_CTRL")
	)
	(segment
		(start 158.678372 -140.570712)
		(end 158.678372 -137.769854)
		(width 0.11684)
		(layer "In4.Cu")
		(net "FPGA_DEBUG_LED_CTRL")
	)
	(segment
		(start 164.634418 -99.77882)
		(end 164.634418 -105.37825)
		(width 0.11684)
		(layer "In6.Cu")
		(net "FPGA_DEBUG_LED_CTRL")
	)
	(segment
		(start 249.797316 -80.911446)
		(end 241.248438 -89.460324)
		(width 0.11684)
		(layer "In6.Cu")
		(net "FPGA_DEBUG_LED_CTRL")
	)
	(segment
		(start 166.23157 -98.23831)
		(end 165.929564 -98.540316)
		(width 0.11684)
		(layer "In6.Cu")
		(net "FPGA_DEBUG_LED_CTRL")
	)
	(segment
		(start 165.929564 -98.540316)
		(end 165.872922 -98.540316)
		(width 0.11684)
		(layer "In6.Cu")
		(net "FPGA_DEBUG_LED_CTRL")
	)
	(segment
		(start 270.10487 -70.71995)
		(end 259.913374 -80.911446)
		(width 0.11684)
		(layer "In6.Cu")
		(net "FPGA_DEBUG_LED_CTRL")
	)
	(segment
		(start 165.872922 -98.540316)
		(end 164.634418 -99.77882)
		(width 0.11684)
		(layer "In6.Cu")
		(net "FPGA_DEBUG_LED_CTRL")
	)
	(segment
		(start 194.058286 -84.253578)
		(end 192.901316 -85.410548)
		(width 0.11684)
		(layer "In6.Cu")
		(net "FPGA_DEBUG_LED_CTRL")
	)
	(segment
		(start 304.441606 -51.63185)
		(end 291.132006 -51.63185)
		(width 0.11684)
		(layer "In6.Cu")
		(net "FPGA_DEBUG_LED_CTRL")
	)
	(segment
		(start 211.935822 -89.460324)
		(end 210.876896 -88.401398)
		(width 0.11684)
		(layer "In6.Cu")
		(net "FPGA_DEBUG_LED_CTRL")
	)
	(segment
		(start 402.778468 -29.116528)
		(end 379.635258 -52.259738)
		(width 0.11684)
		(layer "In6.Cu")
		(net "FPGA_DEBUG_LED_CTRL")
	)
	(segment
		(start 175.293274 -87.559388)
		(end 175.293274 -88.727534)
		(width 0.11684)
		(layer "In6.Cu")
		(net "FPGA_DEBUG_LED_CTRL")
	)
	(segment
		(start 168.05021 -96.254316)
		(end 167.157654 -96.254316)
		(width 0.11684)
		(layer "In6.Cu")
		(net "FPGA_DEBUG_LED_CTRL")
	)
	(segment
		(start 241.248438 -89.460324)
		(end 211.935822 -89.460324)
		(width 0.11684)
		(layer "In6.Cu")
		(net "FPGA_DEBUG_LED_CTRL")
	)
	(segment
		(start 331.420724 -52.259738)
		(end 331.024484 -51.863498)
		(width 0.11684)
		(layer "In6.Cu")
		(net "FPGA_DEBUG_LED_CTRL")
	)
	(segment
		(start 167.157654 -96.254316)
		(end 166.815008 -96.596962)
		(width 0.11684)
		(layer "In6.Cu")
		(net "FPGA_DEBUG_LED_CTRL")
	)
	(segment
		(start 165.745922 -106.489754)
		(end 166.185342 -106.489754)
		(width 0.11684)
		(layer "In6.Cu")
		(net "FPGA_DEBUG_LED_CTRL")
	)
	(segment
		(start 428.74438 -29.116528)
		(end 402.778468 -29.116528)
		(width 0.11684)
		(layer "In6.Cu")
		(net "FPGA_DEBUG_LED_CTRL")
	)
	(segment
		(start 166.815008 -97.59823)
		(end 166.23157 -98.181668)
		(width 0.11684)
		(layer "In6.Cu")
		(net "FPGA_DEBUG_LED_CTRL")
	)
	(segment
		(start 175.293274 -88.727534)
		(end 172.578268 -91.44254)
		(width 0.11684)
		(layer "In6.Cu")
		(net "FPGA_DEBUG_LED_CTRL")
	)
	(segment
		(start 168.976802 -95.327724)
		(end 168.05021 -96.254316)
		(width 0.11684)
		(layer "In6.Cu")
		(net "FPGA_DEBUG_LED_CTRL")
	)
	(segment
		(start 166.23157 -98.181668)
		(end 166.23157 -98.23831)
		(width 0.11684)
		(layer "In6.Cu")
		(net "FPGA_DEBUG_LED_CTRL")
	)
	(segment
		(start 278.191214 -64.572642)
		(end 278.191214 -67.59067)
		(width 0.11684)
		(layer "In6.Cu")
		(net "FPGA_DEBUG_LED_CTRL")
	)
	(segment
		(start 305.18227 -52.372514)
		(end 304.441606 -51.63185)
		(width 0.11684)
		(layer "In6.Cu")
		(net "FPGA_DEBUG_LED_CTRL")
	)
	(segment
		(start 164.634418 -105.37825)
		(end 165.745922 -106.489754)
		(width 0.11684)
		(layer "In6.Cu")
		(net "FPGA_DEBUG_LED_CTRL")
	)
	(segment
		(start 430.5554 -30.927548)
		(end 428.74438 -29.116528)
		(width 0.11684)
		(layer "In6.Cu")
		(net "FPGA_DEBUG_LED_CTRL")
	)
	(segment
		(start 172.043852 -91.961462)
		(end 172.043852 -91.97721)
		(width 0.11684)
		(layer "In6.Cu")
		(net "FPGA_DEBUG_LED_CTRL")
	)
	(segment
		(start 204.647038 -86.75497)
		(end 204.647038 -86.68258)
		(width 0.11684)
		(layer "In6.Cu")
		(net "FPGA_DEBUG_LED_CTRL")
	)
	(segment
		(start 202.891898 -84.92744)
		(end 197.389496 -84.92744)
		(width 0.11684)
		(layer "In6.Cu")
		(net "FPGA_DEBUG_LED_CTRL")
	)
	(segment
		(start 172.562774 -91.44254)
		(end 172.043852 -91.961462)
		(width 0.11684)
		(layer "In6.Cu")
		(net "FPGA_DEBUG_LED_CTRL")
	)
	(segment
		(start 379.635258 -52.259738)
		(end 331.420724 -52.259738)
		(width 0.11684)
		(layer "In6.Cu")
		(net "FPGA_DEBUG_LED_CTRL")
	)
	(segment
		(start 278.191214 -67.59067)
		(end 275.061934 -70.71995)
		(width 0.11684)
		(layer "In6.Cu")
		(net "FPGA_DEBUG_LED_CTRL")
	)
	(segment
		(start 177.442114 -85.410548)
		(end 175.293274 -87.559388)
		(width 0.11684)
		(layer "In6.Cu")
		(net "FPGA_DEBUG_LED_CTRL")
	)
	(segment
		(start 259.913374 -80.911446)
		(end 249.797316 -80.911446)
		(width 0.11684)
		(layer "In6.Cu")
		(net "FPGA_DEBUG_LED_CTRL")
	)
	(segment
		(start 210.876896 -88.401398)
		(end 206.293466 -88.401398)
		(width 0.11684)
		(layer "In6.Cu")
		(net "FPGA_DEBUG_LED_CTRL")
	)
	(segment
		(start 172.578268 -91.44254)
		(end 172.562774 -91.44254)
		(width 0.11684)
		(layer "In6.Cu")
		(net "FPGA_DEBUG_LED_CTRL")
	)
	(segment
		(start 309.72379 -51.863498)
		(end 309.214774 -52.372514)
		(width 0.11684)
		(layer "In6.Cu")
		(net "FPGA_DEBUG_LED_CTRL")
	)
	(segment
		(start 168.976802 -95.04426)
		(end 168.976802 -95.327724)
		(width 0.11684)
		(layer "In6.Cu")
		(net "FPGA_DEBUG_LED_CTRL")
	)
	(segment
		(start 204.647038 -86.68258)
		(end 202.891898 -84.92744)
		(width 0.11684)
		(layer "In6.Cu")
		(net "FPGA_DEBUG_LED_CTRL")
	)
	(segment
		(start 166.815008 -96.596962)
		(end 166.815008 -97.59823)
		(width 0.11684)
		(layer "In6.Cu")
		(net "FPGA_DEBUG_LED_CTRL")
	)
	(segment
		(start 172.043852 -91.97721)
		(end 168.976802 -95.04426)
		(width 0.11684)
		(layer "In6.Cu")
		(net "FPGA_DEBUG_LED_CTRL")
	)
	(segment
		(start 192.901316 -85.410548)
		(end 177.442114 -85.410548)
		(width 0.11684)
		(layer "In6.Cu")
		(net "FPGA_DEBUG_LED_CTRL")
	)
	(segment
		(start 309.214774 -52.372514)
		(end 305.18227 -52.372514)
		(width 0.11684)
		(layer "In6.Cu")
		(net "FPGA_DEBUG_LED_CTRL")
	)
	(segment
		(start 196.715634 -84.253578)
		(end 194.058286 -84.253578)
		(width 0.11684)
		(layer "In6.Cu")
		(net "FPGA_DEBUG_LED_CTRL")
	)
	(segment
		(start 275.061934 -70.71995)
		(end 270.10487 -70.71995)
		(width 0.11684)
		(layer "In6.Cu")
		(net "FPGA_DEBUG_LED_CTRL")
	)
	(segment
		(start 331.024484 -51.863498)
		(end 309.72379 -51.863498)
		(width 0.11684)
		(layer "In6.Cu")
		(net "FPGA_DEBUG_LED_CTRL")
	)
	(segment
		(start 206.293466 -88.401398)
		(end 204.647038 -86.75497)
		(width 0.11684)
		(layer "In6.Cu")
		(net "FPGA_DEBUG_LED_CTRL")
	)
	(segment
		(start 197.389496 -84.92744)
		(end 196.715634 -84.253578)
		(width 0.11684)
		(layer "In6.Cu")
		(net "FPGA_DEBUG_LED_CTRL")
	)
	(segment
		(start 291.132006 -51.63185)
		(end 278.191214 -64.572642)
		(width 0.11684)
		(layer "In6.Cu")
		(net "FPGA_DEBUG_LED_CTRL")
	)
	(segment
		(start 220.006672 -95.192596)
		(end 219.263468 -94.449392)
		(width 0.10668)
		(layer "F.Cu")
		(net "FM_SMM_CRASHDUMP")
	)
	(segment
		(start 200.227184 -89.918286)
		(end 200.032874 -90.112596)
		(width 0.10668)
		(layer "F.Cu")
		(net "FM_SMM_CRASHDUMP")
	)
	(segment
		(start 188.701934 -89.546684)
		(end 179.720494 -89.546684)
		(width 0.10668)
		(layer "F.Cu")
		(net "FM_SMM_CRASHDUMP")
	)
	(segment
		(start 202.697334 -90.112596)
		(end 202.503024 -89.918286)
		(width 0.10668)
		(layer "F.Cu")
		(net "FM_SMM_CRASHDUMP")
	)
	(segment
		(start 200.032874 -90.112596)
		(end 189.267846 -90.112596)
		(width 0.10668)
		(layer "F.Cu")
		(net "FM_SMM_CRASHDUMP")
	)
	(segment
		(start 358.137968 -293.260018)
		(end 357.671116 -293.525956)
		(width 0.10668)
		(layer "F.Cu")
		(net "FM_SMM_CRASHDUMP")
	)
	(segment
		(start 202.503024 -89.918286)
		(end 200.227184 -89.918286)
		(width 0.10668)
		(layer "F.Cu")
		(net "FM_SMM_CRASHDUMP")
	)
	(segment
		(start 206.397606 -90.112596)
		(end 202.697334 -90.112596)
		(width 0.10668)
		(layer "F.Cu")
		(net "FM_SMM_CRASHDUMP")
	)
	(segment
		(start 178.689 -99.894898)
		(end 178.689 -99.278948)
		(width 0.10668)
		(layer "F.Cu")
		(net "FM_SMM_CRASHDUMP")
	)
	(segment
		(start 189.267846 -90.112596)
		(end 188.701934 -89.546684)
		(width 0.10668)
		(layer "F.Cu")
		(net "FM_SMM_CRASHDUMP")
	)
	(segment
		(start 219.263468 -94.449392)
		(end 210.734402 -94.449392)
		(width 0.10668)
		(layer "F.Cu")
		(net "FM_SMM_CRASHDUMP")
	)
	(segment
		(start 210.734402 -94.449392)
		(end 206.397606 -90.112596)
		(width 0.10668)
		(layer "F.Cu")
		(net "FM_SMM_CRASHDUMP")
	)
	(segment
		(start 179.720494 -89.546684)
		(end 177.752502 -87.578692)
		(width 0.10668)
		(layer "F.Cu")
		(net "FM_SMM_CRASHDUMP")
	)
	(via
		(at 233.500676 -95.123762)
		(size 0.508)
		(drill 0.254)
		(layers "F.Cu" "B.Cu")
		(net "FM_SMM_CRASHDUMP")
	)
	(via
		(at 178.689 -99.278948)
		(size 0.508)
		(drill 0.254)
		(layers "F.Cu" "B.Cu")
		(net "FM_SMM_CRASHDUMP")
	)
	(via
		(at 357.671116 -293.525956)
		(size 0.4064)
		(drill 0.2032)
		(layers "F.Cu" "B.Cu")
		(net "FM_SMM_CRASHDUMP")
	)
	(via
		(at 359.737406 -302.405796)
		(size 0.6604)
		(drill 0.3302)
		(layers "F.Cu" "B.Cu")
		(net "FM_SMM_CRASHDUMP")
	)
	(via
		(at 233.065828 -139.589256)
		(size 0.508)
		(drill 0.254)
		(layers "F.Cu" "B.Cu")
		(net "FM_SMM_CRASHDUMP")
	)
	(via
		(at 177.752502 -87.578692)
		(size 0.508)
		(drill 0.254)
		(layers "F.Cu" "B.Cu")
		(net "FM_SMM_CRASHDUMP")
	)
	(via
		(at 408.518614 -333.570326)
		(size 0.508)
		(drill 0.254)
		(layers "F.Cu" "B.Cu")
		(net "FM_SMM_CRASHDUMP")
	)
	(via
		(at 220.006672 -95.192596)
		(size 0.508)
		(drill 0.254)
		(layers "F.Cu" "B.Cu")
		(net "FM_SMM_CRASHDUMP")
	)
	(segment
		(start 404.068026 -335.41843)
		(end 405.91613 -333.570326)
		(width 0.10668)
		(layer "B.Cu")
		(net "FM_SMM_CRASHDUMP")
	)
	(segment
		(start 390.32688 -335.41843)
		(end 404.068026 -335.41843)
		(width 0.10668)
		(layer "B.Cu")
		(net "FM_SMM_CRASHDUMP")
	)
	(segment
		(start 406.298908 -329.942952)
		(end 406.298908 -330.288392)
		(width 0.10668)
		(layer "B.Cu")
		(net "FM_SMM_CRASHDUMP")
	)
	(segment
		(start 359.200958 -294.802814)
		(end 359.200958 -301.869348)
		(width 0.10668)
		(layer "B.Cu")
		(net "FM_SMM_CRASHDUMP")
	)
	(segment
		(start 359.737406 -302.405796)
		(end 360.056176 -302.724566)
		(width 0.10668)
		(layer "B.Cu")
		(net "FM_SMM_CRASHDUMP")
	)
	(segment
		(start 406.298908 -330.288392)
		(end 406.423622 -330.413106)
		(width 0.10668)
		(layer "B.Cu")
		(net "FM_SMM_CRASHDUMP")
	)
	(segment
		(start 406.423622 -330.413106)
		(end 407.724102 -330.413106)
		(width 0.10668)
		(layer "B.Cu")
		(net "FM_SMM_CRASHDUMP")
	)
	(segment
		(start 407.724102 -330.413106)
		(end 407.878026 -330.56703)
		(width 0.10668)
		(layer "B.Cu")
		(net "FM_SMM_CRASHDUMP")
	)
	(segment
		(start 407.878026 -331.3049)
		(end 408.691588 -332.118462)
		(width 0.10668)
		(layer "B.Cu")
		(net "FM_SMM_CRASHDUMP")
	)
	(segment
		(start 370.021358 -313.300872)
		(end 370.021358 -315.112908)
		(width 0.10668)
		(layer "B.Cu")
		(net "FM_SMM_CRASHDUMP")
	)
	(segment
		(start 360.056176 -302.724566)
		(end 360.056176 -303.33569)
		(width 0.10668)
		(layer "B.Cu")
		(net "FM_SMM_CRASHDUMP")
	)
	(segment
		(start 405.91613 -333.570326)
		(end 408.518614 -333.570326)
		(width 0.10668)
		(layer "B.Cu")
		(net "FM_SMM_CRASHDUMP")
	)
	(segment
		(start 408.691588 -332.118462)
		(end 408.716734 -332.118462)
		(width 0.10668)
		(layer "B.Cu")
		(net "FM_SMM_CRASHDUMP")
	)
	(segment
		(start 408.518614 -333.570326)
		(end 408.716734 -333.372206)
		(width 0.10668)
		(layer "B.Cu")
		(net "FM_SMM_CRASHDUMP")
	)
	(segment
		(start 408.716734 -333.372206)
		(end 408.716734 -332.118462)
		(width 0.10668)
		(layer "B.Cu")
		(net "FM_SMM_CRASHDUMP")
	)
	(segment
		(start 360.056176 -303.33569)
		(end 370.021358 -313.300872)
		(width 0.10668)
		(layer "B.Cu")
		(net "FM_SMM_CRASHDUMP")
	)
	(segment
		(start 357.9241 -293.525956)
		(end 359.200958 -294.802814)
		(width 0.10668)
		(layer "B.Cu")
		(net "FM_SMM_CRASHDUMP")
	)
	(segment
		(start 357.671116 -293.525956)
		(end 357.9241 -293.525956)
		(width 0.10668)
		(layer "B.Cu")
		(net "FM_SMM_CRASHDUMP")
	)
	(segment
		(start 370.021358 -315.112908)
		(end 390.32688 -335.41843)
		(width 0.10668)
		(layer "B.Cu")
		(net "FM_SMM_CRASHDUMP")
	)
	(segment
		(start 359.200958 -301.869348)
		(end 359.737406 -302.405796)
		(width 0.10668)
		(layer "B.Cu")
		(net "FM_SMM_CRASHDUMP")
	)
	(segment
		(start 407.878026 -330.56703)
		(end 407.878026 -331.3049)
		(width 0.10668)
		(layer "B.Cu")
		(net "FM_SMM_CRASHDUMP")
	)
	(segment
		(start 232.689146 -139.212574)
		(end 232.689146 -95.935292)
		(width 0.11684)
		(layer "In4.Cu")
		(net "FM_SMM_CRASHDUMP")
	)
	(segment
		(start 232.689146 -95.935292)
		(end 233.500676 -95.123762)
		(width 0.11684)
		(layer "In4.Cu")
		(net "FM_SMM_CRASHDUMP")
	)
	(segment
		(start 233.065828 -139.589256)
		(end 232.689146 -139.212574)
		(width 0.11684)
		(layer "In4.Cu")
		(net "FM_SMM_CRASHDUMP")
	)
	(segment
		(start 413.701992 -328.386948)
		(end 408.518614 -333.570326)
		(width 0.11684)
		(layer "In6.Cu")
		(net "FM_SMM_CRASHDUMP")
	)
	(segment
		(start 348.59341 -130.693668)
		(end 359.018332 -130.693668)
		(width 0.11684)
		(layer "In6.Cu")
		(net "FM_SMM_CRASHDUMP")
	)
	(segment
		(start 451.422262 -176.719738)
		(end 462.499456 -187.796932)
		(width 0.11684)
		(layer "In6.Cu")
		(net "FM_SMM_CRASHDUMP")
	)
	(segment
		(start 433.265326 -146.520662)
		(end 433.265326 -153.669238)
		(width 0.11684)
		(layer "In6.Cu")
		(net "FM_SMM_CRASHDUMP")
	)
	(segment
		(start 244.794786 -144.572736)
		(end 251.136658 -150.914608)
		(width 0.11684)
		(layer "In6.Cu")
		(net "FM_SMM_CRASHDUMP")
	)
	(segment
		(start 233.482388 -140.005816)
		(end 240.0935 -140.005816)
		(width 0.11684)
		(layer "In6.Cu")
		(net "FM_SMM_CRASHDUMP")
	)
	(segment
		(start 462.499456 -187.796932)
		(end 462.499456 -320.896742)
		(width 0.11684)
		(layer "In6.Cu")
		(net "FM_SMM_CRASHDUMP")
	)
	(segment
		(start 455.00925 -328.386948)
		(end 413.701992 -328.386948)
		(width 0.11684)
		(layer "In6.Cu")
		(net "FM_SMM_CRASHDUMP")
	)
	(segment
		(start 303.509934 -128.834642)
		(end 319.316862 -128.834642)
		(width 0.11684)
		(layer "In6.Cu")
		(net "FM_SMM_CRASHDUMP")
	)
	(segment
		(start 343.711022 -125.81128)
		(end 348.59341 -130.693668)
		(width 0.11684)
		(layer "In6.Cu")
		(net "FM_SMM_CRASHDUMP")
	)
	(segment
		(start 272.622518 -141.130274)
		(end 291.214302 -141.130274)
		(width 0.11684)
		(layer "In6.Cu")
		(net "FM_SMM_CRASHDUMP")
	)
	(segment
		(start 240.0935 -140.005816)
		(end 244.66042 -144.572736)
		(width 0.11684)
		(layer "In6.Cu")
		(net "FM_SMM_CRASHDUMP")
	)
	(segment
		(start 291.214302 -141.130274)
		(end 303.509934 -128.834642)
		(width 0.11684)
		(layer "In6.Cu")
		(net "FM_SMM_CRASHDUMP")
	)
	(segment
		(start 262.838184 -150.914608)
		(end 272.622518 -141.130274)
		(width 0.11684)
		(layer "In6.Cu")
		(net "FM_SMM_CRASHDUMP")
	)
	(segment
		(start 451.422262 -169.658538)
		(end 451.422262 -176.719738)
		(width 0.11684)
		(layer "In6.Cu")
		(net "FM_SMM_CRASHDUMP")
	)
	(segment
		(start 462.499456 -320.896742)
		(end 455.00925 -328.386948)
		(width 0.11684)
		(layer "In6.Cu")
		(net "FM_SMM_CRASHDUMP")
	)
	(segment
		(start 244.66042 -144.572736)
		(end 244.794786 -144.572736)
		(width 0.11684)
		(layer "In6.Cu")
		(net "FM_SMM_CRASHDUMP")
	)
	(segment
		(start 439.746136 -160.150048)
		(end 441.913772 -160.150048)
		(width 0.11684)
		(layer "In6.Cu")
		(net "FM_SMM_CRASHDUMP")
	)
	(segment
		(start 359.018332 -130.693668)
		(end 360.25074 -129.46126)
		(width 0.11684)
		(layer "In6.Cu")
		(net "FM_SMM_CRASHDUMP")
	)
	(segment
		(start 233.065828 -139.589256)
		(end 233.482388 -140.005816)
		(width 0.11684)
		(layer "In6.Cu")
		(net "FM_SMM_CRASHDUMP")
	)
	(segment
		(start 416.205924 -129.46126)
		(end 433.265326 -146.520662)
		(width 0.11684)
		(layer "In6.Cu")
		(net "FM_SMM_CRASHDUMP")
	)
	(segment
		(start 251.136658 -150.914608)
		(end 262.838184 -150.914608)
		(width 0.11684)
		(layer "In6.Cu")
		(net "FM_SMM_CRASHDUMP")
	)
	(segment
		(start 360.25074 -129.46126)
		(end 416.205924 -129.46126)
		(width 0.11684)
		(layer "In6.Cu")
		(net "FM_SMM_CRASHDUMP")
	)
	(segment
		(start 319.316862 -128.834642)
		(end 322.340224 -125.81128)
		(width 0.11684)
		(layer "In6.Cu")
		(net "FM_SMM_CRASHDUMP")
	)
	(segment
		(start 433.265326 -153.669238)
		(end 439.746136 -160.150048)
		(width 0.11684)
		(layer "In6.Cu")
		(net "FM_SMM_CRASHDUMP")
	)
	(segment
		(start 322.340224 -125.81128)
		(end 343.711022 -125.81128)
		(width 0.11684)
		(layer "In6.Cu")
		(net "FM_SMM_CRASHDUMP")
	)
	(segment
		(start 441.913772 -160.150048)
		(end 451.422262 -169.658538)
		(width 0.11684)
		(layer "In6.Cu")
		(net "FM_SMM_CRASHDUMP")
	)
	(segment
		(start 178.326288 -96.27743)
		(end 178.164744 -96.115886)
		(width 0.11684)
		(layer "In11.Cu")
		(net "FM_SMM_CRASHDUMP")
	)
	(segment
		(start 178.164744 -94.800166)
		(end 177.752502 -94.387924)
		(width 0.11684)
		(layer "In11.Cu")
		(net "FM_SMM_CRASHDUMP")
	)
	(segment
		(start 178.326288 -97.812352)
		(end 178.326288 -96.27743)
		(width 0.11684)
		(layer "In11.Cu")
		(net "FM_SMM_CRASHDUMP")
	)
	(segment
		(start 178.247548 -98.837496)
		(end 178.247548 -97.891092)
		(width 0.11684)
		(layer "In11.Cu")
		(net "FM_SMM_CRASHDUMP")
	)
	(segment
		(start 178.689 -99.278948)
		(end 178.247548 -98.837496)
		(width 0.11684)
		(layer "In11.Cu")
		(net "FM_SMM_CRASHDUMP")
	)
	(segment
		(start 177.752502 -94.387924)
		(end 177.752502 -87.578692)
		(width 0.11684)
		(layer "In11.Cu")
		(net "FM_SMM_CRASHDUMP")
	)
	(segment
		(start 178.164744 -96.115886)
		(end 178.164744 -94.800166)
		(width 0.11684)
		(layer "In11.Cu")
		(net "FM_SMM_CRASHDUMP")
	)
	(segment
		(start 178.247548 -97.891092)
		(end 178.326288 -97.812352)
		(width 0.11684)
		(layer "In11.Cu")
		(net "FM_SMM_CRASHDUMP")
	)
	(segment
		(start 220.075506 -95.123762)
		(end 220.006672 -95.192596)
		(width 0.11684)
		(layer "In15.Cu")
		(net "FM_SMM_CRASHDUMP")
	)
	(segment
		(start 233.500676 -95.123762)
		(end 220.075506 -95.123762)
		(width 0.11684)
		(layer "In15.Cu")
		(net "FM_SMM_CRASHDUMP")
	)
	(segment
		(start 234.685586 -69.960236)
		(end 234.967272 -69.67855)
		(width 0.10668)
		(layer "F.Cu")
		(net "FM_LED_ACTIVE_E1S_0_R_BUF")
	)
	(segment
		(start 234.967272 -69.67855)
		(end 234.967272 -69.17436)
		(width 0.10668)
		(layer "F.Cu")
		(net "FM_LED_ACTIVE_E1S_0_R_BUF")
	)
	(segment
		(start 236.562392 -69.17436)
		(end 234.967272 -69.17436)
		(width 0.10668)
		(layer "F.Cu")
		(net "FM_LED_ACTIVE_E1S_0_R_BUF")
	)
	(segment
		(start 233.748072 -69.960236)
		(end 234.685586 -69.960236)
		(width 0.10668)
		(layer "F.Cu")
		(net "FM_LED_ACTIVE_E1S_0_R_BUF")
	)
	(via
		(at 234.967272 -69.17436)
		(size 0.762)
		(drill 0.381)
		(layers "F.Cu" "B.Cu")
		(net "FM_LED_ACTIVE_E1S_0_R_BUF")
	)
	(segment
		(start 238.452152 -68.524374)
		(end 240.096802 -68.524374)
		(width 0.10668)
		(layer "F.Cu")
		(net "FM_LED_ACTIVE_E1S_0_R")
	)
	(segment
		(start 240.096802 -68.524374)
		(end 240.096802 -69.743574)
		(width 0.10668)
		(layer "F.Cu")
		(net "FM_LED_ACTIVE_E1S_0_R")
	)
	(segment
		(start 240.096802 -69.743574)
		(end 241.112802 -69.743574)
		(width 0.10668)
		(layer "F.Cu")
		(net "FM_LED_ACTIVE_E1S_0_R")
	)
	(via
		(at 240.096802 -68.524374)
		(size 0.762)
		(drill 0.381)
		(layers "F.Cu" "B.Cu")
		(net "FM_LED_ACTIVE_E1S_0_R")
	)
	(segment
		(start 233.748072 -69.160136)
		(end 232.732072 -69.160136)
		(width 0.10668)
		(layer "F.Cu")
		(net "FM_LED_ACTIVE_E1S_0_BUF")
	)
	(segment
		(start 230.805228 -47.964852)
		(end 232.000044 -47.964852)
		(width 0.10668)
		(layer "F.Cu")
		(net "FM_LED_ACTIVE_E1S_0_BUF")
	)
	(segment
		(start 232.732072 -69.160136)
		(end 232.732072 -68.544186)
		(width 0.10668)
		(layer "F.Cu")
		(net "FM_LED_ACTIVE_E1S_0_BUF")
	)
	(segment
		(start 230.789734 -47.980346)
		(end 230.805228 -47.964852)
		(width 0.10668)
		(layer "F.Cu")
		(net "FM_LED_ACTIVE_E1S_0_BUF")
	)
	(via
		(at 222.29318 -47.018702)
		(size 0.508)
		(drill 0.254)
		(layers "F.Cu" "B.Cu")
		(net "FM_LED_ACTIVE_E1S_0_BUF")
	)
	(via
		(at 232.732072 -68.544186)
		(size 0.508)
		(drill 0.254)
		(layers "F.Cu" "B.Cu")
		(net "FM_LED_ACTIVE_E1S_0_BUF")
	)
	(via
		(at 230.789734 -47.980346)
		(size 0.508)
		(drill 0.254)
		(layers "F.Cu" "B.Cu")
		(net "FM_LED_ACTIVE_E1S_0_BUF")
	)
	(segment
		(start 230.789734 -47.980346)
		(end 224.586292 -47.980346)
		(width 0.10668)
		(layer "B.Cu")
		(net "FM_LED_ACTIVE_E1S_0_BUF")
	)
	(segment
		(start 224.586292 -47.980346)
		(end 223.624648 -47.018702)
		(width 0.10668)
		(layer "B.Cu")
		(net "FM_LED_ACTIVE_E1S_0_BUF")
	)
	(segment
		(start 223.624648 -47.018702)
		(end 222.29318 -47.018702)
		(width 0.10668)
		(layer "B.Cu")
		(net "FM_LED_ACTIVE_E1S_0_BUF")
	)
	(segment
		(start 230.24592 -66.058034)
		(end 232.732072 -68.544186)
		(width 0.11684)
		(layer "In11.Cu")
		(net "FM_LED_ACTIVE_E1S_0_BUF")
	)
	(segment
		(start 230.24592 -48.52416)
		(end 230.24592 -66.058034)
		(width 0.11684)
		(layer "In11.Cu")
		(net "FM_LED_ACTIVE_E1S_0_BUF")
	)
	(segment
		(start 230.789734 -47.980346)
		(end 230.24592 -48.52416)
		(width 0.11684)
		(layer "In11.Cu")
		(net "FM_LED_ACTIVE_E1S_0_BUF")
	)
	(segment
		(start 241.112802 -70.543674)
		(end 241.112802 -71.132446)
		(width 0.10668)
		(layer "F.Cu")
		(net "FM_LED_ACTIVE_E1S_0")
	)
	(segment
		(start 180.32222 -113.85296)
		(end 179.93233 -113.46307)
		(width 0.10668)
		(layer "F.Cu")
		(net "FM_LED_ACTIVE_E1S_0")
	)
	(segment
		(start 241.112802 -71.132446)
		(end 241.091974 -71.153274)
		(width 0.10668)
		(layer "F.Cu")
		(net "FM_LED_ACTIVE_E1S_0")
	)
	(via
		(at 179.93233 -113.46307)
		(size 0.4572)
		(drill 0.254)
		(layers "F.Cu" "B.Cu")
		(net "FM_LED_ACTIVE_E1S_0")
	)
	(via
		(at 241.091974 -71.153274)
		(size 0.508)
		(drill 0.254)
		(layers "F.Cu" "B.Cu")
		(net "FM_LED_ACTIVE_E1S_0")
	)
	(via
		(at 243.357654 -116.292884)
		(size 0.508)
		(drill 0.254)
		(layers "F.Cu" "B.Cu")
		(net "FM_LED_ACTIVE_E1S_0")
	)
	(segment
		(start 240.9444 -75.307444)
		(end 244.456458 -78.819502)
		(width 0.11684)
		(layer "In11.Cu")
		(net "FM_LED_ACTIVE_E1S_0")
	)
	(segment
		(start 244.456458 -78.819502)
		(end 244.456458 -115.19408)
		(width 0.11684)
		(layer "In11.Cu")
		(net "FM_LED_ACTIVE_E1S_0")
	)
	(segment
		(start 240.9444 -71.300848)
		(end 240.9444 -75.307444)
		(width 0.11684)
		(layer "In11.Cu")
		(net "FM_LED_ACTIVE_E1S_0")
	)
	(segment
		(start 244.456458 -115.19408)
		(end 243.357654 -116.292884)
		(width 0.11684)
		(layer "In11.Cu")
		(net "FM_LED_ACTIVE_E1S_0")
	)
	(segment
		(start 241.091974 -71.153274)
		(end 240.9444 -71.300848)
		(width 0.11684)
		(layer "In11.Cu")
		(net "FM_LED_ACTIVE_E1S_0")
	)
	(segment
		(start 180.048154 -113.46307)
		(end 180.331872 -113.746788)
		(width 0.11684)
		(layer "In15.Cu")
		(net "FM_LED_ACTIVE_E1S_0")
	)
	(segment
		(start 206.347822 -111.562642)
		(end 206.871824 -112.086644)
		(width 0.11684)
		(layer "In15.Cu")
		(net "FM_LED_ACTIVE_E1S_0")
	)
	(segment
		(start 243.862098 -116.292884)
		(end 243.357654 -116.292884)
		(width 0.11684)
		(layer "In15.Cu")
		(net "FM_LED_ACTIVE_E1S_0")
	)
	(segment
		(start 244.241066 -115.913916)
		(end 243.862098 -116.292884)
		(width 0.11684)
		(layer "In15.Cu")
		(net "FM_LED_ACTIVE_E1S_0")
	)
	(segment
		(start 243.31168 -112.86871)
		(end 244.241066 -113.798096)
		(width 0.11684)
		(layer "In15.Cu")
		(net "FM_LED_ACTIVE_E1S_0")
	)
	(segment
		(start 194.990974 -114.810286)
		(end 195.5927 -114.20856)
		(width 0.11684)
		(layer "In15.Cu")
		(net "FM_LED_ACTIVE_E1S_0")
	)
	(segment
		(start 222.235014 -112.86871)
		(end 243.31168 -112.86871)
		(width 0.11684)
		(layer "In15.Cu")
		(net "FM_LED_ACTIVE_E1S_0")
	)
	(segment
		(start 202.715622 -112.086644)
		(end 203.239624 -111.562642)
		(width 0.11684)
		(layer "In15.Cu")
		(net "FM_LED_ACTIVE_E1S_0")
	)
	(segment
		(start 180.331872 -113.746788)
		(end 180.331872 -114.523012)
		(width 0.11684)
		(layer "In15.Cu")
		(net "FM_LED_ACTIVE_E1S_0")
	)
	(segment
		(start 244.241066 -113.798096)
		(end 244.241066 -115.913916)
		(width 0.11684)
		(layer "In15.Cu")
		(net "FM_LED_ACTIVE_E1S_0")
	)
	(segment
		(start 195.5927 -114.20856)
		(end 198.385176 -114.20856)
		(width 0.11684)
		(layer "In15.Cu")
		(net "FM_LED_ACTIVE_E1S_0")
	)
	(segment
		(start 200.298304 -113.105438)
		(end 201.317098 -112.086644)
		(width 0.11684)
		(layer "In15.Cu")
		(net "FM_LED_ACTIVE_E1S_0")
	)
	(segment
		(start 180.331872 -114.523012)
		(end 180.619146 -114.810286)
		(width 0.11684)
		(layer "In15.Cu")
		(net "FM_LED_ACTIVE_E1S_0")
	)
	(segment
		(start 179.93233 -113.46307)
		(end 180.048154 -113.46307)
		(width 0.11684)
		(layer "In15.Cu")
		(net "FM_LED_ACTIVE_E1S_0")
	)
	(segment
		(start 221.616524 -112.25022)
		(end 222.235014 -112.86871)
		(width 0.11684)
		(layer "In15.Cu")
		(net "FM_LED_ACTIVE_E1S_0")
	)
	(segment
		(start 203.239624 -111.562642)
		(end 206.347822 -111.562642)
		(width 0.11684)
		(layer "In15.Cu")
		(net "FM_LED_ACTIVE_E1S_0")
	)
	(segment
		(start 206.871824 -112.086644)
		(end 211.28355 -112.086644)
		(width 0.11684)
		(layer "In15.Cu")
		(net "FM_LED_ACTIVE_E1S_0")
	)
	(segment
		(start 199.488298 -113.105438)
		(end 200.298304 -113.105438)
		(width 0.11684)
		(layer "In15.Cu")
		(net "FM_LED_ACTIVE_E1S_0")
	)
	(segment
		(start 201.317098 -112.086644)
		(end 202.715622 -112.086644)
		(width 0.11684)
		(layer "In15.Cu")
		(net "FM_LED_ACTIVE_E1S_0")
	)
	(segment
		(start 211.28355 -112.086644)
		(end 211.447126 -112.25022)
		(width 0.11684)
		(layer "In15.Cu")
		(net "FM_LED_ACTIVE_E1S_0")
	)
	(segment
		(start 180.619146 -114.810286)
		(end 194.990974 -114.810286)
		(width 0.11684)
		(layer "In15.Cu")
		(net "FM_LED_ACTIVE_E1S_0")
	)
	(segment
		(start 198.385176 -114.20856)
		(end 199.488298 -113.105438)
		(width 0.11684)
		(layer "In15.Cu")
		(net "FM_LED_ACTIVE_E1S_0")
	)
	(segment
		(start 211.447126 -112.25022)
		(end 221.616524 -112.25022)
		(width 0.11684)
		(layer "In15.Cu")
		(net "FM_LED_ACTIVE_E1S_0")
	)
	(segment
		(start 208.494376 -112.662208)
		(end 207.293718 -112.662208)
		(width 0.10668)
		(layer "F.Cu")
		(net "FM_FPGA_DEBUG_SW_SPARE")
	)
	(segment
		(start 189.92215 -112.25276)
		(end 190.31204 -111.86287)
		(width 0.10668)
		(layer "F.Cu")
		(net "FM_FPGA_DEBUG_SW_SPARE")
	)
	(via
		(at 190.31204 -111.86287)
		(size 0.4572)
		(drill 0.254)
		(layers "F.Cu" "B.Cu")
		(net "FM_FPGA_DEBUG_SW_SPARE")
	)
	(via
		(at 207.293718 -112.662208)
		(size 0.508)
		(drill 0.254)
		(layers "F.Cu" "B.Cu")
		(net "FM_FPGA_DEBUG_SW_SPARE")
	)
	(segment
		(start 206.819246 -113.13668)
		(end 207.293718 -112.662208)
		(width 0.11684)
		(layer "In6.Cu")
		(net "FM_FPGA_DEBUG_SW_SPARE")
	)
	(segment
		(start 190.31204 -112.011714)
		(end 190.568072 -112.267746)
		(width 0.11684)
		(layer "In6.Cu")
		(net "FM_FPGA_DEBUG_SW_SPARE")
	)
	(segment
		(start 190.568072 -112.267746)
		(end 194.94119 -112.267746)
		(width 0.11684)
		(layer "In6.Cu")
		(net "FM_FPGA_DEBUG_SW_SPARE")
	)
	(segment
		(start 200.208642 -112.043718)
		(end 201.301604 -113.13668)
		(width 0.11684)
		(layer "In6.Cu")
		(net "FM_FPGA_DEBUG_SW_SPARE")
	)
	(segment
		(start 196.135244 -112.851438)
		(end 196.942964 -112.043718)
		(width 0.11684)
		(layer "In6.Cu")
		(net "FM_FPGA_DEBUG_SW_SPARE")
	)
	(segment
		(start 196.942964 -112.043718)
		(end 200.208642 -112.043718)
		(width 0.11684)
		(layer "In6.Cu")
		(net "FM_FPGA_DEBUG_SW_SPARE")
	)
	(segment
		(start 195.524882 -112.851438)
		(end 196.135244 -112.851438)
		(width 0.11684)
		(layer "In6.Cu")
		(net "FM_FPGA_DEBUG_SW_SPARE")
	)
	(segment
		(start 190.31204 -111.86287)
		(end 190.31204 -112.011714)
		(width 0.11684)
		(layer "In6.Cu")
		(net "FM_FPGA_DEBUG_SW_SPARE")
	)
	(segment
		(start 194.94119 -112.267746)
		(end 195.524882 -112.851438)
		(width 0.11684)
		(layer "In6.Cu")
		(net "FM_FPGA_DEBUG_SW_SPARE")
	)
	(segment
		(start 201.301604 -113.13668)
		(end 206.819246 -113.13668)
		(width 0.11684)
		(layer "In6.Cu")
		(net "FM_FPGA_DEBUG_SW_SPARE")
	)
	(segment
		(start 422.3766 -41.087548)
		(end 423.9514 -41.087548)
		(width 0.10668)
		(layer "F.Cu")
		(net "FM_FORCE_ALL_PWRON_ON")
	)
	(segment
		(start 421.1574 -41.087548)
		(end 422.3766 -41.087548)
		(width 0.10668)
		(layer "F.Cu")
		(net "FM_FORCE_ALL_PWRON_ON")
	)
	(via
		(at 422.3766 -41.087548)
		(size 0.762)
		(drill 0.381)
		(layers "F.Cu" "B.Cu")
		(net "FM_FORCE_ALL_PWRON_ON")
	)
	(segment
		(start 87.176102 -302.140874)
		(end 87.176102 -309.261002)
		(width 0.10668)
		(layer "F.Cu")
		(net "FM_BMC_TPM_PRES_N")
	)
	(segment
		(start 108.380784 -321.82689)
		(end 107.718098 -322.489576)
		(width 0.10668)
		(layer "F.Cu")
		(net "FM_BMC_TPM_PRES_N")
	)
	(segment
		(start 85.295232 -300.260004)
		(end 87.176102 -302.140874)
		(width 0.10668)
		(layer "F.Cu")
		(net "FM_BMC_TPM_PRES_N")
	)
	(segment
		(start 16.053054 -320.310256)
		(end 62.137544 -320.310256)
		(width 0.10668)
		(layer "F.Cu")
		(net "FM_BMC_TPM_PRES_N")
	)
	(segment
		(start 131.58978 -127.761238)
		(end 117.702076 -113.873534)
		(width 0.10668)
		(layer "F.Cu")
		(net "FM_BMC_TPM_PRES_N")
	)
	(segment
		(start 8.158226 -183.665368)
		(end 8.158226 -201.709528)
		(width 0.10668)
		(layer "F.Cu")
		(net "FM_BMC_TPM_PRES_N")
	)
	(segment
		(start 100.836476 -313.178952)
		(end 108.380784 -320.72326)
		(width 0.10668)
		(layer "F.Cu")
		(net "FM_BMC_TPM_PRES_N")
	)
	(segment
		(start 18.378424 -173.44517)
		(end 8.158226 -183.665368)
		(width 0.10668)
		(layer "F.Cu")
		(net "FM_BMC_TPM_PRES_N")
	)
	(segment
		(start 74.407014 -309.970424)
		(end 76.956666 -307.420772)
		(width 0.10668)
		(layer "F.Cu")
		(net "FM_BMC_TPM_PRES_N")
	)
	(segment
		(start 36.255706 -146.077178)
		(end 25.44318 -146.077178)
		(width 0.10668)
		(layer "F.Cu")
		(net "FM_BMC_TPM_PRES_N")
	)
	(segment
		(start 76.956666 -304.510694)
		(end 77.983334 -302.031908)
		(width 0.10668)
		(layer "F.Cu")
		(net "FM_BMC_TPM_PRES_N")
	)
	(segment
		(start 134.102094 -127.761238)
		(end 131.58978 -127.761238)
		(width 0.10668)
		(layer "F.Cu")
		(net "FM_BMC_TPM_PRES_N")
	)
	(segment
		(start 25.44318 -146.077178)
		(end 18.378424 -153.141934)
		(width 0.10668)
		(layer "F.Cu")
		(net "FM_BMC_TPM_PRES_N")
	)
	(segment
		(start 107.718098 -322.489576)
		(end 107.702096 -322.489576)
		(width 0.10668)
		(layer "F.Cu")
		(net "FM_BMC_TPM_PRES_N")
	)
	(segment
		(start 76.956666 -307.420772)
		(end 76.956666 -304.510694)
		(width 0.10668)
		(layer "F.Cu")
		(net "FM_BMC_TPM_PRES_N")
	)
	(segment
		(start 18.378424 -153.141934)
		(end 18.378424 -173.44517)
		(width 0.10668)
		(layer "F.Cu")
		(net "FM_BMC_TPM_PRES_N")
	)
	(segment
		(start 117.702076 -113.873534)
		(end 99.231958 -113.873534)
		(width 0.10668)
		(layer "F.Cu")
		(net "FM_BMC_TPM_PRES_N")
	)
	(segment
		(start 180.721 -99.894898)
		(end 180.721 -99.278948)
		(width 0.10668)
		(layer "F.Cu")
		(net "FM_BMC_TPM_PRES_N")
	)
	(segment
		(start 77.983334 -302.031908)
		(end 79.755238 -300.260004)
		(width 0.10668)
		(layer "F.Cu")
		(net "FM_BMC_TPM_PRES_N")
	)
	(segment
		(start 108.380784 -320.72326)
		(end 108.380784 -321.82689)
		(width 0.10668)
		(layer "F.Cu")
		(net "FM_BMC_TPM_PRES_N")
	)
	(segment
		(start 132.757926 -294.880284)
		(end 133.224778 -295.146222)
		(width 0.10668)
		(layer "F.Cu")
		(net "FM_BMC_TPM_PRES_N")
	)
	(segment
		(start 155.421584 -136.697212)
		(end 143.038068 -136.697212)
		(width 0.10668)
		(layer "F.Cu")
		(net "FM_BMC_TPM_PRES_N")
	)
	(segment
		(start 79.755238 -300.260004)
		(end 85.295232 -300.260004)
		(width 0.10668)
		(layer "F.Cu")
		(net "FM_BMC_TPM_PRES_N")
	)
	(segment
		(start 88.981026 -126.80188)
		(end 78.20279 -137.580116)
		(width 0.10668)
		(layer "F.Cu")
		(net "FM_BMC_TPM_PRES_N")
	)
	(segment
		(start 99.231958 -113.873534)
		(end 88.981026 -124.124466)
		(width 0.10668)
		(layer "F.Cu")
		(net "FM_BMC_TPM_PRES_N")
	)
	(segment
		(start 143.038068 -136.697212)
		(end 134.102094 -127.761238)
		(width 0.10668)
		(layer "F.Cu")
		(net "FM_BMC_TPM_PRES_N")
	)
	(segment
		(start 78.20279 -137.580116)
		(end 44.752768 -137.580116)
		(width 0.10668)
		(layer "F.Cu")
		(net "FM_BMC_TPM_PRES_N")
	)
	(segment
		(start 88.981026 -124.124466)
		(end 88.981026 -126.80188)
		(width 0.10668)
		(layer "F.Cu")
		(net "FM_BMC_TPM_PRES_N")
	)
	(segment
		(start 91.094052 -313.178952)
		(end 100.836476 -313.178952)
		(width 0.10668)
		(layer "F.Cu")
		(net "FM_BMC_TPM_PRES_N")
	)
	(segment
		(start 62.137544 -320.310256)
		(end 72.477376 -309.970424)
		(width 0.10668)
		(layer "F.Cu")
		(net "FM_BMC_TPM_PRES_N")
	)
	(segment
		(start 87.176102 -309.261002)
		(end 91.094052 -313.178952)
		(width 0.10668)
		(layer "F.Cu")
		(net "FM_BMC_TPM_PRES_N")
	)
	(segment
		(start 8.158226 -201.709528)
		(end 13.796772 -207.348074)
		(width 0.10668)
		(layer "F.Cu")
		(net "FM_BMC_TPM_PRES_N")
	)
	(segment
		(start 44.752768 -137.580116)
		(end 36.255706 -146.077178)
		(width 0.10668)
		(layer "F.Cu")
		(net "FM_BMC_TPM_PRES_N")
	)
	(segment
		(start 13.796772 -318.053974)
		(end 16.053054 -320.310256)
		(width 0.10668)
		(layer "F.Cu")
		(net "FM_BMC_TPM_PRES_N")
	)
	(segment
		(start 72.477376 -309.970424)
		(end 74.407014 -309.970424)
		(width 0.10668)
		(layer "F.Cu")
		(net "FM_BMC_TPM_PRES_N")
	)
	(segment
		(start 13.796772 -207.348074)
		(end 13.796772 -318.053974)
		(width 0.10668)
		(layer "F.Cu")
		(net "FM_BMC_TPM_PRES_N")
	)
	(via
		(at 155.421584 -136.697212)
		(size 0.508)
		(drill 0.254)
		(layers "F.Cu" "B.Cu")
		(net "FM_BMC_TPM_PRES_N")
	)
	(via
		(at 133.224778 -295.146222)
		(size 0.4064)
		(drill 0.2032)
		(layers "F.Cu" "B.Cu")
		(net "FM_BMC_TPM_PRES_N")
	)
	(via
		(at 141.90726 -311.441846)
		(size 0.508)
		(drill 0.254)
		(layers "F.Cu" "B.Cu")
		(net "FM_BMC_TPM_PRES_N")
	)
	(via
		(at 180.721 -99.278948)
		(size 0.508)
		(drill 0.254)
		(layers "F.Cu" "B.Cu")
		(net "FM_BMC_TPM_PRES_N")
	)
	(via
		(at 146.13763 -111.036354)
		(size 0.508)
		(drill 0.254)
		(layers "F.Cu" "B.Cu")
		(net "FM_BMC_TPM_PRES_N")
	)
	(via
		(at 107.702096 -322.489576)
		(size 0.508)
		(drill 0.254)
		(layers "F.Cu" "B.Cu")
		(net "FM_BMC_TPM_PRES_N")
	)
	(segment
		(start 143.321786 -317.039498)
		(end 142.119858 -317.039498)
		(width 0.10668)
		(layer "B.Cu")
		(net "FM_BMC_TPM_PRES_N")
	)
	(segment
		(start 143.44142 -316.465458)
		(end 143.44142 -316.919864)
		(width 0.10668)
		(layer "B.Cu")
		(net "FM_BMC_TPM_PRES_N")
	)
	(segment
		(start 141.56055 -316.48019)
		(end 141.56055 -311.788556)
		(width 0.10668)
		(layer "B.Cu")
		(net "FM_BMC_TPM_PRES_N")
	)
	(segment
		(start 142.119858 -317.039498)
		(end 141.56055 -316.48019)
		(width 0.10668)
		(layer "B.Cu")
		(net "FM_BMC_TPM_PRES_N")
	)
	(segment
		(start 141.56055 -311.788556)
		(end 141.90726 -311.441846)
		(width 0.10668)
		(layer "B.Cu")
		(net "FM_BMC_TPM_PRES_N")
	)
	(segment
		(start 143.44142 -316.919864)
		(end 143.321786 -317.039498)
		(width 0.10668)
		(layer "B.Cu")
		(net "FM_BMC_TPM_PRES_N")
	)
	(segment
		(start 144.532604 -316.47511)
		(end 143.451072 -316.47511)
		(width 0.10668)
		(layer "B.Cu")
		(net "FM_BMC_TPM_PRES_N")
	)
	(segment
		(start 143.451072 -316.47511)
		(end 143.44142 -316.465458)
		(width 0.10668)
		(layer "B.Cu")
		(net "FM_BMC_TPM_PRES_N")
	)
	(segment
		(start 146.13763 -109.82706)
		(end 149.168104 -106.796586)
		(width 0.11684)
		(layer "In2.Cu")
		(net "FM_BMC_TPM_PRES_N")
	)
	(segment
		(start 133.931914 -294.740076)
		(end 133.929882 -294.741346)
		(width 0.11684)
		(layer "In2.Cu")
		(net "FM_BMC_TPM_PRES_N")
	)
	(segment
		(start 136.78535 -293.951914)
		(end 136.74979 -293.93134)
		(width 0.11684)
		(layer "In2.Cu")
		(net "FM_BMC_TPM_PRES_N")
	)
	(segment
		(start 107.702096 -322.489576)
		(end 132.832348 -322.489576)
		(width 0.11684)
		(layer "In2.Cu")
		(net "FM_BMC_TPM_PRES_N")
	)
	(segment
		(start 146.13763 -111.036354)
		(end 146.13763 -109.82706)
		(width 0.11684)
		(layer "In2.Cu")
		(net "FM_BMC_TPM_PRES_N")
	)
	(segment
		(start 149.168104 -106.796586)
		(end 151.015192 -106.796586)
		(width 0.11684)
		(layer "In2.Cu")
		(net "FM_BMC_TPM_PRES_N")
	)
	(segment
		(start 137.416794 -295.010586)
		(end 137.304272 -294.790114)
		(width 0.11684)
		(layer "In2.Cu")
		(net "FM_BMC_TPM_PRES_N")
	)
	(segment
		(start 167.6273 -102.297992)
		(end 168.40327 -102.297992)
		(width 0.11684)
		(layer "In2.Cu")
		(net "FM_BMC_TPM_PRES_N")
	)
	(segment
		(start 141.90726 -311.441846)
		(end 137.416794 -306.95138)
		(width 0.11684)
		(layer "In2.Cu")
		(net "FM_BMC_TPM_PRES_N")
	)
	(segment
		(start 168.40327 -102.297992)
		(end 168.478708 -102.222554)
		(width 0.11684)
		(layer "In2.Cu")
		(net "FM_BMC_TPM_PRES_N")
	)
	(segment
		(start 166.162228 -103.763064)
		(end 167.6273 -102.297992)
		(width 0.11684)
		(layer "In2.Cu")
		(net "FM_BMC_TPM_PRES_N")
	)
	(segment
		(start 159.214312 -108.305346)
		(end 160.47466 -107.044998)
		(width 0.11684)
		(layer "In2.Cu")
		(net "FM_BMC_TPM_PRES_N")
	)
	(segment
		(start 151.852376 -107.63377)
		(end 154.12593 -107.63377)
		(width 0.11684)
		(layer "In2.Cu")
		(net "FM_BMC_TPM_PRES_N")
	)
	(segment
		(start 143.09979 -311.773062)
		(end 142.768574 -311.441846)
		(width 0.11684)
		(layer "In2.Cu")
		(net "FM_BMC_TPM_PRES_N")
	)
	(segment
		(start 151.015192 -106.796586)
		(end 151.852376 -107.63377)
		(width 0.11684)
		(layer "In2.Cu")
		(net "FM_BMC_TPM_PRES_N")
	)
	(segment
		(start 134.399782 -293.93134)
		(end 134.361682 -293.953438)
		(width 0.11684)
		(layer "In2.Cu")
		(net "FM_BMC_TPM_PRES_N")
	)
	(segment
		(start 137.416794 -306.95138)
		(end 137.416794 -295.010586)
		(width 0.11684)
		(layer "In2.Cu")
		(net "FM_BMC_TPM_PRES_N")
	)
	(segment
		(start 168.478708 -102.222554)
		(end 170.136058 -102.222554)
		(width 0.11684)
		(layer "In2.Cu")
		(net "FM_BMC_TPM_PRES_N")
	)
	(segment
		(start 163.712398 -105.248202)
		(end 163.712398 -104.886506)
		(width 0.11684)
		(layer "In2.Cu")
		(net "FM_BMC_TPM_PRES_N")
	)
	(segment
		(start 154.12593 -107.63377)
		(end 154.797506 -108.305346)
		(width 0.11684)
		(layer "In2.Cu")
		(net "FM_BMC_TPM_PRES_N")
	)
	(segment
		(start 137.304272 -294.790114)
		(end 137.18413 -294.720518)
		(width 0.11684)
		(layer "In2.Cu")
		(net "FM_BMC_TPM_PRES_N")
	)
	(segment
		(start 171.689522 -100.54082)
		(end 179.459128 -100.54082)
		(width 0.11684)
		(layer "In2.Cu")
		(net "FM_BMC_TPM_PRES_N")
	)
	(segment
		(start 170.136058 -102.222554)
		(end 171.090082 -101.26853)
		(width 0.11684)
		(layer "In2.Cu")
		(net "FM_BMC_TPM_PRES_N")
	)
	(segment
		(start 171.090082 -101.26853)
		(end 171.090082 -101.14026)
		(width 0.11684)
		(layer "In2.Cu")
		(net "FM_BMC_TPM_PRES_N")
	)
	(segment
		(start 161.915602 -107.044998)
		(end 163.712398 -105.248202)
		(width 0.11684)
		(layer "In2.Cu")
		(net "FM_BMC_TPM_PRES_N")
	)
	(segment
		(start 179.459128 -100.54082)
		(end 180.721 -99.278948)
		(width 0.11684)
		(layer "In2.Cu")
		(net "FM_BMC_TPM_PRES_N")
	)
	(segment
		(start 135.819388 -293.936928)
		(end 135.800084 -293.925752)
		(width 0.11684)
		(layer "In2.Cu")
		(net "FM_BMC_TPM_PRES_N")
	)
	(segment
		(start 154.797506 -108.305346)
		(end 159.214312 -108.305346)
		(width 0.11684)
		(layer "In2.Cu")
		(net "FM_BMC_TPM_PRES_N")
	)
	(segment
		(start 133.929882 -294.741346)
		(end 133.41731 -294.95369)
		(width 0.11684)
		(layer "In2.Cu")
		(net "FM_BMC_TPM_PRES_N")
	)
	(segment
		(start 143.09979 -312.222134)
		(end 143.09979 -311.773062)
		(width 0.11684)
		(layer "In2.Cu")
		(net "FM_BMC_TPM_PRES_N")
	)
	(segment
		(start 163.712398 -104.886506)
		(end 164.83584 -103.763064)
		(width 0.11684)
		(layer "In2.Cu")
		(net "FM_BMC_TPM_PRES_N")
	)
	(segment
		(start 142.768574 -311.441846)
		(end 141.90726 -311.441846)
		(width 0.11684)
		(layer "In2.Cu")
		(net "FM_BMC_TPM_PRES_N")
	)
	(segment
		(start 171.090082 -101.14026)
		(end 171.689522 -100.54082)
		(width 0.11684)
		(layer "In2.Cu")
		(net "FM_BMC_TPM_PRES_N")
	)
	(segment
		(start 164.83584 -103.763064)
		(end 166.162228 -103.763064)
		(width 0.11684)
		(layer "In2.Cu")
		(net "FM_BMC_TPM_PRES_N")
	)
	(segment
		(start 160.47466 -107.044998)
		(end 161.915602 -107.044998)
		(width 0.11684)
		(layer "In2.Cu")
		(net "FM_BMC_TPM_PRES_N")
	)
	(segment
		(start 133.41731 -294.95369)
		(end 133.224778 -295.146222)
		(width 0.11684)
		(layer "In2.Cu")
		(net "FM_BMC_TPM_PRES_N")
	)
	(segment
		(start 132.832348 -322.489576)
		(end 143.09979 -312.222134)
		(width 0.11684)
		(layer "In2.Cu")
		(net "FM_BMC_TPM_PRES_N")
	)
	(arc
		(start 134.869682 -293.93134)
		(mid 134.634732 -293.868107)
		(end 134.399782 -293.93134)
		(width 0.11684)
		(layer "In2.Cu")
		(net "FM_BMC_TPM_PRES_N")
	)
	(arc
		(start 136.27989 -293.93134)
		(mid 136.050373 -293.994632)
		(end 135.819388 -293.936928)
		(width 0.11684)
		(layer "In2.Cu")
		(net "FM_BMC_TPM_PRES_N")
	)
	(arc
		(start 135.339582 -293.93134)
		(mid 135.104632 -293.994539)
		(end 134.869682 -293.93134)
		(width 0.11684)
		(layer "In2.Cu")
		(net "FM_BMC_TPM_PRES_N")
	)
	(arc
		(start 134.164578 -294.336216)
		(mid 134.102252 -294.56926)
		(end 133.931914 -294.740076)
		(width 0.11684)
		(layer "In2.Cu")
		(net "FM_BMC_TPM_PRES_N")
	)
	(arc
		(start 137.18413 -294.720518)
		(mid 137.037588 -294.55268)
		(end 136.98474 -294.336216)
		(width 0.11684)
		(layer "In2.Cu")
		(net "FM_BMC_TPM_PRES_N")
	)
	(arc
		(start 135.800084 -293.925752)
		(mid 135.569099 -293.86802)
		(end 135.339582 -293.93134)
		(width 0.11684)
		(layer "In2.Cu")
		(net "FM_BMC_TPM_PRES_N")
	)
	(arc
		(start 136.74979 -293.93134)
		(mid 136.51484 -293.868107)
		(end 136.27989 -293.93134)
		(width 0.11684)
		(layer "In2.Cu")
		(net "FM_BMC_TPM_PRES_N")
	)
	(arc
		(start 136.98474 -294.336216)
		(mid 136.931934 -294.119731)
		(end 136.78535 -293.951914)
		(width 0.11684)
		(layer "In2.Cu")
		(net "FM_BMC_TPM_PRES_N")
	)
	(arc
		(start 134.361682 -293.953438)
		(mid 134.216725 -294.120936)
		(end 134.164578 -294.336216)
		(width 0.11684)
		(layer "In2.Cu")
		(net "FM_BMC_TPM_PRES_N")
	)
	(segment
		(start 145.07591 -116.251482)
		(end 145.07591 -112.549178)
		(width 0.11684)
		(layer "In15.Cu")
		(net "FM_BMC_TPM_PRES_N")
	)
	(segment
		(start 155.421584 -136.697212)
		(end 155.820872 -136.697212)
		(width 0.11684)
		(layer "In15.Cu")
		(net "FM_BMC_TPM_PRES_N")
	)
	(segment
		(start 145.07591 -112.549178)
		(end 146.13763 -111.487458)
		(width 0.11684)
		(layer "In15.Cu")
		(net "FM_BMC_TPM_PRES_N")
	)
	(segment
		(start 155.820872 -136.697212)
		(end 156.217112 -136.300972)
		(width 0.11684)
		(layer "In15.Cu")
		(net "FM_BMC_TPM_PRES_N")
	)
	(segment
		(start 146.13763 -124.967746)
		(end 146.13763 -119.369078)
		(width 0.11684)
		(layer "In15.Cu")
		(net "FM_BMC_TPM_PRES_N")
	)
	(segment
		(start 156.217112 -135.047228)
		(end 146.13763 -124.967746)
		(width 0.11684)
		(layer "In15.Cu")
		(net "FM_BMC_TPM_PRES_N")
	)
	(segment
		(start 145.593054 -118.824502)
		(end 145.593054 -116.768626)
		(width 0.11684)
		(layer "In15.Cu")
		(net "FM_BMC_TPM_PRES_N")
	)
	(segment
		(start 145.593054 -116.768626)
		(end 145.07591 -116.251482)
		(width 0.11684)
		(layer "In15.Cu")
		(net "FM_BMC_TPM_PRES_N")
	)
	(segment
		(start 146.13763 -111.487458)
		(end 146.13763 -111.036354)
		(width 0.11684)
		(layer "In15.Cu")
		(net "FM_BMC_TPM_PRES_N")
	)
	(segment
		(start 156.217112 -136.300972)
		(end 156.217112 -135.047228)
		(width 0.11684)
		(layer "In15.Cu")
		(net "FM_BMC_TPM_PRES_N")
	)
	(segment
		(start 146.13763 -119.369078)
		(end 145.593054 -118.824502)
		(width 0.11684)
		(layer "In15.Cu")
		(net "FM_BMC_TPM_PRES_N")
	)
	(segment
		(start 163.82746 -101.360732)
		(end 162.483546 -101.360732)
		(width 0.10668)
		(layer "F.Cu")
		(net "FM_BMC_READY_N")
	)
	(segment
		(start 170.328082 -98.717608)
		(end 167.924988 -101.120702)
		(width 0.10668)
		(layer "F.Cu")
		(net "FM_BMC_READY_N")
	)
	(segment
		(start 167.924988 -101.120702)
		(end 164.06749 -101.120702)
		(width 0.10668)
		(layer "F.Cu")
		(net "FM_BMC_READY_N")
	)
	(segment
		(start 171.527216 -98.717608)
		(end 170.328082 -98.717608)
		(width 0.10668)
		(layer "F.Cu")
		(net "FM_BMC_READY_N")
	)
	(segment
		(start 176.657 -98.262948)
		(end 176.152556 -98.767392)
		(width 0.10668)
		(layer "F.Cu")
		(net "FM_BMC_READY_N")
	)
	(segment
		(start 176.152556 -98.767392)
		(end 171.577 -98.767392)
		(width 0.10668)
		(layer "F.Cu")
		(net "FM_BMC_READY_N")
	)
	(segment
		(start 164.06749 -101.120702)
		(end 163.82746 -101.360732)
		(width 0.10668)
		(layer "F.Cu")
		(net "FM_BMC_READY_N")
	)
	(segment
		(start 171.577 -98.767392)
		(end 171.527216 -98.717608)
		(width 0.10668)
		(layer "F.Cu")
		(net "FM_BMC_READY_N")
	)
	(segment
		(start 110.6678 -292.450266)
		(end 110.200948 -292.716204)
		(width 0.10668)
		(layer "F.Cu")
		(net "FM_BMC_READY_N")
	)
	(segment
		(start 162.483546 -101.360732)
		(end 161.06267 -102.781608)
		(width 0.10668)
		(layer "F.Cu")
		(net "FM_BMC_READY_N")
	)
	(via
		(at 176.657 -98.262948)
		(size 0.508)
		(drill 0.254)
		(layers "F.Cu" "B.Cu")
		(net "FM_BMC_READY_N")
	)
	(via
		(at 110.200948 -292.716204)
		(size 0.4064)
		(drill 0.2032)
		(layers "F.Cu" "B.Cu")
		(net "FM_BMC_READY_N")
	)
	(via
		(at 161.06267 -102.781608)
		(size 0.508)
		(drill 0.254)
		(layers "F.Cu" "B.Cu")
		(net "FM_BMC_READY_N")
	)
	(segment
		(start 141.666722 -116.056664)
		(end 145.465546 -112.25784)
		(width 0.10668)
		(layer "B.Cu")
		(net "FM_BMC_READY_N")
	)
	(segment
		(start 110.200948 -293.656766)
		(end 110.200948 -292.716204)
		(width 0.10668)
		(layer "B.Cu")
		(net "FM_BMC_READY_N")
	)
	(segment
		(start 92.970604 -309.645558)
		(end 91.534996 -311.081166)
		(width 0.10668)
		(layer "B.Cu")
		(net "FM_BMC_READY_N")
	)
	(segment
		(start 147.907756 -111.378746)
		(end 149.942296 -111.378746)
		(width 0.10668)
		(layer "B.Cu")
		(net "FM_BMC_READY_N")
	)
	(segment
		(start 94.88805 -303.748948)
		(end 94.88805 -304.693066)
		(width 0.10668)
		(layer "B.Cu")
		(net "FM_BMC_READY_N")
	)
	(segment
		(start 110.624874 -294.080692)
		(end 110.200948 -293.656766)
		(width 0.10668)
		(layer "B.Cu")
		(net "FM_BMC_READY_N")
	)
	(segment
		(start 154.230832 -104.878632)
		(end 158.965646 -104.878632)
		(width 0.10668)
		(layer "B.Cu")
		(net "FM_BMC_READY_N")
	)
	(segment
		(start 40.659812 -158.129732)
		(end 40.659812 -144.332198)
		(width 0.10668)
		(layer "B.Cu")
		(net "FM_BMC_READY_N")
	)
	(segment
		(start 11.872976 -186.916314)
		(end 33.495488 -165.293802)
		(width 0.10668)
		(layer "B.Cu")
		(net "FM_BMC_READY_N")
	)
	(segment
		(start 145.465546 -112.25784)
		(end 147.028662 -112.25784)
		(width 0.10668)
		(layer "B.Cu")
		(net "FM_BMC_READY_N")
	)
	(segment
		(start 158.965646 -104.878632)
		(end 161.06267 -102.781608)
		(width 0.10668)
		(layer "B.Cu")
		(net "FM_BMC_READY_N")
	)
	(segment
		(start 94.870524 -304.976276)
		(end 94.440502 -305.406298)
		(width 0.10668)
		(layer "B.Cu")
		(net "FM_BMC_READY_N")
	)
	(segment
		(start 110.624874 -294.553132)
		(end 110.624874 -294.080692)
		(width 0.10668)
		(layer "B.Cu")
		(net "FM_BMC_READY_N")
	)
	(segment
		(start 110.144814 -295.033192)
		(end 110.624874 -294.553132)
		(width 0.10668)
		(layer "B.Cu")
		(net "FM_BMC_READY_N")
	)
	(segment
		(start 40.659812 -144.332198)
		(end 68.935346 -116.056664)
		(width 0.10668)
		(layer "B.Cu")
		(net "FM_BMC_READY_N")
	)
	(segment
		(start 94.440502 -305.406298)
		(end 93.58503 -305.406298)
		(width 0.10668)
		(layer "B.Cu")
		(net "FM_BMC_READY_N")
	)
	(segment
		(start 94.88805 -304.693066)
		(end 94.870524 -304.710592)
		(width 0.10668)
		(layer "B.Cu")
		(net "FM_BMC_READY_N")
	)
	(segment
		(start 91.534996 -311.081166)
		(end 68.914772 -311.081166)
		(width 0.10668)
		(layer "B.Cu")
		(net "FM_BMC_READY_N")
	)
	(segment
		(start 11.872976 -322.683886)
		(end 11.872976 -186.916314)
		(width 0.10668)
		(layer "B.Cu")
		(net "FM_BMC_READY_N")
	)
	(segment
		(start 150.584154 -110.736888)
		(end 150.584154 -108.52531)
		(width 0.10668)
		(layer "B.Cu")
		(net "FM_BMC_READY_N")
	)
	(segment
		(start 94.870524 -304.710592)
		(end 94.870524 -304.976276)
		(width 0.10668)
		(layer "B.Cu")
		(net "FM_BMC_READY_N")
	)
	(segment
		(start 147.028662 -112.25784)
		(end 147.907756 -111.378746)
		(width 0.10668)
		(layer "B.Cu")
		(net "FM_BMC_READY_N")
	)
	(segment
		(start 68.935346 -116.056664)
		(end 141.666722 -116.056664)
		(width 0.10668)
		(layer "B.Cu")
		(net "FM_BMC_READY_N")
	)
	(segment
		(start 16.044418 -324.933564)
		(end 14.122654 -324.933564)
		(width 0.10668)
		(layer "B.Cu")
		(net "FM_BMC_READY_N")
	)
	(segment
		(start 68.914772 -311.081166)
		(end 57.324752 -322.671186)
		(width 0.10668)
		(layer "B.Cu")
		(net "FM_BMC_READY_N")
	)
	(segment
		(start 176.657 -99.894898)
		(end 176.308004 -99.894898)
		(width 0.10668)
		(layer "B.Cu")
		(net "FM_BMC_READY_N")
	)
	(segment
		(start 176.308004 -99.894898)
		(end 176.0728 -99.659694)
		(width 0.10668)
		(layer "B.Cu")
		(net "FM_BMC_READY_N")
	)
	(segment
		(start 176.0728 -98.847148)
		(end 176.657 -98.262948)
		(width 0.10668)
		(layer "B.Cu")
		(net "FM_BMC_READY_N")
	)
	(segment
		(start 101.614732 -304.710592)
		(end 110.144814 -296.18051)
		(width 0.10668)
		(layer "B.Cu")
		(net "FM_BMC_READY_N")
	)
	(segment
		(start 110.144814 -296.18051)
		(end 110.144814 -295.033192)
		(width 0.10668)
		(layer "B.Cu")
		(net "FM_BMC_READY_N")
	)
	(segment
		(start 18.306796 -322.671186)
		(end 16.044418 -324.933564)
		(width 0.10668)
		(layer "B.Cu")
		(net "FM_BMC_READY_N")
	)
	(segment
		(start 94.870524 -304.710592)
		(end 101.614732 -304.710592)
		(width 0.10668)
		(layer "B.Cu")
		(net "FM_BMC_READY_N")
	)
	(segment
		(start 14.122654 -324.933564)
		(end 11.872976 -322.683886)
		(width 0.10668)
		(layer "B.Cu")
		(net "FM_BMC_READY_N")
	)
	(segment
		(start 176.0728 -99.659694)
		(end 176.0728 -98.847148)
		(width 0.10668)
		(layer "B.Cu")
		(net "FM_BMC_READY_N")
	)
	(segment
		(start 93.58503 -305.406298)
		(end 92.970604 -306.020724)
		(width 0.10668)
		(layer "B.Cu")
		(net "FM_BMC_READY_N")
	)
	(segment
		(start 57.324752 -322.671186)
		(end 18.306796 -322.671186)
		(width 0.10668)
		(layer "B.Cu")
		(net "FM_BMC_READY_N")
	)
	(segment
		(start 33.495742 -165.293802)
		(end 40.659812 -158.129732)
		(width 0.10668)
		(layer "B.Cu")
		(net "FM_BMC_READY_N")
	)
	(segment
		(start 149.942296 -111.378746)
		(end 150.584154 -110.736888)
		(width 0.10668)
		(layer "B.Cu")
		(net "FM_BMC_READY_N")
	)
	(segment
		(start 150.584154 -108.52531)
		(end 154.230832 -104.878632)
		(width 0.10668)
		(layer "B.Cu")
		(net "FM_BMC_READY_N")
	)
	(segment
		(start 92.970604 -306.020724)
		(end 92.970604 -309.645558)
		(width 0.10668)
		(layer "B.Cu")
		(net "FM_BMC_READY_N")
	)
	(segment
		(start 33.495488 -165.293802)
		(end 33.495742 -165.293802)
		(width 0.10668)
		(layer "B.Cu")
		(net "FM_BMC_READY_N")
	)
	(segment
		(start 192.328038 -93.17863)
		(end 191.80429 -93.702378)
		(width 0.10668)
		(layer "F.Cu")
		(net "E1S_0_PRSNT_R_N")
	)
	(segment
		(start 192.762632 -93.17863)
		(end 192.328038 -93.17863)
		(width 0.10668)
		(layer "F.Cu")
		(net "E1S_0_PRSNT_R_N")
	)
	(segment
		(start 189.92215 -108.252768)
		(end 190.31204 -107.862878)
		(width 0.10668)
		(layer "F.Cu")
		(net "E1S_0_PRSNT_R_N")
	)
	(segment
		(start 192.786 -93.201998)
		(end 192.762632 -93.17863)
		(width 0.10668)
		(layer "F.Cu")
		(net "E1S_0_PRSNT_R_N")
	)
	(via
		(at 191.80429 -93.702378)
		(size 0.508)
		(drill 0.254)
		(layers "F.Cu" "B.Cu")
		(net "E1S_0_PRSNT_R_N")
	)
	(via
		(at 190.31204 -107.862878)
		(size 0.4572)
		(drill 0.254)
		(layers "F.Cu" "B.Cu")
		(net "E1S_0_PRSNT_R_N")
	)
	(segment
		(start 190.746888 -101.26472)
		(end 190.746888 -103.768906)
		(width 0.11684)
		(layer "In11.Cu")
		(net "E1S_0_PRSNT_R_N")
	)
	(segment
		(start 190.373 -95.133668)
		(end 190.373 -99.573588)
		(width 0.11684)
		(layer "In11.Cu")
		(net "E1S_0_PRSNT_R_N")
	)
	(segment
		(start 190.746888 -103.768906)
		(end 190.31204 -104.203754)
		(width 0.11684)
		(layer "In11.Cu")
		(net "E1S_0_PRSNT_R_N")
	)
	(segment
		(start 190.31204 -99.634548)
		(end 190.31204 -100.829872)
		(width 0.11684)
		(layer "In11.Cu")
		(net "E1S_0_PRSNT_R_N")
	)
	(segment
		(start 190.373 -99.573588)
		(end 190.31204 -99.634548)
		(width 0.11684)
		(layer "In11.Cu")
		(net "E1S_0_PRSNT_R_N")
	)
	(segment
		(start 191.80429 -93.702378)
		(end 190.373 -95.133668)
		(width 0.11684)
		(layer "In11.Cu")
		(net "E1S_0_PRSNT_R_N")
	)
	(segment
		(start 190.31204 -104.203754)
		(end 190.31204 -107.862878)
		(width 0.11684)
		(layer "In11.Cu")
		(net "E1S_0_PRSNT_R_N")
	)
	(segment
		(start 190.31204 -100.829872)
		(end 190.746888 -101.26472)
		(width 0.11684)
		(layer "In11.Cu")
		(net "E1S_0_PRSNT_R_N")
	)
	(segment
		(start 250.15952 -68.946522)
		(end 249.54357 -68.946522)
		(width 0.10668)
		(layer "F.Cu")
		(net "E1S_0_P3V3_EN")
	)
	(segment
		(start 201.000614 -69.804788)
		(end 202.443588 -69.804788)
		(width 0.10668)
		(layer "F.Cu")
		(net "E1S_0_P3V3_EN")
	)
	(segment
		(start 202.443588 -69.804788)
		(end 203.540614 -70.901814)
		(width 0.10668)
		(layer "F.Cu")
		(net "E1S_0_P3V3_EN")
	)
	(via
		(at 203.540614 -70.901814)
		(size 0.508)
		(drill 0.254)
		(layers "F.Cu" "B.Cu")
		(net "E1S_0_P3V3_EN")
	)
	(via
		(at 218.515946 -124.87148)
		(size 0.508)
		(drill 0.254)
		(layers "F.Cu" "B.Cu")
		(net "E1S_0_P3V3_EN")
	)
	(via
		(at 249.54357 -68.946522)
		(size 0.508)
		(drill 0.254)
		(layers "F.Cu" "B.Cu")
		(net "E1S_0_P3V3_EN")
	)
	(segment
		(start 216.87917 -121.882154)
		(end 217.911172 -122.914156)
		(width 0.10668)
		(layer "B.Cu")
		(net "E1S_0_P3V3_EN")
	)
	(segment
		(start 201.68362 -120.406414)
		(end 201.352658 -120.737376)
		(width 0.10668)
		(layer "B.Cu")
		(net "E1S_0_P3V3_EN")
	)
	(segment
		(start 217.911172 -122.914156)
		(end 217.911172 -124.266706)
		(width 0.10668)
		(layer "B.Cu")
		(net "E1S_0_P3V3_EN")
	)
	(segment
		(start 208.348326 -120.944386)
		(end 208.348326 -121.332752)
		(width 0.10668)
		(layer "B.Cu")
		(net "E1S_0_P3V3_EN")
	)
	(segment
		(start 208.897728 -121.882154)
		(end 216.87917 -121.882154)
		(width 0.10668)
		(layer "B.Cu")
		(net "E1S_0_P3V3_EN")
	)
	(segment
		(start 208.348326 -120.944386)
		(end 207.430116 -120.944386)
		(width 0.10668)
		(layer "B.Cu")
		(net "E1S_0_P3V3_EN")
	)
	(segment
		(start 208.348326 -121.332752)
		(end 208.897728 -121.882154)
		(width 0.10668)
		(layer "B.Cu")
		(net "E1S_0_P3V3_EN")
	)
	(segment
		(start 207.430116 -120.944386)
		(end 206.892144 -120.406414)
		(width 0.10668)
		(layer "B.Cu")
		(net "E1S_0_P3V3_EN")
	)
	(segment
		(start 206.892144 -120.406414)
		(end 201.68362 -120.406414)
		(width 0.10668)
		(layer "B.Cu")
		(net "E1S_0_P3V3_EN")
	)
	(segment
		(start 217.911172 -124.266706)
		(end 218.515946 -124.87148)
		(width 0.10668)
		(layer "B.Cu")
		(net "E1S_0_P3V3_EN")
	)
	(segment
		(start 225.310954 -70.24624)
		(end 222.236284 -70.24624)
		(width 0.11684)
		(layer "In2.Cu")
		(net "E1S_0_P3V3_EN")
	)
	(segment
		(start 222.236284 -70.24624)
		(end 220.878654 -68.88861)
		(width 0.11684)
		(layer "In2.Cu")
		(net "E1S_0_P3V3_EN")
	)
	(segment
		(start 239.823498 -69.652134)
		(end 234.688888 -69.652134)
		(width 0.11684)
		(layer "In2.Cu")
		(net "E1S_0_P3V3_EN")
	)
	(segment
		(start 234.370626 -69.970396)
		(end 225.586798 -69.970396)
		(width 0.11684)
		(layer "In2.Cu")
		(net "E1S_0_P3V3_EN")
	)
	(segment
		(start 207.912716 -68.88861)
		(end 206.53375 -70.267576)
		(width 0.11684)
		(layer "In2.Cu")
		(net "E1S_0_P3V3_EN")
	)
	(segment
		(start 249.54357 -68.946522)
		(end 240.52911 -68.946522)
		(width 0.11684)
		(layer "In2.Cu")
		(net "E1S_0_P3V3_EN")
	)
	(segment
		(start 204.174852 -70.267576)
		(end 203.540614 -70.901814)
		(width 0.11684)
		(layer "In2.Cu")
		(net "E1S_0_P3V3_EN")
	)
	(segment
		(start 234.688888 -69.652134)
		(end 234.370626 -69.970396)
		(width 0.11684)
		(layer "In2.Cu")
		(net "E1S_0_P3V3_EN")
	)
	(segment
		(start 240.52911 -68.946522)
		(end 239.823498 -69.652134)
		(width 0.11684)
		(layer "In2.Cu")
		(net "E1S_0_P3V3_EN")
	)
	(segment
		(start 206.53375 -70.267576)
		(end 204.174852 -70.267576)
		(width 0.11684)
		(layer "In2.Cu")
		(net "E1S_0_P3V3_EN")
	)
	(segment
		(start 225.586798 -69.970396)
		(end 225.310954 -70.24624)
		(width 0.11684)
		(layer "In2.Cu")
		(net "E1S_0_P3V3_EN")
	)
	(segment
		(start 220.878654 -68.88861)
		(end 207.912716 -68.88861)
		(width 0.11684)
		(layer "In2.Cu")
		(net "E1S_0_P3V3_EN")
	)
	(segment
		(start 218.481402 -95.904558)
		(end 217.984832 -95.407988)
		(width 0.11684)
		(layer "In11.Cu")
		(net "E1S_0_P3V3_EN")
	)
	(segment
		(start 215.085168 -88.397842)
		(end 214.249254 -87.561928)
		(width 0.11684)
		(layer "In11.Cu")
		(net "E1S_0_P3V3_EN")
	)
	(segment
		(start 216.873328 -114.824002)
		(end 216.873328 -108.798614)
		(width 0.11684)
		(layer "In11.Cu")
		(net "E1S_0_P3V3_EN")
	)
	(segment
		(start 218.564968 -116.515642)
		(end 216.873328 -114.824002)
		(width 0.11684)
		(layer "In11.Cu")
		(net "E1S_0_P3V3_EN")
	)
	(segment
		(start 218.515946 -124.87148)
		(end 218.01963 -124.375164)
		(width 0.11684)
		(layer "In11.Cu")
		(net "E1S_0_P3V3_EN")
	)
	(segment
		(start 217.984832 -95.407988)
		(end 217.984832 -93.622876)
		(width 0.11684)
		(layer "In11.Cu")
		(net "E1S_0_P3V3_EN")
	)
	(segment
		(start 217.628978 -100.954078)
		(end 218.481402 -100.101654)
		(width 0.11684)
		(layer "In11.Cu")
		(net "E1S_0_P3V3_EN")
	)
	(segment
		(start 203.826364 -74.239374)
		(end 203.826364 -71.187564)
		(width 0.11684)
		(layer "In11.Cu")
		(net "E1S_0_P3V3_EN")
	)
	(segment
		(start 205.553564 -75.966574)
		(end 203.826364 -74.239374)
		(width 0.11684)
		(layer "In11.Cu")
		(net "E1S_0_P3V3_EN")
	)
	(segment
		(start 215.085168 -90.723212)
		(end 215.085168 -88.397842)
		(width 0.11684)
		(layer "In11.Cu")
		(net "E1S_0_P3V3_EN")
	)
	(segment
		(start 217.628978 -101.419914)
		(end 217.628978 -100.954078)
		(width 0.11684)
		(layer "In11.Cu")
		(net "E1S_0_P3V3_EN")
	)
	(segment
		(start 218.564968 -119.052086)
		(end 218.564968 -116.515642)
		(width 0.11684)
		(layer "In11.Cu")
		(net "E1S_0_P3V3_EN")
	)
	(segment
		(start 218.743784 -102.53472)
		(end 217.628978 -101.419914)
		(width 0.11684)
		(layer "In11.Cu")
		(net "E1S_0_P3V3_EN")
	)
	(segment
		(start 205.553564 -81.191608)
		(end 205.553564 -75.966574)
		(width 0.11684)
		(layer "In11.Cu")
		(net "E1S_0_P3V3_EN")
	)
	(segment
		(start 218.481402 -100.101654)
		(end 218.481402 -95.904558)
		(width 0.11684)
		(layer "In11.Cu")
		(net "E1S_0_P3V3_EN")
	)
	(segment
		(start 217.984832 -93.622876)
		(end 215.085168 -90.723212)
		(width 0.11684)
		(layer "In11.Cu")
		(net "E1S_0_P3V3_EN")
	)
	(segment
		(start 214.249254 -87.561928)
		(end 211.923884 -87.561928)
		(width 0.11684)
		(layer "In11.Cu")
		(net "E1S_0_P3V3_EN")
	)
	(segment
		(start 211.923884 -87.561928)
		(end 205.553564 -81.191608)
		(width 0.11684)
		(layer "In11.Cu")
		(net "E1S_0_P3V3_EN")
	)
	(segment
		(start 203.826364 -71.187564)
		(end 203.540614 -70.901814)
		(width 0.11684)
		(layer "In11.Cu")
		(net "E1S_0_P3V3_EN")
	)
	(segment
		(start 218.01963 -124.375164)
		(end 218.01963 -119.597424)
		(width 0.11684)
		(layer "In11.Cu")
		(net "E1S_0_P3V3_EN")
	)
	(segment
		(start 218.01963 -119.597424)
		(end 218.564968 -119.052086)
		(width 0.11684)
		(layer "In11.Cu")
		(net "E1S_0_P3V3_EN")
	)
	(segment
		(start 216.873328 -108.798614)
		(end 218.743784 -106.928158)
		(width 0.11684)
		(layer "In11.Cu")
		(net "E1S_0_P3V3_EN")
	)
	(segment
		(start 218.743784 -106.928158)
		(end 218.743784 -102.53472)
		(width 0.11684)
		(layer "In11.Cu")
		(net "E1S_0_P3V3_EN")
	)
	(segment
		(start 201.17943 -114.133376)
		(end 201.352658 -113.960148)
		(width 0.10668)
		(layer "F.Cu")
		(net "E1S_0_P12V_EN")
	)
	(segment
		(start 201.352658 -113.625376)
		(end 202.488038 -113.625376)
		(width 0.10668)
		(layer "F.Cu")
		(net "E1S_0_P12V_EN")
	)
	(segment
		(start 201.352658 -113.960148)
		(end 201.352658 -113.625376)
		(width 0.10668)
		(layer "F.Cu")
		(net "E1S_0_P12V_EN")
	)
	(segment
		(start 197.826122 -114.133376)
		(end 201.17943 -114.133376)
		(width 0.10668)
		(layer "F.Cu")
		(net "E1S_0_P12V_EN")
	)
	(segment
		(start 250.15952 -66.238374)
		(end 249.54357 -66.238374)
		(width 0.10668)
		(layer "F.Cu")
		(net "E1S_0_P12V_EN")
	)
	(segment
		(start 197.669658 -114.641376)
		(end 197.669658 -114.28984)
		(width 0.10668)
		(layer "F.Cu")
		(net "E1S_0_P12V_EN")
	)
	(segment
		(start 258.29133 -49.402746)
		(end 259.212334 -49.402746)
		(width 0.10668)
		(layer "F.Cu")
		(net "E1S_0_P12V_EN")
	)
	(segment
		(start 197.669658 -114.28984)
		(end 197.826122 -114.133376)
		(width 0.10668)
		(layer "F.Cu")
		(net "E1S_0_P12V_EN")
	)
	(via
		(at 243.344446 -115.293648)
		(size 0.508)
		(drill 0.254)
		(layers "F.Cu" "B.Cu")
		(net "E1S_0_P12V_EN")
	)
	(via
		(at 259.212334 -49.402746)
		(size 0.508)
		(drill 0.254)
		(layers "F.Cu" "B.Cu")
		(net "E1S_0_P12V_EN")
	)
	(via
		(at 202.488038 -113.625376)
		(size 0.508)
		(drill 0.254)
		(layers "F.Cu" "B.Cu")
		(net "E1S_0_P12V_EN")
	)
	(via
		(at 249.54357 -66.238374)
		(size 0.508)
		(drill 0.254)
		(layers "F.Cu" "B.Cu")
		(net "E1S_0_P12V_EN")
	)
	(segment
		(start 255.017524 -60.76442)
		(end 257.594608 -60.76442)
		(width 0.11684)
		(layer "In11.Cu")
		(net "E1S_0_P12V_EN")
	)
	(segment
		(start 240.51514 -66.962528)
		(end 240.51514 -75.485498)
		(width 0.11684)
		(layer "In11.Cu")
		(net "E1S_0_P12V_EN")
	)
	(segment
		(start 259.916422 -58.442606)
		(end 259.916422 -57.230264)
		(width 0.11684)
		(layer "In11.Cu")
		(net "E1S_0_P12V_EN")
	)
	(segment
		(start 241.239294 -66.238374)
		(end 240.51514 -66.962528)
		(width 0.11684)
		(layer "In11.Cu")
		(net "E1S_0_P12V_EN")
	)
	(segment
		(start 257.594608 -60.76442)
		(end 259.916422 -58.442606)
		(width 0.11684)
		(layer "In11.Cu")
		(net "E1S_0_P12V_EN")
	)
	(segment
		(start 259.58038 -56.894222)
		(end 259.58038 -52.458366)
		(width 0.11684)
		(layer "In11.Cu")
		(net "E1S_0_P12V_EN")
	)
	(segment
		(start 240.51514 -75.485498)
		(end 243.855494 -78.825852)
		(width 0.11684)
		(layer "In11.Cu")
		(net "E1S_0_P12V_EN")
	)
	(segment
		(start 249.54357 -66.238374)
		(end 241.239294 -66.238374)
		(width 0.11684)
		(layer "In11.Cu")
		(net "E1S_0_P12V_EN")
	)
	(segment
		(start 243.855494 -114.7826)
		(end 243.344446 -115.293648)
		(width 0.11684)
		(layer "In11.Cu")
		(net "E1S_0_P12V_EN")
	)
	(segment
		(start 243.855494 -78.825852)
		(end 243.855494 -114.7826)
		(width 0.11684)
		(layer "In11.Cu")
		(net "E1S_0_P12V_EN")
	)
	(segment
		(start 259.916422 -57.230264)
		(end 259.58038 -56.894222)
		(width 0.11684)
		(layer "In11.Cu")
		(net "E1S_0_P12V_EN")
	)
	(segment
		(start 259.212334 -52.09032)
		(end 259.212334 -49.402746)
		(width 0.11684)
		(layer "In11.Cu")
		(net "E1S_0_P12V_EN")
	)
	(segment
		(start 249.54357 -66.238374)
		(end 255.017524 -60.76442)
		(width 0.11684)
		(layer "In11.Cu")
		(net "E1S_0_P12V_EN")
	)
	(segment
		(start 259.58038 -52.458366)
		(end 259.212334 -52.09032)
		(width 0.11684)
		(layer "In11.Cu")
		(net "E1S_0_P12V_EN")
	)
	(segment
		(start 202.488038 -113.625376)
		(end 207.669892 -113.625376)
		(width 0.11684)
		(layer "In15.Cu")
		(net "E1S_0_P12V_EN")
	)
	(segment
		(start 242.66017 -115.977924)
		(end 243.344446 -115.293648)
		(width 0.11684)
		(layer "In15.Cu")
		(net "E1S_0_P12V_EN")
	)
	(segment
		(start 213.924896 -115.625118)
		(end 220.157802 -115.625118)
		(width 0.11684)
		(layer "In15.Cu")
		(net "E1S_0_P12V_EN")
	)
	(segment
		(start 220.157802 -115.625118)
		(end 220.510608 -115.977924)
		(width 0.11684)
		(layer "In15.Cu")
		(net "E1S_0_P12V_EN")
	)
	(segment
		(start 208.998566 -114.95405)
		(end 213.253828 -114.95405)
		(width 0.11684)
		(layer "In15.Cu")
		(net "E1S_0_P12V_EN")
	)
	(segment
		(start 207.669892 -113.625376)
		(end 208.998566 -114.95405)
		(width 0.11684)
		(layer "In15.Cu")
		(net "E1S_0_P12V_EN")
	)
	(segment
		(start 220.510608 -115.977924)
		(end 242.66017 -115.977924)
		(width 0.11684)
		(layer "In15.Cu")
		(net "E1S_0_P12V_EN")
	)
	(segment
		(start 213.253828 -114.95405)
		(end 213.924896 -115.625118)
		(width 0.11684)
		(layer "In15.Cu")
		(net "E1S_0_P12V_EN")
	)
	(segment
		(start 35.977068 -125.513338)
		(end 16.06931 -125.513338)
		(width 0.10668)
		(layer "F.Cu")
		(net "SMB_HOST_CLK_3V3AUX_SDA")
	)
	(segment
		(start 16.06931 -125.513338)
		(end 13.437108 -128.14554)
		(width 0.10668)
		(layer "F.Cu")
		(net "SMB_HOST_CLK_3V3AUX_SDA")
	)
	(via
		(at 35.977068 -125.513338)
		(size 0.508)
		(drill 0.254)
		(layers "F.Cu" "B.Cu")
		(net "SMB_HOST_CLK_3V3AUX_SDA")
	)
	(via
		(at 38.822122 -396.917164)
		(size 0.508)
		(drill 0.254)
		(layers "F.Cu" "B.Cu")
		(net "SMB_HOST_CLK_3V3AUX_SDA")
	)
	(via
		(at 149.086062 -16.114014)
		(size 0.508)
		(drill 0.254)
		(layers "F.Cu" "B.Cu")
		(net "SMB_HOST_CLK_3V3AUX_SDA")
	)
	(via
		(at 102.956868 -413.667194)
		(size 0.508)
		(drill 0.254)
		(layers "F.Cu" "B.Cu")
		(net "SMB_HOST_CLK_3V3AUX_SDA")
	)
	(segment
		(start 102.725474 -414.329626)
		(end 102.725474 -413.898588)
		(width 0.10668)
		(layer "B.Cu")
		(net "SMB_HOST_CLK_3V3AUX_SDA")
	)
	(segment
		(start 26.8351 -367.836958)
		(end 26.587196 -367.589054)
		(width 0.10668)
		(layer "B.Cu")
		(net "SMB_HOST_CLK_3V3AUX_SDA")
	)
	(segment
		(start 38.230048 -384.305302)
		(end 36.053268 -382.128522)
		(width 0.10668)
		(layer "B.Cu")
		(net "SMB_HOST_CLK_3V3AUX_SDA")
	)
	(segment
		(start 38.822122 -396.917164)
		(end 38.230048 -396.32509)
		(width 0.10668)
		(layer "B.Cu")
		(net "SMB_HOST_CLK_3V3AUX_SDA")
	)
	(segment
		(start 29.14904 -374.896126)
		(end 26.8351 -372.582186)
		(width 0.10668)
		(layer "B.Cu")
		(net "SMB_HOST_CLK_3V3AUX_SDA")
	)
	(segment
		(start 21.594826 -344.334084)
		(end 19.540474 -344.334084)
		(width 0.10668)
		(layer "B.Cu")
		(net "SMB_HOST_CLK_3V3AUX_SDA")
	)
	(segment
		(start 149.086062 -16.66113)
		(end 149.718776 -17.293844)
		(width 0.10668)
		(layer "B.Cu")
		(net "SMB_HOST_CLK_3V3AUX_SDA")
	)
	(segment
		(start 26.587196 -367.589054)
		(end 26.587196 -360.296968)
		(width 0.10668)
		(layer "B.Cu")
		(net "SMB_HOST_CLK_3V3AUX_SDA")
	)
	(segment
		(start 19.540474 -344.334084)
		(end 14.25956 -339.05317)
		(width 0.10668)
		(layer "B.Cu")
		(net "SMB_HOST_CLK_3V3AUX_SDA")
	)
	(segment
		(start 29.14904 -379.10516)
		(end 29.14904 -374.896126)
		(width 0.10668)
		(layer "B.Cu")
		(net "SMB_HOST_CLK_3V3AUX_SDA")
	)
	(segment
		(start 13.016738 -330.48067)
		(end 13.016738 -326.346312)
		(width 0.10668)
		(layer "B.Cu")
		(net "SMB_HOST_CLK_3V3AUX_SDA")
	)
	(segment
		(start 26.587196 -360.296968)
		(end 25.492456 -357.654098)
		(width 0.10668)
		(layer "B.Cu")
		(net "SMB_HOST_CLK_3V3AUX_SDA")
	)
	(segment
		(start 25.492456 -357.654098)
		(end 23.56866 -355.730302)
		(width 0.10668)
		(layer "B.Cu")
		(net "SMB_HOST_CLK_3V3AUX_SDA")
	)
	(segment
		(start 23.56866 -355.730302)
		(end 23.56866 -346.307918)
		(width 0.10668)
		(layer "B.Cu")
		(net "SMB_HOST_CLK_3V3AUX_SDA")
	)
	(segment
		(start 10.087102 -323.416676)
		(end 10.087102 -186.186826)
		(width 0.10668)
		(layer "B.Cu")
		(net "SMB_HOST_CLK_3V3AUX_SDA")
	)
	(segment
		(start 40.208708 -129.744978)
		(end 35.977068 -125.513338)
		(width 0.10668)
		(layer "B.Cu")
		(net "SMB_HOST_CLK_3V3AUX_SDA")
	)
	(segment
		(start 149.086062 -16.114014)
		(end 149.086062 -16.66113)
		(width 0.10668)
		(layer "B.Cu")
		(net "SMB_HOST_CLK_3V3AUX_SDA")
	)
	(segment
		(start 26.8351 -372.582186)
		(end 26.8351 -367.836958)
		(width 0.10668)
		(layer "B.Cu")
		(net "SMB_HOST_CLK_3V3AUX_SDA")
	)
	(segment
		(start 102.725474 -413.898588)
		(end 102.956868 -413.667194)
		(width 0.10668)
		(layer "B.Cu")
		(net "SMB_HOST_CLK_3V3AUX_SDA")
	)
	(segment
		(start 149.086062 -15.013432)
		(end 149.086062 -16.114014)
		(width 0.10668)
		(layer "B.Cu")
		(net "SMB_HOST_CLK_3V3AUX_SDA")
	)
	(segment
		(start 38.711886 -143.343884)
		(end 40.208708 -141.847062)
		(width 0.10668)
		(layer "B.Cu")
		(net "SMB_HOST_CLK_3V3AUX_SDA")
	)
	(segment
		(start 38.230048 -396.32509)
		(end 38.230048 -384.305302)
		(width 0.10668)
		(layer "B.Cu")
		(net "SMB_HOST_CLK_3V3AUX_SDA")
	)
	(segment
		(start 32.172402 -382.128522)
		(end 29.14904 -379.10516)
		(width 0.10668)
		(layer "B.Cu")
		(net "SMB_HOST_CLK_3V3AUX_SDA")
	)
	(segment
		(start 23.56866 -346.307918)
		(end 21.594826 -344.334084)
		(width 0.10668)
		(layer "B.Cu")
		(net "SMB_HOST_CLK_3V3AUX_SDA")
	)
	(segment
		(start 13.016738 -326.346312)
		(end 10.087102 -323.416676)
		(width 0.10668)
		(layer "B.Cu")
		(net "SMB_HOST_CLK_3V3AUX_SDA")
	)
	(segment
		(start 14.25956 -339.05317)
		(end 14.25956 -331.723492)
		(width 0.10668)
		(layer "B.Cu")
		(net "SMB_HOST_CLK_3V3AUX_SDA")
	)
	(segment
		(start 149.884638 -14.162278)
		(end 149.884638 -14.214856)
		(width 0.10668)
		(layer "B.Cu")
		(net "SMB_HOST_CLK_3V3AUX_SDA")
	)
	(segment
		(start 149.884638 -14.214856)
		(end 149.086062 -15.013432)
		(width 0.10668)
		(layer "B.Cu")
		(net "SMB_HOST_CLK_3V3AUX_SDA")
	)
	(segment
		(start 40.208708 -141.847062)
		(end 40.208708 -129.744978)
		(width 0.10668)
		(layer "B.Cu")
		(net "SMB_HOST_CLK_3V3AUX_SDA")
	)
	(segment
		(start 38.711886 -157.562042)
		(end 38.711886 -143.343884)
		(width 0.10668)
		(layer "B.Cu")
		(net "SMB_HOST_CLK_3V3AUX_SDA")
	)
	(segment
		(start 10.087102 -186.186826)
		(end 38.711886 -157.562042)
		(width 0.10668)
		(layer "B.Cu")
		(net "SMB_HOST_CLK_3V3AUX_SDA")
	)
	(segment
		(start 14.25956 -331.723492)
		(end 13.016738 -330.48067)
		(width 0.10668)
		(layer "B.Cu")
		(net "SMB_HOST_CLK_3V3AUX_SDA")
	)
	(segment
		(start 36.053268 -382.128522)
		(end 32.172402 -382.128522)
		(width 0.10668)
		(layer "B.Cu")
		(net "SMB_HOST_CLK_3V3AUX_SDA")
	)
	(segment
		(start 95.665798 -72.921114)
		(end 98.322638 -70.264274)
		(width 0.11684)
		(layer "In2.Cu")
		(net "SMB_HOST_CLK_3V3AUX_SDA")
	)
	(segment
		(start 98.322638 -65.106804)
		(end 107.495594 -55.933848)
		(width 0.11684)
		(layer "In2.Cu")
		(net "SMB_HOST_CLK_3V3AUX_SDA")
	)
	(segment
		(start 97.865692 -401.80387)
		(end 97.865692 -401.15871)
		(width 0.11684)
		(layer "In2.Cu")
		(net "SMB_HOST_CLK_3V3AUX_SDA")
	)
	(segment
		(start 102.226618 -412.936944)
		(end 102.226618 -411.576266)
		(width 0.11684)
		(layer "In2.Cu")
		(net "SMB_HOST_CLK_3V3AUX_SDA")
	)
	(segment
		(start 121.4374 -52.0446)
		(end 124.765054 -52.0446)
		(width 0.11684)
		(layer "In2.Cu")
		(net "SMB_HOST_CLK_3V3AUX_SDA")
	)
	(segment
		(start 107.495594 -55.933848)
		(end 108.41736 -55.933848)
		(width 0.11684)
		(layer "In2.Cu")
		(net "SMB_HOST_CLK_3V3AUX_SDA")
	)
	(segment
		(start 147.423886 -32.378904)
		(end 147.423886 -27.999182)
		(width 0.11684)
		(layer "In2.Cu")
		(net "SMB_HOST_CLK_3V3AUX_SDA")
	)
	(segment
		(start 126.416054 -53.6956)
		(end 130.8608 -53.6956)
		(width 0.11684)
		(layer "In2.Cu")
		(net "SMB_HOST_CLK_3V3AUX_SDA")
	)
	(segment
		(start 101.894132 -404.341838)
		(end 100.373434 -402.82114)
		(width 0.11684)
		(layer "In2.Cu")
		(net "SMB_HOST_CLK_3V3AUX_SDA")
	)
	(segment
		(start 132.190998 -53.382672)
		(end 146.396202 -39.177468)
		(width 0.11684)
		(layer "In2.Cu")
		(net "SMB_HOST_CLK_3V3AUX_SDA")
	)
	(segment
		(start 98.0694 -402.007578)
		(end 97.865692 -401.80387)
		(width 0.11684)
		(layer "In2.Cu")
		(net "SMB_HOST_CLK_3V3AUX_SDA")
	)
	(segment
		(start 102.956868 -413.667194)
		(end 102.226618 -412.936944)
		(width 0.11684)
		(layer "In2.Cu")
		(net "SMB_HOST_CLK_3V3AUX_SDA")
	)
	(segment
		(start 108.5342 -53.04282)
		(end 108.80344 -52.77358)
		(width 0.11684)
		(layer "In2.Cu")
		(net "SMB_HOST_CLK_3V3AUX_SDA")
	)
	(segment
		(start 102.226618 -411.576266)
		(end 103.926132 -409.876752)
		(width 0.11684)
		(layer "In2.Cu")
		(net "SMB_HOST_CLK_3V3AUX_SDA")
	)
	(segment
		(start 98.322638 -70.264274)
		(end 98.322638 -65.106804)
		(width 0.11684)
		(layer "In2.Cu")
		(net "SMB_HOST_CLK_3V3AUX_SDA")
	)
	(segment
		(start 147.423886 -27.999182)
		(end 146.396202 -26.971498)
		(width 0.11684)
		(layer "In2.Cu")
		(net "SMB_HOST_CLK_3V3AUX_SDA")
	)
	(segment
		(start 146.396202 -18.52041)
		(end 148.802598 -16.114014)
		(width 0.11684)
		(layer "In2.Cu")
		(net "SMB_HOST_CLK_3V3AUX_SDA")
	)
	(segment
		(start 148.802598 -16.114014)
		(end 149.086062 -16.114014)
		(width 0.11684)
		(layer "In2.Cu")
		(net "SMB_HOST_CLK_3V3AUX_SDA")
	)
	(segment
		(start 108.80344 -52.77358)
		(end 120.70842 -52.77358)
		(width 0.11684)
		(layer "In2.Cu")
		(net "SMB_HOST_CLK_3V3AUX_SDA")
	)
	(segment
		(start 146.396202 -39.177468)
		(end 146.396202 -33.406588)
		(width 0.11684)
		(layer "In2.Cu")
		(net "SMB_HOST_CLK_3V3AUX_SDA")
	)
	(segment
		(start 35.977068 -125.513338)
		(end 40.630602 -125.513338)
		(width 0.11684)
		(layer "In2.Cu")
		(net "SMB_HOST_CLK_3V3AUX_SDA")
	)
	(segment
		(start 120.70842 -52.77358)
		(end 121.4374 -52.0446)
		(width 0.11684)
		(layer "In2.Cu")
		(net "SMB_HOST_CLK_3V3AUX_SDA")
	)
	(segment
		(start 146.396202 -26.971498)
		(end 146.396202 -18.52041)
		(width 0.11684)
		(layer "In2.Cu")
		(net "SMB_HOST_CLK_3V3AUX_SDA")
	)
	(segment
		(start 45.309536 -396.29842)
		(end 39.440866 -396.29842)
		(width 0.11684)
		(layer "In2.Cu")
		(net "SMB_HOST_CLK_3V3AUX_SDA")
	)
	(segment
		(start 72.556878 -99.460812)
		(end 95.665798 -76.351892)
		(width 0.11684)
		(layer "In2.Cu")
		(net "SMB_HOST_CLK_3V3AUX_SDA")
	)
	(segment
		(start 102.854252 -404.341838)
		(end 101.894132 -404.341838)
		(width 0.11684)
		(layer "In2.Cu")
		(net "SMB_HOST_CLK_3V3AUX_SDA")
	)
	(segment
		(start 39.440866 -396.29842)
		(end 38.822122 -396.917164)
		(width 0.11684)
		(layer "In2.Cu")
		(net "SMB_HOST_CLK_3V3AUX_SDA")
	)
	(segment
		(start 99.528122 -402.82114)
		(end 99.170744 -402.463762)
		(width 0.11684)
		(layer "In2.Cu")
		(net "SMB_HOST_CLK_3V3AUX_SDA")
	)
	(segment
		(start 40.630602 -125.513338)
		(end 66.683128 -99.460812)
		(width 0.11684)
		(layer "In2.Cu")
		(net "SMB_HOST_CLK_3V3AUX_SDA")
	)
	(segment
		(start 103.926132 -407.190448)
		(end 103.292148 -406.556464)
		(width 0.11684)
		(layer "In2.Cu")
		(net "SMB_HOST_CLK_3V3AUX_SDA")
	)
	(segment
		(start 146.396202 -33.406588)
		(end 147.423886 -32.378904)
		(width 0.11684)
		(layer "In2.Cu")
		(net "SMB_HOST_CLK_3V3AUX_SDA")
	)
	(segment
		(start 103.292148 -406.556464)
		(end 103.292148 -404.779734)
		(width 0.11684)
		(layer "In2.Cu")
		(net "SMB_HOST_CLK_3V3AUX_SDA")
	)
	(segment
		(start 124.765054 -52.0446)
		(end 126.416054 -53.6956)
		(width 0.11684)
		(layer "In2.Cu")
		(net "SMB_HOST_CLK_3V3AUX_SDA")
	)
	(segment
		(start 95.694754 -398.987772)
		(end 47.998888 -398.987772)
		(width 0.11684)
		(layer "In2.Cu")
		(net "SMB_HOST_CLK_3V3AUX_SDA")
	)
	(segment
		(start 103.926132 -409.876752)
		(end 103.926132 -407.190448)
		(width 0.11684)
		(layer "In2.Cu")
		(net "SMB_HOST_CLK_3V3AUX_SDA")
	)
	(segment
		(start 108.5342 -55.817008)
		(end 108.5342 -53.04282)
		(width 0.11684)
		(layer "In2.Cu")
		(net "SMB_HOST_CLK_3V3AUX_SDA")
	)
	(segment
		(start 66.683128 -99.460812)
		(end 72.556878 -99.460812)
		(width 0.11684)
		(layer "In2.Cu")
		(net "SMB_HOST_CLK_3V3AUX_SDA")
	)
	(segment
		(start 103.292148 -404.779734)
		(end 102.854252 -404.341838)
		(width 0.11684)
		(layer "In2.Cu")
		(net "SMB_HOST_CLK_3V3AUX_SDA")
	)
	(segment
		(start 108.41736 -55.933848)
		(end 108.5342 -55.817008)
		(width 0.11684)
		(layer "In2.Cu")
		(net "SMB_HOST_CLK_3V3AUX_SDA")
	)
	(segment
		(start 131.173728 -53.382672)
		(end 132.190998 -53.382672)
		(width 0.11684)
		(layer "In2.Cu")
		(net "SMB_HOST_CLK_3V3AUX_SDA")
	)
	(segment
		(start 95.665798 -76.351892)
		(end 95.665798 -72.921114)
		(width 0.11684)
		(layer "In2.Cu")
		(net "SMB_HOST_CLK_3V3AUX_SDA")
	)
	(segment
		(start 97.865692 -401.15871)
		(end 95.694754 -398.987772)
		(width 0.11684)
		(layer "In2.Cu")
		(net "SMB_HOST_CLK_3V3AUX_SDA")
	)
	(segment
		(start 100.373434 -402.82114)
		(end 99.528122 -402.82114)
		(width 0.11684)
		(layer "In2.Cu")
		(net "SMB_HOST_CLK_3V3AUX_SDA")
	)
	(segment
		(start 47.998888 -398.987772)
		(end 45.309536 -396.29842)
		(width 0.11684)
		(layer "In2.Cu")
		(net "SMB_HOST_CLK_3V3AUX_SDA")
	)
	(segment
		(start 99.170744 -402.463762)
		(end 98.0694 -402.007578)
		(width 0.11684)
		(layer "In2.Cu")
		(net "SMB_HOST_CLK_3V3AUX_SDA")
	)
	(segment
		(start 130.8608 -53.6956)
		(end 131.173728 -53.382672)
		(width 0.11684)
		(layer "In2.Cu")
		(net "SMB_HOST_CLK_3V3AUX_SDA")
	)
	(segment
		(start 15.588234 -124.125736)
		(end 35.977068 -124.125736)
		(width 0.10668)
		(layer "F.Cu")
		(net "SMB_HOST_CLK_3V3AUX_SCL")
	)
	(segment
		(start 12.319508 -128.193038)
		(end 12.319508 -127.394462)
		(width 0.10668)
		(layer "F.Cu")
		(net "SMB_HOST_CLK_3V3AUX_SCL")
	)
	(segment
		(start 12.319508 -127.394462)
		(end 15.588234 -124.125736)
		(width 0.10668)
		(layer "F.Cu")
		(net "SMB_HOST_CLK_3V3AUX_SCL")
	)
	(via
		(at 35.977068 -124.125736)
		(size 0.508)
		(drill 0.254)
		(layers "F.Cu" "B.Cu")
		(net "SMB_HOST_CLK_3V3AUX_SCL")
	)
	(via
		(at 150.13178 -15.291054)
		(size 0.508)
		(drill 0.254)
		(layers "F.Cu" "B.Cu")
		(net "SMB_HOST_CLK_3V3AUX_SCL")
	)
	(via
		(at 102.980744 -411.548072)
		(size 0.508)
		(drill 0.254)
		(layers "F.Cu" "B.Cu")
		(net "SMB_HOST_CLK_3V3AUX_SCL")
	)
	(via
		(at 38.822122 -396.023084)
		(size 0.508)
		(drill 0.254)
		(layers "F.Cu" "B.Cu")
		(net "SMB_HOST_CLK_3V3AUX_SCL")
	)
	(segment
		(start 26.942288 -360.157268)
		(end 25.842214 -357.501444)
		(width 0.10668)
		(layer "B.Cu")
		(net "SMB_HOST_CLK_3V3AUX_SCL")
	)
	(segment
		(start 25.842214 -357.501444)
		(end 23.923752 -355.582982)
		(width 0.10668)
		(layer "B.Cu")
		(net "SMB_HOST_CLK_3V3AUX_SCL")
	)
	(segment
		(start 27.190192 -367.689638)
		(end 26.942288 -367.441734)
		(width 0.10668)
		(layer "B.Cu")
		(net "SMB_HOST_CLK_3V3AUX_SCL")
	)
	(segment
		(start 40.5638 -141.994382)
		(end 40.5638 -128.712468)
		(width 0.10668)
		(layer "B.Cu")
		(net "SMB_HOST_CLK_3V3AUX_SCL")
	)
	(segment
		(start 13.37183 -330.33335)
		(end 13.37183 -326.198992)
		(width 0.10668)
		(layer "B.Cu")
		(net "SMB_HOST_CLK_3V3AUX_SCL")
	)
	(segment
		(start 38.58514 -384.157982)
		(end 36.200588 -381.77343)
		(width 0.10668)
		(layer "B.Cu")
		(net "SMB_HOST_CLK_3V3AUX_SCL")
	)
	(segment
		(start 102.156514 -412.178246)
		(end 102.35057 -412.178246)
		(width 0.10668)
		(layer "B.Cu")
		(net "SMB_HOST_CLK_3V3AUX_SCL")
	)
	(segment
		(start 23.923752 -346.160598)
		(end 21.742146 -343.978992)
		(width 0.10668)
		(layer "B.Cu")
		(net "SMB_HOST_CLK_3V3AUX_SCL")
	)
	(segment
		(start 40.5638 -128.712468)
		(end 35.977068 -124.125736)
		(width 0.10668)
		(layer "B.Cu")
		(net "SMB_HOST_CLK_3V3AUX_SCL")
	)
	(segment
		(start 36.200588 -381.77343)
		(end 32.319722 -381.77343)
		(width 0.10668)
		(layer "B.Cu")
		(net "SMB_HOST_CLK_3V3AUX_SCL")
	)
	(segment
		(start 39.066978 -157.709362)
		(end 39.066978 -143.491204)
		(width 0.10668)
		(layer "B.Cu")
		(net "SMB_HOST_CLK_3V3AUX_SCL")
	)
	(segment
		(start 101.45395 -413.2072)
		(end 101.45395 -412.88081)
		(width 0.10668)
		(layer "B.Cu")
		(net "SMB_HOST_CLK_3V3AUX_SCL")
	)
	(segment
		(start 29.504132 -374.748806)
		(end 27.190192 -372.434866)
		(width 0.10668)
		(layer "B.Cu")
		(net "SMB_HOST_CLK_3V3AUX_SCL")
	)
	(segment
		(start 32.319722 -381.77343)
		(end 29.504132 -378.95784)
		(width 0.10668)
		(layer "B.Cu")
		(net "SMB_HOST_CLK_3V3AUX_SCL")
	)
	(segment
		(start 102.35057 -412.178246)
		(end 102.980744 -411.548072)
		(width 0.10668)
		(layer "B.Cu")
		(net "SMB_HOST_CLK_3V3AUX_SCL")
	)
	(segment
		(start 27.190192 -372.434866)
		(end 27.190192 -367.689638)
		(width 0.10668)
		(layer "B.Cu")
		(net "SMB_HOST_CLK_3V3AUX_SCL")
	)
	(segment
		(start 101.45395 -412.88081)
		(end 102.156514 -412.178246)
		(width 0.10668)
		(layer "B.Cu")
		(net "SMB_HOST_CLK_3V3AUX_SCL")
	)
	(segment
		(start 150.988776 -17.293844)
		(end 150.13178 -16.436848)
		(width 0.10668)
		(layer "B.Cu")
		(net "SMB_HOST_CLK_3V3AUX_SCL")
	)
	(segment
		(start 10.442194 -186.334146)
		(end 39.066978 -157.709362)
		(width 0.10668)
		(layer "B.Cu")
		(net "SMB_HOST_CLK_3V3AUX_SCL")
	)
	(segment
		(start 29.504132 -378.95784)
		(end 29.504132 -374.748806)
		(width 0.10668)
		(layer "B.Cu")
		(net "SMB_HOST_CLK_3V3AUX_SCL")
	)
	(segment
		(start 21.742146 -343.978992)
		(end 19.687794 -343.978992)
		(width 0.10668)
		(layer "B.Cu")
		(net "SMB_HOST_CLK_3V3AUX_SCL")
	)
	(segment
		(start 14.614652 -338.90585)
		(end 14.614652 -331.576172)
		(width 0.10668)
		(layer "B.Cu")
		(net "SMB_HOST_CLK_3V3AUX_SCL")
	)
	(segment
		(start 38.822122 -396.023084)
		(end 38.822122 -394.758418)
		(width 0.10668)
		(layer "B.Cu")
		(net "SMB_HOST_CLK_3V3AUX_SCL")
	)
	(segment
		(start 38.58514 -394.521436)
		(end 38.58514 -384.157982)
		(width 0.10668)
		(layer "B.Cu")
		(net "SMB_HOST_CLK_3V3AUX_SCL")
	)
	(segment
		(start 150.13178 -16.436848)
		(end 150.13178 -15.291054)
		(width 0.10668)
		(layer "B.Cu")
		(net "SMB_HOST_CLK_3V3AUX_SCL")
	)
	(segment
		(start 23.923752 -355.582982)
		(end 23.923752 -346.160598)
		(width 0.10668)
		(layer "B.Cu")
		(net "SMB_HOST_CLK_3V3AUX_SCL")
	)
	(segment
		(start 150.181564 -15.291054)
		(end 150.365206 -15.107412)
		(width 0.10668)
		(layer "B.Cu")
		(net "SMB_HOST_CLK_3V3AUX_SCL")
	)
	(segment
		(start 10.442194 -323.269356)
		(end 10.442194 -186.334146)
		(width 0.10668)
		(layer "B.Cu")
		(net "SMB_HOST_CLK_3V3AUX_SCL")
	)
	(segment
		(start 150.365206 -15.107412)
		(end 150.365206 -14.775942)
		(width 0.10668)
		(layer "B.Cu")
		(net "SMB_HOST_CLK_3V3AUX_SCL")
	)
	(segment
		(start 38.822122 -394.758418)
		(end 38.58514 -394.521436)
		(width 0.10668)
		(layer "B.Cu")
		(net "SMB_HOST_CLK_3V3AUX_SCL")
	)
	(segment
		(start 150.13178 -15.291054)
		(end 150.181564 -15.291054)
		(width 0.10668)
		(layer "B.Cu")
		(net "SMB_HOST_CLK_3V3AUX_SCL")
	)
	(segment
		(start 13.37183 -326.198992)
		(end 10.442194 -323.269356)
		(width 0.10668)
		(layer "B.Cu")
		(net "SMB_HOST_CLK_3V3AUX_SCL")
	)
	(segment
		(start 39.066978 -143.491204)
		(end 40.5638 -141.994382)
		(width 0.10668)
		(layer "B.Cu")
		(net "SMB_HOST_CLK_3V3AUX_SCL")
	)
	(segment
		(start 14.614652 -331.576172)
		(end 13.37183 -330.33335)
		(width 0.10668)
		(layer "B.Cu")
		(net "SMB_HOST_CLK_3V3AUX_SCL")
	)
	(segment
		(start 19.687794 -343.978992)
		(end 14.614652 -338.90585)
		(width 0.10668)
		(layer "B.Cu")
		(net "SMB_HOST_CLK_3V3AUX_SCL")
	)
	(segment
		(start 150.365206 -14.775942)
		(end 150.97887 -14.162278)
		(width 0.10668)
		(layer "B.Cu")
		(net "SMB_HOST_CLK_3V3AUX_SCL")
	)
	(segment
		(start 26.942288 -367.441734)
		(end 26.942288 -360.157268)
		(width 0.10668)
		(layer "B.Cu")
		(net "SMB_HOST_CLK_3V3AUX_SCL")
	)
	(segment
		(start 104.357424 -410.171392)
		(end 104.357424 -407.011632)
		(width 0.11684)
		(layer "In2.Cu")
		(net "SMB_HOST_CLK_3V3AUX_SCL")
	)
	(segment
		(start 103.72344 -406.377648)
		(end 103.72344 -404.570946)
		(width 0.11684)
		(layer "In2.Cu")
		(net "SMB_HOST_CLK_3V3AUX_SCL")
	)
	(segment
		(start 120.41124 -52.30876)
		(end 121.1072 -51.6128)
		(width 0.11684)
		(layer "In2.Cu")
		(net "SMB_HOST_CLK_3V3AUX_SCL")
	)
	(segment
		(start 108.24972 -52.30876)
		(end 109.34827 -52.30876)
		(width 0.11684)
		(layer "In2.Cu")
		(net "SMB_HOST_CLK_3V3AUX_SCL")
	)
	(segment
		(start 146.958304 -32.220916)
		(end 146.958304 -29.248862)
		(width 0.11684)
		(layer "In2.Cu")
		(net "SMB_HOST_CLK_3V3AUX_SCL")
	)
	(segment
		(start 109.35716 -52.31765)
		(end 109.742732 -52.31765)
		(width 0.11684)
		(layer "In2.Cu")
		(net "SMB_HOST_CLK_3V3AUX_SCL")
	)
	(segment
		(start 149.029166 -15.291054)
		(end 150.13178 -15.291054)
		(width 0.11684)
		(layer "In2.Cu")
		(net "SMB_HOST_CLK_3V3AUX_SCL")
	)
	(segment
		(start 97.900998 -64.932052)
		(end 106.790998 -56.042052)
		(width 0.11684)
		(layer "In2.Cu")
		(net "SMB_HOST_CLK_3V3AUX_SCL")
	)
	(segment
		(start 96.760538 -398.55648)
		(end 48.177704 -398.55648)
		(width 0.11684)
		(layer "In2.Cu")
		(net "SMB_HOST_CLK_3V3AUX_SCL")
	)
	(segment
		(start 41.421812 -124.125736)
		(end 66.508376 -99.039172)
		(width 0.11684)
		(layer "In2.Cu")
		(net "SMB_HOST_CLK_3V3AUX_SCL")
	)
	(segment
		(start 145.6182 -27.908758)
		(end 145.6182 -18.70202)
		(width 0.11684)
		(layer "In2.Cu")
		(net "SMB_HOST_CLK_3V3AUX_SCL")
	)
	(segment
		(start 106.790998 -55.311802)
		(end 108.0262 -54.0766)
		(width 0.11684)
		(layer "In2.Cu")
		(net "SMB_HOST_CLK_3V3AUX_SCL")
	)
	(segment
		(start 97.900998 -70.089522)
		(end 97.900998 -64.932052)
		(width 0.11684)
		(layer "In2.Cu")
		(net "SMB_HOST_CLK_3V3AUX_SCL")
	)
	(segment
		(start 146.958304 -29.248862)
		(end 145.6182 -27.908758)
		(width 0.11684)
		(layer "In2.Cu")
		(net "SMB_HOST_CLK_3V3AUX_SCL")
	)
	(segment
		(start 126.7968 -51.3334)
		(end 127.7366 -52.2732)
		(width 0.11684)
		(layer "In2.Cu")
		(net "SMB_HOST_CLK_3V3AUX_SCL")
	)
	(segment
		(start 145.6182 -39.359078)
		(end 145.6182 -33.56102)
		(width 0.11684)
		(layer "In2.Cu")
		(net "SMB_HOST_CLK_3V3AUX_SCL")
	)
	(segment
		(start 39.04996 -395.795246)
		(end 38.822122 -396.023084)
		(width 0.11684)
		(layer "In2.Cu")
		(net "SMB_HOST_CLK_3V3AUX_SCL")
	)
	(segment
		(start 108.0262 -52.53228)
		(end 108.24972 -52.30876)
		(width 0.11684)
		(layer "In2.Cu")
		(net "SMB_HOST_CLK_3V3AUX_SCL")
	)
	(segment
		(start 131.8514 -51.5874)
		(end 131.958334 -51.480466)
		(width 0.11684)
		(layer "In2.Cu")
		(net "SMB_HOST_CLK_3V3AUX_SCL")
	)
	(segment
		(start 128.8034 -52.2732)
		(end 129.4892 -51.5874)
		(width 0.11684)
		(layer "In2.Cu")
		(net "SMB_HOST_CLK_3V3AUX_SCL")
	)
	(segment
		(start 145.6182 -33.56102)
		(end 146.958304 -32.220916)
		(width 0.11684)
		(layer "In2.Cu")
		(net "SMB_HOST_CLK_3V3AUX_SCL")
	)
	(segment
		(start 133.496812 -51.480466)
		(end 145.6182 -39.359078)
		(width 0.11684)
		(layer "In2.Cu")
		(net "SMB_HOST_CLK_3V3AUX_SCL")
	)
	(segment
		(start 103.06304 -403.910546)
		(end 102.114604 -403.910546)
		(width 0.11684)
		(layer "In2.Cu")
		(net "SMB_HOST_CLK_3V3AUX_SCL")
	)
	(segment
		(start 124.6378 -51.6128)
		(end 124.9172 -51.3334)
		(width 0.11684)
		(layer "In2.Cu")
		(net "SMB_HOST_CLK_3V3AUX_SCL")
	)
	(segment
		(start 109.742732 -52.31765)
		(end 109.751622 -52.30876)
		(width 0.11684)
		(layer "In2.Cu")
		(net "SMB_HOST_CLK_3V3AUX_SCL")
	)
	(segment
		(start 106.790998 -56.042052)
		(end 106.790998 -55.311802)
		(width 0.11684)
		(layer "In2.Cu")
		(net "SMB_HOST_CLK_3V3AUX_SCL")
	)
	(segment
		(start 131.958334 -51.480466)
		(end 133.496812 -51.480466)
		(width 0.11684)
		(layer "In2.Cu")
		(net "SMB_HOST_CLK_3V3AUX_SCL")
	)
	(segment
		(start 109.751622 -52.30876)
		(end 120.41124 -52.30876)
		(width 0.11684)
		(layer "In2.Cu")
		(net "SMB_HOST_CLK_3V3AUX_SCL")
	)
	(segment
		(start 127.7366 -52.2732)
		(end 128.8034 -52.2732)
		(width 0.11684)
		(layer "In2.Cu")
		(net "SMB_HOST_CLK_3V3AUX_SCL")
	)
	(segment
		(start 95.244158 -72.746362)
		(end 97.900998 -70.089522)
		(width 0.11684)
		(layer "In2.Cu")
		(net "SMB_HOST_CLK_3V3AUX_SCL")
	)
	(segment
		(start 109.34827 -52.30876)
		(end 109.35716 -52.31765)
		(width 0.11684)
		(layer "In2.Cu")
		(net "SMB_HOST_CLK_3V3AUX_SCL")
	)
	(segment
		(start 102.980744 -411.548072)
		(end 104.357424 -410.171392)
		(width 0.11684)
		(layer "In2.Cu")
		(net "SMB_HOST_CLK_3V3AUX_SCL")
	)
	(segment
		(start 45.41647 -395.795246)
		(end 39.04996 -395.795246)
		(width 0.11684)
		(layer "In2.Cu")
		(net "SMB_HOST_CLK_3V3AUX_SCL")
	)
	(segment
		(start 72.382126 -99.039172)
		(end 95.244158 -76.17714)
		(width 0.11684)
		(layer "In2.Cu")
		(net "SMB_HOST_CLK_3V3AUX_SCL")
	)
	(segment
		(start 129.4892 -51.5874)
		(end 131.8514 -51.5874)
		(width 0.11684)
		(layer "In2.Cu")
		(net "SMB_HOST_CLK_3V3AUX_SCL")
	)
	(segment
		(start 104.357424 -407.011632)
		(end 103.72344 -406.377648)
		(width 0.11684)
		(layer "In2.Cu")
		(net "SMB_HOST_CLK_3V3AUX_SCL")
	)
	(segment
		(start 48.177704 -398.55648)
		(end 45.41647 -395.795246)
		(width 0.11684)
		(layer "In2.Cu")
		(net "SMB_HOST_CLK_3V3AUX_SCL")
	)
	(segment
		(start 108.0262 -54.0766)
		(end 108.0262 -52.53228)
		(width 0.11684)
		(layer "In2.Cu")
		(net "SMB_HOST_CLK_3V3AUX_SCL")
	)
	(segment
		(start 103.72344 -404.570946)
		(end 103.06304 -403.910546)
		(width 0.11684)
		(layer "In2.Cu")
		(net "SMB_HOST_CLK_3V3AUX_SCL")
	)
	(segment
		(start 124.9172 -51.3334)
		(end 126.7968 -51.3334)
		(width 0.11684)
		(layer "In2.Cu")
		(net "SMB_HOST_CLK_3V3AUX_SCL")
	)
	(segment
		(start 145.6182 -18.70202)
		(end 149.029166 -15.291054)
		(width 0.11684)
		(layer "In2.Cu")
		(net "SMB_HOST_CLK_3V3AUX_SCL")
	)
	(segment
		(start 102.114604 -403.910546)
		(end 96.760538 -398.55648)
		(width 0.11684)
		(layer "In2.Cu")
		(net "SMB_HOST_CLK_3V3AUX_SCL")
	)
	(segment
		(start 66.508376 -99.039172)
		(end 72.382126 -99.039172)
		(width 0.11684)
		(layer "In2.Cu")
		(net "SMB_HOST_CLK_3V3AUX_SCL")
	)
	(segment
		(start 121.1072 -51.6128)
		(end 124.6378 -51.6128)
		(width 0.11684)
		(layer "In2.Cu")
		(net "SMB_HOST_CLK_3V3AUX_SCL")
	)
	(segment
		(start 95.244158 -76.17714)
		(end 95.244158 -72.746362)
		(width 0.11684)
		(layer "In2.Cu")
		(net "SMB_HOST_CLK_3V3AUX_SCL")
	)
	(segment
		(start 35.977068 -124.125736)
		(end 41.421812 -124.125736)
		(width 0.11684)
		(layer "In2.Cu")
		(net "SMB_HOST_CLK_3V3AUX_SCL")
	)
	(segment
		(start 106.276648 -300.44771)
		(end 123.152408 -317.32347)
		(width 0.12954)
		(layer "F.Cu")
		(net "CLK_100M_CPU1_CLK12_R_DP")
	)
	(segment
		(start 106.276648 -295.999154)
		(end 106.276648 -300.44771)
		(width 0.12954)
		(layer "F.Cu")
		(net "CLK_100M_CPU1_CLK12_R_DP")
	)
	(segment
		(start 105.967784 -295.69029)
		(end 106.276648 -295.999154)
		(width 0.12954)
		(layer "F.Cu")
		(net "CLK_100M_CPU1_CLK12_R_DP")
	)
	(segment
		(start 123.152408 -317.32347)
		(end 123.152408 -320.91249)
		(width 0.12954)
		(layer "F.Cu")
		(net "CLK_100M_CPU1_CLK12_R_DP")
	)
	(segment
		(start 123.152408 -320.91249)
		(end 122.809 -321.255898)
		(width 0.12954)
		(layer "F.Cu")
		(net "CLK_100M_CPU1_CLK12_R_DP")
	)
	(segment
		(start 106.599228 -300.313852)
		(end 123.474988 -317.189612)
		(width 0.12954)
		(layer "F.Cu")
		(net "CLK_100M_CPU1_CLK12_R_DN")
	)
	(segment
		(start 123.474988 -317.189612)
		(end 123.474988 -320.905886)
		(width 0.12954)
		(layer "F.Cu")
		(net "CLK_100M_CPU1_CLK12_R_DN")
	)
	(segment
		(start 106.907838 -295.69029)
		(end 106.599228 -295.9989)
		(width 0.12954)
		(layer "F.Cu")
		(net "CLK_100M_CPU1_CLK12_R_DN")
	)
	(segment
		(start 123.474988 -320.905886)
		(end 123.825 -321.255898)
		(width 0.12954)
		(layer "F.Cu")
		(net "CLK_100M_CPU1_CLK12_R_DN")
	)
	(segment
		(start 106.599228 -295.9989)
		(end 106.599228 -300.313852)
		(width 0.12954)
		(layer "F.Cu")
		(net "CLK_100M_CPU1_CLK12_R_DN")
	)
	(segment
		(start 178.741324 -42.888662)
		(end 179.011834 -42.618152)
		(width 0.12954)
		(layer "F.Cu")
		(net "CLK_100M_CPU1_CLK12_DP")
	)
	(segment
		(start 141.683994 -370.13896)
		(end 141.954504 -370.40947)
		(width 0.12954)
		(layer "F.Cu")
		(net "CLK_100M_CPU1_CLK12_DP")
	)
	(segment
		(start 177.885344 -42.888662)
		(end 178.741324 -42.888662)
		(width 0.12954)
		(layer "F.Cu")
		(net "CLK_100M_CPU1_CLK12_DP")
	)
	(segment
		(start 140.791184 -369.689126)
		(end 141.241018 -370.13896)
		(width 0.12954)
		(layer "F.Cu")
		(net "CLK_100M_CPU1_CLK12_DP")
	)
	(segment
		(start 140.791184 -367.63833)
		(end 140.791184 -369.689126)
		(width 0.12954)
		(layer "F.Cu")
		(net "CLK_100M_CPU1_CLK12_DP")
	)
	(segment
		(start 123.15571 -340.594696)
		(end 123.15571 -350.002856)
		(width 0.12954)
		(layer "F.Cu")
		(net "CLK_100M_CPU1_CLK12_DP")
	)
	(segment
		(start 177.108358 -42.800016)
		(end 177.796698 -42.800016)
		(width 0.12954)
		(layer "F.Cu")
		(net "CLK_100M_CPU1_CLK12_DP")
	)
	(segment
		(start 122.809 -322.055998)
		(end 123.15571 -322.402708)
		(width 0.12954)
		(layer "F.Cu")
		(net "CLK_100M_CPU1_CLK12_DP")
	)
	(segment
		(start 177.796698 -42.800016)
		(end 177.885344 -42.888662)
		(width 0.12954)
		(layer "F.Cu")
		(net "CLK_100M_CPU1_CLK12_DP")
	)
	(segment
		(start 141.241018 -370.13896)
		(end 141.683994 -370.13896)
		(width 0.12954)
		(layer "F.Cu")
		(net "CLK_100M_CPU1_CLK12_DP")
	)
	(segment
		(start 123.15571 -350.002856)
		(end 140.791184 -367.63833)
		(width 0.12954)
		(layer "F.Cu")
		(net "CLK_100M_CPU1_CLK12_DP")
	)
	(segment
		(start 123.15571 -322.402708)
		(end 123.15571 -340.594696)
		(width 0.12954)
		(layer "F.Cu")
		(net "CLK_100M_CPU1_CLK12_DP")
	)
	(via
		(at 141.954504 -370.40947)
		(size 0.508)
		(drill 0.254)
		(layers "F.Cu" "B.Cu")
		(net "CLK_100M_CPU1_CLK12_DP")
	)
	(via
		(at 179.011834 -42.618152)
		(size 0.508)
		(drill 0.254)
		(layers "F.Cu" "B.Cu")
		(net "CLK_100M_CPU1_CLK12_DP")
	)
	(via
		(at 123.15571 -340.594696)
		(size 0.4064)
		(drill 0.2032)
		(layers "F.Cu" "B.Cu")
		(net "CLK_100M_CPU1_CLK12_DP")
	)
	(segment
		(start 13.11402 -179.774088)
		(end 20.56892 -161.77641)
		(width 0.14224)
		(layer "In2.Cu")
		(net "CLK_100M_CPU1_CLK12_DP")
	)
	(segment
		(start 10.863834 -340.599014)
		(end 10.863834 -314.89015)
		(width 0.14224)
		(layer "In2.Cu")
		(net "CLK_100M_CPU1_CLK12_DP")
	)
	(segment
		(start 44.26839 -367.830354)
		(end 40.97147 -371.127274)
		(width 0.14224)
		(layer "In2.Cu")
		(net "CLK_100M_CPU1_CLK12_DP")
	)
	(segment
		(start 17.364964 -353.983544)
		(end 15.6972 -352.31578)
		(width 0.14224)
		(layer "In2.Cu")
		(net "CLK_100M_CPU1_CLK12_DP")
	)
	(segment
		(start 141.093952 -370.11864)
		(end 138.805666 -367.830354)
		(width 0.14224)
		(layer "In2.Cu")
		(net "CLK_100M_CPU1_CLK12_DP")
	)
	(segment
		(start 168.800526 -54.349396)
		(end 171.734734 -47.266098)
		(width 0.14224)
		(layer "In2.Cu")
		(net "CLK_100M_CPU1_CLK12_DP")
	)
	(segment
		(start 178.721004 -42.908982)
		(end 179.011834 -42.618152)
		(width 0.14224)
		(layer "In2.Cu")
		(net "CLK_100M_CPU1_CLK12_DP")
	)
	(segment
		(start 10.863834 -314.89015)
		(end 9.39292 -253.008384)
		(width 0.14224)
		(layer "In2.Cu")
		(net "CLK_100M_CPU1_CLK12_DP")
	)
	(segment
		(start 21.669248 -155.536392)
		(end 23.84806 -150.27656)
		(width 0.14224)
		(layer "In2.Cu")
		(net "CLK_100M_CPU1_CLK12_DP")
	)
	(segment
		(start 40.97147 -371.127274)
		(end 31.626302 -371.127274)
		(width 0.14224)
		(layer "In2.Cu")
		(net "CLK_100M_CPU1_CLK12_DP")
	)
	(segment
		(start 19.656806 -370.690648)
		(end 17.364964 -368.398806)
		(width 0.14224)
		(layer "In2.Cu")
		(net "CLK_100M_CPU1_CLK12_DP")
	)
	(segment
		(start 63.429388 -113.587022)
		(end 88.039194 -88.974422)
		(width 0.14224)
		(layer "In2.Cu")
		(net "CLK_100M_CPU1_CLK12_DP")
	)
	(segment
		(start 17.364964 -368.398806)
		(end 17.364964 -353.983544)
		(width 0.14224)
		(layer "In2.Cu")
		(net "CLK_100M_CPU1_CLK12_DP")
	)
	(segment
		(start 168.178988 -54.970934)
		(end 168.800526 -54.349396)
		(width 0.14224)
		(layer "In2.Cu")
		(net "CLK_100M_CPU1_CLK12_DP")
	)
	(segment
		(start 25.080468 -148.51634)
		(end 34.901886 -141.63929)
		(width 0.14224)
		(layer "In2.Cu")
		(net "CLK_100M_CPU1_CLK12_DP")
	)
	(segment
		(start 171.734734 -47.266098)
		(end 176.09185 -42.908982)
		(width 0.14224)
		(layer "In2.Cu")
		(net "CLK_100M_CPU1_CLK12_DP")
	)
	(segment
		(start 34.901886 -141.63929)
		(end 44.191682 -127.057404)
		(width 0.14224)
		(layer "In2.Cu")
		(net "CLK_100M_CPU1_CLK12_DP")
	)
	(segment
		(start 112.465104 -64.240156)
		(end 116.617242 -63.508128)
		(width 0.14224)
		(layer "In2.Cu")
		(net "CLK_100M_CPU1_CLK12_DP")
	)
	(segment
		(start 23.84806 -150.27656)
		(end 25.080468 -148.51634)
		(width 0.14224)
		(layer "In2.Cu")
		(net "CLK_100M_CPU1_CLK12_DP")
	)
	(segment
		(start 44.191682 -127.057404)
		(end 63.429388 -113.587022)
		(width 0.14224)
		(layer "In2.Cu")
		(net "CLK_100M_CPU1_CLK12_DP")
	)
	(segment
		(start 164.937694 -56.31307)
		(end 168.178988 -54.970934)
		(width 0.14224)
		(layer "In2.Cu")
		(net "CLK_100M_CPU1_CLK12_DP")
	)
	(segment
		(start 141.954504 -370.40947)
		(end 141.663674 -370.11864)
		(width 0.14224)
		(layer "In2.Cu")
		(net "CLK_100M_CPU1_CLK12_DP")
	)
	(segment
		(start 9.39292 -253.003304)
		(end 7.920736 -191.072516)
		(width 0.14224)
		(layer "In2.Cu")
		(net "CLK_100M_CPU1_CLK12_DP")
	)
	(segment
		(start 9.39292 -253.008384)
		(end 9.39292 -253.003304)
		(width 0.14224)
		(layer "In2.Cu")
		(net "CLK_100M_CPU1_CLK12_DP")
	)
	(segment
		(start 141.663674 -370.11864)
		(end 141.093952 -370.11864)
		(width 0.14224)
		(layer "In2.Cu")
		(net "CLK_100M_CPU1_CLK12_DP")
	)
	(segment
		(start 28.214574 -370.690648)
		(end 19.656806 -370.690648)
		(width 0.14224)
		(layer "In2.Cu")
		(net "CLK_100M_CPU1_CLK12_DP")
	)
	(segment
		(start 29.399738 -371.875812)
		(end 28.214574 -370.690648)
		(width 0.14224)
		(layer "In2.Cu")
		(net "CLK_100M_CPU1_CLK12_DP")
	)
	(segment
		(start 116.617242 -63.508128)
		(end 153.90241 -59.547506)
		(width 0.14224)
		(layer "In2.Cu")
		(net "CLK_100M_CPU1_CLK12_DP")
	)
	(segment
		(start 88.039194 -88.974422)
		(end 98.517456 -74.005948)
		(width 0.14224)
		(layer "In2.Cu")
		(net "CLK_100M_CPU1_CLK12_DP")
	)
	(segment
		(start 7.920736 -191.072516)
		(end 8.835644 -185.884312)
		(width 0.14224)
		(layer "In2.Cu")
		(net "CLK_100M_CPU1_CLK12_DP")
	)
	(segment
		(start 8.835644 -185.884312)
		(end 11.001756 -182.790846)
		(width 0.14224)
		(layer "In2.Cu")
		(net "CLK_100M_CPU1_CLK12_DP")
	)
	(segment
		(start 161.216594 -56.968898)
		(end 164.937694 -56.31307)
		(width 0.14224)
		(layer "In2.Cu")
		(net "CLK_100M_CPU1_CLK12_DP")
	)
	(segment
		(start 30.877764 -371.875812)
		(end 29.399738 -371.875812)
		(width 0.14224)
		(layer "In2.Cu")
		(net "CLK_100M_CPU1_CLK12_DP")
	)
	(segment
		(start 158.756604 -58.691526)
		(end 161.216594 -56.968898)
		(width 0.14224)
		(layer "In2.Cu")
		(net "CLK_100M_CPU1_CLK12_DP")
	)
	(segment
		(start 176.09185 -42.908982)
		(end 178.721004 -42.908982)
		(width 0.14224)
		(layer "In2.Cu")
		(net "CLK_100M_CPU1_CLK12_DP")
	)
	(segment
		(start 153.90241 -59.547506)
		(end 158.756604 -58.691526)
		(width 0.14224)
		(layer "In2.Cu")
		(net "CLK_100M_CPU1_CLK12_DP")
	)
	(segment
		(start 98.517456 -74.005948)
		(end 112.465104 -64.240156)
		(width 0.14224)
		(layer "In2.Cu")
		(net "CLK_100M_CPU1_CLK12_DP")
	)
	(segment
		(start 15.6972 -352.31578)
		(end 15.6972 -345.43238)
		(width 0.14224)
		(layer "In2.Cu")
		(net "CLK_100M_CPU1_CLK12_DP")
	)
	(segment
		(start 11.001756 -182.790592)
		(end 13.11402 -179.774088)
		(width 0.14224)
		(layer "In2.Cu")
		(net "CLK_100M_CPU1_CLK12_DP")
	)
	(segment
		(start 138.805666 -367.830354)
		(end 44.26839 -367.830354)
		(width 0.14224)
		(layer "In2.Cu")
		(net "CLK_100M_CPU1_CLK12_DP")
	)
	(segment
		(start 20.56892 -161.77641)
		(end 21.669248 -155.536392)
		(width 0.14224)
		(layer "In2.Cu")
		(net "CLK_100M_CPU1_CLK12_DP")
	)
	(segment
		(start 15.6972 -345.43238)
		(end 10.863834 -340.599014)
		(width 0.14224)
		(layer "In2.Cu")
		(net "CLK_100M_CPU1_CLK12_DP")
	)
	(segment
		(start 31.626302 -371.127274)
		(end 30.877764 -371.875812)
		(width 0.14224)
		(layer "In2.Cu")
		(net "CLK_100M_CPU1_CLK12_DP")
	)
	(segment
		(start 11.001756 -182.790846)
		(end 11.001756 -182.790592)
		(width 0.14224)
		(layer "In2.Cu")
		(net "CLK_100M_CPU1_CLK12_DP")
	)
	(segment
		(start 123.47829 -343.262966)
		(end 123.47829 -346.394278)
		(width 0.12954)
		(layer "F.Cu")
		(net "CLK_100M_CPU1_CLK12_DN")
	)
	(segment
		(start 123.66879 -347.743018)
		(end 123.66879 -348.131638)
		(width 0.12954)
		(layer "F.Cu")
		(net "CLK_100M_CPU1_CLK12_DN")
	)
	(segment
		(start 123.47829 -347.552518)
		(end 123.66879 -347.743018)
		(width 0.12954)
		(layer "F.Cu")
		(net "CLK_100M_CPU1_CLK12_DN")
	)
	(segment
		(start 123.47829 -348.322138)
		(end 123.47829 -348.710758)
		(width 0.12954)
		(layer "F.Cu")
		(net "CLK_100M_CPU1_CLK12_DN")
	)
	(segment
		(start 123.66879 -346.584778)
		(end 123.66879 -346.973398)
		(width 0.12954)
		(layer "F.Cu")
		(net "CLK_100M_CPU1_CLK12_DN")
	)
	(segment
		(start 177.786538 -43.299888)
		(end 177.875184 -43.211242)
		(width 0.12954)
		(layer "F.Cu")
		(net "CLK_100M_CPU1_CLK12_DN")
	)
	(segment
		(start 141.374876 -369.81638)
		(end 141.683994 -369.81638)
		(width 0.12954)
		(layer "F.Cu")
		(net "CLK_100M_CPU1_CLK12_DN")
	)
	(segment
		(start 123.47829 -322.402708)
		(end 123.47829 -343.262966)
		(width 0.12954)
		(layer "F.Cu")
		(net "CLK_100M_CPU1_CLK12_DN")
	)
	(segment
		(start 123.47829 -346.394278)
		(end 123.66879 -346.584778)
		(width 0.12954)
		(layer "F.Cu")
		(net "CLK_100M_CPU1_CLK12_DN")
	)
	(segment
		(start 178.741324 -43.211242)
		(end 179.011834 -43.481752)
		(width 0.12954)
		(layer "F.Cu")
		(net "CLK_100M_CPU1_CLK12_DN")
	)
	(segment
		(start 177.108358 -43.299888)
		(end 177.786538 -43.299888)
		(width 0.12954)
		(layer "F.Cu")
		(net "CLK_100M_CPU1_CLK12_DN")
	)
	(segment
		(start 177.875184 -43.211242)
		(end 178.741324 -43.211242)
		(width 0.12954)
		(layer "F.Cu")
		(net "CLK_100M_CPU1_CLK12_DN")
	)
	(segment
		(start 123.825 -322.055998)
		(end 123.47829 -322.402708)
		(width 0.12954)
		(layer "F.Cu")
		(net "CLK_100M_CPU1_CLK12_DN")
	)
	(segment
		(start 123.47829 -349.480378)
		(end 123.47829 -349.868998)
		(width 0.12954)
		(layer "F.Cu")
		(net "CLK_100M_CPU1_CLK12_DN")
	)
	(segment
		(start 123.66879 -348.131638)
		(end 123.47829 -348.322138)
		(width 0.12954)
		(layer "F.Cu")
		(net "CLK_100M_CPU1_CLK12_DN")
	)
	(segment
		(start 123.66879 -348.901258)
		(end 123.66879 -349.289878)
		(width 0.12954)
		(layer "F.Cu")
		(net "CLK_100M_CPU1_CLK12_DN")
	)
	(segment
		(start 141.113764 -367.504472)
		(end 141.113764 -369.555268)
		(width 0.12954)
		(layer "F.Cu")
		(net "CLK_100M_CPU1_CLK12_DN")
	)
	(segment
		(start 123.47829 -348.710758)
		(end 123.66879 -348.901258)
		(width 0.12954)
		(layer "F.Cu")
		(net "CLK_100M_CPU1_CLK12_DN")
	)
	(segment
		(start 123.66879 -346.973398)
		(end 123.47829 -347.163898)
		(width 0.12954)
		(layer "F.Cu")
		(net "CLK_100M_CPU1_CLK12_DN")
	)
	(segment
		(start 141.683994 -369.81638)
		(end 141.954504 -369.54587)
		(width 0.12954)
		(layer "F.Cu")
		(net "CLK_100M_CPU1_CLK12_DN")
	)
	(segment
		(start 123.66879 -349.289878)
		(end 123.47829 -349.480378)
		(width 0.12954)
		(layer "F.Cu")
		(net "CLK_100M_CPU1_CLK12_DN")
	)
	(segment
		(start 141.113764 -369.555268)
		(end 141.374876 -369.81638)
		(width 0.12954)
		(layer "F.Cu")
		(net "CLK_100M_CPU1_CLK12_DN")
	)
	(segment
		(start 123.47829 -347.163898)
		(end 123.47829 -347.552518)
		(width 0.12954)
		(layer "F.Cu")
		(net "CLK_100M_CPU1_CLK12_DN")
	)
	(segment
		(start 123.47829 -349.868998)
		(end 141.113764 -367.504472)
		(width 0.12954)
		(layer "F.Cu")
		(net "CLK_100M_CPU1_CLK12_DN")
	)
	(via
		(at 123.47829 -343.262966)
		(size 0.4064)
		(drill 0.2032)
		(layers "F.Cu" "B.Cu")
		(net "CLK_100M_CPU1_CLK12_DN")
	)
	(via
		(at 179.011834 -43.481752)
		(size 0.508)
		(drill 0.254)
		(layers "F.Cu" "B.Cu")
		(net "CLK_100M_CPU1_CLK12_DN")
	)
	(via
		(at 141.954504 -369.54587)
		(size 0.508)
		(drill 0.254)
		(layers "F.Cu" "B.Cu")
		(net "CLK_100M_CPU1_CLK12_DN")
	)
	(segment
		(start 178.721004 -43.190922)
		(end 179.011834 -43.481752)
		(width 0.14224)
		(layer "In2.Cu")
		(net "CLK_100M_CPU1_CLK12_DN")
	)
	(segment
		(start 40.85463 -370.845334)
		(end 31.509462 -370.845334)
		(width 0.14224)
		(layer "In2.Cu")
		(net "CLK_100M_CPU1_CLK12_DN")
	)
	(segment
		(start 30.387036 -145.144998)
		(end 30.734254 -144.90192)
		(width 0.14224)
		(layer "In2.Cu")
		(net "CLK_100M_CPU1_CLK12_DN")
	)
	(segment
		(start 141.954504 -369.54587)
		(end 141.663674 -369.8367)
		(width 0.14224)
		(layer "In2.Cu")
		(net "CLK_100M_CPU1_CLK12_DN")
	)
	(segment
		(start 13.36294 -179.91074)
		(end 14.765782 -176.523904)
		(width 0.14224)
		(layer "In2.Cu")
		(net "CLK_100M_CPU1_CLK12_DN")
	)
	(segment
		(start 141.663674 -369.8367)
		(end 141.210792 -369.8367)
		(width 0.14224)
		(layer "In2.Cu")
		(net "CLK_100M_CPU1_CLK12_DN")
	)
	(segment
		(start 16.492728 -172.355256)
		(end 16.672306 -172.281088)
		(width 0.14224)
		(layer "In2.Cu")
		(net "CLK_100M_CPU1_CLK12_DN")
	)
	(segment
		(start 11.145774 -340.482174)
		(end 11.145774 -314.886594)
		(width 0.14224)
		(layer "In2.Cu")
		(net "CLK_100M_CPU1_CLK12_DN")
	)
	(segment
		(start 9.67486 -252.999748)
		(end 8.203438 -191.093852)
		(width 0.14224)
		(layer "In2.Cu")
		(net "CLK_100M_CPU1_CLK12_DN")
	)
	(segment
		(start 16.32966 -172.749464)
		(end 16.492728 -172.355256)
		(width 0.14224)
		(layer "In2.Cu")
		(net "CLK_100M_CPU1_CLK12_DN")
	)
	(segment
		(start 9.102598 -185.994802)
		(end 13.36294 -179.91074)
		(width 0.14224)
		(layer "In2.Cu")
		(net "CLK_100M_CPU1_CLK12_DN")
	)
	(segment
		(start 16.403828 -172.928788)
		(end 16.32966 -172.749464)
		(width 0.14224)
		(layer "In2.Cu")
		(net "CLK_100M_CPU1_CLK12_DN")
	)
	(segment
		(start 20.841462 -161.855912)
		(end 21.94179 -155.615894)
		(width 0.14224)
		(layer "In2.Cu")
		(net "CLK_100M_CPU1_CLK12_DN")
	)
	(segment
		(start 30.760924 -371.593872)
		(end 29.516578 -371.593872)
		(width 0.14224)
		(layer "In2.Cu")
		(net "CLK_100M_CPU1_CLK12_DN")
	)
	(segment
		(start 16.672306 -172.281088)
		(end 16.835628 -171.886626)
		(width 0.14224)
		(layer "In2.Cu")
		(net "CLK_100M_CPU1_CLK12_DN")
	)
	(segment
		(start 24.09698 -150.413212)
		(end 25.28316 -148.719032)
		(width 0.14224)
		(layer "In2.Cu")
		(net "CLK_100M_CPU1_CLK12_DN")
	)
	(segment
		(start 29.086048 -146.223736)
		(end 29.433774 -145.980404)
		(width 0.14224)
		(layer "In2.Cu")
		(net "CLK_100M_CPU1_CLK12_DN")
	)
	(segment
		(start 44.399454 -127.256286)
		(end 63.611252 -113.803938)
		(width 0.14224)
		(layer "In2.Cu")
		(net "CLK_100M_CPU1_CLK12_DN")
	)
	(segment
		(start 141.210792 -369.8367)
		(end 138.922506 -367.548414)
		(width 0.14224)
		(layer "In2.Cu")
		(net "CLK_100M_CPU1_CLK12_DN")
	)
	(segment
		(start 21.94179 -155.615894)
		(end 24.09698 -150.413212)
		(width 0.14224)
		(layer "In2.Cu")
		(net "CLK_100M_CPU1_CLK12_DN")
	)
	(segment
		(start 15.46606 -174.833788)
		(end 15.629128 -174.43958)
		(width 0.14224)
		(layer "In2.Cu")
		(net "CLK_100M_CPU1_CLK12_DN")
	)
	(segment
		(start 28.331414 -370.408708)
		(end 19.773646 -370.408708)
		(width 0.14224)
		(layer "In2.Cu")
		(net "CLK_100M_CPU1_CLK12_DN")
	)
	(segment
		(start 16.761206 -171.707302)
		(end 20.841462 -161.855912)
		(width 0.14224)
		(layer "In2.Cu")
		(net "CLK_100M_CPU1_CLK12_DN")
	)
	(segment
		(start 16.835628 -171.886626)
		(end 16.761206 -171.707302)
		(width 0.14224)
		(layer "In2.Cu")
		(net "CLK_100M_CPU1_CLK12_DN")
	)
	(segment
		(start 30.925516 -144.935448)
		(end 31.273242 -144.691862)
		(width 0.14224)
		(layer "In2.Cu")
		(net "CLK_100M_CPU1_CLK12_DN")
	)
	(segment
		(start 153.94178 -59.826906)
		(end 158.867094 -58.95848)
		(width 0.14224)
		(layer "In2.Cu")
		(net "CLK_100M_CPU1_CLK12_DN")
	)
	(segment
		(start 158.867094 -58.95848)
		(end 161.327084 -57.235852)
		(width 0.14224)
		(layer "In2.Cu")
		(net "CLK_100M_CPU1_CLK12_DN")
	)
	(segment
		(start 11.145774 -314.886594)
		(end 9.67486 -253.004828)
		(width 0.14224)
		(layer "In2.Cu")
		(net "CLK_100M_CPU1_CLK12_DN")
	)
	(segment
		(start 15.808706 -174.365412)
		(end 15.972028 -173.97095)
		(width 0.14224)
		(layer "In2.Cu")
		(net "CLK_100M_CPU1_CLK12_DN")
	)
	(segment
		(start 15.97914 -352.19894)
		(end 15.97914 -345.31554)
		(width 0.14224)
		(layer "In2.Cu")
		(net "CLK_100M_CPU1_CLK12_DN")
	)
	(segment
		(start 15.540228 -175.013112)
		(end 15.46606 -174.833788)
		(width 0.14224)
		(layer "In2.Cu")
		(net "CLK_100M_CPU1_CLK12_DN")
	)
	(segment
		(start 171.973748 -47.425864)
		(end 176.20869 -43.190922)
		(width 0.14224)
		(layer "In2.Cu")
		(net "CLK_100M_CPU1_CLK12_DN")
	)
	(segment
		(start 15.629128 -174.43958)
		(end 15.808706 -174.365412)
		(width 0.14224)
		(layer "In2.Cu")
		(net "CLK_100M_CPU1_CLK12_DN")
	)
	(segment
		(start 15.197328 -175.481742)
		(end 15.376906 -175.407574)
		(width 0.14224)
		(layer "In2.Cu")
		(net "CLK_100M_CPU1_CLK12_DN")
	)
	(segment
		(start 30.005782 -145.579592)
		(end 30.353508 -145.336006)
		(width 0.14224)
		(layer "In2.Cu")
		(net "CLK_100M_CPU1_CLK12_DN")
	)
	(segment
		(start 31.509462 -370.845334)
		(end 30.760924 -371.593872)
		(width 0.14224)
		(layer "In2.Cu")
		(net "CLK_100M_CPU1_CLK12_DN")
	)
	(segment
		(start 29.433774 -145.980404)
		(end 29.467302 -145.789142)
		(width 0.14224)
		(layer "In2.Cu")
		(net "CLK_100M_CPU1_CLK12_DN")
	)
	(segment
		(start 25.28316 -148.719032)
		(end 28.894786 -146.190208)
		(width 0.14224)
		(layer "In2.Cu")
		(net "CLK_100M_CPU1_CLK12_DN")
	)
	(segment
		(start 161.327084 -57.235852)
		(end 165.017196 -56.585612)
		(width 0.14224)
		(layer "In2.Cu")
		(net "CLK_100M_CPU1_CLK12_DN")
	)
	(segment
		(start 35.109658 -141.838172)
		(end 44.399454 -127.256286)
		(width 0.14224)
		(layer "In2.Cu")
		(net "CLK_100M_CPU1_CLK12_DN")
	)
	(segment
		(start 14.945106 -176.449736)
		(end 15.108428 -176.055274)
		(width 0.14224)
		(layer "In2.Cu")
		(net "CLK_100M_CPU1_CLK12_DN")
	)
	(segment
		(start 30.734254 -144.90192)
		(end 30.925516 -144.935448)
		(width 0.14224)
		(layer "In2.Cu")
		(net "CLK_100M_CPU1_CLK12_DN")
	)
	(segment
		(start 15.89786 -173.791626)
		(end 16.060928 -173.397418)
		(width 0.14224)
		(layer "In2.Cu")
		(net "CLK_100M_CPU1_CLK12_DN")
	)
	(segment
		(start 14.765782 -176.523904)
		(end 14.945106 -176.449736)
		(width 0.14224)
		(layer "In2.Cu")
		(net "CLK_100M_CPU1_CLK12_DN")
	)
	(segment
		(start 28.894786 -146.190208)
		(end 29.086048 -146.223736)
		(width 0.14224)
		(layer "In2.Cu")
		(net "CLK_100M_CPU1_CLK12_DN")
	)
	(segment
		(start 17.646904 -368.281966)
		(end 17.646904 -353.866704)
		(width 0.14224)
		(layer "In2.Cu")
		(net "CLK_100M_CPU1_CLK12_DN")
	)
	(segment
		(start 165.017196 -56.585612)
		(end 168.338754 -55.209948)
		(width 0.14224)
		(layer "In2.Cu")
		(net "CLK_100M_CPU1_CLK12_DN")
	)
	(segment
		(start 15.376906 -175.407574)
		(end 15.540228 -175.013112)
		(width 0.14224)
		(layer "In2.Cu")
		(net "CLK_100M_CPU1_CLK12_DN")
	)
	(segment
		(start 29.467302 -145.789142)
		(end 29.81452 -145.546064)
		(width 0.14224)
		(layer "In2.Cu")
		(net "CLK_100M_CPU1_CLK12_DN")
	)
	(segment
		(start 16.060928 -173.397418)
		(end 16.240506 -173.32325)
		(width 0.14224)
		(layer "In2.Cu")
		(net "CLK_100M_CPU1_CLK12_DN")
	)
	(segment
		(start 138.922506 -367.548414)
		(end 44.15155 -367.548414)
		(width 0.14224)
		(layer "In2.Cu")
		(net "CLK_100M_CPU1_CLK12_DN")
	)
	(segment
		(start 169.03954 -54.509162)
		(end 171.973748 -47.425864)
		(width 0.14224)
		(layer "In2.Cu")
		(net "CLK_100M_CPU1_CLK12_DN")
	)
	(segment
		(start 19.773646 -370.408708)
		(end 17.646904 -368.281966)
		(width 0.14224)
		(layer "In2.Cu")
		(net "CLK_100M_CPU1_CLK12_DN")
	)
	(segment
		(start 98.720148 -74.20864)
		(end 112.575594 -64.50711)
		(width 0.14224)
		(layer "In2.Cu")
		(net "CLK_100M_CPU1_CLK12_DN")
	)
	(segment
		(start 31.273242 -144.691862)
		(end 31.30677 -144.501108)
		(width 0.14224)
		(layer "In2.Cu")
		(net "CLK_100M_CPU1_CLK12_DN")
	)
	(segment
		(start 15.108428 -176.055274)
		(end 15.03426 -175.87595)
		(width 0.14224)
		(layer "In2.Cu")
		(net "CLK_100M_CPU1_CLK12_DN")
	)
	(segment
		(start 31.30677 -144.501108)
		(end 35.109658 -141.838172)
		(width 0.14224)
		(layer "In2.Cu")
		(net "CLK_100M_CPU1_CLK12_DN")
	)
	(segment
		(start 15.972028 -173.97095)
		(end 15.89786 -173.791626)
		(width 0.14224)
		(layer "In2.Cu")
		(net "CLK_100M_CPU1_CLK12_DN")
	)
	(segment
		(start 15.03426 -175.87595)
		(end 15.197328 -175.481742)
		(width 0.14224)
		(layer "In2.Cu")
		(net "CLK_100M_CPU1_CLK12_DN")
	)
	(segment
		(start 88.25611 -89.156286)
		(end 98.720148 -74.20864)
		(width 0.14224)
		(layer "In2.Cu")
		(net "CLK_100M_CPU1_CLK12_DN")
	)
	(segment
		(start 116.656612 -63.787528)
		(end 153.94178 -59.826906)
		(width 0.14224)
		(layer "In2.Cu")
		(net "CLK_100M_CPU1_CLK12_DN")
	)
	(segment
		(start 29.516578 -371.593872)
		(end 28.331414 -370.408708)
		(width 0.14224)
		(layer "In2.Cu")
		(net "CLK_100M_CPU1_CLK12_DN")
	)
	(segment
		(start 44.15155 -367.548414)
		(end 40.85463 -370.845334)
		(width 0.14224)
		(layer "In2.Cu")
		(net "CLK_100M_CPU1_CLK12_DN")
	)
	(segment
		(start 16.240506 -173.32325)
		(end 16.403828 -172.928788)
		(width 0.14224)
		(layer "In2.Cu")
		(net "CLK_100M_CPU1_CLK12_DN")
	)
	(segment
		(start 63.611252 -113.803938)
		(end 88.25611 -89.156286)
		(width 0.14224)
		(layer "In2.Cu")
		(net "CLK_100M_CPU1_CLK12_DN")
	)
	(segment
		(start 29.81452 -145.546064)
		(end 30.005782 -145.579592)
		(width 0.14224)
		(layer "In2.Cu")
		(net "CLK_100M_CPU1_CLK12_DN")
	)
	(segment
		(start 17.646904 -353.866704)
		(end 15.97914 -352.19894)
		(width 0.14224)
		(layer "In2.Cu")
		(net "CLK_100M_CPU1_CLK12_DN")
	)
	(segment
		(start 15.97914 -345.31554)
		(end 11.145774 -340.482174)
		(width 0.14224)
		(layer "In2.Cu")
		(net "CLK_100M_CPU1_CLK12_DN")
	)
	(segment
		(start 9.67486 -253.004828)
		(end 9.67486 -252.999748)
		(width 0.14224)
		(layer "In2.Cu")
		(net "CLK_100M_CPU1_CLK12_DN")
	)
	(segment
		(start 176.20869 -43.190922)
		(end 178.721004 -43.190922)
		(width 0.14224)
		(layer "In2.Cu")
		(net "CLK_100M_CPU1_CLK12_DN")
	)
	(segment
		(start 112.575594 -64.50711)
		(end 116.656612 -63.787528)
		(width 0.14224)
		(layer "In2.Cu")
		(net "CLK_100M_CPU1_CLK12_DN")
	)
	(segment
		(start 30.353508 -145.336006)
		(end 30.387036 -145.144998)
		(width 0.14224)
		(layer "In2.Cu")
		(net "CLK_100M_CPU1_CLK12_DN")
	)
	(segment
		(start 8.203438 -191.093852)
		(end 9.102598 -185.994802)
		(width 0.14224)
		(layer "In2.Cu")
		(net "CLK_100M_CPU1_CLK12_DN")
	)
	(segment
		(start 168.338754 -55.209948)
		(end 169.03954 -54.509162)
		(width 0.14224)
		(layer "In2.Cu")
		(net "CLK_100M_CPU1_CLK12_DN")
	)
	(segment
		(start 139.037822 -222.880428)
		(end 138.879326 -223.153732)
		(width 0.0762)
		(layer "F.Cu")
		(net "CLK_100M_CPU1_CLK05_R_DP")
	)
	(segment
		(start 139.2555 -223.185228)
		(end 139.25677 -223.184466)
		(width 0.0762)
		(layer "F.Cu")
		(net "CLK_100M_CPU1_CLK05_R_DP")
	)
	(segment
		(start 137.220452 -210.428332)
		(end 150.759668 -196.889116)
		(width 0.12954)
		(layer "F.Cu")
		(net "CLK_100M_CPU1_CLK05_R_DP")
	)
	(segment
		(start 138.866372 -221.193614)
		(end 138.866372 -221.174564)
		(width 0.0762)
		(layer "F.Cu")
		(net "CLK_100M_CPU1_CLK05_R_DP")
	)
	(segment
		(start 151.600916 -192.10147)
		(end 151.254206 -191.75476)
		(width 0.12954)
		(layer "F.Cu")
		(net "CLK_100M_CPU1_CLK05_R_DP")
	)
	(segment
		(start 138.866372 -219.50553)
		(end 138.866372 -219.11945)
		(width 0.12954)
		(layer "F.Cu")
		(net "CLK_100M_CPU1_CLK05_R_DP")
	)
	(segment
		(start 138.932412 -221.259654)
		(end 138.866372 -221.193614)
		(width 0.0762)
		(layer "F.Cu")
		(net "CLK_100M_CPU1_CLK05_R_DP")
	)
	(segment
		(start 139.22502 -222.557848)
		(end 139.185904 -222.534988)
		(width 0.0762)
		(layer "F.Cu")
		(net "CLK_100M_CPU1_CLK05_R_DP")
	)
	(segment
		(start 139.22502 -223.203008)
		(end 139.2555 -223.185228)
		(width 0.0762)
		(layer "F.Cu")
		(net "CLK_100M_CPU1_CLK05_R_DP")
	)
	(segment
		(start 138.866372 -217.971878)
		(end 137.220452 -213.99881)
		(width 0.12954)
		(layer "F.Cu")
		(net "CLK_100M_CPU1_CLK05_R_DP")
	)
	(segment
		(start 138.675872 -218.54287)
		(end 138.866372 -218.35237)
		(width 0.12954)
		(layer "F.Cu")
		(net "CLK_100M_CPU1_CLK05_R_DP")
	)
	(segment
		(start 138.942826 -221.77629)
		(end 138.932412 -221.543118)
		(width 0.0762)
		(layer "F.Cu")
		(net "CLK_100M_CPU1_CLK05_R_DP")
	)
	(segment
		(start 138.675872 -220.08211)
		(end 138.675872 -219.69603)
		(width 0.12954)
		(layer "F.Cu")
		(net "CLK_100M_CPU1_CLK05_R_DP")
	)
	(segment
		(start 138.866372 -219.11945)
		(end 138.675872 -218.92895)
		(width 0.12954)
		(layer "F.Cu")
		(net "CLK_100M_CPU1_CLK05_R_DP")
	)
	(segment
		(start 138.866372 -221.174564)
		(end 138.866372 -220.27261)
		(width 0.12954)
		(layer "F.Cu")
		(net "CLK_100M_CPU1_CLK05_R_DP")
	)
	(segment
		(start 138.942572 -222.070422)
		(end 138.942826 -222.070422)
		(width 0.0762)
		(layer "F.Cu")
		(net "CLK_100M_CPU1_CLK05_R_DP")
	)
	(segment
		(start 138.675872 -219.69603)
		(end 138.866372 -219.50553)
		(width 0.12954)
		(layer "F.Cu")
		(net "CLK_100M_CPU1_CLK05_R_DP")
	)
	(segment
		(start 151.600916 -194.858132)
		(end 151.600916 -194.437)
		(width 0.12954)
		(layer "F.Cu")
		(net "CLK_100M_CPU1_CLK05_R_DP")
	)
	(segment
		(start 150.759668 -196.889116)
		(end 151.600916 -194.858132)
		(width 0.12954)
		(layer "F.Cu")
		(net "CLK_100M_CPU1_CLK05_R_DP")
	)
	(segment
		(start 138.866372 -218.35237)
		(end 138.866372 -217.971878)
		(width 0.12954)
		(layer "F.Cu")
		(net "CLK_100M_CPU1_CLK05_R_DP")
	)
	(segment
		(start 138.675872 -218.92895)
		(end 138.675872 -218.54287)
		(width 0.12954)
		(layer "F.Cu")
		(net "CLK_100M_CPU1_CLK05_R_DP")
	)
	(segment
		(start 138.866372 -220.27261)
		(end 138.675872 -220.08211)
		(width 0.12954)
		(layer "F.Cu")
		(net "CLK_100M_CPU1_CLK05_R_DP")
	)
	(segment
		(start 138.942826 -222.070422)
		(end 138.942826 -221.77629)
		(width 0.0762)
		(layer "F.Cu")
		(net "CLK_100M_CPU1_CLK05_R_DP")
	)
	(segment
		(start 138.879326 -223.153732)
		(end 138.898884 -223.226376)
		(width 0.0762)
		(layer "F.Cu")
		(net "CLK_100M_CPU1_CLK05_R_DP")
	)
	(segment
		(start 138.932412 -221.543118)
		(end 138.932412 -221.259654)
		(width 0.0762)
		(layer "F.Cu")
		(net "CLK_100M_CPU1_CLK05_R_DP")
	)
	(segment
		(start 137.220452 -213.99881)
		(end 137.220452 -210.428332)
		(width 0.12954)
		(layer "F.Cu")
		(net "CLK_100M_CPU1_CLK05_R_DP")
	)
	(segment
		(start 139.251182 -222.57258)
		(end 139.22502 -222.557848)
		(width 0.0762)
		(layer "F.Cu")
		(net "CLK_100M_CPU1_CLK05_R_DP")
	)
	(segment
		(start 151.600916 -194.437)
		(end 151.600916 -192.10147)
		(width 0.12954)
		(layer "F.Cu")
		(net "CLK_100M_CPU1_CLK05_R_DP")
	)
	(via
		(at 151.600916 -194.437)
		(size 0.4064)
		(drill 0.2032)
		(layers "F.Cu" "B.Cu")
		(net "CLK_100M_CPU1_CLK05_R_DP")
	)
	(arc
		(start 139.25677 -223.184466)
		(mid 139.412582 -222.877046)
		(end 139.251182 -222.57258)
		(width 0.0762)
		(layer "F.Cu")
		(net "CLK_100M_CPU1_CLK05_R_DP")
	)
	(arc
		(start 139.185904 -222.534988)
		(mid 139.007091 -222.332638)
		(end 138.942572 -222.070422)
		(width 0.0762)
		(layer "F.Cu")
		(net "CLK_100M_CPU1_CLK05_R_DP")
	)
	(arc
		(start 138.898884 -223.226376)
		(mid 139.06466 -223.252379)
		(end 139.22502 -223.203008)
		(width 0.0762)
		(layer "F.Cu")
		(net "CLK_100M_CPU1_CLK05_R_DP")
	)
	(segment
		(start 151.923496 -192.913)
		(end 151.923496 -192.10147)
		(width 0.12954)
		(layer "F.Cu")
		(net "CLK_100M_CPU1_CLK05_R_DN")
	)
	(segment
		(start 139.359894 -222.415862)
		(end 139.359386 -222.415608)
		(width 0.0762)
		(layer "F.Cu")
		(net "CLK_100M_CPU1_CLK05_R_DN")
	)
	(segment
		(start 138.726418 -223.41713)
		(end 138.80846 -223.39554)
		(width 0.0762)
		(layer "F.Cu")
		(net "CLK_100M_CPU1_CLK05_R_DN")
	)
	(segment
		(start 139.320778 -223.367854)
		(end 139.359894 -223.344994)
		(width 0.0762)
		(layer "F.Cu")
		(net "CLK_100M_CPU1_CLK05_R_DN")
	)
	(segment
		(start 139.188952 -221.193614)
		(end 139.188952 -221.174564)
		(width 0.0762)
		(layer "F.Cu")
		(net "CLK_100M_CPU1_CLK05_R_DN")
	)
	(segment
		(start 151.923496 -194.922394)
		(end 151.923496 -192.913)
		(width 0.12954)
		(layer "F.Cu")
		(net "CLK_100M_CPU1_CLK05_R_DN")
	)
	(segment
		(start 151.923496 -192.10147)
		(end 152.270206 -191.75476)
		(width 0.12954)
		(layer "F.Cu")
		(net "CLK_100M_CPU1_CLK05_R_DN")
	)
	(segment
		(start 137.543032 -210.56219)
		(end 151.033226 -197.071996)
		(width 0.12954)
		(layer "F.Cu")
		(net "CLK_100M_CPU1_CLK05_R_DN")
	)
	(segment
		(start 139.133326 -222.070422)
		(end 139.133326 -221.771972)
		(width 0.0762)
		(layer "F.Cu")
		(net "CLK_100M_CPU1_CLK05_R_DN")
	)
	(segment
		(start 139.320778 -222.393002)
		(end 139.290298 -222.375222)
		(width 0.0762)
		(layer "F.Cu")
		(net "CLK_100M_CPU1_CLK05_R_DN")
	)
	(segment
		(start 151.033226 -197.071996)
		(end 151.923496 -194.922394)
		(width 0.12954)
		(layer "F.Cu")
		(net "CLK_100M_CPU1_CLK05_R_DN")
	)
	(segment
		(start 138.567922 -223.690434)
		(end 138.726418 -223.41713)
		(width 0.0762)
		(layer "F.Cu")
		(net "CLK_100M_CPU1_CLK05_R_DN")
	)
	(segment
		(start 139.359386 -222.415608)
		(end 139.320778 -222.393002)
		(width 0.0762)
		(layer "F.Cu")
		(net "CLK_100M_CPU1_CLK05_R_DN")
	)
	(segment
		(start 139.188952 -217.907616)
		(end 137.543032 -213.934548)
		(width 0.12954)
		(layer "F.Cu")
		(net "CLK_100M_CPU1_CLK05_R_DN")
	)
	(segment
		(start 137.543032 -213.934548)
		(end 137.543032 -210.56219)
		(width 0.12954)
		(layer "F.Cu")
		(net "CLK_100M_CPU1_CLK05_R_DN")
	)
	(segment
		(start 139.122912 -221.259654)
		(end 139.188952 -221.193614)
		(width 0.0762)
		(layer "F.Cu")
		(net "CLK_100M_CPU1_CLK05_R_DN")
	)
	(segment
		(start 139.188952 -221.174564)
		(end 139.188952 -217.907616)
		(width 0.12954)
		(layer "F.Cu")
		(net "CLK_100M_CPU1_CLK05_R_DN")
	)
	(segment
		(start 139.122912 -221.5388)
		(end 139.122912 -221.259654)
		(width 0.0762)
		(layer "F.Cu")
		(net "CLK_100M_CPU1_CLK05_R_DN")
	)
	(segment
		(start 139.133326 -221.771972)
		(end 139.122912 -221.5388)
		(width 0.0762)
		(layer "F.Cu")
		(net "CLK_100M_CPU1_CLK05_R_DN")
	)
	(via
		(at 151.923496 -192.913)
		(size 0.4064)
		(drill 0.2032)
		(layers "F.Cu" "B.Cu")
		(net "CLK_100M_CPU1_CLK05_R_DN")
	)
	(arc
		(start 139.359894 -223.344994)
		(mid 139.603221 -222.880428)
		(end 139.359894 -222.415862)
		(width 0.0762)
		(layer "F.Cu")
		(net "CLK_100M_CPU1_CLK05_R_DN")
	)
	(arc
		(start 138.80846 -223.39554)
		(mid 139.067956 -223.443395)
		(end 139.320778 -223.367854)
		(width 0.0762)
		(layer "F.Cu")
		(net "CLK_100M_CPU1_CLK05_R_DN")
	)
	(arc
		(start 139.290298 -222.375222)
		(mid 139.174871 -222.241846)
		(end 139.133326 -222.070422)
		(width 0.0762)
		(layer "F.Cu")
		(net "CLK_100M_CPU1_CLK05_R_DN")
	)
	(segment
		(start 71.461884 -7.748778)
		(end 71.461884 -8.320024)
		(width 0.12954)
		(layer "F.Cu")
		(net "CLK_100M_CPU1_CLK05_DP")
	)
	(segment
		(start 151.600916 -164.260276)
		(end 151.600916 -190.60795)
		(width 0.12954)
		(layer "F.Cu")
		(net "CLK_100M_CPU1_CLK05_DP")
	)
	(segment
		(start 71.600822 -7.60984)
		(end 71.461884 -7.748778)
		(width 0.12954)
		(layer "F.Cu")
		(net "CLK_100M_CPU1_CLK05_DP")
	)
	(segment
		(start 71.600822 -6.858)
		(end 71.600822 -7.60984)
		(width 0.12954)
		(layer "F.Cu")
		(net "CLK_100M_CPU1_CLK05_DP")
	)
	(segment
		(start 164.508942 -151.35225)
		(end 151.600916 -164.260276)
		(width 0.12954)
		(layer "F.Cu")
		(net "CLK_100M_CPU1_CLK05_DP")
	)
	(segment
		(start 164.174932 -149.940264)
		(end 164.508942 -150.274274)
		(width 0.12954)
		(layer "F.Cu")
		(net "CLK_100M_CPU1_CLK05_DP")
	)
	(segment
		(start 151.600916 -190.60795)
		(end 151.254206 -190.95466)
		(width 0.12954)
		(layer "F.Cu")
		(net "CLK_100M_CPU1_CLK05_DP")
	)
	(segment
		(start 164.508942 -150.274274)
		(end 164.508942 -151.35225)
		(width 0.12954)
		(layer "F.Cu")
		(net "CLK_100M_CPU1_CLK05_DP")
	)
	(segment
		(start 71.330312 -6.58749)
		(end 71.600822 -6.858)
		(width 0.12954)
		(layer "F.Cu")
		(net "CLK_100M_CPU1_CLK05_DP")
	)
	(via
		(at 164.174932 -149.940264)
		(size 0.508)
		(drill 0.254)
		(layers "F.Cu" "B.Cu")
		(net "CLK_100M_CPU1_CLK05_DP")
	)
	(via
		(at 71.330312 -6.58749)
		(size 0.508)
		(drill 0.254)
		(layers "F.Cu" "B.Cu")
		(net "CLK_100M_CPU1_CLK05_DP")
	)
	(segment
		(start 71.790814 -17.613884)
		(end 71.790814 -23.753064)
		(width 0.14224)
		(layer "In11.Cu")
		(net "CLK_100M_CPU1_CLK05_DP")
	)
	(segment
		(start 79.286862 -36.546282)
		(end 79.286862 -46.519846)
		(width 0.14224)
		(layer "In11.Cu")
		(net "CLK_100M_CPU1_CLK05_DP")
	)
	(segment
		(start 78.23708 -35.4965)
		(end 79.286862 -36.546282)
		(width 0.14224)
		(layer "In11.Cu")
		(net "CLK_100M_CPU1_CLK05_DP")
	)
	(segment
		(start 74.253852 -32.746188)
		(end 77.004164 -35.4965)
		(width 0.14224)
		(layer "In11.Cu")
		(net "CLK_100M_CPU1_CLK05_DP")
	)
	(segment
		(start 71.330312 -6.58749)
		(end 71.621142 -6.87832)
		(width 0.14224)
		(layer "In11.Cu")
		(net "CLK_100M_CPU1_CLK05_DP")
	)
	(segment
		(start 77.004164 -35.4965)
		(end 78.23708 -35.4965)
		(width 0.14224)
		(layer "In11.Cu")
		(net "CLK_100M_CPU1_CLK05_DP")
	)
	(segment
		(start 164.529262 -149.585934)
		(end 164.174932 -149.940264)
		(width 0.14224)
		(layer "In11.Cu")
		(net "CLK_100M_CPU1_CLK05_DP")
	)
	(segment
		(start 69.131434 -10.99185)
		(end 69.131434 -14.954504)
		(width 0.14224)
		(layer "In11.Cu")
		(net "CLK_100M_CPU1_CLK05_DP")
	)
	(segment
		(start 69.131434 -14.954504)
		(end 71.790814 -17.613884)
		(width 0.14224)
		(layer "In11.Cu")
		(net "CLK_100M_CPU1_CLK05_DP")
	)
	(segment
		(start 164.529262 -148.56714)
		(end 164.529262 -149.585934)
		(width 0.14224)
		(layer "In11.Cu")
		(net "CLK_100M_CPU1_CLK05_DP")
	)
	(segment
		(start 162.070542 -138.019028)
		(end 162.070542 -146.10842)
		(width 0.14224)
		(layer "In11.Cu")
		(net "CLK_100M_CPU1_CLK05_DP")
	)
	(segment
		(start 71.621142 -6.87832)
		(end 71.621142 -8.502142)
		(width 0.14224)
		(layer "In11.Cu")
		(net "CLK_100M_CPU1_CLK05_DP")
	)
	(segment
		(start 71.790814 -23.753064)
		(end 74.253852 -26.216102)
		(width 0.14224)
		(layer "In11.Cu")
		(net "CLK_100M_CPU1_CLK05_DP")
	)
	(segment
		(start 162.070542 -146.10842)
		(end 164.529262 -148.56714)
		(width 0.14224)
		(layer "In11.Cu")
		(net "CLK_100M_CPU1_CLK05_DP")
	)
	(segment
		(start 85.449664 -61.39815)
		(end 162.070542 -138.019028)
		(width 0.14224)
		(layer "In11.Cu")
		(net "CLK_100M_CPU1_CLK05_DP")
	)
	(segment
		(start 74.253852 -26.216102)
		(end 74.253852 -32.746188)
		(width 0.14224)
		(layer "In11.Cu")
		(net "CLK_100M_CPU1_CLK05_DP")
	)
	(segment
		(start 79.286862 -46.519846)
		(end 85.449664 -61.39815)
		(width 0.14224)
		(layer "In11.Cu")
		(net "CLK_100M_CPU1_CLK05_DP")
	)
	(segment
		(start 71.621142 -8.502142)
		(end 69.131434 -10.99185)
		(width 0.14224)
		(layer "In11.Cu")
		(net "CLK_100M_CPU1_CLK05_DP")
	)
	(segment
		(start 151.923496 -164.394134)
		(end 151.923496 -190.60795)
		(width 0.12954)
		(layer "F.Cu")
		(net "CLK_100M_CPU1_CLK05_DN")
	)
	(segment
		(start 164.831522 -150.274274)
		(end 164.831522 -151.486108)
		(width 0.12954)
		(layer "F.Cu")
		(net "CLK_100M_CPU1_CLK05_DN")
	)
	(segment
		(start 71.923402 -6.858)
		(end 71.923402 -7.613396)
		(width 0.12954)
		(layer "F.Cu")
		(net "CLK_100M_CPU1_CLK05_DN")
	)
	(segment
		(start 71.923402 -7.613396)
		(end 72.062086 -7.75208)
		(width 0.12954)
		(layer "F.Cu")
		(net "CLK_100M_CPU1_CLK05_DN")
	)
	(segment
		(start 165.165532 -149.940264)
		(end 164.831522 -150.274274)
		(width 0.12954)
		(layer "F.Cu")
		(net "CLK_100M_CPU1_CLK05_DN")
	)
	(segment
		(start 72.193912 -6.58749)
		(end 71.923402 -6.858)
		(width 0.12954)
		(layer "F.Cu")
		(net "CLK_100M_CPU1_CLK05_DN")
	)
	(segment
		(start 151.923496 -190.60795)
		(end 152.270206 -190.95466)
		(width 0.12954)
		(layer "F.Cu")
		(net "CLK_100M_CPU1_CLK05_DN")
	)
	(segment
		(start 72.062086 -7.75208)
		(end 72.062086 -8.320024)
		(width 0.12954)
		(layer "F.Cu")
		(net "CLK_100M_CPU1_CLK05_DN")
	)
	(segment
		(start 164.831522 -151.486108)
		(end 151.923496 -164.394134)
		(width 0.12954)
		(layer "F.Cu")
		(net "CLK_100M_CPU1_CLK05_DN")
	)
	(via
		(at 165.165532 -149.940264)
		(size 0.508)
		(drill 0.254)
		(layers "F.Cu" "B.Cu")
		(net "CLK_100M_CPU1_CLK05_DN")
	)
	(via
		(at 72.193912 -6.58749)
		(size 0.508)
		(drill 0.254)
		(layers "F.Cu" "B.Cu")
		(net "CLK_100M_CPU1_CLK05_DN")
	)
	(segment
		(start 69.413374 -14.837664)
		(end 72.072754 -17.497044)
		(width 0.14224)
		(layer "In11.Cu")
		(net "CLK_100M_CPU1_CLK05_DN")
	)
	(segment
		(start 79.568802 -46.463712)
		(end 85.688678 -61.238384)
		(width 0.14224)
		(layer "In11.Cu")
		(net "CLK_100M_CPU1_CLK05_DN")
	)
	(segment
		(start 72.072754 -23.636224)
		(end 74.535792 -26.099262)
		(width 0.14224)
		(layer "In11.Cu")
		(net "CLK_100M_CPU1_CLK05_DN")
	)
	(segment
		(start 164.811202 -148.4503)
		(end 164.811202 -149.585934)
		(width 0.14224)
		(layer "In11.Cu")
		(net "CLK_100M_CPU1_CLK05_DN")
	)
	(segment
		(start 74.535792 -26.099262)
		(end 74.535792 -32.629348)
		(width 0.14224)
		(layer "In11.Cu")
		(net "CLK_100M_CPU1_CLK05_DN")
	)
	(segment
		(start 78.35392 -35.21456)
		(end 79.568802 -36.429442)
		(width 0.14224)
		(layer "In11.Cu")
		(net "CLK_100M_CPU1_CLK05_DN")
	)
	(segment
		(start 162.352482 -145.99158)
		(end 164.811202 -148.4503)
		(width 0.14224)
		(layer "In11.Cu")
		(net "CLK_100M_CPU1_CLK05_DN")
	)
	(segment
		(start 74.535792 -32.629348)
		(end 77.121004 -35.21456)
		(width 0.14224)
		(layer "In11.Cu")
		(net "CLK_100M_CPU1_CLK05_DN")
	)
	(segment
		(start 164.811202 -149.585934)
		(end 165.165532 -149.940264)
		(width 0.14224)
		(layer "In11.Cu")
		(net "CLK_100M_CPU1_CLK05_DN")
	)
	(segment
		(start 79.568802 -36.429442)
		(end 79.568802 -46.463712)
		(width 0.14224)
		(layer "In11.Cu")
		(net "CLK_100M_CPU1_CLK05_DN")
	)
	(segment
		(start 162.352482 -137.902188)
		(end 162.352482 -145.99158)
		(width 0.14224)
		(layer "In11.Cu")
		(net "CLK_100M_CPU1_CLK05_DN")
	)
	(segment
		(start 71.903082 -8.618982)
		(end 69.413374 -11.10869)
		(width 0.14224)
		(layer "In11.Cu")
		(net "CLK_100M_CPU1_CLK05_DN")
	)
	(segment
		(start 72.193912 -6.58749)
		(end 71.903082 -6.87832)
		(width 0.14224)
		(layer "In11.Cu")
		(net "CLK_100M_CPU1_CLK05_DN")
	)
	(segment
		(start 69.413374 -11.10869)
		(end 69.413374 -14.837664)
		(width 0.14224)
		(layer "In11.Cu")
		(net "CLK_100M_CPU1_CLK05_DN")
	)
	(segment
		(start 72.072754 -17.497044)
		(end 72.072754 -23.636224)
		(width 0.14224)
		(layer "In11.Cu")
		(net "CLK_100M_CPU1_CLK05_DN")
	)
	(segment
		(start 71.903082 -6.87832)
		(end 71.903082 -8.618982)
		(width 0.14224)
		(layer "In11.Cu")
		(net "CLK_100M_CPU1_CLK05_DN")
	)
	(segment
		(start 85.688678 -61.238384)
		(end 162.352482 -137.902188)
		(width 0.14224)
		(layer "In11.Cu")
		(net "CLK_100M_CPU1_CLK05_DN")
	)
	(segment
		(start 77.121004 -35.21456)
		(end 78.35392 -35.21456)
		(width 0.14224)
		(layer "In11.Cu")
		(net "CLK_100M_CPU1_CLK05_DN")
	)
	(segment
		(start 135.9027 -221.334584)
		(end 135.9027 -219.750132)
		(width 0.12954)
		(layer "F.Cu")
		(net "CLK_100M_CPU1_CLK04_R_DP")
	)
	(segment
		(start 144.997678 -200.213214)
		(end 144.997678 -199.94372)
		(width 0.12954)
		(layer "F.Cu")
		(net "CLK_100M_CPU1_CLK04_R_DP")
	)
	(segment
		(start 136.524238 -216.68994)
		(end 135.237982 -213.584028)
		(width 0.12954)
		(layer "F.Cu")
		(net "CLK_100M_CPU1_CLK04_R_DP")
	)
	(segment
		(start 147.44446 -195.3514)
		(end 147.44446 -192.10147)
		(width 0.12954)
		(layer "F.Cu")
		(net "CLK_100M_CPU1_CLK04_R_DP")
	)
	(segment
		(start 136.436608 -222.576136)
		(end 136.324848 -222.510858)
		(width 0.0762)
		(layer "F.Cu")
		(net "CLK_100M_CPU1_CLK04_R_DP")
	)
	(segment
		(start 136.059418 -223.153732)
		(end 136.078722 -223.226122)
		(width 0.0762)
		(layer "F.Cu")
		(net "CLK_100M_CPU1_CLK04_R_DP")
	)
	(segment
		(start 136.40689 -223.201738)
		(end 136.436608 -223.18472)
		(width 0.0762)
		(layer "F.Cu")
		(net "CLK_100M_CPU1_CLK04_R_DP")
	)
	(segment
		(start 135.237982 -209.97291)
		(end 144.997678 -200.213214)
		(width 0.12954)
		(layer "F.Cu")
		(net "CLK_100M_CPU1_CLK04_R_DP")
	)
	(segment
		(start 145.540476 -199.670416)
		(end 145.813272 -199.39762)
		(width 0.12954)
		(layer "F.Cu")
		(net "CLK_100M_CPU1_CLK04_R_DP")
	)
	(segment
		(start 146.086576 -198.854822)
		(end 146.35607 -198.854822)
		(width 0.12954)
		(layer "F.Cu")
		(net "CLK_100M_CPU1_CLK04_R_DP")
	)
	(segment
		(start 136.404858 -223.203008)
		(end 136.40562 -223.2025)
		(width 0.0762)
		(layer "F.Cu")
		(net "CLK_100M_CPU1_CLK04_R_DP")
	)
	(segment
		(start 136.524238 -219.128594)
		(end 136.524238 -216.68994)
		(width 0.12954)
		(layer "F.Cu")
		(net "CLK_100M_CPU1_CLK04_R_DP")
	)
	(segment
		(start 135.96874 -221.419674)
		(end 135.9027 -221.353634)
		(width 0.0762)
		(layer "F.Cu")
		(net "CLK_100M_CPU1_CLK04_R_DP")
	)
	(segment
		(start 145.813272 -199.128126)
		(end 146.086576 -198.854822)
		(width 0.12954)
		(layer "F.Cu")
		(net "CLK_100M_CPU1_CLK04_R_DP")
	)
	(segment
		(start 144.997678 -199.94372)
		(end 145.270982 -199.670416)
		(width 0.12954)
		(layer "F.Cu")
		(net "CLK_100M_CPU1_CLK04_R_DP")
	)
	(segment
		(start 145.813272 -199.39762)
		(end 145.813272 -199.128126)
		(width 0.12954)
		(layer "F.Cu")
		(net "CLK_100M_CPU1_CLK04_R_DP")
	)
	(segment
		(start 135.9027 -221.353634)
		(end 135.9027 -221.334584)
		(width 0.0762)
		(layer "F.Cu")
		(net "CLK_100M_CPU1_CLK04_R_DP")
	)
	(segment
		(start 147.44446 -197.766432)
		(end 147.44446 -195.3514)
		(width 0.12954)
		(layer "F.Cu")
		(net "CLK_100M_CPU1_CLK04_R_DP")
	)
	(segment
		(start 136.324848 -222.510858)
		(end 135.96874 -222.15475)
		(width 0.0762)
		(layer "F.Cu")
		(net "CLK_100M_CPU1_CLK04_R_DP")
	)
	(segment
		(start 147.44446 -192.10147)
		(end 147.09775 -191.75476)
		(width 0.12954)
		(layer "F.Cu")
		(net "CLK_100M_CPU1_CLK04_R_DP")
	)
	(segment
		(start 146.35607 -198.854822)
		(end 146.628866 -198.582026)
		(width 0.12954)
		(layer "F.Cu")
		(net "CLK_100M_CPU1_CLK04_R_DP")
	)
	(segment
		(start 135.96874 -222.15475)
		(end 135.96874 -221.419674)
		(width 0.0762)
		(layer "F.Cu")
		(net "CLK_100M_CPU1_CLK04_R_DP")
	)
	(segment
		(start 136.40562 -223.2025)
		(end 136.40689 -223.201738)
		(width 0.0762)
		(layer "F.Cu")
		(net "CLK_100M_CPU1_CLK04_R_DP")
	)
	(segment
		(start 135.9027 -219.750132)
		(end 136.524238 -219.128594)
		(width 0.12954)
		(layer "F.Cu")
		(net "CLK_100M_CPU1_CLK04_R_DP")
	)
	(segment
		(start 146.628866 -198.312532)
		(end 146.90217 -198.039228)
		(width 0.12954)
		(layer "F.Cu")
		(net "CLK_100M_CPU1_CLK04_R_DP")
	)
	(segment
		(start 147.171664 -198.039228)
		(end 147.44446 -197.766432)
		(width 0.12954)
		(layer "F.Cu")
		(net "CLK_100M_CPU1_CLK04_R_DP")
	)
	(segment
		(start 146.90217 -198.039228)
		(end 147.171664 -198.039228)
		(width 0.12954)
		(layer "F.Cu")
		(net "CLK_100M_CPU1_CLK04_R_DP")
	)
	(segment
		(start 145.270982 -199.670416)
		(end 145.540476 -199.670416)
		(width 0.12954)
		(layer "F.Cu")
		(net "CLK_100M_CPU1_CLK04_R_DP")
	)
	(segment
		(start 136.217914 -222.880428)
		(end 136.059418 -223.153732)
		(width 0.0762)
		(layer "F.Cu")
		(net "CLK_100M_CPU1_CLK04_R_DP")
	)
	(segment
		(start 135.237982 -213.584028)
		(end 135.237982 -209.97291)
		(width 0.12954)
		(layer "F.Cu")
		(net "CLK_100M_CPU1_CLK04_R_DP")
	)
	(segment
		(start 146.628866 -198.582026)
		(end 146.628866 -198.312532)
		(width 0.12954)
		(layer "F.Cu")
		(net "CLK_100M_CPU1_CLK04_R_DP")
	)
	(via
		(at 147.44446 -195.3514)
		(size 0.4064)
		(drill 0.2032)
		(layers "F.Cu" "B.Cu")
		(net "CLK_100M_CPU1_CLK04_R_DP")
	)
	(arc
		(start 136.078722 -223.226122)
		(mid 136.244467 -223.252258)
		(end 136.404858 -223.203008)
		(width 0.0762)
		(layer "F.Cu")
		(net "CLK_100M_CPU1_CLK04_R_DP")
	)
	(arc
		(start 136.436608 -223.18472)
		(mid 136.592536 -222.880428)
		(end 136.436608 -222.576136)
		(width 0.0762)
		(layer "F.Cu")
		(net "CLK_100M_CPU1_CLK04_R_DP")
	)
	(segment
		(start 147.76704 -192.9638)
		(end 147.76704 -192.10147)
		(width 0.12954)
		(layer "F.Cu")
		(net "CLK_100M_CPU1_CLK04_R_DN")
	)
	(segment
		(start 136.539986 -222.415862)
		(end 136.442196 -222.358712)
		(width 0.0762)
		(layer "F.Cu")
		(net "CLK_100M_CPU1_CLK04_R_DN")
	)
	(segment
		(start 135.560562 -213.519766)
		(end 135.560562 -210.106768)
		(width 0.12954)
		(layer "F.Cu")
		(net "CLK_100M_CPU1_CLK04_R_DN")
	)
	(segment
		(start 135.748014 -223.690434)
		(end 135.90651 -223.41713)
		(width 0.0762)
		(layer "F.Cu")
		(net "CLK_100M_CPU1_CLK04_R_DN")
	)
	(segment
		(start 136.846818 -216.625678)
		(end 135.560562 -213.519766)
		(width 0.12954)
		(layer "F.Cu")
		(net "CLK_100M_CPU1_CLK04_R_DN")
	)
	(segment
		(start 147.76704 -197.90029)
		(end 147.76704 -192.9638)
		(width 0.12954)
		(layer "F.Cu")
		(net "CLK_100M_CPU1_CLK04_R_DN")
	)
	(segment
		(start 136.22528 -221.353634)
		(end 136.22528 -221.334584)
		(width 0.0762)
		(layer "F.Cu")
		(net "CLK_100M_CPU1_CLK04_R_DN")
	)
	(segment
		(start 136.15924 -222.075756)
		(end 136.15924 -221.419674)
		(width 0.0762)
		(layer "F.Cu")
		(net "CLK_100M_CPU1_CLK04_R_DN")
	)
	(segment
		(start 147.76704 -192.10147)
		(end 148.11375 -191.75476)
		(width 0.12954)
		(layer "F.Cu")
		(net "CLK_100M_CPU1_CLK04_R_DN")
	)
	(segment
		(start 136.22528 -221.334584)
		(end 136.22528 -219.88399)
		(width 0.12954)
		(layer "F.Cu")
		(net "CLK_100M_CPU1_CLK04_R_DN")
	)
	(segment
		(start 136.846818 -219.262452)
		(end 136.846818 -216.625678)
		(width 0.12954)
		(layer "F.Cu")
		(net "CLK_100M_CPU1_CLK04_R_DN")
	)
	(segment
		(start 136.15924 -221.419674)
		(end 136.22528 -221.353634)
		(width 0.0762)
		(layer "F.Cu")
		(net "CLK_100M_CPU1_CLK04_R_DN")
	)
	(segment
		(start 136.501886 -223.367346)
		(end 136.50341 -223.36633)
		(width 0.0762)
		(layer "F.Cu")
		(net "CLK_100M_CPU1_CLK04_R_DN")
	)
	(segment
		(start 136.22528 -219.88399)
		(end 136.846818 -219.262452)
		(width 0.12954)
		(layer "F.Cu")
		(net "CLK_100M_CPU1_CLK04_R_DN")
	)
	(segment
		(start 136.50087 -223.367854)
		(end 136.501886 -223.367346)
		(width 0.0762)
		(layer "F.Cu")
		(net "CLK_100M_CPU1_CLK04_R_DN")
	)
	(segment
		(start 136.442196 -222.358712)
		(end 136.15924 -222.075756)
		(width 0.0762)
		(layer "F.Cu")
		(net "CLK_100M_CPU1_CLK04_R_DN")
	)
	(segment
		(start 135.90651 -223.41713)
		(end 135.988552 -223.39554)
		(width 0.0762)
		(layer "F.Cu")
		(net "CLK_100M_CPU1_CLK04_R_DN")
	)
	(segment
		(start 136.50341 -223.36633)
		(end 136.539986 -223.344994)
		(width 0.0762)
		(layer "F.Cu")
		(net "CLK_100M_CPU1_CLK04_R_DN")
	)
	(segment
		(start 135.560562 -210.106768)
		(end 147.76704 -197.90029)
		(width 0.12954)
		(layer "F.Cu")
		(net "CLK_100M_CPU1_CLK04_R_DN")
	)
	(via
		(at 147.76704 -192.9638)
		(size 0.4064)
		(drill 0.2032)
		(layers "F.Cu" "B.Cu")
		(net "CLK_100M_CPU1_CLK04_R_DN")
	)
	(arc
		(start 136.539986 -223.344994)
		(mid 136.783313 -222.880428)
		(end 136.539986 -222.415862)
		(width 0.0762)
		(layer "F.Cu")
		(net "CLK_100M_CPU1_CLK04_R_DN")
	)
	(arc
		(start 135.988552 -223.39554)
		(mid 136.248048 -223.443395)
		(end 136.50087 -223.367854)
		(width 0.0762)
		(layer "F.Cu")
		(net "CLK_100M_CPU1_CLK04_R_DN")
	)
	(segment
		(start 164.015166 -146.722592)
		(end 164.015166 -145.410936)
		(width 0.12954)
		(layer "F.Cu")
		(net "CLK_100M_CPU1_CLK04_DP")
	)
	(segment
		(start 158.969964 -149.227794)
		(end 160.068006 -148.129752)
		(width 0.12954)
		(layer "F.Cu")
		(net "CLK_100M_CPU1_CLK04_DP")
	)
	(segment
		(start 162.608006 -148.129752)
		(end 164.015166 -146.722592)
		(width 0.12954)
		(layer "F.Cu")
		(net "CLK_100M_CPU1_CLK04_DP")
	)
	(segment
		(start 71.600822 -12.010898)
		(end 71.461884 -11.87196)
		(width 0.12954)
		(layer "F.Cu")
		(net "CLK_100M_CPU1_CLK04_DP")
	)
	(segment
		(start 71.461884 -11.87196)
		(end 71.461884 -11.26998)
		(width 0.12954)
		(layer "F.Cu")
		(net "CLK_100M_CPU1_CLK04_DP")
	)
	(segment
		(start 164.015166 -145.410936)
		(end 163.681156 -145.076926)
		(width 0.12954)
		(layer "F.Cu")
		(net "CLK_100M_CPU1_CLK04_DP")
	)
	(segment
		(start 147.09775 -190.95466)
		(end 147.44446 -190.60795)
		(width 0.12954)
		(layer "F.Cu")
		(net "CLK_100M_CPU1_CLK04_DP")
	)
	(segment
		(start 147.44446 -190.60795)
		(end 147.44446 -162.537902)
		(width 0.12954)
		(layer "F.Cu")
		(net "CLK_100M_CPU1_CLK04_DP")
	)
	(segment
		(start 71.329804 -12.864846)
		(end 71.600822 -12.593828)
		(width 0.12954)
		(layer "F.Cu")
		(net "CLK_100M_CPU1_CLK04_DP")
	)
	(segment
		(start 147.44446 -162.537902)
		(end 158.969964 -151.012398)
		(width 0.12954)
		(layer "F.Cu")
		(net "CLK_100M_CPU1_CLK04_DP")
	)
	(segment
		(start 160.068006 -148.129752)
		(end 162.608006 -148.129752)
		(width 0.12954)
		(layer "F.Cu")
		(net "CLK_100M_CPU1_CLK04_DP")
	)
	(segment
		(start 158.969964 -151.012398)
		(end 158.969964 -149.227794)
		(width 0.12954)
		(layer "F.Cu")
		(net "CLK_100M_CPU1_CLK04_DP")
	)
	(segment
		(start 71.600822 -12.593828)
		(end 71.600822 -12.010898)
		(width 0.12954)
		(layer "F.Cu")
		(net "CLK_100M_CPU1_CLK04_DP")
	)
	(via
		(at 71.329804 -12.864846)
		(size 0.508)
		(drill 0.254)
		(layers "F.Cu" "B.Cu")
		(net "CLK_100M_CPU1_CLK04_DP")
	)
	(via
		(at 163.681156 -145.076926)
		(size 0.508)
		(drill 0.254)
		(layers "F.Cu" "B.Cu")
		(net "CLK_100M_CPU1_CLK04_DP")
	)
	(segment
		(start 86.088728 -60.504324)
		(end 164.035486 -138.451082)
		(width 0.14224)
		(layer "In11.Cu")
		(net "CLK_100M_CPU1_CLK04_DP")
	)
	(segment
		(start 80.37068 -36.09721)
		(end 80.37068 -46.699678)
		(width 0.14224)
		(layer "In11.Cu")
		(net "CLK_100M_CPU1_CLK04_DP")
	)
	(segment
		(start 164.035486 -138.451082)
		(end 164.035486 -144.722596)
		(width 0.14224)
		(layer "In11.Cu")
		(net "CLK_100M_CPU1_CLK04_DP")
	)
	(segment
		(start 164.035486 -144.722596)
		(end 163.681156 -145.076926)
		(width 0.14224)
		(layer "In11.Cu")
		(net "CLK_100M_CPU1_CLK04_DP")
	)
	(segment
		(start 72.983344 -23.412704)
		(end 75.2348 -25.66416)
		(width 0.14224)
		(layer "In11.Cu")
		(net "CLK_100M_CPU1_CLK04_DP")
	)
	(segment
		(start 77.453236 -34.412682)
		(end 78.686152 -34.412682)
		(width 0.14224)
		(layer "In11.Cu")
		(net "CLK_100M_CPU1_CLK04_DP")
	)
	(segment
		(start 71.329804 -12.864846)
		(end 71.620634 -13.155676)
		(width 0.14224)
		(layer "In11.Cu")
		(net "CLK_100M_CPU1_CLK04_DP")
	)
	(segment
		(start 75.2348 -25.66416)
		(end 75.2348 -32.194246)
		(width 0.14224)
		(layer "In11.Cu")
		(net "CLK_100M_CPU1_CLK04_DP")
	)
	(segment
		(start 80.37068 -46.699678)
		(end 86.088728 -60.504324)
		(width 0.14224)
		(layer "In11.Cu")
		(net "CLK_100M_CPU1_CLK04_DP")
	)
	(segment
		(start 72.983344 -17.157446)
		(end 72.983344 -23.412704)
		(width 0.14224)
		(layer "In11.Cu")
		(net "CLK_100M_CPU1_CLK04_DP")
	)
	(segment
		(start 71.620634 -15.794736)
		(end 72.983344 -17.157446)
		(width 0.14224)
		(layer "In11.Cu")
		(net "CLK_100M_CPU1_CLK04_DP")
	)
	(segment
		(start 78.686152 -34.412682)
		(end 80.37068 -36.09721)
		(width 0.14224)
		(layer "In11.Cu")
		(net "CLK_100M_CPU1_CLK04_DP")
	)
	(segment
		(start 71.620634 -13.155676)
		(end 71.620634 -15.794736)
		(width 0.14224)
		(layer "In11.Cu")
		(net "CLK_100M_CPU1_CLK04_DP")
	)
	(segment
		(start 75.2348 -32.194246)
		(end 77.453236 -34.412682)
		(width 0.14224)
		(layer "In11.Cu")
		(net "CLK_100M_CPU1_CLK04_DP")
	)
	(segment
		(start 147.76704 -162.67176)
		(end 159.292544 -151.146256)
		(width 0.12954)
		(layer "F.Cu")
		(net "CLK_100M_CPU1_CLK04_DN")
	)
	(segment
		(start 148.11375 -190.95466)
		(end 147.76704 -190.60795)
		(width 0.12954)
		(layer "F.Cu")
		(net "CLK_100M_CPU1_CLK04_DN")
	)
	(segment
		(start 164.337746 -145.410936)
		(end 164.671756 -145.076926)
		(width 0.12954)
		(layer "F.Cu")
		(net "CLK_100M_CPU1_CLK04_DN")
	)
	(segment
		(start 159.292544 -151.146256)
		(end 159.292544 -149.361652)
		(width 0.12954)
		(layer "F.Cu")
		(net "CLK_100M_CPU1_CLK04_DN")
	)
	(segment
		(start 147.76704 -190.60795)
		(end 147.76704 -162.67176)
		(width 0.12954)
		(layer "F.Cu")
		(net "CLK_100M_CPU1_CLK04_DN")
	)
	(segment
		(start 162.741864 -148.452332)
		(end 164.337746 -146.85645)
		(width 0.12954)
		(layer "F.Cu")
		(net "CLK_100M_CPU1_CLK04_DN")
	)
	(segment
		(start 159.292544 -149.361652)
		(end 160.201864 -148.452332)
		(width 0.12954)
		(layer "F.Cu")
		(net "CLK_100M_CPU1_CLK04_DN")
	)
	(segment
		(start 72.193404 -12.864846)
		(end 71.923402 -12.594844)
		(width 0.12954)
		(layer "F.Cu")
		(net "CLK_100M_CPU1_CLK04_DN")
	)
	(segment
		(start 71.923402 -12.594844)
		(end 71.923402 -11.95959)
		(width 0.12954)
		(layer "F.Cu")
		(net "CLK_100M_CPU1_CLK04_DN")
	)
	(segment
		(start 72.062086 -11.820906)
		(end 72.062086 -11.26998)
		(width 0.12954)
		(layer "F.Cu")
		(net "CLK_100M_CPU1_CLK04_DN")
	)
	(segment
		(start 160.201864 -148.452332)
		(end 162.741864 -148.452332)
		(width 0.12954)
		(layer "F.Cu")
		(net "CLK_100M_CPU1_CLK04_DN")
	)
	(segment
		(start 164.337746 -146.85645)
		(end 164.337746 -145.410936)
		(width 0.12954)
		(layer "F.Cu")
		(net "CLK_100M_CPU1_CLK04_DN")
	)
	(segment
		(start 71.923402 -11.95959)
		(end 72.062086 -11.820906)
		(width 0.12954)
		(layer "F.Cu")
		(net "CLK_100M_CPU1_CLK04_DN")
	)
	(via
		(at 72.193404 -12.864846)
		(size 0.508)
		(drill 0.254)
		(layers "F.Cu" "B.Cu")
		(net "CLK_100M_CPU1_CLK04_DN")
	)
	(via
		(at 164.671756 -145.076926)
		(size 0.508)
		(drill 0.254)
		(layers "F.Cu" "B.Cu")
		(net "CLK_100M_CPU1_CLK04_DN")
	)
	(segment
		(start 80.65262 -46.643544)
		(end 86.327742 -60.344558)
		(width 0.14224)
		(layer "In11.Cu")
		(net "CLK_100M_CPU1_CLK04_DN")
	)
	(segment
		(start 164.317426 -138.334242)
		(end 164.317426 -144.722596)
		(width 0.14224)
		(layer "In11.Cu")
		(net "CLK_100M_CPU1_CLK04_DN")
	)
	(segment
		(start 73.265284 -23.295864)
		(end 75.51674 -25.54732)
		(width 0.14224)
		(layer "In11.Cu")
		(net "CLK_100M_CPU1_CLK04_DN")
	)
	(segment
		(start 75.51674 -32.077406)
		(end 77.570076 -34.130742)
		(width 0.14224)
		(layer "In11.Cu")
		(net "CLK_100M_CPU1_CLK04_DN")
	)
	(segment
		(start 77.570076 -34.130742)
		(end 78.802992 -34.130742)
		(width 0.14224)
		(layer "In11.Cu")
		(net "CLK_100M_CPU1_CLK04_DN")
	)
	(segment
		(start 164.317426 -144.722596)
		(end 164.671756 -145.076926)
		(width 0.14224)
		(layer "In11.Cu")
		(net "CLK_100M_CPU1_CLK04_DN")
	)
	(segment
		(start 78.802992 -34.130742)
		(end 80.65262 -35.98037)
		(width 0.14224)
		(layer "In11.Cu")
		(net "CLK_100M_CPU1_CLK04_DN")
	)
	(segment
		(start 71.902574 -13.155676)
		(end 71.902574 -15.677896)
		(width 0.14224)
		(layer "In11.Cu")
		(net "CLK_100M_CPU1_CLK04_DN")
	)
	(segment
		(start 80.65262 -35.98037)
		(end 80.65262 -46.643544)
		(width 0.14224)
		(layer "In11.Cu")
		(net "CLK_100M_CPU1_CLK04_DN")
	)
	(segment
		(start 71.902574 -15.677896)
		(end 73.265284 -17.040606)
		(width 0.14224)
		(layer "In11.Cu")
		(net "CLK_100M_CPU1_CLK04_DN")
	)
	(segment
		(start 72.193404 -12.864846)
		(end 71.902574 -13.155676)
		(width 0.14224)
		(layer "In11.Cu")
		(net "CLK_100M_CPU1_CLK04_DN")
	)
	(segment
		(start 86.327742 -60.344558)
		(end 164.317426 -138.334242)
		(width 0.14224)
		(layer "In11.Cu")
		(net "CLK_100M_CPU1_CLK04_DN")
	)
	(segment
		(start 75.51674 -25.54732)
		(end 75.51674 -32.077406)
		(width 0.14224)
		(layer "In11.Cu")
		(net "CLK_100M_CPU1_CLK04_DN")
	)
	(segment
		(start 73.265284 -17.040606)
		(end 73.265284 -23.295864)
		(width 0.14224)
		(layer "In11.Cu")
		(net "CLK_100M_CPU1_CLK04_DN")
	)
	(segment
		(start 137.319258 -220.411294)
		(end 137.725404 -220.005148)
		(width 0.12954)
		(layer "F.Cu")
		(net "CLK_100M_CPU1_CLK03_R_DP")
	)
	(segment
		(start 149.899624 -192.8876)
		(end 149.899624 -192.118742)
		(width 0.12954)
		(layer "F.Cu")
		(net "CLK_100M_CPU1_CLK03_R_DP")
	)
	(segment
		(start 136.664446 -210.245706)
		(end 149.267926 -197.642226)
		(width 0.12954)
		(layer "F.Cu")
		(net "CLK_100M_CPU1_CLK03_R_DP")
	)
	(segment
		(start 137.627868 -222.070422)
		(end 137.319258 -221.761812)
		(width 0.12954)
		(layer "F.Cu")
		(net "CLK_100M_CPU1_CLK03_R_DP")
	)
	(segment
		(start 149.899624 -196.11721)
		(end 149.899624 -192.8876)
		(width 0.12954)
		(layer "F.Cu")
		(net "CLK_100M_CPU1_CLK03_R_DP")
	)
	(segment
		(start 149.267926 -197.642226)
		(end 149.899624 -196.11721)
		(width 0.12954)
		(layer "F.Cu")
		(net "CLK_100M_CPU1_CLK03_R_DP")
	)
	(segment
		(start 149.899624 -192.118742)
		(end 150.246334 -191.772032)
		(width 0.12954)
		(layer "F.Cu")
		(net "CLK_100M_CPU1_CLK03_R_DP")
	)
	(segment
		(start 137.725404 -216.563448)
		(end 136.664446 -214.000842)
		(width 0.12954)
		(layer "F.Cu")
		(net "CLK_100M_CPU1_CLK03_R_DP")
	)
	(segment
		(start 136.664446 -214.000842)
		(end 136.664446 -210.245706)
		(width 0.12954)
		(layer "F.Cu")
		(net "CLK_100M_CPU1_CLK03_R_DP")
	)
	(segment
		(start 137.725404 -220.005148)
		(end 137.725404 -216.563448)
		(width 0.12954)
		(layer "F.Cu")
		(net "CLK_100M_CPU1_CLK03_R_DP")
	)
	(segment
		(start 137.319258 -221.761812)
		(end 137.319258 -220.411294)
		(width 0.12954)
		(layer "F.Cu")
		(net "CLK_100M_CPU1_CLK03_R_DP")
	)
	(via
		(at 149.899624 -192.8876)
		(size 0.4064)
		(drill 0.2032)
		(layers "F.Cu" "B.Cu")
		(net "CLK_100M_CPU1_CLK03_R_DP")
	)
	(segment
		(start 149.577044 -196.052694)
		(end 149.577044 -195.3768)
		(width 0.12954)
		(layer "F.Cu")
		(net "CLK_100M_CPU1_CLK03_R_DN")
	)
	(segment
		(start 137.402824 -216.62771)
		(end 136.341866 -214.065104)
		(width 0.12954)
		(layer "F.Cu")
		(net "CLK_100M_CPU1_CLK03_R_DN")
	)
	(segment
		(start 148.994368 -197.459346)
		(end 149.577044 -196.052694)
		(width 0.12954)
		(layer "F.Cu")
		(net "CLK_100M_CPU1_CLK03_R_DN")
	)
	(segment
		(start 136.996678 -220.277436)
		(end 137.402824 -219.87129)
		(width 0.12954)
		(layer "F.Cu")
		(net "CLK_100M_CPU1_CLK03_R_DN")
	)
	(segment
		(start 149.577044 -192.118742)
		(end 149.230334 -191.772032)
		(width 0.12954)
		(layer "F.Cu")
		(net "CLK_100M_CPU1_CLK03_R_DN")
	)
	(segment
		(start 136.996678 -221.761558)
		(end 136.996678 -220.277436)
		(width 0.12954)
		(layer "F.Cu")
		(net "CLK_100M_CPU1_CLK03_R_DN")
	)
	(segment
		(start 149.577044 -195.3768)
		(end 149.577044 -192.118742)
		(width 0.12954)
		(layer "F.Cu")
		(net "CLK_100M_CPU1_CLK03_R_DN")
	)
	(segment
		(start 136.341866 -210.111848)
		(end 148.994368 -197.459346)
		(width 0.12954)
		(layer "F.Cu")
		(net "CLK_100M_CPU1_CLK03_R_DN")
	)
	(segment
		(start 137.402824 -219.87129)
		(end 137.402824 -216.62771)
		(width 0.12954)
		(layer "F.Cu")
		(net "CLK_100M_CPU1_CLK03_R_DN")
	)
	(segment
		(start 136.687814 -222.070422)
		(end 136.996678 -221.761558)
		(width 0.12954)
		(layer "F.Cu")
		(net "CLK_100M_CPU1_CLK03_R_DN")
	)
	(segment
		(start 136.341866 -214.065104)
		(end 136.341866 -210.111848)
		(width 0.12954)
		(layer "F.Cu")
		(net "CLK_100M_CPU1_CLK03_R_DN")
	)
	(via
		(at 149.577044 -195.3768)
		(size 0.4064)
		(drill 0.2032)
		(layers "F.Cu" "B.Cu")
		(net "CLK_100M_CPU1_CLK03_R_DN")
	)
	(segment
		(start 57.605676 -7.57047)
		(end 57.605676 -6.99516)
		(width 0.12954)
		(layer "F.Cu")
		(net "CLK_100M_CPU1_CLK03_DP")
	)
	(segment
		(start 161.894266 -151.560784)
		(end 149.899624 -163.555426)
		(width 0.12954)
		(layer "F.Cu")
		(net "CLK_100M_CPU1_CLK03_DP")
	)
	(segment
		(start 57.605676 -6.99516)
		(end 57.335674 -6.725158)
		(width 0.12954)
		(layer "F.Cu")
		(net "CLK_100M_CPU1_CLK03_DP")
	)
	(segment
		(start 162.228276 -149.988016)
		(end 161.894266 -150.322026)
		(width 0.12954)
		(layer "F.Cu")
		(net "CLK_100M_CPU1_CLK03_DP")
	)
	(segment
		(start 57.466992 -8.320024)
		(end 57.466992 -7.709154)
		(width 0.12954)
		(layer "F.Cu")
		(net "CLK_100M_CPU1_CLK03_DP")
	)
	(segment
		(start 149.899624 -163.555426)
		(end 149.899624 -190.625222)
		(width 0.12954)
		(layer "F.Cu")
		(net "CLK_100M_CPU1_CLK03_DP")
	)
	(segment
		(start 57.466992 -7.709154)
		(end 57.605676 -7.57047)
		(width 0.12954)
		(layer "F.Cu")
		(net "CLK_100M_CPU1_CLK03_DP")
	)
	(segment
		(start 149.899624 -190.625222)
		(end 150.246334 -190.971932)
		(width 0.12954)
		(layer "F.Cu")
		(net "CLK_100M_CPU1_CLK03_DP")
	)
	(segment
		(start 161.894266 -150.322026)
		(end 161.894266 -151.560784)
		(width 0.12954)
		(layer "F.Cu")
		(net "CLK_100M_CPU1_CLK03_DP")
	)
	(via
		(at 162.228276 -149.988016)
		(size 0.508)
		(drill 0.254)
		(layers "F.Cu" "B.Cu")
		(net "CLK_100M_CPU1_CLK03_DP")
	)
	(via
		(at 57.335674 -6.725158)
		(size 0.508)
		(drill 0.254)
		(layers "F.Cu" "B.Cu")
		(net "CLK_100M_CPU1_CLK03_DP")
	)
	(segment
		(start 64.08039 -20.405598)
		(end 64.08039 -19.981418)
		(width 0.14224)
		(layer "In11.Cu")
		(net "CLK_100M_CPU1_CLK03_DP")
	)
	(segment
		(start 64.21755 -21.665438)
		(end 64.08039 -21.528278)
		(width 0.14224)
		(layer "In11.Cu")
		(net "CLK_100M_CPU1_CLK03_DP")
	)
	(segment
		(start 64.21755 -22.089618)
		(end 64.21755 -21.665438)
		(width 0.14224)
		(layer "In11.Cu")
		(net "CLK_100M_CPU1_CLK03_DP")
	)
	(segment
		(start 63.796672 -16.541496)
		(end 61.78804 -16.541496)
		(width 0.14224)
		(layer "In11.Cu")
		(net "CLK_100M_CPU1_CLK03_DP")
	)
	(segment
		(start 162.976052 -148.628608)
		(end 162.676332 -148.328888)
		(width 0.14224)
		(layer "In11.Cu")
		(net "CLK_100M_CPU1_CLK03_DP")
	)
	(segment
		(start 64.21755 -25.007824)
		(end 64.21755 -22.788118)
		(width 0.14224)
		(layer "In11.Cu")
		(net "CLK_100M_CPU1_CLK03_DP")
	)
	(segment
		(start 161.084768 -144.918938)
		(end 160.947608 -144.781778)
		(width 0.14224)
		(layer "In11.Cu")
		(net "CLK_100M_CPU1_CLK03_DP")
	)
	(segment
		(start 84.712556 -62.055248)
		(end 79.306674 -49.004474)
		(width 0.14224)
		(layer "In11.Cu")
		(net "CLK_100M_CPU1_CLK03_DP")
	)
	(segment
		(start 160.947608 -144.357598)
		(end 161.084768 -144.220438)
		(width 0.14224)
		(layer "In11.Cu")
		(net "CLK_100M_CPU1_CLK03_DP")
	)
	(segment
		(start 162.182048 -147.834604)
		(end 161.882328 -147.534884)
		(width 0.14224)
		(layer "In11.Cu")
		(net "CLK_100M_CPU1_CLK03_DP")
	)
	(segment
		(start 64.21755 -16.962374)
		(end 63.796672 -16.541496)
		(width 0.14224)
		(layer "In11.Cu")
		(net "CLK_100M_CPU1_CLK03_DP")
	)
	(segment
		(start 161.084768 -138.42746)
		(end 84.712556 -62.055248)
		(width 0.14224)
		(layer "In11.Cu")
		(net "CLK_100M_CPU1_CLK03_DP")
	)
	(segment
		(start 160.947608 -143.234918)
		(end 161.084768 -143.097758)
		(width 0.14224)
		(layer "In11.Cu")
		(net "CLK_100M_CPU1_CLK03_DP")
	)
	(segment
		(start 57.626504 -10.333482)
		(end 57.626504 -7.015988)
		(width 0.14224)
		(layer "In11.Cu")
		(net "CLK_100M_CPU1_CLK03_DP")
	)
	(segment
		(start 79.306674 -49.004474)
		(end 66.895472 -36.593272)
		(width 0.14224)
		(layer "In11.Cu")
		(net "CLK_100M_CPU1_CLK03_DP")
	)
	(segment
		(start 162.976052 -150.175468)
		(end 162.976052 -148.628608)
		(width 0.14224)
		(layer "In11.Cu")
		(net "CLK_100M_CPU1_CLK03_DP")
	)
	(segment
		(start 66.895472 -36.593272)
		(end 66.895472 -32.95396)
		(width 0.14224)
		(layer "In11.Cu")
		(net "CLK_100M_CPU1_CLK03_DP")
	)
	(segment
		(start 161.084768 -143.796258)
		(end 160.947608 -143.659098)
		(width 0.14224)
		(layer "In11.Cu")
		(net "CLK_100M_CPU1_CLK03_DP")
	)
	(segment
		(start 65.180718 -27.333194)
		(end 64.21755 -25.007824)
		(width 0.14224)
		(layer "In11.Cu")
		(net "CLK_100M_CPU1_CLK03_DP")
	)
	(segment
		(start 161.084768 -143.097758)
		(end 161.084768 -138.42746)
		(width 0.14224)
		(layer "In11.Cu")
		(net "CLK_100M_CPU1_CLK03_DP")
	)
	(segment
		(start 64.21755 -19.844258)
		(end 64.21755 -16.962374)
		(width 0.14224)
		(layer "In11.Cu")
		(net "CLK_100M_CPU1_CLK03_DP")
	)
	(segment
		(start 161.87928 -150.53818)
		(end 162.057334 -150.716234)
		(width 0.14224)
		(layer "In11.Cu")
		(net "CLK_100M_CPU1_CLK03_DP")
	)
	(segment
		(start 64.08039 -21.104098)
		(end 64.21755 -20.966938)
		(width 0.14224)
		(layer "In11.Cu")
		(net "CLK_100M_CPU1_CLK03_DP")
	)
	(segment
		(start 64.08039 -21.528278)
		(end 64.08039 -21.104098)
		(width 0.14224)
		(layer "In11.Cu")
		(net "CLK_100M_CPU1_CLK03_DP")
	)
	(segment
		(start 160.947608 -144.781778)
		(end 160.947608 -144.357598)
		(width 0.14224)
		(layer "In11.Cu")
		(net "CLK_100M_CPU1_CLK03_DP")
	)
	(segment
		(start 64.21755 -20.542758)
		(end 64.08039 -20.405598)
		(width 0.14224)
		(layer "In11.Cu")
		(net "CLK_100M_CPU1_CLK03_DP")
	)
	(segment
		(start 64.08039 -19.981418)
		(end 64.21755 -19.844258)
		(width 0.14224)
		(layer "In11.Cu")
		(net "CLK_100M_CPU1_CLK03_DP")
	)
	(segment
		(start 161.388044 -147.0406)
		(end 161.084768 -146.737324)
		(width 0.14224)
		(layer "In11.Cu")
		(net "CLK_100M_CPU1_CLK03_DP")
	)
	(segment
		(start 161.87928 -150.337012)
		(end 161.87928 -150.53818)
		(width 0.14224)
		(layer "In11.Cu")
		(net "CLK_100M_CPU1_CLK03_DP")
	)
	(segment
		(start 161.084768 -146.737324)
		(end 161.084768 -146.041618)
		(width 0.14224)
		(layer "In11.Cu")
		(net "CLK_100M_CPU1_CLK03_DP")
	)
	(segment
		(start 59.920886 -12.627864)
		(end 57.626504 -10.333482)
		(width 0.14224)
		(layer "In11.Cu")
		(net "CLK_100M_CPU1_CLK03_DP")
	)
	(segment
		(start 161.084768 -145.343118)
		(end 161.084768 -144.918938)
		(width 0.14224)
		(layer "In11.Cu")
		(net "CLK_100M_CPU1_CLK03_DP")
	)
	(segment
		(start 161.388044 -147.234656)
		(end 161.388044 -147.0406)
		(width 0.14224)
		(layer "In11.Cu")
		(net "CLK_100M_CPU1_CLK03_DP")
	)
	(segment
		(start 162.482276 -148.328888)
		(end 162.182048 -148.02866)
		(width 0.14224)
		(layer "In11.Cu")
		(net "CLK_100M_CPU1_CLK03_DP")
	)
	(segment
		(start 162.676332 -148.328888)
		(end 162.482276 -148.328888)
		(width 0.14224)
		(layer "In11.Cu")
		(net "CLK_100M_CPU1_CLK03_DP")
	)
	(segment
		(start 162.182048 -148.02866)
		(end 162.182048 -147.834604)
		(width 0.14224)
		(layer "In11.Cu")
		(net "CLK_100M_CPU1_CLK03_DP")
	)
	(segment
		(start 64.08039 -22.226778)
		(end 64.21755 -22.089618)
		(width 0.14224)
		(layer "In11.Cu")
		(net "CLK_100M_CPU1_CLK03_DP")
	)
	(segment
		(start 64.21755 -20.966938)
		(end 64.21755 -20.542758)
		(width 0.14224)
		(layer "In11.Cu")
		(net "CLK_100M_CPU1_CLK03_DP")
	)
	(segment
		(start 65.180718 -31.239206)
		(end 65.180718 -27.333194)
		(width 0.14224)
		(layer "In11.Cu")
		(net "CLK_100M_CPU1_CLK03_DP")
	)
	(segment
		(start 61.78804 -16.541496)
		(end 59.920886 -14.674342)
		(width 0.14224)
		(layer "In11.Cu")
		(net "CLK_100M_CPU1_CLK03_DP")
	)
	(segment
		(start 161.084768 -144.220438)
		(end 161.084768 -143.796258)
		(width 0.14224)
		(layer "In11.Cu")
		(net "CLK_100M_CPU1_CLK03_DP")
	)
	(segment
		(start 161.688272 -147.534884)
		(end 161.388044 -147.234656)
		(width 0.14224)
		(layer "In11.Cu")
		(net "CLK_100M_CPU1_CLK03_DP")
	)
	(segment
		(start 162.057334 -150.716234)
		(end 162.435286 -150.716234)
		(width 0.14224)
		(layer "In11.Cu")
		(net "CLK_100M_CPU1_CLK03_DP")
	)
	(segment
		(start 64.21755 -22.788118)
		(end 64.08039 -22.650958)
		(width 0.14224)
		(layer "In11.Cu")
		(net "CLK_100M_CPU1_CLK03_DP")
	)
	(segment
		(start 161.882328 -147.534884)
		(end 161.688272 -147.534884)
		(width 0.14224)
		(layer "In11.Cu")
		(net "CLK_100M_CPU1_CLK03_DP")
	)
	(segment
		(start 66.895472 -32.95396)
		(end 65.180718 -31.239206)
		(width 0.14224)
		(layer "In11.Cu")
		(net "CLK_100M_CPU1_CLK03_DP")
	)
	(segment
		(start 57.626504 -7.015988)
		(end 57.335674 -6.725158)
		(width 0.14224)
		(layer "In11.Cu")
		(net "CLK_100M_CPU1_CLK03_DP")
	)
	(segment
		(start 161.084768 -146.041618)
		(end 160.947608 -145.904458)
		(width 0.14224)
		(layer "In11.Cu")
		(net "CLK_100M_CPU1_CLK03_DP")
	)
	(segment
		(start 160.947608 -143.659098)
		(end 160.947608 -143.234918)
		(width 0.14224)
		(layer "In11.Cu")
		(net "CLK_100M_CPU1_CLK03_DP")
	)
	(segment
		(start 59.920886 -14.674342)
		(end 59.920886 -12.627864)
		(width 0.14224)
		(layer "In11.Cu")
		(net "CLK_100M_CPU1_CLK03_DP")
	)
	(segment
		(start 160.947608 -145.480278)
		(end 161.084768 -145.343118)
		(width 0.14224)
		(layer "In11.Cu")
		(net "CLK_100M_CPU1_CLK03_DP")
	)
	(segment
		(start 162.228276 -149.988016)
		(end 161.87928 -150.337012)
		(width 0.14224)
		(layer "In11.Cu")
		(net "CLK_100M_CPU1_CLK03_DP")
	)
	(segment
		(start 162.435286 -150.716234)
		(end 162.976052 -150.175468)
		(width 0.14224)
		(layer "In11.Cu")
		(net "CLK_100M_CPU1_CLK03_DP")
	)
	(segment
		(start 64.08039 -22.650958)
		(end 64.08039 -22.226778)
		(width 0.14224)
		(layer "In11.Cu")
		(net "CLK_100M_CPU1_CLK03_DP")
	)
	(segment
		(start 160.947608 -145.904458)
		(end 160.947608 -145.480278)
		(width 0.14224)
		(layer "In11.Cu")
		(net "CLK_100M_CPU1_CLK03_DP")
	)
	(segment
		(start 161.571686 -151.426926)
		(end 149.577044 -163.421568)
		(width 0.12954)
		(layer "F.Cu")
		(net "CLK_100M_CPU1_CLK03_DN")
	)
	(segment
		(start 58.06694 -8.320024)
		(end 58.06694 -7.709154)
		(width 0.12954)
		(layer "F.Cu")
		(net "CLK_100M_CPU1_CLK03_DN")
	)
	(segment
		(start 149.577044 -163.421568)
		(end 149.577044 -190.625222)
		(width 0.12954)
		(layer "F.Cu")
		(net "CLK_100M_CPU1_CLK03_DN")
	)
	(segment
		(start 149.577044 -190.625222)
		(end 149.230334 -190.971932)
		(width 0.12954)
		(layer "F.Cu")
		(net "CLK_100M_CPU1_CLK03_DN")
	)
	(segment
		(start 58.06694 -7.709154)
		(end 57.928256 -7.57047)
		(width 0.12954)
		(layer "F.Cu")
		(net "CLK_100M_CPU1_CLK03_DN")
	)
	(segment
		(start 161.237676 -149.988016)
		(end 161.571686 -150.322026)
		(width 0.12954)
		(layer "F.Cu")
		(net "CLK_100M_CPU1_CLK03_DN")
	)
	(segment
		(start 161.571686 -150.322026)
		(end 161.571686 -151.426926)
		(width 0.12954)
		(layer "F.Cu")
		(net "CLK_100M_CPU1_CLK03_DN")
	)
	(segment
		(start 57.928256 -6.996176)
		(end 58.199274 -6.725158)
		(width 0.12954)
		(layer "F.Cu")
		(net "CLK_100M_CPU1_CLK03_DN")
	)
	(segment
		(start 57.928256 -7.57047)
		(end 57.928256 -6.996176)
		(width 0.12954)
		(layer "F.Cu")
		(net "CLK_100M_CPU1_CLK03_DN")
	)
	(via
		(at 161.237676 -149.988016)
		(size 0.508)
		(drill 0.254)
		(layers "F.Cu" "B.Cu")
		(net "CLK_100M_CPU1_CLK03_DN")
	)
	(via
		(at 58.199274 -6.725158)
		(size 0.508)
		(drill 0.254)
		(layers "F.Cu" "B.Cu")
		(net "CLK_100M_CPU1_CLK03_DN")
	)
	(segment
		(start 61.90488 -16.259556)
		(end 60.202826 -14.557502)
		(width 0.14224)
		(layer "In11.Cu")
		(net "CLK_100M_CPU1_CLK03_DN")
	)
	(segment
		(start 161.940494 -150.998174)
		(end 162.552126 -150.998174)
		(width 0.14224)
		(layer "In11.Cu")
		(net "CLK_100M_CPU1_CLK03_DN")
	)
	(segment
		(start 63.913512 -16.259556)
		(end 61.90488 -16.259556)
		(width 0.14224)
		(layer "In11.Cu")
		(net "CLK_100M_CPU1_CLK03_DN")
	)
	(segment
		(start 161.237676 -149.988016)
		(end 161.59734 -150.34768)
		(width 0.14224)
		(layer "In11.Cu")
		(net "CLK_100M_CPU1_CLK03_DN")
	)
	(segment
		(start 161.366708 -138.31062)
		(end 84.95157 -61.895482)
		(width 0.14224)
		(layer "In11.Cu")
		(net "CLK_100M_CPU1_CLK03_DN")
	)
	(segment
		(start 84.95157 -61.895482)
		(end 79.545688 -48.844708)
		(width 0.14224)
		(layer "In11.Cu")
		(net "CLK_100M_CPU1_CLK03_DN")
	)
	(segment
		(start 65.462658 -27.27706)
		(end 64.49949 -24.95169)
		(width 0.14224)
		(layer "In11.Cu")
		(net "CLK_100M_CPU1_CLK03_DN")
	)
	(segment
		(start 161.59734 -150.65502)
		(end 161.940494 -150.998174)
		(width 0.14224)
		(layer "In11.Cu")
		(net "CLK_100M_CPU1_CLK03_DN")
	)
	(segment
		(start 57.908444 -7.015988)
		(end 58.199274 -6.725158)
		(width 0.14224)
		(layer "In11.Cu")
		(net "CLK_100M_CPU1_CLK03_DN")
	)
	(segment
		(start 65.462658 -31.122366)
		(end 65.462658 -27.27706)
		(width 0.14224)
		(layer "In11.Cu")
		(net "CLK_100M_CPU1_CLK03_DN")
	)
	(segment
		(start 163.257992 -148.511768)
		(end 161.366708 -146.620484)
		(width 0.14224)
		(layer "In11.Cu")
		(net "CLK_100M_CPU1_CLK03_DN")
	)
	(segment
		(start 67.177412 -36.476432)
		(end 67.177412 -32.83712)
		(width 0.14224)
		(layer "In11.Cu")
		(net "CLK_100M_CPU1_CLK03_DN")
	)
	(segment
		(start 64.49949 -24.95169)
		(end 64.49949 -16.845534)
		(width 0.14224)
		(layer "In11.Cu")
		(net "CLK_100M_CPU1_CLK03_DN")
	)
	(segment
		(start 67.177412 -32.83712)
		(end 65.462658 -31.122366)
		(width 0.14224)
		(layer "In11.Cu")
		(net "CLK_100M_CPU1_CLK03_DN")
	)
	(segment
		(start 79.545688 -48.844708)
		(end 67.177412 -36.476432)
		(width 0.14224)
		(layer "In11.Cu")
		(net "CLK_100M_CPU1_CLK03_DN")
	)
	(segment
		(start 161.59734 -150.34768)
		(end 161.59734 -150.65502)
		(width 0.14224)
		(layer "In11.Cu")
		(net "CLK_100M_CPU1_CLK03_DN")
	)
	(segment
		(start 64.49949 -16.845534)
		(end 63.913512 -16.259556)
		(width 0.14224)
		(layer "In11.Cu")
		(net "CLK_100M_CPU1_CLK03_DN")
	)
	(segment
		(start 163.257992 -150.292308)
		(end 163.257992 -148.511768)
		(width 0.14224)
		(layer "In11.Cu")
		(net "CLK_100M_CPU1_CLK03_DN")
	)
	(segment
		(start 57.908444 -10.216642)
		(end 57.908444 -7.015988)
		(width 0.14224)
		(layer "In11.Cu")
		(net "CLK_100M_CPU1_CLK03_DN")
	)
	(segment
		(start 162.552126 -150.998174)
		(end 163.257992 -150.292308)
		(width 0.14224)
		(layer "In11.Cu")
		(net "CLK_100M_CPU1_CLK03_DN")
	)
	(segment
		(start 161.366708 -146.620484)
		(end 161.366708 -138.31062)
		(width 0.14224)
		(layer "In11.Cu")
		(net "CLK_100M_CPU1_CLK03_DN")
	)
	(segment
		(start 60.202826 -12.511024)
		(end 57.908444 -10.216642)
		(width 0.14224)
		(layer "In11.Cu")
		(net "CLK_100M_CPU1_CLK03_DN")
	)
	(segment
		(start 60.202826 -14.557502)
		(end 60.202826 -12.511024)
		(width 0.14224)
		(layer "In11.Cu")
		(net "CLK_100M_CPU1_CLK03_DN")
	)
	(segment
		(start 146.206972 -208.898744)
		(end 146.397472 -208.708244)
		(width 0.12954)
		(layer "F.Cu")
		(net "CLK_100M_CPU1_CLK02_R_DP")
	)
	(segment
		(start 141.66088 -221.401132)
		(end 141.66088 -219.910914)
		(width 0.12954)
		(layer "F.Cu")
		(net "CLK_100M_CPU1_CLK02_R_DP")
	)
	(segment
		(start 141.72692 -221.467172)
		(end 141.66088 -221.401132)
		(width 0.0762)
		(layer "F.Cu")
		(net "CLK_100M_CPU1_CLK02_R_DP")
	)
	(segment
		(start 146.206972 -210.437984)
		(end 146.206972 -210.051904)
		(width 0.12954)
		(layer "F.Cu")
		(net "CLK_100M_CPU1_CLK02_R_DP")
	)
	(segment
		(start 146.397472 -209.475324)
		(end 146.206972 -209.284824)
		(width 0.12954)
		(layer "F.Cu")
		(net "CLK_100M_CPU1_CLK02_R_DP")
	)
	(segment
		(start 141.699234 -223.153732)
		(end 141.718792 -223.226376)
		(width 0.0762)
		(layer "F.Cu")
		(net "CLK_100M_CPU1_CLK02_R_DP")
	)
	(segment
		(start 155.653232 -192.40754)
		(end 155.653232 -192.108074)
		(width 0.12954)
		(layer "F.Cu")
		(net "CLK_100M_CPU1_CLK02_R_DP")
	)
	(segment
		(start 141.857984 -222.880428)
		(end 141.818106 -222.948754)
		(width 0.0762)
		(layer "F.Cu")
		(net "CLK_100M_CPU1_CLK02_R_DP")
	)
	(segment
		(start 142.075408 -223.185228)
		(end 142.076678 -223.184466)
		(width 0.0762)
		(layer "F.Cu")
		(net "CLK_100M_CPU1_CLK02_R_DP")
	)
	(segment
		(start 141.727174 -222.066358)
		(end 141.72692 -222.063564)
		(width 0.0762)
		(layer "F.Cu")
		(net "CLK_100M_CPU1_CLK02_R_DP")
	)
	(segment
		(start 141.818106 -222.948754)
		(end 141.699234 -223.153732)
		(width 0.0762)
		(layer "F.Cu")
		(net "CLK_100M_CPU1_CLK02_R_DP")
	)
	(segment
		(start 154.192478 -195.933568)
		(end 155.653232 -192.40754)
		(width 0.12954)
		(layer "F.Cu")
		(net "CLK_100M_CPU1_CLK02_R_DP")
	)
	(segment
		(start 146.397472 -211.604098)
		(end 146.397472 -210.628484)
		(width 0.12954)
		(layer "F.Cu")
		(net "CLK_100M_CPU1_CLK02_R_DP")
	)
	(segment
		(start 142.044928 -222.557848)
		(end 142.044674 -222.557594)
		(width 0.0762)
		(layer "F.Cu")
		(net "CLK_100M_CPU1_CLK02_R_DP")
	)
	(segment
		(start 146.206972 -210.051904)
		(end 146.397472 -209.861404)
		(width 0.12954)
		(layer "F.Cu")
		(net "CLK_100M_CPU1_CLK02_R_DP")
	)
	(segment
		(start 146.725894 -213.52129)
		(end 146.725894 -212.397086)
		(width 0.12954)
		(layer "F.Cu")
		(net "CLK_100M_CPU1_CLK02_R_DP")
	)
	(segment
		(start 142.07109 -222.57258)
		(end 142.044928 -222.557848)
		(width 0.0762)
		(layer "F.Cu")
		(net "CLK_100M_CPU1_CLK02_R_DP")
	)
	(segment
		(start 146.206972 -209.284824)
		(end 146.206972 -208.898744)
		(width 0.12954)
		(layer "F.Cu")
		(net "CLK_100M_CPU1_CLK02_R_DP")
	)
	(segment
		(start 141.66088 -219.910914)
		(end 145.789142 -215.782906)
		(width 0.12954)
		(layer "F.Cu")
		(net "CLK_100M_CPU1_CLK02_R_DP")
	)
	(segment
		(start 142.044674 -222.557594)
		(end 142.007336 -222.536004)
		(width 0.0762)
		(layer "F.Cu")
		(net "CLK_100M_CPU1_CLK02_R_DP")
	)
	(segment
		(start 154.005026 -196.386196)
		(end 154.192478 -195.933568)
		(width 0.12954)
		(layer "F.Cu")
		(net "CLK_100M_CPU1_CLK02_R_DP")
	)
	(segment
		(start 155.653232 -192.108074)
		(end 155.306522 -191.761364)
		(width 0.12954)
		(layer "F.Cu")
		(net "CLK_100M_CPU1_CLK02_R_DP")
	)
	(segment
		(start 146.397472 -208.708244)
		(end 146.397472 -203.99375)
		(width 0.12954)
		(layer "F.Cu")
		(net "CLK_100M_CPU1_CLK02_R_DP")
	)
	(segment
		(start 142.044928 -223.203008)
		(end 142.075408 -223.185228)
		(width 0.0762)
		(layer "F.Cu")
		(net "CLK_100M_CPU1_CLK02_R_DP")
	)
	(segment
		(start 146.397472 -209.861404)
		(end 146.397472 -209.475324)
		(width 0.12954)
		(layer "F.Cu")
		(net "CLK_100M_CPU1_CLK02_R_DP")
	)
	(segment
		(start 141.72692 -222.063564)
		(end 141.72692 -221.467172)
		(width 0.0762)
		(layer "F.Cu")
		(net "CLK_100M_CPU1_CLK02_R_DP")
	)
	(segment
		(start 146.725894 -212.397086)
		(end 146.397472 -211.604098)
		(width 0.12954)
		(layer "F.Cu")
		(net "CLK_100M_CPU1_CLK02_R_DP")
	)
	(segment
		(start 146.397472 -203.99375)
		(end 154.005026 -196.386196)
		(width 0.12954)
		(layer "F.Cu")
		(net "CLK_100M_CPU1_CLK02_R_DP")
	)
	(segment
		(start 145.789142 -215.782906)
		(end 146.725894 -213.52129)
		(width 0.12954)
		(layer "F.Cu")
		(net "CLK_100M_CPU1_CLK02_R_DP")
	)
	(segment
		(start 146.397472 -210.628484)
		(end 146.206972 -210.437984)
		(width 0.12954)
		(layer "F.Cu")
		(net "CLK_100M_CPU1_CLK02_R_DP")
	)
	(via
		(at 154.192478 -195.933568)
		(size 0.4064)
		(drill 0.2032)
		(layers "F.Cu" "B.Cu")
		(net "CLK_100M_CPU1_CLK02_R_DP")
	)
	(arc
		(start 142.007336 -222.536004)
		(mid 141.815963 -222.331784)
		(end 141.727174 -222.066358)
		(width 0.0762)
		(layer "F.Cu")
		(net "CLK_100M_CPU1_CLK02_R_DP")
	)
	(arc
		(start 142.076678 -223.184466)
		(mid 142.23249 -222.877046)
		(end 142.07109 -222.57258)
		(width 0.0762)
		(layer "F.Cu")
		(net "CLK_100M_CPU1_CLK02_R_DP")
	)
	(arc
		(start 141.718792 -223.226376)
		(mid 141.884568 -223.252379)
		(end 142.044928 -223.203008)
		(width 0.0762)
		(layer "F.Cu")
		(net "CLK_100M_CPU1_CLK02_R_DP")
	)
	(segment
		(start 142.179802 -222.415862)
		(end 142.179294 -222.415608)
		(width 0.0762)
		(layer "F.Cu")
		(net "CLK_100M_CPU1_CLK02_R_DN")
	)
	(segment
		(start 155.975812 -192.108074)
		(end 156.322522 -191.761364)
		(width 0.12954)
		(layer "F.Cu")
		(net "CLK_100M_CPU1_CLK02_R_DN")
	)
	(segment
		(start 146.062954 -215.965786)
		(end 147.048474 -213.585552)
		(width 0.12954)
		(layer "F.Cu")
		(net "CLK_100M_CPU1_CLK02_R_DN")
	)
	(segment
		(start 141.38783 -223.690434)
		(end 141.546326 -223.41713)
		(width 0.0762)
		(layer "F.Cu")
		(net "CLK_100M_CPU1_CLK02_R_DN")
	)
	(segment
		(start 141.98346 -221.401132)
		(end 141.98346 -221.382082)
		(width 0.0762)
		(layer "F.Cu")
		(net "CLK_100M_CPU1_CLK02_R_DN")
	)
	(segment
		(start 155.82138 -192.84442)
		(end 155.975812 -192.471802)
		(width 0.12954)
		(layer "F.Cu")
		(net "CLK_100M_CPU1_CLK02_R_DN")
	)
	(segment
		(start 141.98346 -220.044772)
		(end 146.062954 -215.965786)
		(width 0.12954)
		(layer "F.Cu")
		(net "CLK_100M_CPU1_CLK02_R_DN")
	)
	(segment
		(start 146.720052 -204.127608)
		(end 154.278584 -196.569076)
		(width 0.12954)
		(layer "F.Cu")
		(net "CLK_100M_CPU1_CLK02_R_DN")
	)
	(segment
		(start 141.98346 -221.382082)
		(end 141.98346 -220.044772)
		(width 0.12954)
		(layer "F.Cu")
		(net "CLK_100M_CPU1_CLK02_R_DN")
	)
	(segment
		(start 142.179294 -222.415608)
		(end 142.109952 -222.374968)
		(width 0.0762)
		(layer "F.Cu")
		(net "CLK_100M_CPU1_CLK02_R_DN")
	)
	(segment
		(start 141.91742 -221.467172)
		(end 141.98346 -221.401132)
		(width 0.0762)
		(layer "F.Cu")
		(net "CLK_100M_CPU1_CLK02_R_DN")
	)
	(segment
		(start 142.140686 -223.367854)
		(end 142.179802 -223.344994)
		(width 0.0762)
		(layer "F.Cu")
		(net "CLK_100M_CPU1_CLK02_R_DN")
	)
	(segment
		(start 155.82138 -192.844674)
		(end 155.82138 -192.84442)
		(width 0.12954)
		(layer "F.Cu")
		(net "CLK_100M_CPU1_CLK02_R_DN")
	)
	(segment
		(start 147.048474 -213.585552)
		(end 147.048474 -212.332824)
		(width 0.12954)
		(layer "F.Cu")
		(net "CLK_100M_CPU1_CLK02_R_DN")
	)
	(segment
		(start 146.720052 -211.539836)
		(end 146.720052 -204.127608)
		(width 0.12954)
		(layer "F.Cu")
		(net "CLK_100M_CPU1_CLK02_R_DN")
	)
	(segment
		(start 154.278584 -196.569076)
		(end 155.82138 -192.844674)
		(width 0.12954)
		(layer "F.Cu")
		(net "CLK_100M_CPU1_CLK02_R_DN")
	)
	(segment
		(start 155.975812 -192.471802)
		(end 155.975812 -192.108074)
		(width 0.12954)
		(layer "F.Cu")
		(net "CLK_100M_CPU1_CLK02_R_DN")
	)
	(segment
		(start 141.91742 -222.05315)
		(end 141.91742 -221.467172)
		(width 0.0762)
		(layer "F.Cu")
		(net "CLK_100M_CPU1_CLK02_R_DN")
	)
	(segment
		(start 147.048474 -212.332824)
		(end 146.720052 -211.539836)
		(width 0.12954)
		(layer "F.Cu")
		(net "CLK_100M_CPU1_CLK02_R_DN")
	)
	(segment
		(start 141.546326 -223.41713)
		(end 141.628368 -223.39554)
		(width 0.0762)
		(layer "F.Cu")
		(net "CLK_100M_CPU1_CLK02_R_DN")
	)
	(via
		(at 155.82138 -192.84442)
		(size 0.4064)
		(drill 0.2032)
		(layers "F.Cu" "B.Cu")
		(net "CLK_100M_CPU1_CLK02_R_DN")
	)
	(arc
		(start 142.179802 -223.344994)
		(mid 142.423129 -222.880428)
		(end 142.179802 -222.415862)
		(width 0.0762)
		(layer "F.Cu")
		(net "CLK_100M_CPU1_CLK02_R_DN")
	)
	(arc
		(start 142.109952 -222.374968)
		(mid 141.979807 -222.234332)
		(end 141.91742 -222.05315)
		(width 0.0762)
		(layer "F.Cu")
		(net "CLK_100M_CPU1_CLK02_R_DN")
	)
	(arc
		(start 141.628368 -223.39554)
		(mid 141.887864 -223.443395)
		(end 142.140686 -223.367854)
		(width 0.0762)
		(layer "F.Cu")
		(net "CLK_100M_CPU1_CLK02_R_DN")
	)
	(segment
		(start 57.466992 -11.26998)
		(end 57.466992 -11.881104)
		(width 0.12954)
		(layer "F.Cu")
		(net "CLK_100M_CPU1_CLK02_DP")
	)
	(segment
		(start 161.704528 -170.901106)
		(end 161.704528 -172.268134)
		(width 0.12954)
		(layer "F.Cu")
		(net "CLK_100M_CPU1_CLK02_DP")
	)
	(segment
		(start 155.653232 -190.614554)
		(end 155.306522 -190.961264)
		(width 0.12954)
		(layer "F.Cu")
		(net "CLK_100M_CPU1_CLK02_DP")
	)
	(segment
		(start 57.605676 -12.019788)
		(end 57.605676 -12.593828)
		(width 0.12954)
		(layer "F.Cu")
		(net "CLK_100M_CPU1_CLK02_DP")
	)
	(segment
		(start 155.653232 -178.31943)
		(end 155.653232 -190.614554)
		(width 0.12954)
		(layer "F.Cu")
		(net "CLK_100M_CPU1_CLK02_DP")
	)
	(segment
		(start 57.466992 -11.881104)
		(end 57.605676 -12.019788)
		(width 0.12954)
		(layer "F.Cu")
		(net "CLK_100M_CPU1_CLK02_DP")
	)
	(segment
		(start 57.605676 -12.593828)
		(end 57.334658 -12.864846)
		(width 0.12954)
		(layer "F.Cu")
		(net "CLK_100M_CPU1_CLK02_DP")
	)
	(segment
		(start 161.704528 -172.268134)
		(end 155.653232 -178.31943)
		(width 0.12954)
		(layer "F.Cu")
		(net "CLK_100M_CPU1_CLK02_DP")
	)
	(segment
		(start 161.434018 -170.630596)
		(end 161.704528 -170.901106)
		(width 0.12954)
		(layer "F.Cu")
		(net "CLK_100M_CPU1_CLK02_DP")
	)
	(via
		(at 161.434018 -170.630596)
		(size 0.508)
		(drill 0.254)
		(layers "F.Cu" "B.Cu")
		(net "CLK_100M_CPU1_CLK02_DP")
	)
	(via
		(at 57.334658 -12.864846)
		(size 0.508)
		(drill 0.254)
		(layers "F.Cu" "B.Cu")
		(net "CLK_100M_CPU1_CLK02_DP")
	)
	(segment
		(start 159.67202 -138.486134)
		(end 83.97748 -62.791594)
		(width 0.14224)
		(layer "In11.Cu")
		(net "CLK_100M_CPU1_CLK02_DP")
	)
	(segment
		(start 159.982662 -150.682706)
		(end 159.67202 -147.533614)
		(width 0.14224)
		(layer "In11.Cu")
		(net "CLK_100M_CPU1_CLK02_DP")
	)
	(segment
		(start 61.64326 -18.536158)
		(end 57.625488 -14.518386)
		(width 0.14224)
		(layer "In11.Cu")
		(net "CLK_100M_CPU1_CLK02_DP")
	)
	(segment
		(start 161.724848 -169.239692)
		(end 160.571434 -153.633424)
		(width 0.14224)
		(layer "In11.Cu")
		(net "CLK_100M_CPU1_CLK02_DP")
	)
	(segment
		(start 64.08166 -38.636956)
		(end 63.042292 -37.597588)
		(width 0.14224)
		(layer "In11.Cu")
		(net "CLK_100M_CPU1_CLK02_DP")
	)
	(segment
		(start 78.464156 -49.481232)
		(end 70.9422 -41.959276)
		(width 0.14224)
		(layer "In11.Cu")
		(net "CLK_100M_CPU1_CLK02_DP")
	)
	(segment
		(start 63.042292 -27.754326)
		(end 61.64326 -26.355294)
		(width 0.14224)
		(layer "In11.Cu")
		(net "CLK_100M_CPU1_CLK02_DP")
	)
	(segment
		(start 161.724848 -170.339766)
		(end 161.724848 -169.239692)
		(width 0.14224)
		(layer "In11.Cu")
		(net "CLK_100M_CPU1_CLK02_DP")
	)
	(segment
		(start 57.625488 -13.155676)
		(end 57.334658 -12.864846)
		(width 0.14224)
		(layer "In11.Cu")
		(net "CLK_100M_CPU1_CLK02_DP")
	)
	(segment
		(start 70.9422 -41.959276)
		(end 65.614296 -41.959276)
		(width 0.14224)
		(layer "In11.Cu")
		(net "CLK_100M_CPU1_CLK02_DP")
	)
	(segment
		(start 63.042292 -37.597588)
		(end 63.042292 -27.754326)
		(width 0.14224)
		(layer "In11.Cu")
		(net "CLK_100M_CPU1_CLK02_DP")
	)
	(segment
		(start 160.571434 -153.633424)
		(end 159.982662 -150.682706)
		(width 0.14224)
		(layer "In11.Cu")
		(net "CLK_100M_CPU1_CLK02_DP")
	)
	(segment
		(start 159.67202 -147.533614)
		(end 159.67202 -138.486134)
		(width 0.14224)
		(layer "In11.Cu")
		(net "CLK_100M_CPU1_CLK02_DP")
	)
	(segment
		(start 161.434018 -170.630596)
		(end 161.724848 -170.339766)
		(width 0.14224)
		(layer "In11.Cu")
		(net "CLK_100M_CPU1_CLK02_DP")
	)
	(segment
		(start 83.97748 -62.791594)
		(end 78.464156 -49.481232)
		(width 0.14224)
		(layer "In11.Cu")
		(net "CLK_100M_CPU1_CLK02_DP")
	)
	(segment
		(start 65.614296 -41.959276)
		(end 64.08166 -40.42664)
		(width 0.14224)
		(layer "In11.Cu")
		(net "CLK_100M_CPU1_CLK02_DP")
	)
	(segment
		(start 64.08166 -40.42664)
		(end 64.08166 -38.636956)
		(width 0.14224)
		(layer "In11.Cu")
		(net "CLK_100M_CPU1_CLK02_DP")
	)
	(segment
		(start 61.64326 -26.355294)
		(end 61.64326 -18.536158)
		(width 0.14224)
		(layer "In11.Cu")
		(net "CLK_100M_CPU1_CLK02_DP")
	)
	(segment
		(start 57.625488 -14.518386)
		(end 57.625488 -13.155676)
		(width 0.14224)
		(layer "In11.Cu")
		(net "CLK_100M_CPU1_CLK02_DP")
	)
	(segment
		(start 162.027108 -172.401992)
		(end 155.975812 -178.453288)
		(width 0.12954)
		(layer "F.Cu")
		(net "CLK_100M_CPU1_CLK02_DN")
	)
	(segment
		(start 162.297618 -170.630596)
		(end 162.027108 -170.901106)
		(width 0.12954)
		(layer "F.Cu")
		(net "CLK_100M_CPU1_CLK02_DN")
	)
	(segment
		(start 58.06694 -11.26998)
		(end 58.06694 -11.880596)
		(width 0.12954)
		(layer "F.Cu")
		(net "CLK_100M_CPU1_CLK02_DN")
	)
	(segment
		(start 57.928256 -12.019788)
		(end 57.928256 -12.594844)
		(width 0.12954)
		(layer "F.Cu")
		(net "CLK_100M_CPU1_CLK02_DN")
	)
	(segment
		(start 57.928256 -12.594844)
		(end 58.198258 -12.864846)
		(width 0.12954)
		(layer "F.Cu")
		(net "CLK_100M_CPU1_CLK02_DN")
	)
	(segment
		(start 162.027108 -170.901106)
		(end 162.027108 -172.401992)
		(width 0.12954)
		(layer "F.Cu")
		(net "CLK_100M_CPU1_CLK02_DN")
	)
	(segment
		(start 58.06694 -11.880596)
		(end 58.067194 -11.88085)
		(width 0.12954)
		(layer "F.Cu")
		(net "CLK_100M_CPU1_CLK02_DN")
	)
	(segment
		(start 155.975812 -190.614554)
		(end 156.322522 -190.961264)
		(width 0.12954)
		(layer "F.Cu")
		(net "CLK_100M_CPU1_CLK02_DN")
	)
	(segment
		(start 58.067194 -11.88085)
		(end 57.928256 -12.019788)
		(width 0.12954)
		(layer "F.Cu")
		(net "CLK_100M_CPU1_CLK02_DN")
	)
	(segment
		(start 155.975812 -178.453288)
		(end 155.975812 -190.614554)
		(width 0.12954)
		(layer "F.Cu")
		(net "CLK_100M_CPU1_CLK02_DN")
	)
	(via
		(at 58.198258 -12.864846)
		(size 0.508)
		(drill 0.254)
		(layers "F.Cu" "B.Cu")
		(net "CLK_100M_CPU1_CLK02_DN")
	)
	(via
		(at 162.297618 -170.630596)
		(size 0.762)
		(drill 0.254)
		(layers "F.Cu" "B.Cu")
		(net "CLK_100M_CPU1_CLK02_DN")
	)
	(segment
		(start 61.9252 -18.419318)
		(end 57.907428 -14.401546)
		(width 0.14224)
		(layer "In11.Cu")
		(net "CLK_100M_CPU1_CLK02_DN")
	)
	(segment
		(start 71.05904 -41.677336)
		(end 65.731136 -41.677336)
		(width 0.14224)
		(layer "In11.Cu")
		(net "CLK_100M_CPU1_CLK02_DN")
	)
	(segment
		(start 162.006788 -169.229278)
		(end 160.851342 -153.595324)
		(width 0.14224)
		(layer "In11.Cu")
		(net "CLK_100M_CPU1_CLK02_DN")
	)
	(segment
		(start 84.216494 -62.631828)
		(end 78.70317 -49.321466)
		(width 0.14224)
		(layer "In11.Cu")
		(net "CLK_100M_CPU1_CLK02_DN")
	)
	(segment
		(start 64.3636 -38.520116)
		(end 63.324232 -37.480748)
		(width 0.14224)
		(layer "In11.Cu")
		(net "CLK_100M_CPU1_CLK02_DN")
	)
	(segment
		(start 65.731136 -41.677336)
		(end 64.3636 -40.3098)
		(width 0.14224)
		(layer "In11.Cu")
		(net "CLK_100M_CPU1_CLK02_DN")
	)
	(segment
		(start 78.70317 -49.321466)
		(end 71.05904 -41.677336)
		(width 0.14224)
		(layer "In11.Cu")
		(net "CLK_100M_CPU1_CLK02_DN")
	)
	(segment
		(start 57.907428 -13.155676)
		(end 58.198258 -12.864846)
		(width 0.14224)
		(layer "In11.Cu")
		(net "CLK_100M_CPU1_CLK02_DN")
	)
	(segment
		(start 160.851342 -153.595324)
		(end 160.262062 -150.64105)
		(width 0.14224)
		(layer "In11.Cu")
		(net "CLK_100M_CPU1_CLK02_DN")
	)
	(segment
		(start 162.006788 -170.339766)
		(end 162.006788 -169.229278)
		(width 0.14224)
		(layer "In11.Cu")
		(net "CLK_100M_CPU1_CLK02_DN")
	)
	(segment
		(start 63.324232 -27.637486)
		(end 61.9252 -26.238454)
		(width 0.14224)
		(layer "In11.Cu")
		(net "CLK_100M_CPU1_CLK02_DN")
	)
	(segment
		(start 160.262062 -150.64105)
		(end 159.95396 -147.519644)
		(width 0.14224)
		(layer "In11.Cu")
		(net "CLK_100M_CPU1_CLK02_DN")
	)
	(segment
		(start 159.95396 -138.369294)
		(end 84.216494 -62.631828)
		(width 0.14224)
		(layer "In11.Cu")
		(net "CLK_100M_CPU1_CLK02_DN")
	)
	(segment
		(start 63.324232 -37.480748)
		(end 63.324232 -27.637486)
		(width 0.14224)
		(layer "In11.Cu")
		(net "CLK_100M_CPU1_CLK02_DN")
	)
	(segment
		(start 159.95396 -147.519644)
		(end 159.95396 -138.369294)
		(width 0.14224)
		(layer "In11.Cu")
		(net "CLK_100M_CPU1_CLK02_DN")
	)
	(segment
		(start 64.3636 -40.3098)
		(end 64.3636 -38.520116)
		(width 0.14224)
		(layer "In11.Cu")
		(net "CLK_100M_CPU1_CLK02_DN")
	)
	(segment
		(start 57.907428 -14.401546)
		(end 57.907428 -13.155676)
		(width 0.14224)
		(layer "In11.Cu")
		(net "CLK_100M_CPU1_CLK02_DN")
	)
	(segment
		(start 162.297618 -170.630596)
		(end 162.006788 -170.339766)
		(width 0.14224)
		(layer "In11.Cu")
		(net "CLK_100M_CPU1_CLK02_DN")
	)
	(segment
		(start 61.9252 -26.238454)
		(end 61.9252 -18.419318)
		(width 0.14224)
		(layer "In11.Cu")
		(net "CLK_100M_CPU1_CLK02_DN")
	)
	(segment
		(start 138.0744 -210.813904)
		(end 138.0744 -213.826852)
		(width 0.12954)
		(layer "F.Cu")
		(net "CLK_100M_CPU1_CLK01_R_DP")
	)
	(segment
		(start 153.624534 -192.105026)
		(end 153.624534 -194.378834)
		(width 0.12954)
		(layer "F.Cu")
		(net "CLK_100M_CPU1_CLK01_R_DP")
	)
	(segment
		(start 153.624534 -194.378834)
		(end 152.998678 -195.889626)
		(width 0.12954)
		(layer "F.Cu")
		(net "CLK_100M_CPU1_CLK01_R_DP")
	)
	(segment
		(start 152.998678 -195.889626)
		(end 152.564338 -196.323966)
		(width 0.12954)
		(layer "F.Cu")
		(net "CLK_100M_CPU1_CLK01_R_DP")
	)
	(segment
		(start 153.277824 -191.758316)
		(end 153.624534 -192.105026)
		(width 0.12954)
		(layer "F.Cu")
		(net "CLK_100M_CPU1_CLK01_R_DP")
	)
	(segment
		(start 139.816586 -218.032838)
		(end 139.816586 -221.761812)
		(width 0.12954)
		(layer "F.Cu")
		(net "CLK_100M_CPU1_CLK01_R_DP")
	)
	(segment
		(start 138.0744 -213.826852)
		(end 139.816586 -218.032838)
		(width 0.12954)
		(layer "F.Cu")
		(net "CLK_100M_CPU1_CLK01_R_DP")
	)
	(segment
		(start 139.816586 -221.761812)
		(end 139.507976 -222.070422)
		(width 0.12954)
		(layer "F.Cu")
		(net "CLK_100M_CPU1_CLK01_R_DP")
	)
	(segment
		(start 152.564338 -196.323966)
		(end 138.0744 -210.813904)
		(width 0.12954)
		(layer "F.Cu")
		(net "CLK_100M_CPU1_CLK01_R_DP")
	)
	(via
		(at 152.564338 -196.323966)
		(size 0.4064)
		(drill 0.2032)
		(layers "F.Cu" "B.Cu")
		(net "CLK_100M_CPU1_CLK01_R_DP")
	)
	(segment
		(start 153.947114 -193.138044)
		(end 153.947114 -194.443096)
		(width 0.12954)
		(layer "F.Cu")
		(net "CLK_100M_CPU1_CLK01_R_DN")
	)
	(segment
		(start 154.293824 -191.758316)
		(end 153.947114 -192.105026)
		(width 0.12954)
		(layer "F.Cu")
		(net "CLK_100M_CPU1_CLK01_R_DN")
	)
	(segment
		(start 140.139166 -217.968576)
		(end 140.139166 -221.761812)
		(width 0.12954)
		(layer "F.Cu")
		(net "CLK_100M_CPU1_CLK01_R_DN")
	)
	(segment
		(start 138.39698 -213.76259)
		(end 140.139166 -217.968576)
		(width 0.12954)
		(layer "F.Cu")
		(net "CLK_100M_CPU1_CLK01_R_DN")
	)
	(segment
		(start 153.272236 -196.072506)
		(end 138.39698 -210.947762)
		(width 0.12954)
		(layer "F.Cu")
		(net "CLK_100M_CPU1_CLK01_R_DN")
	)
	(segment
		(start 153.947114 -194.443096)
		(end 153.272236 -196.072506)
		(width 0.12954)
		(layer "F.Cu")
		(net "CLK_100M_CPU1_CLK01_R_DN")
	)
	(segment
		(start 140.139166 -221.761812)
		(end 140.447776 -222.070422)
		(width 0.12954)
		(layer "F.Cu")
		(net "CLK_100M_CPU1_CLK01_R_DN")
	)
	(segment
		(start 138.39698 -210.947762)
		(end 138.39698 -213.76259)
		(width 0.12954)
		(layer "F.Cu")
		(net "CLK_100M_CPU1_CLK01_R_DN")
	)
	(segment
		(start 153.947114 -192.105026)
		(end 153.947114 -193.138044)
		(width 0.12954)
		(layer "F.Cu")
		(net "CLK_100M_CPU1_CLK01_R_DN")
	)
	(via
		(at 153.947114 -193.138044)
		(size 0.4064)
		(drill 0.2032)
		(layers "F.Cu" "B.Cu")
		(net "CLK_100M_CPU1_CLK01_R_DN")
	)
	(segment
		(start 215.129872 -207.618584)
		(end 215.129872 -318.703452)
		(width 0.12954)
		(layer "F.Cu")
		(net "CLK_100M_CPU1_CLK01_DP")
	)
	(segment
		(start 153.624534 -176.900332)
		(end 160.979358 -169.545508)
		(width 0.12954)
		(layer "F.Cu")
		(net "CLK_100M_CPU1_CLK01_DP")
	)
	(segment
		(start 215.129872 -318.703452)
		(end 210.610196 -323.223128)
		(width 0.12954)
		(layer "F.Cu")
		(net "CLK_100M_CPU1_CLK01_DP")
	)
	(segment
		(start 172.403008 -167.49268)
		(end 181.385972 -158.509716)
		(width 0.12954)
		(layer "F.Cu")
		(net "CLK_100M_CPU1_CLK01_DP")
	)
	(segment
		(start 207.090264 -352.15195)
		(end 206.831184 -352.41103)
		(width 0.12954)
		(layer "F.Cu")
		(net "CLK_100M_CPU1_CLK01_DP")
	)
	(segment
		(start 181.385972 -158.509716)
		(end 185.032904 -158.509716)
		(width 0.12954)
		(layer "F.Cu")
		(net "CLK_100M_CPU1_CLK01_DP")
	)
	(segment
		(start 153.277824 -190.958216)
		(end 153.624534 -190.611506)
		(width 0.12954)
		(layer "F.Cu")
		(net "CLK_100M_CPU1_CLK01_DP")
	)
	(segment
		(start 210.610196 -336.089498)
		(end 210.610196 -349.68434)
		(width 0.12954)
		(layer "F.Cu")
		(net "CLK_100M_CPU1_CLK01_DP")
	)
	(segment
		(start 194.000374 -162.22345)
		(end 212.783166 -181.007512)
		(width 0.12954)
		(layer "F.Cu")
		(net "CLK_100M_CPU1_CLK01_DP")
	)
	(segment
		(start 208.142586 -352.15195)
		(end 207.090264 -352.15195)
		(width 0.12954)
		(layer "F.Cu")
		(net "CLK_100M_CPU1_CLK01_DP")
	)
	(segment
		(start 185.032904 -158.509716)
		(end 194.000374 -162.22345)
		(width 0.12954)
		(layer "F.Cu")
		(net "CLK_100M_CPU1_CLK01_DP")
	)
	(segment
		(start 210.610196 -349.68434)
		(end 208.142586 -352.15195)
		(width 0.12954)
		(layer "F.Cu")
		(net "CLK_100M_CPU1_CLK01_DP")
	)
	(segment
		(start 160.979358 -169.545508)
		(end 167.447214 -169.545508)
		(width 0.12954)
		(layer "F.Cu")
		(net "CLK_100M_CPU1_CLK01_DP")
	)
	(segment
		(start 167.447214 -169.545508)
		(end 172.403008 -167.49268)
		(width 0.12954)
		(layer "F.Cu")
		(net "CLK_100M_CPU1_CLK01_DP")
	)
	(segment
		(start 153.624534 -190.611506)
		(end 153.624534 -176.900332)
		(width 0.12954)
		(layer "F.Cu")
		(net "CLK_100M_CPU1_CLK01_DP")
	)
	(segment
		(start 215.312498 -187.113672)
		(end 215.312498 -207.435958)
		(width 0.12954)
		(layer "F.Cu")
		(net "CLK_100M_CPU1_CLK01_DP")
	)
	(segment
		(start 215.312498 -207.435958)
		(end 215.129872 -207.618584)
		(width 0.12954)
		(layer "F.Cu")
		(net "CLK_100M_CPU1_CLK01_DP")
	)
	(segment
		(start 210.610196 -323.223128)
		(end 210.610196 -336.089498)
		(width 0.12954)
		(layer "F.Cu")
		(net "CLK_100M_CPU1_CLK01_DP")
	)
	(segment
		(start 212.783166 -181.007512)
		(end 215.312498 -187.113672)
		(width 0.12954)
		(layer "F.Cu")
		(net "CLK_100M_CPU1_CLK01_DP")
	)
	(via
		(at 210.610196 -336.089498)
		(size 0.4064)
		(drill 0.2032)
		(layers "F.Cu" "B.Cu")
		(net "CLK_100M_CPU1_CLK01_DP")
	)
	(segment
		(start 57.302146 -420.87927)
		(end 57.439306 -420.74211)
		(width 0.14224)
		(layer "In4.Cu")
		(net "CLK_100M_CPU1_CLK01_DP")
	)
	(segment
		(start 134.289292 -390.795764)
		(end 134.531862 -390.337548)
		(width 0.14224)
		(layer "In4.Cu")
		(net "CLK_100M_CPU1_CLK01_DP")
	)
	(segment
		(start 141.210284 -384.384296)
		(end 142.92199 -382.298702)
		(width 0.14224)
		(layer "In4.Cu")
		(net "CLK_100M_CPU1_CLK01_DP")
	)
	(segment
		(start 59.581034 -411.386274)
		(end 60.074048 -411.386274)
		(width 0.14224)
		(layer "In4.Cu")
		(net "CLK_100M_CPU1_CLK01_DP")
	)
	(segment
		(start 135.441944 -387.460998)
		(end 137.03808 -387.916928)
		(width 0.14224)
		(layer "In4.Cu")
		(net "CLK_100M_CPU1_CLK01_DP")
	)
	(segment
		(start 151.160734 -363.89183)
		(end 151.35479 -363.89183)
		(width 0.14224)
		(layer "In4.Cu")
		(net "CLK_100M_CPU1_CLK01_DP")
	)
	(segment
		(start 146.628866 -373.30126)
		(end 146.10588 -372.778274)
		(width 0.14224)
		(layer "In4.Cu")
		(net "CLK_100M_CPU1_CLK01_DP")
	)
	(segment
		(start 57.439306 -419.61435)
		(end 57.439306 -419.18763)
		(width 0.14224)
		(layer "In4.Cu")
		(net "CLK_100M_CPU1_CLK01_DP")
	)
	(segment
		(start 151.958294 -363.09427)
		(end 152.15235 -363.09427)
		(width 0.14224)
		(layer "In4.Cu")
		(net "CLK_100M_CPU1_CLK01_DP")
	)
	(segment
		(start 57.439306 -420.31539)
		(end 57.302146 -420.17823)
		(width 0.14224)
		(layer "In4.Cu")
		(net "CLK_100M_CPU1_CLK01_DP")
	)
	(segment
		(start 137.780014 -387.814566)
		(end 141.210284 -384.384296)
		(width 0.14224)
		(layer "In4.Cu")
		(net "CLK_100M_CPU1_CLK01_DP")
	)
	(segment
		(start 134.7216 -387.580886)
		(end 135.441944 -387.460998)
		(width 0.14224)
		(layer "In4.Cu")
		(net "CLK_100M_CPU1_CLK01_DP")
	)
	(segment
		(start 152.755854 -362.29671)
		(end 152.94991 -362.29671)
		(width 0.14224)
		(layer "In4.Cu")
		(net "CLK_100M_CPU1_CLK01_DP")
	)
	(segment
		(start 203.261722 -354.693728)
		(end 204.429614 -353.525836)
		(width 0.14224)
		(layer "In4.Cu")
		(net "CLK_100M_CPU1_CLK01_DP")
	)
	(segment
		(start 146.628866 -375.083832)
		(end 146.628866 -373.30126)
		(width 0.14224)
		(layer "In4.Cu")
		(net "CLK_100M_CPU1_CLK01_DP")
	)
	(segment
		(start 57.523888 -422.948862)
		(end 57.302146 -422.72712)
		(width 0.14224)
		(layer "In4.Cu")
		(net "CLK_100M_CPU1_CLK01_DP")
	)
	(segment
		(start 60.618878 -410.841444)
		(end 60.618878 -409.08478)
		(width 0.14224)
		(layer "In4.Cu")
		(net "CLK_100M_CPU1_CLK01_DP")
	)
	(segment
		(start 204.429614 -353.525836)
		(end 204.62367 -353.525836)
		(width 0.14224)
		(layer "In4.Cu")
		(net "CLK_100M_CPU1_CLK01_DP")
	)
	(segment
		(start 57.302146 -422.72712)
		(end 57.302146 -420.87927)
		(width 0.14224)
		(layer "In4.Cu")
		(net "CLK_100M_CPU1_CLK01_DP")
	)
	(segment
		(start 58.369962 -414.446466)
		(end 59.088274 -413.728154)
		(width 0.14224)
		(layer "In4.Cu")
		(net "CLK_100M_CPU1_CLK01_DP")
	)
	(segment
		(start 99.437952 -407.070052)
		(end 105.054908 -401.453096)
		(width 0.14224)
		(layer "In4.Cu")
		(net "CLK_100M_CPU1_CLK01_DP")
	)
	(segment
		(start 205.82382 -352.13163)
		(end 206.551784 -352.13163)
		(width 0.14224)
		(layer "In4.Cu")
		(net "CLK_100M_CPU1_CLK01_DP")
	)
	(segment
		(start 150.55723 -364.68939)
		(end 150.859236 -364.387384)
		(width 0.14224)
		(layer "In4.Cu")
		(net "CLK_100M_CPU1_CLK01_DP")
	)
	(segment
		(start 142.92199 -382.298702)
		(end 144.81175 -379.470666)
		(width 0.14224)
		(layer "In4.Cu")
		(net "CLK_100M_CPU1_CLK01_DP")
	)
	(segment
		(start 114.00663 -393.088876)
		(end 114.348768 -392.4046)
		(width 0.14224)
		(layer "In4.Cu")
		(net "CLK_100M_CPU1_CLK01_DP")
	)
	(segment
		(start 113.7158 -393.257786)
		(end 114.00663 -393.088876)
		(width 0.14224)
		(layer "In4.Cu")
		(net "CLK_100M_CPU1_CLK01_DP")
	)
	(segment
		(start 59.088274 -411.879034)
		(end 59.581034 -411.386274)
		(width 0.14224)
		(layer "In4.Cu")
		(net "CLK_100M_CPU1_CLK01_DP")
	)
	(segment
		(start 146.615404 -369.570508)
		(end 146.615404 -368.43716)
		(width 0.14224)
		(layer "In4.Cu")
		(net "CLK_100M_CPU1_CLK01_DP")
	)
	(segment
		(start 134.099046 -388.578852)
		(end 134.25424 -388.06628)
		(width 0.14224)
		(layer "In4.Cu")
		(net "CLK_100M_CPU1_CLK01_DP")
	)
	(segment
		(start 57.439306 -420.74211)
		(end 57.439306 -420.31539)
		(width 0.14224)
		(layer "In4.Cu")
		(net "CLK_100M_CPU1_CLK01_DP")
	)
	(segment
		(start 204.925676 -353.22383)
		(end 204.925676 -353.029774)
		(width 0.14224)
		(layer "In4.Cu")
		(net "CLK_100M_CPU1_CLK01_DP")
	)
	(segment
		(start 134.531862 -390.337548)
		(end 134.56158 -389.99033)
		(width 0.14224)
		(layer "In4.Cu")
		(net "CLK_100M_CPU1_CLK01_DP")
	)
	(segment
		(start 114.421158 -391.412222)
		(end 114.721894 -391.11174)
		(width 0.14224)
		(layer "In4.Cu")
		(net "CLK_100M_CPU1_CLK01_DP")
	)
	(segment
		(start 134.25424 -388.06628)
		(end 134.7216 -387.580886)
		(width 0.14224)
		(layer "In4.Cu")
		(net "CLK_100M_CPU1_CLK01_DP")
	)
	(segment
		(start 153.251916 -361.800648)
		(end 154.964384 -360.08818)
		(width 0.14224)
		(layer "In4.Cu")
		(net "CLK_100M_CPU1_CLK01_DP")
	)
	(segment
		(start 96.752664 -408.649678)
		(end 98.33229 -407.070052)
		(width 0.14224)
		(layer "In4.Cu")
		(net "CLK_100M_CPU1_CLK01_DP")
	)
	(segment
		(start 58.369962 -414.640268)
		(end 58.369962 -414.446466)
		(width 0.14224)
		(layer "In4.Cu")
		(net "CLK_100M_CPU1_CLK01_DP")
	)
	(segment
		(start 60.074048 -411.386274)
		(end 60.618878 -410.841444)
		(width 0.14224)
		(layer "In4.Cu")
		(net "CLK_100M_CPU1_CLK01_DP")
	)
	(segment
		(start 150.363174 -364.68939)
		(end 150.55723 -364.68939)
		(width 0.14224)
		(layer "In4.Cu")
		(net "CLK_100M_CPU1_CLK01_DP")
	)
	(segment
		(start 98.33229 -407.070052)
		(end 99.437952 -407.070052)
		(width 0.14224)
		(layer "In4.Cu")
		(net "CLK_100M_CPU1_CLK01_DP")
	)
	(segment
		(start 145.882106 -370.303806)
		(end 146.615404 -369.570508)
		(width 0.14224)
		(layer "In4.Cu")
		(net "CLK_100M_CPU1_CLK01_DP")
	)
	(segment
		(start 151.656796 -363.395768)
		(end 151.958294 -363.09427)
		(width 0.14224)
		(layer "In4.Cu")
		(net "CLK_100M_CPU1_CLK01_DP")
	)
	(segment
		(start 59.088274 -413.728154)
		(end 59.088274 -411.879034)
		(width 0.14224)
		(layer "In4.Cu")
		(net "CLK_100M_CPU1_CLK01_DP")
	)
	(segment
		(start 177.250852 -364.014258)
		(end 179.757324 -366.52073)
		(width 0.14224)
		(layer "In4.Cu")
		(net "CLK_100M_CPU1_CLK01_DP")
	)
	(segment
		(start 199.917812 -362.76407)
		(end 203.261722 -354.693728)
		(width 0.14224)
		(layer "In4.Cu")
		(net "CLK_100M_CPU1_CLK01_DP")
	)
	(segment
		(start 105.054908 -401.453096)
		(end 109.598968 -399.570956)
		(width 0.14224)
		(layer "In4.Cu")
		(net "CLK_100M_CPU1_CLK01_DP")
	)
	(segment
		(start 193.228722 -366.52073)
		(end 198.23049 -364.451646)
		(width 0.14224)
		(layer "In4.Cu")
		(net "CLK_100M_CPU1_CLK01_DP")
	)
	(segment
		(start 57.302146 -415.514282)
		(end 57.874154 -414.942274)
		(width 0.14224)
		(layer "In4.Cu")
		(net "CLK_100M_CPU1_CLK01_DP")
	)
	(segment
		(start 150.859236 -364.387384)
		(end 150.859236 -364.193328)
		(width 0.14224)
		(layer "In4.Cu")
		(net "CLK_100M_CPU1_CLK01_DP")
	)
	(segment
		(start 57.302146 -419.05047)
		(end 57.302146 -415.514282)
		(width 0.14224)
		(layer "In4.Cu")
		(net "CLK_100M_CPU1_CLK01_DP")
	)
	(segment
		(start 58.190892 -422.948862)
		(end 57.523888 -422.948862)
		(width 0.14224)
		(layer "In4.Cu")
		(net "CLK_100M_CPU1_CLK01_DP")
	)
	(segment
		(start 144.81175 -379.470666)
		(end 146.628866 -375.083832)
		(width 0.14224)
		(layer "In4.Cu")
		(net "CLK_100M_CPU1_CLK01_DP")
	)
	(segment
		(start 146.615404 -368.43716)
		(end 150.363174 -364.68939)
		(width 0.14224)
		(layer "In4.Cu")
		(net "CLK_100M_CPU1_CLK01_DP")
	)
	(segment
		(start 144.929606 -371.884956)
		(end 144.929606 -370.87937)
		(width 0.14224)
		(layer "In4.Cu")
		(net "CLK_100M_CPU1_CLK01_DP")
	)
	(segment
		(start 145.23847 -370.570506)
		(end 145.882106 -370.303806)
		(width 0.14224)
		(layer "In4.Cu")
		(net "CLK_100M_CPU1_CLK01_DP")
	)
	(segment
		(start 152.454356 -362.598208)
		(end 152.755854 -362.29671)
		(width 0.14224)
		(layer "In4.Cu")
		(net "CLK_100M_CPU1_CLK01_DP")
	)
	(segment
		(start 114.348768 -392.4046)
		(end 114.421158 -391.412222)
		(width 0.14224)
		(layer "In4.Cu")
		(net "CLK_100M_CPU1_CLK01_DP")
	)
	(segment
		(start 150.859236 -364.193328)
		(end 151.160734 -363.89183)
		(width 0.14224)
		(layer "In4.Cu")
		(net "CLK_100M_CPU1_CLK01_DP")
	)
	(segment
		(start 169.047414 -360.08818)
		(end 172.973492 -364.014258)
		(width 0.14224)
		(layer "In4.Cu")
		(net "CLK_100M_CPU1_CLK01_DP")
	)
	(segment
		(start 109.598968 -399.570956)
		(end 113.7158 -393.257786)
		(width 0.14224)
		(layer "In4.Cu")
		(net "CLK_100M_CPU1_CLK01_DP")
	)
	(segment
		(start 145.622772 -372.578122)
		(end 144.929606 -371.884956)
		(width 0.14224)
		(layer "In4.Cu")
		(net "CLK_100M_CPU1_CLK01_DP")
	)
	(segment
		(start 198.23049 -364.451646)
		(end 199.917812 -362.76407)
		(width 0.14224)
		(layer "In4.Cu")
		(net "CLK_100M_CPU1_CLK01_DP")
	)
	(segment
		(start 58.64987 -422.489884)
		(end 58.190892 -422.948862)
		(width 0.14224)
		(layer "In4.Cu")
		(net "CLK_100M_CPU1_CLK01_DP")
	)
	(segment
		(start 151.35479 -363.89183)
		(end 151.656796 -363.589824)
		(width 0.14224)
		(layer "In4.Cu")
		(net "CLK_100M_CPU1_CLK01_DP")
	)
	(segment
		(start 179.757324 -366.52073)
		(end 193.228722 -366.52073)
		(width 0.14224)
		(layer "In4.Cu")
		(net "CLK_100M_CPU1_CLK01_DP")
	)
	(segment
		(start 151.656796 -363.589824)
		(end 151.656796 -363.395768)
		(width 0.14224)
		(layer "In4.Cu")
		(net "CLK_100M_CPU1_CLK01_DP")
	)
	(segment
		(start 204.925676 -353.029774)
		(end 205.82382 -352.13163)
		(width 0.14224)
		(layer "In4.Cu")
		(net "CLK_100M_CPU1_CLK01_DP")
	)
	(segment
		(start 153.251916 -361.994704)
		(end 153.251916 -361.800648)
		(width 0.14224)
		(layer "In4.Cu")
		(net "CLK_100M_CPU1_CLK01_DP")
	)
	(segment
		(start 58.067956 -414.942274)
		(end 58.369962 -414.640268)
		(width 0.14224)
		(layer "In4.Cu")
		(net "CLK_100M_CPU1_CLK01_DP")
	)
	(segment
		(start 57.874154 -414.942274)
		(end 58.067956 -414.942274)
		(width 0.14224)
		(layer "In4.Cu")
		(net "CLK_100M_CPU1_CLK01_DP")
	)
	(segment
		(start 133.611366 -391.08634)
		(end 134.289292 -390.795764)
		(width 0.14224)
		(layer "In4.Cu")
		(net "CLK_100M_CPU1_CLK01_DP")
	)
	(segment
		(start 152.454356 -362.792264)
		(end 152.454356 -362.598208)
		(width 0.14224)
		(layer "In4.Cu")
		(net "CLK_100M_CPU1_CLK01_DP")
	)
	(segment
		(start 172.973492 -364.014258)
		(end 177.250852 -364.014258)
		(width 0.14224)
		(layer "In4.Cu")
		(net "CLK_100M_CPU1_CLK01_DP")
	)
	(segment
		(start 57.302146 -420.17823)
		(end 57.302146 -419.75151)
		(width 0.14224)
		(layer "In4.Cu")
		(net "CLK_100M_CPU1_CLK01_DP")
	)
	(segment
		(start 154.964384 -360.08818)
		(end 169.047414 -360.08818)
		(width 0.14224)
		(layer "In4.Cu")
		(net "CLK_100M_CPU1_CLK01_DP")
	)
	(segment
		(start 57.439306 -419.18763)
		(end 57.302146 -419.05047)
		(width 0.14224)
		(layer "In4.Cu")
		(net "CLK_100M_CPU1_CLK01_DP")
	)
	(segment
		(start 137.03808 -387.916928)
		(end 137.780014 -387.814566)
		(width 0.14224)
		(layer "In4.Cu")
		(net "CLK_100M_CPU1_CLK01_DP")
	)
	(segment
		(start 152.94991 -362.29671)
		(end 153.251916 -361.994704)
		(width 0.14224)
		(layer "In4.Cu")
		(net "CLK_100M_CPU1_CLK01_DP")
	)
	(segment
		(start 206.551784 -352.13163)
		(end 206.831184 -352.41103)
		(width 0.14224)
		(layer "In4.Cu")
		(net "CLK_100M_CPU1_CLK01_DP")
	)
	(segment
		(start 61.05398 -408.649678)
		(end 96.752664 -408.649678)
		(width 0.14224)
		(layer "In4.Cu")
		(net "CLK_100M_CPU1_CLK01_DP")
	)
	(segment
		(start 57.302146 -419.75151)
		(end 57.439306 -419.61435)
		(width 0.14224)
		(layer "In4.Cu")
		(net "CLK_100M_CPU1_CLK01_DP")
	)
	(segment
		(start 152.15235 -363.09427)
		(end 152.454356 -362.792264)
		(width 0.14224)
		(layer "In4.Cu")
		(net "CLK_100M_CPU1_CLK01_DP")
	)
	(segment
		(start 204.62367 -353.525836)
		(end 204.925676 -353.22383)
		(width 0.14224)
		(layer "In4.Cu")
		(net "CLK_100M_CPU1_CLK01_DP")
	)
	(segment
		(start 144.929606 -370.87937)
		(end 145.23847 -370.570506)
		(width 0.14224)
		(layer "In4.Cu")
		(net "CLK_100M_CPU1_CLK01_DP")
	)
	(segment
		(start 60.618878 -409.08478)
		(end 61.05398 -408.649678)
		(width 0.14224)
		(layer "In4.Cu")
		(net "CLK_100M_CPU1_CLK01_DP")
	)
	(segment
		(start 146.10588 -372.778274)
		(end 145.622772 -372.578122)
		(width 0.14224)
		(layer "In4.Cu")
		(net "CLK_100M_CPU1_CLK01_DP")
	)
	(segment
		(start 114.721894 -391.11174)
		(end 133.611366 -391.08634)
		(width 0.14224)
		(layer "In4.Cu")
		(net "CLK_100M_CPU1_CLK01_DP")
	)
	(segment
		(start 134.56158 -389.99033)
		(end 134.099046 -388.578852)
		(width 0.14224)
		(layer "In4.Cu")
		(net "CLK_100M_CPU1_CLK01_DP")
	)
	(segment
		(start 214.989918 -204.880464)
		(end 214.799418 -205.070964)
		(width 0.12954)
		(layer "F.Cu")
		(net "CLK_100M_CPU1_CLK01_DN")
	)
	(segment
		(start 153.947114 -190.611506)
		(end 153.947114 -177.03419)
		(width 0.12954)
		(layer "F.Cu")
		(net "CLK_100M_CPU1_CLK01_DN")
	)
	(segment
		(start 211.629244 -180.579776)
		(end 211.898992 -180.579776)
		(width 0.12954)
		(layer "F.Cu")
		(net "CLK_100M_CPU1_CLK01_DN")
	)
	(segment
		(start 214.989918 -204.491844)
		(end 214.989918 -204.880464)
		(width 0.12954)
		(layer "F.Cu")
		(net "CLK_100M_CPU1_CLK01_DN")
	)
	(segment
		(start 214.989918 -203.722224)
		(end 214.799418 -203.912724)
		(width 0.12954)
		(layer "F.Cu")
		(net "CLK_100M_CPU1_CLK01_DN")
	)
	(segment
		(start 207.113124 -351.82937)
		(end 206.831184 -351.54743)
		(width 0.12954)
		(layer "F.Cu")
		(net "CLK_100M_CPU1_CLK01_DN")
	)
	(segment
		(start 210.287616 -346.845382)
		(end 210.287616 -347.234002)
		(width 0.12954)
		(layer "F.Cu")
		(net "CLK_100M_CPU1_CLK01_DN")
	)
	(segment
		(start 210.287616 -323.08927)
		(end 210.287616 -333.421228)
		(width 0.12954)
		(layer "F.Cu")
		(net "CLK_100M_CPU1_CLK01_DN")
	)
	(segment
		(start 172.585888 -167.766238)
		(end 181.51983 -158.832296)
		(width 0.12954)
		(layer "F.Cu")
		(net "CLK_100M_CPU1_CLK01_DN")
	)
	(segment
		(start 209.743548 -349.825056)
		(end 209.468466 -350.100138)
		(width 0.12954)
		(layer "F.Cu")
		(net "CLK_100M_CPU1_CLK01_DN")
	)
	(segment
		(start 210.097116 -346.266262)
		(end 210.097116 -346.654882)
		(width 0.12954)
		(layer "F.Cu")
		(net "CLK_100M_CPU1_CLK01_DN")
	)
	(segment
		(start 154.293824 -190.958216)
		(end 153.947114 -190.611506)
		(width 0.12954)
		(layer "F.Cu")
		(net "CLK_100M_CPU1_CLK01_DN")
	)
	(segment
		(start 210.287616 -349.550482)
		(end 210.013042 -349.825056)
		(width 0.12954)
		(layer "F.Cu")
		(net "CLK_100M_CPU1_CLK01_DN")
	)
	(segment
		(start 208.008728 -351.82937)
		(end 207.113124 -351.82937)
		(width 0.12954)
		(layer "F.Cu")
		(net "CLK_100M_CPU1_CLK01_DN")
	)
	(segment
		(start 210.287616 -347.234002)
		(end 210.097116 -347.424502)
		(width 0.12954)
		(layer "F.Cu")
		(net "CLK_100M_CPU1_CLK01_DN")
	)
	(segment
		(start 210.810094 -179.76088)
		(end 211.079588 -179.76088)
		(width 0.12954)
		(layer "F.Cu")
		(net "CLK_100M_CPU1_CLK01_DN")
	)
	(segment
		(start 157.273498 -173.707806)
		(end 161.113216 -169.868088)
		(width 0.12954)
		(layer "F.Cu")
		(net "CLK_100M_CPU1_CLK01_DN")
	)
	(segment
		(start 210.535012 -179.485798)
		(end 210.810094 -179.76088)
		(width 0.12954)
		(layer "F.Cu")
		(net "CLK_100M_CPU1_CLK01_DN")
	)
	(segment
		(start 210.097116 -346.654882)
		(end 210.287616 -346.845382)
		(width 0.12954)
		(layer "F.Cu")
		(net "CLK_100M_CPU1_CLK01_DN")
	)
	(segment
		(start 210.097116 -348.971362)
		(end 210.287616 -349.161862)
		(width 0.12954)
		(layer "F.Cu")
		(net "CLK_100M_CPU1_CLK01_DN")
	)
	(segment
		(start 155.64231 -175.338994)
		(end 155.915106 -175.066198)
		(width 0.12954)
		(layer "F.Cu")
		(net "CLK_100M_CPU1_CLK01_DN")
	)
	(segment
		(start 214.807292 -207.484726)
		(end 214.807292 -318.569594)
		(width 0.12954)
		(layer "F.Cu")
		(net "CLK_100M_CPU1_CLK01_DN")
	)
	(segment
		(start 156.457904 -174.5234)
		(end 156.7307 -174.250604)
		(width 0.12954)
		(layer "F.Cu")
		(net "CLK_100M_CPU1_CLK01_DN")
	)
	(segment
		(start 210.097116 -347.813122)
		(end 210.287616 -348.003622)
		(width 0.12954)
		(layer "F.Cu")
		(net "CLK_100M_CPU1_CLK01_DN")
	)
	(segment
		(start 156.7307 -174.250604)
		(end 157.000194 -174.250604)
		(width 0.12954)
		(layer "F.Cu")
		(net "CLK_100M_CPU1_CLK01_DN")
	)
	(segment
		(start 210.287616 -346.075762)
		(end 210.097116 -346.266262)
		(width 0.12954)
		(layer "F.Cu")
		(net "CLK_100M_CPU1_CLK01_DN")
	)
	(segment
		(start 181.51983 -158.832296)
		(end 184.968642 -158.832296)
		(width 0.12954)
		(layer "F.Cu")
		(net "CLK_100M_CPU1_CLK01_DN")
	)
	(segment
		(start 155.099766 -175.881538)
		(end 155.369006 -175.881538)
		(width 0.12954)
		(layer "F.Cu")
		(net "CLK_100M_CPU1_CLK01_DN")
	)
	(segment
		(start 214.989918 -187.177934)
		(end 214.989918 -203.722224)
		(width 0.12954)
		(layer "F.Cu")
		(net "CLK_100M_CPU1_CLK01_DN")
	)
	(segment
		(start 210.287616 -348.003622)
		(end 210.287616 -348.392242)
		(width 0.12954)
		(layer "F.Cu")
		(net "CLK_100M_CPU1_CLK01_DN")
	)
	(segment
		(start 211.079588 -179.76088)
		(end 211.354162 -180.035454)
		(width 0.12954)
		(layer "F.Cu")
		(net "CLK_100M_CPU1_CLK01_DN")
	)
	(segment
		(start 167.511476 -169.868088)
		(end 172.585888 -167.766238)
		(width 0.12954)
		(layer "F.Cu")
		(net "CLK_100M_CPU1_CLK01_DN")
	)
	(segment
		(start 193.817494 -162.497262)
		(end 210.535012 -179.216304)
		(width 0.12954)
		(layer "F.Cu")
		(net "CLK_100M_CPU1_CLK01_DN")
	)
	(segment
		(start 209.468466 -350.369632)
		(end 208.008728 -351.82937)
		(width 0.12954)
		(layer "F.Cu")
		(net "CLK_100M_CPU1_CLK01_DN")
	)
	(segment
		(start 184.968642 -158.832296)
		(end 193.817494 -162.497262)
		(width 0.12954)
		(layer "F.Cu")
		(net "CLK_100M_CPU1_CLK01_DN")
	)
	(segment
		(start 211.898992 -180.579776)
		(end 212.509608 -181.190392)
		(width 0.12954)
		(layer "F.Cu")
		(net "CLK_100M_CPU1_CLK01_DN")
	)
	(segment
		(start 210.535012 -179.216304)
		(end 210.535012 -179.485798)
		(width 0.12954)
		(layer "F.Cu")
		(net "CLK_100M_CPU1_CLK01_DN")
	)
	(segment
		(start 210.097116 -348.582742)
		(end 210.097116 -348.971362)
		(width 0.12954)
		(layer "F.Cu")
		(net "CLK_100M_CPU1_CLK01_DN")
	)
	(segment
		(start 210.287616 -348.392242)
		(end 210.097116 -348.582742)
		(width 0.12954)
		(layer "F.Cu")
		(net "CLK_100M_CPU1_CLK01_DN")
	)
	(segment
		(start 210.287616 -333.421228)
		(end 210.287616 -346.075762)
		(width 0.12954)
		(layer "F.Cu")
		(net "CLK_100M_CPU1_CLK01_DN")
	)
	(segment
		(start 214.989918 -205.650084)
		(end 214.989918 -207.3021)
		(width 0.12954)
		(layer "F.Cu")
		(net "CLK_100M_CPU1_CLK01_DN")
	)
	(segment
		(start 161.113216 -169.868088)
		(end 167.511476 -169.868088)
		(width 0.12954)
		(layer "F.Cu")
		(net "CLK_100M_CPU1_CLK01_DN")
	)
	(segment
		(start 155.64231 -175.608234)
		(end 155.64231 -175.338994)
		(width 0.12954)
		(layer "F.Cu")
		(net "CLK_100M_CPU1_CLK01_DN")
	)
	(segment
		(start 156.457904 -174.792894)
		(end 156.457904 -174.5234)
		(width 0.12954)
		(layer "F.Cu")
		(net "CLK_100M_CPU1_CLK01_DN")
	)
	(segment
		(start 210.097116 -347.424502)
		(end 210.097116 -347.813122)
		(width 0.12954)
		(layer "F.Cu")
		(net "CLK_100M_CPU1_CLK01_DN")
	)
	(segment
		(start 214.807292 -318.569594)
		(end 210.287616 -323.08927)
		(width 0.12954)
		(layer "F.Cu")
		(net "CLK_100M_CPU1_CLK01_DN")
	)
	(segment
		(start 157.273498 -173.9773)
		(end 157.273498 -173.707806)
		(width 0.12954)
		(layer "F.Cu")
		(net "CLK_100M_CPU1_CLK01_DN")
	)
	(segment
		(start 210.287616 -349.161862)
		(end 210.287616 -349.550482)
		(width 0.12954)
		(layer "F.Cu")
		(net "CLK_100M_CPU1_CLK01_DN")
	)
	(segment
		(start 210.013042 -349.825056)
		(end 209.743548 -349.825056)
		(width 0.12954)
		(layer "F.Cu")
		(net "CLK_100M_CPU1_CLK01_DN")
	)
	(segment
		(start 157.000194 -174.250604)
		(end 157.273498 -173.9773)
		(width 0.12954)
		(layer "F.Cu")
		(net "CLK_100M_CPU1_CLK01_DN")
	)
	(segment
		(start 211.354162 -180.304694)
		(end 211.629244 -180.579776)
		(width 0.12954)
		(layer "F.Cu")
		(net "CLK_100M_CPU1_CLK01_DN")
	)
	(segment
		(start 214.799418 -205.070964)
		(end 214.799418 -205.459584)
		(width 0.12954)
		(layer "F.Cu")
		(net "CLK_100M_CPU1_CLK01_DN")
	)
	(segment
		(start 214.799418 -203.912724)
		(end 214.799418 -204.301344)
		(width 0.12954)
		(layer "F.Cu")
		(net "CLK_100M_CPU1_CLK01_DN")
	)
	(segment
		(start 212.509608 -181.190392)
		(end 214.989918 -187.177934)
		(width 0.12954)
		(layer "F.Cu")
		(net "CLK_100M_CPU1_CLK01_DN")
	)
	(segment
		(start 156.1846 -175.066198)
		(end 156.457904 -174.792894)
		(width 0.12954)
		(layer "F.Cu")
		(net "CLK_100M_CPU1_CLK01_DN")
	)
	(segment
		(start 214.799418 -205.459584)
		(end 214.989918 -205.650084)
		(width 0.12954)
		(layer "F.Cu")
		(net "CLK_100M_CPU1_CLK01_DN")
	)
	(segment
		(start 155.915106 -175.066198)
		(end 156.1846 -175.066198)
		(width 0.12954)
		(layer "F.Cu")
		(net "CLK_100M_CPU1_CLK01_DN")
	)
	(segment
		(start 214.989918 -207.3021)
		(end 214.807292 -207.484726)
		(width 0.12954)
		(layer "F.Cu")
		(net "CLK_100M_CPU1_CLK01_DN")
	)
	(segment
		(start 214.799418 -204.301344)
		(end 214.989918 -204.491844)
		(width 0.12954)
		(layer "F.Cu")
		(net "CLK_100M_CPU1_CLK01_DN")
	)
	(segment
		(start 209.468466 -350.100138)
		(end 209.468466 -350.369632)
		(width 0.12954)
		(layer "F.Cu")
		(net "CLK_100M_CPU1_CLK01_DN")
	)
	(segment
		(start 155.369006 -175.881538)
		(end 155.64231 -175.608234)
		(width 0.12954)
		(layer "F.Cu")
		(net "CLK_100M_CPU1_CLK01_DN")
	)
	(segment
		(start 153.947114 -177.03419)
		(end 155.099766 -175.881538)
		(width 0.12954)
		(layer "F.Cu")
		(net "CLK_100M_CPU1_CLK01_DN")
	)
	(segment
		(start 211.354162 -180.035454)
		(end 211.354162 -180.304694)
		(width 0.12954)
		(layer "F.Cu")
		(net "CLK_100M_CPU1_CLK01_DN")
	)
	(via
		(at 210.287616 -333.421228)
		(size 0.4064)
		(drill 0.2032)
		(layers "F.Cu" "B.Cu")
		(net "CLK_100M_CPU1_CLK01_DN")
	)
	(segment
		(start 142.695168 -382.130554)
		(end 144.561814 -379.337062)
		(width 0.14224)
		(layer "In4.Cu")
		(net "CLK_100M_CPU1_CLK01_DN")
	)
	(segment
		(start 99.321112 -406.788112)
		(end 104.895142 -401.214082)
		(width 0.14224)
		(layer "In4.Cu")
		(net "CLK_100M_CPU1_CLK01_DN")
	)
	(segment
		(start 58.806334 -411.762194)
		(end 59.464194 -411.104334)
		(width 0.14224)
		(layer "In4.Cu")
		(net "CLK_100M_CPU1_CLK01_DN")
	)
	(segment
		(start 135.4582 -387.1722)
		(end 137.0584 -387.6294)
		(width 0.14224)
		(layer "In4.Cu")
		(net "CLK_100M_CPU1_CLK01_DN")
	)
	(segment
		(start 96.635824 -408.367738)
		(end 98.21545 -406.788112)
		(width 0.14224)
		(layer "In4.Cu")
		(net "CLK_100M_CPU1_CLK01_DN")
	)
	(segment
		(start 206.528924 -351.84969)
		(end 206.831184 -351.54743)
		(width 0.14224)
		(layer "In4.Cu")
		(net "CLK_100M_CPU1_CLK01_DN")
	)
	(segment
		(start 205.70698 -351.84969)
		(end 206.528924 -351.84969)
		(width 0.14224)
		(layer "In4.Cu")
		(net "CLK_100M_CPU1_CLK01_DN")
	)
	(segment
		(start 58.64987 -423.68978)
		(end 58.190892 -423.230802)
		(width 0.14224)
		(layer "In4.Cu")
		(net "CLK_100M_CPU1_CLK01_DN")
	)
	(segment
		(start 114.1476 -391.287)
		(end 114.6048 -390.8298)
		(width 0.14224)
		(layer "In4.Cu")
		(net "CLK_100M_CPU1_CLK01_DN")
	)
	(segment
		(start 133.80339 -388.582154)
		(end 134.003796 -387.919468)
		(width 0.14224)
		(layer "In4.Cu")
		(net "CLK_100M_CPU1_CLK01_DN")
	)
	(segment
		(start 57.407048 -423.230802)
		(end 57.020206 -422.84396)
		(width 0.14224)
		(layer "In4.Cu")
		(net "CLK_100M_CPU1_CLK01_DN")
	)
	(segment
		(start 145.078704 -370.331492)
		(end 145.72234 -370.064792)
		(width 0.14224)
		(layer "In4.Cu")
		(net "CLK_100M_CPU1_CLK01_DN")
	)
	(segment
		(start 98.21545 -406.788112)
		(end 99.321112 -406.788112)
		(width 0.14224)
		(layer "In4.Cu")
		(net "CLK_100M_CPU1_CLK01_DN")
	)
	(segment
		(start 109.410246 -399.343626)
		(end 113.516156 -393.047474)
		(width 0.14224)
		(layer "In4.Cu")
		(net "CLK_100M_CPU1_CLK01_DN")
	)
	(segment
		(start 146.346926 -373.4181)
		(end 145.946114 -373.017288)
		(width 0.14224)
		(layer "In4.Cu")
		(net "CLK_100M_CPU1_CLK01_DN")
	)
	(segment
		(start 134.0866 -390.5758)
		(end 134.255764 -390.256268)
		(width 0.14224)
		(layer "In4.Cu")
		(net "CLK_100M_CPU1_CLK01_DN")
	)
	(segment
		(start 134.58317 -387.317996)
		(end 135.4582 -387.1722)
		(width 0.14224)
		(layer "In4.Cu")
		(net "CLK_100M_CPU1_CLK01_DN")
	)
	(segment
		(start 154.847544 -359.80624)
		(end 169.164254 -359.80624)
		(width 0.14224)
		(layer "In4.Cu")
		(net "CLK_100M_CPU1_CLK01_DN")
	)
	(segment
		(start 134.003796 -387.919468)
		(end 134.58317 -387.317996)
		(width 0.14224)
		(layer "In4.Cu")
		(net "CLK_100M_CPU1_CLK01_DN")
	)
	(segment
		(start 145.72234 -370.064792)
		(end 146.333464 -369.453668)
		(width 0.14224)
		(layer "In4.Cu")
		(net "CLK_100M_CPU1_CLK01_DN")
	)
	(segment
		(start 173.090332 -363.732318)
		(end 177.367692 -363.732318)
		(width 0.14224)
		(layer "In4.Cu")
		(net "CLK_100M_CPU1_CLK01_DN")
	)
	(segment
		(start 145.946114 -373.017288)
		(end 145.463006 -372.817136)
		(width 0.14224)
		(layer "In4.Cu")
		(net "CLK_100M_CPU1_CLK01_DN")
	)
	(segment
		(start 59.464194 -411.104334)
		(end 59.957208 -411.104334)
		(width 0.14224)
		(layer "In4.Cu")
		(net "CLK_100M_CPU1_CLK01_DN")
	)
	(segment
		(start 193.172588 -366.23879)
		(end 198.070724 -364.212378)
		(width 0.14224)
		(layer "In4.Cu")
		(net "CLK_100M_CPU1_CLK01_DN")
	)
	(segment
		(start 141.000988 -384.194558)
		(end 142.695168 -382.130554)
		(width 0.14224)
		(layer "In4.Cu")
		(net "CLK_100M_CPU1_CLK01_DN")
	)
	(segment
		(start 60.93714 -408.367738)
		(end 96.635824 -408.367738)
		(width 0.14224)
		(layer "In4.Cu")
		(net "CLK_100M_CPU1_CLK01_DN")
	)
	(segment
		(start 113.792 -392.8872)
		(end 114.0714 -392.3284)
		(width 0.14224)
		(layer "In4.Cu")
		(net "CLK_100M_CPU1_CLK01_DN")
	)
	(segment
		(start 144.647666 -372.001796)
		(end 144.647666 -370.76253)
		(width 0.14224)
		(layer "In4.Cu")
		(net "CLK_100M_CPU1_CLK01_DN")
	)
	(segment
		(start 60.336938 -408.96794)
		(end 60.93714 -408.367738)
		(width 0.14224)
		(layer "In4.Cu")
		(net "CLK_100M_CPU1_CLK01_DN")
	)
	(segment
		(start 144.561814 -379.337062)
		(end 146.346926 -375.027698)
		(width 0.14224)
		(layer "In4.Cu")
		(net "CLK_100M_CPU1_CLK01_DN")
	)
	(segment
		(start 146.333464 -368.32032)
		(end 154.847544 -359.80624)
		(width 0.14224)
		(layer "In4.Cu")
		(net "CLK_100M_CPU1_CLK01_DN")
	)
	(segment
		(start 144.647666 -370.76253)
		(end 145.078704 -370.331492)
		(width 0.14224)
		(layer "In4.Cu")
		(net "CLK_100M_CPU1_CLK01_DN")
	)
	(segment
		(start 114.72164 -390.829546)
		(end 114.72164 -390.8298)
		(width 0.14224)
		(layer "In4.Cu")
		(net "CLK_100M_CPU1_CLK01_DN")
	)
	(segment
		(start 199.678798 -362.604304)
		(end 203.022708 -354.533962)
		(width 0.14224)
		(layer "In4.Cu")
		(net "CLK_100M_CPU1_CLK01_DN")
	)
	(segment
		(start 146.333464 -369.453668)
		(end 146.333464 -368.32032)
		(width 0.14224)
		(layer "In4.Cu")
		(net "CLK_100M_CPU1_CLK01_DN")
	)
	(segment
		(start 133.5532 -390.8044)
		(end 134.0866 -390.5758)
		(width 0.14224)
		(layer "In4.Cu")
		(net "CLK_100M_CPU1_CLK01_DN")
	)
	(segment
		(start 203.022708 -354.533962)
		(end 205.70698 -351.84969)
		(width 0.14224)
		(layer "In4.Cu")
		(net "CLK_100M_CPU1_CLK01_DN")
	)
	(segment
		(start 104.895142 -401.214082)
		(end 109.410246 -399.343626)
		(width 0.14224)
		(layer "In4.Cu")
		(net "CLK_100M_CPU1_CLK01_DN")
	)
	(segment
		(start 169.164254 -359.80624)
		(end 173.090332 -363.732318)
		(width 0.14224)
		(layer "In4.Cu")
		(net "CLK_100M_CPU1_CLK01_DN")
	)
	(segment
		(start 60.336938 -410.724604)
		(end 60.336938 -408.96794)
		(width 0.14224)
		(layer "In4.Cu")
		(net "CLK_100M_CPU1_CLK01_DN")
	)
	(segment
		(start 58.806334 -413.611314)
		(end 58.806334 -411.762194)
		(width 0.14224)
		(layer "In4.Cu")
		(net "CLK_100M_CPU1_CLK01_DN")
	)
	(segment
		(start 59.957208 -411.104334)
		(end 60.336938 -410.724604)
		(width 0.14224)
		(layer "In4.Cu")
		(net "CLK_100M_CPU1_CLK01_DN")
	)
	(segment
		(start 114.0714 -392.3284)
		(end 114.1476 -391.287)
		(width 0.14224)
		(layer "In4.Cu")
		(net "CLK_100M_CPU1_CLK01_DN")
	)
	(segment
		(start 134.275576 -390.023604)
		(end 133.80339 -388.582154)
		(width 0.14224)
		(layer "In4.Cu")
		(net "CLK_100M_CPU1_CLK01_DN")
	)
	(segment
		(start 57.020206 -415.397442)
		(end 58.806334 -413.611314)
		(width 0.14224)
		(layer "In4.Cu")
		(net "CLK_100M_CPU1_CLK01_DN")
	)
	(segment
		(start 114.72164 -390.8298)
		(end 133.5532 -390.8044)
		(width 0.14224)
		(layer "In4.Cu")
		(net "CLK_100M_CPU1_CLK01_DN")
	)
	(segment
		(start 179.874164 -366.23879)
		(end 193.172588 -366.23879)
		(width 0.14224)
		(layer "In4.Cu")
		(net "CLK_100M_CPU1_CLK01_DN")
	)
	(segment
		(start 134.255764 -390.256268)
		(end 134.275576 -390.023604)
		(width 0.14224)
		(layer "In4.Cu")
		(net "CLK_100M_CPU1_CLK01_DN")
	)
	(segment
		(start 57.020206 -422.84396)
		(end 57.020206 -415.397442)
		(width 0.14224)
		(layer "In4.Cu")
		(net "CLK_100M_CPU1_CLK01_DN")
	)
	(segment
		(start 58.190892 -423.230802)
		(end 57.407048 -423.230802)
		(width 0.14224)
		(layer "In4.Cu")
		(net "CLK_100M_CPU1_CLK01_DN")
	)
	(segment
		(start 137.0584 -387.6294)
		(end 137.64768 -387.54812)
		(width 0.14224)
		(layer "In4.Cu")
		(net "CLK_100M_CPU1_CLK01_DN")
	)
	(segment
		(start 145.463006 -372.817136)
		(end 144.647666 -372.001796)
		(width 0.14224)
		(layer "In4.Cu")
		(net "CLK_100M_CPU1_CLK01_DN")
	)
	(segment
		(start 137.64768 -387.54812)
		(end 141.000988 -384.194558)
		(width 0.14224)
		(layer "In4.Cu")
		(net "CLK_100M_CPU1_CLK01_DN")
	)
	(segment
		(start 114.6048 -390.8298)
		(end 114.72164 -390.829546)
		(width 0.14224)
		(layer "In4.Cu")
		(net "CLK_100M_CPU1_CLK01_DN")
	)
	(segment
		(start 113.516156 -393.047474)
		(end 113.792 -392.8872)
		(width 0.14224)
		(layer "In4.Cu")
		(net "CLK_100M_CPU1_CLK01_DN")
	)
	(segment
		(start 146.346926 -375.027698)
		(end 146.346926 -373.4181)
		(width 0.14224)
		(layer "In4.Cu")
		(net "CLK_100M_CPU1_CLK01_DN")
	)
	(segment
		(start 177.367692 -363.732318)
		(end 179.874164 -366.23879)
		(width 0.14224)
		(layer "In4.Cu")
		(net "CLK_100M_CPU1_CLK01_DN")
	)
	(segment
		(start 198.070724 -364.212378)
		(end 199.678798 -362.604304)
		(width 0.14224)
		(layer "In4.Cu")
		(net "CLK_100M_CPU1_CLK01_DN")
	)
	(segment
		(start 353.907852 -295.690036)
		(end 354.216716 -295.9989)
		(width 0.12954)
		(layer "F.Cu")
		(net "CLK_100M_CPU0_CLK12_R_DP")
	)
	(segment
		(start 340.970362 -299.500544)
		(end 340.600792 -299.130974)
		(width 0.12954)
		(layer "F.Cu")
		(net "CLK_100M_CPU0_CLK12_R_DP")
	)
	(segment
		(start 354.216716 -295.9989)
		(end 354.216716 -296.182288)
		(width 0.12954)
		(layer "F.Cu")
		(net "CLK_100M_CPU0_CLK12_R_DP")
	)
	(segment
		(start 351.945956 -298.453048)
		(end 349.417132 -299.500544)
		(width 0.12954)
		(layer "F.Cu")
		(net "CLK_100M_CPU0_CLK12_R_DP")
	)
	(segment
		(start 354.216716 -296.182288)
		(end 351.945956 -298.453048)
		(width 0.12954)
		(layer "F.Cu")
		(net "CLK_100M_CPU0_CLK12_R_DP")
	)
	(segment
		(start 349.417132 -299.500544)
		(end 340.970362 -299.500544)
		(width 0.12954)
		(layer "F.Cu")
		(net "CLK_100M_CPU0_CLK12_R_DP")
	)
	(via
		(at 340.600792 -299.130974)
		(size 0.508)
		(drill 0.254)
		(layers "F.Cu" "B.Cu")
		(net "CLK_100M_CPU0_CLK12_R_DP")
	)
	(segment
		(start 342.781636 -299.475906)
		(end 343.16416 -299.85843)
		(width 0.12954)
		(layer "B.Cu")
		(net "CLK_100M_CPU0_CLK12_R_DP")
	)
	(segment
		(start 343.16416 -299.85843)
		(end 343.16416 -301.160434)
		(width 0.12954)
		(layer "B.Cu")
		(net "CLK_100M_CPU0_CLK12_R_DP")
	)
	(segment
		(start 340.600792 -299.130974)
		(end 340.945724 -299.475906)
		(width 0.12954)
		(layer "B.Cu")
		(net "CLK_100M_CPU0_CLK12_R_DP")
	)
	(segment
		(start 343.16416 -301.160434)
		(end 343.514934 -301.511208)
		(width 0.12954)
		(layer "B.Cu")
		(net "CLK_100M_CPU0_CLK12_R_DP")
	)
	(segment
		(start 340.945724 -299.475906)
		(end 342.781636 -299.475906)
		(width 0.12954)
		(layer "B.Cu")
		(net "CLK_100M_CPU0_CLK12_R_DP")
	)
	(segment
		(start 354.539296 -295.998646)
		(end 354.539296 -296.316146)
		(width 0.12954)
		(layer "F.Cu")
		(net "CLK_100M_CPU0_CLK12_R_DN")
	)
	(segment
		(start 340.924642 -299.823124)
		(end 340.600792 -300.146974)
		(width 0.12954)
		(layer "F.Cu")
		(net "CLK_100M_CPU0_CLK12_R_DN")
	)
	(segment
		(start 349.481394 -299.823124)
		(end 340.924642 -299.823124)
		(width 0.12954)
		(layer "F.Cu")
		(net "CLK_100M_CPU0_CLK12_R_DN")
	)
	(segment
		(start 354.847906 -295.690036)
		(end 354.539296 -295.998646)
		(width 0.12954)
		(layer "F.Cu")
		(net "CLK_100M_CPU0_CLK12_R_DN")
	)
	(segment
		(start 352.128836 -298.726606)
		(end 349.481394 -299.823124)
		(width 0.12954)
		(layer "F.Cu")
		(net "CLK_100M_CPU0_CLK12_R_DN")
	)
	(segment
		(start 354.539296 -296.316146)
		(end 352.128836 -298.726606)
		(width 0.12954)
		(layer "F.Cu")
		(net "CLK_100M_CPU0_CLK12_R_DN")
	)
	(via
		(at 340.600792 -300.146974)
		(size 0.508)
		(drill 0.254)
		(layers "F.Cu" "B.Cu")
		(net "CLK_100M_CPU0_CLK12_R_DN")
	)
	(segment
		(start 340.94928 -299.798486)
		(end 340.600792 -300.146974)
		(width 0.12954)
		(layer "B.Cu")
		(net "CLK_100M_CPU0_CLK12_R_DN")
	)
	(segment
		(start 342.498934 -301.511208)
		(end 342.84158 -301.168562)
		(width 0.12954)
		(layer "B.Cu")
		(net "CLK_100M_CPU0_CLK12_R_DN")
	)
	(segment
		(start 342.647778 -299.798486)
		(end 342.259158 -299.798486)
		(width 0.12954)
		(layer "B.Cu")
		(net "CLK_100M_CPU0_CLK12_R_DN")
	)
	(segment
		(start 342.84158 -299.992288)
		(end 342.647778 -299.798486)
		(width 0.12954)
		(layer "B.Cu")
		(net "CLK_100M_CPU0_CLK12_R_DN")
	)
	(segment
		(start 342.259158 -299.798486)
		(end 342.081358 -299.976286)
		(width 0.12954)
		(layer "B.Cu")
		(net "CLK_100M_CPU0_CLK12_R_DN")
	)
	(segment
		(start 342.081358 -299.976286)
		(end 341.692738 -299.976286)
		(width 0.12954)
		(layer "B.Cu")
		(net "CLK_100M_CPU0_CLK12_R_DN")
	)
	(segment
		(start 341.514938 -299.798486)
		(end 340.94928 -299.798486)
		(width 0.12954)
		(layer "B.Cu")
		(net "CLK_100M_CPU0_CLK12_R_DN")
	)
	(segment
		(start 342.84158 -301.168562)
		(end 342.84158 -299.992288)
		(width 0.12954)
		(layer "B.Cu")
		(net "CLK_100M_CPU0_CLK12_R_DN")
	)
	(segment
		(start 341.692738 -299.976286)
		(end 341.514938 -299.798486)
		(width 0.12954)
		(layer "B.Cu")
		(net "CLK_100M_CPU0_CLK12_R_DN")
	)
	(segment
		(start 243.243862 -53.114702)
		(end 242.974368 -53.114702)
		(width 0.12954)
		(layer "F.Cu")
		(net "CLK_100M_CPU0_CLK12_DP")
	)
	(segment
		(start 245.40972 -64.710564)
		(end 245.40972 -57.390284)
		(width 0.12954)
		(layer "F.Cu")
		(net "CLK_100M_CPU0_CLK12_DP")
	)
	(segment
		(start 260.924802 -193.8274)
		(end 261.097522 -193.65468)
		(width 0.12954)
		(layer "F.Cu")
		(net "CLK_100M_CPU0_CLK12_DP")
	)
	(segment
		(start 242.701064 -52.841398)
		(end 242.701064 -52.571904)
		(width 0.12954)
		(layer "F.Cu")
		(net "CLK_100M_CPU0_CLK12_DP")
	)
	(segment
		(start 237.254796 -50.825654)
		(end 237.115604 -50.964846)
		(width 0.12954)
		(layer "F.Cu")
		(net "CLK_100M_CPU0_CLK12_DP")
	)
	(segment
		(start 239.634776 -50.85842)
		(end 239.248696 -50.85842)
		(width 0.12954)
		(layer "F.Cu")
		(net "CLK_100M_CPU0_CLK12_DP")
	)
	(segment
		(start 260.475222 -193.502026)
		(end 260.800596 -193.8274)
		(width 0.12954)
		(layer "F.Cu")
		(net "CLK_100M_CPU0_CLK12_DP")
	)
	(segment
		(start 239.825276 -50.66792)
		(end 239.634776 -50.85842)
		(width 0.12954)
		(layer "F.Cu")
		(net "CLK_100M_CPU0_CLK12_DP")
	)
	(segment
		(start 260.764274 -191.65951)
		(end 260.664452 -191.28613)
		(width 0.12954)
		(layer "F.Cu")
		(net "CLK_100M_CPU0_CLK12_DP")
	)
	(segment
		(start 241.88547 -51.75631)
		(end 241.612674 -51.483514)
		(width 0.12954)
		(layer "F.Cu")
		(net "CLK_100M_CPU0_CLK12_DP")
	)
	(segment
		(start 260.9977 -191.79413)
		(end 260.764274 -191.65951)
		(width 0.12954)
		(layer "F.Cu")
		(net "CLK_100M_CPU0_CLK12_DP")
	)
	(segment
		(start 260.4008 -189.566042)
		(end 260.167374 -189.431422)
		(width 0.12954)
		(layer "F.Cu")
		(net "CLK_100M_CPU0_CLK12_DP")
	)
	(segment
		(start 239.248696 -50.85842)
		(end 239.058196 -50.66792)
		(width 0.12954)
		(layer "F.Cu")
		(net "CLK_100M_CPU0_CLK12_DP")
	)
	(segment
		(start 260.202172 -188.82487)
		(end 260.202426 -188.824616)
		(width 0.12954)
		(layer "F.Cu")
		(net "CLK_100M_CPU0_CLK12_DP")
	)
	(segment
		(start 260.366002 -190.172086)
		(end 260.500622 -189.938914)
		(width 0.12954)
		(layer "F.Cu")
		(net "CLK_100M_CPU0_CLK12_DP")
	)
	(segment
		(start 242.974368 -53.114702)
		(end 242.701064 -52.841398)
		(width 0.12954)
		(layer "F.Cu")
		(net "CLK_100M_CPU0_CLK12_DP")
	)
	(segment
		(start 243.917978 -53.788818)
		(end 243.243862 -53.114702)
		(width 0.12954)
		(layer "F.Cu")
		(net "CLK_100M_CPU0_CLK12_DP")
	)
	(segment
		(start 261.097522 -193.65468)
		(end 261.097522 -192.167002)
		(width 0.12954)
		(layer "F.Cu")
		(net "CLK_100M_CPU0_CLK12_DP")
	)
	(segment
		(start 258.325366 -181.813454)
		(end 248.714006 -127.863854)
		(width 0.12954)
		(layer "F.Cu")
		(net "CLK_100M_CPU0_CLK12_DP")
	)
	(segment
		(start 239.058196 -50.66792)
		(end 238.151162 -50.66792)
		(width 0.12954)
		(layer "F.Cu")
		(net "CLK_100M_CPU0_CLK12_DP")
	)
	(segment
		(start 237.115604 -50.964846)
		(end 236.599984 -50.964846)
		(width 0.12954)
		(layer "F.Cu")
		(net "CLK_100M_CPU0_CLK12_DP")
	)
	(segment
		(start 260.800596 -193.8274)
		(end 260.924802 -193.8274)
		(width 0.12954)
		(layer "F.Cu")
		(net "CLK_100M_CPU0_CLK12_DP")
	)
	(segment
		(start 242.428268 -52.299108)
		(end 242.158774 -52.299108)
		(width 0.12954)
		(layer "F.Cu")
		(net "CLK_100M_CPU0_CLK12_DP")
	)
	(segment
		(start 260.067552 -189.058042)
		(end 260.202172 -188.82487)
		(width 0.12954)
		(layer "F.Cu")
		(net "CLK_100M_CPU0_CLK12_DP")
	)
	(segment
		(start 245.40972 -57.390284)
		(end 243.917978 -53.788818)
		(width 0.12954)
		(layer "F.Cu")
		(net "CLK_100M_CPU0_CLK12_DP")
	)
	(segment
		(start 241.88547 -52.025804)
		(end 241.88547 -51.75631)
		(width 0.12954)
		(layer "F.Cu")
		(net "CLK_100M_CPU0_CLK12_DP")
	)
	(segment
		(start 241.34318 -51.483514)
		(end 241.069876 -51.21021)
		(width 0.12954)
		(layer "F.Cu")
		(net "CLK_100M_CPU0_CLK12_DP")
	)
	(segment
		(start 248.714006 -127.863854)
		(end 245.40972 -64.710564)
		(width 0.12954)
		(layer "F.Cu")
		(net "CLK_100M_CPU0_CLK12_DP")
	)
	(segment
		(start 241.069876 -50.940716)
		(end 240.79708 -50.66792)
		(width 0.12954)
		(layer "F.Cu")
		(net "CLK_100M_CPU0_CLK12_DP")
	)
	(segment
		(start 260.202426 -188.824616)
		(end 258.325366 -181.813454)
		(width 0.12954)
		(layer "F.Cu")
		(net "CLK_100M_CPU0_CLK12_DP")
	)
	(segment
		(start 260.664452 -191.28613)
		(end 260.799072 -191.052958)
		(width 0.12954)
		(layer "F.Cu")
		(net "CLK_100M_CPU0_CLK12_DP")
	)
	(segment
		(start 260.799072 -191.052958)
		(end 260.69925 -190.680086)
		(width 0.12954)
		(layer "F.Cu")
		(net "CLK_100M_CPU0_CLK12_DP")
	)
	(segment
		(start 241.069876 -51.21021)
		(end 241.069876 -50.940716)
		(width 0.12954)
		(layer "F.Cu")
		(net "CLK_100M_CPU0_CLK12_DP")
	)
	(segment
		(start 261.097522 -192.167002)
		(end 260.9977 -191.79413)
		(width 0.12954)
		(layer "F.Cu")
		(net "CLK_100M_CPU0_CLK12_DP")
	)
	(segment
		(start 260.167374 -189.431422)
		(end 260.067552 -189.058042)
		(width 0.12954)
		(layer "F.Cu")
		(net "CLK_100M_CPU0_CLK12_DP")
	)
	(segment
		(start 242.158774 -52.299108)
		(end 241.88547 -52.025804)
		(width 0.12954)
		(layer "F.Cu")
		(net "CLK_100M_CPU0_CLK12_DP")
	)
	(segment
		(start 238.151162 -50.66792)
		(end 237.993428 -50.825654)
		(width 0.12954)
		(layer "F.Cu")
		(net "CLK_100M_CPU0_CLK12_DP")
	)
	(segment
		(start 260.500622 -189.938914)
		(end 260.4008 -189.566042)
		(width 0.12954)
		(layer "F.Cu")
		(net "CLK_100M_CPU0_CLK12_DP")
	)
	(segment
		(start 260.465824 -190.545466)
		(end 260.366002 -190.172086)
		(width 0.12954)
		(layer "F.Cu")
		(net "CLK_100M_CPU0_CLK12_DP")
	)
	(segment
		(start 240.79708 -50.66792)
		(end 239.825276 -50.66792)
		(width 0.12954)
		(layer "F.Cu")
		(net "CLK_100M_CPU0_CLK12_DP")
	)
	(segment
		(start 260.69925 -190.680086)
		(end 260.465824 -190.545466)
		(width 0.12954)
		(layer "F.Cu")
		(net "CLK_100M_CPU0_CLK12_DP")
	)
	(segment
		(start 237.993428 -50.825654)
		(end 237.254796 -50.825654)
		(width 0.12954)
		(layer "F.Cu")
		(net "CLK_100M_CPU0_CLK12_DP")
	)
	(segment
		(start 241.612674 -51.483514)
		(end 241.34318 -51.483514)
		(width 0.12954)
		(layer "F.Cu")
		(net "CLK_100M_CPU0_CLK12_DP")
	)
	(segment
		(start 242.701064 -52.571904)
		(end 242.428268 -52.299108)
		(width 0.12954)
		(layer "F.Cu")
		(net "CLK_100M_CPU0_CLK12_DP")
	)
	(via
		(at 260.475222 -193.502026)
		(size 0.508)
		(drill 0.254)
		(layers "F.Cu" "B.Cu")
		(net "CLK_100M_CPU0_CLK12_DP")
	)
	(segment
		(start 259.005578 -193.80708)
		(end 257.574034 -195.238624)
		(width 0.12954)
		(layer "B.Cu")
		(net "CLK_100M_CPU0_CLK12_DP")
	)
	(segment
		(start 343.168224 -302.93056)
		(end 343.168224 -302.658018)
		(width 0.12954)
		(layer "B.Cu")
		(net "CLK_100M_CPU0_CLK12_DP")
	)
	(segment
		(start 303.784762 -318.370966)
		(end 321.875658 -300.28007)
		(width 0.12954)
		(layer "B.Cu")
		(net "CLK_100M_CPU0_CLK12_DP")
	)
	(segment
		(start 332.56093 -300.28007)
		(end 335.527142 -303.246282)
		(width 0.12954)
		(layer "B.Cu")
		(net "CLK_100M_CPU0_CLK12_DP")
	)
	(segment
		(start 257.574034 -195.238624)
		(end 257.574034 -217.188034)
		(width 0.12954)
		(layer "B.Cu")
		(net "CLK_100M_CPU0_CLK12_DP")
	)
	(segment
		(start 343.168224 -302.658018)
		(end 343.514934 -302.311308)
		(width 0.12954)
		(layer "B.Cu")
		(net "CLK_100M_CPU0_CLK12_DP")
	)
	(segment
		(start 262.128 -319.659)
		(end 263.53008 -321.06108)
		(width 0.12954)
		(layer "B.Cu")
		(net "CLK_100M_CPU0_CLK12_DP")
	)
	(segment
		(start 342.852502 -303.246282)
		(end 343.168224 -302.93056)
		(width 0.12954)
		(layer "B.Cu")
		(net "CLK_100M_CPU0_CLK12_DP")
	)
	(segment
		(start 302.922686 -318.370966)
		(end 303.784762 -318.370966)
		(width 0.12954)
		(layer "B.Cu")
		(net "CLK_100M_CPU0_CLK12_DP")
	)
	(segment
		(start 321.875658 -300.28007)
		(end 332.56093 -300.28007)
		(width 0.12954)
		(layer "B.Cu")
		(net "CLK_100M_CPU0_CLK12_DP")
	)
	(segment
		(start 260.475222 -193.502026)
		(end 260.170168 -193.80708)
		(width 0.12954)
		(layer "B.Cu")
		(net "CLK_100M_CPU0_CLK12_DP")
	)
	(segment
		(start 335.527142 -303.246282)
		(end 342.852502 -303.246282)
		(width 0.12954)
		(layer "B.Cu")
		(net "CLK_100M_CPU0_CLK12_DP")
	)
	(segment
		(start 262.128 -221.742)
		(end 262.128 -319.659)
		(width 0.12954)
		(layer "B.Cu")
		(net "CLK_100M_CPU0_CLK12_DP")
	)
	(segment
		(start 263.53008 -321.06108)
		(end 300.232572 -321.06108)
		(width 0.12954)
		(layer "B.Cu")
		(net "CLK_100M_CPU0_CLK12_DP")
	)
	(segment
		(start 257.574034 -217.188034)
		(end 262.128 -221.742)
		(width 0.12954)
		(layer "B.Cu")
		(net "CLK_100M_CPU0_CLK12_DP")
	)
	(segment
		(start 300.232572 -321.06108)
		(end 302.922686 -318.370966)
		(width 0.12954)
		(layer "B.Cu")
		(net "CLK_100M_CPU0_CLK12_DP")
	)
	(segment
		(start 260.170168 -193.80708)
		(end 259.005578 -193.80708)
		(width 0.12954)
		(layer "B.Cu")
		(net "CLK_100M_CPU0_CLK12_DP")
	)
	(segment
		(start 238.017304 -50.34534)
		(end 237.85957 -50.503074)
		(width 0.12954)
		(layer "F.Cu")
		(net "CLK_100M_CPU0_CLK12_DN")
	)
	(segment
		(start 261.05866 -194.14998)
		(end 261.420102 -193.788538)
		(width 0.12954)
		(layer "F.Cu")
		(net "CLK_100M_CPU0_CLK12_DN")
	)
	(segment
		(start 258.64058 -181.74335)
		(end 249.035316 -127.827024)
		(width 0.12954)
		(layer "F.Cu")
		(net "CLK_100M_CPU0_CLK12_DN")
	)
	(segment
		(start 245.7323 -57.326022)
		(end 244.191536 -53.605938)
		(width 0.12954)
		(layer "F.Cu")
		(net "CLK_100M_CPU0_CLK12_DN")
	)
	(segment
		(start 249.035316 -127.827024)
		(end 245.7323 -64.701928)
		(width 0.12954)
		(layer "F.Cu")
		(net "CLK_100M_CPU0_CLK12_DN")
	)
	(segment
		(start 261.25932 -191.524382)
		(end 258.64058 -181.74335)
		(width 0.12954)
		(layer "F.Cu")
		(net "CLK_100M_CPU0_CLK12_DN")
	)
	(segment
		(start 237.119668 -50.364898)
		(end 236.599984 -50.364898)
		(width 0.12954)
		(layer "F.Cu")
		(net "CLK_100M_CPU0_CLK12_DN")
	)
	(segment
		(start 244.191536 -53.605938)
		(end 240.930938 -50.34534)
		(width 0.12954)
		(layer "F.Cu")
		(net "CLK_100M_CPU0_CLK12_DN")
	)
	(segment
		(start 245.7323 -64.701928)
		(end 245.7323 -57.326022)
		(width 0.12954)
		(layer "F.Cu")
		(net "CLK_100M_CPU0_CLK12_DN")
	)
	(segment
		(start 260.817868 -194.14998)
		(end 261.05866 -194.14998)
		(width 0.12954)
		(layer "F.Cu")
		(net "CLK_100M_CPU0_CLK12_DN")
	)
	(segment
		(start 261.420102 -192.12433)
		(end 261.25932 -191.524382)
		(width 0.12954)
		(layer "F.Cu")
		(net "CLK_100M_CPU0_CLK12_DN")
	)
	(segment
		(start 240.930938 -50.34534)
		(end 238.017304 -50.34534)
		(width 0.12954)
		(layer "F.Cu")
		(net "CLK_100M_CPU0_CLK12_DN")
	)
	(segment
		(start 260.475222 -194.492626)
		(end 260.817868 -194.14998)
		(width 0.12954)
		(layer "F.Cu")
		(net "CLK_100M_CPU0_CLK12_DN")
	)
	(segment
		(start 237.257844 -50.503074)
		(end 237.119668 -50.364898)
		(width 0.12954)
		(layer "F.Cu")
		(net "CLK_100M_CPU0_CLK12_DN")
	)
	(segment
		(start 237.85957 -50.503074)
		(end 237.257844 -50.503074)
		(width 0.12954)
		(layer "F.Cu")
		(net "CLK_100M_CPU0_CLK12_DN")
	)
	(segment
		(start 261.420102 -193.788538)
		(end 261.420102 -192.12433)
		(width 0.12954)
		(layer "F.Cu")
		(net "CLK_100M_CPU0_CLK12_DN")
	)
	(via
		(at 260.475222 -194.492626)
		(size 0.508)
		(drill 0.254)
		(layers "F.Cu" "B.Cu")
		(net "CLK_100M_CPU0_CLK12_DN")
	)
	(segment
		(start 258.087114 -200.561702)
		(end 257.896614 -200.371202)
		(width 0.12954)
		(layer "B.Cu")
		(net "CLK_100M_CPU0_CLK12_DN")
	)
	(segment
		(start 310.590438 -311.108852)
		(end 310.320944 -311.108852)
		(width 0.12954)
		(layer "B.Cu")
		(net "CLK_100M_CPU0_CLK12_DN")
	)
	(segment
		(start 259.139436 -194.12966)
		(end 260.112256 -194.12966)
		(width 0.12954)
		(layer "B.Cu")
		(net "CLK_100M_CPU0_CLK12_DN")
	)
	(segment
		(start 257.896614 -217.054176)
		(end 257.896614 -201.138282)
		(width 0.12954)
		(layer "B.Cu")
		(net "CLK_100M_CPU0_CLK12_DN")
	)
	(segment
		(start 258.087114 -197.488302)
		(end 258.087114 -197.102222)
		(width 0.12954)
		(layer "B.Cu")
		(net "CLK_100M_CPU0_CLK12_DN")
	)
	(segment
		(start 337.61299 -302.923702)
		(end 335.661 -302.923702)
		(width 0.12954)
		(layer "B.Cu")
		(net "CLK_100M_CPU0_CLK12_DN")
	)
	(segment
		(start 340.11997 -302.733202)
		(end 339.92947 -302.923702)
		(width 0.12954)
		(layer "B.Cu")
		(net "CLK_100M_CPU0_CLK12_DN")
	)
	(segment
		(start 342.718644 -302.923702)
		(end 341.975694 -302.923702)
		(width 0.12954)
		(layer "B.Cu")
		(net "CLK_100M_CPU0_CLK12_DN")
	)
	(segment
		(start 321.7418 -299.95749)
		(end 310.590438 -311.108852)
		(width 0.12954)
		(layer "B.Cu")
		(net "CLK_100M_CPU0_CLK12_DN")
	)
	(segment
		(start 338.19211 -302.733202)
		(end 337.80349 -302.733202)
		(width 0.12954)
		(layer "B.Cu")
		(net "CLK_100M_CPU0_CLK12_DN")
	)
	(segment
		(start 257.896614 -201.138282)
		(end 258.087114 -200.947782)
		(width 0.12954)
		(layer "B.Cu")
		(net "CLK_100M_CPU0_CLK12_DN")
	)
	(segment
		(start 258.087114 -200.947782)
		(end 258.087114 -200.561702)
		(width 0.12954)
		(layer "B.Cu")
		(net "CLK_100M_CPU0_CLK12_DN")
	)
	(segment
		(start 262.45058 -319.525142)
		(end 262.45058 -221.608142)
		(width 0.12954)
		(layer "B.Cu")
		(net "CLK_100M_CPU0_CLK12_DN")
	)
	(segment
		(start 257.896614 -197.678802)
		(end 258.087114 -197.488302)
		(width 0.12954)
		(layer "B.Cu")
		(net "CLK_100M_CPU0_CLK12_DN")
	)
	(segment
		(start 339.54085 -302.923702)
		(end 339.35035 -302.733202)
		(width 0.12954)
		(layer "B.Cu")
		(net "CLK_100M_CPU0_CLK12_DN")
	)
	(segment
		(start 262.45058 -221.608142)
		(end 257.896614 -217.054176)
		(width 0.12954)
		(layer "B.Cu")
		(net "CLK_100M_CPU0_CLK12_DN")
	)
	(segment
		(start 339.35035 -302.733202)
		(end 338.96173 -302.733202)
		(width 0.12954)
		(layer "B.Cu")
		(net "CLK_100M_CPU0_CLK12_DN")
	)
	(segment
		(start 335.661 -302.923702)
		(end 332.694788 -299.95749)
		(width 0.12954)
		(layer "B.Cu")
		(net "CLK_100M_CPU0_CLK12_DN")
	)
	(segment
		(start 342.498934 -302.311308)
		(end 342.845644 -302.658018)
		(width 0.12954)
		(layer "B.Cu")
		(net "CLK_100M_CPU0_CLK12_DN")
	)
	(segment
		(start 342.845644 -302.658018)
		(end 342.845644 -302.796702)
		(width 0.12954)
		(layer "B.Cu")
		(net "CLK_100M_CPU0_CLK12_DN")
	)
	(segment
		(start 258.087114 -199.408542)
		(end 257.896614 -199.218042)
		(width 0.12954)
		(layer "B.Cu")
		(net "CLK_100M_CPU0_CLK12_DN")
	)
	(segment
		(start 310.045862 -311.383934)
		(end 310.045862 -311.653428)
		(width 0.12954)
		(layer "B.Cu")
		(net "CLK_100M_CPU0_CLK12_DN")
	)
	(segment
		(start 310.320944 -311.108852)
		(end 310.045862 -311.383934)
		(width 0.12954)
		(layer "B.Cu")
		(net "CLK_100M_CPU0_CLK12_DN")
	)
	(segment
		(start 340.69909 -302.923702)
		(end 340.50859 -302.733202)
		(width 0.12954)
		(layer "B.Cu")
		(net "CLK_100M_CPU0_CLK12_DN")
	)
	(segment
		(start 338.96173 -302.733202)
		(end 338.77123 -302.923702)
		(width 0.12954)
		(layer "B.Cu")
		(net "CLK_100M_CPU0_CLK12_DN")
	)
	(segment
		(start 257.896614 -199.218042)
		(end 257.896614 -198.831962)
		(width 0.12954)
		(layer "B.Cu")
		(net "CLK_100M_CPU0_CLK12_DN")
	)
	(segment
		(start 258.087114 -195.949062)
		(end 257.896614 -195.758562)
		(width 0.12954)
		(layer "B.Cu")
		(net "CLK_100M_CPU0_CLK12_DN")
	)
	(segment
		(start 342.845644 -302.796702)
		(end 342.718644 -302.923702)
		(width 0.12954)
		(layer "B.Cu")
		(net "CLK_100M_CPU0_CLK12_DN")
	)
	(segment
		(start 257.896614 -198.064882)
		(end 257.896614 -197.678802)
		(width 0.12954)
		(layer "B.Cu")
		(net "CLK_100M_CPU0_CLK12_DN")
	)
	(segment
		(start 302.788828 -318.048386)
		(end 300.098714 -320.7385)
		(width 0.12954)
		(layer "B.Cu")
		(net "CLK_100M_CPU0_CLK12_DN")
	)
	(segment
		(start 257.896614 -195.758562)
		(end 257.896614 -195.372482)
		(width 0.12954)
		(layer "B.Cu")
		(net "CLK_100M_CPU0_CLK12_DN")
	)
	(segment
		(start 257.896614 -196.911722)
		(end 257.896614 -196.525642)
		(width 0.12954)
		(layer "B.Cu")
		(net "CLK_100M_CPU0_CLK12_DN")
	)
	(segment
		(start 338.38261 -302.923702)
		(end 338.19211 -302.733202)
		(width 0.12954)
		(layer "B.Cu")
		(net "CLK_100M_CPU0_CLK12_DN")
	)
	(segment
		(start 257.896614 -198.831962)
		(end 258.087114 -198.641462)
		(width 0.12954)
		(layer "B.Cu")
		(net "CLK_100M_CPU0_CLK12_DN")
	)
	(segment
		(start 300.098714 -320.7385)
		(end 263.663938 -320.7385)
		(width 0.12954)
		(layer "B.Cu")
		(net "CLK_100M_CPU0_CLK12_DN")
	)
	(segment
		(start 303.650904 -318.048386)
		(end 302.788828 -318.048386)
		(width 0.12954)
		(layer "B.Cu")
		(net "CLK_100M_CPU0_CLK12_DN")
	)
	(segment
		(start 257.896614 -196.525642)
		(end 258.087114 -196.335142)
		(width 0.12954)
		(layer "B.Cu")
		(net "CLK_100M_CPU0_CLK12_DN")
	)
	(segment
		(start 260.112256 -194.12966)
		(end 260.475222 -194.492626)
		(width 0.12954)
		(layer "B.Cu")
		(net "CLK_100M_CPU0_CLK12_DN")
	)
	(segment
		(start 258.087114 -198.641462)
		(end 258.087114 -198.255382)
		(width 0.12954)
		(layer "B.Cu")
		(net "CLK_100M_CPU0_CLK12_DN")
	)
	(segment
		(start 338.77123 -302.923702)
		(end 338.38261 -302.923702)
		(width 0.12954)
		(layer "B.Cu")
		(net "CLK_100M_CPU0_CLK12_DN")
	)
	(segment
		(start 341.975694 -302.923702)
		(end 341.785194 -302.733202)
		(width 0.12954)
		(layer "B.Cu")
		(net "CLK_100M_CPU0_CLK12_DN")
	)
	(segment
		(start 257.896614 -200.371202)
		(end 257.896614 -199.985122)
		(width 0.12954)
		(layer "B.Cu")
		(net "CLK_100M_CPU0_CLK12_DN")
	)
	(segment
		(start 340.50859 -302.733202)
		(end 340.11997 -302.733202)
		(width 0.12954)
		(layer "B.Cu")
		(net "CLK_100M_CPU0_CLK12_DN")
	)
	(segment
		(start 341.396574 -302.733202)
		(end 341.206074 -302.923702)
		(width 0.12954)
		(layer "B.Cu")
		(net "CLK_100M_CPU0_CLK12_DN")
	)
	(segment
		(start 341.785194 -302.733202)
		(end 341.396574 -302.733202)
		(width 0.12954)
		(layer "B.Cu")
		(net "CLK_100M_CPU0_CLK12_DN")
	)
	(segment
		(start 332.694788 -299.95749)
		(end 321.7418 -299.95749)
		(width 0.12954)
		(layer "B.Cu")
		(net "CLK_100M_CPU0_CLK12_DN")
	)
	(segment
		(start 258.087114 -196.335142)
		(end 258.087114 -195.949062)
		(width 0.12954)
		(layer "B.Cu")
		(net "CLK_100M_CPU0_CLK12_DN")
	)
	(segment
		(start 341.206074 -302.923702)
		(end 340.69909 -302.923702)
		(width 0.12954)
		(layer "B.Cu")
		(net "CLK_100M_CPU0_CLK12_DN")
	)
	(segment
		(start 258.087114 -198.255382)
		(end 257.896614 -198.064882)
		(width 0.12954)
		(layer "B.Cu")
		(net "CLK_100M_CPU0_CLK12_DN")
	)
	(segment
		(start 337.80349 -302.733202)
		(end 337.61299 -302.923702)
		(width 0.12954)
		(layer "B.Cu")
		(net "CLK_100M_CPU0_CLK12_DN")
	)
	(segment
		(start 258.087114 -197.102222)
		(end 257.896614 -196.911722)
		(width 0.12954)
		(layer "B.Cu")
		(net "CLK_100M_CPU0_CLK12_DN")
	)
	(segment
		(start 339.92947 -302.923702)
		(end 339.54085 -302.923702)
		(width 0.12954)
		(layer "B.Cu")
		(net "CLK_100M_CPU0_CLK12_DN")
	)
	(segment
		(start 310.045862 -311.653428)
		(end 303.650904 -318.048386)
		(width 0.12954)
		(layer "B.Cu")
		(net "CLK_100M_CPU0_CLK12_DN")
	)
	(segment
		(start 257.896614 -195.372482)
		(end 259.139436 -194.12966)
		(width 0.12954)
		(layer "B.Cu")
		(net "CLK_100M_CPU0_CLK12_DN")
	)
	(segment
		(start 263.663938 -320.7385)
		(end 262.45058 -319.525142)
		(width 0.12954)
		(layer "B.Cu")
		(net "CLK_100M_CPU0_CLK12_DN")
	)
	(segment
		(start 257.896614 -199.985122)
		(end 258.087114 -199.794622)
		(width 0.12954)
		(layer "B.Cu")
		(net "CLK_100M_CPU0_CLK12_DN")
	)
	(segment
		(start 258.087114 -199.794622)
		(end 258.087114 -199.408542)
		(width 0.12954)
		(layer "B.Cu")
		(net "CLK_100M_CPU0_CLK12_DN")
	)
	(segment
		(start 164.143944 -120.37187)
		(end 164.149278 -120.366536)
		(width 0.10668)
		(layer "F.Cu")
		(net "VIRTUAL_RESEAT_FPGA_R_N")
	)
	(segment
		(start 180.32222 -119.452898)
		(end 179.93233 -119.842788)
		(width 0.10668)
		(layer "F.Cu")
		(net "VIRTUAL_RESEAT_FPGA_R_N")
	)
	(segment
		(start 164.149278 -120.366536)
		(end 165.382956 -120.366536)
		(width 0.10668)
		(layer "F.Cu")
		(net "VIRTUAL_RESEAT_FPGA_R_N")
	)
	(via
		(at 165.382956 -120.366536)
		(size 0.508)
		(drill 0.254)
		(layers "F.Cu" "B.Cu")
		(net "VIRTUAL_RESEAT_FPGA_R_N")
	)
	(via
		(at 179.93233 -119.842788)
		(size 0.4572)
		(drill 0.254)
		(layers "F.Cu" "B.Cu")
		(net "VIRTUAL_RESEAT_FPGA_R_N")
	)
	(segment
		(start 179.93233 -119.842788)
		(end 179.93233 -119.751094)
		(width 0.11684)
		(layer "In2.Cu")
		(net "VIRTUAL_RESEAT_FPGA_R_N")
	)
	(segment
		(start 166.014146 -120.997726)
		(end 165.382956 -120.366536)
		(width 0.11684)
		(layer "In2.Cu")
		(net "VIRTUAL_RESEAT_FPGA_R_N")
	)
	(segment
		(start 172.018706 -118.854982)
		(end 169.875962 -120.997726)
		(width 0.11684)
		(layer "In2.Cu")
		(net "VIRTUAL_RESEAT_FPGA_R_N")
	)
	(segment
		(start 175.595534 -119.4435)
		(end 175.007016 -118.854982)
		(width 0.11684)
		(layer "In2.Cu")
		(net "VIRTUAL_RESEAT_FPGA_R_N")
	)
	(segment
		(start 169.875962 -120.997726)
		(end 166.014146 -120.997726)
		(width 0.11684)
		(layer "In2.Cu")
		(net "VIRTUAL_RESEAT_FPGA_R_N")
	)
	(segment
		(start 175.007016 -118.854982)
		(end 172.018706 -118.854982)
		(width 0.11684)
		(layer "In2.Cu")
		(net "VIRTUAL_RESEAT_FPGA_R_N")
	)
	(segment
		(start 179.624736 -119.4435)
		(end 175.595534 -119.4435)
		(width 0.11684)
		(layer "In2.Cu")
		(net "VIRTUAL_RESEAT_FPGA_R_N")
	)
	(segment
		(start 179.93233 -119.751094)
		(end 179.624736 -119.4435)
		(width 0.11684)
		(layer "In2.Cu")
		(net "VIRTUAL_RESEAT_FPGA_R_N")
	)
	(segment
		(start 16.04391 -134.289038)
		(end 16.162782 -134.170166)
		(width 0.254)
		(layer "F.Cu")
		(net "VFG_3P3A_CLK_GEN")
	)
	(segment
		(start 15.42161 -134.289038)
		(end 16.04391 -134.289038)
		(width 0.254)
		(layer "F.Cu")
		(net "VFG_3P3A_CLK_GEN")
	)
	(via
		(at 16.609314 -133.235446)
		(size 0.6604)
		(drill 0.3302)
		(layers "F.Cu" "B.Cu")
		(net "VFG_3P3A_CLK_GEN")
	)
	(via
		(at 16.162782 -134.170166)
		(size 0.508)
		(drill 0.254)
		(layers "F.Cu" "B.Cu")
		(net "VFG_3P3A_CLK_GEN")
	)
	(segment
		(start 11.671554 -134.289038)
		(end 11.032998 -134.289038)
		(width 0.254)
		(layer "F.Cu")
		(net "VFG3P3_CLK_GEN")
	)
	(segment
		(start 14.296644 -132.164074)
		(end 14.296644 -131.622546)
		(width 0.254)
		(layer "F.Cu")
		(net "VFG3P3_CLK_GEN")
	)
	(segment
		(start 11.032998 -134.289038)
		(end 10.87374 -134.12978)
		(width 0.254)
		(layer "F.Cu")
		(net "VFG3P3_CLK_GEN")
	)
	(segment
		(start 12.296648 -132.164074)
		(end 12.296648 -131.63169)
		(width 0.254)
		(layer "F.Cu")
		(net "VFG3P3_CLK_GEN")
	)
	(segment
		(start 14.296644 -135.91413)
		(end 14.296644 -136.576054)
		(width 0.254)
		(layer "F.Cu")
		(net "VFG3P3_CLK_GEN")
	)
	(segment
		(start 14.296644 -131.622546)
		(end 14.143228 -131.46913)
		(width 0.254)
		(layer "F.Cu")
		(net "VFG3P3_CLK_GEN")
	)
	(segment
		(start 14.296644 -136.576054)
		(end 14.272768 -136.59993)
		(width 0.254)
		(layer "F.Cu")
		(net "VFG3P3_CLK_GEN")
	)
	(segment
		(start 12.296648 -131.63169)
		(end 12.144248 -131.47929)
		(width 0.254)
		(layer "F.Cu")
		(net "VFG3P3_CLK_GEN")
	)
	(via
		(at 14.143228 -131.46913)
		(size 0.508)
		(drill 0.254)
		(layers "F.Cu" "B.Cu")
		(net "VFG3P3_CLK_GEN")
	)
	(via
		(at 10.87374 -134.12978)
		(size 0.508)
		(drill 0.254)
		(layers "F.Cu" "B.Cu")
		(net "VFG3P3_CLK_GEN")
	)
	(via
		(at 14.272768 -136.59993)
		(size 0.508)
		(drill 0.254)
		(layers "F.Cu" "B.Cu")
		(net "VFG3P3_CLK_GEN")
	)
	(via
		(at 15.784068 -137.03173)
		(size 0.508)
		(drill 0.254)
		(layers "F.Cu" "B.Cu")
		(net "VFG3P3_CLK_GEN")
	)
	(via
		(at 12.144248 -131.47929)
		(size 0.508)
		(drill 0.254)
		(layers "F.Cu" "B.Cu")
		(net "VFG3P3_CLK_GEN")
	)
	(segment
		(start 145.48739 -31.18739)
		(end 144.99844 -31.67634)
		(width 0.12954)
		(layer "F.Cu")
		(net "USB3_CPU0_BMC_TX_DP")
	)
	(segment
		(start 145.63344 -31.18739)
		(end 145.48739 -31.18739)
		(width 0.12954)
		(layer "F.Cu")
		(net "USB3_CPU0_BMC_TX_DP")
	)
	(segment
		(start 371.467888 -223.69018)
		(end 371.93474 -223.424242)
		(width 0.12954)
		(layer "F.Cu")
		(net "USB3_CPU0_BMC_TX_DP")
	)
	(segment
		(start 371.636798 -223.424242)
		(end 371.553994 -223.341438)
		(width 0.1143)
		(layer "In15.Cu")
		(net "USB3_CPU0_BMC_TX_DP")
	)
	(segment
		(start 370.620036 -221.44355)
		(end 370.665756 -221.39783)
		(width 0.1143)
		(layer "In15.Cu")
		(net "USB3_CPU0_BMC_TX_DP")
	)
	(segment
		(start 152.58796 -158.225744)
		(end 145.25752 -153.093166)
		(width 0.14224)
		(layer "In15.Cu")
		(net "USB3_CPU0_BMC_TX_DP")
	)
	(segment
		(start 137.64006 -42.986706)
		(end 137.821924 -42.929556)
		(width 0.14224)
		(layer "In15.Cu")
		(net "USB3_CPU0_BMC_TX_DP")
	)
	(segment
		(start 370.80698 -222.126302)
		(end 370.80444 -222.125032)
		(width 0.1143)
		(layer "In15.Cu")
		(net "USB3_CPU0_BMC_TX_DP")
	)
	(segment
		(start 168.653714 -166.968678)
		(end 168.60774 -166.957756)
		(width 0.14224)
		(layer "In15.Cu")
		(net "USB3_CPU0_BMC_TX_DP")
	)
	(segment
		(start 370.846858 -222.14967)
		(end 370.808758 -222.127318)
		(width 0.1143)
		(layer "In15.Cu")
		(net "USB3_CPU0_BMC_TX_DP")
	)
	(segment
		(start 370.665756 -221.369382)
		(end 370.665756 -220.744542)
		(width 0.14224)
		(layer "In15.Cu")
		(net "USB3_CPU0_BMC_TX_DP")
	)
	(segment
		(start 370.807742 -222.12681)
		(end 370.80698 -222.126302)
		(width 0.1143)
		(layer "In15.Cu")
		(net "USB3_CPU0_BMC_TX_DP")
	)
	(segment
		(start 370.80444 -222.125032)
		(end 370.775992 -222.108522)
		(width 0.1143)
		(layer "In15.Cu")
		(net "USB3_CPU0_BMC_TX_DP")
	)
	(segment
		(start 133.054852 -59.009534)
		(end 134.978394 -48.09998)
		(width 0.14224)
		(layer "In15.Cu")
		(net "USB3_CPU0_BMC_TX_DP")
	)
	(segment
		(start 370.620036 -221.962218)
		(end 370.620036 -221.44355)
		(width 0.1143)
		(layer "In15.Cu")
		(net "USB3_CPU0_BMC_TX_DP")
	)
	(segment
		(start 188.81979 -167.40505)
		(end 181.085744 -167.41267)
		(width 0.14224)
		(layer "In15.Cu")
		(net "USB3_CPU0_BMC_TX_DP")
	)
	(segment
		(start 138.509248 -41.60901)
		(end 138.451844 -41.4274)
		(width 0.14224)
		(layer "In15.Cu")
		(net "USB3_CPU0_BMC_TX_DP")
	)
	(segment
		(start 135.35406 -75.80503)
		(end 135.35406 -72.050402)
		(width 0.14224)
		(layer "In15.Cu")
		(net "USB3_CPU0_BMC_TX_DP")
	)
	(segment
		(start 138.451844 -41.4274)
		(end 142.12316 -34.374582)
		(width 0.14224)
		(layer "In15.Cu")
		(net "USB3_CPU0_BMC_TX_DP")
	)
	(segment
		(start 138.321542 -41.96969)
		(end 138.509248 -41.60901)
		(width 0.14224)
		(layer "In15.Cu")
		(net "USB3_CPU0_BMC_TX_DP")
	)
	(segment
		(start 145.25752 -153.093166)
		(end 135.342884 -138.933682)
		(width 0.14224)
		(layer "In15.Cu")
		(net "USB3_CPU0_BMC_TX_DP")
	)
	(segment
		(start 142.25778 -32.87268)
		(end 142.12316 -32.73806)
		(width 0.14224)
		(layer "In15.Cu")
		(net "USB3_CPU0_BMC_TX_DP")
	)
	(segment
		(start 137.509758 -43.528742)
		(end 137.452608 -43.347132)
		(width 0.14224)
		(layer "In15.Cu")
		(net "USB3_CPU0_BMC_TX_DP")
	)
	(segment
		(start 142.12316 -34.374582)
		(end 142.12316 -33.4137)
		(width 0.14224)
		(layer "In15.Cu")
		(net "USB3_CPU0_BMC_TX_DP")
	)
	(segment
		(start 137.452608 -43.347132)
		(end 137.64006 -42.986706)
		(width 0.14224)
		(layer "In15.Cu")
		(net "USB3_CPU0_BMC_TX_DP")
	)
	(segment
		(start 371.93474 -223.424242)
		(end 371.636798 -223.424242)
		(width 0.1143)
		(layer "In15.Cu")
		(net "USB3_CPU0_BMC_TX_DP")
	)
	(segment
		(start 137.952226 -42.387266)
		(end 138.139678 -42.02684)
		(width 0.14224)
		(layer "In15.Cu")
		(net "USB3_CPU0_BMC_TX_DP")
	)
	(segment
		(start 134.978394 -48.09998)
		(end 137.140188 -43.946826)
		(width 0.14224)
		(layer "In15.Cu")
		(net "USB3_CPU0_BMC_TX_DP")
	)
	(segment
		(start 142.25778 -33.27908)
		(end 142.25778 -32.87268)
		(width 0.14224)
		(layer "In15.Cu")
		(net "USB3_CPU0_BMC_TX_DP")
	)
	(segment
		(start 135.35406 -72.050402)
		(end 133.054852 -59.009534)
		(width 0.14224)
		(layer "In15.Cu")
		(net "USB3_CPU0_BMC_TX_DP")
	)
	(segment
		(start 129.782824 -107.40136)
		(end 135.35406 -75.80503)
		(width 0.14224)
		(layer "In15.Cu")
		(net "USB3_CPU0_BMC_TX_DP")
	)
	(segment
		(start 311.300114 -171.543218)
		(end 307.157628 -171.543218)
		(width 0.14224)
		(layer "In15.Cu")
		(net "USB3_CPU0_BMC_TX_DP")
	)
	(segment
		(start 307.157628 -171.543218)
		(end 205.740762 -170.463464)
		(width 0.14224)
		(layer "In15.Cu")
		(net "USB3_CPU0_BMC_TX_DP")
	)
	(segment
		(start 142.12316 -33.4137)
		(end 142.25778 -33.27908)
		(width 0.14224)
		(layer "In15.Cu")
		(net "USB3_CPU0_BMC_TX_DP")
	)
	(segment
		(start 168.60774 -166.957756)
		(end 159.919162 -163.35883)
		(width 0.14224)
		(layer "In15.Cu")
		(net "USB3_CPU0_BMC_TX_DP")
	)
	(segment
		(start 370.665756 -221.39783)
		(end 370.665756 -221.369382)
		(width 0.1143)
		(layer "In15.Cu")
		(net "USB3_CPU0_BMC_TX_DP")
	)
	(segment
		(start 177.758598 -167.60952)
		(end 175.658018 -167.60952)
		(width 0.14224)
		(layer "In15.Cu")
		(net "USB3_CPU0_BMC_TX_DP")
	)
	(segment
		(start 144.70761 -31.38551)
		(end 144.99844 -31.67634)
		(width 0.14224)
		(layer "In15.Cu")
		(net "USB3_CPU0_BMC_TX_DP")
	)
	(segment
		(start 159.919162 -163.35883)
		(end 152.588214 -158.225998)
		(width 0.14224)
		(layer "In15.Cu")
		(net "USB3_CPU0_BMC_TX_DP")
	)
	(segment
		(start 138.139678 -42.02684)
		(end 138.321542 -41.96969)
		(width 0.14224)
		(layer "In15.Cu")
		(net "USB3_CPU0_BMC_TX_DP")
	)
	(segment
		(start 205.740762 -170.463464)
		(end 191.386206 -167.963088)
		(width 0.14224)
		(layer "In15.Cu")
		(net "USB3_CPU0_BMC_TX_DP")
	)
	(segment
		(start 142.12316 -32.004)
		(end 142.74165 -31.38551)
		(width 0.14224)
		(layer "In15.Cu")
		(net "USB3_CPU0_BMC_TX_DP")
	)
	(segment
		(start 137.821924 -42.929556)
		(end 138.00963 -42.568876)
		(width 0.14224)
		(layer "In15.Cu")
		(net "USB3_CPU0_BMC_TX_DP")
	)
	(segment
		(start 370.665756 -220.744542)
		(end 328.65187 -178.730656)
		(width 0.14224)
		(layer "In15.Cu")
		(net "USB3_CPU0_BMC_TX_DP")
	)
	(segment
		(start 370.808758 -222.127318)
		(end 370.807742 -222.12681)
		(width 0.1143)
		(layer "In15.Cu")
		(net "USB3_CPU0_BMC_TX_DP")
	)
	(segment
		(start 137.322052 -43.889422)
		(end 137.509758 -43.528742)
		(width 0.14224)
		(layer "In15.Cu")
		(net "USB3_CPU0_BMC_TX_DP")
	)
	(segment
		(start 191.386206 -167.963088)
		(end 188.81979 -167.40505)
		(width 0.14224)
		(layer "In15.Cu")
		(net "USB3_CPU0_BMC_TX_DP")
	)
	(segment
		(start 181.085744 -167.41267)
		(end 179.758848 -167.41267)
		(width 0.14224)
		(layer "In15.Cu")
		(net "USB3_CPU0_BMC_TX_DP")
	)
	(segment
		(start 179.758848 -167.41267)
		(end 177.758598 -167.60952)
		(width 0.14224)
		(layer "In15.Cu")
		(net "USB3_CPU0_BMC_TX_DP")
	)
	(segment
		(start 135.342884 -138.933682)
		(end 129.782824 -107.40136)
		(width 0.14224)
		(layer "In15.Cu")
		(net "USB3_CPU0_BMC_TX_DP")
	)
	(segment
		(start 142.74165 -31.38551)
		(end 144.70761 -31.38551)
		(width 0.14224)
		(layer "In15.Cu")
		(net "USB3_CPU0_BMC_TX_DP")
	)
	(segment
		(start 371.316758 -222.959676)
		(end 371.247162 -222.919036)
		(width 0.1143)
		(layer "In15.Cu")
		(net "USB3_CPU0_BMC_TX_DP")
	)
	(segment
		(start 142.12316 -32.73806)
		(end 142.12316 -32.004)
		(width 0.14224)
		(layer "In15.Cu")
		(net "USB3_CPU0_BMC_TX_DP")
	)
	(segment
		(start 138.00963 -42.568876)
		(end 137.952226 -42.387266)
		(width 0.14224)
		(layer "In15.Cu")
		(net "USB3_CPU0_BMC_TX_DP")
	)
	(segment
		(start 328.65187 -178.730656)
		(end 311.300114 -171.543218)
		(width 0.14224)
		(layer "In15.Cu")
		(net "USB3_CPU0_BMC_TX_DP")
	)
	(segment
		(start 152.588214 -158.225998)
		(end 152.58796 -158.225744)
		(width 0.14224)
		(layer "In15.Cu")
		(net "USB3_CPU0_BMC_TX_DP")
	)
	(segment
		(start 137.140188 -43.946826)
		(end 137.322052 -43.889422)
		(width 0.14224)
		(layer "In15.Cu")
		(net "USB3_CPU0_BMC_TX_DP")
	)
	(segment
		(start 175.658018 -167.60952)
		(end 168.653714 -166.968678)
		(width 0.14224)
		(layer "In15.Cu")
		(net "USB3_CPU0_BMC_TX_DP")
	)
	(arc
		(start 371.247162 -222.919036)
		(mid 371.131735 -222.78566)
		(end 371.09019 -222.614236)
		(width 0.1143)
		(layer "In15.Cu")
		(net "USB3_CPU0_BMC_TX_DP")
	)
	(arc
		(start 370.775992 -222.108522)
		(mid 370.687701 -222.046364)
		(end 370.620036 -221.962218)
		(width 0.1143)
		(layer "In15.Cu")
		(net "USB3_CPU0_BMC_TX_DP")
	)
	(arc
		(start 371.553994 -223.341438)
		(mid 371.474964 -223.125955)
		(end 371.316758 -222.959676)
		(width 0.1143)
		(layer "In15.Cu")
		(net "USB3_CPU0_BMC_TX_DP")
	)
	(arc
		(start 371.09019 -222.614236)
		(mid 371.025675 -222.352017)
		(end 370.846858 -222.14967)
		(width 0.1143)
		(layer "In15.Cu")
		(net "USB3_CPU0_BMC_TX_DP")
	)
	(segment
		(start 144.62379 -31.18739)
		(end 144.99844 -30.81274)
		(width 0.12954)
		(layer "F.Cu")
		(net "USB3_CPU0_BMC_TX_DN")
	)
	(segment
		(start 370.527834 -223.69018)
		(end 370.994686 -223.424242)
		(width 0.12954)
		(layer "F.Cu")
		(net "USB3_CPU0_BMC_TX_DN")
	)
	(segment
		(start 144.36344 -31.18739)
		(end 144.62379 -31.18739)
		(width 0.12954)
		(layer "F.Cu")
		(net "USB3_CPU0_BMC_TX_DN")
	)
	(segment
		(start 371.292628 -223.424242)
		(end 371.362478 -223.354392)
		(width 0.1143)
		(layer "In15.Cu")
		(net "USB3_CPU0_BMC_TX_DN")
	)
	(segment
		(start 370.383816 -221.39783)
		(end 370.383816 -221.369382)
		(width 0.1143)
		(layer "In15.Cu")
		(net "USB3_CPU0_BMC_TX_DN")
	)
	(segment
		(start 370.994686 -223.424242)
		(end 371.292628 -223.424242)
		(width 0.1143)
		(layer "In15.Cu")
		(net "USB3_CPU0_BMC_TX_DN")
	)
	(segment
		(start 205.714854 -170.74515)
		(end 191.332104 -168.239948)
		(width 0.14224)
		(layer "In15.Cu")
		(net "USB3_CPU0_BMC_TX_DN")
	)
	(segment
		(start 177.772568 -167.89146)
		(end 175.645064 -167.89146)
		(width 0.14224)
		(layer "In15.Cu")
		(net "USB3_CPU0_BMC_TX_DN")
	)
	(segment
		(start 191.332104 -168.239948)
		(end 188.789564 -167.687244)
		(width 0.14224)
		(layer "In15.Cu")
		(net "USB3_CPU0_BMC_TX_DN")
	)
	(segment
		(start 135.07212 -75.780138)
		(end 135.07212 -72.075294)
		(width 0.14224)
		(layer "In15.Cu")
		(net "USB3_CPU0_BMC_TX_DN")
	)
	(segment
		(start 370.70919 -222.290132)
		(end 370.708428 -222.289624)
		(width 0.1143)
		(layer "In15.Cu")
		(net "USB3_CPU0_BMC_TX_DN")
	)
	(segment
		(start 175.645064 -167.89146)
		(end 168.607486 -167.247824)
		(width 0.14224)
		(layer "In15.Cu")
		(net "USB3_CPU0_BMC_TX_DN")
	)
	(segment
		(start 370.429536 -221.44355)
		(end 370.383816 -221.39783)
		(width 0.1143)
		(layer "In15.Cu")
		(net "USB3_CPU0_BMC_TX_DN")
	)
	(segment
		(start 181.085998 -167.69461)
		(end 179.772818 -167.69461)
		(width 0.14224)
		(layer "In15.Cu")
		(net "USB3_CPU0_BMC_TX_DN")
	)
	(segment
		(start 141.84122 -31.88716)
		(end 142.62481 -31.10357)
		(width 0.14224)
		(layer "In15.Cu")
		(net "USB3_CPU0_BMC_TX_DN")
	)
	(segment
		(start 370.708428 -222.289624)
		(end 370.684806 -222.275908)
		(width 0.1143)
		(layer "In15.Cu")
		(net "USB3_CPU0_BMC_TX_DN")
	)
	(segment
		(start 311.24398 -171.825158)
		(end 307.156104 -171.825158)
		(width 0.14224)
		(layer "In15.Cu")
		(net "USB3_CPU0_BMC_TX_DN")
	)
	(segment
		(start 135.07212 -72.075294)
		(end 132.76834 -59.009534)
		(width 0.14224)
		(layer "In15.Cu")
		(net "USB3_CPU0_BMC_TX_DN")
	)
	(segment
		(start 370.383816 -220.861382)
		(end 328.492104 -178.96967)
		(width 0.14224)
		(layer "In15.Cu")
		(net "USB3_CPU0_BMC_TX_DN")
	)
	(segment
		(start 179.772818 -167.69461)
		(end 177.772568 -167.89146)
		(width 0.14224)
		(layer "In15.Cu")
		(net "USB3_CPU0_BMC_TX_DN")
	)
	(segment
		(start 370.383816 -221.369382)
		(end 370.383816 -220.861382)
		(width 0.14224)
		(layer "In15.Cu")
		(net "USB3_CPU0_BMC_TX_DN")
	)
	(segment
		(start 328.492104 -178.96967)
		(end 311.24398 -171.825158)
		(width 0.14224)
		(layer "In15.Cu")
		(net "USB3_CPU0_BMC_TX_DN")
	)
	(segment
		(start 168.521888 -167.227504)
		(end 159.78251 -163.60775)
		(width 0.14224)
		(layer "In15.Cu")
		(net "USB3_CPU0_BMC_TX_DN")
	)
	(segment
		(start 370.429536 -222.009208)
		(end 370.429536 -221.44355)
		(width 0.1143)
		(layer "In15.Cu")
		(net "USB3_CPU0_BMC_TX_DN")
	)
	(segment
		(start 370.74348 -222.310198)
		(end 370.70919 -222.290132)
		(width 0.1143)
		(layer "In15.Cu")
		(net "USB3_CPU0_BMC_TX_DN")
	)
	(segment
		(start 188.789564 -167.687244)
		(end 181.085998 -167.69461)
		(width 0.14224)
		(layer "In15.Cu")
		(net "USB3_CPU0_BMC_TX_DN")
	)
	(segment
		(start 135.07593 -139.044172)
		(end 129.496312 -107.40136)
		(width 0.14224)
		(layer "In15.Cu")
		(net "USB3_CPU0_BMC_TX_DN")
	)
	(segment
		(start 144.70761 -31.10357)
		(end 144.99844 -30.81274)
		(width 0.14224)
		(layer "In15.Cu")
		(net "USB3_CPU0_BMC_TX_DN")
	)
	(segment
		(start 141.84122 -34.305494)
		(end 141.84122 -31.88716)
		(width 0.14224)
		(layer "In15.Cu")
		(net "USB3_CPU0_BMC_TX_DN")
	)
	(segment
		(start 145.055082 -153.295604)
		(end 135.07593 -139.044172)
		(width 0.14224)
		(layer "In15.Cu")
		(net "USB3_CPU0_BMC_TX_DN")
	)
	(segment
		(start 307.156104 -171.825158)
		(end 205.714854 -170.74515)
		(width 0.14224)
		(layer "In15.Cu")
		(net "USB3_CPU0_BMC_TX_DN")
	)
	(segment
		(start 168.607486 -167.247824)
		(end 168.521888 -167.227504)
		(width 0.14224)
		(layer "In15.Cu")
		(net "USB3_CPU0_BMC_TX_DN")
	)
	(segment
		(start 371.362478 -223.354392)
		(end 371.362986 -223.354392)
		(width 0.1143)
		(layer "In15.Cu")
		(net "USB3_CPU0_BMC_TX_DN")
	)
	(segment
		(start 142.62481 -31.10357)
		(end 144.70761 -31.10357)
		(width 0.14224)
		(layer "In15.Cu")
		(net "USB3_CPU0_BMC_TX_DN")
	)
	(segment
		(start 129.496312 -107.40136)
		(end 135.07212 -75.780138)
		(width 0.14224)
		(layer "In15.Cu")
		(net "USB3_CPU0_BMC_TX_DN")
	)
	(segment
		(start 132.76834 -59.009534)
		(end 134.708138 -48.008286)
		(width 0.14224)
		(layer "In15.Cu")
		(net "USB3_CPU0_BMC_TX_DN")
	)
	(segment
		(start 371.213634 -223.120204)
		(end 371.144292 -223.079818)
		(width 0.1143)
		(layer "In15.Cu")
		(net "USB3_CPU0_BMC_TX_DN")
	)
	(segment
		(start 134.708138 -48.008286)
		(end 141.84122 -34.305494)
		(width 0.14224)
		(layer "In15.Cu")
		(net "USB3_CPU0_BMC_TX_DN")
	)
	(segment
		(start 159.78251 -163.60775)
		(end 145.055082 -153.295604)
		(width 0.14224)
		(layer "In15.Cu")
		(net "USB3_CPU0_BMC_TX_DN")
	)
	(arc
		(start 370.89969 -222.614236)
		(mid 370.858292 -222.443362)
		(end 370.74348 -222.310198)
		(width 0.1143)
		(layer "In15.Cu")
		(net "USB3_CPU0_BMC_TX_DN")
	)
	(arc
		(start 371.362986 -223.354392)
		(mid 371.310788 -223.22297)
		(end 371.213634 -223.120204)
		(width 0.1143)
		(layer "In15.Cu")
		(net "USB3_CPU0_BMC_TX_DN")
	)
	(arc
		(start 370.684806 -222.275908)
		(mid 370.535267 -222.163521)
		(end 370.429536 -222.009208)
		(width 0.1143)
		(layer "In15.Cu")
		(net "USB3_CPU0_BMC_TX_DN")
	)
	(arc
		(start 371.144292 -223.079818)
		(mid 370.9645 -222.87723)
		(end 370.89969 -222.614236)
		(width 0.1143)
		(layer "In15.Cu")
		(net "USB3_CPU0_BMC_TX_DN")
	)
	(segment
		(start 136.208262 -21.705316)
		(end 136.909048 -22.406102)
		(width 0.12954)
		(layer "F.Cu")
		(net "USB3_CPU0_BMC_TX_BUF_C_DP")
	)
	(segment
		(start 136.208262 -19.432016)
		(end 136.393682 -19.617436)
		(width 0.12954)
		(layer "F.Cu")
		(net "USB3_CPU0_BMC_TX_BUF_C_DP")
	)
	(segment
		(start 136.346946 -16.549878)
		(end 136.346946 -17.117314)
		(width 0.12954)
		(layer "F.Cu")
		(net "USB3_CPU0_BMC_TX_BUF_C_DP")
	)
	(segment
		(start 136.393682 -19.998436)
		(end 136.208262 -20.183856)
		(width 0.12954)
		(layer "F.Cu")
		(net "USB3_CPU0_BMC_TX_BUF_C_DP")
	)
	(segment
		(start 122.95632 -36.485068)
		(end 122.52452 -36.053268)
		(width 0.12954)
		(layer "F.Cu")
		(net "USB3_CPU0_BMC_TX_BUF_C_DP")
	)
	(segment
		(start 136.208262 -20.183856)
		(end 136.208262 -20.564856)
		(width 0.12954)
		(layer "F.Cu")
		(net "USB3_CPU0_BMC_TX_BUF_C_DP")
	)
	(segment
		(start 136.393682 -21.131276)
		(end 136.208262 -21.316696)
		(width 0.12954)
		(layer "F.Cu")
		(net "USB3_CPU0_BMC_TX_BUF_C_DP")
	)
	(segment
		(start 136.393682 -19.617436)
		(end 136.393682 -19.998436)
		(width 0.12954)
		(layer "F.Cu")
		(net "USB3_CPU0_BMC_TX_BUF_C_DP")
	)
	(segment
		(start 136.346946 -17.117314)
		(end 136.208262 -17.255998)
		(width 0.12954)
		(layer "F.Cu")
		(net "USB3_CPU0_BMC_TX_BUF_C_DP")
	)
	(segment
		(start 136.208262 -20.564856)
		(end 136.393682 -20.750276)
		(width 0.12954)
		(layer "F.Cu")
		(net "USB3_CPU0_BMC_TX_BUF_C_DP")
	)
	(segment
		(start 136.909048 -22.406102)
		(end 137.31621 -22.406102)
		(width 0.12954)
		(layer "F.Cu")
		(net "USB3_CPU0_BMC_TX_BUF_C_DP")
	)
	(segment
		(start 136.208262 -21.316696)
		(end 136.208262 -21.705316)
		(width 0.12954)
		(layer "F.Cu")
		(net "USB3_CPU0_BMC_TX_BUF_C_DP")
	)
	(segment
		(start 136.393682 -20.750276)
		(end 136.393682 -21.131276)
		(width 0.12954)
		(layer "F.Cu")
		(net "USB3_CPU0_BMC_TX_BUF_C_DP")
	)
	(segment
		(start 122.95632 -36.675568)
		(end 122.95632 -36.485068)
		(width 0.12954)
		(layer "F.Cu")
		(net "USB3_CPU0_BMC_TX_BUF_C_DP")
	)
	(segment
		(start 136.208262 -17.255998)
		(end 136.208262 -19.432016)
		(width 0.12954)
		(layer "F.Cu")
		(net "USB3_CPU0_BMC_TX_BUF_C_DP")
	)
	(segment
		(start 129.0701 -28.643834)
		(end 128.724406 -30.02407)
		(width 0.14224)
		(layer "In15.Cu")
		(net "USB3_CPU0_BMC_TX_BUF_C_DP")
	)
	(segment
		(start 131.413504 -22.057614)
		(end 130.645408 -22.375876)
		(width 0.14224)
		(layer "In15.Cu")
		(net "USB3_CPU0_BMC_TX_BUF_C_DP")
	)
	(segment
		(start 123.725432 -34.856674)
		(end 123.725432 -34.85642)
		(width 0.14224)
		(layer "In15.Cu")
		(net "USB3_CPU0_BMC_TX_BUF_C_DP")
	)
	(segment
		(start 122.81535 -35.762438)
		(end 122.52452 -36.053268)
		(width 0.14224)
		(layer "In15.Cu")
		(net "USB3_CPU0_BMC_TX_BUF_C_DP")
	)
	(segment
		(start 136.534906 -22.036278)
		(end 131.43484 -22.036278)
		(width 0.14224)
		(layer "In15.Cu")
		(net "USB3_CPU0_BMC_TX_BUF_C_DP")
	)
	(segment
		(start 126.764034 -33.692338)
		(end 126.150878 -34.304224)
		(width 0.14224)
		(layer "In15.Cu")
		(net "USB3_CPU0_BMC_TX_BUF_C_DP")
	)
	(segment
		(start 130.645408 -22.375876)
		(end 129.283968 -23.737316)
		(width 0.14224)
		(layer "In15.Cu")
		(net "USB3_CPU0_BMC_TX_BUF_C_DP")
	)
	(segment
		(start 131.43484 -22.036278)
		(end 131.413504 -22.057614)
		(width 0.14224)
		(layer "In15.Cu")
		(net "USB3_CPU0_BMC_TX_BUF_C_DP")
	)
	(segment
		(start 129.283968 -23.737316)
		(end 129.0701 -24.253698)
		(width 0.14224)
		(layer "In15.Cu")
		(net "USB3_CPU0_BMC_TX_BUF_C_DP")
	)
	(segment
		(start 136.90473 -22.406102)
		(end 136.534906 -22.036278)
		(width 0.14224)
		(layer "In15.Cu")
		(net "USB3_CPU0_BMC_TX_BUF_C_DP")
	)
	(segment
		(start 126.150878 -34.304224)
		(end 125.82779 -34.438336)
		(width 0.14224)
		(layer "In15.Cu")
		(net "USB3_CPU0_BMC_TX_BUF_C_DP")
	)
	(segment
		(start 123.185174 -35.074606)
		(end 122.81535 -35.44443)
		(width 0.14224)
		(layer "In15.Cu")
		(net "USB3_CPU0_BMC_TX_BUF_C_DP")
	)
	(segment
		(start 125.82779 -34.438336)
		(end 123.725432 -34.856674)
		(width 0.14224)
		(layer "In15.Cu")
		(net "USB3_CPU0_BMC_TX_BUF_C_DP")
	)
	(segment
		(start 123.725432 -34.85642)
		(end 123.698 -34.862008)
		(width 0.14224)
		(layer "In15.Cu")
		(net "USB3_CPU0_BMC_TX_BUF_C_DP")
	)
	(segment
		(start 128.724406 -30.02407)
		(end 126.764034 -33.692338)
		(width 0.14224)
		(layer "In15.Cu")
		(net "USB3_CPU0_BMC_TX_BUF_C_DP")
	)
	(segment
		(start 129.0701 -24.253698)
		(end 129.0701 -28.643834)
		(width 0.14224)
		(layer "In15.Cu")
		(net "USB3_CPU0_BMC_TX_BUF_C_DP")
	)
	(segment
		(start 122.81535 -35.44443)
		(end 122.81535 -35.762438)
		(width 0.14224)
		(layer "In15.Cu")
		(net "USB3_CPU0_BMC_TX_BUF_C_DP")
	)
	(segment
		(start 123.698 -34.862008)
		(end 123.185174 -35.074606)
		(width 0.14224)
		(layer "In15.Cu")
		(net "USB3_CPU0_BMC_TX_BUF_C_DP")
	)
	(segment
		(start 137.31621 -22.406102)
		(end 136.90473 -22.406102)
		(width 0.14224)
		(layer "In15.Cu")
		(net "USB3_CPU0_BMC_TX_BUF_C_DP")
	)
	(segment
		(start 135.885682 -17.250918)
		(end 135.885682 -21.839174)
		(width 0.12954)
		(layer "F.Cu")
		(net "USB3_CPU0_BMC_TX_BUF_C_DN")
	)
	(segment
		(start 122.95632 -35.430968)
		(end 122.95632 -35.621468)
		(width 0.12954)
		(layer "F.Cu")
		(net "USB3_CPU0_BMC_TX_BUF_C_DN")
	)
	(segment
		(start 135.746998 -17.112234)
		(end 135.885682 -17.250918)
		(width 0.12954)
		(layer "F.Cu")
		(net "USB3_CPU0_BMC_TX_BUF_C_DN")
	)
	(segment
		(start 136.70534 -22.658832)
		(end 136.70534 -23.016972)
		(width 0.12954)
		(layer "F.Cu")
		(net "USB3_CPU0_BMC_TX_BUF_C_DN")
	)
	(segment
		(start 135.885682 -21.839174)
		(end 136.70534 -22.658832)
		(width 0.12954)
		(layer "F.Cu")
		(net "USB3_CPU0_BMC_TX_BUF_C_DN")
	)
	(segment
		(start 122.95632 -35.621468)
		(end 123.38812 -36.053268)
		(width 0.12954)
		(layer "F.Cu")
		(net "USB3_CPU0_BMC_TX_BUF_C_DN")
	)
	(segment
		(start 135.746998 -16.549878)
		(end 135.746998 -17.112234)
		(width 0.12954)
		(layer "F.Cu")
		(net "USB3_CPU0_BMC_TX_BUF_C_DN")
	)
	(segment
		(start 136.00684 -22.318218)
		(end 135.87222 -22.452838)
		(width 0.14224)
		(layer "In15.Cu")
		(net "USB3_CPU0_BMC_TX_BUF_C_DN")
	)
	(segment
		(start 125.910086 -34.709608)
		(end 123.780296 -35.13328)
		(width 0.14224)
		(layer "In15.Cu")
		(net "USB3_CPU0_BMC_TX_BUF_C_DN")
	)
	(segment
		(start 135.3312 -22.318218)
		(end 134.9248 -22.318218)
		(width 0.14224)
		(layer "In15.Cu")
		(net "USB3_CPU0_BMC_TX_BUF_C_DN")
	)
	(segment
		(start 135.87222 -22.452838)
		(end 135.46582 -22.452838)
		(width 0.14224)
		(layer "In15.Cu")
		(net "USB3_CPU0_BMC_TX_BUF_C_DN")
	)
	(segment
		(start 132.2197 -22.452838)
		(end 132.08508 -22.318218)
		(width 0.14224)
		(layer "In15.Cu")
		(net "USB3_CPU0_BMC_TX_BUF_C_DN")
	)
	(segment
		(start 123.09729 -35.762438)
		(end 123.38812 -36.053268)
		(width 0.14224)
		(layer "In15.Cu")
		(net "USB3_CPU0_BMC_TX_BUF_C_DN")
	)
	(segment
		(start 123.780296 -35.13328)
		(end 123.34494 -35.31362)
		(width 0.14224)
		(layer "In15.Cu")
		(net "USB3_CPU0_BMC_TX_BUF_C_DN")
	)
	(segment
		(start 123.34494 -35.31362)
		(end 123.09729 -35.56127)
		(width 0.14224)
		(layer "In15.Cu")
		(net "USB3_CPU0_BMC_TX_BUF_C_DN")
	)
	(segment
		(start 128.989582 -30.126178)
		(end 126.993142 -33.862518)
		(width 0.14224)
		(layer "In15.Cu")
		(net "USB3_CPU0_BMC_TX_BUF_C_DN")
	)
	(segment
		(start 131.5212 -22.318218)
		(end 130.805174 -22.61489)
		(width 0.14224)
		(layer "In15.Cu")
		(net "USB3_CPU0_BMC_TX_BUF_C_DN")
	)
	(segment
		(start 129.48666 -26.52014)
		(end 129.35204 -26.65476)
		(width 0.14224)
		(layer "In15.Cu")
		(net "USB3_CPU0_BMC_TX_BUF_C_DN")
	)
	(segment
		(start 129.35204 -28.678632)
		(end 128.989582 -30.126178)
		(width 0.14224)
		(layer "In15.Cu")
		(net "USB3_CPU0_BMC_TX_BUF_C_DN")
	)
	(segment
		(start 133.70814 -22.452838)
		(end 133.30174 -22.452838)
		(width 0.14224)
		(layer "In15.Cu")
		(net "USB3_CPU0_BMC_TX_BUF_C_DN")
	)
	(segment
		(start 129.522982 -23.897082)
		(end 129.35204 -24.309832)
		(width 0.14224)
		(layer "In15.Cu")
		(net "USB3_CPU0_BMC_TX_BUF_C_DN")
	)
	(segment
		(start 126.993142 -33.862518)
		(end 126.310644 -34.543492)
		(width 0.14224)
		(layer "In15.Cu")
		(net "USB3_CPU0_BMC_TX_BUF_C_DN")
	)
	(segment
		(start 129.35204 -24.89708)
		(end 129.48666 -25.0317)
		(width 0.14224)
		(layer "In15.Cu")
		(net "USB3_CPU0_BMC_TX_BUF_C_DN")
	)
	(segment
		(start 123.09729 -35.56127)
		(end 123.09729 -35.762438)
		(width 0.14224)
		(layer "In15.Cu")
		(net "USB3_CPU0_BMC_TX_BUF_C_DN")
	)
	(segment
		(start 129.48666 -25.0317)
		(end 129.48666 -25.4381)
		(width 0.14224)
		(layer "In15.Cu")
		(net "USB3_CPU0_BMC_TX_BUF_C_DN")
	)
	(segment
		(start 135.46582 -22.452838)
		(end 135.3312 -22.318218)
		(width 0.14224)
		(layer "In15.Cu")
		(net "USB3_CPU0_BMC_TX_BUF_C_DN")
	)
	(segment
		(start 129.35204 -25.97912)
		(end 129.48666 -26.11374)
		(width 0.14224)
		(layer "In15.Cu")
		(net "USB3_CPU0_BMC_TX_BUF_C_DN")
	)
	(segment
		(start 136.70534 -23.016972)
		(end 136.70534 -22.605492)
		(width 0.14224)
		(layer "In15.Cu")
		(net "USB3_CPU0_BMC_TX_BUF_C_DN")
	)
	(segment
		(start 129.35204 -26.65476)
		(end 129.35204 -28.678632)
		(width 0.14224)
		(layer "In15.Cu")
		(net "USB3_CPU0_BMC_TX_BUF_C_DN")
	)
	(segment
		(start 129.48666 -25.4381)
		(end 129.35204 -25.57272)
		(width 0.14224)
		(layer "In15.Cu")
		(net "USB3_CPU0_BMC_TX_BUF_C_DN")
	)
	(segment
		(start 136.70534 -22.605492)
		(end 136.418066 -22.318218)
		(width 0.14224)
		(layer "In15.Cu")
		(net "USB3_CPU0_BMC_TX_BUF_C_DN")
	)
	(segment
		(start 134.24916 -22.318218)
		(end 133.84276 -22.318218)
		(width 0.14224)
		(layer "In15.Cu")
		(net "USB3_CPU0_BMC_TX_BUF_C_DN")
	)
	(segment
		(start 134.79018 -22.452838)
		(end 134.38378 -22.452838)
		(width 0.14224)
		(layer "In15.Cu")
		(net "USB3_CPU0_BMC_TX_BUF_C_DN")
	)
	(segment
		(start 136.418066 -22.318218)
		(end 136.00684 -22.318218)
		(width 0.14224)
		(layer "In15.Cu")
		(net "USB3_CPU0_BMC_TX_BUF_C_DN")
	)
	(segment
		(start 129.35204 -24.309832)
		(end 129.35204 -24.89708)
		(width 0.14224)
		(layer "In15.Cu")
		(net "USB3_CPU0_BMC_TX_BUF_C_DN")
	)
	(segment
		(start 132.08508 -22.318218)
		(end 131.5212 -22.318218)
		(width 0.14224)
		(layer "In15.Cu")
		(net "USB3_CPU0_BMC_TX_BUF_C_DN")
	)
	(segment
		(start 126.310644 -34.543492)
		(end 125.910086 -34.709608)
		(width 0.14224)
		(layer "In15.Cu")
		(net "USB3_CPU0_BMC_TX_BUF_C_DN")
	)
	(segment
		(start 134.38378 -22.452838)
		(end 134.24916 -22.318218)
		(width 0.14224)
		(layer "In15.Cu")
		(net "USB3_CPU0_BMC_TX_BUF_C_DN")
	)
	(segment
		(start 133.16712 -22.318218)
		(end 132.76072 -22.318218)
		(width 0.14224)
		(layer "In15.Cu")
		(net "USB3_CPU0_BMC_TX_BUF_C_DN")
	)
	(segment
		(start 129.48666 -26.11374)
		(end 129.48666 -26.52014)
		(width 0.14224)
		(layer "In15.Cu")
		(net "USB3_CPU0_BMC_TX_BUF_C_DN")
	)
	(segment
		(start 132.76072 -22.318218)
		(end 132.6261 -22.452838)
		(width 0.14224)
		(layer "In15.Cu")
		(net "USB3_CPU0_BMC_TX_BUF_C_DN")
	)
	(segment
		(start 129.35204 -25.57272)
		(end 129.35204 -25.97912)
		(width 0.14224)
		(layer "In15.Cu")
		(net "USB3_CPU0_BMC_TX_BUF_C_DN")
	)
	(segment
		(start 133.84276 -22.318218)
		(end 133.70814 -22.452838)
		(width 0.14224)
		(layer "In15.Cu")
		(net "USB3_CPU0_BMC_TX_BUF_C_DN")
	)
	(segment
		(start 132.6261 -22.452838)
		(end 132.2197 -22.452838)
		(width 0.14224)
		(layer "In15.Cu")
		(net "USB3_CPU0_BMC_TX_BUF_C_DN")
	)
	(segment
		(start 134.9248 -22.318218)
		(end 134.79018 -22.452838)
		(width 0.14224)
		(layer "In15.Cu")
		(net "USB3_CPU0_BMC_TX_BUF_C_DN")
	)
	(segment
		(start 133.30174 -22.452838)
		(end 133.16712 -22.318218)
		(width 0.14224)
		(layer "In15.Cu")
		(net "USB3_CPU0_BMC_TX_BUF_C_DN")
	)
	(segment
		(start 130.805174 -22.61489)
		(end 129.522982 -23.897082)
		(width 0.14224)
		(layer "In15.Cu")
		(net "USB3_CPU0_BMC_TX_BUF_C_DN")
	)
	(segment
		(start 124.98832 -32.954468)
		(end 124.98832 -32.751268)
		(width 0.12954)
		(layer "F.Cu")
		(net "USB3_CPU0_BMC_RX_DP")
	)
	(segment
		(start 136.346946 -13.599922)
		(end 136.346946 -12.995148)
		(width 0.12954)
		(layer "F.Cu")
		(net "USB3_CPU0_BMC_RX_DP")
	)
	(segment
		(start 136.208262 -12.225528)
		(end 136.478772 -11.955018)
		(width 0.12954)
		(layer "F.Cu")
		(net "USB3_CPU0_BMC_RX_DP")
	)
	(segment
		(start 136.346946 -12.995148)
		(end 136.208262 -12.856464)
		(width 0.12954)
		(layer "F.Cu")
		(net "USB3_CPU0_BMC_RX_DP")
	)
	(segment
		(start 136.208262 -12.856464)
		(end 136.208262 -12.225528)
		(width 0.12954)
		(layer "F.Cu")
		(net "USB3_CPU0_BMC_RX_DP")
	)
	(segment
		(start 125.42012 -33.386268)
		(end 124.98832 -32.954468)
		(width 0.12954)
		(layer "F.Cu")
		(net "USB3_CPU0_BMC_RX_DP")
	)
	(segment
		(start 129.242312 -22.657816)
		(end 130.602228 -21.2979)
		(width 0.14224)
		(layer "In11.Cu")
		(net "USB3_CPU0_BMC_RX_DP")
	)
	(segment
		(start 125.12929 -32.89427)
		(end 126.21768 -31.80588)
		(width 0.14224)
		(layer "In11.Cu")
		(net "USB3_CPU0_BMC_RX_DP")
	)
	(segment
		(start 136.187942 -12.245848)
		(end 136.478772 -11.955018)
		(width 0.14224)
		(layer "In11.Cu")
		(net "USB3_CPU0_BMC_RX_DP")
	)
	(segment
		(start 136.187942 -18.914618)
		(end 136.187942 -12.245848)
		(width 0.14224)
		(layer "In11.Cu")
		(net "USB3_CPU0_BMC_RX_DP")
	)
	(segment
		(start 125.42012 -33.386268)
		(end 125.12929 -33.095438)
		(width 0.14224)
		(layer "In11.Cu")
		(net "USB3_CPU0_BMC_RX_DP")
	)
	(segment
		(start 129.242312 -30.485588)
		(end 129.242312 -22.657816)
		(width 0.14224)
		(layer "In11.Cu")
		(net "USB3_CPU0_BMC_RX_DP")
	)
	(segment
		(start 133.80466 -21.2979)
		(end 136.187942 -18.914618)
		(width 0.14224)
		(layer "In11.Cu")
		(net "USB3_CPU0_BMC_RX_DP")
	)
	(segment
		(start 125.12929 -33.095438)
		(end 125.12929 -32.89427)
		(width 0.14224)
		(layer "In11.Cu")
		(net "USB3_CPU0_BMC_RX_DP")
	)
	(segment
		(start 127.92202 -31.80588)
		(end 129.242312 -30.485588)
		(width 0.14224)
		(layer "In11.Cu")
		(net "USB3_CPU0_BMC_RX_DP")
	)
	(segment
		(start 126.21768 -31.80588)
		(end 127.92202 -31.80588)
		(width 0.14224)
		(layer "In11.Cu")
		(net "USB3_CPU0_BMC_RX_DP")
	)
	(segment
		(start 130.602228 -21.2979)
		(end 133.80466 -21.2979)
		(width 0.14224)
		(layer "In11.Cu")
		(net "USB3_CPU0_BMC_RX_DP")
	)
	(segment
		(start 135.885682 -12.92352)
		(end 135.885682 -12.225528)
		(width 0.12954)
		(layer "F.Cu")
		(net "USB3_CPU0_BMC_RX_DN")
	)
	(segment
		(start 124.98832 -33.818068)
		(end 124.98832 -34.021268)
		(width 0.12954)
		(layer "F.Cu")
		(net "USB3_CPU0_BMC_RX_DN")
	)
	(segment
		(start 135.746998 -13.599922)
		(end 135.746998 -13.062204)
		(width 0.12954)
		(layer "F.Cu")
		(net "USB3_CPU0_BMC_RX_DN")
	)
	(segment
		(start 124.55652 -33.386268)
		(end 124.98832 -33.818068)
		(width 0.12954)
		(layer "F.Cu")
		(net "USB3_CPU0_BMC_RX_DN")
	)
	(segment
		(start 135.885682 -12.225528)
		(end 135.615172 -11.955018)
		(width 0.12954)
		(layer "F.Cu")
		(net "USB3_CPU0_BMC_RX_DN")
	)
	(segment
		(start 135.746998 -13.062204)
		(end 135.885682 -12.92352)
		(width 0.12954)
		(layer "F.Cu")
		(net "USB3_CPU0_BMC_RX_DN")
	)
	(segment
		(start 124.84735 -33.095438)
		(end 124.84735 -32.77743)
		(width 0.14224)
		(layer "In11.Cu")
		(net "USB3_CPU0_BMC_RX_DN")
	)
	(segment
		(start 127.80518 -31.52394)
		(end 128.960372 -30.368748)
		(width 0.14224)
		(layer "In11.Cu")
		(net "USB3_CPU0_BMC_RX_DN")
	)
	(segment
		(start 128.960372 -30.368748)
		(end 128.960372 -22.540976)
		(width 0.14224)
		(layer "In11.Cu")
		(net "USB3_CPU0_BMC_RX_DN")
	)
	(segment
		(start 124.84735 -32.77743)
		(end 126.10084 -31.52394)
		(width 0.14224)
		(layer "In11.Cu")
		(net "USB3_CPU0_BMC_RX_DN")
	)
	(segment
		(start 133.68782 -21.01596)
		(end 135.906002 -18.797778)
		(width 0.14224)
		(layer "In11.Cu")
		(net "USB3_CPU0_BMC_RX_DN")
	)
	(segment
		(start 126.10084 -31.52394)
		(end 127.80518 -31.52394)
		(width 0.14224)
		(layer "In11.Cu")
		(net "USB3_CPU0_BMC_RX_DN")
	)
	(segment
		(start 128.960372 -22.540976)
		(end 130.485388 -21.01596)
		(width 0.14224)
		(layer "In11.Cu")
		(net "USB3_CPU0_BMC_RX_DN")
	)
	(segment
		(start 124.55652 -33.386268)
		(end 124.84735 -33.095438)
		(width 0.14224)
		(layer "In11.Cu")
		(net "USB3_CPU0_BMC_RX_DN")
	)
	(segment
		(start 130.485388 -21.01596)
		(end 133.68782 -21.01596)
		(width 0.14224)
		(layer "In11.Cu")
		(net "USB3_CPU0_BMC_RX_DN")
	)
	(segment
		(start 135.906002 -12.245848)
		(end 135.615172 -11.955018)
		(width 0.14224)
		(layer "In11.Cu")
		(net "USB3_CPU0_BMC_RX_DN")
	)
	(segment
		(start 135.906002 -18.797778)
		(end 135.906002 -12.245848)
		(width 0.14224)
		(layer "In11.Cu")
		(net "USB3_CPU0_BMC_RX_DN")
	)
	(segment
		(start 317.284608 -15.337536)
		(end 317.284608 -18.51533)
		(width 0.10668)
		(layer "F.Cu")
		(net "UART_VCC_J8")
	)
	(segment
		(start 319.905888 -22.171406)
		(end 320.921888 -22.171406)
		(width 0.10668)
		(layer "F.Cu")
		(net "UART_VCC_J8")
	)
	(segment
		(start 317.284608 -19.13128)
		(end 317.284608 -18.51533)
		(width 0.10668)
		(layer "F.Cu")
		(net "UART_VCC_J8")
	)
	(segment
		(start 319.905888 -22.171406)
		(end 319.905888 -21.75256)
		(width 0.10668)
		(layer "F.Cu")
		(net "UART_VCC_J8")
	)
	(segment
		(start 319.905888 -21.75256)
		(end 317.284608 -19.13128)
		(width 0.10668)
		(layer "F.Cu")
		(net "UART_VCC_J8")
	)
	(via
		(at 317.284608 -18.51533)
		(size 0.508)
		(drill 0.254)
		(layers "F.Cu" "B.Cu")
		(net "UART_VCC_J8")
	)
	(segment
		(start 163.40455 -19.723608)
		(end 163.205414 -19.922744)
		(width 0.10668)
		(layer "F.Cu")
		(net "TP_PVCCIO_PECI_BMC")
	)
	(segment
		(start 163.40455 -18.700496)
		(end 163.40455 -19.723608)
		(width 0.10668)
		(layer "F.Cu")
		(net "TP_PVCCIO_PECI_BMC")
	)
	(segment
		(start 162.996626 -18.292572)
		(end 163.40455 -18.700496)
		(width 0.10668)
		(layer "F.Cu")
		(net "TP_PVCCIO_PECI_BMC")
	)
	(segment
		(start 162.996626 -17.480788)
		(end 162.996626 -18.292572)
		(width 0.10668)
		(layer "F.Cu")
		(net "TP_PVCCIO_PECI_BMC")
	)
	(segment
		(start 162.666934 -17.151096)
		(end 162.996626 -17.480788)
		(width 0.10668)
		(layer "F.Cu")
		(net "TP_PVCCIO_PECI_BMC")
	)
	(segment
		(start 162.666934 -16.549878)
		(end 162.666934 -17.151096)
		(width 0.10668)
		(layer "F.Cu")
		(net "TP_PVCCIO_PECI_BMC")
	)
	(via
		(at 163.205414 -19.922744)
		(size 0.762)
		(drill 0.381)
		(layers "F.Cu" "B.Cu")
		(net "TP_PVCCIO_PECI_BMC")
	)
	(segment
		(start 130.346958 -18.228818)
		(end 129.661158 -18.914618)
		(width 0.10668)
		(layer "F.Cu")
		(net "TP_BEEP_LED")
	)
	(segment
		(start 130.346958 -16.549878)
		(end 130.346958 -18.228818)
		(width 0.10668)
		(layer "F.Cu")
		(net "TP_BEEP_LED")
	)
	(segment
		(start 129.661158 -18.914618)
		(end 129.661158 -19.752818)
		(width 0.10668)
		(layer "F.Cu")
		(net "TP_BEEP_LED")
	)
	(via
		(at 129.661158 -19.752818)
		(size 0.762)
		(drill 0.381)
		(layers "F.Cu" "B.Cu")
		(net "TP_BEEP_LED")
	)
	(segment
		(start 179.831238 -414.215072)
		(end 179.831238 -415.064956)
		(width 0.10668)
		(layer "F.Cu")
		(net "TCA9539_0_ADD1")
	)
	(segment
		(start 177.748946 -414.215072)
		(end 178.764946 -414.215072)
		(width 0.10668)
		(layer "F.Cu")
		(net "TCA9539_0_ADD1")
	)
	(segment
		(start 179.831238 -415.064956)
		(end 181.412134 -416.645852)
		(width 0.10668)
		(layer "F.Cu")
		(net "TCA9539_0_ADD1")
	)
	(segment
		(start 181.412134 -416.645852)
		(end 181.412134 -417.404804)
		(width 0.10668)
		(layer "F.Cu")
		(net "TCA9539_0_ADD1")
	)
	(segment
		(start 179.831238 -414.215072)
		(end 178.764946 -414.215072)
		(width 0.10668)
		(layer "F.Cu")
		(net "TCA9539_0_ADD1")
	)
	(via
		(at 179.831238 -414.215072)
		(size 0.762)
		(drill 0.381)
		(layers "F.Cu" "B.Cu")
		(net "TCA9539_0_ADD1")
	)
	(segment
		(start 177.778156 -426.332396)
		(end 177.778156 -427.226984)
		(width 0.10668)
		(layer "F.Cu")
		(net "TCA9539_0_ADD0")
	)
	(segment
		(start 180.34381 -426.332396)
		(end 178.983386 -426.332396)
		(width 0.10668)
		(layer "F.Cu")
		(net "TCA9539_0_ADD0")
	)
	(segment
		(start 182.712106 -423.9641)
		(end 180.34381 -426.332396)
		(width 0.10668)
		(layer "F.Cu")
		(net "TCA9539_0_ADD0")
	)
	(segment
		(start 178.983386 -426.332396)
		(end 177.778156 -426.332396)
		(width 0.10668)
		(layer "F.Cu")
		(net "TCA9539_0_ADD0")
	)
	(segment
		(start 182.712106 -423.254932)
		(end 182.712106 -423.9641)
		(width 0.10668)
		(layer "F.Cu")
		(net "TCA9539_0_ADD0")
	)
	(via
		(at 178.983386 -426.332396)
		(size 0.762)
		(drill 0.381)
		(layers "F.Cu" "B.Cu")
		(net "TCA9539_0_ADD0")
	)
	(segment
		(start 270.685006 -123.86437)
		(end 269.837662 -123.86437)
		(width 0.10668)
		(layer "F.Cu")
		(net "SMB_VR_SENSOR_3V3AUX_SDA_R")
	)
	(segment
		(start 268.46784 -122.494548)
		(end 268.105382 -122.13209)
		(width 0.10668)
		(layer "F.Cu")
		(net "SMB_VR_SENSOR_3V3AUX_SDA_R")
	)
	(segment
		(start 269.837662 -123.86437)
		(end 268.46784 -122.494548)
		(width 0.10668)
		(layer "F.Cu")
		(net "SMB_VR_SENSOR_3V3AUX_SDA_R")
	)
	(segment
		(start 268.105382 -122.13209)
		(end 266.975082 -122.13209)
		(width 0.10668)
		(layer "F.Cu")
		(net "SMB_VR_SENSOR_3V3AUX_SDA_R")
	)
	(via
		(at 268.46784 -122.494548)
		(size 0.508)
		(drill 0.254)
		(layers "F.Cu" "B.Cu")
		(net "SMB_VR_SENSOR_3V3AUX_SDA_R")
	)
	(segment
		(start 270.426688 -123.106688)
		(end 270.685006 -122.84837)
		(width 0.10668)
		(layer "F.Cu")
		(net "SMB_VR_SENSOR_3V3AUX_SCL_R")
	)
	(segment
		(start 268.135862 -121.482104)
		(end 268.186916 -121.482104)
		(width 0.10668)
		(layer "F.Cu")
		(net "SMB_VR_SENSOR_3V3AUX_SCL_R")
	)
	(segment
		(start 268.186916 -121.482104)
		(end 269.8115 -123.106688)
		(width 0.10668)
		(layer "F.Cu")
		(net "SMB_VR_SENSOR_3V3AUX_SCL_R")
	)
	(segment
		(start 266.975082 -121.482104)
		(end 268.135862 -121.482104)
		(width 0.10668)
		(layer "F.Cu")
		(net "SMB_VR_SENSOR_3V3AUX_SCL_R")
	)
	(segment
		(start 269.8115 -123.106688)
		(end 270.426688 -123.106688)
		(width 0.10668)
		(layer "F.Cu")
		(net "SMB_VR_SENSOR_3V3AUX_SCL_R")
	)
	(via
		(at 269.8115 -123.106688)
		(size 0.508)
		(drill 0.254)
		(layers "F.Cu" "B.Cu")
		(net "SMB_VR_SENSOR_3V3AUX_SCL_R")
	)
	(segment
		(start 258.87934 -121.95937)
		(end 259.274056 -121.95937)
		(width 0.10668)
		(layer "F.Cu")
		(net "SMB_VR_3V3AUX_SDA_R6")
	)
	(segment
		(start 257.642106 -121.95937)
		(end 258.87934 -121.95937)
		(width 0.10668)
		(layer "F.Cu")
		(net "SMB_VR_3V3AUX_SDA_R6")
	)
	(segment
		(start 260.401308 -120.832118)
		(end 261.37489 -120.832118)
		(width 0.10668)
		(layer "F.Cu")
		(net "SMB_VR_3V3AUX_SDA_R6")
	)
	(segment
		(start 259.274056 -121.95937)
		(end 260.401308 -120.832118)
		(width 0.10668)
		(layer "F.Cu")
		(net "SMB_VR_3V3AUX_SDA_R6")
	)
	(via
		(at 258.87934 -121.95937)
		(size 0.508)
		(drill 0.254)
		(layers "F.Cu" "B.Cu")
		(net "SMB_VR_3V3AUX_SDA_R6")
	)
	(segment
		(start 259.809996 -120.53443)
		(end 259.401056 -120.94337)
		(width 0.10668)
		(layer "F.Cu")
		(net "SMB_VR_3V3AUX_SCL_R6")
	)
	(segment
		(start 259.401056 -120.94337)
		(end 257.642106 -120.94337)
		(width 0.10668)
		(layer "F.Cu")
		(net "SMB_VR_3V3AUX_SCL_R6")
	)
	(segment
		(start 260.162294 -120.182132)
		(end 259.809996 -120.53443)
		(width 0.10668)
		(layer "F.Cu")
		(net "SMB_VR_3V3AUX_SCL_R6")
	)
	(segment
		(start 261.37489 -120.182132)
		(end 260.162294 -120.182132)
		(width 0.10668)
		(layer "F.Cu")
		(net "SMB_VR_3V3AUX_SCL_R6")
	)
	(via
		(at 259.809996 -120.53443)
		(size 0.508)
		(drill 0.254)
		(layers "F.Cu" "B.Cu")
		(net "SMB_VR_3V3AUX_SCL_R6")
	)
	(via
		(at 164.036756 -15.252954)
		(size 0.6604)
		(drill 0.3302)
		(layers "F.Cu" "B.Cu")
		(net "SMB_PMBUS_3V3AUX_SDA")
	)
	(segment
		(start 164.036756 -15.252954)
		(end 164.557456 -15.773654)
		(width 0.10668)
		(layer "B.Cu")
		(net "SMB_PMBUS_3V3AUX_SDA")
	)
	(segment
		(start 164.549328 -17.417288)
		(end 164.549328 -16.453358)
		(width 0.10668)
		(layer "B.Cu")
		(net "SMB_PMBUS_3V3AUX_SDA")
	)
	(segment
		(start 163.886388 -15.102586)
		(end 164.036756 -15.252954)
		(width 0.10668)
		(layer "B.Cu")
		(net "SMB_PMBUS_3V3AUX_SDA")
	)
	(segment
		(start 163.886388 -14.05509)
		(end 163.886388 -15.102586)
		(width 0.10668)
		(layer "B.Cu")
		(net "SMB_PMBUS_3V3AUX_SDA")
	)
	(segment
		(start 164.549328 -16.453358)
		(end 164.557456 -16.44523)
		(width 0.10668)
		(layer "B.Cu")
		(net "SMB_PMBUS_3V3AUX_SDA")
	)
	(segment
		(start 164.557456 -15.773654)
		(end 164.557456 -16.44523)
		(width 0.10668)
		(layer "B.Cu")
		(net "SMB_PMBUS_3V3AUX_SDA")
	)
	(via
		(at 166.088568 -13.795756)
		(size 0.6604)
		(drill 0.3302)
		(layers "F.Cu" "B.Cu")
		(net "SMB_PMBUS_3V3AUX_SCL")
	)
	(segment
		(start 166.088568 -13.795756)
		(end 165.829234 -14.05509)
		(width 0.10668)
		(layer "B.Cu")
		(net "SMB_PMBUS_3V3AUX_SCL")
	)
	(segment
		(start 167.311324 -14.05509)
		(end 166.347902 -14.05509)
		(width 0.10668)
		(layer "B.Cu")
		(net "SMB_PMBUS_3V3AUX_SCL")
	)
	(segment
		(start 165.829234 -14.05509)
		(end 164.902388 -14.05509)
		(width 0.10668)
		(layer "B.Cu")
		(net "SMB_PMBUS_3V3AUX_SCL")
	)
	(segment
		(start 166.347902 -14.05509)
		(end 166.088568 -13.795756)
		(width 0.10668)
		(layer "B.Cu")
		(net "SMB_PMBUS_3V3AUX_SCL")
	)
	(segment
		(start 168.367202 -14.06525)
		(end 167.321484 -14.06525)
		(width 0.10668)
		(layer "B.Cu")
		(net "SMB_PMBUS_3V3AUX_SCL")
	)
	(segment
		(start 167.321484 -14.06525)
		(end 167.31869 -14.062456)
		(width 0.10668)
		(layer "B.Cu")
		(net "SMB_PMBUS_3V3AUX_SCL")
	)
	(segment
		(start 167.31869 -14.062456)
		(end 167.311324 -14.05509)
		(width 0.10668)
		(layer "B.Cu")
		(net "SMB_PMBUS_3V3AUX_SCL")
	)
	(segment
		(start 281.315922 -114.64417)
		(end 281.696922 -115.02517)
		(width 0.10668)
		(layer "F.Cu")
		(net "SMB_PCIE0_3V3AUX_SDA_R5")
	)
	(segment
		(start 281.696922 -115.02517)
		(end 281.696922 -115.68049)
		(width 0.10668)
		(layer "F.Cu")
		(net "SMB_PCIE0_3V3AUX_SDA_R5")
	)
	(segment
		(start 279.913842 -114.64417)
		(end 281.315922 -114.64417)
		(width 0.10668)
		(layer "F.Cu")
		(net "SMB_PCIE0_3V3AUX_SDA_R5")
	)
	(segment
		(start 282.94838 -116.931948)
		(end 284.127956 -116.931948)
		(width 0.10668)
		(layer "F.Cu")
		(net "SMB_PCIE0_3V3AUX_SDA_R5")
	)
	(segment
		(start 281.696922 -115.68049)
		(end 282.94838 -116.931948)
		(width 0.10668)
		(layer "F.Cu")
		(net "SMB_PCIE0_3V3AUX_SDA_R5")
	)
	(via
		(at 281.696922 -115.02517)
		(size 0.762)
		(drill 0.381)
		(layers "F.Cu" "B.Cu")
		(net "SMB_PCIE0_3V3AUX_SDA_R5")
	)
	(segment
		(start 282.213304 -117.954552)
		(end 282.490672 -118.23192)
		(width 0.10668)
		(layer "F.Cu")
		(net "SMB_PCIE0_3V3AUX_SDA_R3")
	)
	(segment
		(start 282.490672 -118.23192)
		(end 284.127956 -118.23192)
		(width 0.10668)
		(layer "F.Cu")
		(net "SMB_PCIE0_3V3AUX_SDA_R3")
	)
	(segment
		(start 281.950922 -117.69217)
		(end 282.213304 -117.954552)
		(width 0.10668)
		(layer "F.Cu")
		(net "SMB_PCIE0_3V3AUX_SDA_R3")
	)
	(segment
		(start 279.913842 -116.67617)
		(end 280.929842 -117.69217)
		(width 0.10668)
		(layer "F.Cu")
		(net "SMB_PCIE0_3V3AUX_SDA_R3")
	)
	(segment
		(start 280.929842 -117.69217)
		(end 281.950922 -117.69217)
		(width 0.10668)
		(layer "F.Cu")
		(net "SMB_PCIE0_3V3AUX_SDA_R3")
	)
	(via
		(at 282.213304 -117.954552)
		(size 0.508)
		(drill 0.254)
		(layers "F.Cu" "B.Cu")
		(net "SMB_PCIE0_3V3AUX_SDA_R3")
	)
	(segment
		(start 292.323266 -123.746514)
		(end 290.708842 -122.13209)
		(width 0.10668)
		(layer "F.Cu")
		(net "SMB_PCIE0_3V3AUX_SDA_R")
	)
	(segment
		(start 294.326056 -124.337064)
		(end 293.735506 -123.746514)
		(width 0.10668)
		(layer "F.Cu")
		(net "SMB_PCIE0_3V3AUX_SDA_R")
	)
	(segment
		(start 290.708842 -122.13209)
		(end 289.728148 -122.13209)
		(width 0.10668)
		(layer "F.Cu")
		(net "SMB_PCIE0_3V3AUX_SDA_R")
	)
	(segment
		(start 293.735506 -123.746514)
		(end 292.323266 -123.746514)
		(width 0.10668)
		(layer "F.Cu")
		(net "SMB_PCIE0_3V3AUX_SDA_R")
	)
	(via
		(at 163.820602 -7.402322)
		(size 0.508)
		(drill 0.254)
		(layers "F.Cu" "B.Cu")
		(net "SMB_PCIE0_3V3AUX_SDA_R")
	)
	(via
		(at 294.326056 -124.337064)
		(size 0.508)
		(drill 0.254)
		(layers "F.Cu" "B.Cu")
		(net "SMB_PCIE0_3V3AUX_SDA_R")
	)
	(segment
		(start 163.820602 -7.402322)
		(end 163.854892 -7.436612)
		(width 0.10668)
		(layer "B.Cu")
		(net "SMB_PCIE0_3V3AUX_SDA_R")
	)
	(segment
		(start 163.854892 -7.436612)
		(end 163.854892 -7.609332)
		(width 0.10668)
		(layer "B.Cu")
		(net "SMB_PCIE0_3V3AUX_SDA_R")
	)
	(segment
		(start 163.854892 -7.609332)
		(end 164.508688 -8.263128)
		(width 0.10668)
		(layer "B.Cu")
		(net "SMB_PCIE0_3V3AUX_SDA_R")
	)
	(segment
		(start 164.508688 -8.263128)
		(end 164.508688 -8.613394)
		(width 0.10668)
		(layer "B.Cu")
		(net "SMB_PCIE0_3V3AUX_SDA_R")
	)
	(segment
		(start 164.46754 -9.005316)
		(end 167.271954 -9.005316)
		(width 0.11684)
		(layer "In4.Cu")
		(net "SMB_PCIE0_3V3AUX_SDA_R")
	)
	(segment
		(start 168.059862 -7.925816)
		(end 168.176702 -7.808976)
		(width 0.11684)
		(layer "In4.Cu")
		(net "SMB_PCIE0_3V3AUX_SDA_R")
	)
	(segment
		(start 209.68208 -25.556972)
		(end 207.08874 -28.150312)
		(width 0.11684)
		(layer "In4.Cu")
		(net "SMB_PCIE0_3V3AUX_SDA_R")
	)
	(segment
		(start 264.832592 -64.67856)
		(end 266.545314 -62.965838)
		(width 0.11684)
		(layer "In4.Cu")
		(net "SMB_PCIE0_3V3AUX_SDA_R")
	)
	(segment
		(start 212.41258 -35.597084)
		(end 212.41258 -38.281864)
		(width 0.11684)
		(layer "In4.Cu")
		(net "SMB_PCIE0_3V3AUX_SDA_R")
	)
	(segment
		(start 195.978018 -13.892784)
		(end 205.05674 -13.892784)
		(width 0.11684)
		(layer "In4.Cu")
		(net "SMB_PCIE0_3V3AUX_SDA_R")
	)
	(segment
		(start 193.320162 -10.478262)
		(end 193.565526 -10.723626)
		(width 0.11684)
		(layer "In4.Cu")
		(net "SMB_PCIE0_3V3AUX_SDA_R")
	)
	(segment
		(start 214.60968 -40.478964)
		(end 214.60968 -43.880024)
		(width 0.11684)
		(layer "In4.Cu")
		(net "SMB_PCIE0_3V3AUX_SDA_R")
	)
	(segment
		(start 205.05674 -13.892784)
		(end 209.68208 -18.518124)
		(width 0.11684)
		(layer "In4.Cu")
		(net "SMB_PCIE0_3V3AUX_SDA_R")
	)
	(segment
		(start 182.45582 -9.083802)
		(end 190.869062 -9.083802)
		(width 0.11684)
		(layer "In4.Cu")
		(net "SMB_PCIE0_3V3AUX_SDA_R")
	)
	(segment
		(start 191.516254 -9.730994)
		(end 193.320162 -10.478262)
		(width 0.11684)
		(layer "In4.Cu")
		(net "SMB_PCIE0_3V3AUX_SDA_R")
	)
	(segment
		(start 282.659074 -111.553244)
		(end 284.48889 -113.38306)
		(width 0.11684)
		(layer "In4.Cu")
		(net "SMB_PCIE0_3V3AUX_SDA_R")
	)
	(segment
		(start 231.909874 -64.67856)
		(end 264.832592 -64.67856)
		(width 0.11684)
		(layer "In4.Cu")
		(net "SMB_PCIE0_3V3AUX_SDA_R")
	)
	(segment
		(start 212.41258 -38.281864)
		(end 214.60968 -40.478964)
		(width 0.11684)
		(layer "In4.Cu")
		(net "SMB_PCIE0_3V3AUX_SDA_R")
	)
	(segment
		(start 207.08874 -30.273244)
		(end 212.41258 -35.597084)
		(width 0.11684)
		(layer "In4.Cu")
		(net "SMB_PCIE0_3V3AUX_SDA_R")
	)
	(segment
		(start 284.48889 -121.028206)
		(end 286.800036 -123.339352)
		(width 0.11684)
		(layer "In4.Cu")
		(net "SMB_PCIE0_3V3AUX_SDA_R")
	)
	(segment
		(start 284.48889 -113.38306)
		(end 284.48889 -121.028206)
		(width 0.11684)
		(layer "In4.Cu")
		(net "SMB_PCIE0_3V3AUX_SDA_R")
	)
	(segment
		(start 218.454732 -51.223418)
		(end 231.909874 -64.67856)
		(width 0.11684)
		(layer "In4.Cu")
		(net "SMB_PCIE0_3V3AUX_SDA_R")
	)
	(segment
		(start 193.565526 -10.723626)
		(end 194.10045 -12.015216)
		(width 0.11684)
		(layer "In4.Cu")
		(net "SMB_PCIE0_3V3AUX_SDA_R")
	)
	(segment
		(start 214.60968 -43.880024)
		(end 218.454732 -47.725076)
		(width 0.11684)
		(layer "In4.Cu")
		(net "SMB_PCIE0_3V3AUX_SDA_R")
	)
	(segment
		(start 168.059862 -8.217408)
		(end 168.059862 -7.925816)
		(width 0.11684)
		(layer "In4.Cu")
		(net "SMB_PCIE0_3V3AUX_SDA_R")
	)
	(segment
		(start 209.68208 -18.518124)
		(end 209.68208 -25.556972)
		(width 0.11684)
		(layer "In4.Cu")
		(net "SMB_PCIE0_3V3AUX_SDA_R")
	)
	(segment
		(start 293.328344 -123.339352)
		(end 294.326056 -124.337064)
		(width 0.11684)
		(layer "In4.Cu")
		(net "SMB_PCIE0_3V3AUX_SDA_R")
	)
	(segment
		(start 218.454732 -47.725076)
		(end 218.454732 -51.223418)
		(width 0.11684)
		(layer "In4.Cu")
		(net "SMB_PCIE0_3V3AUX_SDA_R")
	)
	(segment
		(start 286.800036 -123.339352)
		(end 293.328344 -123.339352)
		(width 0.11684)
		(layer "In4.Cu")
		(net "SMB_PCIE0_3V3AUX_SDA_R")
	)
	(segment
		(start 207.08874 -28.150312)
		(end 207.08874 -30.273244)
		(width 0.11684)
		(layer "In4.Cu")
		(net "SMB_PCIE0_3V3AUX_SDA_R")
	)
	(segment
		(start 273.035522 -62.965838)
		(end 282.659074 -72.58939)
		(width 0.11684)
		(layer "In4.Cu")
		(net "SMB_PCIE0_3V3AUX_SDA_R")
	)
	(segment
		(start 179.431188 -10.299192)
		(end 181.24043 -10.299192)
		(width 0.11684)
		(layer "In4.Cu")
		(net "SMB_PCIE0_3V3AUX_SDA_R")
	)
	(segment
		(start 167.271954 -9.005316)
		(end 168.059862 -8.217408)
		(width 0.11684)
		(layer "In4.Cu")
		(net "SMB_PCIE0_3V3AUX_SDA_R")
	)
	(segment
		(start 163.820602 -8.358378)
		(end 164.46754 -9.005316)
		(width 0.11684)
		(layer "In4.Cu")
		(net "SMB_PCIE0_3V3AUX_SDA_R")
	)
	(segment
		(start 190.869062 -9.083802)
		(end 191.516254 -9.730994)
		(width 0.11684)
		(layer "In4.Cu")
		(net "SMB_PCIE0_3V3AUX_SDA_R")
	)
	(segment
		(start 168.176702 -7.808976)
		(end 176.940972 -7.808976)
		(width 0.11684)
		(layer "In4.Cu")
		(net "SMB_PCIE0_3V3AUX_SDA_R")
	)
	(segment
		(start 176.940972 -7.808976)
		(end 179.431188 -10.299192)
		(width 0.11684)
		(layer "In4.Cu")
		(net "SMB_PCIE0_3V3AUX_SDA_R")
	)
	(segment
		(start 194.10045 -12.015216)
		(end 195.978018 -13.892784)
		(width 0.11684)
		(layer "In4.Cu")
		(net "SMB_PCIE0_3V3AUX_SDA_R")
	)
	(segment
		(start 282.659074 -72.58939)
		(end 282.659074 -111.553244)
		(width 0.11684)
		(layer "In4.Cu")
		(net "SMB_PCIE0_3V3AUX_SDA_R")
	)
	(segment
		(start 266.545314 -62.965838)
		(end 273.035522 -62.965838)
		(width 0.11684)
		(layer "In4.Cu")
		(net "SMB_PCIE0_3V3AUX_SDA_R")
	)
	(segment
		(start 163.820602 -7.402322)
		(end 163.820602 -8.358378)
		(width 0.11684)
		(layer "In4.Cu")
		(net "SMB_PCIE0_3V3AUX_SDA_R")
	)
	(segment
		(start 181.24043 -10.299192)
		(end 182.45582 -9.083802)
		(width 0.11684)
		(layer "In4.Cu")
		(net "SMB_PCIE0_3V3AUX_SDA_R")
	)
	(segment
		(start 279.913842 -113.62817)
		(end 281.188922 -113.62817)
		(width 0.10668)
		(layer "F.Cu")
		(net "SMB_PCIE0_3V3AUX_SCL_R5")
	)
	(segment
		(start 282.331922 -115.66017)
		(end 282.953714 -116.281962)
		(width 0.10668)
		(layer "F.Cu")
		(net "SMB_PCIE0_3V3AUX_SCL_R5")
	)
	(segment
		(start 282.953714 -116.281962)
		(end 284.127956 -116.281962)
		(width 0.10668)
		(layer "F.Cu")
		(net "SMB_PCIE0_3V3AUX_SCL_R5")
	)
	(segment
		(start 281.188922 -113.62817)
		(end 282.331922 -114.77117)
		(width 0.10668)
		(layer "F.Cu")
		(net "SMB_PCIE0_3V3AUX_SCL_R5")
	)
	(segment
		(start 282.331922 -114.77117)
		(end 282.331922 -115.66017)
		(width 0.10668)
		(layer "F.Cu")
		(net "SMB_PCIE0_3V3AUX_SCL_R5")
	)
	(via
		(at 281.188922 -113.62817)
		(size 0.762)
		(drill 0.381)
		(layers "F.Cu" "B.Cu")
		(net "SMB_PCIE0_3V3AUX_SCL_R5")
	)
	(segment
		(start 282.772358 -117.581934)
		(end 281.2542 -116.063776)
		(width 0.10668)
		(layer "F.Cu")
		(net "SMB_PCIE0_3V3AUX_SCL_R3")
	)
	(segment
		(start 284.127956 -117.581934)
		(end 282.772358 -117.581934)
		(width 0.10668)
		(layer "F.Cu")
		(net "SMB_PCIE0_3V3AUX_SCL_R3")
	)
	(segment
		(start 281.2542 -116.063776)
		(end 280.317448 -116.063776)
		(width 0.10668)
		(layer "F.Cu")
		(net "SMB_PCIE0_3V3AUX_SCL_R3")
	)
	(segment
		(start 280.317448 -116.063776)
		(end 279.913842 -115.66017)
		(width 0.10668)
		(layer "F.Cu")
		(net "SMB_PCIE0_3V3AUX_SCL_R3")
	)
	(via
		(at 281.2542 -116.063776)
		(size 0.508)
		(drill 0.254)
		(layers "F.Cu" "B.Cu")
		(net "SMB_PCIE0_3V3AUX_SCL_R3")
	)
	(segment
		(start 290.820856 -121.482104)
		(end 289.728148 -121.482104)
		(width 0.10668)
		(layer "F.Cu")
		(net "SMB_PCIE0_3V3AUX_SCL_R")
	)
	(segment
		(start 292.704266 -123.365514)
		(end 290.820856 -121.482104)
		(width 0.10668)
		(layer "F.Cu")
		(net "SMB_PCIE0_3V3AUX_SCL_R")
	)
	(segment
		(start 294.69207 -123.365514)
		(end 292.704266 -123.365514)
		(width 0.10668)
		(layer "F.Cu")
		(net "SMB_PCIE0_3V3AUX_SCL_R")
	)
	(segment
		(start 295.184576 -123.85802)
		(end 294.69207 -123.365514)
		(width 0.10668)
		(layer "F.Cu")
		(net "SMB_PCIE0_3V3AUX_SCL_R")
	)
	(via
		(at 295.184576 -123.85802)
		(size 0.508)
		(drill 0.254)
		(layers "F.Cu" "B.Cu")
		(net "SMB_PCIE0_3V3AUX_SCL_R")
	)
	(via
		(at 166.145718 -7.391146)
		(size 0.508)
		(drill 0.254)
		(layers "F.Cu" "B.Cu")
		(net "SMB_PCIE0_3V3AUX_SCL_R")
	)
	(segment
		(start 166.145718 -7.391146)
		(end 166.145718 -7.532624)
		(width 0.10668)
		(layer "B.Cu")
		(net "SMB_PCIE0_3V3AUX_SCL_R")
	)
	(segment
		(start 166.145718 -7.532624)
		(end 165.58514 -8.093202)
		(width 0.10668)
		(layer "B.Cu")
		(net "SMB_PCIE0_3V3AUX_SCL_R")
	)
	(segment
		(start 165.58514 -8.093202)
		(end 165.58514 -8.613394)
		(width 0.10668)
		(layer "B.Cu")
		(net "SMB_PCIE0_3V3AUX_SCL_R")
	)
	(segment
		(start 178.17973 -7.41807)
		(end 178.01463 -7.41807)
		(width 0.11684)
		(layer "In4.Cu")
		(net "SMB_PCIE0_3V3AUX_SCL_R")
	)
	(segment
		(start 295.184576 -123.85802)
		(end 294.217852 -122.891296)
		(width 0.11684)
		(layer "In4.Cu")
		(net "SMB_PCIE0_3V3AUX_SCL_R")
	)
	(segment
		(start 177.963068 -8.23468)
		(end 177.963068 -8.06958)
		(width 0.11684)
		(layer "In4.Cu")
		(net "SMB_PCIE0_3V3AUX_SCL_R")
	)
	(segment
		(start 191.072262 -8.662162)
		(end 182.281068 -8.662162)
		(width 0.11684)
		(layer "In4.Cu")
		(net "SMB_PCIE0_3V3AUX_SCL_R")
	)
	(segment
		(start 273.210274 -62.544198)
		(end 266.370308 -62.544198)
		(width 0.11684)
		(layer "In4.Cu")
		(net "SMB_PCIE0_3V3AUX_SCL_R")
	)
	(segment
		(start 286.948372 -122.891296)
		(end 284.91053 -120.853454)
		(width 0.11684)
		(layer "In4.Cu")
		(net "SMB_PCIE0_3V3AUX_SCL_R")
	)
	(segment
		(start 178.914552 -8.152892)
		(end 178.779678 -8.018018)
		(width 0.11684)
		(layer "In4.Cu")
		(net "SMB_PCIE0_3V3AUX_SCL_R")
	)
	(segment
		(start 266.370308 -62.544198)
		(end 264.659618 -64.254888)
		(width 0.11684)
		(layer "In4.Cu")
		(net "SMB_PCIE0_3V3AUX_SCL_R")
	)
	(segment
		(start 178.314604 -7.718044)
		(end 178.314604 -7.552944)
		(width 0.11684)
		(layer "In4.Cu")
		(net "SMB_PCIE0_3V3AUX_SCL_R")
	)
	(segment
		(start 210.10372 -25.731724)
		(end 210.10372 -18.343372)
		(width 0.11684)
		(layer "In4.Cu")
		(net "SMB_PCIE0_3V3AUX_SCL_R")
	)
	(segment
		(start 177.963068 -8.06958)
		(end 178.314604 -7.718044)
		(width 0.11684)
		(layer "In4.Cu")
		(net "SMB_PCIE0_3V3AUX_SCL_R")
	)
	(segment
		(start 177.497994 -7.769606)
		(end 177.115724 -7.387336)
		(width 0.11684)
		(layer "In4.Cu")
		(net "SMB_PCIE0_3V3AUX_SCL_R")
	)
	(segment
		(start 215.03132 -40.304212)
		(end 212.83422 -38.107112)
		(width 0.11684)
		(layer "In4.Cu")
		(net "SMB_PCIE0_3V3AUX_SCL_R")
	)
	(segment
		(start 283.080714 -72.414638)
		(end 273.210274 -62.544198)
		(width 0.11684)
		(layer "In4.Cu")
		(net "SMB_PCIE0_3V3AUX_SCL_R")
	)
	(segment
		(start 178.779678 -8.018018)
		(end 178.614578 -8.018018)
		(width 0.11684)
		(layer "In4.Cu")
		(net "SMB_PCIE0_3V3AUX_SCL_R")
	)
	(segment
		(start 182.281068 -8.662162)
		(end 181.065678 -9.877552)
		(width 0.11684)
		(layer "In4.Cu")
		(net "SMB_PCIE0_3V3AUX_SCL_R")
	)
	(segment
		(start 294.217852 -122.891296)
		(end 286.948372 -122.891296)
		(width 0.11684)
		(layer "In4.Cu")
		(net "SMB_PCIE0_3V3AUX_SCL_R")
	)
	(segment
		(start 207.51038 -30.098492)
		(end 207.51038 -28.325064)
		(width 0.11684)
		(layer "In4.Cu")
		(net "SMB_PCIE0_3V3AUX_SCL_R")
	)
	(segment
		(start 218.876372 -51.048666)
		(end 218.876372 -47.550324)
		(width 0.11684)
		(layer "In4.Cu")
		(net "SMB_PCIE0_3V3AUX_SCL_R")
	)
	(segment
		(start 166.262558 -8.355076)
		(end 166.145718 -8.238236)
		(width 0.11684)
		(layer "In4.Cu")
		(net "SMB_PCIE0_3V3AUX_SCL_R")
	)
	(segment
		(start 284.91053 -120.853454)
		(end 284.91053 -113.208308)
		(width 0.11684)
		(layer "In4.Cu")
		(net "SMB_PCIE0_3V3AUX_SCL_R")
	)
	(segment
		(start 167.638222 -8.042402)
		(end 167.325548 -8.355076)
		(width 0.11684)
		(layer "In4.Cu")
		(net "SMB_PCIE0_3V3AUX_SCL_R")
	)
	(segment
		(start 178.614578 -8.018018)
		(end 178.263042 -8.369554)
		(width 0.11684)
		(layer "In4.Cu")
		(net "SMB_PCIE0_3V3AUX_SCL_R")
	)
	(segment
		(start 193.938906 -10.393426)
		(end 193.717672 -10.172192)
		(width 0.11684)
		(layer "In4.Cu")
		(net "SMB_PCIE0_3V3AUX_SCL_R")
	)
	(segment
		(start 283.080714 -111.378492)
		(end 283.080714 -72.414638)
		(width 0.11684)
		(layer "In4.Cu")
		(net "SMB_PCIE0_3V3AUX_SCL_R")
	)
	(segment
		(start 207.51038 -28.325064)
		(end 210.10372 -25.731724)
		(width 0.11684)
		(layer "In4.Cu")
		(net "SMB_PCIE0_3V3AUX_SCL_R")
	)
	(segment
		(start 167.325548 -8.355076)
		(end 166.262558 -8.355076)
		(width 0.11684)
		(layer "In4.Cu")
		(net "SMB_PCIE0_3V3AUX_SCL_R")
	)
	(segment
		(start 167.900096 -7.387336)
		(end 167.638222 -7.64921)
		(width 0.11684)
		(layer "In4.Cu")
		(net "SMB_PCIE0_3V3AUX_SCL_R")
	)
	(segment
		(start 191.779144 -9.369044)
		(end 191.072262 -8.662162)
		(width 0.11684)
		(layer "In4.Cu")
		(net "SMB_PCIE0_3V3AUX_SCL_R")
	)
	(segment
		(start 177.663094 -7.769606)
		(end 177.497994 -7.769606)
		(width 0.11684)
		(layer "In4.Cu")
		(net "SMB_PCIE0_3V3AUX_SCL_R")
	)
	(segment
		(start 212.83422 -35.422332)
		(end 207.51038 -30.098492)
		(width 0.11684)
		(layer "In4.Cu")
		(net "SMB_PCIE0_3V3AUX_SCL_R")
	)
	(segment
		(start 177.115724 -7.387336)
		(end 167.900096 -7.387336)
		(width 0.11684)
		(layer "In4.Cu")
		(net "SMB_PCIE0_3V3AUX_SCL_R")
	)
	(segment
		(start 178.314604 -7.552944)
		(end 178.17973 -7.41807)
		(width 0.11684)
		(layer "In4.Cu")
		(net "SMB_PCIE0_3V3AUX_SCL_R")
	)
	(segment
		(start 218.876372 -47.550324)
		(end 215.03132 -43.705272)
		(width 0.11684)
		(layer "In4.Cu")
		(net "SMB_PCIE0_3V3AUX_SCL_R")
	)
	(segment
		(start 264.659618 -64.254888)
		(end 232.082594 -64.254888)
		(width 0.11684)
		(layer "In4.Cu")
		(net "SMB_PCIE0_3V3AUX_SCL_R")
	)
	(segment
		(start 167.638222 -7.64921)
		(end 167.638222 -8.042402)
		(width 0.11684)
		(layer "In4.Cu")
		(net "SMB_PCIE0_3V3AUX_SCL_R")
	)
	(segment
		(start 166.145718 -8.238236)
		(end 166.145718 -7.391146)
		(width 0.11684)
		(layer "In4.Cu")
		(net "SMB_PCIE0_3V3AUX_SCL_R")
	)
	(segment
		(start 196.15277 -13.471144)
		(end 194.55003 -11.868404)
		(width 0.11684)
		(layer "In4.Cu")
		(net "SMB_PCIE0_3V3AUX_SCL_R")
	)
	(segment
		(start 215.03132 -43.705272)
		(end 215.03132 -40.304212)
		(width 0.11684)
		(layer "In4.Cu")
		(net "SMB_PCIE0_3V3AUX_SCL_R")
	)
	(segment
		(start 179.60594 -9.877552)
		(end 178.563016 -8.834628)
		(width 0.11684)
		(layer "In4.Cu")
		(net "SMB_PCIE0_3V3AUX_SCL_R")
	)
	(segment
		(start 181.065678 -9.877552)
		(end 179.60594 -9.877552)
		(width 0.11684)
		(layer "In4.Cu")
		(net "SMB_PCIE0_3V3AUX_SCL_R")
	)
	(segment
		(start 178.097942 -8.369554)
		(end 177.963068 -8.23468)
		(width 0.11684)
		(layer "In4.Cu")
		(net "SMB_PCIE0_3V3AUX_SCL_R")
	)
	(segment
		(start 193.717672 -10.172192)
		(end 191.779144 -9.369044)
		(width 0.11684)
		(layer "In4.Cu")
		(net "SMB_PCIE0_3V3AUX_SCL_R")
	)
	(segment
		(start 232.082594 -64.254888)
		(end 218.876372 -51.048666)
		(width 0.11684)
		(layer "In4.Cu")
		(net "SMB_PCIE0_3V3AUX_SCL_R")
	)
	(segment
		(start 210.10372 -18.343372)
		(end 205.231492 -13.471144)
		(width 0.11684)
		(layer "In4.Cu")
		(net "SMB_PCIE0_3V3AUX_SCL_R")
	)
	(segment
		(start 212.83422 -38.107112)
		(end 212.83422 -35.422332)
		(width 0.11684)
		(layer "In4.Cu")
		(net "SMB_PCIE0_3V3AUX_SCL_R")
	)
	(segment
		(start 178.914552 -8.317992)
		(end 178.914552 -8.152892)
		(width 0.11684)
		(layer "In4.Cu")
		(net "SMB_PCIE0_3V3AUX_SCL_R")
	)
	(segment
		(start 178.263042 -8.369554)
		(end 178.097942 -8.369554)
		(width 0.11684)
		(layer "In4.Cu")
		(net "SMB_PCIE0_3V3AUX_SCL_R")
	)
	(segment
		(start 205.231492 -13.471144)
		(end 196.15277 -13.471144)
		(width 0.11684)
		(layer "In4.Cu")
		(net "SMB_PCIE0_3V3AUX_SCL_R")
	)
	(segment
		(start 284.91053 -113.208308)
		(end 283.080714 -111.378492)
		(width 0.11684)
		(layer "In4.Cu")
		(net "SMB_PCIE0_3V3AUX_SCL_R")
	)
	(segment
		(start 178.563016 -8.834628)
		(end 178.563016 -8.669528)
		(width 0.11684)
		(layer "In4.Cu")
		(net "SMB_PCIE0_3V3AUX_SCL_R")
	)
	(segment
		(start 178.563016 -8.669528)
		(end 178.914552 -8.317992)
		(width 0.11684)
		(layer "In4.Cu")
		(net "SMB_PCIE0_3V3AUX_SCL_R")
	)
	(segment
		(start 194.55003 -11.868404)
		(end 193.938906 -10.393426)
		(width 0.11684)
		(layer "In4.Cu")
		(net "SMB_PCIE0_3V3AUX_SCL_R")
	)
	(segment
		(start 178.01463 -7.41807)
		(end 177.663094 -7.769606)
		(width 0.11684)
		(layer "In4.Cu")
		(net "SMB_PCIE0_3V3AUX_SCL_R")
	)
	(segment
		(start 266.975082 -115.631976)
		(end 268.363954 -115.631976)
		(width 0.10668)
		(layer "F.Cu")
		(net "SMB_LM75_3_3V3AUX_SDA_R")
	)
	(segment
		(start 270.558006 -114.08537)
		(end 270.685006 -114.21237)
		(width 0.10668)
		(layer "F.Cu")
		(net "SMB_LM75_3_3V3AUX_SDA_R")
	)
	(segment
		(start 269.91056 -114.08537)
		(end 270.558006 -114.08537)
		(width 0.10668)
		(layer "F.Cu")
		(net "SMB_LM75_3_3V3AUX_SDA_R")
	)
	(segment
		(start 268.363954 -115.631976)
		(end 269.91056 -114.08537)
		(width 0.10668)
		(layer "F.Cu")
		(net "SMB_LM75_3_3V3AUX_SDA_R")
	)
	(via
		(at 269.91056 -114.08537)
		(size 0.508)
		(drill 0.254)
		(layers "F.Cu" "B.Cu")
		(net "SMB_LM75_3_3V3AUX_SDA_R")
	)
	(segment
		(start 270.685006 -115.22837)
		(end 269.691104 -115.22837)
		(width 0.10668)
		(layer "F.Cu")
		(net "SMB_LM75_3_3V3AUX_SCL_R")
	)
	(segment
		(start 269.691104 -115.22837)
		(end 268.548104 -116.37137)
		(width 0.10668)
		(layer "F.Cu")
		(net "SMB_LM75_3_3V3AUX_SCL_R")
	)
	(segment
		(start 268.037056 -116.37137)
		(end 267.947648 -116.281962)
		(width 0.10668)
		(layer "F.Cu")
		(net "SMB_LM75_3_3V3AUX_SCL_R")
	)
	(segment
		(start 268.548104 -116.37137)
		(end 268.037056 -116.37137)
		(width 0.10668)
		(layer "F.Cu")
		(net "SMB_LM75_3_3V3AUX_SCL_R")
	)
	(segment
		(start 267.947648 -116.281962)
		(end 266.975082 -116.281962)
		(width 0.10668)
		(layer "F.Cu")
		(net "SMB_LM75_3_3V3AUX_SCL_R")
	)
	(via
		(at 268.548104 -116.37137)
		(size 0.508)
		(drill 0.254)
		(layers "F.Cu" "B.Cu")
		(net "SMB_LM75_3_3V3AUX_SCL_R")
	)
	(segment
		(start 258.87807 -116.252498)
		(end 258.488942 -115.86337)
		(width 0.10668)
		(layer "F.Cu")
		(net "SMB_LM75_2_3V3AUX_SDA_R")
	)
	(segment
		(start 258.488942 -115.86337)
		(end 257.642106 -115.86337)
		(width 0.10668)
		(layer "F.Cu")
		(net "SMB_LM75_2_3V3AUX_SDA_R")
	)
	(segment
		(start 261.37489 -116.931948)
		(end 259.55752 -116.931948)
		(width 0.10668)
		(layer "F.Cu")
		(net "SMB_LM75_2_3V3AUX_SDA_R")
	)
	(segment
		(start 259.55752 -116.931948)
		(end 258.87807 -116.252498)
		(width 0.10668)
		(layer "F.Cu")
		(net "SMB_LM75_2_3V3AUX_SDA_R")
	)
	(via
		(at 258.87807 -116.252498)
		(size 0.508)
		(drill 0.254)
		(layers "F.Cu" "B.Cu")
		(net "SMB_LM75_2_3V3AUX_SDA_R")
	)
	(segment
		(start 259.403342 -114.84737)
		(end 257.642106 -114.84737)
		(width 0.10668)
		(layer "F.Cu")
		(net "SMB_LM75_2_3V3AUX_SCL_R")
	)
	(segment
		(start 261.37489 -116.281962)
		(end 260.205474 -116.281962)
		(width 0.10668)
		(layer "F.Cu")
		(net "SMB_LM75_2_3V3AUX_SCL_R")
	)
	(segment
		(start 260.205474 -116.281962)
		(end 259.97281 -116.049298)
		(width 0.10668)
		(layer "F.Cu")
		(net "SMB_LM75_2_3V3AUX_SCL_R")
	)
	(segment
		(start 259.97281 -115.416838)
		(end 259.403342 -114.84737)
		(width 0.10668)
		(layer "F.Cu")
		(net "SMB_LM75_2_3V3AUX_SCL_R")
	)
	(segment
		(start 259.97281 -116.049298)
		(end 259.97281 -115.416838)
		(width 0.10668)
		(layer "F.Cu")
		(net "SMB_LM75_2_3V3AUX_SCL_R")
	)
	(via
		(at 259.97281 -115.416838)
		(size 0.508)
		(drill 0.254)
		(layers "F.Cu" "B.Cu")
		(net "SMB_LM75_2_3V3AUX_SCL_R")
	)
	(segment
		(start 257.642106 -117.89537)
		(end 258.37388 -117.89537)
		(width 0.10668)
		(layer "F.Cu")
		(net "SMB_LM75_1_3V3AUX_SDA_R")
	)
	(segment
		(start 258.71043 -118.23192)
		(end 261.37489 -118.23192)
		(width 0.10668)
		(layer "F.Cu")
		(net "SMB_LM75_1_3V3AUX_SDA_R")
	)
	(segment
		(start 258.37388 -117.89537)
		(end 258.71043 -118.23192)
		(width 0.10668)
		(layer "F.Cu")
		(net "SMB_LM75_1_3V3AUX_SDA_R")
	)
	(via
		(at 258.37388 -117.89537)
		(size 0.508)
		(drill 0.254)
		(layers "F.Cu" "B.Cu")
		(net "SMB_LM75_1_3V3AUX_SDA_R")
	)
	(segment
		(start 257.999484 -117.236748)
		(end 258.777486 -117.236748)
		(width 0.10668)
		(layer "F.Cu")
		(net "SMB_LM75_1_3V3AUX_SCL_R")
	)
	(segment
		(start 258.777486 -117.236748)
		(end 259.122672 -117.581934)
		(width 0.10668)
		(layer "F.Cu")
		(net "SMB_LM75_1_3V3AUX_SCL_R")
	)
	(segment
		(start 259.94868 -117.581934)
		(end 261.37489 -117.581934)
		(width 0.10668)
		(layer "F.Cu")
		(net "SMB_LM75_1_3V3AUX_SCL_R")
	)
	(segment
		(start 257.642106 -116.87937)
		(end 257.999484 -117.236748)
		(width 0.10668)
		(layer "F.Cu")
		(net "SMB_LM75_1_3V3AUX_SCL_R")
	)
	(segment
		(start 259.122672 -117.581934)
		(end 259.94868 -117.581934)
		(width 0.10668)
		(layer "F.Cu")
		(net "SMB_LM75_1_3V3AUX_SCL_R")
	)
	(via
		(at 259.94868 -117.581934)
		(size 0.508)
		(drill 0.254)
		(layers "F.Cu" "B.Cu")
		(net "SMB_LM75_1_3V3AUX_SCL_R")
	)
	(segment
		(start 259.03174 -119.532146)
		(end 261.37489 -119.532146)
		(width 0.10668)
		(layer "F.Cu")
		(net "SMB_LM75_0_3V3AUX_SDA_R")
	)
	(segment
		(start 258.4069 -119.92737)
		(end 258.636516 -119.92737)
		(width 0.10668)
		(layer "F.Cu")
		(net "SMB_LM75_0_3V3AUX_SDA_R")
	)
	(segment
		(start 258.636516 -119.92737)
		(end 259.03174 -119.532146)
		(width 0.10668)
		(layer "F.Cu")
		(net "SMB_LM75_0_3V3AUX_SDA_R")
	)
	(segment
		(start 257.642106 -119.92737)
		(end 258.4069 -119.92737)
		(width 0.10668)
		(layer "F.Cu")
		(net "SMB_LM75_0_3V3AUX_SDA_R")
	)
	(via
		(at 258.4069 -119.92737)
		(size 0.508)
		(drill 0.254)
		(layers "F.Cu" "B.Cu")
		(net "SMB_LM75_0_3V3AUX_SDA_R")
	)
	(segment
		(start 259.17652 -118.881906)
		(end 259.147056 -118.91137)
		(width 0.10668)
		(layer "F.Cu")
		(net "SMB_LM75_0_3V3AUX_SCL_R")
	)
	(segment
		(start 259.94868 -118.881906)
		(end 259.17652 -118.881906)
		(width 0.10668)
		(layer "F.Cu")
		(net "SMB_LM75_0_3V3AUX_SCL_R")
	)
	(segment
		(start 261.37489 -118.881906)
		(end 259.94868 -118.881906)
		(width 0.10668)
		(layer "F.Cu")
		(net "SMB_LM75_0_3V3AUX_SCL_R")
	)
	(segment
		(start 259.147056 -118.91137)
		(end 257.642106 -118.91137)
		(width 0.10668)
		(layer "F.Cu")
		(net "SMB_LM75_0_3V3AUX_SCL_R")
	)
	(via
		(at 259.94868 -118.881906)
		(size 0.508)
		(drill 0.254)
		(layers "F.Cu" "B.Cu")
		(net "SMB_LM75_0_3V3AUX_SCL_R")
	)
	(segment
		(start 180.912516 -424.562778)
		(end 181.412134 -424.06316)
		(width 0.10668)
		(layer "F.Cu")
		(net "SMB_IOEXP_3V3AUX_SDA_R1")
	)
	(segment
		(start 178.54168 -424.283632)
		(end 178.820826 -424.562778)
		(width 0.10668)
		(layer "F.Cu")
		(net "SMB_IOEXP_3V3AUX_SDA_R1")
	)
	(segment
		(start 177.797968 -424.283632)
		(end 178.54168 -424.283632)
		(width 0.10668)
		(layer "F.Cu")
		(net "SMB_IOEXP_3V3AUX_SDA_R1")
	)
	(segment
		(start 178.820826 -424.562778)
		(end 180.912516 -424.562778)
		(width 0.10668)
		(layer "F.Cu")
		(net "SMB_IOEXP_3V3AUX_SDA_R1")
	)
	(segment
		(start 181.412134 -424.06316)
		(end 181.412134 -423.254932)
		(width 0.10668)
		(layer "F.Cu")
		(net "SMB_IOEXP_3V3AUX_SDA_R1")
	)
	(via
		(at 178.820826 -424.562778)
		(size 0.762)
		(drill 0.381)
		(layers "F.Cu" "B.Cu")
		(net "SMB_IOEXP_3V3AUX_SDA_R1")
	)
	(segment
		(start 280.807922 -119.85117)
		(end 282.204922 -119.85117)
		(width 0.10668)
		(layer "F.Cu")
		(net "SMB_IOEXP_3V3AUX_SDA_R")
	)
	(segment
		(start 282.204922 -119.85117)
		(end 282.523946 -119.532146)
		(width 0.10668)
		(layer "F.Cu")
		(net "SMB_IOEXP_3V3AUX_SDA_R")
	)
	(segment
		(start 279.913842 -118.70817)
		(end 279.913842 -118.95709)
		(width 0.10668)
		(layer "F.Cu")
		(net "SMB_IOEXP_3V3AUX_SDA_R")
	)
	(segment
		(start 282.523946 -119.532146)
		(end 284.127956 -119.532146)
		(width 0.10668)
		(layer "F.Cu")
		(net "SMB_IOEXP_3V3AUX_SDA_R")
	)
	(segment
		(start 279.913842 -118.95709)
		(end 280.807922 -119.85117)
		(width 0.10668)
		(layer "F.Cu")
		(net "SMB_IOEXP_3V3AUX_SDA_R")
	)
	(via
		(at 282.204922 -119.85117)
		(size 0.762)
		(drill 0.381)
		(layers "F.Cu" "B.Cu")
		(net "SMB_IOEXP_3V3AUX_SDA_R")
	)
	(segment
		(start 278.923242 -118.89867)
		(end 277.752302 -118.89867)
		(width 0.10668)
		(layer "F.Cu")
		(net "SMB_IOEXP_3V3AUX_SDA")
	)
	(segment
		(start 45.272452 -414.703768)
		(end 43.278806 -416.697414)
		(width 0.10668)
		(layer "F.Cu")
		(net "SMB_IOEXP_3V3AUX_SDA")
	)
	(segment
		(start 277.023068 -118.169436)
		(end 277.752302 -118.89867)
		(width 0.10668)
		(layer "F.Cu")
		(net "SMB_IOEXP_3V3AUX_SDA")
	)
	(segment
		(start 53.721 -415.714942)
		(end 52.709826 -414.703768)
		(width 0.10668)
		(layer "F.Cu")
		(net "SMB_IOEXP_3V3AUX_SDA")
	)
	(segment
		(start 275.806154 -118.358412)
		(end 275.99513 -118.169436)
		(width 0.10668)
		(layer "F.Cu")
		(net "SMB_IOEXP_3V3AUX_SDA")
	)
	(segment
		(start 94.303596 -426.072046)
		(end 83.946492 -415.714942)
		(width 0.10668)
		(layer "F.Cu")
		(net "SMB_IOEXP_3V3AUX_SDA")
	)
	(segment
		(start 40.493442 -416.697414)
		(end 35.724592 -411.928564)
		(width 0.10668)
		(layer "F.Cu")
		(net "SMB_IOEXP_3V3AUX_SDA")
	)
	(segment
		(start 176.997868 -424.283632)
		(end 176.347374 -424.283632)
		(width 0.10668)
		(layer "F.Cu")
		(net "SMB_IOEXP_3V3AUX_SDA")
	)
	(segment
		(start 52.709826 -414.703768)
		(end 45.272452 -414.703768)
		(width 0.10668)
		(layer "F.Cu")
		(net "SMB_IOEXP_3V3AUX_SDA")
	)
	(segment
		(start 275.99513 -118.169436)
		(end 277.023068 -118.169436)
		(width 0.10668)
		(layer "F.Cu")
		(net "SMB_IOEXP_3V3AUX_SDA")
	)
	(segment
		(start 35.724592 -411.928564)
		(end 29.88437 -411.928564)
		(width 0.10668)
		(layer "F.Cu")
		(net "SMB_IOEXP_3V3AUX_SDA")
	)
	(segment
		(start 43.278806 -416.697414)
		(end 40.493442 -416.697414)
		(width 0.10668)
		(layer "F.Cu")
		(net "SMB_IOEXP_3V3AUX_SDA")
	)
	(segment
		(start 176.347374 -424.283632)
		(end 176.176432 -424.454574)
		(width 0.10668)
		(layer "F.Cu")
		(net "SMB_IOEXP_3V3AUX_SDA")
	)
	(segment
		(start 279.113742 -118.70817)
		(end 278.923242 -118.89867)
		(width 0.10668)
		(layer "F.Cu")
		(net "SMB_IOEXP_3V3AUX_SDA")
	)
	(segment
		(start 83.946492 -415.714942)
		(end 53.721 -415.714942)
		(width 0.10668)
		(layer "F.Cu")
		(net "SMB_IOEXP_3V3AUX_SDA")
	)
	(segment
		(start 94.58833 -426.072046)
		(end 94.303596 -426.072046)
		(width 0.10668)
		(layer "F.Cu")
		(net "SMB_IOEXP_3V3AUX_SDA")
	)
	(via
		(at 176.176432 -424.454574)
		(size 0.508)
		(drill 0.254)
		(layers "F.Cu" "B.Cu")
		(net "SMB_IOEXP_3V3AUX_SDA")
	)
	(via
		(at 29.88437 -411.928564)
		(size 0.508)
		(drill 0.254)
		(layers "F.Cu" "B.Cu")
		(net "SMB_IOEXP_3V3AUX_SDA")
	)
	(via
		(at 94.58833 -426.072046)
		(size 0.508)
		(drill 0.254)
		(layers "F.Cu" "B.Cu")
		(net "SMB_IOEXP_3V3AUX_SDA")
	)
	(via
		(at 275.806154 -118.358412)
		(size 0.508)
		(drill 0.254)
		(layers "F.Cu" "B.Cu")
		(net "SMB_IOEXP_3V3AUX_SDA")
	)
	(via
		(at 67.647058 -132.703824)
		(size 0.508)
		(drill 0.254)
		(layers "F.Cu" "B.Cu")
		(net "SMB_IOEXP_3V3AUX_SDA")
	)
	(segment
		(start 267.948664 -99.851972)
		(end 273.460464 -99.851972)
		(width 0.11684)
		(layer "In2.Cu")
		(net "SMB_IOEXP_3V3AUX_SDA")
	)
	(segment
		(start 120.653556 -423.619168)
		(end 117.083078 -423.619168)
		(width 0.11684)
		(layer "In2.Cu")
		(net "SMB_IOEXP_3V3AUX_SDA")
	)
	(segment
		(start 175.935386 -87.462106)
		(end 176.37252 -87.462106)
		(width 0.11684)
		(layer "In2.Cu")
		(net "SMB_IOEXP_3V3AUX_SDA")
	)
	(segment
		(start 67.647058 -132.703824)
		(end 70.40245 -129.948432)
		(width 0.11684)
		(layer "In2.Cu")
		(net "SMB_IOEXP_3V3AUX_SDA")
	)
	(segment
		(start 176.176432 -423.842942)
		(end 175.199294 -422.865804)
		(width 0.11684)
		(layer "In2.Cu")
		(net "SMB_IOEXP_3V3AUX_SDA")
	)
	(segment
		(start 176.644554 -87.985854)
		(end 176.946814 -88.288114)
		(width 0.11684)
		(layer "In2.Cu")
		(net "SMB_IOEXP_3V3AUX_SDA")
	)
	(segment
		(start 176.644554 -87.73414)
		(end 176.644554 -87.985854)
		(width 0.11684)
		(layer "In2.Cu")
		(net "SMB_IOEXP_3V3AUX_SDA")
	)
	(segment
		(start 276.219412 -118.358412)
		(end 275.806154 -118.358412)
		(width 0.11684)
		(layer "In2.Cu")
		(net "SMB_IOEXP_3V3AUX_SDA")
	)
	(segment
		(start 117.083078 -423.619168)
		(end 114.846354 -421.382444)
		(width 0.11684)
		(layer "In2.Cu")
		(net "SMB_IOEXP_3V3AUX_SDA")
	)
	(segment
		(start 120.932702 -423.898314)
		(end 120.653556 -423.619168)
		(width 0.11684)
		(layer "In2.Cu")
		(net "SMB_IOEXP_3V3AUX_SDA")
	)
	(segment
		(start 197.188836 -88.938862)
		(end 211.241386 -88.938862)
		(width 0.11684)
		(layer "In2.Cu")
		(net "SMB_IOEXP_3V3AUX_SDA")
	)
	(segment
		(start 73.672446 -129.948432)
		(end 116.259864 -87.361014)
		(width 0.11684)
		(layer "In2.Cu")
		(net "SMB_IOEXP_3V3AUX_SDA")
	)
	(segment
		(start 215.228678 -92.926154)
		(end 243.357908 -92.926154)
		(width 0.11684)
		(layer "In2.Cu")
		(net "SMB_IOEXP_3V3AUX_SDA")
	)
	(segment
		(start 277.550372 -110.4265)
		(end 277.550372 -117.027452)
		(width 0.11684)
		(layer "In2.Cu")
		(net "SMB_IOEXP_3V3AUX_SDA")
	)
	(segment
		(start 160.705038 -419.967664)
		(end 160.223962 -419.486588)
		(width 0.11684)
		(layer "In2.Cu")
		(net "SMB_IOEXP_3V3AUX_SDA")
	)
	(segment
		(start 175.199294 -422.865804)
		(end 168.443148 -422.865804)
		(width 0.11684)
		(layer "In2.Cu")
		(net "SMB_IOEXP_3V3AUX_SDA")
	)
	(segment
		(start 243.357908 -92.926154)
		(end 248.645426 -87.638636)
		(width 0.11684)
		(layer "In2.Cu")
		(net "SMB_IOEXP_3V3AUX_SDA")
	)
	(segment
		(start 167.45331 -421.875966)
		(end 162.102292 -421.875966)
		(width 0.11684)
		(layer "In2.Cu")
		(net "SMB_IOEXP_3V3AUX_SDA")
	)
	(segment
		(start 273.460464 -99.851972)
		(end 274.38731 -100.235766)
		(width 0.11684)
		(layer "In2.Cu")
		(net "SMB_IOEXP_3V3AUX_SDA")
	)
	(segment
		(start 114.846354 -421.382444)
		(end 109.64545 -421.382444)
		(width 0.11684)
		(layer "In2.Cu")
		(net "SMB_IOEXP_3V3AUX_SDA")
	)
	(segment
		(start 158.063692 -88.4809)
		(end 171.083986 -88.4809)
		(width 0.11684)
		(layer "In2.Cu")
		(net "SMB_IOEXP_3V3AUX_SDA")
	)
	(segment
		(start 175.094646 -88.302846)
		(end 175.935386 -87.462106)
		(width 0.11684)
		(layer "In2.Cu")
		(net "SMB_IOEXP_3V3AUX_SDA")
	)
	(segment
		(start 156.943806 -87.361014)
		(end 158.063692 -88.4809)
		(width 0.11684)
		(layer "In2.Cu")
		(net "SMB_IOEXP_3V3AUX_SDA")
	)
	(segment
		(start 178.74742 -88.532208)
		(end 196.782182 -88.532208)
		(width 0.11684)
		(layer "In2.Cu")
		(net "SMB_IOEXP_3V3AUX_SDA")
	)
	(segment
		(start 162.102292 -421.875966)
		(end 160.705038 -420.478712)
		(width 0.11684)
		(layer "In2.Cu")
		(net "SMB_IOEXP_3V3AUX_SDA")
	)
	(segment
		(start 171.083986 -88.4809)
		(end 171.26204 -88.302846)
		(width 0.11684)
		(layer "In2.Cu")
		(net "SMB_IOEXP_3V3AUX_SDA")
	)
	(segment
		(start 168.443148 -422.865804)
		(end 167.45331 -421.875966)
		(width 0.11684)
		(layer "In2.Cu")
		(net "SMB_IOEXP_3V3AUX_SDA")
	)
	(segment
		(start 70.40245 -129.948432)
		(end 73.672446 -129.948432)
		(width 0.11684)
		(layer "In2.Cu")
		(net "SMB_IOEXP_3V3AUX_SDA")
	)
	(segment
		(start 108.495084 -425.92498)
		(end 106.253026 -428.167038)
		(width 0.11684)
		(layer "In2.Cu")
		(net "SMB_IOEXP_3V3AUX_SDA")
	)
	(segment
		(start 276.258274 -109.134402)
		(end 277.550372 -110.4265)
		(width 0.11684)
		(layer "In2.Cu")
		(net "SMB_IOEXP_3V3AUX_SDA")
	)
	(segment
		(start 160.223962 -419.486588)
		(end 126.590044 -419.486588)
		(width 0.11684)
		(layer "In2.Cu")
		(net "SMB_IOEXP_3V3AUX_SDA")
	)
	(segment
		(start 211.241386 -88.938862)
		(end 215.228678 -92.926154)
		(width 0.11684)
		(layer "In2.Cu")
		(net "SMB_IOEXP_3V3AUX_SDA")
	)
	(segment
		(start 160.705038 -420.478712)
		(end 160.705038 -419.967664)
		(width 0.11684)
		(layer "In2.Cu")
		(net "SMB_IOEXP_3V3AUX_SDA")
	)
	(segment
		(start 276.258274 -102.10673)
		(end 276.258274 -109.134402)
		(width 0.11684)
		(layer "In2.Cu")
		(net "SMB_IOEXP_3V3AUX_SDA")
	)
	(segment
		(start 248.645426 -87.638636)
		(end 255.735328 -87.638636)
		(width 0.11684)
		(layer "In2.Cu")
		(net "SMB_IOEXP_3V3AUX_SDA")
	)
	(segment
		(start 122.178318 -423.898314)
		(end 120.932702 -423.898314)
		(width 0.11684)
		(layer "In2.Cu")
		(net "SMB_IOEXP_3V3AUX_SDA")
	)
	(segment
		(start 277.550372 -117.027452)
		(end 276.219412 -118.358412)
		(width 0.11684)
		(layer "In2.Cu")
		(net "SMB_IOEXP_3V3AUX_SDA")
	)
	(segment
		(start 178.503326 -88.288114)
		(end 178.74742 -88.532208)
		(width 0.11684)
		(layer "In2.Cu")
		(net "SMB_IOEXP_3V3AUX_SDA")
	)
	(segment
		(start 274.38731 -100.235766)
		(end 276.258274 -102.10673)
		(width 0.11684)
		(layer "In2.Cu")
		(net "SMB_IOEXP_3V3AUX_SDA")
	)
	(segment
		(start 109.64545 -421.382444)
		(end 108.495084 -422.53281)
		(width 0.11684)
		(layer "In2.Cu")
		(net "SMB_IOEXP_3V3AUX_SDA")
	)
	(segment
		(start 255.735328 -87.638636)
		(end 267.948664 -99.851972)
		(width 0.11684)
		(layer "In2.Cu")
		(net "SMB_IOEXP_3V3AUX_SDA")
	)
	(segment
		(start 196.782182 -88.532208)
		(end 197.188836 -88.938862)
		(width 0.11684)
		(layer "In2.Cu")
		(net "SMB_IOEXP_3V3AUX_SDA")
	)
	(segment
		(start 108.495084 -422.53281)
		(end 108.495084 -425.92498)
		(width 0.11684)
		(layer "In2.Cu")
		(net "SMB_IOEXP_3V3AUX_SDA")
	)
	(segment
		(start 171.26204 -88.302846)
		(end 175.094646 -88.302846)
		(width 0.11684)
		(layer "In2.Cu")
		(net "SMB_IOEXP_3V3AUX_SDA")
	)
	(segment
		(start 96.683322 -428.167038)
		(end 94.58833 -426.072046)
		(width 0.11684)
		(layer "In2.Cu")
		(net "SMB_IOEXP_3V3AUX_SDA")
	)
	(segment
		(start 176.37252 -87.462106)
		(end 176.644554 -87.73414)
		(width 0.11684)
		(layer "In2.Cu")
		(net "SMB_IOEXP_3V3AUX_SDA")
	)
	(segment
		(start 176.946814 -88.288114)
		(end 178.503326 -88.288114)
		(width 0.11684)
		(layer "In2.Cu")
		(net "SMB_IOEXP_3V3AUX_SDA")
	)
	(segment
		(start 126.590044 -419.486588)
		(end 122.178318 -423.898314)
		(width 0.11684)
		(layer "In2.Cu")
		(net "SMB_IOEXP_3V3AUX_SDA")
	)
	(segment
		(start 176.176432 -424.454574)
		(end 176.176432 -423.842942)
		(width 0.11684)
		(layer "In2.Cu")
		(net "SMB_IOEXP_3V3AUX_SDA")
	)
	(segment
		(start 116.259864 -87.361014)
		(end 156.943806 -87.361014)
		(width 0.11684)
		(layer "In2.Cu")
		(net "SMB_IOEXP_3V3AUX_SDA")
	)
	(segment
		(start 106.253026 -428.167038)
		(end 96.683322 -428.167038)
		(width 0.11684)
		(layer "In2.Cu")
		(net "SMB_IOEXP_3V3AUX_SDA")
	)
	(segment
		(start 29.626306 -413.111188)
		(end 29.88437 -412.853124)
		(width 0.11684)
		(layer "In4.Cu")
		(net "SMB_IOEXP_3V3AUX_SDA")
	)
	(segment
		(start 3.776472 -330.889356)
		(end 3.519424 -331.146404)
		(width 0.11684)
		(layer "In4.Cu")
		(net "SMB_IOEXP_3V3AUX_SDA")
	)
	(segment
		(start 67.647058 -132.703824)
		(end 64.682624 -135.668258)
		(width 0.11684)
		(layer "In4.Cu")
		(net "SMB_IOEXP_3V3AUX_SDA")
	)
	(segment
		(start 8.416036 -407.573988)
		(end 8.416036 -415.241994)
		(width 0.11684)
		(layer "In4.Cu")
		(net "SMB_IOEXP_3V3AUX_SDA")
	)
	(segment
		(start 10.28065 -392.393424)
		(end 3.915156 -398.758918)
		(width 0.11684)
		(layer "In4.Cu")
		(net "SMB_IOEXP_3V3AUX_SDA")
	)
	(segment
		(start 18.060162 -415.87928)
		(end 18.928842 -415.0106)
		(width 0.11684)
		(layer "In4.Cu")
		(net "SMB_IOEXP_3V3AUX_SDA")
	)
	(segment
		(start 10.399268 -417.225226)
		(end 11.235436 -417.225226)
		(width 0.11684)
		(layer "In4.Cu")
		(net "SMB_IOEXP_3V3AUX_SDA")
	)
	(segment
		(start 11.235436 -417.225226)
		(end 12.581382 -415.87928)
		(width 0.11684)
		(layer "In4.Cu")
		(net "SMB_IOEXP_3V3AUX_SDA")
	)
	(segment
		(start 3.519424 -350.237552)
		(end 3.858514 -350.576642)
		(width 0.11684)
		(layer "In4.Cu")
		(net "SMB_IOEXP_3V3AUX_SDA")
	)
	(segment
		(start 3.915156 -403.073108)
		(end 8.416036 -407.573988)
		(width 0.11684)
		(layer "In4.Cu")
		(net "SMB_IOEXP_3V3AUX_SDA")
	)
	(segment
		(start 64.682624 -135.668258)
		(end 25.454864 -135.668258)
		(width 0.11684)
		(layer "In4.Cu")
		(net "SMB_IOEXP_3V3AUX_SDA")
	)
	(segment
		(start 23.818342 -413.111188)
		(end 29.626306 -413.111188)
		(width 0.11684)
		(layer "In4.Cu")
		(net "SMB_IOEXP_3V3AUX_SDA")
	)
	(segment
		(start 18.928842 -415.0106)
		(end 21.91893 -415.0106)
		(width 0.11684)
		(layer "In4.Cu")
		(net "SMB_IOEXP_3V3AUX_SDA")
	)
	(segment
		(start 3.776472 -157.34665)
		(end 3.776472 -330.889356)
		(width 0.11684)
		(layer "In4.Cu")
		(net "SMB_IOEXP_3V3AUX_SDA")
	)
	(segment
		(start 21.91893 -415.0106)
		(end 23.818342 -413.111188)
		(width 0.11684)
		(layer "In4.Cu")
		(net "SMB_IOEXP_3V3AUX_SDA")
	)
	(segment
		(start 10.28065 -388.65048)
		(end 10.28065 -392.393424)
		(width 0.11684)
		(layer "In4.Cu")
		(net "SMB_IOEXP_3V3AUX_SDA")
	)
	(segment
		(start 3.858514 -350.576642)
		(end 3.858514 -382.228344)
		(width 0.11684)
		(layer "In4.Cu")
		(net "SMB_IOEXP_3V3AUX_SDA")
	)
	(segment
		(start 8.416036 -415.241994)
		(end 10.399268 -417.225226)
		(width 0.11684)
		(layer "In4.Cu")
		(net "SMB_IOEXP_3V3AUX_SDA")
	)
	(segment
		(start 3.858514 -382.228344)
		(end 10.28065 -388.65048)
		(width 0.11684)
		(layer "In4.Cu")
		(net "SMB_IOEXP_3V3AUX_SDA")
	)
	(segment
		(start 25.454864 -135.668258)
		(end 3.776472 -157.34665)
		(width 0.11684)
		(layer "In4.Cu")
		(net "SMB_IOEXP_3V3AUX_SDA")
	)
	(segment
		(start 3.519424 -331.146404)
		(end 3.519424 -350.237552)
		(width 0.11684)
		(layer "In4.Cu")
		(net "SMB_IOEXP_3V3AUX_SDA")
	)
	(segment
		(start 12.581382 -415.87928)
		(end 18.060162 -415.87928)
		(width 0.11684)
		(layer "In4.Cu")
		(net "SMB_IOEXP_3V3AUX_SDA")
	)
	(segment
		(start 29.88437 -412.853124)
		(end 29.88437 -411.928564)
		(width 0.11684)
		(layer "In4.Cu")
		(net "SMB_IOEXP_3V3AUX_SDA")
	)
	(segment
		(start 3.915156 -398.758918)
		(end 3.915156 -403.073108)
		(width 0.11684)
		(layer "In4.Cu")
		(net "SMB_IOEXP_3V3AUX_SDA")
	)
	(segment
		(start 180.2892 -425.234608)
		(end 180.218842 -425.304966)
		(width 0.10668)
		(layer "F.Cu")
		(net "SMB_IOEXP_3V3AUX_SCL_R1")
	)
	(segment
		(start 180.218842 -425.304966)
		(end 177.80762 -425.304966)
		(width 0.10668)
		(layer "F.Cu")
		(net "SMB_IOEXP_3V3AUX_SCL_R1")
	)
	(segment
		(start 182.06212 -424.031156)
		(end 180.858668 -425.234608)
		(width 0.10668)
		(layer "F.Cu")
		(net "SMB_IOEXP_3V3AUX_SCL_R1")
	)
	(segment
		(start 182.06212 -423.254932)
		(end 182.06212 -424.031156)
		(width 0.10668)
		(layer "F.Cu")
		(net "SMB_IOEXP_3V3AUX_SCL_R1")
	)
	(segment
		(start 180.858668 -425.234608)
		(end 180.2892 -425.234608)
		(width 0.10668)
		(layer "F.Cu")
		(net "SMB_IOEXP_3V3AUX_SCL_R1")
	)
	(via
		(at 180.218842 -425.304966)
		(size 0.762)
		(drill 0.381)
		(layers "F.Cu" "B.Cu")
		(net "SMB_IOEXP_3V3AUX_SCL_R1")
	)
	(segment
		(start 279.913842 -117.94109)
		(end 280.854658 -118.881906)
		(width 0.10668)
		(layer "F.Cu")
		(net "SMB_IOEXP_3V3AUX_SCL_R")
	)
	(segment
		(start 279.913842 -117.69217)
		(end 279.913842 -117.94109)
		(width 0.10668)
		(layer "F.Cu")
		(net "SMB_IOEXP_3V3AUX_SCL_R")
	)
	(segment
		(start 281.188922 -118.881906)
		(end 284.127956 -118.881906)
		(width 0.10668)
		(layer "F.Cu")
		(net "SMB_IOEXP_3V3AUX_SCL_R")
	)
	(segment
		(start 280.854658 -118.881906)
		(end 281.188922 -118.881906)
		(width 0.10668)
		(layer "F.Cu")
		(net "SMB_IOEXP_3V3AUX_SCL_R")
	)
	(via
		(at 281.188922 -118.881906)
		(size 0.762)
		(drill 0.381)
		(layers "F.Cu" "B.Cu")
		(net "SMB_IOEXP_3V3AUX_SCL_R")
	)
	(segment
		(start 83.805268 -416.055302)
		(end 53.579776 -416.055302)
		(width 0.10668)
		(layer "F.Cu")
		(net "SMB_IOEXP_3V3AUX_SCL")
	)
	(segment
		(start 45.413676 -415.044128)
		(end 43.42003 -417.037774)
		(width 0.10668)
		(layer "F.Cu")
		(net "SMB_IOEXP_3V3AUX_SCL")
	)
	(segment
		(start 35.947858 -412.633414)
		(end 29.112972 -412.633414)
		(width 0.10668)
		(layer "F.Cu")
		(net "SMB_IOEXP_3V3AUX_SCL")
	)
	(segment
		(start 176.268126 -425.304966)
		(end 176.14392 -425.18076)
		(width 0.10668)
		(layer "F.Cu")
		(net "SMB_IOEXP_3V3AUX_SCL")
	)
	(segment
		(start 53.579776 -416.055302)
		(end 52.568602 -415.044128)
		(width 0.10668)
		(layer "F.Cu")
		(net "SMB_IOEXP_3V3AUX_SCL")
	)
	(segment
		(start 177.00752 -425.304966)
		(end 176.268126 -425.304966)
		(width 0.10668)
		(layer "F.Cu")
		(net "SMB_IOEXP_3V3AUX_SCL")
	)
	(segment
		(start 52.568602 -415.044128)
		(end 45.413676 -415.044128)
		(width 0.10668)
		(layer "F.Cu")
		(net "SMB_IOEXP_3V3AUX_SCL")
	)
	(segment
		(start 275.54936 -116.84127)
		(end 277.091902 -116.84127)
		(width 0.10668)
		(layer "F.Cu")
		(net "SMB_IOEXP_3V3AUX_SCL")
	)
	(segment
		(start 40.352218 -417.037774)
		(end 35.947858 -412.633414)
		(width 0.10668)
		(layer "F.Cu")
		(net "SMB_IOEXP_3V3AUX_SCL")
	)
	(segment
		(start 277.942802 -117.69217)
		(end 277.752302 -117.50167)
		(width 0.10668)
		(layer "F.Cu")
		(net "SMB_IOEXP_3V3AUX_SCL")
	)
	(segment
		(start 43.42003 -417.037774)
		(end 40.352218 -417.037774)
		(width 0.10668)
		(layer "F.Cu")
		(net "SMB_IOEXP_3V3AUX_SCL")
	)
	(segment
		(start 94.602046 -426.85208)
		(end 83.805268 -416.055302)
		(width 0.10668)
		(layer "F.Cu")
		(net "SMB_IOEXP_3V3AUX_SCL")
	)
	(segment
		(start 279.113742 -117.69217)
		(end 277.942802 -117.69217)
		(width 0.10668)
		(layer "F.Cu")
		(net "SMB_IOEXP_3V3AUX_SCL")
	)
	(segment
		(start 277.091902 -116.84127)
		(end 277.752302 -117.50167)
		(width 0.10668)
		(layer "F.Cu")
		(net "SMB_IOEXP_3V3AUX_SCL")
	)
	(via
		(at 275.54936 -116.84127)
		(size 0.508)
		(drill 0.254)
		(layers "F.Cu" "B.Cu")
		(net "SMB_IOEXP_3V3AUX_SCL")
	)
	(via
		(at 68.470272 -132.680964)
		(size 0.508)
		(drill 0.254)
		(layers "F.Cu" "B.Cu")
		(net "SMB_IOEXP_3V3AUX_SCL")
	)
	(via
		(at 29.112972 -412.633414)
		(size 0.508)
		(drill 0.254)
		(layers "F.Cu" "B.Cu")
		(net "SMB_IOEXP_3V3AUX_SCL")
	)
	(via
		(at 94.602046 -426.85208)
		(size 0.508)
		(drill 0.254)
		(layers "F.Cu" "B.Cu")
		(net "SMB_IOEXP_3V3AUX_SCL")
	)
	(via
		(at 176.14392 -425.18076)
		(size 0.508)
		(drill 0.254)
		(layers "F.Cu" "B.Cu")
		(net "SMB_IOEXP_3V3AUX_SCL")
	)
	(segment
		(start 163.553394 -422.341802)
		(end 161.903918 -422.341802)
		(width 0.11684)
		(layer "In2.Cu")
		(net "SMB_IOEXP_3V3AUX_SCL")
	)
	(segment
		(start 157.7975 -88.953848)
		(end 171.20743 -88.953848)
		(width 0.11684)
		(layer "In2.Cu")
		(net "SMB_IOEXP_3V3AUX_SCL")
	)
	(segment
		(start 275.815552 -109.288072)
		(end 277.128732 -110.601252)
		(width 0.11684)
		(layer "In2.Cu")
		(net "SMB_IOEXP_3V3AUX_SCL")
	)
	(segment
		(start 274.13966 -100.589588)
		(end 275.815552 -102.26548)
		(width 0.11684)
		(layer "In2.Cu")
		(net "SMB_IOEXP_3V3AUX_SCL")
	)
	(segment
		(start 175.200818 -424.237658)
		(end 175.200818 -424.042586)
		(width 0.11684)
		(layer "In2.Cu")
		(net "SMB_IOEXP_3V3AUX_SCL")
	)
	(segment
		(start 114.65179 -421.85209)
		(end 109.840014 -421.85209)
		(width 0.11684)
		(layer "In2.Cu")
		(net "SMB_IOEXP_3V3AUX_SCL")
	)
	(segment
		(start 73.651364 -130.565906)
		(end 116.434616 -87.782654)
		(width 0.11684)
		(layer "In2.Cu")
		(net "SMB_IOEXP_3V3AUX_SCL")
	)
	(segment
		(start 273.409664 -100.287328)
		(end 274.13966 -100.589588)
		(width 0.11684)
		(layer "In2.Cu")
		(net "SMB_IOEXP_3V3AUX_SCL")
	)
	(segment
		(start 108.96473 -426.119544)
		(end 106.44759 -428.636684)
		(width 0.11684)
		(layer "In2.Cu")
		(net "SMB_IOEXP_3V3AUX_SCL")
	)
	(segment
		(start 255.477264 -88.060276)
		(end 267.704316 -100.287328)
		(width 0.11684)
		(layer "In2.Cu")
		(net "SMB_IOEXP_3V3AUX_SCL")
	)
	(segment
		(start 156.626306 -87.782654)
		(end 157.7975 -88.953848)
		(width 0.11684)
		(layer "In2.Cu")
		(net "SMB_IOEXP_3V3AUX_SCL")
	)
	(segment
		(start 122.143012 -424.713146)
		(end 117.512846 -424.713146)
		(width 0.11684)
		(layer "In2.Cu")
		(net "SMB_IOEXP_3V3AUX_SCL")
	)
	(segment
		(start 175.200818 -424.042586)
		(end 174.548546 -423.390314)
		(width 0.11684)
		(layer "In2.Cu")
		(net "SMB_IOEXP_3V3AUX_SCL")
	)
	(segment
		(start 117.512846 -424.713146)
		(end 114.65179 -421.85209)
		(width 0.11684)
		(layer "In2.Cu")
		(net "SMB_IOEXP_3V3AUX_SCL")
	)
	(segment
		(start 108.96473 -422.727374)
		(end 108.96473 -426.119544)
		(width 0.11684)
		(layer "In2.Cu")
		(net "SMB_IOEXP_3V3AUX_SCL")
	)
	(segment
		(start 160.37687 -420.814754)
		(end 126.041404 -420.814754)
		(width 0.11684)
		(layer "In2.Cu")
		(net "SMB_IOEXP_3V3AUX_SCL")
	)
	(segment
		(start 214.999062 -93.347794)
		(end 243.576348 -93.347794)
		(width 0.11684)
		(layer "In2.Cu")
		(net "SMB_IOEXP_3V3AUX_SCL")
	)
	(segment
		(start 109.840014 -421.85209)
		(end 108.96473 -422.727374)
		(width 0.11684)
		(layer "In2.Cu")
		(net "SMB_IOEXP_3V3AUX_SCL")
	)
	(segment
		(start 267.704316 -100.287328)
		(end 273.409664 -100.287328)
		(width 0.11684)
		(layer "In2.Cu")
		(net "SMB_IOEXP_3V3AUX_SCL")
	)
	(segment
		(start 277.128732 -110.601252)
		(end 277.128732 -116.155216)
		(width 0.11684)
		(layer "In2.Cu")
		(net "SMB_IOEXP_3V3AUX_SCL")
	)
	(segment
		(start 178.572668 -88.953848)
		(end 196.587872 -88.953848)
		(width 0.11684)
		(layer "In2.Cu")
		(net "SMB_IOEXP_3V3AUX_SCL")
	)
	(segment
		(start 175.28413 -88.709754)
		(end 178.328574 -88.709754)
		(width 0.11684)
		(layer "In2.Cu")
		(net "SMB_IOEXP_3V3AUX_SCL")
	)
	(segment
		(start 275.815552 -102.26548)
		(end 275.815552 -109.288072)
		(width 0.11684)
		(layer "In2.Cu")
		(net "SMB_IOEXP_3V3AUX_SCL")
	)
	(segment
		(start 276.442678 -116.84127)
		(end 275.54936 -116.84127)
		(width 0.11684)
		(layer "In2.Cu")
		(net "SMB_IOEXP_3V3AUX_SCL")
	)
	(segment
		(start 174.548546 -423.390314)
		(end 166.149274 -423.390314)
		(width 0.11684)
		(layer "In2.Cu")
		(net "SMB_IOEXP_3V3AUX_SCL")
	)
	(segment
		(start 277.128732 -116.155216)
		(end 276.442678 -116.84127)
		(width 0.11684)
		(layer "In2.Cu")
		(net "SMB_IOEXP_3V3AUX_SCL")
	)
	(segment
		(start 96.38665 -428.636684)
		(end 94.602046 -426.85208)
		(width 0.11684)
		(layer "In2.Cu")
		(net "SMB_IOEXP_3V3AUX_SCL")
	)
	(segment
		(start 175.040036 -88.953848)
		(end 175.28413 -88.709754)
		(width 0.11684)
		(layer "In2.Cu")
		(net "SMB_IOEXP_3V3AUX_SCL")
	)
	(segment
		(start 174.424086 -88.72474)
		(end 174.653194 -88.953848)
		(width 0.11684)
		(layer "In2.Cu")
		(net "SMB_IOEXP_3V3AUX_SCL")
	)
	(segment
		(start 171.436538 -88.72474)
		(end 174.424086 -88.72474)
		(width 0.11684)
		(layer "In2.Cu")
		(net "SMB_IOEXP_3V3AUX_SCL")
	)
	(segment
		(start 174.653194 -88.953848)
		(end 175.040036 -88.953848)
		(width 0.11684)
		(layer "In2.Cu")
		(net "SMB_IOEXP_3V3AUX_SCL")
	)
	(segment
		(start 176.14392 -425.18076)
		(end 175.200818 -424.237658)
		(width 0.11684)
		(layer "In2.Cu")
		(net "SMB_IOEXP_3V3AUX_SCL")
	)
	(segment
		(start 196.994526 -89.360502)
		(end 211.01177 -89.360502)
		(width 0.11684)
		(layer "In2.Cu")
		(net "SMB_IOEXP_3V3AUX_SCL")
	)
	(segment
		(start 211.01177 -89.360502)
		(end 214.999062 -93.347794)
		(width 0.11684)
		(layer "In2.Cu")
		(net "SMB_IOEXP_3V3AUX_SCL")
	)
	(segment
		(start 243.576348 -93.347794)
		(end 248.863866 -88.060276)
		(width 0.11684)
		(layer "In2.Cu")
		(net "SMB_IOEXP_3V3AUX_SCL")
	)
	(segment
		(start 161.903918 -422.341802)
		(end 160.37687 -420.814754)
		(width 0.11684)
		(layer "In2.Cu")
		(net "SMB_IOEXP_3V3AUX_SCL")
	)
	(segment
		(start 68.470272 -132.680964)
		(end 70.58533 -130.565906)
		(width 0.11684)
		(layer "In2.Cu")
		(net "SMB_IOEXP_3V3AUX_SCL")
	)
	(segment
		(start 166.149274 -423.390314)
		(end 165.641782 -422.882822)
		(width 0.11684)
		(layer "In2.Cu")
		(net "SMB_IOEXP_3V3AUX_SCL")
	)
	(segment
		(start 178.328574 -88.709754)
		(end 178.572668 -88.953848)
		(width 0.11684)
		(layer "In2.Cu")
		(net "SMB_IOEXP_3V3AUX_SCL")
	)
	(segment
		(start 164.094414 -422.882822)
		(end 163.553394 -422.341802)
		(width 0.11684)
		(layer "In2.Cu")
		(net "SMB_IOEXP_3V3AUX_SCL")
	)
	(segment
		(start 248.863866 -88.060276)
		(end 255.477264 -88.060276)
		(width 0.11684)
		(layer "In2.Cu")
		(net "SMB_IOEXP_3V3AUX_SCL")
	)
	(segment
		(start 70.58533 -130.565906)
		(end 73.651364 -130.565906)
		(width 0.11684)
		(layer "In2.Cu")
		(net "SMB_IOEXP_3V3AUX_SCL")
	)
	(segment
		(start 165.641782 -422.882822)
		(end 164.094414 -422.882822)
		(width 0.11684)
		(layer "In2.Cu")
		(net "SMB_IOEXP_3V3AUX_SCL")
	)
	(segment
		(start 196.587872 -88.953848)
		(end 196.994526 -89.360502)
		(width 0.11684)
		(layer "In2.Cu")
		(net "SMB_IOEXP_3V3AUX_SCL")
	)
	(segment
		(start 116.434616 -87.782654)
		(end 156.626306 -87.782654)
		(width 0.11684)
		(layer "In2.Cu")
		(net "SMB_IOEXP_3V3AUX_SCL")
	)
	(segment
		(start 106.44759 -428.636684)
		(end 96.38665 -428.636684)
		(width 0.11684)
		(layer "In2.Cu")
		(net "SMB_IOEXP_3V3AUX_SCL")
	)
	(segment
		(start 171.20743 -88.953848)
		(end 171.436538 -88.72474)
		(width 0.11684)
		(layer "In2.Cu")
		(net "SMB_IOEXP_3V3AUX_SCL")
	)
	(segment
		(start 126.041404 -420.814754)
		(end 122.143012 -424.713146)
		(width 0.11684)
		(layer "In2.Cu")
		(net "SMB_IOEXP_3V3AUX_SCL")
	)
	(segment
		(start 17.993868 -415.349182)
		(end 18.75409 -414.58896)
		(width 0.11684)
		(layer "In4.Cu")
		(net "SMB_IOEXP_3V3AUX_SCL")
	)
	(segment
		(start 65.018158 -136.133078)
		(end 25.610312 -136.133078)
		(width 0.11684)
		(layer "In4.Cu")
		(net "SMB_IOEXP_3V3AUX_SCL")
	)
	(segment
		(start 9.646158 -408.04846)
		(end 9.646158 -412.87827)
		(width 0.11684)
		(layer "In4.Cu")
		(net "SMB_IOEXP_3V3AUX_SCL")
	)
	(segment
		(start 10.70229 -392.568176)
		(end 4.336796 -398.93367)
		(width 0.11684)
		(layer "In4.Cu")
		(net "SMB_IOEXP_3V3AUX_SCL")
	)
	(segment
		(start 9.371076 -405.089868)
		(end 9.950958 -405.66975)
		(width 0.11684)
		(layer "In4.Cu")
		(net "SMB_IOEXP_3V3AUX_SCL")
	)
	(segment
		(start 68.470272 -132.680964)
		(end 65.018158 -136.133078)
		(width 0.11684)
		(layer "In4.Cu")
		(net "SMB_IOEXP_3V3AUX_SCL")
	)
	(segment
		(start 4.280154 -382.04648)
		(end 10.70229 -388.468616)
		(width 0.11684)
		(layer "In4.Cu")
		(net "SMB_IOEXP_3V3AUX_SCL")
	)
	(segment
		(start 4.205986 -331.056234)
		(end 3.941064 -331.321156)
		(width 0.11684)
		(layer "In4.Cu")
		(net "SMB_IOEXP_3V3AUX_SCL")
	)
	(segment
		(start 4.280154 -350.40189)
		(end 4.280154 -382.04648)
		(width 0.11684)
		(layer "In4.Cu")
		(net "SMB_IOEXP_3V3AUX_SCL")
	)
	(segment
		(start 3.941064 -350.0628)
		(end 4.280154 -350.40189)
		(width 0.11684)
		(layer "In4.Cu")
		(net "SMB_IOEXP_3V3AUX_SCL")
	)
	(segment
		(start 21.744178 -414.58896)
		(end 23.699724 -412.633414)
		(width 0.11684)
		(layer "In4.Cu")
		(net "SMB_IOEXP_3V3AUX_SCL")
	)
	(segment
		(start 10.70229 -388.468616)
		(end 10.70229 -392.568176)
		(width 0.11684)
		(layer "In4.Cu")
		(net "SMB_IOEXP_3V3AUX_SCL")
	)
	(segment
		(start 4.336796 -398.93367)
		(end 4.336796 -402.898356)
		(width 0.11684)
		(layer "In4.Cu")
		(net "SMB_IOEXP_3V3AUX_SCL")
	)
	(segment
		(start 12.11707 -415.349182)
		(end 17.993868 -415.349182)
		(width 0.11684)
		(layer "In4.Cu")
		(net "SMB_IOEXP_3V3AUX_SCL")
	)
	(segment
		(start 4.336796 -402.898356)
		(end 6.528308 -405.089868)
		(width 0.11684)
		(layer "In4.Cu")
		(net "SMB_IOEXP_3V3AUX_SCL")
	)
	(segment
		(start 9.950958 -405.66975)
		(end 9.950958 -407.74366)
		(width 0.11684)
		(layer "In4.Cu")
		(net "SMB_IOEXP_3V3AUX_SCL")
	)
	(segment
		(start 9.646158 -412.87827)
		(end 12.11707 -415.349182)
		(width 0.11684)
		(layer "In4.Cu")
		(net "SMB_IOEXP_3V3AUX_SCL")
	)
	(segment
		(start 18.75409 -414.58896)
		(end 21.744178 -414.58896)
		(width 0.11684)
		(layer "In4.Cu")
		(net "SMB_IOEXP_3V3AUX_SCL")
	)
	(segment
		(start 6.528308 -405.089868)
		(end 9.371076 -405.089868)
		(width 0.11684)
		(layer "In4.Cu")
		(net "SMB_IOEXP_3V3AUX_SCL")
	)
	(segment
		(start 4.205986 -157.537404)
		(end 4.205986 -331.056234)
		(width 0.11684)
		(layer "In4.Cu")
		(net "SMB_IOEXP_3V3AUX_SCL")
	)
	(segment
		(start 25.610312 -136.133078)
		(end 4.205986 -157.537404)
		(width 0.11684)
		(layer "In4.Cu")
		(net "SMB_IOEXP_3V3AUX_SCL")
	)
	(segment
		(start 9.950958 -407.74366)
		(end 9.646158 -408.04846)
		(width 0.11684)
		(layer "In4.Cu")
		(net "SMB_IOEXP_3V3AUX_SCL")
	)
	(segment
		(start 3.941064 -331.321156)
		(end 3.941064 -350.0628)
		(width 0.11684)
		(layer "In4.Cu")
		(net "SMB_IOEXP_3V3AUX_SCL")
	)
	(segment
		(start 23.699724 -412.633414)
		(end 29.112972 -412.633414)
		(width 0.11684)
		(layer "In4.Cu")
		(net "SMB_IOEXP_3V3AUX_SCL")
	)
	(segment
		(start 289.728148 -118.23192)
		(end 292.745922 -118.23192)
		(width 0.10668)
		(layer "F.Cu")
		(net "SMB_INA230_3V3AUX_SDA_R")
	)
	(segment
		(start 293.967408 -118.23192)
		(end 294.021002 -118.285514)
		(width 0.10668)
		(layer "F.Cu")
		(net "SMB_INA230_3V3AUX_SDA_R")
	)
	(segment
		(start 292.745922 -118.23192)
		(end 293.967408 -118.23192)
		(width 0.10668)
		(layer "F.Cu")
		(net "SMB_INA230_3V3AUX_SDA_R")
	)
	(via
		(at 292.745922 -118.23192)
		(size 0.762)
		(drill 0.381)
		(layers "F.Cu" "B.Cu")
		(net "SMB_INA230_3V3AUX_SDA_R")
	)
	(segment
		(start 299.72 -109.36605)
		(end 299.72 -110.744)
		(width 0.10668)
		(layer "F.Cu")
		(net "SMB_INA230_3V3AUX_SDA")
	)
	(segment
		(start 213.416134 -46.700948)
		(end 213.416134 -46.935898)
		(width 0.10668)
		(layer "F.Cu")
		(net "SMB_INA230_3V3AUX_SDA")
	)
	(segment
		(start 299.935646 -117.25021)
		(end 299.29836 -117.25021)
		(width 0.10668)
		(layer "F.Cu")
		(net "SMB_INA230_3V3AUX_SDA")
	)
	(segment
		(start 300.355254 -108.966)
		(end 299.955204 -109.36605)
		(width 0.10668)
		(layer "F.Cu")
		(net "SMB_INA230_3V3AUX_SDA")
	)
	(segment
		(start 214.051134 -46.065948)
		(end 213.416134 -46.700948)
		(width 0.10668)
		(layer "F.Cu")
		(net "SMB_INA230_3V3AUX_SDA")
	)
	(segment
		(start 146.171158 -50.160174)
		(end 146.16176 -50.169572)
		(width 0.10668)
		(layer "F.Cu")
		(net "SMB_INA230_3V3AUX_SDA")
	)
	(segment
		(start 151.966676 -50.339244)
		(end 151.712422 -50.08499)
		(width 0.10668)
		(layer "F.Cu")
		(net "SMB_INA230_3V3AUX_SDA")
	)
	(segment
		(start 146.16176 -50.169572)
		(end 146.16176 -50.99939)
		(width 0.10668)
		(layer "F.Cu")
		(net "SMB_INA230_3V3AUX_SDA")
	)
	(segment
		(start 294.821102 -118.285514)
		(end 296.743374 -118.285514)
		(width 0.10668)
		(layer "F.Cu")
		(net "SMB_INA230_3V3AUX_SDA")
	)
	(segment
		(start 299.29836 -117.25021)
		(end 297.778678 -117.25021)
		(width 0.10668)
		(layer "F.Cu")
		(net "SMB_INA230_3V3AUX_SDA")
	)
	(segment
		(start 297.778678 -117.25021)
		(end 297.086274 -117.942614)
		(width 0.10668)
		(layer "F.Cu")
		(net "SMB_INA230_3V3AUX_SDA")
	)
	(segment
		(start 296.743374 -118.285514)
		(end 297.086274 -117.942614)
		(width 0.10668)
		(layer "F.Cu")
		(net "SMB_INA230_3V3AUX_SDA")
	)
	(segment
		(start 151.966676 -50.339244)
		(end 152.982676 -50.339244)
		(width 0.10668)
		(layer "F.Cu")
		(net "SMB_INA230_3V3AUX_SDA")
	)
	(segment
		(start 216.356184 -32.857948)
		(end 216.972134 -32.857948)
		(width 0.10668)
		(layer "F.Cu")
		(net "SMB_INA230_3V3AUX_SDA")
	)
	(segment
		(start 300.736 -108.966)
		(end 300.355254 -108.966)
		(width 0.10668)
		(layer "F.Cu")
		(net "SMB_INA230_3V3AUX_SDA")
	)
	(segment
		(start 299.955204 -109.36605)
		(end 299.72 -109.36605)
		(width 0.10668)
		(layer "F.Cu")
		(net "SMB_INA230_3V3AUX_SDA")
	)
	(segment
		(start 151.712422 -50.08499)
		(end 151.712422 -49.069244)
		(width 0.10668)
		(layer "F.Cu")
		(net "SMB_INA230_3V3AUX_SDA")
	)
	(via
		(at 214.051134 -46.065948)
		(size 0.508)
		(drill 0.254)
		(layers "F.Cu" "B.Cu")
		(net "SMB_INA230_3V3AUX_SDA")
	)
	(via
		(at 299.29836 -117.25021)
		(size 0.508)
		(drill 0.254)
		(layers "F.Cu" "B.Cu")
		(net "SMB_INA230_3V3AUX_SDA")
	)
	(via
		(at 146.16176 -50.99939)
		(size 0.508)
		(drill 0.254)
		(layers "F.Cu" "B.Cu")
		(net "SMB_INA230_3V3AUX_SDA")
	)
	(via
		(at 216.972134 -32.857948)
		(size 0.508)
		(drill 0.254)
		(layers "F.Cu" "B.Cu")
		(net "SMB_INA230_3V3AUX_SDA")
	)
	(via
		(at 299.72 -110.744)
		(size 0.508)
		(drill 0.254)
		(layers "F.Cu" "B.Cu")
		(net "SMB_INA230_3V3AUX_SDA")
	)
	(via
		(at 151.712422 -49.069244)
		(size 0.508)
		(drill 0.254)
		(layers "F.Cu" "B.Cu")
		(net "SMB_INA230_3V3AUX_SDA")
	)
	(segment
		(start 299.30979 -117.25021)
		(end 299.29836 -117.25021)
		(width 0.10668)
		(layer "B.Cu")
		(net "SMB_INA230_3V3AUX_SDA")
	)
	(segment
		(start 300.101 -116.459)
		(end 299.30979 -117.25021)
		(width 0.10668)
		(layer "B.Cu")
		(net "SMB_INA230_3V3AUX_SDA")
	)
	(segment
		(start 299.72 -110.744)
		(end 300.101 -111.125)
		(width 0.10668)
		(layer "B.Cu")
		(net "SMB_INA230_3V3AUX_SDA")
	)
	(segment
		(start 300.101 -111.125)
		(end 300.101 -116.459)
		(width 0.10668)
		(layer "B.Cu")
		(net "SMB_INA230_3V3AUX_SDA")
	)
	(segment
		(start 215.531192 -34.871406)
		(end 214.391494 -36.011104)
		(width 0.11684)
		(layer "In2.Cu")
		(net "SMB_INA230_3V3AUX_SDA")
	)
	(segment
		(start 214.391494 -36.011104)
		(end 214.391494 -45.725588)
		(width 0.11684)
		(layer "In2.Cu")
		(net "SMB_INA230_3V3AUX_SDA")
	)
	(segment
		(start 149.782276 -50.99939)
		(end 151.712422 -49.069244)
		(width 0.11684)
		(layer "In2.Cu")
		(net "SMB_INA230_3V3AUX_SDA")
	)
	(segment
		(start 215.531192 -33.93313)
		(end 215.531192 -34.871406)
		(width 0.11684)
		(layer "In2.Cu")
		(net "SMB_INA230_3V3AUX_SDA")
	)
	(segment
		(start 146.16176 -50.99939)
		(end 149.782276 -50.99939)
		(width 0.11684)
		(layer "In2.Cu")
		(net "SMB_INA230_3V3AUX_SDA")
	)
	(segment
		(start 216.972134 -32.857948)
		(end 216.606374 -32.857948)
		(width 0.11684)
		(layer "In2.Cu")
		(net "SMB_INA230_3V3AUX_SDA")
	)
	(segment
		(start 216.606374 -32.857948)
		(end 215.531192 -33.93313)
		(width 0.11684)
		(layer "In2.Cu")
		(net "SMB_INA230_3V3AUX_SDA")
	)
	(segment
		(start 214.391494 -45.725588)
		(end 214.051134 -46.065948)
		(width 0.11684)
		(layer "In2.Cu")
		(net "SMB_INA230_3V3AUX_SDA")
	)
	(segment
		(start 273.854672 -60.048648)
		(end 265.32078 -60.048648)
		(width 0.11684)
		(layer "In4.Cu")
		(net "SMB_INA230_3V3AUX_SDA")
	)
	(segment
		(start 285.300674 -98.72218)
		(end 285.300674 -71.49465)
		(width 0.11684)
		(layer "In4.Cu")
		(net "SMB_INA230_3V3AUX_SDA")
	)
	(segment
		(start 228.183694 -50.300382)
		(end 224.120456 -46.237144)
		(width 0.11684)
		(layer "In4.Cu")
		(net "SMB_INA230_3V3AUX_SDA")
	)
	(segment
		(start 295.768776 -109.190282)
		(end 285.300674 -98.72218)
		(width 0.11684)
		(layer "In4.Cu")
		(net "SMB_INA230_3V3AUX_SDA")
	)
	(segment
		(start 224.120456 -46.237144)
		(end 224.120456 -41.957498)
		(width 0.11684)
		(layer "In4.Cu")
		(net "SMB_INA230_3V3AUX_SDA")
	)
	(segment
		(start 299.29836 -117.25021)
		(end 298.248832 -117.25021)
		(width 0.11684)
		(layer "In4.Cu")
		(net "SMB_INA230_3V3AUX_SDA")
	)
	(segment
		(start 218.486228 -33.523936)
		(end 217.82024 -32.857948)
		(width 0.11684)
		(layer "In4.Cu")
		(net "SMB_INA230_3V3AUX_SDA")
	)
	(segment
		(start 233.55046 -56.884824)
		(end 233.55046 -52.027328)
		(width 0.11684)
		(layer "In4.Cu")
		(net "SMB_INA230_3V3AUX_SDA")
	)
	(segment
		(start 237.557564 -60.891928)
		(end 233.55046 -56.884824)
		(width 0.11684)
		(layer "In4.Cu")
		(net "SMB_INA230_3V3AUX_SDA")
	)
	(segment
		(start 264.4775 -60.891928)
		(end 237.557564 -60.891928)
		(width 0.11684)
		(layer "In4.Cu")
		(net "SMB_INA230_3V3AUX_SDA")
	)
	(segment
		(start 285.300674 -71.49465)
		(end 273.854672 -60.048648)
		(width 0.11684)
		(layer "In4.Cu")
		(net "SMB_INA230_3V3AUX_SDA")
	)
	(segment
		(start 233.55046 -52.027328)
		(end 231.823514 -50.300382)
		(width 0.11684)
		(layer "In4.Cu")
		(net "SMB_INA230_3V3AUX_SDA")
	)
	(segment
		(start 222.317818 -40.15486)
		(end 219.059252 -40.15486)
		(width 0.11684)
		(layer "In4.Cu")
		(net "SMB_INA230_3V3AUX_SDA")
	)
	(segment
		(start 265.32078 -60.048648)
		(end 264.4775 -60.891928)
		(width 0.11684)
		(layer "In4.Cu")
		(net "SMB_INA230_3V3AUX_SDA")
	)
	(segment
		(start 218.486228 -39.581836)
		(end 218.486228 -33.523936)
		(width 0.11684)
		(layer "In4.Cu")
		(net "SMB_INA230_3V3AUX_SDA")
	)
	(segment
		(start 219.059252 -40.15486)
		(end 218.486228 -39.581836)
		(width 0.11684)
		(layer "In4.Cu")
		(net "SMB_INA230_3V3AUX_SDA")
	)
	(segment
		(start 231.823514 -50.300382)
		(end 228.183694 -50.300382)
		(width 0.11684)
		(layer "In4.Cu")
		(net "SMB_INA230_3V3AUX_SDA")
	)
	(segment
		(start 298.248832 -117.25021)
		(end 295.768776 -114.770154)
		(width 0.11684)
		(layer "In4.Cu")
		(net "SMB_INA230_3V3AUX_SDA")
	)
	(segment
		(start 217.82024 -32.857948)
		(end 216.972134 -32.857948)
		(width 0.11684)
		(layer "In4.Cu")
		(net "SMB_INA230_3V3AUX_SDA")
	)
	(segment
		(start 295.768776 -114.770154)
		(end 295.768776 -109.190282)
		(width 0.11684)
		(layer "In4.Cu")
		(net "SMB_INA230_3V3AUX_SDA")
	)
	(segment
		(start 224.120456 -41.957498)
		(end 222.317818 -40.15486)
		(width 0.11684)
		(layer "In4.Cu")
		(net "SMB_INA230_3V3AUX_SDA")
	)
	(segment
		(start 158.986982 -49.90084)
		(end 152.544272 -49.90084)
		(width 0.11684)
		(layer "In6.Cu")
		(net "SMB_INA230_3V3AUX_SDA")
	)
	(segment
		(start 167.512746 -41.375076)
		(end 158.986982 -49.90084)
		(width 0.11684)
		(layer "In6.Cu")
		(net "SMB_INA230_3V3AUX_SDA")
	)
	(segment
		(start 180.06187 -42.198544)
		(end 179.238402 -41.375076)
		(width 0.11684)
		(layer "In6.Cu")
		(net "SMB_INA230_3V3AUX_SDA")
	)
	(segment
		(start 179.238402 -41.375076)
		(end 167.512746 -41.375076)
		(width 0.11684)
		(layer "In6.Cu")
		(net "SMB_INA230_3V3AUX_SDA")
	)
	(segment
		(start 194.202812 -46.065948)
		(end 192.17132 -48.09744)
		(width 0.11684)
		(layer "In6.Cu")
		(net "SMB_INA230_3V3AUX_SDA")
	)
	(segment
		(start 188.11748 -48.09744)
		(end 182.218584 -42.198544)
		(width 0.11684)
		(layer "In6.Cu")
		(net "SMB_INA230_3V3AUX_SDA")
	)
	(segment
		(start 214.051134 -46.065948)
		(end 194.202812 -46.065948)
		(width 0.11684)
		(layer "In6.Cu")
		(net "SMB_INA230_3V3AUX_SDA")
	)
	(segment
		(start 192.17132 -48.09744)
		(end 188.11748 -48.09744)
		(width 0.11684)
		(layer "In6.Cu")
		(net "SMB_INA230_3V3AUX_SDA")
	)
	(segment
		(start 152.544272 -49.90084)
		(end 151.712676 -49.069244)
		(width 0.11684)
		(layer "In6.Cu")
		(net "SMB_INA230_3V3AUX_SDA")
	)
	(segment
		(start 151.712676 -49.069244)
		(end 151.712422 -49.069244)
		(width 0.11684)
		(layer "In6.Cu")
		(net "SMB_INA230_3V3AUX_SDA")
	)
	(segment
		(start 182.218584 -42.198544)
		(end 180.06187 -42.198544)
		(width 0.11684)
		(layer "In6.Cu")
		(net "SMB_INA230_3V3AUX_SDA")
	)
	(segment
		(start 293.601394 -118.881906)
		(end 294.021002 -119.301514)
		(width 0.10668)
		(layer "F.Cu")
		(net "SMB_INA230_3V3AUX_SCL_R")
	)
	(segment
		(start 291.602922 -118.881906)
		(end 293.601394 -118.881906)
		(width 0.10668)
		(layer "F.Cu")
		(net "SMB_INA230_3V3AUX_SCL_R")
	)
	(segment
		(start 289.728148 -118.881906)
		(end 291.602922 -118.881906)
		(width 0.10668)
		(layer "F.Cu")
		(net "SMB_INA230_3V3AUX_SCL_R")
	)
	(via
		(at 291.602922 -118.881906)
		(size 0.762)
		(drill 0.381)
		(layers "F.Cu" "B.Cu")
		(net "SMB_INA230_3V3AUX_SCL_R")
	)
	(segment
		(start 294.859202 -119.339614)
		(end 297.086274 -119.339614)
		(width 0.10668)
		(layer "F.Cu")
		(net "SMB_INA230_3V3AUX_SCL")
	)
	(segment
		(start 146.167348 -48.718724)
		(end 146.15795 -48.709326)
		(width 0.10668)
		(layer "F.Cu")
		(net "SMB_INA230_3V3AUX_SCL")
	)
	(segment
		(start 146.15795 -48.709326)
		(end 146.15795 -48.21809)
		(width 0.10668)
		(layer "F.Cu")
		(net "SMB_INA230_3V3AUX_SCL")
	)
	(segment
		(start 216.356184 -34.508948)
		(end 216.972134 -34.508948)
		(width 0.10668)
		(layer "F.Cu")
		(net "SMB_INA230_3V3AUX_SCL")
	)
	(segment
		(start 297.688 -109.36605)
		(end 298.704 -109.36605)
		(width 0.10668)
		(layer "F.Cu")
		(net "SMB_INA230_3V3AUX_SCL")
	)
	(segment
		(start 154.633676 -49.361344)
		(end 153.782776 -49.361344)
		(width 0.10668)
		(layer "F.Cu")
		(net "SMB_INA230_3V3AUX_SCL")
	)
	(segment
		(start 154.633676 -50.339244)
		(end 154.633676 -49.361344)
		(width 0.10668)
		(layer "F.Cu")
		(net "SMB_INA230_3V3AUX_SCL")
	)
	(segment
		(start 297.765978 -118.65991)
		(end 297.086274 -119.339614)
		(width 0.10668)
		(layer "F.Cu")
		(net "SMB_INA230_3V3AUX_SCL")
	)
	(segment
		(start 299.29836 -118.65991)
		(end 297.765978 -118.65991)
		(width 0.10668)
		(layer "F.Cu")
		(net "SMB_INA230_3V3AUX_SCL")
	)
	(segment
		(start 214.813134 -46.554898)
		(end 214.813134 -46.065948)
		(width 0.10668)
		(layer "F.Cu")
		(net "SMB_INA230_3V3AUX_SCL")
	)
	(segment
		(start 298.704 -109.36605)
		(end 298.704 -110.871)
		(width 0.10668)
		(layer "F.Cu")
		(net "SMB_INA230_3V3AUX_SCL")
	)
	(segment
		(start 299.29836 -119.27586)
		(end 299.29836 -118.65991)
		(width 0.10668)
		(layer "F.Cu")
		(net "SMB_INA230_3V3AUX_SCL")
	)
	(segment
		(start 294.821102 -119.301514)
		(end 294.859202 -119.339614)
		(width 0.10668)
		(layer "F.Cu")
		(net "SMB_INA230_3V3AUX_SCL")
	)
	(segment
		(start 153.782776 -49.361344)
		(end 153.490422 -49.06899)
		(width 0.10668)
		(layer "F.Cu")
		(net "SMB_INA230_3V3AUX_SCL")
	)
	(segment
		(start 214.432134 -46.935898)
		(end 214.813134 -46.554898)
		(width 0.10668)
		(layer "F.Cu")
		(net "SMB_INA230_3V3AUX_SCL")
	)
	(segment
		(start 146.167348 -49.153064)
		(end 146.167348 -48.718724)
		(width 0.10668)
		(layer "F.Cu")
		(net "SMB_INA230_3V3AUX_SCL")
	)
	(via
		(at 146.15795 -48.21809)
		(size 0.508)
		(drill 0.254)
		(layers "F.Cu" "B.Cu")
		(net "SMB_INA230_3V3AUX_SCL")
	)
	(via
		(at 299.29836 -118.65991)
		(size 0.508)
		(drill 0.254)
		(layers "F.Cu" "B.Cu")
		(net "SMB_INA230_3V3AUX_SCL")
	)
	(via
		(at 216.972134 -34.508948)
		(size 0.508)
		(drill 0.254)
		(layers "F.Cu" "B.Cu")
		(net "SMB_INA230_3V3AUX_SCL")
	)
	(via
		(at 298.704 -110.871)
		(size 0.508)
		(drill 0.254)
		(layers "F.Cu" "B.Cu")
		(net "SMB_INA230_3V3AUX_SCL")
	)
	(via
		(at 214.813134 -46.065948)
		(size 0.508)
		(drill 0.254)
		(layers "F.Cu" "B.Cu")
		(net "SMB_INA230_3V3AUX_SCL")
	)
	(via
		(at 153.490422 -49.06899)
		(size 0.508)
		(drill 0.254)
		(layers "F.Cu" "B.Cu")
		(net "SMB_INA230_3V3AUX_SCL")
	)
	(segment
		(start 298.23791 -118.65991)
		(end 299.29836 -118.65991)
		(width 0.10668)
		(layer "B.Cu")
		(net "SMB_INA230_3V3AUX_SCL")
	)
	(segment
		(start 297.815 -111.76)
		(end 297.815 -118.237)
		(width 0.10668)
		(layer "B.Cu")
		(net "SMB_INA230_3V3AUX_SCL")
	)
	(segment
		(start 297.815 -118.237)
		(end 298.23791 -118.65991)
		(width 0.10668)
		(layer "B.Cu")
		(net "SMB_INA230_3V3AUX_SCL")
	)
	(segment
		(start 298.704 -110.871)
		(end 297.815 -111.76)
		(width 0.10668)
		(layer "B.Cu")
		(net "SMB_INA230_3V3AUX_SCL")
	)
	(segment
		(start 214.813134 -36.185856)
		(end 214.813134 -46.065948)
		(width 0.11684)
		(layer "In2.Cu")
		(net "SMB_INA230_3V3AUX_SCL")
	)
	(segment
		(start 146.15795 -48.21809)
		(end 147.077938 -47.298102)
		(width 0.11684)
		(layer "In2.Cu")
		(net "SMB_INA230_3V3AUX_SCL")
	)
	(segment
		(start 153.490422 -47.884334)
		(end 153.490422 -49.06899)
		(width 0.11684)
		(layer "In2.Cu")
		(net "SMB_INA230_3V3AUX_SCL")
	)
	(segment
		(start 147.077938 -47.298102)
		(end 152.90419 -47.298102)
		(width 0.11684)
		(layer "In2.Cu")
		(net "SMB_INA230_3V3AUX_SCL")
	)
	(segment
		(start 152.90419 -47.298102)
		(end 153.490422 -47.884334)
		(width 0.11684)
		(layer "In2.Cu")
		(net "SMB_INA230_3V3AUX_SCL")
	)
	(segment
		(start 216.490042 -34.508948)
		(end 214.813134 -36.185856)
		(width 0.11684)
		(layer "In2.Cu")
		(net "SMB_INA230_3V3AUX_SCL")
	)
	(segment
		(start 216.972134 -34.508948)
		(end 216.490042 -34.508948)
		(width 0.11684)
		(layer "In2.Cu")
		(net "SMB_INA230_3V3AUX_SCL")
	)
	(segment
		(start 273.70786 -60.498228)
		(end 265.72972 -60.498228)
		(width 0.11684)
		(layer "In4.Cu")
		(net "SMB_INA230_3V3AUX_SCL")
	)
	(segment
		(start 265.72972 -60.498228)
		(end 264.91438 -61.313568)
		(width 0.11684)
		(layer "In4.Cu")
		(net "SMB_INA230_3V3AUX_SCL")
	)
	(segment
		(start 228.008942 -50.722022)
		(end 223.698816 -46.411896)
		(width 0.11684)
		(layer "In4.Cu")
		(net "SMB_INA230_3V3AUX_SCL")
	)
	(segment
		(start 222.143066 -40.5765)
		(end 218.8845 -40.5765)
		(width 0.11684)
		(layer "In4.Cu")
		(net "SMB_INA230_3V3AUX_SCL")
	)
	(segment
		(start 218.064588 -35.15233)
		(end 217.421206 -34.508948)
		(width 0.11684)
		(layer "In4.Cu")
		(net "SMB_INA230_3V3AUX_SCL")
	)
	(segment
		(start 284.879034 -99.117912)
		(end 284.879034 -71.669402)
		(width 0.11684)
		(layer "In4.Cu")
		(net "SMB_INA230_3V3AUX_SCL")
	)
	(segment
		(start 223.698816 -42.13225)
		(end 222.143066 -40.5765)
		(width 0.11684)
		(layer "In4.Cu")
		(net "SMB_INA230_3V3AUX_SCL")
	)
	(segment
		(start 264.91438 -61.313568)
		(end 237.161832 -61.313568)
		(width 0.11684)
		(layer "In4.Cu")
		(net "SMB_INA230_3V3AUX_SCL")
	)
	(segment
		(start 295.190926 -109.429804)
		(end 284.879034 -99.117912)
		(width 0.11684)
		(layer "In4.Cu")
		(net "SMB_INA230_3V3AUX_SCL")
	)
	(segment
		(start 232.97261 -52.236878)
		(end 231.457754 -50.722022)
		(width 0.11684)
		(layer "In4.Cu")
		(net "SMB_INA230_3V3AUX_SCL")
	)
	(segment
		(start 297.724576 -118.65991)
		(end 295.190926 -116.12626)
		(width 0.11684)
		(layer "In4.Cu")
		(net "SMB_INA230_3V3AUX_SCL")
	)
	(segment
		(start 223.698816 -46.411896)
		(end 223.698816 -42.13225)
		(width 0.11684)
		(layer "In4.Cu")
		(net "SMB_INA230_3V3AUX_SCL")
	)
	(segment
		(start 217.421206 -34.508948)
		(end 216.972134 -34.508948)
		(width 0.11684)
		(layer "In4.Cu")
		(net "SMB_INA230_3V3AUX_SCL")
	)
	(segment
		(start 231.457754 -50.722022)
		(end 228.008942 -50.722022)
		(width 0.11684)
		(layer "In4.Cu")
		(net "SMB_INA230_3V3AUX_SCL")
	)
	(segment
		(start 284.879034 -71.669402)
		(end 273.70786 -60.498228)
		(width 0.11684)
		(layer "In4.Cu")
		(net "SMB_INA230_3V3AUX_SCL")
	)
	(segment
		(start 218.8845 -40.5765)
		(end 218.064588 -39.756588)
		(width 0.11684)
		(layer "In4.Cu")
		(net "SMB_INA230_3V3AUX_SCL")
	)
	(segment
		(start 295.190926 -116.12626)
		(end 295.190926 -109.429804)
		(width 0.11684)
		(layer "In4.Cu")
		(net "SMB_INA230_3V3AUX_SCL")
	)
	(segment
		(start 232.97261 -57.124346)
		(end 232.97261 -52.236878)
		(width 0.11684)
		(layer "In4.Cu")
		(net "SMB_INA230_3V3AUX_SCL")
	)
	(segment
		(start 218.064588 -39.756588)
		(end 218.064588 -35.15233)
		(width 0.11684)
		(layer "In4.Cu")
		(net "SMB_INA230_3V3AUX_SCL")
	)
	(segment
		(start 299.29836 -118.65991)
		(end 297.724576 -118.65991)
		(width 0.11684)
		(layer "In4.Cu")
		(net "SMB_INA230_3V3AUX_SCL")
	)
	(segment
		(start 237.161832 -61.313568)
		(end 232.97261 -57.124346)
		(width 0.11684)
		(layer "In4.Cu")
		(net "SMB_INA230_3V3AUX_SCL")
	)
	(segment
		(start 153.490422 -49.06899)
		(end 158.10103 -49.06899)
		(width 0.11684)
		(layer "In6.Cu")
		(net "SMB_INA230_3V3AUX_SCL")
	)
	(segment
		(start 194.004946 -45.601128)
		(end 214.348314 -45.601128)
		(width 0.11684)
		(layer "In6.Cu")
		(net "SMB_INA230_3V3AUX_SCL")
	)
	(segment
		(start 182.393336 -41.776904)
		(end 188.276992 -47.66056)
		(width 0.11684)
		(layer "In6.Cu")
		(net "SMB_INA230_3V3AUX_SCL")
	)
	(segment
		(start 158.10103 -49.06899)
		(end 158.88462 -48.2854)
		(width 0.11684)
		(layer "In6.Cu")
		(net "SMB_INA230_3V3AUX_SCL")
	)
	(segment
		(start 159.976566 -48.2854)
		(end 167.311578 -40.950388)
		(width 0.11684)
		(layer "In6.Cu")
		(net "SMB_INA230_3V3AUX_SCL")
	)
	(segment
		(start 214.348314 -45.601128)
		(end 214.813134 -46.065948)
		(width 0.11684)
		(layer "In6.Cu")
		(net "SMB_INA230_3V3AUX_SCL")
	)
	(segment
		(start 188.276992 -47.66056)
		(end 191.945514 -47.66056)
		(width 0.11684)
		(layer "In6.Cu")
		(net "SMB_INA230_3V3AUX_SCL")
	)
	(segment
		(start 158.88462 -48.2854)
		(end 159.976566 -48.2854)
		(width 0.11684)
		(layer "In6.Cu")
		(net "SMB_INA230_3V3AUX_SCL")
	)
	(segment
		(start 191.945514 -47.66056)
		(end 194.004946 -45.601128)
		(width 0.11684)
		(layer "In6.Cu")
		(net "SMB_INA230_3V3AUX_SCL")
	)
	(segment
		(start 167.311578 -40.950388)
		(end 179.41036 -40.950388)
		(width 0.11684)
		(layer "In6.Cu")
		(net "SMB_INA230_3V3AUX_SCL")
	)
	(segment
		(start 179.41036 -40.950388)
		(end 180.236876 -41.776904)
		(width 0.11684)
		(layer "In6.Cu")
		(net "SMB_INA230_3V3AUX_SCL")
	)
	(segment
		(start 180.236876 -41.776904)
		(end 182.393336 -41.776904)
		(width 0.11684)
		(layer "In6.Cu")
		(net "SMB_INA230_3V3AUX_SCL")
	)
	(segment
		(start 291.730938 -116.931948)
		(end 289.728148 -116.931948)
		(width 0.10668)
		(layer "F.Cu")
		(net "SMB_FRU_3V3AUX_SDA_R")
	)
	(segment
		(start 292.745922 -116.80317)
		(end 291.859716 -116.80317)
		(width 0.10668)
		(layer "F.Cu")
		(net "SMB_FRU_3V3AUX_SDA_R")
	)
	(segment
		(start 291.859716 -116.80317)
		(end 291.730938 -116.931948)
		(width 0.10668)
		(layer "F.Cu")
		(net "SMB_FRU_3V3AUX_SDA_R")
	)
	(segment
		(start 293.471346 -116.80317)
		(end 292.745922 -116.80317)
		(width 0.10668)
		(layer "F.Cu")
		(net "SMB_FRU_3V3AUX_SDA_R")
	)
	(segment
		(start 294.021002 -116.253514)
		(end 293.471346 -116.80317)
		(width 0.10668)
		(layer "F.Cu")
		(net "SMB_FRU_3V3AUX_SDA_R")
	)
	(via
		(at 292.745922 -116.80317)
		(size 0.762)
		(drill 0.381)
		(layers "F.Cu" "B.Cu")
		(net "SMB_FRU_3V3AUX_SDA_R")
	)
	(segment
		(start 289.728148 -117.581934)
		(end 291.602922 -117.581934)
		(width 0.10668)
		(layer "F.Cu")
		(net "SMB_FRU_3V3AUX_SCL_R")
	)
	(segment
		(start 291.602922 -117.581934)
		(end 293.708582 -117.581934)
		(width 0.10668)
		(layer "F.Cu")
		(net "SMB_FRU_3V3AUX_SCL_R")
	)
	(segment
		(start 293.708582 -117.581934)
		(end 294.021002 -117.269514)
		(width 0.10668)
		(layer "F.Cu")
		(net "SMB_FRU_3V3AUX_SCL_R")
	)
	(via
		(at 291.602922 -117.581934)
		(size 0.762)
		(drill 0.381)
		(layers "F.Cu" "B.Cu")
		(net "SMB_FRU_3V3AUX_SCL_R")
	)
	(segment
		(start 232.463848 -184.446926)
		(end 232.235502 -184.675272)
		(width 0.10668)
		(layer "F.Cu")
		(net "SMB_CPU0_CPU1_SEC_SDA")
	)
	(segment
		(start 195.612766 -82.83067)
		(end 196.792342 -84.010246)
		(width 0.10668)
		(layer "F.Cu")
		(net "SMB_CPU0_CPU1_SEC_SDA")
	)
	(segment
		(start 189.616588 -78.436216)
		(end 190.114682 -78.93431)
		(width 0.10668)
		(layer "F.Cu")
		(net "SMB_CPU0_CPU1_SEC_SDA")
	)
	(segment
		(start 231.501442 -211.720176)
		(end 231.501442 -213.184486)
		(width 0.10668)
		(layer "F.Cu")
		(net "SMB_CPU0_CPU1_SEC_SDA")
	)
	(segment
		(start 196.792342 -84.010246)
		(end 198.758048 -84.010246)
		(width 0.10668)
		(layer "F.Cu")
		(net "SMB_CPU0_CPU1_SEC_SDA")
	)
	(segment
		(start 224.653602 -120.34393)
		(end 227.723954 -123.414282)
		(width 0.10668)
		(layer "F.Cu")
		(net "SMB_CPU0_CPU1_SEC_SDA")
	)
	(segment
		(start 227.723954 -140.316204)
		(end 227.41509 -140.625068)
		(width 0.10668)
		(layer "F.Cu")
		(net "SMB_CPU0_CPU1_SEC_SDA")
	)
	(segment
		(start 225.135948 -149.200616)
		(end 225.135948 -159.060388)
		(width 0.10668)
		(layer "F.Cu")
		(net "SMB_CPU0_CPU1_SEC_SDA")
	)
	(segment
		(start 232.235502 -187.253118)
		(end 230.553006 -191.315086)
		(width 0.10668)
		(layer "F.Cu")
		(net "SMB_CPU0_CPU1_SEC_SDA")
	)
	(segment
		(start 231.087422 -211.720176)
		(end 231.194102 -211.613496)
		(width 0.10668)
		(layer "F.Cu")
		(net "SMB_CPU0_CPU1_SEC_SDA")
	)
	(segment
		(start 231.501442 -213.184486)
		(end 231.608122 -213.291166)
		(width 0.10668)
		(layer "F.Cu")
		(net "SMB_CPU0_CPU1_SEC_SDA")
	)
	(segment
		(start 221.061534 -89.978992)
		(end 226.348036 -95.265494)
		(width 0.10668)
		(layer "F.Cu")
		(net "SMB_CPU0_CPU1_SEC_SDA")
	)
	(segment
		(start 231.194102 -211.613496)
		(end 231.394762 -211.613496)
		(width 0.10668)
		(layer "F.Cu")
		(net "SMB_CPU0_CPU1_SEC_SDA")
	)
	(segment
		(start 243.05768 -219.22232)
		(end 243.332 -218.948)
		(width 0.10668)
		(layer "F.Cu")
		(net "SMB_CPU0_CPU1_SEC_SDA")
	)
	(segment
		(start 199.39381 -84.646008)
		(end 208.557368 -84.646008)
		(width 0.10668)
		(layer "F.Cu")
		(net "SMB_CPU0_CPU1_SEC_SDA")
	)
	(segment
		(start 226.348036 -117.164866)
		(end 224.653602 -118.8593)
		(width 0.10668)
		(layer "F.Cu")
		(net "SMB_CPU0_CPU1_SEC_SDA")
	)
	(segment
		(start 230.553006 -203.889864)
		(end 227.616258 -206.826612)
		(width 0.10668)
		(layer "F.Cu")
		(net "SMB_CPU0_CPU1_SEC_SDA")
	)
	(segment
		(start 236.073188 -213.291166)
		(end 242.004342 -219.22232)
		(width 0.10668)
		(layer "F.Cu")
		(net "SMB_CPU0_CPU1_SEC_SDA")
	)
	(segment
		(start 193.239898 -82.83067)
		(end 195.612766 -82.83067)
		(width 0.10668)
		(layer "F.Cu")
		(net "SMB_CPU0_CPU1_SEC_SDA")
	)
	(segment
		(start 230.980742 -213.291166)
		(end 231.087422 -213.184486)
		(width 0.10668)
		(layer "F.Cu")
		(net "SMB_CPU0_CPU1_SEC_SDA")
	)
	(segment
		(start 230.553006 -191.315086)
		(end 230.553006 -203.889864)
		(width 0.10668)
		(layer "F.Cu")
		(net "SMB_CPU0_CPU1_SEC_SDA")
	)
	(segment
		(start 227.41509 -146.921474)
		(end 225.135948 -149.200616)
		(width 0.10668)
		(layer "F.Cu")
		(net "SMB_CPU0_CPU1_SEC_SDA")
	)
	(segment
		(start 227.616258 -206.826612)
		(end 227.616258 -211.518246)
		(width 0.10668)
		(layer "F.Cu")
		(net "SMB_CPU0_CPU1_SEC_SDA")
	)
	(segment
		(start 227.723954 -123.414282)
		(end 227.723954 -140.316204)
		(width 0.10668)
		(layer "F.Cu")
		(net "SMB_CPU0_CPU1_SEC_SDA")
	)
	(segment
		(start 227.41509 -140.625068)
		(end 227.41509 -146.921474)
		(width 0.10668)
		(layer "F.Cu")
		(net "SMB_CPU0_CPU1_SEC_SDA")
	)
	(segment
		(start 224.653602 -118.8593)
		(end 224.653602 -120.34393)
		(width 0.10668)
		(layer "F.Cu")
		(net "SMB_CPU0_CPU1_SEC_SDA")
	)
	(segment
		(start 190.114682 -78.93431)
		(end 190.66002 -80.250792)
		(width 0.10668)
		(layer "F.Cu")
		(net "SMB_CPU0_CPU1_SEC_SDA")
	)
	(segment
		(start 232.463848 -166.388288)
		(end 232.463848 -184.446926)
		(width 0.10668)
		(layer "F.Cu")
		(net "SMB_CPU0_CPU1_SEC_SDA")
	)
	(segment
		(start 231.394762 -211.613496)
		(end 231.501442 -211.720176)
		(width 0.10668)
		(layer "F.Cu")
		(net "SMB_CPU0_CPU1_SEC_SDA")
	)
	(segment
		(start 198.758048 -84.010246)
		(end 199.39381 -84.646008)
		(width 0.10668)
		(layer "F.Cu")
		(net "SMB_CPU0_CPU1_SEC_SDA")
	)
	(segment
		(start 227.616258 -211.518246)
		(end 229.389178 -213.291166)
		(width 0.10668)
		(layer "F.Cu")
		(net "SMB_CPU0_CPU1_SEC_SDA")
	)
	(segment
		(start 225.135948 -159.060388)
		(end 232.463848 -166.388288)
		(width 0.10668)
		(layer "F.Cu")
		(net "SMB_CPU0_CPU1_SEC_SDA")
	)
	(segment
		(start 242.004342 -219.22232)
		(end 243.05768 -219.22232)
		(width 0.10668)
		(layer "F.Cu")
		(net "SMB_CPU0_CPU1_SEC_SDA")
	)
	(segment
		(start 213.890352 -89.978992)
		(end 221.061534 -89.978992)
		(width 0.10668)
		(layer "F.Cu")
		(net "SMB_CPU0_CPU1_SEC_SDA")
	)
	(segment
		(start 226.348036 -95.265494)
		(end 226.348036 -117.164866)
		(width 0.10668)
		(layer "F.Cu")
		(net "SMB_CPU0_CPU1_SEC_SDA")
	)
	(segment
		(start 231.608122 -213.291166)
		(end 236.073188 -213.291166)
		(width 0.10668)
		(layer "F.Cu")
		(net "SMB_CPU0_CPU1_SEC_SDA")
	)
	(segment
		(start 208.557368 -84.646008)
		(end 213.890352 -89.978992)
		(width 0.10668)
		(layer "F.Cu")
		(net "SMB_CPU0_CPU1_SEC_SDA")
	)
	(segment
		(start 229.389178 -213.291166)
		(end 230.980742 -213.291166)
		(width 0.10668)
		(layer "F.Cu")
		(net "SMB_CPU0_CPU1_SEC_SDA")
	)
	(segment
		(start 232.235502 -184.675272)
		(end 232.235502 -187.253118)
		(width 0.10668)
		(layer "F.Cu")
		(net "SMB_CPU0_CPU1_SEC_SDA")
	)
	(segment
		(start 231.087422 -213.184486)
		(end 231.087422 -211.720176)
		(width 0.10668)
		(layer "F.Cu")
		(net "SMB_CPU0_CPU1_SEC_SDA")
	)
	(segment
		(start 190.66002 -80.250792)
		(end 193.239898 -82.83067)
		(width 0.10668)
		(layer "F.Cu")
		(net "SMB_CPU0_CPU1_SEC_SDA")
	)
	(via
		(at 189.616588 -78.436216)
		(size 0.508)
		(drill 0.254)
		(layers "F.Cu" "B.Cu")
		(net "SMB_CPU0_CPU1_SEC_SDA")
	)
	(via
		(at 243.332 -218.948)
		(size 0.508)
		(drill 0.254)
		(layers "F.Cu" "B.Cu")
		(net "SMB_CPU0_CPU1_SEC_SDA")
	)
	(via
		(at 176.58588 -15.35557)
		(size 0.508)
		(drill 0.254)
		(layers "F.Cu" "B.Cu")
		(net "SMB_CPU0_CPU1_SEC_SDA")
	)
	(segment
		(start 176.3776 -14.162278)
		(end 176.3776 -15.14729)
		(width 0.10668)
		(layer "B.Cu")
		(net "SMB_CPU0_CPU1_SEC_SDA")
	)
	(segment
		(start 176.3776 -14.162278)
		(end 175.880014 -14.162278)
		(width 0.10668)
		(layer "B.Cu")
		(net "SMB_CPU0_CPU1_SEC_SDA")
	)
	(segment
		(start 175.880014 -14.162278)
		(end 175.333914 -14.708378)
		(width 0.10668)
		(layer "B.Cu")
		(net "SMB_CPU0_CPU1_SEC_SDA")
	)
	(segment
		(start 243.91112 -220.963998)
		(end 243.91112 -219.52712)
		(width 0.10668)
		(layer "B.Cu")
		(net "SMB_CPU0_CPU1_SEC_SDA")
	)
	(segment
		(start 176.3776 -15.14729)
		(end 176.58588 -15.35557)
		(width 0.10668)
		(layer "B.Cu")
		(net "SMB_CPU0_CPU1_SEC_SDA")
	)
	(segment
		(start 243.91112 -219.52712)
		(end 243.332 -218.948)
		(width 0.10668)
		(layer "B.Cu")
		(net "SMB_CPU0_CPU1_SEC_SDA")
	)
	(segment
		(start 175.972978 -15.968472)
		(end 176.58588 -15.35557)
		(width 0.11684)
		(layer "In2.Cu")
		(net "SMB_CPU0_CPU1_SEC_SDA")
	)
	(segment
		(start 177.814986 -37.756592)
		(end 170.432222 -30.373828)
		(width 0.11684)
		(layer "In2.Cu")
		(net "SMB_CPU0_CPU1_SEC_SDA")
	)
	(segment
		(start 173.332902 -15.968472)
		(end 175.972978 -15.968472)
		(width 0.11684)
		(layer "In2.Cu")
		(net "SMB_CPU0_CPU1_SEC_SDA")
	)
	(segment
		(start 170.432222 -30.373828)
		(end 170.432222 -21.835872)
		(width 0.11684)
		(layer "In2.Cu")
		(net "SMB_CPU0_CPU1_SEC_SDA")
	)
	(segment
		(start 188.21654 -77.036168)
		(end 188.21654 -43.7261)
		(width 0.11684)
		(layer "In2.Cu")
		(net "SMB_CPU0_CPU1_SEC_SDA")
	)
	(segment
		(start 171.986956 -17.314418)
		(end 173.332902 -15.968472)
		(width 0.11684)
		(layer "In2.Cu")
		(net "SMB_CPU0_CPU1_SEC_SDA")
	)
	(segment
		(start 188.21654 -43.7261)
		(end 182.247032 -37.756592)
		(width 0.11684)
		(layer "In2.Cu")
		(net "SMB_CPU0_CPU1_SEC_SDA")
	)
	(segment
		(start 171.602908 -20.665186)
		(end 171.602908 -19.525996)
		(width 0.11684)
		(layer "In2.Cu")
		(net "SMB_CPU0_CPU1_SEC_SDA")
	)
	(segment
		(start 171.986956 -19.141948)
		(end 171.986956 -17.314418)
		(width 0.11684)
		(layer "In2.Cu")
		(net "SMB_CPU0_CPU1_SEC_SDA")
	)
	(segment
		(start 170.432222 -21.835872)
		(end 171.602908 -20.665186)
		(width 0.11684)
		(layer "In2.Cu")
		(net "SMB_CPU0_CPU1_SEC_SDA")
	)
	(segment
		(start 171.602908 -19.525996)
		(end 171.986956 -19.141948)
		(width 0.11684)
		(layer "In2.Cu")
		(net "SMB_CPU0_CPU1_SEC_SDA")
	)
	(segment
		(start 182.247032 -37.756592)
		(end 177.814986 -37.756592)
		(width 0.11684)
		(layer "In2.Cu")
		(net "SMB_CPU0_CPU1_SEC_SDA")
	)
	(segment
		(start 189.616588 -78.436216)
		(end 188.21654 -77.036168)
		(width 0.11684)
		(layer "In2.Cu")
		(net "SMB_CPU0_CPU1_SEC_SDA")
	)
	(segment
		(start 230.212646 -203.630276)
		(end 227.226114 -206.616808)
		(width 0.10668)
		(layer "F.Cu")
		(net "SMB_CPU0_CPU1_SEC_SCL")
	)
	(segment
		(start 226.007676 -117.023642)
		(end 224.313242 -118.718076)
		(width 0.10668)
		(layer "F.Cu")
		(net "SMB_CPU0_CPU1_SEC_SCL")
	)
	(segment
		(start 241.863118 -219.56268)
		(end 243.05768 -219.56268)
		(width 0.10668)
		(layer "F.Cu")
		(net "SMB_CPU0_CPU1_SEC_SCL")
	)
	(segment
		(start 227.07473 -140.483844)
		(end 227.07473 -146.78025)
		(width 0.10668)
		(layer "F.Cu")
		(net "SMB_CPU0_CPU1_SEC_SCL")
	)
	(segment
		(start 227.226114 -206.616808)
		(end 227.226114 -211.609686)
		(width 0.10668)
		(layer "F.Cu")
		(net "SMB_CPU0_CPU1_SEC_SCL")
	)
	(segment
		(start 208.355692 -84.986368)
		(end 213.688676 -90.319352)
		(width 0.10668)
		(layer "F.Cu")
		(net "SMB_CPU0_CPU1_SEC_SCL")
	)
	(segment
		(start 227.226114 -211.609686)
		(end 229.247954 -213.631526)
		(width 0.10668)
		(layer "F.Cu")
		(net "SMB_CPU0_CPU1_SEC_SCL")
	)
	(segment
		(start 231.863138 -184.552844)
		(end 231.863138 -187.262516)
		(width 0.10668)
		(layer "F.Cu")
		(net "SMB_CPU0_CPU1_SEC_SCL")
	)
	(segment
		(start 235.931964 -213.631526)
		(end 241.863118 -219.56268)
		(width 0.10668)
		(layer "F.Cu")
		(net "SMB_CPU0_CPU1_SEC_SCL")
	)
	(segment
		(start 231.863138 -187.262516)
		(end 230.212646 -191.247014)
		(width 0.10668)
		(layer "F.Cu")
		(net "SMB_CPU0_CPU1_SEC_SCL")
	)
	(segment
		(start 227.383594 -140.17498)
		(end 227.07473 -140.483844)
		(width 0.10668)
		(layer "F.Cu")
		(net "SMB_CPU0_CPU1_SEC_SCL")
	)
	(segment
		(start 191.500506 -83.17103)
		(end 195.471542 -83.17103)
		(width 0.10668)
		(layer "F.Cu")
		(net "SMB_CPU0_CPU1_SEC_SCL")
	)
	(segment
		(start 232.123488 -184.292494)
		(end 231.863138 -184.552844)
		(width 0.10668)
		(layer "F.Cu")
		(net "SMB_CPU0_CPU1_SEC_SCL")
	)
	(segment
		(start 230.212646 -191.247014)
		(end 230.212646 -203.630276)
		(width 0.10668)
		(layer "F.Cu")
		(net "SMB_CPU0_CPU1_SEC_SCL")
	)
	(segment
		(start 213.688676 -90.319352)
		(end 220.92031 -90.319352)
		(width 0.10668)
		(layer "F.Cu")
		(net "SMB_CPU0_CPU1_SEC_SCL")
	)
	(segment
		(start 243.05768 -219.56268)
		(end 243.332 -219.837)
		(width 0.10668)
		(layer "F.Cu")
		(net "SMB_CPU0_CPU1_SEC_SCL")
	)
	(segment
		(start 224.313242 -120.485154)
		(end 227.383594 -123.555506)
		(width 0.10668)
		(layer "F.Cu")
		(net "SMB_CPU0_CPU1_SEC_SCL")
	)
	(segment
		(start 224.795588 -159.201612)
		(end 232.123488 -166.529512)
		(width 0.10668)
		(layer "F.Cu")
		(net "SMB_CPU0_CPU1_SEC_SCL")
	)
	(segment
		(start 227.383594 -123.555506)
		(end 227.383594 -140.17498)
		(width 0.10668)
		(layer "F.Cu")
		(net "SMB_CPU0_CPU1_SEC_SCL")
	)
	(segment
		(start 226.007676 -95.406718)
		(end 226.007676 -117.023642)
		(width 0.10668)
		(layer "F.Cu")
		(net "SMB_CPU0_CPU1_SEC_SCL")
	)
	(segment
		(start 220.92031 -90.319352)
		(end 226.007676 -95.406718)
		(width 0.10668)
		(layer "F.Cu")
		(net "SMB_CPU0_CPU1_SEC_SCL")
	)
	(segment
		(start 227.07473 -146.78025)
		(end 224.795588 -149.059392)
		(width 0.10668)
		(layer "F.Cu")
		(net "SMB_CPU0_CPU1_SEC_SCL")
	)
	(segment
		(start 195.471542 -83.17103)
		(end 196.651118 -84.350606)
		(width 0.10668)
		(layer "F.Cu")
		(net "SMB_CPU0_CPU1_SEC_SCL")
	)
	(segment
		(start 189.888876 -81.052924)
		(end 189.888876 -81.5594)
		(width 0.10668)
		(layer "F.Cu")
		(net "SMB_CPU0_CPU1_SEC_SCL")
	)
	(segment
		(start 198.616824 -84.350606)
		(end 199.252586 -84.986368)
		(width 0.10668)
		(layer "F.Cu")
		(net "SMB_CPU0_CPU1_SEC_SCL")
	)
	(segment
		(start 224.795588 -149.059392)
		(end 224.795588 -159.201612)
		(width 0.10668)
		(layer "F.Cu")
		(net "SMB_CPU0_CPU1_SEC_SCL")
	)
	(segment
		(start 199.252586 -84.986368)
		(end 208.355692 -84.986368)
		(width 0.10668)
		(layer "F.Cu")
		(net "SMB_CPU0_CPU1_SEC_SCL")
	)
	(segment
		(start 229.247954 -213.631526)
		(end 235.931964 -213.631526)
		(width 0.10668)
		(layer "F.Cu")
		(net "SMB_CPU0_CPU1_SEC_SCL")
	)
	(segment
		(start 189.888876 -81.5594)
		(end 191.500506 -83.17103)
		(width 0.10668)
		(layer "F.Cu")
		(net "SMB_CPU0_CPU1_SEC_SCL")
	)
	(segment
		(start 196.651118 -84.350606)
		(end 198.616824 -84.350606)
		(width 0.10668)
		(layer "F.Cu")
		(net "SMB_CPU0_CPU1_SEC_SCL")
	)
	(segment
		(start 224.313242 -118.718076)
		(end 224.313242 -120.485154)
		(width 0.10668)
		(layer "F.Cu")
		(net "SMB_CPU0_CPU1_SEC_SCL")
	)
	(segment
		(start 232.123488 -166.529512)
		(end 232.123488 -184.292494)
		(width 0.10668)
		(layer "F.Cu")
		(net "SMB_CPU0_CPU1_SEC_SCL")
	)
	(via
		(at 243.332 -219.837)
		(size 0.508)
		(drill 0.254)
		(layers "F.Cu" "B.Cu")
		(net "SMB_CPU0_CPU1_SEC_SCL")
	)
	(via
		(at 177.409348 -15.413482)
		(size 0.508)
		(drill 0.254)
		(layers "F.Cu" "B.Cu")
		(net "SMB_CPU0_CPU1_SEC_SCL")
	)
	(via
		(at 189.888876 -81.052924)
		(size 0.508)
		(drill 0.254)
		(layers "F.Cu" "B.Cu")
		(net "SMB_CPU0_CPU1_SEC_SCL")
	)
	(segment
		(start 177.443638 -15.379192)
		(end 177.409348 -15.413482)
		(width 0.10668)
		(layer "B.Cu")
		(net "SMB_CPU0_CPU1_SEC_SCL")
	)
	(segment
		(start 178.430174 -14.156182)
		(end 177.449734 -14.156182)
		(width 0.10668)
		(layer "B.Cu")
		(net "SMB_CPU0_CPU1_SEC_SCL")
	)
	(segment
		(start 177.443638 -14.162278)
		(end 177.443638 -15.379192)
		(width 0.10668)
		(layer "B.Cu")
		(net "SMB_CPU0_CPU1_SEC_SCL")
	)
	(segment
		(start 177.449734 -14.156182)
		(end 177.443638 -14.162278)
		(width 0.10668)
		(layer "B.Cu")
		(net "SMB_CPU0_CPU1_SEC_SCL")
	)
	(segment
		(start 243.26088 -219.90812)
		(end 243.332 -219.837)
		(width 0.10668)
		(layer "B.Cu")
		(net "SMB_CPU0_CPU1_SEC_SCL")
	)
	(segment
		(start 243.26088 -220.963998)
		(end 243.26088 -219.90812)
		(width 0.10668)
		(layer "B.Cu")
		(net "SMB_CPU0_CPU1_SEC_SCL")
	)
	(segment
		(start 173.509686 -16.394938)
		(end 176.427892 -16.394938)
		(width 0.11684)
		(layer "In2.Cu")
		(net "SMB_CPU0_CPU1_SEC_SCL")
	)
	(segment
		(start 172.027342 -20.844002)
		(end 172.027342 -19.727164)
		(width 0.11684)
		(layer "In2.Cu")
		(net "SMB_CPU0_CPU1_SEC_SCL")
	)
	(segment
		(start 176.427892 -16.394938)
		(end 177.409348 -15.413482)
		(width 0.11684)
		(layer "In2.Cu")
		(net "SMB_CPU0_CPU1_SEC_SCL")
	)
	(segment
		(start 190.800228 -78.534514)
		(end 188.643006 -76.377292)
		(width 0.11684)
		(layer "In2.Cu")
		(net "SMB_CPU0_CPU1_SEC_SCL")
	)
	(segment
		(start 190.800228 -80.141572)
		(end 190.800228 -78.534514)
		(width 0.11684)
		(layer "In2.Cu")
		(net "SMB_CPU0_CPU1_SEC_SCL")
	)
	(segment
		(start 189.888876 -81.052924)
		(end 190.800228 -80.141572)
		(width 0.11684)
		(layer "In2.Cu")
		(net "SMB_CPU0_CPU1_SEC_SCL")
	)
	(segment
		(start 170.858688 -22.012656)
		(end 172.027342 -20.844002)
		(width 0.11684)
		(layer "In2.Cu")
		(net "SMB_CPU0_CPU1_SEC_SCL")
	)
	(segment
		(start 188.643006 -43.549316)
		(end 182.423816 -37.330126)
		(width 0.11684)
		(layer "In2.Cu")
		(net "SMB_CPU0_CPU1_SEC_SCL")
	)
	(segment
		(start 170.858688 -30.197044)
		(end 170.858688 -22.012656)
		(width 0.11684)
		(layer "In2.Cu")
		(net "SMB_CPU0_CPU1_SEC_SCL")
	)
	(segment
		(start 172.027342 -19.727164)
		(end 172.413422 -19.341084)
		(width 0.11684)
		(layer "In2.Cu")
		(net "SMB_CPU0_CPU1_SEC_SCL")
	)
	(segment
		(start 172.413422 -19.341084)
		(end 172.413422 -17.491202)
		(width 0.11684)
		(layer "In2.Cu")
		(net "SMB_CPU0_CPU1_SEC_SCL")
	)
	(segment
		(start 172.413422 -17.491202)
		(end 173.509686 -16.394938)
		(width 0.11684)
		(layer "In2.Cu")
		(net "SMB_CPU0_CPU1_SEC_SCL")
	)
	(segment
		(start 188.643006 -76.377292)
		(end 188.643006 -43.549316)
		(width 0.11684)
		(layer "In2.Cu")
		(net "SMB_CPU0_CPU1_SEC_SCL")
	)
	(segment
		(start 177.99177 -37.330126)
		(end 170.858688 -30.197044)
		(width 0.11684)
		(layer "In2.Cu")
		(net "SMB_CPU0_CPU1_SEC_SCL")
	)
	(segment
		(start 182.423816 -37.330126)
		(end 177.99177 -37.330126)
		(width 0.11684)
		(layer "In2.Cu")
		(net "SMB_CPU0_CPU1_SEC_SCL")
	)
	(segment
		(start 224.311718 -159.284924)
		(end 224.311718 -148.971762)
		(width 0.10668)
		(layer "F.Cu")
		(net "SMB_CPU0_CPU1_APML_SDA")
	)
	(segment
		(start 220.628718 -90.74404)
		(end 213.617302 -90.74404)
		(width 0.10668)
		(layer "F.Cu")
		(net "SMB_CPU0_CPU1_APML_SDA")
	)
	(segment
		(start 226.05365 -212.953346)
		(end 226.05365 -205.920594)
		(width 0.10668)
		(layer "F.Cu")
		(net "SMB_CPU0_CPU1_APML_SDA")
	)
	(segment
		(start 235.458 -222.357696)
		(end 226.05365 -212.953346)
		(width 0.10668)
		(layer "F.Cu")
		(net "SMB_CPU0_CPU1_APML_SDA")
	)
	(segment
		(start 213.617302 -90.74404)
		(end 208.856834 -85.983572)
		(width 0.10668)
		(layer "F.Cu")
		(net "SMB_CPU0_CPU1_APML_SDA")
	)
	(segment
		(start 226.05365 -205.920594)
		(end 229.29215 -202.682094)
		(width 0.10668)
		(layer "F.Cu")
		(net "SMB_CPU0_CPU1_APML_SDA")
	)
	(segment
		(start 226.73437 -140.416026)
		(end 226.836986 -140.168122)
		(width 0.10668)
		(layer "F.Cu")
		(net "SMB_CPU0_CPU1_APML_SDA")
	)
	(segment
		(start 234.442 -227.457)
		(end 235.458 -226.441)
		(width 0.10668)
		(layer "F.Cu")
		(net "SMB_CPU0_CPU1_APML_SDA")
	)
	(segment
		(start 224.311718 -148.971762)
		(end 226.73437 -146.54911)
		(width 0.10668)
		(layer "F.Cu")
		(net "SMB_CPU0_CPU1_APML_SDA")
	)
	(segment
		(start 226.73437 -146.54911)
		(end 226.73437 -140.416026)
		(width 0.10668)
		(layer "F.Cu")
		(net "SMB_CPU0_CPU1_APML_SDA")
	)
	(segment
		(start 207.046068 -85.983572)
		(end 206.26578 -86.76386)
		(width 0.10668)
		(layer "F.Cu")
		(net "SMB_CPU0_CPU1_APML_SDA")
	)
	(segment
		(start 223.776286 -120.447054)
		(end 223.776286 -118.753128)
		(width 0.10668)
		(layer "F.Cu")
		(net "SMB_CPU0_CPU1_APML_SDA")
	)
	(segment
		(start 229.29215 -164.265356)
		(end 224.311718 -159.284924)
		(width 0.10668)
		(layer "F.Cu")
		(net "SMB_CPU0_CPU1_APML_SDA")
	)
	(segment
		(start 235.458 -226.441)
		(end 235.458 -222.357696)
		(width 0.10668)
		(layer "F.Cu")
		(net "SMB_CPU0_CPU1_APML_SDA")
	)
	(segment
		(start 225.667316 -95.782638)
		(end 220.628718 -90.74404)
		(width 0.10668)
		(layer "F.Cu")
		(net "SMB_CPU0_CPU1_APML_SDA")
	)
	(segment
		(start 225.667316 -116.862098)
		(end 225.667316 -95.782638)
		(width 0.10668)
		(layer "F.Cu")
		(net "SMB_CPU0_CPU1_APML_SDA")
	)
	(segment
		(start 229.29215 -202.682094)
		(end 229.29215 -164.265356)
		(width 0.10668)
		(layer "F.Cu")
		(net "SMB_CPU0_CPU1_APML_SDA")
	)
	(segment
		(start 226.836986 -140.168122)
		(end 226.836986 -123.507754)
		(width 0.10668)
		(layer "F.Cu")
		(net "SMB_CPU0_CPU1_APML_SDA")
	)
	(segment
		(start 208.856834 -85.983572)
		(end 207.046068 -85.983572)
		(width 0.10668)
		(layer "F.Cu")
		(net "SMB_CPU0_CPU1_APML_SDA")
	)
	(segment
		(start 223.776286 -118.753128)
		(end 225.667316 -116.862098)
		(width 0.10668)
		(layer "F.Cu")
		(net "SMB_CPU0_CPU1_APML_SDA")
	)
	(segment
		(start 226.836986 -123.507754)
		(end 223.776286 -120.447054)
		(width 0.10668)
		(layer "F.Cu")
		(net "SMB_CPU0_CPU1_APML_SDA")
	)
	(via
		(at 181.03215 -21.517356)
		(size 0.508)
		(drill 0.254)
		(layers "F.Cu" "B.Cu")
		(net "SMB_CPU0_CPU1_APML_SDA")
	)
	(via
		(at 234.442 -227.457)
		(size 0.508)
		(drill 0.254)
		(layers "F.Cu" "B.Cu")
		(net "SMB_CPU0_CPU1_APML_SDA")
	)
	(via
		(at 206.26578 -86.76386)
		(size 0.508)
		(drill 0.254)
		(layers "F.Cu" "B.Cu")
		(net "SMB_CPU0_CPU1_APML_SDA")
	)
	(segment
		(start 234.08005 -227.81895)
		(end 234.442 -227.457)
		(width 0.10668)
		(layer "B.Cu")
		(net "SMB_CPU0_CPU1_APML_SDA")
	)
	(segment
		(start 234.08005 -228.092)
		(end 234.08005 -227.81895)
		(width 0.10668)
		(layer "B.Cu")
		(net "SMB_CPU0_CPU1_APML_SDA")
	)
	(segment
		(start 180.509164 -22.040342)
		(end 181.03215 -21.517356)
		(width 0.10668)
		(layer "B.Cu")
		(net "SMB_CPU0_CPU1_APML_SDA")
	)
	(segment
		(start 180.858922 -20.778216)
		(end 180.858922 -21.344128)
		(width 0.10668)
		(layer "B.Cu")
		(net "SMB_CPU0_CPU1_APML_SDA")
	)
	(segment
		(start 180.509164 -23.255732)
		(end 180.509164 -22.040342)
		(width 0.10668)
		(layer "B.Cu")
		(net "SMB_CPU0_CPU1_APML_SDA")
	)
	(segment
		(start 180.858922 -21.344128)
		(end 181.03215 -21.517356)
		(width 0.10668)
		(layer "B.Cu")
		(net "SMB_CPU0_CPU1_APML_SDA")
	)
	(segment
		(start 189.81674 -35.398964)
		(end 189.81674 -33.48736)
		(width 0.11684)
		(layer "In4.Cu")
		(net "SMB_CPU0_CPU1_APML_SDA")
	)
	(segment
		(start 198.805292 -49.017682)
		(end 199.862186 -47.960788)
		(width 0.11684)
		(layer "In4.Cu")
		(net "SMB_CPU0_CPU1_APML_SDA")
	)
	(segment
		(start 198.087234 -35.829494)
		(end 192.56502 -35.829494)
		(width 0.11684)
		(layer "In4.Cu")
		(net "SMB_CPU0_CPU1_APML_SDA")
	)
	(segment
		(start 207.516984 -71.400924)
		(end 207.516984 -67.516756)
		(width 0.11684)
		(layer "In4.Cu")
		(net "SMB_CPU0_CPU1_APML_SDA")
	)
	(segment
		(start 207.516984 -67.516756)
		(end 198.805292 -58.805064)
		(width 0.11684)
		(layer "In4.Cu")
		(net "SMB_CPU0_CPU1_APML_SDA")
	)
	(segment
		(start 199.862186 -47.960788)
		(end 199.862186 -37.604446)
		(width 0.11684)
		(layer "In4.Cu")
		(net "SMB_CPU0_CPU1_APML_SDA")
	)
	(segment
		(start 198.805292 -58.805064)
		(end 198.805292 -49.017682)
		(width 0.11684)
		(layer "In4.Cu")
		(net "SMB_CPU0_CPU1_APML_SDA")
	)
	(segment
		(start 192.56502 -35.829494)
		(end 192.280032 -36.114482)
		(width 0.11684)
		(layer "In4.Cu")
		(net "SMB_CPU0_CPU1_APML_SDA")
	)
	(segment
		(start 206.25689 -86.667086)
		(end 206.25689 -72.661018)
		(width 0.11684)
		(layer "In4.Cu")
		(net "SMB_CPU0_CPU1_APML_SDA")
	)
	(segment
		(start 206.26578 -86.675976)
		(end 206.25689 -86.667086)
		(width 0.11684)
		(layer "In4.Cu")
		(net "SMB_CPU0_CPU1_APML_SDA")
	)
	(segment
		(start 189.81674 -33.48736)
		(end 183.326278 -26.996898)
		(width 0.11684)
		(layer "In4.Cu")
		(net "SMB_CPU0_CPU1_APML_SDA")
	)
	(segment
		(start 181.03215 -23.168356)
		(end 181.03215 -21.517356)
		(width 0.11684)
		(layer "In4.Cu")
		(net "SMB_CPU0_CPU1_APML_SDA")
	)
	(segment
		(start 183.326278 -25.462484)
		(end 181.03215 -23.168356)
		(width 0.11684)
		(layer "In4.Cu")
		(net "SMB_CPU0_CPU1_APML_SDA")
	)
	(segment
		(start 206.25689 -72.661018)
		(end 207.516984 -71.400924)
		(width 0.11684)
		(layer "In4.Cu")
		(net "SMB_CPU0_CPU1_APML_SDA")
	)
	(segment
		(start 183.326278 -26.996898)
		(end 183.326278 -25.462484)
		(width 0.11684)
		(layer "In4.Cu")
		(net "SMB_CPU0_CPU1_APML_SDA")
	)
	(segment
		(start 206.26578 -86.76386)
		(end 206.26578 -86.675976)
		(width 0.11684)
		(layer "In4.Cu")
		(net "SMB_CPU0_CPU1_APML_SDA")
	)
	(segment
		(start 192.280032 -36.114482)
		(end 190.532258 -36.114482)
		(width 0.11684)
		(layer "In4.Cu")
		(net "SMB_CPU0_CPU1_APML_SDA")
	)
	(segment
		(start 190.532258 -36.114482)
		(end 189.81674 -35.398964)
		(width 0.11684)
		(layer "In4.Cu")
		(net "SMB_CPU0_CPU1_APML_SDA")
	)
	(segment
		(start 199.862186 -37.604446)
		(end 198.087234 -35.829494)
		(width 0.11684)
		(layer "In4.Cu")
		(net "SMB_CPU0_CPU1_APML_SDA")
	)
	(segment
		(start 223.971358 -148.830538)
		(end 223.971358 -159.426148)
		(width 0.10668)
		(layer "F.Cu")
		(net "SMB_CPU0_CPU1_APML_SCL")
	)
	(segment
		(start 226.478592 -140.143738)
		(end 226.39401 -140.22832)
		(width 0.10668)
		(layer "F.Cu")
		(net "SMB_CPU0_CPU1_APML_SCL")
	)
	(segment
		(start 225.326956 -95.923862)
		(end 225.326956 -116.720874)
		(width 0.10668)
		(layer "F.Cu")
		(net "SMB_CPU0_CPU1_APML_SCL")
	)
	(segment
		(start 208.71561 -86.323932)
		(end 213.476078 -91.0844)
		(width 0.10668)
		(layer "F.Cu")
		(net "SMB_CPU0_CPU1_APML_SCL")
	)
	(segment
		(start 207.322928 -86.762336)
		(end 207.761332 -86.323932)
		(width 0.10668)
		(layer "F.Cu")
		(net "SMB_CPU0_CPU1_APML_SCL")
	)
	(segment
		(start 228.95179 -164.40658)
		(end 228.95179 -202.530964)
		(width 0.10668)
		(layer "F.Cu")
		(net "SMB_CPU0_CPU1_APML_SCL")
	)
	(segment
		(start 220.487494 -91.0844)
		(end 225.326956 -95.923862)
		(width 0.10668)
		(layer "F.Cu")
		(net "SMB_CPU0_CPU1_APML_SCL")
	)
	(segment
		(start 225.326956 -116.720874)
		(end 223.435926 -118.611904)
		(width 0.10668)
		(layer "F.Cu")
		(net "SMB_CPU0_CPU1_APML_SCL")
	)
	(segment
		(start 223.971358 -159.426148)
		(end 228.95179 -164.40658)
		(width 0.10668)
		(layer "F.Cu")
		(net "SMB_CPU0_CPU1_APML_SCL")
	)
	(segment
		(start 223.435926 -120.588278)
		(end 226.478592 -123.630944)
		(width 0.10668)
		(layer "F.Cu")
		(net "SMB_CPU0_CPU1_APML_SCL")
	)
	(segment
		(start 226.39401 -146.407886)
		(end 223.971358 -148.830538)
		(width 0.10668)
		(layer "F.Cu")
		(net "SMB_CPU0_CPU1_APML_SCL")
	)
	(segment
		(start 234.95 -226.187)
		(end 233.68 -227.457)
		(width 0.10668)
		(layer "F.Cu")
		(net "SMB_CPU0_CPU1_APML_SCL")
	)
	(segment
		(start 223.435926 -118.611904)
		(end 223.435926 -120.588278)
		(width 0.10668)
		(layer "F.Cu")
		(net "SMB_CPU0_CPU1_APML_SCL")
	)
	(segment
		(start 207.761332 -86.323932)
		(end 208.71561 -86.323932)
		(width 0.10668)
		(layer "F.Cu")
		(net "SMB_CPU0_CPU1_APML_SCL")
	)
	(segment
		(start 225.71329 -213.108032)
		(end 234.95 -222.344742)
		(width 0.10668)
		(layer "F.Cu")
		(net "SMB_CPU0_CPU1_APML_SCL")
	)
	(segment
		(start 226.39401 -140.22832)
		(end 226.39401 -146.407886)
		(width 0.10668)
		(layer "F.Cu")
		(net "SMB_CPU0_CPU1_APML_SCL")
	)
	(segment
		(start 228.95179 -202.530964)
		(end 225.71329 -205.769464)
		(width 0.10668)
		(layer "F.Cu")
		(net "SMB_CPU0_CPU1_APML_SCL")
	)
	(segment
		(start 226.478592 -123.630944)
		(end 226.478592 -140.143738)
		(width 0.10668)
		(layer "F.Cu")
		(net "SMB_CPU0_CPU1_APML_SCL")
	)
	(segment
		(start 234.95 -222.344742)
		(end 234.95 -226.187)
		(width 0.10668)
		(layer "F.Cu")
		(net "SMB_CPU0_CPU1_APML_SCL")
	)
	(segment
		(start 225.71329 -205.769464)
		(end 225.71329 -213.108032)
		(width 0.10668)
		(layer "F.Cu")
		(net "SMB_CPU0_CPU1_APML_SCL")
	)
	(segment
		(start 213.476078 -91.0844)
		(end 220.487494 -91.0844)
		(width 0.10668)
		(layer "F.Cu")
		(net "SMB_CPU0_CPU1_APML_SCL")
	)
	(via
		(at 207.322928 -86.762336)
		(size 0.762)
		(drill 0.254)
		(layers "F.Cu" "B.Cu")
		(net "SMB_CPU0_CPU1_APML_SCL")
	)
	(via
		(at 181.79923 -21.9202)
		(size 0.508)
		(drill 0.254)
		(layers "F.Cu" "B.Cu")
		(net "SMB_CPU0_CPU1_APML_SCL")
	)
	(via
		(at 233.68 -227.457)
		(size 0.508)
		(drill 0.254)
		(layers "F.Cu" "B.Cu")
		(net "SMB_CPU0_CPU1_APML_SCL")
	)
	(segment
		(start 234.08005 -227.05695)
		(end 233.68 -227.457)
		(width 0.10668)
		(layer "B.Cu")
		(net "SMB_CPU0_CPU1_APML_SCL")
	)
	(segment
		(start 181.79923 -22.572726)
		(end 181.79923 -21.9202)
		(width 0.10668)
		(layer "B.Cu")
		(net "SMB_CPU0_CPU1_APML_SCL")
	)
	(segment
		(start 181.525164 -22.846792)
		(end 181.79923 -22.572726)
		(width 0.10668)
		(layer "B.Cu")
		(net "SMB_CPU0_CPU1_APML_SCL")
	)
	(segment
		(start 234.08005 -226.822)
		(end 234.08005 -227.05695)
		(width 0.10668)
		(layer "B.Cu")
		(net "SMB_CPU0_CPU1_APML_SCL")
	)
	(segment
		(start 181.525164 -23.255732)
		(end 181.525164 -22.846792)
		(width 0.10668)
		(layer "B.Cu")
		(net "SMB_CPU0_CPU1_APML_SCL")
	)
	(segment
		(start 181.872382 -20.778216)
		(end 181.872382 -21.847048)
		(width 0.10668)
		(layer "B.Cu")
		(net "SMB_CPU0_CPU1_APML_SCL")
	)
	(segment
		(start 181.872382 -21.847048)
		(end 181.79923 -21.9202)
		(width 0.10668)
		(layer "B.Cu")
		(net "SMB_CPU0_CPU1_APML_SCL")
	)
	(segment
		(start 200.296272 -48.14062)
		(end 200.296272 -37.441886)
		(width 0.11684)
		(layer "In4.Cu")
		(net "SMB_CPU0_CPU1_APML_SCL")
	)
	(segment
		(start 181.79923 -23.038816)
		(end 181.79923 -21.9202)
		(width 0.11684)
		(layer "In4.Cu")
		(net "SMB_CPU0_CPU1_APML_SCL")
	)
	(segment
		(start 198.249794 -35.395408)
		(end 192.385188 -35.395408)
		(width 0.11684)
		(layer "In4.Cu")
		(net "SMB_CPU0_CPU1_APML_SCL")
	)
	(segment
		(start 200.296272 -37.441886)
		(end 198.249794 -35.395408)
		(width 0.11684)
		(layer "In4.Cu")
		(net "SMB_CPU0_CPU1_APML_SCL")
	)
	(segment
		(start 206.67853 -86.117938)
		(end 206.67853 -73.935082)
		(width 0.11684)
		(layer "In4.Cu")
		(net "SMB_CPU0_CPU1_APML_SCL")
	)
	(segment
		(start 207.322928 -86.762336)
		(end 206.67853 -86.117938)
		(width 0.11684)
		(layer "In4.Cu")
		(net "SMB_CPU0_CPU1_APML_SCL")
	)
	(segment
		(start 199.226932 -49.20996)
		(end 200.296272 -48.14062)
		(width 0.11684)
		(layer "In4.Cu")
		(net "SMB_CPU0_CPU1_APML_SCL")
	)
	(segment
		(start 192.1002 -35.680396)
		(end 190.71463 -35.680396)
		(width 0.11684)
		(layer "In4.Cu")
		(net "SMB_CPU0_CPU1_APML_SCL")
	)
	(segment
		(start 199.226932 -58.630058)
		(end 199.226932 -49.20996)
		(width 0.11684)
		(layer "In4.Cu")
		(net "SMB_CPU0_CPU1_APML_SCL")
	)
	(segment
		(start 183.79948 -25.039066)
		(end 181.79923 -23.038816)
		(width 0.11684)
		(layer "In4.Cu")
		(net "SMB_CPU0_CPU1_APML_SCL")
	)
	(segment
		(start 192.385188 -35.395408)
		(end 192.1002 -35.680396)
		(width 0.11684)
		(layer "In4.Cu")
		(net "SMB_CPU0_CPU1_APML_SCL")
	)
	(segment
		(start 206.67853 -73.935082)
		(end 207.987392 -72.62622)
		(width 0.11684)
		(layer "In4.Cu")
		(net "SMB_CPU0_CPU1_APML_SCL")
	)
	(segment
		(start 207.987392 -72.62622)
		(end 207.987392 -67.390518)
		(width 0.11684)
		(layer "In4.Cu")
		(net "SMB_CPU0_CPU1_APML_SCL")
	)
	(segment
		(start 190.246 -33.319974)
		(end 183.79948 -26.873454)
		(width 0.11684)
		(layer "In4.Cu")
		(net "SMB_CPU0_CPU1_APML_SCL")
	)
	(segment
		(start 207.987392 -67.390518)
		(end 199.226932 -58.630058)
		(width 0.11684)
		(layer "In4.Cu")
		(net "SMB_CPU0_CPU1_APML_SCL")
	)
	(segment
		(start 183.79948 -26.873454)
		(end 183.79948 -25.039066)
		(width 0.11684)
		(layer "In4.Cu")
		(net "SMB_CPU0_CPU1_APML_SCL")
	)
	(segment
		(start 190.71463 -35.680396)
		(end 190.246 -35.211766)
		(width 0.11684)
		(layer "In4.Cu")
		(net "SMB_CPU0_CPU1_APML_SCL")
	)
	(segment
		(start 190.246 -35.211766)
		(end 190.246 -33.319974)
		(width 0.11684)
		(layer "In4.Cu")
		(net "SMB_CPU0_CPU1_APML_SCL")
	)
	(segment
		(start 294.021002 -114.221514)
		(end 293.490142 -114.221514)
		(width 0.10668)
		(layer "F.Cu")
		(net "SMB_BMC_SWB_SDA_R4")
	)
	(segment
		(start 292.618922 -115.092734)
		(end 291.032438 -115.092734)
		(width 0.10668)
		(layer "F.Cu")
		(net "SMB_BMC_SWB_SDA_R4")
	)
	(segment
		(start 293.490142 -114.221514)
		(end 292.618922 -115.092734)
		(width 0.10668)
		(layer "F.Cu")
		(net "SMB_BMC_SWB_SDA_R4")
	)
	(segment
		(start 291.032438 -115.092734)
		(end 290.493196 -115.631976)
		(width 0.10668)
		(layer "F.Cu")
		(net "SMB_BMC_SWB_SDA_R4")
	)
	(segment
		(start 290.493196 -115.631976)
		(end 289.728148 -115.631976)
		(width 0.10668)
		(layer "F.Cu")
		(net "SMB_BMC_SWB_SDA_R4")
	)
	(via
		(at 292.618922 -115.092734)
		(size 0.762)
		(drill 0.381)
		(layers "F.Cu" "B.Cu")
		(net "SMB_BMC_SWB_SDA_R4")
	)
	(segment
		(start 233.604816 -206.65567)
		(end 233.498136 -206.54899)
		(width 0.10668)
		(layer "F.Cu")
		(net "SMB_BMC_SWB_SDA")
	)
	(segment
		(start 299.29836 -112.073436)
		(end 298.968414 -111.74349)
		(width 0.10668)
		(layer "F.Cu")
		(net "SMB_BMC_SWB_SDA")
	)
	(segment
		(start 238.560864 -168.850818)
		(end 238.560864 -176.894236)
		(width 0.10668)
		(layer "F.Cu")
		(net "SMB_BMC_SWB_SDA")
	)
	(segment
		(start 231.485186 -207.955134)
		(end 230.723186 -207.193134)
		(width 0.10668)
		(layer "F.Cu")
		(net "SMB_BMC_SWB_SDA")
	)
	(segment
		(start 237.089696 -206.65567)
		(end 236.983016 -206.54899)
		(width 0.10668)
		(layer "F.Cu")
		(net "SMB_BMC_SWB_SDA")
	)
	(segment
		(start 237.089696 -207.848454)
		(end 237.089696 -206.65567)
		(width 0.10668)
		(layer "F.Cu")
		(net "SMB_BMC_SWB_SDA")
	)
	(segment
		(start 297.697398 -111.74349)
		(end 297.086274 -112.354614)
		(width 0.10668)
		(layer "F.Cu")
		(net "SMB_BMC_SWB_SDA")
	)
	(segment
		(start 298.968414 -111.74349)
		(end 297.697398 -111.74349)
		(width 0.10668)
		(layer "F.Cu")
		(net "SMB_BMC_SWB_SDA")
	)
	(segment
		(start 237.196376 -207.955134)
		(end 237.089696 -207.848454)
		(width 0.10668)
		(layer "F.Cu")
		(net "SMB_BMC_SWB_SDA")
	)
	(segment
		(start 166.982648 -433.615338)
		(end 167.324786 -433.615338)
		(width 0.10668)
		(layer "F.Cu")
		(net "SMB_BMC_SWB_SDA")
	)
	(segment
		(start 232.840276 -206.54899)
		(end 232.733596 -206.65567)
		(width 0.10668)
		(layer "F.Cu")
		(net "SMB_BMC_SWB_SDA")
	)
	(segment
		(start 235.240576 -206.54899)
		(end 234.582716 -206.54899)
		(width 0.10668)
		(layer "F.Cu")
		(net "SMB_BMC_SWB_SDA")
	)
	(segment
		(start 234.476036 -206.65567)
		(end 234.476036 -207.848454)
		(width 0.10668)
		(layer "F.Cu")
		(net "SMB_BMC_SWB_SDA")
	)
	(segment
		(start 236.983016 -206.54899)
		(end 236.325156 -206.54899)
		(width 0.10668)
		(layer "F.Cu")
		(net "SMB_BMC_SWB_SDA")
	)
	(segment
		(start 234.476036 -207.848454)
		(end 234.369356 -207.955134)
		(width 0.10668)
		(layer "F.Cu")
		(net "SMB_BMC_SWB_SDA")
	)
	(segment
		(start 232.733596 -206.65567)
		(end 232.733596 -207.848454)
		(width 0.10668)
		(layer "F.Cu")
		(net "SMB_BMC_SWB_SDA")
	)
	(segment
		(start 235.347256 -206.65567)
		(end 235.240576 -206.54899)
		(width 0.10668)
		(layer "F.Cu")
		(net "SMB_BMC_SWB_SDA")
	)
	(segment
		(start 244.19306 -190.493904)
		(end 244.19306 -205.66253)
		(width 0.10668)
		(layer "F.Cu")
		(net "SMB_BMC_SWB_SDA")
	)
	(segment
		(start 238.560864 -176.894236)
		(end 244.19306 -190.493904)
		(width 0.10668)
		(layer "F.Cu")
		(net "SMB_BMC_SWB_SDA")
	)
	(segment
		(start 233.604816 -207.848454)
		(end 233.604816 -206.65567)
		(width 0.10668)
		(layer "F.Cu")
		(net "SMB_BMC_SWB_SDA")
	)
	(segment
		(start 294.821102 -114.221514)
		(end 295.219374 -114.221514)
		(width 0.10668)
		(layer "F.Cu")
		(net "SMB_BMC_SWB_SDA")
	)
	(segment
		(start 236.325156 -206.54899)
		(end 236.218476 -206.65567)
		(width 0.10668)
		(layer "F.Cu")
		(net "SMB_BMC_SWB_SDA")
	)
	(segment
		(start 236.218476 -206.65567)
		(end 236.218476 -207.848454)
		(width 0.10668)
		(layer "F.Cu")
		(net "SMB_BMC_SWB_SDA")
	)
	(segment
		(start 295.219374 -114.221514)
		(end 297.086274 -112.354614)
		(width 0.10668)
		(layer "F.Cu")
		(net "SMB_BMC_SWB_SDA")
	)
	(segment
		(start 236.218476 -207.848454)
		(end 236.111796 -207.955134)
		(width 0.10668)
		(layer "F.Cu")
		(net "SMB_BMC_SWB_SDA")
	)
	(segment
		(start 232.626916 -207.955134)
		(end 231.485186 -207.955134)
		(width 0.10668)
		(layer "F.Cu")
		(net "SMB_BMC_SWB_SDA")
	)
	(segment
		(start 234.582716 -206.54899)
		(end 234.476036 -206.65567)
		(width 0.10668)
		(layer "F.Cu")
		(net "SMB_BMC_SWB_SDA")
	)
	(segment
		(start 235.453936 -207.955134)
		(end 235.347256 -207.848454)
		(width 0.10668)
		(layer "F.Cu")
		(net "SMB_BMC_SWB_SDA")
	)
	(segment
		(start 235.347256 -207.848454)
		(end 235.347256 -206.65567)
		(width 0.10668)
		(layer "F.Cu")
		(net "SMB_BMC_SWB_SDA")
	)
	(segment
		(start 232.733596 -207.848454)
		(end 232.626916 -207.955134)
		(width 0.10668)
		(layer "F.Cu")
		(net "SMB_BMC_SWB_SDA")
	)
	(segment
		(start 299.29836 -112.327436)
		(end 299.29836 -112.073436)
		(width 0.10668)
		(layer "F.Cu")
		(net "SMB_BMC_SWB_SDA")
	)
	(segment
		(start 234.369356 -207.955134)
		(end 233.711496 -207.955134)
		(width 0.10668)
		(layer "F.Cu")
		(net "SMB_BMC_SWB_SDA")
	)
	(segment
		(start 230.723186 -207.193134)
		(end 230.222298 -207.193134)
		(width 0.10668)
		(layer "F.Cu")
		(net "SMB_BMC_SWB_SDA")
	)
	(segment
		(start 244.19306 -205.66253)
		(end 241.900456 -207.955134)
		(width 0.10668)
		(layer "F.Cu")
		(net "SMB_BMC_SWB_SDA")
	)
	(segment
		(start 233.498136 -206.54899)
		(end 232.840276 -206.54899)
		(width 0.10668)
		(layer "F.Cu")
		(net "SMB_BMC_SWB_SDA")
	)
	(segment
		(start 233.711496 -207.955134)
		(end 233.604816 -207.848454)
		(width 0.10668)
		(layer "F.Cu")
		(net "SMB_BMC_SWB_SDA")
	)
	(segment
		(start 241.900456 -207.955134)
		(end 237.196376 -207.955134)
		(width 0.10668)
		(layer "F.Cu")
		(net "SMB_BMC_SWB_SDA")
	)
	(segment
		(start 166.71925 -433.878736)
		(end 166.982648 -433.615338)
		(width 0.10668)
		(layer "F.Cu")
		(net "SMB_BMC_SWB_SDA")
	)
	(segment
		(start 236.111796 -207.955134)
		(end 235.453936 -207.955134)
		(width 0.10668)
		(layer "F.Cu")
		(net "SMB_BMC_SWB_SDA")
	)
	(via
		(at 299.29836 -112.327436)
		(size 0.508)
		(drill 0.254)
		(layers "F.Cu" "B.Cu")
		(net "SMB_BMC_SWB_SDA")
	)
	(via
		(at 167.324786 -433.615338)
		(size 0.508)
		(drill 0.254)
		(layers "F.Cu" "B.Cu")
		(net "SMB_BMC_SWB_SDA")
	)
	(via
		(at 230.222298 -207.193134)
		(size 0.508)
		(drill 0.254)
		(layers "F.Cu" "B.Cu")
		(net "SMB_BMC_SWB_SDA")
	)
	(via
		(at 238.560864 -168.850818)
		(size 0.508)
		(drill 0.254)
		(layers "F.Cu" "B.Cu")
		(net "SMB_BMC_SWB_SDA")
	)
	(segment
		(start 171.342304 -389.131556)
		(end 172.339254 -389.131556)
		(width 0.11684)
		(layer "In4.Cu")
		(net "SMB_BMC_SWB_SDA")
	)
	(segment
		(start 167.775128 -415.247074)
		(end 166.111936 -415.247074)
		(width 0.11684)
		(layer "In4.Cu")
		(net "SMB_BMC_SWB_SDA")
	)
	(segment
		(start 163.477194 -408.417268)
		(end 161.975546 -408.417268)
		(width 0.11684)
		(layer "In4.Cu")
		(net "SMB_BMC_SWB_SDA")
	)
	(segment
		(start 250.304554 -157.107128)
		(end 263.163304 -157.107128)
		(width 0.11684)
		(layer "In4.Cu")
		(net "SMB_BMC_SWB_SDA")
	)
	(segment
		(start 161.230564 -406.68321)
		(end 163.628324 -404.28545)
		(width 0.11684)
		(layer "In4.Cu")
		(net "SMB_BMC_SWB_SDA")
	)
	(segment
		(start 229.800658 -207.193134)
		(end 230.222298 -207.193134)
		(width 0.11684)
		(layer "In4.Cu")
		(net "SMB_BMC_SWB_SDA")
	)
	(segment
		(start 164.348922 -409.288996)
		(end 163.477194 -408.417268)
		(width 0.11684)
		(layer "In4.Cu")
		(net "SMB_BMC_SWB_SDA")
	)
	(segment
		(start 238.560864 -168.850818)
		(end 250.304554 -157.107128)
		(width 0.11684)
		(layer "In4.Cu")
		(net "SMB_BMC_SWB_SDA")
	)
	(segment
		(start 170.875452 -396.979902)
		(end 171.230798 -396.624556)
		(width 0.11684)
		(layer "In4.Cu")
		(net "SMB_BMC_SWB_SDA")
	)
	(segment
		(start 221.652846 -253.964186)
		(end 221.652846 -215.340946)
		(width 0.11684)
		(layer "In4.Cu")
		(net "SMB_BMC_SWB_SDA")
	)
	(segment
		(start 207.427322 -362.93552)
		(end 207.427322 -360.008678)
		(width 0.11684)
		(layer "In4.Cu")
		(net "SMB_BMC_SWB_SDA")
	)
	(segment
		(start 174.719234 -388.220966)
		(end 185.169048 -377.771152)
		(width 0.11684)
		(layer "In4.Cu")
		(net "SMB_BMC_SWB_SDA")
	)
	(segment
		(start 161.230564 -407.672286)
		(end 161.230564 -406.68321)
		(width 0.11684)
		(layer "In4.Cu")
		(net "SMB_BMC_SWB_SDA")
	)
	(segment
		(start 169.065956 -416.537902)
		(end 167.775128 -415.247074)
		(width 0.11684)
		(layer "In4.Cu")
		(net "SMB_BMC_SWB_SDA")
	)
	(segment
		(start 215.055196 -260.561836)
		(end 221.652846 -253.964186)
		(width 0.11684)
		(layer "In4.Cu")
		(net "SMB_BMC_SWB_SDA")
	)
	(segment
		(start 168.211246 -423.188892)
		(end 168.211246 -419.631114)
		(width 0.11684)
		(layer "In4.Cu")
		(net "SMB_BMC_SWB_SDA")
	)
	(segment
		(start 207.427322 -360.008678)
		(end 224.634552 -342.801448)
		(width 0.11684)
		(layer "In4.Cu")
		(net "SMB_BMC_SWB_SDA")
	)
	(segment
		(start 163.628324 -404.28545)
		(end 163.628324 -402.828252)
		(width 0.11684)
		(layer "In4.Cu")
		(net "SMB_BMC_SWB_SDA")
	)
	(segment
		(start 287.065212 -133.20522)
		(end 287.065212 -127.106426)
		(width 0.11684)
		(layer "In4.Cu")
		(net "SMB_BMC_SWB_SDA")
	)
	(segment
		(start 300.61154 -113.640616)
		(end 299.29836 -112.327436)
		(width 0.11684)
		(layer "In4.Cu")
		(net "SMB_BMC_SWB_SDA")
	)
	(segment
		(start 263.163304 -157.107128)
		(end 287.065212 -133.20522)
		(width 0.11684)
		(layer "In4.Cu")
		(net "SMB_BMC_SWB_SDA")
	)
	(segment
		(start 300.61154 -124.215398)
		(end 300.61154 -113.640616)
		(width 0.11684)
		(layer "In4.Cu")
		(net "SMB_BMC_SWB_SDA")
	)
	(segment
		(start 224.06356 -332.439772)
		(end 224.06356 -330.687426)
		(width 0.11684)
		(layer "In4.Cu")
		(net "SMB_BMC_SWB_SDA")
	)
	(segment
		(start 168.211246 -419.631114)
		(end 169.065956 -418.776404)
		(width 0.11684)
		(layer "In4.Cu")
		(net "SMB_BMC_SWB_SDA")
	)
	(segment
		(start 173.249844 -388.220966)
		(end 174.719234 -388.220966)
		(width 0.11684)
		(layer "In4.Cu")
		(net "SMB_BMC_SWB_SDA")
	)
	(segment
		(start 165.029642 -399.44548)
		(end 167.49522 -396.979902)
		(width 0.11684)
		(layer "In4.Cu")
		(net "SMB_BMC_SWB_SDA")
	)
	(segment
		(start 299.223176 -125.603762)
		(end 300.61154 -124.215398)
		(width 0.11684)
		(layer "In4.Cu")
		(net "SMB_BMC_SWB_SDA")
	)
	(segment
		(start 163.628324 -402.828252)
		(end 165.029642 -399.44548)
		(width 0.11684)
		(layer "In4.Cu")
		(net "SMB_BMC_SWB_SDA")
	)
	(segment
		(start 224.634552 -342.801448)
		(end 224.634552 -333.010764)
		(width 0.11684)
		(layer "In4.Cu")
		(net "SMB_BMC_SWB_SDA")
	)
	(segment
		(start 167.49522 -396.979902)
		(end 170.875452 -396.979902)
		(width 0.11684)
		(layer "In4.Cu")
		(net "SMB_BMC_SWB_SDA")
	)
	(segment
		(start 165.232334 -427.759622)
		(end 165.232334 -426.167804)
		(width 0.11684)
		(layer "In4.Cu")
		(net "SMB_BMC_SWB_SDA")
	)
	(segment
		(start 166.111936 -415.247074)
		(end 164.348922 -413.48406)
		(width 0.11684)
		(layer "In4.Cu")
		(net "SMB_BMC_SWB_SDA")
	)
	(segment
		(start 169.065956 -418.776404)
		(end 169.065956 -416.537902)
		(width 0.11684)
		(layer "In4.Cu")
		(net "SMB_BMC_SWB_SDA")
	)
	(segment
		(start 171.230798 -396.18031)
		(end 170.3451 -395.294612)
		(width 0.11684)
		(layer "In4.Cu")
		(net "SMB_BMC_SWB_SDA")
	)
	(segment
		(start 224.634552 -333.010764)
		(end 224.06356 -332.439772)
		(width 0.11684)
		(layer "In4.Cu")
		(net "SMB_BMC_SWB_SDA")
	)
	(segment
		(start 215.055196 -321.679062)
		(end 215.055196 -260.561836)
		(width 0.11684)
		(layer "In4.Cu")
		(net "SMB_BMC_SWB_SDA")
	)
	(segment
		(start 171.230798 -396.624556)
		(end 171.230798 -396.18031)
		(width 0.11684)
		(layer "In4.Cu")
		(net "SMB_BMC_SWB_SDA")
	)
	(segment
		(start 170.3451 -395.294612)
		(end 170.3451 -390.12876)
		(width 0.11684)
		(layer "In4.Cu")
		(net "SMB_BMC_SWB_SDA")
	)
	(segment
		(start 194.314064 -369.339114)
		(end 195.387468 -368.26571)
		(width 0.11684)
		(layer "In4.Cu")
		(net "SMB_BMC_SWB_SDA")
	)
	(segment
		(start 166.231316 -428.758604)
		(end 165.232334 -427.759622)
		(width 0.11684)
		(layer "In4.Cu")
		(net "SMB_BMC_SWB_SDA")
	)
	(segment
		(start 185.169048 -371.759988)
		(end 187.589922 -369.339114)
		(width 0.11684)
		(layer "In4.Cu")
		(net "SMB_BMC_SWB_SDA")
	)
	(segment
		(start 166.231316 -432.521868)
		(end 166.231316 -428.758604)
		(width 0.11684)
		(layer "In4.Cu")
		(net "SMB_BMC_SWB_SDA")
	)
	(segment
		(start 187.589922 -369.339114)
		(end 194.314064 -369.339114)
		(width 0.11684)
		(layer "In4.Cu")
		(net "SMB_BMC_SWB_SDA")
	)
	(segment
		(start 164.348922 -413.48406)
		(end 164.348922 -409.288996)
		(width 0.11684)
		(layer "In4.Cu")
		(net "SMB_BMC_SWB_SDA")
	)
	(segment
		(start 195.387468 -368.26571)
		(end 202.097132 -368.26571)
		(width 0.11684)
		(layer "In4.Cu")
		(net "SMB_BMC_SWB_SDA")
	)
	(segment
		(start 170.3451 -390.12876)
		(end 171.342304 -389.131556)
		(width 0.11684)
		(layer "In4.Cu")
		(net "SMB_BMC_SWB_SDA")
	)
	(segment
		(start 224.06356 -330.687426)
		(end 215.055196 -321.679062)
		(width 0.11684)
		(layer "In4.Cu")
		(net "SMB_BMC_SWB_SDA")
	)
	(segment
		(start 185.169048 -377.771152)
		(end 185.169048 -371.759988)
		(width 0.11684)
		(layer "In4.Cu")
		(net "SMB_BMC_SWB_SDA")
	)
	(segment
		(start 161.975546 -408.417268)
		(end 161.230564 -407.672286)
		(width 0.11684)
		(layer "In4.Cu")
		(net "SMB_BMC_SWB_SDA")
	)
	(segment
		(start 167.324786 -433.615338)
		(end 166.231316 -432.521868)
		(width 0.11684)
		(layer "In4.Cu")
		(net "SMB_BMC_SWB_SDA")
	)
	(segment
		(start 202.097132 -368.26571)
		(end 207.427322 -362.93552)
		(width 0.11684)
		(layer "In4.Cu")
		(net "SMB_BMC_SWB_SDA")
	)
	(segment
		(start 172.339254 -389.131556)
		(end 173.249844 -388.220966)
		(width 0.11684)
		(layer "In4.Cu")
		(net "SMB_BMC_SWB_SDA")
	)
	(segment
		(start 288.567876 -125.603762)
		(end 299.223176 -125.603762)
		(width 0.11684)
		(layer "In4.Cu")
		(net "SMB_BMC_SWB_SDA")
	)
	(segment
		(start 287.065212 -127.106426)
		(end 288.567876 -125.603762)
		(width 0.11684)
		(layer "In4.Cu")
		(net "SMB_BMC_SWB_SDA")
	)
	(segment
		(start 221.652846 -215.340946)
		(end 229.800658 -207.193134)
		(width 0.11684)
		(layer "In4.Cu")
		(net "SMB_BMC_SWB_SDA")
	)
	(segment
		(start 165.232334 -426.167804)
		(end 168.211246 -423.188892)
		(width 0.11684)
		(layer "In4.Cu")
		(net "SMB_BMC_SWB_SDA")
	)
	(segment
		(start 290.572444 -116.281962)
		(end 289.728148 -116.281962)
		(width 0.10668)
		(layer "F.Cu")
		(net "SMB_BMC_SWB_SCL_R4")
	)
	(segment
		(start 292.999922 -116.04117)
		(end 291.602922 -116.04117)
		(width 0.10668)
		(layer "F.Cu")
		(net "SMB_BMC_SWB_SCL_R4")
	)
	(segment
		(start 291.602922 -116.04117)
		(end 290.813236 -116.04117)
		(width 0.10668)
		(layer "F.Cu")
		(net "SMB_BMC_SWB_SCL_R4")
	)
	(segment
		(start 290.813236 -116.04117)
		(end 290.572444 -116.281962)
		(width 0.10668)
		(layer "F.Cu")
		(net "SMB_BMC_SWB_SCL_R4")
	)
	(segment
		(start 293.803578 -115.237514)
		(end 292.999922 -116.04117)
		(width 0.10668)
		(layer "F.Cu")
		(net "SMB_BMC_SWB_SCL_R4")
	)
	(segment
		(start 294.021002 -115.237514)
		(end 293.803578 -115.237514)
		(width 0.10668)
		(layer "F.Cu")
		(net "SMB_BMC_SWB_SCL_R4")
	)
	(via
		(at 291.602922 -116.04117)
		(size 0.762)
		(drill 0.381)
		(layers "F.Cu" "B.Cu")
		(net "SMB_BMC_SWB_SCL_R4")
	)
	(segment
		(start 297.086274 -113.377726)
		(end 297.086274 -113.751614)
		(width 0.10668)
		(layer "F.Cu")
		(net "SMB_BMC_SWB_SCL")
	)
	(segment
		(start 297.434 -113.03)
		(end 297.086274 -113.377726)
		(width 0.10668)
		(layer "F.Cu")
		(net "SMB_BMC_SWB_SCL")
	)
	(segment
		(start 295.600374 -115.237514)
		(end 297.086274 -113.751614)
		(width 0.10668)
		(layer "F.Cu")
		(net "SMB_BMC_SWB_SCL")
	)
	(segment
		(start 299.29836 -113.724436)
		(end 299.29836 -113.470436)
		(width 0.10668)
		(layer "F.Cu")
		(net "SMB_BMC_SWB_SCL")
	)
	(segment
		(start 294.821102 -115.237514)
		(end 295.600374 -115.237514)
		(width 0.10668)
		(layer "F.Cu")
		(net "SMB_BMC_SWB_SCL")
	)
	(segment
		(start 166.56685 -428.215044)
		(end 166.56685 -428.5996)
		(width 0.10668)
		(layer "F.Cu")
		(net "SMB_BMC_SWB_SCL")
	)
	(segment
		(start 298.857924 -113.03)
		(end 297.434 -113.03)
		(width 0.10668)
		(layer "F.Cu")
		(net "SMB_BMC_SWB_SCL")
	)
	(segment
		(start 299.29836 -113.470436)
		(end 298.857924 -113.03)
		(width 0.10668)
		(layer "F.Cu")
		(net "SMB_BMC_SWB_SCL")
	)
	(segment
		(start 241.74704 -208.590134)
		(end 230.222298 -208.590134)
		(width 0.10668)
		(layer "F.Cu")
		(net "SMB_BMC_SWB_SCL")
	)
	(segment
		(start 244.53342 -205.803754)
		(end 241.74704 -208.590134)
		(width 0.10668)
		(layer "F.Cu")
		(net "SMB_BMC_SWB_SCL")
	)
	(segment
		(start 165.901116 -427.54931)
		(end 166.56685 -428.215044)
		(width 0.10668)
		(layer "F.Cu")
		(net "SMB_BMC_SWB_SCL")
	)
	(segment
		(start 239.135412 -177.391822)
		(end 244.53342 -190.423038)
		(width 0.10668)
		(layer "F.Cu")
		(net "SMB_BMC_SWB_SCL")
	)
	(segment
		(start 239.135412 -169.836592)
		(end 239.135412 -177.391822)
		(width 0.10668)
		(layer "F.Cu")
		(net "SMB_BMC_SWB_SCL")
	)
	(segment
		(start 244.53342 -190.423038)
		(end 244.53342 -205.803754)
		(width 0.10668)
		(layer "F.Cu")
		(net "SMB_BMC_SWB_SCL")
	)
	(via
		(at 230.222298 -208.590134)
		(size 0.508)
		(drill 0.254)
		(layers "F.Cu" "B.Cu")
		(net "SMB_BMC_SWB_SCL")
	)
	(via
		(at 299.29836 -113.724436)
		(size 0.508)
		(drill 0.254)
		(layers "F.Cu" "B.Cu")
		(net "SMB_BMC_SWB_SCL")
	)
	(via
		(at 239.135412 -169.836592)
		(size 0.508)
		(drill 0.254)
		(layers "F.Cu" "B.Cu")
		(net "SMB_BMC_SWB_SCL")
	)
	(via
		(at 165.901116 -427.54931)
		(size 0.508)
		(drill 0.254)
		(layers "F.Cu" "B.Cu")
		(net "SMB_BMC_SWB_SCL")
	)
	(segment
		(start 285.222188 -134.413498)
		(end 286.538162 -133.097524)
		(width 0.11684)
		(layer "In4.Cu")
		(net "SMB_BMC_SWB_SCL")
	)
	(segment
		(start 215.638634 -366.023144)
		(end 205.033372 -366.023144)
		(width 0.11684)
		(layer "In4.Cu")
		(net "SMB_BMC_SWB_SCL")
	)
	(segment
		(start 282.80106 -134.90702)
		(end 283.682186 -135.7884)
		(width 0.11684)
		(layer "In4.Cu")
		(net "SMB_BMC_SWB_SCL")
	)
	(segment
		(start 171.652438 -396.799308)
		(end 171.050204 -397.401542)
		(width 0.11684)
		(layer "In4.Cu")
		(net "SMB_BMC_SWB_SCL")
	)
	(segment
		(start 225.284284 -331.311504)
		(end 225.284284 -343.337896)
		(width 0.11684)
		(layer "In4.Cu")
		(net "SMB_BMC_SWB_SCL")
	)
	(segment
		(start 282.483052 -135.225028)
		(end 282.483052 -135.059928)
		(width 0.11684)
		(layer "In4.Cu")
		(net "SMB_BMC_SWB_SCL")
	)
	(segment
		(start 218.50223 -350.11995)
		(end 218.50223 -363.159548)
		(width 0.11684)
		(layer "In4.Cu")
		(net "SMB_BMC_SWB_SCL")
	)
	(segment
		(start 284.483302 -135.152384)
		(end 284.73908 -134.896606)
		(width 0.11684)
		(layer "In4.Cu")
		(net "SMB_BMC_SWB_SCL")
	)
	(segment
		(start 185.644282 -371.913658)
		(end 185.644282 -377.89231)
		(width 0.11684)
		(layer "In4.Cu")
		(net "SMB_BMC_SWB_SCL")
	)
	(segment
		(start 167.099488 -414.36671)
		(end 167.588184 -414.36671)
		(width 0.11684)
		(layer "In4.Cu")
		(net "SMB_BMC_SWB_SCL")
	)
	(segment
		(start 194.529456 -369.80114)
		(end 187.7568 -369.80114)
		(width 0.11684)
		(layer "In4.Cu")
		(net "SMB_BMC_SWB_SCL")
	)
	(segment
		(start 164.787072 -411.433264)
		(end 165.720776 -412.366968)
		(width 0.11684)
		(layer "In4.Cu")
		(net "SMB_BMC_SWB_SCL")
	)
	(segment
		(start 171.938442 -390.627108)
		(end 171.938442 -392.308334)
		(width 0.11684)
		(layer "In4.Cu")
		(net "SMB_BMC_SWB_SCL")
	)
	(segment
		(start 284.000194 -135.470392)
		(end 283.119068 -134.589012)
		(width 0.11684)
		(layer "In4.Cu")
		(net "SMB_BMC_SWB_SCL")
	)
	(segment
		(start 205.033372 -366.023144)
		(end 202.369166 -368.68735)
		(width 0.11684)
		(layer "In4.Cu")
		(net "SMB_BMC_SWB_SCL")
	)
	(segment
		(start 222.074486 -215.515698)
		(end 222.074486 -254.138938)
		(width 0.11684)
		(layer "In4.Cu")
		(net "SMB_BMC_SWB_SCL")
	)
	(segment
		(start 171.938442 -392.308334)
		(end 171.652438 -392.594338)
		(width 0.11684)
		(layer "In4.Cu")
		(net "SMB_BMC_SWB_SCL")
	)
	(segment
		(start 239.135412 -169.836592)
		(end 238.626396 -169.836592)
		(width 0.11684)
		(layer "In4.Cu")
		(net "SMB_BMC_SWB_SCL")
	)
	(segment
		(start 283.847286 -135.7884)
		(end 284.000194 -135.635492)
		(width 0.11684)
		(layer "In4.Cu")
		(net "SMB_BMC_SWB_SCL")
	)
	(segment
		(start 215.483948 -260.729476)
		(end 215.483948 -321.511168)
		(width 0.11684)
		(layer "In4.Cu")
		(net "SMB_BMC_SWB_SCL")
	)
	(segment
		(start 283.119068 -134.423912)
		(end 283.271976 -134.271004)
		(width 0.11684)
		(layer "In4.Cu")
		(net "SMB_BMC_SWB_SCL")
	)
	(segment
		(start 284.73908 -134.731506)
		(end 283.98978 -133.982206)
		(width 0.11684)
		(layer "In4.Cu")
		(net "SMB_BMC_SWB_SCL")
	)
	(segment
		(start 215.483948 -321.511168)
		(end 225.284284 -331.311504)
		(width 0.11684)
		(layer "In4.Cu")
		(net "SMB_BMC_SWB_SCL")
	)
	(segment
		(start 230.222298 -208.590134)
		(end 229.00005 -208.590134)
		(width 0.11684)
		(layer "In4.Cu")
		(net "SMB_BMC_SWB_SCL")
	)
	(segment
		(start 195.643246 -368.68735)
		(end 194.529456 -369.80114)
		(width 0.11684)
		(layer "In4.Cu")
		(net "SMB_BMC_SWB_SCL")
	)
	(segment
		(start 170.634914 -419.784784)
		(end 171.004992 -420.154862)
		(width 0.11684)
		(layer "In4.Cu")
		(net "SMB_BMC_SWB_SCL")
	)
	(segment
		(start 165.387274 -399.684494)
		(end 164.561774 -401.677632)
		(width 0.11684)
		(layer "In4.Cu")
		(net "SMB_BMC_SWB_SCL")
	)
	(segment
		(start 289.233102 -124.221494)
		(end 292.48354 -124.221494)
		(width 0.11684)
		(layer "In4.Cu")
		(net "SMB_BMC_SWB_SCL")
	)
	(segment
		(start 202.369166 -368.68735)
		(end 195.643246 -368.68735)
		(width 0.11684)
		(layer "In4.Cu")
		(net "SMB_BMC_SWB_SCL")
	)
	(segment
		(start 284.73908 -134.896606)
		(end 284.73908 -134.731506)
		(width 0.11684)
		(layer "In4.Cu")
		(net "SMB_BMC_SWB_SCL")
	)
	(segment
		(start 225.284284 -343.337896)
		(end 218.50223 -350.11995)
		(width 0.11684)
		(layer "In4.Cu")
		(net "SMB_BMC_SWB_SCL")
	)
	(segment
		(start 167.588184 -414.36671)
		(end 169.487596 -416.266122)
		(width 0.11684)
		(layer "In4.Cu")
		(net "SMB_BMC_SWB_SCL")
	)
	(segment
		(start 293.378382 -125.116336)
		(end 299.075856 -125.116336)
		(width 0.11684)
		(layer "In4.Cu")
		(net "SMB_BMC_SWB_SCL")
	)
	(segment
		(start 284.318202 -135.152384)
		(end 284.483302 -135.152384)
		(width 0.11684)
		(layer "In4.Cu")
		(net "SMB_BMC_SWB_SCL")
	)
	(segment
		(start 248.96064 -156.65831)
		(end 262.977376 -156.65831)
		(width 0.11684)
		(layer "In4.Cu")
		(net "SMB_BMC_SWB_SCL")
	)
	(segment
		(start 222.074486 -254.138938)
		(end 215.483948 -260.729476)
		(width 0.11684)
		(layer "In4.Cu")
		(net "SMB_BMC_SWB_SCL")
	)
	(segment
		(start 164.787072 -408.933904)
		(end 164.787072 -411.433264)
		(width 0.11684)
		(layer "In4.Cu")
		(net "SMB_BMC_SWB_SCL")
	)
	(segment
		(start 283.98978 -133.817106)
		(end 284.142688 -133.664198)
		(width 0.11684)
		(layer "In4.Cu")
		(net "SMB_BMC_SWB_SCL")
	)
	(segment
		(start 299.075856 -125.116336)
		(end 300.162722 -124.02947)
		(width 0.11684)
		(layer "In4.Cu")
		(net "SMB_BMC_SWB_SCL")
	)
	(segment
		(start 172.805344 -389.760206)
		(end 171.938442 -390.627108)
		(width 0.11684)
		(layer "In4.Cu")
		(net "SMB_BMC_SWB_SCL")
	)
	(segment
		(start 173.776386 -389.760206)
		(end 172.805344 -389.760206)
		(width 0.11684)
		(layer "In4.Cu")
		(net "SMB_BMC_SWB_SCL")
	)
	(segment
		(start 286.538162 -133.097524)
		(end 286.538162 -126.916434)
		(width 0.11684)
		(layer "In4.Cu")
		(net "SMB_BMC_SWB_SCL")
	)
	(segment
		(start 237.866428 -167.752522)
		(end 248.96064 -156.65831)
		(width 0.11684)
		(layer "In4.Cu")
		(net "SMB_BMC_SWB_SCL")
	)
	(segment
		(start 283.98978 -133.982206)
		(end 283.98978 -133.817106)
		(width 0.11684)
		(layer "In4.Cu")
		(net "SMB_BMC_SWB_SCL")
	)
	(segment
		(start 165.720776 -412.987998)
		(end 167.099488 -414.36671)
		(width 0.11684)
		(layer "In4.Cu")
		(net "SMB_BMC_SWB_SCL")
	)
	(segment
		(start 283.364178 -136.106408)
		(end 282.483052 -135.225028)
		(width 0.11684)
		(layer "In4.Cu")
		(net "SMB_BMC_SWB_SCL")
	)
	(segment
		(start 171.050204 -397.401542)
		(end 167.670226 -397.401542)
		(width 0.11684)
		(layer "In4.Cu")
		(net "SMB_BMC_SWB_SCL")
	)
	(segment
		(start 165.901116 -426.165264)
		(end 165.901116 -427.54931)
		(width 0.11684)
		(layer "In4.Cu")
		(net "SMB_BMC_SWB_SCL")
	)
	(segment
		(start 237.866428 -169.076624)
		(end 237.866428 -167.752522)
		(width 0.11684)
		(layer "In4.Cu")
		(net "SMB_BMC_SWB_SCL")
	)
	(segment
		(start 283.364178 -136.271508)
		(end 283.364178 -136.106408)
		(width 0.11684)
		(layer "In4.Cu")
		(net "SMB_BMC_SWB_SCL")
	)
	(segment
		(start 167.670226 -397.401542)
		(end 165.387274 -399.684494)
		(width 0.11684)
		(layer "In4.Cu")
		(net "SMB_BMC_SWB_SCL")
	)
	(segment
		(start 300.162722 -124.02947)
		(end 300.162722 -114.588798)
		(width 0.11684)
		(layer "In4.Cu")
		(net "SMB_BMC_SWB_SCL")
	)
	(segment
		(start 164.561774 -408.708606)
		(end 164.787072 -408.933904)
		(width 0.11684)
		(layer "In4.Cu")
		(net "SMB_BMC_SWB_SCL")
	)
	(segment
		(start 170.079924 -419.784784)
		(end 170.634914 -419.784784)
		(width 0.11684)
		(layer "In4.Cu")
		(net "SMB_BMC_SWB_SCL")
	)
	(segment
		(start 292.48354 -124.221494)
		(end 293.378382 -125.116336)
		(width 0.11684)
		(layer "In4.Cu")
		(net "SMB_BMC_SWB_SCL")
	)
	(segment
		(start 229.00005 -208.590134)
		(end 222.074486 -215.515698)
		(width 0.11684)
		(layer "In4.Cu")
		(net "SMB_BMC_SWB_SCL")
	)
	(segment
		(start 171.004992 -420.154862)
		(end 171.004992 -421.061388)
		(width 0.11684)
		(layer "In4.Cu")
		(net "SMB_BMC_SWB_SCL")
	)
	(segment
		(start 283.271976 -134.271004)
		(end 283.437076 -134.271004)
		(width 0.11684)
		(layer "In4.Cu")
		(net "SMB_BMC_SWB_SCL")
	)
	(segment
		(start 262.977376 -156.65831)
		(end 283.364178 -136.271508)
		(width 0.11684)
		(layer "In4.Cu")
		(net "SMB_BMC_SWB_SCL")
	)
	(segment
		(start 169.487596 -416.266122)
		(end 169.487596 -419.192456)
		(width 0.11684)
		(layer "In4.Cu")
		(net "SMB_BMC_SWB_SCL")
	)
	(segment
		(start 283.437076 -134.271004)
		(end 284.318202 -135.152384)
		(width 0.11684)
		(layer "In4.Cu")
		(net "SMB_BMC_SWB_SCL")
	)
	(segment
		(start 171.652438 -392.594338)
		(end 171.652438 -396.799308)
		(width 0.11684)
		(layer "In4.Cu")
		(net "SMB_BMC_SWB_SCL")
	)
	(segment
		(start 284.142688 -133.664198)
		(end 284.307788 -133.664198)
		(width 0.11684)
		(layer "In4.Cu")
		(net "SMB_BMC_SWB_SCL")
	)
	(segment
		(start 171.004992 -421.061388)
		(end 165.901116 -426.165264)
		(width 0.11684)
		(layer "In4.Cu")
		(net "SMB_BMC_SWB_SCL")
	)
	(segment
		(start 238.626396 -169.836592)
		(end 237.866428 -169.076624)
		(width 0.11684)
		(layer "In4.Cu")
		(net "SMB_BMC_SWB_SCL")
	)
	(segment
		(start 286.538162 -126.916434)
		(end 289.233102 -124.221494)
		(width 0.11684)
		(layer "In4.Cu")
		(net "SMB_BMC_SWB_SCL")
	)
	(segment
		(start 185.644282 -377.89231)
		(end 173.776386 -389.760206)
		(width 0.11684)
		(layer "In4.Cu")
		(net "SMB_BMC_SWB_SCL")
	)
	(segment
		(start 282.63596 -134.90702)
		(end 282.80106 -134.90702)
		(width 0.11684)
		(layer "In4.Cu")
		(net "SMB_BMC_SWB_SCL")
	)
	(segment
		(start 284.307788 -133.664198)
		(end 285.057088 -134.413498)
		(width 0.11684)
		(layer "In4.Cu")
		(net "SMB_BMC_SWB_SCL")
	)
	(segment
		(start 283.682186 -135.7884)
		(end 283.847286 -135.7884)
		(width 0.11684)
		(layer "In4.Cu")
		(net "SMB_BMC_SWB_SCL")
	)
	(segment
		(start 169.487596 -419.192456)
		(end 170.079924 -419.784784)
		(width 0.11684)
		(layer "In4.Cu")
		(net "SMB_BMC_SWB_SCL")
	)
	(segment
		(start 300.162722 -114.588798)
		(end 299.29836 -113.724436)
		(width 0.11684)
		(layer "In4.Cu")
		(net "SMB_BMC_SWB_SCL")
	)
	(segment
		(start 187.7568 -369.80114)
		(end 185.644282 -371.913658)
		(width 0.11684)
		(layer "In4.Cu")
		(net "SMB_BMC_SWB_SCL")
	)
	(segment
		(start 284.000194 -135.635492)
		(end 284.000194 -135.470392)
		(width 0.11684)
		(layer "In4.Cu")
		(net "SMB_BMC_SWB_SCL")
	)
	(segment
		(start 282.483052 -135.059928)
		(end 282.63596 -134.90702)
		(width 0.11684)
		(layer "In4.Cu")
		(net "SMB_BMC_SWB_SCL")
	)
	(segment
		(start 283.119068 -134.589012)
		(end 283.119068 -134.423912)
		(width 0.11684)
		(layer "In4.Cu")
		(net "SMB_BMC_SWB_SCL")
	)
	(segment
		(start 218.50223 -363.159548)
		(end 215.638634 -366.023144)
		(width 0.11684)
		(layer "In4.Cu")
		(net "SMB_BMC_SWB_SCL")
	)
	(segment
		(start 164.561774 -401.677632)
		(end 164.561774 -408.708606)
		(width 0.11684)
		(layer "In4.Cu")
		(net "SMB_BMC_SWB_SCL")
	)
	(segment
		(start 165.720776 -412.366968)
		(end 165.720776 -412.987998)
		(width 0.11684)
		(layer "In4.Cu")
		(net "SMB_BMC_SWB_SCL")
	)
	(segment
		(start 285.057088 -134.413498)
		(end 285.222188 -134.413498)
		(width 0.11684)
		(layer "In4.Cu")
		(net "SMB_BMC_SWB_SCL")
	)
	(segment
		(start 165.91915 -433.878736)
		(end 165.90391 -433.878736)
		(width 0.10668)
		(layer "F.Cu")
		(net "SMB_BMC_SWB_R_SDA")
	)
	(segment
		(start 165.390322 -433.365148)
		(end 165.366446 -433.341272)
		(width 0.10668)
		(layer "F.Cu")
		(net "SMB_BMC_SWB_R_SDA")
	)
	(segment
		(start 163.575238 -433.489862)
		(end 163.575238 -434.272436)
		(width 0.10668)
		(layer "F.Cu")
		(net "SMB_BMC_SWB_R_SDA")
	)
	(segment
		(start 165.366446 -433.341272)
		(end 163.723828 -433.341272)
		(width 0.10668)
		(layer "F.Cu")
		(net "SMB_BMC_SWB_R_SDA")
	)
	(segment
		(start 165.91915 -433.878736)
		(end 165.91915 -434.869336)
		(width 0.10668)
		(layer "F.Cu")
		(net "SMB_BMC_SWB_R_SDA")
	)
	(segment
		(start 163.723828 -433.341272)
		(end 163.575238 -433.489862)
		(width 0.10668)
		(layer "F.Cu")
		(net "SMB_BMC_SWB_R_SDA")
	)
	(segment
		(start 165.90391 -433.878736)
		(end 165.390322 -433.365148)
		(width 0.10668)
		(layer "F.Cu")
		(net "SMB_BMC_SWB_R_SDA")
	)
	(via
		(at 165.390322 -433.365148)
		(size 0.508)
		(drill 0.254)
		(layers "F.Cu" "B.Cu")
		(net "SMB_BMC_SWB_R_SDA")
	)
	(segment
		(start 165.8112 -429.57115)
		(end 165.140132 -428.900082)
		(width 0.10668)
		(layer "F.Cu")
		(net "SMB_BMC_SWB_R_SCL")
	)
	(segment
		(start 165.713156 -428.546006)
		(end 165.76675 -428.5996)
		(width 0.10668)
		(layer "F.Cu")
		(net "SMB_BMC_SWB_R_SCL")
	)
	(segment
		(start 165.8112 -429.57115)
		(end 164.54755 -430.8348)
		(width 0.10668)
		(layer "F.Cu")
		(net "SMB_BMC_SWB_R_SCL")
	)
	(segment
		(start 165.140132 -428.546006)
		(end 165.713156 -428.546006)
		(width 0.10668)
		(layer "F.Cu")
		(net "SMB_BMC_SWB_R_SCL")
	)
	(segment
		(start 164.54755 -430.8348)
		(end 163.727638 -430.8348)
		(width 0.10668)
		(layer "F.Cu")
		(net "SMB_BMC_SWB_R_SCL")
	)
	(segment
		(start 163.727638 -430.8348)
		(end 163.575238 -430.6824)
		(width 0.10668)
		(layer "F.Cu")
		(net "SMB_BMC_SWB_R_SCL")
	)
	(segment
		(start 165.140132 -428.900082)
		(end 165.140132 -428.546006)
		(width 0.10668)
		(layer "F.Cu")
		(net "SMB_BMC_SWB_R_SCL")
	)
	(segment
		(start 163.575238 -430.6824)
		(end 163.575238 -429.807624)
		(width 0.10668)
		(layer "F.Cu")
		(net "SMB_BMC_SWB_R_SCL")
	)
	(via
		(at 165.140132 -428.546006)
		(size 0.508)
		(drill 0.254)
		(layers "F.Cu" "B.Cu")
		(net "SMB_BMC_SWB_R_SCL")
	)
	(segment
		(start 285.918148 -427.332648)
		(end 285.519114 -427.731682)
		(width 0.10668)
		(layer "F.Cu")
		(net "SMB_BMC_SWB_EN_R2")
	)
	(segment
		(start 286.737806 -427.332648)
		(end 285.918148 -427.332648)
		(width 0.10668)
		(layer "F.Cu")
		(net "SMB_BMC_SWB_EN_R2")
	)
	(via
		(at 285.519114 -427.731682)
		(size 0.508)
		(drill 0.254)
		(layers "F.Cu" "B.Cu")
		(net "SMB_BMC_SWB_EN_R2")
	)
	(segment
		(start 286.749236 -427.37151)
		(end 285.879286 -427.37151)
		(width 0.10668)
		(layer "B.Cu")
		(net "SMB_BMC_SWB_EN_R2")
	)
	(segment
		(start 285.879286 -427.37151)
		(end 285.519114 -427.731682)
		(width 0.10668)
		(layer "B.Cu")
		(net "SMB_BMC_SWB_EN_R2")
	)
	(segment
		(start 162.275012 -429.807624)
		(end 160.866582 -429.807624)
		(width 0.10668)
		(layer "F.Cu")
		(net "SMB_BMC_SWB_EN_R")
	)
	(segment
		(start 165.91915 -432.4096)
		(end 163.967668 -432.4096)
		(width 0.10668)
		(layer "F.Cu")
		(net "SMB_BMC_SWB_EN_R")
	)
	(segment
		(start 162.275012 -430.716944)
		(end 162.275012 -429.807624)
		(width 0.10668)
		(layer "F.Cu")
		(net "SMB_BMC_SWB_EN_R")
	)
	(segment
		(start 163.967668 -432.4096)
		(end 162.275012 -430.716944)
		(width 0.10668)
		(layer "F.Cu")
		(net "SMB_BMC_SWB_EN_R")
	)
	(via
		(at 160.866582 -429.807624)
		(size 0.762)
		(drill 0.381)
		(layers "F.Cu" "B.Cu")
		(net "SMB_BMC_SWB_EN_R")
	)
	(segment
		(start 177.122074 -122.65279)
		(end 176.732184 -123.04268)
		(width 0.10668)
		(layer "F.Cu")
		(net "SMB_BMC_SWB_EN")
	)
	(segment
		(start 210.877912 -189.23381)
		(end 210.877912 -195.03771)
		(width 0.10668)
		(layer "F.Cu")
		(net "SMB_BMC_SWB_EN")
	)
	(segment
		(start 209.697828 -196.217794)
		(end 208.989676 -196.217794)
		(width 0.10668)
		(layer "F.Cu")
		(net "SMB_BMC_SWB_EN")
	)
	(segment
		(start 193.174366 -172.13961)
		(end 200.939654 -179.904898)
		(width 0.10668)
		(layer "F.Cu")
		(net "SMB_BMC_SWB_EN")
	)
	(segment
		(start 167.475154 -432.4096)
		(end 168.198038 -431.686716)
		(width 0.10668)
		(layer "F.Cu")
		(net "SMB_BMC_SWB_EN")
	)
	(segment
		(start 166.71925 -432.4096)
		(end 167.475154 -432.4096)
		(width 0.10668)
		(layer "F.Cu")
		(net "SMB_BMC_SWB_EN")
	)
	(segment
		(start 208.883758 -184.419494)
		(end 210.877912 -189.23381)
		(width 0.10668)
		(layer "F.Cu")
		(net "SMB_BMC_SWB_EN")
	)
	(segment
		(start 200.939654 -179.904898)
		(end 204.369162 -179.904898)
		(width 0.10668)
		(layer "F.Cu")
		(net "SMB_BMC_SWB_EN")
	)
	(segment
		(start 168.198038 -431.686716)
		(end 169.535856 -431.686716)
		(width 0.10668)
		(layer "F.Cu")
		(net "SMB_BMC_SWB_EN")
	)
	(segment
		(start 169.535856 -431.686716)
		(end 170.434254 -430.788318)
		(width 0.10668)
		(layer "F.Cu")
		(net "SMB_BMC_SWB_EN")
	)
	(segment
		(start 204.369162 -179.904898)
		(end 208.883758 -184.419494)
		(width 0.10668)
		(layer "F.Cu")
		(net "SMB_BMC_SWB_EN")
	)
	(segment
		(start 210.877912 -195.03771)
		(end 209.697828 -196.217794)
		(width 0.10668)
		(layer "F.Cu")
		(net "SMB_BMC_SWB_EN")
	)
	(via
		(at 193.174366 -172.13961)
		(size 0.508)
		(drill 0.254)
		(layers "F.Cu" "B.Cu")
		(net "SMB_BMC_SWB_EN")
	)
	(via
		(at 208.989676 -196.217794)
		(size 0.508)
		(drill 0.254)
		(layers "F.Cu" "B.Cu")
		(net "SMB_BMC_SWB_EN")
	)
	(via
		(at 170.434254 -430.788318)
		(size 0.508)
		(drill 0.254)
		(layers "F.Cu" "B.Cu")
		(net "SMB_BMC_SWB_EN")
	)
	(via
		(at 287.572704 -429.269652)
		(size 0.508)
		(drill 0.254)
		(layers "F.Cu" "B.Cu")
		(net "SMB_BMC_SWB_EN")
	)
	(via
		(at 176.732184 -123.04268)
		(size 0.4572)
		(drill 0.254)
		(layers "F.Cu" "B.Cu")
		(net "SMB_BMC_SWB_EN")
	)
	(via
		(at 179.938172 -165.198806)
		(size 0.508)
		(drill 0.254)
		(layers "F.Cu" "B.Cu")
		(net "SMB_BMC_SWB_EN")
	)
	(via
		(at 285.876492 -377.772168)
		(size 0.508)
		(drill 0.254)
		(layers "F.Cu" "B.Cu")
		(net "SMB_BMC_SWB_EN")
	)
	(via
		(at 221.288356 -372.501668)
		(size 0.508)
		(drill 0.254)
		(layers "F.Cu" "B.Cu")
		(net "SMB_BMC_SWB_EN")
	)
	(segment
		(start 221.506796 -372.720108)
		(end 279.687528 -372.720108)
		(width 0.10668)
		(layer "B.Cu")
		(net "SMB_BMC_SWB_EN")
	)
	(segment
		(start 187.217812 -166.845234)
		(end 180.756306 -166.845234)
		(width 0.10668)
		(layer "B.Cu")
		(net "SMB_BMC_SWB_EN")
	)
	(segment
		(start 180.756306 -166.845234)
		(end 180.402738 -166.491666)
		(width 0.10668)
		(layer "B.Cu")
		(net "SMB_BMC_SWB_EN")
	)
	(segment
		(start 193.174366 -172.13961)
		(end 193.174366 -171.948094)
		(width 0.10668)
		(layer "B.Cu")
		(net "SMB_BMC_SWB_EN")
	)
	(segment
		(start 190.629286 -170.256708)
		(end 187.217812 -166.845234)
		(width 0.10668)
		(layer "B.Cu")
		(net "SMB_BMC_SWB_EN")
	)
	(segment
		(start 180.402738 -166.491666)
		(end 180.402738 -165.663372)
		(width 0.10668)
		(layer "B.Cu")
		(net "SMB_BMC_SWB_EN")
	)
	(segment
		(start 279.687528 -372.720108)
		(end 284.739588 -377.772168)
		(width 0.10668)
		(layer "B.Cu")
		(net "SMB_BMC_SWB_EN")
	)
	(segment
		(start 191.48298 -170.256708)
		(end 190.629286 -170.256708)
		(width 0.10668)
		(layer "B.Cu")
		(net "SMB_BMC_SWB_EN")
	)
	(segment
		(start 221.288356 -372.501668)
		(end 221.506796 -372.720108)
		(width 0.10668)
		(layer "B.Cu")
		(net "SMB_BMC_SWB_EN")
	)
	(segment
		(start 284.739588 -377.772168)
		(end 285.876492 -377.772168)
		(width 0.10668)
		(layer "B.Cu")
		(net "SMB_BMC_SWB_EN")
	)
	(segment
		(start 193.174366 -171.948094)
		(end 191.48298 -170.256708)
		(width 0.10668)
		(layer "B.Cu")
		(net "SMB_BMC_SWB_EN")
	)
	(segment
		(start 287.549336 -427.37151)
		(end 287.549336 -428.26051)
		(width 0.10668)
		(layer "B.Cu")
		(net "SMB_BMC_SWB_EN")
	)
	(segment
		(start 287.549336 -429.246284)
		(end 287.572704 -429.269652)
		(width 0.10668)
		(layer "B.Cu")
		(net "SMB_BMC_SWB_EN")
	)
	(segment
		(start 180.402738 -165.663372)
		(end 179.938172 -165.198806)
		(width 0.10668)
		(layer "B.Cu")
		(net "SMB_BMC_SWB_EN")
	)
	(segment
		(start 287.549336 -428.26051)
		(end 287.549336 -429.246284)
		(width 0.10668)
		(layer "B.Cu")
		(net "SMB_BMC_SWB_EN")
	)
	(segment
		(start 291.504878 -424.081448)
		(end 287.661604 -420.238174)
		(width 0.11684)
		(layer "In4.Cu")
		(net "SMB_BMC_SWB_EN")
	)
	(segment
		(start 291.504878 -427.723808)
		(end 291.504878 -424.081448)
		(width 0.11684)
		(layer "In4.Cu")
		(net "SMB_BMC_SWB_EN")
	)
	(segment
		(start 175.765968 -153.310336)
		(end 172.255434 -149.799802)
		(width 0.11684)
		(layer "In4.Cu")
		(net "SMB_BMC_SWB_EN")
	)
	(segment
		(start 175.244506 -124.43841)
		(end 175.409352 -124.43841)
		(width 0.11684)
		(layer "In4.Cu")
		(net "SMB_BMC_SWB_EN")
	)
	(segment
		(start 287.417764 -403.212808)
		(end 287.417764 -401.349718)
		(width 0.11684)
		(layer "In4.Cu")
		(net "SMB_BMC_SWB_EN")
	)
	(segment
		(start 287.417764 -388.539228)
		(end 286.172148 -387.293612)
		(width 0.11684)
		(layer "In4.Cu")
		(net "SMB_BMC_SWB_EN")
	)
	(segment
		(start 172.255434 -149.799802)
		(end 172.255434 -138.27125)
		(width 0.11684)
		(layer "In4.Cu")
		(net "SMB_BMC_SWB_EN")
	)
	(segment
		(start 286.005524 -399.937478)
		(end 286.005524 -397.87068)
		(width 0.11684)
		(layer "In4.Cu")
		(net "SMB_BMC_SWB_EN")
	)
	(segment
		(start 179.174648 -165.198806)
		(end 175.765968 -161.790126)
		(width 0.11684)
		(layer "In4.Cu")
		(net "SMB_BMC_SWB_EN")
	)
	(segment
		(start 176.732184 -123.115578)
		(end 176.732184 -123.04268)
		(width 0.11684)
		(layer "In4.Cu")
		(net "SMB_BMC_SWB_EN")
	)
	(segment
		(start 285.135066 -378.915168)
		(end 285.135066 -378.318522)
		(width 0.11684)
		(layer "In4.Cu")
		(net "SMB_BMC_SWB_EN")
	)
	(segment
		(start 287.661604 -415.967418)
		(end 288.243772 -415.38525)
		(width 0.11684)
		(layer "In4.Cu")
		(net "SMB_BMC_SWB_EN")
	)
	(segment
		(start 286.754316 -418.142928)
		(end 287.661604 -417.23564)
		(width 0.11684)
		(layer "In4.Cu")
		(net "SMB_BMC_SWB_EN")
	)
	(segment
		(start 287.417764 -396.45844)
		(end 287.417764 -388.539228)
		(width 0.11684)
		(layer "In4.Cu")
		(net "SMB_BMC_SWB_EN")
	)
	(segment
		(start 287.661604 -419.414452)
		(end 286.754316 -418.507164)
		(width 0.11684)
		(layer "In4.Cu")
		(net "SMB_BMC_SWB_EN")
	)
	(segment
		(start 287.572704 -429.269652)
		(end 288.18586 -428.656496)
		(width 0.11684)
		(layer "In4.Cu")
		(net "SMB_BMC_SWB_EN")
	)
	(segment
		(start 288.18586 -428.656496)
		(end 290.57219 -428.656496)
		(width 0.11684)
		(layer "In4.Cu")
		(net "SMB_BMC_SWB_EN")
	)
	(segment
		(start 287.981898 -405.833326)
		(end 287.981898 -403.776942)
		(width 0.11684)
		(layer "In4.Cu")
		(net "SMB_BMC_SWB_EN")
	)
	(segment
		(start 175.409352 -124.43841)
		(end 176.732184 -123.115578)
		(width 0.11684)
		(layer "In4.Cu")
		(net "SMB_BMC_SWB_EN")
	)
	(segment
		(start 179.938172 -165.198806)
		(end 179.174648 -165.198806)
		(width 0.11684)
		(layer "In4.Cu")
		(net "SMB_BMC_SWB_EN")
	)
	(segment
		(start 171.552108 -133.514592)
		(end 172.255434 -132.811266)
		(width 0.11684)
		(layer "In4.Cu")
		(net "SMB_BMC_SWB_EN")
	)
	(segment
		(start 288.243772 -415.38525)
		(end 288.243772 -406.0952)
		(width 0.11684)
		(layer "In4.Cu")
		(net "SMB_BMC_SWB_EN")
	)
	(segment
		(start 285.68142 -377.772168)
		(end 285.876492 -377.772168)
		(width 0.11684)
		(layer "In4.Cu")
		(net "SMB_BMC_SWB_EN")
	)
	(segment
		(start 287.661604 -417.23564)
		(end 287.661604 -415.967418)
		(width 0.11684)
		(layer "In4.Cu")
		(net "SMB_BMC_SWB_EN")
	)
	(segment
		(start 286.172148 -387.293612)
		(end 286.172148 -379.95225)
		(width 0.11684)
		(layer "In4.Cu")
		(net "SMB_BMC_SWB_EN")
	)
	(segment
		(start 172.255434 -132.811266)
		(end 172.255434 -127.427482)
		(width 0.11684)
		(layer "In4.Cu")
		(net "SMB_BMC_SWB_EN")
	)
	(segment
		(start 286.172148 -379.95225)
		(end 285.135066 -378.915168)
		(width 0.11684)
		(layer "In4.Cu")
		(net "SMB_BMC_SWB_EN")
	)
	(segment
		(start 286.754316 -418.507164)
		(end 286.754316 -418.142928)
		(width 0.11684)
		(layer "In4.Cu")
		(net "SMB_BMC_SWB_EN")
	)
	(segment
		(start 175.765968 -161.790126)
		(end 175.765968 -153.310336)
		(width 0.11684)
		(layer "In4.Cu")
		(net "SMB_BMC_SWB_EN")
	)
	(segment
		(start 287.661604 -420.238174)
		(end 287.661604 -419.414452)
		(width 0.11684)
		(layer "In4.Cu")
		(net "SMB_BMC_SWB_EN")
	)
	(segment
		(start 287.981898 -403.776942)
		(end 287.417764 -403.212808)
		(width 0.11684)
		(layer "In4.Cu")
		(net "SMB_BMC_SWB_EN")
	)
	(segment
		(start 172.255434 -138.27125)
		(end 171.552108 -137.567924)
		(width 0.11684)
		(layer "In4.Cu")
		(net "SMB_BMC_SWB_EN")
	)
	(segment
		(start 290.57219 -428.656496)
		(end 291.504878 -427.723808)
		(width 0.11684)
		(layer "In4.Cu")
		(net "SMB_BMC_SWB_EN")
	)
	(segment
		(start 286.005524 -397.87068)
		(end 287.417764 -396.45844)
		(width 0.11684)
		(layer "In4.Cu")
		(net "SMB_BMC_SWB_EN")
	)
	(segment
		(start 288.243772 -406.0952)
		(end 287.981898 -405.833326)
		(width 0.11684)
		(layer "In4.Cu")
		(net "SMB_BMC_SWB_EN")
	)
	(segment
		(start 287.417764 -401.349718)
		(end 286.005524 -399.937478)
		(width 0.11684)
		(layer "In4.Cu")
		(net "SMB_BMC_SWB_EN")
	)
	(segment
		(start 171.552108 -137.567924)
		(end 171.552108 -133.514592)
		(width 0.11684)
		(layer "In4.Cu")
		(net "SMB_BMC_SWB_EN")
	)
	(segment
		(start 285.135066 -378.318522)
		(end 285.68142 -377.772168)
		(width 0.11684)
		(layer "In4.Cu")
		(net "SMB_BMC_SWB_EN")
	)
	(segment
		(start 172.255434 -127.427482)
		(end 175.244506 -124.43841)
		(width 0.11684)
		(layer "In4.Cu")
		(net "SMB_BMC_SWB_EN")
	)
	(segment
		(start 193.226944 -373.138954)
		(end 191.490346 -374.875552)
		(width 0.11684)
		(layer "In6.Cu")
		(net "SMB_BMC_SWB_EN")
	)
	(segment
		(start 173.034198 -418.484812)
		(end 173.086522 -418.537136)
		(width 0.11684)
		(layer "In6.Cu")
		(net "SMB_BMC_SWB_EN")
	)
	(segment
		(start 173.086522 -418.537136)
		(end 173.086522 -420.444676)
		(width 0.11684)
		(layer "In6.Cu")
		(net "SMB_BMC_SWB_EN")
	)
	(segment
		(start 181.176422 -385.987544)
		(end 175.754538 -391.409428)
		(width 0.11684)
		(layer "In6.Cu")
		(net "SMB_BMC_SWB_EN")
	)
	(segment
		(start 175.754538 -400.318224)
		(end 176.613566 -401.177252)
		(width 0.11684)
		(layer "In6.Cu")
		(net "SMB_BMC_SWB_EN")
	)
	(segment
		(start 172.757338 -428.465234)
		(end 170.434254 -430.788318)
		(width 0.11684)
		(layer "In6.Cu")
		(net "SMB_BMC_SWB_EN")
	)
	(segment
		(start 215.872568 -202.298808)
		(end 209.791554 -196.217794)
		(width 0.11684)
		(layer "In6.Cu")
		(net "SMB_BMC_SWB_EN")
	)
	(segment
		(start 221.6531 -372.193312)
		(end 226.590352 -367.25606)
		(width 0.11684)
		(layer "In6.Cu")
		(net "SMB_BMC_SWB_EN")
	)
	(segment
		(start 175.754538 -391.409428)
		(end 175.754538 -400.318224)
		(width 0.11684)
		(layer "In6.Cu")
		(net "SMB_BMC_SWB_EN")
	)
	(segment
		(start 176.613566 -407.510234)
		(end 173.034198 -411.089602)
		(width 0.11684)
		(layer "In6.Cu")
		(net "SMB_BMC_SWB_EN")
	)
	(segment
		(start 172.757338 -420.77386)
		(end 172.757338 -428.465234)
		(width 0.11684)
		(layer "In6.Cu")
		(net "SMB_BMC_SWB_EN")
	)
	(segment
		(start 220.65107 -373.138954)
		(end 193.226944 -373.138954)
		(width 0.11684)
		(layer "In6.Cu")
		(net "SMB_BMC_SWB_EN")
	)
	(segment
		(start 173.034198 -411.089602)
		(end 173.034198 -418.484812)
		(width 0.11684)
		(layer "In6.Cu")
		(net "SMB_BMC_SWB_EN")
	)
	(segment
		(start 181.176422 -383.612898)
		(end 181.176422 -385.987544)
		(width 0.11684)
		(layer "In6.Cu")
		(net "SMB_BMC_SWB_EN")
	)
	(segment
		(start 226.590352 -367.25606)
		(end 226.590352 -364.12551)
		(width 0.11684)
		(layer "In6.Cu")
		(net "SMB_BMC_SWB_EN")
	)
	(segment
		(start 176.613566 -401.177252)
		(end 176.613566 -407.510234)
		(width 0.11684)
		(layer "In6.Cu")
		(net "SMB_BMC_SWB_EN")
	)
	(segment
		(start 173.086522 -420.444676)
		(end 172.757338 -420.77386)
		(width 0.11684)
		(layer "In6.Cu")
		(net "SMB_BMC_SWB_EN")
	)
	(segment
		(start 189.913768 -374.875552)
		(end 181.176422 -383.612898)
		(width 0.11684)
		(layer "In6.Cu")
		(net "SMB_BMC_SWB_EN")
	)
	(segment
		(start 191.490346 -374.875552)
		(end 189.913768 -374.875552)
		(width 0.11684)
		(layer "In6.Cu")
		(net "SMB_BMC_SWB_EN")
	)
	(segment
		(start 221.596712 -372.193312)
		(end 221.6531 -372.193312)
		(width 0.11684)
		(layer "In6.Cu")
		(net "SMB_BMC_SWB_EN")
	)
	(segment
		(start 221.288356 -372.501668)
		(end 220.65107 -373.138954)
		(width 0.11684)
		(layer "In6.Cu")
		(net "SMB_BMC_SWB_EN")
	)
	(segment
		(start 226.590352 -364.12551)
		(end 227.701856 -363.014006)
		(width 0.11684)
		(layer "In6.Cu")
		(net "SMB_BMC_SWB_EN")
	)
	(segment
		(start 227.701856 -363.014006)
		(end 227.701856 -331.866494)
		(width 0.11684)
		(layer "In6.Cu")
		(net "SMB_BMC_SWB_EN")
	)
	(segment
		(start 215.872568 -320.037206)
		(end 215.872568 -202.298808)
		(width 0.11684)
		(layer "In6.Cu")
		(net "SMB_BMC_SWB_EN")
	)
	(segment
		(start 221.288356 -372.501668)
		(end 221.596712 -372.193312)
		(width 0.11684)
		(layer "In6.Cu")
		(net "SMB_BMC_SWB_EN")
	)
	(segment
		(start 227.701856 -331.866494)
		(end 215.872568 -320.037206)
		(width 0.11684)
		(layer "In6.Cu")
		(net "SMB_BMC_SWB_EN")
	)
	(segment
		(start 209.791554 -196.217794)
		(end 208.989676 -196.217794)
		(width 0.11684)
		(layer "In6.Cu")
		(net "SMB_BMC_SWB_EN")
	)
	(segment
		(start 168.25595 -433.464716)
		(end 168.25595 -433.878736)
		(width 0.10668)
		(layer "F.Cu")
		(net "SMB_BMC_SWB_BUF_R_SDA")
	)
	(segment
		(start 168.25595 -434.869336)
		(end 168.25595 -433.878736)
		(width 0.10668)
		(layer "F.Cu")
		(net "SMB_BMC_SWB_BUF_R_SDA")
	)
	(segment
		(start 166.71925 -434.869336)
		(end 168.25595 -434.869336)
		(width 0.10668)
		(layer "F.Cu")
		(net "SMB_BMC_SWB_BUF_R_SDA")
	)
	(segment
		(start 167.680894 -432.88966)
		(end 167.806116 -433.014882)
		(width 0.10668)
		(layer "F.Cu")
		(net "SMB_BMC_SWB_BUF_R_SDA")
	)
	(segment
		(start 163.47948 -432.88966)
		(end 167.680894 -432.88966)
		(width 0.10668)
		(layer "F.Cu")
		(net "SMB_BMC_SWB_BUF_R_SDA")
	)
	(segment
		(start 162.924998 -434.272436)
		(end 162.924998 -433.444142)
		(width 0.10668)
		(layer "F.Cu")
		(net "SMB_BMC_SWB_BUF_R_SDA")
	)
	(segment
		(start 167.806116 -433.014882)
		(end 168.25595 -433.464716)
		(width 0.10668)
		(layer "F.Cu")
		(net "SMB_BMC_SWB_BUF_R_SDA")
	)
	(segment
		(start 162.924998 -433.444142)
		(end 163.47948 -432.88966)
		(width 0.10668)
		(layer "F.Cu")
		(net "SMB_BMC_SWB_BUF_R_SDA")
	)
	(via
		(at 167.806116 -433.014882)
		(size 0.762)
		(drill 0.381)
		(layers "F.Cu" "B.Cu")
		(net "SMB_BMC_SWB_BUF_R_SDA")
	)
	(segment
		(start 165.91915 -431.029872)
		(end 165.8112 -430.921922)
		(width 0.10668)
		(layer "F.Cu")
		(net "SMB_BMC_SWB_BUF_R_SCL")
	)
	(segment
		(start 163.610544 -431.3936)
		(end 162.924998 -430.708054)
		(width 0.10668)
		(layer "F.Cu")
		(net "SMB_BMC_SWB_BUF_R_SCL")
	)
	(segment
		(start 165.91915 -431.3936)
		(end 163.610544 -431.3936)
		(width 0.10668)
		(layer "F.Cu")
		(net "SMB_BMC_SWB_BUF_R_SCL")
	)
	(segment
		(start 162.924998 -429.273208)
		(end 162.034728 -428.382938)
		(width 0.10668)
		(layer "F.Cu")
		(net "SMB_BMC_SWB_BUF_R_SCL")
	)
	(segment
		(start 165.8112 -430.37125)
		(end 166.8272 -430.37125)
		(width 0.10668)
		(layer "F.Cu")
		(net "SMB_BMC_SWB_BUF_R_SCL")
	)
	(segment
		(start 165.8112 -430.921922)
		(end 165.8112 -430.37125)
		(width 0.10668)
		(layer "F.Cu")
		(net "SMB_BMC_SWB_BUF_R_SCL")
	)
	(segment
		(start 162.034728 -428.382938)
		(end 161.167064 -428.382938)
		(width 0.10668)
		(layer "F.Cu")
		(net "SMB_BMC_SWB_BUF_R_SCL")
	)
	(segment
		(start 162.924998 -430.708054)
		(end 162.924998 -429.807624)
		(width 0.10668)
		(layer "F.Cu")
		(net "SMB_BMC_SWB_BUF_R_SCL")
	)
	(segment
		(start 162.924998 -429.807624)
		(end 162.924998 -429.273208)
		(width 0.10668)
		(layer "F.Cu")
		(net "SMB_BMC_SWB_BUF_R_SCL")
	)
	(segment
		(start 165.91915 -431.3936)
		(end 165.91915 -431.029872)
		(width 0.10668)
		(layer "F.Cu")
		(net "SMB_BMC_SWB_BUF_R_SCL")
	)
	(via
		(at 161.167064 -428.382938)
		(size 0.762)
		(drill 0.381)
		(layers "F.Cu" "B.Cu")
		(net "SMB_BMC_SWB_BUF_R_SCL")
	)
	(segment
		(start 33.703768 -436.433214)
		(end 33.322768 -436.052214)
		(width 0.10668)
		(layer "F.Cu")
		(net "SMB_BMC_GPU_EN_R3")
	)
	(segment
		(start 33.322768 -436.052214)
		(end 31.796482 -436.052214)
		(width 0.10668)
		(layer "F.Cu")
		(net "SMB_BMC_GPU_EN_R3")
	)
	(segment
		(start 31.33598 -436.483252)
		(end 30.520894 -436.483252)
		(width 0.10668)
		(layer "F.Cu")
		(net "SMB_BMC_GPU_EN_R3")
	)
	(segment
		(start 31.796482 -436.052214)
		(end 31.767018 -436.052214)
		(width 0.10668)
		(layer "F.Cu")
		(net "SMB_BMC_GPU_EN_R3")
	)
	(segment
		(start 31.767018 -436.052214)
		(end 31.33598 -436.483252)
		(width 0.10668)
		(layer "F.Cu")
		(net "SMB_BMC_GPU_EN_R3")
	)
	(via
		(at 31.796482 -436.052214)
		(size 0.508)
		(drill 0.254)
		(layers "F.Cu" "B.Cu")
		(net "SMB_BMC_GPU_EN_R3")
	)
	(segment
		(start 27.28595 -433.71135)
		(end 27.305 -433.6923)
		(width 0.10668)
		(layer "F.Cu")
		(net "SMB_BMC_GPU_EN_R1")
	)
	(segment
		(start 27.28595 -434.9623)
		(end 27.28595 -433.71135)
		(width 0.10668)
		(layer "F.Cu")
		(net "SMB_BMC_GPU_EN_R1")
	)
	(segment
		(start 27.06497 -433.45227)
		(end 26.042366 -433.45227)
		(width 0.10668)
		(layer "F.Cu")
		(net "SMB_BMC_GPU_EN_R1")
	)
	(segment
		(start 27.305 -433.6923)
		(end 27.06497 -433.45227)
		(width 0.10668)
		(layer "F.Cu")
		(net "SMB_BMC_GPU_EN_R1")
	)
	(via
		(at 27.305 -433.6923)
		(size 0.508)
		(drill 0.254)
		(layers "F.Cu" "B.Cu")
		(net "SMB_BMC_GPU_EN_R1")
	)
	(segment
		(start 34.503868 -435.811168)
		(end 34.503868 -436.433214)
		(width 0.10668)
		(layer "F.Cu")
		(net "SMB_BMC_GPU_EN")
	)
	(segment
		(start 34.473388 -435.780688)
		(end 34.503868 -435.811168)
		(width 0.10668)
		(layer "F.Cu")
		(net "SMB_BMC_GPU_EN")
	)
	(segment
		(start 31.341568 -435.4703)
		(end 34.163 -435.4703)
		(width 0.10668)
		(layer "F.Cu")
		(net "SMB_BMC_GPU_EN")
	)
	(segment
		(start 34.163 -435.4703)
		(end 34.473388 -435.780688)
		(width 0.10668)
		(layer "F.Cu")
		(net "SMB_BMC_GPU_EN")
	)
	(segment
		(start 30.919674 -435.892194)
		(end 31.341568 -435.4703)
		(width 0.10668)
		(layer "F.Cu")
		(net "SMB_BMC_GPU_EN")
	)
	(segment
		(start 185.122058 -109.052868)
		(end 184.732168 -108.662978)
		(width 0.10668)
		(layer "F.Cu")
		(net "SMB_BMC_GPU_EN")
	)
	(segment
		(start 29.591 -435.892194)
		(end 30.919674 -435.892194)
		(width 0.10668)
		(layer "F.Cu")
		(net "SMB_BMC_GPU_EN")
	)
	(segment
		(start 28.08605 -434.9623)
		(end 29.06395 -434.9623)
		(width 0.10668)
		(layer "F.Cu")
		(net "SMB_BMC_GPU_EN")
	)
	(segment
		(start 29.06395 -435.365144)
		(end 29.591 -435.892194)
		(width 0.10668)
		(layer "F.Cu")
		(net "SMB_BMC_GPU_EN")
	)
	(segment
		(start 29.06395 -434.9623)
		(end 29.06395 -435.365144)
		(width 0.10668)
		(layer "F.Cu")
		(net "SMB_BMC_GPU_EN")
	)
	(via
		(at 69.848222 -132.601208)
		(size 0.508)
		(drill 0.254)
		(layers "F.Cu" "B.Cu")
		(net "SMB_BMC_GPU_EN")
	)
	(via
		(at 30.214824 -415.351976)
		(size 0.508)
		(drill 0.254)
		(layers "F.Cu" "B.Cu")
		(net "SMB_BMC_GPU_EN")
	)
	(via
		(at 184.732168 -108.662978)
		(size 0.4572)
		(drill 0.254)
		(layers "F.Cu" "B.Cu")
		(net "SMB_BMC_GPU_EN")
	)
	(via
		(at 34.473388 -435.780688)
		(size 0.508)
		(drill 0.254)
		(layers "F.Cu" "B.Cu")
		(net "SMB_BMC_GPU_EN")
	)
	(segment
		(start 20.858734 -434.427376)
		(end 19.291808 -432.86045)
		(width 0.10668)
		(layer "B.Cu")
		(net "SMB_BMC_GPU_EN")
	)
	(segment
		(start 31.929578 -436.767986)
		(end 26.723594 -436.767986)
		(width 0.10668)
		(layer "B.Cu")
		(net "SMB_BMC_GPU_EN")
	)
	(segment
		(start 21.223224 -417.06546)
		(end 28.50134 -417.06546)
		(width 0.10668)
		(layer "B.Cu")
		(net "SMB_BMC_GPU_EN")
	)
	(segment
		(start 34.473388 -435.780688)
		(end 32.916876 -435.780688)
		(width 0.10668)
		(layer "B.Cu")
		(net "SMB_BMC_GPU_EN")
	)
	(segment
		(start 24.382984 -434.427376)
		(end 20.858734 -434.427376)
		(width 0.10668)
		(layer "B.Cu")
		(net "SMB_BMC_GPU_EN")
	)
	(segment
		(start 19.291808 -418.996876)
		(end 21.223224 -417.06546)
		(width 0.10668)
		(layer "B.Cu")
		(net "SMB_BMC_GPU_EN")
	)
	(segment
		(start 28.50134 -417.06546)
		(end 30.214824 -415.351976)
		(width 0.10668)
		(layer "B.Cu")
		(net "SMB_BMC_GPU_EN")
	)
	(segment
		(start 26.723594 -436.767986)
		(end 24.382984 -434.427376)
		(width 0.10668)
		(layer "B.Cu")
		(net "SMB_BMC_GPU_EN")
	)
	(segment
		(start 32.916876 -435.780688)
		(end 31.929578 -436.767986)
		(width 0.10668)
		(layer "B.Cu")
		(net "SMB_BMC_GPU_EN")
	)
	(segment
		(start 19.291808 -432.86045)
		(end 19.291808 -418.996876)
		(width 0.10668)
		(layer "B.Cu")
		(net "SMB_BMC_GPU_EN")
	)
	(segment
		(start 34.967164 -410.599636)
		(end 34.967164 -396.346172)
		(width 0.11684)
		(layer "In4.Cu")
		(net "SMB_BMC_GPU_EN")
	)
	(segment
		(start 5.088128 -345.739212)
		(end 5.088128 -167.44061)
		(width 0.11684)
		(layer "In4.Cu")
		(net "SMB_BMC_GPU_EN")
	)
	(segment
		(start 5.006848 -345.820492)
		(end 5.088128 -345.739212)
		(width 0.11684)
		(layer "In4.Cu")
		(net "SMB_BMC_GPU_EN")
	)
	(segment
		(start 6.655308 -165.87343)
		(end 12.587732 -165.87343)
		(width 0.11684)
		(layer "In4.Cu")
		(net "SMB_BMC_GPU_EN")
	)
	(segment
		(start 30.214824 -415.351976)
		(end 34.967164 -410.599636)
		(width 0.11684)
		(layer "In4.Cu")
		(net "SMB_BMC_GPU_EN")
	)
	(segment
		(start 31.118048 -391.024364)
		(end 31.118048 -379.50902)
		(width 0.11684)
		(layer "In4.Cu")
		(net "SMB_BMC_GPU_EN")
	)
	(segment
		(start 29.228034 -374.946164)
		(end 23.159466 -368.877596)
		(width 0.11684)
		(layer "In4.Cu")
		(net "SMB_BMC_GPU_EN")
	)
	(segment
		(start 11.772392 -362.456222)
		(end 11.772392 -356.700836)
		(width 0.11684)
		(layer "In4.Cu")
		(net "SMB_BMC_GPU_EN")
	)
	(segment
		(start 5.006848 -349.935292)
		(end 5.006848 -345.820492)
		(width 0.11684)
		(layer "In4.Cu")
		(net "SMB_BMC_GPU_EN")
	)
	(segment
		(start 66.437002 -136.554718)
		(end 69.848222 -133.143498)
		(width 0.11684)
		(layer "In4.Cu")
		(net "SMB_BMC_GPU_EN")
	)
	(segment
		(start 69.848222 -133.143498)
		(end 69.848222 -132.601208)
		(width 0.11684)
		(layer "In4.Cu")
		(net "SMB_BMC_GPU_EN")
	)
	(segment
		(start 31.276544 -391.820908)
		(end 31.118048 -391.024364)
		(width 0.11684)
		(layer "In4.Cu")
		(net "SMB_BMC_GPU_EN")
	)
	(segment
		(start 5.088128 -167.44061)
		(end 6.655308 -165.87343)
		(width 0.11684)
		(layer "In4.Cu")
		(net "SMB_BMC_GPU_EN")
	)
	(segment
		(start 23.159466 -368.877596)
		(end 18.193766 -368.877596)
		(width 0.11684)
		(layer "In4.Cu")
		(net "SMB_BMC_GPU_EN")
	)
	(segment
		(start 12.587732 -165.87343)
		(end 15.745714 -162.715448)
		(width 0.11684)
		(layer "In4.Cu")
		(net "SMB_BMC_GPU_EN")
	)
	(segment
		(start 11.772392 -356.700836)
		(end 5.006848 -349.935292)
		(width 0.11684)
		(layer "In4.Cu")
		(net "SMB_BMC_GPU_EN")
	)
	(segment
		(start 18.193766 -368.877596)
		(end 11.772392 -362.456222)
		(width 0.11684)
		(layer "In4.Cu")
		(net "SMB_BMC_GPU_EN")
	)
	(segment
		(start 15.745714 -162.715448)
		(end 15.745714 -153.732738)
		(width 0.11684)
		(layer "In4.Cu")
		(net "SMB_BMC_GPU_EN")
	)
	(segment
		(start 34.967164 -396.346172)
		(end 31.866586 -393.245594)
		(width 0.11684)
		(layer "In4.Cu")
		(net "SMB_BMC_GPU_EN")
	)
	(segment
		(start 31.866586 -393.245594)
		(end 31.276544 -391.820908)
		(width 0.11684)
		(layer "In4.Cu")
		(net "SMB_BMC_GPU_EN")
	)
	(segment
		(start 15.745714 -153.732738)
		(end 32.923734 -136.554718)
		(width 0.11684)
		(layer "In4.Cu")
		(net "SMB_BMC_GPU_EN")
	)
	(segment
		(start 32.923734 -136.554718)
		(end 66.437002 -136.554718)
		(width 0.11684)
		(layer "In4.Cu")
		(net "SMB_BMC_GPU_EN")
	)
	(segment
		(start 31.118048 -379.50902)
		(end 29.228034 -374.946164)
		(width 0.11684)
		(layer "In4.Cu")
		(net "SMB_BMC_GPU_EN")
	)
	(segment
		(start 157.646116 -127.072136)
		(end 163.63442 -121.083832)
		(width 0.11684)
		(layer "In6.Cu")
		(net "SMB_BMC_GPU_EN")
	)
	(segment
		(start 184.336944 -112.007904)
		(end 184.336944 -109.058202)
		(width 0.11684)
		(layer "In6.Cu")
		(net "SMB_BMC_GPU_EN")
	)
	(segment
		(start 115.574572 -127.424688)
		(end 155.810458 -127.424688)
		(width 0.11684)
		(layer "In6.Cu")
		(net "SMB_BMC_GPU_EN")
	)
	(segment
		(start 109.527086 -126.7587)
		(end 110.706916 -127.93853)
		(width 0.11684)
		(layer "In6.Cu")
		(net "SMB_BMC_GPU_EN")
	)
	(segment
		(start 184.336944 -109.058202)
		(end 184.732168 -108.662978)
		(width 0.11684)
		(layer "In6.Cu")
		(net "SMB_BMC_GPU_EN")
	)
	(segment
		(start 177.470308 -112.26292)
		(end 184.081928 -112.26292)
		(width 0.11684)
		(layer "In6.Cu")
		(net "SMB_BMC_GPU_EN")
	)
	(segment
		(start 112.510824 -126.840488)
		(end 114.990372 -126.840488)
		(width 0.11684)
		(layer "In6.Cu")
		(net "SMB_BMC_GPU_EN")
	)
	(segment
		(start 75.69073 -126.7587)
		(end 109.527086 -126.7587)
		(width 0.11684)
		(layer "In6.Cu")
		(net "SMB_BMC_GPU_EN")
	)
	(segment
		(start 156.16301 -127.072136)
		(end 157.646116 -127.072136)
		(width 0.11684)
		(layer "In6.Cu")
		(net "SMB_BMC_GPU_EN")
	)
	(segment
		(start 69.848222 -132.601208)
		(end 75.69073 -126.7587)
		(width 0.11684)
		(layer "In6.Cu")
		(net "SMB_BMC_GPU_EN")
	)
	(segment
		(start 163.63442 -119.428768)
		(end 165.259512 -117.803676)
		(width 0.11684)
		(layer "In6.Cu")
		(net "SMB_BMC_GPU_EN")
	)
	(segment
		(start 172.43806 -117.295168)
		(end 177.470308 -112.26292)
		(width 0.11684)
		(layer "In6.Cu")
		(net "SMB_BMC_GPU_EN")
	)
	(segment
		(start 111.412782 -127.93853)
		(end 112.510824 -126.840488)
		(width 0.11684)
		(layer "In6.Cu")
		(net "SMB_BMC_GPU_EN")
	)
	(segment
		(start 169.918888 -117.295168)
		(end 172.43806 -117.295168)
		(width 0.11684)
		(layer "In6.Cu")
		(net "SMB_BMC_GPU_EN")
	)
	(segment
		(start 169.41038 -117.803676)
		(end 169.918888 -117.295168)
		(width 0.11684)
		(layer "In6.Cu")
		(net "SMB_BMC_GPU_EN")
	)
	(segment
		(start 155.810458 -127.424688)
		(end 156.16301 -127.072136)
		(width 0.11684)
		(layer "In6.Cu")
		(net "SMB_BMC_GPU_EN")
	)
	(segment
		(start 163.63442 -121.083832)
		(end 163.63442 -119.428768)
		(width 0.11684)
		(layer "In6.Cu")
		(net "SMB_BMC_GPU_EN")
	)
	(segment
		(start 110.706916 -127.93853)
		(end 111.412782 -127.93853)
		(width 0.11684)
		(layer "In6.Cu")
		(net "SMB_BMC_GPU_EN")
	)
	(segment
		(start 114.990372 -126.840488)
		(end 115.574572 -127.424688)
		(width 0.11684)
		(layer "In6.Cu")
		(net "SMB_BMC_GPU_EN")
	)
	(segment
		(start 165.259512 -117.803676)
		(end 169.41038 -117.803676)
		(width 0.11684)
		(layer "In6.Cu")
		(net "SMB_BMC_GPU_EN")
	)
	(segment
		(start 184.081928 -112.26292)
		(end 184.336944 -112.007904)
		(width 0.11684)
		(layer "In6.Cu")
		(net "SMB_BMC_GPU_EN")
	)
	(segment
		(start 24.24684 -438.211214)
		(end 24.878538 -438.211214)
		(width 0.10668)
		(layer "F.Cu")
		(net "SMB_2_BMC_GPU_R_SDA")
	)
	(segment
		(start 25.306274 -437.783478)
		(end 26.056082 -437.783478)
		(width 0.10668)
		(layer "F.Cu")
		(net "SMB_2_BMC_GPU_R_SDA")
	)
	(segment
		(start 24.878538 -438.211214)
		(end 25.306274 -437.783478)
		(width 0.10668)
		(layer "F.Cu")
		(net "SMB_2_BMC_GPU_R_SDA")
	)
	(segment
		(start 22.436328 -437.980074)
		(end 22.455378 -437.999124)
		(width 0.10668)
		(layer "F.Cu")
		(net "SMB_2_BMC_GPU_R_SDA")
	)
	(segment
		(start 22.455378 -437.999124)
		(end 23.433278 -437.999124)
		(width 0.10668)
		(layer "F.Cu")
		(net "SMB_2_BMC_GPU_R_SDA")
	)
	(segment
		(start 23.433278 -437.999124)
		(end 23.645368 -438.211214)
		(width 0.10668)
		(layer "F.Cu")
		(net "SMB_2_BMC_GPU_R_SDA")
	)
	(segment
		(start 23.645368 -438.211214)
		(end 24.24684 -438.211214)
		(width 0.10668)
		(layer "F.Cu")
		(net "SMB_2_BMC_GPU_R_SDA")
	)
	(via
		(at 24.24684 -438.211214)
		(size 0.508)
		(drill 0.254)
		(layers "F.Cu" "B.Cu")
		(net "SMB_2_BMC_GPU_R_SDA")
	)
	(segment
		(start 32.77108 -438.592214)
		(end 33.360868 -438.592214)
		(width 0.10668)
		(layer "F.Cu")
		(net "SMB_2_BMC_GPU_R_SCL")
	)
	(segment
		(start 31.644082 -437.783478)
		(end 32.452818 -438.592214)
		(width 0.10668)
		(layer "F.Cu")
		(net "SMB_2_BMC_GPU_R_SCL")
	)
	(segment
		(start 33.360868 -438.592214)
		(end 33.468818 -438.484264)
		(width 0.10668)
		(layer "F.Cu")
		(net "SMB_2_BMC_GPU_R_SCL")
	)
	(segment
		(start 35.481768 -438.465214)
		(end 35.462718 -438.484264)
		(width 0.10668)
		(layer "F.Cu")
		(net "SMB_2_BMC_GPU_R_SCL")
	)
	(segment
		(start 33.468818 -438.484264)
		(end 33.722818 -438.484264)
		(width 0.10668)
		(layer "F.Cu")
		(net "SMB_2_BMC_GPU_R_SCL")
	)
	(segment
		(start 32.452818 -438.592214)
		(end 32.77108 -438.592214)
		(width 0.10668)
		(layer "F.Cu")
		(net "SMB_2_BMC_GPU_R_SCL")
	)
	(segment
		(start 35.462718 -438.484264)
		(end 33.722818 -438.484264)
		(width 0.10668)
		(layer "F.Cu")
		(net "SMB_2_BMC_GPU_R_SCL")
	)
	(segment
		(start 30.520894 -437.783478)
		(end 31.644082 -437.783478)
		(width 0.10668)
		(layer "F.Cu")
		(net "SMB_2_BMC_GPU_R_SCL")
	)
	(via
		(at 32.77108 -438.592214)
		(size 0.508)
		(drill 0.254)
		(layers "F.Cu" "B.Cu")
		(net "SMB_2_BMC_GPU_R_SCL")
	)
	(segment
		(start 26.056082 -437.133238)
		(end 25.233122 -437.133238)
		(width 0.10668)
		(layer "F.Cu")
		(net "SMB_2_BMC_GPU_BUF_R_SDA")
	)
	(segment
		(start 22.436328 -436.964074)
		(end 22.733254 -436.964074)
		(width 0.10668)
		(layer "F.Cu")
		(net "SMB_2_BMC_GPU_BUF_R_SDA")
	)
	(segment
		(start 24.914098 -436.814214)
		(end 24.2316 -436.814214)
		(width 0.10668)
		(layer "F.Cu")
		(net "SMB_2_BMC_GPU_BUF_R_SDA")
	)
	(segment
		(start 22.968204 -437.199024)
		(end 23.433278 -437.199024)
		(width 0.10668)
		(layer "F.Cu")
		(net "SMB_2_BMC_GPU_BUF_R_SDA")
	)
	(segment
		(start 23.818088 -436.814214)
		(end 23.433278 -437.199024)
		(width 0.10668)
		(layer "F.Cu")
		(net "SMB_2_BMC_GPU_BUF_R_SDA")
	)
	(segment
		(start 22.436328 -435.948074)
		(end 22.436328 -436.964074)
		(width 0.10668)
		(layer "F.Cu")
		(net "SMB_2_BMC_GPU_BUF_R_SDA")
	)
	(segment
		(start 25.233122 -437.133238)
		(end 24.914098 -436.814214)
		(width 0.10668)
		(layer "F.Cu")
		(net "SMB_2_BMC_GPU_BUF_R_SDA")
	)
	(segment
		(start 22.733254 -436.964074)
		(end 22.968204 -437.199024)
		(width 0.10668)
		(layer "F.Cu")
		(net "SMB_2_BMC_GPU_BUF_R_SDA")
	)
	(segment
		(start 24.2316 -436.814214)
		(end 23.818088 -436.814214)
		(width 0.10668)
		(layer "F.Cu")
		(net "SMB_2_BMC_GPU_BUF_R_SDA")
	)
	(via
		(at 24.2316 -436.814214)
		(size 0.508)
		(drill 0.254)
		(layers "F.Cu" "B.Cu")
		(net "SMB_2_BMC_GPU_BUF_R_SDA")
	)
	(segment
		(start 32.300672 -437.31053)
		(end 32.674306 -437.684164)
		(width 0.10668)
		(layer "F.Cu")
		(net "SMB_2_BMC_GPU_BUF_R_SCL")
	)
	(segment
		(start 30.520894 -437.133238)
		(end 31.690818 -437.133238)
		(width 0.10668)
		(layer "F.Cu")
		(net "SMB_2_BMC_GPU_BUF_R_SCL")
	)
	(segment
		(start 35.481768 -437.449214)
		(end 35.246818 -437.684164)
		(width 0.10668)
		(layer "F.Cu")
		(net "SMB_2_BMC_GPU_BUF_R_SCL")
	)
	(segment
		(start 31.86811 -437.31053)
		(end 32.300672 -437.31053)
		(width 0.10668)
		(layer "F.Cu")
		(net "SMB_2_BMC_GPU_BUF_R_SCL")
	)
	(segment
		(start 32.674306 -437.684164)
		(end 33.722818 -437.684164)
		(width 0.10668)
		(layer "F.Cu")
		(net "SMB_2_BMC_GPU_BUF_R_SCL")
	)
	(segment
		(start 35.246818 -437.684164)
		(end 33.722818 -437.684164)
		(width 0.10668)
		(layer "F.Cu")
		(net "SMB_2_BMC_GPU_BUF_R_SCL")
	)
	(segment
		(start 31.690818 -437.133238)
		(end 31.86811 -437.31053)
		(width 0.10668)
		(layer "F.Cu")
		(net "SMB_2_BMC_GPU_BUF_R_SCL")
	)
	(segment
		(start 35.481768 -436.433214)
		(end 35.481768 -437.449214)
		(width 0.10668)
		(layer "F.Cu")
		(net "SMB_2_BMC_GPU_BUF_R_SCL")
	)
	(via
		(at 32.300672 -437.31053)
		(size 0.508)
		(drill 0.254)
		(layers "F.Cu" "B.Cu")
		(net "SMB_2_BMC_GPU_BUF_R_SCL")
	)
	(segment
		(start 31.338012 -432.152044)
		(end 30.507178 -432.152044)
		(width 0.10668)
		(layer "F.Cu")
		(net "SMB_1_BMC_GPU_R_SDA")
	)
	(segment
		(start 34.75863 -432.056794)
		(end 34.65068 -432.164744)
		(width 0.10668)
		(layer "F.Cu")
		(net "SMB_1_BMC_GPU_R_SDA")
	)
	(segment
		(start 33.355026 -431.842164)
		(end 32.43834 -431.842164)
		(width 0.10668)
		(layer "F.Cu")
		(net "SMB_1_BMC_GPU_R_SDA")
	)
	(segment
		(start 32.43834 -431.842164)
		(end 31.647892 -431.842164)
		(width 0.10668)
		(layer "F.Cu")
		(net "SMB_1_BMC_GPU_R_SDA")
	)
	(segment
		(start 33.63468 -432.121818)
		(end 33.355026 -431.842164)
		(width 0.10668)
		(layer "F.Cu")
		(net "SMB_1_BMC_GPU_R_SDA")
	)
	(segment
		(start 34.65068 -432.164744)
		(end 33.63468 -432.164744)
		(width 0.10668)
		(layer "F.Cu")
		(net "SMB_1_BMC_GPU_R_SDA")
	)
	(segment
		(start 31.647892 -431.842164)
		(end 31.338012 -432.152044)
		(width 0.10668)
		(layer "F.Cu")
		(net "SMB_1_BMC_GPU_R_SDA")
	)
	(segment
		(start 33.63468 -432.164744)
		(end 33.63468 -432.121818)
		(width 0.10668)
		(layer "F.Cu")
		(net "SMB_1_BMC_GPU_R_SDA")
	)
	(via
		(at 32.43834 -431.842164)
		(size 0.508)
		(drill 0.254)
		(layers "F.Cu" "B.Cu")
		(net "SMB_1_BMC_GPU_R_SDA")
	)
	(segment
		(start 23.495 -431.51425)
		(end 24.106124 -430.903126)
		(width 0.10668)
		(layer "F.Cu")
		(net "SMB_1_BMC_GPU_R_SCL")
	)
	(segment
		(start 22.47773 -431.421794)
		(end 22.570186 -431.51425)
		(width 0.10668)
		(layer "F.Cu")
		(net "SMB_1_BMC_GPU_R_SCL")
	)
	(segment
		(start 24.409654 -431.575718)
		(end 24.98598 -432.152044)
		(width 0.10668)
		(layer "F.Cu")
		(net "SMB_1_BMC_GPU_R_SCL")
	)
	(segment
		(start 24.106124 -430.903126)
		(end 24.409654 -430.903126)
		(width 0.10668)
		(layer "F.Cu")
		(net "SMB_1_BMC_GPU_R_SCL")
	)
	(segment
		(start 24.409654 -430.903126)
		(end 24.409654 -431.575718)
		(width 0.10668)
		(layer "F.Cu")
		(net "SMB_1_BMC_GPU_R_SCL")
	)
	(segment
		(start 24.98598 -432.152044)
		(end 26.042366 -432.152044)
		(width 0.10668)
		(layer "F.Cu")
		(net "SMB_1_BMC_GPU_R_SCL")
	)
	(segment
		(start 22.570186 -431.51425)
		(end 23.495 -431.51425)
		(width 0.10668)
		(layer "F.Cu")
		(net "SMB_1_BMC_GPU_R_SCL")
	)
	(via
		(at 24.409654 -430.903126)
		(size 0.508)
		(drill 0.254)
		(layers "F.Cu" "B.Cu")
		(net "SMB_1_BMC_GPU_R_SCL")
	)
	(segment
		(start 34.732722 -434.128164)
		(end 34.732722 -433.112164)
		(width 0.10668)
		(layer "F.Cu")
		(net "SMB_1_BMC_GPU_BUF_R_SDA")
	)
	(segment
		(start 34.732722 -433.112164)
		(end 34.497772 -432.877214)
		(width 0.10668)
		(layer "F.Cu")
		(net "SMB_1_BMC_GPU_BUF_R_SDA")
	)
	(segment
		(start 33.63468 -432.964844)
		(end 33.188656 -432.964844)
		(width 0.10668)
		(layer "F.Cu")
		(net "SMB_1_BMC_GPU_BUF_R_SDA")
	)
	(segment
		(start 32.33166 -433.239164)
		(end 31.662116 -433.239164)
		(width 0.10668)
		(layer "F.Cu")
		(net "SMB_1_BMC_GPU_BUF_R_SDA")
	)
	(segment
		(start 33.72231 -432.877214)
		(end 33.63468 -432.964844)
		(width 0.10668)
		(layer "F.Cu")
		(net "SMB_1_BMC_GPU_BUF_R_SDA")
	)
	(segment
		(start 31.662116 -433.239164)
		(end 31.225236 -432.802284)
		(width 0.10668)
		(layer "F.Cu")
		(net "SMB_1_BMC_GPU_BUF_R_SDA")
	)
	(segment
		(start 34.497772 -432.877214)
		(end 33.72231 -432.877214)
		(width 0.10668)
		(layer "F.Cu")
		(net "SMB_1_BMC_GPU_BUF_R_SDA")
	)
	(segment
		(start 31.225236 -432.802284)
		(end 30.507178 -432.802284)
		(width 0.10668)
		(layer "F.Cu")
		(net "SMB_1_BMC_GPU_BUF_R_SDA")
	)
	(segment
		(start 32.914336 -433.239164)
		(end 32.33166 -433.239164)
		(width 0.10668)
		(layer "F.Cu")
		(net "SMB_1_BMC_GPU_BUF_R_SDA")
	)
	(segment
		(start 33.188656 -432.964844)
		(end 32.914336 -433.239164)
		(width 0.10668)
		(layer "F.Cu")
		(net "SMB_1_BMC_GPU_BUF_R_SDA")
	)
	(via
		(at 32.33166 -433.239164)
		(size 0.508)
		(drill 0.254)
		(layers "F.Cu" "B.Cu")
		(net "SMB_1_BMC_GPU_BUF_R_SDA")
	)
	(segment
		(start 24.921718 -432.802284)
		(end 26.042366 -432.802284)
		(width 0.10668)
		(layer "F.Cu")
		(net "SMB_1_BMC_GPU_BUF_R_SCL")
	)
	(segment
		(start 24.52497 -433.199032)
		(end 24.921718 -432.802284)
		(width 0.10668)
		(layer "F.Cu")
		(net "SMB_1_BMC_GPU_BUF_R_SCL")
	)
	(segment
		(start 23.495 -432.31435)
		(end 23.640288 -432.31435)
		(width 0.10668)
		(layer "F.Cu")
		(net "SMB_1_BMC_GPU_BUF_R_SCL")
	)
	(segment
		(start 22.47773 -432.437794)
		(end 23.371556 -432.437794)
		(width 0.10668)
		(layer "F.Cu")
		(net "SMB_1_BMC_GPU_BUF_R_SCL")
	)
	(segment
		(start 23.640288 -432.31435)
		(end 24.52497 -433.199032)
		(width 0.10668)
		(layer "F.Cu")
		(net "SMB_1_BMC_GPU_BUF_R_SCL")
	)
	(segment
		(start 23.371556 -432.437794)
		(end 23.495 -432.31435)
		(width 0.10668)
		(layer "F.Cu")
		(net "SMB_1_BMC_GPU_BUF_R_SCL")
	)
	(segment
		(start 22.47773 -433.453794)
		(end 22.47773 -432.437794)
		(width 0.10668)
		(layer "F.Cu")
		(net "SMB_1_BMC_GPU_BUF_R_SCL")
	)
	(via
		(at 24.52497 -433.199032)
		(size 0.508)
		(drill 0.254)
		(layers "F.Cu" "B.Cu")
		(net "SMB_1_BMC_GPU_BUF_R_SCL")
	)
	(segment
		(start 151.065738 -26.791158)
		(end 151.401272 -27.126692)
		(width 0.10668)
		(layer "F.Cu")
		(net "SGPIO_SCM_RESET_R_N")
	)
	(segment
		(start 170.8912 -94.433898)
		(end 170.8912 -93.817948)
		(width 0.10668)
		(layer "F.Cu")
		(net "SGPIO_SCM_RESET_R_N")
	)
	(segment
		(start 152.657048 -16.549878)
		(end 152.657048 -18.521172)
		(width 0.10668)
		(layer "F.Cu")
		(net "SGPIO_SCM_RESET_R_N")
	)
	(segment
		(start 152.657048 -18.521172)
		(end 151.065738 -20.112482)
		(width 0.10668)
		(layer "F.Cu")
		(net "SGPIO_SCM_RESET_R_N")
	)
	(segment
		(start 151.065738 -20.112482)
		(end 151.065738 -26.791158)
		(width 0.10668)
		(layer "F.Cu")
		(net "SGPIO_SCM_RESET_R_N")
	)
	(via
		(at 151.401272 -27.126692)
		(size 0.508)
		(drill 0.254)
		(layers "F.Cu" "B.Cu")
		(net "SGPIO_SCM_RESET_R_N")
	)
	(via
		(at 170.8912 -93.817948)
		(size 0.508)
		(drill 0.254)
		(layers "F.Cu" "B.Cu")
		(net "SGPIO_SCM_RESET_R_N")
	)
	(segment
		(start 168.168828 -93.817948)
		(end 163.316666 -88.965786)
		(width 0.11684)
		(layer "In4.Cu")
		(net "SGPIO_SCM_RESET_R_N")
	)
	(segment
		(start 163.316666 -88.965786)
		(end 163.316666 -81.696814)
		(width 0.11684)
		(layer "In4.Cu")
		(net "SGPIO_SCM_RESET_R_N")
	)
	(segment
		(start 154.471878 -45.37583)
		(end 155.600146 -44.247562)
		(width 0.11684)
		(layer "In4.Cu")
		(net "SGPIO_SCM_RESET_R_N")
	)
	(segment
		(start 155.600146 -34.027618)
		(end 151.685498 -30.11297)
		(width 0.11684)
		(layer "In4.Cu")
		(net "SGPIO_SCM_RESET_R_N")
	)
	(segment
		(start 155.946094 -56.324246)
		(end 155.946094 -48.415956)
		(width 0.11684)
		(layer "In4.Cu")
		(net "SGPIO_SCM_RESET_R_N")
	)
	(segment
		(start 156.528516 -63.898526)
		(end 156.528516 -56.906668)
		(width 0.11684)
		(layer "In4.Cu")
		(net "SGPIO_SCM_RESET_R_N")
	)
	(segment
		(start 154.471878 -46.94174)
		(end 154.471878 -45.37583)
		(width 0.11684)
		(layer "In4.Cu")
		(net "SGPIO_SCM_RESET_R_N")
	)
	(segment
		(start 151.685498 -27.410918)
		(end 151.401272 -27.126692)
		(width 0.11684)
		(layer "In4.Cu")
		(net "SGPIO_SCM_RESET_R_N")
	)
	(segment
		(start 170.8912 -93.817948)
		(end 168.168828 -93.817948)
		(width 0.11684)
		(layer "In4.Cu")
		(net "SGPIO_SCM_RESET_R_N")
	)
	(segment
		(start 155.946094 -48.415956)
		(end 154.471878 -46.94174)
		(width 0.11684)
		(layer "In4.Cu")
		(net "SGPIO_SCM_RESET_R_N")
	)
	(segment
		(start 162.472116 -69.842126)
		(end 156.528516 -63.898526)
		(width 0.11684)
		(layer "In4.Cu")
		(net "SGPIO_SCM_RESET_R_N")
	)
	(segment
		(start 156.528516 -56.906668)
		(end 155.946094 -56.324246)
		(width 0.11684)
		(layer "In4.Cu")
		(net "SGPIO_SCM_RESET_R_N")
	)
	(segment
		(start 151.685498 -30.11297)
		(end 151.685498 -27.410918)
		(width 0.11684)
		(layer "In4.Cu")
		(net "SGPIO_SCM_RESET_R_N")
	)
	(segment
		(start 162.472116 -80.852264)
		(end 162.472116 -69.842126)
		(width 0.11684)
		(layer "In4.Cu")
		(net "SGPIO_SCM_RESET_R_N")
	)
	(segment
		(start 155.600146 -44.247562)
		(end 155.600146 -34.027618)
		(width 0.11684)
		(layer "In4.Cu")
		(net "SGPIO_SCM_RESET_R_N")
	)
	(segment
		(start 163.316666 -81.696814)
		(end 162.472116 -80.852264)
		(width 0.11684)
		(layer "In4.Cu")
		(net "SGPIO_SCM_RESET_R_N")
	)
	(segment
		(start 151.980646 -23.837392)
		(end 151.70785 -24.110188)
		(width 0.10668)
		(layer "F.Cu")
		(net "SGPIO_SCM_LD_R_<1>")
	)
	(segment
		(start 152.208992 -19.969734)
		(end 151.980646 -20.19808)
		(width 0.10668)
		(layer "F.Cu")
		(net "SGPIO_SCM_LD_R_<1>")
	)
	(segment
		(start 153.856944 -18.89379)
		(end 152.781 -19.969734)
		(width 0.10668)
		(layer "F.Cu")
		(net "SGPIO_SCM_LD_R_<1>")
	)
	(segment
		(start 151.980646 -20.19808)
		(end 151.980646 -23.837392)
		(width 0.10668)
		(layer "F.Cu")
		(net "SGPIO_SCM_LD_R_<1>")
	)
	(segment
		(start 172.9232 -94.433898)
		(end 172.9232 -93.817948)
		(width 0.10668)
		(layer "F.Cu")
		(net "SGPIO_SCM_LD_R_<1>")
	)
	(segment
		(start 153.856944 -16.549878)
		(end 153.856944 -18.89379)
		(width 0.10668)
		(layer "F.Cu")
		(net "SGPIO_SCM_LD_R_<1>")
	)
	(segment
		(start 152.781 -19.969734)
		(end 152.208992 -19.969734)
		(width 0.10668)
		(layer "F.Cu")
		(net "SGPIO_SCM_LD_R_<1>")
	)
	(via
		(at 172.9232 -93.817948)
		(size 0.508)
		(drill 0.254)
		(layers "F.Cu" "B.Cu")
		(net "SGPIO_SCM_LD_R_<1>")
	)
	(via
		(at 151.70785 -24.110188)
		(size 0.508)
		(drill 0.254)
		(layers "F.Cu" "B.Cu")
		(net "SGPIO_SCM_LD_R_<1>")
	)
	(segment
		(start 165.334442 -87.64524)
		(end 169.23004 -91.540838)
		(width 0.11684)
		(layer "In4.Cu")
		(net "SGPIO_SCM_LD_R_<1>")
	)
	(segment
		(start 154.45232 -25.395936)
		(end 154.45232 -29.989526)
		(width 0.11684)
		(layer "In4.Cu")
		(net "SGPIO_SCM_LD_R_<1>")
	)
	(segment
		(start 171.213018 -91.540838)
		(end 172.9232 -93.25102)
		(width 0.11684)
		(layer "In4.Cu")
		(net "SGPIO_SCM_LD_R_<1>")
	)
	(segment
		(start 156.25826 -23.612348)
		(end 156.596588 -23.950676)
		(width 0.11684)
		(layer "In4.Cu")
		(net "SGPIO_SCM_LD_R_<1>")
	)
	(segment
		(start 169.23004 -91.540838)
		(end 171.213018 -91.540838)
		(width 0.11684)
		(layer "In4.Cu")
		(net "SGPIO_SCM_LD_R_<1>")
	)
	(segment
		(start 159.803846 -64.788034)
		(end 165.334442 -70.31863)
		(width 0.11684)
		(layer "In4.Cu")
		(net "SGPIO_SCM_LD_R_<1>")
	)
	(segment
		(start 154.45232 -29.989526)
		(end 159.803846 -35.341052)
		(width 0.11684)
		(layer "In4.Cu")
		(net "SGPIO_SCM_LD_R_<1>")
	)
	(segment
		(start 165.334442 -70.31863)
		(end 165.334442 -87.64524)
		(width 0.11684)
		(layer "In4.Cu")
		(net "SGPIO_SCM_LD_R_<1>")
	)
	(segment
		(start 156.596588 -24.725884)
		(end 156.227272 -25.0952)
		(width 0.11684)
		(layer "In4.Cu")
		(net "SGPIO_SCM_LD_R_<1>")
	)
	(segment
		(start 154.753056 -25.0952)
		(end 154.45232 -25.395936)
		(width 0.11684)
		(layer "In4.Cu")
		(net "SGPIO_SCM_LD_R_<1>")
	)
	(segment
		(start 172.9232 -93.25102)
		(end 172.9232 -93.817948)
		(width 0.11684)
		(layer "In4.Cu")
		(net "SGPIO_SCM_LD_R_<1>")
	)
	(segment
		(start 156.227272 -25.0952)
		(end 154.753056 -25.0952)
		(width 0.11684)
		(layer "In4.Cu")
		(net "SGPIO_SCM_LD_R_<1>")
	)
	(segment
		(start 156.596588 -23.950676)
		(end 156.596588 -24.725884)
		(width 0.11684)
		(layer "In4.Cu")
		(net "SGPIO_SCM_LD_R_<1>")
	)
	(segment
		(start 159.803846 -35.341052)
		(end 159.803846 -64.788034)
		(width 0.11684)
		(layer "In4.Cu")
		(net "SGPIO_SCM_LD_R_<1>")
	)
	(segment
		(start 152.67813 -23.612348)
		(end 156.25826 -23.612348)
		(width 0.11684)
		(layer "In4.Cu")
		(net "SGPIO_SCM_LD_R_<1>")
	)
	(segment
		(start 152.18029 -24.110188)
		(end 152.67813 -23.612348)
		(width 0.11684)
		(layer "In4.Cu")
		(net "SGPIO_SCM_LD_R_<1>")
	)
	(segment
		(start 151.70785 -24.110188)
		(end 152.18029 -24.110188)
		(width 0.11684)
		(layer "In4.Cu")
		(net "SGPIO_SCM_LD_R_<1>")
	)
	(segment
		(start 156.856938 -19.818096)
		(end 156.029152 -20.645882)
		(width 0.10668)
		(layer "F.Cu")
		(net "SGPIO_SCM_LD_R_<0>")
	)
	(segment
		(start 156.856938 -16.549878)
		(end 156.856938 -19.818096)
		(width 0.10668)
		(layer "F.Cu")
		(net "SGPIO_SCM_LD_R_<0>")
	)
	(segment
		(start 156.029152 -20.645882)
		(end 156.029152 -22.883368)
		(width 0.10668)
		(layer "F.Cu")
		(net "SGPIO_SCM_LD_R_<0>")
	)
	(segment
		(start 156.029152 -22.883368)
		(end 156.027628 -22.883368)
		(width 0.10668)
		(layer "F.Cu")
		(net "SGPIO_SCM_LD_R_<0>")
	)
	(segment
		(start 171.577 -99.894898)
		(end 171.577 -99.278948)
		(width 0.10668)
		(layer "F.Cu")
		(net "SGPIO_SCM_LD_R_<0>")
	)
	(segment
		(start 156.027628 -22.883368)
		(end 156.027628 -24.351742)
		(width 0.10668)
		(layer "F.Cu")
		(net "SGPIO_SCM_LD_R_<0>")
	)
	(via
		(at 171.577 -99.278948)
		(size 0.508)
		(drill 0.254)
		(layers "F.Cu" "B.Cu")
		(net "SGPIO_SCM_LD_R_<0>")
	)
	(via
		(at 156.027628 -24.351742)
		(size 0.508)
		(drill 0.254)
		(layers "F.Cu" "B.Cu")
		(net "SGPIO_SCM_LD_R_<0>")
	)
	(segment
		(start 159.37484 -53.865526)
		(end 159.37484 -64.95542)
		(width 0.11684)
		(layer "In4.Cu")
		(net "SGPIO_SCM_LD_R_<0>")
	)
	(segment
		(start 158.246318 -52.737004)
		(end 159.37484 -53.865526)
		(width 0.11684)
		(layer "In4.Cu")
		(net "SGPIO_SCM_LD_R_<0>")
	)
	(segment
		(start 172.385736 -93.39961)
		(end 172.385736 -97.725484)
		(width 0.11684)
		(layer "In4.Cu")
		(net "SGPIO_SCM_LD_R_<0>")
	)
	(segment
		(start 153.970228 -25.25903)
		(end 153.970228 -30.463744)
		(width 0.11684)
		(layer "In4.Cu")
		(net "SGPIO_SCM_LD_R_<0>")
	)
	(segment
		(start 159.37484 -64.95542)
		(end 164.832792 -70.413372)
		(width 0.11684)
		(layer "In4.Cu")
		(net "SGPIO_SCM_LD_R_<0>")
	)
	(segment
		(start 154.616404 -24.612854)
		(end 153.970228 -25.25903)
		(width 0.11684)
		(layer "In4.Cu")
		(net "SGPIO_SCM_LD_R_<0>")
	)
	(segment
		(start 158.246318 -34.739834)
		(end 158.246318 -52.737004)
		(width 0.11684)
		(layer "In4.Cu")
		(net "SGPIO_SCM_LD_R_<0>")
	)
	(segment
		(start 156.027628 -24.351742)
		(end 155.766516 -24.612854)
		(width 0.11684)
		(layer "In4.Cu")
		(net "SGPIO_SCM_LD_R_<0>")
	)
	(segment
		(start 172.385736 -97.725484)
		(end 171.577 -98.53422)
		(width 0.11684)
		(layer "In4.Cu")
		(net "SGPIO_SCM_LD_R_<0>")
	)
	(segment
		(start 171.00677 -92.020644)
		(end 172.385736 -93.39961)
		(width 0.11684)
		(layer "In4.Cu")
		(net "SGPIO_SCM_LD_R_<0>")
	)
	(segment
		(start 169.03573 -92.020644)
		(end 171.00677 -92.020644)
		(width 0.11684)
		(layer "In4.Cu")
		(net "SGPIO_SCM_LD_R_<0>")
	)
	(segment
		(start 153.970228 -30.463744)
		(end 158.246318 -34.739834)
		(width 0.11684)
		(layer "In4.Cu")
		(net "SGPIO_SCM_LD_R_<0>")
	)
	(segment
		(start 155.766516 -24.612854)
		(end 154.616404 -24.612854)
		(width 0.11684)
		(layer "In4.Cu")
		(net "SGPIO_SCM_LD_R_<0>")
	)
	(segment
		(start 164.832792 -87.817706)
		(end 169.03573 -92.020644)
		(width 0.11684)
		(layer "In4.Cu")
		(net "SGPIO_SCM_LD_R_<0>")
	)
	(segment
		(start 164.832792 -70.413372)
		(end 164.832792 -87.817706)
		(width 0.11684)
		(layer "In4.Cu")
		(net "SGPIO_SCM_LD_R_<0>")
	)
	(segment
		(start 171.577 -98.53422)
		(end 171.577 -99.278948)
		(width 0.11684)
		(layer "In4.Cu")
		(net "SGPIO_SCM_LD_R_<0>")
	)
	(segment
		(start 155.657042 -19.931888)
		(end 154.943048 -20.645882)
		(width 0.10668)
		(layer "F.Cu")
		(net "SGPIO_SCM_DO_R_<1>")
	)
	(segment
		(start 155.657042 -16.549878)
		(end 155.657042 -19.931888)
		(width 0.10668)
		(layer "F.Cu")
		(net "SGPIO_SCM_DO_R_<1>")
	)
	(segment
		(start 154.943048 -25.58923)
		(end 154.942286 -25.589992)
		(width 0.10668)
		(layer "F.Cu")
		(net "SGPIO_SCM_DO_R_<1>")
	)
	(segment
		(start 154.943048 -20.645882)
		(end 154.943048 -25.58923)
		(width 0.10668)
		(layer "F.Cu")
		(net "SGPIO_SCM_DO_R_<1>")
	)
	(segment
		(start 172.593 -99.894898)
		(end 172.593 -99.278948)
		(width 0.10668)
		(layer "F.Cu")
		(net "SGPIO_SCM_DO_R_<1>")
	)
	(via
		(at 172.593 -99.278948)
		(size 0.508)
		(drill 0.254)
		(layers "F.Cu" "B.Cu")
		(net "SGPIO_SCM_DO_R_<1>")
	)
	(via
		(at 154.942286 -25.589992)
		(size 0.508)
		(drill 0.254)
		(layers "F.Cu" "B.Cu")
		(net "SGPIO_SCM_DO_R_<1>")
	)
	(segment
		(start 162.252914 -65.023492)
		(end 162.252914 -65.188592)
		(width 0.11684)
		(layer "In4.Cu")
		(net "SGPIO_SCM_DO_R_<1>")
	)
	(segment
		(start 160.514284 -64.692276)
		(end 160.649158 -64.82715)
		(width 0.11684)
		(layer "In4.Cu")
		(net "SGPIO_SCM_DO_R_<1>")
	)
	(segment
		(start 154.942286 -29.824934)
		(end 160.266634 -35.149282)
		(width 0.11684)
		(layer "In4.Cu")
		(net "SGPIO_SCM_DO_R_<1>")
	)
	(segment
		(start 161.114232 -65.127124)
		(end 161.114232 -65.292224)
		(width 0.11684)
		(layer "In4.Cu")
		(net "SGPIO_SCM_DO_R_<1>")
	)
	(segment
		(start 162.449002 -66.626994)
		(end 162.614102 -66.626994)
		(width 0.11684)
		(layer "In4.Cu")
		(net "SGPIO_SCM_DO_R_<1>")
	)
	(segment
		(start 162.852862 -65.62344)
		(end 162.852862 -65.78854)
		(width 0.11684)
		(layer "In4.Cu")
		(net "SGPIO_SCM_DO_R_<1>")
	)
	(segment
		(start 160.649158 -64.82715)
		(end 160.814258 -64.82715)
		(width 0.11684)
		(layer "In4.Cu")
		(net "SGPIO_SCM_DO_R_<1>")
	)
	(segment
		(start 160.266634 -35.149282)
		(end 160.266634 -63.037212)
		(width 0.11684)
		(layer "In4.Cu")
		(net "SGPIO_SCM_DO_R_<1>")
	)
	(segment
		(start 162.252914 -65.188592)
		(end 161.71418 -65.727072)
		(width 0.11684)
		(layer "In4.Cu")
		(net "SGPIO_SCM_DO_R_<1>")
	)
	(segment
		(start 165.79723 -68.567808)
		(end 165.79723 -87.479378)
		(width 0.11684)
		(layer "In4.Cu")
		(net "SGPIO_SCM_DO_R_<1>")
	)
	(segment
		(start 161.518092 -64.28867)
		(end 161.652966 -64.423544)
		(width 0.11684)
		(layer "In4.Cu")
		(net "SGPIO_SCM_DO_R_<1>")
	)
	(segment
		(start 161.95294 -64.888618)
		(end 162.11804 -64.888618)
		(width 0.11684)
		(layer "In4.Cu")
		(net "SGPIO_SCM_DO_R_<1>")
	)
	(segment
		(start 161.352992 -64.28867)
		(end 161.518092 -64.28867)
		(width 0.11684)
		(layer "In4.Cu")
		(net "SGPIO_SCM_DO_R_<1>")
	)
	(segment
		(start 161.414206 -65.427098)
		(end 161.95294 -64.888618)
		(width 0.11684)
		(layer "In4.Cu")
		(net "SGPIO_SCM_DO_R_<1>")
	)
	(segment
		(start 162.852862 -65.78854)
		(end 162.314128 -66.32702)
		(width 0.11684)
		(layer "In4.Cu")
		(net "SGPIO_SCM_DO_R_<1>")
	)
	(segment
		(start 162.552888 -65.488566)
		(end 162.717988 -65.488566)
		(width 0.11684)
		(layer "In4.Cu")
		(net "SGPIO_SCM_DO_R_<1>")
	)
	(segment
		(start 161.053018 -63.823596)
		(end 161.053018 -63.988696)
		(width 0.11684)
		(layer "In4.Cu")
		(net "SGPIO_SCM_DO_R_<1>")
	)
	(segment
		(start 162.314128 -66.49212)
		(end 162.449002 -66.626994)
		(width 0.11684)
		(layer "In4.Cu")
		(net "SGPIO_SCM_DO_R_<1>")
	)
	(segment
		(start 162.11804 -64.888618)
		(end 162.252914 -65.023492)
		(width 0.11684)
		(layer "In4.Cu")
		(net "SGPIO_SCM_DO_R_<1>")
	)
	(segment
		(start 165.79723 -87.479378)
		(end 169.39006 -91.072208)
		(width 0.11684)
		(layer "In4.Cu")
		(net "SGPIO_SCM_DO_R_<1>")
	)
	(segment
		(start 160.266634 -63.037212)
		(end 161.053018 -63.823596)
		(width 0.11684)
		(layer "In4.Cu")
		(net "SGPIO_SCM_DO_R_<1>")
	)
	(segment
		(start 161.652966 -64.588644)
		(end 161.114232 -65.127124)
		(width 0.11684)
		(layer "In4.Cu")
		(net "SGPIO_SCM_DO_R_<1>")
	)
	(segment
		(start 173.397672 -92.07119)
		(end 173.397672 -98.03638)
		(width 0.11684)
		(layer "In4.Cu")
		(net "SGPIO_SCM_DO_R_<1>")
	)
	(segment
		(start 161.249106 -65.427098)
		(end 161.414206 -65.427098)
		(width 0.11684)
		(layer "In4.Cu")
		(net "SGPIO_SCM_DO_R_<1>")
	)
	(segment
		(start 161.652966 -64.423544)
		(end 161.652966 -64.588644)
		(width 0.11684)
		(layer "In4.Cu")
		(net "SGPIO_SCM_DO_R_<1>")
	)
	(segment
		(start 169.39006 -91.072208)
		(end 172.39869 -91.072208)
		(width 0.11684)
		(layer "In4.Cu")
		(net "SGPIO_SCM_DO_R_<1>")
	)
	(segment
		(start 162.014154 -66.027046)
		(end 162.552888 -65.488566)
		(width 0.11684)
		(layer "In4.Cu")
		(net "SGPIO_SCM_DO_R_<1>")
	)
	(segment
		(start 162.314128 -66.32702)
		(end 162.314128 -66.49212)
		(width 0.11684)
		(layer "In4.Cu")
		(net "SGPIO_SCM_DO_R_<1>")
	)
	(segment
		(start 163.317936 -66.088514)
		(end 165.79723 -68.567808)
		(width 0.11684)
		(layer "In4.Cu")
		(net "SGPIO_SCM_DO_R_<1>")
	)
	(segment
		(start 161.71418 -65.892172)
		(end 161.849054 -66.027046)
		(width 0.11684)
		(layer "In4.Cu")
		(net "SGPIO_SCM_DO_R_<1>")
	)
	(segment
		(start 160.814258 -64.82715)
		(end 161.352992 -64.28867)
		(width 0.11684)
		(layer "In4.Cu")
		(net "SGPIO_SCM_DO_R_<1>")
	)
	(segment
		(start 161.114232 -65.292224)
		(end 161.249106 -65.427098)
		(width 0.11684)
		(layer "In4.Cu")
		(net "SGPIO_SCM_DO_R_<1>")
	)
	(segment
		(start 161.053018 -63.988696)
		(end 160.514284 -64.527176)
		(width 0.11684)
		(layer "In4.Cu")
		(net "SGPIO_SCM_DO_R_<1>")
	)
	(segment
		(start 154.942286 -25.589992)
		(end 154.942286 -29.824934)
		(width 0.11684)
		(layer "In4.Cu")
		(net "SGPIO_SCM_DO_R_<1>")
	)
	(segment
		(start 162.614102 -66.626994)
		(end 163.152836 -66.088514)
		(width 0.11684)
		(layer "In4.Cu")
		(net "SGPIO_SCM_DO_R_<1>")
	)
	(segment
		(start 160.514284 -64.527176)
		(end 160.514284 -64.692276)
		(width 0.11684)
		(layer "In4.Cu")
		(net "SGPIO_SCM_DO_R_<1>")
	)
	(segment
		(start 161.71418 -65.727072)
		(end 161.71418 -65.892172)
		(width 0.11684)
		(layer "In4.Cu")
		(net "SGPIO_SCM_DO_R_<1>")
	)
	(segment
		(start 172.39869 -91.072208)
		(end 173.397672 -92.07119)
		(width 0.11684)
		(layer "In4.Cu")
		(net "SGPIO_SCM_DO_R_<1>")
	)
	(segment
		(start 163.152836 -66.088514)
		(end 163.317936 -66.088514)
		(width 0.11684)
		(layer "In4.Cu")
		(net "SGPIO_SCM_DO_R_<1>")
	)
	(segment
		(start 172.59554 -99.276408)
		(end 172.593 -99.278948)
		(width 0.11684)
		(layer "In4.Cu")
		(net "SGPIO_SCM_DO_R_<1>")
	)
	(segment
		(start 172.59554 -98.838512)
		(end 172.59554 -99.276408)
		(width 0.11684)
		(layer "In4.Cu")
		(net "SGPIO_SCM_DO_R_<1>")
	)
	(segment
		(start 162.717988 -65.488566)
		(end 162.852862 -65.62344)
		(width 0.11684)
		(layer "In4.Cu")
		(net "SGPIO_SCM_DO_R_<1>")
	)
	(segment
		(start 161.849054 -66.027046)
		(end 162.014154 -66.027046)
		(width 0.11684)
		(layer "In4.Cu")
		(net "SGPIO_SCM_DO_R_<1>")
	)
	(segment
		(start 173.397672 -98.03638)
		(end 172.59554 -98.838512)
		(width 0.11684)
		(layer "In4.Cu")
		(net "SGPIO_SCM_DO_R_<1>")
	)
	(segment
		(start 158.657036 -19.692112)
		(end 159.056832 -20.091908)
		(width 0.10668)
		(layer "F.Cu")
		(net "SGPIO_SCM_DO_R_<0>")
	)
	(segment
		(start 158.657036 -16.549878)
		(end 158.657036 -19.692112)
		(width 0.10668)
		(layer "F.Cu")
		(net "SGPIO_SCM_DO_R_<0>")
	)
	(segment
		(start 159.056832 -20.091908)
		(end 159.056832 -25.618694)
		(width 0.10668)
		(layer "F.Cu")
		(net "SGPIO_SCM_DO_R_<0>")
	)
	(segment
		(start 173.609 -99.894898)
		(end 173.609 -99.278948)
		(width 0.10668)
		(layer "F.Cu")
		(net "SGPIO_SCM_DO_R_<0>")
	)
	(via
		(at 173.609 -99.278948)
		(size 0.508)
		(drill 0.254)
		(layers "F.Cu" "B.Cu")
		(net "SGPIO_SCM_DO_R_<0>")
	)
	(via
		(at 159.056832 -25.618694)
		(size 0.508)
		(drill 0.254)
		(layers "F.Cu" "B.Cu")
		(net "SGPIO_SCM_DO_R_<0>")
	)
	(segment
		(start 175.244506 -96.826324)
		(end 175.156876 -97.037906)
		(width 0.11684)
		(layer "In4.Cu")
		(net "SGPIO_SCM_DO_R_<0>")
	)
	(segment
		(start 169.741342 -90.166698)
		(end 172.72762 -90.166698)
		(width 0.11684)
		(layer "In4.Cu")
		(net "SGPIO_SCM_DO_R_<0>")
	)
	(segment
		(start 172.72762 -90.166698)
		(end 175.244506 -92.683584)
		(width 0.11684)
		(layer "In4.Cu")
		(net "SGPIO_SCM_DO_R_<0>")
	)
	(segment
		(start 158.455868 -31.919164)
		(end 161.212784 -34.67608)
		(width 0.11684)
		(layer "In4.Cu")
		(net "SGPIO_SCM_DO_R_<0>")
	)
	(segment
		(start 158.605728 -25.618694)
		(end 158.455868 -25.768554)
		(width 0.11684)
		(layer "In4.Cu")
		(net "SGPIO_SCM_DO_R_<0>")
	)
	(segment
		(start 166.743634 -87.16899)
		(end 169.741342 -90.166698)
		(width 0.11684)
		(layer "In4.Cu")
		(net "SGPIO_SCM_DO_R_<0>")
	)
	(segment
		(start 175.156876 -97.589086)
		(end 173.609 -99.136962)
		(width 0.11684)
		(layer "In4.Cu")
		(net "SGPIO_SCM_DO_R_<0>")
	)
	(segment
		(start 159.056832 -25.618694)
		(end 158.605728 -25.618694)
		(width 0.11684)
		(layer "In4.Cu")
		(net "SGPIO_SCM_DO_R_<0>")
	)
	(segment
		(start 161.212784 -62.61862)
		(end 166.743634 -68.14947)
		(width 0.11684)
		(layer "In4.Cu")
		(net "SGPIO_SCM_DO_R_<0>")
	)
	(segment
		(start 161.212784 -34.67608)
		(end 161.212784 -62.61862)
		(width 0.11684)
		(layer "In4.Cu")
		(net "SGPIO_SCM_DO_R_<0>")
	)
	(segment
		(start 158.455868 -25.768554)
		(end 158.455868 -31.919164)
		(width 0.11684)
		(layer "In4.Cu")
		(net "SGPIO_SCM_DO_R_<0>")
	)
	(segment
		(start 175.244506 -92.683584)
		(end 175.244506 -96.826324)
		(width 0.11684)
		(layer "In4.Cu")
		(net "SGPIO_SCM_DO_R_<0>")
	)
	(segment
		(start 166.743634 -68.14947)
		(end 166.743634 -87.16899)
		(width 0.11684)
		(layer "In4.Cu")
		(net "SGPIO_SCM_DO_R_<0>")
	)
	(segment
		(start 173.609 -99.136962)
		(end 173.609 -99.278948)
		(width 0.11684)
		(layer "In4.Cu")
		(net "SGPIO_SCM_DO_R_<0>")
	)
	(segment
		(start 175.156876 -97.037906)
		(end 175.156876 -97.589086)
		(width 0.11684)
		(layer "In4.Cu")
		(net "SGPIO_SCM_DO_R_<0>")
	)
	(segment
		(start 152.980898 -22.883114)
		(end 152.980898 -21.608034)
		(width 0.10668)
		(layer "F.Cu")
		(net "SGPIO_SCM_DI_R_<1>")
	)
	(segment
		(start 152.980898 -20.420838)
		(end 152.980898 -21.608034)
		(width 0.10668)
		(layer "F.Cu")
		(net "SGPIO_SCM_DI_R_<1>")
	)
	(segment
		(start 154.456892 -18.944844)
		(end 152.980898 -20.420838)
		(width 0.10668)
		(layer "F.Cu")
		(net "SGPIO_SCM_DI_R_<1>")
	)
	(segment
		(start 152.97912 -22.884892)
		(end 152.980898 -22.883114)
		(width 0.10668)
		(layer "F.Cu")
		(net "SGPIO_SCM_DI_R_<1>")
	)
	(segment
		(start 154.456892 -16.549878)
		(end 154.456892 -18.944844)
		(width 0.10668)
		(layer "F.Cu")
		(net "SGPIO_SCM_DI_R_<1>")
	)
	(via
		(at 152.980898 -21.608034)
		(size 0.762)
		(drill 0.381)
		(layers "F.Cu" "B.Cu")
		(net "SGPIO_SCM_DI_R_<1>")
	)
	(segment
		(start 157.018228 -22.884892)
		(end 156.981906 -22.84857)
		(width 0.10668)
		(layer "F.Cu")
		(net "SGPIO_SCM_DI_R_<0>")
	)
	(segment
		(start 156.981906 -22.84857)
		(end 156.981906 -21.484336)
		(width 0.10668)
		(layer "F.Cu")
		(net "SGPIO_SCM_DI_R_<0>")
	)
	(segment
		(start 157.45714 -20.170648)
		(end 156.981906 -20.645882)
		(width 0.10668)
		(layer "F.Cu")
		(net "SGPIO_SCM_DI_R_<0>")
	)
	(segment
		(start 157.45714 -16.549878)
		(end 157.45714 -20.170648)
		(width 0.10668)
		(layer "F.Cu")
		(net "SGPIO_SCM_DI_R_<0>")
	)
	(segment
		(start 156.981906 -20.645882)
		(end 156.981906 -21.484336)
		(width 0.10668)
		(layer "F.Cu")
		(net "SGPIO_SCM_DI_R_<0>")
	)
	(via
		(at 156.981906 -21.484336)
		(size 0.762)
		(drill 0.381)
		(layers "F.Cu" "B.Cu")
		(net "SGPIO_SCM_DI_R_<0>")
	)
	(segment
		(start 171.9072 -94.433898)
		(end 171.9072 -93.817948)
		(width 0.10668)
		(layer "F.Cu")
		(net "SGPIO_SCM_CLK_R_<1>")
	)
	(segment
		(start 153.970482 -22.87651)
		(end 153.970482 -24.351742)
		(width 0.10668)
		(layer "F.Cu")
		(net "SGPIO_SCM_CLK_R_<1>")
	)
	(segment
		(start 153.9621 -20.341082)
		(end 153.9621 -22.87651)
		(width 0.10668)
		(layer "F.Cu")
		(net "SGPIO_SCM_CLK_R_<1>")
	)
	(segment
		(start 155.057094 -16.549878)
		(end 155.057094 -19.246088)
		(width 0.10668)
		(layer "F.Cu")
		(net "SGPIO_SCM_CLK_R_<1>")
	)
	(segment
		(start 153.9621 -22.87651)
		(end 153.970482 -22.87651)
		(width 0.10668)
		(layer "F.Cu")
		(net "SGPIO_SCM_CLK_R_<1>")
	)
	(segment
		(start 155.057094 -19.246088)
		(end 153.9621 -20.341082)
		(width 0.10668)
		(layer "F.Cu")
		(net "SGPIO_SCM_CLK_R_<1>")
	)
	(via
		(at 153.970482 -24.351742)
		(size 0.508)
		(drill 0.254)
		(layers "F.Cu" "B.Cu")
		(net "SGPIO_SCM_CLK_R_<1>")
	)
	(via
		(at 171.9072 -93.817948)
		(size 0.508)
		(drill 0.254)
		(layers "F.Cu" "B.Cu")
		(net "SGPIO_SCM_CLK_R_<1>")
	)
	(segment
		(start 157.809946 -34.920682)
		(end 157.809946 -52.917852)
		(width 0.11684)
		(layer "In4.Cu")
		(net "SGPIO_SCM_CLK_R_<1>")
	)
	(segment
		(start 171.9072 -93.525086)
		(end 171.9072 -93.817948)
		(width 0.11684)
		(layer "In4.Cu")
		(net "SGPIO_SCM_CLK_R_<1>")
	)
	(segment
		(start 168.610788 -92.59189)
		(end 170.974004 -92.59189)
		(width 0.11684)
		(layer "In4.Cu")
		(net "SGPIO_SCM_CLK_R_<1>")
	)
	(segment
		(start 164.39642 -88.377522)
		(end 168.610788 -92.59189)
		(width 0.11684)
		(layer "In4.Cu")
		(net "SGPIO_SCM_CLK_R_<1>")
	)
	(segment
		(start 170.974004 -92.59189)
		(end 171.9072 -93.525086)
		(width 0.11684)
		(layer "In4.Cu")
		(net "SGPIO_SCM_CLK_R_<1>")
	)
	(segment
		(start 157.809946 -52.917852)
		(end 158.938468 -54.046374)
		(width 0.11684)
		(layer "In4.Cu")
		(net "SGPIO_SCM_CLK_R_<1>")
	)
	(segment
		(start 153.519886 -24.802338)
		(end 153.519886 -30.630622)
		(width 0.11684)
		(layer "In4.Cu")
		(net "SGPIO_SCM_CLK_R_<1>")
	)
	(segment
		(start 153.519886 -30.630622)
		(end 157.809946 -34.920682)
		(width 0.11684)
		(layer "In4.Cu")
		(net "SGPIO_SCM_CLK_R_<1>")
	)
	(segment
		(start 153.970482 -24.351742)
		(end 153.519886 -24.802338)
		(width 0.11684)
		(layer "In4.Cu")
		(net "SGPIO_SCM_CLK_R_<1>")
	)
	(segment
		(start 164.39642 -78.488794)
		(end 164.39642 -88.377522)
		(width 0.11684)
		(layer "In4.Cu")
		(net "SGPIO_SCM_CLK_R_<1>")
	)
	(segment
		(start 163.511992 -77.604366)
		(end 164.39642 -78.488794)
		(width 0.11684)
		(layer "In4.Cu")
		(net "SGPIO_SCM_CLK_R_<1>")
	)
	(segment
		(start 158.938468 -65.11544)
		(end 163.511992 -69.688964)
		(width 0.11684)
		(layer "In4.Cu")
		(net "SGPIO_SCM_CLK_R_<1>")
	)
	(segment
		(start 163.511992 -69.688964)
		(end 163.511992 -77.604366)
		(width 0.11684)
		(layer "In4.Cu")
		(net "SGPIO_SCM_CLK_R_<1>")
	)
	(segment
		(start 158.938468 -54.046374)
		(end 158.938468 -65.11544)
		(width 0.11684)
		(layer "In4.Cu")
		(net "SGPIO_SCM_CLK_R_<1>")
	)
	(segment
		(start 173.9392 -94.433898)
		(end 173.9392 -93.817948)
		(width 0.10668)
		(layer "F.Cu")
		(net "SGPIO_SCM_CLK_R_<0>")
	)
	(segment
		(start 158.057088 -24.341328)
		(end 158.027624 -24.370792)
		(width 0.10668)
		(layer "F.Cu")
		(net "SGPIO_SCM_CLK_R_<0>")
	)
	(segment
		(start 158.057088 -16.549878)
		(end 158.057088 -24.341328)
		(width 0.10668)
		(layer "F.Cu")
		(net "SGPIO_SCM_CLK_R_<0>")
	)
	(via
		(at 158.027624 -24.370792)
		(size 0.508)
		(drill 0.254)
		(layers "F.Cu" "B.Cu")
		(net "SGPIO_SCM_CLK_R_<0>")
	)
	(via
		(at 173.9392 -93.817948)
		(size 0.508)
		(drill 0.254)
		(layers "F.Cu" "B.Cu")
		(net "SGPIO_SCM_CLK_R_<0>")
	)
	(segment
		(start 169.53865 -90.603832)
		(end 172.558964 -90.603832)
		(width 0.11684)
		(layer "In4.Cu")
		(net "SGPIO_SCM_CLK_R_<0>")
	)
	(segment
		(start 160.78454 -62.796166)
		(end 166.31539 -68.327016)
		(width 0.11684)
		(layer "In4.Cu")
		(net "SGPIO_SCM_CLK_R_<0>")
	)
	(segment
		(start 157.76702 -24.631396)
		(end 157.76702 -31.836106)
		(width 0.11684)
		(layer "In4.Cu")
		(net "SGPIO_SCM_CLK_R_<0>")
	)
	(segment
		(start 157.76702 -31.836106)
		(end 160.78454 -34.853626)
		(width 0.11684)
		(layer "In4.Cu")
		(net "SGPIO_SCM_CLK_R_<0>")
	)
	(segment
		(start 166.31539 -68.327016)
		(end 166.31539 -87.380572)
		(width 0.11684)
		(layer "In4.Cu")
		(net "SGPIO_SCM_CLK_R_<0>")
	)
	(segment
		(start 160.78454 -34.853626)
		(end 160.78454 -62.796166)
		(width 0.11684)
		(layer "In4.Cu")
		(net "SGPIO_SCM_CLK_R_<0>")
	)
	(segment
		(start 166.31539 -87.380572)
		(end 169.53865 -90.603832)
		(width 0.11684)
		(layer "In4.Cu")
		(net "SGPIO_SCM_CLK_R_<0>")
	)
	(segment
		(start 172.558964 -90.603832)
		(end 173.9392 -91.984068)
		(width 0.11684)
		(layer "In4.Cu")
		(net "SGPIO_SCM_CLK_R_<0>")
	)
	(segment
		(start 173.9392 -91.984068)
		(end 173.9392 -93.817948)
		(width 0.11684)
		(layer "In4.Cu")
		(net "SGPIO_SCM_CLK_R_<0>")
	)
	(segment
		(start 158.027624 -24.370792)
		(end 157.76702 -24.631396)
		(width 0.11684)
		(layer "In4.Cu")
		(net "SGPIO_SCM_CLK_R_<0>")
	)
	(segment
		(start 171.9072 -95.8342)
		(end 171.704 -96.0374)
		(width 0.10668)
		(layer "F.Cu")
		(net "SGPIO_SCM_CLK_<1>")
	)
	(segment
		(start 171.9072 -95.233998)
		(end 171.9072 -95.8342)
		(width 0.10668)
		(layer "F.Cu")
		(net "SGPIO_SCM_CLK_<1>")
	)
	(segment
		(start 179.52212 -120.252744)
		(end 179.13223 -120.642634)
		(width 0.10668)
		(layer "F.Cu")
		(net "SGPIO_SCM_CLK_<1>")
	)
	(via
		(at 179.13223 -120.642634)
		(size 0.4572)
		(drill 0.254)
		(layers "F.Cu" "B.Cu")
		(net "SGPIO_SCM_CLK_<1>")
	)
	(via
		(at 171.704 -96.0374)
		(size 0.508)
		(drill 0.254)
		(layers "F.Cu" "B.Cu")
		(net "SGPIO_SCM_CLK_<1>")
	)
	(segment
		(start 171.8818 -97.431098)
		(end 171.8818 -96.2152)
		(width 0.10668)
		(layer "B.Cu")
		(net "SGPIO_SCM_CLK_<1>")
	)
	(segment
		(start 171.8818 -96.2152)
		(end 171.704 -96.0374)
		(width 0.10668)
		(layer "B.Cu")
		(net "SGPIO_SCM_CLK_<1>")
	)
	(segment
		(start 171.577 -97.735898)
		(end 171.8818 -97.431098)
		(width 0.10668)
		(layer "B.Cu")
		(net "SGPIO_SCM_CLK_<1>")
	)
	(segment
		(start 172.217842 -105.44175)
		(end 172.217842 -104.785414)
		(width 0.11684)
		(layer "In4.Cu")
		(net "SGPIO_SCM_CLK_<1>")
	)
	(segment
		(start 171.514262 -103.30434)
		(end 171.105068 -102.895146)
		(width 0.11684)
		(layer "In4.Cu")
		(net "SGPIO_SCM_CLK_<1>")
	)
	(segment
		(start 171.514262 -104.081834)
		(end 171.514262 -103.30434)
		(width 0.11684)
		(layer "In4.Cu")
		(net "SGPIO_SCM_CLK_<1>")
	)
	(segment
		(start 179.52085 -120.254014)
		(end 179.52085 -115.480592)
		(width 0.11684)
		(layer "In4.Cu")
		(net "SGPIO_SCM_CLK_<1>")
	)
	(segment
		(start 180.33365 -114.667792)
		(end 180.33365 -111.692436)
		(width 0.11684)
		(layer "In4.Cu")
		(net "SGPIO_SCM_CLK_<1>")
	)
	(segment
		(start 174.751746 -111.460788)
		(end 174.03318 -110.742222)
		(width 0.11684)
		(layer "In4.Cu")
		(net "SGPIO_SCM_CLK_<1>")
	)
	(segment
		(start 180.33365 -111.692436)
		(end 180.102002 -111.460788)
		(width 0.11684)
		(layer "In4.Cu")
		(net "SGPIO_SCM_CLK_<1>")
	)
	(segment
		(start 171.8818 -96.6216)
		(end 171.704 -96.4438)
		(width 0.11684)
		(layer "In4.Cu")
		(net "SGPIO_SCM_CLK_<1>")
	)
	(segment
		(start 171.105068 -98.3234)
		(end 171.8818 -97.546668)
		(width 0.11684)
		(layer "In4.Cu")
		(net "SGPIO_SCM_CLK_<1>")
	)
	(segment
		(start 179.52085 -115.480592)
		(end 180.33365 -114.667792)
		(width 0.11684)
		(layer "In4.Cu")
		(net "SGPIO_SCM_CLK_<1>")
	)
	(segment
		(start 174.03318 -106.292904)
		(end 173.350682 -105.610406)
		(width 0.11684)
		(layer "In4.Cu")
		(net "SGPIO_SCM_CLK_<1>")
	)
	(segment
		(start 174.03318 -110.742222)
		(end 174.03318 -106.292904)
		(width 0.11684)
		(layer "In4.Cu")
		(net "SGPIO_SCM_CLK_<1>")
	)
	(segment
		(start 171.704 -96.4438)
		(end 171.704 -96.0374)
		(width 0.11684)
		(layer "In4.Cu")
		(net "SGPIO_SCM_CLK_<1>")
	)
	(segment
		(start 180.102002 -111.460788)
		(end 174.751746 -111.460788)
		(width 0.11684)
		(layer "In4.Cu")
		(net "SGPIO_SCM_CLK_<1>")
	)
	(segment
		(start 172.386498 -105.610406)
		(end 172.217842 -105.44175)
		(width 0.11684)
		(layer "In4.Cu")
		(net "SGPIO_SCM_CLK_<1>")
	)
	(segment
		(start 172.217842 -104.785414)
		(end 171.514262 -104.081834)
		(width 0.11684)
		(layer "In4.Cu")
		(net "SGPIO_SCM_CLK_<1>")
	)
	(segment
		(start 171.8818 -97.546668)
		(end 171.8818 -96.6216)
		(width 0.11684)
		(layer "In4.Cu")
		(net "SGPIO_SCM_CLK_<1>")
	)
	(segment
		(start 173.350682 -105.610406)
		(end 172.386498 -105.610406)
		(width 0.11684)
		(layer "In4.Cu")
		(net "SGPIO_SCM_CLK_<1>")
	)
	(segment
		(start 171.105068 -102.895146)
		(end 171.105068 -98.3234)
		(width 0.11684)
		(layer "In4.Cu")
		(net "SGPIO_SCM_CLK_<1>")
	)
	(segment
		(start 179.13223 -120.642634)
		(end 179.52085 -120.254014)
		(width 0.11684)
		(layer "In4.Cu")
		(net "SGPIO_SCM_CLK_<1>")
	)
	(segment
		(start 173.9392 -95.86468)
		(end 174.0408 -95.96628)
		(width 0.10668)
		(layer "F.Cu")
		(net "SGPIO_SCM_CLK_<0>")
	)
	(segment
		(start 173.9392 -95.233998)
		(end 173.9392 -95.86468)
		(width 0.10668)
		(layer "F.Cu")
		(net "SGPIO_SCM_CLK_<0>")
	)
	(segment
		(start 179.52212 -110.652814)
		(end 179.13223 -110.262924)
		(width 0.10668)
		(layer "F.Cu")
		(net "SGPIO_SCM_CLK_<0>")
	)
	(via
		(at 179.13223 -110.262924)
		(size 0.4572)
		(drill 0.254)
		(layers "F.Cu" "B.Cu")
		(net "SGPIO_SCM_CLK_<0>")
	)
	(via
		(at 174.0408 -95.96628)
		(size 0.508)
		(drill 0.254)
		(layers "F.Cu" "B.Cu")
		(net "SGPIO_SCM_CLK_<0>")
	)
	(segment
		(start 173.609 -97.735898)
		(end 173.9392 -97.405698)
		(width 0.10668)
		(layer "B.Cu")
		(net "SGPIO_SCM_CLK_<0>")
	)
	(segment
		(start 173.9392 -97.405698)
		(end 173.9392 -96.06788)
		(width 0.10668)
		(layer "B.Cu")
		(net "SGPIO_SCM_CLK_<0>")
	)
	(segment
		(start 173.9392 -96.06788)
		(end 174.0408 -95.96628)
		(width 0.10668)
		(layer "B.Cu")
		(net "SGPIO_SCM_CLK_<0>")
	)
	(segment
		(start 178.145694 -109.868462)
		(end 178.737768 -109.868462)
		(width 0.11684)
		(layer "In4.Cu")
		(net "SGPIO_SCM_CLK_<0>")
	)
	(segment
		(start 173.322234 -100.917502)
		(end 173.322234 -102.529132)
		(width 0.11684)
		(layer "In4.Cu")
		(net "SGPIO_SCM_CLK_<0>")
	)
	(segment
		(start 173.08957 -98.984562)
		(end 173.08957 -100.684838)
		(width 0.11684)
		(layer "In4.Cu")
		(net "SGPIO_SCM_CLK_<0>")
	)
	(segment
		(start 176.36744 -104.278684)
		(end 177.310542 -105.221786)
		(width 0.11684)
		(layer "In4.Cu")
		(net "SGPIO_SCM_CLK_<0>")
	)
	(segment
		(start 177.310542 -107.586526)
		(end 177.931826 -108.20781)
		(width 0.11684)
		(layer "In4.Cu")
		(net "SGPIO_SCM_CLK_<0>")
	)
	(segment
		(start 177.931826 -108.20781)
		(end 177.931826 -109.654594)
		(width 0.11684)
		(layer "In4.Cu")
		(net "SGPIO_SCM_CLK_<0>")
	)
	(segment
		(start 173.9392 -96.06788)
		(end 173.9392 -98.134932)
		(width 0.11684)
		(layer "In4.Cu")
		(net "SGPIO_SCM_CLK_<0>")
	)
	(segment
		(start 177.931826 -109.654594)
		(end 178.145694 -109.868462)
		(width 0.11684)
		(layer "In4.Cu")
		(net "SGPIO_SCM_CLK_<0>")
	)
	(segment
		(start 173.9392 -98.134932)
		(end 173.08957 -98.984562)
		(width 0.11684)
		(layer "In4.Cu")
		(net "SGPIO_SCM_CLK_<0>")
	)
	(segment
		(start 174.0408 -95.96628)
		(end 173.9392 -96.06788)
		(width 0.11684)
		(layer "In4.Cu")
		(net "SGPIO_SCM_CLK_<0>")
	)
	(segment
		(start 178.737768 -109.868462)
		(end 179.13223 -110.262924)
		(width 0.11684)
		(layer "In4.Cu")
		(net "SGPIO_SCM_CLK_<0>")
	)
	(segment
		(start 173.08957 -100.684838)
		(end 173.322234 -100.917502)
		(width 0.11684)
		(layer "In4.Cu")
		(net "SGPIO_SCM_CLK_<0>")
	)
	(segment
		(start 174.156878 -103.363776)
		(end 176.36744 -104.278684)
		(width 0.11684)
		(layer "In4.Cu")
		(net "SGPIO_SCM_CLK_<0>")
	)
	(segment
		(start 177.310542 -105.221786)
		(end 177.310542 -107.586526)
		(width 0.11684)
		(layer "In4.Cu")
		(net "SGPIO_SCM_CLK_<0>")
	)
	(segment
		(start 173.322234 -102.529132)
		(end 174.156878 -103.363776)
		(width 0.11684)
		(layer "In4.Cu")
		(net "SGPIO_SCM_CLK_<0>")
	)
	(segment
		(start 148.944076 -19.92884)
		(end 148.944076 -19.937476)
		(width 0.10668)
		(layer "F.Cu")
		(net "SCM_VDD_RTC")
	)
	(segment
		(start 151.456898 -17.416018)
		(end 148.944076 -19.92884)
		(width 0.10668)
		(layer "F.Cu")
		(net "SCM_VDD_RTC")
	)
	(segment
		(start 147.877022 -22.884892)
		(end 148.944076 -22.884892)
		(width 0.10668)
		(layer "F.Cu")
		(net "SCM_VDD_RTC")
	)
	(segment
		(start 149.192234 -20.185634)
		(end 148.944076 -19.937476)
		(width 0.10668)
		(layer "F.Cu")
		(net "SCM_VDD_RTC")
	)
	(segment
		(start 151.456898 -16.549878)
		(end 151.456898 -17.416018)
		(width 0.10668)
		(layer "F.Cu")
		(net "SCM_VDD_RTC")
	)
	(segment
		(start 148.944076 -22.884892)
		(end 149.192234 -22.636734)
		(width 0.10668)
		(layer "F.Cu")
		(net "SCM_VDD_RTC")
	)
	(segment
		(start 149.192234 -22.636734)
		(end 149.192234 -20.185634)
		(width 0.10668)
		(layer "F.Cu")
		(net "SCM_VDD_RTC")
	)
	(via
		(at 148.944076 -19.937476)
		(size 0.762)
		(drill 0.381)
		(layers "F.Cu" "B.Cu")
		(net "SCM_VDD_RTC")
	)
	(segment
		(start 142.346934 -12.732512)
		(end 142.219934 -12.42568)
		(width 0.10668)
		(layer "F.Cu")
		(net "SCM_HDT_DBREQ_N")
	)
	(segment
		(start 142.219934 -11.542776)
		(end 142.677134 -10.438892)
		(width 0.10668)
		(layer "F.Cu")
		(net "SCM_HDT_DBREQ_N")
	)
	(segment
		(start 142.346934 -13.599922)
		(end 142.346934 -12.732512)
		(width 0.10668)
		(layer "F.Cu")
		(net "SCM_HDT_DBREQ_N")
	)
	(segment
		(start 142.677134 -10.438892)
		(end 142.677134 -10.420096)
		(width 0.10668)
		(layer "F.Cu")
		(net "SCM_HDT_DBREQ_N")
	)
	(segment
		(start 142.219934 -12.42568)
		(end 142.219934 -11.542776)
		(width 0.10668)
		(layer "F.Cu")
		(net "SCM_HDT_DBREQ_N")
	)
	(via
		(at 142.677134 -10.420096)
		(size 0.508)
		(drill 0.254)
		(layers "F.Cu" "B.Cu")
		(net "SCM_HDT_DBREQ_N")
	)
	(segment
		(start 142.2908 -13.363702)
		(end 142.219934 -13.292836)
		(width 0.10668)
		(layer "B.Cu")
		(net "SCM_HDT_DBREQ_N")
	)
	(segment
		(start 142.219934 -13.292836)
		(end 142.219934 -12.049252)
		(width 0.10668)
		(layer "B.Cu")
		(net "SCM_HDT_DBREQ_N")
	)
	(segment
		(start 142.219934 -12.049252)
		(end 142.677134 -11.592052)
		(width 0.10668)
		(layer "B.Cu")
		(net "SCM_HDT_DBREQ_N")
	)
	(segment
		(start 142.677134 -11.592052)
		(end 142.677134 -10.420096)
		(width 0.10668)
		(layer "B.Cu")
		(net "SCM_HDT_DBREQ_N")
	)
	(segment
		(start 183.362092 -417.404804)
		(end 183.362092 -416.611562)
		(width 0.10668)
		(layer "F.Cu")
		(net "RST_SWB_BIC_N")
	)
	(segment
		(start 183.667146 -416.306508)
		(end 183.667146 -416.00755)
		(width 0.10668)
		(layer "F.Cu")
		(net "RST_SWB_BIC_N")
	)
	(segment
		(start 183.362092 -416.611562)
		(end 183.667146 -416.306508)
		(width 0.10668)
		(layer "F.Cu")
		(net "RST_SWB_BIC_N")
	)
	(segment
		(start 183.667146 -416.00755)
		(end 183.362092 -415.702496)
		(width 0.10668)
		(layer "F.Cu")
		(net "RST_SWB_BIC_N")
	)
	(segment
		(start 183.362092 -415.702496)
		(end 183.362092 -414.76168)
		(width 0.10668)
		(layer "F.Cu")
		(net "RST_SWB_BIC_N")
	)
	(segment
		(start 183.362092 -414.76168)
		(end 184.079642 -414.04413)
		(width 0.10668)
		(layer "F.Cu")
		(net "RST_SWB_BIC_N")
	)
	(via
		(at 183.362092 -415.702496)
		(size 0.762)
		(drill 0.381)
		(layers "F.Cu" "B.Cu")
		(net "RST_SWB_BIC_N")
	)
	(segment
		(start 179.63896 -415.54527)
		(end 177.763932 -415.54527)
		(width 0.10668)
		(layer "F.Cu")
		(net "PU_U181_INT")
	)
	(segment
		(start 180.662326 -417.404804)
		(end 180.662326 -416.568636)
		(width 0.10668)
		(layer "F.Cu")
		(net "PU_U181_INT")
	)
	(segment
		(start 177.2793 -415.060638)
		(end 176.79162 -414.572958)
		(width 0.10668)
		(layer "F.Cu")
		(net "PU_U181_INT")
	)
	(segment
		(start 180.662326 -416.568636)
		(end 179.63896 -415.54527)
		(width 0.10668)
		(layer "F.Cu")
		(net "PU_U181_INT")
	)
	(segment
		(start 176.79162 -414.572958)
		(end 176.79162 -414.236408)
		(width 0.10668)
		(layer "F.Cu")
		(net "PU_U181_INT")
	)
	(segment
		(start 177.763932 -415.54527)
		(end 177.2793 -415.060638)
		(width 0.10668)
		(layer "F.Cu")
		(net "PU_U181_INT")
	)
	(via
		(at 177.2793 -415.060638)
		(size 0.762)
		(drill 0.381)
		(layers "F.Cu" "B.Cu")
		(net "PU_U181_INT")
	)
	(segment
		(start 182.06212 -416.660076)
		(end 181.648608 -416.246564)
		(width 0.10668)
		(layer "F.Cu")
		(net "PU_RST_SMB_U181_N")
	)
	(segment
		(start 181.648608 -415.10331)
		(end 181.648608 -414.186624)
		(width 0.10668)
		(layer "F.Cu")
		(net "PU_RST_SMB_U181_N")
	)
	(segment
		(start 182.06212 -417.404804)
		(end 182.06212 -416.660076)
		(width 0.10668)
		(layer "F.Cu")
		(net "PU_RST_SMB_U181_N")
	)
	(segment
		(start 181.648608 -416.246564)
		(end 181.648608 -415.10331)
		(width 0.10668)
		(layer "F.Cu")
		(net "PU_RST_SMB_U181_N")
	)
	(via
		(at 181.648608 -415.10331)
		(size 0.762)
		(drill 0.381)
		(layers "F.Cu" "B.Cu")
		(net "PU_RST_SMB_U181_N")
	)
	(segment
		(start 258.93014 -123.337828)
		(end 258.567682 -122.97537)
		(width 0.10668)
		(layer "F.Cu")
		(net "PU_RST_SMB_PCIE2_N")
	)
	(segment
		(start 258.93014 -122.956828)
		(end 258.93014 -123.337828)
		(width 0.10668)
		(layer "F.Cu")
		(net "PU_RST_SMB_PCIE2_N")
	)
	(segment
		(start 258.567682 -122.97537)
		(end 257.642106 -122.97537)
		(width 0.10668)
		(layer "F.Cu")
		(net "PU_RST_SMB_PCIE2_N")
	)
	(segment
		(start 260.404864 -121.482104)
		(end 258.93014 -122.956828)
		(width 0.10668)
		(layer "F.Cu")
		(net "PU_RST_SMB_PCIE2_N")
	)
	(segment
		(start 261.37489 -121.482104)
		(end 260.404864 -121.482104)
		(width 0.10668)
		(layer "F.Cu")
		(net "PU_RST_SMB_PCIE2_N")
	)
	(via
		(at 258.93014 -123.337828)
		(size 0.762)
		(drill 0.381)
		(layers "F.Cu" "B.Cu")
		(net "PU_RST_SMB_PCIE2_N")
	)
	(segment
		(start 284.127956 -121.482104)
		(end 283.240988 -121.482104)
		(width 0.10668)
		(layer "F.Cu")
		(net "PU_RST_SMB_PCIE0_N")
	)
	(segment
		(start 282.458922 -122.26417)
		(end 281.17927 -122.26417)
		(width 0.10668)
		(layer "F.Cu")
		(net "PU_RST_SMB_PCIE0_N")
	)
	(segment
		(start 280.421842 -122.26417)
		(end 279.913842 -121.75617)
		(width 0.10668)
		(layer "F.Cu")
		(net "PU_RST_SMB_PCIE0_N")
	)
	(segment
		(start 283.240988 -121.482104)
		(end 282.458922 -122.26417)
		(width 0.10668)
		(layer "F.Cu")
		(net "PU_RST_SMB_PCIE0_N")
	)
	(segment
		(start 281.17927 -122.26417)
		(end 280.421842 -122.26417)
		(width 0.10668)
		(layer "F.Cu")
		(net "PU_RST_SMB_PCIE0_N")
	)
	(via
		(at 281.17927 -122.26417)
		(size 0.762)
		(drill 0.381)
		(layers "F.Cu" "B.Cu")
		(net "PU_RST_SMB_PCIE0_N")
	)
	(segment
		(start 292.821106 -122.522996)
		(end 292.994588 -122.349514)
		(width 0.10668)
		(layer "F.Cu")
		(net "PCA9548_PCIE3_ADDR2")
	)
	(segment
		(start 297.052238 -122.349514)
		(end 296.35196 -121.649236)
		(width 0.10668)
		(layer "F.Cu")
		(net "PCA9548_PCIE3_ADDR2")
	)
	(segment
		(start 294.72128 -121.649236)
		(end 294.021002 -122.349514)
		(width 0.10668)
		(layer "F.Cu")
		(net "PCA9548_PCIE3_ADDR2")
	)
	(segment
		(start 297.086274 -122.349514)
		(end 297.052238 -122.349514)
		(width 0.10668)
		(layer "F.Cu")
		(net "PCA9548_PCIE3_ADDR2")
	)
	(segment
		(start 296.35196 -121.649236)
		(end 294.72128 -121.649236)
		(width 0.10668)
		(layer "F.Cu")
		(net "PCA9548_PCIE3_ADDR2")
	)
	(segment
		(start 292.343586 -122.522996)
		(end 292.821106 -122.522996)
		(width 0.10668)
		(layer "F.Cu")
		(net "PCA9548_PCIE3_ADDR2")
	)
	(segment
		(start 290.652708 -120.832118)
		(end 292.343586 -122.522996)
		(width 0.10668)
		(layer "F.Cu")
		(net "PCA9548_PCIE3_ADDR2")
	)
	(segment
		(start 289.728148 -120.832118)
		(end 290.652708 -120.832118)
		(width 0.10668)
		(layer "F.Cu")
		(net "PCA9548_PCIE3_ADDR2")
	)
	(segment
		(start 292.994588 -122.349514)
		(end 294.021002 -122.349514)
		(width 0.10668)
		(layer "F.Cu")
		(net "PCA9548_PCIE3_ADDR2")
	)
	(via
		(at 292.821106 -122.522996)
		(size 0.762)
		(drill 0.381)
		(layers "F.Cu" "B.Cu")
		(net "PCA9548_PCIE3_ADDR2")
	)
	(segment
		(start 280.264362 -123.385834)
		(end 282.204922 -123.385834)
		(width 0.10668)
		(layer "F.Cu")
		(net "PCA9548_PCIE3_ADDR1")
	)
	(segment
		(start 283.458666 -122.13209)
		(end 284.127956 -122.13209)
		(width 0.10668)
		(layer "F.Cu")
		(net "PCA9548_PCIE3_ADDR1")
	)
	(segment
		(start 282.204922 -123.385834)
		(end 283.458666 -122.13209)
		(width 0.10668)
		(layer "F.Cu")
		(net "PCA9548_PCIE3_ADDR1")
	)
	(segment
		(start 277.752302 -124.368814)
		(end 278.452326 -123.66879)
		(width 0.10668)
		(layer "F.Cu")
		(net "PCA9548_PCIE3_ADDR1")
	)
	(segment
		(start 279.280366 -123.66879)
		(end 279.913842 -123.035314)
		(width 0.10668)
		(layer "F.Cu")
		(net "PCA9548_PCIE3_ADDR1")
	)
	(segment
		(start 278.452326 -123.66879)
		(end 279.280366 -123.66879)
		(width 0.10668)
		(layer "F.Cu")
		(net "PCA9548_PCIE3_ADDR1")
	)
	(segment
		(start 279.913842 -123.035314)
		(end 280.264362 -123.385834)
		(width 0.10668)
		(layer "F.Cu")
		(net "PCA9548_PCIE3_ADDR1")
	)
	(via
		(at 282.204922 -123.385834)
		(size 0.762)
		(drill 0.381)
		(layers "F.Cu" "B.Cu")
		(net "PCA9548_PCIE3_ADDR1")
	)
	(segment
		(start 282.449778 -124.305314)
		(end 283.093922 -123.66117)
		(width 0.10668)
		(layer "F.Cu")
		(net "PCA9548_PCIE3_ADDR0")
	)
	(segment
		(start 281.188922 -124.305314)
		(end 282.449778 -124.305314)
		(width 0.10668)
		(layer "F.Cu")
		(net "PCA9548_PCIE3_ADDR0")
	)
	(segment
		(start 283.465016 -122.782076)
		(end 284.127956 -122.782076)
		(width 0.10668)
		(layer "F.Cu")
		(net "PCA9548_PCIE3_ADDR0")
	)
	(segment
		(start 278.580342 -125.638814)
		(end 277.752302 -125.638814)
		(width 0.10668)
		(layer "F.Cu")
		(net "PCA9548_PCIE3_ADDR0")
	)
	(segment
		(start 283.093922 -123.66117)
		(end 283.093922 -123.15317)
		(width 0.10668)
		(layer "F.Cu")
		(net "PCA9548_PCIE3_ADDR0")
	)
	(segment
		(start 279.913842 -124.305314)
		(end 278.580342 -125.638814)
		(width 0.10668)
		(layer "F.Cu")
		(net "PCA9548_PCIE3_ADDR0")
	)
	(segment
		(start 283.093922 -123.15317)
		(end 283.465016 -122.782076)
		(width 0.10668)
		(layer "F.Cu")
		(net "PCA9548_PCIE3_ADDR0")
	)
	(segment
		(start 279.913842 -124.305314)
		(end 281.188922 -124.305314)
		(width 0.10668)
		(layer "F.Cu")
		(net "PCA9548_PCIE3_ADDR0")
	)
	(via
		(at 281.188922 -124.305314)
		(size 0.762)
		(drill 0.381)
		(layers "F.Cu" "B.Cu")
		(net "PCA9548_PCIE3_ADDR0")
	)
	(segment
		(start 270.692626 -121.82475)
		(end 270.692626 -120.78335)
		(width 0.10668)
		(layer "F.Cu")
		(net "PCA9548_PCIE0_ADDR2")
	)
	(segment
		(start 267.894308 -120.832118)
		(end 268.79169 -120.832118)
		(width 0.10668)
		(layer "F.Cu")
		(net "PCA9548_PCIE0_ADDR2")
	)
	(segment
		(start 270.685006 -121.83237)
		(end 269.791942 -121.83237)
		(width 0.10668)
		(layer "F.Cu")
		(net "PCA9548_PCIE0_ADDR2")
	)
	(segment
		(start 267.894308 -120.832118)
		(end 266.975082 -120.832118)
		(width 0.10668)
		(layer "F.Cu")
		(net "PCA9548_PCIE0_ADDR2")
	)
	(segment
		(start 268.79169 -120.832118)
		(end 269.791942 -121.83237)
		(width 0.10668)
		(layer "F.Cu")
		(net "PCA9548_PCIE0_ADDR2")
	)
	(segment
		(start 270.685006 -121.83237)
		(end 270.692626 -121.82475)
		(width 0.10668)
		(layer "F.Cu")
		(net "PCA9548_PCIE0_ADDR2")
	)
	(via
		(at 269.791942 -121.83237)
		(size 0.508)
		(drill 0.254)
		(layers "F.Cu" "B.Cu")
		(net "PCA9548_PCIE0_ADDR2")
	)
	(segment
		(start 259.782056 -124.37237)
		(end 260.036056 -124.11837)
		(width 0.10668)
		(layer "F.Cu")
		(net "PCA9548_PCIE0_ADDR1")
	)
	(segment
		(start 260.036056 -124.11837)
		(end 260.036056 -122.72137)
		(width 0.10668)
		(layer "F.Cu")
		(net "PCA9548_PCIE0_ADDR1")
	)
	(segment
		(start 255.721866 -124.79147)
		(end 254.992886 -125.52045)
		(width 0.10668)
		(layer "F.Cu")
		(net "PCA9548_PCIE0_ADDR1")
	)
	(segment
		(start 260.036056 -122.72137)
		(end 260.625336 -122.13209)
		(width 0.10668)
		(layer "F.Cu")
		(net "PCA9548_PCIE0_ADDR1")
	)
	(segment
		(start 256.965704 -124.79147)
		(end 255.721866 -124.79147)
		(width 0.10668)
		(layer "F.Cu")
		(net "PCA9548_PCIE0_ADDR1")
	)
	(segment
		(start 257.642106 -124.11837)
		(end 257.896106 -124.37237)
		(width 0.10668)
		(layer "F.Cu")
		(net "PCA9548_PCIE0_ADDR1")
	)
	(segment
		(start 257.896106 -124.37237)
		(end 259.782056 -124.37237)
		(width 0.10668)
		(layer "F.Cu")
		(net "PCA9548_PCIE0_ADDR1")
	)
	(segment
		(start 260.625336 -122.13209)
		(end 261.37489 -122.13209)
		(width 0.10668)
		(layer "F.Cu")
		(net "PCA9548_PCIE0_ADDR1")
	)
	(segment
		(start 257.642106 -124.115068)
		(end 256.965704 -124.79147)
		(width 0.10668)
		(layer "F.Cu")
		(net "PCA9548_PCIE0_ADDR1")
	)
	(segment
		(start 257.642106 -124.115068)
		(end 257.642106 -124.11837)
		(width 0.10668)
		(layer "F.Cu")
		(net "PCA9548_PCIE0_ADDR1")
	)
	(via
		(at 259.782056 -124.37237)
		(size 0.762)
		(drill 0.381)
		(layers "F.Cu" "B.Cu")
		(net "PCA9548_PCIE0_ADDR1")
	)
	(segment
		(start 260.61035 -122.782076)
		(end 261.37489 -122.782076)
		(width 0.10668)
		(layer "F.Cu")
		(net "PCA9548_PCIE0_ADDR0")
	)
	(segment
		(start 257.642106 -125.38837)
		(end 257.642106 -125.41377)
		(width 0.10668)
		(layer "F.Cu")
		(net "PCA9548_PCIE0_ADDR0")
	)
	(segment
		(start 260.417056 -122.97537)
		(end 260.61035 -122.782076)
		(width 0.10668)
		(layer "F.Cu")
		(net "PCA9548_PCIE0_ADDR0")
	)
	(segment
		(start 258.893056 -125.38837)
		(end 259.782056 -125.38837)
		(width 0.10668)
		(layer "F.Cu")
		(net "PCA9548_PCIE0_ADDR0")
	)
	(segment
		(start 257.642106 -125.41377)
		(end 256.138426 -126.91745)
		(width 0.10668)
		(layer "F.Cu")
		(net "PCA9548_PCIE0_ADDR0")
	)
	(segment
		(start 257.642106 -125.38837)
		(end 258.893056 -125.38837)
		(width 0.10668)
		(layer "F.Cu")
		(net "PCA9548_PCIE0_ADDR0")
	)
	(segment
		(start 259.782056 -125.38837)
		(end 260.417056 -124.75337)
		(width 0.10668)
		(layer "F.Cu")
		(net "PCA9548_PCIE0_ADDR0")
	)
	(segment
		(start 256.138426 -126.91745)
		(end 254.992886 -126.91745)
		(width 0.10668)
		(layer "F.Cu")
		(net "PCA9548_PCIE0_ADDR0")
	)
	(segment
		(start 260.417056 -124.75337)
		(end 260.417056 -122.97537)
		(width 0.10668)
		(layer "F.Cu")
		(net "PCA9548_PCIE0_ADDR0")
	)
	(via
		(at 258.893056 -125.38837)
		(size 0.762)
		(drill 0.381)
		(layers "F.Cu" "B.Cu")
		(net "PCA9548_PCIE0_ADDR0")
	)
	(segment
		(start 14.82471 -138.682222)
		(end 13.817346 -137.674858)
		(width 0.10668)
		(layer "F.Cu")
		(net "P3V3_PWRGD_CLKGEN")
	)
	(segment
		(start 14.82471 -138.85799)
		(end 14.82471 -138.682222)
		(width 0.10668)
		(layer "F.Cu")
		(net "P3V3_PWRGD_CLKGEN")
	)
	(segment
		(start 13.296646 -137.154158)
		(end 13.817346 -137.674858)
		(width 0.10668)
		(layer "F.Cu")
		(net "P3V3_PWRGD_CLKGEN")
	)
	(segment
		(start 13.296646 -135.91413)
		(end 13.296646 -137.154158)
		(width 0.10668)
		(layer "F.Cu")
		(net "P3V3_PWRGD_CLKGEN")
	)
	(via
		(at 13.817346 -137.674858)
		(size 0.762)
		(drill 0.381)
		(layers "F.Cu" "B.Cu")
		(net "P3V3_PWRGD_CLKGEN")
	)
	(segment
		(start 160.29559 -20.573746)
		(end 160.057338 -20.335494)
		(width 0.12954)
		(layer "F.Cu")
		(net "P2E_CPU0_P5_TX_DP")
	)
	(segment
		(start 217.725498 -86.92134)
		(end 217.996008 -86.65083)
		(width 0.12954)
		(layer "F.Cu")
		(net "P2E_CPU0_P5_TX_DP")
	)
	(segment
		(start 217.805762 -85.642704)
		(end 216.851484 -84.554314)
		(width 0.12954)
		(layer "F.Cu")
		(net "P2E_CPU0_P5_TX_DP")
	)
	(segment
		(start 190.221362 -62.809882)
		(end 189.406784 -59.779408)
		(width 0.12954)
		(layer "F.Cu")
		(net "P2E_CPU0_P5_TX_DP")
	)
	(segment
		(start 168.048686 -33.885378)
		(end 166.683436 -32.884364)
		(width 0.12954)
		(layer "F.Cu")
		(net "P2E_CPU0_P5_TX_DP")
	)
	(segment
		(start 206.140812 -82.50682)
		(end 204.312266 -82.47253)
		(width 0.12954)
		(layer "F.Cu")
		(net "P2E_CPU0_P5_TX_DP")
	)
	(segment
		(start 185.149236 -48.221646)
		(end 184.21477 -42.920666)
		(width 0.12954)
		(layer "F.Cu")
		(net "P2E_CPU0_P5_TX_DP")
	)
	(segment
		(start 217.996008 -86.65083)
		(end 217.996008 -86.007194)
		(width 0.12954)
		(layer "F.Cu")
		(net "P2E_CPU0_P5_TX_DP")
	)
	(segment
		(start 189.557914 -66.937636)
		(end 190.124588 -65.331848)
		(width 0.12954)
		(layer "F.Cu")
		(net "P2E_CPU0_P5_TX_DP")
	)
	(segment
		(start 216.851484 -84.554314)
		(end 214.347298 -82.801206)
		(width 0.12954)
		(layer "F.Cu")
		(net "P2E_CPU0_P5_TX_DP")
	)
	(segment
		(start 214.347298 -82.801206)
		(end 213.461854 -82.644996)
		(width 0.12954)
		(layer "F.Cu")
		(net "P2E_CPU0_P5_TX_DP")
	)
	(segment
		(start 195.07581 -81.719166)
		(end 191.258698 -79.046832)
		(width 0.12954)
		(layer "F.Cu")
		(net "P2E_CPU0_P5_TX_DP")
	)
	(segment
		(start 213.461854 -82.644996)
		(end 209.804254 -82.575908)
		(width 0.12954)
		(layer "F.Cu")
		(net "P2E_CPU0_P5_TX_DP")
	)
	(segment
		(start 160.29559 -21.537168)
		(end 160.29559 -20.573746)
		(width 0.12954)
		(layer "F.Cu")
		(net "P2E_CPU0_P5_TX_DP")
	)
	(segment
		(start 204.312266 -82.472276)
		(end 198.74992 -82.36712)
		(width 0.12954)
		(layer "F.Cu")
		(net "P2E_CPU0_P5_TX_DP")
	)
	(segment
		(start 187.926472 -57.665366)
		(end 185.524902 -52.514754)
		(width 0.12954)
		(layer "F.Cu")
		(net "P2E_CPU0_P5_TX_DP")
	)
	(segment
		(start 173.480476 -35.598354)
		(end 168.048686 -33.885378)
		(width 0.12954)
		(layer "F.Cu")
		(net "P2E_CPU0_P5_TX_DP")
	)
	(segment
		(start 198.74992 -82.36712)
		(end 195.07581 -81.719166)
		(width 0.12954)
		(layer "F.Cu")
		(net "P2E_CPU0_P5_TX_DP")
	)
	(segment
		(start 185.524902 -52.514754)
		(end 185.149236 -48.221646)
		(width 0.12954)
		(layer "F.Cu")
		(net "P2E_CPU0_P5_TX_DP")
	)
	(segment
		(start 177.9651 -35.598354)
		(end 173.480476 -35.598354)
		(width 0.12954)
		(layer "F.Cu")
		(net "P2E_CPU0_P5_TX_DP")
	)
	(segment
		(start 182.477664 -39.583868)
		(end 179.553616 -36.65982)
		(width 0.12954)
		(layer "F.Cu")
		(net "P2E_CPU0_P5_TX_DP")
	)
	(segment
		(start 189.406784 -59.779408)
		(end 187.926472 -57.665366)
		(width 0.12954)
		(layer "F.Cu")
		(net "P2E_CPU0_P5_TX_DP")
	)
	(segment
		(start 217.996008 -86.007194)
		(end 217.805762 -85.642704)
		(width 0.12954)
		(layer "F.Cu")
		(net "P2E_CPU0_P5_TX_DP")
	)
	(segment
		(start 179.553616 -36.65982)
		(end 177.9651 -35.598354)
		(width 0.12954)
		(layer "F.Cu")
		(net "P2E_CPU0_P5_TX_DP")
	)
	(segment
		(start 184.21477 -42.920666)
		(end 182.477664 -39.583868)
		(width 0.12954)
		(layer "F.Cu")
		(net "P2E_CPU0_P5_TX_DP")
	)
	(segment
		(start 160.819084 -24.509476)
		(end 160.29559 -21.537168)
		(width 0.12954)
		(layer "F.Cu")
		(net "P2E_CPU0_P5_TX_DP")
	)
	(segment
		(start 354.547932 -223.69018)
		(end 354.081334 -223.424242)
		(width 0.12954)
		(layer "F.Cu")
		(net "P2E_CPU0_P5_TX_DP")
	)
	(segment
		(start 204.312266 -82.47253)
		(end 204.312266 -82.472276)
		(width 0.12954)
		(layer "F.Cu")
		(net "P2E_CPU0_P5_TX_DP")
	)
	(segment
		(start 209.804254 -82.575908)
		(end 206.146908 -82.50682)
		(width 0.12954)
		(layer "F.Cu")
		(net "P2E_CPU0_P5_TX_DP")
	)
	(segment
		(start 206.146908 -82.50682)
		(end 206.140812 -82.50682)
		(width 0.12954)
		(layer "F.Cu")
		(net "P2E_CPU0_P5_TX_DP")
	)
	(segment
		(start 190.124588 -65.331848)
		(end 190.221362 -62.809882)
		(width 0.12954)
		(layer "F.Cu")
		(net "P2E_CPU0_P5_TX_DP")
	)
	(segment
		(start 166.683436 -32.884364)
		(end 160.819084 -24.509476)
		(width 0.12954)
		(layer "F.Cu")
		(net "P2E_CPU0_P5_TX_DP")
	)
	(segment
		(start 190.523114 -77.996542)
		(end 189.557914 -74.934318)
		(width 0.12954)
		(layer "F.Cu")
		(net "P2E_CPU0_P5_TX_DP")
	)
	(segment
		(start 191.258698 -79.046832)
		(end 190.523114 -77.996542)
		(width 0.12954)
		(layer "F.Cu")
		(net "P2E_CPU0_P5_TX_DP")
	)
	(segment
		(start 189.557914 -74.934318)
		(end 189.557914 -66.937636)
		(width 0.12954)
		(layer "F.Cu")
		(net "P2E_CPU0_P5_TX_DP")
	)
	(via
		(at 217.725498 -86.92134)
		(size 0.508)
		(drill 0.254)
		(layers "F.Cu" "B.Cu")
		(net "P2E_CPU0_P5_TX_DP")
	)
	(via
		(at 354.081334 -223.424242)
		(size 0.4064)
		(drill 0.2032)
		(layers "F.Cu" "B.Cu")
		(net "P2E_CPU0_P5_TX_DP")
	)
	(segment
		(start 220.276928 -89.45499)
		(end 222.900494 -95.788734)
		(width 0.12954)
		(layer "B.Cu")
		(net "P2E_CPU0_P5_TX_DP")
	)
	(segment
		(start 353.767644 -223.424242)
		(end 354.081334 -223.424242)
		(width 0.0762)
		(layer "B.Cu")
		(net "P2E_CPU0_P5_TX_DP")
	)
	(segment
		(start 217.996008 -85.68055)
		(end 218.315032 -85.361526)
		(width 0.12954)
		(layer "B.Cu")
		(net "P2E_CPU0_P5_TX_DP")
	)
	(segment
		(start 218.315032 -85.361526)
		(end 219.00134 -85.361526)
		(width 0.12954)
		(layer "B.Cu")
		(net "P2E_CPU0_P5_TX_DP")
	)
	(segment
		(start 353.302316 -221.332552)
		(end 353.302316 -221.86519)
		(width 0.12954)
		(layer "B.Cu")
		(net "P2E_CPU0_P5_TX_DP")
	)
	(segment
		(start 220.276928 -87.347806)
		(end 220.276928 -89.45499)
		(width 0.12954)
		(layer "B.Cu")
		(net "P2E_CPU0_P5_TX_DP")
	)
	(segment
		(start 325.636636 -189.484)
		(end 350.34474 -214.192104)
		(width 0.12954)
		(layer "B.Cu")
		(net "P2E_CPU0_P5_TX_DP")
	)
	(segment
		(start 219.774262 -86.134448)
		(end 220.276928 -87.347806)
		(width 0.12954)
		(layer "B.Cu")
		(net "P2E_CPU0_P5_TX_DP")
	)
	(segment
		(start 353.392486 -222.918528)
		(end 353.463352 -222.959676)
		(width 0.0762)
		(layer "B.Cu")
		(net "P2E_CPU0_P5_TX_DP")
	)
	(segment
		(start 222.900748 -95.789496)
		(end 238.331248 -133.042406)
		(width 0.12954)
		(layer "B.Cu")
		(net "P2E_CPU0_P5_TX_DP")
	)
	(segment
		(start 222.900494 -95.788988)
		(end 222.900748 -95.789496)
		(width 0.12954)
		(layer "B.Cu")
		(net "P2E_CPU0_P5_TX_DP")
	)
	(segment
		(start 217.996008 -86.65083)
		(end 217.996008 -85.68055)
		(width 0.12954)
		(layer "B.Cu")
		(net "P2E_CPU0_P5_TX_DP")
	)
	(segment
		(start 217.725498 -86.92134)
		(end 217.996008 -86.65083)
		(width 0.12954)
		(layer "B.Cu")
		(net "P2E_CPU0_P5_TX_DP")
	)
	(segment
		(start 353.703128 -223.359726)
		(end 353.767644 -223.424242)
		(width 0.0762)
		(layer "B.Cu")
		(net "P2E_CPU0_P5_TX_DP")
	)
	(segment
		(start 313.144408 -182.361332)
		(end 319.046606 -185.521346)
		(width 0.12954)
		(layer "B.Cu")
		(net "P2E_CPU0_P5_TX_DP")
	)
	(segment
		(start 289.352228 -175.132238)
		(end 313.144408 -182.361332)
		(width 0.12954)
		(layer "B.Cu")
		(net "P2E_CPU0_P5_TX_DP")
	)
	(segment
		(start 353.236276 -221.95028)
		(end 353.236276 -222.614236)
		(width 0.0762)
		(layer "B.Cu")
		(net "P2E_CPU0_P5_TX_DP")
	)
	(segment
		(start 270.165576 -164.876734)
		(end 289.352228 -175.132238)
		(width 0.12954)
		(layer "B.Cu")
		(net "P2E_CPU0_P5_TX_DP")
	)
	(segment
		(start 319.046606 -185.521346)
		(end 325.524114 -189.408562)
		(width 0.12954)
		(layer "B.Cu")
		(net "P2E_CPU0_P5_TX_DP")
	)
	(segment
		(start 325.524114 -189.408562)
		(end 325.636636 -189.484)
		(width 0.12954)
		(layer "B.Cu")
		(net "P2E_CPU0_P5_TX_DP")
	)
	(segment
		(start 222.900494 -95.788734)
		(end 222.900494 -95.788988)
		(width 0.12954)
		(layer "B.Cu")
		(net "P2E_CPU0_P5_TX_DP")
	)
	(segment
		(start 350.34474 -214.192104)
		(end 353.302316 -221.332552)
		(width 0.12954)
		(layer "B.Cu")
		(net "P2E_CPU0_P5_TX_DP")
	)
	(segment
		(start 353.302316 -221.88424)
		(end 353.236276 -221.95028)
		(width 0.0762)
		(layer "B.Cu")
		(net "P2E_CPU0_P5_TX_DP")
	)
	(segment
		(start 219.00134 -85.361526)
		(end 219.774262 -86.134448)
		(width 0.12954)
		(layer "B.Cu")
		(net "P2E_CPU0_P5_TX_DP")
	)
	(segment
		(start 238.331248 -133.042406)
		(end 270.165576 -164.876734)
		(width 0.12954)
		(layer "B.Cu")
		(net "P2E_CPU0_P5_TX_DP")
	)
	(segment
		(start 353.302316 -221.86519)
		(end 353.302316 -221.88424)
		(width 0.0762)
		(layer "B.Cu")
		(net "P2E_CPU0_P5_TX_DP")
	)
	(arc
		(start 353.700334 -223.338644)
		(mid 353.70183 -223.349172)
		(end 353.703128 -223.359726)
		(width 0.0762)
		(layer "B.Cu")
		(net "P2E_CPU0_P5_TX_DP")
	)
	(arc
		(start 353.30257 -222.82658)
		(mid 353.343553 -222.876442)
		(end 353.392486 -222.918528)
		(width 0.0762)
		(layer "B.Cu")
		(net "P2E_CPU0_P5_TX_DP")
	)
	(arc
		(start 353.463352 -222.959676)
		(mid 353.620882 -223.124747)
		(end 353.700334 -223.338644)
		(width 0.0762)
		(layer "B.Cu")
		(net "P2E_CPU0_P5_TX_DP")
	)
	(arc
		(start 353.236276 -222.614236)
		(mid 353.253326 -222.725427)
		(end 353.30257 -222.82658)
		(width 0.0762)
		(layer "B.Cu")
		(net "P2E_CPU0_P5_TX_DP")
	)
	(segment
		(start 198.781162 -82.045048)
		(end 195.202302 -81.413858)
		(width 0.12954)
		(layer "F.Cu")
		(net "P2E_CPU0_P5_TX_DN")
	)
	(segment
		(start 182.741062 -39.390828)
		(end 179.759356 -36.409122)
		(width 0.12954)
		(layer "F.Cu")
		(net "P2E_CPU0_P5_TX_DN")
	)
	(segment
		(start 189.880494 -66.993008)
		(end 190.445136 -65.393062)
		(width 0.12954)
		(layer "F.Cu")
		(net "P2E_CPU0_P5_TX_DN")
	)
	(segment
		(start 185.46953 -48.179482)
		(end 184.523888 -42.815764)
		(width 0.12954)
		(layer "F.Cu")
		(net "P2E_CPU0_P5_TX_DN")
	)
	(segment
		(start 178.063144 -35.275774)
		(end 173.53026 -35.275774)
		(width 0.12954)
		(layer "F.Cu")
		(net "P2E_CPU0_P5_TX_DN")
	)
	(segment
		(start 168.196514 -33.593532)
		(end 166.91737 -32.65551)
		(width 0.12954)
		(layer "F.Cu")
		(net "P2E_CPU0_P5_TX_DN")
	)
	(segment
		(start 173.53026 -35.275774)
		(end 168.196514 -33.593532)
		(width 0.12954)
		(layer "F.Cu")
		(net "P2E_CPU0_P5_TX_DN")
	)
	(segment
		(start 213.493096 -82.322924)
		(end 206.153004 -82.18424)
		(width 0.12954)
		(layer "F.Cu")
		(net "P2E_CPU0_P5_TX_DN")
	)
	(segment
		(start 191.490346 -78.815184)
		(end 190.815976 -77.852016)
		(width 0.12954)
		(layer "F.Cu")
		(net "P2E_CPU0_P5_TX_DN")
	)
	(segment
		(start 160.61817 -21.508974)
		(end 160.61817 -20.573746)
		(width 0.12954)
		(layer "F.Cu")
		(net "P2E_CPU0_P5_TX_DN")
	)
	(segment
		(start 189.70371 -59.640724)
		(end 188.207142 -57.503314)
		(width 0.12954)
		(layer "F.Cu")
		(net "P2E_CPU0_P5_TX_DN")
	)
	(segment
		(start 218.589098 -86.92134)
		(end 218.318588 -86.65083)
		(width 0.12954)
		(layer "F.Cu")
		(net "P2E_CPU0_P5_TX_DN")
	)
	(segment
		(start 188.207142 -57.503314)
		(end 185.841386 -52.429918)
		(width 0.12954)
		(layer "F.Cu")
		(net "P2E_CPU0_P5_TX_DN")
	)
	(segment
		(start 184.523888 -42.815764)
		(end 182.741062 -39.390828)
		(width 0.12954)
		(layer "F.Cu")
		(net "P2E_CPU0_P5_TX_DN")
	)
	(segment
		(start 185.841386 -52.429918)
		(end 185.46953 -48.179482)
		(width 0.12954)
		(layer "F.Cu")
		(net "P2E_CPU0_P5_TX_DN")
	)
	(segment
		(start 218.318588 -86.65083)
		(end 218.318588 -85.9282)
		(width 0.12954)
		(layer "F.Cu")
		(net "P2E_CPU0_P5_TX_DN")
	)
	(segment
		(start 179.759356 -36.409122)
		(end 178.063144 -35.275774)
		(width 0.12954)
		(layer "F.Cu")
		(net "P2E_CPU0_P5_TX_DN")
	)
	(segment
		(start 218.318588 -85.9282)
		(end 218.07424 -85.459062)
		(width 0.12954)
		(layer "F.Cu")
		(net "P2E_CPU0_P5_TX_DN")
	)
	(segment
		(start 217.0684 -84.312252)
		(end 214.47379 -82.495898)
		(width 0.12954)
		(layer "F.Cu")
		(net "P2E_CPU0_P5_TX_DN")
	)
	(segment
		(start 218.07424 -85.459062)
		(end 217.0684 -84.312252)
		(width 0.12954)
		(layer "F.Cu")
		(net "P2E_CPU0_P5_TX_DN")
	)
	(segment
		(start 206.153004 -82.18424)
		(end 206.146908 -82.18424)
		(width 0.12954)
		(layer "F.Cu")
		(net "P2E_CPU0_P5_TX_DN")
	)
	(segment
		(start 189.880494 -74.884534)
		(end 189.880494 -66.993008)
		(width 0.12954)
		(layer "F.Cu")
		(net "P2E_CPU0_P5_TX_DN")
	)
	(segment
		(start 161.124392 -24.382984)
		(end 160.61817 -21.508974)
		(width 0.12954)
		(layer "F.Cu")
		(net "P2E_CPU0_P5_TX_DN")
	)
	(segment
		(start 190.445136 -65.393062)
		(end 190.54572 -62.773306)
		(width 0.12954)
		(layer "F.Cu")
		(net "P2E_CPU0_P5_TX_DN")
	)
	(segment
		(start 190.54572 -62.773306)
		(end 189.70371 -59.640724)
		(width 0.12954)
		(layer "F.Cu")
		(net "P2E_CPU0_P5_TX_DN")
	)
	(segment
		(start 214.47379 -82.495898)
		(end 213.493096 -82.322924)
		(width 0.12954)
		(layer "F.Cu")
		(net "P2E_CPU0_P5_TX_DN")
	)
	(segment
		(start 160.61817 -20.573746)
		(end 160.856422 -20.335494)
		(width 0.12954)
		(layer "F.Cu")
		(net "P2E_CPU0_P5_TX_DN")
	)
	(segment
		(start 190.815976 -77.852016)
		(end 189.880494 -74.884534)
		(width 0.12954)
		(layer "F.Cu")
		(net "P2E_CPU0_P5_TX_DN")
	)
	(segment
		(start 206.146908 -82.18424)
		(end 198.781162 -82.045048)
		(width 0.12954)
		(layer "F.Cu")
		(net "P2E_CPU0_P5_TX_DN")
	)
	(segment
		(start 353.607878 -223.69018)
		(end 353.14128 -223.424242)
		(width 0.12954)
		(layer "F.Cu")
		(net "P2E_CPU0_P5_TX_DN")
	)
	(segment
		(start 195.202302 -81.413858)
		(end 191.490346 -78.815184)
		(width 0.12954)
		(layer "F.Cu")
		(net "P2E_CPU0_P5_TX_DN")
	)
	(segment
		(start 166.91737 -32.65551)
		(end 161.124392 -24.382984)
		(width 0.12954)
		(layer "F.Cu")
		(net "P2E_CPU0_P5_TX_DN")
	)
	(via
		(at 353.14128 -223.424242)
		(size 0.4064)
		(drill 0.2032)
		(layers "F.Cu" "B.Cu")
		(net "P2E_CPU0_P5_TX_DN")
	)
	(via
		(at 218.589098 -86.92134)
		(size 0.508)
		(drill 0.254)
		(layers "F.Cu" "B.Cu")
		(net "P2E_CPU0_P5_TX_DN")
	)
	(segment
		(start 218.589098 -86.92134)
		(end 218.318588 -86.65083)
		(width 0.12954)
		(layer "B.Cu")
		(net "P2E_CPU0_P5_TX_DN")
	)
	(segment
		(start 222.353886 -95.809308)
		(end 222.60306 -95.912432)
		(width 0.12954)
		(layer "B.Cu")
		(net "P2E_CPU0_P5_TX_DN")
	)
	(segment
		(start 219.954348 -87.933276)
		(end 219.763848 -88.123776)
		(width 0.12954)
		(layer "B.Cu")
		(net "P2E_CPU0_P5_TX_DN")
	)
	(segment
		(start 222.206058 -95.452438)
		(end 222.353886 -95.809308)
		(width 0.12954)
		(layer "B.Cu")
		(net "P2E_CPU0_P5_TX_DN")
	)
	(segment
		(start 325.430896 -189.734698)
		(end 350.071182 -214.374984)
		(width 0.12954)
		(layer "B.Cu")
		(net "P2E_CPU0_P5_TX_DN")
	)
	(segment
		(start 221.278196 -92.716096)
		(end 221.426024 -93.072458)
		(width 0.12954)
		(layer "B.Cu")
		(net "P2E_CPU0_P5_TX_DN")
	)
	(segment
		(start 220.101922 -89.875868)
		(end 219.998798 -90.124788)
		(width 0.12954)
		(layer "B.Cu")
		(net "P2E_CPU0_P5_TX_DN")
	)
	(segment
		(start 318.887348 -185.802016)
		(end 325.35114 -189.681358)
		(width 0.12954)
		(layer "B.Cu")
		(net "P2E_CPU0_P5_TX_DN")
	)
	(segment
		(start 289.228022 -175.431704)
		(end 313.020202 -182.660798)
		(width 0.12954)
		(layer "B.Cu")
		(net "P2E_CPU0_P5_TX_DN")
	)
	(segment
		(start 221.912434 -94.743778)
		(end 222.161608 -94.846902)
		(width 0.12954)
		(layer "B.Cu")
		(net "P2E_CPU0_P5_TX_DN")
	)
	(segment
		(start 222.308928 -95.203518)
		(end 222.309182 -95.203518)
		(width 0.12954)
		(layer "B.Cu")
		(net "P2E_CPU0_P5_TX_DN")
	)
	(segment
		(start 220.543374 -90.941398)
		(end 220.44025 -91.190318)
		(width 0.12954)
		(layer "B.Cu")
		(net "P2E_CPU0_P5_TX_DN")
	)
	(segment
		(start 218.318588 -85.814408)
		(end 218.44889 -85.684106)
		(width 0.12954)
		(layer "B.Cu")
		(net "P2E_CPU0_P5_TX_DN")
	)
	(segment
		(start 313.020202 -182.660798)
		(end 318.887348 -185.802016)
		(width 0.12954)
		(layer "B.Cu")
		(net "P2E_CPU0_P5_TX_DN")
	)
	(segment
		(start 353.045776 -221.95028)
		(end 353.045776 -222.614236)
		(width 0.0762)
		(layer "B.Cu")
		(net "P2E_CPU0_P5_TX_DN")
	)
	(segment
		(start 220.836998 -91.650312)
		(end 220.984826 -92.006928)
		(width 0.12954)
		(layer "B.Cu")
		(net "P2E_CPU0_P5_TX_DN")
	)
	(segment
		(start 221.720156 -93.781372)
		(end 221.719648 -93.781372)
		(width 0.12954)
		(layer "B.Cu")
		(net "P2E_CPU0_P5_TX_DN")
	)
	(segment
		(start 222.1611 -94.847156)
		(end 222.308928 -95.203518)
		(width 0.12954)
		(layer "B.Cu")
		(net "P2E_CPU0_P5_TX_DN")
	)
	(segment
		(start 219.763848 -88.509856)
		(end 219.954348 -88.700356)
		(width 0.12954)
		(layer "B.Cu")
		(net "P2E_CPU0_P5_TX_DN")
	)
	(segment
		(start 221.86773 -94.137988)
		(end 221.764606 -94.386908)
		(width 0.12954)
		(layer "B.Cu")
		(net "P2E_CPU0_P5_TX_DN")
	)
	(segment
		(start 221.867476 -94.137988)
		(end 221.86773 -94.137988)
		(width 0.12954)
		(layer "B.Cu")
		(net "P2E_CPU0_P5_TX_DN")
	)
	(segment
		(start 350.071182 -214.374984)
		(end 352.979736 -221.396814)
		(width 0.12954)
		(layer "B.Cu")
		(net "P2E_CPU0_P5_TX_DN")
	)
	(segment
		(start 353.45497 -223.424242)
		(end 353.14128 -223.424242)
		(width 0.0762)
		(layer "B.Cu")
		(net "P2E_CPU0_P5_TX_DN")
	)
	(segment
		(start 221.764606 -94.386908)
		(end 221.912434 -94.743778)
		(width 0.12954)
		(layer "B.Cu")
		(net "P2E_CPU0_P5_TX_DN")
	)
	(segment
		(start 220.3958 -90.584782)
		(end 220.543374 -90.941398)
		(width 0.12954)
		(layer "B.Cu")
		(net "P2E_CPU0_P5_TX_DN")
	)
	(segment
		(start 222.161608 -94.846902)
		(end 222.1611 -94.847156)
		(width 0.12954)
		(layer "B.Cu")
		(net "P2E_CPU0_P5_TX_DN")
	)
	(segment
		(start 219.998798 -90.124788)
		(end 220.146626 -90.481658)
		(width 0.12954)
		(layer "B.Cu")
		(net "P2E_CPU0_P5_TX_DN")
	)
	(segment
		(start 352.979736 -221.396814)
		(end 352.979736 -221.86519)
		(width 0.12954)
		(layer "B.Cu")
		(net "P2E_CPU0_P5_TX_DN")
	)
	(segment
		(start 353.289108 -223.078802)
		(end 353.328224 -223.101662)
		(width 0.0762)
		(layer "B.Cu")
		(net "P2E_CPU0_P5_TX_DN")
	)
	(segment
		(start 222.309182 -95.203518)
		(end 222.206058 -95.452438)
		(width 0.12954)
		(layer "B.Cu")
		(net "P2E_CPU0_P5_TX_DN")
	)
	(segment
		(start 269.971266 -165.138862)
		(end 289.228022 -175.431704)
		(width 0.12954)
		(layer "B.Cu")
		(net "P2E_CPU0_P5_TX_DN")
	)
	(segment
		(start 219.954348 -89.519252)
		(end 220.101922 -89.875868)
		(width 0.12954)
		(layer "B.Cu")
		(net "P2E_CPU0_P5_TX_DN")
	)
	(segment
		(start 221.426278 -93.072458)
		(end 221.323154 -93.321378)
		(width 0.12954)
		(layer "B.Cu")
		(net "P2E_CPU0_P5_TX_DN")
	)
	(segment
		(start 220.837252 -91.650312)
		(end 220.836998 -91.650312)
		(width 0.12954)
		(layer "B.Cu")
		(net "P2E_CPU0_P5_TX_DN")
	)
	(segment
		(start 352.979736 -221.86519)
		(end 352.979736 -221.88424)
		(width 0.0762)
		(layer "B.Cu")
		(net "P2E_CPU0_P5_TX_DN")
	)
	(segment
		(start 221.323154 -93.321378)
		(end 221.470982 -93.678248)
		(width 0.12954)
		(layer "B.Cu")
		(net "P2E_CPU0_P5_TX_DN")
	)
	(segment
		(start 222.60306 -95.912432)
		(end 222.602552 -95.912686)
		(width 0.12954)
		(layer "B.Cu")
		(net "P2E_CPU0_P5_TX_DN")
	)
	(segment
		(start 238.05769 -133.225286)
		(end 269.971266 -165.138862)
		(width 0.12954)
		(layer "B.Cu")
		(net "P2E_CPU0_P5_TX_DN")
	)
	(segment
		(start 221.02953 -92.612718)
		(end 221.278704 -92.715842)
		(width 0.12954)
		(layer "B.Cu")
		(net "P2E_CPU0_P5_TX_DN")
	)
	(segment
		(start 218.318588 -86.65083)
		(end 218.318588 -85.814408)
		(width 0.12954)
		(layer "B.Cu")
		(net "P2E_CPU0_P5_TX_DN")
	)
	(segment
		(start 219.954348 -88.700356)
		(end 219.954348 -89.519252)
		(width 0.12954)
		(layer "B.Cu")
		(net "P2E_CPU0_P5_TX_DN")
	)
	(segment
		(start 221.470982 -93.678248)
		(end 221.720156 -93.781372)
		(width 0.12954)
		(layer "B.Cu")
		(net "P2E_CPU0_P5_TX_DN")
	)
	(segment
		(start 220.146626 -90.481658)
		(end 220.3958 -90.584782)
		(width 0.12954)
		(layer "B.Cu")
		(net "P2E_CPU0_P5_TX_DN")
	)
	(segment
		(start 221.426024 -93.072458)
		(end 221.426278 -93.072458)
		(width 0.12954)
		(layer "B.Cu")
		(net "P2E_CPU0_P5_TX_DN")
	)
	(segment
		(start 220.984826 -92.006928)
		(end 220.881702 -92.255848)
		(width 0.12954)
		(layer "B.Cu")
		(net "P2E_CPU0_P5_TX_DN")
	)
	(segment
		(start 325.35114 -189.681358)
		(end 325.430896 -189.734698)
		(width 0.12954)
		(layer "B.Cu")
		(net "P2E_CPU0_P5_TX_DN")
	)
	(segment
		(start 353.511612 -223.3676)
		(end 353.45497 -223.424242)
		(width 0.0762)
		(layer "B.Cu")
		(net "P2E_CPU0_P5_TX_DN")
	)
	(segment
		(start 219.500704 -86.317328)
		(end 219.954348 -87.412068)
		(width 0.12954)
		(layer "B.Cu")
		(net "P2E_CPU0_P5_TX_DN")
	)
	(segment
		(start 220.881702 -92.255848)
		(end 221.02953 -92.612718)
		(width 0.12954)
		(layer "B.Cu")
		(net "P2E_CPU0_P5_TX_DN")
	)
	(segment
		(start 222.602552 -95.912686)
		(end 238.05769 -133.225286)
		(width 0.12954)
		(layer "B.Cu")
		(net "P2E_CPU0_P5_TX_DN")
	)
	(segment
		(start 353.328224 -223.101662)
		(end 353.359974 -223.11995)
		(width 0.0762)
		(layer "B.Cu")
		(net "P2E_CPU0_P5_TX_DN")
	)
	(segment
		(start 219.763848 -88.123776)
		(end 219.763848 -88.509856)
		(width 0.12954)
		(layer "B.Cu")
		(net "P2E_CPU0_P5_TX_DN")
	)
	(segment
		(start 218.44889 -85.684106)
		(end 218.867482 -85.684106)
		(width 0.12954)
		(layer "B.Cu")
		(net "P2E_CPU0_P5_TX_DN")
	)
	(segment
		(start 352.979736 -221.88424)
		(end 353.045776 -221.95028)
		(width 0.0762)
		(layer "B.Cu")
		(net "P2E_CPU0_P5_TX_DN")
	)
	(segment
		(start 220.44025 -91.190318)
		(end 220.588078 -91.547188)
		(width 0.12954)
		(layer "B.Cu")
		(net "P2E_CPU0_P5_TX_DN")
	)
	(segment
		(start 219.954348 -87.412068)
		(end 219.954348 -87.933276)
		(width 0.12954)
		(layer "B.Cu")
		(net "P2E_CPU0_P5_TX_DN")
	)
	(segment
		(start 220.588078 -91.547188)
		(end 220.837252 -91.650312)
		(width 0.12954)
		(layer "B.Cu")
		(net "P2E_CPU0_P5_TX_DN")
	)
	(segment
		(start 221.278704 -92.715842)
		(end 221.278196 -92.716096)
		(width 0.12954)
		(layer "B.Cu")
		(net "P2E_CPU0_P5_TX_DN")
	)
	(segment
		(start 218.867482 -85.684106)
		(end 219.500704 -86.317328)
		(width 0.12954)
		(layer "B.Cu")
		(net "P2E_CPU0_P5_TX_DN")
	)
	(segment
		(start 221.719648 -93.781372)
		(end 221.867476 -94.137988)
		(width 0.12954)
		(layer "B.Cu")
		(net "P2E_CPU0_P5_TX_DN")
	)
	(arc
		(start 353.045776 -222.614236)
		(mid 353.071196 -222.782081)
		(end 353.145344 -222.934784)
		(width 0.0762)
		(layer "B.Cu")
		(net "P2E_CPU0_P5_TX_DN")
	)
	(arc
		(start 353.145344 -222.934784)
		(mid 353.210696 -223.013311)
		(end 353.289108 -223.078802)
		(width 0.0762)
		(layer "B.Cu")
		(net "P2E_CPU0_P5_TX_DN")
	)
	(arc
		(start 353.359974 -223.11995)
		(mid 353.460803 -223.228472)
		(end 353.511612 -223.3676)
		(width 0.0762)
		(layer "B.Cu")
		(net "P2E_CPU0_P5_TX_DN")
	)
	(segment
		(start 184.461912 -12.384278)
		(end 183.726582 -11.648948)
		(width 0.10668)
		(layer "F.Cu")
		(net "I3C_SCM_3_SDA")
	)
	(segment
		(start 183.726582 -11.648948)
		(end 182.834534 -11.648948)
		(width 0.10668)
		(layer "F.Cu")
		(net "I3C_SCM_3_SDA")
	)
	(segment
		(start 184.461912 -13.599922)
		(end 184.461912 -12.384278)
		(width 0.10668)
		(layer "F.Cu")
		(net "I3C_SCM_3_SDA")
	)
	(via
		(at 182.834534 -11.648948)
		(size 0.508)
		(drill 0.254)
		(layers "F.Cu" "B.Cu")
		(net "I3C_SCM_3_SDA")
	)
	(segment
		(start 182.8673 -11.681714)
		(end 182.8673 -13.20038)
		(width 0.10668)
		(layer "B.Cu")
		(net "I3C_SCM_3_SDA")
	)
	(segment
		(start 182.834534 -11.648948)
		(end 182.8673 -11.681714)
		(width 0.10668)
		(layer "B.Cu")
		(net "I3C_SCM_3_SDA")
	)
	(segment
		(start 185.062114 -13.599922)
		(end 185.062114 -12.057888)
		(width 0.10668)
		(layer "F.Cu")
		(net "I3C_SCM_3_SCL")
	)
	(segment
		(start 185.062114 -12.057888)
		(end 184.053734 -11.049508)
		(width 0.10668)
		(layer "F.Cu")
		(net "I3C_SCM_3_SCL")
	)
	(segment
		(start 184.053734 -11.049508)
		(end 184.053734 -10.175748)
		(width 0.10668)
		(layer "F.Cu")
		(net "I3C_SCM_3_SCL")
	)
	(via
		(at 184.053734 -10.175748)
		(size 0.508)
		(drill 0.254)
		(layers "F.Cu" "B.Cu")
		(net "I3C_SCM_3_SCL")
	)
	(segment
		(start 184.05983 -10.181844)
		(end 184.05983 -13.20038)
		(width 0.10668)
		(layer "B.Cu")
		(net "I3C_SCM_3_SCL")
	)
	(segment
		(start 184.053734 -10.175748)
		(end 184.05983 -10.181844)
		(width 0.10668)
		(layer "B.Cu")
		(net "I3C_SCM_3_SCL")
	)
	(segment
		(start 185.662062 -13.599922)
		(end 185.662062 -11.631676)
		(width 0.10668)
		(layer "F.Cu")
		(net "I3C_SCM_2_SDA")
	)
	(segment
		(start 185.662062 -11.631676)
		(end 185.095134 -11.064748)
		(width 0.10668)
		(layer "F.Cu")
		(net "I3C_SCM_2_SDA")
	)
	(via
		(at 185.095134 -11.064748)
		(size 0.508)
		(drill 0.254)
		(layers "F.Cu" "B.Cu")
		(net "I3C_SCM_2_SDA")
	)
	(segment
		(start 185.095134 -11.064748)
		(end 185.240676 -11.21029)
		(width 0.10668)
		(layer "B.Cu")
		(net "I3C_SCM_2_SDA")
	)
	(segment
		(start 185.240676 -11.21029)
		(end 185.240676 -13.20038)
		(width 0.10668)
		(layer "B.Cu")
		(net "I3C_SCM_2_SDA")
	)
	(segment
		(start 186.26201 -13.599922)
		(end 186.26201 -10.378948)
		(width 0.10668)
		(layer "F.Cu")
		(net "I3C_SCM_2_SCL")
	)
	(via
		(at 186.26201 -10.378948)
		(size 0.508)
		(drill 0.254)
		(layers "F.Cu" "B.Cu")
		(net "I3C_SCM_2_SCL")
	)
	(segment
		(start 186.26201 -10.378948)
		(end 186.26201 -10.812272)
		(width 0.10668)
		(layer "B.Cu")
		(net "I3C_SCM_2_SCL")
	)
	(segment
		(start 186.26201 -10.812272)
		(end 186.345322 -10.895584)
		(width 0.10668)
		(layer "B.Cu")
		(net "I3C_SCM_2_SCL")
	)
	(segment
		(start 186.345322 -10.895584)
		(end 186.345322 -13.20038)
		(width 0.10668)
		(layer "B.Cu")
		(net "I3C_SCM_2_SCL")
	)
	(segment
		(start 186.861958 -13.599922)
		(end 186.861958 -11.736324)
		(width 0.10668)
		(layer "F.Cu")
		(net "I3C_SCM_1_SDA")
	)
	(segment
		(start 186.861958 -11.736324)
		(end 187.101734 -11.496548)
		(width 0.10668)
		(layer "F.Cu")
		(net "I3C_SCM_1_SDA")
	)
	(via
		(at 187.101734 -11.496548)
		(size 0.508)
		(drill 0.254)
		(layers "F.Cu" "B.Cu")
		(net "I3C_SCM_1_SDA")
	)
	(segment
		(start 187.349384 -13.20038)
		(end 187.349384 -11.744198)
		(width 0.10668)
		(layer "B.Cu")
		(net "I3C_SCM_1_SDA")
	)
	(segment
		(start 187.349384 -11.744198)
		(end 187.101734 -11.496548)
		(width 0.10668)
		(layer "B.Cu")
		(net "I3C_SCM_1_SDA")
	)
	(segment
		(start 187.461906 -11.898376)
		(end 187.985654 -11.374628)
		(width 0.10668)
		(layer "F.Cu")
		(net "I3C_SCM_1_SCL")
	)
	(segment
		(start 187.461906 -13.599922)
		(end 187.461906 -11.898376)
		(width 0.10668)
		(layer "F.Cu")
		(net "I3C_SCM_1_SCL")
	)
	(segment
		(start 187.985654 -11.374628)
		(end 187.985654 -10.455148)
		(width 0.10668)
		(layer "F.Cu")
		(net "I3C_SCM_1_SCL")
	)
	(via
		(at 187.985654 -10.455148)
		(size 0.508)
		(drill 0.254)
		(layers "F.Cu" "B.Cu")
		(net "I3C_SCM_1_SCL")
	)
	(segment
		(start 188.19622 -13.20038)
		(end 188.066934 -13.071094)
		(width 0.10668)
		(layer "B.Cu")
		(net "I3C_SCM_1_SCL")
	)
	(segment
		(start 188.310012 -13.20038)
		(end 188.19622 -13.20038)
		(width 0.10668)
		(layer "B.Cu")
		(net "I3C_SCM_1_SCL")
	)
	(segment
		(start 188.066934 -13.071094)
		(end 188.066934 -10.536428)
		(width 0.10668)
		(layer "B.Cu")
		(net "I3C_SCM_1_SCL")
	)
	(segment
		(start 188.066934 -10.536428)
		(end 187.985654 -10.455148)
		(width 0.10668)
		(layer "B.Cu")
		(net "I3C_SCM_1_SCL")
	)
	(segment
		(start 189.458854 -10.663428)
		(end 189.458854 -10.251948)
		(width 0.10668)
		(layer "F.Cu")
		(net "I3C_SCM_0_SDA")
	)
	(segment
		(start 188.062108 -12.060174)
		(end 189.458854 -10.663428)
		(width 0.10668)
		(layer "F.Cu")
		(net "I3C_SCM_0_SDA")
	)
	(segment
		(start 188.062108 -13.599922)
		(end 188.062108 -12.060174)
		(width 0.10668)
		(layer "F.Cu")
		(net "I3C_SCM_0_SDA")
	)
	(via
		(at 189.458854 -10.251948)
		(size 0.508)
		(drill 0.254)
		(layers "F.Cu" "B.Cu")
		(net "I3C_SCM_0_SDA")
	)
	(segment
		(start 188.857382 -12.845796)
		(end 188.752734 -12.593066)
		(width 0.10668)
		(layer "B.Cu")
		(net "I3C_SCM_0_SDA")
	)
	(segment
		(start 188.752734 -10.958068)
		(end 189.458854 -10.251948)
		(width 0.10668)
		(layer "B.Cu")
		(net "I3C_SCM_0_SDA")
	)
	(segment
		(start 189.35065 -13.20038)
		(end 189.211966 -13.20038)
		(width 0.10668)
		(layer "B.Cu")
		(net "I3C_SCM_0_SDA")
	)
	(segment
		(start 188.752734 -12.593066)
		(end 188.752734 -10.958068)
		(width 0.10668)
		(layer "B.Cu")
		(net "I3C_SCM_0_SDA")
	)
	(segment
		(start 189.211966 -13.20038)
		(end 188.857382 -12.845796)
		(width 0.10668)
		(layer "B.Cu")
		(net "I3C_SCM_0_SDA")
	)
	(segment
		(start 188.662056 -13.599922)
		(end 188.662056 -12.234418)
		(width 0.10668)
		(layer "F.Cu")
		(net "I3C_SCM_0_SCL")
	)
	(segment
		(start 189.145926 -11.750548)
		(end 189.509654 -11.750548)
		(width 0.10668)
		(layer "F.Cu")
		(net "I3C_SCM_0_SCL")
	)
	(segment
		(start 188.662056 -12.234418)
		(end 189.145926 -11.750548)
		(width 0.10668)
		(layer "F.Cu")
		(net "I3C_SCM_0_SCL")
	)
	(via
		(at 189.509654 -11.750548)
		(size 0.508)
		(drill 0.254)
		(layers "F.Cu" "B.Cu")
		(net "I3C_SCM_0_SCL")
	)
	(segment
		(start 189.509654 -11.750548)
		(end 190.017654 -11.750548)
		(width 0.10668)
		(layer "B.Cu")
		(net "I3C_SCM_0_SCL")
	)
	(segment
		(start 190.017654 -11.750548)
		(end 190.367412 -12.100306)
		(width 0.10668)
		(layer "B.Cu")
		(net "I3C_SCM_0_SCL")
	)
	(segment
		(start 190.367412 -12.100306)
		(end 190.367412 -13.20038)
		(width 0.10668)
		(layer "B.Cu")
		(net "I3C_SCM_0_SCL")
	)
	(segment
		(start 292.372796 -426.032422)
		(end 292.636956 -425.768262)
		(width 0.10668)
		(layer "F.Cu")
		(net "I3C_BMC_SWB_R_SDA")
	)
	(segment
		(start 291.202618 -426.032422)
		(end 292.372796 -426.032422)
		(width 0.10668)
		(layer "F.Cu")
		(net "I3C_BMC_SWB_R_SDA")
	)
	(segment
		(start 292.636956 -425.768262)
		(end 292.636956 -424.819318)
		(width 0.10668)
		(layer "F.Cu")
		(net "I3C_BMC_SWB_R_SDA")
	)
	(via
		(at 292.636956 -424.819318)
		(size 0.508)
		(drill 0.254)
		(layers "F.Cu" "B.Cu")
		(net "I3C_BMC_SWB_R_SDA")
	)
	(segment
		(start 291.097716 -425.179998)
		(end 291.578538 -425.66082)
		(width 0.10668)
		(layer "B.Cu")
		(net "I3C_BMC_SWB_R_SDA")
	)
	(segment
		(start 292.636956 -424.819318)
		(end 292.42004 -424.819318)
		(width 0.10668)
		(layer "B.Cu")
		(net "I3C_BMC_SWB_R_SDA")
	)
	(segment
		(start 290.492434 -425.179998)
		(end 291.097716 -425.179998)
		(width 0.10668)
		(layer "B.Cu")
		(net "I3C_BMC_SWB_R_SDA")
	)
	(segment
		(start 292.42004 -424.819318)
		(end 291.578538 -425.66082)
		(width 0.10668)
		(layer "B.Cu")
		(net "I3C_BMC_SWB_R_SDA")
	)
	(segment
		(start 230.604822 -140.590778)
		(end 230.604822 -121.06529)
		(width 0.10668)
		(layer "F.Cu")
		(net "I3C_BMC_SWB_R_SCL")
	)
	(segment
		(start 226.892358 -150.446486)
		(end 229.074218 -148.264626)
		(width 0.10668)
		(layer "F.Cu")
		(net "I3C_BMC_SWB_R_SCL")
	)
	(segment
		(start 235.049822 -166.671244)
		(end 226.892358 -158.51378)
		(width 0.10668)
		(layer "F.Cu")
		(net "I3C_BMC_SWB_R_SCL")
	)
	(segment
		(start 229.074218 -142.121382)
		(end 230.604822 -140.590778)
		(width 0.10668)
		(layer "F.Cu")
		(net "I3C_BMC_SWB_R_SCL")
	)
	(segment
		(start 235.049822 -173.01337)
		(end 235.049822 -166.671244)
		(width 0.10668)
		(layer "F.Cu")
		(net "I3C_BMC_SWB_R_SCL")
	)
	(segment
		(start 226.892358 -158.51378)
		(end 226.892358 -150.446486)
		(width 0.10668)
		(layer "F.Cu")
		(net "I3C_BMC_SWB_R_SCL")
	)
	(segment
		(start 287.834324 -425.678092)
		(end 287.834324 -425.547282)
		(width 0.10668)
		(layer "F.Cu")
		(net "I3C_BMC_SWB_R_SCL")
	)
	(segment
		(start 229.074218 -148.264626)
		(end 229.074218 -142.121382)
		(width 0.10668)
		(layer "F.Cu")
		(net "I3C_BMC_SWB_R_SCL")
	)
	(segment
		(start 241.779044 -204.34173)
		(end 242.434872 -203.685902)
		(width 0.10668)
		(layer "F.Cu")
		(net "I3C_BMC_SWB_R_SCL")
	)
	(segment
		(start 227.667566 -94.753938)
		(end 221.509082 -88.595454)
		(width 0.10668)
		(layer "F.Cu")
		(net "I3C_BMC_SWB_R_SCL")
	)
	(segment
		(start 230.604822 -121.06529)
		(end 227.667566 -118.128034)
		(width 0.10668)
		(layer "F.Cu")
		(net "I3C_BMC_SWB_R_SCL")
	)
	(segment
		(start 287.479994 -426.032422)
		(end 287.834324 -425.678092)
		(width 0.10668)
		(layer "F.Cu")
		(net "I3C_BMC_SWB_R_SCL")
	)
	(segment
		(start 286.737806 -426.032422)
		(end 287.479994 -426.032422)
		(width 0.10668)
		(layer "F.Cu")
		(net "I3C_BMC_SWB_R_SCL")
	)
	(segment
		(start 213.476078 -85.572854)
		(end 213.476078 -85.183472)
		(width 0.10668)
		(layer "F.Cu")
		(net "I3C_BMC_SWB_R_SCL")
	)
	(segment
		(start 242.434872 -203.685902)
		(end 242.434872 -190.843408)
		(width 0.10668)
		(layer "F.Cu")
		(net "I3C_BMC_SWB_R_SCL")
	)
	(segment
		(start 216.498678 -88.595454)
		(end 213.476078 -85.572854)
		(width 0.10668)
		(layer "F.Cu")
		(net "I3C_BMC_SWB_R_SCL")
	)
	(segment
		(start 227.667566 -118.128034)
		(end 227.667566 -94.753938)
		(width 0.10668)
		(layer "F.Cu")
		(net "I3C_BMC_SWB_R_SCL")
	)
	(segment
		(start 242.434872 -190.843408)
		(end 235.049822 -173.01337)
		(width 0.10668)
		(layer "F.Cu")
		(net "I3C_BMC_SWB_R_SCL")
	)
	(segment
		(start 221.509082 -88.595454)
		(end 216.498678 -88.595454)
		(width 0.10668)
		(layer "F.Cu")
		(net "I3C_BMC_SWB_R_SCL")
	)
	(via
		(at 241.779044 -204.34173)
		(size 0.508)
		(drill 0.254)
		(layers "F.Cu" "B.Cu")
		(net "I3C_BMC_SWB_R_SCL")
	)
	(via
		(at 213.476078 -85.183472)
		(size 0.508)
		(drill 0.254)
		(layers "F.Cu" "B.Cu")
		(net "I3C_BMC_SWB_R_SCL")
	)
	(via
		(at 173.575726 -14.771878)
		(size 0.508)
		(drill 0.254)
		(layers "F.Cu" "B.Cu")
		(net "I3C_BMC_SWB_R_SCL")
	)
	(via
		(at 287.834324 -425.547282)
		(size 0.508)
		(drill 0.254)
		(layers "F.Cu" "B.Cu")
		(net "I3C_BMC_SWB_R_SCL")
	)
	(segment
		(start 172.285914 -14.035278)
		(end 172.797216 -14.54658)
		(width 0.10668)
		(layer "B.Cu")
		(net "I3C_BMC_SWB_R_SCL")
	)
	(segment
		(start 173.350428 -14.54658)
		(end 173.575726 -14.771878)
		(width 0.10668)
		(layer "B.Cu")
		(net "I3C_BMC_SWB_R_SCL")
	)
	(segment
		(start 287.823656 -425.55795)
		(end 287.834324 -425.547282)
		(width 0.10668)
		(layer "B.Cu")
		(net "I3C_BMC_SWB_R_SCL")
	)
	(segment
		(start 286.893 -425.55795)
		(end 287.823656 -425.55795)
		(width 0.10668)
		(layer "B.Cu")
		(net "I3C_BMC_SWB_R_SCL")
	)
	(segment
		(start 172.797216 -14.54658)
		(end 173.350428 -14.54658)
		(width 0.10668)
		(layer "B.Cu")
		(net "I3C_BMC_SWB_R_SCL")
	)
	(segment
		(start 286.154876 -418.755576)
		(end 286.554418 -419.155118)
		(width 0.11684)
		(layer "In4.Cu")
		(net "I3C_BMC_SWB_R_SCL")
	)
	(segment
		(start 241.779044 -204.34173)
		(end 242.777772 -204.34173)
		(width 0.11684)
		(layer "In4.Cu")
		(net "I3C_BMC_SWB_R_SCL")
	)
	(segment
		(start 212.254084 -80.98155)
		(end 213.476078 -82.203544)
		(width 0.11684)
		(layer "In4.Cu")
		(net "I3C_BMC_SWB_R_SCL")
	)
	(segment
		(start 211.37118 -58.45429)
		(end 210.39709 -59.42838)
		(width 0.11684)
		(layer "In4.Cu")
		(net "I3C_BMC_SWB_R_SCL")
	)
	(segment
		(start 173.771052 -14.249908)
		(end 176.888394 -14.249908)
		(width 0.11684)
		(layer "In4.Cu")
		(net "I3C_BMC_SWB_R_SCL")
	)
	(segment
		(start 286.554418 -419.155118)
		(end 286.554418 -421.048942)
		(width 0.11684)
		(layer "In4.Cu")
		(net "I3C_BMC_SWB_R_SCL")
	)
	(segment
		(start 270.322548 -363.93882)
		(end 270.322548 -365.041942)
		(width 0.11684)
		(layer "In4.Cu")
		(net "I3C_BMC_SWB_R_SCL")
	)
	(segment
		(start 242.777772 -204.34173)
		(end 250.140978 -211.704936)
		(width 0.11684)
		(layer "In4.Cu")
		(net "I3C_BMC_SWB_R_SCL")
	)
	(segment
		(start 173.575726 -14.445234)
		(end 173.771052 -14.249908)
		(width 0.11684)
		(layer "In4.Cu")
		(net "I3C_BMC_SWB_R_SCL")
	)
	(segment
		(start 185.450734 -13.680694)
		(end 186.08421 -14.31417)
		(width 0.11684)
		(layer "In4.Cu")
		(net "I3C_BMC_SWB_R_SCL")
	)
	(segment
		(start 285.572708 -381.995426)
		(end 285.572708 -387.542278)
		(width 0.11684)
		(layer "In4.Cu")
		(net "I3C_BMC_SWB_R_SCL")
	)
	(segment
		(start 270.322548 -365.041942)
		(end 271.077436 -365.79683)
		(width 0.11684)
		(layer "In4.Cu")
		(net "I3C_BMC_SWB_R_SCL")
	)
	(segment
		(start 187.024772 -16.694658)
		(end 187.597796 -16.694658)
		(width 0.11684)
		(layer "In4.Cu")
		(net "I3C_BMC_SWB_R_SCL")
	)
	(segment
		(start 285.28391 -400.138138)
		(end 286.80664 -401.660868)
		(width 0.11684)
		(layer "In4.Cu")
		(net "I3C_BMC_SWB_R_SCL")
	)
	(segment
		(start 286.80664 -401.660868)
		(end 286.80664 -411.268926)
		(width 0.11684)
		(layer "In4.Cu")
		(net "I3C_BMC_SWB_R_SCL")
	)
	(segment
		(start 286.80664 -411.268926)
		(end 286.554418 -411.521148)
		(width 0.11684)
		(layer "In4.Cu")
		(net "I3C_BMC_SWB_R_SCL")
	)
	(segment
		(start 250.140978 -211.704936)
		(end 250.140978 -248.089674)
		(width 0.11684)
		(layer "In4.Cu")
		(net "I3C_BMC_SWB_R_SCL")
	)
	(segment
		(start 286.154876 -417.894516)
		(end 286.154876 -418.755576)
		(width 0.11684)
		(layer "In4.Cu")
		(net "I3C_BMC_SWB_R_SCL")
	)
	(segment
		(start 210.39709 -59.42838)
		(end 210.39709 -71.850758)
		(width 0.11684)
		(layer "In4.Cu")
		(net "I3C_BMC_SWB_R_SCL")
	)
	(segment
		(start 211.37118 -45.972984)
		(end 211.37118 -58.45429)
		(width 0.11684)
		(layer "In4.Cu")
		(net "I3C_BMC_SWB_R_SCL")
	)
	(segment
		(start 193.846196 -28.448)
		(end 211.37118 -45.972984)
		(width 0.11684)
		(layer "In4.Cu")
		(net "I3C_BMC_SWB_R_SCL")
	)
	(segment
		(start 189.125352 -19.138646)
		(end 192.969896 -22.98319)
		(width 0.11684)
		(layer "In4.Cu")
		(net "I3C_BMC_SWB_R_SCL")
	)
	(segment
		(start 256.969514 -326.732646)
		(end 256.969514 -328.216514)
		(width 0.11684)
		(layer "In4.Cu")
		(net "I3C_BMC_SWB_R_SCL")
	)
	(segment
		(start 192.969896 -22.98319)
		(end 192.969896 -25.978104)
		(width 0.11684)
		(layer "In4.Cu")
		(net "I3C_BMC_SWB_R_SCL")
	)
	(segment
		(start 186.08421 -15.754096)
		(end 187.024772 -16.694658)
		(width 0.11684)
		(layer "In4.Cu")
		(net "I3C_BMC_SWB_R_SCL")
	)
	(segment
		(start 250.140978 -248.089674)
		(end 259.301742 -257.250438)
		(width 0.11684)
		(layer "In4.Cu")
		(net "I3C_BMC_SWB_R_SCL")
	)
	(segment
		(start 285.572708 -387.542278)
		(end 286.80664 -388.77621)
		(width 0.11684)
		(layer "In4.Cu")
		(net "I3C_BMC_SWB_R_SCL")
	)
	(segment
		(start 288.59226 -423.086784)
		(end 288.59226 -424.789346)
		(width 0.11684)
		(layer "In4.Cu")
		(net "I3C_BMC_SWB_R_SCL")
	)
	(segment
		(start 256.969514 -328.216514)
		(end 259.334 -330.581)
		(width 0.11684)
		(layer "In4.Cu")
		(net "I3C_BMC_SWB_R_SCL")
	)
	(segment
		(start 286.673036 -375.73839)
		(end 284.512512 -377.898914)
		(width 0.11684)
		(layer "In4.Cu")
		(net "I3C_BMC_SWB_R_SCL")
	)
	(segment
		(start 271.077436 -365.79683)
		(end 273.312128 -365.79683)
		(width 0.11684)
		(layer "In4.Cu")
		(net "I3C_BMC_SWB_R_SCL")
	)
	(segment
		(start 259.334 -330.581)
		(end 259.334 -352.950272)
		(width 0.11684)
		(layer "In4.Cu")
		(net "I3C_BMC_SWB_R_SCL")
	)
	(segment
		(start 286.80664 -396.188438)
		(end 285.28391 -397.711168)
		(width 0.11684)
		(layer "In4.Cu")
		(net "I3C_BMC_SWB_R_SCL")
	)
	(segment
		(start 284.225492 -369.408456)
		(end 286.673036 -371.856)
		(width 0.11684)
		(layer "In4.Cu")
		(net "I3C_BMC_SWB_R_SCL")
	)
	(segment
		(start 192.969896 -25.978104)
		(end 192.532 -26.416)
		(width 0.11684)
		(layer "In4.Cu")
		(net "I3C_BMC_SWB_R_SCL")
	)
	(segment
		(start 186.08421 -14.31417)
		(end 186.08421 -15.754096)
		(width 0.11684)
		(layer "In4.Cu")
		(net "I3C_BMC_SWB_R_SCL")
	)
	(segment
		(start 176.888394 -14.249908)
		(end 177.457608 -13.680694)
		(width 0.11684)
		(layer "In4.Cu")
		(net "I3C_BMC_SWB_R_SCL")
	)
	(segment
		(start 177.457608 -13.680694)
		(end 185.450734 -13.680694)
		(width 0.11684)
		(layer "In4.Cu")
		(net "I3C_BMC_SWB_R_SCL")
	)
	(segment
		(start 286.80664 -388.77621)
		(end 286.80664 -396.188438)
		(width 0.11684)
		(layer "In4.Cu")
		(net "I3C_BMC_SWB_R_SCL")
	)
	(segment
		(start 286.554418 -411.521148)
		(end 286.554418 -417.494974)
		(width 0.11684)
		(layer "In4.Cu")
		(net "I3C_BMC_SWB_R_SCL")
	)
	(segment
		(start 286.554418 -421.048942)
		(end 288.59226 -423.086784)
		(width 0.11684)
		(layer "In4.Cu")
		(net "I3C_BMC_SWB_R_SCL")
	)
	(segment
		(start 189.125352 -18.222214)
		(end 189.125352 -19.138646)
		(width 0.11684)
		(layer "In4.Cu")
		(net "I3C_BMC_SWB_R_SCL")
	)
	(segment
		(start 259.301742 -324.400418)
		(end 256.969514 -326.732646)
		(width 0.11684)
		(layer "In4.Cu")
		(net "I3C_BMC_SWB_R_SCL")
	)
	(segment
		(start 193.294 -28.448)
		(end 193.846196 -28.448)
		(width 0.11684)
		(layer "In4.Cu")
		(net "I3C_BMC_SWB_R_SCL")
	)
	(segment
		(start 286.673036 -371.856)
		(end 286.673036 -375.73839)
		(width 0.11684)
		(layer "In4.Cu")
		(net "I3C_BMC_SWB_R_SCL")
	)
	(segment
		(start 284.512512 -380.93523)
		(end 285.572708 -381.995426)
		(width 0.11684)
		(layer "In4.Cu")
		(net "I3C_BMC_SWB_R_SCL")
	)
	(segment
		(start 288.59226 -424.789346)
		(end 287.834324 -425.547282)
		(width 0.11684)
		(layer "In4.Cu")
		(net "I3C_BMC_SWB_R_SCL")
	)
	(segment
		(start 259.334 -352.950272)
		(end 270.322548 -363.93882)
		(width 0.11684)
		(layer "In4.Cu")
		(net "I3C_BMC_SWB_R_SCL")
	)
	(segment
		(start 284.512512 -377.898914)
		(end 284.512512 -380.93523)
		(width 0.11684)
		(layer "In4.Cu")
		(net "I3C_BMC_SWB_R_SCL")
	)
	(segment
		(start 285.28391 -397.711168)
		(end 285.28391 -400.138138)
		(width 0.11684)
		(layer "In4.Cu")
		(net "I3C_BMC_SWB_R_SCL")
	)
	(segment
		(start 213.476078 -82.203544)
		(end 213.476078 -85.183472)
		(width 0.11684)
		(layer "In4.Cu")
		(net "I3C_BMC_SWB_R_SCL")
	)
	(segment
		(start 286.554418 -417.494974)
		(end 286.154876 -417.894516)
		(width 0.11684)
		(layer "In4.Cu")
		(net "I3C_BMC_SWB_R_SCL")
	)
	(segment
		(start 192.532 -27.686)
		(end 193.294 -28.448)
		(width 0.11684)
		(layer "In4.Cu")
		(net "I3C_BMC_SWB_R_SCL")
	)
	(segment
		(start 187.597796 -16.694658)
		(end 189.125352 -18.222214)
		(width 0.11684)
		(layer "In4.Cu")
		(net "I3C_BMC_SWB_R_SCL")
	)
	(segment
		(start 276.923754 -369.408456)
		(end 284.225492 -369.408456)
		(width 0.11684)
		(layer "In4.Cu")
		(net "I3C_BMC_SWB_R_SCL")
	)
	(segment
		(start 212.254084 -73.707752)
		(end 212.254084 -80.98155)
		(width 0.11684)
		(layer "In4.Cu")
		(net "I3C_BMC_SWB_R_SCL")
	)
	(segment
		(start 210.39709 -71.850758)
		(end 212.254084 -73.707752)
		(width 0.11684)
		(layer "In4.Cu")
		(net "I3C_BMC_SWB_R_SCL")
	)
	(segment
		(start 173.575726 -14.771878)
		(end 173.575726 -14.445234)
		(width 0.11684)
		(layer "In4.Cu")
		(net "I3C_BMC_SWB_R_SCL")
	)
	(segment
		(start 192.532 -26.416)
		(end 192.532 -27.686)
		(width 0.11684)
		(layer "In4.Cu")
		(net "I3C_BMC_SWB_R_SCL")
	)
	(segment
		(start 259.301742 -257.250438)
		(end 259.301742 -324.400418)
		(width 0.11684)
		(layer "In4.Cu")
		(net "I3C_BMC_SWB_R_SCL")
	)
	(segment
		(start 273.312128 -365.79683)
		(end 276.923754 -369.408456)
		(width 0.11684)
		(layer "In4.Cu")
		(net "I3C_BMC_SWB_R_SCL")
	)
	(segment
		(start 291.202618 -426.682662)
		(end 292.021514 -426.682662)
		(width 0.10668)
		(layer "F.Cu")
		(net "I3C_BMC_SWB_BUF_R_SDA")
	)
	(segment
		(start 292.021514 -426.682662)
		(end 292.661594 -427.322742)
		(width 0.10668)
		(layer "F.Cu")
		(net "I3C_BMC_SWB_BUF_R_SDA")
	)
	(via
		(at 292.661594 -427.322742)
		(size 0.508)
		(drill 0.254)
		(layers "F.Cu" "B.Cu")
		(net "I3C_BMC_SWB_BUF_R_SDA")
	)
	(segment
		(start 291.578538 -426.46092)
		(end 290.34613 -426.46092)
		(width 0.10668)
		(layer "B.Cu")
		(net "I3C_BMC_SWB_BUF_R_SDA")
	)
	(segment
		(start 290.34613 -426.46092)
		(end 290.34105 -426.466)
		(width 0.10668)
		(layer "B.Cu")
		(net "I3C_BMC_SWB_BUF_R_SDA")
	)
	(segment
		(start 292.608 -426.48505)
		(end 291.602668 -426.48505)
		(width 0.10668)
		(layer "B.Cu")
		(net "I3C_BMC_SWB_BUF_R_SDA")
	)
	(segment
		(start 292.661594 -426.538644)
		(end 292.608 -426.48505)
		(width 0.10668)
		(layer "B.Cu")
		(net "I3C_BMC_SWB_BUF_R_SDA")
	)
	(segment
		(start 291.602668 -426.48505)
		(end 291.578538 -426.46092)
		(width 0.10668)
		(layer "B.Cu")
		(net "I3C_BMC_SWB_BUF_R_SDA")
	)
	(segment
		(start 292.661594 -427.322742)
		(end 292.661594 -426.538644)
		(width 0.10668)
		(layer "B.Cu")
		(net "I3C_BMC_SWB_BUF_R_SDA")
	)
	(segment
		(start 286.737806 -426.682662)
		(end 285.619698 -426.682662)
		(width 0.10668)
		(layer "F.Cu")
		(net "I3C_BMC_SWB_BUF_R_SCL")
	)
	(segment
		(start 285.619698 -426.682662)
		(end 285.14294 -426.205904)
		(width 0.10668)
		(layer "F.Cu")
		(net "I3C_BMC_SWB_BUF_R_SCL")
	)
	(via
		(at 285.14294 -426.205904)
		(size 0.508)
		(drill 0.254)
		(layers "F.Cu" "B.Cu")
		(net "I3C_BMC_SWB_BUF_R_SCL")
	)
	(segment
		(start 286.004 -426.35805)
		(end 285.295086 -426.35805)
		(width 0.10668)
		(layer "B.Cu")
		(net "I3C_BMC_SWB_BUF_R_SCL")
	)
	(segment
		(start 287.00095 -426.466)
		(end 286.893 -426.35805)
		(width 0.10668)
		(layer "B.Cu")
		(net "I3C_BMC_SWB_BUF_R_SCL")
	)
	(segment
		(start 286.004 -426.35805)
		(end 286.893 -426.35805)
		(width 0.10668)
		(layer "B.Cu")
		(net "I3C_BMC_SWB_BUF_R_SCL")
	)
	(segment
		(start 287.88995 -426.466)
		(end 287.00095 -426.466)
		(width 0.10668)
		(layer "B.Cu")
		(net "I3C_BMC_SWB_BUF_R_SCL")
	)
	(segment
		(start 285.295086 -426.35805)
		(end 285.14294 -426.205904)
		(width 0.10668)
		(layer "B.Cu")
		(net "I3C_BMC_SWB_BUF_R_SCL")
	)
	(segment
		(start 152.448768 -35.976052)
		(end 152.449276 -35.97656)
		(width 0.10668)
		(layer "F.Cu")
		(net "HP_LVC3_OCP_V3_2_R_EN")
	)
	(segment
		(start 151.230076 -37.241734)
		(end 150.568406 -37.903404)
		(width 0.10668)
		(layer "F.Cu")
		(net "HP_LVC3_OCP_V3_2_R_EN")
	)
	(segment
		(start 151.230076 -36.73856)
		(end 151.230076 -37.241734)
		(width 0.10668)
		(layer "F.Cu")
		(net "HP_LVC3_OCP_V3_2_R_EN")
	)
	(segment
		(start 152.44953 -34.64687)
		(end 152.448768 -34.647632)
		(width 0.10668)
		(layer "F.Cu")
		(net "HP_LVC3_OCP_V3_2_R_EN")
	)
	(segment
		(start 152.448768 -34.647632)
		(end 152.448768 -35.976052)
		(width 0.10668)
		(layer "F.Cu")
		(net "HP_LVC3_OCP_V3_2_R_EN")
	)
	(segment
		(start 151.230076 -36.73856)
		(end 151.992076 -35.97656)
		(width 0.10668)
		(layer "F.Cu")
		(net "HP_LVC3_OCP_V3_2_R_EN")
	)
	(segment
		(start 152.44953 -33.59658)
		(end 152.44953 -34.64687)
		(width 0.10668)
		(layer "F.Cu")
		(net "HP_LVC3_OCP_V3_2_R_EN")
	)
	(segment
		(start 151.992076 -35.97656)
		(end 152.449276 -35.97656)
		(width 0.10668)
		(layer "F.Cu")
		(net "HP_LVC3_OCP_V3_2_R_EN")
	)
	(segment
		(start 150.568406 -37.903404)
		(end 149.713442 -37.903404)
		(width 0.10668)
		(layer "F.Cu")
		(net "HP_LVC3_OCP_V3_2_R_EN")
	)
	(via
		(at 151.230076 -36.73856)
		(size 0.762)
		(drill 0.381)
		(layers "F.Cu" "B.Cu")
		(net "HP_LVC3_OCP_V3_2_R_EN")
	)
	(segment
		(start 412.081218 -71.812912)
		(end 412.081218 -72.824086)
		(width 0.10668)
		(layer "F.Cu")
		(net "HP_LVC3_OCP_V3_1_R_EN")
	)
	(segment
		(start 412.072836 -72.832468)
		(end 411.615636 -72.832468)
		(width 0.10668)
		(layer "F.Cu")
		(net "HP_LVC3_OCP_V3_1_R_EN")
	)
	(segment
		(start 412.081218 -72.824086)
		(end 412.072836 -72.832468)
		(width 0.10668)
		(layer "F.Cu")
		(net "HP_LVC3_OCP_V3_1_R_EN")
	)
	(segment
		(start 412.081218 -70.74408)
		(end 412.081218 -71.812912)
		(width 0.10668)
		(layer "F.Cu")
		(net "HP_LVC3_OCP_V3_1_R_EN")
	)
	(segment
		(start 411.615636 -72.832468)
		(end 410.853636 -73.594468)
		(width 0.10668)
		(layer "F.Cu")
		(net "HP_LVC3_OCP_V3_1_R_EN")
	)
	(segment
		(start 410.853636 -73.594468)
		(end 410.853636 -74.23531)
		(width 0.10668)
		(layer "F.Cu")
		(net "HP_LVC3_OCP_V3_1_R_EN")
	)
	(segment
		(start 410.075634 -75.013312)
		(end 409.362402 -75.013312)
		(width 0.10668)
		(layer "F.Cu")
		(net "HP_LVC3_OCP_V3_1_R_EN")
	)
	(segment
		(start 410.853636 -74.23531)
		(end 410.075634 -75.013312)
		(width 0.10668)
		(layer "F.Cu")
		(net "HP_LVC3_OCP_V3_1_R_EN")
	)
	(via
		(at 410.853636 -73.594468)
		(size 0.762)
		(drill 0.381)
		(layers "F.Cu" "B.Cu")
		(net "HP_LVC3_OCP_V3_1_R_EN")
	)
	(segment
		(start 144.147032 -10.63498)
		(end 143.959834 -10.447782)
		(width 0.10668)
		(layer "F.Cu")
		(net "RST_MB_STBY_R_N")
	)
	(segment
		(start 144.147032 -13.599922)
		(end 144.147032 -10.63498)
		(width 0.10668)
		(layer "F.Cu")
		(net "RST_MB_STBY_R_N")
	)
	(via
		(at 143.959834 -10.447782)
		(size 0.508)
		(drill 0.254)
		(layers "F.Cu" "B.Cu")
		(net "RST_MB_STBY_R_N")
	)
	(segment
		(start 144.187672 -11.18616)
		(end 143.959834 -10.958322)
		(width 0.10668)
		(layer "B.Cu")
		(net "RST_MB_STBY_R_N")
	)
	(segment
		(start 143.959834 -10.958322)
		(end 143.959834 -10.447782)
		(width 0.10668)
		(layer "B.Cu")
		(net "RST_MB_STBY_R_N")
	)
	(segment
		(start 144.3228 -13.364972)
		(end 144.187672 -13.229844)
		(width 0.10668)
		(layer "B.Cu")
		(net "RST_MB_STBY_R_N")
	)
	(segment
		(start 144.187672 -13.229844)
		(end 144.187672 -11.18616)
		(width 0.10668)
		(layer "B.Cu")
		(net "RST_MB_STBY_R_N")
	)
	(segment
		(start 184.310528 -426.00499)
		(end 184.310528 -425.534836)
		(width 0.10668)
		(layer "F.Cu")
		(net "GPU_PEX_STRAP1_R")
	)
	(segment
		(start 184.310528 -425.534836)
		(end 184.244234 -425.468542)
		(width 0.10668)
		(layer "F.Cu")
		(net "GPU_PEX_STRAP1_R")
	)
	(segment
		(start 184.244234 -425.468542)
		(end 184.244234 -425.00042)
		(width 0.10668)
		(layer "F.Cu")
		(net "GPU_PEX_STRAP1_R")
	)
	(segment
		(start 184.662318 -424.582336)
		(end 184.244234 -425.00042)
		(width 0.10668)
		(layer "F.Cu")
		(net "GPU_PEX_STRAP1_R")
	)
	(segment
		(start 184.662318 -423.254932)
		(end 184.662318 -424.582336)
		(width 0.10668)
		(layer "F.Cu")
		(net "GPU_PEX_STRAP1_R")
	)
	(via
		(at 184.244234 -425.00042)
		(size 0.762)
		(drill 0.381)
		(layers "F.Cu" "B.Cu")
		(net "GPU_PEX_STRAP1_R")
	)
	(segment
		(start 185.312304 -424.66387)
		(end 185.312304 -423.254932)
		(width 0.10668)
		(layer "F.Cu")
		(net "GPU_PEX_STRAP0_R")
	)
	(segment
		(start 185.570368 -424.921934)
		(end 185.312304 -424.66387)
		(width 0.10668)
		(layer "F.Cu")
		(net "GPU_PEX_STRAP0_R")
	)
	(segment
		(start 185.570368 -425.75734)
		(end 185.570368 -424.921934)
		(width 0.10668)
		(layer "F.Cu")
		(net "GPU_PEX_STRAP0_R")
	)
	(segment
		(start 185.322464 -426.005244)
		(end 185.570368 -425.75734)
		(width 0.10668)
		(layer "F.Cu")
		(net "GPU_PEX_STRAP0_R")
	)
	(via
		(at 185.570368 -424.921934)
		(size 0.762)
		(drill 0.381)
		(layers "F.Cu" "B.Cu")
		(net "GPU_PEX_STRAP0_R")
	)
	(segment
		(start 33.225994 -133.188964)
		(end 34.098992 -133.188964)
		(width 0.10668)
		(layer "F.Cu")
		(net "GPU_FPGA_READY_R_N")
	)
	(segment
		(start 34.098992 -133.188964)
		(end 34.700718 -132.587238)
		(width 0.10668)
		(layer "F.Cu")
		(net "GPU_FPGA_READY_R_N")
	)
	(segment
		(start 34.700718 -132.587238)
		(end 35.919918 -132.587238)
		(width 0.10668)
		(layer "F.Cu")
		(net "GPU_FPGA_READY_R_N")
	)
	(via
		(at 34.700718 -132.587238)
		(size 0.762)
		(drill 0.381)
		(layers "F.Cu" "B.Cu")
		(net "GPU_FPGA_READY_R_N")
	)
	(segment
		(start 185.96229 -424.13047)
		(end 185.96229 -423.254932)
		(width 0.10668)
		(layer "F.Cu")
		(net "GPU_BASE_ID1_R")
	)
	(segment
		(start 187.316618 -426.789596)
		(end 186.440318 -425.913296)
		(width 0.10668)
		(layer "F.Cu")
		(net "GPU_BASE_ID1_R")
	)
	(segment
		(start 186.440318 -425.913296)
		(end 186.440318 -424.608498)
		(width 0.10668)
		(layer "F.Cu")
		(net "GPU_BASE_ID1_R")
	)
	(segment
		(start 186.440318 -424.608498)
		(end 185.96229 -424.13047)
		(width 0.10668)
		(layer "F.Cu")
		(net "GPU_BASE_ID1_R")
	)
	(segment
		(start 187.316618 -426.855128)
		(end 187.316618 -426.789596)
		(width 0.10668)
		(layer "F.Cu")
		(net "GPU_BASE_ID1_R")
	)
	(via
		(at 186.440318 -425.913296)
		(size 0.762)
		(drill 0.381)
		(layers "F.Cu" "B.Cu")
		(net "GPU_BASE_ID1_R")
	)
	(segment
		(start 186.612276 -423.254932)
		(end 186.612276 -424.32224)
		(width 0.10668)
		(layer "F.Cu")
		(net "GPU_BASE_ID0_R")
	)
	(segment
		(start 187.939426 -425.64939)
		(end 187.992766 -425.64939)
		(width 0.10668)
		(layer "F.Cu")
		(net "GPU_BASE_ID0_R")
	)
	(segment
		(start 186.612276 -424.32224)
		(end 187.585604 -425.295568)
		(width 0.10668)
		(layer "F.Cu")
		(net "GPU_BASE_ID0_R")
	)
	(segment
		(start 187.992766 -425.64939)
		(end 188.296804 -425.953428)
		(width 0.10668)
		(layer "F.Cu")
		(net "GPU_BASE_ID0_R")
	)
	(segment
		(start 187.585604 -425.295568)
		(end 187.939426 -425.64939)
		(width 0.10668)
		(layer "F.Cu")
		(net "GPU_BASE_ID0_R")
	)
	(via
		(at 187.585604 -425.295568)
		(size 0.762)
		(drill 0.381)
		(layers "F.Cu" "B.Cu")
		(net "GPU_BASE_ID0_R")
	)
	(segment
		(start 12.79652 -135.91413)
		(end 12.79652 -137.334244)
		(width 0.10668)
		(layer "F.Cu")
		(net "FG_SS_EN")
	)
	(segment
		(start 13.537946 -138.86688)
		(end 12.359894 -138.86688)
		(width 0.10668)
		(layer "F.Cu")
		(net "FG_SS_EN")
	)
	(segment
		(start 12.455906 -137.908792)
		(end 12.455906 -137.674858)
		(width 0.10668)
		(layer "F.Cu")
		(net "FG_SS_EN")
	)
	(segment
		(start 12.359894 -138.86688)
		(end 12.351004 -138.85799)
		(width 0.10668)
		(layer "F.Cu")
		(net "FG_SS_EN")
	)
	(segment
		(start 12.351004 -138.85799)
		(end 12.351004 -138.013694)
		(width 0.10668)
		(layer "F.Cu")
		(net "FG_SS_EN")
	)
	(segment
		(start 12.351004 -138.013694)
		(end 12.455906 -137.908792)
		(width 0.10668)
		(layer "F.Cu")
		(net "FG_SS_EN")
	)
	(segment
		(start 12.79652 -137.334244)
		(end 12.455906 -137.674858)
		(width 0.10668)
		(layer "F.Cu")
		(net "FG_SS_EN")
	)
	(via
		(at 12.455906 -137.674858)
		(size 0.762)
		(drill 0.381)
		(layers "F.Cu" "B.Cu")
		(net "FG_SS_EN")
	)
	(segment
		(start 10.151618 -134.609078)
		(end 10.151618 -133.784086)
		(width 0.10668)
		(layer "F.Cu")
		(net "CLK_GEN2_XTAL_OUT")
	)
	(segment
		(start 8.30072 -134.328154)
		(end 8.324596 -134.35203)
		(width 0.10668)
		(layer "F.Cu")
		(net "CLK_GEN2_XTAL_OUT")
	)
	(segment
		(start 11.599418 -134.8613)
		(end 10.40384 -134.8613)
		(width 0.10668)
		(layer "F.Cu")
		(net "CLK_GEN2_XTAL_OUT")
	)
	(segment
		(start 9.033764 -133.354318)
		(end 9.291574 -133.354318)
		(width 0.10668)
		(layer "F.Cu")
		(net "CLK_GEN2_XTAL_OUT")
	)
	(segment
		(start 9.291574 -133.354318)
		(end 9.72185 -133.354318)
		(width 0.10668)
		(layer "F.Cu")
		(net "CLK_GEN2_XTAL_OUT")
	)
	(segment
		(start 6.86943 -134.328154)
		(end 8.30072 -134.328154)
		(width 0.10668)
		(layer "F.Cu")
		(net "CLK_GEN2_XTAL_OUT")
	)
	(segment
		(start 8.880348 -133.796278)
		(end 8.880348 -133.507734)
		(width 0.10668)
		(layer "F.Cu")
		(net "CLK_GEN2_XTAL_OUT")
	)
	(segment
		(start 11.671554 -134.789164)
		(end 11.599418 -134.8613)
		(width 0.10668)
		(layer "F.Cu")
		(net "CLK_GEN2_XTAL_OUT")
	)
	(segment
		(start 6.829298 -134.288022)
		(end 6.86943 -134.328154)
		(width 0.10668)
		(layer "F.Cu")
		(net "CLK_GEN2_XTAL_OUT")
	)
	(segment
		(start 8.324596 -134.35203)
		(end 8.880348 -133.796278)
		(width 0.10668)
		(layer "F.Cu")
		(net "CLK_GEN2_XTAL_OUT")
	)
	(segment
		(start 9.72185 -133.354318)
		(end 10.151618 -133.784086)
		(width 0.10668)
		(layer "F.Cu")
		(net "CLK_GEN2_XTAL_OUT")
	)
	(segment
		(start 10.40384 -134.8613)
		(end 10.151618 -134.609078)
		(width 0.10668)
		(layer "F.Cu")
		(net "CLK_GEN2_XTAL_OUT")
	)
	(segment
		(start 8.880348 -133.507734)
		(end 9.033764 -133.354318)
		(width 0.10668)
		(layer "F.Cu")
		(net "CLK_GEN2_XTAL_OUT")
	)
	(via
		(at 10.151618 -133.784086)
		(size 0.508)
		(drill 0.254)
		(layers "F.Cu" "B.Cu")
		(net "CLK_GEN2_XTAL_OUT")
	)
	(segment
		(start 6.090158 -135.4963)
		(end 7.662418 -135.4963)
		(width 0.10668)
		(layer "F.Cu")
		(net "CLK_GEN2_XTAL_IN_R")
	)
	(segment
		(start 5.229098 -136.35736)
		(end 6.090158 -135.4963)
		(width 0.10668)
		(layer "F.Cu")
		(net "CLK_GEN2_XTAL_IN_R")
	)
	(segment
		(start 9.167368 -134.92988)
		(end 8.343138 -135.75411)
		(width 0.10668)
		(layer "F.Cu")
		(net "CLK_GEN2_XTAL_IN_R")
	)
	(segment
		(start 7.662418 -135.4963)
		(end 7.762748 -135.39597)
		(width 0.10668)
		(layer "F.Cu")
		(net "CLK_GEN2_XTAL_IN_R")
	)
	(segment
		(start 9.238488 -134.92988)
		(end 9.167368 -134.92988)
		(width 0.10668)
		(layer "F.Cu")
		(net "CLK_GEN2_XTAL_IN_R")
	)
	(segment
		(start 5.229098 -136.48817)
		(end 5.229098 -136.35736)
		(width 0.10668)
		(layer "F.Cu")
		(net "CLK_GEN2_XTAL_IN_R")
	)
	(segment
		(start 8.343138 -135.75411)
		(end 8.120888 -135.75411)
		(width 0.10668)
		(layer "F.Cu")
		(net "CLK_GEN2_XTAL_IN_R")
	)
	(segment
		(start 8.120888 -135.75411)
		(end 7.762748 -135.39597)
		(width 0.10668)
		(layer "F.Cu")
		(net "CLK_GEN2_XTAL_IN_R")
	)
	(via
		(at 7.762748 -135.39597)
		(size 0.508)
		(drill 0.254)
		(layers "F.Cu" "B.Cu")
		(net "CLK_GEN2_XTAL_IN_R")
	)
	(segment
		(start 11.154156 -135.66267)
		(end 10.41654 -135.66267)
		(width 0.10668)
		(layer "F.Cu")
		(net "CLK_GEN2_XTAL_IN")
	)
	(segment
		(start 11.671554 -135.289036)
		(end 11.52779 -135.289036)
		(width 0.10668)
		(layer "F.Cu")
		(net "CLK_GEN2_XTAL_IN")
	)
	(segment
		(start 9.305798 -135.66267)
		(end 9.238488 -135.72998)
		(width 0.10668)
		(layer "F.Cu")
		(net "CLK_GEN2_XTAL_IN")
	)
	(segment
		(start 10.41654 -135.66267)
		(end 9.305798 -135.66267)
		(width 0.10668)
		(layer "F.Cu")
		(net "CLK_GEN2_XTAL_IN")
	)
	(segment
		(start 11.52779 -135.289036)
		(end 11.154156 -135.66267)
		(width 0.10668)
		(layer "F.Cu")
		(net "CLK_GEN2_XTAL_IN")
	)
	(via
		(at 10.41654 -135.66267)
		(size 0.762)
		(drill 0.381)
		(layers "F.Cu" "B.Cu")
		(net "CLK_GEN2_XTAL_IN")
	)
	(segment
		(start 8.078978 -131.97967)
		(end 6.238494 -131.97967)
		(width 0.10668)
		(layer "F.Cu")
		(net "CLK_GEN2_SMB_SADR")
	)
	(segment
		(start 6.238494 -131.97967)
		(end 5.564378 -131.305554)
		(width 0.10668)
		(layer "F.Cu")
		(net "CLK_GEN2_SMB_SADR")
	)
	(segment
		(start 9.468104 -132.058156)
		(end 9.947402 -132.058156)
		(width 0.10668)
		(layer "F.Cu")
		(net "CLK_GEN2_SMB_SADR")
	)
	(segment
		(start 8.734298 -131.32435)
		(end 9.468104 -132.058156)
		(width 0.10668)
		(layer "F.Cu")
		(net "CLK_GEN2_SMB_SADR")
	)
	(segment
		(start 9.947402 -132.446522)
		(end 9.947402 -132.058156)
		(width 0.10668)
		(layer "F.Cu")
		(net "CLK_GEN2_SMB_SADR")
	)
	(segment
		(start 11.290046 -133.789166)
		(end 9.947402 -132.446522)
		(width 0.10668)
		(layer "F.Cu")
		(net "CLK_GEN2_SMB_SADR")
	)
	(segment
		(start 11.671554 -133.789166)
		(end 11.290046 -133.789166)
		(width 0.10668)
		(layer "F.Cu")
		(net "CLK_GEN2_SMB_SADR")
	)
	(segment
		(start 8.734298 -131.32435)
		(end 8.078978 -131.97967)
		(width 0.10668)
		(layer "F.Cu")
		(net "CLK_GEN2_SMB_SADR")
	)
	(via
		(at 9.947402 -132.058156)
		(size 0.762)
		(drill 0.381)
		(layers "F.Cu" "B.Cu")
		(net "CLK_GEN2_SMB_SADR")
	)
	(segment
		(start 14.796516 -135.91413)
		(end 14.796516 -137.259568)
		(width 0.10668)
		(layer "F.Cu")
		(net "CLK_GEN2_GPU_OE_N")
	)
	(segment
		(start 15.201646 -138.020044)
		(end 15.201646 -137.664698)
		(width 0.10668)
		(layer "F.Cu")
		(net "CLK_GEN2_GPU_OE_N")
	)
	(segment
		(start 16.039592 -138.85799)
		(end 15.201646 -138.020044)
		(width 0.10668)
		(layer "F.Cu")
		(net "CLK_GEN2_GPU_OE_N")
	)
	(segment
		(start 14.796516 -137.259568)
		(end 15.201646 -137.664698)
		(width 0.10668)
		(layer "F.Cu")
		(net "CLK_GEN2_GPU_OE_N")
	)
	(via
		(at 15.201646 -137.664698)
		(size 0.762)
		(drill 0.381)
		(layers "F.Cu" "B.Cu")
		(net "CLK_GEN2_GPU_OE_N")
	)
	(segment
		(start 171.59605 -122.646948)
		(end 172.212 -122.646948)
		(width 0.10668)
		(layer "F.Cu")
		(net "CLK_GEN2_GPU_FPGA_OE_R_N")
	)
	(segment
		(start 178.72202 -121.852944)
		(end 178.33213 -122.242834)
		(width 0.10668)
		(layer "F.Cu")
		(net "CLK_GEN2_GPU_FPGA_OE_R_N")
	)
	(via
		(at 172.212 -122.646948)
		(size 0.508)
		(drill 0.254)
		(layers "F.Cu" "B.Cu")
		(net "CLK_GEN2_GPU_FPGA_OE_R_N")
	)
	(via
		(at 178.33213 -122.242834)
		(size 0.4572)
		(drill 0.254)
		(layers "F.Cu" "B.Cu")
		(net "CLK_GEN2_GPU_FPGA_OE_R_N")
	)
	(segment
		(start 178.33213 -122.483626)
		(end 178.178968 -122.636788)
		(width 0.11684)
		(layer "In2.Cu")
		(net "CLK_GEN2_GPU_FPGA_OE_R_N")
	)
	(segment
		(start 172.65142 -122.646948)
		(end 172.212 -122.646948)
		(width 0.11684)
		(layer "In2.Cu")
		(net "CLK_GEN2_GPU_FPGA_OE_R_N")
	)
	(segment
		(start 172.87748 -122.873008)
		(end 172.65142 -122.646948)
		(width 0.11684)
		(layer "In2.Cu")
		(net "CLK_GEN2_GPU_FPGA_OE_R_N")
	)
	(segment
		(start 176.06264 -122.636788)
		(end 175.82642 -122.873008)
		(width 0.11684)
		(layer "In2.Cu")
		(net "CLK_GEN2_GPU_FPGA_OE_R_N")
	)
	(segment
		(start 175.82642 -122.873008)
		(end 172.87748 -122.873008)
		(width 0.11684)
		(layer "In2.Cu")
		(net "CLK_GEN2_GPU_FPGA_OE_R_N")
	)
	(segment
		(start 178.33213 -122.242834)
		(end 178.33213 -122.483626)
		(width 0.11684)
		(layer "In2.Cu")
		(net "CLK_GEN2_GPU_FPGA_OE_R_N")
	)
	(segment
		(start 178.178968 -122.636788)
		(end 176.06264 -122.636788)
		(width 0.11684)
		(layer "In2.Cu")
		(net "CLK_GEN2_GPU_FPGA_OE_R_N")
	)
	(segment
		(start 34.68243 -133.83895)
		(end 34.700718 -133.857238)
		(width 0.10668)
		(layer "F.Cu")
		(net "CLK_GEN2_GPU_FPGA_OE_R2_N")
	)
	(segment
		(start 35.919918 -135.889238)
		(end 35.919918 -134.873238)
		(width 0.10668)
		(layer "F.Cu")
		(net "CLK_GEN2_GPU_FPGA_OE_R2_N")
	)
	(segment
		(start 35.919918 -134.873238)
		(end 35.919918 -133.857238)
		(width 0.10668)
		(layer "F.Cu")
		(net "CLK_GEN2_GPU_FPGA_OE_R2_N")
	)
	(segment
		(start 33.225994 -133.83895)
		(end 34.68243 -133.83895)
		(width 0.10668)
		(layer "F.Cu")
		(net "CLK_GEN2_GPU_FPGA_OE_R2_N")
	)
	(segment
		(start 34.700718 -133.857238)
		(end 35.919918 -133.857238)
		(width 0.10668)
		(layer "F.Cu")
		(net "CLK_GEN2_GPU_FPGA_OE_R2_N")
	)
	(via
		(at 34.700718 -133.857238)
		(size 0.762)
		(drill 0.381)
		(layers "F.Cu" "B.Cu")
		(net "CLK_GEN2_GPU_FPGA_OE_R2_N")
	)
	(segment
		(start 58.340498 -132.703062)
		(end 55.84444 -135.19912)
		(width 0.10668)
		(layer "F.Cu")
		(net "CLK_GEN2_GPU_FPGA_OE_N")
	)
	(segment
		(start 55.84444 -135.19912)
		(end 38.483032 -135.19912)
		(width 0.10668)
		(layer "F.Cu")
		(net "CLK_GEN2_GPU_FPGA_OE_N")
	)
	(segment
		(start 37.792914 -135.889238)
		(end 36.720018 -135.889238)
		(width 0.10668)
		(layer "F.Cu")
		(net "CLK_GEN2_GPU_FPGA_OE_N")
	)
	(segment
		(start 38.483032 -135.19912)
		(end 37.792914 -135.889238)
		(width 0.10668)
		(layer "F.Cu")
		(net "CLK_GEN2_GPU_FPGA_OE_N")
	)
	(segment
		(start 170.79595 -122.646948)
		(end 170.18 -122.646948)
		(width 0.10668)
		(layer "F.Cu")
		(net "CLK_GEN2_GPU_FPGA_OE_N")
	)
	(via
		(at 58.340498 -132.703062)
		(size 0.508)
		(drill 0.254)
		(layers "F.Cu" "B.Cu")
		(net "CLK_GEN2_GPU_FPGA_OE_N")
	)
	(via
		(at 170.18 -122.646948)
		(size 0.508)
		(drill 0.254)
		(layers "F.Cu" "B.Cu")
		(net "CLK_GEN2_GPU_FPGA_OE_N")
	)
	(segment
		(start 167.231822 -123.03379)
		(end 166.678102 -123.03379)
		(width 0.10668)
		(layer "B.Cu")
		(net "CLK_GEN2_GPU_FPGA_OE_N")
	)
	(segment
		(start 65.472564 -123.403614)
		(end 58.340498 -130.53568)
		(width 0.10668)
		(layer "B.Cu")
		(net "CLK_GEN2_GPU_FPGA_OE_N")
	)
	(segment
		(start 132.329936 -123.403614)
		(end 65.472564 -123.403614)
		(width 0.10668)
		(layer "B.Cu")
		(net "CLK_GEN2_GPU_FPGA_OE_N")
	)
	(segment
		(start 167.777414 -123.579382)
		(end 167.231822 -123.03379)
		(width 0.10668)
		(layer "B.Cu")
		(net "CLK_GEN2_GPU_FPGA_OE_N")
	)
	(segment
		(start 170.18 -122.646948)
		(end 169.247566 -123.579382)
		(width 0.10668)
		(layer "B.Cu")
		(net "CLK_GEN2_GPU_FPGA_OE_N")
	)
	(segment
		(start 136.155684 -119.577866)
		(end 132.329936 -123.403614)
		(width 0.10668)
		(layer "B.Cu")
		(net "CLK_GEN2_GPU_FPGA_OE_N")
	)
	(segment
		(start 143.29283 -119.577866)
		(end 136.155684 -119.577866)
		(width 0.10668)
		(layer "B.Cu")
		(net "CLK_GEN2_GPU_FPGA_OE_N")
	)
	(segment
		(start 166.678102 -123.03379)
		(end 165.678612 -124.03328)
		(width 0.10668)
		(layer "B.Cu")
		(net "CLK_GEN2_GPU_FPGA_OE_N")
	)
	(segment
		(start 155.650438 -126.991872)
		(end 150.706836 -126.991872)
		(width 0.10668)
		(layer "B.Cu")
		(net "CLK_GEN2_GPU_FPGA_OE_N")
	)
	(segment
		(start 58.340498 -130.53568)
		(end 58.340498 -132.703062)
		(width 0.10668)
		(layer "B.Cu")
		(net "CLK_GEN2_GPU_FPGA_OE_N")
	)
	(segment
		(start 158.60903 -124.03328)
		(end 155.650438 -126.991872)
		(width 0.10668)
		(layer "B.Cu")
		(net "CLK_GEN2_GPU_FPGA_OE_N")
	)
	(segment
		(start 150.706836 -126.991872)
		(end 143.29283 -119.577866)
		(width 0.10668)
		(layer "B.Cu")
		(net "CLK_GEN2_GPU_FPGA_OE_N")
	)
	(segment
		(start 165.678612 -124.03328)
		(end 158.60903 -124.03328)
		(width 0.10668)
		(layer "B.Cu")
		(net "CLK_GEN2_GPU_FPGA_OE_N")
	)
	(segment
		(start 169.247566 -123.579382)
		(end 167.777414 -123.579382)
		(width 0.10668)
		(layer "B.Cu")
		(net "CLK_GEN2_GPU_FPGA_OE_N")
	)
	(segment
		(start 178.72202 -121.052844)
		(end 178.33213 -121.442734)
		(width 0.10668)
		(layer "F.Cu")
		(net "CLK_GEN2_BMC_RC_OE_R_N")
	)
	(segment
		(start 171.59605 -121.376948)
		(end 172.212 -121.376948)
		(width 0.10668)
		(layer "F.Cu")
		(net "CLK_GEN2_BMC_RC_OE_R_N")
	)
	(via
		(at 178.33213 -121.442734)
		(size 0.4572)
		(drill 0.254)
		(layers "F.Cu" "B.Cu")
		(net "CLK_GEN2_BMC_RC_OE_R_N")
	)
	(via
		(at 172.212 -121.376948)
		(size 0.508)
		(drill 0.254)
		(layers "F.Cu" "B.Cu")
		(net "CLK_GEN2_BMC_RC_OE_R_N")
	)
	(segment
		(start 172.6819 -121.846848)
		(end 172.212 -121.376948)
		(width 0.11684)
		(layer "In2.Cu")
		(net "CLK_GEN2_BMC_RC_OE_R_N")
	)
	(segment
		(start 177.928016 -121.846848)
		(end 172.6819 -121.846848)
		(width 0.11684)
		(layer "In2.Cu")
		(net "CLK_GEN2_BMC_RC_OE_R_N")
	)
	(segment
		(start 178.33213 -121.442734)
		(end 177.928016 -121.846848)
		(width 0.11684)
		(layer "In2.Cu")
		(net "CLK_GEN2_BMC_RC_OE_R_N")
	)
	(segment
		(start 14.834108 -129.366264)
		(end 14.834108 -128.94564)
		(width 0.10668)
		(layer "F.Cu")
		(net "CLK_GEN2_BMC_RC_OE_R3_N")
	)
	(segment
		(start 14.796516 -130.80365)
		(end 14.796516 -129.403856)
		(width 0.10668)
		(layer "F.Cu")
		(net "CLK_GEN2_BMC_RC_OE_R3_N")
	)
	(segment
		(start 14.796516 -132.164074)
		(end 14.796516 -130.80365)
		(width 0.10668)
		(layer "F.Cu")
		(net "CLK_GEN2_BMC_RC_OE_R3_N")
	)
	(segment
		(start 14.796516 -129.403856)
		(end 14.834108 -129.366264)
		(width 0.10668)
		(layer "F.Cu")
		(net "CLK_GEN2_BMC_RC_OE_R3_N")
	)
	(via
		(at 14.796516 -130.80365)
		(size 0.762)
		(drill 0.381)
		(layers "F.Cu" "B.Cu")
		(net "CLK_GEN2_BMC_RC_OE_R3_N")
	)
	(segment
		(start 16.368268 -128.11506)
		(end 15.626588 -128.11506)
		(width 0.10668)
		(layer "F.Cu")
		(net "CLK_GEN2_BMC_RC_OE_N")
	)
	(segment
		(start 170.79595 -121.376948)
		(end 170.18 -121.376948)
		(width 0.10668)
		(layer "F.Cu")
		(net "CLK_GEN2_BMC_RC_OE_N")
	)
	(segment
		(start 54.1909 -130.712464)
		(end 55.292498 -131.814062)
		(width 0.10668)
		(layer "F.Cu")
		(net "CLK_GEN2_BMC_RC_OE_N")
	)
	(segment
		(start 30.899608 -130.712464)
		(end 54.1909 -130.712464)
		(width 0.10668)
		(layer "F.Cu")
		(net "CLK_GEN2_BMC_RC_OE_N")
	)
	(segment
		(start 28.302204 -128.11506)
		(end 30.899608 -130.712464)
		(width 0.10668)
		(layer "F.Cu")
		(net "CLK_GEN2_BMC_RC_OE_N")
	)
	(segment
		(start 15.626588 -128.11506)
		(end 15.596108 -128.14554)
		(width 0.10668)
		(layer "F.Cu")
		(net "CLK_GEN2_BMC_RC_OE_N")
	)
	(segment
		(start 55.292498 -131.814062)
		(end 55.292498 -132.703062)
		(width 0.10668)
		(layer "F.Cu")
		(net "CLK_GEN2_BMC_RC_OE_N")
	)
	(segment
		(start 16.368268 -128.11506)
		(end 28.302204 -128.11506)
		(width 0.10668)
		(layer "F.Cu")
		(net "CLK_GEN2_BMC_RC_OE_N")
	)
	(segment
		(start 15.596108 -128.14554)
		(end 14.834108 -128.14554)
		(width 0.10668)
		(layer "F.Cu")
		(net "CLK_GEN2_BMC_RC_OE_N")
	)
	(via
		(at 55.292498 -132.703062)
		(size 0.508)
		(drill 0.254)
		(layers "F.Cu" "B.Cu")
		(net "CLK_GEN2_BMC_RC_OE_N")
	)
	(via
		(at 170.18 -121.376948)
		(size 0.508)
		(drill 0.254)
		(layers "F.Cu" "B.Cu")
		(net "CLK_GEN2_BMC_RC_OE_N")
	)
	(segment
		(start 144.029176 -119.040148)
		(end 135.419338 -119.040148)
		(width 0.10668)
		(layer "B.Cu")
		(net "CLK_GEN2_BMC_RC_OE_N")
	)
	(segment
		(start 152.57526 -124.024898)
		(end 149.013926 -124.024898)
		(width 0.10668)
		(layer "B.Cu")
		(net "CLK_GEN2_BMC_RC_OE_N")
	)
	(segment
		(start 153.120344 -123.479814)
		(end 152.57526 -124.024898)
		(width 0.10668)
		(layer "B.Cu")
		(net "CLK_GEN2_BMC_RC_OE_N")
	)
	(segment
		(start 110.74781 -121.757948)
		(end 110.002828 -122.50293)
		(width 0.10668)
		(layer "B.Cu")
		(net "CLK_GEN2_BMC_RC_OE_N")
	)
	(segment
		(start 65.099184 -122.50293)
		(end 55.292498 -132.309616)
		(width 0.10668)
		(layer "B.Cu")
		(net "CLK_GEN2_BMC_RC_OE_N")
	)
	(segment
		(start 157.888432 -123.479814)
		(end 153.120344 -123.479814)
		(width 0.10668)
		(layer "B.Cu")
		(net "CLK_GEN2_BMC_RC_OE_N")
	)
	(segment
		(start 165.75278 -123.132596)
		(end 158.23565 -123.132596)
		(width 0.10668)
		(layer "B.Cu")
		(net "CLK_GEN2_BMC_RC_OE_N")
	)
	(segment
		(start 112.374934 -121.757948)
		(end 110.74781 -121.757948)
		(width 0.10668)
		(layer "B.Cu")
		(net "CLK_GEN2_BMC_RC_OE_N")
	)
	(segment
		(start 170.18 -121.376948)
		(end 167.508428 -121.376948)
		(width 0.10668)
		(layer "B.Cu")
		(net "CLK_GEN2_BMC_RC_OE_N")
	)
	(segment
		(start 149.013926 -124.024898)
		(end 144.029176 -119.040148)
		(width 0.10668)
		(layer "B.Cu")
		(net "CLK_GEN2_BMC_RC_OE_N")
	)
	(segment
		(start 131.956556 -122.50293)
		(end 113.119916 -122.50293)
		(width 0.10668)
		(layer "B.Cu")
		(net "CLK_GEN2_BMC_RC_OE_N")
	)
	(segment
		(start 110.002828 -122.50293)
		(end 65.099184 -122.50293)
		(width 0.10668)
		(layer "B.Cu")
		(net "CLK_GEN2_BMC_RC_OE_N")
	)
	(segment
		(start 158.23565 -123.132596)
		(end 157.888432 -123.479814)
		(width 0.10668)
		(layer "B.Cu")
		(net "CLK_GEN2_BMC_RC_OE_N")
	)
	(segment
		(start 55.292498 -132.309616)
		(end 55.292498 -132.703062)
		(width 0.10668)
		(layer "B.Cu")
		(net "CLK_GEN2_BMC_RC_OE_N")
	)
	(segment
		(start 135.419338 -119.040148)
		(end 131.956556 -122.50293)
		(width 0.10668)
		(layer "B.Cu")
		(net "CLK_GEN2_BMC_RC_OE_N")
	)
	(segment
		(start 167.508428 -121.376948)
		(end 165.75278 -123.132596)
		(width 0.10668)
		(layer "B.Cu")
		(net "CLK_GEN2_BMC_RC_OE_N")
	)
	(segment
		(start 113.119916 -122.50293)
		(end 112.374934 -121.757948)
		(width 0.10668)
		(layer "B.Cu")
		(net "CLK_GEN2_BMC_RC_OE_N")
	)
	(segment
		(start 17.626584 -137.319512)
		(end 17.968722 -137.319512)
		(width 0.12954)
		(layer "F.Cu")
		(net "CLK_100M_GPU_FPGA_DP_R")
	)
	(segment
		(start 15.587218 -134.789164)
		(end 15.675864 -134.87781)
		(width 0.12954)
		(layer "F.Cu")
		(net "CLK_100M_GPU_FPGA_DP_R")
	)
	(segment
		(start 15.42161 -134.789164)
		(end 15.587218 -134.789164)
		(width 0.12954)
		(layer "F.Cu")
		(net "CLK_100M_GPU_FPGA_DP_R")
	)
	(segment
		(start 16.219932 -134.87781)
		(end 17.235424 -135.893302)
		(width 0.12954)
		(layer "F.Cu")
		(net "CLK_100M_GPU_FPGA_DP_R")
	)
	(segment
		(start 17.968722 -137.319512)
		(end 18.302732 -136.985502)
		(width 0.12954)
		(layer "F.Cu")
		(net "CLK_100M_GPU_FPGA_DP_R")
	)
	(segment
		(start 15.675864 -134.87781)
		(end 16.219932 -134.87781)
		(width 0.12954)
		(layer "F.Cu")
		(net "CLK_100M_GPU_FPGA_DP_R")
	)
	(segment
		(start 17.235424 -136.928352)
		(end 17.626584 -137.319512)
		(width 0.12954)
		(layer "F.Cu")
		(net "CLK_100M_GPU_FPGA_DP_R")
	)
	(segment
		(start 17.235424 -135.893302)
		(end 17.235424 -136.928352)
		(width 0.12954)
		(layer "F.Cu")
		(net "CLK_100M_GPU_FPGA_DP_R")
	)
	(segment
		(start 17.968722 -137.642092)
		(end 18.302732 -137.976102)
		(width 0.12954)
		(layer "F.Cu")
		(net "CLK_100M_GPU_FPGA_DN_R")
	)
	(segment
		(start 15.56893 -135.289036)
		(end 15.657576 -135.20039)
		(width 0.12954)
		(layer "F.Cu")
		(net "CLK_100M_GPU_FPGA_DN_R")
	)
	(segment
		(start 15.42161 -135.289036)
		(end 15.56893 -135.289036)
		(width 0.12954)
		(layer "F.Cu")
		(net "CLK_100M_GPU_FPGA_DN_R")
	)
	(segment
		(start 16.086074 -135.20039)
		(end 16.912844 -136.02716)
		(width 0.12954)
		(layer "F.Cu")
		(net "CLK_100M_GPU_FPGA_DN_R")
	)
	(segment
		(start 16.912844 -137.06221)
		(end 17.492726 -137.642092)
		(width 0.12954)
		(layer "F.Cu")
		(net "CLK_100M_GPU_FPGA_DN_R")
	)
	(segment
		(start 17.492726 -137.642092)
		(end 17.968722 -137.642092)
		(width 0.12954)
		(layer "F.Cu")
		(net "CLK_100M_GPU_FPGA_DN_R")
	)
	(segment
		(start 15.657576 -135.20039)
		(end 16.086074 -135.20039)
		(width 0.12954)
		(layer "F.Cu")
		(net "CLK_100M_GPU_FPGA_DN_R")
	)
	(segment
		(start 16.912844 -136.02716)
		(end 16.912844 -137.06221)
		(width 0.12954)
		(layer "F.Cu")
		(net "CLK_100M_GPU_FPGA_DN_R")
	)
	(segment
		(start 386.97789 -222.880174)
		(end 387.444742 -222.614236)
		(width 0.12954)
		(layer "F.Cu")
		(net "CLK_100M_CPU0_CLK05_R_DP")
	)
	(via
		(at 387.444742 -222.614236)
		(size 0.4064)
		(drill 0.2032)
		(layers "F.Cu" "B.Cu")
		(net "CLK_100M_CPU0_CLK05_R_DP")
	)
	(segment
		(start 383.410968 -216.725246)
		(end 383.799334 -217.113612)
		(width 0.12954)
		(layer "B.Cu")
		(net "CLK_100M_CPU0_CLK05_R_DP")
	)
	(segment
		(start 384.068828 -217.113612)
		(end 384.342132 -217.386916)
		(width 0.12954)
		(layer "B.Cu")
		(net "CLK_100M_CPU0_CLK05_R_DP")
	)
	(segment
		(start 386.666232 -221.19336)
		(end 386.600192 -221.2594)
		(width 0.0762)
		(layer "B.Cu")
		(net "CLK_100M_CPU0_CLK05_R_DP")
	)
	(segment
		(start 383.799334 -217.113612)
		(end 384.068828 -217.113612)
		(width 0.12954)
		(layer "B.Cu")
		(net "CLK_100M_CPU0_CLK05_R_DP")
	)
	(segment
		(start 379.452124 -216.725246)
		(end 383.410968 -216.725246)
		(width 0.12954)
		(layer "B.Cu")
		(net "CLK_100M_CPU0_CLK05_R_DP")
	)
	(segment
		(start 387.288278 -222.884238)
		(end 387.444742 -222.614236)
		(width 0.0762)
		(layer "B.Cu")
		(net "CLK_100M_CPU0_CLK05_R_DP")
	)
	(segment
		(start 386.600192 -221.2594)
		(end 386.600192 -221.803976)
		(width 0.0762)
		(layer "B.Cu")
		(net "CLK_100M_CPU0_CLK05_R_DP")
	)
	(segment
		(start 378.957586 -214.923878)
		(end 378.536454 -215.34501)
		(width 0.12954)
		(layer "B.Cu")
		(net "CLK_100M_CPU0_CLK05_R_DP")
	)
	(segment
		(start 384.342132 -217.386916)
		(end 384.342132 -217.65641)
		(width 0.12954)
		(layer "B.Cu")
		(net "CLK_100M_CPU0_CLK05_R_DP")
	)
	(segment
		(start 386.755894 -222.108014)
		(end 386.827522 -222.149924)
		(width 0.0762)
		(layer "B.Cu")
		(net "CLK_100M_CPU0_CLK05_R_DP")
	)
	(segment
		(start 387.070092 -222.595186)
		(end 387.070092 -222.61449)
		(width 0.0762)
		(layer "B.Cu")
		(net "CLK_100M_CPU0_CLK05_R_DP")
	)
	(segment
		(start 386.666232 -219.98051)
		(end 386.666232 -221.17431)
		(width 0.12954)
		(layer "B.Cu")
		(net "CLK_100M_CPU0_CLK05_R_DP")
	)
	(segment
		(start 378.536454 -215.809576)
		(end 379.452124 -216.725246)
		(width 0.12954)
		(layer "B.Cu")
		(net "CLK_100M_CPU0_CLK05_R_DP")
	)
	(segment
		(start 387.070092 -222.61449)
		(end 387.070346 -222.614236)
		(width 0.0762)
		(layer "B.Cu")
		(net "CLK_100M_CPU0_CLK05_R_DP")
	)
	(segment
		(start 384.342132 -217.65641)
		(end 386.666232 -219.98051)
		(width 0.12954)
		(layer "B.Cu")
		(net "CLK_100M_CPU0_CLK05_R_DP")
	)
	(segment
		(start 386.827522 -222.149924)
		(end 386.850636 -222.166434)
		(width 0.0762)
		(layer "B.Cu")
		(net "CLK_100M_CPU0_CLK05_R_DP")
	)
	(segment
		(start 378.536454 -215.34501)
		(end 378.536454 -215.809576)
		(width 0.12954)
		(layer "B.Cu")
		(net "CLK_100M_CPU0_CLK05_R_DP")
	)
	(segment
		(start 386.666232 -221.17431)
		(end 386.666232 -221.19336)
		(width 0.0762)
		(layer "B.Cu")
		(net "CLK_100M_CPU0_CLK05_R_DP")
	)
	(segment
		(start 387.20903 -222.90532)
		(end 387.288278 -222.884238)
		(width 0.0762)
		(layer "B.Cu")
		(net "CLK_100M_CPU0_CLK05_R_DP")
	)
	(arc
		(start 387.070346 -222.614236)
		(mid 387.106729 -222.775486)
		(end 387.20903 -222.90532)
		(width 0.0762)
		(layer "B.Cu")
		(net "CLK_100M_CPU0_CLK05_R_DP")
	)
	(arc
		(start 386.850636 -222.166434)
		(mid 387.012018 -222.354356)
		(end 387.070092 -222.595186)
		(width 0.0762)
		(layer "B.Cu")
		(net "CLK_100M_CPU0_CLK05_R_DP")
	)
	(arc
		(start 386.600192 -221.803976)
		(mid 386.641366 -221.974789)
		(end 386.755894 -222.108014)
		(width 0.0762)
		(layer "B.Cu")
		(net "CLK_100M_CPU0_CLK05_R_DP")
	)
	(segment
		(start 386.50799 -223.69018)
		(end 386.974842 -223.424242)
		(width 0.12954)
		(layer "F.Cu")
		(net "CLK_100M_CPU0_CLK05_R_DN")
	)
	(via
		(at 386.974842 -223.424242)
		(size 0.4064)
		(drill 0.2032)
		(layers "F.Cu" "B.Cu")
		(net "CLK_100M_CPU0_CLK05_R_DN")
	)
	(segment
		(start 379.318266 -217.047826)
		(end 383.27711 -217.047826)
		(width 0.12954)
		(layer "B.Cu")
		(net "CLK_100M_CPU0_CLK05_R_DN")
	)
	(segment
		(start 386.65277 -222.268796)
		(end 386.723636 -222.309944)
		(width 0.0762)
		(layer "B.Cu")
		(net "CLK_100M_CPU0_CLK05_R_DN")
	)
	(segment
		(start 386.343652 -221.17431)
		(end 386.343652 -221.19336)
		(width 0.0762)
		(layer "B.Cu")
		(net "CLK_100M_CPU0_CLK05_R_DN")
	)
	(segment
		(start 386.343652 -221.19336)
		(end 386.409692 -221.2594)
		(width 0.0762)
		(layer "B.Cu")
		(net "CLK_100M_CPU0_CLK05_R_DN")
	)
	(segment
		(start 377.839986 -214.923878)
		(end 378.213874 -215.297766)
		(width 0.12954)
		(layer "B.Cu")
		(net "CLK_100M_CPU0_CLK05_R_DN")
	)
	(segment
		(start 386.343652 -220.114368)
		(end 386.343652 -221.17431)
		(width 0.12954)
		(layer "B.Cu")
		(net "CLK_100M_CPU0_CLK05_R_DN")
	)
	(segment
		(start 378.213874 -215.297766)
		(end 378.213874 -215.943434)
		(width 0.12954)
		(layer "B.Cu")
		(net "CLK_100M_CPU0_CLK05_R_DN")
	)
	(segment
		(start 386.409692 -221.2594)
		(end 386.409692 -221.80423)
		(width 0.0762)
		(layer "B.Cu")
		(net "CLK_100M_CPU0_CLK05_R_DN")
	)
	(segment
		(start 386.723636 -222.309944)
		(end 386.73913 -222.32112)
		(width 0.0762)
		(layer "B.Cu")
		(net "CLK_100M_CPU0_CLK05_R_DN")
	)
	(segment
		(start 387.108446 -223.068642)
		(end 387.131306 -223.15424)
		(width 0.0762)
		(layer "B.Cu")
		(net "CLK_100M_CPU0_CLK05_R_DN")
	)
	(segment
		(start 378.213874 -215.943434)
		(end 379.318266 -217.047826)
		(width 0.12954)
		(layer "B.Cu")
		(net "CLK_100M_CPU0_CLK05_R_DN")
	)
	(segment
		(start 386.879592 -222.595186)
		(end 386.879592 -222.614236)
		(width 0.0762)
		(layer "B.Cu")
		(net "CLK_100M_CPU0_CLK05_R_DN")
	)
	(segment
		(start 383.27711 -217.047826)
		(end 386.343652 -220.114368)
		(width 0.12954)
		(layer "B.Cu")
		(net "CLK_100M_CPU0_CLK05_R_DN")
	)
	(segment
		(start 387.131306 -223.15424)
		(end 386.974842 -223.424242)
		(width 0.0762)
		(layer "B.Cu")
		(net "CLK_100M_CPU0_CLK05_R_DN")
	)
	(arc
		(start 386.879592 -222.614236)
		(mid 386.934519 -222.857528)
		(end 387.088888 -223.053402)
		(width 0.0762)
		(layer "B.Cu")
		(net "CLK_100M_CPU0_CLK05_R_DN")
	)
	(arc
		(start 386.409692 -221.80423)
		(mid 386.474139 -222.066382)
		(end 386.65277 -222.268796)
		(width 0.0762)
		(layer "B.Cu")
		(net "CLK_100M_CPU0_CLK05_R_DN")
	)
	(arc
		(start 387.088888 -223.053402)
		(mid 387.098584 -223.061129)
		(end 387.108446 -223.068642)
		(width 0.0762)
		(layer "B.Cu")
		(net "CLK_100M_CPU0_CLK05_R_DN")
	)
	(arc
		(start 386.73913 -222.32112)
		(mid 386.842443 -222.4412)
		(end 386.879592 -222.595186)
		(width 0.0762)
		(layer "B.Cu")
		(net "CLK_100M_CPU0_CLK05_R_DN")
	)
	(segment
		(start 446.100708 -6.995414)
		(end 445.830452 -6.725158)
		(width 0.12954)
		(layer "F.Cu")
		(net "CLK_100M_CPU0_CLK05_DP")
	)
	(segment
		(start 445.96177 -7.707122)
		(end 446.100708 -7.568184)
		(width 0.12954)
		(layer "F.Cu")
		(net "CLK_100M_CPU0_CLK05_DP")
	)
	(segment
		(start 446.100708 -7.568184)
		(end 446.100708 -6.995414)
		(width 0.12954)
		(layer "F.Cu")
		(net "CLK_100M_CPU0_CLK05_DP")
	)
	(segment
		(start 445.96177 -8.320024)
		(end 445.96177 -7.707122)
		(width 0.12954)
		(layer "F.Cu")
		(net "CLK_100M_CPU0_CLK05_DP")
	)
	(via
		(at 445.830452 -6.725158)
		(size 0.508)
		(drill 0.254)
		(layers "F.Cu" "B.Cu")
		(net "CLK_100M_CPU0_CLK05_DP")
	)
	(segment
		(start 315.217302 -153.323036)
		(end 315.407802 -153.132536)
		(width 0.12954)
		(layer "B.Cu")
		(net "CLK_100M_CPU0_CLK05_DP")
	)
	(segment
		(start 429.663606 -8.45693)
		(end 433.323746 -8.45693)
		(width 0.12954)
		(layer "B.Cu")
		(net "CLK_100M_CPU0_CLK05_DP")
	)
	(segment
		(start 373.004334 -210.517232)
		(end 368.62766 -206.140558)
		(width 0.12954)
		(layer "B.Cu")
		(net "CLK_100M_CPU0_CLK05_DP")
	)
	(segment
		(start 315.217302 -153.709116)
		(end 315.217302 -153.323036)
		(width 0.12954)
		(layer "B.Cu")
		(net "CLK_100M_CPU0_CLK05_DP")
	)
	(segment
		(start 433.323746 -8.45693)
		(end 434.209952 -7.570724)
		(width 0.12954)
		(layer "B.Cu")
		(net "CLK_100M_CPU0_CLK05_DP")
	)
	(segment
		(start 422.199816 -24.047958)
		(end 422.474898 -23.772876)
		(width 0.12954)
		(layer "B.Cu")
		(net "CLK_100M_CPU0_CLK05_DP")
	)
	(segment
		(start 421.930576 -24.047958)
		(end 422.199816 -24.047958)
		(width 0.12954)
		(layer "B.Cu")
		(net "CLK_100M_CPU0_CLK05_DP")
	)
	(segment
		(start 438.89041 -3.920998)
		(end 440.663076 -5.693664)
		(width 0.12954)
		(layer "B.Cu")
		(net "CLK_100M_CPU0_CLK05_DP")
	)
	(segment
		(start 428.92218 -9.198356)
		(end 429.663606 -8.45693)
		(width 0.12954)
		(layer "B.Cu")
		(net "CLK_100M_CPU0_CLK05_DP")
	)
	(segment
		(start 429.095662 -18.724626)
		(end 428.209456 -17.83842)
		(width 0.12954)
		(layer "B.Cu")
		(net "CLK_100M_CPU0_CLK05_DP")
	)
	(segment
		(start 435.114446 -3.920998)
		(end 438.89041 -3.920998)
		(width 0.12954)
		(layer "B.Cu")
		(net "CLK_100M_CPU0_CLK05_DP")
	)
	(segment
		(start 442.877702 -5.693664)
		(end 443.068202 -5.884164)
		(width 0.12954)
		(layer "B.Cu")
		(net "CLK_100M_CPU0_CLK05_DP")
	)
	(segment
		(start 446.100962 -6.27126)
		(end 446.100962 -6.454648)
		(width 0.12954)
		(layer "B.Cu")
		(net "CLK_100M_CPU0_CLK05_DP")
	)
	(segment
		(start 373.969788 -210.517232)
		(end 373.004334 -210.517232)
		(width 0.12954)
		(layer "B.Cu")
		(net "CLK_100M_CPU0_CLK05_DP")
	)
	(segment
		(start 315.217302 -144.907508)
		(end 331.986128 -128.138682)
		(width 0.12954)
		(layer "B.Cu")
		(net "CLK_100M_CPU0_CLK05_DP")
	)
	(segment
		(start 422.474898 -23.503636)
		(end 424.297094 -21.68144)
		(width 0.12954)
		(layer "B.Cu")
		(net "CLK_100M_CPU0_CLK05_DP")
	)
	(segment
		(start 446.100962 -6.454648)
		(end 445.830452 -6.725158)
		(width 0.12954)
		(layer "B.Cu")
		(net "CLK_100M_CPU0_CLK05_DP")
	)
	(segment
		(start 315.407802 -153.899616)
		(end 315.217302 -153.709116)
		(width 0.12954)
		(layer "B.Cu")
		(net "CLK_100M_CPU0_CLK05_DP")
	)
	(segment
		(start 378.560076 -213.190582)
		(end 377.417584 -212.04809)
		(width 0.12954)
		(layer "B.Cu")
		(net "CLK_100M_CPU0_CLK05_DP")
	)
	(segment
		(start 315.407802 -151.979376)
		(end 315.407802 -151.593296)
		(width 0.12954)
		(layer "B.Cu")
		(net "CLK_100M_CPU0_CLK05_DP")
	)
	(segment
		(start 417.62045 -43.839384)
		(end 417.62045 -28.358084)
		(width 0.12954)
		(layer "B.Cu")
		(net "CLK_100M_CPU0_CLK05_DP")
	)
	(segment
		(start 334.968088 -184.43321)
		(end 334.968088 -183.044338)
		(width 0.12954)
		(layer "B.Cu")
		(net "CLK_100M_CPU0_CLK05_DP")
	)
	(segment
		(start 429.095662 -20.023836)
		(end 429.095662 -18.724626)
		(width 0.12954)
		(layer "B.Cu")
		(net "CLK_100M_CPU0_CLK05_DP")
	)
	(segment
		(start 378.957586 -214.123778)
		(end 378.560076 -213.726268)
		(width 0.12954)
		(layer "B.Cu")
		(net "CLK_100M_CPU0_CLK05_DP")
	)
	(segment
		(start 333.321152 -128.138682)
		(end 417.62045 -43.839384)
		(width 0.12954)
		(layer "B.Cu")
		(net "CLK_100M_CPU0_CLK05_DP")
	)
	(segment
		(start 443.068202 -5.884164)
		(end 443.454282 -5.884164)
		(width 0.12954)
		(layer "B.Cu")
		(net "CLK_100M_CPU0_CLK05_DP")
	)
	(segment
		(start 422.474898 -23.772876)
		(end 422.474898 -23.503636)
		(width 0.12954)
		(layer "B.Cu")
		(net "CLK_100M_CPU0_CLK05_DP")
	)
	(segment
		(start 441.915042 -5.884164)
		(end 442.301122 -5.884164)
		(width 0.12954)
		(layer "B.Cu")
		(net "CLK_100M_CPU0_CLK05_DP")
	)
	(segment
		(start 434.209952 -7.570724)
		(end 434.209952 -4.825492)
		(width 0.12954)
		(layer "B.Cu")
		(net "CLK_100M_CPU0_CLK05_DP")
	)
	(segment
		(start 428.209456 -16.152622)
		(end 428.92218 -15.439898)
		(width 0.12954)
		(layer "B.Cu")
		(net "CLK_100M_CPU0_CLK05_DP")
	)
	(segment
		(start 315.407802 -152.746456)
		(end 315.217302 -152.555956)
		(width 0.12954)
		(layer "B.Cu")
		(net "CLK_100M_CPU0_CLK05_DP")
	)
	(segment
		(start 356.675436 -206.140558)
		(end 334.968088 -184.43321)
		(width 0.12954)
		(layer "B.Cu")
		(net "CLK_100M_CPU0_CLK05_DP")
	)
	(segment
		(start 315.217302 -154.476196)
		(end 315.407802 -154.285696)
		(width 0.12954)
		(layer "B.Cu")
		(net "CLK_100M_CPU0_CLK05_DP")
	)
	(segment
		(start 315.217302 -155.629356)
		(end 315.407802 -155.438856)
		(width 0.12954)
		(layer "B.Cu")
		(net "CLK_100M_CPU0_CLK05_DP")
	)
	(segment
		(start 331.986128 -128.138682)
		(end 333.321152 -128.138682)
		(width 0.12954)
		(layer "B.Cu")
		(net "CLK_100M_CPU0_CLK05_DP")
	)
	(segment
		(start 442.301122 -5.884164)
		(end 442.491622 -5.693664)
		(width 0.12954)
		(layer "B.Cu")
		(net "CLK_100M_CPU0_CLK05_DP")
	)
	(segment
		(start 315.407802 -151.593296)
		(end 315.217302 -151.402796)
		(width 0.12954)
		(layer "B.Cu")
		(net "CLK_100M_CPU0_CLK05_DP")
	)
	(segment
		(start 315.217302 -152.169876)
		(end 315.407802 -151.979376)
		(width 0.12954)
		(layer "B.Cu")
		(net "CLK_100M_CPU0_CLK05_DP")
	)
	(segment
		(start 315.407802 -154.285696)
		(end 315.407802 -153.899616)
		(width 0.12954)
		(layer "B.Cu")
		(net "CLK_100M_CPU0_CLK05_DP")
	)
	(segment
		(start 441.724542 -5.693664)
		(end 441.915042 -5.884164)
		(width 0.12954)
		(layer "B.Cu")
		(net "CLK_100M_CPU0_CLK05_DP")
	)
	(segment
		(start 443.454282 -5.884164)
		(end 443.644782 -5.693664)
		(width 0.12954)
		(layer "B.Cu")
		(net "CLK_100M_CPU0_CLK05_DP")
	)
	(segment
		(start 315.217302 -163.293552)
		(end 315.217302 -155.629356)
		(width 0.12954)
		(layer "B.Cu")
		(net "CLK_100M_CPU0_CLK05_DP")
	)
	(segment
		(start 428.92218 -15.439898)
		(end 428.92218 -9.198356)
		(width 0.12954)
		(layer "B.Cu")
		(net "CLK_100M_CPU0_CLK05_DP")
	)
	(segment
		(start 440.663076 -5.693664)
		(end 441.724542 -5.693664)
		(width 0.12954)
		(layer "B.Cu")
		(net "CLK_100M_CPU0_CLK05_DP")
	)
	(segment
		(start 434.209952 -4.825492)
		(end 435.114446 -3.920998)
		(width 0.12954)
		(layer "B.Cu")
		(net "CLK_100M_CPU0_CLK05_DP")
	)
	(segment
		(start 315.217302 -151.402796)
		(end 315.217302 -144.907508)
		(width 0.12954)
		(layer "B.Cu")
		(net "CLK_100M_CPU0_CLK05_DP")
	)
	(segment
		(start 427.438058 -21.68144)
		(end 429.095662 -20.023836)
		(width 0.12954)
		(layer "B.Cu")
		(net "CLK_100M_CPU0_CLK05_DP")
	)
	(segment
		(start 315.217302 -154.862276)
		(end 315.217302 -154.476196)
		(width 0.12954)
		(layer "B.Cu")
		(net "CLK_100M_CPU0_CLK05_DP")
	)
	(segment
		(start 315.407802 -153.132536)
		(end 315.407802 -152.746456)
		(width 0.12954)
		(layer "B.Cu")
		(net "CLK_100M_CPU0_CLK05_DP")
	)
	(segment
		(start 315.407802 -155.438856)
		(end 315.407802 -155.052776)
		(width 0.12954)
		(layer "B.Cu")
		(net "CLK_100M_CPU0_CLK05_DP")
	)
	(segment
		(start 417.62045 -28.358084)
		(end 421.930576 -24.047958)
		(width 0.12954)
		(layer "B.Cu")
		(net "CLK_100M_CPU0_CLK05_DP")
	)
	(segment
		(start 375.500646 -212.04809)
		(end 373.969788 -210.517232)
		(width 0.12954)
		(layer "B.Cu")
		(net "CLK_100M_CPU0_CLK05_DP")
	)
	(segment
		(start 445.523366 -5.693664)
		(end 446.100962 -6.27126)
		(width 0.12954)
		(layer "B.Cu")
		(net "CLK_100M_CPU0_CLK05_DP")
	)
	(segment
		(start 377.417584 -212.04809)
		(end 375.500646 -212.04809)
		(width 0.12954)
		(layer "B.Cu")
		(net "CLK_100M_CPU0_CLK05_DP")
	)
	(segment
		(start 442.491622 -5.693664)
		(end 442.877702 -5.693664)
		(width 0.12954)
		(layer "B.Cu")
		(net "CLK_100M_CPU0_CLK05_DP")
	)
	(segment
		(start 334.968088 -183.044338)
		(end 315.217302 -163.293552)
		(width 0.12954)
		(layer "B.Cu")
		(net "CLK_100M_CPU0_CLK05_DP")
	)
	(segment
		(start 424.297094 -21.68144)
		(end 427.438058 -21.68144)
		(width 0.12954)
		(layer "B.Cu")
		(net "CLK_100M_CPU0_CLK05_DP")
	)
	(segment
		(start 368.62766 -206.140558)
		(end 356.675436 -206.140558)
		(width 0.12954)
		(layer "B.Cu")
		(net "CLK_100M_CPU0_CLK05_DP")
	)
	(segment
		(start 443.644782 -5.693664)
		(end 445.523366 -5.693664)
		(width 0.12954)
		(layer "B.Cu")
		(net "CLK_100M_CPU0_CLK05_DP")
	)
	(segment
		(start 428.209456 -17.83842)
		(end 428.209456 -16.152622)
		(width 0.12954)
		(layer "B.Cu")
		(net "CLK_100M_CPU0_CLK05_DP")
	)
	(segment
		(start 378.560076 -213.726268)
		(end 378.560076 -213.190582)
		(width 0.12954)
		(layer "B.Cu")
		(net "CLK_100M_CPU0_CLK05_DP")
	)
	(segment
		(start 315.407802 -155.052776)
		(end 315.217302 -154.862276)
		(width 0.12954)
		(layer "B.Cu")
		(net "CLK_100M_CPU0_CLK05_DP")
	)
	(segment
		(start 315.217302 -152.555956)
		(end 315.217302 -152.169876)
		(width 0.12954)
		(layer "B.Cu")
		(net "CLK_100M_CPU0_CLK05_DP")
	)
	(segment
		(start 446.423288 -6.995922)
		(end 446.694052 -6.725158)
		(width 0.12954)
		(layer "F.Cu")
		(net "CLK_100M_CPU0_CLK05_DN")
	)
	(segment
		(start 446.561972 -7.705852)
		(end 446.423288 -7.567168)
		(width 0.12954)
		(layer "F.Cu")
		(net "CLK_100M_CPU0_CLK05_DN")
	)
	(segment
		(start 446.561972 -8.320024)
		(end 446.561972 -7.705852)
		(width 0.12954)
		(layer "F.Cu")
		(net "CLK_100M_CPU0_CLK05_DN")
	)
	(segment
		(start 446.423288 -7.567168)
		(end 446.423288 -6.995922)
		(width 0.12954)
		(layer "F.Cu")
		(net "CLK_100M_CPU0_CLK05_DN")
	)
	(via
		(at 446.694052 -6.725158)
		(size 0.508)
		(drill 0.254)
		(layers "F.Cu" "B.Cu")
		(net "CLK_100M_CPU0_CLK05_DN")
	)
	(segment
		(start 434.980588 -3.598418)
		(end 439.024268 -3.598418)
		(width 0.12954)
		(layer "B.Cu")
		(net "CLK_100M_CPU0_CLK05_DN")
	)
	(segment
		(start 378.237496 -213.726268)
		(end 378.237496 -213.32444)
		(width 0.12954)
		(layer "B.Cu")
		(net "CLK_100M_CPU0_CLK05_DN")
	)
	(segment
		(start 428.773082 -19.889978)
		(end 428.773082 -18.858484)
		(width 0.12954)
		(layer "B.Cu")
		(net "CLK_100M_CPU0_CLK05_DN")
	)
	(segment
		(start 378.237496 -213.32444)
		(end 377.283726 -212.37067)
		(width 0.12954)
		(layer "B.Cu")
		(net "CLK_100M_CPU0_CLK05_DN")
	)
	(segment
		(start 375.366788 -212.37067)
		(end 373.83593 -210.839812)
		(width 0.12954)
		(layer "B.Cu")
		(net "CLK_100M_CPU0_CLK05_DN")
	)
	(segment
		(start 428.773082 -18.858484)
		(end 427.886876 -17.972278)
		(width 0.12954)
		(layer "B.Cu")
		(net "CLK_100M_CPU0_CLK05_DN")
	)
	(segment
		(start 417.29787 -43.705526)
		(end 417.29787 -28.224226)
		(width 0.12954)
		(layer "B.Cu")
		(net "CLK_100M_CPU0_CLK05_DN")
	)
	(segment
		(start 331.85227 -127.816102)
		(end 333.187294 -127.816102)
		(width 0.12954)
		(layer "B.Cu")
		(net "CLK_100M_CPU0_CLK05_DN")
	)
	(segment
		(start 334.645508 -183.178196)
		(end 314.894722 -163.42741)
		(width 0.12954)
		(layer "B.Cu")
		(net "CLK_100M_CPU0_CLK05_DN")
	)
	(segment
		(start 377.283726 -212.37067)
		(end 375.366788 -212.37067)
		(width 0.12954)
		(layer "B.Cu")
		(net "CLK_100M_CPU0_CLK05_DN")
	)
	(segment
		(start 440.796934 -5.371084)
		(end 445.657224 -5.371084)
		(width 0.12954)
		(layer "B.Cu")
		(net "CLK_100M_CPU0_CLK05_DN")
	)
	(segment
		(start 428.5996 -9.064498)
		(end 429.529748 -8.13435)
		(width 0.12954)
		(layer "B.Cu")
		(net "CLK_100M_CPU0_CLK05_DN")
	)
	(segment
		(start 333.187294 -127.816102)
		(end 417.29787 -43.705526)
		(width 0.12954)
		(layer "B.Cu")
		(net "CLK_100M_CPU0_CLK05_DN")
	)
	(segment
		(start 445.657224 -5.371084)
		(end 446.423542 -6.137402)
		(width 0.12954)
		(layer "B.Cu")
		(net "CLK_100M_CPU0_CLK05_DN")
	)
	(segment
		(start 433.189888 -8.13435)
		(end 433.887372 -7.436866)
		(width 0.12954)
		(layer "B.Cu")
		(net "CLK_100M_CPU0_CLK05_DN")
	)
	(segment
		(start 427.886876 -17.972278)
		(end 427.886876 -16.018764)
		(width 0.12954)
		(layer "B.Cu")
		(net "CLK_100M_CPU0_CLK05_DN")
	)
	(segment
		(start 368.493802 -206.463138)
		(end 356.541578 -206.463138)
		(width 0.12954)
		(layer "B.Cu")
		(net "CLK_100M_CPU0_CLK05_DN")
	)
	(segment
		(start 439.024268 -3.598418)
		(end 440.796934 -5.371084)
		(width 0.12954)
		(layer "B.Cu")
		(net "CLK_100M_CPU0_CLK05_DN")
	)
	(segment
		(start 373.83593 -210.839812)
		(end 372.870476 -210.839812)
		(width 0.12954)
		(layer "B.Cu")
		(net "CLK_100M_CPU0_CLK05_DN")
	)
	(segment
		(start 446.423542 -6.454648)
		(end 446.694052 -6.725158)
		(width 0.12954)
		(layer "B.Cu")
		(net "CLK_100M_CPU0_CLK05_DN")
	)
	(segment
		(start 417.29787 -28.224226)
		(end 424.163236 -21.35886)
		(width 0.12954)
		(layer "B.Cu")
		(net "CLK_100M_CPU0_CLK05_DN")
	)
	(segment
		(start 334.645508 -184.567068)
		(end 334.645508 -183.178196)
		(width 0.12954)
		(layer "B.Cu")
		(net "CLK_100M_CPU0_CLK05_DN")
	)
	(segment
		(start 314.894722 -144.77365)
		(end 331.85227 -127.816102)
		(width 0.12954)
		(layer "B.Cu")
		(net "CLK_100M_CPU0_CLK05_DN")
	)
	(segment
		(start 433.887372 -4.691634)
		(end 434.980588 -3.598418)
		(width 0.12954)
		(layer "B.Cu")
		(net "CLK_100M_CPU0_CLK05_DN")
	)
	(segment
		(start 314.894722 -163.42741)
		(end 314.894722 -144.77365)
		(width 0.12954)
		(layer "B.Cu")
		(net "CLK_100M_CPU0_CLK05_DN")
	)
	(segment
		(start 356.541578 -206.463138)
		(end 334.645508 -184.567068)
		(width 0.12954)
		(layer "B.Cu")
		(net "CLK_100M_CPU0_CLK05_DN")
	)
	(segment
		(start 427.3042 -21.35886)
		(end 428.773082 -19.889978)
		(width 0.12954)
		(layer "B.Cu")
		(net "CLK_100M_CPU0_CLK05_DN")
	)
	(segment
		(start 428.5996 -15.30604)
		(end 428.5996 -9.064498)
		(width 0.12954)
		(layer "B.Cu")
		(net "CLK_100M_CPU0_CLK05_DN")
	)
	(segment
		(start 429.529748 -8.13435)
		(end 433.189888 -8.13435)
		(width 0.12954)
		(layer "B.Cu")
		(net "CLK_100M_CPU0_CLK05_DN")
	)
	(segment
		(start 372.870476 -210.839812)
		(end 368.493802 -206.463138)
		(width 0.12954)
		(layer "B.Cu")
		(net "CLK_100M_CPU0_CLK05_DN")
	)
	(segment
		(start 424.163236 -21.35886)
		(end 427.3042 -21.35886)
		(width 0.12954)
		(layer "B.Cu")
		(net "CLK_100M_CPU0_CLK05_DN")
	)
	(segment
		(start 433.887372 -7.436866)
		(end 433.887372 -4.691634)
		(width 0.12954)
		(layer "B.Cu")
		(net "CLK_100M_CPU0_CLK05_DN")
	)
	(segment
		(start 377.839986 -214.123778)
		(end 378.237496 -213.726268)
		(width 0.12954)
		(layer "B.Cu")
		(net "CLK_100M_CPU0_CLK05_DN")
	)
	(segment
		(start 427.886876 -16.018764)
		(end 428.5996 -15.30604)
		(width 0.12954)
		(layer "B.Cu")
		(net "CLK_100M_CPU0_CLK05_DN")
	)
	(segment
		(start 446.423542 -6.137402)
		(end 446.423542 -6.454648)
		(width 0.12954)
		(layer "B.Cu")
		(net "CLK_100M_CPU0_CLK05_DN")
	)
	(segment
		(start 384.157982 -222.880174)
		(end 384.624834 -222.614236)
		(width 0.12954)
		(layer "F.Cu")
		(net "CLK_100M_CPU0_CLK04_R_DP")
	)
	(via
		(at 384.624834 -222.614236)
		(size 0.4064)
		(drill 0.2032)
		(layers "F.Cu" "B.Cu")
		(net "CLK_100M_CPU0_CLK04_R_DP")
	)
	(segment
		(start 384.313176 -222.131128)
		(end 384.247136 -222.197168)
		(width 0.0762)
		(layer "B.Cu")
		(net "CLK_100M_CPU0_CLK04_R_DP")
	)
	(segment
		(start 384.299714 -222.856552)
		(end 384.371596 -222.898208)
		(width 0.0762)
		(layer "B.Cu")
		(net "CLK_100M_CPU0_CLK04_R_DP")
	)
	(segment
		(start 384.247136 -222.197168)
		(end 384.247136 -222.803974)
		(width 0.0762)
		(layer "B.Cu")
		(net "CLK_100M_CPU0_CLK04_R_DP")
	)
	(segment
		(start 375.637806 -217.101674)
		(end 375.91111 -217.374978)
		(width 0.12954)
		(layer "B.Cu")
		(net "CLK_100M_CPU0_CLK04_R_DP")
	)
	(segment
		(start 384.313176 -221.794832)
		(end 384.313176 -222.112078)
		(width 0.12954)
		(layer "B.Cu")
		(net "CLK_100M_CPU0_CLK04_R_DP")
	)
	(segment
		(start 383.589022 -221.070678)
		(end 384.313176 -221.794832)
		(width 0.12954)
		(layer "B.Cu")
		(net "CLK_100M_CPU0_CLK04_R_DP")
	)
	(segment
		(start 384.371596 -222.898208)
		(end 384.475736 -222.870776)
		(width 0.0762)
		(layer "B.Cu")
		(net "CLK_100M_CPU0_CLK04_R_DP")
	)
	(segment
		(start 375.91111 -217.644472)
		(end 379.337316 -221.070678)
		(width 0.12954)
		(layer "B.Cu")
		(net "CLK_100M_CPU0_CLK04_R_DP")
	)
	(segment
		(start 384.313176 -222.112078)
		(end 384.313176 -222.131128)
		(width 0.0762)
		(layer "B.Cu")
		(net "CLK_100M_CPU0_CLK04_R_DP")
	)
	(segment
		(start 375.91111 -217.374978)
		(end 375.91111 -217.644472)
		(width 0.12954)
		(layer "B.Cu")
		(net "CLK_100M_CPU0_CLK04_R_DP")
	)
	(segment
		(start 379.337316 -221.070678)
		(end 383.589022 -221.070678)
		(width 0.12954)
		(layer "B.Cu")
		(net "CLK_100M_CPU0_CLK04_R_DP")
	)
	(segment
		(start 384.247136 -222.803974)
		(end 384.299714 -222.856552)
		(width 0.0762)
		(layer "B.Cu")
		(net "CLK_100M_CPU0_CLK04_R_DP")
	)
	(segment
		(start 374.061736 -215.795098)
		(end 375.368312 -217.101674)
		(width 0.12954)
		(layer "B.Cu")
		(net "CLK_100M_CPU0_CLK04_R_DP")
	)
	(segment
		(start 384.475736 -222.870776)
		(end 384.624834 -222.614236)
		(width 0.0762)
		(layer "B.Cu")
		(net "CLK_100M_CPU0_CLK04_R_DP")
	)
	(segment
		(start 375.368312 -217.101674)
		(end 375.637806 -217.101674)
		(width 0.12954)
		(layer "B.Cu")
		(net "CLK_100M_CPU0_CLK04_R_DP")
	)
	(segment
		(start 374.487186 -214.923878)
		(end 374.061736 -215.349328)
		(width 0.12954)
		(layer "B.Cu")
		(net "CLK_100M_CPU0_CLK04_R_DP")
	)
	(segment
		(start 374.061736 -215.349328)
		(end 374.061736 -215.795098)
		(width 0.12954)
		(layer "B.Cu")
		(net "CLK_100M_CPU0_CLK04_R_DP")
	)
	(segment
		(start 383.688082 -223.69018)
		(end 384.154934 -223.424242)
		(width 0.12954)
		(layer "F.Cu")
		(net "CLK_100M_CPU0_CLK04_R_DN")
	)
	(via
		(at 384.154934 -223.424242)
		(size 0.4064)
		(drill 0.2032)
		(layers "F.Cu" "B.Cu")
		(net "CLK_100M_CPU0_CLK04_R_DN")
	)
	(segment
		(start 383.455164 -221.393258)
		(end 383.990596 -221.92869)
		(width 0.12954)
		(layer "B.Cu")
		(net "CLK_100M_CPU0_CLK04_R_DN")
	)
	(segment
		(start 373.739156 -215.293448)
		(end 373.739156 -215.928956)
		(width 0.12954)
		(layer "B.Cu")
		(net "CLK_100M_CPU0_CLK04_R_DN")
	)
	(segment
		(start 384.056636 -222.197168)
		(end 384.056636 -222.882968)
		(width 0.0762)
		(layer "B.Cu")
		(net "CLK_100M_CPU0_CLK04_R_DN")
	)
	(segment
		(start 384.304032 -223.167448)
		(end 384.154934 -223.424242)
		(width 0.0762)
		(layer "B.Cu")
		(net "CLK_100M_CPU0_CLK04_R_DN")
	)
	(segment
		(start 384.276092 -223.063308)
		(end 384.304032 -223.167448)
		(width 0.0762)
		(layer "B.Cu")
		(net "CLK_100M_CPU0_CLK04_R_DN")
	)
	(segment
		(start 384.182874 -223.009206)
		(end 384.276092 -223.063308)
		(width 0.0762)
		(layer "B.Cu")
		(net "CLK_100M_CPU0_CLK04_R_DN")
	)
	(segment
		(start 373.369586 -214.923878)
		(end 373.739156 -215.293448)
		(width 0.12954)
		(layer "B.Cu")
		(net "CLK_100M_CPU0_CLK04_R_DN")
	)
	(segment
		(start 383.990596 -222.112078)
		(end 383.990596 -222.131128)
		(width 0.0762)
		(layer "B.Cu")
		(net "CLK_100M_CPU0_CLK04_R_DN")
	)
	(segment
		(start 373.739156 -215.928956)
		(end 379.203458 -221.393258)
		(width 0.12954)
		(layer "B.Cu")
		(net "CLK_100M_CPU0_CLK04_R_DN")
	)
	(segment
		(start 379.203458 -221.393258)
		(end 383.455164 -221.393258)
		(width 0.12954)
		(layer "B.Cu")
		(net "CLK_100M_CPU0_CLK04_R_DN")
	)
	(segment
		(start 384.056636 -222.882968)
		(end 384.182874 -223.009206)
		(width 0.0762)
		(layer "B.Cu")
		(net "CLK_100M_CPU0_CLK04_R_DN")
	)
	(segment
		(start 383.990596 -221.92869)
		(end 383.990596 -222.112078)
		(width 0.12954)
		(layer "B.Cu")
		(net "CLK_100M_CPU0_CLK04_R_DN")
	)
	(segment
		(start 383.990596 -222.131128)
		(end 384.056636 -222.197168)
		(width 0.0762)
		(layer "B.Cu")
		(net "CLK_100M_CPU0_CLK04_R_DN")
	)
	(segment
		(start 446.100708 -11.979402)
		(end 446.100708 -12.593828)
		(width 0.12954)
		(layer "F.Cu")
		(net "CLK_100M_CPU0_CLK04_DP")
	)
	(segment
		(start 445.96177 -11.26998)
		(end 445.96177 -11.840464)
		(width 0.12954)
		(layer "F.Cu")
		(net "CLK_100M_CPU0_CLK04_DP")
	)
	(segment
		(start 446.100708 -12.593828)
		(end 445.82969 -12.864846)
		(width 0.12954)
		(layer "F.Cu")
		(net "CLK_100M_CPU0_CLK04_DP")
	)
	(segment
		(start 445.96177 -11.840464)
		(end 446.100708 -11.979402)
		(width 0.12954)
		(layer "F.Cu")
		(net "CLK_100M_CPU0_CLK04_DP")
	)
	(via
		(at 445.82969 -12.864846)
		(size 0.508)
		(drill 0.254)
		(layers "F.Cu" "B.Cu")
		(net "CLK_100M_CPU0_CLK04_DP")
	)
	(segment
		(start 372.208044 -212.437472)
		(end 367.922302 -208.15173)
		(width 0.12954)
		(layer "B.Cu")
		(net "CLK_100M_CPU0_CLK04_DP")
	)
	(segment
		(start 312.809128 -153.443178)
		(end 312.999628 -153.252678)
		(width 0.12954)
		(layer "B.Cu")
		(net "CLK_100M_CPU0_CLK04_DP")
	)
	(segment
		(start 437.998362 -2.494026)
		(end 438.188862 -2.684526)
		(width 0.12954)
		(layer "B.Cu")
		(net "CLK_100M_CPU0_CLK04_DP")
	)
	(segment
		(start 421.7797 -5.84581)
		(end 425.131484 -2.494026)
		(width 0.12954)
		(layer "B.Cu")
		(net "CLK_100M_CPU0_CLK04_DP")
	)
	(segment
		(start 332.892146 -185.293762)
		(end 332.892146 -183.90489)
		(width 0.12954)
		(layer "B.Cu")
		(net "CLK_100M_CPU0_CLK04_DP")
	)
	(segment
		(start 312.999628 -154.019758)
		(end 312.809128 -153.829258)
		(width 0.12954)
		(layer "B.Cu")
		(net "CLK_100M_CPU0_CLK04_DP")
	)
	(segment
		(start 441.47486 -4.642358)
		(end 446.676526 -4.642358)
		(width 0.12954)
		(layer "B.Cu")
		(net "CLK_100M_CPU0_CLK04_DP")
	)
	(segment
		(start 437.421782 -2.684526)
		(end 437.612282 -2.494026)
		(width 0.12954)
		(layer "B.Cu")
		(net "CLK_100M_CPU0_CLK04_DP")
	)
	(segment
		(start 438.188862 -2.684526)
		(end 438.574942 -2.684526)
		(width 0.12954)
		(layer "B.Cu")
		(net "CLK_100M_CPU0_CLK04_DP")
	)
	(segment
		(start 415.544508 -23.18639)
		(end 420.76878 -17.962118)
		(width 0.12954)
		(layer "B.Cu")
		(net "CLK_100M_CPU0_CLK04_DP")
	)
	(segment
		(start 374.487186 -214.123778)
		(end 374.089676 -213.726268)
		(width 0.12954)
		(layer "B.Cu")
		(net "CLK_100M_CPU0_CLK04_DP")
	)
	(segment
		(start 373.09298 -212.437472)
		(end 372.208044 -212.437472)
		(width 0.12954)
		(layer "B.Cu")
		(net "CLK_100M_CPU0_CLK04_DP")
	)
	(segment
		(start 374.089676 -213.434168)
		(end 373.09298 -212.437472)
		(width 0.12954)
		(layer "B.Cu")
		(net "CLK_100M_CPU0_CLK04_DP")
	)
	(segment
		(start 446.406778 -10.441432)
		(end 446.1002 -10.74801)
		(width 0.12954)
		(layer "B.Cu")
		(net "CLK_100M_CPU0_CLK04_DP")
	)
	(segment
		(start 436.268622 -2.684526)
		(end 436.459122 -2.494026)
		(width 0.12954)
		(layer "B.Cu")
		(net "CLK_100M_CPU0_CLK04_DP")
	)
	(segment
		(start 437.612282 -2.494026)
		(end 437.998362 -2.494026)
		(width 0.12954)
		(layer "B.Cu")
		(net "CLK_100M_CPU0_CLK04_DP")
	)
	(segment
		(start 312.809128 -152.290018)
		(end 312.999628 -152.099518)
		(width 0.12954)
		(layer "B.Cu")
		(net "CLK_100M_CPU0_CLK04_DP")
	)
	(segment
		(start 447.27368 -6.10489)
		(end 447.61277 -6.44398)
		(width 0.12954)
		(layer "B.Cu")
		(net "CLK_100M_CPU0_CLK04_DP")
	)
	(segment
		(start 367.922302 -208.15173)
		(end 355.750114 -208.15173)
		(width 0.12954)
		(layer "B.Cu")
		(net "CLK_100M_CPU0_CLK04_DP")
	)
	(segment
		(start 332.892146 -183.90489)
		(end 312.809128 -163.821872)
		(width 0.12954)
		(layer "B.Cu")
		(net "CLK_100M_CPU0_CLK04_DP")
	)
	(segment
		(start 447.61277 -8.021574)
		(end 446.406778 -9.227566)
		(width 0.12954)
		(layer "B.Cu")
		(net "CLK_100M_CPU0_CLK04_DP")
	)
	(segment
		(start 447.27368 -5.239512)
		(end 447.27368 -6.10489)
		(width 0.12954)
		(layer "B.Cu")
		(net "CLK_100M_CPU0_CLK04_DP")
	)
	(segment
		(start 312.999628 -151.713438)
		(end 312.809128 -151.522938)
		(width 0.12954)
		(layer "B.Cu")
		(net "CLK_100M_CPU0_CLK04_DP")
	)
	(segment
		(start 312.809128 -154.596338)
		(end 312.999628 -154.405838)
		(width 0.12954)
		(layer "B.Cu")
		(net "CLK_100M_CPU0_CLK04_DP")
	)
	(segment
		(start 437.035702 -2.684526)
		(end 437.421782 -2.684526)
		(width 0.12954)
		(layer "B.Cu")
		(net "CLK_100M_CPU0_CLK04_DP")
	)
	(segment
		(start 435.882542 -2.684526)
		(end 436.268622 -2.684526)
		(width 0.12954)
		(layer "B.Cu")
		(net "CLK_100M_CPU0_CLK04_DP")
	)
	(segment
		(start 312.809128 -163.821872)
		(end 312.809128 -155.749498)
		(width 0.12954)
		(layer "B.Cu")
		(net "CLK_100M_CPU0_CLK04_DP")
	)
	(segment
		(start 415.544508 -42.978832)
		(end 415.544508 -23.18639)
		(width 0.12954)
		(layer "B.Cu")
		(net "CLK_100M_CPU0_CLK04_DP")
	)
	(segment
		(start 312.809128 -154.982418)
		(end 312.809128 -154.596338)
		(width 0.12954)
		(layer "B.Cu")
		(net "CLK_100M_CPU0_CLK04_DP")
	)
	(segment
		(start 436.459122 -2.494026)
		(end 436.845202 -2.494026)
		(width 0.12954)
		(layer "B.Cu")
		(net "CLK_100M_CPU0_CLK04_DP")
	)
	(segment
		(start 312.999628 -154.405838)
		(end 312.999628 -154.019758)
		(width 0.12954)
		(layer "B.Cu")
		(net "CLK_100M_CPU0_CLK04_DP")
	)
	(segment
		(start 446.1002 -10.74801)
		(end 446.1002 -12.594336)
		(width 0.12954)
		(layer "B.Cu")
		(net "CLK_100M_CPU0_CLK04_DP")
	)
	(segment
		(start 355.750114 -208.15173)
		(end 332.892146 -185.293762)
		(width 0.12954)
		(layer "B.Cu")
		(net "CLK_100M_CPU0_CLK04_DP")
	)
	(segment
		(start 312.809128 -155.749498)
		(end 312.999628 -155.558998)
		(width 0.12954)
		(layer "B.Cu")
		(net "CLK_100M_CPU0_CLK04_DP")
	)
	(segment
		(start 332.855062 -125.668278)
		(end 415.544508 -42.978832)
		(width 0.12954)
		(layer "B.Cu")
		(net "CLK_100M_CPU0_CLK04_DP")
	)
	(segment
		(start 447.61277 -6.44398)
		(end 447.61277 -8.021574)
		(width 0.12954)
		(layer "B.Cu")
		(net "CLK_100M_CPU0_CLK04_DP")
	)
	(segment
		(start 438.765442 -2.494026)
		(end 439.326528 -2.494026)
		(width 0.12954)
		(layer "B.Cu")
		(net "CLK_100M_CPU0_CLK04_DP")
	)
	(segment
		(start 312.999628 -153.252678)
		(end 312.999628 -152.866598)
		(width 0.12954)
		(layer "B.Cu")
		(net "CLK_100M_CPU0_CLK04_DP")
	)
	(segment
		(start 436.845202 -2.494026)
		(end 437.035702 -2.684526)
		(width 0.12954)
		(layer "B.Cu")
		(net "CLK_100M_CPU0_CLK04_DP")
	)
	(segment
		(start 425.131484 -2.494026)
		(end 435.692042 -2.494026)
		(width 0.12954)
		(layer "B.Cu")
		(net "CLK_100M_CPU0_CLK04_DP")
	)
	(segment
		(start 312.809128 -152.676098)
		(end 312.809128 -152.290018)
		(width 0.12954)
		(layer "B.Cu")
		(net "CLK_100M_CPU0_CLK04_DP")
	)
	(segment
		(start 331.436726 -125.668278)
		(end 332.855062 -125.668278)
		(width 0.12954)
		(layer "B.Cu")
		(net "CLK_100M_CPU0_CLK04_DP")
	)
	(segment
		(start 421.7797 -15.698978)
		(end 421.7797 -5.84581)
		(width 0.12954)
		(layer "B.Cu")
		(net "CLK_100M_CPU0_CLK04_DP")
	)
	(segment
		(start 446.676526 -4.642358)
		(end 447.27368 -5.239512)
		(width 0.12954)
		(layer "B.Cu")
		(net "CLK_100M_CPU0_CLK04_DP")
	)
	(segment
		(start 312.809128 -144.295876)
		(end 331.436726 -125.668278)
		(width 0.12954)
		(layer "B.Cu")
		(net "CLK_100M_CPU0_CLK04_DP")
	)
	(segment
		(start 446.1002 -12.594336)
		(end 445.82969 -12.864846)
		(width 0.12954)
		(layer "B.Cu")
		(net "CLK_100M_CPU0_CLK04_DP")
	)
	(segment
		(start 439.326528 -2.494026)
		(end 441.47486 -4.642358)
		(width 0.12954)
		(layer "B.Cu")
		(net "CLK_100M_CPU0_CLK04_DP")
	)
	(segment
		(start 312.999628 -152.866598)
		(end 312.809128 -152.676098)
		(width 0.12954)
		(layer "B.Cu")
		(net "CLK_100M_CPU0_CLK04_DP")
	)
	(segment
		(start 312.999628 -155.172918)
		(end 312.809128 -154.982418)
		(width 0.12954)
		(layer "B.Cu")
		(net "CLK_100M_CPU0_CLK04_DP")
	)
	(segment
		(start 435.692042 -2.494026)
		(end 435.882542 -2.684526)
		(width 0.12954)
		(layer "B.Cu")
		(net "CLK_100M_CPU0_CLK04_DP")
	)
	(segment
		(start 312.999628 -155.558998)
		(end 312.999628 -155.172918)
		(width 0.12954)
		(layer "B.Cu")
		(net "CLK_100M_CPU0_CLK04_DP")
	)
	(segment
		(start 446.406778 -9.227566)
		(end 446.406778 -10.441432)
		(width 0.12954)
		(layer "B.Cu")
		(net "CLK_100M_CPU0_CLK04_DP")
	)
	(segment
		(start 420.76878 -17.962118)
		(end 420.76878 -16.709898)
		(width 0.12954)
		(layer "B.Cu")
		(net "CLK_100M_CPU0_CLK04_DP")
	)
	(segment
		(start 420.76878 -16.709898)
		(end 421.7797 -15.698978)
		(width 0.12954)
		(layer "B.Cu")
		(net "CLK_100M_CPU0_CLK04_DP")
	)
	(segment
		(start 438.574942 -2.684526)
		(end 438.765442 -2.494026)
		(width 0.12954)
		(layer "B.Cu")
		(net "CLK_100M_CPU0_CLK04_DP")
	)
	(segment
		(start 312.809128 -151.522938)
		(end 312.809128 -144.295876)
		(width 0.12954)
		(layer "B.Cu")
		(net "CLK_100M_CPU0_CLK04_DP")
	)
	(segment
		(start 312.809128 -153.829258)
		(end 312.809128 -153.443178)
		(width 0.12954)
		(layer "B.Cu")
		(net "CLK_100M_CPU0_CLK04_DP")
	)
	(segment
		(start 312.999628 -152.099518)
		(end 312.999628 -151.713438)
		(width 0.12954)
		(layer "B.Cu")
		(net "CLK_100M_CPU0_CLK04_DP")
	)
	(segment
		(start 374.089676 -213.726268)
		(end 374.089676 -213.434168)
		(width 0.12954)
		(layer "B.Cu")
		(net "CLK_100M_CPU0_CLK04_DP")
	)
	(segment
		(start 446.423288 -11.985498)
		(end 446.561972 -11.846814)
		(width 0.12954)
		(layer "F.Cu")
		(net "CLK_100M_CPU0_CLK04_DN")
	)
	(segment
		(start 446.69329 -12.864846)
		(end 446.423288 -12.594844)
		(width 0.12954)
		(layer "F.Cu")
		(net "CLK_100M_CPU0_CLK04_DN")
	)
	(segment
		(start 446.561972 -11.846814)
		(end 446.561972 -11.26998)
		(width 0.12954)
		(layer "F.Cu")
		(net "CLK_100M_CPU0_CLK04_DN")
	)
	(segment
		(start 446.423288 -12.594844)
		(end 446.423288 -11.985498)
		(width 0.12954)
		(layer "F.Cu")
		(net "CLK_100M_CPU0_CLK04_DN")
	)
	(via
		(at 446.69329 -12.864846)
		(size 0.508)
		(drill 0.254)
		(layers "F.Cu" "B.Cu")
		(net "CLK_100M_CPU0_CLK04_DN")
	)
	(segment
		(start 447.93535 -6.310122)
		(end 447.93535 -8.155432)
		(width 0.12954)
		(layer "B.Cu")
		(net "CLK_100M_CPU0_CLK04_DN")
	)
	(segment
		(start 446.729358 -9.361424)
		(end 446.729358 -10.57529)
		(width 0.12954)
		(layer "B.Cu")
		(net "CLK_100M_CPU0_CLK04_DN")
	)
	(segment
		(start 439.460386 -2.171446)
		(end 441.608718 -4.319778)
		(width 0.12954)
		(layer "B.Cu")
		(net "CLK_100M_CPU0_CLK04_DN")
	)
	(segment
		(start 446.42278 -10.881868)
		(end 446.42278 -12.594336)
		(width 0.12954)
		(layer "B.Cu")
		(net "CLK_100M_CPU0_CLK04_DN")
	)
	(segment
		(start 415.221928 -42.844974)
		(end 415.221928 -23.052532)
		(width 0.12954)
		(layer "B.Cu")
		(net "CLK_100M_CPU0_CLK04_DN")
	)
	(segment
		(start 447.59626 -5.971032)
		(end 447.93535 -6.310122)
		(width 0.12954)
		(layer "B.Cu")
		(net "CLK_100M_CPU0_CLK04_DN")
	)
	(segment
		(start 415.221928 -23.052532)
		(end 420.4462 -17.82826)
		(width 0.12954)
		(layer "B.Cu")
		(net "CLK_100M_CPU0_CLK04_DN")
	)
	(segment
		(start 421.45712 -5.711952)
		(end 424.997626 -2.171446)
		(width 0.12954)
		(layer "B.Cu")
		(net "CLK_100M_CPU0_CLK04_DN")
	)
	(segment
		(start 372.074186 -212.760052)
		(end 367.788444 -208.47431)
		(width 0.12954)
		(layer "B.Cu")
		(net "CLK_100M_CPU0_CLK04_DN")
	)
	(segment
		(start 446.810384 -4.319778)
		(end 447.59626 -5.105654)
		(width 0.12954)
		(layer "B.Cu")
		(net "CLK_100M_CPU0_CLK04_DN")
	)
	(segment
		(start 332.569566 -184.038748)
		(end 312.486548 -163.95573)
		(width 0.12954)
		(layer "B.Cu")
		(net "CLK_100M_CPU0_CLK04_DN")
	)
	(segment
		(start 373.369586 -214.123778)
		(end 373.767096 -213.726268)
		(width 0.12954)
		(layer "B.Cu")
		(net "CLK_100M_CPU0_CLK04_DN")
	)
	(segment
		(start 441.608718 -4.319778)
		(end 446.810384 -4.319778)
		(width 0.12954)
		(layer "B.Cu")
		(net "CLK_100M_CPU0_CLK04_DN")
	)
	(segment
		(start 446.729358 -10.57529)
		(end 446.42278 -10.881868)
		(width 0.12954)
		(layer "B.Cu")
		(net "CLK_100M_CPU0_CLK04_DN")
	)
	(segment
		(start 421.45712 -15.56512)
		(end 421.45712 -5.711952)
		(width 0.12954)
		(layer "B.Cu")
		(net "CLK_100M_CPU0_CLK04_DN")
	)
	(segment
		(start 332.721204 -125.345698)
		(end 415.221928 -42.844974)
		(width 0.12954)
		(layer "B.Cu")
		(net "CLK_100M_CPU0_CLK04_DN")
	)
	(segment
		(start 446.42278 -12.594336)
		(end 446.69329 -12.864846)
		(width 0.12954)
		(layer "B.Cu")
		(net "CLK_100M_CPU0_CLK04_DN")
	)
	(segment
		(start 420.4462 -17.82826)
		(end 420.4462 -16.57604)
		(width 0.12954)
		(layer "B.Cu")
		(net "CLK_100M_CPU0_CLK04_DN")
	)
	(segment
		(start 332.569566 -185.42762)
		(end 332.569566 -184.038748)
		(width 0.12954)
		(layer "B.Cu")
		(net "CLK_100M_CPU0_CLK04_DN")
	)
	(segment
		(start 367.788444 -208.47431)
		(end 355.616256 -208.47431)
		(width 0.12954)
		(layer "B.Cu")
		(net "CLK_100M_CPU0_CLK04_DN")
	)
	(segment
		(start 312.486548 -144.162018)
		(end 331.302868 -125.345698)
		(width 0.12954)
		(layer "B.Cu")
		(net "CLK_100M_CPU0_CLK04_DN")
	)
	(segment
		(start 424.997626 -2.171446)
		(end 439.460386 -2.171446)
		(width 0.12954)
		(layer "B.Cu")
		(net "CLK_100M_CPU0_CLK04_DN")
	)
	(segment
		(start 373.767096 -213.726268)
		(end 373.767096 -213.568026)
		(width 0.12954)
		(layer "B.Cu")
		(net "CLK_100M_CPU0_CLK04_DN")
	)
	(segment
		(start 420.4462 -16.57604)
		(end 421.45712 -15.56512)
		(width 0.12954)
		(layer "B.Cu")
		(net "CLK_100M_CPU0_CLK04_DN")
	)
	(segment
		(start 447.93535 -8.155432)
		(end 446.729358 -9.361424)
		(width 0.12954)
		(layer "B.Cu")
		(net "CLK_100M_CPU0_CLK04_DN")
	)
	(segment
		(start 447.59626 -5.105654)
		(end 447.59626 -5.971032)
		(width 0.12954)
		(layer "B.Cu")
		(net "CLK_100M_CPU0_CLK04_DN")
	)
	(segment
		(start 373.767096 -213.568026)
		(end 372.959122 -212.760052)
		(width 0.12954)
		(layer "B.Cu")
		(net "CLK_100M_CPU0_CLK04_DN")
	)
	(segment
		(start 331.302868 -125.345698)
		(end 332.721204 -125.345698)
		(width 0.12954)
		(layer "B.Cu")
		(net "CLK_100M_CPU0_CLK04_DN")
	)
	(segment
		(start 355.616256 -208.47431)
		(end 332.569566 -185.42762)
		(width 0.12954)
		(layer "B.Cu")
		(net "CLK_100M_CPU0_CLK04_DN")
	)
	(segment
		(start 312.486548 -163.95573)
		(end 312.486548 -144.162018)
		(width 0.12954)
		(layer "B.Cu")
		(net "CLK_100M_CPU0_CLK04_DN")
	)
	(segment
		(start 372.959122 -212.760052)
		(end 372.074186 -212.760052)
		(width 0.12954)
		(layer "B.Cu")
		(net "CLK_100M_CPU0_CLK04_DN")
	)
	(segment
		(start 385.567936 -222.070168)
		(end 386.034788 -221.80423)
		(width 0.12954)
		(layer "F.Cu")
		(net "CLK_100M_CPU0_CLK03_R_DP")
	)
	(via
		(at 386.034788 -221.80423)
		(size 0.4064)
		(drill 0.2032)
		(layers "F.Cu" "B.Cu")
		(net "CLK_100M_CPU0_CLK03_R_DP")
	)
	(segment
		(start 384.658616 -220.110558)
		(end 380.438914 -220.110558)
		(width 0.12954)
		(layer "B.Cu")
		(net "CLK_100M_CPU0_CLK03_R_DP")
	)
	(segment
		(start 385.726178 -221.49562)
		(end 385.726178 -221.2721)
		(width 0.12954)
		(layer "B.Cu")
		(net "CLK_100M_CPU0_CLK03_R_DP")
	)
	(segment
		(start 385.726178 -221.2721)
		(end 385.65963 -221.111572)
		(width 0.12954)
		(layer "B.Cu")
		(net "CLK_100M_CPU0_CLK03_R_DP")
	)
	(segment
		(start 376.28703 -215.359234)
		(end 376.722386 -214.923878)
		(width 0.12954)
		(layer "B.Cu")
		(net "CLK_100M_CPU0_CLK03_R_DP")
	)
	(segment
		(start 385.65963 -221.111572)
		(end 384.658616 -220.110558)
		(width 0.12954)
		(layer "B.Cu")
		(net "CLK_100M_CPU0_CLK03_R_DP")
	)
	(segment
		(start 386.034788 -221.80423)
		(end 385.726178 -221.49562)
		(width 0.12954)
		(layer "B.Cu")
		(net "CLK_100M_CPU0_CLK03_R_DP")
	)
	(segment
		(start 376.28703 -215.958674)
		(end 376.28703 -215.359234)
		(width 0.12954)
		(layer "B.Cu")
		(net "CLK_100M_CPU0_CLK03_R_DP")
	)
	(segment
		(start 380.438914 -220.110558)
		(end 376.28703 -215.958674)
		(width 0.12954)
		(layer "B.Cu")
		(net "CLK_100M_CPU0_CLK03_R_DP")
	)
	(segment
		(start 384.627882 -222.070168)
		(end 385.094734 -221.80423)
		(width 0.12954)
		(layer "F.Cu")
		(net "CLK_100M_CPU0_CLK03_R_DN")
	)
	(via
		(at 385.094734 -221.80423)
		(size 0.4064)
		(drill 0.2032)
		(layers "F.Cu" "B.Cu")
		(net "CLK_100M_CPU0_CLK03_R_DN")
	)
	(segment
		(start 385.094734 -221.80423)
		(end 385.403598 -221.495366)
		(width 0.12954)
		(layer "B.Cu")
		(net "CLK_100M_CPU0_CLK03_R_DN")
	)
	(segment
		(start 385.403598 -221.336362)
		(end 385.386072 -221.294452)
		(width 0.12954)
		(layer "B.Cu")
		(net "CLK_100M_CPU0_CLK03_R_DN")
	)
	(segment
		(start 375.96445 -215.283542)
		(end 375.604786 -214.923878)
		(width 0.12954)
		(layer "B.Cu")
		(net "CLK_100M_CPU0_CLK03_R_DN")
	)
	(segment
		(start 384.524758 -220.433138)
		(end 380.305056 -220.433138)
		(width 0.12954)
		(layer "B.Cu")
		(net "CLK_100M_CPU0_CLK03_R_DN")
	)
	(segment
		(start 375.96445 -216.092532)
		(end 375.96445 -215.283542)
		(width 0.12954)
		(layer "B.Cu")
		(net "CLK_100M_CPU0_CLK03_R_DN")
	)
	(segment
		(start 385.386072 -221.294452)
		(end 384.524758 -220.433138)
		(width 0.12954)
		(layer "B.Cu")
		(net "CLK_100M_CPU0_CLK03_R_DN")
	)
	(segment
		(start 385.403598 -221.495366)
		(end 385.403598 -221.336362)
		(width 0.12954)
		(layer "B.Cu")
		(net "CLK_100M_CPU0_CLK03_R_DN")
	)
	(segment
		(start 380.305056 -220.433138)
		(end 375.96445 -216.092532)
		(width 0.12954)
		(layer "B.Cu")
		(net "CLK_100M_CPU0_CLK03_R_DN")
	)
	(segment
		(start 431.966878 -7.755128)
		(end 431.966878 -8.320024)
		(width 0.12954)
		(layer "F.Cu")
		(net "CLK_100M_CPU0_CLK03_DP")
	)
	(segment
		(start 432.096926 -7.62508)
		(end 431.966878 -7.755128)
		(width 0.12954)
		(layer "F.Cu")
		(net "CLK_100M_CPU0_CLK03_DP")
	)
	(segment
		(start 431.846482 -6.73227)
		(end 432.096926 -6.982714)
		(width 0.12954)
		(layer "F.Cu")
		(net "CLK_100M_CPU0_CLK03_DP")
	)
	(segment
		(start 432.096926 -6.982714)
		(end 432.096926 -7.62508)
		(width 0.12954)
		(layer "F.Cu")
		(net "CLK_100M_CPU0_CLK03_DP")
	)
	(via
		(at 431.846482 -6.73227)
		(size 0.508)
		(drill 0.254)
		(layers "F.Cu" "B.Cu")
		(net "CLK_100M_CPU0_CLK03_DP")
	)
	(segment
		(start 314.221368 -153.280872)
		(end 314.221368 -152.894792)
		(width 0.12954)
		(layer "B.Cu")
		(net "CLK_100M_CPU0_CLK03_DP")
	)
	(segment
		(start 356.25405 -207.157066)
		(end 333.95158 -184.854596)
		(width 0.12954)
		(layer "B.Cu")
		(net "CLK_100M_CPU0_CLK03_DP")
	)
	(segment
		(start 428.66437 -3.631438)
		(end 428.85487 -3.821938)
		(width 0.12954)
		(layer "B.Cu")
		(net "CLK_100M_CPU0_CLK03_DP")
	)
	(segment
		(start 423.171112 -18.376646)
		(end 422.661588 -17.867122)
		(width 0.12954)
		(layer "B.Cu")
		(net "CLK_100M_CPU0_CLK03_DP")
	)
	(segment
		(start 331.883258 -126.80061)
		(end 333.22133 -126.80061)
		(width 0.12954)
		(layer "B.Cu")
		(net "CLK_100M_CPU0_CLK03_DP")
	)
	(segment
		(start 423.140886 -9.483344)
		(end 422.950386 -9.292844)
		(width 0.12954)
		(layer "B.Cu")
		(net "CLK_100M_CPU0_CLK03_DP")
	)
	(segment
		(start 422.950386 -6.618224)
		(end 422.950386 -6.232144)
		(width 0.12954)
		(layer "B.Cu")
		(net "CLK_100M_CPU0_CLK03_DP")
	)
	(segment
		(start 376.324876 -213.409022)
		(end 376.006614 -213.09076)
		(width 0.12954)
		(layer "B.Cu")
		(net "CLK_100M_CPU0_CLK03_DP")
	)
	(segment
		(start 314.030868 -153.471372)
		(end 314.221368 -153.280872)
		(width 0.12954)
		(layer "B.Cu")
		(net "CLK_100M_CPU0_CLK03_DP")
	)
	(segment
		(start 423.77868 -19.613372)
		(end 423.422064 -18.751804)
		(width 0.12954)
		(layer "B.Cu")
		(net "CLK_100M_CPU0_CLK03_DP")
	)
	(segment
		(start 423.62882 -20.173442)
		(end 423.77868 -19.811492)
		(width 0.12954)
		(layer "B.Cu")
		(net "CLK_100M_CPU0_CLK03_DP")
	)
	(segment
		(start 422.950386 -9.292844)
		(end 422.950386 -8.538464)
		(width 0.12954)
		(layer "B.Cu")
		(net "CLK_100M_CPU0_CLK03_DP")
	)
	(segment
		(start 423.422064 -18.751804)
		(end 423.171112 -18.376646)
		(width 0.12954)
		(layer "B.Cu")
		(net "CLK_100M_CPU0_CLK03_DP")
	)
	(segment
		(start 422.950386 -8.538464)
		(end 423.120312 -8.368538)
		(width 0.12954)
		(layer "B.Cu")
		(net "CLK_100M_CPU0_CLK03_DP")
	)
	(segment
		(start 314.030868 -151.551132)
		(end 314.030868 -144.653)
		(width 0.12954)
		(layer "B.Cu")
		(net "CLK_100M_CPU0_CLK03_DP")
	)
	(segment
		(start 431.850292 -3.631438)
		(end 432.116992 -3.898138)
		(width 0.12954)
		(layer "B.Cu")
		(net "CLK_100M_CPU0_CLK03_DP")
	)
	(segment
		(start 429.24095 -3.821938)
		(end 429.43145 -3.631438)
		(width 0.12954)
		(layer "B.Cu")
		(net "CLK_100M_CPU0_CLK03_DP")
	)
	(segment
		(start 423.140886 -6.808724)
		(end 422.950386 -6.618224)
		(width 0.12954)
		(layer "B.Cu")
		(net "CLK_100M_CPU0_CLK03_DP")
	)
	(segment
		(start 428.85487 -3.821938)
		(end 429.24095 -3.821938)
		(width 0.12954)
		(layer "B.Cu")
		(net "CLK_100M_CPU0_CLK03_DP")
	)
	(segment
		(start 333.22133 -126.80061)
		(end 416.603942 -43.417998)
		(width 0.12954)
		(layer "B.Cu")
		(net "CLK_100M_CPU0_CLK03_DP")
	)
	(segment
		(start 314.221368 -152.894792)
		(end 314.030868 -152.704292)
		(width 0.12954)
		(layer "B.Cu")
		(net "CLK_100M_CPU0_CLK03_DP")
	)
	(segment
		(start 376.324876 -213.726268)
		(end 376.324876 -213.409022)
		(width 0.12954)
		(layer "B.Cu")
		(net "CLK_100M_CPU0_CLK03_DP")
	)
	(segment
		(start 372.606316 -211.477352)
		(end 368.28603 -207.157066)
		(width 0.12954)
		(layer "B.Cu")
		(net "CLK_100M_CPU0_CLK03_DP")
	)
	(segment
		(start 314.030868 -152.704292)
		(end 314.030868 -152.318212)
		(width 0.12954)
		(layer "B.Cu")
		(net "CLK_100M_CPU0_CLK03_DP")
	)
	(segment
		(start 333.95158 -183.465724)
		(end 314.030868 -163.545012)
		(width 0.12954)
		(layer "B.Cu")
		(net "CLK_100M_CPU0_CLK03_DP")
	)
	(segment
		(start 423.120312 -8.368538)
		(end 423.120312 -7.94131)
		(width 0.12954)
		(layer "B.Cu")
		(net "CLK_100M_CPU0_CLK03_DP")
	)
	(segment
		(start 422.950386 -10.062464)
		(end 423.140886 -9.871964)
		(width 0.12954)
		(layer "B.Cu")
		(net "CLK_100M_CPU0_CLK03_DP")
	)
	(segment
		(start 314.221368 -152.127712)
		(end 314.221368 -151.741632)
		(width 0.12954)
		(layer "B.Cu")
		(net "CLK_100M_CPU0_CLK03_DP")
	)
	(segment
		(start 416.603942 -27.19832)
		(end 423.62882 -20.173442)
		(width 0.12954)
		(layer "B.Cu")
		(net "CLK_100M_CPU0_CLK03_DP")
	)
	(segment
		(start 375.137426 -213.09076)
		(end 373.524018 -211.477352)
		(width 0.12954)
		(layer "B.Cu")
		(net "CLK_100M_CPU0_CLK03_DP")
	)
	(segment
		(start 425.551092 -3.631438)
		(end 428.66437 -3.631438)
		(width 0.12954)
		(layer "B.Cu")
		(net "CLK_100M_CPU0_CLK03_DP")
	)
	(segment
		(start 429.43145 -3.631438)
		(end 431.850292 -3.631438)
		(width 0.12954)
		(layer "B.Cu")
		(net "CLK_100M_CPU0_CLK03_DP")
	)
	(segment
		(start 422.950386 -6.232144)
		(end 425.551092 -3.631438)
		(width 0.12954)
		(layer "B.Cu")
		(net "CLK_100M_CPU0_CLK03_DP")
	)
	(segment
		(start 376.722386 -214.123778)
		(end 376.324876 -213.726268)
		(width 0.12954)
		(layer "B.Cu")
		(net "CLK_100M_CPU0_CLK03_DP")
	)
	(segment
		(start 314.030868 -144.653)
		(end 331.883258 -126.80061)
		(width 0.12954)
		(layer "B.Cu")
		(net "CLK_100M_CPU0_CLK03_DP")
	)
	(segment
		(start 422.661588 -17.867122)
		(end 422.661588 -16.826738)
		(width 0.12954)
		(layer "B.Cu")
		(net "CLK_100M_CPU0_CLK03_DP")
	)
	(segment
		(start 423.77868 -19.811492)
		(end 423.77868 -19.613372)
		(width 0.12954)
		(layer "B.Cu")
		(net "CLK_100M_CPU0_CLK03_DP")
	)
	(segment
		(start 314.030868 -154.624532)
		(end 314.221368 -154.434032)
		(width 0.12954)
		(layer "B.Cu")
		(net "CLK_100M_CPU0_CLK03_DP")
	)
	(segment
		(start 333.95158 -184.854596)
		(end 333.95158 -183.465724)
		(width 0.12954)
		(layer "B.Cu")
		(net "CLK_100M_CPU0_CLK03_DP")
	)
	(segment
		(start 376.006614 -213.09076)
		(end 375.137426 -213.09076)
		(width 0.12954)
		(layer "B.Cu")
		(net "CLK_100M_CPU0_CLK03_DP")
	)
	(segment
		(start 314.221368 -151.741632)
		(end 314.030868 -151.551132)
		(width 0.12954)
		(layer "B.Cu")
		(net "CLK_100M_CPU0_CLK03_DP")
	)
	(segment
		(start 422.950386 -7.385304)
		(end 423.140886 -7.194804)
		(width 0.12954)
		(layer "B.Cu")
		(net "CLK_100M_CPU0_CLK03_DP")
	)
	(segment
		(start 314.030868 -152.318212)
		(end 314.221368 -152.127712)
		(width 0.12954)
		(layer "B.Cu")
		(net "CLK_100M_CPU0_CLK03_DP")
	)
	(segment
		(start 368.28603 -207.157066)
		(end 356.25405 -207.157066)
		(width 0.12954)
		(layer "B.Cu")
		(net "CLK_100M_CPU0_CLK03_DP")
	)
	(segment
		(start 422.661588 -16.826738)
		(end 422.950386 -16.53794)
		(width 0.12954)
		(layer "B.Cu")
		(net "CLK_100M_CPU0_CLK03_DP")
	)
	(segment
		(start 314.221368 -154.434032)
		(end 314.221368 -154.047952)
		(width 0.12954)
		(layer "B.Cu")
		(net "CLK_100M_CPU0_CLK03_DP")
	)
	(segment
		(start 422.950386 -7.771384)
		(end 422.950386 -7.385304)
		(width 0.12954)
		(layer "B.Cu")
		(net "CLK_100M_CPU0_CLK03_DP")
	)
	(segment
		(start 314.030868 -163.545012)
		(end 314.030868 -154.624532)
		(width 0.12954)
		(layer "B.Cu")
		(net "CLK_100M_CPU0_CLK03_DP")
	)
	(segment
		(start 423.140886 -7.194804)
		(end 423.140886 -6.808724)
		(width 0.12954)
		(layer "B.Cu")
		(net "CLK_100M_CPU0_CLK03_DP")
	)
	(segment
		(start 422.950386 -16.53794)
		(end 422.950386 -10.062464)
		(width 0.12954)
		(layer "B.Cu")
		(net "CLK_100M_CPU0_CLK03_DP")
	)
	(segment
		(start 314.221368 -154.047952)
		(end 314.030868 -153.857452)
		(width 0.12954)
		(layer "B.Cu")
		(net "CLK_100M_CPU0_CLK03_DP")
	)
	(segment
		(start 423.120312 -7.94131)
		(end 422.950386 -7.771384)
		(width 0.12954)
		(layer "B.Cu")
		(net "CLK_100M_CPU0_CLK03_DP")
	)
	(segment
		(start 432.116992 -6.46176)
		(end 431.846482 -6.73227)
		(width 0.12954)
		(layer "B.Cu")
		(net "CLK_100M_CPU0_CLK03_DP")
	)
	(segment
		(start 314.030868 -153.857452)
		(end 314.030868 -153.471372)
		(width 0.12954)
		(layer "B.Cu")
		(net "CLK_100M_CPU0_CLK03_DP")
	)
	(segment
		(start 416.603942 -43.417998)
		(end 416.603942 -27.19832)
		(width 0.12954)
		(layer "B.Cu")
		(net "CLK_100M_CPU0_CLK03_DP")
	)
	(segment
		(start 373.524018 -211.477352)
		(end 372.606316 -211.477352)
		(width 0.12954)
		(layer "B.Cu")
		(net "CLK_100M_CPU0_CLK03_DP")
	)
	(segment
		(start 423.140886 -9.871964)
		(end 423.140886 -9.483344)
		(width 0.12954)
		(layer "B.Cu")
		(net "CLK_100M_CPU0_CLK03_DP")
	)
	(segment
		(start 432.116992 -3.898138)
		(end 432.116992 -6.46176)
		(width 0.12954)
		(layer "B.Cu")
		(net "CLK_100M_CPU0_CLK03_DP")
	)
	(segment
		(start 432.710082 -6.73227)
		(end 432.419506 -7.022846)
		(width 0.12954)
		(layer "F.Cu")
		(net "CLK_100M_CPU0_CLK03_DN")
	)
	(segment
		(start 432.419506 -7.022846)
		(end 432.419506 -7.624572)
		(width 0.12954)
		(layer "F.Cu")
		(net "CLK_100M_CPU0_CLK03_DN")
	)
	(segment
		(start 432.566826 -7.771892)
		(end 432.566826 -8.320024)
		(width 0.12954)
		(layer "F.Cu")
		(net "CLK_100M_CPU0_CLK03_DN")
	)
	(segment
		(start 432.419506 -7.624572)
		(end 432.566826 -7.771892)
		(width 0.12954)
		(layer "F.Cu")
		(net "CLK_100M_CPU0_CLK03_DN")
	)
	(via
		(at 432.710082 -6.73227)
		(size 0.508)
		(drill 0.254)
		(layers "F.Cu" "B.Cu")
		(net "CLK_100M_CPU0_CLK03_DN")
	)
	(segment
		(start 423.13606 -18.904712)
		(end 423.4561 -19.677634)
		(width 0.12954)
		(layer "B.Cu")
		(net "CLK_100M_CPU0_CLK03_DN")
	)
	(segment
		(start 423.4561 -19.74723)
		(end 423.355008 -19.990562)
		(width 0.12954)
		(layer "B.Cu")
		(net "CLK_100M_CPU0_CLK03_DN")
	)
	(segment
		(start 431.98415 -3.308858)
		(end 425.417234 -3.308858)
		(width 0.12954)
		(layer "B.Cu")
		(net "CLK_100M_CPU0_CLK03_DN")
	)
	(segment
		(start 313.708288 -144.519142)
		(end 313.708288 -163.67887)
		(width 0.12954)
		(layer "B.Cu")
		(net "CLK_100M_CPU0_CLK03_DN")
	)
	(segment
		(start 373.39016 -211.799932)
		(end 375.003568 -213.41334)
		(width 0.12954)
		(layer "B.Cu")
		(net "CLK_100M_CPU0_CLK03_DN")
	)
	(segment
		(start 422.627806 -16.404082)
		(end 422.339008 -16.69288)
		(width 0.12954)
		(layer "B.Cu")
		(net "CLK_100M_CPU0_CLK03_DN")
	)
	(segment
		(start 422.339008 -16.69288)
		(end 422.339008 -18.00098)
		(width 0.12954)
		(layer "B.Cu")
		(net "CLK_100M_CPU0_CLK03_DN")
	)
	(segment
		(start 356.120192 -207.479646)
		(end 368.152172 -207.479646)
		(width 0.12954)
		(layer "B.Cu")
		(net "CLK_100M_CPU0_CLK03_DN")
	)
	(segment
		(start 375.872756 -213.41334)
		(end 376.002296 -213.54288)
		(width 0.12954)
		(layer "B.Cu")
		(net "CLK_100M_CPU0_CLK03_DN")
	)
	(segment
		(start 331.7494 -126.47803)
		(end 313.708288 -144.519142)
		(width 0.12954)
		(layer "B.Cu")
		(net "CLK_100M_CPU0_CLK03_DN")
	)
	(segment
		(start 375.003568 -213.41334)
		(end 375.872756 -213.41334)
		(width 0.12954)
		(layer "B.Cu")
		(net "CLK_100M_CPU0_CLK03_DN")
	)
	(segment
		(start 376.002296 -213.726268)
		(end 375.604786 -214.123778)
		(width 0.12954)
		(layer "B.Cu")
		(net "CLK_100M_CPU0_CLK03_DN")
	)
	(segment
		(start 432.439572 -3.76428)
		(end 431.98415 -3.308858)
		(width 0.12954)
		(layer "B.Cu")
		(net "CLK_100M_CPU0_CLK03_DN")
	)
	(segment
		(start 422.920414 -18.582386)
		(end 423.13606 -18.904712)
		(width 0.12954)
		(layer "B.Cu")
		(net "CLK_100M_CPU0_CLK03_DN")
	)
	(segment
		(start 372.472458 -211.799932)
		(end 373.39016 -211.799932)
		(width 0.12954)
		(layer "B.Cu")
		(net "CLK_100M_CPU0_CLK03_DN")
	)
	(segment
		(start 423.355008 -19.990562)
		(end 416.281362 -27.064462)
		(width 0.12954)
		(layer "B.Cu")
		(net "CLK_100M_CPU0_CLK03_DN")
	)
	(segment
		(start 423.4561 -19.677634)
		(end 423.4561 -19.74723)
		(width 0.12954)
		(layer "B.Cu")
		(net "CLK_100M_CPU0_CLK03_DN")
	)
	(segment
		(start 432.439572 -6.46176)
		(end 432.439572 -3.76428)
		(width 0.12954)
		(layer "B.Cu")
		(net "CLK_100M_CPU0_CLK03_DN")
	)
	(segment
		(start 368.152172 -207.479646)
		(end 372.472458 -211.799932)
		(width 0.12954)
		(layer "B.Cu")
		(net "CLK_100M_CPU0_CLK03_DN")
	)
	(segment
		(start 333.087472 -126.47803)
		(end 331.7494 -126.47803)
		(width 0.12954)
		(layer "B.Cu")
		(net "CLK_100M_CPU0_CLK03_DN")
	)
	(segment
		(start 416.281362 -27.064462)
		(end 416.281362 -43.28414)
		(width 0.12954)
		(layer "B.Cu")
		(net "CLK_100M_CPU0_CLK03_DN")
	)
	(segment
		(start 333.629 -184.988454)
		(end 356.120192 -207.479646)
		(width 0.12954)
		(layer "B.Cu")
		(net "CLK_100M_CPU0_CLK03_DN")
	)
	(segment
		(start 416.281362 -43.28414)
		(end 333.087472 -126.47803)
		(width 0.12954)
		(layer "B.Cu")
		(net "CLK_100M_CPU0_CLK03_DN")
	)
	(segment
		(start 313.708288 -163.67887)
		(end 333.629 -183.599582)
		(width 0.12954)
		(layer "B.Cu")
		(net "CLK_100M_CPU0_CLK03_DN")
	)
	(segment
		(start 333.629 -183.599582)
		(end 333.629 -184.988454)
		(width 0.12954)
		(layer "B.Cu")
		(net "CLK_100M_CPU0_CLK03_DN")
	)
	(segment
		(start 376.002296 -213.54288)
		(end 376.002296 -213.726268)
		(width 0.12954)
		(layer "B.Cu")
		(net "CLK_100M_CPU0_CLK03_DN")
	)
	(segment
		(start 422.627806 -6.098286)
		(end 422.627806 -16.404082)
		(width 0.12954)
		(layer "B.Cu")
		(net "CLK_100M_CPU0_CLK03_DN")
	)
	(segment
		(start 425.417234 -3.308858)
		(end 422.627806 -6.098286)
		(width 0.12954)
		(layer "B.Cu")
		(net "CLK_100M_CPU0_CLK03_DN")
	)
	(segment
		(start 422.339008 -18.00098)
		(end 422.920414 -18.582386)
		(width 0.12954)
		(layer "B.Cu")
		(net "CLK_100M_CPU0_CLK03_DN")
	)
	(segment
		(start 432.710082 -6.73227)
		(end 432.439572 -6.46176)
		(width 0.12954)
		(layer "B.Cu")
		(net "CLK_100M_CPU0_CLK03_DN")
	)
	(segment
		(start 389.798052 -222.880174)
		(end 390.264904 -222.614236)
		(width 0.12954)
		(layer "F.Cu")
		(net "CLK_100M_CPU0_CLK02_R_DP")
	)
	(via
		(at 390.264904 -222.614236)
		(size 0.4064)
		(drill 0.2032)
		(layers "F.Cu" "B.Cu")
		(net "CLK_100M_CPU0_CLK02_R_DP")
	)
	(segment
		(start 389.686292 -221.185486)
		(end 385.143502 -216.642696)
		(width 0.12954)
		(layer "B.Cu")
		(net "CLK_100M_CPU0_CLK02_R_DP")
	)
	(segment
		(start 384.185668 -215.684862)
		(end 382.718056 -215.684862)
		(width 0.12954)
		(layer "B.Cu")
		(net "CLK_100M_CPU0_CLK02_R_DP")
	)
	(segment
		(start 382.527556 -215.494362)
		(end 382.141476 -215.494362)
		(width 0.12954)
		(layer "B.Cu")
		(net "CLK_100M_CPU0_CLK02_R_DP")
	)
	(segment
		(start 389.845042 -222.725742)
		(end 389.686546 -222.633794)
		(width 0.12954)
		(layer "B.Cu")
		(net "CLK_100M_CPU0_CLK02_R_DP")
	)
	(segment
		(start 384.600958 -216.100152)
		(end 384.185668 -215.684862)
		(width 0.12954)
		(layer "B.Cu")
		(net "CLK_100M_CPU0_CLK02_R_DP")
	)
	(segment
		(start 385.143502 -216.373456)
		(end 384.870198 -216.100152)
		(width 0.12954)
		(layer "B.Cu")
		(net "CLK_100M_CPU0_CLK02_R_DP")
	)
	(segment
		(start 382.718056 -215.684862)
		(end 382.527556 -215.494362)
		(width 0.12954)
		(layer "B.Cu")
		(net "CLK_100M_CPU0_CLK02_R_DP")
	)
	(segment
		(start 390.264904 -222.614236)
		(end 389.845042 -222.725742)
		(width 0.12954)
		(layer "B.Cu")
		(net "CLK_100M_CPU0_CLK02_R_DP")
	)
	(segment
		(start 382.141476 -215.494362)
		(end 381.950976 -215.684862)
		(width 0.12954)
		(layer "B.Cu")
		(net "CLK_100M_CPU0_CLK02_R_DP")
	)
	(segment
		(start 380.756668 -215.555322)
		(end 380.756668 -215.359996)
		(width 0.12954)
		(layer "B.Cu")
		(net "CLK_100M_CPU0_CLK02_R_DP")
	)
	(segment
		(start 381.950976 -215.684862)
		(end 380.886208 -215.684862)
		(width 0.12954)
		(layer "B.Cu")
		(net "CLK_100M_CPU0_CLK02_R_DP")
	)
	(segment
		(start 380.756668 -215.359996)
		(end 381.192786 -214.923878)
		(width 0.12954)
		(layer "B.Cu")
		(net "CLK_100M_CPU0_CLK02_R_DP")
	)
	(segment
		(start 389.686292 -222.63354)
		(end 389.686292 -221.185486)
		(width 0.12954)
		(layer "B.Cu")
		(net "CLK_100M_CPU0_CLK02_R_DP")
	)
	(segment
		(start 389.686546 -222.633794)
		(end 389.686292 -222.63354)
		(width 0.12954)
		(layer "B.Cu")
		(net "CLK_100M_CPU0_CLK02_R_DP")
	)
	(segment
		(start 380.886208 -215.684862)
		(end 380.756668 -215.555322)
		(width 0.12954)
		(layer "B.Cu")
		(net "CLK_100M_CPU0_CLK02_R_DP")
	)
	(segment
		(start 384.870198 -216.100152)
		(end 384.600958 -216.100152)
		(width 0.12954)
		(layer "B.Cu")
		(net "CLK_100M_CPU0_CLK02_R_DP")
	)
	(segment
		(start 385.143502 -216.642696)
		(end 385.143502 -216.373456)
		(width 0.12954)
		(layer "B.Cu")
		(net "CLK_100M_CPU0_CLK02_R_DP")
	)
	(segment
		(start 389.327898 -223.69018)
		(end 389.79475 -223.424242)
		(width 0.12954)
		(layer "F.Cu")
		(net "CLK_100M_CPU0_CLK02_R_DN")
	)
	(via
		(at 389.79475 -223.424242)
		(size 0.4064)
		(drill 0.2032)
		(layers "F.Cu" "B.Cu")
		(net "CLK_100M_CPU0_CLK02_R_DN")
	)
	(segment
		(start 389.363712 -221.319344)
		(end 384.05181 -216.007442)
		(width 0.12954)
		(layer "B.Cu")
		(net "CLK_100M_CPU0_CLK02_R_DN")
	)
	(segment
		(start 380.434088 -215.28278)
		(end 380.075186 -214.923878)
		(width 0.12954)
		(layer "B.Cu")
		(net "CLK_100M_CPU0_CLK02_R_DN")
	)
	(segment
		(start 384.05181 -216.007442)
		(end 380.75235 -216.007442)
		(width 0.12954)
		(layer "B.Cu")
		(net "CLK_100M_CPU0_CLK02_R_DN")
	)
	(segment
		(start 389.79475 -223.424242)
		(end 389.683752 -223.005396)
		(width 0.12954)
		(layer "B.Cu")
		(net "CLK_100M_CPU0_CLK02_R_DN")
	)
	(segment
		(start 380.434088 -215.68918)
		(end 380.434088 -215.28278)
		(width 0.12954)
		(layer "B.Cu")
		(net "CLK_100M_CPU0_CLK02_R_DN")
	)
	(segment
		(start 389.488172 -222.891858)
		(end 389.363712 -222.767398)
		(width 0.12954)
		(layer "B.Cu")
		(net "CLK_100M_CPU0_CLK02_R_DN")
	)
	(segment
		(start 389.683752 -223.005396)
		(end 389.68299 -223.004888)
		(width 0.12954)
		(layer "B.Cu")
		(net "CLK_100M_CPU0_CLK02_R_DN")
	)
	(segment
		(start 389.363712 -222.767398)
		(end 389.363712 -221.319344)
		(width 0.12954)
		(layer "B.Cu")
		(net "CLK_100M_CPU0_CLK02_R_DN")
	)
	(segment
		(start 389.68299 -223.004888)
		(end 389.488172 -222.891858)
		(width 0.12954)
		(layer "B.Cu")
		(net "CLK_100M_CPU0_CLK02_R_DN")
	)
	(segment
		(start 380.75235 -216.007442)
		(end 380.434088 -215.68918)
		(width 0.12954)
		(layer "B.Cu")
		(net "CLK_100M_CPU0_CLK02_R_DN")
	)
	(segment
		(start 431.966878 -11.814048)
		(end 432.105562 -11.952732)
		(width 0.12954)
		(layer "F.Cu")
		(net "CLK_100M_CPU0_CLK02_DP")
	)
	(segment
		(start 431.966878 -11.26998)
		(end 431.966878 -11.814048)
		(width 0.12954)
		(layer "F.Cu")
		(net "CLK_100M_CPU0_CLK02_DP")
	)
	(segment
		(start 432.105562 -11.952732)
		(end 432.105562 -12.593828)
		(width 0.12954)
		(layer "F.Cu")
		(net "CLK_100M_CPU0_CLK02_DP")
	)
	(segment
		(start 432.105562 -12.593828)
		(end 431.834544 -12.864846)
		(width 0.12954)
		(layer "F.Cu")
		(net "CLK_100M_CPU0_CLK02_DP")
	)
	(via
		(at 431.834544 -12.864846)
		(size 0.508)
		(drill 0.254)
		(layers "F.Cu" "B.Cu")
		(net "CLK_100M_CPU0_CLK02_DP")
	)
	(segment
		(start 316.3951 -155.509214)
		(end 316.5856 -155.318714)
		(width 0.12954)
		(layer "B.Cu")
		(net "CLK_100M_CPU0_CLK02_DP")
	)
	(segment
		(start 374.43537 -209.557112)
		(end 373.402352 -209.557112)
		(width 0.12954)
		(layer "B.Cu")
		(net "CLK_100M_CPU0_CLK02_DP")
	)
	(segment
		(start 435.111652 -19.250406)
		(end 435.111652 -17.598898)
		(width 0.12954)
		(layer "B.Cu")
		(net "CLK_100M_CPU0_CLK02_DP")
	)
	(segment
		(start 316.3951 -154.356054)
		(end 316.5856 -154.165554)
		(width 0.12954)
		(layer "B.Cu")
		(net "CLK_100M_CPU0_CLK02_DP")
	)
	(segment
		(start 336.04708 -183.985916)
		(end 336.04708 -182.597044)
		(width 0.12954)
		(layer "B.Cu")
		(net "CLK_100M_CPU0_CLK02_DP")
	)
	(segment
		(start 316.3951 -153.202894)
		(end 316.5856 -153.012394)
		(width 0.12954)
		(layer "B.Cu")
		(net "CLK_100M_CPU0_CLK02_DP")
	)
	(segment
		(start 316.3951 -145.307812)
		(end 332.363064 -129.339848)
		(width 0.12954)
		(layer "B.Cu")
		(net "CLK_100M_CPU0_CLK02_DP")
	)
	(segment
		(start 380.795276 -212.709252)
		(end 379.161294 -211.07527)
		(width 0.12954)
		(layer "B.Cu")
		(net "CLK_100M_CPU0_CLK02_DP")
	)
	(segment
		(start 316.5856 -155.318714)
		(end 316.5856 -154.932634)
		(width 0.12954)
		(layer "B.Cu")
		(net "CLK_100M_CPU0_CLK02_DP")
	)
	(segment
		(start 433.774088 -16.261334)
		(end 433.501292 -15.988538)
		(width 0.12954)
		(layer "B.Cu")
		(net "CLK_100M_CPU0_CLK02_DP")
	)
	(segment
		(start 427.496224 -23.445978)
		(end 429.846486 -21.095716)
		(width 0.12954)
		(layer "B.Cu")
		(net "CLK_100M_CPU0_CLK02_DP")
	)
	(segment
		(start 316.3951 -152.049734)
		(end 316.5856 -151.859234)
		(width 0.12954)
		(layer "B.Cu")
		(net "CLK_100M_CPU0_CLK02_DP")
	)
	(segment
		(start 316.5856 -153.012394)
		(end 316.5856 -152.626314)
		(width 0.12954)
		(layer "B.Cu")
		(net "CLK_100M_CPU0_CLK02_DP")
	)
	(segment
		(start 316.3951 -151.282654)
		(end 316.3951 -145.307812)
		(width 0.12954)
		(layer "B.Cu")
		(net "CLK_100M_CPU0_CLK02_DP")
	)
	(segment
		(start 432.105054 -12.594336)
		(end 431.834544 -12.864846)
		(width 0.12954)
		(layer "B.Cu")
		(net "CLK_100M_CPU0_CLK02_DP")
	)
	(segment
		(start 316.5856 -152.626314)
		(end 316.3951 -152.435814)
		(width 0.12954)
		(layer "B.Cu")
		(net "CLK_100M_CPU0_CLK02_DP")
	)
	(segment
		(start 432.958494 -15.44574)
		(end 432.685698 -15.172944)
		(width 0.12954)
		(layer "B.Cu")
		(net "CLK_100M_CPU0_CLK02_DP")
	)
	(segment
		(start 381.192786 -214.123778)
		(end 380.795276 -213.726268)
		(width 0.12954)
		(layer "B.Cu")
		(net "CLK_100M_CPU0_CLK02_DP")
	)
	(segment
		(start 434.043582 -16.261334)
		(end 433.774088 -16.261334)
		(width 0.12954)
		(layer "B.Cu")
		(net "CLK_100M_CPU0_CLK02_DP")
	)
	(segment
		(start 316.3951 -162.945064)
		(end 316.3951 -155.509214)
		(width 0.12954)
		(layer "B.Cu")
		(net "CLK_100M_CPU0_CLK02_DP")
	)
	(segment
		(start 432.105054 -11.682984)
		(end 432.105054 -12.594336)
		(width 0.12954)
		(layer "B.Cu")
		(net "CLK_100M_CPU0_CLK02_DP")
	)
	(segment
		(start 432.412394 -14.630146)
		(end 432.1429 -14.630146)
		(width 0.12954)
		(layer "B.Cu")
		(net "CLK_100M_CPU0_CLK02_DP")
	)
	(segment
		(start 316.5856 -154.932634)
		(end 316.3951 -154.742134)
		(width 0.12954)
		(layer "B.Cu")
		(net "CLK_100M_CPU0_CLK02_DP")
	)
	(segment
		(start 432.1429 -14.630146)
		(end 430.892458 -13.379704)
		(width 0.12954)
		(layer "B.Cu")
		(net "CLK_100M_CPU0_CLK02_DP")
	)
	(segment
		(start 424.680888 -23.445978)
		(end 427.496224 -23.445978)
		(width 0.12954)
		(layer "B.Cu")
		(net "CLK_100M_CPU0_CLK02_DP")
	)
	(segment
		(start 434.316886 -16.534638)
		(end 434.043582 -16.261334)
		(width 0.12954)
		(layer "B.Cu")
		(net "CLK_100M_CPU0_CLK02_DP")
	)
	(segment
		(start 316.5856 -153.779474)
		(end 316.3951 -153.588974)
		(width 0.12954)
		(layer "B.Cu")
		(net "CLK_100M_CPU0_CLK02_DP")
	)
	(segment
		(start 375.953528 -211.07527)
		(end 374.43537 -209.557112)
		(width 0.12954)
		(layer "B.Cu")
		(net "CLK_100M_CPU0_CLK02_DP")
	)
	(segment
		(start 433.227988 -15.44574)
		(end 432.958494 -15.44574)
		(width 0.12954)
		(layer "B.Cu")
		(net "CLK_100M_CPU0_CLK02_DP")
	)
	(segment
		(start 431.87493 -11.45286)
		(end 432.105054 -11.682984)
		(width 0.12954)
		(layer "B.Cu")
		(net "CLK_100M_CPU0_CLK02_DP")
	)
	(segment
		(start 316.3951 -152.435814)
		(end 316.3951 -152.049734)
		(width 0.12954)
		(layer "B.Cu")
		(net "CLK_100M_CPU0_CLK02_DP")
	)
	(segment
		(start 333.646272 -129.339848)
		(end 418.699442 -44.286678)
		(width 0.12954)
		(layer "B.Cu")
		(net "CLK_100M_CPU0_CLK02_DP")
	)
	(segment
		(start 316.5856 -151.859234)
		(end 316.5856 -151.473154)
		(width 0.12954)
		(layer "B.Cu")
		(net "CLK_100M_CPU0_CLK02_DP")
	)
	(segment
		(start 430.892458 -13.379704)
		(end 430.892458 -11.741912)
		(width 0.12954)
		(layer "B.Cu")
		(net "CLK_100M_CPU0_CLK02_DP")
	)
	(segment
		(start 418.699442 -44.286678)
		(end 418.699442 -29.427424)
		(width 0.12954)
		(layer "B.Cu")
		(net "CLK_100M_CPU0_CLK02_DP")
	)
	(segment
		(start 432.685698 -14.90345)
		(end 432.412394 -14.630146)
		(width 0.12954)
		(layer "B.Cu")
		(net "CLK_100M_CPU0_CLK02_DP")
	)
	(segment
		(start 432.685698 -15.172944)
		(end 432.685698 -14.90345)
		(width 0.12954)
		(layer "B.Cu")
		(net "CLK_100M_CPU0_CLK02_DP")
	)
	(segment
		(start 379.161294 -211.07527)
		(end 375.953528 -211.07527)
		(width 0.12954)
		(layer "B.Cu")
		(net "CLK_100M_CPU0_CLK02_DP")
	)
	(segment
		(start 336.04708 -182.597044)
		(end 316.3951 -162.945064)
		(width 0.12954)
		(layer "B.Cu")
		(net "CLK_100M_CPU0_CLK02_DP")
	)
	(segment
		(start 430.892458 -11.741912)
		(end 431.18151 -11.45286)
		(width 0.12954)
		(layer "B.Cu")
		(net "CLK_100M_CPU0_CLK02_DP")
	)
	(segment
		(start 316.5856 -151.473154)
		(end 316.3951 -151.282654)
		(width 0.12954)
		(layer "B.Cu")
		(net "CLK_100M_CPU0_CLK02_DP")
	)
	(segment
		(start 316.3951 -154.742134)
		(end 316.3951 -154.356054)
		(width 0.12954)
		(layer "B.Cu")
		(net "CLK_100M_CPU0_CLK02_DP")
	)
	(segment
		(start 373.402352 -209.557112)
		(end 368.906806 -205.061566)
		(width 0.12954)
		(layer "B.Cu")
		(net "CLK_100M_CPU0_CLK02_DP")
	)
	(segment
		(start 435.111652 -17.598898)
		(end 434.316886 -16.804132)
		(width 0.12954)
		(layer "B.Cu")
		(net "CLK_100M_CPU0_CLK02_DP")
	)
	(segment
		(start 433.501292 -15.719044)
		(end 433.227988 -15.44574)
		(width 0.12954)
		(layer "B.Cu")
		(net "CLK_100M_CPU0_CLK02_DP")
	)
	(segment
		(start 316.5856 -154.165554)
		(end 316.5856 -153.779474)
		(width 0.12954)
		(layer "B.Cu")
		(net "CLK_100M_CPU0_CLK02_DP")
	)
	(segment
		(start 431.18151 -11.45286)
		(end 431.87493 -11.45286)
		(width 0.12954)
		(layer "B.Cu")
		(net "CLK_100M_CPU0_CLK02_DP")
	)
	(segment
		(start 434.316886 -16.804132)
		(end 434.316886 -16.534638)
		(width 0.12954)
		(layer "B.Cu")
		(net "CLK_100M_CPU0_CLK02_DP")
	)
	(segment
		(start 433.501292 -15.988538)
		(end 433.501292 -15.719044)
		(width 0.12954)
		(layer "B.Cu")
		(net "CLK_100M_CPU0_CLK02_DP")
	)
	(segment
		(start 357.12273 -205.061566)
		(end 336.04708 -183.985916)
		(width 0.12954)
		(layer "B.Cu")
		(net "CLK_100M_CPU0_CLK02_DP")
	)
	(segment
		(start 433.266342 -21.095716)
		(end 435.111652 -19.250406)
		(width 0.12954)
		(layer "B.Cu")
		(net "CLK_100M_CPU0_CLK02_DP")
	)
	(segment
		(start 316.3951 -153.588974)
		(end 316.3951 -153.202894)
		(width 0.12954)
		(layer "B.Cu")
		(net "CLK_100M_CPU0_CLK02_DP")
	)
	(segment
		(start 429.846486 -21.095716)
		(end 433.266342 -21.095716)
		(width 0.12954)
		(layer "B.Cu")
		(net "CLK_100M_CPU0_CLK02_DP")
	)
	(segment
		(start 332.363064 -129.339848)
		(end 333.646272 -129.339848)
		(width 0.12954)
		(layer "B.Cu")
		(net "CLK_100M_CPU0_CLK02_DP")
	)
	(segment
		(start 418.699442 -29.427424)
		(end 424.680888 -23.445978)
		(width 0.12954)
		(layer "B.Cu")
		(net "CLK_100M_CPU0_CLK02_DP")
	)
	(segment
		(start 368.906806 -205.061566)
		(end 357.12273 -205.061566)
		(width 0.12954)
		(layer "B.Cu")
		(net "CLK_100M_CPU0_CLK02_DP")
	)
	(segment
		(start 380.795276 -213.726268)
		(end 380.795276 -212.709252)
		(width 0.12954)
		(layer "B.Cu")
		(net "CLK_100M_CPU0_CLK02_DP")
	)
	(segment
		(start 432.428142 -11.984228)
		(end 432.566826 -11.845544)
		(width 0.12954)
		(layer "F.Cu")
		(net "CLK_100M_CPU0_CLK02_DN")
	)
	(segment
		(start 432.698144 -12.864846)
		(end 432.428142 -12.594844)
		(width 0.12954)
		(layer "F.Cu")
		(net "CLK_100M_CPU0_CLK02_DN")
	)
	(segment
		(start 432.566826 -11.845544)
		(end 432.566826 -11.26998)
		(width 0.12954)
		(layer "F.Cu")
		(net "CLK_100M_CPU0_CLK02_DN")
	)
	(segment
		(start 432.428142 -12.594844)
		(end 432.428142 -11.984228)
		(width 0.12954)
		(layer "F.Cu")
		(net "CLK_100M_CPU0_CLK02_DN")
	)
	(via
		(at 432.698144 -12.864846)
		(size 0.508)
		(drill 0.254)
		(layers "F.Cu" "B.Cu")
		(net "CLK_100M_CPU0_CLK02_DN")
	)
	(segment
		(start 418.376862 -29.293566)
		(end 424.54703 -23.123398)
		(width 0.12954)
		(layer "B.Cu")
		(net "CLK_100M_CPU0_CLK02_DN")
	)
	(segment
		(start 429.712628 -20.773136)
		(end 433.132484 -20.773136)
		(width 0.12954)
		(layer "B.Cu")
		(net "CLK_100M_CPU0_CLK02_DN")
	)
	(segment
		(start 434.789072 -19.116548)
		(end 434.789072 -17.732756)
		(width 0.12954)
		(layer "B.Cu")
		(net "CLK_100M_CPU0_CLK02_DN")
	)
	(segment
		(start 430.569878 -13.513562)
		(end 430.569878 -11.608054)
		(width 0.12954)
		(layer "B.Cu")
		(net "CLK_100M_CPU0_CLK02_DN")
	)
	(segment
		(start 433.132484 -20.773136)
		(end 434.789072 -19.116548)
		(width 0.12954)
		(layer "B.Cu")
		(net "CLK_100M_CPU0_CLK02_DN")
	)
	(segment
		(start 432.427634 -11.549126)
		(end 432.427634 -12.594336)
		(width 0.12954)
		(layer "B.Cu")
		(net "CLK_100M_CPU0_CLK02_DN")
	)
	(segment
		(start 374.301512 -209.879692)
		(end 373.268494 -209.879692)
		(width 0.12954)
		(layer "B.Cu")
		(net "CLK_100M_CPU0_CLK02_DN")
	)
	(segment
		(start 368.772948 -205.384146)
		(end 356.988872 -205.384146)
		(width 0.12954)
		(layer "B.Cu")
		(net "CLK_100M_CPU0_CLK02_DN")
	)
	(segment
		(start 335.7245 -184.119774)
		(end 335.7245 -182.730902)
		(width 0.12954)
		(layer "B.Cu")
		(net "CLK_100M_CPU0_CLK02_DN")
	)
	(segment
		(start 431.047652 -11.13028)
		(end 432.008788 -11.13028)
		(width 0.12954)
		(layer "B.Cu")
		(net "CLK_100M_CPU0_CLK02_DN")
	)
	(segment
		(start 333.512414 -129.017268)
		(end 418.376862 -44.15282)
		(width 0.12954)
		(layer "B.Cu")
		(net "CLK_100M_CPU0_CLK02_DN")
	)
	(segment
		(start 434.789072 -17.732756)
		(end 430.569878 -13.513562)
		(width 0.12954)
		(layer "B.Cu")
		(net "CLK_100M_CPU0_CLK02_DN")
	)
	(segment
		(start 430.569878 -11.608054)
		(end 431.047652 -11.13028)
		(width 0.12954)
		(layer "B.Cu")
		(net "CLK_100M_CPU0_CLK02_DN")
	)
	(segment
		(start 356.988872 -205.384146)
		(end 335.7245 -184.119774)
		(width 0.12954)
		(layer "B.Cu")
		(net "CLK_100M_CPU0_CLK02_DN")
	)
	(segment
		(start 418.376862 -44.15282)
		(end 418.376862 -29.293566)
		(width 0.12954)
		(layer "B.Cu")
		(net "CLK_100M_CPU0_CLK02_DN")
	)
	(segment
		(start 375.81967 -211.39785)
		(end 374.301512 -209.879692)
		(width 0.12954)
		(layer "B.Cu")
		(net "CLK_100M_CPU0_CLK02_DN")
	)
	(segment
		(start 316.07252 -145.173954)
		(end 332.229206 -129.017268)
		(width 0.12954)
		(layer "B.Cu")
		(net "CLK_100M_CPU0_CLK02_DN")
	)
	(segment
		(start 380.472696 -213.726268)
		(end 380.472696 -212.84311)
		(width 0.12954)
		(layer "B.Cu")
		(net "CLK_100M_CPU0_CLK02_DN")
	)
	(segment
		(start 424.54703 -23.123398)
		(end 427.362366 -23.123398)
		(width 0.12954)
		(layer "B.Cu")
		(net "CLK_100M_CPU0_CLK02_DN")
	)
	(segment
		(start 373.268494 -209.879692)
		(end 368.772948 -205.384146)
		(width 0.12954)
		(layer "B.Cu")
		(net "CLK_100M_CPU0_CLK02_DN")
	)
	(segment
		(start 380.075186 -214.123778)
		(end 380.472696 -213.726268)
		(width 0.12954)
		(layer "B.Cu")
		(net "CLK_100M_CPU0_CLK02_DN")
	)
	(segment
		(start 335.7245 -182.730902)
		(end 316.07252 -163.078922)
		(width 0.12954)
		(layer "B.Cu")
		(net "CLK_100M_CPU0_CLK02_DN")
	)
	(segment
		(start 379.027436 -211.39785)
		(end 375.81967 -211.39785)
		(width 0.12954)
		(layer "B.Cu")
		(net "CLK_100M_CPU0_CLK02_DN")
	)
	(segment
		(start 432.427634 -12.594336)
		(end 432.698144 -12.864846)
		(width 0.12954)
		(layer "B.Cu")
		(net "CLK_100M_CPU0_CLK02_DN")
	)
	(segment
		(start 432.008788 -11.13028)
		(end 432.427634 -11.549126)
		(width 0.12954)
		(layer "B.Cu")
		(net "CLK_100M_CPU0_CLK02_DN")
	)
	(segment
		(start 316.07252 -163.078922)
		(end 316.07252 -145.173954)
		(width 0.12954)
		(layer "B.Cu")
		(net "CLK_100M_CPU0_CLK02_DN")
	)
	(segment
		(start 380.472696 -212.84311)
		(end 379.027436 -211.39785)
		(width 0.12954)
		(layer "B.Cu")
		(net "CLK_100M_CPU0_CLK02_DN")
	)
	(segment
		(start 332.229206 -129.017268)
		(end 333.512414 -129.017268)
		(width 0.12954)
		(layer "B.Cu")
		(net "CLK_100M_CPU0_CLK02_DN")
	)
	(segment
		(start 427.362366 -23.123398)
		(end 429.712628 -20.773136)
		(width 0.12954)
		(layer "B.Cu")
		(net "CLK_100M_CPU0_CLK02_DN")
	)
	(segment
		(start 387.448044 -222.070168)
		(end 387.914896 -221.80423)
		(width 0.12954)
		(layer "F.Cu")
		(net "CLK_100M_CPU0_CLK01_R_DP")
	)
	(via
		(at 387.914896 -221.80423)
		(size 0.4064)
		(drill 0.2032)
		(layers "F.Cu" "B.Cu")
		(net "CLK_100M_CPU0_CLK01_R_DP")
	)
	(segment
		(start 375.69775 -219.523564)
		(end 375.42851 -219.254324)
		(width 0.12954)
		(layer "B.Cu")
		(net "CLK_100M_CPU0_CLK01_R_DP")
	)
	(segment
		(start 381.84201 -222.794576)
		(end 381.302006 -222.254572)
		(width 0.12954)
		(layer "B.Cu")
		(net "CLK_100M_CPU0_CLK01_R_DP")
	)
	(segment
		(start 374.623838 -218.449652)
		(end 374.623838 -218.183968)
		(width 0.12954)
		(layer "B.Cu")
		(net "CLK_100M_CPU0_CLK01_R_DP")
	)
	(segment
		(start 373.276368 -217.102182)
		(end 373.003572 -216.829386)
		(width 0.12954)
		(layer "B.Cu")
		(net "CLK_100M_CPU0_CLK01_R_DP")
	)
	(segment
		(start 388.11073 -222.121476)
		(end 388.10946 -222.122238)
		(width 0.0762)
		(layer "B.Cu")
		(net "CLK_100M_CPU0_CLK01_R_DP")
	)
	(segment
		(start 382.044448 -222.794576)
		(end 382.025398 -222.794576)
		(width 0.0762)
		(layer "B.Cu")
		(net "CLK_100M_CPU0_CLK01_R_DP")
	)
	(segment
		(start 374.893078 -218.718892)
		(end 374.623838 -218.449652)
		(width 0.12954)
		(layer "B.Cu")
		(net "CLK_100M_CPU0_CLK01_R_DP")
	)
	(segment
		(start 379.809756 -221.895924)
		(end 378.07011 -221.895924)
		(width 0.12954)
		(layer "B.Cu")
		(net "CLK_100M_CPU0_CLK01_R_DP")
	)
	(segment
		(start 371.826536 -215.349328)
		(end 372.251986 -214.923878)
		(width 0.12954)
		(layer "B.Cu")
		(net "CLK_100M_CPU0_CLK01_R_DP")
	)
	(segment
		(start 383.967736 -223.746822)
		(end 383.937256 -223.729042)
		(width 0.0762)
		(layer "B.Cu")
		(net "CLK_100M_CPU0_CLK01_R_DP")
	)
	(segment
		(start 373.819166 -217.64498)
		(end 373.819166 -217.375486)
		(width 0.12954)
		(layer "B.Cu")
		(net "CLK_100M_CPU0_CLK01_R_DP")
	)
	(segment
		(start 382.025398 -222.794576)
		(end 381.84201 -222.794576)
		(width 0.12954)
		(layer "B.Cu")
		(net "CLK_100M_CPU0_CLK01_R_DP")
	)
	(segment
		(start 388.10184 -222.12681)
		(end 388.062724 -222.14967)
		(width 0.0762)
		(layer "B.Cu")
		(net "CLK_100M_CPU0_CLK01_R_DP")
	)
	(segment
		(start 374.354344 -217.91422)
		(end 374.088406 -217.91422)
		(width 0.12954)
		(layer "B.Cu")
		(net "CLK_100M_CPU0_CLK01_R_DP")
	)
	(segment
		(start 373.819166 -217.375486)
		(end 373.545862 -217.102182)
		(width 0.12954)
		(layer "B.Cu")
		(net "CLK_100M_CPU0_CLK01_R_DP")
	)
	(segment
		(start 383.536952 -222.959676)
		(end 383.498852 -222.937324)
		(width 0.0762)
		(layer "B.Cu")
		(net "CLK_100M_CPU0_CLK01_R_DP")
	)
	(segment
		(start 381.302006 -222.254572)
		(end 380.168404 -222.254572)
		(width 0.12954)
		(layer "B.Cu")
		(net "CLK_100M_CPU0_CLK01_R_DP")
	)
	(segment
		(start 372.460774 -216.286588)
		(end 371.826536 -215.65235)
		(width 0.12954)
		(layer "B.Cu")
		(net "CLK_100M_CPU0_CLK01_R_DP")
	)
	(segment
		(start 388.10946 -222.122238)
		(end 388.108698 -222.122746)
		(width 0.0762)
		(layer "B.Cu")
		(net "CLK_100M_CPU0_CLK01_R_DP")
	)
	(segment
		(start 382.372616 -222.871792)
		(end 382.297178 -222.860616)
		(width 0.0762)
		(layer "B.Cu")
		(net "CLK_100M_CPU0_CLK01_R_DP")
	)
	(segment
		(start 387.193536 -223.728534)
		(end 387.161786 -223.746822)
		(width 0.0762)
		(layer "B.Cu")
		(net "CLK_100M_CPU0_CLK01_R_DP")
	)
	(segment
		(start 388.13359 -222.108522)
		(end 388.115556 -222.118936)
		(width 0.0762)
		(layer "B.Cu")
		(net "CLK_100M_CPU0_CLK01_R_DP")
	)
	(segment
		(start 387.914896 -221.80423)
		(end 388.228586 -221.80423)
		(width 0.0762)
		(layer "B.Cu")
		(net "CLK_100M_CPU0_CLK01_R_DP")
	)
	(segment
		(start 374.623838 -218.183968)
		(end 374.354344 -217.91422)
		(width 0.12954)
		(layer "B.Cu")
		(net "CLK_100M_CPU0_CLK01_R_DP")
	)
	(segment
		(start 373.003572 -216.829386)
		(end 373.003572 -216.559892)
		(width 0.12954)
		(layer "B.Cu")
		(net "CLK_100M_CPU0_CLK01_R_DP")
	)
	(segment
		(start 371.826536 -215.65235)
		(end 371.826536 -215.349328)
		(width 0.12954)
		(layer "B.Cu")
		(net "CLK_100M_CPU0_CLK01_R_DP")
	)
	(segment
		(start 388.228586 -221.80423)
		(end 388.285228 -221.860872)
		(width 0.0762)
		(layer "B.Cu")
		(net "CLK_100M_CPU0_CLK01_R_DP")
	)
	(segment
		(start 384.916172 -223.751648)
		(end 384.909822 -223.748092)
		(width 0.0762)
		(layer "B.Cu")
		(net "CLK_100M_CPU0_CLK01_R_DP")
	)
	(segment
		(start 384.339846 -223.748092)
		(end 384.333496 -223.751648)
		(width 0.0762)
		(layer "B.Cu")
		(net "CLK_100M_CPU0_CLK01_R_DP")
	)
	(segment
		(start 388.115556 -222.118936)
		(end 388.112254 -222.120714)
		(width 0.0762)
		(layer "B.Cu")
		(net "CLK_100M_CPU0_CLK01_R_DP")
	)
	(segment
		(start 387.66242 -222.919036)
		(end 387.63194 -222.936816)
		(width 0.0762)
		(layer "B.Cu")
		(net "CLK_100M_CPU0_CLK01_R_DP")
	)
	(segment
		(start 378.07011 -221.895924)
		(end 376.233182 -220.058996)
		(width 0.12954)
		(layer "B.Cu")
		(net "CLK_100M_CPU0_CLK01_R_DP")
	)
	(segment
		(start 388.112254 -222.120714)
		(end 388.11073 -222.121476)
		(width 0.0762)
		(layer "B.Cu")
		(net "CLK_100M_CPU0_CLK01_R_DP")
	)
	(segment
		(start 385.847844 -223.746822)
		(end 385.833112 -223.738186)
		(width 0.0762)
		(layer "B.Cu")
		(net "CLK_100M_CPU0_CLK01_R_DP")
	)
	(segment
		(start 383.498852 -222.937324)
		(end 383.497836 -222.936816)
		(width 0.0762)
		(layer "B.Cu")
		(net "CLK_100M_CPU0_CLK01_R_DP")
	)
	(segment
		(start 376.233182 -219.793312)
		(end 375.963688 -219.523564)
		(width 0.12954)
		(layer "B.Cu")
		(net "CLK_100M_CPU0_CLK01_R_DP")
	)
	(segment
		(start 375.42851 -219.254324)
		(end 375.42851 -218.98864)
		(width 0.12954)
		(layer "B.Cu")
		(net "CLK_100M_CPU0_CLK01_R_DP")
	)
	(segment
		(start 373.545862 -217.102182)
		(end 373.276368 -217.102182)
		(width 0.12954)
		(layer "B.Cu")
		(net "CLK_100M_CPU0_CLK01_R_DP")
	)
	(segment
		(start 382.297178 -222.860616)
		(end 382.110488 -222.860616)
		(width 0.0762)
		(layer "B.Cu")
		(net "CLK_100M_CPU0_CLK01_R_DP")
	)
	(segment
		(start 376.233182 -220.058996)
		(end 376.233182 -219.793312)
		(width 0.12954)
		(layer "B.Cu")
		(net "CLK_100M_CPU0_CLK01_R_DP")
	)
	(segment
		(start 385.856226 -223.751648)
		(end 385.847844 -223.746822)
		(width 0.0762)
		(layer "B.Cu")
		(net "CLK_100M_CPU0_CLK01_R_DP")
	)
	(segment
		(start 388.105904 -222.12427)
		(end 388.102602 -222.126302)
		(width 0.0762)
		(layer "B.Cu")
		(net "CLK_100M_CPU0_CLK01_R_DP")
	)
	(segment
		(start 372.730268 -216.286588)
		(end 372.460774 -216.286588)
		(width 0.12954)
		(layer "B.Cu")
		(net "CLK_100M_CPU0_CLK01_R_DP")
	)
	(segment
		(start 384.909822 -223.748092)
		(end 384.90779 -223.746822)
		(width 0.0762)
		(layer "B.Cu")
		(net "CLK_100M_CPU0_CLK01_R_DP")
	)
	(segment
		(start 388.108698 -222.122746)
		(end 388.105904 -222.12427)
		(width 0.0762)
		(layer "B.Cu")
		(net "CLK_100M_CPU0_CLK01_R_DP")
	)
	(segment
		(start 375.42851 -218.98864)
		(end 375.159016 -218.718892)
		(width 0.12954)
		(layer "B.Cu")
		(net "CLK_100M_CPU0_CLK01_R_DP")
	)
	(segment
		(start 388.102602 -222.126302)
		(end 388.10184 -222.12681)
		(width 0.0762)
		(layer "B.Cu")
		(net "CLK_100M_CPU0_CLK01_R_DP")
	)
	(segment
		(start 382.110488 -222.860616)
		(end 382.044448 -222.794576)
		(width 0.0762)
		(layer "B.Cu")
		(net "CLK_100M_CPU0_CLK01_R_DP")
	)
	(segment
		(start 375.963688 -219.523564)
		(end 375.69775 -219.523564)
		(width 0.12954)
		(layer "B.Cu")
		(net "CLK_100M_CPU0_CLK01_R_DP")
	)
	(segment
		(start 373.003572 -216.559892)
		(end 372.730268 -216.286588)
		(width 0.12954)
		(layer "B.Cu")
		(net "CLK_100M_CPU0_CLK01_R_DP")
	)
	(segment
		(start 384.341878 -223.746822)
		(end 384.339846 -223.748092)
		(width 0.0762)
		(layer "B.Cu")
		(net "CLK_100M_CPU0_CLK01_R_DP")
	)
	(segment
		(start 375.159016 -218.718892)
		(end 374.893078 -218.718892)
		(width 0.12954)
		(layer "B.Cu")
		(net "CLK_100M_CPU0_CLK01_R_DP")
	)
	(segment
		(start 380.168404 -222.254572)
		(end 379.809756 -221.895924)
		(width 0.12954)
		(layer "B.Cu")
		(net "CLK_100M_CPU0_CLK01_R_DP")
	)
	(segment
		(start 387.63194 -222.936816)
		(end 387.592824 -222.959676)
		(width 0.0762)
		(layer "B.Cu")
		(net "CLK_100M_CPU0_CLK01_R_DP")
	)
	(segment
		(start 374.088406 -217.91422)
		(end 373.819166 -217.64498)
		(width 0.12954)
		(layer "B.Cu")
		(net "CLK_100M_CPU0_CLK01_R_DP")
	)
	(arc
		(start 387.819392 -222.614236)
		(mid 387.777843 -222.785658)
		(end 387.66242 -222.919036)
		(width 0.0762)
		(layer "B.Cu")
		(net "CLK_100M_CPU0_CLK01_R_DP")
	)
	(arc
		(start 383.497836 -222.936816)
		(mid 383.21488 -222.860639)
		(end 382.931924 -222.936816)
		(width 0.0762)
		(layer "B.Cu")
		(net "CLK_100M_CPU0_CLK01_R_DP")
	)
	(arc
		(start 386.221986 -223.746822)
		(mid 386.039735 -223.797172)
		(end 385.856226 -223.751648)
		(width 0.0762)
		(layer "B.Cu")
		(net "CLK_100M_CPU0_CLK01_R_DP")
	)
	(arc
		(start 386.787898 -223.746822)
		(mid 386.504942 -223.670645)
		(end 386.221986 -223.746822)
		(width 0.0762)
		(layer "B.Cu")
		(net "CLK_100M_CPU0_CLK01_R_DP")
	)
	(arc
		(start 382.931924 -222.936816)
		(mid 382.744726 -222.987198)
		(end 382.557528 -222.936816)
		(width 0.0762)
		(layer "B.Cu")
		(net "CLK_100M_CPU0_CLK01_R_DP")
	)
	(arc
		(start 383.937256 -223.729042)
		(mid 383.821829 -223.595666)
		(end 383.780284 -223.424242)
		(width 0.0762)
		(layer "B.Cu")
		(net "CLK_100M_CPU0_CLK01_R_DP")
	)
	(arc
		(start 388.285228 -221.860872)
		(mid 388.234343 -221.999954)
		(end 388.13359 -222.108522)
		(width 0.0762)
		(layer "B.Cu")
		(net "CLK_100M_CPU0_CLK01_R_DP")
	)
	(arc
		(start 387.161786 -223.746822)
		(mid 386.974842 -223.797077)
		(end 386.787898 -223.746822)
		(width 0.0762)
		(layer "B.Cu")
		(net "CLK_100M_CPU0_CLK01_R_DP")
	)
	(arc
		(start 382.557528 -222.936816)
		(mid 382.468125 -222.895624)
		(end 382.372616 -222.871792)
		(width 0.0762)
		(layer "B.Cu")
		(net "CLK_100M_CPU0_CLK01_R_DP")
	)
	(arc
		(start 385.281932 -223.746822)
		(mid 385.099681 -223.797172)
		(end 384.916172 -223.751648)
		(width 0.0762)
		(layer "B.Cu")
		(net "CLK_100M_CPU0_CLK01_R_DP")
	)
	(arc
		(start 387.592824 -222.959676)
		(mid 387.414011 -223.162026)
		(end 387.349492 -223.424242)
		(width 0.0762)
		(layer "B.Cu")
		(net "CLK_100M_CPU0_CLK01_R_DP")
	)
	(arc
		(start 384.90779 -223.746822)
		(mid 384.624834 -223.670645)
		(end 384.341878 -223.746822)
		(width 0.0762)
		(layer "B.Cu")
		(net "CLK_100M_CPU0_CLK01_R_DP")
	)
	(arc
		(start 387.349492 -223.424242)
		(mid 387.308237 -223.595213)
		(end 387.193536 -223.728534)
		(width 0.0762)
		(layer "B.Cu")
		(net "CLK_100M_CPU0_CLK01_R_DP")
	)
	(arc
		(start 385.833112 -223.738186)
		(mid 385.556383 -223.670503)
		(end 385.281932 -223.746822)
		(width 0.0762)
		(layer "B.Cu")
		(net "CLK_100M_CPU0_CLK01_R_DP")
	)
	(arc
		(start 383.780284 -223.424242)
		(mid 383.715769 -223.162023)
		(end 383.536952 -222.959676)
		(width 0.0762)
		(layer "B.Cu")
		(net "CLK_100M_CPU0_CLK01_R_DP")
	)
	(arc
		(start 384.333496 -223.751648)
		(mid 384.149988 -223.797142)
		(end 383.967736 -223.746822)
		(width 0.0762)
		(layer "B.Cu")
		(net "CLK_100M_CPU0_CLK01_R_DP")
	)
	(arc
		(start 388.062724 -222.14967)
		(mid 387.883911 -222.35202)
		(end 387.819392 -222.614236)
		(width 0.0762)
		(layer "B.Cu")
		(net "CLK_100M_CPU0_CLK01_R_DP")
	)
	(segment
		(start 388.387844 -222.070168)
		(end 388.854696 -221.80423)
		(width 0.12954)
		(layer "F.Cu")
		(net "CLK_100M_CPU0_CLK01_R_DN")
	)
	(via
		(at 388.854696 -221.80423)
		(size 0.4064)
		(drill 0.2032)
		(layers "F.Cu" "B.Cu")
		(net "CLK_100M_CPU0_CLK01_R_DN")
	)
	(segment
		(start 382.044448 -223.117156)
		(end 382.025398 -223.117156)
		(width 0.0762)
		(layer "B.Cu")
		(net "CLK_100M_CPU0_CLK01_R_DN")
	)
	(segment
		(start 388.203186 -222.288608)
		(end 388.202932 -222.288608)
		(width 0.0762)
		(layer "B.Cu")
		(net "CLK_100M_CPU0_CLK01_R_DN")
	)
	(segment
		(start 383.412492 -223.107758)
		(end 383.412238 -223.107504)
		(width 0.0762)
		(layer "B.Cu")
		(net "CLK_100M_CPU0_CLK01_R_DN")
	)
	(segment
		(start 381.168148 -222.577152)
		(end 380.034546 -222.577152)
		(width 0.12954)
		(layer "B.Cu")
		(net "CLK_100M_CPU0_CLK01_R_DN")
	)
	(segment
		(start 385.762754 -223.917764)
		(end 385.752086 -223.911668)
		(width 0.0762)
		(layer "B.Cu")
		(net "CLK_100M_CPU0_CLK01_R_DN")
	)
	(segment
		(start 384.437636 -223.911668)
		(end 384.437382 -223.911922)
		(width 0.0762)
		(layer "B.Cu")
		(net "CLK_100M_CPU0_CLK01_R_DN")
	)
	(segment
		(start 388.19836 -222.291402)
		(end 388.166102 -222.310198)
		(width 0.0762)
		(layer "B.Cu")
		(net "CLK_100M_CPU0_CLK01_R_DN")
	)
	(segment
		(start 385.752086 -223.911668)
		(end 385.739894 -223.904556)
		(width 0.0762)
		(layer "B.Cu")
		(net "CLK_100M_CPU0_CLK01_R_DN")
	)
	(segment
		(start 379.675898 -222.218504)
		(end 377.936252 -222.218504)
		(width 0.12954)
		(layer "B.Cu")
		(net "CLK_100M_CPU0_CLK01_R_DN")
	)
	(segment
		(start 371.503956 -215.293448)
		(end 371.134386 -214.923878)
		(width 0.12954)
		(layer "B.Cu")
		(net "CLK_100M_CPU0_CLK01_R_DN")
	)
	(segment
		(start 384.81889 -223.915732)
		(end 384.812286 -223.911922)
		(width 0.0762)
		(layer "B.Cu")
		(net "CLK_100M_CPU0_CLK01_R_DN")
	)
	(segment
		(start 383.412238 -223.107504)
		(end 383.408174 -223.107504)
		(width 0.0762)
		(layer "B.Cu")
		(net "CLK_100M_CPU0_CLK01_R_DN")
	)
	(segment
		(start 384.812286 -223.911922)
		(end 384.812032 -223.911668)
		(width 0.0762)
		(layer "B.Cu")
		(net "CLK_100M_CPU0_CLK01_R_DN")
	)
	(segment
		(start 384.430778 -223.915732)
		(end 384.426968 -223.917764)
		(width 0.0762)
		(layer "B.Cu")
		(net "CLK_100M_CPU0_CLK01_R_DN")
	)
	(segment
		(start 387.727952 -223.101408)
		(end 387.696202 -223.120204)
		(width 0.0762)
		(layer "B.Cu")
		(net "CLK_100M_CPU0_CLK01_R_DN")
	)
	(segment
		(start 371.503956 -215.786208)
		(end 371.503956 -215.293448)
		(width 0.12954)
		(layer "B.Cu")
		(net "CLK_100M_CPU0_CLK01_R_DN")
	)
	(segment
		(start 382.110488 -223.051116)
		(end 382.044448 -223.117156)
		(width 0.0762)
		(layer "B.Cu")
		(net "CLK_100M_CPU0_CLK01_R_DN")
	)
	(segment
		(start 388.21106 -222.284036)
		(end 388.210298 -222.284544)
		(width 0.0762)
		(layer "B.Cu")
		(net "CLK_100M_CPU0_CLK01_R_DN")
	)
	(segment
		(start 377.936252 -222.218504)
		(end 371.503956 -215.786208)
		(width 0.12954)
		(layer "B.Cu")
		(net "CLK_100M_CPU0_CLK01_R_DN")
	)
	(segment
		(start 388.206742 -222.28683)
		(end 388.203186 -222.288608)
		(width 0.0762)
		(layer "B.Cu")
		(net "CLK_100M_CPU0_CLK01_R_DN")
	)
	(segment
		(start 383.413508 -223.10852)
		(end 383.412492 -223.108012)
		(width 0.0762)
		(layer "B.Cu")
		(net "CLK_100M_CPU0_CLK01_R_DN")
	)
	(segment
		(start 388.210298 -222.284544)
		(end 388.206742 -222.28683)
		(width 0.0762)
		(layer "B.Cu")
		(net "CLK_100M_CPU0_CLK01_R_DN")
	)
	(segment
		(start 384.437382 -223.911922)
		(end 384.430778 -223.915732)
		(width 0.0762)
		(layer "B.Cu")
		(net "CLK_100M_CPU0_CLK01_R_DN")
	)
	(segment
		(start 382.025398 -223.117156)
		(end 381.708152 -223.117156)
		(width 0.12954)
		(layer "B.Cu")
		(net "CLK_100M_CPU0_CLK01_R_DN")
	)
	(segment
		(start 382.344168 -223.06026)
		(end 382.282954 -223.051116)
		(width 0.0762)
		(layer "B.Cu")
		(net "CLK_100M_CPU0_CLK01_R_DN")
	)
	(segment
		(start 384.8227 -223.917764)
		(end 384.81889 -223.915732)
		(width 0.0762)
		(layer "B.Cu")
		(net "CLK_100M_CPU0_CLK01_R_DN")
	)
	(segment
		(start 383.433574 -223.120204)
		(end 383.413508 -223.10852)
		(width 0.0762)
		(layer "B.Cu")
		(net "CLK_100M_CPU0_CLK01_R_DN")
	)
	(segment
		(start 383.412492 -223.108012)
		(end 383.412492 -223.107758)
		(width 0.0762)
		(layer "B.Cu")
		(net "CLK_100M_CPU0_CLK01_R_DN")
	)
	(segment
		(start 388.854696 -221.80423)
		(end 388.541006 -221.80423)
		(width 0.0762)
		(layer "B.Cu")
		(net "CLK_100M_CPU0_CLK01_R_DN")
	)
	(segment
		(start 388.202932 -222.288608)
		(end 388.19836 -222.291402)
		(width 0.0762)
		(layer "B.Cu")
		(net "CLK_100M_CPU0_CLK01_R_DN")
	)
	(segment
		(start 380.034546 -222.577152)
		(end 379.675898 -222.218504)
		(width 0.12954)
		(layer "B.Cu")
		(net "CLK_100M_CPU0_CLK01_R_DN")
	)
	(segment
		(start 388.541006 -221.80423)
		(end 388.47649 -221.868746)
		(width 0.0762)
		(layer "B.Cu")
		(net "CLK_100M_CPU0_CLK01_R_DN")
	)
	(segment
		(start 387.76529 -223.079818)
		(end 387.727952 -223.101408)
		(width 0.0762)
		(layer "B.Cu")
		(net "CLK_100M_CPU0_CLK01_R_DN")
	)
	(segment
		(start 383.408174 -223.107504)
		(end 383.402332 -223.101662)
		(width 0.0762)
		(layer "B.Cu")
		(net "CLK_100M_CPU0_CLK01_R_DN")
	)
	(segment
		(start 381.708152 -223.117156)
		(end 381.168148 -222.577152)
		(width 0.12954)
		(layer "B.Cu")
		(net "CLK_100M_CPU0_CLK01_R_DN")
	)
	(segment
		(start 388.236206 -222.269558)
		(end 388.21106 -222.284036)
		(width 0.0762)
		(layer "B.Cu")
		(net "CLK_100M_CPU0_CLK01_R_DN")
	)
	(segment
		(start 382.282954 -223.051116)
		(end 382.110488 -223.051116)
		(width 0.0762)
		(layer "B.Cu")
		(net "CLK_100M_CPU0_CLK01_R_DN")
	)
	(segment
		(start 387.296152 -223.889316)
		(end 387.257036 -223.911922)
		(width 0.0762)
		(layer "B.Cu")
		(net "CLK_100M_CPU0_CLK01_R_DN")
	)
	(segment
		(start 383.871724 -223.911668)
		(end 383.834386 -223.889824)
		(width 0.0762)
		(layer "B.Cu")
		(net "CLK_100M_CPU0_CLK01_R_DN")
	)
	(arc
		(start 387.539992 -223.424242)
		(mid 387.475333 -223.686799)
		(end 387.296152 -223.889316)
		(width 0.0762)
		(layer "B.Cu")
		(net "CLK_100M_CPU0_CLK01_R_DN")
	)
	(arc
		(start 385.37769 -223.911668)
		(mid 385.100988 -223.98781)
		(end 384.8227 -223.917764)
		(width 0.0762)
		(layer "B.Cu")
		(net "CLK_100M_CPU0_CLK01_R_DN")
	)
	(arc
		(start 385.739894 -223.904556)
		(mid 385.557864 -223.861177)
		(end 385.37769 -223.911668)
		(width 0.0762)
		(layer "B.Cu")
		(net "CLK_100M_CPU0_CLK01_R_DN")
	)
	(arc
		(start 388.47649 -221.868746)
		(mid 388.475189 -221.879173)
		(end 388.473696 -221.889574)
		(width 0.0762)
		(layer "B.Cu")
		(net "CLK_100M_CPU0_CLK01_R_DN")
	)
	(arc
		(start 382.462024 -223.101662)
		(mid 382.405033 -223.075454)
		(end 382.344168 -223.06026)
		(width 0.0762)
		(layer "B.Cu")
		(net "CLK_100M_CPU0_CLK01_R_DN")
	)
	(arc
		(start 383.402332 -223.101662)
		(mid 383.21488 -223.051152)
		(end 383.027428 -223.101662)
		(width 0.0762)
		(layer "B.Cu")
		(net "CLK_100M_CPU0_CLK01_R_DN")
	)
	(arc
		(start 387.696202 -223.120204)
		(mid 387.581359 -223.253352)
		(end 387.539992 -223.424242)
		(width 0.0762)
		(layer "B.Cu")
		(net "CLK_100M_CPU0_CLK01_R_DN")
	)
	(arc
		(start 383.589784 -223.424242)
		(mid 383.548386 -223.253368)
		(end 383.433574 -223.120204)
		(width 0.0762)
		(layer "B.Cu")
		(net "CLK_100M_CPU0_CLK01_R_DN")
	)
	(arc
		(start 388.473696 -221.889574)
		(mid 388.3942 -222.104093)
		(end 388.236206 -222.269558)
		(width 0.0762)
		(layer "B.Cu")
		(net "CLK_100M_CPU0_CLK01_R_DN")
	)
	(arc
		(start 388.166102 -222.310198)
		(mid 388.051259 -222.443346)
		(end 388.009892 -222.614236)
		(width 0.0762)
		(layer "B.Cu")
		(net "CLK_100M_CPU0_CLK01_R_DN")
	)
	(arc
		(start 384.426968 -223.917764)
		(mid 384.148536 -223.987862)
		(end 383.871724 -223.911668)
		(width 0.0762)
		(layer "B.Cu")
		(net "CLK_100M_CPU0_CLK01_R_DN")
	)
	(arc
		(start 383.834386 -223.889824)
		(mid 383.654594 -223.687236)
		(end 383.589784 -223.424242)
		(width 0.0762)
		(layer "B.Cu")
		(net "CLK_100M_CPU0_CLK01_R_DN")
	)
	(arc
		(start 387.257036 -223.911922)
		(mid 386.974668 -223.987683)
		(end 386.692394 -223.911668)
		(width 0.0762)
		(layer "B.Cu")
		(net "CLK_100M_CPU0_CLK01_R_DN")
	)
	(arc
		(start 384.812032 -223.911668)
		(mid 384.624834 -223.861286)
		(end 384.437636 -223.911668)
		(width 0.0762)
		(layer "B.Cu")
		(net "CLK_100M_CPU0_CLK01_R_DN")
	)
	(arc
		(start 388.009892 -222.614236)
		(mid 387.945074 -222.877225)
		(end 387.76529 -223.079818)
		(width 0.0762)
		(layer "B.Cu")
		(net "CLK_100M_CPU0_CLK01_R_DN")
	)
	(arc
		(start 386.31749 -223.911668)
		(mid 386.040931 -223.987684)
		(end 385.762754 -223.917764)
		(width 0.0762)
		(layer "B.Cu")
		(net "CLK_100M_CPU0_CLK01_R_DN")
	)
	(arc
		(start 383.027428 -223.101662)
		(mid 382.744726 -223.177711)
		(end 382.462024 -223.101662)
		(width 0.0762)
		(layer "B.Cu")
		(net "CLK_100M_CPU0_CLK01_R_DN")
	)
	(arc
		(start 386.692394 -223.911668)
		(mid 386.504942 -223.861158)
		(end 386.31749 -223.911668)
		(width 0.0762)
		(layer "B.Cu")
		(net "CLK_100M_CPU0_CLK01_R_DN")
	)
	(segment
		(start 17.91462 -132.877814)
		(end 18.302732 -132.489702)
		(width 0.12954)
		(layer "F.Cu")
		(net "CLK_100M_BMC_RC_DP_R")
	)
	(segment
		(start 15.42161 -132.789168)
		(end 15.586202 -132.789168)
		(width 0.12954)
		(layer "F.Cu")
		(net "CLK_100M_BMC_RC_DP_R")
	)
	(segment
		(start 15.674848 -132.877814)
		(end 17.91462 -132.877814)
		(width 0.12954)
		(layer "F.Cu")
		(net "CLK_100M_BMC_RC_DP_R")
	)
	(segment
		(start 15.586202 -132.789168)
		(end 15.674848 -132.877814)
		(width 0.12954)
		(layer "F.Cu")
		(net "CLK_100M_BMC_RC_DP_R")
	)
	(segment
		(start 15.42161 -133.28904)
		(end 15.589758 -133.28904)
		(width 0.12954)
		(layer "F.Cu")
		(net "CLK_100M_BMC_RC_DN_R")
	)
	(segment
		(start 15.589758 -133.28904)
		(end 15.678404 -133.200394)
		(width 0.12954)
		(layer "F.Cu")
		(net "CLK_100M_BMC_RC_DN_R")
	)
	(segment
		(start 15.678404 -133.200394)
		(end 18.022824 -133.200394)
		(width 0.12954)
		(layer "F.Cu")
		(net "CLK_100M_BMC_RC_DN_R")
	)
	(segment
		(start 18.022824 -133.200394)
		(end 18.302732 -133.480302)
		(width 0.12954)
		(layer "F.Cu")
		(net "CLK_100M_BMC_RC_DN_R")
	)
	(segment
		(start 38.043612 -424.202098)
		(end 37.277294 -424.202098)
		(width 0.10668)
		(layer "F.Cu")
		(net "PU_TEST")
	)
	(segment
		(start 36.82619 -424.653202)
		(end 36.12769 -424.653202)
		(width 0.10668)
		(layer "F.Cu")
		(net "PU_TEST")
	)
	(segment
		(start 37.277294 -424.202098)
		(end 36.82619 -424.653202)
		(width 0.10668)
		(layer "F.Cu")
		(net "PU_TEST")
	)
	(segment
		(start 35.984688 -424.5102)
		(end 35.502596 -424.5102)
		(width 0.10668)
		(layer "F.Cu")
		(net "PU_TEST")
	)
	(segment
		(start 36.12769 -424.653202)
		(end 35.984688 -424.5102)
		(width 0.10668)
		(layer "F.Cu")
		(net "PU_TEST")
	)
	(via
		(at 36.82619 -424.653202)
		(size 0.762)
		(drill 0.381)
		(layers "F.Cu" "B.Cu")
		(net "PU_TEST")
	)
	(segment
		(start 77.133958 -418.10559)
		(end 77.77226 -418.10559)
		(width 0.12954)
		(layer "B.Cu")
		(net "P3E_CPU1_P5_TX_C_DP<1>")
	)
	(segment
		(start 47.290228 -411.462474)
		(end 73.555352 -411.462474)
		(width 0.12954)
		(layer "B.Cu")
		(net "P3E_CPU1_P5_TX_C_DP<1>")
	)
	(segment
		(start 74.102214 -415.073846)
		(end 77.133958 -418.10559)
		(width 0.12954)
		(layer "B.Cu")
		(net "P3E_CPU1_P5_TX_C_DP<1>")
	)
	(segment
		(start 44.41571 -413.691578)
		(end 44.67352 -413.433768)
		(width 0.12954)
		(layer "B.Cu")
		(net "P3E_CPU1_P5_TX_C_DP<1>")
	)
	(segment
		(start 44.67352 -413.433768)
		(end 45.318934 -413.433768)
		(width 0.12954)
		(layer "B.Cu")
		(net "P3E_CPU1_P5_TX_C_DP<1>")
	)
	(segment
		(start 74.102214 -412.009336)
		(end 74.102214 -415.073846)
		(width 0.12954)
		(layer "B.Cu")
		(net "P3E_CPU1_P5_TX_C_DP<1>")
	)
	(segment
		(start 45.318934 -413.433768)
		(end 47.290228 -411.462474)
		(width 0.12954)
		(layer "B.Cu")
		(net "P3E_CPU1_P5_TX_C_DP<1>")
	)
	(segment
		(start 77.77226 -418.10559)
		(end 78.04277 -418.3761)
		(width 0.12954)
		(layer "B.Cu")
		(net "P3E_CPU1_P5_TX_C_DP<1>")
	)
	(segment
		(start 73.555352 -411.462474)
		(end 74.102214 -412.009336)
		(width 0.12954)
		(layer "B.Cu")
		(net "P3E_CPU1_P5_TX_C_DP<1>")
	)
	(segment
		(start 77.75194 -418.08527)
		(end 78.04277 -418.3761)
		(width 0.14224)
		(layer "In4.Cu")
		(net "P3E_CPU1_P5_TX_C_DP<1>")
	)
	(segment
		(start 71.734172 -419.32352)
		(end 71.734172 -417.317428)
		(width 0.14224)
		(layer "In4.Cu")
		(net "P3E_CPU1_P5_TX_C_DP<1>")
	)
	(segment
		(start 77.062076 -418.08527)
		(end 77.75194 -418.08527)
		(width 0.14224)
		(layer "In4.Cu")
		(net "P3E_CPU1_P5_TX_C_DP<1>")
	)
	(segment
		(start 74.191876 -416.81654)
		(end 74.329036 -416.9537)
		(width 0.14224)
		(layer "In4.Cu")
		(net "P3E_CPU1_P5_TX_C_DP<1>")
	)
	(segment
		(start 71.734172 -417.317428)
		(end 72.23506 -416.81654)
		(width 0.14224)
		(layer "In4.Cu")
		(net "P3E_CPU1_P5_TX_C_DP<1>")
	)
	(segment
		(start 71.108824 -419.63086)
		(end 71.426832 -419.63086)
		(width 0.14224)
		(layer "In4.Cu")
		(net "P3E_CPU1_P5_TX_C_DP<1>")
	)
	(segment
		(start 74.892916 -416.81654)
		(end 75.793346 -416.81654)
		(width 0.14224)
		(layer "In4.Cu")
		(net "P3E_CPU1_P5_TX_C_DP<1>")
	)
	(segment
		(start 70.649846 -420.089838)
		(end 71.108824 -419.63086)
		(width 0.14224)
		(layer "In4.Cu")
		(net "P3E_CPU1_P5_TX_C_DP<1>")
	)
	(segment
		(start 72.23506 -416.81654)
		(end 74.191876 -416.81654)
		(width 0.14224)
		(layer "In4.Cu")
		(net "P3E_CPU1_P5_TX_C_DP<1>")
	)
	(segment
		(start 71.426832 -419.63086)
		(end 71.734172 -419.32352)
		(width 0.14224)
		(layer "In4.Cu")
		(net "P3E_CPU1_P5_TX_C_DP<1>")
	)
	(segment
		(start 74.755756 -416.9537)
		(end 74.892916 -416.81654)
		(width 0.14224)
		(layer "In4.Cu")
		(net "P3E_CPU1_P5_TX_C_DP<1>")
	)
	(segment
		(start 74.329036 -416.9537)
		(end 74.755756 -416.9537)
		(width 0.14224)
		(layer "In4.Cu")
		(net "P3E_CPU1_P5_TX_C_DP<1>")
	)
	(segment
		(start 75.793346 -416.81654)
		(end 77.062076 -418.08527)
		(width 0.14224)
		(layer "In4.Cu")
		(net "P3E_CPU1_P5_TX_C_DP<1>")
	)
	(segment
		(start 70.973442 -413.94634)
		(end 74.27214 -417.245038)
		(width 0.12954)
		(layer "B.Cu")
		(net "P3E_CPU1_P5_TX_C_DP<0>")
	)
	(segment
		(start 53.161438 -416.348926)
		(end 55.564024 -413.94634)
		(width 0.12954)
		(layer "B.Cu")
		(net "P3E_CPU1_P5_TX_C_DP<0>")
	)
	(segment
		(start 75.249532 -420.328598)
		(end 75.520042 -420.058088)
		(width 0.12954)
		(layer "B.Cu")
		(net "P3E_CPU1_P5_TX_C_DP<0>")
	)
	(segment
		(start 74.27214 -420.034466)
		(end 74.566272 -420.328598)
		(width 0.12954)
		(layer "B.Cu")
		(net "P3E_CPU1_P5_TX_C_DP<0>")
	)
	(segment
		(start 74.566272 -420.328598)
		(end 75.249532 -420.328598)
		(width 0.12954)
		(layer "B.Cu")
		(net "P3E_CPU1_P5_TX_C_DP<0>")
	)
	(segment
		(start 55.564024 -413.94634)
		(end 70.973442 -413.94634)
		(width 0.12954)
		(layer "B.Cu")
		(net "P3E_CPU1_P5_TX_C_DP<0>")
	)
	(segment
		(start 52.001674 -416.091116)
		(end 52.259484 -416.348926)
		(width 0.12954)
		(layer "B.Cu")
		(net "P3E_CPU1_P5_TX_C_DP<0>")
	)
	(segment
		(start 74.27214 -417.245038)
		(end 74.27214 -420.034466)
		(width 0.12954)
		(layer "B.Cu")
		(net "P3E_CPU1_P5_TX_C_DP<0>")
	)
	(segment
		(start 52.259484 -416.348926)
		(end 53.161438 -416.348926)
		(width 0.12954)
		(layer "B.Cu")
		(net "P3E_CPU1_P5_TX_C_DP<0>")
	)
	(segment
		(start 73.10882 -420.348918)
		(end 72.649842 -419.88994)
		(width 0.14224)
		(layer "In4.Cu")
		(net "P3E_CPU1_P5_TX_C_DP<0>")
	)
	(segment
		(start 75.520042 -420.058088)
		(end 75.229212 -420.348918)
		(width 0.14224)
		(layer "In4.Cu")
		(net "P3E_CPU1_P5_TX_C_DP<0>")
	)
	(segment
		(start 75.229212 -420.348918)
		(end 73.10882 -420.348918)
		(width 0.14224)
		(layer "In4.Cu")
		(net "P3E_CPU1_P5_TX_C_DP<0>")
	)
	(segment
		(start 73.68921 -411.139894)
		(end 74.424794 -411.875478)
		(width 0.12954)
		(layer "B.Cu")
		(net "P3E_CPU1_P5_TX_C_DN<1>")
	)
	(segment
		(start 47.15637 -411.139894)
		(end 73.68921 -411.139894)
		(width 0.12954)
		(layer "B.Cu")
		(net "P3E_CPU1_P5_TX_C_DN<1>")
	)
	(segment
		(start 44.41571 -412.853378)
		(end 44.67352 -413.111188)
		(width 0.12954)
		(layer "B.Cu")
		(net "P3E_CPU1_P5_TX_C_DN<1>")
	)
	(segment
		(start 45.185076 -413.111188)
		(end 47.15637 -411.139894)
		(width 0.12954)
		(layer "B.Cu")
		(net "P3E_CPU1_P5_TX_C_DN<1>")
	)
	(segment
		(start 77.77226 -417.78301)
		(end 78.04277 -417.5125)
		(width 0.12954)
		(layer "B.Cu")
		(net "P3E_CPU1_P5_TX_C_DN<1>")
	)
	(segment
		(start 77.267816 -417.78301)
		(end 77.77226 -417.78301)
		(width 0.12954)
		(layer "B.Cu")
		(net "P3E_CPU1_P5_TX_C_DN<1>")
	)
	(segment
		(start 74.424794 -411.875478)
		(end 74.424794 -414.939988)
		(width 0.12954)
		(layer "B.Cu")
		(net "P3E_CPU1_P5_TX_C_DN<1>")
	)
	(segment
		(start 74.424794 -414.939988)
		(end 77.267816 -417.78301)
		(width 0.12954)
		(layer "B.Cu")
		(net "P3E_CPU1_P5_TX_C_DN<1>")
	)
	(segment
		(start 44.67352 -413.111188)
		(end 45.185076 -413.111188)
		(width 0.12954)
		(layer "B.Cu")
		(net "P3E_CPU1_P5_TX_C_DN<1>")
	)
	(segment
		(start 72.11822 -416.5346)
		(end 75.910186 -416.5346)
		(width 0.14224)
		(layer "In4.Cu")
		(net "P3E_CPU1_P5_TX_C_DN<1>")
	)
	(segment
		(start 71.309992 -419.34892)
		(end 71.452232 -419.20668)
		(width 0.14224)
		(layer "In4.Cu")
		(net "P3E_CPU1_P5_TX_C_DN<1>")
	)
	(segment
		(start 71.108824 -419.34892)
		(end 71.309992 -419.34892)
		(width 0.14224)
		(layer "In4.Cu")
		(net "P3E_CPU1_P5_TX_C_DN<1>")
	)
	(segment
		(start 75.910186 -416.5346)
		(end 77.178916 -417.80333)
		(width 0.14224)
		(layer "In4.Cu")
		(net "P3E_CPU1_P5_TX_C_DN<1>")
	)
	(segment
		(start 77.75194 -417.80333)
		(end 78.04277 -417.5125)
		(width 0.14224)
		(layer "In4.Cu")
		(net "P3E_CPU1_P5_TX_C_DN<1>")
	)
	(segment
		(start 77.178916 -417.80333)
		(end 77.75194 -417.80333)
		(width 0.14224)
		(layer "In4.Cu")
		(net "P3E_CPU1_P5_TX_C_DN<1>")
	)
	(segment
		(start 70.649846 -418.889942)
		(end 71.108824 -419.34892)
		(width 0.14224)
		(layer "In4.Cu")
		(net "P3E_CPU1_P5_TX_C_DN<1>")
	)
	(segment
		(start 71.452232 -419.20668)
		(end 71.452232 -417.200588)
		(width 0.14224)
		(layer "In4.Cu")
		(net "P3E_CPU1_P5_TX_C_DN<1>")
	)
	(segment
		(start 71.452232 -417.200588)
		(end 72.11822 -416.5346)
		(width 0.14224)
		(layer "In4.Cu")
		(net "P3E_CPU1_P5_TX_C_DN<1>")
	)
	(segment
		(start 52.001674 -416.929316)
		(end 52.259484 -416.671506)
		(width 0.12954)
		(layer "B.Cu")
		(net "P3E_CPU1_P5_TX_C_DN<0>")
	)
	(segment
		(start 53.295296 -416.671506)
		(end 55.697882 -414.26892)
		(width 0.12954)
		(layer "B.Cu")
		(net "P3E_CPU1_P5_TX_C_DN<0>")
	)
	(segment
		(start 70.839584 -414.26892)
		(end 73.94956 -417.378896)
		(width 0.12954)
		(layer "B.Cu")
		(net "P3E_CPU1_P5_TX_C_DN<0>")
	)
	(segment
		(start 73.94956 -420.168324)
		(end 74.432414 -420.651178)
		(width 0.12954)
		(layer "B.Cu")
		(net "P3E_CPU1_P5_TX_C_DN<0>")
	)
	(segment
		(start 73.94956 -417.378896)
		(end 73.94956 -420.168324)
		(width 0.12954)
		(layer "B.Cu")
		(net "P3E_CPU1_P5_TX_C_DN<0>")
	)
	(segment
		(start 52.259484 -416.671506)
		(end 53.295296 -416.671506)
		(width 0.12954)
		(layer "B.Cu")
		(net "P3E_CPU1_P5_TX_C_DN<0>")
	)
	(segment
		(start 75.249532 -420.651178)
		(end 75.520042 -420.921688)
		(width 0.12954)
		(layer "B.Cu")
		(net "P3E_CPU1_P5_TX_C_DN<0>")
	)
	(segment
		(start 55.697882 -414.26892)
		(end 70.839584 -414.26892)
		(width 0.12954)
		(layer "B.Cu")
		(net "P3E_CPU1_P5_TX_C_DN<0>")
	)
	(segment
		(start 74.432414 -420.651178)
		(end 75.249532 -420.651178)
		(width 0.12954)
		(layer "B.Cu")
		(net "P3E_CPU1_P5_TX_C_DN<0>")
	)
	(segment
		(start 75.229212 -420.630858)
		(end 74.333862 -420.630858)
		(width 0.14224)
		(layer "In4.Cu")
		(net "P3E_CPU1_P5_TX_C_DN<0>")
	)
	(segment
		(start 74.196702 -420.768018)
		(end 73.769982 -420.768018)
		(width 0.14224)
		(layer "In4.Cu")
		(net "P3E_CPU1_P5_TX_C_DN<0>")
	)
	(segment
		(start 74.333862 -420.630858)
		(end 74.196702 -420.768018)
		(width 0.14224)
		(layer "In4.Cu")
		(net "P3E_CPU1_P5_TX_C_DN<0>")
	)
	(segment
		(start 75.520042 -420.921688)
		(end 75.229212 -420.630858)
		(width 0.14224)
		(layer "In4.Cu")
		(net "P3E_CPU1_P5_TX_C_DN<0>")
	)
	(segment
		(start 73.632822 -420.630858)
		(end 73.10882 -420.630858)
		(width 0.14224)
		(layer "In4.Cu")
		(net "P3E_CPU1_P5_TX_C_DN<0>")
	)
	(segment
		(start 73.10882 -420.630858)
		(end 72.649842 -421.089836)
		(width 0.14224)
		(layer "In4.Cu")
		(net "P3E_CPU1_P5_TX_C_DN<0>")
	)
	(segment
		(start 73.769982 -420.768018)
		(end 73.632822 -420.630858)
		(width 0.14224)
		(layer "In4.Cu")
		(net "P3E_CPU1_P5_TX_C_DN<0>")
	)
	(segment
		(start 177.794666 -53.299868)
		(end 177.108358 -53.299868)
		(width 0.12954)
		(layer "F.Cu")
		(net "P3E_CPU1_P4_TX_C_DP<3>")
	)
	(segment
		(start 177.883312 -53.388514)
		(end 177.794666 -53.299868)
		(width 0.12954)
		(layer "F.Cu")
		(net "P3E_CPU1_P4_TX_C_DP<3>")
	)
	(segment
		(start 180.261768 -53.065934)
		(end 179.939188 -53.388514)
		(width 0.12954)
		(layer "F.Cu")
		(net "P3E_CPU1_P4_TX_C_DP<3>")
	)
	(segment
		(start 179.939188 -53.388514)
		(end 177.883312 -53.388514)
		(width 0.12954)
		(layer "F.Cu")
		(net "P3E_CPU1_P4_TX_C_DP<3>")
	)
	(segment
		(start 177.794666 -50.299874)
		(end 177.883312 -50.38852)
		(width 0.12954)
		(layer "F.Cu")
		(net "P3E_CPU1_P4_TX_C_DP<2>")
	)
	(segment
		(start 177.883312 -50.38852)
		(end 179.939188 -50.38852)
		(width 0.12954)
		(layer "F.Cu")
		(net "P3E_CPU1_P4_TX_C_DP<2>")
	)
	(segment
		(start 179.939188 -50.38852)
		(end 180.261768 -50.06594)
		(width 0.12954)
		(layer "F.Cu")
		(net "P3E_CPU1_P4_TX_C_DP<2>")
	)
	(segment
		(start 177.108358 -50.299874)
		(end 177.794666 -50.299874)
		(width 0.12954)
		(layer "F.Cu")
		(net "P3E_CPU1_P4_TX_C_DP<2>")
	)
	(segment
		(start 180.261768 -50.06594)
		(end 180.261768 -50.060098)
		(width 0.12954)
		(layer "F.Cu")
		(net "P3E_CPU1_P4_TX_C_DP<2>")
	)
	(segment
		(start 177.794666 -47.29988)
		(end 177.883312 -47.388526)
		(width 0.12954)
		(layer "F.Cu")
		(net "P3E_CPU1_P4_TX_C_DP<1>")
	)
	(segment
		(start 177.883312 -47.388526)
		(end 180.01234 -47.388526)
		(width 0.12954)
		(layer "F.Cu")
		(net "P3E_CPU1_P4_TX_C_DP<1>")
	)
	(segment
		(start 180.01234 -47.388526)
		(end 180.261768 -47.139098)
		(width 0.12954)
		(layer "F.Cu")
		(net "P3E_CPU1_P4_TX_C_DP<1>")
	)
	(segment
		(start 177.108358 -47.29988)
		(end 177.794666 -47.29988)
		(width 0.12954)
		(layer "F.Cu")
		(net "P3E_CPU1_P4_TX_C_DP<1>")
	)
	(segment
		(start 179.964334 -44.388532)
		(end 180.261768 -44.091098)
		(width 0.12954)
		(layer "F.Cu")
		(net "P3E_CPU1_P4_TX_C_DP<0>")
	)
	(segment
		(start 177.108358 -44.299886)
		(end 177.794666 -44.299886)
		(width 0.12954)
		(layer "F.Cu")
		(net "P3E_CPU1_P4_TX_C_DP<0>")
	)
	(segment
		(start 177.883312 -44.388532)
		(end 179.964334 -44.388532)
		(width 0.12954)
		(layer "F.Cu")
		(net "P3E_CPU1_P4_TX_C_DP<0>")
	)
	(segment
		(start 177.794666 -44.299886)
		(end 177.883312 -44.388532)
		(width 0.12954)
		(layer "F.Cu")
		(net "P3E_CPU1_P4_TX_C_DP<0>")
	)
	(segment
		(start 180.261768 -53.980334)
		(end 179.992528 -53.711094)
		(width 0.12954)
		(layer "F.Cu")
		(net "P3E_CPU1_P4_TX_C_DN<3>")
	)
	(segment
		(start 179.992528 -53.711094)
		(end 177.8762 -53.711094)
		(width 0.12954)
		(layer "F.Cu")
		(net "P3E_CPU1_P4_TX_C_DN<3>")
	)
	(segment
		(start 177.7873 -53.799994)
		(end 177.108358 -53.799994)
		(width 0.12954)
		(layer "F.Cu")
		(net "P3E_CPU1_P4_TX_C_DN<3>")
	)
	(segment
		(start 177.8762 -53.711094)
		(end 177.7873 -53.799994)
		(width 0.12954)
		(layer "F.Cu")
		(net "P3E_CPU1_P4_TX_C_DN<3>")
	)
	(segment
		(start 177.8762 -50.7111)
		(end 179.99837 -50.7111)
		(width 0.12954)
		(layer "F.Cu")
		(net "P3E_CPU1_P4_TX_C_DN<2>")
	)
	(segment
		(start 179.99837 -50.7111)
		(end 180.261768 -50.974498)
		(width 0.12954)
		(layer "F.Cu")
		(net "P3E_CPU1_P4_TX_C_DN<2>")
	)
	(segment
		(start 177.108358 -50.8)
		(end 177.7873 -50.8)
		(width 0.12954)
		(layer "F.Cu")
		(net "P3E_CPU1_P4_TX_C_DN<2>")
	)
	(segment
		(start 177.7873 -50.8)
		(end 177.8762 -50.7111)
		(width 0.12954)
		(layer "F.Cu")
		(net "P3E_CPU1_P4_TX_C_DN<2>")
	)
	(segment
		(start 177.8762 -47.711106)
		(end 179.919376 -47.711106)
		(width 0.12954)
		(layer "F.Cu")
		(net "P3E_CPU1_P4_TX_C_DN<1>")
	)
	(segment
		(start 177.108358 -47.800006)
		(end 177.7873 -47.800006)
		(width 0.12954)
		(layer "F.Cu")
		(net "P3E_CPU1_P4_TX_C_DN<1>")
	)
	(segment
		(start 179.919376 -47.711106)
		(end 180.261768 -48.053498)
		(width 0.12954)
		(layer "F.Cu")
		(net "P3E_CPU1_P4_TX_C_DN<1>")
	)
	(segment
		(start 177.7873 -47.800006)
		(end 177.8762 -47.711106)
		(width 0.12954)
		(layer "F.Cu")
		(net "P3E_CPU1_P4_TX_C_DN<1>")
	)
	(segment
		(start 177.108358 -44.800012)
		(end 177.7873 -44.800012)
		(width 0.12954)
		(layer "F.Cu")
		(net "P3E_CPU1_P4_TX_C_DN<0>")
	)
	(segment
		(start 177.8762 -44.711112)
		(end 179.967382 -44.711112)
		(width 0.12954)
		(layer "F.Cu")
		(net "P3E_CPU1_P4_TX_C_DN<0>")
	)
	(segment
		(start 177.7873 -44.800012)
		(end 177.8762 -44.711112)
		(width 0.12954)
		(layer "F.Cu")
		(net "P3E_CPU1_P4_TX_C_DN<0>")
	)
	(segment
		(start 179.967382 -44.711112)
		(end 180.261768 -45.005498)
		(width 0.12954)
		(layer "F.Cu")
		(net "P3E_CPU1_P4_TX_C_DN<0>")
	)
	(segment
		(start 237.079536 -58.164984)
		(end 236.599984 -58.164984)
		(width 0.12954)
		(layer "F.Cu")
		(net "P3E_CPU0_P4_TX_C_DP<3>")
	)
	(segment
		(start 238.584994 -58.0263)
		(end 237.21822 -58.0263)
		(width 0.12954)
		(layer "F.Cu")
		(net "P3E_CPU0_P4_TX_C_DP<3>")
	)
	(segment
		(start 238.885984 -58.32729)
		(end 238.584994 -58.0263)
		(width 0.12954)
		(layer "F.Cu")
		(net "P3E_CPU0_P4_TX_C_DP<3>")
	)
	(segment
		(start 237.21822 -58.0263)
		(end 237.079536 -58.164984)
		(width 0.12954)
		(layer "F.Cu")
		(net "P3E_CPU0_P4_TX_C_DP<3>")
	)
	(segment
		(start 237.195868 -55.903622)
		(end 237.057184 -55.764938)
		(width 0.12954)
		(layer "F.Cu")
		(net "P3E_CPU0_P4_TX_C_DP<2>")
	)
	(segment
		(start 240.296954 -55.903622)
		(end 237.195868 -55.903622)
		(width 0.12954)
		(layer "F.Cu")
		(net "P3E_CPU0_P4_TX_C_DP<2>")
	)
	(segment
		(start 240.587784 -55.612792)
		(end 240.296954 -55.903622)
		(width 0.12954)
		(layer "F.Cu")
		(net "P3E_CPU0_P4_TX_C_DP<2>")
	)
	(segment
		(start 237.057184 -55.764938)
		(end 236.599984 -55.764938)
		(width 0.12954)
		(layer "F.Cu")
		(net "P3E_CPU0_P4_TX_C_DP<2>")
	)
	(segment
		(start 237.049056 -53.965094)
		(end 236.599984 -53.965094)
		(width 0.12954)
		(layer "F.Cu")
		(net "P3E_CPU0_P4_TX_C_DP<1>")
	)
	(segment
		(start 237.18774 -54.103778)
		(end 237.049056 -53.965094)
		(width 0.12954)
		(layer "F.Cu")
		(net "P3E_CPU0_P4_TX_C_DP<1>")
	)
	(segment
		(start 238.604044 -54.103778)
		(end 237.18774 -54.103778)
		(width 0.12954)
		(layer "F.Cu")
		(net "P3E_CPU0_P4_TX_C_DP<1>")
	)
	(segment
		(start 238.885984 -53.821838)
		(end 238.604044 -54.103778)
		(width 0.12954)
		(layer "F.Cu")
		(net "P3E_CPU0_P4_TX_C_DP<1>")
	)
	(segment
		(start 237.184692 -52.30368)
		(end 237.046008 -52.164996)
		(width 0.12954)
		(layer "F.Cu")
		(net "P3E_CPU0_P4_TX_C_DP<0>")
	)
	(segment
		(start 238.595154 -52.30368)
		(end 237.184692 -52.30368)
		(width 0.12954)
		(layer "F.Cu")
		(net "P3E_CPU0_P4_TX_C_DP<0>")
	)
	(segment
		(start 237.046008 -52.164996)
		(end 236.599984 -52.164996)
		(width 0.12954)
		(layer "F.Cu")
		(net "P3E_CPU0_P4_TX_C_DP<0>")
	)
	(segment
		(start 238.885984 -52.01285)
		(end 238.595154 -52.30368)
		(width 0.12954)
		(layer "F.Cu")
		(net "P3E_CPU0_P4_TX_C_DP<0>")
	)
	(segment
		(start 238.595154 -57.70372)
		(end 237.221268 -57.70372)
		(width 0.12954)
		(layer "F.Cu")
		(net "P3E_CPU0_P4_TX_C_DN<3>")
	)
	(segment
		(start 237.221268 -57.70372)
		(end 237.082584 -57.565036)
		(width 0.12954)
		(layer "F.Cu")
		(net "P3E_CPU0_P4_TX_C_DN<3>")
	)
	(segment
		(start 238.885984 -57.41289)
		(end 238.595154 -57.70372)
		(width 0.12954)
		(layer "F.Cu")
		(net "P3E_CPU0_P4_TX_C_DN<3>")
	)
	(segment
		(start 237.082584 -57.565036)
		(end 236.599984 -57.565036)
		(width 0.12954)
		(layer "F.Cu")
		(net "P3E_CPU0_P4_TX_C_DN<3>")
	)
	(segment
		(start 240.587784 -56.527192)
		(end 240.286794 -56.226202)
		(width 0.12954)
		(layer "F.Cu")
		(net "P3E_CPU0_P4_TX_C_DN<2>")
	)
	(segment
		(start 240.286794 -56.226202)
		(end 237.232444 -56.226202)
		(width 0.12954)
		(layer "F.Cu")
		(net "P3E_CPU0_P4_TX_C_DN<2>")
	)
	(segment
		(start 237.232444 -56.226202)
		(end 237.09376 -56.364886)
		(width 0.12954)
		(layer "F.Cu")
		(net "P3E_CPU0_P4_TX_C_DN<2>")
	)
	(segment
		(start 237.09376 -56.364886)
		(end 236.599984 -56.364886)
		(width 0.12954)
		(layer "F.Cu")
		(net "P3E_CPU0_P4_TX_C_DN<2>")
	)
	(segment
		(start 237.073948 -54.565042)
		(end 236.599984 -54.565042)
		(width 0.12954)
		(layer "F.Cu")
		(net "P3E_CPU0_P4_TX_C_DN<1>")
	)
	(segment
		(start 238.885984 -54.736238)
		(end 238.576104 -54.426358)
		(width 0.12954)
		(layer "F.Cu")
		(net "P3E_CPU0_P4_TX_C_DN<1>")
	)
	(segment
		(start 238.576104 -54.426358)
		(end 237.212632 -54.426358)
		(width 0.12954)
		(layer "F.Cu")
		(net "P3E_CPU0_P4_TX_C_DN<1>")
	)
	(segment
		(start 237.212632 -54.426358)
		(end 237.073948 -54.565042)
		(width 0.12954)
		(layer "F.Cu")
		(net "P3E_CPU0_P4_TX_C_DN<1>")
	)
	(segment
		(start 237.071408 -52.764944)
		(end 236.599984 -52.764944)
		(width 0.12954)
		(layer "F.Cu")
		(net "P3E_CPU0_P4_TX_C_DN<0>")
	)
	(segment
		(start 237.210092 -52.62626)
		(end 237.071408 -52.764944)
		(width 0.12954)
		(layer "F.Cu")
		(net "P3E_CPU0_P4_TX_C_DN<0>")
	)
	(segment
		(start 238.885984 -52.92725)
		(end 238.584994 -52.62626)
		(width 0.12954)
		(layer "F.Cu")
		(net "P3E_CPU0_P4_TX_C_DN<0>")
	)
	(segment
		(start 238.584994 -52.62626)
		(end 237.210092 -52.62626)
		(width 0.12954)
		(layer "F.Cu")
		(net "P3E_CPU0_P4_TX_C_DN<0>")
	)
	(segment
		(start 29.295344 -421.069008)
		(end 29.757878 -421.531542)
		(width 0.12954)
		(layer "F.Cu")
		(net "P2E_MB_BMC_TX_BUF_DP<0>")
	)
	(segment
		(start 30.214062 -421.531542)
		(end 32.031432 -423.348912)
		(width 0.12954)
		(layer "F.Cu")
		(net "P2E_MB_BMC_TX_BUF_DP<0>")
	)
	(segment
		(start 32.751268 -423.31005)
		(end 33.002728 -423.31005)
		(width 0.12954)
		(layer "F.Cu")
		(net "P2E_MB_BMC_TX_BUF_DP<0>")
	)
	(segment
		(start 32.031432 -423.348912)
		(end 32.712406 -423.348912)
		(width 0.12954)
		(layer "F.Cu")
		(net "P2E_MB_BMC_TX_BUF_DP<0>")
	)
	(segment
		(start 28.93695 -421.069008)
		(end 29.295344 -421.069008)
		(width 0.12954)
		(layer "F.Cu")
		(net "P2E_MB_BMC_TX_BUF_DP<0>")
	)
	(segment
		(start 32.712406 -423.348912)
		(end 32.751268 -423.31005)
		(width 0.12954)
		(layer "F.Cu")
		(net "P2E_MB_BMC_TX_BUF_DP<0>")
	)
	(segment
		(start 29.757878 -421.531542)
		(end 30.214062 -421.531542)
		(width 0.12954)
		(layer "F.Cu")
		(net "P2E_MB_BMC_TX_BUF_DP<0>")
	)
	(segment
		(start 32.712406 -423.671492)
		(end 32.751014 -423.7101)
		(width 0.12954)
		(layer "F.Cu")
		(net "P2E_MB_BMC_TX_BUF_DN<0>")
	)
	(segment
		(start 32.751014 -423.7101)
		(end 33.002728 -423.7101)
		(width 0.12954)
		(layer "F.Cu")
		(net "P2E_MB_BMC_TX_BUF_DN<0>")
	)
	(segment
		(start 30.080204 -421.854122)
		(end 31.897574 -423.671492)
		(width 0.12954)
		(layer "F.Cu")
		(net "P2E_MB_BMC_TX_BUF_DN<0>")
	)
	(segment
		(start 31.897574 -423.671492)
		(end 32.712406 -423.671492)
		(width 0.12954)
		(layer "F.Cu")
		(net "P2E_MB_BMC_TX_BUF_DN<0>")
	)
	(segment
		(start 29.349954 -422.330626)
		(end 29.826458 -421.854122)
		(width 0.12954)
		(layer "F.Cu")
		(net "P2E_MB_BMC_TX_BUF_DN<0>")
	)
	(segment
		(start 29.826458 -421.854122)
		(end 30.080204 -421.854122)
		(width 0.12954)
		(layer "F.Cu")
		(net "P2E_MB_BMC_TX_BUF_DN<0>")
	)
	(segment
		(start 28.93568 -422.330626)
		(end 29.349954 -422.330626)
		(width 0.12954)
		(layer "F.Cu")
		(net "P2E_MB_BMC_TX_BUF_DN<0>")
	)
	(segment
		(start 37.92982 -426.071284)
		(end 35.792918 -426.071284)
		(width 0.12954)
		(layer "F.Cu")
		(net "P2E_MB_BMC_RX_BUF_C_DP<0>")
	)
	(segment
		(start 38.422072 -426.563536)
		(end 37.92982 -426.071284)
		(width 0.12954)
		(layer "F.Cu")
		(net "P2E_MB_BMC_RX_BUF_C_DP<0>")
	)
	(segment
		(start 38.75024 -426.563536)
		(end 38.422072 -426.563536)
		(width 0.12954)
		(layer "F.Cu")
		(net "P2E_MB_BMC_RX_BUF_C_DP<0>")
	)
	(segment
		(start 35.792918 -426.071284)
		(end 35.754056 -426.110146)
		(width 0.12954)
		(layer "F.Cu")
		(net "P2E_MB_BMC_RX_BUF_C_DP<0>")
	)
	(segment
		(start 35.754056 -426.110146)
		(end 35.502596 -426.110146)
		(width 0.12954)
		(layer "F.Cu")
		(net "P2E_MB_BMC_RX_BUF_C_DP<0>")
	)
	(segment
		(start 38.75024 -425.256706)
		(end 38.415976 -425.256706)
		(width 0.12954)
		(layer "F.Cu")
		(net "P2E_MB_BMC_RX_BUF_C_DN<0>")
	)
	(segment
		(start 37.923978 -425.748704)
		(end 35.792918 -425.748704)
		(width 0.12954)
		(layer "F.Cu")
		(net "P2E_MB_BMC_RX_BUF_C_DN<0>")
	)
	(segment
		(start 38.415976 -425.256706)
		(end 37.923978 -425.748704)
		(width 0.12954)
		(layer "F.Cu")
		(net "P2E_MB_BMC_RX_BUF_C_DN<0>")
	)
	(segment
		(start 35.792918 -425.748704)
		(end 35.75431 -425.710096)
		(width 0.12954)
		(layer "F.Cu")
		(net "P2E_MB_BMC_RX_BUF_C_DN<0>")
	)
	(segment
		(start 35.75431 -425.710096)
		(end 35.502596 -425.710096)
		(width 0.12954)
		(layer "F.Cu")
		(net "P2E_MB_BMC_RX_BUF_C_DN<0>")
	)
	(segment
		(start 169.127424 -12.879578)
		(end 169.127424 -12.365736)
		(width 0.12954)
		(layer "F.Cu")
		(net "P2E_CPU0_P5_TX_C_DP")
	)
	(segment
		(start 169.267124 -13.599922)
		(end 169.267124 -13.019278)
		(width 0.12954)
		(layer "F.Cu")
		(net "P2E_CPU0_P5_TX_C_DP")
	)
	(segment
		(start 165.77691 -8.473694)
		(end 163.657534 -8.473694)
		(width 0.12954)
		(layer "F.Cu")
		(net "P2E_CPU0_P5_TX_C_DP")
	)
	(segment
		(start 167.188642 -9.058402)
		(end 165.77691 -8.473694)
		(width 0.12954)
		(layer "F.Cu")
		(net "P2E_CPU0_P5_TX_C_DP")
	)
	(segment
		(start 160.263078 -19.596354)
		(end 160.057338 -19.802094)
		(width 0.12954)
		(layer "F.Cu")
		(net "P2E_CPU0_P5_TX_C_DP")
	)
	(segment
		(start 160.263078 -11.748516)
		(end 160.263078 -19.596354)
		(width 0.12954)
		(layer "F.Cu")
		(net "P2E_CPU0_P5_TX_C_DP")
	)
	(segment
		(start 169.127424 -12.365736)
		(end 168.159938 -10.029698)
		(width 0.12954)
		(layer "F.Cu")
		(net "P2E_CPU0_P5_TX_C_DP")
	)
	(segment
		(start 169.267124 -13.019278)
		(end 169.127424 -12.879578)
		(width 0.12954)
		(layer "F.Cu")
		(net "P2E_CPU0_P5_TX_C_DP")
	)
	(segment
		(start 162.596068 -8.913368)
		(end 160.618678 -10.890758)
		(width 0.12954)
		(layer "F.Cu")
		(net "P2E_CPU0_P5_TX_C_DP")
	)
	(segment
		(start 163.657534 -8.473694)
		(end 162.596068 -8.913368)
		(width 0.12954)
		(layer "F.Cu")
		(net "P2E_CPU0_P5_TX_C_DP")
	)
	(segment
		(start 168.159938 -10.029698)
		(end 167.188642 -9.058402)
		(width 0.12954)
		(layer "F.Cu")
		(net "P2E_CPU0_P5_TX_C_DP")
	)
	(segment
		(start 160.618678 -10.890758)
		(end 160.263078 -11.748516)
		(width 0.12954)
		(layer "F.Cu")
		(net "P2E_CPU0_P5_TX_C_DP")
	)
	(segment
		(start 160.585658 -14.924786)
		(end 160.776158 -15.115286)
		(width 0.12954)
		(layer "F.Cu")
		(net "P2E_CPU0_P5_TX_C_DN")
	)
	(segment
		(start 160.776158 -17.421606)
		(end 160.776158 -17.807686)
		(width 0.12954)
		(layer "F.Cu")
		(net "P2E_CPU0_P5_TX_C_DN")
	)
	(segment
		(start 168.666922 -13.019532)
		(end 168.804844 -12.88161)
		(width 0.12954)
		(layer "F.Cu")
		(net "P2E_CPU0_P5_TX_C_DN")
	)
	(segment
		(start 160.776158 -16.268446)
		(end 160.776158 -16.654526)
		(width 0.12954)
		(layer "F.Cu")
		(net "P2E_CPU0_P5_TX_C_DN")
	)
	(segment
		(start 160.776158 -17.807686)
		(end 160.585658 -17.998186)
		(width 0.12954)
		(layer "F.Cu")
		(net "P2E_CPU0_P5_TX_C_DN")
	)
	(segment
		(start 168.804844 -12.429998)
		(end 167.88638 -10.212578)
		(width 0.12954)
		(layer "F.Cu")
		(net "P2E_CPU0_P5_TX_C_DN")
	)
	(segment
		(start 160.585658 -16.845026)
		(end 160.585658 -17.231106)
		(width 0.12954)
		(layer "F.Cu")
		(net "P2E_CPU0_P5_TX_C_DN")
	)
	(segment
		(start 160.585658 -14.538706)
		(end 160.585658 -14.924786)
		(width 0.12954)
		(layer "F.Cu")
		(net "P2E_CPU0_P5_TX_C_DN")
	)
	(segment
		(start 160.776158 -12.949682)
		(end 160.585658 -13.140182)
		(width 0.12954)
		(layer "F.Cu")
		(net "P2E_CPU0_P5_TX_C_DN")
	)
	(segment
		(start 160.776158 -13.962126)
		(end 160.776158 -14.348206)
		(width 0.12954)
		(layer "F.Cu")
		(net "P2E_CPU0_P5_TX_C_DN")
	)
	(segment
		(start 160.585658 -13.140182)
		(end 160.585658 -13.771626)
		(width 0.12954)
		(layer "F.Cu")
		(net "P2E_CPU0_P5_TX_C_DN")
	)
	(segment
		(start 160.776158 -15.115286)
		(end 160.776158 -15.501366)
		(width 0.12954)
		(layer "F.Cu")
		(net "P2E_CPU0_P5_TX_C_DN")
	)
	(segment
		(start 167.005762 -9.33196)
		(end 165.712648 -8.796274)
		(width 0.12954)
		(layer "F.Cu")
		(net "P2E_CPU0_P5_TX_C_DN")
	)
	(segment
		(start 160.585658 -15.691866)
		(end 160.585658 -16.077946)
		(width 0.12954)
		(layer "F.Cu")
		(net "P2E_CPU0_P5_TX_C_DN")
	)
	(segment
		(start 160.776158 -16.654526)
		(end 160.585658 -16.845026)
		(width 0.12954)
		(layer "F.Cu")
		(net "P2E_CPU0_P5_TX_C_DN")
	)
	(segment
		(start 160.585658 -16.077946)
		(end 160.776158 -16.268446)
		(width 0.12954)
		(layer "F.Cu")
		(net "P2E_CPU0_P5_TX_C_DN")
	)
	(segment
		(start 160.776158 -15.501366)
		(end 160.585658 -15.691866)
		(width 0.12954)
		(layer "F.Cu")
		(net "P2E_CPU0_P5_TX_C_DN")
	)
	(segment
		(start 160.585658 -19.151346)
		(end 160.585658 -19.53133)
		(width 0.12954)
		(layer "F.Cu")
		(net "P2E_CPU0_P5_TX_C_DN")
	)
	(segment
		(start 162.778948 -9.186926)
		(end 160.892236 -11.073638)
		(width 0.12954)
		(layer "F.Cu")
		(net "P2E_CPU0_P5_TX_C_DN")
	)
	(segment
		(start 160.585658 -19.53133)
		(end 160.856422 -19.802094)
		(width 0.12954)
		(layer "F.Cu")
		(net "P2E_CPU0_P5_TX_C_DN")
	)
	(segment
		(start 160.585658 -17.231106)
		(end 160.776158 -17.421606)
		(width 0.12954)
		(layer "F.Cu")
		(net "P2E_CPU0_P5_TX_C_DN")
	)
	(segment
		(start 163.721796 -8.796274)
		(end 162.778948 -9.186926)
		(width 0.12954)
		(layer "F.Cu")
		(net "P2E_CPU0_P5_TX_C_DN")
	)
	(segment
		(start 160.585658 -12.373102)
		(end 160.776158 -12.563602)
		(width 0.12954)
		(layer "F.Cu")
		(net "P2E_CPU0_P5_TX_C_DN")
	)
	(segment
		(start 168.804844 -12.88161)
		(end 168.804844 -12.429998)
		(width 0.12954)
		(layer "F.Cu")
		(net "P2E_CPU0_P5_TX_C_DN")
	)
	(segment
		(start 160.892236 -11.073638)
		(end 160.585658 -11.812778)
		(width 0.12954)
		(layer "F.Cu")
		(net "P2E_CPU0_P5_TX_C_DN")
	)
	(segment
		(start 160.585658 -11.812778)
		(end 160.585658 -12.373102)
		(width 0.12954)
		(layer "F.Cu")
		(net "P2E_CPU0_P5_TX_C_DN")
	)
	(segment
		(start 165.712648 -8.796274)
		(end 163.721796 -8.796274)
		(width 0.12954)
		(layer "F.Cu")
		(net "P2E_CPU0_P5_TX_C_DN")
	)
	(segment
		(start 160.776158 -18.574766)
		(end 160.776158 -18.960846)
		(width 0.12954)
		(layer "F.Cu")
		(net "P2E_CPU0_P5_TX_C_DN")
	)
	(segment
		(start 160.776158 -12.563602)
		(end 160.776158 -12.949682)
		(width 0.12954)
		(layer "F.Cu")
		(net "P2E_CPU0_P5_TX_C_DN")
	)
	(segment
		(start 160.585658 -17.998186)
		(end 160.585658 -18.384266)
		(width 0.12954)
		(layer "F.Cu")
		(net "P2E_CPU0_P5_TX_C_DN")
	)
	(segment
		(start 167.88638 -10.212578)
		(end 167.005762 -9.33196)
		(width 0.12954)
		(layer "F.Cu")
		(net "P2E_CPU0_P5_TX_C_DN")
	)
	(segment
		(start 160.776158 -18.960846)
		(end 160.585658 -19.151346)
		(width 0.12954)
		(layer "F.Cu")
		(net "P2E_CPU0_P5_TX_C_DN")
	)
	(segment
		(start 160.585658 -13.771626)
		(end 160.776158 -13.962126)
		(width 0.12954)
		(layer "F.Cu")
		(net "P2E_CPU0_P5_TX_C_DN")
	)
	(segment
		(start 168.666922 -13.599922)
		(end 168.666922 -13.019532)
		(width 0.12954)
		(layer "F.Cu")
		(net "P2E_CPU0_P5_TX_C_DN")
	)
	(segment
		(start 160.776158 -14.348206)
		(end 160.585658 -14.538706)
		(width 0.12954)
		(layer "F.Cu")
		(net "P2E_CPU0_P5_TX_C_DN")
	)
	(segment
		(start 160.585658 -18.384266)
		(end 160.776158 -18.574766)
		(width 0.12954)
		(layer "F.Cu")
		(net "P2E_CPU0_P5_TX_C_DN")
	)
	(segment
		(start 36.411662 -429.390048)
		(end 35.395662 -429.390048)
		(width 0.10668)
		(layer "F.Cu")
		(net "FM_P2E_SWB")
	)
	(segment
		(start 34.652712 -428.077376)
		(end 34.652712 -426.96003)
		(width 0.10668)
		(layer "F.Cu")
		(net "FM_P2E_SWB")
	)
	(segment
		(start 35.395662 -429.390048)
		(end 35.395662 -428.820326)
		(width 0.10668)
		(layer "F.Cu")
		(net "FM_P2E_SWB")
	)
	(segment
		(start 34.906458 -428.331122)
		(end 34.652712 -428.077376)
		(width 0.10668)
		(layer "F.Cu")
		(net "FM_P2E_SWB")
	)
	(segment
		(start 35.395662 -428.820326)
		(end 34.906458 -428.331122)
		(width 0.10668)
		(layer "F.Cu")
		(net "FM_P2E_SWB")
	)
	(segment
		(start 37.402262 -429.390048)
		(end 36.411662 -429.390048)
		(width 0.10668)
		(layer "F.Cu")
		(net "FM_P2E_SWB")
	)
	(via
		(at 34.906458 -428.331122)
		(size 0.762)
		(drill 0.381)
		(layers "F.Cu" "B.Cu")
		(net "FM_P2E_SWB")
	)
	(segment
		(start 35.649662 -419.649148)
		(end 36.640262 -419.649148)
		(width 0.10668)
		(layer "F.Cu")
		(net "FM_P2E_SWA")
	)
	(segment
		(start 36.640262 -420.584122)
		(end 34.949638 -420.584122)
		(width 0.10668)
		(layer "F.Cu")
		(net "FM_P2E_SWA")
	)
	(segment
		(start 36.640262 -419.649148)
		(end 36.640262 -420.584122)
		(width 0.10668)
		(layer "F.Cu")
		(net "FM_P2E_SWA")
	)
	(segment
		(start 34.949638 -420.584122)
		(end 34.652712 -420.881048)
		(width 0.10668)
		(layer "F.Cu")
		(net "FM_P2E_SWA")
	)
	(segment
		(start 34.652712 -420.881048)
		(end 34.652712 -422.460166)
		(width 0.10668)
		(layer "F.Cu")
		(net "FM_P2E_SWA")
	)
	(segment
		(start 34.633662 -419.649148)
		(end 35.649662 -419.649148)
		(width 0.10668)
		(layer "F.Cu")
		(net "FM_P2E_SWA")
	)
	(via
		(at 36.640262 -420.584122)
		(size 0.762)
		(drill 0.381)
		(layers "F.Cu" "B.Cu")
		(net "FM_P2E_SWA")
	)
	(segment
		(start 38.037008 -421.219122)
		(end 38.694106 -420.562024)
		(width 0.10668)
		(layer "F.Cu")
		(net "FM_P2E_MODE")
	)
	(segment
		(start 35.795458 -421.219122)
		(end 37.148008 -421.219122)
		(width 0.10668)
		(layer "F.Cu")
		(net "FM_P2E_MODE")
	)
	(segment
		(start 37.681662 -419.649148)
		(end 38.697662 -419.649148)
		(width 0.10668)
		(layer "F.Cu")
		(net "FM_P2E_MODE")
	)
	(segment
		(start 37.148008 -421.219122)
		(end 38.037008 -421.219122)
		(width 0.10668)
		(layer "F.Cu")
		(net "FM_P2E_MODE")
	)
	(segment
		(start 35.052762 -422.460166)
		(end 35.052762 -421.961818)
		(width 0.10668)
		(layer "F.Cu")
		(net "FM_P2E_MODE")
	)
	(segment
		(start 38.694106 -420.562024)
		(end 38.697662 -420.558468)
		(width 0.10668)
		(layer "F.Cu")
		(net "FM_P2E_MODE")
	)
	(segment
		(start 35.052762 -421.961818)
		(end 35.795458 -421.219122)
		(width 0.10668)
		(layer "F.Cu")
		(net "FM_P2E_MODE")
	)
	(segment
		(start 38.697662 -420.558468)
		(end 38.697662 -419.649148)
		(width 0.10668)
		(layer "F.Cu")
		(net "FM_P2E_MODE")
	)
	(via
		(at 38.694106 -420.562024)
		(size 0.762)
		(drill 0.381)
		(layers "F.Cu" "B.Cu")
		(net "FM_P2E_MODE")
	)
	(segment
		(start 34.379662 -429.390048)
		(end 33.363662 -429.390048)
		(width 0.10668)
		(layer "F.Cu")
		(net "FM_P2E_FGB")
	)
	(segment
		(start 33.636458 -427.785276)
		(end 33.852612 -427.569122)
		(width 0.10668)
		(layer "F.Cu")
		(net "FM_P2E_FGB")
	)
	(segment
		(start 33.636458 -428.331122)
		(end 33.636458 -427.785276)
		(width 0.10668)
		(layer "F.Cu")
		(net "FM_P2E_FGB")
	)
	(segment
		(start 34.379662 -429.074326)
		(end 34.379662 -429.390048)
		(width 0.10668)
		(layer "F.Cu")
		(net "FM_P2E_FGB")
	)
	(segment
		(start 33.636458 -428.331122)
		(end 34.379662 -429.074326)
		(width 0.10668)
		(layer "F.Cu")
		(net "FM_P2E_FGB")
	)
	(segment
		(start 33.852612 -426.96003)
		(end 33.852612 -427.569122)
		(width 0.10668)
		(layer "F.Cu")
		(net "FM_P2E_FGB")
	)
	(segment
		(start 33.363662 -429.390048)
		(end 32.347662 -429.390048)
		(width 0.10668)
		(layer "F.Cu")
		(net "FM_P2E_FGB")
	)
	(via
		(at 33.636458 -428.331122)
		(size 0.762)
		(drill 0.381)
		(layers "F.Cu" "B.Cu")
		(net "FM_P2E_FGB")
	)
	(segment
		(start 31.585662 -419.649148)
		(end 32.601662 -419.649148)
		(width 0.10668)
		(layer "F.Cu")
		(net "FM_P2E_FGA")
	)
	(segment
		(start 33.852612 -420.800276)
		(end 33.852612 -422.460166)
		(width 0.10668)
		(layer "F.Cu")
		(net "FM_P2E_FGA")
	)
	(segment
		(start 33.852612 -420.800276)
		(end 33.617662 -420.565326)
		(width 0.10668)
		(layer "F.Cu")
		(net "FM_P2E_FGA")
	)
	(segment
		(start 33.617662 -419.649148)
		(end 33.617662 -420.565326)
		(width 0.10668)
		(layer "F.Cu")
		(net "FM_P2E_FGA")
	)
	(segment
		(start 32.601662 -419.649148)
		(end 33.617662 -419.649148)
		(width 0.10668)
		(layer "F.Cu")
		(net "FM_P2E_FGA")
	)
	(via
		(at 33.617662 -420.565326)
		(size 0.762)
		(drill 0.381)
		(layers "F.Cu" "B.Cu")
		(net "FM_P2E_FGA")
	)
	(segment
		(start 33.452562 -427.288198)
		(end 32.696658 -428.044102)
		(width 0.10668)
		(layer "F.Cu")
		(net "FM_P2E_EQB1")
	)
	(segment
		(start 29.299662 -429.359314)
		(end 30.315662 -429.359314)
		(width 0.10668)
		(layer "F.Cu")
		(net "FM_P2E_EQB1")
	)
	(segment
		(start 33.452562 -426.96003)
		(end 33.452562 -427.288198)
		(width 0.10668)
		(layer "F.Cu")
		(net "FM_P2E_EQB1")
	)
	(segment
		(start 31.331662 -428.458122)
		(end 31.331662 -429.359314)
		(width 0.10668)
		(layer "F.Cu")
		(net "FM_P2E_EQB1")
	)
	(segment
		(start 30.315662 -429.359314)
		(end 31.331662 -429.359314)
		(width 0.10668)
		(layer "F.Cu")
		(net "FM_P2E_EQB1")
	)
	(segment
		(start 31.745682 -428.044102)
		(end 31.331662 -428.458122)
		(width 0.10668)
		(layer "F.Cu")
		(net "FM_P2E_EQB1")
	)
	(segment
		(start 32.696658 -428.044102)
		(end 31.745682 -428.044102)
		(width 0.10668)
		(layer "F.Cu")
		(net "FM_P2E_EQB1")
	)
	(via
		(at 31.331662 -428.458122)
		(size 0.762)
		(drill 0.381)
		(layers "F.Cu" "B.Cu")
		(net "FM_P2E_EQB1")
	)
	(segment
		(start 33.002728 -424.909996)
		(end 30.961584 -424.909996)
		(width 0.10668)
		(layer "F.Cu")
		(net "FM_P2E_EQB0")
	)
	(segment
		(start 30.461458 -425.410122)
		(end 29.580332 -425.410122)
		(width 0.10668)
		(layer "F.Cu")
		(net "FM_P2E_EQB0")
	)
	(segment
		(start 30.961584 -424.909996)
		(end 30.461458 -425.410122)
		(width 0.10668)
		(layer "F.Cu")
		(net "FM_P2E_EQB0")
	)
	(segment
		(start 27.193494 -425.593256)
		(end 27.193494 -426.609256)
		(width 0.10668)
		(layer "F.Cu")
		(net "FM_P2E_EQB0")
	)
	(segment
		(start 29.580332 -425.410122)
		(end 29.445712 -425.275502)
		(width 0.10668)
		(layer "F.Cu")
		(net "FM_P2E_EQB0")
	)
	(segment
		(start 27.193494 -426.609256)
		(end 28.111958 -426.609256)
		(width 0.10668)
		(layer "F.Cu")
		(net "FM_P2E_EQB0")
	)
	(segment
		(start 28.111958 -426.609256)
		(end 29.445712 -425.275502)
		(width 0.10668)
		(layer "F.Cu")
		(net "FM_P2E_EQB0")
	)
	(via
		(at 30.461458 -425.410122)
		(size 0.762)
		(drill 0.381)
		(layers "F.Cu" "B.Cu")
		(net "FM_P2E_EQB0")
	)
	(segment
		(start 33.452562 -421.797226)
		(end 33.452562 -422.460166)
		(width 0.10668)
		(layer "F.Cu")
		(net "FM_P2E_EQA1")
	)
	(segment
		(start 32.672782 -421.017446)
		(end 33.452562 -421.797226)
		(width 0.10668)
		(layer "F.Cu")
		(net "FM_P2E_EQA1")
	)
	(segment
		(start 30.569662 -419.649148)
		(end 29.553662 -419.649148)
		(width 0.10668)
		(layer "F.Cu")
		(net "FM_P2E_EQA1")
	)
	(segment
		(start 28.537662 -419.649148)
		(end 29.553662 -419.649148)
		(width 0.10668)
		(layer "F.Cu")
		(net "FM_P2E_EQA1")
	)
	(segment
		(start 30.569662 -419.649148)
		(end 30.569662 -420.584122)
		(width 0.10668)
		(layer "F.Cu")
		(net "FM_P2E_EQA1")
	)
	(segment
		(start 32.239458 -420.584122)
		(end 32.672782 -421.017446)
		(width 0.10668)
		(layer "F.Cu")
		(net "FM_P2E_EQA1")
	)
	(segment
		(start 30.569662 -420.584122)
		(end 32.239458 -420.584122)
		(width 0.10668)
		(layer "F.Cu")
		(net "FM_P2E_EQA1")
	)
	(via
		(at 30.569662 -420.584122)
		(size 0.762)
		(drill 0.381)
		(layers "F.Cu" "B.Cu")
		(net "FM_P2E_EQA1")
	)
	(segment
		(start 33.002728 -424.5102)
		(end 30.831536 -424.5102)
		(width 0.10668)
		(layer "F.Cu")
		(net "FM_P2E_EQA0")
	)
	(segment
		(start 27.193494 -423.509694)
		(end 27.193494 -424.525694)
		(width 0.10668)
		(layer "F.Cu")
		(net "FM_P2E_EQA0")
	)
	(segment
		(start 30.831536 -424.5102)
		(end 30.461458 -424.140122)
		(width 0.10668)
		(layer "F.Cu")
		(net "FM_P2E_EQA0")
	)
	(segment
		(start 27.193494 -423.509694)
		(end 28.695904 -423.509694)
		(width 0.10668)
		(layer "F.Cu")
		(net "FM_P2E_EQA0")
	)
	(segment
		(start 28.695904 -423.509694)
		(end 29.445712 -424.259502)
		(width 0.10668)
		(layer "F.Cu")
		(net "FM_P2E_EQA0")
	)
	(segment
		(start 29.565092 -424.140122)
		(end 30.461458 -424.140122)
		(width 0.10668)
		(layer "F.Cu")
		(net "FM_P2E_EQA0")
	)
	(segment
		(start 29.445712 -424.259502)
		(end 29.565092 -424.140122)
		(width 0.10668)
		(layer "F.Cu")
		(net "FM_P2E_EQA0")
	)
	(via
		(at 30.461458 -424.140122)
		(size 0.762)
		(drill 0.381)
		(layers "F.Cu" "B.Cu")
		(net "FM_P2E_EQA0")
	)
	(segment
		(start 38.443662 -428.458122)
		(end 38.443662 -429.390048)
		(width 0.10668)
		(layer "F.Cu")
		(net "FM_P2E_EN_N")
	)
	(segment
		(start 37.827458 -428.458122)
		(end 37.700458 -428.585122)
		(width 0.10668)
		(layer "F.Cu")
		(net "FM_P2E_EN_N")
	)
	(segment
		(start 35.052762 -427.46168)
		(end 36.176204 -428.585122)
		(width 0.10668)
		(layer "F.Cu")
		(net "FM_P2E_EN_N")
	)
	(segment
		(start 38.443662 -428.458122)
		(end 37.827458 -428.458122)
		(width 0.10668)
		(layer "F.Cu")
		(net "FM_P2E_EN_N")
	)
	(segment
		(start 36.176204 -428.585122)
		(end 37.700458 -428.585122)
		(width 0.10668)
		(layer "F.Cu")
		(net "FM_P2E_EN_N")
	)
	(segment
		(start 35.052762 -426.96003)
		(end 35.052762 -427.46168)
		(width 0.10668)
		(layer "F.Cu")
		(net "FM_P2E_EN_N")
	)
	(via
		(at 38.443662 -428.458122)
		(size 0.762)
		(drill 0.381)
		(layers "F.Cu" "B.Cu")
		(net "FM_P2E_EN_N")
	)
	(segment
		(start 16.039592 -139.65809)
		(end 16.039592 -147.141438)
		(width 0.10668)
		(layer "F.Cu")
		(net "CLK_GEN2_GPU_FPGA_OE_OR_N")
	)
	(segment
		(start 40.494458 -430.190148)
		(end 40.494458 -430.949608)
		(width 0.10668)
		(layer "F.Cu")
		(net "CLK_GEN2_GPU_FPGA_OE_OR_N")
	)
	(segment
		(start 20.065746 -139.65809)
		(end 25.2349 -134.488936)
		(width 0.10668)
		(layer "F.Cu")
		(net "CLK_GEN2_GPU_FPGA_OE_OR_N")
	)
	(segment
		(start 16.039592 -147.141438)
		(end 14.383258 -148.797772)
		(width 0.10668)
		(layer "F.Cu")
		(net "CLK_GEN2_GPU_FPGA_OE_OR_N")
	)
	(segment
		(start 40.494458 -430.190148)
		(end 39.459662 -430.190148)
		(width 0.10668)
		(layer "F.Cu")
		(net "CLK_GEN2_GPU_FPGA_OE_OR_N")
	)
	(segment
		(start 39.459662 -430.190148)
		(end 38.443662 -430.190148)
		(width 0.10668)
		(layer "F.Cu")
		(net "CLK_GEN2_GPU_FPGA_OE_OR_N")
	)
	(segment
		(start 25.2349 -134.488936)
		(end 31.447994 -134.488936)
		(width 0.10668)
		(layer "F.Cu")
		(net "CLK_GEN2_GPU_FPGA_OE_OR_N")
	)
	(segment
		(start 16.039592 -139.65809)
		(end 20.065746 -139.65809)
		(width 0.10668)
		(layer "F.Cu")
		(net "CLK_GEN2_GPU_FPGA_OE_OR_N")
	)
	(segment
		(start 11.443208 -427.13783)
		(end 11.443208 -427.807882)
		(width 0.10668)
		(layer "F.Cu")
		(net "CLK_GEN2_GPU_FPGA_OE_OR_N")
	)
	(via
		(at 14.383258 -148.797772)
		(size 0.508)
		(drill 0.254)
		(layers "F.Cu" "B.Cu")
		(net "CLK_GEN2_GPU_FPGA_OE_OR_N")
	)
	(via
		(at 40.494458 -430.949608)
		(size 0.508)
		(drill 0.254)
		(layers "F.Cu" "B.Cu")
		(net "CLK_GEN2_GPU_FPGA_OE_OR_N")
	)
	(via
		(at 11.443208 -427.807882)
		(size 0.508)
		(drill 0.254)
		(layers "F.Cu" "B.Cu")
		(net "CLK_GEN2_GPU_FPGA_OE_OR_N")
	)
	(segment
		(start 31.502604 -393.514834)
		(end 30.86227 -391.969244)
		(width 0.11684)
		(layer "In4.Cu")
		(net "CLK_GEN2_GPU_FPGA_OE_OR_N")
	)
	(segment
		(start 21.149056 -417.99002)
		(end 21.149056 -416.973258)
		(width 0.11684)
		(layer "In4.Cu")
		(net "CLK_GEN2_GPU_FPGA_OE_OR_N")
	)
	(segment
		(start 11.340592 -362.635292)
		(end 11.340592 -356.865682)
		(width 0.11684)
		(layer "In4.Cu")
		(net "CLK_GEN2_GPU_FPGA_OE_OR_N")
	)
	(segment
		(start 30.86227 -391.969244)
		(end 30.682438 -391.06475)
		(width 0.11684)
		(layer "In4.Cu")
		(net "CLK_GEN2_GPU_FPGA_OE_OR_N")
	)
	(segment
		(start 20.306792 -418.832284)
		(end 21.149056 -417.99002)
		(width 0.11684)
		(layer "In4.Cu")
		(net "CLK_GEN2_GPU_FPGA_OE_OR_N")
	)
	(segment
		(start 22.813264 -369.314984)
		(end 18.020284 -369.314984)
		(width 0.11684)
		(layer "In4.Cu")
		(net "CLK_GEN2_GPU_FPGA_OE_OR_N")
	)
	(segment
		(start 28.946856 -375.448576)
		(end 22.813264 -369.314984)
		(width 0.11684)
		(layer "In4.Cu")
		(net "CLK_GEN2_GPU_FPGA_OE_OR_N")
	)
	(segment
		(start 4.585208 -350.110298)
		(end 4.585208 -345.465908)
		(width 0.11684)
		(layer "In4.Cu")
		(net "CLK_GEN2_GPU_FPGA_OE_OR_N")
	)
	(segment
		(start 30.682438 -391.06475)
		(end 30.682438 -379.63856)
		(width 0.11684)
		(layer "In4.Cu")
		(net "CLK_GEN2_GPU_FPGA_OE_OR_N")
	)
	(segment
		(start 34.532824 -410.021024)
		(end 34.532824 -396.545054)
		(width 0.11684)
		(layer "In4.Cu")
		(net "CLK_GEN2_GPU_FPGA_OE_OR_N")
	)
	(segment
		(start 4.647184 -345.403932)
		(end 4.647184 -158.533846)
		(width 0.11684)
		(layer "In4.Cu")
		(net "CLK_GEN2_GPU_FPGA_OE_OR_N")
	)
	(segment
		(start 34.532824 -396.545054)
		(end 31.502604 -393.514834)
		(width 0.11684)
		(layer "In4.Cu")
		(net "CLK_GEN2_GPU_FPGA_OE_OR_N")
	)
	(segment
		(start 18.020284 -369.314984)
		(end 11.340592 -362.635292)
		(width 0.11684)
		(layer "In4.Cu")
		(net "CLK_GEN2_GPU_FPGA_OE_OR_N")
	)
	(segment
		(start 4.647184 -158.533846)
		(end 14.383258 -148.797772)
		(width 0.11684)
		(layer "In4.Cu")
		(net "CLK_GEN2_GPU_FPGA_OE_OR_N")
	)
	(segment
		(start 12.188698 -422.3004)
		(end 15.656814 -418.832284)
		(width 0.11684)
		(layer "In4.Cu")
		(net "CLK_GEN2_GPU_FPGA_OE_OR_N")
	)
	(segment
		(start 11.443208 -427.807882)
		(end 12.188698 -427.062392)
		(width 0.11684)
		(layer "In4.Cu")
		(net "CLK_GEN2_GPU_FPGA_OE_OR_N")
	)
	(segment
		(start 24.031956 -414.090358)
		(end 30.46349 -414.090358)
		(width 0.11684)
		(layer "In4.Cu")
		(net "CLK_GEN2_GPU_FPGA_OE_OR_N")
	)
	(segment
		(start 30.682438 -379.63856)
		(end 28.946856 -375.448576)
		(width 0.11684)
		(layer "In4.Cu")
		(net "CLK_GEN2_GPU_FPGA_OE_OR_N")
	)
	(segment
		(start 30.46349 -414.090358)
		(end 34.532824 -410.021024)
		(width 0.11684)
		(layer "In4.Cu")
		(net "CLK_GEN2_GPU_FPGA_OE_OR_N")
	)
	(segment
		(start 21.149056 -416.973258)
		(end 24.031956 -414.090358)
		(width 0.11684)
		(layer "In4.Cu")
		(net "CLK_GEN2_GPU_FPGA_OE_OR_N")
	)
	(segment
		(start 4.585208 -345.465908)
		(end 4.647184 -345.403932)
		(width 0.11684)
		(layer "In4.Cu")
		(net "CLK_GEN2_GPU_FPGA_OE_OR_N")
	)
	(segment
		(start 11.340592 -356.865682)
		(end 4.585208 -350.110298)
		(width 0.11684)
		(layer "In4.Cu")
		(net "CLK_GEN2_GPU_FPGA_OE_OR_N")
	)
	(segment
		(start 12.188698 -427.062392)
		(end 12.188698 -422.3004)
		(width 0.11684)
		(layer "In4.Cu")
		(net "CLK_GEN2_GPU_FPGA_OE_OR_N")
	)
	(segment
		(start 15.656814 -418.832284)
		(end 20.306792 -418.832284)
		(width 0.11684)
		(layer "In4.Cu")
		(net "CLK_GEN2_GPU_FPGA_OE_OR_N")
	)
	(segment
		(start 23.030434 -427.11878)
		(end 12.13231 -427.11878)
		(width 0.11684)
		(layer "In13.Cu")
		(net "CLK_GEN2_GPU_FPGA_OE_OR_N")
	)
	(segment
		(start 30.935422 -430.070006)
		(end 30.745684 -430.259744)
		(width 0.11684)
		(layer "In13.Cu")
		(net "CLK_GEN2_GPU_FPGA_OE_OR_N")
	)
	(segment
		(start 26.171398 -430.259744)
		(end 23.030434 -427.11878)
		(width 0.11684)
		(layer "In13.Cu")
		(net "CLK_GEN2_GPU_FPGA_OE_OR_N")
	)
	(segment
		(start 39.614856 -430.070006)
		(end 30.935422 -430.070006)
		(width 0.11684)
		(layer "In13.Cu")
		(net "CLK_GEN2_GPU_FPGA_OE_OR_N")
	)
	(segment
		(start 30.745684 -430.259744)
		(end 26.171398 -430.259744)
		(width 0.11684)
		(layer "In13.Cu")
		(net "CLK_GEN2_GPU_FPGA_OE_OR_N")
	)
	(segment
		(start 12.13231 -427.11878)
		(end 11.443208 -427.807882)
		(width 0.11684)
		(layer "In13.Cu")
		(net "CLK_GEN2_GPU_FPGA_OE_OR_N")
	)
	(segment
		(start 40.494458 -430.949608)
		(end 39.614856 -430.070006)
		(width 0.11684)
		(layer "In13.Cu")
		(net "CLK_GEN2_GPU_FPGA_OE_OR_N")
	)
	(segment
		(start 216.009728 -56.447436)
		(end 216.009728 -55.855362)
		(width 0.254)
		(layer "F.Cu")
		(net "VSENSE_P3V3_INA230_2_INP")
	)
	(segment
		(start 216.278714 -56.716168)
		(end 216.27846 -56.716168)
		(width 0.254)
		(layer "F.Cu")
		(net "VSENSE_P3V3_INA230_2_INP")
	)
	(segment
		(start 216.27846 -56.716168)
		(end 216.009728 -56.447436)
		(width 0.254)
		(layer "F.Cu")
		(net "VSENSE_P3V3_INA230_2_INP")
	)
	(segment
		(start 219.457778 -57.518808)
		(end 218.411806 -57.518808)
		(width 0.254)
		(layer "F.Cu")
		(net "VSENSE_P3V3_INA230_2_INP")
	)
	(segment
		(start 218.411806 -57.518808)
		(end 218.130882 -57.799732)
		(width 0.254)
		(layer "F.Cu")
		(net "VSENSE_P3V3_INA230_2_INP")
	)
	(segment
		(start 217.152728 -57.590182)
		(end 216.278714 -56.716168)
		(width 0.254)
		(layer "F.Cu")
		(net "VSENSE_P3V3_INA230_2_INP")
	)
	(segment
		(start 219.790772 -57.851802)
		(end 219.457778 -57.518808)
		(width 0.254)
		(layer "F.Cu")
		(net "VSENSE_P3V3_INA230_2_INP")
	)
	(segment
		(start 217.921332 -57.590182)
		(end 217.152728 -57.590182)
		(width 0.254)
		(layer "F.Cu")
		(net "VSENSE_P3V3_INA230_2_INP")
	)
	(segment
		(start 218.130882 -57.799732)
		(end 217.921332 -57.590182)
		(width 0.254)
		(layer "F.Cu")
		(net "VSENSE_P3V3_INA230_2_INP")
	)
	(segment
		(start 219.488766 -57.137808)
		(end 219.790772 -56.835802)
		(width 0.254)
		(layer "F.Cu")
		(net "VSENSE_P3V3_INA230_2_INN")
	)
	(segment
		(start 216.659714 -56.55818)
		(end 216.659714 -55.205376)
		(width 0.254)
		(layer "F.Cu")
		(net "VSENSE_P3V3_INA230_2_INN")
	)
	(segment
		(start 217.921332 -57.209182)
		(end 217.310716 -57.209182)
		(width 0.254)
		(layer "F.Cu")
		(net "VSENSE_P3V3_INA230_2_INN")
	)
	(segment
		(start 217.310716 -57.209182)
		(end 216.659714 -56.55818)
		(width 0.254)
		(layer "F.Cu")
		(net "VSENSE_P3V3_INA230_2_INN")
	)
	(segment
		(start 218.130882 -56.999632)
		(end 218.269058 -57.137808)
		(width 0.254)
		(layer "F.Cu")
		(net "VSENSE_P3V3_INA230_2_INN")
	)
	(segment
		(start 218.130882 -56.999632)
		(end 217.921332 -57.209182)
		(width 0.254)
		(layer "F.Cu")
		(net "VSENSE_P3V3_INA230_2_INN")
	)
	(segment
		(start 218.269058 -57.137808)
		(end 219.488766 -57.137808)
		(width 0.254)
		(layer "F.Cu")
		(net "VSENSE_P3V3_INA230_2_INN")
	)
	(segment
		(start 438.14238 -92.334588)
		(end 439.036714 -92.334588)
		(width 0.254)
		(layer "F.Cu")
		(net "VSENSE_P3V3_INA230_1_INP")
	)
	(segment
		(start 439.036714 -92.334588)
		(end 439.225436 -92.52331)
		(width 0.254)
		(layer "F.Cu")
		(net "VSENSE_P3V3_INA230_1_INP")
	)
	(segment
		(start 439.68797 -92.427552)
		(end 439.937906 -92.677488)
		(width 0.254)
		(layer "F.Cu")
		(net "VSENSE_P3V3_INA230_1_INP")
	)
	(segment
		(start 435.72176 -92.909898)
		(end 435.51221 -92.700348)
		(width 0.254)
		(layer "F.Cu")
		(net "VSENSE_P3V3_INA230_1_INP")
	)
	(segment
		(start 435.737 -92.475558)
		(end 435.737 -91.745308)
		(width 0.254)
		(layer "F.Cu")
		(net "VSENSE_P3V3_INA230_1_INP")
	)
	(segment
		(start 435.72176 -93.817694)
		(end 435.72176 -92.909898)
		(width 0.254)
		(layer "F.Cu")
		(net "VSENSE_P3V3_INA230_1_INP")
	)
	(segment
		(start 437.02986 -91.222068)
		(end 438.14238 -92.334588)
		(width 0.254)
		(layer "F.Cu")
		(net "VSENSE_P3V3_INA230_1_INP")
	)
	(segment
		(start 436.26024 -91.222068)
		(end 437.02986 -91.222068)
		(width 0.254)
		(layer "F.Cu")
		(net "VSENSE_P3V3_INA230_1_INP")
	)
	(segment
		(start 433.036726 -93.922342)
		(end 433.359052 -94.244668)
		(width 0.254)
		(layer "F.Cu")
		(net "VSENSE_P3V3_INA230_1_INP")
	)
	(segment
		(start 435.51221 -92.700348)
		(end 435.737 -92.475558)
		(width 0.254)
		(layer "F.Cu")
		(net "VSENSE_P3V3_INA230_1_INP")
	)
	(segment
		(start 439.225436 -92.52331)
		(end 439.408824 -92.52331)
		(width 0.254)
		(layer "F.Cu")
		(net "VSENSE_P3V3_INA230_1_INP")
	)
	(segment
		(start 439.408824 -92.52331)
		(end 439.504582 -92.427552)
		(width 0.254)
		(layer "F.Cu")
		(net "VSENSE_P3V3_INA230_1_INP")
	)
	(segment
		(start 433.359052 -94.244668)
		(end 435.294786 -94.244668)
		(width 0.254)
		(layer "F.Cu")
		(net "VSENSE_P3V3_INA230_1_INP")
	)
	(segment
		(start 435.737 -91.745308)
		(end 436.26024 -91.222068)
		(width 0.254)
		(layer "F.Cu")
		(net "VSENSE_P3V3_INA230_1_INP")
	)
	(segment
		(start 435.294786 -94.244668)
		(end 435.72176 -93.817694)
		(width 0.254)
		(layer "F.Cu")
		(net "VSENSE_P3V3_INA230_1_INP")
	)
	(segment
		(start 439.504582 -92.427552)
		(end 439.68797 -92.427552)
		(width 0.254)
		(layer "F.Cu")
		(net "VSENSE_P3V3_INA230_1_INP")
	)
	(segment
		(start 435.452774 -94.625668)
		(end 436.10276 -93.975682)
		(width 0.254)
		(layer "F.Cu")
		(net "VSENSE_P3V3_INA230_1_INN")
	)
	(segment
		(start 436.118 -91.903296)
		(end 436.418228 -91.603068)
		(width 0.254)
		(layer "F.Cu")
		(net "VSENSE_P3V3_INA230_1_INN")
	)
	(segment
		(start 437.984392 -92.715588)
		(end 438.859422 -92.715588)
		(width 0.254)
		(layer "F.Cu")
		(net "VSENSE_P3V3_INA230_1_INN")
	)
	(segment
		(start 436.418228 -91.603068)
		(end 436.871872 -91.603068)
		(width 0.254)
		(layer "F.Cu")
		(net "VSENSE_P3V3_INA230_1_INN")
	)
	(segment
		(start 438.859422 -92.715588)
		(end 439.037984 -92.89415)
		(width 0.254)
		(layer "F.Cu")
		(net "VSENSE_P3V3_INA230_1_INN")
	)
	(segment
		(start 433.3494 -94.625668)
		(end 435.452774 -94.625668)
		(width 0.254)
		(layer "F.Cu")
		(net "VSENSE_P3V3_INA230_1_INN")
	)
	(segment
		(start 439.037984 -93.077538)
		(end 439.28792 -93.327474)
		(width 0.254)
		(layer "F.Cu")
		(net "VSENSE_P3V3_INA230_1_INN")
	)
	(segment
		(start 436.10276 -92.909898)
		(end 436.31231 -92.700348)
		(width 0.254)
		(layer "F.Cu")
		(net "VSENSE_P3V3_INA230_1_INN")
	)
	(segment
		(start 433.036726 -94.938342)
		(end 433.3494 -94.625668)
		(width 0.254)
		(layer "F.Cu")
		(net "VSENSE_P3V3_INA230_1_INN")
	)
	(segment
		(start 436.871872 -91.603068)
		(end 437.984392 -92.715588)
		(width 0.254)
		(layer "F.Cu")
		(net "VSENSE_P3V3_INA230_1_INN")
	)
	(segment
		(start 439.037984 -92.89415)
		(end 439.037984 -93.077538)
		(width 0.254)
		(layer "F.Cu")
		(net "VSENSE_P3V3_INA230_1_INN")
	)
	(segment
		(start 436.10276 -93.975682)
		(end 436.10276 -92.909898)
		(width 0.254)
		(layer "F.Cu")
		(net "VSENSE_P3V3_INA230_1_INN")
	)
	(segment
		(start 436.118 -92.506038)
		(end 436.118 -91.903296)
		(width 0.254)
		(layer "F.Cu")
		(net "VSENSE_P3V3_INA230_1_INN")
	)
	(segment
		(start 436.31231 -92.700348)
		(end 436.118 -92.506038)
		(width 0.254)
		(layer "F.Cu")
		(net "VSENSE_P3V3_INA230_1_INN")
	)
	(segment
		(start 207.772508 -35.522154)
		(end 206.891128 -35.522154)
		(width 0.254)
		(layer "F.Cu")
		(net "VSENSE_P12V_INA230_5_INP")
	)
	(via
		(at 206.891128 -35.522154)
		(size 0.508)
		(drill 0.254)
		(layers "F.Cu" "B.Cu")
		(net "VSENSE_P12V_INA230_5_INP")
	)
	(segment
		(start 206.24165 -35.049714)
		(end 206.24165 -35.775138)
		(width 0.254)
		(layer "B.Cu")
		(net "VSENSE_P12V_INA230_5_INP")
	)
	(segment
		(start 205.07833 -36.147248)
		(end 204.22743 -36.147248)
		(width 0.254)
		(layer "B.Cu")
		(net "VSENSE_P12V_INA230_5_INP")
	)
	(segment
		(start 207.497426 -35.894772)
		(end 207.497426 -34.918396)
		(width 0.254)
		(layer "B.Cu")
		(net "VSENSE_P12V_INA230_5_INP")
	)
	(segment
		(start 207.243426 -34.664396)
		(end 206.626968 -34.664396)
		(width 0.254)
		(layer "B.Cu")
		(net "VSENSE_P12V_INA230_5_INP")
	)
	(segment
		(start 207.497426 -34.918396)
		(end 207.243426 -34.664396)
		(width 0.254)
		(layer "B.Cu")
		(net "VSENSE_P12V_INA230_5_INP")
	)
	(segment
		(start 206.89443 -36.02482)
		(end 206.978758 -36.109148)
		(width 0.254)
		(layer "B.Cu")
		(net "VSENSE_P12V_INA230_5_INP")
	)
	(segment
		(start 206.626968 -34.664396)
		(end 206.24165 -35.049714)
		(width 0.254)
		(layer "B.Cu")
		(net "VSENSE_P12V_INA230_5_INP")
	)
	(segment
		(start 204.22743 -36.147248)
		(end 203.73213 -36.642548)
		(width 0.254)
		(layer "B.Cu")
		(net "VSENSE_P12V_INA230_5_INP")
	)
	(segment
		(start 206.891128 -35.522154)
		(end 206.89443 -36.02482)
		(width 0.254)
		(layer "B.Cu")
		(net "VSENSE_P12V_INA230_5_INP")
	)
	(segment
		(start 205.861158 -36.15563)
		(end 205.489048 -36.15563)
		(width 0.254)
		(layer "B.Cu")
		(net "VSENSE_P12V_INA230_5_INP")
	)
	(segment
		(start 207.28305 -36.109148)
		(end 207.497426 -35.894772)
		(width 0.254)
		(layer "B.Cu")
		(net "VSENSE_P12V_INA230_5_INP")
	)
	(segment
		(start 205.28788 -36.356798)
		(end 205.07833 -36.147248)
		(width 0.254)
		(layer "B.Cu")
		(net "VSENSE_P12V_INA230_5_INP")
	)
	(segment
		(start 206.24165 -35.775138)
		(end 205.861158 -36.15563)
		(width 0.254)
		(layer "B.Cu")
		(net "VSENSE_P12V_INA230_5_INP")
	)
	(segment
		(start 205.489048 -36.15563)
		(end 205.28788 -36.356798)
		(width 0.254)
		(layer "B.Cu")
		(net "VSENSE_P12V_INA230_5_INP")
	)
	(segment
		(start 206.978758 -36.109148)
		(end 207.28305 -36.109148)
		(width 0.254)
		(layer "B.Cu")
		(net "VSENSE_P12V_INA230_5_INP")
	)
	(segment
		(start 206.901034 -37.071808)
		(end 207.800702 -36.17214)
		(width 0.254)
		(layer "F.Cu")
		(net "VSENSE_P12V_INA230_5_INN")
	)
	(segment
		(start 207.800702 -36.17214)
		(end 208.422494 -36.17214)
		(width 0.254)
		(layer "F.Cu")
		(net "VSENSE_P12V_INA230_5_INN")
	)
	(via
		(at 206.901034 -37.071808)
		(size 0.508)
		(drill 0.254)
		(layers "F.Cu" "B.Cu")
		(net "VSENSE_P12V_INA230_5_INN")
	)
	(segment
		(start 205.505812 -35.77463)
		(end 205.28788 -35.556698)
		(width 0.254)
		(layer "B.Cu")
		(net "VSENSE_P12V_INA230_5_INN")
	)
	(segment
		(start 206.46898 -34.283396)
		(end 205.86065 -34.891726)
		(width 0.254)
		(layer "B.Cu")
		(net "VSENSE_P12V_INA230_5_INN")
	)
	(segment
		(start 205.86065 -35.61715)
		(end 205.70317 -35.77463)
		(width 0.254)
		(layer "B.Cu")
		(net "VSENSE_P12V_INA230_5_INN")
	)
	(segment
		(start 207.044036 -36.529772)
		(end 207.401414 -36.529772)
		(width 0.254)
		(layer "B.Cu")
		(net "VSENSE_P12V_INA230_5_INN")
	)
	(segment
		(start 207.878426 -34.760408)
		(end 207.401414 -34.283396)
		(width 0.254)
		(layer "B.Cu")
		(net "VSENSE_P12V_INA230_5_INN")
	)
	(segment
		(start 207.401414 -34.283396)
		(end 206.46898 -34.283396)
		(width 0.254)
		(layer "B.Cu")
		(net "VSENSE_P12V_INA230_5_INN")
	)
	(segment
		(start 205.07833 -35.766248)
		(end 204.12583 -35.766248)
		(width 0.254)
		(layer "B.Cu")
		(net "VSENSE_P12V_INA230_5_INN")
	)
	(segment
		(start 206.901034 -36.672774)
		(end 207.044036 -36.529772)
		(width 0.254)
		(layer "B.Cu")
		(net "VSENSE_P12V_INA230_5_INN")
	)
	(segment
		(start 204.12583 -35.766248)
		(end 203.73213 -35.372548)
		(width 0.254)
		(layer "B.Cu")
		(net "VSENSE_P12V_INA230_5_INN")
	)
	(segment
		(start 205.28788 -35.556698)
		(end 205.07833 -35.766248)
		(width 0.254)
		(layer "B.Cu")
		(net "VSENSE_P12V_INA230_5_INN")
	)
	(segment
		(start 205.70317 -35.77463)
		(end 205.505812 -35.77463)
		(width 0.254)
		(layer "B.Cu")
		(net "VSENSE_P12V_INA230_5_INN")
	)
	(segment
		(start 207.878426 -36.05276)
		(end 207.878426 -34.760408)
		(width 0.254)
		(layer "B.Cu")
		(net "VSENSE_P12V_INA230_5_INN")
	)
	(segment
		(start 207.401414 -36.529772)
		(end 207.878426 -36.05276)
		(width 0.254)
		(layer "B.Cu")
		(net "VSENSE_P12V_INA230_5_INN")
	)
	(segment
		(start 206.901034 -37.071808)
		(end 206.901034 -36.672774)
		(width 0.254)
		(layer "B.Cu")
		(net "VSENSE_P12V_INA230_5_INN")
	)
	(segment
		(start 205.86065 -34.891726)
		(end 205.86065 -35.61715)
		(width 0.254)
		(layer "B.Cu")
		(net "VSENSE_P12V_INA230_5_INN")
	)
	(segment
		(start 155.748228 -58.843926)
		(end 156.633926 -59.729624)
		(width 0.254)
		(layer "F.Cu")
		(net "VSENSE_P12V_INA230_4_INP")
	)
	(segment
		(start 158.23184 -59.729624)
		(end 156.633926 -59.729624)
		(width 0.254)
		(layer "F.Cu")
		(net "VSENSE_P12V_INA230_4_INP")
	)
	(segment
		(start 155.748228 -58.518806)
		(end 155.748228 -58.843926)
		(width 0.254)
		(layer "F.Cu")
		(net "VSENSE_P12V_INA230_4_INP")
	)
	(segment
		(start 159.401764 -58.5597)
		(end 158.23184 -59.729624)
		(width 0.254)
		(layer "F.Cu")
		(net "VSENSE_P12V_INA230_4_INP")
	)
	(segment
		(start 160.174686 -58.5597)
		(end 159.401764 -58.5597)
		(width 0.254)
		(layer "F.Cu")
		(net "VSENSE_P12V_INA230_4_INP")
	)
	(segment
		(start 160.282636 -58.66765)
		(end 160.174686 -58.5597)
		(width 0.254)
		(layer "F.Cu")
		(net "VSENSE_P12V_INA230_4_INP")
	)
	(segment
		(start 161.171636 -58.66765)
		(end 160.282636 -58.66765)
		(width 0.254)
		(layer "F.Cu")
		(net "VSENSE_P12V_INA230_4_INP")
	)
	(segment
		(start 156.576522 -57.86882)
		(end 157.539182 -58.83148)
		(width 0.254)
		(layer "F.Cu")
		(net "VSENSE_P12V_INA230_4_INN")
	)
	(segment
		(start 159.657796 -57.7596)
		(end 160.174686 -57.7596)
		(width 0.254)
		(layer "F.Cu")
		(net "VSENSE_P12V_INA230_4_INN")
	)
	(segment
		(start 160.282636 -57.65165)
		(end 160.174686 -57.7596)
		(width 0.254)
		(layer "F.Cu")
		(net "VSENSE_P12V_INA230_4_INN")
	)
	(segment
		(start 156.398468 -57.86882)
		(end 156.576522 -57.86882)
		(width 0.254)
		(layer "F.Cu")
		(net "VSENSE_P12V_INA230_4_INN")
	)
	(segment
		(start 161.171636 -57.65165)
		(end 160.282636 -57.65165)
		(width 0.254)
		(layer "F.Cu")
		(net "VSENSE_P12V_INA230_4_INN")
	)
	(segment
		(start 158.585916 -58.83148)
		(end 159.657796 -57.7596)
		(width 0.254)
		(layer "F.Cu")
		(net "VSENSE_P12V_INA230_4_INN")
	)
	(segment
		(start 157.539182 -58.83148)
		(end 158.585916 -58.83148)
		(width 0.254)
		(layer "F.Cu")
		(net "VSENSE_P12V_INA230_4_INN")
	)
	(segment
		(start 156.398214 -57.86882)
		(end 156.398468 -57.86882)
		(width 0.254)
		(layer "F.Cu")
		(net "VSENSE_P12V_INA230_4_INN")
	)
	(segment
		(start 79.61757 -58.68416)
		(end 78.92415 -58.68416)
		(width 0.254)
		(layer "F.Cu")
		(net "VSENSE_P12V_INA230_3_INP")
	)
	(segment
		(start 78.751938 -58.708036)
		(end 78.826106 -58.782204)
		(width 0.254)
		(layer "F.Cu")
		(net "VSENSE_P12V_INA230_3_INP")
	)
	(segment
		(start 75.608434 -56.518048)
		(end 77.798422 -58.708036)
		(width 0.254)
		(layer "F.Cu")
		(net "VSENSE_P12V_INA230_3_INP")
	)
	(segment
		(start 75.608434 -43.908726)
		(end 75.608434 -56.518048)
		(width 0.254)
		(layer "F.Cu")
		(net "VSENSE_P12V_INA230_3_INP")
	)
	(segment
		(start 73.458324 -41.758616)
		(end 75.608434 -43.908726)
		(width 0.254)
		(layer "F.Cu")
		(net "VSENSE_P12V_INA230_3_INP")
	)
	(segment
		(start 79.823056 -58.889646)
		(end 79.61757 -58.68416)
		(width 0.254)
		(layer "F.Cu")
		(net "VSENSE_P12V_INA230_3_INP")
	)
	(segment
		(start 78.92415 -58.68416)
		(end 78.826106 -58.782204)
		(width 0.254)
		(layer "F.Cu")
		(net "VSENSE_P12V_INA230_3_INP")
	)
	(segment
		(start 73.458324 -40.72001)
		(end 73.458324 -41.758616)
		(width 0.254)
		(layer "F.Cu")
		(net "VSENSE_P12V_INA230_3_INP")
	)
	(segment
		(start 77.798422 -58.708036)
		(end 78.751938 -58.708036)
		(width 0.254)
		(layer "F.Cu")
		(net "VSENSE_P12V_INA230_3_INP")
	)
	(segment
		(start 79.823056 -58.890154)
		(end 79.823056 -58.889646)
		(width 0.254)
		(layer "F.Cu")
		(net "VSENSE_P12V_INA230_3_INP")
	)
	(segment
		(start 76.036424 -43.720512)
		(end 76.036424 -56.398414)
		(width 0.254)
		(layer "F.Cu")
		(net "VSENSE_P12V_INA230_3_INN")
	)
	(segment
		(start 79.823056 -57.874154)
		(end 79.823056 -57.931304)
		(width 0.254)
		(layer "F.Cu")
		(net "VSENSE_P12V_INA230_3_INN")
	)
	(segment
		(start 74.573384 -42.257472)
		(end 76.036424 -43.720512)
		(width 0.254)
		(layer "F.Cu")
		(net "VSENSE_P12V_INA230_3_INN")
	)
	(segment
		(start 79.656178 -58.098182)
		(end 78.942184 -58.098182)
		(width 0.254)
		(layer "F.Cu")
		(net "VSENSE_P12V_INA230_3_INN")
	)
	(segment
		(start 78.63078 -58.17743)
		(end 78.826106 -57.982104)
		(width 0.254)
		(layer "F.Cu")
		(net "VSENSE_P12V_INA230_3_INN")
	)
	(segment
		(start 74.34453 -40.070024)
		(end 74.573384 -40.298878)
		(width 0.254)
		(layer "F.Cu")
		(net "VSENSE_P12V_INA230_3_INN")
	)
	(segment
		(start 74.573384 -40.298878)
		(end 74.573384 -42.257472)
		(width 0.254)
		(layer "F.Cu")
		(net "VSENSE_P12V_INA230_3_INN")
	)
	(segment
		(start 74.10831 -40.070024)
		(end 74.34453 -40.070024)
		(width 0.254)
		(layer "F.Cu")
		(net "VSENSE_P12V_INA230_3_INN")
	)
	(segment
		(start 79.823056 -57.931304)
		(end 79.656178 -58.098182)
		(width 0.254)
		(layer "F.Cu")
		(net "VSENSE_P12V_INA230_3_INN")
	)
	(segment
		(start 77.81544 -58.17743)
		(end 78.63078 -58.17743)
		(width 0.254)
		(layer "F.Cu")
		(net "VSENSE_P12V_INA230_3_INN")
	)
	(segment
		(start 78.942184 -58.098182)
		(end 78.826106 -57.982104)
		(width 0.254)
		(layer "F.Cu")
		(net "VSENSE_P12V_INA230_3_INN")
	)
	(segment
		(start 76.036424 -56.398414)
		(end 77.81544 -58.17743)
		(width 0.254)
		(layer "F.Cu")
		(net "VSENSE_P12V_INA230_3_INN")
	)
	(segment
		(start 141.286992 -107.683046)
		(end 141.286992 -109.080554)
		(width 0.10668)
		(layer "F.Cu")
		(net "VR_P5V_EN_N")
	)
	(segment
		(start 142.500096 -110.293658)
		(end 144.452086 -110.293658)
		(width 0.10668)
		(layer "F.Cu")
		(net "VR_P5V_EN_N")
	)
	(segment
		(start 143.740632 -107.683046)
		(end 141.286992 -107.683046)
		(width 0.10668)
		(layer "F.Cu")
		(net "VR_P5V_EN_N")
	)
	(segment
		(start 141.286992 -109.080554)
		(end 142.500096 -110.293658)
		(width 0.10668)
		(layer "F.Cu")
		(net "VR_P5V_EN_N")
	)
	(segment
		(start 143.740632 -107.03306)
		(end 143.740632 -107.683046)
		(width 0.10668)
		(layer "F.Cu")
		(net "VR_P5V_EN_N")
	)
	(via
		(at 372.518686 -116.486432)
		(size 0.508)
		(drill 0.254)
		(layers "F.Cu" "B.Cu")
		(net "VR_P5V_EN_N")
	)
	(via
		(at 399.665698 -138.936984)
		(size 0.508)
		(drill 0.254)
		(layers "F.Cu" "B.Cu")
		(net "VR_P5V_EN_N")
	)
	(via
		(at 410.581856 -116.207286)
		(size 0.508)
		(drill 0.254)
		(layers "F.Cu" "B.Cu")
		(net "VR_P5V_EN_N")
	)
	(via
		(at 219.30868 -109.057948)
		(size 0.508)
		(drill 0.254)
		(layers "F.Cu" "B.Cu")
		(net "VR_P5V_EN_N")
	)
	(via
		(at 144.452086 -110.293658)
		(size 0.508)
		(drill 0.254)
		(layers "F.Cu" "B.Cu")
		(net "VR_P5V_EN_N")
	)
	(segment
		(start 211.64423 -90.821256)
		(end 211.64423 -93.595444)
		(width 0.10668)
		(layer "B.Cu")
		(net "VR_P5V_EN_N")
	)
	(segment
		(start 372.518686 -116.486432)
		(end 372.797832 -116.207286)
		(width 0.10668)
		(layer "B.Cu")
		(net "VR_P5V_EN_N")
	)
	(segment
		(start 153.424382 -102.883462)
		(end 157.088332 -102.883462)
		(width 0.10668)
		(layer "B.Cu")
		(net "VR_P5V_EN_N")
	)
	(segment
		(start 157.639004 -99.367086)
		(end 167.630602 -89.375488)
		(width 0.10668)
		(layer "B.Cu")
		(net "VR_P5V_EN_N")
	)
	(segment
		(start 144.550638 -110.195106)
		(end 144.550638 -109.735366)
		(width 0.10668)
		(layer "B.Cu")
		(net "VR_P5V_EN_N")
	)
	(segment
		(start 157.088332 -102.883462)
		(end 157.639004 -102.33279)
		(width 0.10668)
		(layer "B.Cu")
		(net "VR_P5V_EN_N")
	)
	(segment
		(start 219.206064 -104.344978)
		(end 219.206064 -108.955332)
		(width 0.10668)
		(layer "B.Cu")
		(net "VR_P5V_EN_N")
	)
	(segment
		(start 152.966928 -103.340916)
		(end 153.424382 -102.883462)
		(width 0.10668)
		(layer "B.Cu")
		(net "VR_P5V_EN_N")
	)
	(segment
		(start 394.179298 -151.67737)
		(end 394.179298 -153.116026)
		(width 0.10668)
		(layer "B.Cu")
		(net "VR_P5V_EN_N")
	)
	(segment
		(start 219.42679 -104.124252)
		(end 219.206064 -104.344978)
		(width 0.10668)
		(layer "B.Cu")
		(net "VR_P5V_EN_N")
	)
	(segment
		(start 189.71514 -87.207598)
		(end 189.71514 -87.487506)
		(width 0.10668)
		(layer "B.Cu")
		(net "VR_P5V_EN_N")
	)
	(segment
		(start 190.029338 -87.801704)
		(end 208.624678 -87.801704)
		(width 0.10668)
		(layer "B.Cu")
		(net "VR_P5V_EN_N")
	)
	(segment
		(start 372.797832 -116.207286)
		(end 410.581856 -116.207286)
		(width 0.10668)
		(layer "B.Cu")
		(net "VR_P5V_EN_N")
	)
	(segment
		(start 399.665698 -139.973558)
		(end 395.665706 -143.97355)
		(width 0.10668)
		(layer "B.Cu")
		(net "VR_P5V_EN_N")
	)
	(segment
		(start 187.155328 -87.498682)
		(end 187.532264 -87.121746)
		(width 0.10668)
		(layer "B.Cu")
		(net "VR_P5V_EN_N")
	)
	(segment
		(start 211.64423 -93.595444)
		(end 214.903812 -96.855026)
		(width 0.10668)
		(layer "B.Cu")
		(net "VR_P5V_EN_N")
	)
	(segment
		(start 157.639004 -102.33279)
		(end 157.639004 -99.367086)
		(width 0.10668)
		(layer "B.Cu")
		(net "VR_P5V_EN_N")
	)
	(segment
		(start 208.624678 -87.801704)
		(end 211.64423 -90.821256)
		(width 0.10668)
		(layer "B.Cu")
		(net "VR_P5V_EN_N")
	)
	(segment
		(start 187.532264 -87.121746)
		(end 189.629288 -87.121746)
		(width 0.10668)
		(layer "B.Cu")
		(net "VR_P5V_EN_N")
	)
	(segment
		(start 219.42679 -101.037898)
		(end 219.42679 -104.124252)
		(width 0.10668)
		(layer "B.Cu")
		(net "VR_P5V_EN_N")
	)
	(segment
		(start 150.945088 -103.340916)
		(end 152.966928 -103.340916)
		(width 0.10668)
		(layer "B.Cu")
		(net "VR_P5V_EN_N")
	)
	(segment
		(start 395.665706 -143.97355)
		(end 395.665706 -150.190962)
		(width 0.10668)
		(layer "B.Cu")
		(net "VR_P5V_EN_N")
	)
	(segment
		(start 189.629288 -87.121746)
		(end 189.71514 -87.207598)
		(width 0.10668)
		(layer "B.Cu")
		(net "VR_P5V_EN_N")
	)
	(segment
		(start 186.518042 -89.375488)
		(end 187.155328 -88.738202)
		(width 0.10668)
		(layer "B.Cu")
		(net "VR_P5V_EN_N")
	)
	(segment
		(start 189.71514 -87.487506)
		(end 190.029338 -87.801704)
		(width 0.10668)
		(layer "B.Cu")
		(net "VR_P5V_EN_N")
	)
	(segment
		(start 144.452086 -110.293658)
		(end 144.550638 -110.195106)
		(width 0.10668)
		(layer "B.Cu")
		(net "VR_P5V_EN_N")
	)
	(segment
		(start 219.206064 -108.955332)
		(end 219.30868 -109.057948)
		(width 0.10668)
		(layer "B.Cu")
		(net "VR_P5V_EN_N")
	)
	(segment
		(start 187.155328 -88.738202)
		(end 187.155328 -87.498682)
		(width 0.10668)
		(layer "B.Cu")
		(net "VR_P5V_EN_N")
	)
	(segment
		(start 214.903812 -96.855026)
		(end 215.243918 -96.855026)
		(width 0.10668)
		(layer "B.Cu")
		(net "VR_P5V_EN_N")
	)
	(segment
		(start 144.550638 -109.735366)
		(end 150.945088 -103.340916)
		(width 0.10668)
		(layer "B.Cu")
		(net "VR_P5V_EN_N")
	)
	(segment
		(start 395.665706 -150.190962)
		(end 394.179298 -151.67737)
		(width 0.10668)
		(layer "B.Cu")
		(net "VR_P5V_EN_N")
	)
	(segment
		(start 399.665698 -138.936984)
		(end 399.665698 -139.973558)
		(width 0.10668)
		(layer "B.Cu")
		(net "VR_P5V_EN_N")
	)
	(segment
		(start 167.630602 -89.375488)
		(end 186.518042 -89.375488)
		(width 0.10668)
		(layer "B.Cu")
		(net "VR_P5V_EN_N")
	)
	(segment
		(start 215.243918 -96.855026)
		(end 219.42679 -101.037898)
		(width 0.10668)
		(layer "B.Cu")
		(net "VR_P5V_EN_N")
	)
	(segment
		(start 254.71374 -110.605824)
		(end 254.25527 -110.147354)
		(width 0.11684)
		(layer "In6.Cu")
		(net "VR_P5V_EN_N")
	)
	(segment
		(start 317.836804 -111.08436)
		(end 313.459114 -111.08436)
		(width 0.11684)
		(layer "In6.Cu")
		(net "VR_P5V_EN_N")
	)
	(segment
		(start 254.25527 -110.147354)
		(end 225.570542 -110.147354)
		(width 0.11684)
		(layer "In6.Cu")
		(net "VR_P5V_EN_N")
	)
	(segment
		(start 320.976752 -114.224308)
		(end 317.836804 -111.08436)
		(width 0.11684)
		(layer "In6.Cu")
		(net "VR_P5V_EN_N")
	)
	(segment
		(start 225.50374 -110.214156)
		(end 220.464888 -110.214156)
		(width 0.11684)
		(layer "In6.Cu")
		(net "VR_P5V_EN_N")
	)
	(segment
		(start 220.464888 -110.214156)
		(end 219.30868 -109.057948)
		(width 0.11684)
		(layer "In6.Cu")
		(net "VR_P5V_EN_N")
	)
	(segment
		(start 273.293332 -110.605824)
		(end 254.71374 -110.605824)
		(width 0.11684)
		(layer "In6.Cu")
		(net "VR_P5V_EN_N")
	)
	(segment
		(start 367.716308 -114.224308)
		(end 320.976752 -114.224308)
		(width 0.11684)
		(layer "In6.Cu")
		(net "VR_P5V_EN_N")
	)
	(segment
		(start 225.570542 -110.147354)
		(end 225.50374 -110.214156)
		(width 0.11684)
		(layer "In6.Cu")
		(net "VR_P5V_EN_N")
	)
	(segment
		(start 368.935 -115.443)
		(end 367.716308 -114.224308)
		(width 0.11684)
		(layer "In6.Cu")
		(net "VR_P5V_EN_N")
	)
	(segment
		(start 371.475254 -115.443)
		(end 368.935 -115.443)
		(width 0.11684)
		(layer "In6.Cu")
		(net "VR_P5V_EN_N")
	)
	(segment
		(start 313.459114 -111.08436)
		(end 311.606184 -109.23143)
		(width 0.11684)
		(layer "In6.Cu")
		(net "VR_P5V_EN_N")
	)
	(segment
		(start 279.213564 -109.23143)
		(end 278.689308 -109.755686)
		(width 0.11684)
		(layer "In6.Cu")
		(net "VR_P5V_EN_N")
	)
	(segment
		(start 372.518686 -116.486432)
		(end 371.475254 -115.443)
		(width 0.11684)
		(layer "In6.Cu")
		(net "VR_P5V_EN_N")
	)
	(segment
		(start 274.14347 -109.755686)
		(end 273.293332 -110.605824)
		(width 0.11684)
		(layer "In6.Cu")
		(net "VR_P5V_EN_N")
	)
	(segment
		(start 278.689308 -109.755686)
		(end 274.14347 -109.755686)
		(width 0.11684)
		(layer "In6.Cu")
		(net "VR_P5V_EN_N")
	)
	(segment
		(start 311.606184 -109.23143)
		(end 279.213564 -109.23143)
		(width 0.11684)
		(layer "In6.Cu")
		(net "VR_P5V_EN_N")
	)
	(segment
		(start 400.274282 -134.250176)
		(end 400.274282 -138.3284)
		(width 0.11684)
		(layer "In11.Cu")
		(net "VR_P5V_EN_N")
	)
	(segment
		(start 408.681682 -118.10746)
		(end 408.681682 -125.842776)
		(width 0.11684)
		(layer "In11.Cu")
		(net "VR_P5V_EN_N")
	)
	(segment
		(start 400.274282 -138.3284)
		(end 399.665698 -138.936984)
		(width 0.11684)
		(layer "In11.Cu")
		(net "VR_P5V_EN_N")
	)
	(segment
		(start 408.681682 -125.842776)
		(end 400.274282 -134.250176)
		(width 0.11684)
		(layer "In11.Cu")
		(net "VR_P5V_EN_N")
	)
	(segment
		(start 410.581856 -116.207286)
		(end 408.681682 -118.10746)
		(width 0.11684)
		(layer "In11.Cu")
		(net "VR_P5V_EN_N")
	)
	(segment
		(start 148.099018 -109.721904)
		(end 146.879818 -109.721904)
		(width 0.10668)
		(layer "F.Cu")
		(net "VR_P5V_EN_D_R1")
	)
	(segment
		(start 145.640552 -108.333032)
		(end 145.640552 -108.482638)
		(width 0.10668)
		(layer "F.Cu")
		(net "VR_P5V_EN_D_R1")
	)
	(segment
		(start 145.640552 -108.482638)
		(end 146.879818 -109.721904)
		(width 0.10668)
		(layer "F.Cu")
		(net "VR_P5V_EN_D_R1")
	)
	(via
		(at 146.879818 -109.721904)
		(size 0.762)
		(drill 0.381)
		(layers "F.Cu" "B.Cu")
		(net "VR_P5V_EN_D_R1")
	)
	(segment
		(start 148.899118 -109.721904)
		(end 149.540468 -109.721904)
		(width 0.10668)
		(layer "F.Cu")
		(net "VR_P5V_EN_D_R")
	)
	(segment
		(start 400.47672 -145.801588)
		(end 399.398744 -145.801588)
		(width 0.10668)
		(layer "F.Cu")
		(net "VR_P5V_EN_D_R")
	)
	(via
		(at 399.398744 -145.801588)
		(size 0.508)
		(drill 0.254)
		(layers "F.Cu" "B.Cu")
		(net "VR_P5V_EN_D_R")
	)
	(via
		(at 149.540468 -109.721904)
		(size 0.508)
		(drill 0.254)
		(layers "F.Cu" "B.Cu")
		(net "VR_P5V_EN_D_R")
	)
	(via
		(at 410.5275 -118.120668)
		(size 0.508)
		(drill 0.254)
		(layers "F.Cu" "B.Cu")
		(net "VR_P5V_EN_D_R")
	)
	(via
		(at 218.313 -109.057948)
		(size 0.508)
		(drill 0.254)
		(layers "F.Cu" "B.Cu")
		(net "VR_P5V_EN_D_R")
	)
	(segment
		(start 399.796 -145.404332)
		(end 399.398744 -145.801588)
		(width 0.10668)
		(layer "B.Cu")
		(net "VR_P5V_EN_D_R")
	)
	(segment
		(start 150.14194 -108.199682)
		(end 154.769058 -103.572564)
		(width 0.10668)
		(layer "B.Cu")
		(net "VR_P5V_EN_D_R")
	)
	(segment
		(start 167.853868 -89.736168)
		(end 188.032644 -89.736168)
		(width 0.10668)
		(layer "B.Cu")
		(net "VR_P5V_EN_D_R")
	)
	(segment
		(start 209.216498 -89.472008)
		(end 209.216498 -91.7448)
		(width 0.10668)
		(layer "B.Cu")
		(net "VR_P5V_EN_D_R")
	)
	(segment
		(start 150.14194 -109.120432)
		(end 150.14194 -108.199682)
		(width 0.10668)
		(layer "B.Cu")
		(net "VR_P5V_EN_D_R")
	)
	(segment
		(start 156.232352 -104.032558)
		(end 157.261306 -104.032558)
		(width 0.10668)
		(layer "B.Cu")
		(net "VR_P5V_EN_D_R")
	)
	(segment
		(start 207.906874 -88.162384)
		(end 209.216498 -89.472008)
		(width 0.10668)
		(layer "B.Cu")
		(net "VR_P5V_EN_D_R")
	)
	(segment
		(start 398.230344 -145.801588)
		(end 399.398744 -145.801588)
		(width 0.10668)
		(layer "B.Cu")
		(net "VR_P5V_EN_D_R")
	)
	(segment
		(start 158.035752 -99.554284)
		(end 167.853868 -89.736168)
		(width 0.10668)
		(layer "B.Cu")
		(net "VR_P5V_EN_D_R")
	)
	(segment
		(start 218.764866 -108.606082)
		(end 218.313 -109.057948)
		(width 0.10668)
		(layer "B.Cu")
		(net "VR_P5V_EN_D_R")
	)
	(segment
		(start 218.764866 -102.680008)
		(end 218.764866 -108.606082)
		(width 0.10668)
		(layer "B.Cu")
		(net "VR_P5V_EN_D_R")
	)
	(segment
		(start 188.032644 -89.736168)
		(end 189.606428 -88.162384)
		(width 0.10668)
		(layer "B.Cu")
		(net "VR_P5V_EN_D_R")
	)
	(segment
		(start 214.425784 -96.954086)
		(end 214.425784 -98.340926)
		(width 0.10668)
		(layer "B.Cu")
		(net "VR_P5V_EN_D_R")
	)
	(segment
		(start 154.769058 -103.572564)
		(end 155.772358 -103.572564)
		(width 0.10668)
		(layer "B.Cu")
		(net "VR_P5V_EN_D_R")
	)
	(segment
		(start 189.606428 -88.162384)
		(end 207.906874 -88.162384)
		(width 0.10668)
		(layer "B.Cu")
		(net "VR_P5V_EN_D_R")
	)
	(segment
		(start 157.261306 -104.032558)
		(end 158.035752 -103.258112)
		(width 0.10668)
		(layer "B.Cu")
		(net "VR_P5V_EN_D_R")
	)
	(segment
		(start 155.772358 -103.572564)
		(end 156.232352 -104.032558)
		(width 0.10668)
		(layer "B.Cu")
		(net "VR_P5V_EN_D_R")
	)
	(segment
		(start 209.216498 -91.7448)
		(end 214.425784 -96.954086)
		(width 0.10668)
		(layer "B.Cu")
		(net "VR_P5V_EN_D_R")
	)
	(segment
		(start 149.540468 -109.721904)
		(end 150.14194 -109.120432)
		(width 0.10668)
		(layer "B.Cu")
		(net "VR_P5V_EN_D_R")
	)
	(segment
		(start 158.035752 -103.258112)
		(end 158.035752 -99.554284)
		(width 0.10668)
		(layer "B.Cu")
		(net "VR_P5V_EN_D_R")
	)
	(segment
		(start 214.425784 -98.340926)
		(end 218.764866 -102.680008)
		(width 0.10668)
		(layer "B.Cu")
		(net "VR_P5V_EN_D_R")
	)
	(segment
		(start 399.796 -144.41805)
		(end 399.796 -145.404332)
		(width 0.10668)
		(layer "B.Cu")
		(net "VR_P5V_EN_D_R")
	)
	(segment
		(start 219.501466 -108.593128)
		(end 220.700854 -109.792516)
		(width 0.11684)
		(layer "In6.Cu")
		(net "VR_P5V_EN_D_R")
	)
	(segment
		(start 220.700854 -109.792516)
		(end 223.889316 -109.792516)
		(width 0.11684)
		(layer "In6.Cu")
		(net "VR_P5V_EN_D_R")
	)
	(segment
		(start 223.889316 -109.792516)
		(end 224.107248 -109.574584)
		(width 0.11684)
		(layer "In6.Cu")
		(net "VR_P5V_EN_D_R")
	)
	(segment
		(start 259.791708 -110.161832)
		(end 273.00174 -110.161832)
		(width 0.11684)
		(layer "In6.Cu")
		(net "VR_P5V_EN_D_R")
	)
	(segment
		(start 273.00174 -110.161832)
		(end 273.829526 -109.334046)
		(width 0.11684)
		(layer "In6.Cu")
		(net "VR_P5V_EN_D_R")
	)
	(segment
		(start 218.313 -109.057948)
		(end 218.77782 -108.593128)
		(width 0.11684)
		(layer "In6.Cu")
		(net "VR_P5V_EN_D_R")
	)
	(segment
		(start 368.070384 -113.742724)
		(end 369.26266 -114.935)
		(width 0.11684)
		(layer "In6.Cu")
		(net "VR_P5V_EN_D_R")
	)
	(segment
		(start 314.664344 -108.80979)
		(end 314.877704 -109.02315)
		(width 0.11684)
		(layer "In6.Cu")
		(net "VR_P5V_EN_D_R")
	)
	(segment
		(start 369.26266 -114.935)
		(end 373.575834 -114.935)
		(width 0.11684)
		(layer "In6.Cu")
		(net "VR_P5V_EN_D_R")
	)
	(segment
		(start 382.750568 -124.109734)
		(end 400.393154 -124.109734)
		(width 0.11684)
		(layer "In6.Cu")
		(net "VR_P5V_EN_D_R")
	)
	(segment
		(start 400.393154 -124.109734)
		(end 406.38222 -118.120668)
		(width 0.11684)
		(layer "In6.Cu")
		(net "VR_P5V_EN_D_R")
	)
	(segment
		(start 314.877704 -109.02315)
		(end 316.683898 -109.02315)
		(width 0.11684)
		(layer "In6.Cu")
		(net "VR_P5V_EN_D_R")
	)
	(segment
		(start 273.829526 -109.334046)
		(end 278.285448 -109.334046)
		(width 0.11684)
		(layer "In6.Cu")
		(net "VR_P5V_EN_D_R")
	)
	(segment
		(start 224.107248 -109.574584)
		(end 259.20446 -109.574584)
		(width 0.11684)
		(layer "In6.Cu")
		(net "VR_P5V_EN_D_R")
	)
	(segment
		(start 278.809704 -108.80979)
		(end 314.664344 -108.80979)
		(width 0.11684)
		(layer "In6.Cu")
		(net "VR_P5V_EN_D_R")
	)
	(segment
		(start 259.20446 -109.574584)
		(end 259.791708 -110.161832)
		(width 0.11684)
		(layer "In6.Cu")
		(net "VR_P5V_EN_D_R")
	)
	(segment
		(start 406.38222 -118.120668)
		(end 410.5275 -118.120668)
		(width 0.11684)
		(layer "In6.Cu")
		(net "VR_P5V_EN_D_R")
	)
	(segment
		(start 321.403472 -113.742724)
		(end 368.070384 -113.742724)
		(width 0.11684)
		(layer "In6.Cu")
		(net "VR_P5V_EN_D_R")
	)
	(segment
		(start 373.575834 -114.935)
		(end 382.750568 -124.109734)
		(width 0.11684)
		(layer "In6.Cu")
		(net "VR_P5V_EN_D_R")
	)
	(segment
		(start 278.285448 -109.334046)
		(end 278.809704 -108.80979)
		(width 0.11684)
		(layer "In6.Cu")
		(net "VR_P5V_EN_D_R")
	)
	(segment
		(start 316.683898 -109.02315)
		(end 321.403472 -113.742724)
		(width 0.11684)
		(layer "In6.Cu")
		(net "VR_P5V_EN_D_R")
	)
	(segment
		(start 218.77782 -108.593128)
		(end 219.501466 -108.593128)
		(width 0.11684)
		(layer "In6.Cu")
		(net "VR_P5V_EN_D_R")
	)
	(segment
		(start 399.398744 -145.801588)
		(end 400.695922 -144.50441)
		(width 0.11684)
		(layer "In11.Cu")
		(net "VR_P5V_EN_D_R")
	)
	(segment
		(start 400.695922 -144.50441)
		(end 400.695922 -134.424928)
		(width 0.11684)
		(layer "In11.Cu")
		(net "VR_P5V_EN_D_R")
	)
	(segment
		(start 409.103322 -126.017528)
		(end 409.103322 -119.544846)
		(width 0.11684)
		(layer "In11.Cu")
		(net "VR_P5V_EN_D_R")
	)
	(segment
		(start 409.103322 -119.544846)
		(end 410.5275 -118.120668)
		(width 0.11684)
		(layer "In11.Cu")
		(net "VR_P5V_EN_D_R")
	)
	(segment
		(start 400.695922 -134.424928)
		(end 409.103322 -126.017528)
		(width 0.11684)
		(layer "In11.Cu")
		(net "VR_P5V_EN_D_R")
	)
	(via
		(at 401.538694 -155.30576)
		(size 0.6604)
		(drill 0.3302)
		(layers "F.Cu" "B.Cu")
		(net "VR_P5V_EN_D")
	)
	(via
		(at 399.480786 -155.313634)
		(size 0.6604)
		(drill 0.3302)
		(layers "F.Cu" "B.Cu")
		(net "VR_P5V_EN_D")
	)
	(via
		(at 403.803612 -155.309824)
		(size 0.6604)
		(drill 0.3302)
		(layers "F.Cu" "B.Cu")
		(net "VR_P5V_EN_D")
	)
	(via
		(at 397.45539 -155.299664)
		(size 0.6604)
		(drill 0.3302)
		(layers "F.Cu" "B.Cu")
		(net "VR_P5V_EN_D")
	)
	(segment
		(start 148.094192 -107.683046)
		(end 146.874992 -107.683046)
		(width 0.10668)
		(layer "F.Cu")
		(net "VR_P5V_EN")
	)
	(segment
		(start 148.094192 -108.699046)
		(end 148.094192 -107.683046)
		(width 0.10668)
		(layer "F.Cu")
		(net "VR_P5V_EN")
	)
	(segment
		(start 145.640552 -107.683046)
		(end 146.874992 -107.683046)
		(width 0.10668)
		(layer "F.Cu")
		(net "VR_P5V_EN")
	)
	(via
		(at 146.874992 -107.683046)
		(size 0.762)
		(drill 0.381)
		(layers "F.Cu" "B.Cu")
		(net "VR_P5V_EN")
	)
	(segment
		(start 9.96442 -98.374708)
		(end 10.39876 -98.374708)
		(width 0.10668)
		(layer "F.Cu")
		(net "USB_HUB_XTAL_OUT")
	)
	(segment
		(start 8.85444 -98.143568)
		(end 9.29513 -98.584258)
		(width 0.10668)
		(layer "F.Cu")
		(net "USB_HUB_XTAL_OUT")
	)
	(segment
		(start 8.25246 -98.143568)
		(end 8.85444 -98.143568)
		(width 0.10668)
		(layer "F.Cu")
		(net "USB_HUB_XTAL_OUT")
	)
	(segment
		(start 9.75487 -98.584258)
		(end 9.96442 -98.374708)
		(width 0.10668)
		(layer "F.Cu")
		(net "USB_HUB_XTAL_OUT")
	)
	(segment
		(start 7.899146 -98.496882)
		(end 8.25246 -98.143568)
		(width 0.10668)
		(layer "F.Cu")
		(net "USB_HUB_XTAL_OUT")
	)
	(segment
		(start 10.39876 -98.374708)
		(end 11.160506 -99.136454)
		(width 0.10668)
		(layer "F.Cu")
		(net "USB_HUB_XTAL_OUT")
	)
	(segment
		(start 9.29513 -98.584258)
		(end 9.75487 -98.584258)
		(width 0.10668)
		(layer "F.Cu")
		(net "USB_HUB_XTAL_OUT")
	)
	(segment
		(start 11.160506 -99.136454)
		(end 11.652504 -99.136454)
		(width 0.10668)
		(layer "F.Cu")
		(net "USB_HUB_XTAL_OUT")
	)
	(via
		(at 10.39876 -98.374708)
		(size 0.508)
		(drill 0.254)
		(layers "F.Cu" "B.Cu")
		(net "USB_HUB_XTAL_OUT")
	)
	(segment
		(start 9.98728 -99.636326)
		(end 9.295638 -99.636326)
		(width 0.10668)
		(layer "F.Cu")
		(net "USB_HUB_XTAL_IN")
	)
	(segment
		(start 7.234428 -99.461828)
		(end 8.49884 -99.461828)
		(width 0.10668)
		(layer "F.Cu")
		(net "USB_HUB_XTAL_IN")
	)
	(segment
		(start 6.349238 -100.347018)
		(end 7.234428 -99.461828)
		(width 0.10668)
		(layer "F.Cu")
		(net "USB_HUB_XTAL_IN")
	)
	(segment
		(start 9.295638 -99.636326)
		(end 9.277096 -99.617784)
		(width 0.10668)
		(layer "F.Cu")
		(net "USB_HUB_XTAL_IN")
	)
	(segment
		(start 11.652504 -99.636326)
		(end 9.98728 -99.636326)
		(width 0.10668)
		(layer "F.Cu")
		(net "USB_HUB_XTAL_IN")
	)
	(segment
		(start 8.49884 -99.461828)
		(end 8.654796 -99.617784)
		(width 0.10668)
		(layer "F.Cu")
		(net "USB_HUB_XTAL_IN")
	)
	(segment
		(start 8.654796 -99.617784)
		(end 9.277096 -99.617784)
		(width 0.10668)
		(layer "F.Cu")
		(net "USB_HUB_XTAL_IN")
	)
	(via
		(at 9.98728 -99.636326)
		(size 0.508)
		(drill 0.254)
		(layers "F.Cu" "B.Cu")
		(net "USB_HUB_XTAL_IN")
	)
	(segment
		(start 13.589 -95.545148)
		(end 13.589 -94.325948)
		(width 0.10668)
		(layer "F.Cu")
		(net "USB_HUB_TEST")
	)
	(segment
		(start 14.01826 -93.896688)
		(end 14.01826 -93.087698)
		(width 0.10668)
		(layer "F.Cu")
		(net "USB_HUB_TEST")
	)
	(segment
		(start 13.589 -94.325948)
		(end 14.01826 -93.896688)
		(width 0.10668)
		(layer "F.Cu")
		(net "USB_HUB_TEST")
	)
	(segment
		(start 14.064996 -96.723962)
		(end 14.064996 -96.021144)
		(width 0.10668)
		(layer "F.Cu")
		(net "USB_HUB_TEST")
	)
	(segment
		(start 14.064996 -96.021144)
		(end 13.589 -95.545148)
		(width 0.10668)
		(layer "F.Cu")
		(net "USB_HUB_TEST")
	)
	(via
		(at 13.589 -94.325948)
		(size 0.762)
		(drill 0.381)
		(layers "F.Cu" "B.Cu")
		(net "USB_HUB_TEST")
	)
	(segment
		(start 10.3632 -101.717602)
		(end 10.3632 -101.844348)
		(width 0.10668)
		(layer "F.Cu")
		(net "USB_HUB_RREF")
	)
	(segment
		(start 10.3632 -101.844348)
		(end 9.168892 -101.844348)
		(width 0.10668)
		(layer "F.Cu")
		(net "USB_HUB_RREF")
	)
	(segment
		(start 11.444224 -100.636578)
		(end 10.3632 -101.717602)
		(width 0.10668)
		(layer "F.Cu")
		(net "USB_HUB_RREF")
	)
	(segment
		(start 11.652504 -100.636578)
		(end 11.444224 -100.636578)
		(width 0.10668)
		(layer "F.Cu")
		(net "USB_HUB_RREF")
	)
	(segment
		(start 9.168892 -101.844348)
		(end 9.15924 -101.854)
		(width 0.10668)
		(layer "F.Cu")
		(net "USB_HUB_RREF")
	)
	(via
		(at 10.3632 -101.844348)
		(size 0.762)
		(drill 0.381)
		(layers "F.Cu" "B.Cu")
		(net "USB_HUB_RREF")
	)
	(segment
		(start 17.187418 -97.63633)
		(end 16.477488 -97.63633)
		(width 0.10668)
		(layer "F.Cu")
		(net "USB_HUB_PSELF")
	)
	(segment
		(start 18.8468 -96.916748)
		(end 17.907 -96.916748)
		(width 0.10668)
		(layer "F.Cu")
		(net "USB_HUB_PSELF")
	)
	(segment
		(start 17.907 -96.916748)
		(end 17.187418 -97.63633)
		(width 0.10668)
		(layer "F.Cu")
		(net "USB_HUB_PSELF")
	)
	(segment
		(start 20.461224 -97.399348)
		(end 19.3294 -97.399348)
		(width 0.10668)
		(layer "F.Cu")
		(net "USB_HUB_PSELF")
	)
	(segment
		(start 20.776946 -97.083626)
		(end 20.461224 -97.399348)
		(width 0.10668)
		(layer "F.Cu")
		(net "USB_HUB_PSELF")
	)
	(segment
		(start 19.3294 -97.399348)
		(end 18.8468 -96.916748)
		(width 0.10668)
		(layer "F.Cu")
		(net "USB_HUB_PSELF")
	)
	(segment
		(start 20.776946 -97.083626)
		(end 20.781264 -97.079308)
		(width 0.10668)
		(layer "F.Cu")
		(net "USB_HUB_PSELF")
	)
	(segment
		(start 20.781264 -97.079308)
		(end 20.781264 -95.510604)
		(width 0.10668)
		(layer "F.Cu")
		(net "USB_HUB_PSELF")
	)
	(via
		(at 17.907 -96.916748)
		(size 0.762)
		(drill 0.381)
		(layers "F.Cu" "B.Cu")
		(net "USB_HUB_PSELF")
	)
	(segment
		(start 20.741894 -98.136456)
		(end 20.776946 -98.171508)
		(width 0.10668)
		(layer "F.Cu")
		(net "USB_HUB_PGANG")
	)
	(segment
		(start 19.4564 -98.136456)
		(end 20.741894 -98.136456)
		(width 0.10668)
		(layer "F.Cu")
		(net "USB_HUB_PGANG")
	)
	(segment
		(start 16.477488 -98.136456)
		(end 19.4564 -98.136456)
		(width 0.10668)
		(layer "F.Cu")
		(net "USB_HUB_PGANG")
	)
	(via
		(at 19.4564 -98.136456)
		(size 0.762)
		(drill 0.381)
		(layers "F.Cu" "B.Cu")
		(net "USB_HUB_PGANG")
	)
	(segment
		(start 14.564868 -96.723962)
		(end 14.564868 -95.316548)
		(width 0.10668)
		(layer "F.Cu")
		(net "USB_HUB_OVCUR4")
	)
	(segment
		(start 15.067788 -93.735906)
		(end 15.067788 -93.087698)
		(width 0.10668)
		(layer "F.Cu")
		(net "USB_HUB_OVCUR4")
	)
	(segment
		(start 14.564868 -94.238826)
		(end 15.067788 -93.735906)
		(width 0.10668)
		(layer "F.Cu")
		(net "USB_HUB_OVCUR4")
	)
	(segment
		(start 14.564868 -95.316548)
		(end 14.564868 -94.238826)
		(width 0.10668)
		(layer "F.Cu")
		(net "USB_HUB_OVCUR4")
	)
	(via
		(at 14.564868 -95.316548)
		(size 0.762)
		(drill 0.381)
		(layers "F.Cu" "B.Cu")
		(net "USB_HUB_OVCUR4")
	)
	(segment
		(start 16.0909 -93.107764)
		(end 16.110966 -93.087698)
		(width 0.10668)
		(layer "F.Cu")
		(net "USB_HUB_OVCUR3")
	)
	(segment
		(start 15.064994 -96.723962)
		(end 15.064994 -95.783146)
		(width 0.10668)
		(layer "F.Cu")
		(net "USB_HUB_OVCUR3")
	)
	(segment
		(start 16.0909 -94.325948)
		(end 16.0909 -93.107764)
		(width 0.10668)
		(layer "F.Cu")
		(net "USB_HUB_OVCUR3")
	)
	(segment
		(start 16.0909 -94.75724)
		(end 16.0909 -94.325948)
		(width 0.10668)
		(layer "F.Cu")
		(net "USB_HUB_OVCUR3")
	)
	(segment
		(start 15.064994 -95.783146)
		(end 16.0909 -94.75724)
		(width 0.10668)
		(layer "F.Cu")
		(net "USB_HUB_OVCUR3")
	)
	(via
		(at 16.0909 -94.325948)
		(size 0.762)
		(drill 0.381)
		(layers "F.Cu" "B.Cu")
		(net "USB_HUB_OVCUR3")
	)
	(segment
		(start 18.068544 -99.161092)
		(end 18.320766 -99.413314)
		(width 0.10668)
		(layer "F.Cu")
		(net "USB_HUB_OVCUR2")
	)
	(segment
		(start 17.544034 -98.636582)
		(end 18.068544 -99.161092)
		(width 0.10668)
		(layer "F.Cu")
		(net "USB_HUB_OVCUR2")
	)
	(segment
		(start 16.477488 -98.636582)
		(end 17.544034 -98.636582)
		(width 0.10668)
		(layer "F.Cu")
		(net "USB_HUB_OVCUR2")
	)
	(segment
		(start 18.320766 -99.413314)
		(end 20.776946 -99.413314)
		(width 0.10668)
		(layer "F.Cu")
		(net "USB_HUB_OVCUR2")
	)
	(via
		(at 18.068544 -99.161092)
		(size 0.762)
		(drill 0.381)
		(layers "F.Cu" "B.Cu")
		(net "USB_HUB_OVCUR2")
	)
	(segment
		(start 19.3548 -100.54971)
		(end 18.608802 -100.54971)
		(width 0.10668)
		(layer "F.Cu")
		(net "USB_HUB_OVCUR1")
	)
	(segment
		(start 17.195546 -99.136454)
		(end 16.477488 -99.136454)
		(width 0.10668)
		(layer "F.Cu")
		(net "USB_HUB_OVCUR1")
	)
	(segment
		(start 18.608802 -100.54971)
		(end 17.195546 -99.136454)
		(width 0.10668)
		(layer "F.Cu")
		(net "USB_HUB_OVCUR1")
	)
	(segment
		(start 20.776946 -100.54971)
		(end 19.3548 -100.54971)
		(width 0.10668)
		(layer "F.Cu")
		(net "USB_HUB_OVCUR1")
	)
	(via
		(at 19.3548 -100.54971)
		(size 0.762)
		(drill 0.381)
		(layers "F.Cu" "B.Cu")
		(net "USB_HUB_OVCUR1")
	)
	(segment
		(start 16.69034 -95.514668)
		(end 16.69034 -94.991936)
		(width 0.3048)
		(layer "F.Cu")
		(net "USB_HUB_DVDD")
	)
	(segment
		(start 16.14932 -95.514668)
		(end 16.69034 -95.514668)
		(width 0.3048)
		(layer "F.Cu")
		(net "USB_HUB_DVDD")
	)
	(segment
		(start 15.56512 -96.098868)
		(end 16.14932 -95.514668)
		(width 0.3048)
		(layer "F.Cu")
		(net "USB_HUB_DVDD")
	)
	(segment
		(start 15.56512 -96.723962)
		(end 15.56512 -96.098868)
		(width 0.3048)
		(layer "F.Cu")
		(net "USB_HUB_DVDD")
	)
	(segment
		(start 17.16532 -93.113352)
		(end 17.190974 -93.087698)
		(width 0.3048)
		(layer "F.Cu")
		(net "USB_HUB_DVDD")
	)
	(segment
		(start 16.69034 -94.991936)
		(end 17.16532 -94.516956)
		(width 0.3048)
		(layer "F.Cu")
		(net "USB_HUB_DVDD")
	)
	(segment
		(start 17.16532 -94.516956)
		(end 17.16532 -93.113352)
		(width 0.3048)
		(layer "F.Cu")
		(net "USB_HUB_DVDD")
	)
	(via
		(at 16.69034 -95.514668)
		(size 0.762)
		(drill 0.381)
		(layers "F.Cu" "B.Cu")
		(net "USB_HUB_DVDD")
	)
	(segment
		(start 15.824962 -103.458264)
		(end 15.824962 -102.91826)
		(width 0.12954)
		(layer "F.Cu")
		(net "USB2_P0_R_DP")
	)
	(segment
		(start 15.824962 -102.91826)
		(end 15.15364 -102.246938)
		(width 0.12954)
		(layer "F.Cu")
		(net "USB2_P0_R_DP")
	)
	(segment
		(start 15.15364 -101.933756)
		(end 15.064994 -101.84511)
		(width 0.12954)
		(layer "F.Cu")
		(net "USB2_P0_R_DP")
	)
	(segment
		(start 15.288006 -103.99522)
		(end 15.824962 -103.458264)
		(width 0.12954)
		(layer "F.Cu")
		(net "USB2_P0_R_DP")
	)
	(segment
		(start 15.288006 -104.33558)
		(end 15.288006 -103.99522)
		(width 0.12954)
		(layer "F.Cu")
		(net "USB2_P0_R_DP")
	)
	(segment
		(start 15.064994 -101.84511)
		(end 15.064994 -101.548946)
		(width 0.12954)
		(layer "F.Cu")
		(net "USB2_P0_R_DP")
	)
	(segment
		(start 15.15364 -102.246938)
		(end 15.15364 -101.933756)
		(width 0.12954)
		(layer "F.Cu")
		(net "USB2_P0_R_DP")
	)
	(segment
		(start 15.56512 -101.844856)
		(end 15.56512 -101.548946)
		(width 0.12954)
		(layer "F.Cu")
		(net "USB2_P0_R_DN")
	)
	(segment
		(start 15.47622 -101.933756)
		(end 15.56512 -101.844856)
		(width 0.12954)
		(layer "F.Cu")
		(net "USB2_P0_R_DN")
	)
	(segment
		(start 16.147542 -102.784402)
		(end 15.47622 -102.11308)
		(width 0.12954)
		(layer "F.Cu")
		(net "USB2_P0_R_DN")
	)
	(segment
		(start 15.47622 -102.11308)
		(end 15.47622 -101.933756)
		(width 0.12954)
		(layer "F.Cu")
		(net "USB2_P0_R_DN")
	)
	(segment
		(start 16.147542 -103.515668)
		(end 16.147542 -102.784402)
		(width 0.12954)
		(layer "F.Cu")
		(net "USB2_P0_R_DN")
	)
	(segment
		(start 16.645382 -104.013508)
		(end 16.147542 -103.515668)
		(width 0.12954)
		(layer "F.Cu")
		(net "USB2_P0_R_DN")
	)
	(segment
		(start 16.645382 -104.36606)
		(end 16.645382 -104.013508)
		(width 0.12954)
		(layer "F.Cu")
		(net "USB2_P0_R_DN")
	)
	(segment
		(start 11.421618 -104.740456)
		(end 11.949938 -104.212136)
		(width 0.12954)
		(layer "F.Cu")
		(net "USB2_HUB_SWB_DP")
	)
	(segment
		(start 14.153642 -101.933756)
		(end 14.064996 -101.84511)
		(width 0.12954)
		(layer "F.Cu")
		(net "USB2_HUB_SWB_DP")
	)
	(segment
		(start 13.566394 -103.421688)
		(end 14.153642 -102.83444)
		(width 0.12954)
		(layer "F.Cu")
		(net "USB2_HUB_SWB_DP")
	)
	(segment
		(start 11.421618 -105.08234)
		(end 11.421618 -104.740456)
		(width 0.12954)
		(layer "F.Cu")
		(net "USB2_HUB_SWB_DP")
	)
	(segment
		(start 14.064996 -101.84511)
		(end 14.064996 -101.548946)
		(width 0.12954)
		(layer "F.Cu")
		(net "USB2_HUB_SWB_DP")
	)
	(segment
		(start 12.38377 -103.421688)
		(end 13.566394 -103.421688)
		(width 0.12954)
		(layer "F.Cu")
		(net "USB2_HUB_SWB_DP")
	)
	(segment
		(start 11.949938 -104.212136)
		(end 11.949938 -103.85552)
		(width 0.12954)
		(layer "F.Cu")
		(net "USB2_HUB_SWB_DP")
	)
	(segment
		(start 14.153642 -102.83444)
		(end 14.153642 -101.933756)
		(width 0.12954)
		(layer "F.Cu")
		(net "USB2_HUB_SWB_DP")
	)
	(segment
		(start 11.949938 -103.85552)
		(end 12.38377 -103.421688)
		(width 0.12954)
		(layer "F.Cu")
		(net "USB2_HUB_SWB_DP")
	)
	(segment
		(start 12.272518 -104.243632)
		(end 12.272518 -103.989378)
		(width 0.12954)
		(layer "F.Cu")
		(net "USB2_HUB_SWB_DN")
	)
	(segment
		(start 14.564868 -101.84511)
		(end 14.564868 -101.548946)
		(width 0.12954)
		(layer "F.Cu")
		(net "USB2_HUB_SWB_DN")
	)
	(segment
		(start 13.700252 -103.744268)
		(end 14.476222 -102.968298)
		(width 0.12954)
		(layer "F.Cu")
		(net "USB2_HUB_SWB_DN")
	)
	(segment
		(start 14.476222 -101.933756)
		(end 14.564868 -101.84511)
		(width 0.12954)
		(layer "F.Cu")
		(net "USB2_HUB_SWB_DN")
	)
	(segment
		(start 14.476222 -102.968298)
		(end 14.476222 -101.933756)
		(width 0.12954)
		(layer "F.Cu")
		(net "USB2_HUB_SWB_DN")
	)
	(segment
		(start 12.786106 -104.75722)
		(end 12.272518 -104.243632)
		(width 0.12954)
		(layer "F.Cu")
		(net "USB2_HUB_SWB_DN")
	)
	(segment
		(start 12.517628 -103.744268)
		(end 13.700252 -103.744268)
		(width 0.12954)
		(layer "F.Cu")
		(net "USB2_HUB_SWB_DN")
	)
	(segment
		(start 12.272518 -103.989378)
		(end 12.517628 -103.744268)
		(width 0.12954)
		(layer "F.Cu")
		(net "USB2_HUB_SWB_DN")
	)
	(segment
		(start 12.786106 -105.10393)
		(end 12.786106 -104.75722)
		(width 0.12954)
		(layer "F.Cu")
		(net "USB2_HUB_SWB_DN")
	)
	(segment
		(start 11.421618 -105.88244)
		(end 11.669268 -105.88244)
		(width 0.12954)
		(layer "F.Cu")
		(net "USB2_HUB_BUF_SWB_R_DP")
	)
	(segment
		(start 11.669268 -105.88244)
		(end 12.094972 -105.456736)
		(width 0.12954)
		(layer "F.Cu")
		(net "USB2_HUB_BUF_SWB_R_DP")
	)
	(via
		(at 12.094972 -105.456736)
		(size 0.508)
		(drill 0.254)
		(layers "F.Cu" "B.Cu")
		(net "USB2_HUB_BUF_SWB_R_DP")
	)
	(segment
		(start 11.876786 -113.019332)
		(end 11.876786 -113.360962)
		(width 0.12954)
		(layer "B.Cu")
		(net "USB2_HUB_BUF_SWB_R_DP")
	)
	(segment
		(start 9.916414 -105.67924)
		(end 9.516872 -106.078782)
		(width 0.12954)
		(layer "B.Cu")
		(net "USB2_HUB_BUF_SWB_R_DP")
	)
	(segment
		(start 11.92403 -111.049308)
		(end 11.92403 -111.247682)
		(width 0.12954)
		(layer "B.Cu")
		(net "USB2_HUB_BUF_SWB_R_DP")
	)
	(segment
		(start 40.900858 -416.871912)
		(end 36.484814 -416.871912)
		(width 0.12954)
		(layer "B.Cu")
		(net "USB2_HUB_BUF_SWB_R_DP")
	)
	(segment
		(start 9.516872 -106.078782)
		(end 9.516872 -109.578902)
		(width 0.12954)
		(layer "B.Cu")
		(net "USB2_HUB_BUF_SWB_R_DP")
	)
	(segment
		(start 11.981434 -105.67924)
		(end 9.916414 -105.67924)
		(width 0.12954)
		(layer "B.Cu")
		(net "USB2_HUB_BUF_SWB_R_DP")
	)
	(segment
		(start 11.681714 -110.806992)
		(end 11.92403 -111.049308)
		(width 0.12954)
		(layer "B.Cu")
		(net "USB2_HUB_BUF_SWB_R_DP")
	)
	(segment
		(start 9.516872 -109.578902)
		(end 10.744962 -110.806992)
		(width 0.12954)
		(layer "B.Cu")
		(net "USB2_HUB_BUF_SWB_R_DP")
	)
	(segment
		(start 11.906758 -113.390934)
		(end 11.906758 -114.436398)
		(width 0.12954)
		(layer "B.Cu")
		(net "USB2_HUB_BUF_SWB_R_DP")
	)
	(segment
		(start 50.318924 -418.707316)
		(end 49.970944 -419.055296)
		(width 0.12954)
		(layer "B.Cu")
		(net "USB2_HUB_BUF_SWB_R_DP")
	)
	(segment
		(start 11.92403 -111.247682)
		(end 11.876786 -111.294926)
		(width 0.12954)
		(layer "B.Cu")
		(net "USB2_HUB_BUF_SWB_R_DP")
	)
	(segment
		(start 46.228762 -417.931346)
		(end 40.900858 -416.871912)
		(width 0.12954)
		(layer "B.Cu")
		(net "USB2_HUB_BUF_SWB_R_DP")
	)
	(segment
		(start 11.876786 -113.360962)
		(end 11.906758 -113.390934)
		(width 0.12954)
		(layer "B.Cu")
		(net "USB2_HUB_BUF_SWB_R_DP")
	)
	(segment
		(start 11.876786 -113.019332)
		(end 11.876786 -111.619284)
		(width 0.12954)
		(layer "B.Cu")
		(net "USB2_HUB_BUF_SWB_R_DP")
	)
	(segment
		(start 36.484814 -416.871912)
		(end 36.214304 -416.601402)
		(width 0.12954)
		(layer "B.Cu")
		(net "USB2_HUB_BUF_SWB_R_DP")
	)
	(segment
		(start 48.941736 -419.055296)
		(end 46.228762 -417.931346)
		(width 0.12954)
		(layer "B.Cu")
		(net "USB2_HUB_BUF_SWB_R_DP")
	)
	(segment
		(start 12.094972 -105.456736)
		(end 12.094972 -105.565702)
		(width 0.12954)
		(layer "B.Cu")
		(net "USB2_HUB_BUF_SWB_R_DP")
	)
	(segment
		(start 12.094972 -105.565702)
		(end 11.981434 -105.67924)
		(width 0.12954)
		(layer "B.Cu")
		(net "USB2_HUB_BUF_SWB_R_DP")
	)
	(segment
		(start 10.744962 -110.806992)
		(end 11.681714 -110.806992)
		(width 0.12954)
		(layer "B.Cu")
		(net "USB2_HUB_BUF_SWB_R_DP")
	)
	(segment
		(start 11.876786 -111.294926)
		(end 11.876786 -111.619284)
		(width 0.12954)
		(layer "B.Cu")
		(net "USB2_HUB_BUF_SWB_R_DP")
	)
	(segment
		(start 11.906758 -114.436398)
		(end 11.636248 -114.706908)
		(width 0.12954)
		(layer "B.Cu")
		(net "USB2_HUB_BUF_SWB_R_DP")
	)
	(segment
		(start 49.970944 -419.055296)
		(end 48.941736 -419.055296)
		(width 0.12954)
		(layer "B.Cu")
		(net "USB2_HUB_BUF_SWB_R_DP")
	)
	(segment
		(start 10.938256 -403.04339)
		(end 10.938256 -406.568148)
		(width 0.14224)
		(layer "In2.Cu")
		(net "USB2_HUB_BUF_SWB_R_DP")
	)
	(segment
		(start 17.814798 -129.190242)
		(end 18.26387 -137.126726)
		(width 0.14224)
		(layer "In2.Cu")
		(net "USB2_HUB_BUF_SWB_R_DP")
	)
	(segment
		(start 14.1351 -418.51326)
		(end 20.353274 -418.51326)
		(width 0.14224)
		(layer "In2.Cu")
		(net "USB2_HUB_BUF_SWB_R_DP")
	)
	(segment
		(start 14.20495 -120.546114)
		(end 14.384528 -120.619774)
		(width 0.14224)
		(layer "In2.Cu")
		(net "USB2_HUB_BUF_SWB_R_DP")
	)
	(segment
		(start 12.823698 -118.135146)
		(end 13.125704 -118.437152)
		(width 0.14224)
		(layer "In2.Cu")
		(net "USB2_HUB_BUF_SWB_R_DP")
	)
	(segment
		(start 16.500094 -161.722816)
		(end 11.08456 -179.40274)
		(width 0.14224)
		(layer "In2.Cu")
		(net "USB2_HUB_BUF_SWB_R_DP")
	)
	(segment
		(start 12.26439 -117.575838)
		(end 12.26439 -117.769894)
		(width 0.14224)
		(layer "In2.Cu")
		(net "USB2_HUB_BUF_SWB_R_DP")
	)
	(segment
		(start 10.091674 -409.528772)
		(end 9.400286 -410.22016)
		(width 0.14224)
		(layer "In2.Cu")
		(net "USB2_HUB_BUF_SWB_R_DP")
	)
	(segment
		(start 29.201872 -416.755072)
		(end 29.339032 -416.892232)
		(width 0.14224)
		(layer "In2.Cu")
		(net "USB2_HUB_BUF_SWB_R_DP")
	)
	(segment
		(start 9.400286 -411.189932)
		(end 9.935464 -412.481776)
		(width 0.14224)
		(layer "In2.Cu")
		(net "USB2_HUB_BUF_SWB_R_DP")
	)
	(segment
		(start 28.074112 -416.755072)
		(end 28.211272 -416.892232)
		(width 0.14224)
		(layer "In2.Cu")
		(net "USB2_HUB_BUF_SWB_R_DP")
	)
	(segment
		(start 14.114526 -119.972836)
		(end 14.040612 -120.152414)
		(width 0.14224)
		(layer "In2.Cu")
		(net "USB2_HUB_BUF_SWB_R_DP")
	)
	(segment
		(start 9.400286 -410.22016)
		(end 9.400286 -411.189932)
		(width 0.14224)
		(layer "In2.Cu")
		(net "USB2_HUB_BUF_SWB_R_DP")
	)
	(segment
		(start 32.158432 -416.755072)
		(end 32.585152 -416.755072)
		(width 0.14224)
		(layer "In2.Cu")
		(net "USB2_HUB_BUF_SWB_R_DP")
	)
	(segment
		(start 14.639544 -121.587006)
		(end 14.819122 -121.660666)
		(width 0.14224)
		(layer "In2.Cu")
		(net "USB2_HUB_BUF_SWB_R_DP")
	)
	(segment
		(start 32.585152 -416.755072)
		(end 32.722312 -416.892232)
		(width 0.14224)
		(layer "In2.Cu")
		(net "USB2_HUB_BUF_SWB_R_DP")
	)
	(segment
		(start 11.941048 -113.660174)
		(end 11.697716 -113.416842)
		(width 0.14224)
		(layer "In2.Cu")
		(net "USB2_HUB_BUF_SWB_R_DP")
	)
	(segment
		(start 13.125704 -118.631208)
		(end 13.606018 -119.111522)
		(width 0.14224)
		(layer "In2.Cu")
		(net "USB2_HUB_BUF_SWB_R_DP")
	)
	(segment
		(start 3.881882 -338.194142)
		(end 3.881882 -395.987016)
		(width 0.14224)
		(layer "In2.Cu")
		(net "USB2_HUB_BUF_SWB_R_DP")
	)
	(segment
		(start 30.329632 -416.755072)
		(end 30.466792 -416.892232)
		(width 0.14224)
		(layer "In2.Cu")
		(net "USB2_HUB_BUF_SWB_R_DP")
	)
	(segment
		(start 13.125704 -118.437152)
		(end 13.125704 -118.631208)
		(width 0.14224)
		(layer "In2.Cu")
		(net "USB2_HUB_BUF_SWB_R_DP")
	)
	(segment
		(start 13.770356 -119.505222)
		(end 13.949934 -119.578882)
		(width 0.14224)
		(layer "In2.Cu")
		(net "USB2_HUB_BUF_SWB_R_DP")
	)
	(segment
		(start 13.198348 -417.576508)
		(end 14.1351 -418.51326)
		(width 0.14224)
		(layer "In2.Cu")
		(net "USB2_HUB_BUF_SWB_R_DP")
	)
	(segment
		(start 27.647392 -416.755072)
		(end 28.074112 -416.755072)
		(width 0.14224)
		(layer "In2.Cu")
		(net "USB2_HUB_BUF_SWB_R_DP")
	)
	(segment
		(start 10.40638 -115.911884)
		(end 11.768328 -117.273832)
		(width 0.14224)
		(layer "In2.Cu")
		(net "USB2_HUB_BUF_SWB_R_DP")
	)
	(segment
		(start 10.091674 -407.41473)
		(end 10.091674 -409.528772)
		(width 0.14224)
		(layer "In2.Cu")
		(net "USB2_HUB_BUF_SWB_R_DP")
	)
	(segment
		(start 20.490434 -418.3761)
		(end 20.917154 -418.3761)
		(width 0.14224)
		(layer "In2.Cu")
		(net "USB2_HUB_BUF_SWB_R_DP")
	)
	(segment
		(start 11.65606 -414.202372)
		(end 12.323572 -415.814002)
		(width 0.14224)
		(layer "In2.Cu")
		(net "USB2_HUB_BUF_SWB_R_DP")
	)
	(segment
		(start 14.819122 -121.660666)
		(end 14.983714 -122.05462)
		(width 0.14224)
		(layer "In2.Cu")
		(net "USB2_HUB_BUF_SWB_R_DP")
	)
	(segment
		(start 10.40638 -114.026188)
		(end 10.40638 -115.911884)
		(width 0.14224)
		(layer "In2.Cu")
		(net "USB2_HUB_BUF_SWB_R_DP")
	)
	(segment
		(start 16.50238 -161.690812)
		(end 16.50238 -161.691066)
		(width 0.14224)
		(layer "In2.Cu")
		(net "USB2_HUB_BUF_SWB_R_DP")
	)
	(segment
		(start 29.339032 -416.892232)
		(end 29.765752 -416.892232)
		(width 0.14224)
		(layer "In2.Cu")
		(net "USB2_HUB_BUF_SWB_R_DP")
	)
	(segment
		(start 35.923474 -416.892232)
		(end 36.214304 -416.601402)
		(width 0.14224)
		(layer "In2.Cu")
		(net "USB2_HUB_BUF_SWB_R_DP")
	)
	(segment
		(start 14.475206 -121.193306)
		(end 14.639544 -121.587006)
		(width 0.14224)
		(layer "In2.Cu")
		(net "USB2_HUB_BUF_SWB_R_DP")
	)
	(segment
		(start 31.457392 -416.755072)
		(end 31.594552 -416.892232)
		(width 0.14224)
		(layer "In2.Cu")
		(net "USB2_HUB_BUF_SWB_R_DP")
	)
	(segment
		(start 11.015726 -113.416842)
		(end 10.40638 -114.026188)
		(width 0.14224)
		(layer "In2.Cu")
		(net "USB2_HUB_BUF_SWB_R_DP")
	)
	(segment
		(start 11.768328 -117.273832)
		(end 11.962384 -117.273832)
		(width 0.14224)
		(layer "In2.Cu")
		(net "USB2_HUB_BUF_SWB_R_DP")
	)
	(segment
		(start 13.606018 -119.111522)
		(end 13.770356 -119.505222)
		(width 0.14224)
		(layer "In2.Cu")
		(net "USB2_HUB_BUF_SWB_R_DP")
	)
	(segment
		(start 31.030672 -416.755072)
		(end 31.457392 -416.755072)
		(width 0.14224)
		(layer "In2.Cu")
		(net "USB2_HUB_BUF_SWB_R_DP")
	)
	(segment
		(start 28.637992 -416.892232)
		(end 28.775152 -416.755072)
		(width 0.14224)
		(layer "In2.Cu")
		(net "USB2_HUB_BUF_SWB_R_DP")
	)
	(segment
		(start 24.32939 -417.7157)
		(end 25.152858 -416.892232)
		(width 0.14224)
		(layer "In2.Cu")
		(net "USB2_HUB_BUF_SWB_R_DP")
	)
	(segment
		(start 32.722312 -416.892232)
		(end 35.923474 -416.892232)
		(width 0.14224)
		(layer "In2.Cu")
		(net "USB2_HUB_BUF_SWB_R_DP")
	)
	(segment
		(start 11.962384 -117.273832)
		(end 12.26439 -117.575838)
		(width 0.14224)
		(layer "In2.Cu")
		(net "USB2_HUB_BUF_SWB_R_DP")
	)
	(segment
		(start 30.466792 -416.892232)
		(end 30.893512 -416.892232)
		(width 0.14224)
		(layer "In2.Cu")
		(net "USB2_HUB_BUF_SWB_R_DP")
	)
	(segment
		(start 23.53183 -418.51326)
		(end 23.833328 -418.211762)
		(width 0.14224)
		(layer "In2.Cu")
		(net "USB2_HUB_BUF_SWB_R_DP")
	)
	(segment
		(start 25.152858 -416.892232)
		(end 27.510232 -416.892232)
		(width 0.14224)
		(layer "In2.Cu")
		(net "USB2_HUB_BUF_SWB_R_DP")
	)
	(segment
		(start 14.040612 -120.152414)
		(end 14.20495 -120.546114)
		(width 0.14224)
		(layer "In2.Cu")
		(net "USB2_HUB_BUF_SWB_R_DP")
	)
	(segment
		(start 11.636248 -114.706908)
		(end 11.941048 -114.402108)
		(width 0.14224)
		(layer "In2.Cu")
		(net "USB2_HUB_BUF_SWB_R_DP")
	)
	(segment
		(start 11.697716 -113.416842)
		(end 11.015726 -113.416842)
		(width 0.14224)
		(layer "In2.Cu")
		(net "USB2_HUB_BUF_SWB_R_DP")
	)
	(segment
		(start 23.833328 -418.017706)
		(end 24.135334 -417.7157)
		(width 0.14224)
		(layer "In2.Cu")
		(net "USB2_HUB_BUF_SWB_R_DP")
	)
	(segment
		(start 11.08456 -179.40274)
		(end 7.4549 -185.23204)
		(width 0.14224)
		(layer "In2.Cu")
		(net "USB2_HUB_BUF_SWB_R_DP")
	)
	(segment
		(start 12.629642 -118.135146)
		(end 12.823698 -118.135146)
		(width 0.14224)
		(layer "In2.Cu")
		(net "USB2_HUB_BUF_SWB_R_DP")
	)
	(segment
		(start 32.021272 -416.892232)
		(end 32.158432 -416.755072)
		(width 0.14224)
		(layer "In2.Cu")
		(net "USB2_HUB_BUF_SWB_R_DP")
	)
	(segment
		(start 24.135334 -417.7157)
		(end 24.32939 -417.7157)
		(width 0.14224)
		(layer "In2.Cu")
		(net "USB2_HUB_BUF_SWB_R_DP")
	)
	(segment
		(start 8.098536 -326.869298)
		(end 3.881882 -338.194142)
		(width 0.14224)
		(layer "In2.Cu")
		(net "USB2_HUB_BUF_SWB_R_DP")
	)
	(segment
		(start 16.50238 -161.691066)
		(end 16.500094 -161.722816)
		(width 0.14224)
		(layer "In2.Cu")
		(net "USB2_HUB_BUF_SWB_R_DP")
	)
	(segment
		(start 31.594552 -416.892232)
		(end 32.021272 -416.892232)
		(width 0.14224)
		(layer "In2.Cu")
		(net "USB2_HUB_BUF_SWB_R_DP")
	)
	(segment
		(start 22.044914 -418.3761)
		(end 22.182074 -418.51326)
		(width 0.14224)
		(layer "In2.Cu")
		(net "USB2_HUB_BUF_SWB_R_DP")
	)
	(segment
		(start 7.4549 -185.23204)
		(end 6.487922 -190.584836)
		(width 0.14224)
		(layer "In2.Cu")
		(net "USB2_HUB_BUF_SWB_R_DP")
	)
	(segment
		(start 18.26387 -137.126726)
		(end 16.50238 -161.690812)
		(width 0.14224)
		(layer "In2.Cu")
		(net "USB2_HUB_BUF_SWB_R_DP")
	)
	(segment
		(start 11.941048 -114.402108)
		(end 11.941048 -113.660174)
		(width 0.14224)
		(layer "In2.Cu")
		(net "USB2_HUB_BUF_SWB_R_DP")
	)
	(segment
		(start 14.9098 -122.234198)
		(end 17.814798 -129.190242)
		(width 0.14224)
		(layer "In2.Cu")
		(net "USB2_HUB_BUF_SWB_R_DP")
	)
	(segment
		(start 14.54912 -121.013728)
		(end 14.475206 -121.193306)
		(width 0.14224)
		(layer "In2.Cu")
		(net "USB2_HUB_BUF_SWB_R_DP")
	)
	(segment
		(start 29.902912 -416.755072)
		(end 30.329632 -416.755072)
		(width 0.14224)
		(layer "In2.Cu")
		(net "USB2_HUB_BUF_SWB_R_DP")
	)
	(segment
		(start 12.323572 -415.814002)
		(end 12.323572 -416.879532)
		(width 0.14224)
		(layer "In2.Cu")
		(net "USB2_HUB_BUF_SWB_R_DP")
	)
	(segment
		(start 10.938256 -406.568148)
		(end 10.091674 -407.41473)
		(width 0.14224)
		(layer "In2.Cu")
		(net "USB2_HUB_BUF_SWB_R_DP")
	)
	(segment
		(start 22.182074 -418.51326)
		(end 23.53183 -418.51326)
		(width 0.14224)
		(layer "In2.Cu")
		(net "USB2_HUB_BUF_SWB_R_DP")
	)
	(segment
		(start 21.054314 -418.51326)
		(end 21.481034 -418.51326)
		(width 0.14224)
		(layer "In2.Cu")
		(net "USB2_HUB_BUF_SWB_R_DP")
	)
	(segment
		(start 3.881882 -395.987016)
		(end 10.938256 -403.04339)
		(width 0.14224)
		(layer "In2.Cu")
		(net "USB2_HUB_BUF_SWB_R_DP")
	)
	(segment
		(start 23.833328 -418.211762)
		(end 23.833328 -418.017706)
		(width 0.14224)
		(layer "In2.Cu")
		(net "USB2_HUB_BUF_SWB_R_DP")
	)
	(segment
		(start 30.893512 -416.892232)
		(end 31.030672 -416.755072)
		(width 0.14224)
		(layer "In2.Cu")
		(net "USB2_HUB_BUF_SWB_R_DP")
	)
	(segment
		(start 12.323572 -416.879532)
		(end 13.020548 -417.576508)
		(width 0.14224)
		(layer "In2.Cu")
		(net "USB2_HUB_BUF_SWB_R_DP")
	)
	(segment
		(start 12.26439 -117.769894)
		(end 12.629642 -118.135146)
		(width 0.14224)
		(layer "In2.Cu")
		(net "USB2_HUB_BUF_SWB_R_DP")
	)
	(segment
		(start 9.935464 -412.481776)
		(end 11.65606 -414.202372)
		(width 0.14224)
		(layer "In2.Cu")
		(net "USB2_HUB_BUF_SWB_R_DP")
	)
	(segment
		(start 14.983714 -122.05462)
		(end 14.9098 -122.234198)
		(width 0.14224)
		(layer "In2.Cu")
		(net "USB2_HUB_BUF_SWB_R_DP")
	)
	(segment
		(start 20.353274 -418.51326)
		(end 20.490434 -418.3761)
		(width 0.14224)
		(layer "In2.Cu")
		(net "USB2_HUB_BUF_SWB_R_DP")
	)
	(segment
		(start 27.510232 -416.892232)
		(end 27.647392 -416.755072)
		(width 0.14224)
		(layer "In2.Cu")
		(net "USB2_HUB_BUF_SWB_R_DP")
	)
	(segment
		(start 29.765752 -416.892232)
		(end 29.902912 -416.755072)
		(width 0.14224)
		(layer "In2.Cu")
		(net "USB2_HUB_BUF_SWB_R_DP")
	)
	(segment
		(start 13.949934 -119.578882)
		(end 14.114526 -119.972836)
		(width 0.14224)
		(layer "In2.Cu")
		(net "USB2_HUB_BUF_SWB_R_DP")
	)
	(segment
		(start 20.917154 -418.3761)
		(end 21.054314 -418.51326)
		(width 0.14224)
		(layer "In2.Cu")
		(net "USB2_HUB_BUF_SWB_R_DP")
	)
	(segment
		(start 14.384528 -120.619774)
		(end 14.54912 -121.013728)
		(width 0.14224)
		(layer "In2.Cu")
		(net "USB2_HUB_BUF_SWB_R_DP")
	)
	(segment
		(start 21.481034 -418.51326)
		(end 21.618194 -418.3761)
		(width 0.14224)
		(layer "In2.Cu")
		(net "USB2_HUB_BUF_SWB_R_DP")
	)
	(segment
		(start 28.211272 -416.892232)
		(end 28.637992 -416.892232)
		(width 0.14224)
		(layer "In2.Cu")
		(net "USB2_HUB_BUF_SWB_R_DP")
	)
	(segment
		(start 13.020548 -417.576508)
		(end 13.198348 -417.576508)
		(width 0.14224)
		(layer "In2.Cu")
		(net "USB2_HUB_BUF_SWB_R_DP")
	)
	(segment
		(start 21.618194 -418.3761)
		(end 22.044914 -418.3761)
		(width 0.14224)
		(layer "In2.Cu")
		(net "USB2_HUB_BUF_SWB_R_DP")
	)
	(segment
		(start 28.775152 -416.755072)
		(end 29.201872 -416.755072)
		(width 0.14224)
		(layer "In2.Cu")
		(net "USB2_HUB_BUF_SWB_R_DP")
	)
	(segment
		(start 6.487922 -190.584836)
		(end 8.098536 -326.869298)
		(width 0.14224)
		(layer "In2.Cu")
		(net "USB2_HUB_BUF_SWB_R_DP")
	)
	(segment
		(start 12.638532 -105.90403)
		(end 12.095226 -106.447336)
		(width 0.12954)
		(layer "F.Cu")
		(net "USB2_HUB_BUF_SWB_R_DN")
	)
	(segment
		(start 12.786106 -105.90403)
		(end 12.638532 -105.90403)
		(width 0.12954)
		(layer "F.Cu")
		(net "USB2_HUB_BUF_SWB_R_DN")
	)
	(via
		(at 12.095226 -106.447336)
		(size 0.508)
		(drill 0.254)
		(layers "F.Cu" "B.Cu")
		(net "USB2_HUB_BUF_SWB_R_DN")
	)
	(segment
		(start 50.318924 -419.723316)
		(end 49.973484 -419.377876)
		(width 0.12954)
		(layer "B.Cu")
		(net "USB2_HUB_BUF_SWB_R_DN")
	)
	(segment
		(start 9.839452 -109.445044)
		(end 10.186924 -109.792516)
		(width 0.12954)
		(layer "B.Cu")
		(net "USB2_HUB_BUF_SWB_R_DN")
	)
	(segment
		(start 11.815572 -110.484412)
		(end 12.24661 -110.91545)
		(width 0.12954)
		(layer "B.Cu")
		(net "USB2_HUB_BUF_SWB_R_DN")
	)
	(segment
		(start 12.095226 -106.176572)
		(end 11.920474 -106.00182)
		(width 0.12954)
		(layer "B.Cu")
		(net "USB2_HUB_BUF_SWB_R_DN")
	)
	(segment
		(start 12.095226 -106.447336)
		(end 12.095226 -106.176572)
		(width 0.12954)
		(layer "B.Cu")
		(net "USB2_HUB_BUF_SWB_R_DN")
	)
	(segment
		(start 12.229338 -113.390934)
		(end 12.229338 -114.436398)
		(width 0.12954)
		(layer "B.Cu")
		(net "USB2_HUB_BUF_SWB_R_DN")
	)
	(segment
		(start 36.484814 -417.194492)
		(end 36.214304 -417.465002)
		(width 0.12954)
		(layer "B.Cu")
		(net "USB2_HUB_BUF_SWB_R_DN")
	)
	(segment
		(start 48.877474 -419.377876)
		(end 46.134528 -418.241734)
		(width 0.12954)
		(layer "B.Cu")
		(net "USB2_HUB_BUF_SWB_R_DN")
	)
	(segment
		(start 10.449306 -109.792516)
		(end 10.7188 -110.06201)
		(width 0.12954)
		(layer "B.Cu")
		(net "USB2_HUB_BUF_SWB_R_DN")
	)
	(segment
		(start 12.276582 -111.277654)
		(end 12.276582 -111.619284)
		(width 0.12954)
		(layer "B.Cu")
		(net "USB2_HUB_BUF_SWB_R_DN")
	)
	(segment
		(start 12.24661 -110.91545)
		(end 12.24661 -111.247682)
		(width 0.12954)
		(layer "B.Cu")
		(net "USB2_HUB_BUF_SWB_R_DN")
	)
	(segment
		(start 10.050272 -106.00182)
		(end 9.839452 -106.21264)
		(width 0.12954)
		(layer "B.Cu")
		(net "USB2_HUB_BUF_SWB_R_DN")
	)
	(segment
		(start 11.920474 -106.00182)
		(end 11.08583 -106.00182)
		(width 0.12954)
		(layer "B.Cu")
		(net "USB2_HUB_BUF_SWB_R_DN")
	)
	(segment
		(start 12.24661 -111.247682)
		(end 12.276582 -111.277654)
		(width 0.12954)
		(layer "B.Cu")
		(net "USB2_HUB_BUF_SWB_R_DN")
	)
	(segment
		(start 10.33399 -106.00182)
		(end 10.050272 -106.00182)
		(width 0.12954)
		(layer "B.Cu")
		(net "USB2_HUB_BUF_SWB_R_DN")
	)
	(segment
		(start 40.868854 -417.194492)
		(end 36.484814 -417.194492)
		(width 0.12954)
		(layer "B.Cu")
		(net "USB2_HUB_BUF_SWB_R_DN")
	)
	(segment
		(start 9.839452 -106.21264)
		(end 9.839452 -109.445044)
		(width 0.12954)
		(layer "B.Cu")
		(net "USB2_HUB_BUF_SWB_R_DN")
	)
	(segment
		(start 12.276582 -113.019332)
		(end 12.276582 -113.34369)
		(width 0.12954)
		(layer "B.Cu")
		(net "USB2_HUB_BUF_SWB_R_DN")
	)
	(segment
		(start 49.973484 -419.377876)
		(end 48.877474 -419.377876)
		(width 0.12954)
		(layer "B.Cu")
		(net "USB2_HUB_BUF_SWB_R_DN")
	)
	(segment
		(start 11.08583 -106.00182)
		(end 10.90041 -106.18724)
		(width 0.12954)
		(layer "B.Cu")
		(net "USB2_HUB_BUF_SWB_R_DN")
	)
	(segment
		(start 10.7188 -110.06201)
		(end 10.7188 -110.324392)
		(width 0.12954)
		(layer "B.Cu")
		(net "USB2_HUB_BUF_SWB_R_DN")
	)
	(segment
		(start 10.7188 -110.324392)
		(end 10.87882 -110.484412)
		(width 0.12954)
		(layer "B.Cu")
		(net "USB2_HUB_BUF_SWB_R_DN")
	)
	(segment
		(start 12.276582 -113.019332)
		(end 12.276582 -111.619284)
		(width 0.12954)
		(layer "B.Cu")
		(net "USB2_HUB_BUF_SWB_R_DN")
	)
	(segment
		(start 12.229338 -114.436398)
		(end 12.499848 -114.706908)
		(width 0.12954)
		(layer "B.Cu")
		(net "USB2_HUB_BUF_SWB_R_DN")
	)
	(segment
		(start 10.90041 -106.18724)
		(end 10.51941 -106.18724)
		(width 0.12954)
		(layer "B.Cu")
		(net "USB2_HUB_BUF_SWB_R_DN")
	)
	(segment
		(start 10.87882 -110.484412)
		(end 11.815572 -110.484412)
		(width 0.12954)
		(layer "B.Cu")
		(net "USB2_HUB_BUF_SWB_R_DN")
	)
	(segment
		(start 10.51941 -106.18724)
		(end 10.33399 -106.00182)
		(width 0.12954)
		(layer "B.Cu")
		(net "USB2_HUB_BUF_SWB_R_DN")
	)
	(segment
		(start 12.276582 -113.34369)
		(end 12.229338 -113.390934)
		(width 0.12954)
		(layer "B.Cu")
		(net "USB2_HUB_BUF_SWB_R_DN")
	)
	(segment
		(start 46.134528 -418.241734)
		(end 40.868854 -417.194492)
		(width 0.12954)
		(layer "B.Cu")
		(net "USB2_HUB_BUF_SWB_R_DN")
	)
	(segment
		(start 10.186924 -109.792516)
		(end 10.449306 -109.792516)
		(width 0.12954)
		(layer "B.Cu")
		(net "USB2_HUB_BUF_SWB_R_DN")
	)
	(segment
		(start 14.01826 -418.7952)
		(end 23.64867 -418.7952)
		(width 0.14224)
		(layer "In2.Cu")
		(net "USB2_HUB_BUF_SWB_R_DN")
	)
	(segment
		(start 7.815834 -326.820022)
		(end 3.599942 -338.143342)
		(width 0.14224)
		(layer "In2.Cu")
		(net "USB2_HUB_BUF_SWB_R_DN")
	)
	(segment
		(start 12.903708 -417.858448)
		(end 13.081508 -417.858448)
		(width 0.14224)
		(layer "In2.Cu")
		(net "USB2_HUB_BUF_SWB_R_DN")
	)
	(segment
		(start 12.041632 -416.996372)
		(end 12.903708 -417.858448)
		(width 0.14224)
		(layer "In2.Cu")
		(net "USB2_HUB_BUF_SWB_R_DN")
	)
	(segment
		(start 3.599942 -338.143342)
		(end 3.599942 -396.103856)
		(width 0.14224)
		(layer "In2.Cu")
		(net "USB2_HUB_BUF_SWB_R_DN")
	)
	(segment
		(start 10.898886 -113.134902)
		(end 10.12444 -113.909348)
		(width 0.14224)
		(layer "In2.Cu")
		(net "USB2_HUB_BUF_SWB_R_DN")
	)
	(segment
		(start 7.18693 -185.128916)
		(end 6.205474 -190.561214)
		(width 0.14224)
		(layer "In2.Cu")
		(net "USB2_HUB_BUF_SWB_R_DN")
	)
	(segment
		(start 12.499848 -114.706908)
		(end 12.222988 -114.430048)
		(width 0.14224)
		(layer "In2.Cu")
		(net "USB2_HUB_BUF_SWB_R_DN")
	)
	(segment
		(start 17.981168 -137.124694)
		(end 16.220948 -161.670746)
		(width 0.14224)
		(layer "In2.Cu")
		(net "USB2_HUB_BUF_SWB_R_DN")
	)
	(segment
		(start 11.417046 -414.362138)
		(end 12.041632 -415.870136)
		(width 0.14224)
		(layer "In2.Cu")
		(net "USB2_HUB_BUF_SWB_R_DN")
	)
	(segment
		(start 3.599942 -396.103856)
		(end 10.656316 -403.16023)
		(width 0.14224)
		(layer "In2.Cu")
		(net "USB2_HUB_BUF_SWB_R_DN")
	)
	(segment
		(start 10.12444 -113.909348)
		(end 10.12444 -116.028724)
		(width 0.14224)
		(layer "In2.Cu")
		(net "USB2_HUB_BUF_SWB_R_DN")
	)
	(segment
		(start 23.64867 -418.7952)
		(end 25.269698 -417.174172)
		(width 0.14224)
		(layer "In2.Cu")
		(net "USB2_HUB_BUF_SWB_R_DN")
	)
	(segment
		(start 13.081508 -417.858448)
		(end 14.01826 -418.7952)
		(width 0.14224)
		(layer "In2.Cu")
		(net "USB2_HUB_BUF_SWB_R_DN")
	)
	(segment
		(start 25.269698 -417.174172)
		(end 35.923474 -417.174172)
		(width 0.14224)
		(layer "In2.Cu")
		(net "USB2_HUB_BUF_SWB_R_DN")
	)
	(segment
		(start 10.825734 -179.284884)
		(end 7.18693 -185.128916)
		(width 0.14224)
		(layer "In2.Cu")
		(net "USB2_HUB_BUF_SWB_R_DN")
	)
	(segment
		(start 9.809734 -407.29789)
		(end 9.809734 -409.411932)
		(width 0.14224)
		(layer "In2.Cu")
		(net "USB2_HUB_BUF_SWB_R_DN")
	)
	(segment
		(start 9.809734 -409.411932)
		(end 9.118346 -410.10332)
		(width 0.14224)
		(layer "In2.Cu")
		(net "USB2_HUB_BUF_SWB_R_DN")
	)
	(segment
		(start 10.656316 -403.16023)
		(end 10.656316 -406.451308)
		(width 0.14224)
		(layer "In2.Cu")
		(net "USB2_HUB_BUF_SWB_R_DN")
	)
	(segment
		(start 12.222988 -113.543334)
		(end 11.814556 -113.134902)
		(width 0.14224)
		(layer "In2.Cu")
		(net "USB2_HUB_BUF_SWB_R_DN")
	)
	(segment
		(start 16.220948 -161.670746)
		(end 10.825734 -179.284884)
		(width 0.14224)
		(layer "In2.Cu")
		(net "USB2_HUB_BUF_SWB_R_DN")
	)
	(segment
		(start 35.923474 -417.174172)
		(end 36.214304 -417.465002)
		(width 0.14224)
		(layer "In2.Cu")
		(net "USB2_HUB_BUF_SWB_R_DN")
	)
	(segment
		(start 6.205474 -190.561214)
		(end 7.815834 -326.820022)
		(width 0.14224)
		(layer "In2.Cu")
		(net "USB2_HUB_BUF_SWB_R_DN")
	)
	(segment
		(start 9.118346 -411.246066)
		(end 9.69645 -412.641542)
		(width 0.14224)
		(layer "In2.Cu")
		(net "USB2_HUB_BUF_SWB_R_DN")
	)
	(segment
		(start 13.367258 -119.271542)
		(end 17.535906 -129.254504)
		(width 0.14224)
		(layer "In2.Cu")
		(net "USB2_HUB_BUF_SWB_R_DN")
	)
	(segment
		(start 11.814556 -113.134902)
		(end 10.898886 -113.134902)
		(width 0.14224)
		(layer "In2.Cu")
		(net "USB2_HUB_BUF_SWB_R_DN")
	)
	(segment
		(start 9.118346 -410.10332)
		(end 9.118346 -411.246066)
		(width 0.14224)
		(layer "In2.Cu")
		(net "USB2_HUB_BUF_SWB_R_DN")
	)
	(segment
		(start 12.222988 -114.430048)
		(end 12.222988 -113.543334)
		(width 0.14224)
		(layer "In2.Cu")
		(net "USB2_HUB_BUF_SWB_R_DN")
	)
	(segment
		(start 9.69645 -412.641542)
		(end 11.417046 -414.362138)
		(width 0.14224)
		(layer "In2.Cu")
		(net "USB2_HUB_BUF_SWB_R_DN")
	)
	(segment
		(start 12.041632 -415.870136)
		(end 12.041632 -416.996372)
		(width 0.14224)
		(layer "In2.Cu")
		(net "USB2_HUB_BUF_SWB_R_DN")
	)
	(segment
		(start 10.656316 -406.451308)
		(end 9.809734 -407.29789)
		(width 0.14224)
		(layer "In2.Cu")
		(net "USB2_HUB_BUF_SWB_R_DN")
	)
	(segment
		(start 17.535906 -129.254504)
		(end 17.981168 -137.124694)
		(width 0.14224)
		(layer "In2.Cu")
		(net "USB2_HUB_BUF_SWB_R_DN")
	)
	(segment
		(start 10.12444 -116.028724)
		(end 13.367258 -119.271542)
		(width 0.14224)
		(layer "In2.Cu")
		(net "USB2_HUB_BUF_SWB_R_DN")
	)
	(segment
		(start 15.288006 -105.93578)
		(end 15.288006 -106.415586)
		(width 0.12954)
		(layer "F.Cu")
		(net "USB2_HOST_BMC_B_BUF_DP")
	)
	(segment
		(start 11.966702 -108.623862)
		(end 11.67384 -108.916724)
		(width 0.12954)
		(layer "F.Cu")
		(net "USB2_HOST_BMC_B_BUF_DP")
	)
	(segment
		(start 11.421618 -106.68254)
		(end 11.421618 -107.278678)
		(width 0.12954)
		(layer "F.Cu")
		(net "USB2_HOST_BMC_B_BUF_DP")
	)
	(segment
		(start 15.627096 -107.631484)
		(end 15.286228 -107.631484)
		(width 0.12954)
		(layer "F.Cu")
		(net "USB2_HOST_BMC_B_BUF_DP")
	)
	(segment
		(start 15.79372 -106.9213)
		(end 15.79372 -107.46486)
		(width 0.12954)
		(layer "F.Cu")
		(net "USB2_HOST_BMC_B_BUF_DP")
	)
	(segment
		(start 15.79372 -107.46486)
		(end 15.627096 -107.631484)
		(width 0.12954)
		(layer "F.Cu")
		(net "USB2_HOST_BMC_B_BUF_DP")
	)
	(segment
		(start 15.804642 -109.094016)
		(end 15.804642 -108.149898)
		(width 0.12954)
		(layer "F.Cu")
		(net "USB2_HOST_BMC_B_BUF_DP")
	)
	(segment
		(start 15.288006 -106.415586)
		(end 15.79372 -106.9213)
		(width 0.12954)
		(layer "F.Cu")
		(net "USB2_HOST_BMC_B_BUF_DP")
	)
	(segment
		(start 15.804642 -108.149898)
		(end 15.286228 -107.631484)
		(width 0.12954)
		(layer "F.Cu")
		(net "USB2_HOST_BMC_B_BUF_DP")
	)
	(segment
		(start 15.473934 -109.424724)
		(end 15.804642 -109.094016)
		(width 0.12954)
		(layer "F.Cu")
		(net "USB2_HOST_BMC_B_BUF_DP")
	)
	(segment
		(start 11.966702 -107.823762)
		(end 11.966702 -108.623862)
		(width 0.12954)
		(layer "F.Cu")
		(net "USB2_HOST_BMC_B_BUF_DP")
	)
	(segment
		(start 11.421618 -107.278678)
		(end 11.966702 -107.823762)
		(width 0.12954)
		(layer "F.Cu")
		(net "USB2_HOST_BMC_B_BUF_DP")
	)
	(via
		(at 11.67384 -108.916724)
		(size 0.508)
		(drill 0.254)
		(layers "F.Cu" "B.Cu")
		(net "USB2_HOST_BMC_B_BUF_DP")
	)
	(via
		(at 15.473934 -109.424724)
		(size 0.508)
		(drill 0.254)
		(layers "F.Cu" "B.Cu")
		(net "USB2_HOST_BMC_B_BUF_DP")
	)
	(segment
		(start 15.333726 -107.383834)
		(end 12.894818 -109.822742)
		(width 0.12954)
		(layer "B.Cu")
		(net "USB2_HOST_BMC_B_BUF_DP")
	)
	(segment
		(start 11.94435 -109.187234)
		(end 11.67384 -108.916724)
		(width 0.12954)
		(layer "B.Cu")
		(net "USB2_HOST_BMC_B_BUF_DP")
	)
	(segment
		(start 15.81277 -107.513374)
		(end 15.68323 -107.383834)
		(width 0.12954)
		(layer "B.Cu")
		(net "USB2_HOST_BMC_B_BUF_DP")
	)
	(segment
		(start 12.323572 -109.822742)
		(end 11.94435 -109.44352)
		(width 0.12954)
		(layer "B.Cu")
		(net "USB2_HOST_BMC_B_BUF_DP")
	)
	(segment
		(start 15.473934 -109.424724)
		(end 15.81277 -109.085888)
		(width 0.12954)
		(layer "B.Cu")
		(net "USB2_HOST_BMC_B_BUF_DP")
	)
	(segment
		(start 15.81277 -109.085888)
		(end 15.81277 -107.513374)
		(width 0.12954)
		(layer "B.Cu")
		(net "USB2_HOST_BMC_B_BUF_DP")
	)
	(segment
		(start 15.68323 -107.383834)
		(end 15.333726 -107.383834)
		(width 0.12954)
		(layer "B.Cu")
		(net "USB2_HOST_BMC_B_BUF_DP")
	)
	(segment
		(start 11.94435 -109.44352)
		(end 11.94435 -109.187234)
		(width 0.12954)
		(layer "B.Cu")
		(net "USB2_HOST_BMC_B_BUF_DP")
	)
	(segment
		(start 12.894818 -109.822742)
		(end 12.323572 -109.822742)
		(width 0.12954)
		(layer "B.Cu")
		(net "USB2_HOST_BMC_B_BUF_DP")
	)
	(segment
		(start 16.127222 -109.087412)
		(end 16.127222 -108.149644)
		(width 0.12954)
		(layer "F.Cu")
		(net "USB2_HOST_BMC_B_BUF_DN")
	)
	(segment
		(start 16.645382 -106.419904)
		(end 16.1163 -106.948986)
		(width 0.12954)
		(layer "F.Cu")
		(net "USB2_HOST_BMC_B_BUF_DN")
	)
	(segment
		(start 12.289282 -107.809538)
		(end 12.289282 -108.668566)
		(width 0.12954)
		(layer "F.Cu")
		(net "USB2_HOST_BMC_B_BUF_DN")
	)
	(segment
		(start 12.786106 -106.70413)
		(end 12.786106 -107.312714)
		(width 0.12954)
		(layer "F.Cu")
		(net "USB2_HOST_BMC_B_BUF_DN")
	)
	(segment
		(start 16.645382 -105.96626)
		(end 16.645382 -106.419904)
		(width 0.12954)
		(layer "F.Cu")
		(net "USB2_HOST_BMC_B_BUF_DN")
	)
	(segment
		(start 16.1163 -107.431586)
		(end 16.316198 -107.631484)
		(width 0.12954)
		(layer "F.Cu")
		(net "USB2_HOST_BMC_B_BUF_DN")
	)
	(segment
		(start 16.464534 -109.424724)
		(end 16.127222 -109.087412)
		(width 0.12954)
		(layer "F.Cu")
		(net "USB2_HOST_BMC_B_BUF_DN")
	)
	(segment
		(start 12.289282 -108.668566)
		(end 12.53744 -108.916724)
		(width 0.12954)
		(layer "F.Cu")
		(net "USB2_HOST_BMC_B_BUF_DN")
	)
	(segment
		(start 12.786106 -107.312714)
		(end 12.289282 -107.809538)
		(width 0.12954)
		(layer "F.Cu")
		(net "USB2_HOST_BMC_B_BUF_DN")
	)
	(segment
		(start 16.316198 -107.631484)
		(end 16.645382 -107.631484)
		(width 0.12954)
		(layer "F.Cu")
		(net "USB2_HOST_BMC_B_BUF_DN")
	)
	(segment
		(start 16.127222 -108.149644)
		(end 16.645382 -107.631484)
		(width 0.12954)
		(layer "F.Cu")
		(net "USB2_HOST_BMC_B_BUF_DN")
	)
	(segment
		(start 16.1163 -106.948986)
		(end 16.1163 -107.431586)
		(width 0.12954)
		(layer "F.Cu")
		(net "USB2_HOST_BMC_B_BUF_DN")
	)
	(via
		(at 12.53744 -108.916724)
		(size 0.508)
		(drill 0.254)
		(layers "F.Cu" "B.Cu")
		(net "USB2_HOST_BMC_B_BUF_DN")
	)
	(via
		(at 16.464534 -109.424724)
		(size 0.508)
		(drill 0.254)
		(layers "F.Cu" "B.Cu")
		(net "USB2_HOST_BMC_B_BUF_DN")
	)
	(segment
		(start 15.817088 -107.061254)
		(end 15.199868 -107.061254)
		(width 0.12954)
		(layer "B.Cu")
		(net "USB2_HOST_BMC_B_BUF_DN")
	)
	(segment
		(start 16.464534 -109.424724)
		(end 16.13535 -109.09554)
		(width 0.12954)
		(layer "B.Cu")
		(net "USB2_HOST_BMC_B_BUF_DN")
	)
	(segment
		(start 12.76096 -109.500162)
		(end 12.45743 -109.500162)
		(width 0.12954)
		(layer "B.Cu")
		(net "USB2_HOST_BMC_B_BUF_DN")
	)
	(segment
		(start 16.13535 -107.379516)
		(end 15.817088 -107.061254)
		(width 0.12954)
		(layer "B.Cu")
		(net "USB2_HOST_BMC_B_BUF_DN")
	)
	(segment
		(start 12.26693 -109.309662)
		(end 12.26693 -109.187234)
		(width 0.12954)
		(layer "B.Cu")
		(net "USB2_HOST_BMC_B_BUF_DN")
	)
	(segment
		(start 12.45743 -109.500162)
		(end 12.26693 -109.309662)
		(width 0.12954)
		(layer "B.Cu")
		(net "USB2_HOST_BMC_B_BUF_DN")
	)
	(segment
		(start 12.26693 -109.187234)
		(end 12.53744 -108.916724)
		(width 0.12954)
		(layer "B.Cu")
		(net "USB2_HOST_BMC_B_BUF_DN")
	)
	(segment
		(start 15.199868 -107.061254)
		(end 12.76096 -109.500162)
		(width 0.12954)
		(layer "B.Cu")
		(net "USB2_HOST_BMC_B_BUF_DN")
	)
	(segment
		(start 16.13535 -109.09554)
		(end 16.13535 -107.379516)
		(width 0.12954)
		(layer "B.Cu")
		(net "USB2_HOST_BMC_B_BUF_DN")
	)
	(segment
		(start 119.910606 -13.974064)
		(end 119.940832 -14.00429)
		(width 0.10668)
		(layer "F.Cu")
		(net "U273_3_ADD2")
	)
	(segment
		(start 115.856512 -13.974064)
		(end 118.478046 -13.974064)
		(width 0.10668)
		(layer "F.Cu")
		(net "U273_3_ADD2")
	)
	(segment
		(start 120.047512 -14.536166)
		(end 123.329192 -14.536166)
		(width 0.10668)
		(layer "F.Cu")
		(net "U273_3_ADD2")
	)
	(segment
		(start 119.940832 -14.00429)
		(end 119.940832 -14.429486)
		(width 0.10668)
		(layer "F.Cu")
		(net "U273_3_ADD2")
	)
	(segment
		(start 118.478046 -13.974064)
		(end 119.910606 -13.974064)
		(width 0.10668)
		(layer "F.Cu")
		(net "U273_3_ADD2")
	)
	(segment
		(start 123.329192 -14.536166)
		(end 123.435872 -14.429486)
		(width 0.10668)
		(layer "F.Cu")
		(net "U273_3_ADD2")
	)
	(segment
		(start 119.940832 -14.429486)
		(end 120.047512 -14.536166)
		(width 0.10668)
		(layer "F.Cu")
		(net "U273_3_ADD2")
	)
	(segment
		(start 123.435872 -14.429486)
		(end 123.435872 -13.99413)
		(width 0.10668)
		(layer "F.Cu")
		(net "U273_3_ADD2")
	)
	(via
		(at 118.478046 -13.974064)
		(size 0.762)
		(drill 0.381)
		(layers "F.Cu" "B.Cu")
		(net "U273_3_ADD2")
	)
	(segment
		(start 119.958612 -15.722346)
		(end 120.129046 -15.89278)
		(width 0.10668)
		(layer "F.Cu")
		(net "U273_3_ADD1")
	)
	(segment
		(start 119.958612 -15.247366)
		(end 119.958612 -15.722346)
		(width 0.10668)
		(layer "F.Cu")
		(net "U273_3_ADD1")
	)
	(segment
		(start 120.129046 -15.89278)
		(end 122.769122 -15.89278)
		(width 0.10668)
		(layer "F.Cu")
		(net "U273_3_ADD1")
	)
	(segment
		(start 115.856512 -15.244064)
		(end 117.919246 -15.244064)
		(width 0.10668)
		(layer "F.Cu")
		(net "U273_3_ADD1")
	)
	(segment
		(start 119.95531 -15.244064)
		(end 119.958612 -15.247366)
		(width 0.10668)
		(layer "F.Cu")
		(net "U273_3_ADD1")
	)
	(segment
		(start 117.919246 -15.244064)
		(end 119.95531 -15.244064)
		(width 0.10668)
		(layer "F.Cu")
		(net "U273_3_ADD1")
	)
	(segment
		(start 122.769122 -15.89278)
		(end 123.395232 -15.26667)
		(width 0.10668)
		(layer "F.Cu")
		(net "U273_3_ADD1")
	)
	(via
		(at 117.919246 -15.244064)
		(size 0.762)
		(drill 0.381)
		(layers "F.Cu" "B.Cu")
		(net "U273_3_ADD1")
	)
	(segment
		(start 118.325646 -16.514064)
		(end 119.948198 -16.514064)
		(width 0.10668)
		(layer "F.Cu")
		(net "U273_3_ADD0")
	)
	(segment
		(start 123.367292 -17.048734)
		(end 123.367292 -16.50111)
		(width 0.10668)
		(layer "F.Cu")
		(net "U273_3_ADD0")
	)
	(segment
		(start 120.306846 -17.51838)
		(end 122.897646 -17.51838)
		(width 0.10668)
		(layer "F.Cu")
		(net "U273_3_ADD0")
	)
	(segment
		(start 122.897646 -17.51838)
		(end 123.367292 -17.048734)
		(width 0.10668)
		(layer "F.Cu")
		(net "U273_3_ADD0")
	)
	(segment
		(start 115.856512 -16.514064)
		(end 118.325646 -16.514064)
		(width 0.10668)
		(layer "F.Cu")
		(net "U273_3_ADD0")
	)
	(segment
		(start 119.948198 -16.514064)
		(end 119.958612 -16.50365)
		(width 0.10668)
		(layer "F.Cu")
		(net "U273_3_ADD0")
	)
	(segment
		(start 119.958612 -16.50365)
		(end 119.958612 -17.170146)
		(width 0.10668)
		(layer "F.Cu")
		(net "U273_3_ADD0")
	)
	(segment
		(start 119.958612 -17.170146)
		(end 120.306846 -17.51838)
		(width 0.10668)
		(layer "F.Cu")
		(net "U273_3_ADD0")
	)
	(via
		(at 118.325646 -16.514064)
		(size 0.762)
		(drill 0.381)
		(layers "F.Cu" "B.Cu")
		(net "U273_3_ADD0")
	)
	(segment
		(start 101.555296 -420.37508)
		(end 101.555296 -422.03243)
		(width 0.10668)
		(layer "F.Cu")
		(net "U272_2_ADD2")
	)
	(segment
		(start 100.920296 -424.21048)
		(end 100.920296 -425.42968)
		(width 0.10668)
		(layer "F.Cu")
		(net "U272_2_ADD2")
	)
	(segment
		(start 101.555296 -422.03243)
		(end 101.174296 -422.03243)
		(width 0.10668)
		(layer "F.Cu")
		(net "U272_2_ADD2")
	)
	(segment
		(start 101.174296 -422.03243)
		(end 100.920296 -422.28643)
		(width 0.10668)
		(layer "F.Cu")
		(net "U272_2_ADD2")
	)
	(segment
		(start 100.920296 -422.28643)
		(end 100.920296 -424.21048)
		(width 0.10668)
		(layer "F.Cu")
		(net "U272_2_ADD2")
	)
	(via
		(at 100.920296 -424.21048)
		(size 0.762)
		(drill 0.381)
		(layers "F.Cu" "B.Cu")
		(net "U272_2_ADD2")
	)
	(segment
		(start 99.904296 -422.03243)
		(end 99.650296 -422.28643)
		(width 0.10668)
		(layer "F.Cu")
		(net "U272_2_ADD1")
	)
	(segment
		(start 99.650296 -424.21048)
		(end 99.650296 -425.42968)
		(width 0.10668)
		(layer "F.Cu")
		(net "U272_2_ADD1")
	)
	(segment
		(start 99.650296 -422.28643)
		(end 99.650296 -424.21048)
		(width 0.10668)
		(layer "F.Cu")
		(net "U272_2_ADD1")
	)
	(segment
		(start 100.285296 -422.03243)
		(end 99.904296 -422.03243)
		(width 0.10668)
		(layer "F.Cu")
		(net "U272_2_ADD1")
	)
	(segment
		(start 100.285296 -420.37508)
		(end 100.285296 -422.03243)
		(width 0.10668)
		(layer "F.Cu")
		(net "U272_2_ADD1")
	)
	(via
		(at 99.650296 -424.21048)
		(size 0.762)
		(drill 0.381)
		(layers "F.Cu" "B.Cu")
		(net "U272_2_ADD1")
	)
	(segment
		(start 98.380296 -422.28643)
		(end 98.380296 -424.21048)
		(width 0.10668)
		(layer "F.Cu")
		(net "U272_2_ADD0")
	)
	(segment
		(start 98.634296 -422.03243)
		(end 98.380296 -422.28643)
		(width 0.10668)
		(layer "F.Cu")
		(net "U272_2_ADD0")
	)
	(segment
		(start 99.015296 -420.37508)
		(end 99.015296 -422.03243)
		(width 0.10668)
		(layer "F.Cu")
		(net "U272_2_ADD0")
	)
	(segment
		(start 98.380296 -424.21048)
		(end 98.380296 -425.42968)
		(width 0.10668)
		(layer "F.Cu")
		(net "U272_2_ADD0")
	)
	(segment
		(start 99.015296 -422.03243)
		(end 98.634296 -422.03243)
		(width 0.10668)
		(layer "F.Cu")
		(net "U272_2_ADD0")
	)
	(via
		(at 98.380296 -424.21048)
		(size 0.762)
		(drill 0.381)
		(layers "F.Cu" "B.Cu")
		(net "U272_2_ADD0")
	)
	(segment
		(start 299.372528 -13.41501)
		(end 297.109642 -13.41501)
		(width 0.10668)
		(layer "F.Cu")
		(net "U271_1_ADD2")
	)
	(segment
		(start 301.163736 -12.964668)
		(end 301.552356 -13.353288)
		(width 0.10668)
		(layer "F.Cu")
		(net "U271_1_ADD2")
	)
	(segment
		(start 299.372528 -13.41501)
		(end 299.82287 -12.964668)
		(width 0.10668)
		(layer "F.Cu")
		(net "U271_1_ADD2")
	)
	(segment
		(start 299.82287 -12.964668)
		(end 301.163736 -12.964668)
		(width 0.10668)
		(layer "F.Cu")
		(net "U271_1_ADD2")
	)
	(segment
		(start 297.109642 -13.41501)
		(end 297.015408 -13.509244)
		(width 0.10668)
		(layer "F.Cu")
		(net "U271_1_ADD2")
	)
	(segment
		(start 301.552356 -13.353288)
		(end 302.892206 -13.353288)
		(width 0.10668)
		(layer "F.Cu")
		(net "U271_1_ADD2")
	)
	(segment
		(start 302.892206 -13.353288)
		(end 302.953928 -13.41501)
		(width 0.10668)
		(layer "F.Cu")
		(net "U271_1_ADD2")
	)
	(via
		(at 301.552356 -13.353288)
		(size 0.762)
		(drill 0.381)
		(layers "F.Cu" "B.Cu")
		(net "U271_1_ADD2")
	)
	(segment
		(start 299.367448 -14.61516)
		(end 299.811948 -15.05966)
		(width 0.10668)
		(layer "F.Cu")
		(net "U271_1_ADD1")
	)
	(segment
		(start 301.592996 -15.016988)
		(end 302.43907 -15.016988)
		(width 0.10668)
		(layer "F.Cu")
		(net "U271_1_ADD1")
	)
	(segment
		(start 299.367448 -14.48181)
		(end 299.367448 -14.61516)
		(width 0.10668)
		(layer "F.Cu")
		(net "U271_1_ADD1")
	)
	(segment
		(start 301.550324 -15.05966)
		(end 301.592996 -15.016988)
		(width 0.10668)
		(layer "F.Cu")
		(net "U271_1_ADD1")
	)
	(segment
		(start 299.811948 -15.05966)
		(end 301.550324 -15.05966)
		(width 0.10668)
		(layer "F.Cu")
		(net "U271_1_ADD1")
	)
	(segment
		(start 299.367448 -14.48181)
		(end 299.36567 -14.483588)
		(width 0.10668)
		(layer "F.Cu")
		(net "U271_1_ADD1")
	)
	(segment
		(start 302.43907 -15.016988)
		(end 302.974248 -14.48181)
		(width 0.10668)
		(layer "F.Cu")
		(net "U271_1_ADD1")
	)
	(segment
		(start 298.35602 -14.779244)
		(end 297.015408 -14.779244)
		(width 0.10668)
		(layer "F.Cu")
		(net "U271_1_ADD1")
	)
	(segment
		(start 299.36567 -14.483588)
		(end 298.651676 -14.483588)
		(width 0.10668)
		(layer "F.Cu")
		(net "U271_1_ADD1")
	)
	(segment
		(start 298.651676 -14.483588)
		(end 298.35602 -14.779244)
		(width 0.10668)
		(layer "F.Cu")
		(net "U271_1_ADD1")
	)
	(via
		(at 301.592996 -15.016988)
		(size 0.762)
		(drill 0.381)
		(layers "F.Cu" "B.Cu")
		(net "U271_1_ADD1")
	)
	(segment
		(start 299.367448 -15.62481)
		(end 299.367448 -16.26616)
		(width 0.10668)
		(layer "F.Cu")
		(net "U271_1_ADD0")
	)
	(segment
		(start 299.642276 -16.540988)
		(end 301.430436 -16.540988)
		(width 0.10668)
		(layer "F.Cu")
		(net "U271_1_ADD0")
	)
	(segment
		(start 299.367448 -16.26616)
		(end 299.642276 -16.540988)
		(width 0.10668)
		(layer "F.Cu")
		(net "U271_1_ADD0")
	)
	(segment
		(start 302.03267 -16.540988)
		(end 302.948848 -15.62481)
		(width 0.10668)
		(layer "F.Cu")
		(net "U271_1_ADD0")
	)
	(segment
		(start 298.677076 -15.651988)
		(end 298.27982 -16.049244)
		(width 0.10668)
		(layer "F.Cu")
		(net "U271_1_ADD0")
	)
	(segment
		(start 299.34027 -15.651988)
		(end 298.677076 -15.651988)
		(width 0.10668)
		(layer "F.Cu")
		(net "U271_1_ADD0")
	)
	(segment
		(start 301.430436 -16.540988)
		(end 302.03267 -16.540988)
		(width 0.10668)
		(layer "F.Cu")
		(net "U271_1_ADD0")
	)
	(segment
		(start 299.367448 -15.62481)
		(end 299.34027 -15.651988)
		(width 0.10668)
		(layer "F.Cu")
		(net "U271_1_ADD0")
	)
	(segment
		(start 298.27982 -16.049244)
		(end 297.015408 -16.049244)
		(width 0.10668)
		(layer "F.Cu")
		(net "U271_1_ADD0")
	)
	(via
		(at 301.430436 -16.540988)
		(size 0.762)
		(drill 0.381)
		(layers "F.Cu" "B.Cu")
		(net "U271_1_ADD0")
	)
	(segment
		(start 371.250718 -423.602912)
		(end 371.272308 -423.624502)
		(width 0.10668)
		(layer "F.Cu")
		(net "U270_0_ADD2")
	)
	(segment
		(start 369.717066 -421.945562)
		(end 369.717066 -423.088054)
		(width 0.10668)
		(layer "F.Cu")
		(net "U270_0_ADD2")
	)
	(segment
		(start 369.717066 -423.088054)
		(end 369.717066 -423.157904)
		(width 0.10668)
		(layer "F.Cu")
		(net "U270_0_ADD2")
	)
	(segment
		(start 370.225066 -423.602912)
		(end 371.250718 -423.602912)
		(width 0.10668)
		(layer "F.Cu")
		(net "U270_0_ADD2")
	)
	(segment
		(start 369.717066 -423.157904)
		(end 370.162074 -423.602912)
		(width 0.10668)
		(layer "F.Cu")
		(net "U270_0_ADD2")
	)
	(segment
		(start 370.162074 -423.602912)
		(end 370.225066 -423.602912)
		(width 0.10668)
		(layer "F.Cu")
		(net "U270_0_ADD2")
	)
	(via
		(at 369.717066 -423.088054)
		(size 0.508)
		(drill 0.254)
		(layers "F.Cu" "B.Cu")
		(net "U270_0_ADD2")
	)
	(segment
		(start 368.589306 -423.602912)
		(end 368.955066 -423.602912)
		(width 0.10668)
		(layer "F.Cu")
		(net "U270_0_ADD1")
	)
	(segment
		(start 368.462306 -425.866306)
		(end 368.462306 -423.729912)
		(width 0.10668)
		(layer "F.Cu")
		(net "U270_0_ADD1")
	)
	(segment
		(start 368.462306 -423.729912)
		(end 368.589306 -423.602912)
		(width 0.10668)
		(layer "F.Cu")
		(net "U270_0_ADD1")
	)
	(segment
		(start 368.320066 -426.755052)
		(end 368.06378 -427.011338)
		(width 0.10668)
		(layer "F.Cu")
		(net "U270_0_ADD1")
	)
	(segment
		(start 368.447066 -422.673272)
		(end 368.955066 -423.181272)
		(width 0.10668)
		(layer "F.Cu")
		(net "U270_0_ADD1")
	)
	(segment
		(start 368.320066 -426.755052)
		(end 368.554 -426.521118)
		(width 0.10668)
		(layer "F.Cu")
		(net "U270_0_ADD1")
	)
	(segment
		(start 368.554 -425.958)
		(end 368.462306 -425.866306)
		(width 0.10668)
		(layer "F.Cu")
		(net "U270_0_ADD1")
	)
	(segment
		(start 368.955066 -423.181272)
		(end 368.955066 -423.602912)
		(width 0.10668)
		(layer "F.Cu")
		(net "U270_0_ADD1")
	)
	(segment
		(start 368.447066 -421.945562)
		(end 368.447066 -422.673272)
		(width 0.10668)
		(layer "F.Cu")
		(net "U270_0_ADD1")
	)
	(segment
		(start 368.554 -426.521118)
		(end 368.554 -425.958)
		(width 0.10668)
		(layer "F.Cu")
		(net "U270_0_ADD1")
	)
	(via
		(at 368.554 -425.958)
		(size 0.762)
		(drill 0.381)
		(layers "F.Cu" "B.Cu")
		(net "U270_0_ADD1")
	)
	(segment
		(start 367.685066 -423.602912)
		(end 367.685066 -423.197274)
		(width 0.10668)
		(layer "F.Cu")
		(net "U270_0_ADD0")
	)
	(segment
		(start 367.304066 -423.602912)
		(end 367.685066 -423.602912)
		(width 0.10668)
		(layer "F.Cu")
		(net "U270_0_ADD0")
	)
	(segment
		(start 367.050066 -425.980606)
		(end 367.050066 -423.856912)
		(width 0.10668)
		(layer "F.Cu")
		(net "U270_0_ADD0")
	)
	(segment
		(start 367.177066 -422.689274)
		(end 367.177066 -421.945562)
		(width 0.10668)
		(layer "F.Cu")
		(net "U270_0_ADD0")
	)
	(segment
		(start 367.685066 -423.197274)
		(end 367.177066 -422.689274)
		(width 0.10668)
		(layer "F.Cu")
		(net "U270_0_ADD0")
	)
	(segment
		(start 367.050066 -427.000162)
		(end 367.050066 -425.980606)
		(width 0.10668)
		(layer "F.Cu")
		(net "U270_0_ADD0")
	)
	(segment
		(start 367.050066 -423.856912)
		(end 367.304066 -423.602912)
		(width 0.10668)
		(layer "F.Cu")
		(net "U270_0_ADD0")
	)
	(via
		(at 367.050066 -425.980606)
		(size 0.762)
		(drill 0.381)
		(layers "F.Cu" "B.Cu")
		(net "U270_0_ADD0")
	)
	(via
		(at 6.99008 -110.487968)
		(size 0.6604)
		(drill 0.3302)
		(layers "F.Cu" "B.Cu")
		(net "TP_USB2_TEST")
	)
	(segment
		(start 9.676384 -111.177324)
		(end 9.13384 -110.63478)
		(width 0.10668)
		(layer "B.Cu")
		(net "TP_USB2_TEST")
	)
	(segment
		(start 8.684768 -109.858048)
		(end 7.62 -109.858048)
		(width 0.10668)
		(layer "B.Cu")
		(net "TP_USB2_TEST")
	)
	(segment
		(start 7.62 -109.858048)
		(end 6.99008 -110.487968)
		(width 0.10668)
		(layer "B.Cu")
		(net "TP_USB2_TEST")
	)
	(segment
		(start 11.276584 -111.71936)
		(end 10.56132 -111.71936)
		(width 0.10668)
		(layer "B.Cu")
		(net "TP_USB2_TEST")
	)
	(segment
		(start 10.56132 -111.71936)
		(end 10.019284 -111.177324)
		(width 0.10668)
		(layer "B.Cu")
		(net "TP_USB2_TEST")
	)
	(segment
		(start 10.019284 -111.177324)
		(end 9.676384 -111.177324)
		(width 0.10668)
		(layer "B.Cu")
		(net "TP_USB2_TEST")
	)
	(segment
		(start 9.13384 -110.63478)
		(end 9.13384 -110.30712)
		(width 0.10668)
		(layer "B.Cu")
		(net "TP_USB2_TEST")
	)
	(segment
		(start 9.13384 -110.30712)
		(end 8.684768 -109.858048)
		(width 0.10668)
		(layer "B.Cu")
		(net "TP_USB2_TEST")
	)
	(via
		(at 14.71168 -113.970308)
		(size 0.6604)
		(drill 0.3302)
		(layers "F.Cu" "B.Cu")
		(net "TP_USB2_ENA_HS")
	)
	(segment
		(start 13.927836 -113.970308)
		(end 14.71168 -113.970308)
		(width 0.10668)
		(layer "B.Cu")
		(net "TP_USB2_ENA_HS")
	)
	(segment
		(start 12.876784 -112.919256)
		(end 13.927836 -113.970308)
		(width 0.10668)
		(layer "B.Cu")
		(net "TP_USB2_ENA_HS")
	)
	(via
		(at 8.4709 -110.487968)
		(size 0.6604)
		(drill 0.3302)
		(layers "F.Cu" "B.Cu")
		(net "TP_USB2_CD")
	)
	(segment
		(start 10.53973 -112.11941)
		(end 10.01268 -111.59236)
		(width 0.10668)
		(layer "B.Cu")
		(net "TP_USB2_CD")
	)
	(segment
		(start 11.276584 -112.11941)
		(end 10.53973 -112.11941)
		(width 0.10668)
		(layer "B.Cu")
		(net "TP_USB2_CD")
	)
	(segment
		(start 9.575292 -111.59236)
		(end 8.4709 -110.487968)
		(width 0.10668)
		(layer "B.Cu")
		(net "TP_USB2_CD")
	)
	(segment
		(start 10.01268 -111.59236)
		(end 9.575292 -111.59236)
		(width 0.10668)
		(layer "B.Cu")
		(net "TP_USB2_CD")
	)
	(segment
		(start 108.44149 -18.20291)
		(end 108.5342 -18.1102)
		(width 0.10668)
		(layer "F.Cu")
		(net "SMB_LM75_3_3V3AUX_SDA_R1")
	)
	(segment
		(start 109.067092 -17.784064)
		(end 110.556548 -17.784064)
		(width 0.10668)
		(layer "F.Cu")
		(net "SMB_LM75_3_3V3AUX_SDA_R1")
	)
	(segment
		(start 107.292648 -18.20291)
		(end 108.44149 -18.20291)
		(width 0.10668)
		(layer "F.Cu")
		(net "SMB_LM75_3_3V3AUX_SDA_R1")
	)
	(segment
		(start 108.713016 -18.13814)
		(end 109.067092 -17.784064)
		(width 0.10668)
		(layer "F.Cu")
		(net "SMB_LM75_3_3V3AUX_SDA_R1")
	)
	(segment
		(start 108.56214 -18.13814)
		(end 108.713016 -18.13814)
		(width 0.10668)
		(layer "F.Cu")
		(net "SMB_LM75_3_3V3AUX_SDA_R1")
	)
	(segment
		(start 108.5342 -18.1102)
		(end 108.56214 -18.13814)
		(width 0.10668)
		(layer "F.Cu")
		(net "SMB_LM75_3_3V3AUX_SDA_R1")
	)
	(via
		(at 108.5342 -18.1102)
		(size 0.508)
		(drill 0.254)
		(layers "F.Cu" "B.Cu")
		(net "SMB_LM75_3_3V3AUX_SDA_R1")
	)
	(segment
		(start 292.270688 -102.57155)
		(end 285.457138 -109.3851)
		(width 0.10668)
		(layer "F.Cu")
		(net "SMB_LM75_3_3V3AUX_SDA")
	)
	(segment
		(start 267.061442 -76.712572)
		(end 280.993596 -90.644726)
		(width 0.10668)
		(layer "F.Cu")
		(net "SMB_LM75_3_3V3AUX_SDA")
	)
	(segment
		(start 271.485106 -113.161318)
		(end 271.480534 -113.156746)
		(width 0.10668)
		(layer "F.Cu")
		(net "SMB_LM75_3_3V3AUX_SDA")
	)
	(segment
		(start 280.993596 -90.644726)
		(end 288.318194 -90.644726)
		(width 0.10668)
		(layer "F.Cu")
		(net "SMB_LM75_3_3V3AUX_SDA")
	)
	(segment
		(start 267.061442 -72.603614)
		(end 267.061442 -76.712572)
		(width 0.10668)
		(layer "F.Cu")
		(net "SMB_LM75_3_3V3AUX_SDA")
	)
	(segment
		(start 271.480534 -112.08893)
		(end 271.480534 -113.156746)
		(width 0.10668)
		(layer "F.Cu")
		(net "SMB_LM75_3_3V3AUX_SDA")
	)
	(segment
		(start 256.34188 -61.884052)
		(end 267.061442 -72.603614)
		(width 0.10668)
		(layer "F.Cu")
		(net "SMB_LM75_3_3V3AUX_SDA")
	)
	(segment
		(start 288.318194 -90.644726)
		(end 292.270688 -94.59722)
		(width 0.10668)
		(layer "F.Cu")
		(net "SMB_LM75_3_3V3AUX_SDA")
	)
	(segment
		(start 274.184364 -109.3851)
		(end 271.480534 -112.08893)
		(width 0.10668)
		(layer "F.Cu")
		(net "SMB_LM75_3_3V3AUX_SDA")
	)
	(segment
		(start 271.485106 -114.21237)
		(end 271.485106 -113.161318)
		(width 0.10668)
		(layer "F.Cu")
		(net "SMB_LM75_3_3V3AUX_SDA")
	)
	(segment
		(start 285.457138 -109.3851)
		(end 274.184364 -109.3851)
		(width 0.10668)
		(layer "F.Cu")
		(net "SMB_LM75_3_3V3AUX_SDA")
	)
	(segment
		(start 292.270688 -94.59722)
		(end 292.270688 -102.57155)
		(width 0.10668)
		(layer "F.Cu")
		(net "SMB_LM75_3_3V3AUX_SDA")
	)
	(segment
		(start 106.492548 -18.20291)
		(end 105.803446 -18.20291)
		(width 0.10668)
		(layer "F.Cu")
		(net "SMB_LM75_3_3V3AUX_SDA")
	)
	(via
		(at 105.803446 -18.20291)
		(size 0.508)
		(drill 0.254)
		(layers "F.Cu" "B.Cu")
		(net "SMB_LM75_3_3V3AUX_SDA")
	)
	(via
		(at 256.34188 -61.884052)
		(size 0.508)
		(drill 0.254)
		(layers "F.Cu" "B.Cu")
		(net "SMB_LM75_3_3V3AUX_SDA")
	)
	(segment
		(start 220.404944 -46.646338)
		(end 214.37346 -40.614854)
		(width 0.11684)
		(layer "In6.Cu")
		(net "SMB_LM75_3_3V3AUX_SDA")
	)
	(segment
		(start 231.721152 -60.135262)
		(end 226.274884 -60.135262)
		(width 0.11684)
		(layer "In6.Cu")
		(net "SMB_LM75_3_3V3AUX_SDA")
	)
	(segment
		(start 112.495076 -20.6883)
		(end 110.291118 -20.6883)
		(width 0.11684)
		(layer "In6.Cu")
		(net "SMB_LM75_3_3V3AUX_SDA")
	)
	(segment
		(start 113.358676 -19.8247)
		(end 112.495076 -20.6883)
		(width 0.11684)
		(layer "In6.Cu")
		(net "SMB_LM75_3_3V3AUX_SDA")
	)
	(segment
		(start 186.422284 -39.213028)
		(end 184.72912 -37.519864)
		(width 0.11684)
		(layer "In6.Cu")
		(net "SMB_LM75_3_3V3AUX_SDA")
	)
	(segment
		(start 106.553254 -18.20291)
		(end 105.803446 -18.20291)
		(width 0.11684)
		(layer "In6.Cu")
		(net "SMB_LM75_3_3V3AUX_SDA")
	)
	(segment
		(start 176.977548 -35.394646)
		(end 175.053752 -35.394646)
		(width 0.11684)
		(layer "In6.Cu")
		(net "SMB_LM75_3_3V3AUX_SDA")
	)
	(segment
		(start 220.404944 -54.265322)
		(end 220.404944 -46.646338)
		(width 0.11684)
		(layer "In6.Cu")
		(net "SMB_LM75_3_3V3AUX_SDA")
	)
	(segment
		(start 163.970462 -33.813242)
		(end 153.778204 -33.813242)
		(width 0.11684)
		(layer "In6.Cu")
		(net "SMB_LM75_3_3V3AUX_SDA")
	)
	(segment
		(start 232.787444 -59.06897)
		(end 231.721152 -60.135262)
		(width 0.11684)
		(layer "In6.Cu")
		(net "SMB_LM75_3_3V3AUX_SDA")
	)
	(segment
		(start 226.274884 -60.135262)
		(end 220.404944 -54.265322)
		(width 0.11684)
		(layer "In6.Cu")
		(net "SMB_LM75_3_3V3AUX_SDA")
	)
	(segment
		(start 256.34188 -61.884052)
		(end 238.6203 -61.884052)
		(width 0.11684)
		(layer "In6.Cu")
		(net "SMB_LM75_3_3V3AUX_SDA")
	)
	(segment
		(start 238.6203 -61.884052)
		(end 235.805218 -59.06897)
		(width 0.11684)
		(layer "In6.Cu")
		(net "SMB_LM75_3_3V3AUX_SDA")
	)
	(segment
		(start 180.760116 -36.278312)
		(end 177.861214 -36.278312)
		(width 0.11684)
		(layer "In6.Cu")
		(net "SMB_LM75_3_3V3AUX_SDA")
	)
	(segment
		(start 164.13734 -33.646364)
		(end 163.970462 -33.813242)
		(width 0.11684)
		(layer "In6.Cu")
		(net "SMB_LM75_3_3V3AUX_SDA")
	)
	(segment
		(start 177.861214 -36.278312)
		(end 176.977548 -35.394646)
		(width 0.11684)
		(layer "In6.Cu")
		(net "SMB_LM75_3_3V3AUX_SDA")
	)
	(segment
		(start 194.635882 -41.241472)
		(end 192.607438 -39.213028)
		(width 0.11684)
		(layer "In6.Cu")
		(net "SMB_LM75_3_3V3AUX_SDA")
	)
	(segment
		(start 173.30547 -33.646364)
		(end 164.13734 -33.646364)
		(width 0.11684)
		(layer "In6.Cu")
		(net "SMB_LM75_3_3V3AUX_SDA")
	)
	(segment
		(start 175.053752 -35.394646)
		(end 173.30547 -33.646364)
		(width 0.11684)
		(layer "In6.Cu")
		(net "SMB_LM75_3_3V3AUX_SDA")
	)
	(segment
		(start 141.831822 -21.86686)
		(end 138.167872 -21.86686)
		(width 0.11684)
		(layer "In6.Cu")
		(net "SMB_LM75_3_3V3AUX_SDA")
	)
	(segment
		(start 153.778204 -33.813242)
		(end 141.831822 -21.86686)
		(width 0.11684)
		(layer "In6.Cu")
		(net "SMB_LM75_3_3V3AUX_SDA")
	)
	(segment
		(start 192.607438 -39.213028)
		(end 186.422284 -39.213028)
		(width 0.11684)
		(layer "In6.Cu")
		(net "SMB_LM75_3_3V3AUX_SDA")
	)
	(segment
		(start 138.167872 -21.86686)
		(end 136.125712 -19.8247)
		(width 0.11684)
		(layer "In6.Cu")
		(net "SMB_LM75_3_3V3AUX_SDA")
	)
	(segment
		(start 182.001668 -37.519864)
		(end 180.760116 -36.278312)
		(width 0.11684)
		(layer "In6.Cu")
		(net "SMB_LM75_3_3V3AUX_SDA")
	)
	(segment
		(start 208.077054 -40.614854)
		(end 207.450436 -41.241472)
		(width 0.11684)
		(layer "In6.Cu")
		(net "SMB_LM75_3_3V3AUX_SDA")
	)
	(segment
		(start 109.84484 -20.242022)
		(end 108.592366 -20.242022)
		(width 0.11684)
		(layer "In6.Cu")
		(net "SMB_LM75_3_3V3AUX_SDA")
	)
	(segment
		(start 184.72912 -37.519864)
		(end 182.001668 -37.519864)
		(width 0.11684)
		(layer "In6.Cu")
		(net "SMB_LM75_3_3V3AUX_SDA")
	)
	(segment
		(start 108.592366 -20.242022)
		(end 106.553254 -18.20291)
		(width 0.11684)
		(layer "In6.Cu")
		(net "SMB_LM75_3_3V3AUX_SDA")
	)
	(segment
		(start 136.125712 -19.8247)
		(end 113.358676 -19.8247)
		(width 0.11684)
		(layer "In6.Cu")
		(net "SMB_LM75_3_3V3AUX_SDA")
	)
	(segment
		(start 235.805218 -59.06897)
		(end 232.787444 -59.06897)
		(width 0.11684)
		(layer "In6.Cu")
		(net "SMB_LM75_3_3V3AUX_SDA")
	)
	(segment
		(start 207.450436 -41.241472)
		(end 194.635882 -41.241472)
		(width 0.11684)
		(layer "In6.Cu")
		(net "SMB_LM75_3_3V3AUX_SDA")
	)
	(segment
		(start 214.37346 -40.614854)
		(end 208.077054 -40.614854)
		(width 0.11684)
		(layer "In6.Cu")
		(net "SMB_LM75_3_3V3AUX_SDA")
	)
	(segment
		(start 110.291118 -20.6883)
		(end 109.84484 -20.242022)
		(width 0.11684)
		(layer "In6.Cu")
		(net "SMB_LM75_3_3V3AUX_SDA")
	)
	(segment
		(start 107.292648 -16.98371)
		(end 108.2802 -16.98371)
		(width 0.10668)
		(layer "F.Cu")
		(net "SMB_LM75_3_3V3AUX_SCL_R1")
	)
	(segment
		(start 108.2802 -16.98371)
		(end 108.749846 -16.514064)
		(width 0.10668)
		(layer "F.Cu")
		(net "SMB_LM75_3_3V3AUX_SCL_R1")
	)
	(segment
		(start 108.749846 -16.514064)
		(end 110.556548 -16.514064)
		(width 0.10668)
		(layer "F.Cu")
		(net "SMB_LM75_3_3V3AUX_SCL_R1")
	)
	(via
		(at 108.749846 -16.514064)
		(size 0.508)
		(drill 0.254)
		(layers "F.Cu" "B.Cu")
		(net "SMB_LM75_3_3V3AUX_SCL_R1")
	)
	(segment
		(start 257.86588 -62.86754)
		(end 267.401802 -72.403462)
		(width 0.10668)
		(layer "F.Cu")
		(net "SMB_LM75_3_3V3AUX_SCL")
	)
	(segment
		(start 105.930446 -16.98371)
		(end 105.803446 -16.85671)
		(width 0.10668)
		(layer "F.Cu")
		(net "SMB_LM75_3_3V3AUX_SCL")
	)
	(segment
		(start 257.86588 -61.884052)
		(end 257.86588 -62.86754)
		(width 0.10668)
		(layer "F.Cu")
		(net "SMB_LM75_3_3V3AUX_SCL")
	)
	(segment
		(start 267.401802 -72.403462)
		(end 267.401802 -76.571348)
		(width 0.10668)
		(layer "F.Cu")
		(net "SMB_LM75_3_3V3AUX_SCL")
	)
	(segment
		(start 285.598362 -109.72546)
		(end 275.393404 -109.72546)
		(width 0.10668)
		(layer "F.Cu")
		(net "SMB_LM75_3_3V3AUX_SCL")
	)
	(segment
		(start 271.493234 -115.236498)
		(end 271.485106 -115.22837)
		(width 0.10668)
		(layer "F.Cu")
		(net "SMB_LM75_3_3V3AUX_SCL")
	)
	(segment
		(start 267.401802 -76.571348)
		(end 281.13482 -90.304366)
		(width 0.10668)
		(layer "F.Cu")
		(net "SMB_LM75_3_3V3AUX_SCL")
	)
	(segment
		(start 288.459418 -90.304366)
		(end 292.611048 -94.455996)
		(width 0.10668)
		(layer "F.Cu")
		(net "SMB_LM75_3_3V3AUX_SCL")
	)
	(segment
		(start 292.611048 -94.455996)
		(end 292.611048 -102.712774)
		(width 0.10668)
		(layer "F.Cu")
		(net "SMB_LM75_3_3V3AUX_SCL")
	)
	(segment
		(start 292.611048 -102.712774)
		(end 285.598362 -109.72546)
		(width 0.10668)
		(layer "F.Cu")
		(net "SMB_LM75_3_3V3AUX_SCL")
	)
	(segment
		(start 281.13482 -90.304366)
		(end 288.459418 -90.304366)
		(width 0.10668)
		(layer "F.Cu")
		(net "SMB_LM75_3_3V3AUX_SCL")
	)
	(segment
		(start 271.493234 -116.321586)
		(end 271.493234 -115.236498)
		(width 0.10668)
		(layer "F.Cu")
		(net "SMB_LM75_3_3V3AUX_SCL")
	)
	(segment
		(start 273.88693 -111.231934)
		(end 273.88693 -113.92789)
		(width 0.10668)
		(layer "F.Cu")
		(net "SMB_LM75_3_3V3AUX_SCL")
	)
	(segment
		(start 275.393404 -109.72546)
		(end 273.88693 -111.231934)
		(width 0.10668)
		(layer "F.Cu")
		(net "SMB_LM75_3_3V3AUX_SCL")
	)
	(segment
		(start 106.492548 -16.98371)
		(end 105.930446 -16.98371)
		(width 0.10668)
		(layer "F.Cu")
		(net "SMB_LM75_3_3V3AUX_SCL")
	)
	(segment
		(start 273.88693 -113.92789)
		(end 271.493234 -116.321586)
		(width 0.10668)
		(layer "F.Cu")
		(net "SMB_LM75_3_3V3AUX_SCL")
	)
	(via
		(at 257.86588 -61.884052)
		(size 0.508)
		(drill 0.254)
		(layers "F.Cu" "B.Cu")
		(net "SMB_LM75_3_3V3AUX_SCL")
	)
	(via
		(at 105.803446 -16.85671)
		(size 0.508)
		(drill 0.254)
		(layers "F.Cu" "B.Cu")
		(net "SMB_LM75_3_3V3AUX_SCL")
	)
	(segment
		(start 173.20387 -32.828484)
		(end 175.348392 -34.973006)
		(width 0.11684)
		(layer "In6.Cu")
		(net "SMB_LM75_3_3V3AUX_SCL")
	)
	(segment
		(start 175.348392 -34.973006)
		(end 177.1523 -34.973006)
		(width 0.11684)
		(layer "In6.Cu")
		(net "SMB_LM75_3_3V3AUX_SCL")
	)
	(segment
		(start 232.612692 -58.64733)
		(end 235.97997 -58.64733)
		(width 0.11684)
		(layer "In6.Cu")
		(net "SMB_LM75_3_3V3AUX_SCL")
	)
	(segment
		(start 216.867994 -40.104568)
		(end 216.867994 -41.371012)
		(width 0.11684)
		(layer "In6.Cu")
		(net "SMB_LM75_3_3V3AUX_SCL")
	)
	(segment
		(start 235.97997 -58.64733)
		(end 238.646208 -61.313568)
		(width 0.11684)
		(layer "In6.Cu")
		(net "SMB_LM75_3_3V3AUX_SCL")
	)
	(segment
		(start 142.006574 -21.44522)
		(end 153.604214 -33.04286)
		(width 0.11684)
		(layer "In6.Cu")
		(net "SMB_LM75_3_3V3AUX_SCL")
	)
	(segment
		(start 180.935122 -35.856672)
		(end 182.176674 -37.098224)
		(width 0.11684)
		(layer "In6.Cu")
		(net "SMB_LM75_3_3V3AUX_SCL")
	)
	(segment
		(start 177.1523 -34.973006)
		(end 178.035966 -35.856672)
		(width 0.11684)
		(layer "In6.Cu")
		(net "SMB_LM75_3_3V3AUX_SCL")
	)
	(segment
		(start 112.48136 -20.10537)
		(end 113.18367 -19.40306)
		(width 0.11684)
		(layer "In6.Cu")
		(net "SMB_LM75_3_3V3AUX_SCL")
	)
	(segment
		(start 184.903872 -37.098224)
		(end 186.597036 -38.791388)
		(width 0.11684)
		(layer "In6.Cu")
		(net "SMB_LM75_3_3V3AUX_SCL")
	)
	(segment
		(start 160.55848 -32.828484)
		(end 173.20387 -32.828484)
		(width 0.11684)
		(layer "In6.Cu")
		(net "SMB_LM75_3_3V3AUX_SCL")
	)
	(segment
		(start 226.449636 -59.713622)
		(end 231.5464 -59.713622)
		(width 0.11684)
		(layer "In6.Cu")
		(net "SMB_LM75_3_3V3AUX_SCL")
	)
	(segment
		(start 178.035966 -35.856672)
		(end 180.935122 -35.856672)
		(width 0.11684)
		(layer "In6.Cu")
		(net "SMB_LM75_3_3V3AUX_SCL")
	)
	(segment
		(start 186.597036 -38.791388)
		(end 193.436494 -38.791388)
		(width 0.11684)
		(layer "In6.Cu")
		(net "SMB_LM75_3_3V3AUX_SCL")
	)
	(segment
		(start 110.30458 -20.10537)
		(end 112.48136 -20.10537)
		(width 0.11684)
		(layer "In6.Cu")
		(net "SMB_LM75_3_3V3AUX_SCL")
	)
	(segment
		(start 105.803446 -16.85671)
		(end 108.767118 -19.820382)
		(width 0.11684)
		(layer "In6.Cu")
		(net "SMB_LM75_3_3V3AUX_SCL")
	)
	(segment
		(start 182.176674 -37.098224)
		(end 184.903872 -37.098224)
		(width 0.11684)
		(layer "In6.Cu")
		(net "SMB_LM75_3_3V3AUX_SCL")
	)
	(segment
		(start 213.797896 -40.192198)
		(end 214.695786 -39.294308)
		(width 0.11684)
		(layer "In6.Cu")
		(net "SMB_LM75_3_3V3AUX_SCL")
	)
	(segment
		(start 113.18367 -19.40306)
		(end 136.388856 -19.40306)
		(width 0.11684)
		(layer "In6.Cu")
		(net "SMB_LM75_3_3V3AUX_SCL")
	)
	(segment
		(start 216.057734 -39.294308)
		(end 216.867994 -40.104568)
		(width 0.11684)
		(layer "In6.Cu")
		(net "SMB_LM75_3_3V3AUX_SCL")
	)
	(segment
		(start 136.388856 -19.40306)
		(end 138.431016 -21.44522)
		(width 0.11684)
		(layer "In6.Cu")
		(net "SMB_LM75_3_3V3AUX_SCL")
	)
	(segment
		(start 207.275684 -40.819832)
		(end 207.903318 -40.192198)
		(width 0.11684)
		(layer "In6.Cu")
		(net "SMB_LM75_3_3V3AUX_SCL")
	)
	(segment
		(start 193.436494 -38.791388)
		(end 195.464938 -40.819832)
		(width 0.11684)
		(layer "In6.Cu")
		(net "SMB_LM75_3_3V3AUX_SCL")
	)
	(segment
		(start 238.646208 -61.313568)
		(end 257.295396 -61.313568)
		(width 0.11684)
		(layer "In6.Cu")
		(net "SMB_LM75_3_3V3AUX_SCL")
	)
	(segment
		(start 108.767118 -19.820382)
		(end 110.019592 -19.820382)
		(width 0.11684)
		(layer "In6.Cu")
		(net "SMB_LM75_3_3V3AUX_SCL")
	)
	(segment
		(start 195.464938 -40.819832)
		(end 207.275684 -40.819832)
		(width 0.11684)
		(layer "In6.Cu")
		(net "SMB_LM75_3_3V3AUX_SCL")
	)
	(segment
		(start 214.695786 -39.294308)
		(end 216.057734 -39.294308)
		(width 0.11684)
		(layer "In6.Cu")
		(net "SMB_LM75_3_3V3AUX_SCL")
	)
	(segment
		(start 216.867994 -41.371012)
		(end 220.826584 -45.329602)
		(width 0.11684)
		(layer "In6.Cu")
		(net "SMB_LM75_3_3V3AUX_SCL")
	)
	(segment
		(start 110.019592 -19.820382)
		(end 110.30458 -20.10537)
		(width 0.11684)
		(layer "In6.Cu")
		(net "SMB_LM75_3_3V3AUX_SCL")
	)
	(segment
		(start 220.826584 -45.329602)
		(end 220.826584 -54.09057)
		(width 0.11684)
		(layer "In6.Cu")
		(net "SMB_LM75_3_3V3AUX_SCL")
	)
	(segment
		(start 160.344104 -33.04286)
		(end 160.55848 -32.828484)
		(width 0.11684)
		(layer "In6.Cu")
		(net "SMB_LM75_3_3V3AUX_SCL")
	)
	(segment
		(start 138.431016 -21.44522)
		(end 142.006574 -21.44522)
		(width 0.11684)
		(layer "In6.Cu")
		(net "SMB_LM75_3_3V3AUX_SCL")
	)
	(segment
		(start 220.826584 -54.09057)
		(end 226.449636 -59.713622)
		(width 0.11684)
		(layer "In6.Cu")
		(net "SMB_LM75_3_3V3AUX_SCL")
	)
	(segment
		(start 153.604214 -33.04286)
		(end 160.344104 -33.04286)
		(width 0.11684)
		(layer "In6.Cu")
		(net "SMB_LM75_3_3V3AUX_SCL")
	)
	(segment
		(start 207.903318 -40.192198)
		(end 213.797896 -40.192198)
		(width 0.11684)
		(layer "In6.Cu")
		(net "SMB_LM75_3_3V3AUX_SCL")
	)
	(segment
		(start 231.5464 -59.713622)
		(end 232.612692 -58.64733)
		(width 0.11684)
		(layer "In6.Cu")
		(net "SMB_LM75_3_3V3AUX_SCL")
	)
	(segment
		(start 257.295396 -61.313568)
		(end 257.86588 -61.884052)
		(width 0.11684)
		(layer "In6.Cu")
		(net "SMB_LM75_3_3V3AUX_SCL")
	)
	(segment
		(start 97.745296 -413.331152)
		(end 97.745296 -413.947102)
		(width 0.10668)
		(layer "F.Cu")
		(net "SMB_LM75_2_3V3AUX_SDA_R1")
	)
	(segment
		(start 97.745296 -415.075116)
		(end 97.745296 -413.947102)
		(width 0.10668)
		(layer "F.Cu")
		(net "SMB_LM75_2_3V3AUX_SDA_R1")
	)
	(via
		(at 97.745296 -413.947102)
		(size 0.508)
		(drill 0.254)
		(layers "F.Cu" "B.Cu")
		(net "SMB_LM75_2_3V3AUX_SDA_R1")
	)
	(segment
		(start 224.86239 -199.46747)
		(end 224.86239 -167.702992)
		(width 0.10668)
		(layer "F.Cu")
		(net "SMB_LM75_2_3V3AUX_SDA")
	)
	(segment
		(start 253.252732 -115.322858)
		(end 254.395478 -115.322858)
		(width 0.10668)
		(layer "F.Cu")
		(net "SMB_LM75_2_3V3AUX_SDA")
	)
	(segment
		(start 220.365574 -160.722564)
		(end 220.365574 -147.33778)
		(width 0.10668)
		(layer "F.Cu")
		(net "SMB_LM75_2_3V3AUX_SDA")
	)
	(segment
		(start 219.953332 -122.240294)
		(end 219.953332 -115.787678)
		(width 0.10668)
		(layer "F.Cu")
		(net "SMB_LM75_2_3V3AUX_SDA")
	)
	(segment
		(start 223.623378 -163.980368)
		(end 220.365574 -160.722564)
		(width 0.10668)
		(layer "F.Cu")
		(net "SMB_LM75_2_3V3AUX_SDA")
	)
	(segment
		(start 223.623378 -166.46398)
		(end 223.623378 -163.980368)
		(width 0.10668)
		(layer "F.Cu")
		(net "SMB_LM75_2_3V3AUX_SDA")
	)
	(segment
		(start 221.951296 -113.789714)
		(end 221.966536 -113.789714)
		(width 0.10668)
		(layer "F.Cu")
		(net "SMB_LM75_2_3V3AUX_SDA")
	)
	(segment
		(start 251.882656 -113.378488)
		(end 251.936758 -113.43259)
		(width 0.10668)
		(layer "F.Cu")
		(net "SMB_LM75_2_3V3AUX_SDA")
	)
	(segment
		(start 222.927418 -137.255758)
		(end 222.927418 -125.21438)
		(width 0.10668)
		(layer "F.Cu")
		(net "SMB_LM75_2_3V3AUX_SDA")
	)
	(segment
		(start 224.86239 -167.702992)
		(end 223.623378 -166.46398)
		(width 0.10668)
		(layer "F.Cu")
		(net "SMB_LM75_2_3V3AUX_SDA")
	)
	(segment
		(start 254.395478 -115.322858)
		(end 254.992886 -114.72545)
		(width 0.10668)
		(layer "F.Cu")
		(net "SMB_LM75_2_3V3AUX_SDA")
	)
	(segment
		(start 222.927418 -125.21438)
		(end 219.953332 -122.240294)
		(width 0.10668)
		(layer "F.Cu")
		(net "SMB_LM75_2_3V3AUX_SDA")
	)
	(segment
		(start 98.806 -411.861)
		(end 98.415348 -411.861)
		(width 0.10668)
		(layer "F.Cu")
		(net "SMB_LM75_2_3V3AUX_SDA")
	)
	(segment
		(start 255.704086 -114.72545)
		(end 254.992886 -114.72545)
		(width 0.10668)
		(layer "F.Cu")
		(net "SMB_LM75_2_3V3AUX_SDA")
	)
	(segment
		(start 222.403416 -137.77976)
		(end 222.927418 -137.255758)
		(width 0.10668)
		(layer "F.Cu")
		(net "SMB_LM75_2_3V3AUX_SDA")
	)
	(segment
		(start 220.365574 -147.33778)
		(end 222.403416 -145.299938)
		(width 0.10668)
		(layer "F.Cu")
		(net "SMB_LM75_2_3V3AUX_SDA")
	)
	(segment
		(start 219.953332 -115.787678)
		(end 221.951296 -113.789714)
		(width 0.10668)
		(layer "F.Cu")
		(net "SMB_LM75_2_3V3AUX_SDA")
	)
	(segment
		(start 251.936758 -113.43259)
		(end 251.936758 -114.006884)
		(width 0.10668)
		(layer "F.Cu")
		(net "SMB_LM75_2_3V3AUX_SDA")
	)
	(segment
		(start 222.403416 -145.299938)
		(end 222.403416 -137.77976)
		(width 0.10668)
		(layer "F.Cu")
		(net "SMB_LM75_2_3V3AUX_SDA")
	)
	(segment
		(start 251.936758 -114.006884)
		(end 253.252732 -115.322858)
		(width 0.10668)
		(layer "F.Cu")
		(net "SMB_LM75_2_3V3AUX_SDA")
	)
	(segment
		(start 98.415348 -411.861)
		(end 97.745296 -412.531052)
		(width 0.10668)
		(layer "F.Cu")
		(net "SMB_LM75_2_3V3AUX_SDA")
	)
	(segment
		(start 224.479104 -199.850756)
		(end 224.86239 -199.46747)
		(width 0.10668)
		(layer "F.Cu")
		(net "SMB_LM75_2_3V3AUX_SDA")
	)
	(segment
		(start 256.842006 -115.86337)
		(end 255.704086 -114.72545)
		(width 0.10668)
		(layer "F.Cu")
		(net "SMB_LM75_2_3V3AUX_SDA")
	)
	(via
		(at 104.356154 -395.588236)
		(size 0.508)
		(drill 0.254)
		(layers "F.Cu" "B.Cu")
		(net "SMB_LM75_2_3V3AUX_SDA")
	)
	(via
		(at 98.806 -411.861)
		(size 0.508)
		(drill 0.254)
		(layers "F.Cu" "B.Cu")
		(net "SMB_LM75_2_3V3AUX_SDA")
	)
	(via
		(at 172.570902 -393.406122)
		(size 0.508)
		(drill 0.254)
		(layers "F.Cu" "B.Cu")
		(net "SMB_LM75_2_3V3AUX_SDA")
	)
	(via
		(at 251.882656 -113.378488)
		(size 0.508)
		(drill 0.254)
		(layers "F.Cu" "B.Cu")
		(net "SMB_LM75_2_3V3AUX_SDA")
	)
	(via
		(at 221.966536 -113.789714)
		(size 0.508)
		(drill 0.254)
		(layers "F.Cu" "B.Cu")
		(net "SMB_LM75_2_3V3AUX_SDA")
	)
	(via
		(at 224.479104 -199.850756)
		(size 0.508)
		(drill 0.254)
		(layers "F.Cu" "B.Cu")
		(net "SMB_LM75_2_3V3AUX_SDA")
	)
	(segment
		(start 251.3076 -112.803432)
		(end 251.882656 -113.378488)
		(width 0.11684)
		(layer "In2.Cu")
		(net "SMB_LM75_2_3V3AUX_SDA")
	)
	(segment
		(start 110.399068 -394.633196)
		(end 111.00435 -395.238478)
		(width 0.11684)
		(layer "In2.Cu")
		(net "SMB_LM75_2_3V3AUX_SDA")
	)
	(segment
		(start 104.98074 -394.633196)
		(end 110.399068 -394.633196)
		(width 0.11684)
		(layer "In2.Cu")
		(net "SMB_LM75_2_3V3AUX_SDA")
	)
	(segment
		(start 104.356154 -395.588236)
		(end 104.356154 -395.257782)
		(width 0.11684)
		(layer "In2.Cu")
		(net "SMB_LM75_2_3V3AUX_SDA")
	)
	(segment
		(start 169.709338 -395.51991)
		(end 171.823126 -393.406122)
		(width 0.11684)
		(layer "In2.Cu")
		(net "SMB_LM75_2_3V3AUX_SDA")
	)
	(segment
		(start 166.438072 -395.51991)
		(end 169.709338 -395.51991)
		(width 0.11684)
		(layer "In2.Cu")
		(net "SMB_LM75_2_3V3AUX_SDA")
	)
	(segment
		(start 134.717282 -395.660118)
		(end 166.297864 -395.660118)
		(width 0.11684)
		(layer "In2.Cu")
		(net "SMB_LM75_2_3V3AUX_SDA")
	)
	(segment
		(start 222.952818 -112.803432)
		(end 251.3076 -112.803432)
		(width 0.11684)
		(layer "In2.Cu")
		(net "SMB_LM75_2_3V3AUX_SDA")
	)
	(segment
		(start 171.823126 -393.406122)
		(end 172.570902 -393.406122)
		(width 0.11684)
		(layer "In2.Cu")
		(net "SMB_LM75_2_3V3AUX_SDA")
	)
	(segment
		(start 166.297864 -395.660118)
		(end 166.438072 -395.51991)
		(width 0.11684)
		(layer "In2.Cu")
		(net "SMB_LM75_2_3V3AUX_SDA")
	)
	(segment
		(start 111.00435 -395.238478)
		(end 134.295642 -395.238478)
		(width 0.11684)
		(layer "In2.Cu")
		(net "SMB_LM75_2_3V3AUX_SDA")
	)
	(segment
		(start 104.356154 -395.257782)
		(end 104.98074 -394.633196)
		(width 0.11684)
		(layer "In2.Cu")
		(net "SMB_LM75_2_3V3AUX_SDA")
	)
	(segment
		(start 134.295642 -395.238478)
		(end 134.717282 -395.660118)
		(width 0.11684)
		(layer "In2.Cu")
		(net "SMB_LM75_2_3V3AUX_SDA")
	)
	(segment
		(start 221.966536 -113.789714)
		(end 222.952818 -112.803432)
		(width 0.11684)
		(layer "In2.Cu")
		(net "SMB_LM75_2_3V3AUX_SDA")
	)
	(segment
		(start 99.639374 -411.027626)
		(end 99.639374 -407.671778)
		(width 0.11684)
		(layer "In11.Cu")
		(net "SMB_LM75_2_3V3AUX_SDA")
	)
	(segment
		(start 99.639374 -407.671778)
		(end 100.593652 -405.367998)
		(width 0.11684)
		(layer "In11.Cu")
		(net "SMB_LM75_2_3V3AUX_SDA")
	)
	(segment
		(start 98.806 -411.861)
		(end 99.639374 -411.027626)
		(width 0.11684)
		(layer "In11.Cu")
		(net "SMB_LM75_2_3V3AUX_SDA")
	)
	(segment
		(start 102.950772 -396.993618)
		(end 104.356154 -395.588236)
		(width 0.11684)
		(layer "In11.Cu")
		(net "SMB_LM75_2_3V3AUX_SDA")
	)
	(segment
		(start 102.950772 -403.010878)
		(end 102.950772 -396.993618)
		(width 0.11684)
		(layer "In11.Cu")
		(net "SMB_LM75_2_3V3AUX_SDA")
	)
	(segment
		(start 100.593652 -405.367998)
		(end 102.950772 -403.010878)
		(width 0.11684)
		(layer "In11.Cu")
		(net "SMB_LM75_2_3V3AUX_SDA")
	)
	(segment
		(start 212.152484 -344.83548)
		(end 213.022942 -343.965022)
		(width 0.11684)
		(layer "In15.Cu")
		(net "SMB_LM75_2_3V3AUX_SDA")
	)
	(segment
		(start 211.940902 -202.37831)
		(end 216.3699 -197.949312)
		(width 0.11684)
		(layer "In15.Cu")
		(net "SMB_LM75_2_3V3AUX_SDA")
	)
	(segment
		(start 214.995252 -343.965022)
		(end 218.091766 -340.868508)
		(width 0.11684)
		(layer "In15.Cu")
		(net "SMB_LM75_2_3V3AUX_SDA")
	)
	(segment
		(start 211.940902 -321.897502)
		(end 211.940902 -202.37831)
		(width 0.11684)
		(layer "In15.Cu")
		(net "SMB_LM75_2_3V3AUX_SDA")
	)
	(segment
		(start 185.369708 -380.03988)
		(end 185.369708 -369.475512)
		(width 0.11684)
		(layer "In15.Cu")
		(net "SMB_LM75_2_3V3AUX_SDA")
	)
	(segment
		(start 218.091766 -328.048366)
		(end 211.940902 -321.897502)
		(width 0.11684)
		(layer "In15.Cu")
		(net "SMB_LM75_2_3V3AUX_SDA")
	)
	(segment
		(start 172.570902 -393.406122)
		(end 172.570902 -392.838686)
		(width 0.11684)
		(layer "In15.Cu")
		(net "SMB_LM75_2_3V3AUX_SDA")
	)
	(segment
		(start 216.3699 -197.949312)
		(end 220.822266 -197.949312)
		(width 0.11684)
		(layer "In15.Cu")
		(net "SMB_LM75_2_3V3AUX_SDA")
	)
	(segment
		(start 193.633852 -366.481614)
		(end 212.152484 -347.962982)
		(width 0.11684)
		(layer "In15.Cu")
		(net "SMB_LM75_2_3V3AUX_SDA")
	)
	(segment
		(start 185.369708 -369.475512)
		(end 188.363606 -366.481614)
		(width 0.11684)
		(layer "In15.Cu")
		(net "SMB_LM75_2_3V3AUX_SDA")
	)
	(segment
		(start 218.091766 -340.868508)
		(end 218.091766 -328.048366)
		(width 0.11684)
		(layer "In15.Cu")
		(net "SMB_LM75_2_3V3AUX_SDA")
	)
	(segment
		(start 220.822266 -197.949312)
		(end 223.818704 -199.190356)
		(width 0.11684)
		(layer "In15.Cu")
		(net "SMB_LM75_2_3V3AUX_SDA")
	)
	(segment
		(start 213.022942 -343.965022)
		(end 214.995252 -343.965022)
		(width 0.11684)
		(layer "In15.Cu")
		(net "SMB_LM75_2_3V3AUX_SDA")
	)
	(segment
		(start 188.363606 -366.481614)
		(end 193.633852 -366.481614)
		(width 0.11684)
		(layer "In15.Cu")
		(net "SMB_LM75_2_3V3AUX_SDA")
	)
	(segment
		(start 223.818704 -199.190356)
		(end 224.479104 -199.850756)
		(width 0.11684)
		(layer "In15.Cu")
		(net "SMB_LM75_2_3V3AUX_SDA")
	)
	(segment
		(start 212.152484 -347.962982)
		(end 212.152484 -344.83548)
		(width 0.11684)
		(layer "In15.Cu")
		(net "SMB_LM75_2_3V3AUX_SDA")
	)
	(segment
		(start 172.570902 -392.838686)
		(end 185.369708 -380.03988)
		(width 0.11684)
		(layer "In15.Cu")
		(net "SMB_LM75_2_3V3AUX_SDA")
	)
	(segment
		(start 99.015296 -415.075116)
		(end 99.015296 -413.947102)
		(width 0.10668)
		(layer "F.Cu")
		(net "SMB_LM75_2_3V3AUX_SCL_R1")
	)
	(segment
		(start 99.015296 -413.331152)
		(end 99.015296 -413.947102)
		(width 0.10668)
		(layer "F.Cu")
		(net "SMB_LM75_2_3V3AUX_SCL_R1")
	)
	(via
		(at 99.015296 -413.947102)
		(size 0.508)
		(drill 0.254)
		(layers "F.Cu" "B.Cu")
		(net "SMB_LM75_2_3V3AUX_SCL_R1")
	)
	(segment
		(start 224.004378 -166.363396)
		(end 224.004378 -163.87953)
		(width 0.10668)
		(layer "F.Cu")
		(net "SMB_LM75_2_3V3AUX_SCL")
	)
	(segment
		(start 253.394718 -112.64265)
		(end 254.307086 -112.64265)
		(width 0.10668)
		(layer "F.Cu")
		(net "SMB_LM75_2_3V3AUX_SCL")
	)
	(segment
		(start 220.705934 -160.581086)
		(end 220.705934 -147.479004)
		(width 0.10668)
		(layer "F.Cu")
		(net "SMB_LM75_2_3V3AUX_SCL")
	)
	(segment
		(start 222.743776 -137.920984)
		(end 223.267778 -137.396982)
		(width 0.10668)
		(layer "F.Cu")
		(net "SMB_LM75_2_3V3AUX_SCL")
	)
	(segment
		(start 222.743776 -145.441162)
		(end 222.743776 -137.920984)
		(width 0.10668)
		(layer "F.Cu")
		(net "SMB_LM75_2_3V3AUX_SCL")
	)
	(segment
		(start 224.004378 -163.87953)
		(end 220.705934 -160.581086)
		(width 0.10668)
		(layer "F.Cu")
		(net "SMB_LM75_2_3V3AUX_SCL")
	)
	(segment
		(start 220.705934 -147.479004)
		(end 222.743776 -145.441162)
		(width 0.10668)
		(layer "F.Cu")
		(net "SMB_LM75_2_3V3AUX_SCL")
	)
	(segment
		(start 223.267778 -137.396982)
		(end 223.267778 -125.073156)
		(width 0.10668)
		(layer "F.Cu")
		(net "SMB_LM75_2_3V3AUX_SCL")
	)
	(segment
		(start 224.442782 -200.745344)
		(end 225.20275 -199.985376)
		(width 0.10668)
		(layer "F.Cu")
		(net "SMB_LM75_2_3V3AUX_SCL")
	)
	(segment
		(start 100.076 -411.861)
		(end 99.685348 -411.861)
		(width 0.10668)
		(layer "F.Cu")
		(net "SMB_LM75_2_3V3AUX_SCL")
	)
	(segment
		(start 99.685348 -411.861)
		(end 99.015296 -412.531052)
		(width 0.10668)
		(layer "F.Cu")
		(net "SMB_LM75_2_3V3AUX_SCL")
	)
	(segment
		(start 254.307086 -112.64265)
		(end 254.992886 -113.32845)
		(width 0.10668)
		(layer "F.Cu")
		(net "SMB_LM75_2_3V3AUX_SCL")
	)
	(segment
		(start 225.20275 -167.561768)
		(end 224.004378 -166.363396)
		(width 0.10668)
		(layer "F.Cu")
		(net "SMB_LM75_2_3V3AUX_SCL")
	)
	(segment
		(start 225.20275 -199.985376)
		(end 225.20275 -167.561768)
		(width 0.10668)
		(layer "F.Cu")
		(net "SMB_LM75_2_3V3AUX_SCL")
	)
	(segment
		(start 256.842006 -114.84737)
		(end 255.323086 -113.32845)
		(width 0.10668)
		(layer "F.Cu")
		(net "SMB_LM75_2_3V3AUX_SCL")
	)
	(segment
		(start 223.267778 -125.073156)
		(end 220.293692 -122.09907)
		(width 0.10668)
		(layer "F.Cu")
		(net "SMB_LM75_2_3V3AUX_SCL")
	)
	(segment
		(start 220.293692 -116.066824)
		(end 221.935802 -114.424714)
		(width 0.10668)
		(layer "F.Cu")
		(net "SMB_LM75_2_3V3AUX_SCL")
	)
	(segment
		(start 252.7046 -113.332768)
		(end 253.394718 -112.64265)
		(width 0.10668)
		(layer "F.Cu")
		(net "SMB_LM75_2_3V3AUX_SCL")
	)
	(segment
		(start 220.293692 -122.09907)
		(end 220.293692 -116.066824)
		(width 0.10668)
		(layer "F.Cu")
		(net "SMB_LM75_2_3V3AUX_SCL")
	)
	(segment
		(start 255.323086 -113.32845)
		(end 254.992886 -113.32845)
		(width 0.10668)
		(layer "F.Cu")
		(net "SMB_LM75_2_3V3AUX_SCL")
	)
	(segment
		(start 221.935802 -114.424714)
		(end 221.966536 -114.424714)
		(width 0.10668)
		(layer "F.Cu")
		(net "SMB_LM75_2_3V3AUX_SCL")
	)
	(via
		(at 100.076 -411.861)
		(size 0.508)
		(drill 0.254)
		(layers "F.Cu" "B.Cu")
		(net "SMB_LM75_2_3V3AUX_SCL")
	)
	(via
		(at 172.682916 -394.078968)
		(size 0.508)
		(drill 0.254)
		(layers "F.Cu" "B.Cu")
		(net "SMB_LM75_2_3V3AUX_SCL")
	)
	(via
		(at 221.966536 -114.424714)
		(size 0.508)
		(drill 0.254)
		(layers "F.Cu" "B.Cu")
		(net "SMB_LM75_2_3V3AUX_SCL")
	)
	(via
		(at 106.961432 -396.29969)
		(size 0.508)
		(drill 0.254)
		(layers "F.Cu" "B.Cu")
		(net "SMB_LM75_2_3V3AUX_SCL")
	)
	(via
		(at 224.442782 -200.745344)
		(size 0.508)
		(drill 0.254)
		(layers "F.Cu" "B.Cu")
		(net "SMB_LM75_2_3V3AUX_SCL")
	)
	(via
		(at 252.7046 -113.332768)
		(size 0.508)
		(drill 0.254)
		(layers "F.Cu" "B.Cu")
		(net "SMB_LM75_2_3V3AUX_SCL")
	)
	(segment
		(start 172.682916 -394.078968)
		(end 171.7675 -394.078968)
		(width 0.11684)
		(layer "In2.Cu")
		(net "SMB_LM75_2_3V3AUX_SCL")
	)
	(segment
		(start 133.685026 -396.081758)
		(end 133.263386 -395.660118)
		(width 0.11684)
		(layer "In2.Cu")
		(net "SMB_LM75_2_3V3AUX_SCL")
	)
	(segment
		(start 169.88409 -395.962378)
		(end 166.618158 -395.962378)
		(width 0.11684)
		(layer "In2.Cu")
		(net "SMB_LM75_2_3V3AUX_SCL")
	)
	(segment
		(start 252.7046 -113.332768)
		(end 252.188472 -113.848896)
		(width 0.11684)
		(layer "In2.Cu")
		(net "SMB_LM75_2_3V3AUX_SCL")
	)
	(segment
		(start 107.752134 -395.660118)
		(end 107.112562 -396.29969)
		(width 0.11684)
		(layer "In2.Cu")
		(net "SMB_LM75_2_3V3AUX_SCL")
	)
	(segment
		(start 171.7675 -394.078968)
		(end 169.88409 -395.962378)
		(width 0.11684)
		(layer "In2.Cu")
		(net "SMB_LM75_2_3V3AUX_SCL")
	)
	(segment
		(start 222.260922 -114.424714)
		(end 221.966536 -114.424714)
		(width 0.11684)
		(layer "In2.Cu")
		(net "SMB_LM75_2_3V3AUX_SCL")
	)
	(segment
		(start 133.263386 -395.660118)
		(end 107.752134 -395.660118)
		(width 0.11684)
		(layer "In2.Cu")
		(net "SMB_LM75_2_3V3AUX_SCL")
	)
	(segment
		(start 250.406408 -113.254282)
		(end 223.431354 -113.254282)
		(width 0.11684)
		(layer "In2.Cu")
		(net "SMB_LM75_2_3V3AUX_SCL")
	)
	(segment
		(start 166.498778 -396.081758)
		(end 133.685026 -396.081758)
		(width 0.11684)
		(layer "In2.Cu")
		(net "SMB_LM75_2_3V3AUX_SCL")
	)
	(segment
		(start 107.112562 -396.29969)
		(end 106.961432 -396.29969)
		(width 0.11684)
		(layer "In2.Cu")
		(net "SMB_LM75_2_3V3AUX_SCL")
	)
	(segment
		(start 223.431354 -113.254282)
		(end 222.260922 -114.424714)
		(width 0.11684)
		(layer "In2.Cu")
		(net "SMB_LM75_2_3V3AUX_SCL")
	)
	(segment
		(start 166.618158 -395.962378)
		(end 166.498778 -396.081758)
		(width 0.11684)
		(layer "In2.Cu")
		(net "SMB_LM75_2_3V3AUX_SCL")
	)
	(segment
		(start 252.188472 -113.848896)
		(end 251.001022 -113.848896)
		(width 0.11684)
		(layer "In2.Cu")
		(net "SMB_LM75_2_3V3AUX_SCL")
	)
	(segment
		(start 251.001022 -113.848896)
		(end 250.406408 -113.254282)
		(width 0.11684)
		(layer "In2.Cu")
		(net "SMB_LM75_2_3V3AUX_SCL")
	)
	(segment
		(start 104.930956 -398.094962)
		(end 104.930956 -401.648422)
		(width 0.11684)
		(layer "In11.Cu")
		(net "SMB_LM75_2_3V3AUX_SCL")
	)
	(segment
		(start 106.726228 -396.29969)
		(end 104.930956 -398.094962)
		(width 0.11684)
		(layer "In11.Cu")
		(net "SMB_LM75_2_3V3AUX_SCL")
	)
	(segment
		(start 106.961432 -396.29969)
		(end 106.726228 -396.29969)
		(width 0.11684)
		(layer "In11.Cu")
		(net "SMB_LM75_2_3V3AUX_SCL")
	)
	(segment
		(start 100.076 -407.726642)
		(end 100.076 -411.861)
		(width 0.11684)
		(layer "In11.Cu")
		(net "SMB_LM75_2_3V3AUX_SCL")
	)
	(segment
		(start 104.930956 -401.648422)
		(end 100.94087 -405.638508)
		(width 0.11684)
		(layer "In11.Cu")
		(net "SMB_LM75_2_3V3AUX_SCL")
	)
	(segment
		(start 100.94087 -405.638508)
		(end 100.076 -407.726642)
		(width 0.11684)
		(layer "In11.Cu")
		(net "SMB_LM75_2_3V3AUX_SCL")
	)
	(segment
		(start 223.106742 -199.409304)
		(end 224.442782 -200.745344)
		(width 0.11684)
		(layer "In15.Cu")
		(net "SMB_LM75_2_3V3AUX_SCL")
	)
	(segment
		(start 212.362542 -202.553062)
		(end 216.532968 -198.382636)
		(width 0.11684)
		(layer "In15.Cu")
		(net "SMB_LM75_2_3V3AUX_SCL")
	)
	(segment
		(start 220.627956 -198.382636)
		(end 223.106742 -199.409304)
		(width 0.11684)
		(layer "In15.Cu")
		(net "SMB_LM75_2_3V3AUX_SCL")
	)
	(segment
		(start 172.682916 -394.078968)
		(end 173.056804 -393.70508)
		(width 0.11684)
		(layer "In15.Cu")
		(net "SMB_LM75_2_3V3AUX_SCL")
	)
	(segment
		(start 212.362542 -321.72275)
		(end 212.362542 -202.553062)
		(width 0.11684)
		(layer "In15.Cu")
		(net "SMB_LM75_2_3V3AUX_SCL")
	)
	(segment
		(start 218.587574 -327.947782)
		(end 212.362542 -321.72275)
		(width 0.11684)
		(layer "In15.Cu")
		(net "SMB_LM75_2_3V3AUX_SCL")
	)
	(segment
		(start 216.532968 -198.382636)
		(end 220.627956 -198.382636)
		(width 0.11684)
		(layer "In15.Cu")
		(net "SMB_LM75_2_3V3AUX_SCL")
	)
	(segment
		(start 173.056804 -392.949176)
		(end 185.799222 -380.206758)
		(width 0.11684)
		(layer "In15.Cu")
		(net "SMB_LM75_2_3V3AUX_SCL")
	)
	(segment
		(start 218.587574 -342.21166)
		(end 218.587574 -327.947782)
		(width 0.11684)
		(layer "In15.Cu")
		(net "SMB_LM75_2_3V3AUX_SCL")
	)
	(segment
		(start 212.626448 -348.172786)
		(end 212.626448 -345.219274)
		(width 0.11684)
		(layer "In15.Cu")
		(net "SMB_LM75_2_3V3AUX_SCL")
	)
	(segment
		(start 173.056804 -393.70508)
		(end 173.056804 -392.949176)
		(width 0.11684)
		(layer "In15.Cu")
		(net "SMB_LM75_2_3V3AUX_SCL")
	)
	(segment
		(start 212.626448 -345.219274)
		(end 213.4108 -344.434922)
		(width 0.11684)
		(layer "In15.Cu")
		(net "SMB_LM75_2_3V3AUX_SCL")
	)
	(segment
		(start 188.433456 -367.155222)
		(end 193.644012 -367.155222)
		(width 0.11684)
		(layer "In15.Cu")
		(net "SMB_LM75_2_3V3AUX_SCL")
	)
	(segment
		(start 185.799222 -369.789456)
		(end 188.433456 -367.155222)
		(width 0.11684)
		(layer "In15.Cu")
		(net "SMB_LM75_2_3V3AUX_SCL")
	)
	(segment
		(start 185.799222 -380.206758)
		(end 185.799222 -369.789456)
		(width 0.11684)
		(layer "In15.Cu")
		(net "SMB_LM75_2_3V3AUX_SCL")
	)
	(segment
		(start 216.364312 -344.434922)
		(end 218.587574 -342.21166)
		(width 0.11684)
		(layer "In15.Cu")
		(net "SMB_LM75_2_3V3AUX_SCL")
	)
	(segment
		(start 213.4108 -344.434922)
		(end 216.364312 -344.434922)
		(width 0.11684)
		(layer "In15.Cu")
		(net "SMB_LM75_2_3V3AUX_SCL")
	)
	(segment
		(start 193.644012 -367.155222)
		(end 212.626448 -348.172786)
		(width 0.11684)
		(layer "In15.Cu")
		(net "SMB_LM75_2_3V3AUX_SCL")
	)
	(segment
		(start 292.199822 -18.878296)
		(end 292.526466 -18.551652)
		(width 0.10668)
		(layer "F.Cu")
		(net "SMB_LM75_1_3V3AUX_SDA_R1")
	)
	(segment
		(start 291.715444 -17.319244)
		(end 292.526466 -18.130266)
		(width 0.10668)
		(layer "F.Cu")
		(net "SMB_LM75_1_3V3AUX_SDA_R1")
	)
	(segment
		(start 292.526466 -18.130266)
		(end 292.526466 -18.353532)
		(width 0.10668)
		(layer "F.Cu")
		(net "SMB_LM75_1_3V3AUX_SDA_R1")
	)
	(segment
		(start 292.526466 -18.551652)
		(end 292.526466 -18.353532)
		(width 0.10668)
		(layer "F.Cu")
		(net "SMB_LM75_1_3V3AUX_SDA_R1")
	)
	(segment
		(start 292.199822 -18.983452)
		(end 292.199822 -18.878296)
		(width 0.10668)
		(layer "F.Cu")
		(net "SMB_LM75_1_3V3AUX_SDA_R1")
	)
	(via
		(at 292.526466 -18.353532)
		(size 0.508)
		(drill 0.254)
		(layers "F.Cu" "B.Cu")
		(net "SMB_LM75_1_3V3AUX_SDA_R1")
	)
	(segment
		(start 256.842006 -117.89537)
		(end 256.466086 -117.51945)
		(width 0.10668)
		(layer "F.Cu")
		(net "SMB_LM75_1_3V3AUX_SDA")
	)
	(segment
		(start 291.399722 -18.983452)
		(end 290.231322 -18.983452)
		(width 0.10668)
		(layer "F.Cu")
		(net "SMB_LM75_1_3V3AUX_SDA")
	)
	(segment
		(start 254.992886 -117.51945)
		(end 254.992886 -116.881148)
		(width 0.10668)
		(layer "F.Cu")
		(net "SMB_LM75_1_3V3AUX_SDA")
	)
	(segment
		(start 256.466086 -117.51945)
		(end 254.992886 -117.51945)
		(width 0.10668)
		(layer "F.Cu")
		(net "SMB_LM75_1_3V3AUX_SDA")
	)
	(via
		(at 290.231322 -18.983452)
		(size 0.508)
		(drill 0.254)
		(layers "F.Cu" "B.Cu")
		(net "SMB_LM75_1_3V3AUX_SDA")
	)
	(via
		(at 254.992886 -116.881148)
		(size 0.508)
		(drill 0.254)
		(layers "F.Cu" "B.Cu")
		(net "SMB_LM75_1_3V3AUX_SDA")
	)
	(segment
		(start 255.854708 -116.881148)
		(end 265.2141 -107.521756)
		(width 0.11684)
		(layer "In11.Cu")
		(net "SMB_LM75_1_3V3AUX_SDA")
	)
	(segment
		(start 283.699712 -16.64843)
		(end 287.065212 -16.64843)
		(width 0.11684)
		(layer "In11.Cu")
		(net "SMB_LM75_1_3V3AUX_SDA")
	)
	(segment
		(start 265.2141 -107.521756)
		(end 265.2141 -71.763382)
		(width 0.11684)
		(layer "In11.Cu")
		(net "SMB_LM75_1_3V3AUX_SDA")
	)
	(segment
		(start 278.511762 -58.46572)
		(end 278.511762 -21.83638)
		(width 0.11684)
		(layer "In11.Cu")
		(net "SMB_LM75_1_3V3AUX_SDA")
	)
	(segment
		(start 288.71545 -18.298668)
		(end 289.546538 -18.298668)
		(width 0.11684)
		(layer "In11.Cu")
		(net "SMB_LM75_1_3V3AUX_SDA")
	)
	(segment
		(start 287.065212 -16.64843)
		(end 288.71545 -18.298668)
		(width 0.11684)
		(layer "In11.Cu")
		(net "SMB_LM75_1_3V3AUX_SDA")
	)
	(segment
		(start 254.992886 -116.881148)
		(end 255.854708 -116.881148)
		(width 0.11684)
		(layer "In11.Cu")
		(net "SMB_LM75_1_3V3AUX_SDA")
	)
	(segment
		(start 289.546538 -18.298668)
		(end 290.231322 -18.983452)
		(width 0.11684)
		(layer "In11.Cu")
		(net "SMB_LM75_1_3V3AUX_SDA")
	)
	(segment
		(start 265.2141 -71.763382)
		(end 278.511762 -58.46572)
		(width 0.11684)
		(layer "In11.Cu")
		(net "SMB_LM75_1_3V3AUX_SDA")
	)
	(segment
		(start 278.511762 -21.83638)
		(end 283.699712 -16.64843)
		(width 0.11684)
		(layer "In11.Cu")
		(net "SMB_LM75_1_3V3AUX_SDA")
	)
	(segment
		(start 290.104576 -16.049244)
		(end 289.351974 -16.049244)
		(width 0.10668)
		(layer "F.Cu")
		(net "SMB_LM75_1_3V3AUX_SCL_R1")
	)
	(segment
		(start 288.598102 -15.295372)
		(end 288.598102 -14.807438)
		(width 0.10668)
		(layer "F.Cu")
		(net "SMB_LM75_1_3V3AUX_SCL_R1")
	)
	(segment
		(start 289.351974 -16.049244)
		(end 288.598102 -15.295372)
		(width 0.10668)
		(layer "F.Cu")
		(net "SMB_LM75_1_3V3AUX_SCL_R1")
	)
	(segment
		(start 288.574988 -14.784324)
		(end 288.574988 -14.377162)
		(width 0.10668)
		(layer "F.Cu")
		(net "SMB_LM75_1_3V3AUX_SCL_R1")
	)
	(segment
		(start 288.598102 -14.807438)
		(end 288.574988 -14.784324)
		(width 0.10668)
		(layer "F.Cu")
		(net "SMB_LM75_1_3V3AUX_SCL_R1")
	)
	(segment
		(start 288.574988 -14.377162)
		(end 288.598102 -14.354048)
		(width 0.10668)
		(layer "F.Cu")
		(net "SMB_LM75_1_3V3AUX_SCL_R1")
	)
	(segment
		(start 291.715444 -16.049244)
		(end 290.104576 -16.049244)
		(width 0.10668)
		(layer "F.Cu")
		(net "SMB_LM75_1_3V3AUX_SCL_R1")
	)
	(via
		(at 290.104576 -16.049244)
		(size 0.508)
		(drill 0.254)
		(layers "F.Cu" "B.Cu")
		(net "SMB_LM75_1_3V3AUX_SCL_R1")
	)
	(segment
		(start 255.749806 -116.87937)
		(end 254.992886 -116.12245)
		(width 0.10668)
		(layer "F.Cu")
		(net "SMB_LM75_1_3V3AUX_SCL")
	)
	(segment
		(start 287.798002 -14.354048)
		(end 287.32353 -14.354048)
		(width 0.10668)
		(layer "F.Cu")
		(net "SMB_LM75_1_3V3AUX_SCL")
	)
	(segment
		(start 287.32353 -14.354048)
		(end 286.233108 -15.44447)
		(width 0.10668)
		(layer "F.Cu")
		(net "SMB_LM75_1_3V3AUX_SCL")
	)
	(segment
		(start 256.842006 -116.87937)
		(end 255.749806 -116.87937)
		(width 0.10668)
		(layer "F.Cu")
		(net "SMB_LM75_1_3V3AUX_SCL")
	)
	(segment
		(start 254.992886 -115.484148)
		(end 254.992886 -116.12245)
		(width 0.10668)
		(layer "F.Cu")
		(net "SMB_LM75_1_3V3AUX_SCL")
	)
	(via
		(at 254.992886 -115.484148)
		(size 0.508)
		(drill 0.254)
		(layers "F.Cu" "B.Cu")
		(net "SMB_LM75_1_3V3AUX_SCL")
	)
	(via
		(at 286.233108 -15.44447)
		(size 0.508)
		(drill 0.254)
		(layers "F.Cu" "B.Cu")
		(net "SMB_LM75_1_3V3AUX_SCL")
	)
	(segment
		(start 263.36879 -107.108244)
		(end 263.36879 -98.771964)
		(width 0.11684)
		(layer "In11.Cu")
		(net "SMB_LM75_1_3V3AUX_SCL")
	)
	(segment
		(start 286.167068 -15.37843)
		(end 286.233108 -15.44447)
		(width 0.11684)
		(layer "In11.Cu")
		(net "SMB_LM75_1_3V3AUX_SCL")
	)
	(segment
		(start 263.36879 -98.771964)
		(end 264.79246 -97.348294)
		(width 0.11684)
		(layer "In11.Cu")
		(net "SMB_LM75_1_3V3AUX_SCL")
	)
	(segment
		(start 264.79246 -71.58863)
		(end 278.090122 -58.290968)
		(width 0.11684)
		(layer "In11.Cu")
		(net "SMB_LM75_1_3V3AUX_SCL")
	)
	(segment
		(start 278.090122 -58.290968)
		(end 278.090122 -20.98802)
		(width 0.11684)
		(layer "In11.Cu")
		(net "SMB_LM75_1_3V3AUX_SCL")
	)
	(segment
		(start 283.699712 -15.37843)
		(end 286.167068 -15.37843)
		(width 0.11684)
		(layer "In11.Cu")
		(net "SMB_LM75_1_3V3AUX_SCL")
	)
	(segment
		(start 278.090122 -20.98802)
		(end 283.699712 -15.37843)
		(width 0.11684)
		(layer "In11.Cu")
		(net "SMB_LM75_1_3V3AUX_SCL")
	)
	(segment
		(start 264.79246 -97.348294)
		(end 264.79246 -71.58863)
		(width 0.11684)
		(layer "In11.Cu")
		(net "SMB_LM75_1_3V3AUX_SCL")
	)
	(segment
		(start 254.992886 -115.484148)
		(end 263.36879 -107.108244)
		(width 0.11684)
		(layer "In11.Cu")
		(net "SMB_LM75_1_3V3AUX_SCL")
	)
	(segment
		(start 365.887 -414.03905)
		(end 365.887 -414.655)
		(width 0.10668)
		(layer "F.Cu")
		(net "SMB_LM75_0_3V3AUX_SDA_R1")
	)
	(segment
		(start 365.887 -414.655)
		(end 365.633 -414.909)
		(width 0.10668)
		(layer "F.Cu")
		(net "SMB_LM75_0_3V3AUX_SDA_R1")
	)
	(segment
		(start 365.907066 -415.183066)
		(end 365.633 -414.909)
		(width 0.10668)
		(layer "F.Cu")
		(net "SMB_LM75_0_3V3AUX_SDA_R1")
	)
	(segment
		(start 365.907066 -416.645598)
		(end 365.907066 -415.183066)
		(width 0.10668)
		(layer "F.Cu")
		(net "SMB_LM75_0_3V3AUX_SDA_R1")
	)
	(via
		(at 365.633 -414.909)
		(size 0.762)
		(drill 0.381)
		(layers "F.Cu" "B.Cu")
		(net "SMB_LM75_0_3V3AUX_SDA_R1")
	)
	(segment
		(start 255.378966 -119.92737)
		(end 254.992886 -120.31345)
		(width 0.10668)
		(layer "F.Cu")
		(net "SMB_LM75_0_3V3AUX_SDA")
	)
	(segment
		(start 256.842006 -119.92737)
		(end 255.378966 -119.92737)
		(width 0.10668)
		(layer "F.Cu")
		(net "SMB_LM75_0_3V3AUX_SDA")
	)
	(segment
		(start 254.309626 -119.63019)
		(end 254.992886 -120.31345)
		(width 0.10668)
		(layer "F.Cu")
		(net "SMB_LM75_0_3V3AUX_SDA")
	)
	(segment
		(start 367.284 -408.559)
		(end 366.522 -409.321)
		(width 0.10668)
		(layer "F.Cu")
		(net "SMB_LM75_0_3V3AUX_SDA")
	)
	(segment
		(start 366.522 -410.99105)
		(end 365.887 -411.62605)
		(width 0.10668)
		(layer "F.Cu")
		(net "SMB_LM75_0_3V3AUX_SDA")
	)
	(segment
		(start 253.223014 -119.63019)
		(end 254.309626 -119.63019)
		(width 0.10668)
		(layer "F.Cu")
		(net "SMB_LM75_0_3V3AUX_SDA")
	)
	(segment
		(start 366.522 -409.321)
		(end 366.522 -410.99105)
		(width 0.10668)
		(layer "F.Cu")
		(net "SMB_LM75_0_3V3AUX_SDA")
	)
	(segment
		(start 367.284 -406.527)
		(end 367.284 -408.559)
		(width 0.10668)
		(layer "F.Cu")
		(net "SMB_LM75_0_3V3AUX_SDA")
	)
	(segment
		(start 253.06528 -119.472456)
		(end 253.223014 -119.63019)
		(width 0.10668)
		(layer "F.Cu")
		(net "SMB_LM75_0_3V3AUX_SDA")
	)
	(segment
		(start 365.887 -413.23895)
		(end 365.887 -411.62605)
		(width 0.10668)
		(layer "F.Cu")
		(net "SMB_LM75_0_3V3AUX_SDA")
	)
	(via
		(at 350.890078 -123.3297)
		(size 0.508)
		(drill 0.254)
		(layers "F.Cu" "B.Cu")
		(net "SMB_LM75_0_3V3AUX_SDA")
	)
	(via
		(at 253.06528 -119.472456)
		(size 0.508)
		(drill 0.254)
		(layers "F.Cu" "B.Cu")
		(net "SMB_LM75_0_3V3AUX_SDA")
	)
	(via
		(at 367.284 -406.527)
		(size 0.508)
		(drill 0.254)
		(layers "F.Cu" "B.Cu")
		(net "SMB_LM75_0_3V3AUX_SDA")
	)
	(segment
		(start 376.559572 -122.31751)
		(end 375.99112 -122.885962)
		(width 0.11684)
		(layer "In2.Cu")
		(net "SMB_LM75_0_3V3AUX_SDA")
	)
	(segment
		(start 426.06849 -397.54302)
		(end 426.06849 -391.718038)
		(width 0.11684)
		(layer "In2.Cu")
		(net "SMB_LM75_0_3V3AUX_SDA")
	)
	(segment
		(start 427.486826 -397.80718)
		(end 426.33265 -397.80718)
		(width 0.11684)
		(layer "In2.Cu")
		(net "SMB_LM75_0_3V3AUX_SDA")
	)
	(segment
		(start 423.196004 -406.36063)
		(end 428.244254 -401.31238)
		(width 0.11684)
		(layer "In2.Cu")
		(net "SMB_LM75_0_3V3AUX_SDA")
	)
	(segment
		(start 451.581266 -363.445552)
		(end 451.581266 -342.921082)
		(width 0.11684)
		(layer "In2.Cu")
		(net "SMB_LM75_0_3V3AUX_SDA")
	)
	(segment
		(start 445.362838 -369.66398)
		(end 451.581266 -363.445552)
		(width 0.11684)
		(layer "In2.Cu")
		(net "SMB_LM75_0_3V3AUX_SDA")
	)
	(segment
		(start 452.020178 -164.126672)
		(end 452.020178 -147.028154)
		(width 0.11684)
		(layer "In2.Cu")
		(net "SMB_LM75_0_3V3AUX_SDA")
	)
	(segment
		(start 437.62549 -369.66398)
		(end 445.362838 -369.66398)
		(width 0.11684)
		(layer "In2.Cu")
		(net "SMB_LM75_0_3V3AUX_SDA")
	)
	(segment
		(start 367.646712 -406.164288)
		(end 369.734592 -406.164288)
		(width 0.11684)
		(layer "In2.Cu")
		(net "SMB_LM75_0_3V3AUX_SDA")
	)
	(segment
		(start 426.33265 -397.80718)
		(end 426.06849 -397.54302)
		(width 0.11684)
		(layer "In2.Cu")
		(net "SMB_LM75_0_3V3AUX_SDA")
	)
	(segment
		(start 367.284 -406.527)
		(end 367.646712 -406.164288)
		(width 0.11684)
		(layer "In2.Cu")
		(net "SMB_LM75_0_3V3AUX_SDA")
	)
	(segment
		(start 452.020178 -147.028154)
		(end 426.549566 -121.557542)
		(width 0.11684)
		(layer "In2.Cu")
		(net "SMB_LM75_0_3V3AUX_SDA")
	)
	(segment
		(start 428.244254 -401.31238)
		(end 428.244254 -399.687796)
		(width 0.11684)
		(layer "In2.Cu")
		(net "SMB_LM75_0_3V3AUX_SDA")
	)
	(segment
		(start 375.99112 -122.885962)
		(end 351.333816 -122.885962)
		(width 0.11684)
		(layer "In2.Cu")
		(net "SMB_LM75_0_3V3AUX_SDA")
	)
	(segment
		(start 369.734592 -406.164288)
		(end 369.930934 -406.36063)
		(width 0.11684)
		(layer "In2.Cu")
		(net "SMB_LM75_0_3V3AUX_SDA")
	)
	(segment
		(start 394.523214 -122.31751)
		(end 376.559572 -122.31751)
		(width 0.11684)
		(layer "In2.Cu")
		(net "SMB_LM75_0_3V3AUX_SDA")
	)
	(segment
		(start 428.244254 -399.687796)
		(end 427.852586 -399.296128)
		(width 0.11684)
		(layer "In2.Cu")
		(net "SMB_LM75_0_3V3AUX_SDA")
	)
	(segment
		(start 369.930934 -406.36063)
		(end 423.196004 -406.36063)
		(width 0.11684)
		(layer "In2.Cu")
		(net "SMB_LM75_0_3V3AUX_SDA")
	)
	(segment
		(start 428.70374 -378.58573)
		(end 437.62549 -369.66398)
		(width 0.11684)
		(layer "In2.Cu")
		(net "SMB_LM75_0_3V3AUX_SDA")
	)
	(segment
		(start 426.549566 -121.557542)
		(end 395.283182 -121.557542)
		(width 0.11684)
		(layer "In2.Cu")
		(net "SMB_LM75_0_3V3AUX_SDA")
	)
	(segment
		(start 427.852586 -398.17294)
		(end 427.486826 -397.80718)
		(width 0.11684)
		(layer "In2.Cu")
		(net "SMB_LM75_0_3V3AUX_SDA")
	)
	(segment
		(start 463.388456 -331.113892)
		(end 463.388456 -175.49495)
		(width 0.11684)
		(layer "In2.Cu")
		(net "SMB_LM75_0_3V3AUX_SDA")
	)
	(segment
		(start 395.283182 -121.557542)
		(end 394.523214 -122.31751)
		(width 0.11684)
		(layer "In2.Cu")
		(net "SMB_LM75_0_3V3AUX_SDA")
	)
	(segment
		(start 428.70374 -389.082788)
		(end 428.70374 -378.58573)
		(width 0.11684)
		(layer "In2.Cu")
		(net "SMB_LM75_0_3V3AUX_SDA")
	)
	(segment
		(start 427.852586 -399.296128)
		(end 427.852586 -398.17294)
		(width 0.11684)
		(layer "In2.Cu")
		(net "SMB_LM75_0_3V3AUX_SDA")
	)
	(segment
		(start 351.333816 -122.885962)
		(end 350.890078 -123.3297)
		(width 0.11684)
		(layer "In2.Cu")
		(net "SMB_LM75_0_3V3AUX_SDA")
	)
	(segment
		(start 426.06849 -391.718038)
		(end 428.70374 -389.082788)
		(width 0.11684)
		(layer "In2.Cu")
		(net "SMB_LM75_0_3V3AUX_SDA")
	)
	(segment
		(start 463.388456 -175.49495)
		(end 452.020178 -164.126672)
		(width 0.11684)
		(layer "In2.Cu")
		(net "SMB_LM75_0_3V3AUX_SDA")
	)
	(segment
		(start 451.581266 -342.921082)
		(end 463.388456 -331.113892)
		(width 0.11684)
		(layer "In2.Cu")
		(net "SMB_LM75_0_3V3AUX_SDA")
	)
	(segment
		(start 346.55252 -121.57964)
		(end 320.58483 -121.57964)
		(width 0.11684)
		(layer "In6.Cu")
		(net "SMB_LM75_0_3V3AUX_SDA")
	)
	(segment
		(start 298.561252 -126.576074)
		(end 262.237728 -126.576074)
		(width 0.11684)
		(layer "In6.Cu")
		(net "SMB_LM75_0_3V3AUX_SDA")
	)
	(segment
		(start 350.890078 -123.3297)
		(end 350.300798 -123.91898)
		(width 0.11684)
		(layer "In6.Cu")
		(net "SMB_LM75_0_3V3AUX_SDA")
	)
	(segment
		(start 301.218346 -123.91898)
		(end 298.561252 -126.576074)
		(width 0.11684)
		(layer "In6.Cu")
		(net "SMB_LM75_0_3V3AUX_SDA")
	)
	(segment
		(start 318.24549 -123.91898)
		(end 301.218346 -123.91898)
		(width 0.11684)
		(layer "In6.Cu")
		(net "SMB_LM75_0_3V3AUX_SDA")
	)
	(segment
		(start 253.223014 -119.63019)
		(end 253.06528 -119.472456)
		(width 0.11684)
		(layer "In6.Cu")
		(net "SMB_LM75_0_3V3AUX_SDA")
	)
	(segment
		(start 320.58483 -121.57964)
		(end 318.24549 -123.91898)
		(width 0.11684)
		(layer "In6.Cu")
		(net "SMB_LM75_0_3V3AUX_SDA")
	)
	(segment
		(start 255.291844 -119.63019)
		(end 253.223014 -119.63019)
		(width 0.11684)
		(layer "In6.Cu")
		(net "SMB_LM75_0_3V3AUX_SDA")
	)
	(segment
		(start 350.300798 -123.91898)
		(end 348.89186 -123.91898)
		(width 0.11684)
		(layer "In6.Cu")
		(net "SMB_LM75_0_3V3AUX_SDA")
	)
	(segment
		(start 348.89186 -123.91898)
		(end 346.55252 -121.57964)
		(width 0.11684)
		(layer "In6.Cu")
		(net "SMB_LM75_0_3V3AUX_SDA")
	)
	(segment
		(start 262.237728 -126.576074)
		(end 255.291844 -119.63019)
		(width 0.11684)
		(layer "In6.Cu")
		(net "SMB_LM75_0_3V3AUX_SDA")
	)
	(segment
		(start 367.157 -414.03905)
		(end 367.157 -414.909)
		(width 0.10668)
		(layer "F.Cu")
		(net "SMB_LM75_0_3V3AUX_SCL_R1")
	)
	(segment
		(start 367.177066 -414.929066)
		(end 367.157 -414.909)
		(width 0.10668)
		(layer "F.Cu")
		(net "SMB_LM75_0_3V3AUX_SCL_R1")
	)
	(segment
		(start 367.177066 -416.645598)
		(end 367.177066 -414.929066)
		(width 0.10668)
		(layer "F.Cu")
		(net "SMB_LM75_0_3V3AUX_SCL_R1")
	)
	(via
		(at 367.157 -414.909)
		(size 0.762)
		(drill 0.381)
		(layers "F.Cu" "B.Cu")
		(net "SMB_LM75_0_3V3AUX_SCL_R1")
	)
	(segment
		(start 256.836926 -118.91645)
		(end 254.992886 -118.91645)
		(width 0.10668)
		(layer "F.Cu")
		(net "SMB_LM75_0_3V3AUX_SCL")
	)
	(segment
		(start 256.842006 -118.91137)
		(end 256.836926 -118.91645)
		(width 0.10668)
		(layer "F.Cu")
		(net "SMB_LM75_0_3V3AUX_SCL")
	)
	(segment
		(start 367.39195 -411.62605)
		(end 367.792 -411.226)
		(width 0.10668)
		(layer "F.Cu")
		(net "SMB_LM75_0_3V3AUX_SCL")
	)
	(segment
		(start 367.792 -408.94)
		(end 368.554 -408.178)
		(width 0.10668)
		(layer "F.Cu")
		(net "SMB_LM75_0_3V3AUX_SCL")
	)
	(segment
		(start 254.266446 -118.19001)
		(end 254.992886 -118.91645)
		(width 0.10668)
		(layer "F.Cu")
		(net "SMB_LM75_0_3V3AUX_SCL")
	)
	(segment
		(start 367.157 -411.62605)
		(end 367.39195 -411.62605)
		(width 0.10668)
		(layer "F.Cu")
		(net "SMB_LM75_0_3V3AUX_SCL")
	)
	(segment
		(start 367.792 -411.226)
		(end 367.792 -408.94)
		(width 0.10668)
		(layer "F.Cu")
		(net "SMB_LM75_0_3V3AUX_SCL")
	)
	(segment
		(start 368.554 -408.178)
		(end 368.554 -406.654)
		(width 0.10668)
		(layer "F.Cu")
		(net "SMB_LM75_0_3V3AUX_SCL")
	)
	(segment
		(start 367.157 -411.62605)
		(end 367.157 -413.23895)
		(width 0.10668)
		(layer "F.Cu")
		(net "SMB_LM75_0_3V3AUX_SCL")
	)
	(segment
		(start 252.3871 -118.19001)
		(end 254.266446 -118.19001)
		(width 0.10668)
		(layer "F.Cu")
		(net "SMB_LM75_0_3V3AUX_SCL")
	)
	(via
		(at 348.960948 -123.330208)
		(size 0.508)
		(drill 0.254)
		(layers "F.Cu" "B.Cu")
		(net "SMB_LM75_0_3V3AUX_SCL")
	)
	(via
		(at 252.3871 -118.19001)
		(size 0.508)
		(drill 0.254)
		(layers "F.Cu" "B.Cu")
		(net "SMB_LM75_0_3V3AUX_SCL")
	)
	(via
		(at 368.554 -406.654)
		(size 0.508)
		(drill 0.254)
		(layers "F.Cu" "B.Cu")
		(net "SMB_LM75_0_3V3AUX_SCL")
	)
	(segment
		(start 376.214132 -121.835164)
		(end 375.584974 -122.464322)
		(width 0.11684)
		(layer "In2.Cu")
		(net "SMB_LM75_0_3V3AUX_SCL")
	)
	(segment
		(start 428.673514 -399.45818)
		(end 428.302166 -399.086832)
		(width 0.11684)
		(layer "In2.Cu")
		(net "SMB_LM75_0_3V3AUX_SCL")
	)
	(segment
		(start 383.161794 -121.835164)
		(end 376.214132 -121.835164)
		(width 0.11684)
		(layer "In2.Cu")
		(net "SMB_LM75_0_3V3AUX_SCL")
	)
	(segment
		(start 452.441818 -163.919916)
		(end 452.441818 -146.853402)
		(width 0.11684)
		(layer "In2.Cu")
		(net "SMB_LM75_0_3V3AUX_SCL")
	)
	(segment
		(start 430.213516 -395.163548)
		(end 430.213516 -393.685776)
		(width 0.11684)
		(layer "In2.Cu")
		(net "SMB_LM75_0_3V3AUX_SCL")
	)
	(segment
		(start 452.050658 -343.115646)
		(end 463.810096 -331.356208)
		(width 0.11684)
		(layer "In2.Cu")
		(net "SMB_LM75_0_3V3AUX_SCL")
	)
	(segment
		(start 368.554 -406.654)
		(end 369.334288 -406.654)
		(width 0.11684)
		(layer "In2.Cu")
		(net "SMB_LM75_0_3V3AUX_SCL")
	)
	(segment
		(start 437.75249 -370.133372)
		(end 445.557402 -370.133372)
		(width 0.11684)
		(layer "In2.Cu")
		(net "SMB_LM75_0_3V3AUX_SCL")
	)
	(segment
		(start 428.673514 -401.515834)
		(end 428.673514 -399.45818)
		(width 0.11684)
		(layer "In2.Cu")
		(net "SMB_LM75_0_3V3AUX_SCL")
	)
	(segment
		(start 369.512088 -406.8318)
		(end 423.357548 -406.8318)
		(width 0.11684)
		(layer "In2.Cu")
		(net "SMB_LM75_0_3V3AUX_SCL")
	)
	(segment
		(start 445.557402 -370.133372)
		(end 452.050658 -363.640116)
		(width 0.11684)
		(layer "In2.Cu")
		(net "SMB_LM75_0_3V3AUX_SCL")
	)
	(segment
		(start 429.828706 -395.548358)
		(end 430.213516 -395.163548)
		(width 0.11684)
		(layer "In2.Cu")
		(net "SMB_LM75_0_3V3AUX_SCL")
	)
	(segment
		(start 429.12538 -378.760482)
		(end 437.75249 -370.133372)
		(width 0.11684)
		(layer "In2.Cu")
		(net "SMB_LM75_0_3V3AUX_SCL")
	)
	(segment
		(start 452.441818 -146.853402)
		(end 426.684694 -121.096278)
		(width 0.11684)
		(layer "In2.Cu")
		(net "SMB_LM75_0_3V3AUX_SCL")
	)
	(segment
		(start 452.050658 -363.640116)
		(end 452.050658 -343.115646)
		(width 0.11684)
		(layer "In2.Cu")
		(net "SMB_LM75_0_3V3AUX_SCL")
	)
	(segment
		(start 383.90068 -121.096278)
		(end 383.161794 -121.835164)
		(width 0.11684)
		(layer "In2.Cu")
		(net "SMB_LM75_0_3V3AUX_SCL")
	)
	(segment
		(start 430.213516 -393.685776)
		(end 429.12538 -392.59764)
		(width 0.11684)
		(layer "In2.Cu")
		(net "SMB_LM75_0_3V3AUX_SCL")
	)
	(segment
		(start 463.810096 -175.288194)
		(end 452.441818 -163.919916)
		(width 0.11684)
		(layer "In2.Cu")
		(net "SMB_LM75_0_3V3AUX_SCL")
	)
	(segment
		(start 375.584974 -122.464322)
		(end 349.826834 -122.464322)
		(width 0.11684)
		(layer "In2.Cu")
		(net "SMB_LM75_0_3V3AUX_SCL")
	)
	(segment
		(start 426.684694 -121.096278)
		(end 383.90068 -121.096278)
		(width 0.11684)
		(layer "In2.Cu")
		(net "SMB_LM75_0_3V3AUX_SCL")
	)
	(segment
		(start 429.436022 -395.548358)
		(end 429.828706 -395.548358)
		(width 0.11684)
		(layer "In2.Cu")
		(net "SMB_LM75_0_3V3AUX_SCL")
	)
	(segment
		(start 429.12538 -392.59764)
		(end 429.12538 -378.760482)
		(width 0.11684)
		(layer "In2.Cu")
		(net "SMB_LM75_0_3V3AUX_SCL")
	)
	(segment
		(start 428.302166 -399.086832)
		(end 428.302166 -397.690848)
		(width 0.11684)
		(layer "In2.Cu")
		(net "SMB_LM75_0_3V3AUX_SCL")
	)
	(segment
		(start 423.357548 -406.8318)
		(end 428.673514 -401.515834)
		(width 0.11684)
		(layer "In2.Cu")
		(net "SMB_LM75_0_3V3AUX_SCL")
	)
	(segment
		(start 428.825406 -396.158974)
		(end 429.436022 -395.548358)
		(width 0.11684)
		(layer "In2.Cu")
		(net "SMB_LM75_0_3V3AUX_SCL")
	)
	(segment
		(start 369.334288 -406.654)
		(end 369.512088 -406.8318)
		(width 0.11684)
		(layer "In2.Cu")
		(net "SMB_LM75_0_3V3AUX_SCL")
	)
	(segment
		(start 463.810096 -331.356208)
		(end 463.810096 -175.288194)
		(width 0.11684)
		(layer "In2.Cu")
		(net "SMB_LM75_0_3V3AUX_SCL")
	)
	(segment
		(start 428.825406 -397.167608)
		(end 428.825406 -396.158974)
		(width 0.11684)
		(layer "In2.Cu")
		(net "SMB_LM75_0_3V3AUX_SCL")
	)
	(segment
		(start 428.302166 -397.690848)
		(end 428.825406 -397.167608)
		(width 0.11684)
		(layer "In2.Cu")
		(net "SMB_LM75_0_3V3AUX_SCL")
	)
	(segment
		(start 349.826834 -122.464322)
		(end 348.960948 -123.330208)
		(width 0.11684)
		(layer "In2.Cu")
		(net "SMB_LM75_0_3V3AUX_SCL")
	)
	(segment
		(start 254.448056 -118.19001)
		(end 262.41248 -126.154434)
		(width 0.11684)
		(layer "In6.Cu")
		(net "SMB_LM75_0_3V3AUX_SCL")
	)
	(segment
		(start 301.043594 -123.49734)
		(end 318.070484 -123.49734)
		(width 0.11684)
		(layer "In6.Cu")
		(net "SMB_LM75_0_3V3AUX_SCL")
	)
	(segment
		(start 252.3871 -118.19001)
		(end 254.448056 -118.19001)
		(width 0.11684)
		(layer "In6.Cu")
		(net "SMB_LM75_0_3V3AUX_SCL")
	)
	(segment
		(start 262.41248 -126.154434)
		(end 298.3865 -126.154434)
		(width 0.11684)
		(layer "In6.Cu")
		(net "SMB_LM75_0_3V3AUX_SCL")
	)
	(segment
		(start 318.070484 -123.49734)
		(end 320.409824 -121.158)
		(width 0.11684)
		(layer "In6.Cu")
		(net "SMB_LM75_0_3V3AUX_SCL")
	)
	(segment
		(start 298.3865 -126.154434)
		(end 301.043594 -123.49734)
		(width 0.11684)
		(layer "In6.Cu")
		(net "SMB_LM75_0_3V3AUX_SCL")
	)
	(segment
		(start 320.409824 -121.158)
		(end 346.78874 -121.158)
		(width 0.11684)
		(layer "In6.Cu")
		(net "SMB_LM75_0_3V3AUX_SCL")
	)
	(segment
		(start 346.78874 -121.158)
		(end 348.960948 -123.330208)
		(width 0.11684)
		(layer "In6.Cu")
		(net "SMB_LM75_0_3V3AUX_SCL")
	)
	(segment
		(start 212.72246 -32.857948)
		(end 212.680804 -32.816292)
		(width 0.10668)
		(layer "F.Cu")
		(net "SMB_INA230_5_3V3AUX_SDA_R1")
	)
	(segment
		(start 210.168744 -32.954214)
		(end 211.600288 -32.954214)
		(width 0.10668)
		(layer "F.Cu")
		(net "SMB_INA230_5_3V3AUX_SDA_R1")
	)
	(segment
		(start 209.922618 -33.20034)
		(end 210.168744 -32.954214)
		(width 0.10668)
		(layer "F.Cu")
		(net "SMB_INA230_5_3V3AUX_SDA_R1")
	)
	(segment
		(start 212.680804 -32.816292)
		(end 211.73821 -32.816292)
		(width 0.10668)
		(layer "F.Cu")
		(net "SMB_INA230_5_3V3AUX_SDA_R1")
	)
	(segment
		(start 213.14283 -32.857948)
		(end 212.72246 -32.857948)
		(width 0.10668)
		(layer "F.Cu")
		(net "SMB_INA230_5_3V3AUX_SDA_R1")
	)
	(segment
		(start 209.922618 -33.372044)
		(end 209.922618 -33.20034)
		(width 0.10668)
		(layer "F.Cu")
		(net "SMB_INA230_5_3V3AUX_SDA_R1")
	)
	(segment
		(start 211.600288 -32.954214)
		(end 211.73821 -32.816292)
		(width 0.10668)
		(layer "F.Cu")
		(net "SMB_INA230_5_3V3AUX_SDA_R1")
	)
	(via
		(at 211.73821 -32.816292)
		(size 0.762)
		(drill 0.381)
		(layers "F.Cu" "B.Cu")
		(net "SMB_INA230_5_3V3AUX_SDA_R1")
	)
	(segment
		(start 215.556084 -32.857948)
		(end 214.686134 -32.857948)
		(width 0.10668)
		(layer "F.Cu")
		(net "SMB_INA230_5_3V3AUX_SDA_R")
	)
	(segment
		(start 213.94293 -32.857948)
		(end 214.686134 -32.857948)
		(width 0.10668)
		(layer "F.Cu")
		(net "SMB_INA230_5_3V3AUX_SDA_R")
	)
	(via
		(at 214.686134 -32.857948)
		(size 0.508)
		(drill 0.254)
		(layers "F.Cu" "B.Cu")
		(net "SMB_INA230_5_3V3AUX_SDA_R")
	)
	(segment
		(start 213.14283 -34.508948)
		(end 211.906866 -34.508948)
		(width 0.10668)
		(layer "F.Cu")
		(net "SMB_INA230_5_3V3AUX_SCL_R1")
	)
	(segment
		(start 211.419948 -34.02203)
		(end 211.86521 -34.467292)
		(width 0.10668)
		(layer "F.Cu")
		(net "SMB_INA230_5_3V3AUX_SCL_R1")
	)
	(segment
		(start 210.572604 -34.02203)
		(end 211.419948 -34.02203)
		(width 0.10668)
		(layer "F.Cu")
		(net "SMB_INA230_5_3V3AUX_SCL_R1")
	)
	(segment
		(start 211.906866 -34.508948)
		(end 211.86521 -34.467292)
		(width 0.10668)
		(layer "F.Cu")
		(net "SMB_INA230_5_3V3AUX_SCL_R1")
	)
	(via
		(at 211.86521 -34.467292)
		(size 0.762)
		(drill 0.381)
		(layers "F.Cu" "B.Cu")
		(net "SMB_INA230_5_3V3AUX_SCL_R1")
	)
	(segment
		(start 215.556084 -34.508948)
		(end 214.686134 -34.508948)
		(width 0.10668)
		(layer "F.Cu")
		(net "SMB_INA230_5_3V3AUX_SCL_R")
	)
	(segment
		(start 213.94293 -34.508948)
		(end 214.686134 -34.508948)
		(width 0.10668)
		(layer "F.Cu")
		(net "SMB_INA230_5_3V3AUX_SCL_R")
	)
	(via
		(at 214.686134 -34.508948)
		(size 0.508)
		(drill 0.254)
		(layers "F.Cu" "B.Cu")
		(net "SMB_INA230_5_3V3AUX_SCL_R")
	)
	(segment
		(start 153.333958 -56.368696)
		(end 153.598118 -56.368696)
		(width 0.10668)
		(layer "F.Cu")
		(net "SMB_INA230_4_3V3AUX_SDA_R1")
	)
	(segment
		(start 152.982422 -53.884068)
		(end 152.393396 -54.473094)
		(width 0.10668)
		(layer "F.Cu")
		(net "SMB_INA230_4_3V3AUX_SDA_R1")
	)
	(segment
		(start 153.04262 -55.122318)
		(end 153.04262 -56.077358)
		(width 0.10668)
		(layer "F.Cu")
		(net "SMB_INA230_4_3V3AUX_SDA_R1")
	)
	(segment
		(start 152.393396 -54.473094)
		(end 153.04262 -55.122318)
		(width 0.10668)
		(layer "F.Cu")
		(net "SMB_INA230_4_3V3AUX_SDA_R1")
	)
	(segment
		(start 152.982422 -53.171344)
		(end 152.982422 -53.884068)
		(width 0.10668)
		(layer "F.Cu")
		(net "SMB_INA230_4_3V3AUX_SDA_R1")
	)
	(segment
		(start 153.04262 -56.077358)
		(end 153.333958 -56.368696)
		(width 0.10668)
		(layer "F.Cu")
		(net "SMB_INA230_4_3V3AUX_SDA_R1")
	)
	(via
		(at 152.393396 -54.473094)
		(size 0.762)
		(drill 0.381)
		(layers "F.Cu" "B.Cu")
		(net "SMB_INA230_4_3V3AUX_SDA_R1")
	)
	(segment
		(start 152.982676 -51.139344)
		(end 152.982676 -51.761644)
		(width 0.10668)
		(layer "F.Cu")
		(net "SMB_INA230_4_3V3AUX_SDA_R")
	)
	(segment
		(start 152.982422 -51.761898)
		(end 152.982676 -51.761644)
		(width 0.10668)
		(layer "F.Cu")
		(net "SMB_INA230_4_3V3AUX_SDA_R")
	)
	(segment
		(start 152.982422 -52.371244)
		(end 152.982422 -51.761898)
		(width 0.10668)
		(layer "F.Cu")
		(net "SMB_INA230_4_3V3AUX_SDA_R")
	)
	(via
		(at 152.982676 -51.761644)
		(size 0.508)
		(drill 0.254)
		(layers "F.Cu" "B.Cu")
		(net "SMB_INA230_4_3V3AUX_SDA_R")
	)
	(segment
		(start 154.248104 -54.803548)
		(end 153.8351 -54.390544)
		(width 0.10668)
		(layer "F.Cu")
		(net "SMB_INA230_4_3V3AUX_SCL_R1")
	)
	(segment
		(start 154.633422 -53.171344)
		(end 154.633422 -53.592222)
		(width 0.10668)
		(layer "F.Cu")
		(net "SMB_INA230_4_3V3AUX_SCL_R1")
	)
	(segment
		(start 154.248104 -55.71871)
		(end 154.248104 -54.803548)
		(width 0.10668)
		(layer "F.Cu")
		(net "SMB_INA230_4_3V3AUX_SCL_R1")
	)
	(segment
		(start 154.633422 -53.592222)
		(end 153.8351 -54.390544)
		(width 0.10668)
		(layer "F.Cu")
		(net "SMB_INA230_4_3V3AUX_SCL_R1")
	)
	(via
		(at 153.8351 -54.390544)
		(size 0.762)
		(drill 0.381)
		(layers "F.Cu" "B.Cu")
		(net "SMB_INA230_4_3V3AUX_SCL_R1")
	)
	(segment
		(start 154.633422 -52.371244)
		(end 154.633422 -51.761898)
		(width 0.10668)
		(layer "F.Cu")
		(net "SMB_INA230_4_3V3AUX_SCL_R")
	)
	(segment
		(start 154.633422 -51.761898)
		(end 154.633676 -51.761644)
		(width 0.10668)
		(layer "F.Cu")
		(net "SMB_INA230_4_3V3AUX_SCL_R")
	)
	(segment
		(start 154.633676 -51.139344)
		(end 154.633676 -51.761644)
		(width 0.10668)
		(layer "F.Cu")
		(net "SMB_INA230_4_3V3AUX_SCL_R")
	)
	(via
		(at 154.633676 -51.761644)
		(size 0.508)
		(drill 0.254)
		(layers "F.Cu" "B.Cu")
		(net "SMB_INA230_4_3V3AUX_SCL_R")
	)
	(segment
		(start 70.817232 -38.291008)
		(end 70.817232 -37.027358)
		(width 0.10668)
		(layer "F.Cu")
		(net "SMB_INA230_3_3V3AUX_SDA_R1")
	)
	(segment
		(start 71.11365 -35.810444)
		(end 70.356984 -36.56711)
		(width 0.10668)
		(layer "F.Cu")
		(net "SMB_INA230_3_3V3AUX_SDA_R1")
	)
	(segment
		(start 71.096124 -38.5699)
		(end 70.817232 -38.291008)
		(width 0.10668)
		(layer "F.Cu")
		(net "SMB_INA230_3_3V3AUX_SDA_R1")
	)
	(segment
		(start 71.11365 -34.788348)
		(end 71.11365 -35.810444)
		(width 0.10668)
		(layer "F.Cu")
		(net "SMB_INA230_3_3V3AUX_SDA_R1")
	)
	(segment
		(start 71.308214 -38.5699)
		(end 71.096124 -38.5699)
		(width 0.10668)
		(layer "F.Cu")
		(net "SMB_INA230_3_3V3AUX_SDA_R1")
	)
	(segment
		(start 70.817232 -37.027358)
		(end 70.356984 -36.56711)
		(width 0.10668)
		(layer "F.Cu")
		(net "SMB_INA230_3_3V3AUX_SDA_R1")
	)
	(via
		(at 70.356984 -36.56711)
		(size 0.762)
		(drill 0.381)
		(layers "F.Cu" "B.Cu")
		(net "SMB_INA230_3_3V3AUX_SDA_R1")
	)
	(segment
		(start 150.789894 -50.454814)
		(end 150.789894 -47.949104)
		(width 0.10668)
		(layer "F.Cu")
		(net "SMB_INA230_3_3V3AUX_SDA_R")
	)
	(segment
		(start 70.31355 -35.677094)
		(end 70.312534 -35.67811)
		(width 0.10668)
		(layer "F.Cu")
		(net "SMB_INA230_3_3V3AUX_SDA_R")
	)
	(segment
		(start 151.966676 -51.139344)
		(end 151.474424 -51.139344)
		(width 0.10668)
		(layer "F.Cu")
		(net "SMB_INA230_3_3V3AUX_SDA_R")
	)
	(segment
		(start 151.474424 -51.139344)
		(end 150.789894 -50.454814)
		(width 0.10668)
		(layer "F.Cu")
		(net "SMB_INA230_3_3V3AUX_SDA_R")
	)
	(segment
		(start 70.31355 -34.788348)
		(end 70.31355 -35.677094)
		(width 0.10668)
		(layer "F.Cu")
		(net "SMB_INA230_3_3V3AUX_SDA_R")
	)
	(via
		(at 70.312534 -35.67811)
		(size 0.508)
		(drill 0.254)
		(layers "F.Cu" "B.Cu")
		(net "SMB_INA230_3_3V3AUX_SDA_R")
	)
	(via
		(at 150.789894 -47.949104)
		(size 0.508)
		(drill 0.254)
		(layers "F.Cu" "B.Cu")
		(net "SMB_INA230_3_3V3AUX_SDA_R")
	)
	(segment
		(start 116.628672 -46.206664)
		(end 115.629436 -47.2059)
		(width 0.11684)
		(layer "In6.Cu")
		(net "SMB_INA230_3_3V3AUX_SDA_R")
	)
	(segment
		(start 101.00564 -42.646854)
		(end 88.015318 -42.646854)
		(width 0.11684)
		(layer "In6.Cu")
		(net "SMB_INA230_3_3V3AUX_SDA_R")
	)
	(segment
		(start 106.751374 -47.2059)
		(end 103.03129 -43.485816)
		(width 0.11684)
		(layer "In6.Cu")
		(net "SMB_INA230_3_3V3AUX_SDA_R")
	)
	(segment
		(start 88.015318 -42.646854)
		(end 87.822532 -42.83964)
		(width 0.11684)
		(layer "In6.Cu")
		(net "SMB_INA230_3_3V3AUX_SDA_R")
	)
	(segment
		(start 115.629436 -47.2059)
		(end 106.751374 -47.2059)
		(width 0.11684)
		(layer "In6.Cu")
		(net "SMB_INA230_3_3V3AUX_SDA_R")
	)
	(segment
		(start 150.789894 -47.949104)
		(end 150.54199 -47.7012)
		(width 0.11684)
		(layer "In6.Cu")
		(net "SMB_INA230_3_3V3AUX_SDA_R")
	)
	(segment
		(start 72.86752 -36.146232)
		(end 70.780656 -36.146232)
		(width 0.11684)
		(layer "In6.Cu")
		(net "SMB_INA230_3_3V3AUX_SDA_R")
	)
	(segment
		(start 145.687796 -46.6344)
		(end 128.203452 -46.6344)
		(width 0.11684)
		(layer "In6.Cu")
		(net "SMB_INA230_3_3V3AUX_SDA_R")
	)
	(segment
		(start 73.906888 -37.1856)
		(end 72.86752 -36.146232)
		(width 0.11684)
		(layer "In6.Cu")
		(net "SMB_INA230_3_3V3AUX_SDA_R")
	)
	(segment
		(start 146.754596 -47.7012)
		(end 145.687796 -46.6344)
		(width 0.11684)
		(layer "In6.Cu")
		(net "SMB_INA230_3_3V3AUX_SDA_R")
	)
	(segment
		(start 103.03129 -43.485816)
		(end 101.00564 -42.646854)
		(width 0.11684)
		(layer "In6.Cu")
		(net "SMB_INA230_3_3V3AUX_SDA_R")
	)
	(segment
		(start 87.822532 -42.83964)
		(end 81.904078 -42.83964)
		(width 0.11684)
		(layer "In6.Cu")
		(net "SMB_INA230_3_3V3AUX_SDA_R")
	)
	(segment
		(start 70.780656 -36.146232)
		(end 70.312534 -35.67811)
		(width 0.11684)
		(layer "In6.Cu")
		(net "SMB_INA230_3_3V3AUX_SDA_R")
	)
	(segment
		(start 128.203452 -46.6344)
		(end 127.775716 -46.206664)
		(width 0.11684)
		(layer "In6.Cu")
		(net "SMB_INA230_3_3V3AUX_SDA_R")
	)
	(segment
		(start 127.775716 -46.206664)
		(end 116.628672 -46.206664)
		(width 0.11684)
		(layer "In6.Cu")
		(net "SMB_INA230_3_3V3AUX_SDA_R")
	)
	(segment
		(start 76.250038 -37.1856)
		(end 73.906888 -37.1856)
		(width 0.11684)
		(layer "In6.Cu")
		(net "SMB_INA230_3_3V3AUX_SDA_R")
	)
	(segment
		(start 81.904078 -42.83964)
		(end 76.250038 -37.1856)
		(width 0.11684)
		(layer "In6.Cu")
		(net "SMB_INA230_3_3V3AUX_SDA_R")
	)
	(segment
		(start 150.54199 -47.7012)
		(end 146.754596 -47.7012)
		(width 0.11684)
		(layer "In6.Cu")
		(net "SMB_INA230_3_3V3AUX_SDA_R")
	)
	(segment
		(start 71.626984 -35.759136)
		(end 71.894446 -35.491674)
		(width 0.10668)
		(layer "F.Cu")
		(net "SMB_INA230_3_3V3AUX_SCL_R1")
	)
	(segment
		(start 67.202558 -38.405562)
		(end 67.201796 -38.406324)
		(width 0.10668)
		(layer "F.Cu")
		(net "SMB_INA230_3_3V3AUX_SCL_R1")
	)
	(segment
		(start 71.9582 -37.919914)
		(end 71.9582 -36.898326)
		(width 0.10668)
		(layer "F.Cu")
		(net "SMB_INA230_3_3V3AUX_SCL_R1")
	)
	(segment
		(start 71.9582 -36.898326)
		(end 71.626984 -36.56711)
		(width 0.10668)
		(layer "F.Cu")
		(net "SMB_INA230_3_3V3AUX_SCL_R1")
	)
	(segment
		(start 72.06615 -34.788348)
		(end 71.894446 -34.960052)
		(width 0.10668)
		(layer "F.Cu")
		(net "SMB_INA230_3_3V3AUX_SCL_R1")
	)
	(segment
		(start 67.812412 -38.405562)
		(end 67.202558 -38.405562)
		(width 0.10668)
		(layer "F.Cu")
		(net "SMB_INA230_3_3V3AUX_SCL_R1")
	)
	(segment
		(start 71.894446 -34.960052)
		(end 71.894446 -35.491674)
		(width 0.10668)
		(layer "F.Cu")
		(net "SMB_INA230_3_3V3AUX_SCL_R1")
	)
	(segment
		(start 71.626984 -36.56711)
		(end 71.626984 -35.759136)
		(width 0.10668)
		(layer "F.Cu")
		(net "SMB_INA230_3_3V3AUX_SCL_R1")
	)
	(via
		(at 71.626984 -36.56711)
		(size 0.762)
		(drill 0.381)
		(layers "F.Cu" "B.Cu")
		(net "SMB_INA230_3_3V3AUX_SCL_R1")
	)
	(via
		(at 71.894446 -35.491674)
		(size 0.508)
		(drill 0.254)
		(layers "F.Cu" "B.Cu")
		(net "SMB_INA230_3_3V3AUX_SCL_R1")
	)
	(via
		(at 67.201796 -38.406324)
		(size 0.508)
		(drill 0.254)
		(layers "F.Cu" "B.Cu")
		(net "SMB_INA230_3_3V3AUX_SCL_R1")
	)
	(segment
		(start 70.490334 -38.406324)
		(end 71.99249 -36.904168)
		(width 0.10668)
		(layer "B.Cu")
		(net "SMB_INA230_3_3V3AUX_SCL_R1")
	)
	(segment
		(start 71.99249 -36.904168)
		(end 71.99249 -35.589718)
		(width 0.10668)
		(layer "B.Cu")
		(net "SMB_INA230_3_3V3AUX_SCL_R1")
	)
	(segment
		(start 67.201796 -38.406324)
		(end 70.490334 -38.406324)
		(width 0.10668)
		(layer "B.Cu")
		(net "SMB_INA230_3_3V3AUX_SCL_R1")
	)
	(segment
		(start 71.99249 -35.589718)
		(end 71.894446 -35.491674)
		(width 0.10668)
		(layer "B.Cu")
		(net "SMB_INA230_3_3V3AUX_SCL_R1")
	)
	(segment
		(start 154.633676 -48.561244)
		(end 154.021536 -47.949104)
		(width 0.10668)
		(layer "F.Cu")
		(net "SMB_INA230_3_3V3AUX_SCL_R")
	)
	(segment
		(start 72.86625 -34.788348)
		(end 72.896984 -34.819082)
		(width 0.10668)
		(layer "F.Cu")
		(net "SMB_INA230_3_3V3AUX_SCL_R")
	)
	(segment
		(start 72.896984 -34.819082)
		(end 72.896984 -35.52571)
		(width 0.10668)
		(layer "F.Cu")
		(net "SMB_INA230_3_3V3AUX_SCL_R")
	)
	(segment
		(start 154.021536 -47.949104)
		(end 152.440894 -47.949104)
		(width 0.10668)
		(layer "F.Cu")
		(net "SMB_INA230_3_3V3AUX_SCL_R")
	)
	(via
		(at 72.896984 -35.52571)
		(size 0.508)
		(drill 0.254)
		(layers "F.Cu" "B.Cu")
		(net "SMB_INA230_3_3V3AUX_SCL_R")
	)
	(via
		(at 152.440894 -47.949104)
		(size 0.508)
		(drill 0.254)
		(layers "F.Cu" "B.Cu")
		(net "SMB_INA230_3_3V3AUX_SCL_R")
	)
	(segment
		(start 74.074274 -36.703)
		(end 76.403454 -36.703)
		(width 0.11684)
		(layer "In6.Cu")
		(net "SMB_INA230_3_3V3AUX_SCL_R")
	)
	(segment
		(start 72.896984 -35.52571)
		(end 74.074274 -36.703)
		(width 0.11684)
		(layer "In6.Cu")
		(net "SMB_INA230_3_3V3AUX_SCL_R")
	)
	(segment
		(start 78.84541 -38.40988)
		(end 79.721964 -37.533326)
		(width 0.11684)
		(layer "In6.Cu")
		(net "SMB_INA230_3_3V3AUX_SCL_R")
	)
	(segment
		(start 80.92186 -38.733222)
		(end 81.08696 -38.733222)
		(width 0.11684)
		(layer "In6.Cu")
		(net "SMB_INA230_3_3V3AUX_SCL_R")
	)
	(segment
		(start 80.34528 -40.07485)
		(end 82.68843 -42.418)
		(width 0.11684)
		(layer "In6.Cu")
		(net "SMB_INA230_3_3V3AUX_SCL_R")
	)
	(segment
		(start 101.303074 -42.225214)
		(end 103.120698 -42.978578)
		(width 0.11684)
		(layer "In6.Cu")
		(net "SMB_INA230_3_3V3AUX_SCL_R")
	)
	(segment
		(start 79.721964 -37.533326)
		(end 79.887064 -37.533326)
		(width 0.11684)
		(layer "In6.Cu")
		(net "SMB_INA230_3_3V3AUX_SCL_R")
	)
	(segment
		(start 80.621886 -38.268148)
		(end 80.621886 -38.433248)
		(width 0.11684)
		(layer "In6.Cu")
		(net "SMB_INA230_3_3V3AUX_SCL_R")
	)
	(segment
		(start 128.060704 -45.785024)
		(end 128.48844 -46.21276)
		(width 0.11684)
		(layer "In6.Cu")
		(net "SMB_INA230_3_3V3AUX_SCL_R")
	)
	(segment
		(start 147.193 -47.27956)
		(end 151.77135 -47.27956)
		(width 0.11684)
		(layer "In6.Cu")
		(net "SMB_INA230_3_3V3AUX_SCL_R")
	)
	(segment
		(start 79.745332 -39.309802)
		(end 79.745332 -39.474902)
		(width 0.11684)
		(layer "In6.Cu")
		(net "SMB_INA230_3_3V3AUX_SCL_R")
	)
	(segment
		(start 80.321912 -38.133274)
		(end 80.487012 -38.133274)
		(width 0.11684)
		(layer "In6.Cu")
		(net "SMB_INA230_3_3V3AUX_SCL_R")
	)
	(segment
		(start 79.280258 -39.009828)
		(end 79.445358 -39.009828)
		(width 0.11684)
		(layer "In6.Cu")
		(net "SMB_INA230_3_3V3AUX_SCL_R")
	)
	(segment
		(start 87.344758 -42.418)
		(end 87.537544 -42.225214)
		(width 0.11684)
		(layer "In6.Cu")
		(net "SMB_INA230_3_3V3AUX_SCL_R")
	)
	(segment
		(start 79.887064 -37.533326)
		(end 80.021938 -37.6682)
		(width 0.11684)
		(layer "In6.Cu")
		(net "SMB_INA230_3_3V3AUX_SCL_R")
	)
	(segment
		(start 146.1262 -46.21276)
		(end 147.193 -47.27956)
		(width 0.11684)
		(layer "In6.Cu")
		(net "SMB_INA230_3_3V3AUX_SCL_R")
	)
	(segment
		(start 80.621886 -38.433248)
		(end 79.745332 -39.309802)
		(width 0.11684)
		(layer "In6.Cu")
		(net "SMB_INA230_3_3V3AUX_SCL_R")
	)
	(segment
		(start 80.021938 -37.6682)
		(end 80.021938 -37.8333)
		(width 0.11684)
		(layer "In6.Cu")
		(net "SMB_INA230_3_3V3AUX_SCL_R")
	)
	(segment
		(start 80.021938 -37.8333)
		(end 79.145384 -38.709854)
		(width 0.11684)
		(layer "In6.Cu")
		(net "SMB_INA230_3_3V3AUX_SCL_R")
	)
	(segment
		(start 151.77135 -47.27956)
		(end 152.440894 -47.949104)
		(width 0.11684)
		(layer "In6.Cu")
		(net "SMB_INA230_3_3V3AUX_SCL_R")
	)
	(segment
		(start 80.34528 -39.90975)
		(end 80.34528 -40.07485)
		(width 0.11684)
		(layer "In6.Cu")
		(net "SMB_INA230_3_3V3AUX_SCL_R")
	)
	(segment
		(start 81.221834 -39.033196)
		(end 80.34528 -39.90975)
		(width 0.11684)
		(layer "In6.Cu")
		(net "SMB_INA230_3_3V3AUX_SCL_R")
	)
	(segment
		(start 78.110334 -38.40988)
		(end 78.84541 -38.40988)
		(width 0.11684)
		(layer "In6.Cu")
		(net "SMB_INA230_3_3V3AUX_SCL_R")
	)
	(segment
		(start 81.08696 -38.733222)
		(end 81.221834 -38.868096)
		(width 0.11684)
		(layer "In6.Cu")
		(net "SMB_INA230_3_3V3AUX_SCL_R")
	)
	(segment
		(start 115.454684 -46.78426)
		(end 116.45392 -45.785024)
		(width 0.11684)
		(layer "In6.Cu")
		(net "SMB_INA230_3_3V3AUX_SCL_R")
	)
	(segment
		(start 79.745332 -39.474902)
		(end 79.880206 -39.609776)
		(width 0.11684)
		(layer "In6.Cu")
		(net "SMB_INA230_3_3V3AUX_SCL_R")
	)
	(segment
		(start 76.403454 -36.703)
		(end 78.110334 -38.40988)
		(width 0.11684)
		(layer "In6.Cu")
		(net "SMB_INA230_3_3V3AUX_SCL_R")
	)
	(segment
		(start 79.145384 -38.874954)
		(end 79.280258 -39.009828)
		(width 0.11684)
		(layer "In6.Cu")
		(net "SMB_INA230_3_3V3AUX_SCL_R")
	)
	(segment
		(start 80.487012 -38.133274)
		(end 80.621886 -38.268148)
		(width 0.11684)
		(layer "In6.Cu")
		(net "SMB_INA230_3_3V3AUX_SCL_R")
	)
	(segment
		(start 79.880206 -39.609776)
		(end 80.045306 -39.609776)
		(width 0.11684)
		(layer "In6.Cu")
		(net "SMB_INA230_3_3V3AUX_SCL_R")
	)
	(segment
		(start 87.537544 -42.225214)
		(end 101.303074 -42.225214)
		(width 0.11684)
		(layer "In6.Cu")
		(net "SMB_INA230_3_3V3AUX_SCL_R")
	)
	(segment
		(start 79.145384 -38.709854)
		(end 79.145384 -38.874954)
		(width 0.11684)
		(layer "In6.Cu")
		(net "SMB_INA230_3_3V3AUX_SCL_R")
	)
	(segment
		(start 116.45392 -45.785024)
		(end 128.060704 -45.785024)
		(width 0.11684)
		(layer "In6.Cu")
		(net "SMB_INA230_3_3V3AUX_SCL_R")
	)
	(segment
		(start 103.120698 -42.978578)
		(end 106.92638 -46.78426)
		(width 0.11684)
		(layer "In6.Cu")
		(net "SMB_INA230_3_3V3AUX_SCL_R")
	)
	(segment
		(start 79.445358 -39.009828)
		(end 80.321912 -38.133274)
		(width 0.11684)
		(layer "In6.Cu")
		(net "SMB_INA230_3_3V3AUX_SCL_R")
	)
	(segment
		(start 80.045306 -39.609776)
		(end 80.92186 -38.733222)
		(width 0.11684)
		(layer "In6.Cu")
		(net "SMB_INA230_3_3V3AUX_SCL_R")
	)
	(segment
		(start 82.68843 -42.418)
		(end 87.344758 -42.418)
		(width 0.11684)
		(layer "In6.Cu")
		(net "SMB_INA230_3_3V3AUX_SCL_R")
	)
	(segment
		(start 128.48844 -46.21276)
		(end 146.1262 -46.21276)
		(width 0.11684)
		(layer "In6.Cu")
		(net "SMB_INA230_3_3V3AUX_SCL_R")
	)
	(segment
		(start 81.221834 -38.868096)
		(end 81.221834 -39.033196)
		(width 0.11684)
		(layer "In6.Cu")
		(net "SMB_INA230_3_3V3AUX_SCL_R")
	)
	(segment
		(start 106.92638 -46.78426)
		(end 115.454684 -46.78426)
		(width 0.11684)
		(layer "In6.Cu")
		(net "SMB_INA230_3_3V3AUX_SCL_R")
	)
	(segment
		(start 213.060534 -52.545488)
		(end 213.060534 -53.177948)
		(width 0.10668)
		(layer "F.Cu")
		(net "SMB_INA230_2_3V3AUX_SDA_R1")
	)
	(segment
		(start 213.41588 -52.190142)
		(end 213.060534 -52.545488)
		(width 0.10668)
		(layer "F.Cu")
		(net "SMB_INA230_2_3V3AUX_SDA_R1")
	)
	(segment
		(start 213.41588 -51.037998)
		(end 213.41588 -52.190142)
		(width 0.10668)
		(layer "F.Cu")
		(net "SMB_INA230_2_3V3AUX_SDA_R1")
	)
	(segment
		(start 213.587838 -53.705252)
		(end 213.859618 -53.705252)
		(width 0.10668)
		(layer "F.Cu")
		(net "SMB_INA230_2_3V3AUX_SDA_R1")
	)
	(segment
		(start 213.060534 -53.177948)
		(end 213.587838 -53.705252)
		(width 0.10668)
		(layer "F.Cu")
		(net "SMB_INA230_2_3V3AUX_SDA_R1")
	)
	(via
		(at 213.060534 -52.545488)
		(size 0.508)
		(drill 0.254)
		(layers "F.Cu" "B.Cu")
		(net "SMB_INA230_2_3V3AUX_SDA_R1")
	)
	(segment
		(start 213.060534 -53.311552)
		(end 213.060534 -52.545488)
		(width 0.10668)
		(layer "B.Cu")
		(net "SMB_INA230_2_3V3AUX_SDA_R1")
	)
	(segment
		(start 213.79688 -54.047898)
		(end 213.060534 -53.311552)
		(width 0.10668)
		(layer "B.Cu")
		(net "SMB_INA230_2_3V3AUX_SDA_R1")
	)
	(segment
		(start 213.162134 -48.986948)
		(end 213.162134 -49.984152)
		(width 0.10668)
		(layer "F.Cu")
		(net "SMB_INA230_2_3V3AUX_SDA_R")
	)
	(segment
		(start 213.162134 -47.989998)
		(end 213.162134 -48.986948)
		(width 0.10668)
		(layer "F.Cu")
		(net "SMB_INA230_2_3V3AUX_SDA_R")
	)
	(segment
		(start 213.162134 -49.984152)
		(end 213.41588 -50.237898)
		(width 0.10668)
		(layer "F.Cu")
		(net "SMB_INA230_2_3V3AUX_SDA_R")
	)
	(segment
		(start 213.416134 -47.735998)
		(end 213.162134 -47.989998)
		(width 0.10668)
		(layer "F.Cu")
		(net "SMB_INA230_2_3V3AUX_SDA_R")
	)
	(via
		(at 213.162134 -48.986948)
		(size 0.762)
		(drill 0.381)
		(layers "F.Cu" "B.Cu")
		(net "SMB_INA230_2_3V3AUX_SDA_R")
	)
	(segment
		(start 214.509858 -51.536346)
		(end 214.509858 -52.061872)
		(width 0.10668)
		(layer "F.Cu")
		(net "SMB_INA230_2_3V3AUX_SCL_R1")
	)
	(segment
		(start 214.43188 -51.458368)
		(end 214.509858 -51.536346)
		(width 0.10668)
		(layer "F.Cu")
		(net "SMB_INA230_2_3V3AUX_SCL_R1")
	)
	(segment
		(start 214.509604 -53.055266)
		(end 214.509604 -52.062126)
		(width 0.10668)
		(layer "F.Cu")
		(net "SMB_INA230_2_3V3AUX_SCL_R1")
	)
	(segment
		(start 214.43188 -51.037998)
		(end 214.43188 -51.458368)
		(width 0.10668)
		(layer "F.Cu")
		(net "SMB_INA230_2_3V3AUX_SCL_R1")
	)
	(segment
		(start 214.509604 -52.062126)
		(end 214.509858 -52.061872)
		(width 0.10668)
		(layer "F.Cu")
		(net "SMB_INA230_2_3V3AUX_SCL_R1")
	)
	(via
		(at 214.509858 -52.061872)
		(size 0.508)
		(drill 0.254)
		(layers "F.Cu" "B.Cu")
		(net "SMB_INA230_2_3V3AUX_SCL_R1")
	)
	(segment
		(start 214.686134 -47.989998)
		(end 214.686134 -48.986948)
		(width 0.10668)
		(layer "F.Cu")
		(net "SMB_INA230_2_3V3AUX_SCL_R")
	)
	(segment
		(start 214.686134 -49.983644)
		(end 214.43188 -50.237898)
		(width 0.10668)
		(layer "F.Cu")
		(net "SMB_INA230_2_3V3AUX_SCL_R")
	)
	(segment
		(start 214.432134 -47.735998)
		(end 214.686134 -47.989998)
		(width 0.10668)
		(layer "F.Cu")
		(net "SMB_INA230_2_3V3AUX_SCL_R")
	)
	(segment
		(start 214.686134 -48.986948)
		(end 214.686134 -49.983644)
		(width 0.10668)
		(layer "F.Cu")
		(net "SMB_INA230_2_3V3AUX_SCL_R")
	)
	(via
		(at 214.686134 -48.986948)
		(size 0.762)
		(drill 0.381)
		(layers "F.Cu" "B.Cu")
		(net "SMB_INA230_2_3V3AUX_SCL_R")
	)
	(segment
		(start 443.10554 -95.872808)
		(end 442.52388 -95.291148)
		(width 0.10668)
		(layer "F.Cu")
		(net "SMB_INA230_1_3V3AUX_SDA_R1")
	)
	(segment
		(start 442.36513 -94.827598)
		(end 442.088016 -94.827598)
		(width 0.10668)
		(layer "F.Cu")
		(net "SMB_INA230_1_3V3AUX_SDA_R1")
	)
	(segment
		(start 442.52388 -94.986348)
		(end 442.36513 -94.827598)
		(width 0.10668)
		(layer "F.Cu")
		(net "SMB_INA230_1_3V3AUX_SDA_R1")
	)
	(segment
		(start 442.52388 -95.291148)
		(end 442.52388 -94.986348)
		(width 0.10668)
		(layer "F.Cu")
		(net "SMB_INA230_1_3V3AUX_SDA_R1")
	)
	(segment
		(start 444.79083 -95.872808)
		(end 443.10554 -95.872808)
		(width 0.10668)
		(layer "F.Cu")
		(net "SMB_INA230_1_3V3AUX_SDA_R1")
	)
	(via
		(at 443.10554 -95.872808)
		(size 0.508)
		(drill 0.254)
		(layers "F.Cu" "B.Cu")
		(net "SMB_INA230_1_3V3AUX_SDA_R1")
	)
	(segment
		(start 445.59093 -95.872808)
		(end 449.63588 -95.872808)
		(width 0.10668)
		(layer "F.Cu")
		(net "SMB_INA230_1_3V3AUX_SDA_R")
	)
	(segment
		(start 299.935646 -119.953786)
		(end 301.77232 -121.79046)
		(width 0.10668)
		(layer "F.Cu")
		(net "SMB_INA230_1_3V3AUX_SDA_R")
	)
	(segment
		(start 303.03216 -122.244866)
		(end 303.03216 -122.349514)
		(width 0.10668)
		(layer "F.Cu")
		(net "SMB_INA230_1_3V3AUX_SDA_R")
	)
	(segment
		(start 299.935646 -118.05031)
		(end 299.935646 -119.953786)
		(width 0.10668)
		(layer "F.Cu")
		(net "SMB_INA230_1_3V3AUX_SDA_R")
	)
	(segment
		(start 301.77232 -121.79046)
		(end 302.577754 -121.79046)
		(width 0.10668)
		(layer "F.Cu")
		(net "SMB_INA230_1_3V3AUX_SDA_R")
	)
	(segment
		(start 302.577754 -121.79046)
		(end 303.03216 -122.244866)
		(width 0.10668)
		(layer "F.Cu")
		(net "SMB_INA230_1_3V3AUX_SDA_R")
	)
	(via
		(at 303.03216 -122.349514)
		(size 0.508)
		(drill 0.254)
		(layers "F.Cu" "B.Cu")
		(net "SMB_INA230_1_3V3AUX_SDA_R")
	)
	(via
		(at 322.702682 -110.019592)
		(size 0.508)
		(drill 0.254)
		(layers "F.Cu" "B.Cu")
		(net "SMB_INA230_1_3V3AUX_SDA_R")
	)
	(via
		(at 449.63588 -95.872808)
		(size 0.508)
		(drill 0.254)
		(layers "F.Cu" "B.Cu")
		(net "SMB_INA230_1_3V3AUX_SDA_R")
	)
	(segment
		(start 317.063374 -114.810286)
		(end 321.854068 -110.019592)
		(width 0.10668)
		(layer "B.Cu")
		(net "SMB_INA230_1_3V3AUX_SDA_R")
	)
	(segment
		(start 302.90516 -122.222514)
		(end 302.90516 -116.18722)
		(width 0.10668)
		(layer "B.Cu")
		(net "SMB_INA230_1_3V3AUX_SDA_R")
	)
	(segment
		(start 304.282094 -114.810286)
		(end 317.063374 -114.810286)
		(width 0.10668)
		(layer "B.Cu")
		(net "SMB_INA230_1_3V3AUX_SDA_R")
	)
	(segment
		(start 303.03216 -122.349514)
		(end 302.90516 -122.222514)
		(width 0.10668)
		(layer "B.Cu")
		(net "SMB_INA230_1_3V3AUX_SDA_R")
	)
	(segment
		(start 302.90516 -116.18722)
		(end 304.282094 -114.810286)
		(width 0.10668)
		(layer "B.Cu")
		(net "SMB_INA230_1_3V3AUX_SDA_R")
	)
	(segment
		(start 321.854068 -110.019592)
		(end 322.702682 -110.019592)
		(width 0.10668)
		(layer "B.Cu")
		(net "SMB_INA230_1_3V3AUX_SDA_R")
	)
	(segment
		(start 330.547472 -117.841522)
		(end 322.725542 -110.019592)
		(width 0.11684)
		(layer "In2.Cu")
		(net "SMB_INA230_1_3V3AUX_SDA_R")
	)
	(segment
		(start 446.517268 -114.502946)
		(end 375.94921 -114.502946)
		(width 0.11684)
		(layer "In2.Cu")
		(net "SMB_INA230_1_3V3AUX_SDA_R")
	)
	(segment
		(start 449.099178 -96.40951)
		(end 449.099178 -111.921036)
		(width 0.11684)
		(layer "In2.Cu")
		(net "SMB_INA230_1_3V3AUX_SDA_R")
	)
	(segment
		(start 449.099178 -111.921036)
		(end 446.517268 -114.502946)
		(width 0.11684)
		(layer "In2.Cu")
		(net "SMB_INA230_1_3V3AUX_SDA_R")
	)
	(segment
		(start 322.725542 -110.019592)
		(end 322.702682 -110.019592)
		(width 0.11684)
		(layer "In2.Cu")
		(net "SMB_INA230_1_3V3AUX_SDA_R")
	)
	(segment
		(start 449.63588 -95.872808)
		(end 449.099178 -96.40951)
		(width 0.11684)
		(layer "In2.Cu")
		(net "SMB_INA230_1_3V3AUX_SDA_R")
	)
	(segment
		(start 375.94921 -114.502946)
		(end 372.610634 -117.841522)
		(width 0.11684)
		(layer "In2.Cu")
		(net "SMB_INA230_1_3V3AUX_SDA_R")
	)
	(segment
		(start 372.610634 -117.841522)
		(end 330.547472 -117.841522)
		(width 0.11684)
		(layer "In2.Cu")
		(net "SMB_INA230_1_3V3AUX_SDA_R")
	)
	(segment
		(start 444.77559 -97.254568)
		(end 444.79083 -97.269808)
		(width 0.10668)
		(layer "F.Cu")
		(net "SMB_INA230_1_3V3AUX_SCL_R1")
	)
	(segment
		(start 442.83122 -97.254568)
		(end 443.07252 -97.254568)
		(width 0.10668)
		(layer "F.Cu")
		(net "SMB_INA230_1_3V3AUX_SCL_R1")
	)
	(segment
		(start 441.43803 -95.477584)
		(end 441.43803 -95.861378)
		(width 0.10668)
		(layer "F.Cu")
		(net "SMB_INA230_1_3V3AUX_SCL_R1")
	)
	(segment
		(start 443.07252 -97.254568)
		(end 444.77559 -97.254568)
		(width 0.10668)
		(layer "F.Cu")
		(net "SMB_INA230_1_3V3AUX_SCL_R1")
	)
	(segment
		(start 441.43803 -95.861378)
		(end 442.83122 -97.254568)
		(width 0.10668)
		(layer "F.Cu")
		(net "SMB_INA230_1_3V3AUX_SCL_R1")
	)
	(via
		(at 443.07252 -97.254568)
		(size 0.508)
		(drill 0.254)
		(layers "F.Cu" "B.Cu")
		(net "SMB_INA230_1_3V3AUX_SCL_R1")
	)
	(segment
		(start 301.25416 -122.222514)
		(end 301.25416 -122.349514)
		(width 0.10668)
		(layer "F.Cu")
		(net "SMB_INA230_1_3V3AUX_SCL_R")
	)
	(segment
		(start 299.29836 -120.07596)
		(end 299.29836 -120.266714)
		(width 0.10668)
		(layer "F.Cu")
		(net "SMB_INA230_1_3V3AUX_SCL_R")
	)
	(segment
		(start 299.29836 -120.266714)
		(end 301.25416 -122.222514)
		(width 0.10668)
		(layer "F.Cu")
		(net "SMB_INA230_1_3V3AUX_SCL_R")
	)
	(segment
		(start 445.59093 -97.269808)
		(end 449.63588 -97.269808)
		(width 0.10668)
		(layer "F.Cu")
		(net "SMB_INA230_1_3V3AUX_SCL_R")
	)
	(via
		(at 322.702682 -110.654592)
		(size 0.508)
		(drill 0.254)
		(layers "F.Cu" "B.Cu")
		(net "SMB_INA230_1_3V3AUX_SCL_R")
	)
	(via
		(at 301.25416 -122.349514)
		(size 0.508)
		(drill 0.254)
		(layers "F.Cu" "B.Cu")
		(net "SMB_INA230_1_3V3AUX_SCL_R")
	)
	(via
		(at 449.63588 -97.269808)
		(size 0.508)
		(drill 0.254)
		(layers "F.Cu" "B.Cu")
		(net "SMB_INA230_1_3V3AUX_SCL_R")
	)
	(segment
		(start 306.505102 -116.35232)
		(end 305.127914 -117.729508)
		(width 0.10668)
		(layer "B.Cu")
		(net "SMB_INA230_1_3V3AUX_SCL_R")
	)
	(segment
		(start 321.77609 -110.654592)
		(end 316.078362 -116.35232)
		(width 0.10668)
		(layer "B.Cu")
		(net "SMB_INA230_1_3V3AUX_SCL_R")
	)
	(segment
		(start 305.127914 -121.871486)
		(end 303.78654 -123.21286)
		(width 0.10668)
		(layer "B.Cu")
		(net "SMB_INA230_1_3V3AUX_SCL_R")
	)
	(segment
		(start 303.78654 -123.21286)
		(end 302.117506 -123.21286)
		(width 0.10668)
		(layer "B.Cu")
		(net "SMB_INA230_1_3V3AUX_SCL_R")
	)
	(segment
		(start 322.702682 -110.654592)
		(end 321.77609 -110.654592)
		(width 0.10668)
		(layer "B.Cu")
		(net "SMB_INA230_1_3V3AUX_SCL_R")
	)
	(segment
		(start 302.117506 -123.21286)
		(end 301.25416 -122.349514)
		(width 0.10668)
		(layer "B.Cu")
		(net "SMB_INA230_1_3V3AUX_SCL_R")
	)
	(segment
		(start 305.127914 -117.729508)
		(end 305.127914 -121.871486)
		(width 0.10668)
		(layer "B.Cu")
		(net "SMB_INA230_1_3V3AUX_SCL_R")
	)
	(segment
		(start 316.078362 -116.35232)
		(end 306.505102 -116.35232)
		(width 0.10668)
		(layer "B.Cu")
		(net "SMB_INA230_1_3V3AUX_SCL_R")
	)
	(segment
		(start 449.63588 -97.269808)
		(end 449.63588 -111.980726)
		(width 0.11684)
		(layer "In2.Cu")
		(net "SMB_INA230_1_3V3AUX_SCL_R")
	)
	(segment
		(start 330.311252 -118.263162)
		(end 322.702682 -110.654592)
		(width 0.11684)
		(layer "In2.Cu")
		(net "SMB_INA230_1_3V3AUX_SCL_R")
	)
	(segment
		(start 446.69202 -114.924586)
		(end 376.123962 -114.924586)
		(width 0.11684)
		(layer "In2.Cu")
		(net "SMB_INA230_1_3V3AUX_SCL_R")
	)
	(segment
		(start 449.63588 -111.980726)
		(end 446.69202 -114.924586)
		(width 0.11684)
		(layer "In2.Cu")
		(net "SMB_INA230_1_3V3AUX_SCL_R")
	)
	(segment
		(start 376.123962 -114.924586)
		(end 372.785386 -118.263162)
		(width 0.11684)
		(layer "In2.Cu")
		(net "SMB_INA230_1_3V3AUX_SCL_R")
	)
	(segment
		(start 372.785386 -118.263162)
		(end 330.311252 -118.263162)
		(width 0.11684)
		(layer "In2.Cu")
		(net "SMB_INA230_1_3V3AUX_SCL_R")
	)
	(segment
		(start 299.276516 -115.098068)
		(end 299.276516 -114.845592)
		(width 0.10668)
		(layer "F.Cu")
		(net "SMB_FRU_3V3AUX_SDA")
	)
	(segment
		(start 295.981374 -116.253514)
		(end 297.086274 -115.148614)
		(width 0.10668)
		(layer "F.Cu")
		(net "SMB_FRU_3V3AUX_SDA")
	)
	(segment
		(start 318.296798 -115.108228)
		(end 318.883538 -115.108228)
		(width 0.10668)
		(layer "F.Cu")
		(net "SMB_FRU_3V3AUX_SDA")
	)
	(segment
		(start 314.967366 -108.52277)
		(end 315.576966 -108.52277)
		(width 0.10668)
		(layer "F.Cu")
		(net "SMB_FRU_3V3AUX_SDA")
	)
	(segment
		(start 318.883538 -115.108228)
		(end 319.058798 -115.283488)
		(width 0.10668)
		(layer "F.Cu")
		(net "SMB_FRU_3V3AUX_SDA")
	)
	(segment
		(start 298.887134 -114.45621)
		(end 297.778678 -114.45621)
		(width 0.10668)
		(layer "F.Cu")
		(net "SMB_FRU_3V3AUX_SDA")
	)
	(segment
		(start 299.276516 -114.845592)
		(end 298.887134 -114.45621)
		(width 0.10668)
		(layer "F.Cu")
		(net "SMB_FRU_3V3AUX_SDA")
	)
	(segment
		(start 297.778678 -114.45621)
		(end 297.086274 -115.148614)
		(width 0.10668)
		(layer "F.Cu")
		(net "SMB_FRU_3V3AUX_SDA")
	)
	(segment
		(start 294.821102 -116.253514)
		(end 295.981374 -116.253514)
		(width 0.10668)
		(layer "F.Cu")
		(net "SMB_FRU_3V3AUX_SDA")
	)
	(via
		(at 299.276516 -115.098068)
		(size 0.508)
		(drill 0.254)
		(layers "F.Cu" "B.Cu")
		(net "SMB_FRU_3V3AUX_SDA")
	)
	(via
		(at 315.576966 -108.52277)
		(size 0.508)
		(drill 0.254)
		(layers "F.Cu" "B.Cu")
		(net "SMB_FRU_3V3AUX_SDA")
	)
	(via
		(at 319.058798 -115.283488)
		(size 0.508)
		(drill 0.254)
		(layers "F.Cu" "B.Cu")
		(net "SMB_FRU_3V3AUX_SDA")
	)
	(segment
		(start 303.178972 -115.098068)
		(end 311.66816 -115.098068)
		(width 0.11684)
		(layer "In6.Cu")
		(net "SMB_FRU_3V3AUX_SDA")
	)
	(segment
		(start 299.799248 -115.6208)
		(end 302.65624 -115.6208)
		(width 0.11684)
		(layer "In6.Cu")
		(net "SMB_FRU_3V3AUX_SDA")
	)
	(segment
		(start 299.276516 -115.098068)
		(end 299.799248 -115.6208)
		(width 0.11684)
		(layer "In6.Cu")
		(net "SMB_FRU_3V3AUX_SDA")
	)
	(segment
		(start 316.05474 -115.79098)
		(end 316.747652 -115.098068)
		(width 0.11684)
		(layer "In6.Cu")
		(net "SMB_FRU_3V3AUX_SDA")
	)
	(segment
		(start 302.65624 -115.6208)
		(end 303.178972 -115.098068)
		(width 0.11684)
		(layer "In6.Cu")
		(net "SMB_FRU_3V3AUX_SDA")
	)
	(segment
		(start 318.873378 -115.098068)
		(end 319.058798 -115.283488)
		(width 0.11684)
		(layer "In6.Cu")
		(net "SMB_FRU_3V3AUX_SDA")
	)
	(segment
		(start 316.747652 -115.098068)
		(end 318.873378 -115.098068)
		(width 0.11684)
		(layer "In6.Cu")
		(net "SMB_FRU_3V3AUX_SDA")
	)
	(segment
		(start 311.66816 -115.098068)
		(end 312.361072 -115.79098)
		(width 0.11684)
		(layer "In6.Cu")
		(net "SMB_FRU_3V3AUX_SDA")
	)
	(segment
		(start 312.361072 -115.79098)
		(end 316.05474 -115.79098)
		(width 0.11684)
		(layer "In6.Cu")
		(net "SMB_FRU_3V3AUX_SDA")
	)
	(segment
		(start 317.80988 -110.755684)
		(end 317.80988 -114.03457)
		(width 0.11684)
		(layer "In11.Cu")
		(net "SMB_FRU_3V3AUX_SDA")
	)
	(segment
		(start 315.576966 -108.52277)
		(end 317.80988 -110.755684)
		(width 0.11684)
		(layer "In11.Cu")
		(net "SMB_FRU_3V3AUX_SDA")
	)
	(segment
		(start 317.80988 -114.03457)
		(end 319.058798 -115.283488)
		(width 0.11684)
		(layer "In11.Cu")
		(net "SMB_FRU_3V3AUX_SDA")
	)
	(segment
		(start 296.362374 -117.269514)
		(end 297.086274 -116.545614)
		(width 0.10668)
		(layer "F.Cu")
		(net "SMB_FRU_3V3AUX_SCL")
	)
	(segment
		(start 297.720258 -115.91163)
		(end 298.818554 -115.91163)
		(width 0.10668)
		(layer "F.Cu")
		(net "SMB_FRU_3V3AUX_SCL")
	)
	(segment
		(start 299.29836 -116.391436)
		(end 299.29836 -116.518436)
		(width 0.10668)
		(layer "F.Cu")
		(net "SMB_FRU_3V3AUX_SCL")
	)
	(segment
		(start 318.804798 -116.378228)
		(end 319.058798 -116.632228)
		(width 0.10668)
		(layer "F.Cu")
		(net "SMB_FRU_3V3AUX_SCL")
	)
	(segment
		(start 297.086274 -116.545614)
		(end 297.720258 -115.91163)
		(width 0.10668)
		(layer "F.Cu")
		(net "SMB_FRU_3V3AUX_SCL")
	)
	(segment
		(start 318.296798 -116.378228)
		(end 318.804798 -116.378228)
		(width 0.10668)
		(layer "F.Cu")
		(net "SMB_FRU_3V3AUX_SCL")
	)
	(segment
		(start 298.818554 -115.91163)
		(end 299.29836 -116.391436)
		(width 0.10668)
		(layer "F.Cu")
		(net "SMB_FRU_3V3AUX_SCL")
	)
	(segment
		(start 314.967366 -111.57077)
		(end 315.576966 -111.57077)
		(width 0.10668)
		(layer "F.Cu")
		(net "SMB_FRU_3V3AUX_SCL")
	)
	(segment
		(start 294.821102 -117.269514)
		(end 296.362374 -117.269514)
		(width 0.10668)
		(layer "F.Cu")
		(net "SMB_FRU_3V3AUX_SCL")
	)
	(via
		(at 319.058798 -116.632228)
		(size 0.508)
		(drill 0.254)
		(layers "F.Cu" "B.Cu")
		(net "SMB_FRU_3V3AUX_SCL")
	)
	(via
		(at 315.576966 -111.57077)
		(size 0.508)
		(drill 0.254)
		(layers "F.Cu" "B.Cu")
		(net "SMB_FRU_3V3AUX_SCL")
	)
	(via
		(at 299.29836 -116.518436)
		(size 0.508)
		(drill 0.254)
		(layers "F.Cu" "B.Cu")
		(net "SMB_FRU_3V3AUX_SCL")
	)
	(segment
		(start 318.802258 -116.375688)
		(end 299.441108 -116.375688)
		(width 0.11684)
		(layer "In6.Cu")
		(net "SMB_FRU_3V3AUX_SCL")
	)
	(segment
		(start 319.058798 -116.632228)
		(end 318.802258 -116.375688)
		(width 0.11684)
		(layer "In6.Cu")
		(net "SMB_FRU_3V3AUX_SCL")
	)
	(segment
		(start 299.441108 -116.375688)
		(end 299.29836 -116.518436)
		(width 0.11684)
		(layer "In6.Cu")
		(net "SMB_FRU_3V3AUX_SCL")
	)
	(segment
		(start 317.1444 -111.90986)
		(end 317.1444 -114.71783)
		(width 0.11684)
		(layer "In11.Cu")
		(net "SMB_FRU_3V3AUX_SCL")
	)
	(segment
		(start 317.1444 -114.71783)
		(end 319.058798 -116.632228)
		(width 0.11684)
		(layer "In11.Cu")
		(net "SMB_FRU_3V3AUX_SCL")
	)
	(segment
		(start 316.80531 -111.57077)
		(end 317.1444 -111.90986)
		(width 0.11684)
		(layer "In11.Cu")
		(net "SMB_FRU_3V3AUX_SCL")
	)
	(segment
		(start 315.576966 -111.57077)
		(end 316.80531 -111.57077)
		(width 0.11684)
		(layer "In11.Cu")
		(net "SMB_FRU_3V3AUX_SCL")
	)
	(segment
		(start 198.780908 -88.410796)
		(end 190.053468 -88.410796)
		(width 0.10668)
		(layer "F.Cu")
		(net "SMB_FAN_3V3AUX_R_SDA")
	)
	(segment
		(start 222.548958 -160.01619)
		(end 222.548958 -148.0439)
		(width 0.10668)
		(layer "F.Cu")
		(net "SMB_FAN_3V3AUX_R_SDA")
	)
	(segment
		(start 209.53857 -89.61628)
		(end 208.333086 -88.410796)
		(width 0.10668)
		(layer "F.Cu")
		(net "SMB_FAN_3V3AUX_R_SDA")
	)
	(segment
		(start 227.52939 -201.940414)
		(end 227.52939 -164.996622)
		(width 0.10668)
		(layer "F.Cu")
		(net "SMB_FAN_3V3AUX_R_SDA")
	)
	(segment
		(start 223.868996 -116.131848)
		(end 223.868996 -96.478344)
		(width 0.10668)
		(layer "F.Cu")
		(net "SMB_FAN_3V3AUX_R_SDA")
	)
	(segment
		(start 203.44511 -88.410796)
		(end 203.075286 -88.040972)
		(width 0.10668)
		(layer "F.Cu")
		(net "SMB_FAN_3V3AUX_R_SDA")
	)
	(segment
		(start 211.43468 -92.595446)
		(end 209.53857 -90.699336)
		(width 0.10668)
		(layer "F.Cu")
		(net "SMB_FAN_3V3AUX_R_SDA")
	)
	(segment
		(start 221.995492 -121.33961)
		(end 221.995492 -118.005352)
		(width 0.10668)
		(layer "F.Cu")
		(net "SMB_FAN_3V3AUX_R_SDA")
	)
	(segment
		(start 221.995492 -118.005352)
		(end 223.868996 -116.131848)
		(width 0.10668)
		(layer "F.Cu")
		(net "SMB_FAN_3V3AUX_R_SDA")
	)
	(segment
		(start 220.382084 -211.680552)
		(end 224.26422 -207.798416)
		(width 0.10668)
		(layer "F.Cu")
		(net "SMB_FAN_3V3AUX_R_SDA")
	)
	(segment
		(start 199.150732 -88.040972)
		(end 198.780908 -88.410796)
		(width 0.10668)
		(layer "F.Cu")
		(net "SMB_FAN_3V3AUX_R_SDA")
	)
	(segment
		(start 225.009202 -124.353574)
		(end 224.543366 -123.887738)
		(width 0.10668)
		(layer "F.Cu")
		(net "SMB_FAN_3V3AUX_R_SDA")
	)
	(segment
		(start 208.333086 -88.410796)
		(end 203.44511 -88.410796)
		(width 0.10668)
		(layer "F.Cu")
		(net "SMB_FAN_3V3AUX_R_SDA")
	)
	(segment
		(start 224.445576 -146.147282)
		(end 224.445576 -138.627866)
		(width 0.10668)
		(layer "F.Cu")
		(net "SMB_FAN_3V3AUX_R_SDA")
	)
	(segment
		(start 209.53857 -90.699336)
		(end 209.53857 -89.61628)
		(width 0.10668)
		(layer "F.Cu")
		(net "SMB_FAN_3V3AUX_R_SDA")
	)
	(segment
		(start 225.009202 -138.06424)
		(end 225.009202 -124.353574)
		(width 0.10668)
		(layer "F.Cu")
		(net "SMB_FAN_3V3AUX_R_SDA")
	)
	(segment
		(start 222.548958 -148.0439)
		(end 224.445576 -146.147282)
		(width 0.10668)
		(layer "F.Cu")
		(net "SMB_FAN_3V3AUX_R_SDA")
	)
	(segment
		(start 227.52939 -164.996622)
		(end 222.548958 -160.01619)
		(width 0.10668)
		(layer "F.Cu")
		(net "SMB_FAN_3V3AUX_R_SDA")
	)
	(segment
		(start 190.053468 -88.410796)
		(end 189.263528 -87.620856)
		(width 0.10668)
		(layer "F.Cu")
		(net "SMB_FAN_3V3AUX_R_SDA")
	)
	(segment
		(start 224.543366 -123.887738)
		(end 224.543366 -123.887484)
		(width 0.10668)
		(layer "F.Cu")
		(net "SMB_FAN_3V3AUX_R_SDA")
	)
	(segment
		(start 224.543366 -123.887484)
		(end 221.995492 -121.33961)
		(width 0.10668)
		(layer "F.Cu")
		(net "SMB_FAN_3V3AUX_R_SDA")
	)
	(segment
		(start 203.075286 -88.040972)
		(end 199.150732 -88.040972)
		(width 0.10668)
		(layer "F.Cu")
		(net "SMB_FAN_3V3AUX_R_SDA")
	)
	(segment
		(start 224.26422 -205.205584)
		(end 227.52939 -201.940414)
		(width 0.10668)
		(layer "F.Cu")
		(net "SMB_FAN_3V3AUX_R_SDA")
	)
	(segment
		(start 224.26422 -207.798416)
		(end 224.26422 -205.205584)
		(width 0.10668)
		(layer "F.Cu")
		(net "SMB_FAN_3V3AUX_R_SDA")
	)
	(segment
		(start 224.445576 -138.627866)
		(end 225.009202 -138.06424)
		(width 0.10668)
		(layer "F.Cu")
		(net "SMB_FAN_3V3AUX_R_SDA")
	)
	(segment
		(start 223.868996 -96.478344)
		(end 219.986098 -92.595446)
		(width 0.10668)
		(layer "F.Cu")
		(net "SMB_FAN_3V3AUX_R_SDA")
	)
	(segment
		(start 219.986098 -92.595446)
		(end 211.43468 -92.595446)
		(width 0.10668)
		(layer "F.Cu")
		(net "SMB_FAN_3V3AUX_R_SDA")
	)
	(via
		(at 174.449232 -417.449)
		(size 0.508)
		(drill 0.254)
		(layers "F.Cu" "B.Cu")
		(net "SMB_FAN_3V3AUX_R_SDA")
	)
	(via
		(at 156.25826 -18.931382)
		(size 0.508)
		(drill 0.254)
		(layers "F.Cu" "B.Cu")
		(net "SMB_FAN_3V3AUX_R_SDA")
	)
	(via
		(at 189.263528 -87.620856)
		(size 0.508)
		(drill 0.254)
		(layers "F.Cu" "B.Cu")
		(net "SMB_FAN_3V3AUX_R_SDA")
	)
	(via
		(at 170.729402 -396.468346)
		(size 0.508)
		(drill 0.254)
		(layers "F.Cu" "B.Cu")
		(net "SMB_FAN_3V3AUX_R_SDA")
	)
	(via
		(at 220.382084 -211.680552)
		(size 0.508)
		(drill 0.254)
		(layers "F.Cu" "B.Cu")
		(net "SMB_FAN_3V3AUX_R_SDA")
	)
	(segment
		(start 176.071022 -418.07638)
		(end 175.067722 -418.07638)
		(width 0.10668)
		(layer "B.Cu")
		(net "SMB_FAN_3V3AUX_R_SDA")
	)
	(segment
		(start 157.989778 -18.370042)
		(end 157.428438 -18.931382)
		(width 0.10668)
		(layer "B.Cu")
		(net "SMB_FAN_3V3AUX_R_SDA")
	)
	(segment
		(start 175.067722 -418.07638)
		(end 174.449232 -417.45789)
		(width 0.10668)
		(layer "B.Cu")
		(net "SMB_FAN_3V3AUX_R_SDA")
	)
	(segment
		(start 173.988476 -417.918646)
		(end 174.449232 -417.45789)
		(width 0.10668)
		(layer "B.Cu")
		(net "SMB_FAN_3V3AUX_R_SDA")
	)
	(segment
		(start 174.449232 -417.45789)
		(end 174.449232 -417.449)
		(width 0.10668)
		(layer "B.Cu")
		(net "SMB_FAN_3V3AUX_R_SDA")
	)
	(segment
		(start 173.583092 -418.35705)
		(end 173.988476 -417.951666)
		(width 0.10668)
		(layer "B.Cu")
		(net "SMB_FAN_3V3AUX_R_SDA")
	)
	(segment
		(start 157.428438 -18.931382)
		(end 156.25826 -18.931382)
		(width 0.10668)
		(layer "B.Cu")
		(net "SMB_FAN_3V3AUX_R_SDA")
	)
	(segment
		(start 173.988476 -417.951666)
		(end 173.988476 -417.918646)
		(width 0.10668)
		(layer "B.Cu")
		(net "SMB_FAN_3V3AUX_R_SDA")
	)
	(segment
		(start 201.76363 -367.84407)
		(end 195.050664 -367.84407)
		(width 0.11684)
		(layer "In4.Cu")
		(net "SMB_FAN_3V3AUX_R_SDA")
	)
	(segment
		(start 169.868088 -389.98652)
		(end 169.868088 -395.607032)
		(width 0.11684)
		(layer "In4.Cu")
		(net "SMB_FAN_3V3AUX_R_SDA")
	)
	(segment
		(start 161.696146 -21.472398)
		(end 159.794448 -19.5707)
		(width 0.11684)
		(layer "In4.Cu")
		(net "SMB_FAN_3V3AUX_R_SDA")
	)
	(segment
		(start 194.021202 -368.873532)
		(end 179.116736 -368.873532)
		(width 0.11684)
		(layer "In4.Cu")
		(net "SMB_FAN_3V3AUX_R_SDA")
	)
	(segment
		(start 219.33789 -326.558402)
		(end 219.33789 -327.595992)
		(width 0.11684)
		(layer "In4.Cu")
		(net "SMB_FAN_3V3AUX_R_SDA")
	)
	(segment
		(start 159.794448 -19.5707)
		(end 156.897578 -19.5707)
		(width 0.11684)
		(layer "In4.Cu")
		(net "SMB_FAN_3V3AUX_R_SDA")
	)
	(segment
		(start 219.33789 -327.595992)
		(end 223.350836 -331.608938)
		(width 0.11684)
		(layer "In4.Cu")
		(net "SMB_FAN_3V3AUX_R_SDA")
	)
	(segment
		(start 214.51062 -320.822066)
		(end 213.944708 -321.387978)
		(width 0.11684)
		(layer "In4.Cu")
		(net "SMB_FAN_3V3AUX_R_SDA")
	)
	(segment
		(start 213.944708 -321.387978)
		(end 213.944708 -322.194428)
		(width 0.11684)
		(layer "In4.Cu")
		(net "SMB_FAN_3V3AUX_R_SDA")
	)
	(segment
		(start 224.212912 -333.296514)
		(end 224.212912 -342.47328)
		(width 0.11684)
		(layer "In4.Cu")
		(net "SMB_FAN_3V3AUX_R_SDA")
	)
	(segment
		(start 206.83601 -362.77169)
		(end 201.76363 -367.84407)
		(width 0.11684)
		(layer "In4.Cu")
		(net "SMB_FAN_3V3AUX_R_SDA")
	)
	(segment
		(start 179.116736 -368.873532)
		(end 176.357788 -371.63248)
		(width 0.11684)
		(layer "In4.Cu")
		(net "SMB_FAN_3V3AUX_R_SDA")
	)
	(segment
		(start 176.357788 -371.63248)
		(end 172.4533 -371.63248)
		(width 0.11684)
		(layer "In4.Cu")
		(net "SMB_FAN_3V3AUX_R_SDA")
	)
	(segment
		(start 220.382084 -211.680552)
		(end 221.213426 -212.511894)
		(width 0.11684)
		(layer "In4.Cu")
		(net "SMB_FAN_3V3AUX_R_SDA")
	)
	(segment
		(start 170.311572 -384.664712)
		(end 170.311572 -389.543036)
		(width 0.11684)
		(layer "In4.Cu")
		(net "SMB_FAN_3V3AUX_R_SDA")
	)
	(segment
		(start 187.396882 -44.990766)
		(end 179.99329 -37.587174)
		(width 0.11684)
		(layer "In4.Cu")
		(net "SMB_FAN_3V3AUX_R_SDA")
	)
	(segment
		(start 156.897578 -19.5707)
		(end 156.25826 -18.931382)
		(width 0.11684)
		(layer "In4.Cu")
		(net "SMB_FAN_3V3AUX_R_SDA")
	)
	(segment
		(start 213.944708 -322.194428)
		(end 214.698326 -322.948046)
		(width 0.11684)
		(layer "In4.Cu")
		(net "SMB_FAN_3V3AUX_R_SDA")
	)
	(segment
		(start 166.894002 -33.36798)
		(end 161.696146 -28.170124)
		(width 0.11684)
		(layer "In4.Cu")
		(net "SMB_FAN_3V3AUX_R_SDA")
	)
	(segment
		(start 214.698326 -322.956428)
		(end 217.319098 -325.5772)
		(width 0.11684)
		(layer "In4.Cu")
		(net "SMB_FAN_3V3AUX_R_SDA")
	)
	(segment
		(start 189.263528 -87.620856)
		(end 187.396882 -85.75421)
		(width 0.11684)
		(layer "In4.Cu")
		(net "SMB_FAN_3V3AUX_R_SDA")
	)
	(segment
		(start 218.356688 -325.5772)
		(end 219.33789 -326.558402)
		(width 0.11684)
		(layer "In4.Cu")
		(net "SMB_FAN_3V3AUX_R_SDA")
	)
	(segment
		(start 214.698326 -322.948046)
		(end 214.698326 -322.956428)
		(width 0.11684)
		(layer "In4.Cu")
		(net "SMB_FAN_3V3AUX_R_SDA")
	)
	(segment
		(start 170.311572 -389.543036)
		(end 169.868088 -389.98652)
		(width 0.11684)
		(layer "In4.Cu")
		(net "SMB_FAN_3V3AUX_R_SDA")
	)
	(segment
		(start 206.83601 -359.850182)
		(end 206.83601 -362.77169)
		(width 0.11684)
		(layer "In4.Cu")
		(net "SMB_FAN_3V3AUX_R_SDA")
	)
	(segment
		(start 175.87722 -35.882072)
		(end 173.363128 -33.36798)
		(width 0.11684)
		(layer "In4.Cu")
		(net "SMB_FAN_3V3AUX_R_SDA")
	)
	(segment
		(start 179.99329 -37.587174)
		(end 175.87722 -35.882072)
		(width 0.11684)
		(layer "In4.Cu")
		(net "SMB_FAN_3V3AUX_R_SDA")
	)
	(segment
		(start 161.696146 -28.170124)
		(end 161.696146 -21.472398)
		(width 0.11684)
		(layer "In4.Cu")
		(net "SMB_FAN_3V3AUX_R_SDA")
	)
	(segment
		(start 166.46144 -377.62434)
		(end 166.46144 -380.81458)
		(width 0.11684)
		(layer "In4.Cu")
		(net "SMB_FAN_3V3AUX_R_SDA")
	)
	(segment
		(start 173.363128 -33.36798)
		(end 166.894002 -33.36798)
		(width 0.11684)
		(layer "In4.Cu")
		(net "SMB_FAN_3V3AUX_R_SDA")
	)
	(segment
		(start 187.396882 -85.75421)
		(end 187.396882 -44.990766)
		(width 0.11684)
		(layer "In4.Cu")
		(net "SMB_FAN_3V3AUX_R_SDA")
	)
	(segment
		(start 223.350836 -331.608938)
		(end 223.350836 -332.434438)
		(width 0.11684)
		(layer "In4.Cu")
		(net "SMB_FAN_3V3AUX_R_SDA")
	)
	(segment
		(start 166.46144 -380.81458)
		(end 170.311572 -384.664712)
		(width 0.11684)
		(layer "In4.Cu")
		(net "SMB_FAN_3V3AUX_R_SDA")
	)
	(segment
		(start 224.212912 -342.47328)
		(end 206.83601 -359.850182)
		(width 0.11684)
		(layer "In4.Cu")
		(net "SMB_FAN_3V3AUX_R_SDA")
	)
	(segment
		(start 221.213426 -212.511894)
		(end 221.213426 -253.807214)
		(width 0.11684)
		(layer "In4.Cu")
		(net "SMB_FAN_3V3AUX_R_SDA")
	)
	(segment
		(start 214.51062 -260.51002)
		(end 214.51062 -320.822066)
		(width 0.11684)
		(layer "In4.Cu")
		(net "SMB_FAN_3V3AUX_R_SDA")
	)
	(segment
		(start 221.213426 -253.807214)
		(end 214.51062 -260.51002)
		(width 0.11684)
		(layer "In4.Cu")
		(net "SMB_FAN_3V3AUX_R_SDA")
	)
	(segment
		(start 172.4533 -371.63248)
		(end 166.46144 -377.62434)
		(width 0.11684)
		(layer "In4.Cu")
		(net "SMB_FAN_3V3AUX_R_SDA")
	)
	(segment
		(start 195.050664 -367.84407)
		(end 194.021202 -368.873532)
		(width 0.11684)
		(layer "In4.Cu")
		(net "SMB_FAN_3V3AUX_R_SDA")
	)
	(segment
		(start 223.350836 -332.434438)
		(end 224.212912 -333.296514)
		(width 0.11684)
		(layer "In4.Cu")
		(net "SMB_FAN_3V3AUX_R_SDA")
	)
	(segment
		(start 169.868088 -395.607032)
		(end 170.729402 -396.468346)
		(width 0.11684)
		(layer "In4.Cu")
		(net "SMB_FAN_3V3AUX_R_SDA")
	)
	(segment
		(start 217.319098 -325.5772)
		(end 218.356688 -325.5772)
		(width 0.11684)
		(layer "In4.Cu")
		(net "SMB_FAN_3V3AUX_R_SDA")
	)
	(segment
		(start 173.406816 -398.4498)
		(end 173.406816 -398.2847)
		(width 0.11684)
		(layer "In11.Cu")
		(net "SMB_FAN_3V3AUX_R_SDA")
	)
	(segment
		(start 172.216064 -396.468346)
		(end 170.729402 -396.468346)
		(width 0.11684)
		(layer "In11.Cu")
		(net "SMB_FAN_3V3AUX_R_SDA")
	)
	(segment
		(start 174.591218 -399.0086)
		(end 174.36084 -399.238724)
		(width 0.11684)
		(layer "In11.Cu")
		(net "SMB_FAN_3V3AUX_R_SDA")
	)
	(segment
		(start 174.449232 -417.449)
		(end 174.449232 -417.163504)
		(width 0.11684)
		(layer "In11.Cu")
		(net "SMB_FAN_3V3AUX_R_SDA")
	)
	(segment
		(start 174.831756 -399.87474)
		(end 174.678848 -399.721832)
		(width 0.11684)
		(layer "In11.Cu")
		(net "SMB_FAN_3V3AUX_R_SDA")
	)
	(segment
		(start 174.36084 -399.238724)
		(end 174.19574 -399.238724)
		(width 0.11684)
		(layer "In11.Cu")
		(net "SMB_FAN_3V3AUX_R_SDA")
	)
	(segment
		(start 176.30394 -408.77363)
		(end 176.30394 -400.556222)
		(width 0.11684)
		(layer "In11.Cu")
		(net "SMB_FAN_3V3AUX_R_SDA")
	)
	(segment
		(start 175.314864 -400.357848)
		(end 175.314864 -400.192748)
		(width 0.11684)
		(layer "In11.Cu")
		(net "SMB_FAN_3V3AUX_R_SDA")
	)
	(segment
		(start 174.756318 -399.0086)
		(end 174.591218 -399.0086)
		(width 0.11684)
		(layer "In11.Cu")
		(net "SMB_FAN_3V3AUX_R_SDA")
	)
	(segment
		(start 174.909226 -399.326608)
		(end 174.909226 -399.161508)
		(width 0.11684)
		(layer "In11.Cu")
		(net "SMB_FAN_3V3AUX_R_SDA")
	)
	(segment
		(start 174.678848 -399.556732)
		(end 174.909226 -399.326608)
		(width 0.11684)
		(layer "In11.Cu")
		(net "SMB_FAN_3V3AUX_R_SDA")
	)
	(segment
		(start 175.467772 -400.510756)
		(end 175.314864 -400.357848)
		(width 0.11684)
		(layer "In11.Cu")
		(net "SMB_FAN_3V3AUX_R_SDA")
	)
	(segment
		(start 175.545242 -399.962624)
		(end 175.545242 -399.797524)
		(width 0.11684)
		(layer "In11.Cu")
		(net "SMB_FAN_3V3AUX_R_SDA")
	)
	(segment
		(start 176.30394 -400.556222)
		(end 176.02835 -400.280632)
		(width 0.11684)
		(layer "In11.Cu")
		(net "SMB_FAN_3V3AUX_R_SDA")
	)
	(segment
		(start 173.637194 -397.889476)
		(end 172.216064 -396.468346)
		(width 0.11684)
		(layer "In11.Cu")
		(net "SMB_FAN_3V3AUX_R_SDA")
	)
	(segment
		(start 173.637194 -398.054576)
		(end 173.637194 -397.889476)
		(width 0.11684)
		(layer "In11.Cu")
		(net "SMB_FAN_3V3AUX_R_SDA")
	)
	(segment
		(start 176.02835 -400.280632)
		(end 175.86325 -400.280632)
		(width 0.11684)
		(layer "In11.Cu")
		(net "SMB_FAN_3V3AUX_R_SDA")
	)
	(segment
		(start 174.909226 -399.161508)
		(end 174.756318 -399.0086)
		(width 0.11684)
		(layer "In11.Cu")
		(net "SMB_FAN_3V3AUX_R_SDA")
	)
	(segment
		(start 174.27321 -398.525492)
		(end 174.120302 -398.372584)
		(width 0.11684)
		(layer "In11.Cu")
		(net "SMB_FAN_3V3AUX_R_SDA")
	)
	(segment
		(start 174.19574 -399.238724)
		(end 174.042832 -399.085816)
		(width 0.11684)
		(layer "In11.Cu")
		(net "SMB_FAN_3V3AUX_R_SDA")
	)
	(segment
		(start 174.27321 -398.690592)
		(end 174.27321 -398.525492)
		(width 0.11684)
		(layer "In11.Cu")
		(net "SMB_FAN_3V3AUX_R_SDA")
	)
	(segment
		(start 174.042832 -398.920716)
		(end 174.27321 -398.690592)
		(width 0.11684)
		(layer "In11.Cu")
		(net "SMB_FAN_3V3AUX_R_SDA")
	)
	(segment
		(start 175.314864 -400.192748)
		(end 175.545242 -399.962624)
		(width 0.11684)
		(layer "In11.Cu")
		(net "SMB_FAN_3V3AUX_R_SDA")
	)
	(segment
		(start 173.559724 -398.602708)
		(end 173.406816 -398.4498)
		(width 0.11684)
		(layer "In11.Cu")
		(net "SMB_FAN_3V3AUX_R_SDA")
	)
	(segment
		(start 173.611286 -416.325558)
		(end 173.611286 -411.466284)
		(width 0.11684)
		(layer "In11.Cu")
		(net "SMB_FAN_3V3AUX_R_SDA")
	)
	(segment
		(start 173.611286 -411.466284)
		(end 176.30394 -408.77363)
		(width 0.11684)
		(layer "In11.Cu")
		(net "SMB_FAN_3V3AUX_R_SDA")
	)
	(segment
		(start 174.120302 -398.372584)
		(end 173.955202 -398.372584)
		(width 0.11684)
		(layer "In11.Cu")
		(net "SMB_FAN_3V3AUX_R_SDA")
	)
	(segment
		(start 175.227234 -399.644616)
		(end 174.996856 -399.87474)
		(width 0.11684)
		(layer "In11.Cu")
		(net "SMB_FAN_3V3AUX_R_SDA")
	)
	(segment
		(start 175.632872 -400.510756)
		(end 175.467772 -400.510756)
		(width 0.11684)
		(layer "In11.Cu")
		(net "SMB_FAN_3V3AUX_R_SDA")
	)
	(segment
		(start 175.392334 -399.644616)
		(end 175.227234 -399.644616)
		(width 0.11684)
		(layer "In11.Cu")
		(net "SMB_FAN_3V3AUX_R_SDA")
	)
	(segment
		(start 174.042832 -399.085816)
		(end 174.042832 -398.920716)
		(width 0.11684)
		(layer "In11.Cu")
		(net "SMB_FAN_3V3AUX_R_SDA")
	)
	(segment
		(start 175.545242 -399.797524)
		(end 175.392334 -399.644616)
		(width 0.11684)
		(layer "In11.Cu")
		(net "SMB_FAN_3V3AUX_R_SDA")
	)
	(segment
		(start 175.86325 -400.280632)
		(end 175.632872 -400.510756)
		(width 0.11684)
		(layer "In11.Cu")
		(net "SMB_FAN_3V3AUX_R_SDA")
	)
	(segment
		(start 173.406816 -398.2847)
		(end 173.637194 -398.054576)
		(width 0.11684)
		(layer "In11.Cu")
		(net "SMB_FAN_3V3AUX_R_SDA")
	)
	(segment
		(start 174.996856 -399.87474)
		(end 174.831756 -399.87474)
		(width 0.11684)
		(layer "In11.Cu")
		(net "SMB_FAN_3V3AUX_R_SDA")
	)
	(segment
		(start 174.678848 -399.721832)
		(end 174.678848 -399.556732)
		(width 0.11684)
		(layer "In11.Cu")
		(net "SMB_FAN_3V3AUX_R_SDA")
	)
	(segment
		(start 173.724824 -398.602708)
		(end 173.559724 -398.602708)
		(width 0.11684)
		(layer "In11.Cu")
		(net "SMB_FAN_3V3AUX_R_SDA")
	)
	(segment
		(start 173.955202 -398.372584)
		(end 173.724824 -398.602708)
		(width 0.11684)
		(layer "In11.Cu")
		(net "SMB_FAN_3V3AUX_R_SDA")
	)
	(segment
		(start 174.449232 -417.163504)
		(end 173.611286 -416.325558)
		(width 0.11684)
		(layer "In11.Cu")
		(net "SMB_FAN_3V3AUX_R_SDA")
	)
	(segment
		(start 203.586334 -88.070436)
		(end 203.192126 -87.676228)
		(width 0.10668)
		(layer "F.Cu")
		(net "SMB_FAN_3V3AUX_R_SCL")
	)
	(segment
		(start 224.209356 -116.273072)
		(end 224.209356 -96.33712)
		(width 0.10668)
		(layer "F.Cu")
		(net "SMB_FAN_3V3AUX_R_SCL")
	)
	(segment
		(start 224.60458 -205.347062)
		(end 227.86975 -202.081892)
		(width 0.10668)
		(layer "F.Cu")
		(net "SMB_FAN_3V3AUX_R_SCL")
	)
	(segment
		(start 213.083394 -92.222828)
		(end 208.931002 -88.070436)
		(width 0.10668)
		(layer "F.Cu")
		(net "SMB_FAN_3V3AUX_R_SCL")
	)
	(segment
		(start 220.095064 -92.222828)
		(end 213.083394 -92.222828)
		(width 0.10668)
		(layer "F.Cu")
		(net "SMB_FAN_3V3AUX_R_SCL")
	)
	(segment
		(start 208.931002 -88.070436)
		(end 203.586334 -88.070436)
		(width 0.10668)
		(layer "F.Cu")
		(net "SMB_FAN_3V3AUX_R_SCL")
	)
	(segment
		(start 224.209356 -96.33712)
		(end 220.095064 -92.222828)
		(width 0.10668)
		(layer "F.Cu")
		(net "SMB_FAN_3V3AUX_R_SCL")
	)
	(segment
		(start 227.86975 -164.855398)
		(end 222.889318 -159.874966)
		(width 0.10668)
		(layer "F.Cu")
		(net "SMB_FAN_3V3AUX_R_SCL")
	)
	(segment
		(start 195.878704 -88.070436)
		(end 195.772024 -87.963756)
		(width 0.10668)
		(layer "F.Cu")
		(net "SMB_FAN_3V3AUX_R_SCL")
	)
	(segment
		(start 195.332604 -87.963756)
		(end 195.225924 -88.070436)
		(width 0.10668)
		(layer "F.Cu")
		(net "SMB_FAN_3V3AUX_R_SCL")
	)
	(segment
		(start 195.772024 -87.963756)
		(end 195.772024 -87.501984)
		(width 0.10668)
		(layer "F.Cu")
		(net "SMB_FAN_3V3AUX_R_SCL")
	)
	(segment
		(start 195.225924 -88.070436)
		(end 194.647566 -88.070436)
		(width 0.10668)
		(layer "F.Cu")
		(net "SMB_FAN_3V3AUX_R_SCL")
	)
	(segment
		(start 225.396552 -138.158728)
		(end 225.396552 -124.25934)
		(width 0.10668)
		(layer "F.Cu")
		(net "SMB_FAN_3V3AUX_R_SCL")
	)
	(segment
		(start 224.785936 -123.64847)
		(end 222.335852 -121.198386)
		(width 0.10668)
		(layer "F.Cu")
		(net "SMB_FAN_3V3AUX_R_SCL")
	)
	(segment
		(start 196.211444 -87.963756)
		(end 196.104764 -88.070436)
		(width 0.10668)
		(layer "F.Cu")
		(net "SMB_FAN_3V3AUX_R_SCL")
	)
	(segment
		(start 224.785936 -146.288506)
		(end 224.785936 -138.769344)
		(width 0.10668)
		(layer "F.Cu")
		(net "SMB_FAN_3V3AUX_R_SCL")
	)
	(segment
		(start 196.318124 -87.395304)
		(end 196.211444 -87.501984)
		(width 0.10668)
		(layer "F.Cu")
		(net "SMB_FAN_3V3AUX_R_SCL")
	)
	(segment
		(start 220.383354 -212.55228)
		(end 224.60458 -208.331054)
		(width 0.10668)
		(layer "F.Cu")
		(net "SMB_FAN_3V3AUX_R_SCL")
	)
	(segment
		(start 195.332604 -87.501984)
		(end 195.332604 -87.963756)
		(width 0.10668)
		(layer "F.Cu")
		(net "SMB_FAN_3V3AUX_R_SCL")
	)
	(segment
		(start 224.60458 -208.331054)
		(end 224.60458 -205.347062)
		(width 0.10668)
		(layer "F.Cu")
		(net "SMB_FAN_3V3AUX_R_SCL")
	)
	(segment
		(start 198.639684 -88.070436)
		(end 196.757544 -88.070436)
		(width 0.10668)
		(layer "F.Cu")
		(net "SMB_FAN_3V3AUX_R_SCL")
	)
	(segment
		(start 196.650864 -87.963756)
		(end 196.650864 -87.501984)
		(width 0.10668)
		(layer "F.Cu")
		(net "SMB_FAN_3V3AUX_R_SCL")
	)
	(segment
		(start 190.699644 -86.753192)
		(end 190.183008 -87.269828)
		(width 0.10668)
		(layer "F.Cu")
		(net "SMB_FAN_3V3AUX_R_SCL")
	)
	(segment
		(start 222.889318 -159.874966)
		(end 222.889318 -148.185124)
		(width 0.10668)
		(layer "F.Cu")
		(net "SMB_FAN_3V3AUX_R_SCL")
	)
	(segment
		(start 227.86975 -202.081892)
		(end 227.86975 -164.855398)
		(width 0.10668)
		(layer "F.Cu")
		(net "SMB_FAN_3V3AUX_R_SCL")
	)
	(segment
		(start 199.033892 -87.676228)
		(end 198.639684 -88.070436)
		(width 0.10668)
		(layer "F.Cu")
		(net "SMB_FAN_3V3AUX_R_SCL")
	)
	(segment
		(start 225.396552 -124.25934)
		(end 224.785936 -123.648724)
		(width 0.10668)
		(layer "F.Cu")
		(net "SMB_FAN_3V3AUX_R_SCL")
	)
	(segment
		(start 222.335852 -121.198386)
		(end 222.335852 -118.146576)
		(width 0.10668)
		(layer "F.Cu")
		(net "SMB_FAN_3V3AUX_R_SCL")
	)
	(segment
		(start 222.889318 -148.185124)
		(end 224.785936 -146.288506)
		(width 0.10668)
		(layer "F.Cu")
		(net "SMB_FAN_3V3AUX_R_SCL")
	)
	(segment
		(start 196.544184 -87.395304)
		(end 196.318124 -87.395304)
		(width 0.10668)
		(layer "F.Cu")
		(net "SMB_FAN_3V3AUX_R_SCL")
	)
	(segment
		(start 194.647566 -88.070436)
		(end 193.330322 -86.753192)
		(width 0.10668)
		(layer "F.Cu")
		(net "SMB_FAN_3V3AUX_R_SCL")
	)
	(segment
		(start 196.650864 -87.501984)
		(end 196.544184 -87.395304)
		(width 0.10668)
		(layer "F.Cu")
		(net "SMB_FAN_3V3AUX_R_SCL")
	)
	(segment
		(start 195.439284 -87.395304)
		(end 195.332604 -87.501984)
		(width 0.10668)
		(layer "F.Cu")
		(net "SMB_FAN_3V3AUX_R_SCL")
	)
	(segment
		(start 222.335852 -118.146576)
		(end 224.209356 -116.273072)
		(width 0.10668)
		(layer "F.Cu")
		(net "SMB_FAN_3V3AUX_R_SCL")
	)
	(segment
		(start 196.211444 -87.501984)
		(end 196.211444 -87.963756)
		(width 0.10668)
		(layer "F.Cu")
		(net "SMB_FAN_3V3AUX_R_SCL")
	)
	(segment
		(start 196.757544 -88.070436)
		(end 196.650864 -87.963756)
		(width 0.10668)
		(layer "F.Cu")
		(net "SMB_FAN_3V3AUX_R_SCL")
	)
	(segment
		(start 203.192126 -87.676228)
		(end 199.033892 -87.676228)
		(width 0.10668)
		(layer "F.Cu")
		(net "SMB_FAN_3V3AUX_R_SCL")
	)
	(segment
		(start 224.785936 -123.648724)
		(end 224.785936 -123.64847)
		(width 0.10668)
		(layer "F.Cu")
		(net "SMB_FAN_3V3AUX_R_SCL")
	)
	(segment
		(start 195.772024 -87.501984)
		(end 195.665344 -87.395304)
		(width 0.10668)
		(layer "F.Cu")
		(net "SMB_FAN_3V3AUX_R_SCL")
	)
	(segment
		(start 195.665344 -87.395304)
		(end 195.439284 -87.395304)
		(width 0.10668)
		(layer "F.Cu")
		(net "SMB_FAN_3V3AUX_R_SCL")
	)
	(segment
		(start 224.785936 -138.769344)
		(end 225.396552 -138.158728)
		(width 0.10668)
		(layer "F.Cu")
		(net "SMB_FAN_3V3AUX_R_SCL")
	)
	(segment
		(start 193.330322 -86.753192)
		(end 190.699644 -86.753192)
		(width 0.10668)
		(layer "F.Cu")
		(net "SMB_FAN_3V3AUX_R_SCL")
	)
	(segment
		(start 196.104764 -88.070436)
		(end 195.878704 -88.070436)
		(width 0.10668)
		(layer "F.Cu")
		(net "SMB_FAN_3V3AUX_R_SCL")
	)
	(via
		(at 178.705002 -417.605464)
		(size 0.508)
		(drill 0.254)
		(layers "F.Cu" "B.Cu")
		(net "SMB_FAN_3V3AUX_R_SCL")
	)
	(via
		(at 159.61614 -11.526774)
		(size 0.508)
		(drill 0.254)
		(layers "F.Cu" "B.Cu")
		(net "SMB_FAN_3V3AUX_R_SCL")
	)
	(via
		(at 190.183008 -87.269828)
		(size 0.508)
		(drill 0.254)
		(layers "F.Cu" "B.Cu")
		(net "SMB_FAN_3V3AUX_R_SCL")
	)
	(via
		(at 170.059096 -396.4559)
		(size 0.508)
		(drill 0.254)
		(layers "F.Cu" "B.Cu")
		(net "SMB_FAN_3V3AUX_R_SCL")
	)
	(via
		(at 220.383354 -212.55228)
		(size 0.508)
		(drill 0.254)
		(layers "F.Cu" "B.Cu")
		(net "SMB_FAN_3V3AUX_R_SCL")
	)
	(segment
		(start 181.501796 -418.023548)
		(end 182.225188 -418.023548)
		(width 0.10668)
		(layer "B.Cu")
		(net "SMB_FAN_3V3AUX_R_SCL")
	)
	(segment
		(start 180.535834 -418.07638)
		(end 181.448964 -418.07638)
		(width 0.10668)
		(layer "B.Cu")
		(net "SMB_FAN_3V3AUX_R_SCL")
	)
	(segment
		(start 180.535834 -418.07638)
		(end 179.175918 -418.07638)
		(width 0.10668)
		(layer "B.Cu")
		(net "SMB_FAN_3V3AUX_R_SCL")
	)
	(segment
		(start 179.175918 -418.07638)
		(end 178.705002 -417.605464)
		(width 0.10668)
		(layer "B.Cu")
		(net "SMB_FAN_3V3AUX_R_SCL")
	)
	(segment
		(start 181.448964 -418.07638)
		(end 181.501796 -418.023548)
		(width 0.10668)
		(layer "B.Cu")
		(net "SMB_FAN_3V3AUX_R_SCL")
	)
	(segment
		(start 159.61614 -11.543284)
		(end 159.61614 -11.526774)
		(width 0.10668)
		(layer "B.Cu")
		(net "SMB_FAN_3V3AUX_R_SCL")
	)
	(segment
		(start 159.30118 -13.127228)
		(end 159.61614 -11.543284)
		(width 0.10668)
		(layer "B.Cu")
		(net "SMB_FAN_3V3AUX_R_SCL")
	)
	(segment
		(start 160.480756 -14.86789)
		(end 162.398456 -19.497548)
		(width 0.11684)
		(layer "In4.Cu")
		(net "SMB_FAN_3V3AUX_R_SCL")
	)
	(segment
		(start 222.929196 -331.959712)
		(end 222.929196 -332.60919)
		(width 0.11684)
		(layer "In4.Cu")
		(net "SMB_FAN_3V3AUX_R_SCL")
	)
	(segment
		(start 165.98392 -383.39776)
		(end 166.82974 -384.24358)
		(width 0.11684)
		(layer "In4.Cu")
		(net "SMB_FAN_3V3AUX_R_SCL")
	)
	(segment
		(start 159.61614 -11.526774)
		(end 160.00095 -12.455652)
		(width 0.11684)
		(layer "In4.Cu")
		(net "SMB_FAN_3V3AUX_R_SCL")
	)
	(segment
		(start 223.791272 -333.471266)
		(end 223.791272 -342.079072)
		(width 0.11684)
		(layer "In4.Cu")
		(net "SMB_FAN_3V3AUX_R_SCL")
	)
	(segment
		(start 187.935362 -80.454246)
		(end 187.818522 -80.571086)
		(width 0.11684)
		(layer "In4.Cu")
		(net "SMB_FAN_3V3AUX_R_SCL")
	)
	(segment
		(start 220.740224 -253.604776)
		(end 214.08898 -260.25602)
		(width 0.11684)
		(layer "In4.Cu")
		(net "SMB_FAN_3V3AUX_R_SCL")
	)
	(segment
		(start 180.23332 -37.23005)
		(end 187.818522 -44.815252)
		(width 0.11684)
		(layer "In4.Cu")
		(net "SMB_FAN_3V3AUX_R_SCL")
	)
	(segment
		(start 165.98392 -377.37796)
		(end 165.98392 -383.39776)
		(width 0.11684)
		(layer "In4.Cu")
		(net "SMB_FAN_3V3AUX_R_SCL")
	)
	(segment
		(start 169.36974 -389.820404)
		(end 169.36974 -393.488672)
		(width 0.11684)
		(layer "In4.Cu")
		(net "SMB_FAN_3V3AUX_R_SCL")
	)
	(segment
		(start 222.929196 -332.60919)
		(end 223.791272 -333.471266)
		(width 0.11684)
		(layer "In4.Cu")
		(net "SMB_FAN_3V3AUX_R_SCL")
	)
	(segment
		(start 166.82974 -386.45846)
		(end 168.6179 -388.24662)
		(width 0.11684)
		(layer "In4.Cu")
		(net "SMB_FAN_3V3AUX_R_SCL")
	)
	(segment
		(start 176.184052 -35.552634)
		(end 180.23332 -37.23005)
		(width 0.11684)
		(layer "In4.Cu")
		(net "SMB_FAN_3V3AUX_R_SCL")
	)
	(segment
		(start 187.935362 -79.572866)
		(end 188.893196 -79.572866)
		(width 0.11684)
		(layer "In4.Cu")
		(net "SMB_FAN_3V3AUX_R_SCL")
	)
	(segment
		(start 169.36974 -393.488672)
		(end 168.667684 -394.190728)
		(width 0.11684)
		(layer "In4.Cu")
		(net "SMB_FAN_3V3AUX_R_SCL")
	)
	(segment
		(start 167.108632 -32.94634)
		(end 173.577758 -32.94634)
		(width 0.11684)
		(layer "In4.Cu")
		(net "SMB_FAN_3V3AUX_R_SCL")
	)
	(segment
		(start 166.82974 -384.24358)
		(end 166.82974 -386.45846)
		(width 0.11684)
		(layer "In4.Cu")
		(net "SMB_FAN_3V3AUX_R_SCL")
	)
	(segment
		(start 168.667684 -395.064488)
		(end 170.059096 -396.4559)
		(width 0.11684)
		(layer "In4.Cu")
		(net "SMB_FAN_3V3AUX_R_SCL")
	)
	(segment
		(start 213.51367 -320.883534)
		(end 213.51367 -322.544186)
		(width 0.11684)
		(layer "In4.Cu")
		(net "SMB_FAN_3V3AUX_R_SCL")
	)
	(segment
		(start 176.18456 -371.17528)
		(end 172.1866 -371.17528)
		(width 0.11684)
		(layer "In4.Cu")
		(net "SMB_FAN_3V3AUX_R_SCL")
	)
	(segment
		(start 187.818522 -79.456026)
		(end 187.935362 -79.572866)
		(width 0.11684)
		(layer "In4.Cu")
		(net "SMB_FAN_3V3AUX_R_SCL")
	)
	(segment
		(start 193.81851 -368.4016)
		(end 178.95824 -368.4016)
		(width 0.11684)
		(layer "In4.Cu")
		(net "SMB_FAN_3V3AUX_R_SCL")
	)
	(segment
		(start 201.363834 -367.42243)
		(end 194.79768 -367.42243)
		(width 0.11684)
		(layer "In4.Cu")
		(net "SMB_FAN_3V3AUX_R_SCL")
	)
	(segment
		(start 214.08898 -260.25602)
		(end 214.08898 -320.308224)
		(width 0.11684)
		(layer "In4.Cu")
		(net "SMB_FAN_3V3AUX_R_SCL")
	)
	(segment
		(start 178.95824 -368.4016)
		(end 176.18456 -371.17528)
		(width 0.11684)
		(layer "In4.Cu")
		(net "SMB_FAN_3V3AUX_R_SCL")
	)
	(segment
		(start 172.1866 -371.17528)
		(end 165.98392 -377.37796)
		(width 0.11684)
		(layer "In4.Cu")
		(net "SMB_FAN_3V3AUX_R_SCL")
	)
	(segment
		(start 188.893196 -79.572866)
		(end 189.010036 -79.689706)
		(width 0.11684)
		(layer "In4.Cu")
		(net "SMB_FAN_3V3AUX_R_SCL")
	)
	(segment
		(start 220.383354 -212.55228)
		(end 220.740224 -212.90915)
		(width 0.11684)
		(layer "In4.Cu")
		(net "SMB_FAN_3V3AUX_R_SCL")
	)
	(segment
		(start 187.818522 -80.571086)
		(end 187.818522 -84.905342)
		(width 0.11684)
		(layer "In4.Cu")
		(net "SMB_FAN_3V3AUX_R_SCL")
	)
	(segment
		(start 220.740224 -212.90915)
		(end 220.740224 -253.604776)
		(width 0.11684)
		(layer "In4.Cu")
		(net "SMB_FAN_3V3AUX_R_SCL")
	)
	(segment
		(start 189.010036 -79.689706)
		(end 189.010036 -80.337406)
		(width 0.11684)
		(layer "In4.Cu")
		(net "SMB_FAN_3V3AUX_R_SCL")
	)
	(segment
		(start 206.179166 -362.607098)
		(end 201.363834 -367.42243)
		(width 0.11684)
		(layer "In4.Cu")
		(net "SMB_FAN_3V3AUX_R_SCL")
	)
	(segment
		(start 160.00095 -12.455652)
		(end 160.480756 -14.86789)
		(width 0.11684)
		(layer "In4.Cu")
		(net "SMB_FAN_3V3AUX_R_SCL")
	)
	(segment
		(start 223.791272 -342.079072)
		(end 206.179166 -359.691178)
		(width 0.11684)
		(layer "In4.Cu")
		(net "SMB_FAN_3V3AUX_R_SCL")
	)
	(segment
		(start 187.818522 -84.905342)
		(end 190.183008 -87.269828)
		(width 0.11684)
		(layer "In4.Cu")
		(net "SMB_FAN_3V3AUX_R_SCL")
	)
	(segment
		(start 206.179166 -359.691178)
		(end 206.179166 -362.607098)
		(width 0.11684)
		(layer "In4.Cu")
		(net "SMB_FAN_3V3AUX_R_SCL")
	)
	(segment
		(start 168.667684 -394.190728)
		(end 168.667684 -395.064488)
		(width 0.11684)
		(layer "In4.Cu")
		(net "SMB_FAN_3V3AUX_R_SCL")
	)
	(segment
		(start 214.08898 -320.308224)
		(end 213.51367 -320.883534)
		(width 0.11684)
		(layer "In4.Cu")
		(net "SMB_FAN_3V3AUX_R_SCL")
	)
	(segment
		(start 173.577758 -32.94634)
		(end 176.184052 -35.552634)
		(width 0.11684)
		(layer "In4.Cu")
		(net "SMB_FAN_3V3AUX_R_SCL")
	)
	(segment
		(start 162.398456 -19.497548)
		(end 162.398456 -28.236164)
		(width 0.11684)
		(layer "In4.Cu")
		(net "SMB_FAN_3V3AUX_R_SCL")
	)
	(segment
		(start 168.6179 -389.068564)
		(end 169.36974 -389.820404)
		(width 0.11684)
		(layer "In4.Cu")
		(net "SMB_FAN_3V3AUX_R_SCL")
	)
	(segment
		(start 162.398456 -28.236164)
		(end 167.108632 -32.94634)
		(width 0.11684)
		(layer "In4.Cu")
		(net "SMB_FAN_3V3AUX_R_SCL")
	)
	(segment
		(start 213.51367 -322.544186)
		(end 222.929196 -331.959712)
		(width 0.11684)
		(layer "In4.Cu")
		(net "SMB_FAN_3V3AUX_R_SCL")
	)
	(segment
		(start 168.6179 -388.24662)
		(end 168.6179 -389.068564)
		(width 0.11684)
		(layer "In4.Cu")
		(net "SMB_FAN_3V3AUX_R_SCL")
	)
	(segment
		(start 194.79768 -367.42243)
		(end 193.81851 -368.4016)
		(width 0.11684)
		(layer "In4.Cu")
		(net "SMB_FAN_3V3AUX_R_SCL")
	)
	(segment
		(start 187.818522 -44.815252)
		(end 187.818522 -79.456026)
		(width 0.11684)
		(layer "In4.Cu")
		(net "SMB_FAN_3V3AUX_R_SCL")
	)
	(segment
		(start 189.010036 -80.337406)
		(end 188.893196 -80.454246)
		(width 0.11684)
		(layer "In4.Cu")
		(net "SMB_FAN_3V3AUX_R_SCL")
	)
	(segment
		(start 188.893196 -80.454246)
		(end 187.935362 -80.454246)
		(width 0.11684)
		(layer "In4.Cu")
		(net "SMB_FAN_3V3AUX_R_SCL")
	)
	(segment
		(start 174.673514 -412.239206)
		(end 174.673514 -411.13456)
		(width 0.11684)
		(layer "In11.Cu")
		(net "SMB_FAN_3V3AUX_R_SCL")
	)
	(segment
		(start 176.72558 -400.157188)
		(end 172.537628 -395.969236)
		(width 0.11684)
		(layer "In11.Cu")
		(net "SMB_FAN_3V3AUX_R_SCL")
	)
	(segment
		(start 178.705002 -417.605464)
		(end 178.210718 -417.605464)
		(width 0.11684)
		(layer "In11.Cu")
		(net "SMB_FAN_3V3AUX_R_SCL")
	)
	(segment
		(start 170.54576 -395.969236)
		(end 170.059096 -396.4559)
		(width 0.11684)
		(layer "In11.Cu")
		(net "SMB_FAN_3V3AUX_R_SCL")
	)
	(segment
		(start 178.210718 -417.605464)
		(end 175.30318 -414.697926)
		(width 0.11684)
		(layer "In11.Cu")
		(net "SMB_FAN_3V3AUX_R_SCL")
	)
	(segment
		(start 176.72558 -409.082494)
		(end 176.72558 -400.157188)
		(width 0.11684)
		(layer "In11.Cu")
		(net "SMB_FAN_3V3AUX_R_SCL")
	)
	(segment
		(start 174.964852 -413.59201)
		(end 174.964852 -412.530544)
		(width 0.11684)
		(layer "In11.Cu")
		(net "SMB_FAN_3V3AUX_R_SCL")
	)
	(segment
		(start 174.964852 -412.530544)
		(end 174.673514 -412.239206)
		(width 0.11684)
		(layer "In11.Cu")
		(net "SMB_FAN_3V3AUX_R_SCL")
	)
	(segment
		(start 174.673514 -411.13456)
		(end 176.72558 -409.082494)
		(width 0.11684)
		(layer "In11.Cu")
		(net "SMB_FAN_3V3AUX_R_SCL")
	)
	(segment
		(start 172.537628 -395.969236)
		(end 170.54576 -395.969236)
		(width 0.11684)
		(layer "In11.Cu")
		(net "SMB_FAN_3V3AUX_R_SCL")
	)
	(segment
		(start 175.30318 -413.930338)
		(end 174.964852 -413.59201)
		(width 0.11684)
		(layer "In11.Cu")
		(net "SMB_FAN_3V3AUX_R_SCL")
	)
	(segment
		(start 175.30318 -414.697926)
		(end 175.30318 -413.930338)
		(width 0.11684)
		(layer "In11.Cu")
		(net "SMB_FAN_3V3AUX_R_SCL")
	)
	(via
		(at 174.464218 -419.35654)
		(size 0.6604)
		(drill 0.3302)
		(layers "F.Cu" "B.Cu")
		(net "SMB_FAN_3V3AUX_BUF_SDA")
	)
	(segment
		(start 173.094904 -419.206426)
		(end 172.712888 -419.206426)
		(width 0.10668)
		(layer "B.Cu")
		(net "SMB_FAN_3V3AUX_BUF_SDA")
	)
	(segment
		(start 173.583092 -419.15715)
		(end 173.14418 -419.15715)
		(width 0.10668)
		(layer "B.Cu")
		(net "SMB_FAN_3V3AUX_BUF_SDA")
	)
	(segment
		(start 175.094138 -418.72662)
		(end 174.464218 -419.35654)
		(width 0.10668)
		(layer "B.Cu")
		(net "SMB_FAN_3V3AUX_BUF_SDA")
	)
	(segment
		(start 172.712888 -418.190426)
		(end 172.712888 -419.206426)
		(width 0.10668)
		(layer "B.Cu")
		(net "SMB_FAN_3V3AUX_BUF_SDA")
	)
	(segment
		(start 176.071022 -418.72662)
		(end 175.094138 -418.72662)
		(width 0.10668)
		(layer "B.Cu")
		(net "SMB_FAN_3V3AUX_BUF_SDA")
	)
	(segment
		(start 173.782482 -419.35654)
		(end 173.583092 -419.15715)
		(width 0.10668)
		(layer "B.Cu")
		(net "SMB_FAN_3V3AUX_BUF_SDA")
	)
	(segment
		(start 173.14418 -419.15715)
		(end 173.094904 -419.206426)
		(width 0.10668)
		(layer "B.Cu")
		(net "SMB_FAN_3V3AUX_BUF_SDA")
	)
	(segment
		(start 174.464218 -419.35654)
		(end 173.782482 -419.35654)
		(width 0.10668)
		(layer "B.Cu")
		(net "SMB_FAN_3V3AUX_BUF_SDA")
	)
	(via
		(at 183.30291 -418.140134)
		(size 0.6604)
		(drill 0.3302)
		(layers "F.Cu" "B.Cu")
		(net "SMB_FAN_3V3AUX_BUF_SCL")
	)
	(segment
		(start 181.733444 -418.823648)
		(end 182.225188 -418.823648)
		(width 0.10668)
		(layer "B.Cu")
		(net "SMB_FAN_3V3AUX_BUF_SCL")
	)
	(segment
		(start 181.636416 -418.72662)
		(end 181.733444 -418.823648)
		(width 0.10668)
		(layer "B.Cu")
		(net "SMB_FAN_3V3AUX_BUF_SCL")
	)
	(segment
		(start 182.225188 -418.823648)
		(end 182.619396 -418.823648)
		(width 0.10668)
		(layer "B.Cu")
		(net "SMB_FAN_3V3AUX_BUF_SCL")
	)
	(segment
		(start 183.30291 -418.140134)
		(end 183.754014 -418.591238)
		(width 0.10668)
		(layer "B.Cu")
		(net "SMB_FAN_3V3AUX_BUF_SCL")
	)
	(segment
		(start 182.619396 -418.823648)
		(end 183.30291 -418.140134)
		(width 0.10668)
		(layer "B.Cu")
		(net "SMB_FAN_3V3AUX_BUF_SCL")
	)
	(segment
		(start 183.754014 -418.591238)
		(end 184.281064 -418.591238)
		(width 0.10668)
		(layer "B.Cu")
		(net "SMB_FAN_3V3AUX_BUF_SCL")
	)
	(segment
		(start 184.281064 -417.575238)
		(end 184.281064 -418.591238)
		(width 0.10668)
		(layer "B.Cu")
		(net "SMB_FAN_3V3AUX_BUF_SCL")
	)
	(segment
		(start 180.535834 -418.72662)
		(end 181.636416 -418.72662)
		(width 0.10668)
		(layer "B.Cu")
		(net "SMB_FAN_3V3AUX_BUF_SCL")
	)
	(via
		(at 184.830466 -416.550348)
		(size 0.6604)
		(drill 0.3302)
		(layers "F.Cu" "B.Cu")
		(net "SMB_FAN_3V3AUX_BUF_R_SDA")
	)
	(via
		(at 187.92952 -418.603684)
		(size 0.508)
		(drill 0.254)
		(layers "F.Cu" "B.Cu")
		(net "SMB_FAN_3V3AUX_BUF_R_SDA")
	)
	(segment
		(start 173.961552 -417.161726)
		(end 173.907196 -417.29279)
		(width 0.10668)
		(layer "B.Cu")
		(net "SMB_FAN_3V3AUX_BUF_R_SDA")
	)
	(segment
		(start 173.961552 -416.928554)
		(end 173.961552 -417.161726)
		(width 0.10668)
		(layer "B.Cu")
		(net "SMB_FAN_3V3AUX_BUF_R_SDA")
	)
	(segment
		(start 174.339758 -416.550348)
		(end 173.961552 -416.928554)
		(width 0.10668)
		(layer "B.Cu")
		(net "SMB_FAN_3V3AUX_BUF_R_SDA")
	)
	(segment
		(start 173.476158 -417.723828)
		(end 172.379386 -417.723828)
		(width 0.10668)
		(layer "B.Cu")
		(net "SMB_FAN_3V3AUX_BUF_R_SDA")
	)
	(segment
		(start 175.386238 -416.550348)
		(end 174.339758 -416.550348)
		(width 0.10668)
		(layer "B.Cu")
		(net "SMB_FAN_3V3AUX_BUF_R_SDA")
	)
	(segment
		(start 181.21757 -416.83559)
		(end 178.68392 -416.83559)
		(width 0.10668)
		(layer "B.Cu")
		(net "SMB_FAN_3V3AUX_BUF_R_SDA")
	)
	(segment
		(start 186.537854 -416.550348)
		(end 187.225432 -417.237926)
		(width 0.10668)
		(layer "B.Cu")
		(net "SMB_FAN_3V3AUX_BUF_R_SDA")
	)
	(segment
		(start 178.68392 -416.83559)
		(end 178.388264 -417.131246)
		(width 0.10668)
		(layer "B.Cu")
		(net "SMB_FAN_3V3AUX_BUF_R_SDA")
	)
	(segment
		(start 187.225432 -418.262816)
		(end 187.5663 -418.603684)
		(width 0.10668)
		(layer "B.Cu")
		(net "SMB_FAN_3V3AUX_BUF_R_SDA")
	)
	(segment
		(start 182.916322 -417.279328)
		(end 181.661308 -417.279328)
		(width 0.10668)
		(layer "B.Cu")
		(net "SMB_FAN_3V3AUX_BUF_R_SDA")
	)
	(segment
		(start 181.661308 -417.279328)
		(end 181.21757 -416.83559)
		(width 0.10668)
		(layer "B.Cu")
		(net "SMB_FAN_3V3AUX_BUF_R_SDA")
	)
	(segment
		(start 172.379386 -417.723828)
		(end 171.912788 -418.190426)
		(width 0.10668)
		(layer "B.Cu")
		(net "SMB_FAN_3V3AUX_BUF_R_SDA")
	)
	(segment
		(start 175.657002 -416.279584)
		(end 175.386238 -416.550348)
		(width 0.10668)
		(layer "B.Cu")
		(net "SMB_FAN_3V3AUX_BUF_R_SDA")
	)
	(segment
		(start 187.5663 -418.603684)
		(end 187.92952 -418.603684)
		(width 0.10668)
		(layer "B.Cu")
		(net "SMB_FAN_3V3AUX_BUF_R_SDA")
	)
	(segment
		(start 183.645302 -416.550348)
		(end 182.916322 -417.279328)
		(width 0.10668)
		(layer "B.Cu")
		(net "SMB_FAN_3V3AUX_BUF_R_SDA")
	)
	(segment
		(start 187.225432 -417.237926)
		(end 187.225432 -418.262816)
		(width 0.10668)
		(layer "B.Cu")
		(net "SMB_FAN_3V3AUX_BUF_R_SDA")
	)
	(segment
		(start 184.830466 -416.550348)
		(end 183.645302 -416.550348)
		(width 0.10668)
		(layer "B.Cu")
		(net "SMB_FAN_3V3AUX_BUF_R_SDA")
	)
	(segment
		(start 177.51806 -417.131246)
		(end 176.666398 -416.279584)
		(width 0.10668)
		(layer "B.Cu")
		(net "SMB_FAN_3V3AUX_BUF_R_SDA")
	)
	(segment
		(start 176.666398 -416.279584)
		(end 175.657002 -416.279584)
		(width 0.10668)
		(layer "B.Cu")
		(net "SMB_FAN_3V3AUX_BUF_R_SDA")
	)
	(segment
		(start 184.830466 -416.550348)
		(end 186.537854 -416.550348)
		(width 0.10668)
		(layer "B.Cu")
		(net "SMB_FAN_3V3AUX_BUF_R_SDA")
	)
	(segment
		(start 178.388264 -417.131246)
		(end 177.51806 -417.131246)
		(width 0.10668)
		(layer "B.Cu")
		(net "SMB_FAN_3V3AUX_BUF_R_SDA")
	)
	(segment
		(start 173.907196 -417.29279)
		(end 173.476158 -417.723828)
		(width 0.10668)
		(layer "B.Cu")
		(net "SMB_FAN_3V3AUX_BUF_R_SDA")
	)
	(segment
		(start 186.183016 -420.83482)
		(end 186.56808 -420.449756)
		(width 0.11684)
		(layer "In13.Cu")
		(net "SMB_FAN_3V3AUX_BUF_R_SDA")
	)
	(segment
		(start 186.56808 -420.449756)
		(end 186.56808 -419.716712)
		(width 0.11684)
		(layer "In13.Cu")
		(net "SMB_FAN_3V3AUX_BUF_R_SDA")
	)
	(segment
		(start 186.56808 -421.825928)
		(end 186.183016 -421.440864)
		(width 0.11684)
		(layer "In13.Cu")
		(net "SMB_FAN_3V3AUX_BUF_R_SDA")
	)
	(segment
		(start 186.56808 -419.716712)
		(end 186.287664 -419.436296)
		(width 0.11684)
		(layer "In13.Cu")
		(net "SMB_FAN_3V3AUX_BUF_R_SDA")
	)
	(segment
		(start 186.183016 -421.440864)
		(end 186.183016 -420.83482)
		(width 0.11684)
		(layer "In13.Cu")
		(net "SMB_FAN_3V3AUX_BUF_R_SDA")
	)
	(segment
		(start 191.590676 -428.48784)
		(end 190.599568 -428.48784)
		(width 0.11684)
		(layer "In13.Cu")
		(net "SMB_FAN_3V3AUX_BUF_R_SDA")
	)
	(segment
		(start 235.91012 -430.50206)
		(end 234.810808 -431.601372)
		(width 0.11684)
		(layer "In13.Cu")
		(net "SMB_FAN_3V3AUX_BUF_R_SDA")
	)
	(segment
		(start 234.810808 -431.601372)
		(end 233.12247 -431.601372)
		(width 0.11684)
		(layer "In13.Cu")
		(net "SMB_FAN_3V3AUX_BUF_R_SDA")
	)
	(segment
		(start 186.56808 -424.456352)
		(end 186.56808 -421.825928)
		(width 0.11684)
		(layer "In13.Cu")
		(net "SMB_FAN_3V3AUX_BUF_R_SDA")
	)
	(segment
		(start 197.797674 -438.246774)
		(end 194.56908 -435.01818)
		(width 0.11684)
		(layer "In13.Cu")
		(net "SMB_FAN_3V3AUX_BUF_R_SDA")
	)
	(segment
		(start 186.287664 -418.502084)
		(end 186.63158 -418.158168)
		(width 0.11684)
		(layer "In13.Cu")
		(net "SMB_FAN_3V3AUX_BUF_R_SDA")
	)
	(segment
		(start 186.63158 -418.158168)
		(end 187.484004 -418.158168)
		(width 0.11684)
		(layer "In13.Cu")
		(net "SMB_FAN_3V3AUX_BUF_R_SDA")
	)
	(segment
		(start 231.771444 -432.952398)
		(end 231.771444 -437.264302)
		(width 0.11684)
		(layer "In13.Cu")
		(net "SMB_FAN_3V3AUX_BUF_R_SDA")
	)
	(segment
		(start 187.484004 -418.158168)
		(end 187.92952 -418.603684)
		(width 0.11684)
		(layer "In13.Cu")
		(net "SMB_FAN_3V3AUX_BUF_R_SDA")
	)
	(segment
		(start 230.788972 -438.246774)
		(end 197.797674 -438.246774)
		(width 0.11684)
		(layer "In13.Cu")
		(net "SMB_FAN_3V3AUX_BUF_R_SDA")
	)
	(segment
		(start 194.56908 -435.01818)
		(end 194.56908 -431.466244)
		(width 0.11684)
		(layer "In13.Cu")
		(net "SMB_FAN_3V3AUX_BUF_R_SDA")
	)
	(segment
		(start 233.12247 -431.601372)
		(end 231.771444 -432.952398)
		(width 0.11684)
		(layer "In13.Cu")
		(net "SMB_FAN_3V3AUX_BUF_R_SDA")
	)
	(segment
		(start 231.771444 -437.264302)
		(end 230.788972 -438.246774)
		(width 0.11684)
		(layer "In13.Cu")
		(net "SMB_FAN_3V3AUX_BUF_R_SDA")
	)
	(segment
		(start 194.56908 -431.466244)
		(end 191.590676 -428.48784)
		(width 0.11684)
		(layer "In13.Cu")
		(net "SMB_FAN_3V3AUX_BUF_R_SDA")
	)
	(segment
		(start 186.287664 -419.436296)
		(end 186.287664 -418.502084)
		(width 0.11684)
		(layer "In13.Cu")
		(net "SMB_FAN_3V3AUX_BUF_R_SDA")
	)
	(segment
		(start 190.599568 -428.48784)
		(end 186.56808 -424.456352)
		(width 0.11684)
		(layer "In13.Cu")
		(net "SMB_FAN_3V3AUX_BUF_R_SDA")
	)
	(via
		(at 186.853068 -418.728398)
		(size 0.508)
		(drill 0.254)
		(layers "F.Cu" "B.Cu")
		(net "SMB_FAN_3V3AUX_BUF_R_SCL")
	)
	(via
		(at 186.175904 -417.291012)
		(size 0.6604)
		(drill 0.3302)
		(layers "F.Cu" "B.Cu")
		(net "SMB_FAN_3V3AUX_BUF_R_SCL")
	)
	(segment
		(start 186.853068 -417.968176)
		(end 186.853068 -418.728398)
		(width 0.10668)
		(layer "B.Cu")
		(net "SMB_FAN_3V3AUX_BUF_R_SCL")
	)
	(segment
		(start 185.36539 -417.291012)
		(end 186.175904 -417.291012)
		(width 0.10668)
		(layer "B.Cu")
		(net "SMB_FAN_3V3AUX_BUF_R_SCL")
	)
	(segment
		(start 186.175904 -417.291012)
		(end 186.853068 -417.968176)
		(width 0.10668)
		(layer "B.Cu")
		(net "SMB_FAN_3V3AUX_BUF_R_SCL")
	)
	(segment
		(start 185.081164 -417.575238)
		(end 185.36539 -417.291012)
		(width 0.10668)
		(layer "B.Cu")
		(net "SMB_FAN_3V3AUX_BUF_R_SCL")
	)
	(segment
		(start 188.513974 -425.595034)
		(end 188.348874 -425.595034)
		(width 0.11684)
		(layer "In13.Cu")
		(net "SMB_FAN_3V3AUX_BUF_R_SCL")
	)
	(segment
		(start 188.348874 -425.595034)
		(end 188.195966 -425.442126)
		(width 0.11684)
		(layer "In13.Cu")
		(net "SMB_FAN_3V3AUX_BUF_R_SCL")
	)
	(segment
		(start 238.45012 -430.50206)
		(end 237.41253 -429.46447)
		(width 0.11684)
		(layer "In13.Cu")
		(net "SMB_FAN_3V3AUX_BUF_R_SCL")
	)
	(segment
		(start 187.037218 -423.020236)
		(end 187.154058 -422.903396)
		(width 0.11684)
		(layer "In13.Cu")
		(net "SMB_FAN_3V3AUX_BUF_R_SCL")
	)
	(segment
		(start 188.142626 -423.352976)
		(end 187.154058 -423.352976)
		(width 0.11684)
		(layer "In13.Cu")
		(net "SMB_FAN_3V3AUX_BUF_R_SCL")
	)
	(segment
		(start 187.154058 -422.903396)
		(end 188.142626 -422.903396)
		(width 0.11684)
		(layer "In13.Cu")
		(net "SMB_FAN_3V3AUX_BUF_R_SCL")
	)
	(segment
		(start 188.896244 -424.105832)
		(end 188.731144 -424.105832)
		(width 0.11684)
		(layer "In13.Cu")
		(net "SMB_FAN_3V3AUX_BUF_R_SCL")
	)
	(segment
		(start 187.188348 -421.506904)
		(end 187.188348 -420.811198)
		(width 0.11684)
		(layer "In13.Cu")
		(net "SMB_FAN_3V3AUX_BUF_R_SCL")
	)
	(segment
		(start 186.853068 -419.170612)
		(end 186.853068 -418.728398)
		(width 0.11684)
		(layer "In13.Cu")
		(net "SMB_FAN_3V3AUX_BUF_R_SCL")
	)
	(segment
		(start 188.142626 -422.903396)
		(end 188.259466 -422.786556)
		(width 0.11684)
		(layer "In13.Cu")
		(net "SMB_FAN_3V3AUX_BUF_R_SCL")
	)
	(segment
		(start 188.259466 -422.570656)
		(end 188.142626 -422.453816)
		(width 0.11684)
		(layer "In13.Cu")
		(net "SMB_FAN_3V3AUX_BUF_R_SCL")
	)
	(segment
		(start 189.049152 -424.42384)
		(end 189.049152 -424.25874)
		(width 0.11684)
		(layer "In13.Cu")
		(net "SMB_FAN_3V3AUX_BUF_R_SCL")
	)
	(segment
		(start 231.087676 -436.866792)
		(end 230.218234 -437.736234)
		(width 0.11684)
		(layer "In13.Cu")
		(net "SMB_FAN_3V3AUX_BUF_R_SCL")
	)
	(segment
		(start 188.195966 -425.277026)
		(end 189.049152 -424.42384)
		(width 0.11684)
		(layer "In13.Cu")
		(net "SMB_FAN_3V3AUX_BUF_R_SCL")
	)
	(segment
		(start 188.142626 -423.802556)
		(end 188.259466 -423.685716)
		(width 0.11684)
		(layer "In13.Cu")
		(net "SMB_FAN_3V3AUX_BUF_R_SCL")
	)
	(segment
		(start 189.36716 -424.741848)
		(end 188.513974 -425.595034)
		(width 0.11684)
		(layer "In13.Cu")
		(net "SMB_FAN_3V3AUX_BUF_R_SCL")
	)
	(segment
		(start 187.037218 -422.336976)
		(end 187.037218 -421.658034)
		(width 0.11684)
		(layer "In13.Cu")
		(net "SMB_FAN_3V3AUX_BUF_R_SCL")
	)
	(segment
		(start 187.188348 -420.811198)
		(end 187.037218 -420.660068)
		(width 0.11684)
		(layer "In13.Cu")
		(net "SMB_FAN_3V3AUX_BUF_R_SCL")
	)
	(segment
		(start 187.037218 -423.236136)
		(end 187.037218 -423.020236)
		(width 0.11684)
		(layer "In13.Cu")
		(net "SMB_FAN_3V3AUX_BUF_R_SCL")
	)
	(segment
		(start 187.154058 -423.352976)
		(end 187.037218 -423.236136)
		(width 0.11684)
		(layer "In13.Cu")
		(net "SMB_FAN_3V3AUX_BUF_R_SCL")
	)
	(segment
		(start 189.53226 -424.741848)
		(end 189.36716 -424.741848)
		(width 0.11684)
		(layer "In13.Cu")
		(net "SMB_FAN_3V3AUX_BUF_R_SCL")
	)
	(segment
		(start 230.218234 -437.736234)
		(end 197.92823 -437.736234)
		(width 0.11684)
		(layer "In13.Cu")
		(net "SMB_FAN_3V3AUX_BUF_R_SCL")
	)
	(segment
		(start 195.116958 -431.34407)
		(end 191.819276 -428.046388)
		(width 0.11684)
		(layer "In13.Cu")
		(net "SMB_FAN_3V3AUX_BUF_R_SCL")
	)
	(segment
		(start 187.712858 -424.959018)
		(end 187.037218 -424.283378)
		(width 0.11684)
		(layer "In13.Cu")
		(net "SMB_FAN_3V3AUX_BUF_R_SCL")
	)
	(segment
		(start 190.800228 -428.046388)
		(end 188.831982 -426.078142)
		(width 0.11684)
		(layer "In13.Cu")
		(net "SMB_FAN_3V3AUX_BUF_R_SCL")
	)
	(segment
		(start 188.259466 -422.786556)
		(end 188.259466 -422.570656)
		(width 0.11684)
		(layer "In13.Cu")
		(net "SMB_FAN_3V3AUX_BUF_R_SCL")
	)
	(segment
		(start 187.037218 -421.658034)
		(end 187.188348 -421.506904)
		(width 0.11684)
		(layer "In13.Cu")
		(net "SMB_FAN_3V3AUX_BUF_R_SCL")
	)
	(segment
		(start 188.831982 -425.913042)
		(end 189.685168 -425.059856)
		(width 0.11684)
		(layer "In13.Cu")
		(net "SMB_FAN_3V3AUX_BUF_R_SCL")
	)
	(segment
		(start 187.037218 -424.283378)
		(end 187.037218 -423.919396)
		(width 0.11684)
		(layer "In13.Cu")
		(net "SMB_FAN_3V3AUX_BUF_R_SCL")
	)
	(segment
		(start 187.037218 -423.919396)
		(end 187.154058 -423.802556)
		(width 0.11684)
		(layer "In13.Cu")
		(net "SMB_FAN_3V3AUX_BUF_R_SCL")
	)
	(segment
		(start 188.831982 -426.078142)
		(end 188.831982 -425.913042)
		(width 0.11684)
		(layer "In13.Cu")
		(net "SMB_FAN_3V3AUX_BUF_R_SCL")
	)
	(segment
		(start 195.116958 -434.924962)
		(end 195.116958 -431.34407)
		(width 0.11684)
		(layer "In13.Cu")
		(net "SMB_FAN_3V3AUX_BUF_R_SCL")
	)
	(segment
		(start 189.685168 -424.894756)
		(end 189.53226 -424.741848)
		(width 0.11684)
		(layer "In13.Cu")
		(net "SMB_FAN_3V3AUX_BUF_R_SCL")
	)
	(segment
		(start 191.819276 -428.046388)
		(end 190.800228 -428.046388)
		(width 0.11684)
		(layer "In13.Cu")
		(net "SMB_FAN_3V3AUX_BUF_R_SCL")
	)
	(segment
		(start 187.877958 -424.959018)
		(end 187.712858 -424.959018)
		(width 0.11684)
		(layer "In13.Cu")
		(net "SMB_FAN_3V3AUX_BUF_R_SCL")
	)
	(segment
		(start 187.154058 -422.453816)
		(end 187.037218 -422.336976)
		(width 0.11684)
		(layer "In13.Cu")
		(net "SMB_FAN_3V3AUX_BUF_R_SCL")
	)
	(segment
		(start 189.049152 -424.25874)
		(end 188.896244 -424.105832)
		(width 0.11684)
		(layer "In13.Cu")
		(net "SMB_FAN_3V3AUX_BUF_R_SCL")
	)
	(segment
		(start 188.142626 -422.453816)
		(end 187.154058 -422.453816)
		(width 0.11684)
		(layer "In13.Cu")
		(net "SMB_FAN_3V3AUX_BUF_R_SCL")
	)
	(segment
		(start 197.92823 -437.736234)
		(end 195.116958 -434.924962)
		(width 0.11684)
		(layer "In13.Cu")
		(net "SMB_FAN_3V3AUX_BUF_R_SCL")
	)
	(segment
		(start 187.037218 -419.354762)
		(end 186.853068 -419.170612)
		(width 0.11684)
		(layer "In13.Cu")
		(net "SMB_FAN_3V3AUX_BUF_R_SCL")
	)
	(segment
		(start 188.195966 -425.442126)
		(end 188.195966 -425.277026)
		(width 0.11684)
		(layer "In13.Cu")
		(net "SMB_FAN_3V3AUX_BUF_R_SCL")
	)
	(segment
		(start 188.259466 -423.469816)
		(end 188.142626 -423.352976)
		(width 0.11684)
		(layer "In13.Cu")
		(net "SMB_FAN_3V3AUX_BUF_R_SCL")
	)
	(segment
		(start 188.259466 -423.685716)
		(end 188.259466 -423.469816)
		(width 0.11684)
		(layer "In13.Cu")
		(net "SMB_FAN_3V3AUX_BUF_R_SCL")
	)
	(segment
		(start 237.41253 -429.46447)
		(end 232.783634 -429.46447)
		(width 0.11684)
		(layer "In13.Cu")
		(net "SMB_FAN_3V3AUX_BUF_R_SCL")
	)
	(segment
		(start 231.087676 -431.160428)
		(end 231.087676 -436.866792)
		(width 0.11684)
		(layer "In13.Cu")
		(net "SMB_FAN_3V3AUX_BUF_R_SCL")
	)
	(segment
		(start 187.037218 -420.660068)
		(end 187.037218 -419.354762)
		(width 0.11684)
		(layer "In13.Cu")
		(net "SMB_FAN_3V3AUX_BUF_R_SCL")
	)
	(segment
		(start 232.783634 -429.46447)
		(end 231.087676 -431.160428)
		(width 0.11684)
		(layer "In13.Cu")
		(net "SMB_FAN_3V3AUX_BUF_R_SCL")
	)
	(segment
		(start 188.731144 -424.105832)
		(end 187.877958 -424.959018)
		(width 0.11684)
		(layer "In13.Cu")
		(net "SMB_FAN_3V3AUX_BUF_R_SCL")
	)
	(segment
		(start 189.685168 -425.059856)
		(end 189.685168 -424.894756)
		(width 0.11684)
		(layer "In13.Cu")
		(net "SMB_FAN_3V3AUX_BUF_R_SCL")
	)
	(segment
		(start 187.154058 -423.802556)
		(end 188.142626 -423.802556)
		(width 0.11684)
		(layer "In13.Cu")
		(net "SMB_FAN_3V3AUX_BUF_R_SCL")
	)
	(segment
		(start 13.565124 -96.723962)
		(end 13.565124 -96.130872)
		(width 0.10668)
		(layer "F.Cu")
		(net "RST_USB_HUB_R_N")
	)
	(segment
		(start 12.982956 -93.087698)
		(end 11.895836 -93.087698)
		(width 0.10668)
		(layer "F.Cu")
		(net "RST_USB_HUB_R_N")
	)
	(segment
		(start 11.895836 -93.087698)
		(end 10.873486 -93.087698)
		(width 0.10668)
		(layer "F.Cu")
		(net "RST_USB_HUB_R_N")
	)
	(segment
		(start 9.908032 -93.087698)
		(end 10.873486 -93.087698)
		(width 0.10668)
		(layer "F.Cu")
		(net "RST_USB_HUB_R_N")
	)
	(segment
		(start 13.565124 -96.130872)
		(end 12.7508 -95.316548)
		(width 0.10668)
		(layer "F.Cu")
		(net "RST_USB_HUB_R_N")
	)
	(segment
		(start 12.982956 -95.084392)
		(end 12.982956 -93.087698)
		(width 0.10668)
		(layer "F.Cu")
		(net "RST_USB_HUB_R_N")
	)
	(segment
		(start 12.7508 -95.316548)
		(end 12.982956 -95.084392)
		(width 0.10668)
		(layer "F.Cu")
		(net "RST_USB_HUB_R_N")
	)
	(via
		(at 12.7508 -95.316548)
		(size 0.762)
		(drill 0.381)
		(layers "F.Cu" "B.Cu")
		(net "RST_USB_HUB_R_N")
	)
	(segment
		(start 53.870606 -415.354262)
		(end 52.859432 -414.343088)
		(width 0.10668)
		(layer "F.Cu")
		(net "RST_USB_HUB_N")
	)
	(segment
		(start 40.643048 -416.336734)
		(end 35.649154 -411.34284)
		(width 0.10668)
		(layer "F.Cu")
		(net "RST_USB_HUB_N")
	)
	(segment
		(start 101.413056 -31.386526)
		(end 101.413056 -30.770576)
		(width 0.10668)
		(layer "F.Cu")
		(net "RST_USB_HUB_N")
	)
	(segment
		(start 43.1292 -416.336734)
		(end 40.643048 -416.336734)
		(width 0.10668)
		(layer "F.Cu")
		(net "RST_USB_HUB_N")
	)
	(segment
		(start 90.843354 -422.101518)
		(end 84.096098 -415.354262)
		(width 0.10668)
		(layer "F.Cu")
		(net "RST_USB_HUB_N")
	)
	(segment
		(start 35.649154 -411.34284)
		(end 30.91307 -411.34284)
		(width 0.10668)
		(layer "F.Cu")
		(net "RST_USB_HUB_N")
	)
	(segment
		(start 102.437946 -55.282084)
		(end 102.437946 -55.738014)
		(width 0.10668)
		(layer "F.Cu")
		(net "RST_USB_HUB_N")
	)
	(segment
		(start 84.096098 -415.354262)
		(end 53.870606 -415.354262)
		(width 0.10668)
		(layer "F.Cu")
		(net "RST_USB_HUB_N")
	)
	(segment
		(start 102.21976 -55.9562)
		(end 101.6 -55.9562)
		(width 0.10668)
		(layer "F.Cu")
		(net "RST_USB_HUB_N")
	)
	(segment
		(start 124.233178 -48.137064)
		(end 123.617228 -48.137064)
		(width 0.10668)
		(layer "F.Cu")
		(net "RST_USB_HUB_N")
	)
	(segment
		(start 102.437946 -55.738014)
		(end 102.21976 -55.9562)
		(width 0.10668)
		(layer "F.Cu")
		(net "RST_USB_HUB_N")
	)
	(segment
		(start 182.712106 -417.404804)
		(end 182.712106 -416.649408)
		(width 0.10668)
		(layer "F.Cu")
		(net "RST_USB_HUB_N")
	)
	(segment
		(start 9.911334 -90.724228)
		(end 9.911334 -92.284296)
		(width 0.10668)
		(layer "F.Cu")
		(net "RST_USB_HUB_N")
	)
	(segment
		(start 94.073726 -422.101518)
		(end 90.843354 -422.101518)
		(width 0.10668)
		(layer "F.Cu")
		(net "RST_USB_HUB_N")
	)
	(segment
		(start 9.908032 -92.287598)
		(end 9.07796 -92.287598)
		(width 0.10668)
		(layer "F.Cu")
		(net "RST_USB_HUB_N")
	)
	(segment
		(start 10.955274 -89.680288)
		(end 9.911334 -90.724228)
		(width 0.10668)
		(layer "F.Cu")
		(net "RST_USB_HUB_N")
	)
	(segment
		(start 52.859432 -414.343088)
		(end 45.122846 -414.343088)
		(width 0.10668)
		(layer "F.Cu")
		(net "RST_USB_HUB_N")
	)
	(segment
		(start 9.911334 -92.284296)
		(end 9.908032 -92.287598)
		(width 0.10668)
		(layer "F.Cu")
		(net "RST_USB_HUB_N")
	)
	(segment
		(start 45.122846 -414.343088)
		(end 43.1292 -416.336734)
		(width 0.10668)
		(layer "F.Cu")
		(net "RST_USB_HUB_N")
	)
	(segment
		(start 182.712106 -416.649408)
		(end 182.401464 -416.338766)
		(width 0.10668)
		(layer "F.Cu")
		(net "RST_USB_HUB_N")
	)
	(segment
		(start 48.918368 -89.680288)
		(end 10.955274 -89.680288)
		(width 0.10668)
		(layer "F.Cu")
		(net "RST_USB_HUB_N")
	)
	(via
		(at 30.91307 -411.34284)
		(size 0.508)
		(drill 0.254)
		(layers "F.Cu" "B.Cu")
		(net "RST_USB_HUB_N")
	)
	(via
		(at 101.6 -55.9562)
		(size 0.508)
		(drill 0.254)
		(layers "F.Cu" "B.Cu")
		(net "RST_USB_HUB_N")
	)
	(via
		(at 123.617228 -48.137064)
		(size 0.508)
		(drill 0.254)
		(layers "F.Cu" "B.Cu")
		(net "RST_USB_HUB_N")
	)
	(via
		(at 94.073726 -422.101518)
		(size 0.508)
		(drill 0.254)
		(layers "F.Cu" "B.Cu")
		(net "RST_USB_HUB_N")
	)
	(via
		(at 101.413056 -30.770576)
		(size 0.508)
		(drill 0.254)
		(layers "F.Cu" "B.Cu")
		(net "RST_USB_HUB_N")
	)
	(via
		(at 9.07796 -92.287598)
		(size 0.508)
		(drill 0.254)
		(layers "F.Cu" "B.Cu")
		(net "RST_USB_HUB_N")
	)
	(via
		(at 182.401464 -416.338766)
		(size 0.508)
		(drill 0.254)
		(layers "F.Cu" "B.Cu")
		(net "RST_USB_HUB_N")
	)
	(via
		(at 48.918368 -89.680288)
		(size 0.508)
		(drill 0.254)
		(layers "F.Cu" "B.Cu")
		(net "RST_USB_HUB_N")
	)
	(segment
		(start 116.573046 -415.442146)
		(end 115.34521 -416.669982)
		(width 0.11684)
		(layer "In2.Cu")
		(net "RST_USB_HUB_N")
	)
	(segment
		(start 102.860856 -420.558468)
		(end 101.9302 -421.489124)
		(width 0.11684)
		(layer "In2.Cu")
		(net "RST_USB_HUB_N")
	)
	(segment
		(start 164.423344 -414.999424)
		(end 163.939982 -414.516062)
		(width 0.11684)
		(layer "In2.Cu")
		(net "RST_USB_HUB_N")
	)
	(segment
		(start 107.080812 -416.879532)
		(end 105.212134 -416.879532)
		(width 0.11684)
		(layer "In2.Cu")
		(net "RST_USB_HUB_N")
	)
	(segment
		(start 110.386622 -416.297364)
		(end 110.107222 -416.017964)
		(width 0.11684)
		(layer "In2.Cu")
		(net "RST_USB_HUB_N")
	)
	(segment
		(start 182.401464 -416.338766)
		(end 181.607968 -416.338766)
		(width 0.11684)
		(layer "In2.Cu")
		(net "RST_USB_HUB_N")
	)
	(segment
		(start 87.511636 -38.111938)
		(end 90.549984 -35.07359)
		(width 0.11684)
		(layer "In2.Cu")
		(net "RST_USB_HUB_N")
	)
	(segment
		(start 174.719234 -413.311848)
		(end 171.23029 -413.311848)
		(width 0.11684)
		(layer "In2.Cu")
		(net "RST_USB_HUB_N")
	)
	(segment
		(start 100.6221 -29.97962)
		(end 101.413056 -30.770576)
		(width 0.11684)
		(layer "In2.Cu")
		(net "RST_USB_HUB_N")
	)
	(segment
		(start 101.760528 -56.116728)
		(end 103.044752 -56.116728)
		(width 0.11684)
		(layer "In2.Cu")
		(net "RST_USB_HUB_N")
	)
	(segment
		(start 101.9302 -421.489124)
		(end 94.68612 -421.489124)
		(width 0.11684)
		(layer "In2.Cu")
		(net "RST_USB_HUB_N")
	)
	(segment
		(start 171.23029 -413.311848)
		(end 169.997374 -414.544764)
		(width 0.11684)
		(layer "In2.Cu")
		(net "RST_USB_HUB_N")
	)
	(segment
		(start 167.49014 -414.999424)
		(end 164.423344 -414.999424)
		(width 0.11684)
		(layer "In2.Cu")
		(net "RST_USB_HUB_N")
	)
	(segment
		(start 94.68612 -421.489124)
		(end 94.073726 -422.101518)
		(width 0.11684)
		(layer "In2.Cu")
		(net "RST_USB_HUB_N")
	)
	(segment
		(start 169.997374 -414.544764)
		(end 167.9448 -414.544764)
		(width 0.11684)
		(layer "In2.Cu")
		(net "RST_USB_HUB_N")
	)
	(segment
		(start 87.511636 -48.197516)
		(end 87.511636 -38.111938)
		(width 0.11684)
		(layer "In2.Cu")
		(net "RST_USB_HUB_N")
	)
	(segment
		(start 103.044752 -56.116728)
		(end 107.96778 -51.1937)
		(width 0.11684)
		(layer "In2.Cu")
		(net "RST_USB_HUB_N")
	)
	(segment
		(start 153.131266 -414.516062)
		(end 152.205182 -415.442146)
		(width 0.11684)
		(layer "In2.Cu")
		(net "RST_USB_HUB_N")
	)
	(segment
		(start 102.860856 -419.23081)
		(end 102.860856 -420.558468)
		(width 0.11684)
		(layer "In2.Cu")
		(net "RST_USB_HUB_N")
	)
	(segment
		(start 114.297968 -416.669982)
		(end 113.92535 -416.297364)
		(width 0.11684)
		(layer "In2.Cu")
		(net "RST_USB_HUB_N")
	)
	(segment
		(start 107.94238 -416.017964)
		(end 107.080812 -416.879532)
		(width 0.11684)
		(layer "In2.Cu")
		(net "RST_USB_HUB_N")
	)
	(segment
		(start 110.107222 -416.017964)
		(end 107.94238 -416.017964)
		(width 0.11684)
		(layer "In2.Cu")
		(net "RST_USB_HUB_N")
	)
	(segment
		(start 181.607968 -416.338766)
		(end 179.634896 -414.365694)
		(width 0.11684)
		(layer "In2.Cu")
		(net "RST_USB_HUB_N")
	)
	(segment
		(start 167.9448 -414.544764)
		(end 167.49014 -414.999424)
		(width 0.11684)
		(layer "In2.Cu")
		(net "RST_USB_HUB_N")
	)
	(segment
		(start 152.205182 -415.442146)
		(end 116.573046 -415.442146)
		(width 0.11684)
		(layer "In2.Cu")
		(net "RST_USB_HUB_N")
	)
	(segment
		(start 48.918368 -89.680288)
		(end 74.556874 -64.041782)
		(width 0.11684)
		(layer "In2.Cu")
		(net "RST_USB_HUB_N")
	)
	(segment
		(start 74.556874 -64.041782)
		(end 74.556874 -61.152278)
		(width 0.11684)
		(layer "In2.Cu")
		(net "RST_USB_HUB_N")
	)
	(segment
		(start 101.6 -55.9562)
		(end 101.760528 -56.116728)
		(width 0.11684)
		(layer "In2.Cu")
		(net "RST_USB_HUB_N")
	)
	(segment
		(start 120.560592 -51.1937)
		(end 123.617228 -48.137064)
		(width 0.11684)
		(layer "In2.Cu")
		(net "RST_USB_HUB_N")
	)
	(segment
		(start 98.92792 -29.97962)
		(end 100.6221 -29.97962)
		(width 0.11684)
		(layer "In2.Cu")
		(net "RST_USB_HUB_N")
	)
	(segment
		(start 107.96778 -51.1937)
		(end 120.560592 -51.1937)
		(width 0.11684)
		(layer "In2.Cu")
		(net "RST_USB_HUB_N")
	)
	(segment
		(start 175.77308 -414.365694)
		(end 174.719234 -413.311848)
		(width 0.11684)
		(layer "In2.Cu")
		(net "RST_USB_HUB_N")
	)
	(segment
		(start 93.83395 -35.07359)
		(end 98.92792 -29.97962)
		(width 0.11684)
		(layer "In2.Cu")
		(net "RST_USB_HUB_N")
	)
	(segment
		(start 90.549984 -35.07359)
		(end 93.83395 -35.07359)
		(width 0.11684)
		(layer "In2.Cu")
		(net "RST_USB_HUB_N")
	)
	(segment
		(start 74.556874 -61.152278)
		(end 87.511636 -48.197516)
		(width 0.11684)
		(layer "In2.Cu")
		(net "RST_USB_HUB_N")
	)
	(segment
		(start 113.92535 -416.297364)
		(end 110.386622 -416.297364)
		(width 0.11684)
		(layer "In2.Cu")
		(net "RST_USB_HUB_N")
	)
	(segment
		(start 105.212134 -416.879532)
		(end 102.860856 -419.23081)
		(width 0.11684)
		(layer "In2.Cu")
		(net "RST_USB_HUB_N")
	)
	(segment
		(start 179.634896 -414.365694)
		(end 175.77308 -414.365694)
		(width 0.11684)
		(layer "In2.Cu")
		(net "RST_USB_HUB_N")
	)
	(segment
		(start 115.34521 -416.669982)
		(end 114.297968 -416.669982)
		(width 0.11684)
		(layer "In2.Cu")
		(net "RST_USB_HUB_N")
	)
	(segment
		(start 163.939982 -414.516062)
		(end 153.131266 -414.516062)
		(width 0.11684)
		(layer "In2.Cu")
		(net "RST_USB_HUB_N")
	)
	(segment
		(start 30.107128 -413.5628)
		(end 30.91307 -412.756858)
		(width 0.11684)
		(layer "In4.Cu")
		(net "RST_USB_HUB_N")
	)
	(segment
		(start 3.097784 -330.971652)
		(end 3.097784 -350.412304)
		(width 0.11684)
		(layer "In4.Cu")
		(net "RST_USB_HUB_N")
	)
	(segment
		(start 9.07796 -92.287598)
		(end 6.34619 -92.287598)
		(width 0.11684)
		(layer "In4.Cu")
		(net "RST_USB_HUB_N")
	)
	(segment
		(start 7.989316 -407.750772)
		(end 7.989316 -415.411666)
		(width 0.11684)
		(layer "In4.Cu")
		(net "RST_USB_HUB_N")
	)
	(segment
		(start 3.436874 -350.751394)
		(end 3.436874 -403.198584)
		(width 0.11684)
		(layer "In4.Cu")
		(net "RST_USB_HUB_N")
	)
	(segment
		(start 3.335274 -330.734162)
		(end 3.097784 -330.971652)
		(width 0.11684)
		(layer "In4.Cu")
		(net "RST_USB_HUB_N")
	)
	(segment
		(start 20.614132 -417.741608)
		(end 20.614132 -416.91179)
		(width 0.11684)
		(layer "In4.Cu")
		(net "RST_USB_HUB_N")
	)
	(segment
		(start 13.967714 -418.330888)
		(end 20.024852 -418.330888)
		(width 0.11684)
		(layer "In4.Cu")
		(net "RST_USB_HUB_N")
	)
	(segment
		(start 13.350494 -417.713668)
		(end 13.967714 -418.330888)
		(width 0.11684)
		(layer "In4.Cu")
		(net "RST_USB_HUB_N")
	)
	(segment
		(start 3.436874 -403.198584)
		(end 7.989316 -407.750772)
		(width 0.11684)
		(layer "In4.Cu")
		(net "RST_USB_HUB_N")
	)
	(segment
		(start 101.64572 -55.91048)
		(end 101.64572 -51.73218)
		(width 0.11684)
		(layer "In4.Cu")
		(net "RST_USB_HUB_N")
	)
	(segment
		(start 101.413056 -32.855916)
		(end 101.413056 -30.770576)
		(width 0.11684)
		(layer "In4.Cu")
		(net "RST_USB_HUB_N")
	)
	(segment
		(start 105.91038 -47.46752)
		(end 105.91038 -37.35324)
		(width 0.11684)
		(layer "In4.Cu")
		(net "RST_USB_HUB_N")
	)
	(segment
		(start 20.614132 -416.91179)
		(end 23.963122 -413.5628)
		(width 0.11684)
		(layer "In4.Cu")
		(net "RST_USB_HUB_N")
	)
	(segment
		(start 101.6 -55.9562)
		(end 101.64572 -55.91048)
		(width 0.11684)
		(layer "In4.Cu")
		(net "RST_USB_HUB_N")
	)
	(segment
		(start 7.989316 -415.411666)
		(end 10.291318 -417.713668)
		(width 0.11684)
		(layer "In4.Cu")
		(net "RST_USB_HUB_N")
	)
	(segment
		(start 3.097784 -350.412304)
		(end 3.436874 -350.751394)
		(width 0.11684)
		(layer "In4.Cu")
		(net "RST_USB_HUB_N")
	)
	(segment
		(start 30.91307 -412.756858)
		(end 30.91307 -411.34284)
		(width 0.11684)
		(layer "In4.Cu")
		(net "RST_USB_HUB_N")
	)
	(segment
		(start 20.024852 -418.330888)
		(end 20.614132 -417.741608)
		(width 0.11684)
		(layer "In4.Cu")
		(net "RST_USB_HUB_N")
	)
	(segment
		(start 3.335274 -95.298514)
		(end 3.335274 -330.734162)
		(width 0.11684)
		(layer "In4.Cu")
		(net "RST_USB_HUB_N")
	)
	(segment
		(start 105.91038 -37.35324)
		(end 101.413056 -32.855916)
		(width 0.11684)
		(layer "In4.Cu")
		(net "RST_USB_HUB_N")
	)
	(segment
		(start 6.34619 -92.287598)
		(end 3.335274 -95.298514)
		(width 0.11684)
		(layer "In4.Cu")
		(net "RST_USB_HUB_N")
	)
	(segment
		(start 23.963122 -413.5628)
		(end 30.107128 -413.5628)
		(width 0.11684)
		(layer "In4.Cu")
		(net "RST_USB_HUB_N")
	)
	(segment
		(start 10.291318 -417.713668)
		(end 13.350494 -417.713668)
		(width 0.11684)
		(layer "In4.Cu")
		(net "RST_USB_HUB_N")
	)
	(segment
		(start 101.64572 -51.73218)
		(end 105.91038 -47.46752)
		(width 0.11684)
		(layer "In4.Cu")
		(net "RST_USB_HUB_N")
	)
	(via
		(at 238.708692 -424.417998)
		(size 0.6604)
		(drill 0.3302)
		(layers "F.Cu" "B.Cu")
		(net "RST_SMB_SWITCH_R_N")
	)
	(segment
		(start 237.18012 -431.77206)
		(end 237.18012 -426.798994)
		(width 0.10668)
		(layer "B.Cu")
		(net "RST_SMB_SWITCH_R_N")
	)
	(segment
		(start 239.724692 -423.249598)
		(end 238.708692 -423.249598)
		(width 0.10668)
		(layer "B.Cu")
		(net "RST_SMB_SWITCH_R_N")
	)
	(segment
		(start 238.45012 -433.04206)
		(end 237.18012 -431.77206)
		(width 0.10668)
		(layer "B.Cu")
		(net "RST_SMB_SWITCH_R_N")
	)
	(segment
		(start 238.708692 -425.270422)
		(end 238.708692 -424.417998)
		(width 0.10668)
		(layer "B.Cu")
		(net "RST_SMB_SWITCH_R_N")
	)
	(segment
		(start 237.18012 -426.798994)
		(end 238.708692 -425.270422)
		(width 0.10668)
		(layer "B.Cu")
		(net "RST_SMB_SWITCH_R_N")
	)
	(segment
		(start 238.708692 -423.249598)
		(end 238.708692 -424.417998)
		(width 0.10668)
		(layer "B.Cu")
		(net "RST_SMB_SWITCH_R_N")
	)
	(segment
		(start 278.904192 -434.655976)
		(end 280.286206 -434.655976)
		(width 0.10668)
		(layer "F.Cu")
		(net "PWRGD_P3V3_AUX_PDB_R")
	)
	(segment
		(start 280.286206 -434.655976)
		(end 281.505406 -434.655976)
		(width 0.10668)
		(layer "F.Cu")
		(net "PWRGD_P3V3_AUX_PDB_R")
	)
	(via
		(at 280.286206 -434.655976)
		(size 0.762)
		(drill 0.381)
		(layers "F.Cu" "B.Cu")
		(net "PWRGD_P3V3_AUX_PDB_R")
	)
	(segment
		(start 279.270206 -432.390042)
		(end 279.270206 -430.791366)
		(width 0.10668)
		(layer "F.Cu")
		(net "PWRGD_P3V3_AUX_PDB_BUF_R")
	)
	(segment
		(start 279.270206 -429.66894)
		(end 279.270206 -430.791366)
		(width 0.10668)
		(layer "F.Cu")
		(net "PWRGD_P3V3_AUX_PDB_BUF_R")
	)
	(segment
		(start 278.904192 -432.756056)
		(end 279.270206 -432.390042)
		(width 0.10668)
		(layer "F.Cu")
		(net "PWRGD_P3V3_AUX_PDB_BUF_R")
	)
	(segment
		(start 278.051006 -428.556166)
		(end 278.051006 -429.572166)
		(width 0.10668)
		(layer "F.Cu")
		(net "PWRGD_P3V3_AUX_PDB_BUF_R")
	)
	(segment
		(start 278.051006 -429.572166)
		(end 279.173432 -429.572166)
		(width 0.10668)
		(layer "F.Cu")
		(net "PWRGD_P3V3_AUX_PDB_BUF_R")
	)
	(segment
		(start 279.173432 -429.572166)
		(end 279.270206 -429.66894)
		(width 0.10668)
		(layer "F.Cu")
		(net "PWRGD_P3V3_AUX_PDB_BUF_R")
	)
	(via
		(at 279.173432 -429.572166)
		(size 0.508)
		(drill 0.254)
		(layers "F.Cu" "B.Cu")
		(net "PWRGD_P3V3_AUX_PDB_BUF_R")
	)
	(segment
		(start 276.133814 -428.935896)
		(end 276.513544 -428.556166)
		(width 0.10668)
		(layer "F.Cu")
		(net "PWRGD_P3V3_AUX_PDB_BUF")
	)
	(segment
		(start 276.133814 -428.984156)
		(end 276.133814 -428.935896)
		(width 0.10668)
		(layer "F.Cu")
		(net "PWRGD_P3V3_AUX_PDB_BUF")
	)
	(segment
		(start 276.513544 -428.556166)
		(end 277.250906 -428.556166)
		(width 0.10668)
		(layer "F.Cu")
		(net "PWRGD_P3V3_AUX_PDB_BUF")
	)
	(via
		(at 276.133814 -428.984156)
		(size 0.508)
		(drill 0.254)
		(layers "F.Cu" "B.Cu")
		(net "PWRGD_P3V3_AUX_PDB_BUF")
	)
	(segment
		(start 237.095538 -432.149504)
		(end 237.095538 -427.357794)
		(width 0.11684)
		(layer "In2.Cu")
		(net "PWRGD_P3V3_AUX_PDB_BUF")
	)
	(segment
		(start 276.169882 -428.948088)
		(end 276.133814 -428.984156)
		(width 0.11684)
		(layer "In2.Cu")
		(net "PWRGD_P3V3_AUX_PDB_BUF")
	)
	(segment
		(start 276.169882 -428.112428)
		(end 276.169882 -428.948088)
		(width 0.11684)
		(layer "In2.Cu")
		(net "PWRGD_P3V3_AUX_PDB_BUF")
	)
	(segment
		(start 237.995714 -426.457618)
		(end 274.515072 -426.457618)
		(width 0.11684)
		(layer "In2.Cu")
		(net "PWRGD_P3V3_AUX_PDB_BUF")
	)
	(segment
		(start 236.202982 -433.04206)
		(end 237.095538 -432.149504)
		(width 0.11684)
		(layer "In2.Cu")
		(net "PWRGD_P3V3_AUX_PDB_BUF")
	)
	(segment
		(start 237.095538 -427.357794)
		(end 237.995714 -426.457618)
		(width 0.11684)
		(layer "In2.Cu")
		(net "PWRGD_P3V3_AUX_PDB_BUF")
	)
	(segment
		(start 235.91012 -433.04206)
		(end 236.202982 -433.04206)
		(width 0.11684)
		(layer "In2.Cu")
		(net "PWRGD_P3V3_AUX_PDB_BUF")
	)
	(segment
		(start 274.515072 -426.457618)
		(end 276.169882 -428.112428)
		(width 0.11684)
		(layer "In2.Cu")
		(net "PWRGD_P3V3_AUX_PDB_BUF")
	)
	(segment
		(start 205.603094 -109.561376)
		(end 206.108554 -110.066836)
		(width 0.10668)
		(layer "F.Cu")
		(net "PWRGD_P3V3_AUX_PDB")
	)
	(segment
		(start 211.641182 -108.522262)
		(end 214.331804 -108.522262)
		(width 0.10668)
		(layer "F.Cu")
		(net "PWRGD_P3V3_AUX_PDB")
	)
	(segment
		(start 210.096608 -110.066836)
		(end 211.641182 -108.522262)
		(width 0.10668)
		(layer "F.Cu")
		(net "PWRGD_P3V3_AUX_PDB")
	)
	(segment
		(start 214.331804 -108.522262)
		(end 214.880444 -109.070902)
		(width 0.10668)
		(layer "F.Cu")
		(net "PWRGD_P3V3_AUX_PDB")
	)
	(segment
		(start 282.305506 -434.655976)
		(end 282.942792 -434.655976)
		(width 0.10668)
		(layer "F.Cu")
		(net "PWRGD_P3V3_AUX_PDB")
	)
	(segment
		(start 206.108554 -110.066836)
		(end 210.096608 -110.066836)
		(width 0.10668)
		(layer "F.Cu")
		(net "PWRGD_P3V3_AUX_PDB")
	)
	(via
		(at 282.942792 -434.655976)
		(size 0.508)
		(drill 0.254)
		(layers "F.Cu" "B.Cu")
		(net "PWRGD_P3V3_AUX_PDB")
	)
	(via
		(at 337.420458 -88.760808)
		(size 0.508)
		(drill 0.254)
		(layers "F.Cu" "B.Cu")
		(net "PWRGD_P3V3_AUX_PDB")
	)
	(via
		(at 214.880444 -109.070902)
		(size 0.508)
		(drill 0.254)
		(layers "F.Cu" "B.Cu")
		(net "PWRGD_P3V3_AUX_PDB")
	)
	(via
		(at 317.74765 -120.63603)
		(size 0.508)
		(drill 0.254)
		(layers "F.Cu" "B.Cu")
		(net "PWRGD_P3V3_AUX_PDB")
	)
	(segment
		(start 302.69307 -409.360624)
		(end 301.069502 -409.360624)
		(width 0.11684)
		(layer "In2.Cu")
		(net "PWRGD_P3V3_AUX_PDB")
	)
	(segment
		(start 292.436296 -408.427428)
		(end 292.090856 -408.772868)
		(width 0.11684)
		(layer "In2.Cu")
		(net "PWRGD_P3V3_AUX_PDB")
	)
	(segment
		(start 367.091214 -406.06218)
		(end 367.079784 -406.07361)
		(width 0.11684)
		(layer "In2.Cu")
		(net "PWRGD_P3V3_AUX_PDB")
	)
	(segment
		(start 292.090856 -408.772868)
		(end 288.926016 -408.772868)
		(width 0.11684)
		(layer "In2.Cu")
		(net "PWRGD_P3V3_AUX_PDB")
	)
	(segment
		(start 427.819312 -399.87347)
		(end 427.819312 -400.603212)
		(width 0.11684)
		(layer "In2.Cu")
		(net "PWRGD_P3V3_AUX_PDB")
	)
	(segment
		(start 381.644652 -124.109734)
		(end 397.207994 -124.109734)
		(width 0.11684)
		(layer "In2.Cu")
		(net "PWRGD_P3V3_AUX_PDB")
	)
	(segment
		(start 451.55104 -147.757896)
		(end 451.550786 -147.75815)
		(width 0.11684)
		(layer "In2.Cu")
		(net "PWRGD_P3V3_AUX_PDB")
	)
	(segment
		(start 397.207994 -124.109734)
		(end 399.323814 -121.993914)
		(width 0.11684)
		(layer "In2.Cu")
		(net "PWRGD_P3V3_AUX_PDB")
	)
	(segment
		(start 380.882144 -123.347226)
		(end 381.644652 -124.109734)
		(width 0.11684)
		(layer "In2.Cu")
		(net "PWRGD_P3V3_AUX_PDB")
	)
	(segment
		(start 282.126944 -433.840128)
		(end 282.942792 -434.655976)
		(width 0.11684)
		(layer "In2.Cu")
		(net "PWRGD_P3V3_AUX_PDB")
	)
	(segment
		(start 425.64685 -391.527284)
		(end 425.64685 -399.46961)
		(width 0.11684)
		(layer "In2.Cu")
		(net "PWRGD_P3V3_AUX_PDB")
	)
	(segment
		(start 370.098574 -405.84755)
		(end 369.970812 -405.719788)
		(width 0.11684)
		(layer "In2.Cu")
		(net "PWRGD_P3V3_AUX_PDB")
	)
	(segment
		(start 367.49482 -405.719788)
		(end 367.152428 -406.06218)
		(width 0.11684)
		(layer "In2.Cu")
		(net "PWRGD_P3V3_AUX_PDB")
	)
	(segment
		(start 280.76525 -412.91637)
		(end 280.76525 -425.686474)
		(width 0.11684)
		(layer "In2.Cu")
		(net "PWRGD_P3V3_AUX_PDB")
	)
	(segment
		(start 450.981064 -342.608154)
		(end 450.981064 -363.286548)
		(width 0.11684)
		(layer "In2.Cu")
		(net "PWRGD_P3V3_AUX_PDB")
	)
	(segment
		(start 451.550786 -164.253672)
		(end 462.966816 -175.669702)
		(width 0.11684)
		(layer "In2.Cu")
		(net "PWRGD_P3V3_AUX_PDB")
	)
	(segment
		(start 367.079784 -406.07361)
		(end 363.430566 -406.07361)
		(width 0.11684)
		(layer "In2.Cu")
		(net "PWRGD_P3V3_AUX_PDB")
	)
	(segment
		(start 303.967134 -408.08656)
		(end 302.69307 -409.360624)
		(width 0.11684)
		(layer "In2.Cu")
		(net "PWRGD_P3V3_AUX_PDB")
	)
	(segment
		(start 288.926016 -408.772868)
		(end 288.51606 -409.182824)
		(width 0.11684)
		(layer "In2.Cu")
		(net "PWRGD_P3V3_AUX_PDB")
	)
	(segment
		(start 320.992246 -123.880626)
		(end 351.536254 -123.880626)
		(width 0.11684)
		(layer "In2.Cu")
		(net "PWRGD_P3V3_AUX_PDB")
	)
	(segment
		(start 369.970812 -405.719788)
		(end 367.49482 -405.719788)
		(width 0.11684)
		(layer "In2.Cu")
		(net "PWRGD_P3V3_AUX_PDB")
	)
	(segment
		(start 437.594756 -369.098322)
		(end 428.2821 -378.410978)
		(width 0.11684)
		(layer "In2.Cu")
		(net "PWRGD_P3V3_AUX_PDB")
	)
	(segment
		(start 426.17771 -121.993914)
		(end 451.55104 -147.367244)
		(width 0.11684)
		(layer "In2.Cu")
		(net "PWRGD_P3V3_AUX_PDB")
	)
	(segment
		(start 425.77385 -399.59661)
		(end 427.542452 -399.59661)
		(width 0.11684)
		(layer "In2.Cu")
		(net "PWRGD_P3V3_AUX_PDB")
	)
	(segment
		(start 317.74765 -120.63603)
		(end 320.992246 -123.880626)
		(width 0.11684)
		(layer "In2.Cu")
		(net "PWRGD_P3V3_AUX_PDB")
	)
	(segment
		(start 288.51606 -409.182824)
		(end 286.264858 -409.182824)
		(width 0.11684)
		(layer "In2.Cu")
		(net "PWRGD_P3V3_AUX_PDB")
	)
	(segment
		(start 282.126944 -427.048168)
		(end 282.126944 -433.840128)
		(width 0.11684)
		(layer "In2.Cu")
		(net "PWRGD_P3V3_AUX_PDB")
	)
	(segment
		(start 427.819312 -400.603212)
		(end 427.538642 -400.883882)
		(width 0.11684)
		(layer "In2.Cu")
		(net "PWRGD_P3V3_AUX_PDB")
	)
	(segment
		(start 300.136306 -408.427428)
		(end 292.436296 -408.427428)
		(width 0.11684)
		(layer "In2.Cu")
		(net "PWRGD_P3V3_AUX_PDB")
	)
	(segment
		(start 359.460038 -405.51989)
		(end 356.893368 -408.08656)
		(width 0.11684)
		(layer "In2.Cu")
		(net "PWRGD_P3V3_AUX_PDB")
	)
	(segment
		(start 428.2821 -378.410978)
		(end 428.2821 -388.892034)
		(width 0.11684)
		(layer "In2.Cu")
		(net "PWRGD_P3V3_AUX_PDB")
	)
	(segment
		(start 451.550786 -147.75815)
		(end 451.550786 -164.253672)
		(width 0.11684)
		(layer "In2.Cu")
		(net "PWRGD_P3V3_AUX_PDB")
	)
	(segment
		(start 362.876846 -405.51989)
		(end 359.460038 -405.51989)
		(width 0.11684)
		(layer "In2.Cu")
		(net "PWRGD_P3V3_AUX_PDB")
	)
	(segment
		(start 423.07637 -405.84755)
		(end 370.098574 -405.84755)
		(width 0.11684)
		(layer "In2.Cu")
		(net "PWRGD_P3V3_AUX_PDB")
	)
	(segment
		(start 280.76525 -425.686474)
		(end 282.126944 -427.048168)
		(width 0.11684)
		(layer "In2.Cu")
		(net "PWRGD_P3V3_AUX_PDB")
	)
	(segment
		(start 425.64685 -399.46961)
		(end 425.77385 -399.59661)
		(width 0.11684)
		(layer "In2.Cu")
		(net "PWRGD_P3V3_AUX_PDB")
	)
	(segment
		(start 286.264858 -409.182824)
		(end 285.342076 -410.105606)
		(width 0.11684)
		(layer "In2.Cu")
		(net "PWRGD_P3V3_AUX_PDB")
	)
	(segment
		(start 451.55104 -147.367244)
		(end 451.55104 -147.757896)
		(width 0.11684)
		(layer "In2.Cu")
		(net "PWRGD_P3V3_AUX_PDB")
	)
	(segment
		(start 427.538642 -400.883882)
		(end 427.538642 -401.385278)
		(width 0.11684)
		(layer "In2.Cu")
		(net "PWRGD_P3V3_AUX_PDB")
	)
	(segment
		(start 428.2821 -388.892034)
		(end 425.64685 -391.527284)
		(width 0.11684)
		(layer "In2.Cu")
		(net "PWRGD_P3V3_AUX_PDB")
	)
	(segment
		(start 427.538642 -401.385278)
		(end 423.07637 -405.84755)
		(width 0.11684)
		(layer "In2.Cu")
		(net "PWRGD_P3V3_AUX_PDB")
	)
	(segment
		(start 351.536254 -123.880626)
		(end 352.069654 -123.347226)
		(width 0.11684)
		(layer "In2.Cu")
		(net "PWRGD_P3V3_AUX_PDB")
	)
	(segment
		(start 352.069654 -123.347226)
		(end 380.882144 -123.347226)
		(width 0.11684)
		(layer "In2.Cu")
		(net "PWRGD_P3V3_AUX_PDB")
	)
	(segment
		(start 367.152428 -406.06218)
		(end 367.091214 -406.06218)
		(width 0.11684)
		(layer "In2.Cu")
		(net "PWRGD_P3V3_AUX_PDB")
	)
	(segment
		(start 356.893368 -408.08656)
		(end 303.967134 -408.08656)
		(width 0.11684)
		(layer "In2.Cu")
		(net "PWRGD_P3V3_AUX_PDB")
	)
	(segment
		(start 427.542452 -399.59661)
		(end 427.819312 -399.87347)
		(width 0.11684)
		(layer "In2.Cu")
		(net "PWRGD_P3V3_AUX_PDB")
	)
	(segment
		(start 363.430566 -406.07361)
		(end 362.876846 -405.51989)
		(width 0.11684)
		(layer "In2.Cu")
		(net "PWRGD_P3V3_AUX_PDB")
	)
	(segment
		(start 283.576014 -410.105606)
		(end 280.76525 -412.91637)
		(width 0.11684)
		(layer "In2.Cu")
		(net "PWRGD_P3V3_AUX_PDB")
	)
	(segment
		(start 399.323814 -121.993914)
		(end 426.17771 -121.993914)
		(width 0.11684)
		(layer "In2.Cu")
		(net "PWRGD_P3V3_AUX_PDB")
	)
	(segment
		(start 445.16929 -369.098322)
		(end 437.594756 -369.098322)
		(width 0.11684)
		(layer "In2.Cu")
		(net "PWRGD_P3V3_AUX_PDB")
	)
	(segment
		(start 462.966816 -175.669702)
		(end 462.966816 -330.622402)
		(width 0.11684)
		(layer "In2.Cu")
		(net "PWRGD_P3V3_AUX_PDB")
	)
	(segment
		(start 301.069502 -409.360624)
		(end 300.136306 -408.427428)
		(width 0.11684)
		(layer "In2.Cu")
		(net "PWRGD_P3V3_AUX_PDB")
	)
	(segment
		(start 285.342076 -410.105606)
		(end 283.576014 -410.105606)
		(width 0.11684)
		(layer "In2.Cu")
		(net "PWRGD_P3V3_AUX_PDB")
	)
	(segment
		(start 450.981064 -363.286548)
		(end 445.16929 -369.098322)
		(width 0.11684)
		(layer "In2.Cu")
		(net "PWRGD_P3V3_AUX_PDB")
	)
	(segment
		(start 462.966816 -330.622402)
		(end 450.981064 -342.608154)
		(width 0.11684)
		(layer "In2.Cu")
		(net "PWRGD_P3V3_AUX_PDB")
	)
	(segment
		(start 316.67196 -109.063028)
		(end 316.67196 -117.894608)
		(width 0.11684)
		(layer "In4.Cu")
		(net "PWRGD_P3V3_AUX_PDB")
	)
	(segment
		(start 324.045072 -104.972612)
		(end 321.535044 -107.48264)
		(width 0.11684)
		(layer "In4.Cu")
		(net "PWRGD_P3V3_AUX_PDB")
	)
	(segment
		(start 317.74765 -118.970298)
		(end 317.74765 -120.63603)
		(width 0.11684)
		(layer "In4.Cu")
		(net "PWRGD_P3V3_AUX_PDB")
	)
	(segment
		(start 337.420458 -88.760808)
		(end 324.045072 -102.136194)
		(width 0.11684)
		(layer "In4.Cu")
		(net "PWRGD_P3V3_AUX_PDB")
	)
	(segment
		(start 324.045072 -102.136194)
		(end 324.045072 -104.972612)
		(width 0.11684)
		(layer "In4.Cu")
		(net "PWRGD_P3V3_AUX_PDB")
	)
	(segment
		(start 318.252348 -107.48264)
		(end 316.67196 -109.063028)
		(width 0.11684)
		(layer "In4.Cu")
		(net "PWRGD_P3V3_AUX_PDB")
	)
	(segment
		(start 316.67196 -117.894608)
		(end 317.74765 -118.970298)
		(width 0.11684)
		(layer "In4.Cu")
		(net "PWRGD_P3V3_AUX_PDB")
	)
	(segment
		(start 321.535044 -107.48264)
		(end 318.252348 -107.48264)
		(width 0.11684)
		(layer "In4.Cu")
		(net "PWRGD_P3V3_AUX_PDB")
	)
	(segment
		(start 260.286754 -89.558114)
		(end 257.38582 -89.558114)
		(width 0.11684)
		(layer "In15.Cu")
		(net "PWRGD_P3V3_AUX_PDB")
	)
	(segment
		(start 254.270256 -92.673678)
		(end 249.170444 -92.673678)
		(width 0.11684)
		(layer "In15.Cu")
		(net "PWRGD_P3V3_AUX_PDB")
	)
	(segment
		(start 261.08406 -88.760808)
		(end 260.286754 -89.558114)
		(width 0.11684)
		(layer "In15.Cu")
		(net "PWRGD_P3V3_AUX_PDB")
	)
	(segment
		(start 337.420458 -88.760808)
		(end 261.08406 -88.760808)
		(width 0.11684)
		(layer "In15.Cu")
		(net "PWRGD_P3V3_AUX_PDB")
	)
	(segment
		(start 233.250994 -108.593128)
		(end 222.924624 -108.593128)
		(width 0.11684)
		(layer "In15.Cu")
		(net "PWRGD_P3V3_AUX_PDB")
	)
	(segment
		(start 257.38582 -89.558114)
		(end 254.270256 -92.673678)
		(width 0.11684)
		(layer "In15.Cu")
		(net "PWRGD_P3V3_AUX_PDB")
	)
	(segment
		(start 215.707722 -109.89818)
		(end 214.880444 -109.070902)
		(width 0.11684)
		(layer "In15.Cu")
		(net "PWRGD_P3V3_AUX_PDB")
	)
	(segment
		(start 221.619572 -109.89818)
		(end 215.707722 -109.89818)
		(width 0.11684)
		(layer "In15.Cu")
		(net "PWRGD_P3V3_AUX_PDB")
	)
	(segment
		(start 222.924624 -108.593128)
		(end 221.619572 -109.89818)
		(width 0.11684)
		(layer "In15.Cu")
		(net "PWRGD_P3V3_AUX_PDB")
	)
	(segment
		(start 249.170444 -92.673678)
		(end 233.250994 -108.593128)
		(width 0.11684)
		(layer "In15.Cu")
		(net "PWRGD_P3V3_AUX_PDB")
	)
	(via
		(at 14.71168 -112.700308)
		(size 0.6604)
		(drill 0.3302)
		(layers "F.Cu" "B.Cu")
		(net "PD_U5201_VREG")
	)
	(segment
		(start 13.754862 -112.11941)
		(end 12.876784 -112.11941)
		(width 0.10668)
		(layer "B.Cu")
		(net "PD_U5201_VREG")
	)
	(segment
		(start 14.71168 -112.700308)
		(end 14.33576 -112.700308)
		(width 0.10668)
		(layer "B.Cu")
		(net "PD_U5201_VREG")
	)
	(segment
		(start 14.33576 -112.700308)
		(end 13.754862 -112.11941)
		(width 0.10668)
		(layer "B.Cu")
		(net "PD_U5201_VREG")
	)
	(segment
		(start 14.71168 -112.700308)
		(end 15.831312 -112.700308)
		(width 0.10668)
		(layer "B.Cu")
		(net "PD_U5201_VREG")
	)
	(segment
		(start 15.831312 -112.700308)
		(end 15.837662 -112.693958)
		(width 0.10668)
		(layer "B.Cu")
		(net "PD_U5201_VREG")
	)
	(via
		(at 9.77392 -112.136428)
		(size 0.6604)
		(drill 0.3302)
		(layers "F.Cu" "B.Cu")
		(net "PD_U5201_RSTN")
	)
	(segment
		(start 10.156698 -112.519206)
		(end 11.276584 -112.519206)
		(width 0.10668)
		(layer "B.Cu")
		(net "PD_U5201_RSTN")
	)
	(segment
		(start 9.065006 -112.519206)
		(end 9.391142 -112.519206)
		(width 0.10668)
		(layer "B.Cu")
		(net "PD_U5201_RSTN")
	)
	(segment
		(start 9.77392 -112.136428)
		(end 10.156698 -112.519206)
		(width 0.10668)
		(layer "B.Cu")
		(net "PD_U5201_RSTN")
	)
	(segment
		(start 8.59282 -112.04702)
		(end 9.065006 -112.519206)
		(width 0.10668)
		(layer "B.Cu")
		(net "PD_U5201_RSTN")
	)
	(segment
		(start 9.391142 -112.519206)
		(end 9.77392 -112.136428)
		(width 0.10668)
		(layer "B.Cu")
		(net "PD_U5201_RSTN")
	)
	(via
		(at 9.80948 -113.589308)
		(size 0.6604)
		(drill 0.3302)
		(layers "F.Cu" "B.Cu")
		(net "PD_U5201_EQ")
	)
	(segment
		(start 9.80948 -113.589308)
		(end 10.479532 -112.919256)
		(width 0.10668)
		(layer "B.Cu")
		(net "PD_U5201_EQ")
	)
	(segment
		(start 9.775952 -113.55578)
		(end 9.80948 -113.589308)
		(width 0.10668)
		(layer "B.Cu")
		(net "PD_U5201_EQ")
	)
	(segment
		(start 8.59282 -113.161826)
		(end 8.986774 -113.55578)
		(width 0.10668)
		(layer "B.Cu")
		(net "PD_U5201_EQ")
	)
	(segment
		(start 10.479532 -112.919256)
		(end 11.276584 -112.919256)
		(width 0.10668)
		(layer "B.Cu")
		(net "PD_U5201_EQ")
	)
	(segment
		(start 8.986774 -113.55578)
		(end 9.775952 -113.55578)
		(width 0.10668)
		(layer "B.Cu")
		(net "PD_U5201_EQ")
	)
	(segment
		(start 316.102238 -118.205504)
		(end 316.66561 -117.642132)
		(width 0.10668)
		(layer "F.Cu")
		(net "PD_MB_FRU_WP")
	)
	(segment
		(start 318.737488 -117.950488)
		(end 316.973966 -117.950488)
		(width 0.10668)
		(layer "F.Cu")
		(net "PD_MB_FRU_WP")
	)
	(segment
		(start 314.537852 -118.205504)
		(end 316.102238 -118.205504)
		(width 0.10668)
		(layer "F.Cu")
		(net "PD_MB_FRU_WP")
	)
	(segment
		(start 316.973966 -117.950488)
		(end 316.66561 -117.642132)
		(width 0.10668)
		(layer "F.Cu")
		(net "PD_MB_FRU_WP")
	)
	(via
		(at 316.66561 -117.642132)
		(size 0.762)
		(drill 0.381)
		(layers "F.Cu" "B.Cu")
		(net "PD_MB_FRU_WP")
	)
	(segment
		(start 173.503082 -132.482082)
		(end 173.482 -132.461)
		(width 0.381)
		(layer "F.Cu")
		(net "P5V")
	)
	(segment
		(start 423.57929 -53.388514)
		(end 422.74109 -53.388514)
		(width 0.508)
		(layer "F.Cu")
		(net "P5V")
	)
	(segment
		(start 408.104086 -106.312208)
		(end 393.837668 -120.578626)
		(width 0.4572)
		(layer "F.Cu")
		(net "P5V")
	)
	(segment
		(start 394.827252 -135.635746)
		(end 395.11859 -135.927084)
		(width 0.4572)
		(layer "F.Cu")
		(net "P5V")
	)
	(segment
		(start 172.593 -132.31495)
		(end 173.33595 -132.31495)
		(width 0.381)
		(layer "F.Cu")
		(net "P5V")
	)
	(segment
		(start 395.605762 -146.754342)
		(end 396.58163 -146.754342)
		(width 0.4572)
		(layer "F.Cu")
		(net "P5V")
	)
	(segment
		(start 393.837668 -120.578626)
		(end 393.837668 -124.888244)
		(width 0.4572)
		(layer "F.Cu")
		(net "P5V")
	)
	(segment
		(start 395.11859 -135.927084)
		(end 395.11859 -146.26717)
		(width 0.4572)
		(layer "F.Cu")
		(net "P5V")
	)
	(segment
		(start 172.534326 -135.509)
		(end 173.503082 -134.540244)
		(width 0.381)
		(layer "F.Cu")
		(net "P5V")
	)
	(segment
		(start 171.830746 -132.08)
		(end 172.065696 -132.31495)
		(width 0.381)
		(layer "F.Cu")
		(net "P5V")
	)
	(segment
		(start 409.484576 -106.312208)
		(end 408.104086 -106.312208)
		(width 0.4572)
		(layer "F.Cu")
		(net "P5V")
	)
	(segment
		(start 395.11859 -146.26717)
		(end 395.605762 -146.754342)
		(width 0.4572)
		(layer "F.Cu")
		(net "P5V")
	)
	(segment
		(start 173.503082 -134.540244)
		(end 173.503082 -132.482082)
		(width 0.381)
		(layer "F.Cu")
		(net "P5V")
	)
	(segment
		(start 171.098972 -132.08)
		(end 171.830746 -132.08)
		(width 0.381)
		(layer "F.Cu")
		(net "P5V")
	)
	(segment
		(start 169.81805 -135.509)
		(end 172.534326 -135.509)
		(width 0.381)
		(layer "F.Cu")
		(net "P5V")
	)
	(segment
		(start 329.992228 -43.573954)
		(end 330.601828 -43.573954)
		(width 0.3556)
		(layer "F.Cu")
		(net "P5V")
	)
	(segment
		(start 393.837668 -124.888244)
		(end 394.827252 -125.877828)
		(width 0.4572)
		(layer "F.Cu")
		(net "P5V")
	)
	(segment
		(start 394.827252 -125.877828)
		(end 394.827252 -135.635746)
		(width 0.4572)
		(layer "F.Cu")
		(net "P5V")
	)
	(segment
		(start 173.33595 -132.31495)
		(end 173.482 -132.461)
		(width 0.381)
		(layer "F.Cu")
		(net "P5V")
	)
	(segment
		(start 172.065696 -132.31495)
		(end 172.593 -132.31495)
		(width 0.381)
		(layer "F.Cu")
		(net "P5V")
	)
	(via
		(at 422.74109 -53.388514)
		(size 0.508)
		(drill 0.254)
		(layers "F.Cu" "B.Cu")
		(net "P5V")
	)
	(via
		(at 330.601828 -43.573954)
		(size 0.508)
		(drill 0.254)
		(layers "F.Cu" "B.Cu")
		(net "P5V")
	)
	(via
		(at 399.398744 -147.937982)
		(size 0.508)
		(drill 0.254)
		(layers "F.Cu" "B.Cu")
		(net "P5V")
	)
	(via
		(at 288.180018 -130.52298)
		(size 0.508)
		(drill 0.254)
		(layers "F.Cu" "B.Cu")
		(net "P5V")
	)
	(via
		(at 409.484576 -106.312208)
		(size 0.508)
		(drill 0.254)
		(layers "F.Cu" "B.Cu")
		(net "P5V")
	)
	(via
		(at 398.385284 -148.014182)
		(size 0.508)
		(drill 0.254)
		(layers "F.Cu" "B.Cu")
		(net "P5V")
	)
	(via
		(at 397.620744 -148.826982)
		(size 0.508)
		(drill 0.254)
		(layers "F.Cu" "B.Cu")
		(net "P5V")
	)
	(via
		(at 396.556484 -147.419822)
		(size 0.508)
		(drill 0.254)
		(layers "F.Cu" "B.Cu")
		(net "P5V")
	)
	(via
		(at 173.482 -132.461)
		(size 0.508)
		(drill 0.254)
		(layers "F.Cu" "B.Cu")
		(net "P5V")
	)
	(via
		(at 398.509744 -149.715982)
		(size 0.508)
		(drill 0.254)
		(layers "F.Cu" "B.Cu")
		(net "P5V")
	)
	(via
		(at 399.398744 -148.826982)
		(size 0.508)
		(drill 0.254)
		(layers "F.Cu" "B.Cu")
		(net "P5V")
	)
	(via
		(at 398.509744 -148.826982)
		(size 0.508)
		(drill 0.254)
		(layers "F.Cu" "B.Cu")
		(net "P5V")
	)
	(via
		(at 399.398744 -147.048982)
		(size 0.508)
		(drill 0.254)
		(layers "F.Cu" "B.Cu")
		(net "P5V")
	)
	(via
		(at 209.39252 -131.46913)
		(size 0.508)
		(drill 0.254)
		(layers "F.Cu" "B.Cu")
		(net "P5V")
	)
	(via
		(at 397.496284 -148.014182)
		(size 0.508)
		(drill 0.254)
		(layers "F.Cu" "B.Cu")
		(net "P5V")
	)
	(via
		(at 399.398744 -149.715982)
		(size 0.508)
		(drill 0.254)
		(layers "F.Cu" "B.Cu")
		(net "P5V")
	)
	(via
		(at 396.752064 -149.296882)
		(size 0.508)
		(drill 0.254)
		(layers "F.Cu" "B.Cu")
		(net "P5V")
	)
	(via
		(at 396.752064 -148.407882)
		(size 0.508)
		(drill 0.254)
		(layers "F.Cu" "B.Cu")
		(net "P5V")
	)
	(via
		(at 397.620744 -149.715982)
		(size 0.508)
		(drill 0.254)
		(layers "F.Cu" "B.Cu")
		(net "P5V")
	)
	(via
		(at 314.475876 -65.692782)
		(size 0.508)
		(drill 0.254)
		(layers "F.Cu" "B.Cu")
		(net "P5V")
	)
	(segment
		(start 314.475876 -66.308732)
		(end 314.475876 -65.692782)
		(width 0.4572)
		(layer "B.Cu")
		(net "P5V")
	)
	(segment
		(start 401.762976 -43.632882)
		(end 401.762976 -77.830172)
		(width 0.508)
		(layer "In2.Cu")
		(net "P5V")
	)
	(segment
		(start 330.601828 -43.573954)
		(end 332.280514 -43.573954)
		(width 0.508)
		(layer "In2.Cu")
		(net "P5V")
	)
	(segment
		(start 408.977084 -105.804716)
		(end 409.484576 -106.312208)
		(width 0.508)
		(layer "In2.Cu")
		(net "P5V")
	)
	(segment
		(start 332.280514 -43.573954)
		(end 335.456276 -46.749716)
		(width 0.508)
		(layer "In2.Cu")
		(net "P5V")
	)
	(segment
		(start 408.977084 -85.04428)
		(end 408.977084 -105.804716)
		(width 0.508)
		(layer "In2.Cu")
		(net "P5V")
	)
	(segment
		(start 335.456276 -46.749716)
		(end 360.69778 -46.749716)
		(width 0.508)
		(layer "In2.Cu")
		(net "P5V")
	)
	(segment
		(start 400.857466 -42.727372)
		(end 401.762976 -43.632882)
		(width 0.508)
		(layer "In2.Cu")
		(net "P5V")
	)
	(segment
		(start 364.720124 -42.727372)
		(end 400.857466 -42.727372)
		(width 0.508)
		(layer "In2.Cu")
		(net "P5V")
	)
	(segment
		(start 360.69778 -46.749716)
		(end 364.720124 -42.727372)
		(width 0.508)
		(layer "In2.Cu")
		(net "P5V")
	)
	(segment
		(start 401.762976 -77.830172)
		(end 408.977084 -85.04428)
		(width 0.508)
		(layer "In2.Cu")
		(net "P5V")
	)
	(segment
		(start 314.475876 -65.692782)
		(end 314.475876 -60.898786)
		(width 0.508)
		(layer "In4.Cu")
		(net "P5V")
	)
	(segment
		(start 288.825178 -126.657354)
		(end 288.825178 -129.87782)
		(width 0.4572)
		(layer "In4.Cu")
		(net "P5V")
	)
	(segment
		(start 316.552834 -58.821828)
		(end 330.177902 -58.821828)
		(width 0.508)
		(layer "In4.Cu")
		(net "P5V")
	)
	(segment
		(start 311.182766 -106.845862)
		(end 311.182766 -121.929906)
		(width 0.4572)
		(layer "In4.Cu")
		(net "P5V")
	)
	(segment
		(start 315.52261 -67.46748)
		(end 315.52261 -102.506018)
		(width 0.4572)
		(layer "In4.Cu")
		(net "P5V")
	)
	(segment
		(start 289.181794 -126.300738)
		(end 288.825178 -126.657354)
		(width 0.4572)
		(layer "In4.Cu")
		(net "P5V")
	)
	(segment
		(start 288.825178 -129.87782)
		(end 288.180018 -130.52298)
		(width 0.4572)
		(layer "In4.Cu")
		(net "P5V")
	)
	(segment
		(start 314.475876 -66.420746)
		(end 315.52261 -67.46748)
		(width 0.4572)
		(layer "In4.Cu")
		(net "P5V")
	)
	(segment
		(start 306.811934 -126.300738)
		(end 289.181794 -126.300738)
		(width 0.4572)
		(layer "In4.Cu")
		(net "P5V")
	)
	(segment
		(start 314.475876 -60.898786)
		(end 316.552834 -58.821828)
		(width 0.508)
		(layer "In4.Cu")
		(net "P5V")
	)
	(segment
		(start 409.484576 -58.831988)
		(end 414.92805 -53.388514)
		(width 0.508)
		(layer "In4.Cu")
		(net "P5V")
	)
	(segment
		(start 330.177902 -58.821828)
		(end 333.498444 -55.501286)
		(width 0.508)
		(layer "In4.Cu")
		(net "P5V")
	)
	(segment
		(start 414.92805 -53.388514)
		(end 422.74109 -53.388514)
		(width 0.508)
		(layer "In4.Cu")
		(net "P5V")
	)
	(segment
		(start 333.498444 -55.501286)
		(end 333.498444 -46.47057)
		(width 0.508)
		(layer "In4.Cu")
		(net "P5V")
	)
	(segment
		(start 315.52261 -102.506018)
		(end 311.182766 -106.845862)
		(width 0.4572)
		(layer "In4.Cu")
		(net "P5V")
	)
	(segment
		(start 333.498444 -46.47057)
		(end 330.601828 -43.573954)
		(width 0.508)
		(layer "In4.Cu")
		(net "P5V")
	)
	(segment
		(start 311.182766 -121.929906)
		(end 306.811934 -126.300738)
		(width 0.4572)
		(layer "In4.Cu")
		(net "P5V")
	)
	(segment
		(start 409.484576 -106.312208)
		(end 409.484576 -58.831988)
		(width 0.508)
		(layer "In4.Cu")
		(net "P5V")
	)
	(segment
		(start 314.475876 -65.692782)
		(end 314.475876 -66.420746)
		(width 0.4572)
		(layer "In4.Cu")
		(net "P5V")
	)
	(segment
		(start 173.482 -132.461)
		(end 173.482 -131.453128)
		(width 0.4572)
		(layer "In13.Cu")
		(net "P5V")
	)
	(segment
		(start 189.996572 -129.59969)
		(end 194.438778 -129.59969)
		(width 0.4572)
		(layer "In13.Cu")
		(net "P5V")
	)
	(segment
		(start 197.136258 -132.29717)
		(end 208.908904 -132.29717)
		(width 0.4572)
		(layer "In13.Cu")
		(net "P5V")
	)
	(segment
		(start 208.908904 -132.29717)
		(end 209.39252 -131.813554)
		(width 0.4572)
		(layer "In13.Cu")
		(net "P5V")
	)
	(segment
		(start 176.097946 -128.837182)
		(end 189.234064 -128.837182)
		(width 0.4572)
		(layer "In13.Cu")
		(net "P5V")
	)
	(segment
		(start 194.438778 -129.59969)
		(end 197.136258 -132.29717)
		(width 0.4572)
		(layer "In13.Cu")
		(net "P5V")
	)
	(segment
		(start 209.39252 -131.813554)
		(end 209.39252 -131.46913)
		(width 0.4572)
		(layer "In13.Cu")
		(net "P5V")
	)
	(segment
		(start 173.482 -131.453128)
		(end 176.097946 -128.837182)
		(width 0.4572)
		(layer "In13.Cu")
		(net "P5V")
	)
	(segment
		(start 189.234064 -128.837182)
		(end 189.996572 -129.59969)
		(width 0.4572)
		(layer "In13.Cu")
		(net "P5V")
	)
	(segment
		(start 258.14147 -126.59868)
		(end 258.359656 -126.380494)
		(width 0.4572)
		(layer "In15.Cu")
		(net "P5V")
	)
	(segment
		(start 210.35899 -129.764028)
		(end 238.691166 -129.764028)
		(width 0.4572)
		(layer "In15.Cu")
		(net "P5V")
	)
	(segment
		(start 210.127596 -129.995422)
		(end 210.35899 -129.764028)
		(width 0.4572)
		(layer "In15.Cu")
		(net "P5V")
	)
	(segment
		(start 209.846672 -131.46913)
		(end 210.127596 -131.188206)
		(width 0.4572)
		(layer "In15.Cu")
		(net "P5V")
	)
	(segment
		(start 251.71273 -127.166624)
		(end 252.893322 -125.986032)
		(width 0.4572)
		(layer "In15.Cu")
		(net "P5V")
	)
	(segment
		(start 246.148098 -128.493266)
		(end 248.63044 -126.010924)
		(width 0.4572)
		(layer "In15.Cu")
		(net "P5V")
	)
	(segment
		(start 286.875728 -129.21869)
		(end 288.180018 -130.52298)
		(width 0.4572)
		(layer "In15.Cu")
		(net "P5V")
	)
	(segment
		(start 250.016264 -126.010924)
		(end 251.171964 -127.166624)
		(width 0.4572)
		(layer "In15.Cu")
		(net "P5V")
	)
	(segment
		(start 251.171964 -127.166624)
		(end 251.71273 -127.166624)
		(width 0.4572)
		(layer "In15.Cu")
		(net "P5V")
	)
	(segment
		(start 239.961928 -128.493266)
		(end 246.148098 -128.493266)
		(width 0.4572)
		(layer "In15.Cu")
		(net "P5V")
	)
	(segment
		(start 238.691166 -129.764028)
		(end 239.961928 -128.493266)
		(width 0.4572)
		(layer "In15.Cu")
		(net "P5V")
	)
	(segment
		(start 209.39252 -131.46913)
		(end 209.846672 -131.46913)
		(width 0.4572)
		(layer "In15.Cu")
		(net "P5V")
	)
	(segment
		(start 210.127596 -131.188206)
		(end 210.127596 -129.995422)
		(width 0.4572)
		(layer "In15.Cu")
		(net "P5V")
	)
	(segment
		(start 248.63044 -126.010924)
		(end 250.016264 -126.010924)
		(width 0.4572)
		(layer "In15.Cu")
		(net "P5V")
	)
	(segment
		(start 286.82315 -129.21869)
		(end 286.875728 -129.21869)
		(width 0.4572)
		(layer "In15.Cu")
		(net "P5V")
	)
	(segment
		(start 272.572226 -128.651254)
		(end 286.255714 -128.651254)
		(width 0.4572)
		(layer "In15.Cu")
		(net "P5V")
	)
	(segment
		(start 286.255714 -128.651254)
		(end 286.82315 -129.21869)
		(width 0.4572)
		(layer "In15.Cu")
		(net "P5V")
	)
	(segment
		(start 253.77902 -125.986032)
		(end 254.391668 -126.59868)
		(width 0.4572)
		(layer "In15.Cu")
		(net "P5V")
	)
	(segment
		(start 258.359656 -126.380494)
		(end 261.370318 -126.380494)
		(width 0.4572)
		(layer "In15.Cu")
		(net "P5V")
	)
	(segment
		(start 271.36852 -127.447548)
		(end 272.572226 -128.651254)
		(width 0.4572)
		(layer "In15.Cu")
		(net "P5V")
	)
	(segment
		(start 254.391668 -126.59868)
		(end 258.14147 -126.59868)
		(width 0.4572)
		(layer "In15.Cu")
		(net "P5V")
	)
	(segment
		(start 252.893322 -125.986032)
		(end 253.77902 -125.986032)
		(width 0.4572)
		(layer "In15.Cu")
		(net "P5V")
	)
	(segment
		(start 261.370318 -126.380494)
		(end 262.437372 -127.447548)
		(width 0.4572)
		(layer "In15.Cu")
		(net "P5V")
	)
	(segment
		(start 262.437372 -127.447548)
		(end 271.36852 -127.447548)
		(width 0.4572)
		(layer "In15.Cu")
		(net "P5V")
	)
	(segment
		(start 125.00864 -377.723908)
		(end 125.00864 -382.942592)
		(width 0.1016)
		(layer "F.Cu")
		(net "P5E_CPU1_P3_TX_C_DP<9>")
	)
	(segment
		(start 124.941584 -383.596896)
		(end 125.018038 -383.520442)
		(width 0.1016)
		(layer "F.Cu")
		(net "P5E_CPU1_P3_TX_C_DP<9>")
	)
	(segment
		(start 124.716032 -383.50571)
		(end 124.807218 -383.596896)
		(width 0.1016)
		(layer "F.Cu")
		(net "P5E_CPU1_P3_TX_C_DP<9>")
	)
	(segment
		(start 125.018038 -383.520442)
		(end 125.018038 -383.402586)
		(width 0.1016)
		(layer "F.Cu")
		(net "P5E_CPU1_P3_TX_C_DP<9>")
	)
	(segment
		(start 124.716032 -383.2352)
		(end 124.716032 -383.50571)
		(width 0.1016)
		(layer "F.Cu")
		(net "P5E_CPU1_P3_TX_C_DP<9>")
	)
	(segment
		(start 125.00864 -382.942592)
		(end 124.716032 -383.2352)
		(width 0.1016)
		(layer "F.Cu")
		(net "P5E_CPU1_P3_TX_C_DP<9>")
	)
	(segment
		(start 124.807218 -383.596896)
		(end 124.941584 -383.596896)
		(width 0.1016)
		(layer "F.Cu")
		(net "P5E_CPU1_P3_TX_C_DP<9>")
	)
	(segment
		(start 125.755146 -371.18798)
		(end 125.755146 -371.527578)
		(width 0.1016)
		(layer "F.Cu")
		(net "P5E_CPU1_P3_TX_C_DP<9>")
	)
	(segment
		(start 127.362204 -375.166382)
		(end 125.152404 -377.376182)
		(width 0.1016)
		(layer "F.Cu")
		(net "P5E_CPU1_P3_TX_C_DP<9>")
	)
	(segment
		(start 126.070614 -372.28907)
		(end 127.23368 -373.452136)
		(width 0.1016)
		(layer "F.Cu")
		(net "P5E_CPU1_P3_TX_C_DP<9>")
	)
	(segment
		(start 125.405896 -370.83873)
		(end 125.755146 -371.18798)
		(width 0.1016)
		(layer "F.Cu")
		(net "P5E_CPU1_P3_TX_C_DP<9>")
	)
	(segment
		(start 127.433578 -373.933466)
		(end 127.433578 -374.994932)
		(width 0.1016)
		(layer "F.Cu")
		(net "P5E_CPU1_P3_TX_C_DP<9>")
	)
	(arc
		(start 127.433578 -374.994932)
		(mid 127.414913 -375.087735)
		(end 127.362204 -375.166382)
		(width 0.1016)
		(layer "F.Cu")
		(net "P5E_CPU1_P3_TX_C_DP<9>")
	)
	(arc
		(start 125.152404 -377.376182)
		(mid 125.04597 -377.53575)
		(end 125.00864 -377.723908)
		(width 0.1016)
		(layer "F.Cu")
		(net "P5E_CPU1_P3_TX_C_DP<9>")
	)
	(arc
		(start 127.23368 -373.452136)
		(mid 127.381541 -373.672913)
		(end 127.433578 -373.933466)
		(width 0.1016)
		(layer "F.Cu")
		(net "P5E_CPU1_P3_TX_C_DP<9>")
	)
	(arc
		(start 125.755146 -371.527578)
		(mid 125.837178 -371.939688)
		(end 126.070614 -372.28907)
		(width 0.1016)
		(layer "F.Cu")
		(net "P5E_CPU1_P3_TX_C_DP<9>")
	)
	(segment
		(start 123.515882 -383.2352)
		(end 123.515882 -383.50571)
		(width 0.1016)
		(layer "F.Cu")
		(net "P5E_CPU1_P3_TX_C_DP<8>")
	)
	(segment
		(start 123.80849 -377.31827)
		(end 123.80849 -382.942592)
		(width 0.1016)
		(layer "F.Cu")
		(net "P5E_CPU1_P3_TX_C_DP<8>")
	)
	(segment
		(start 124.053346 -373.71909)
		(end 124.053346 -376.61723)
		(width 0.1016)
		(layer "F.Cu")
		(net "P5E_CPU1_P3_TX_C_DP<8>")
	)
	(segment
		(start 123.704096 -373.30253)
		(end 124.005848 -373.604282)
		(width 0.1016)
		(layer "F.Cu")
		(net "P5E_CPU1_P3_TX_C_DP<8>")
	)
	(segment
		(start 123.817888 -383.520442)
		(end 123.817888 -383.402586)
		(width 0.1016)
		(layer "F.Cu")
		(net "P5E_CPU1_P3_TX_C_DP<8>")
	)
	(segment
		(start 123.80849 -382.942592)
		(end 123.515882 -383.2352)
		(width 0.1016)
		(layer "F.Cu")
		(net "P5E_CPU1_P3_TX_C_DP<8>")
	)
	(segment
		(start 123.515882 -383.50571)
		(end 123.607068 -383.596896)
		(width 0.1016)
		(layer "F.Cu")
		(net "P5E_CPU1_P3_TX_C_DP<8>")
	)
	(segment
		(start 123.741434 -383.596896)
		(end 123.817888 -383.520442)
		(width 0.1016)
		(layer "F.Cu")
		(net "P5E_CPU1_P3_TX_C_DP<8>")
	)
	(segment
		(start 123.607068 -383.596896)
		(end 123.741434 -383.596896)
		(width 0.1016)
		(layer "F.Cu")
		(net "P5E_CPU1_P3_TX_C_DP<8>")
	)
	(arc
		(start 124.053346 -376.61723)
		(mid 124.02913 -376.76075)
		(end 123.959366 -376.888502)
		(width 0.1016)
		(layer "F.Cu")
		(net "P5E_CPU1_P3_TX_C_DP<8>")
	)
	(arc
		(start 124.005848 -373.604282)
		(mid 124.04099 -373.656971)
		(end 124.053346 -373.71909)
		(width 0.1016)
		(layer "F.Cu")
		(net "P5E_CPU1_P3_TX_C_DP<8>")
	)
	(arc
		(start 123.866148 -377.043696)
		(mid 123.822994 -377.177976)
		(end 123.80849 -377.31827)
		(width 0.1016)
		(layer "F.Cu")
		(net "P5E_CPU1_P3_TX_C_DP<8>")
	)
	(arc
		(start 123.959366 -376.888502)
		(mid 123.90787 -376.963163)
		(end 123.866148 -377.043696)
		(width 0.1016)
		(layer "F.Cu")
		(net "P5E_CPU1_P3_TX_C_DP<8>")
	)
	(segment
		(start 122.351546 -376.18289)
		(end 122.351546 -377.907804)
		(width 0.1016)
		(layer "F.Cu")
		(net "P5E_CPU1_P3_TX_C_DP<7>")
	)
	(segment
		(start 122.590814 -378.664216)
		(end 122.608594 -382.942592)
		(width 0.1016)
		(layer "F.Cu")
		(net "P5E_CPU1_P3_TX_C_DP<7>")
	)
	(segment
		(start 122.608594 -382.942592)
		(end 122.315986 -383.2352)
		(width 0.1016)
		(layer "F.Cu")
		(net "P5E_CPU1_P3_TX_C_DP<7>")
	)
	(segment
		(start 122.617992 -383.520442)
		(end 122.617992 -383.402586)
		(width 0.1016)
		(layer "F.Cu")
		(net "P5E_CPU1_P3_TX_C_DP<7>")
	)
	(segment
		(start 122.315986 -383.50571)
		(end 122.407172 -383.596896)
		(width 0.1016)
		(layer "F.Cu")
		(net "P5E_CPU1_P3_TX_C_DP<7>")
	)
	(segment
		(start 122.002296 -375.76633)
		(end 122.304048 -376.068082)
		(width 0.1016)
		(layer "F.Cu")
		(net "P5E_CPU1_P3_TX_C_DP<7>")
	)
	(segment
		(start 122.407172 -383.596896)
		(end 122.541538 -383.596896)
		(width 0.1016)
		(layer "F.Cu")
		(net "P5E_CPU1_P3_TX_C_DP<7>")
	)
	(segment
		(start 122.315986 -383.2352)
		(end 122.315986 -383.50571)
		(width 0.1016)
		(layer "F.Cu")
		(net "P5E_CPU1_P3_TX_C_DP<7>")
	)
	(segment
		(start 122.541538 -383.596896)
		(end 122.617992 -383.520442)
		(width 0.1016)
		(layer "F.Cu")
		(net "P5E_CPU1_P3_TX_C_DP<7>")
	)
	(arc
		(start 122.304048 -376.068082)
		(mid 122.33919 -376.120771)
		(end 122.351546 -376.18289)
		(width 0.1016)
		(layer "F.Cu")
		(net "P5E_CPU1_P3_TX_C_DP<7>")
	)
	(arc
		(start 122.351546 -377.907804)
		(mid 122.392224 -378.171596)
		(end 122.510296 -378.410978)
		(width 0.1016)
		(layer "F.Cu")
		(net "P5E_CPU1_P3_TX_C_DP<7>")
	)
	(arc
		(start 122.510296 -378.410978)
		(mid 122.569858 -378.531463)
		(end 122.590814 -378.664216)
		(width 0.1016)
		(layer "F.Cu")
		(net "P5E_CPU1_P3_TX_C_DP<7>")
	)
	(segment
		(start 121.115836 -383.2352)
		(end 121.115836 -383.50571)
		(width 0.1016)
		(layer "F.Cu")
		(net "P5E_CPU1_P3_TX_C_DP<6>")
	)
	(segment
		(start 119.274336 -372.267734)
		(end 120.506744 -373.500142)
		(width 0.1016)
		(layer "F.Cu")
		(net "P5E_CPU1_P3_TX_C_DP<6>")
	)
	(segment
		(start 121.408444 -381.694436)
		(end 121.408444 -382.942592)
		(width 0.1016)
		(layer "F.Cu")
		(net "P5E_CPU1_P3_TX_C_DP<6>")
	)
	(segment
		(start 120.809258 -378.733558)
		(end 120.845834 -378.823474)
		(width 0.1016)
		(layer "F.Cu")
		(net "P5E_CPU1_P3_TX_C_DP<6>")
	)
	(segment
		(start 120.667272 -373.886984)
		(end 120.667272 -378.006102)
		(width 0.1016)
		(layer "F.Cu")
		(net "P5E_CPU1_P3_TX_C_DP<6>")
	)
	(segment
		(start 118.598696 -370.83873)
		(end 118.947946 -371.18798)
		(width 0.1016)
		(layer "F.Cu")
		(net "P5E_CPU1_P3_TX_C_DP<6>")
	)
	(segment
		(start 121.417842 -383.520442)
		(end 121.417842 -383.402586)
		(width 0.1016)
		(layer "F.Cu")
		(net "P5E_CPU1_P3_TX_C_DP<6>")
	)
	(segment
		(start 118.947946 -371.18798)
		(end 118.947946 -371.48008)
		(width 0.1016)
		(layer "F.Cu")
		(net "P5E_CPU1_P3_TX_C_DP<6>")
	)
	(segment
		(start 121.408444 -382.942592)
		(end 121.115836 -383.2352)
		(width 0.1016)
		(layer "F.Cu")
		(net "P5E_CPU1_P3_TX_C_DP<6>")
	)
	(segment
		(start 121.115836 -383.50571)
		(end 121.207022 -383.596896)
		(width 0.1016)
		(layer "F.Cu")
		(net "P5E_CPU1_P3_TX_C_DP<6>")
	)
	(segment
		(start 121.207022 -383.596896)
		(end 121.341388 -383.596896)
		(width 0.1016)
		(layer "F.Cu")
		(net "P5E_CPU1_P3_TX_C_DP<6>")
	)
	(segment
		(start 121.341388 -383.596896)
		(end 121.417842 -383.520442)
		(width 0.1016)
		(layer "F.Cu")
		(net "P5E_CPU1_P3_TX_C_DP<6>")
	)
	(arc
		(start 120.845834 -378.823474)
		(mid 121.266403 -380.231663)
		(end 121.408444 -381.694436)
		(width 0.1016)
		(layer "F.Cu")
		(net "P5E_CPU1_P3_TX_C_DP<6>")
	)
	(arc
		(start 118.947946 -371.48008)
		(mid 119.032815 -371.906367)
		(end 119.274336 -372.267734)
		(width 0.1016)
		(layer "F.Cu")
		(net "P5E_CPU1_P3_TX_C_DP<6>")
	)
	(arc
		(start 120.667272 -378.006102)
		(mid 120.703077 -378.376698)
		(end 120.809258 -378.733558)
		(width 0.1016)
		(layer "F.Cu")
		(net "P5E_CPU1_P3_TX_C_DP<6>")
	)
	(arc
		(start 120.506744 -373.500142)
		(mid 120.625501 -373.677597)
		(end 120.667272 -373.886984)
		(width 0.1016)
		(layer "F.Cu")
		(net "P5E_CPU1_P3_TX_C_DP<6>")
	)
	(segment
		(start 120.007126 -383.596896)
		(end 120.141492 -383.596896)
		(width 0.1016)
		(layer "F.Cu")
		(net "P5E_CPU1_P3_TX_C_DP<5>")
	)
	(segment
		(start 120.217946 -383.520442)
		(end 120.217946 -383.402586)
		(width 0.1016)
		(layer "F.Cu")
		(net "P5E_CPU1_P3_TX_C_DP<5>")
	)
	(segment
		(start 119.91594 -383.50571)
		(end 120.007126 -383.596896)
		(width 0.1016)
		(layer "F.Cu")
		(net "P5E_CPU1_P3_TX_C_DP<5>")
	)
	(segment
		(start 117.610128 -376.561858)
		(end 119.54002 -379.448822)
		(width 0.1016)
		(layer "F.Cu")
		(net "P5E_CPU1_P3_TX_C_DP<5>")
	)
	(segment
		(start 120.141492 -383.596896)
		(end 120.217946 -383.520442)
		(width 0.1016)
		(layer "F.Cu")
		(net "P5E_CPU1_P3_TX_C_DP<5>")
	)
	(segment
		(start 119.91594 -383.2352)
		(end 119.91594 -383.50571)
		(width 0.1016)
		(layer "F.Cu")
		(net "P5E_CPU1_P3_TX_C_DP<5>")
	)
	(segment
		(start 120.208548 -381.651764)
		(end 120.208548 -382.942592)
		(width 0.1016)
		(layer "F.Cu")
		(net "P5E_CPU1_P3_TX_C_DP<5>")
	)
	(segment
		(start 116.896896 -373.30253)
		(end 117.246146 -373.65178)
		(width 0.1016)
		(layer "F.Cu")
		(net "P5E_CPU1_P3_TX_C_DP<5>")
	)
	(segment
		(start 117.246146 -373.65178)
		(end 117.246146 -375.362216)
		(width 0.1016)
		(layer "F.Cu")
		(net "P5E_CPU1_P3_TX_C_DP<5>")
	)
	(segment
		(start 120.208548 -382.942592)
		(end 119.91594 -383.2352)
		(width 0.1016)
		(layer "F.Cu")
		(net "P5E_CPU1_P3_TX_C_DP<5>")
	)
	(arc
		(start 117.246146 -375.362216)
		(mid 117.339151 -375.989034)
		(end 117.610128 -376.561858)
		(width 0.1016)
		(layer "F.Cu")
		(net "P5E_CPU1_P3_TX_C_DP<5>")
	)
	(arc
		(start 119.54002 -379.448822)
		(mid 120.037726 -380.500692)
		(end 120.208548 -381.651764)
		(width 0.1016)
		(layer "F.Cu")
		(net "P5E_CPU1_P3_TX_C_DP<5>")
	)
	(segment
		(start 118.80723 -383.596896)
		(end 118.941596 -383.596896)
		(width 0.1016)
		(layer "F.Cu")
		(net "P5E_CPU1_P3_TX_C_DP<4>")
	)
	(segment
		(start 118.716044 -383.2352)
		(end 118.716044 -383.50571)
		(width 0.1016)
		(layer "F.Cu")
		(net "P5E_CPU1_P3_TX_C_DP<4>")
	)
	(segment
		(start 115.788694 -376.921776)
		(end 118.676674 -380.440438)
		(width 0.1016)
		(layer "F.Cu")
		(net "P5E_CPU1_P3_TX_C_DP<4>")
	)
	(segment
		(start 119.008652 -381.572008)
		(end 119.008652 -382.942592)
		(width 0.1016)
		(layer "F.Cu")
		(net "P5E_CPU1_P3_TX_C_DP<4>")
	)
	(segment
		(start 118.716044 -383.50571)
		(end 118.80723 -383.596896)
		(width 0.1016)
		(layer "F.Cu")
		(net "P5E_CPU1_P3_TX_C_DP<4>")
	)
	(segment
		(start 118.941596 -383.596896)
		(end 119.01805 -383.520442)
		(width 0.1016)
		(layer "F.Cu")
		(net "P5E_CPU1_P3_TX_C_DP<4>")
	)
	(segment
		(start 115.195096 -375.76633)
		(end 115.544346 -376.11558)
		(width 0.1016)
		(layer "F.Cu")
		(net "P5E_CPU1_P3_TX_C_DP<4>")
	)
	(segment
		(start 115.544346 -376.11558)
		(end 115.544346 -376.33275)
		(width 0.1016)
		(layer "F.Cu")
		(net "P5E_CPU1_P3_TX_C_DP<4>")
	)
	(segment
		(start 119.01805 -383.520442)
		(end 119.01805 -383.402586)
		(width 0.1016)
		(layer "F.Cu")
		(net "P5E_CPU1_P3_TX_C_DP<4>")
	)
	(segment
		(start 115.544346 -376.33275)
		(end 115.788694 -376.921776)
		(width 0.1016)
		(layer "F.Cu")
		(net "P5E_CPU1_P3_TX_C_DP<4>")
	)
	(segment
		(start 119.008652 -382.942592)
		(end 118.716044 -383.2352)
		(width 0.1016)
		(layer "F.Cu")
		(net "P5E_CPU1_P3_TX_C_DP<4>")
	)
	(arc
		(start 118.676674 -380.440438)
		(mid 118.923803 -380.982422)
		(end 119.008652 -381.572008)
		(width 0.1016)
		(layer "F.Cu")
		(net "P5E_CPU1_P3_TX_C_DP<4>")
	)
	(segment
		(start 113.513108 -373.29491)
		(end 113.77422 -373.556022)
		(width 0.1016)
		(layer "F.Cu")
		(net "P5E_CPU1_P3_TX_C_DP<3>")
	)
	(segment
		(start 113.85042 -373.738902)
		(end 113.85042 -375.203466)
		(width 0.1016)
		(layer "F.Cu")
		(net "P5E_CPU1_P3_TX_C_DP<3>")
	)
	(segment
		(start 117.515894 -383.50571)
		(end 117.60708 -383.596896)
		(width 0.1016)
		(layer "F.Cu")
		(net "P5E_CPU1_P3_TX_C_DP<3>")
	)
	(segment
		(start 117.60708 -383.596896)
		(end 117.741446 -383.596896)
		(width 0.1016)
		(layer "F.Cu")
		(net "P5E_CPU1_P3_TX_C_DP<3>")
	)
	(segment
		(start 111.791496 -370.83873)
		(end 112.140746 -371.18798)
		(width 0.1016)
		(layer "F.Cu")
		(net "P5E_CPU1_P3_TX_C_DP<3>")
	)
	(segment
		(start 117.808502 -381.61468)
		(end 117.808502 -382.942592)
		(width 0.1016)
		(layer "F.Cu")
		(net "P5E_CPU1_P3_TX_C_DP<3>")
	)
	(segment
		(start 115.047014 -378.064014)
		(end 117.690138 -381.284734)
		(width 0.1016)
		(layer "F.Cu")
		(net "P5E_CPU1_P3_TX_C_DP<3>")
	)
	(segment
		(start 117.515894 -383.2352)
		(end 117.515894 -383.50571)
		(width 0.1016)
		(layer "F.Cu")
		(net "P5E_CPU1_P3_TX_C_DP<3>")
	)
	(segment
		(start 117.808502 -382.942592)
		(end 117.515894 -383.2352)
		(width 0.1016)
		(layer "F.Cu")
		(net "P5E_CPU1_P3_TX_C_DP<3>")
	)
	(segment
		(start 112.388396 -372.170198)
		(end 113.513108 -373.294656)
		(width 0.1016)
		(layer "F.Cu")
		(net "P5E_CPU1_P3_TX_C_DP<3>")
	)
	(segment
		(start 117.8179 -383.520442)
		(end 117.8179 -383.402586)
		(width 0.1016)
		(layer "F.Cu")
		(net "P5E_CPU1_P3_TX_C_DP<3>")
	)
	(segment
		(start 112.140746 -371.18798)
		(end 112.140746 -371.57152)
		(width 0.1016)
		(layer "F.Cu")
		(net "P5E_CPU1_P3_TX_C_DP<3>")
	)
	(segment
		(start 113.513108 -373.294656)
		(end 113.513108 -373.29491)
		(width 0.1016)
		(layer "F.Cu")
		(net "P5E_CPU1_P3_TX_C_DP<3>")
	)
	(segment
		(start 117.741446 -383.596896)
		(end 117.8179 -383.520442)
		(width 0.1016)
		(layer "F.Cu")
		(net "P5E_CPU1_P3_TX_C_DP<3>")
	)
	(segment
		(start 113.915952 -375.534682)
		(end 114.775996 -377.61164)
		(width 0.1016)
		(layer "F.Cu")
		(net "P5E_CPU1_P3_TX_C_DP<3>")
	)
	(segment
		(start 114.775996 -377.61164)
		(end 115.047014 -378.064014)
		(width 0.1016)
		(layer "F.Cu")
		(net "P5E_CPU1_P3_TX_C_DP<3>")
	)
	(arc
		(start 113.77422 -373.556022)
		(mid 113.830558 -373.639869)
		(end 113.85042 -373.738902)
		(width 0.1016)
		(layer "F.Cu")
		(net "P5E_CPU1_P3_TX_C_DP<3>")
	)
	(arc
		(start 117.690138 -381.284734)
		(mid 117.777995 -381.439418)
		(end 117.808502 -381.61468)
		(width 0.1016)
		(layer "F.Cu")
		(net "P5E_CPU1_P3_TX_C_DP<3>")
	)
	(arc
		(start 113.85042 -375.203466)
		(mid 113.866888 -375.372298)
		(end 113.915952 -375.534682)
		(width 0.1016)
		(layer "F.Cu")
		(net "P5E_CPU1_P3_TX_C_DP<3>")
	)
	(arc
		(start 112.140746 -371.57152)
		(mid 112.205003 -371.895503)
		(end 112.388396 -372.170198)
		(width 0.1016)
		(layer "F.Cu")
		(net "P5E_CPU1_P3_TX_C_DP<3>")
	)
	(segment
		(start 116.315998 -383.50571)
		(end 116.407184 -383.596896)
		(width 0.1016)
		(layer "F.Cu")
		(net "P5E_CPU1_P3_TX_C_DP<2>")
	)
	(segment
		(start 110.089696 -373.30253)
		(end 110.438946 -373.65178)
		(width 0.1016)
		(layer "F.Cu")
		(net "P5E_CPU1_P3_TX_C_DP<2>")
	)
	(segment
		(start 113.088928 -376.682508)
		(end 113.810796 -378.425456)
		(width 0.1016)
		(layer "F.Cu")
		(net "P5E_CPU1_P3_TX_C_DP<2>")
	)
	(segment
		(start 110.438946 -373.65178)
		(end 110.438946 -374.282208)
		(width 0.1016)
		(layer "F.Cu")
		(net "P5E_CPU1_P3_TX_C_DP<2>")
	)
	(segment
		(start 116.315998 -383.2352)
		(end 116.315998 -383.50571)
		(width 0.1016)
		(layer "F.Cu")
		(net "P5E_CPU1_P3_TX_C_DP<2>")
	)
	(segment
		(start 116.54155 -383.596896)
		(end 116.618004 -383.520442)
		(width 0.1016)
		(layer "F.Cu")
		(net "P5E_CPU1_P3_TX_C_DP<2>")
	)
	(segment
		(start 110.696756 -374.904762)
		(end 110.744762 -374.952768)
		(width 0.1016)
		(layer "F.Cu")
		(net "P5E_CPU1_P3_TX_C_DP<2>")
	)
	(segment
		(start 116.608606 -382.942592)
		(end 116.315998 -383.2352)
		(width 0.1016)
		(layer "F.Cu")
		(net "P5E_CPU1_P3_TX_C_DP<2>")
	)
	(segment
		(start 111.16564 -375.2342)
		(end 112.080548 -375.613168)
		(width 0.1016)
		(layer "F.Cu")
		(net "P5E_CPU1_P3_TX_C_DP<2>")
	)
	(segment
		(start 113.810796 -378.425456)
		(end 113.95329 -378.662692)
		(width 0.1016)
		(layer "F.Cu")
		(net "P5E_CPU1_P3_TX_C_DP<2>")
	)
	(segment
		(start 112.131856 -375.647458)
		(end 112.931448 -376.44705)
		(width 0.1016)
		(layer "F.Cu")
		(net "P5E_CPU1_P3_TX_C_DP<2>")
	)
	(segment
		(start 116.608606 -382.22047)
		(end 116.608606 -382.942592)
		(width 0.1016)
		(layer "F.Cu")
		(net "P5E_CPU1_P3_TX_C_DP<2>")
	)
	(segment
		(start 116.618004 -383.520442)
		(end 116.618004 -383.402586)
		(width 0.1016)
		(layer "F.Cu")
		(net "P5E_CPU1_P3_TX_C_DP<2>")
	)
	(segment
		(start 114.231166 -379.057154)
		(end 116.43741 -381.742696)
		(width 0.1016)
		(layer "F.Cu")
		(net "P5E_CPU1_P3_TX_C_DP<2>")
	)
	(segment
		(start 116.407184 -383.596896)
		(end 116.54155 -383.596896)
		(width 0.1016)
		(layer "F.Cu")
		(net "P5E_CPU1_P3_TX_C_DP<2>")
	)
	(arc
		(start 113.95329 -378.662692)
		(mid 114.084982 -378.865028)
		(end 114.231166 -379.057154)
		(width 0.1016)
		(layer "F.Cu")
		(net "P5E_CPU1_P3_TX_C_DP<2>")
	)
	(arc
		(start 110.744762 -374.952768)
		(mid 110.941346 -375.114205)
		(end 111.16564 -375.2342)
		(width 0.1016)
		(layer "F.Cu")
		(net "P5E_CPU1_P3_TX_C_DP<2>")
	)
	(arc
		(start 110.438946 -374.282208)
		(mid 110.505945 -374.619123)
		(end 110.696756 -374.904762)
		(width 0.1016)
		(layer "F.Cu")
		(net "P5E_CPU1_P3_TX_C_DP<2>")
	)
	(arc
		(start 112.080548 -375.613168)
		(mid 112.107896 -375.627779)
		(end 112.131856 -375.647458)
		(width 0.1016)
		(layer "F.Cu")
		(net "P5E_CPU1_P3_TX_C_DP<2>")
	)
	(arc
		(start 112.931448 -376.44705)
		(mid 113.02181 -376.557008)
		(end 113.088928 -376.682508)
		(width 0.1016)
		(layer "F.Cu")
		(net "P5E_CPU1_P3_TX_C_DP<2>")
	)
	(arc
		(start 116.43741 -381.742696)
		(mid 116.564462 -381.966722)
		(end 116.608606 -382.22047)
		(width 0.1016)
		(layer "F.Cu")
		(net "P5E_CPU1_P3_TX_C_DP<2>")
	)
	(segment
		(start 114.329464 -380.722124)
		(end 115.358164 -381.976122)
		(width 0.1016)
		(layer "F.Cu")
		(net "P5E_CPU1_P3_TX_C_DP<1>")
	)
	(segment
		(start 115.717828 -383.230882)
		(end 115.717828 -383.92227)
		(width 0.1016)
		(layer "F.Cu")
		(net "P5E_CPU1_P3_TX_C_DP<1>")
	)
	(segment
		(start 113.033048 -379.118876)
		(end 113.190274 -379.354588)
		(width 0.1016)
		(layer "F.Cu")
		(net "P5E_CPU1_P3_TX_C_DP<1>")
	)
	(segment
		(start 113.718848 -380.111254)
		(end 114.329464 -380.722124)
		(width 0.1016)
		(layer "F.Cu")
		(net "P5E_CPU1_P3_TX_C_DP<1>")
	)
	(segment
		(start 113.484152 -379.794008)
		(end 113.484152 -379.794262)
		(width 0.1016)
		(layer "F.Cu")
		(net "P5E_CPU1_P3_TX_C_DP<1>")
	)
	(segment
		(start 113.484152 -379.794262)
		(end 113.597944 -379.964442)
		(width 0.1016)
		(layer "F.Cu")
		(net "P5E_CPU1_P3_TX_C_DP<1>")
	)
	(segment
		(start 110.334044 -375.94286)
		(end 110.66145 -376.270266)
		(width 0.1016)
		(layer "F.Cu")
		(net "P5E_CPU1_P3_TX_C_DP<1>")
	)
	(segment
		(start 113.190528 -379.354588)
		(end 113.484152 -379.794008)
		(width 0.1016)
		(layer "F.Cu")
		(net "P5E_CPU1_P3_TX_C_DP<1>")
	)
	(segment
		(start 115.624356 -382.511808)
		(end 115.624356 -383.13741)
		(width 0.1016)
		(layer "F.Cu")
		(net "P5E_CPU1_P3_TX_C_DP<1>")
	)
	(segment
		(start 110.66145 -376.270266)
		(end 110.789212 -376.270266)
		(width 0.1016)
		(layer "F.Cu")
		(net "P5E_CPU1_P3_TX_C_DP<1>")
	)
	(segment
		(start 111.77905 -376.679968)
		(end 112.105186 -377.006104)
		(width 0.1016)
		(layer "F.Cu")
		(net "P5E_CPU1_P3_TX_C_DP<1>")
	)
	(segment
		(start 113.190274 -379.354588)
		(end 113.190528 -379.354588)
		(width 0.1016)
		(layer "F.Cu")
		(net "P5E_CPU1_P3_TX_C_DP<1>")
	)
	(segment
		(start 115.501166 -382.21412)
		(end 115.624356 -382.511808)
		(width 0.1016)
		(layer "F.Cu")
		(net "P5E_CPU1_P3_TX_C_DP<1>")
	)
	(segment
		(start 115.624356 -383.13741)
		(end 115.717828 -383.230882)
		(width 0.1016)
		(layer "F.Cu")
		(net "P5E_CPU1_P3_TX_C_DP<1>")
	)
	(segment
		(start 112.245394 -377.216416)
		(end 113.033048 -379.118876)
		(width 0.1016)
		(layer "F.Cu")
		(net "P5E_CPU1_P3_TX_C_DP<1>")
	)
	(segment
		(start 115.358164 -381.976122)
		(end 115.501166 -382.21412)
		(width 0.1016)
		(layer "F.Cu")
		(net "P5E_CPU1_P3_TX_C_DP<1>")
	)
	(arc
		(start 110.789212 -376.270266)
		(mid 111.3249 -376.376634)
		(end 111.77905 -376.679968)
		(width 0.1016)
		(layer "F.Cu")
		(net "P5E_CPU1_P3_TX_C_DP<1>")
	)
	(arc
		(start 113.597944 -379.964442)
		(mid 113.65479 -380.040818)
		(end 113.718848 -380.111254)
		(width 0.1016)
		(layer "F.Cu")
		(net "P5E_CPU1_P3_TX_C_DP<1>")
	)
	(arc
		(start 112.105186 -377.006104)
		(mid 112.185658 -377.104348)
		(end 112.245394 -377.216416)
		(width 0.1016)
		(layer "F.Cu")
		(net "P5E_CPU1_P3_TX_C_DP<1>")
	)
	(segment
		(start 135.651494 -379.708918)
		(end 135.346694 -379.708918)
		(width 0.1016)
		(layer "F.Cu")
		(net "P5E_CPU1_P3_TX_C_DP<15>")
	)
	(segment
		(start 134.266178 -379.92558)
		(end 132.365242 -381.826516)
		(width 0.1016)
		(layer "F.Cu")
		(net "P5E_CPU1_P3_TX_C_DP<15>")
	)
	(segment
		(start 136.225026 -379.820678)
		(end 135.763254 -379.820678)
		(width 0.1016)
		(layer "F.Cu")
		(net "P5E_CPU1_P3_TX_C_DP<15>")
	)
	(segment
		(start 135.234934 -379.820678)
		(end 134.520178 -379.820678)
		(width 0.1016)
		(layer "F.Cu")
		(net "P5E_CPU1_P3_TX_C_DP<15>")
	)
	(segment
		(start 135.346694 -379.708918)
		(end 135.234934 -379.820678)
		(width 0.1016)
		(layer "F.Cu")
		(net "P5E_CPU1_P3_TX_C_DP<15>")
	)
	(segment
		(start 132.208524 -383.016252)
		(end 132.302504 -383.110232)
		(width 0.1016)
		(layer "F.Cu")
		(net "P5E_CPU1_P3_TX_C_DP<15>")
	)
	(segment
		(start 135.763254 -379.820678)
		(end 135.651494 -379.708918)
		(width 0.1016)
		(layer "F.Cu")
		(net "P5E_CPU1_P3_TX_C_DP<15>")
	)
	(segment
		(start 132.302504 -383.110232)
		(end 132.302504 -383.318004)
		(width 0.1016)
		(layer "F.Cu")
		(net "P5E_CPU1_P3_TX_C_DP<15>")
	)
	(segment
		(start 136.574276 -379.471428)
		(end 136.225026 -379.820678)
		(width 0.1016)
		(layer "F.Cu")
		(net "P5E_CPU1_P3_TX_C_DP<15>")
	)
	(segment
		(start 132.302504 -383.318004)
		(end 132.217922 -383.402586)
		(width 0.1016)
		(layer "F.Cu")
		(net "P5E_CPU1_P3_TX_C_DP<15>")
	)
	(segment
		(start 132.208524 -382.205484)
		(end 132.208524 -383.016252)
		(width 0.1016)
		(layer "F.Cu")
		(net "P5E_CPU1_P3_TX_C_DP<15>")
	)
	(arc
		(start 134.520178 -379.820678)
		(mid 134.382725 -379.847832)
		(end 134.266178 -379.92558)
		(width 0.1016)
		(layer "F.Cu")
		(net "P5E_CPU1_P3_TX_C_DP<15>")
	)
	(arc
		(start 132.365242 -381.826516)
		(mid 132.249177 -382.000404)
		(end 132.208524 -382.205484)
		(width 0.1016)
		(layer "F.Cu")
		(net "P5E_CPU1_P3_TX_C_DP<15>")
	)
	(segment
		(start 131.224782 -381.689102)
		(end 131.224528 -381.688848)
		(width 0.1016)
		(layer "F.Cu")
		(net "P5E_CPU1_P3_TX_C_DP<14>")
	)
	(segment
		(start 136.574276 -376.982228)
		(end 136.36879 -376.776742)
		(width 0.1016)
		(layer "F.Cu")
		(net "P5E_CPU1_P3_TX_C_DP<14>")
	)
	(segment
		(start 135.914638 -376.71883)
		(end 131.422394 -381.211074)
		(width 0.1016)
		(layer "F.Cu")
		(net "P5E_CPU1_P3_TX_C_DP<14>")
	)
	(segment
		(start 136.36879 -376.776742)
		(end 136.22909 -376.71883)
		(width 0.1016)
		(layer "F.Cu")
		(net "P5E_CPU1_P3_TX_C_DP<14>")
	)
	(segment
		(start 131.224528 -382.92659)
		(end 131.318508 -383.02057)
		(width 0.1016)
		(layer "F.Cu")
		(net "P5E_CPU1_P3_TX_C_DP<14>")
	)
	(segment
		(start 131.224528 -381.688848)
		(end 131.224528 -382.92659)
		(width 0.1016)
		(layer "F.Cu")
		(net "P5E_CPU1_P3_TX_C_DP<14>")
	)
	(segment
		(start 131.318508 -383.921762)
		(end 131.318 -383.92227)
		(width 0.1016)
		(layer "F.Cu")
		(net "P5E_CPU1_P3_TX_C_DP<14>")
	)
	(segment
		(start 131.318508 -383.02057)
		(end 131.318508 -383.921762)
		(width 0.1016)
		(layer "F.Cu")
		(net "P5E_CPU1_P3_TX_C_DP<14>")
	)
	(segment
		(start 136.22909 -376.71883)
		(end 135.914638 -376.71883)
		(width 0.1016)
		(layer "F.Cu")
		(net "P5E_CPU1_P3_TX_C_DP<14>")
	)
	(arc
		(start 131.422394 -381.211074)
		(mid 131.276068 -381.430439)
		(end 131.224782 -381.689102)
		(width 0.1016)
		(layer "F.Cu")
		(net "P5E_CPU1_P3_TX_C_DP<14>")
	)
	(segment
		(start 137.46734 -374.55348)
		(end 137.04189 -374.97893)
		(width 0.1016)
		(layer "F.Cu")
		(net "P5E_CPU1_P3_TX_C_DP<13>")
	)
	(segment
		(start 137.64006 -373.866156)
		(end 137.64006 -374.136666)
		(width 0.1016)
		(layer "F.Cu")
		(net "P5E_CPU1_P3_TX_C_DP<13>")
	)
	(segment
		(start 129.741422 -383.596896)
		(end 129.817876 -383.520442)
		(width 0.1016)
		(layer "F.Cu")
		(net "P5E_CPU1_P3_TX_C_DP<13>")
	)
	(segment
		(start 129.607056 -383.596896)
		(end 129.741422 -383.596896)
		(width 0.1016)
		(layer "F.Cu")
		(net "P5E_CPU1_P3_TX_C_DP<13>")
	)
	(segment
		(start 129.817876 -383.520442)
		(end 129.817876 -383.402586)
		(width 0.1016)
		(layer "F.Cu")
		(net "P5E_CPU1_P3_TX_C_DP<13>")
	)
	(segment
		(start 129.51587 -383.2352)
		(end 129.51587 -383.50571)
		(width 0.1016)
		(layer "F.Cu")
		(net "P5E_CPU1_P3_TX_C_DP<13>")
	)
	(segment
		(start 129.51587 -383.50571)
		(end 129.607056 -383.596896)
		(width 0.1016)
		(layer "F.Cu")
		(net "P5E_CPU1_P3_TX_C_DP<13>")
	)
	(segment
		(start 135.616696 -370.83873)
		(end 135.965946 -371.18798)
		(width 0.1016)
		(layer "F.Cu")
		(net "P5E_CPU1_P3_TX_C_DP<13>")
	)
	(segment
		(start 136.756902 -375.09704)
		(end 135.87603 -375.09704)
		(width 0.1016)
		(layer "F.Cu")
		(net "P5E_CPU1_P3_TX_C_DP<13>")
	)
	(segment
		(start 135.965946 -371.18798)
		(end 135.965946 -371.527578)
		(width 0.1016)
		(layer "F.Cu")
		(net "P5E_CPU1_P3_TX_C_DP<13>")
	)
	(segment
		(start 129.808478 -382.942592)
		(end 129.51587 -383.2352)
		(width 0.1016)
		(layer "F.Cu")
		(net "P5E_CPU1_P3_TX_C_DP<13>")
	)
	(segment
		(start 135.305546 -375.333006)
		(end 129.908808 -380.729744)
		(width 0.1016)
		(layer "F.Cu")
		(net "P5E_CPU1_P3_TX_C_DP<13>")
	)
	(segment
		(start 136.280906 -372.288816)
		(end 137.485628 -373.493538)
		(width 0.1016)
		(layer "F.Cu")
		(net "P5E_CPU1_P3_TX_C_DP<13>")
	)
	(segment
		(start 129.808478 -380.972822)
		(end 129.808478 -382.942592)
		(width 0.1016)
		(layer "F.Cu")
		(net "P5E_CPU1_P3_TX_C_DP<13>")
	)
	(arc
		(start 137.04189 -374.97893)
		(mid 136.911151 -375.06635)
		(end 136.756902 -375.09704)
		(width 0.1016)
		(layer "F.Cu")
		(net "P5E_CPU1_P3_TX_C_DP<13>")
	)
	(arc
		(start 137.485628 -373.493538)
		(mid 137.599913 -373.664482)
		(end 137.64006 -373.866156)
		(width 0.1016)
		(layer "F.Cu")
		(net "P5E_CPU1_P3_TX_C_DP<13>")
	)
	(arc
		(start 129.908808 -380.729744)
		(mid 129.834509 -380.841313)
		(end 129.808478 -380.972822)
		(width 0.1016)
		(layer "F.Cu")
		(net "P5E_CPU1_P3_TX_C_DP<13>")
	)
	(arc
		(start 135.87603 -375.09704)
		(mid 135.567293 -375.158246)
		(end 135.305546 -375.333006)
		(width 0.1016)
		(layer "F.Cu")
		(net "P5E_CPU1_P3_TX_C_DP<13>")
	)
	(arc
		(start 137.64006 -374.136666)
		(mid 137.595169 -374.362257)
		(end 137.46734 -374.55348)
		(width 0.1016)
		(layer "F.Cu")
		(net "P5E_CPU1_P3_TX_C_DP<13>")
	)
	(arc
		(start 135.965946 -371.527578)
		(mid 136.047686 -371.939543)
		(end 136.280906 -372.288816)
		(width 0.1016)
		(layer "F.Cu")
		(net "P5E_CPU1_P3_TX_C_DP<13>")
	)
	(segment
		(start 134.27202 -373.657368)
		(end 134.27202 -374.562878)
		(width 0.1016)
		(layer "F.Cu")
		(net "P5E_CPU1_P3_TX_C_DP<12>")
	)
	(segment
		(start 128.61798 -383.520442)
		(end 128.61798 -383.402586)
		(width 0.1016)
		(layer "F.Cu")
		(net "P5E_CPU1_P3_TX_C_DP<12>")
	)
	(segment
		(start 128.315974 -383.50571)
		(end 128.40716 -383.596896)
		(width 0.1016)
		(layer "F.Cu")
		(net "P5E_CPU1_P3_TX_C_DP<12>")
	)
	(segment
		(start 128.608582 -382.942592)
		(end 128.315974 -383.2352)
		(width 0.1016)
		(layer "F.Cu")
		(net "P5E_CPU1_P3_TX_C_DP<12>")
	)
	(segment
		(start 134.199376 -374.737376)
		(end 128.895602 -380.04115)
		(width 0.1016)
		(layer "F.Cu")
		(net "P5E_CPU1_P3_TX_C_DP<12>")
	)
	(segment
		(start 128.315974 -383.2352)
		(end 128.315974 -383.50571)
		(width 0.1016)
		(layer "F.Cu")
		(net "P5E_CPU1_P3_TX_C_DP<12>")
	)
	(segment
		(start 128.541526 -383.596896)
		(end 128.61798 -383.520442)
		(width 0.1016)
		(layer "F.Cu")
		(net "P5E_CPU1_P3_TX_C_DP<12>")
	)
	(segment
		(start 132.814568 -372.147338)
		(end 134.234682 -373.567198)
		(width 0.1016)
		(layer "F.Cu")
		(net "P5E_CPU1_P3_TX_C_DP<12>")
	)
	(segment
		(start 132.213096 -370.83873)
		(end 132.562346 -371.18798)
		(width 0.1016)
		(layer "F.Cu")
		(net "P5E_CPU1_P3_TX_C_DP<12>")
	)
	(segment
		(start 128.608582 -380.734062)
		(end 128.608582 -382.942592)
		(width 0.1016)
		(layer "F.Cu")
		(net "P5E_CPU1_P3_TX_C_DP<12>")
	)
	(segment
		(start 132.562346 -371.18798)
		(end 132.562346 -371.5385)
		(width 0.1016)
		(layer "F.Cu")
		(net "P5E_CPU1_P3_TX_C_DP<12>")
	)
	(segment
		(start 128.40716 -383.596896)
		(end 128.541526 -383.596896)
		(width 0.1016)
		(layer "F.Cu")
		(net "P5E_CPU1_P3_TX_C_DP<12>")
	)
	(arc
		(start 128.895602 -380.04115)
		(mid 128.683181 -380.359061)
		(end 128.608582 -380.734062)
		(width 0.1016)
		(layer "F.Cu")
		(net "P5E_CPU1_P3_TX_C_DP<12>")
	)
	(arc
		(start 134.27202 -374.562878)
		(mid 134.253026 -374.657333)
		(end 134.199376 -374.737376)
		(width 0.1016)
		(layer "F.Cu")
		(net "P5E_CPU1_P3_TX_C_DP<12>")
	)
	(arc
		(start 134.234682 -373.567198)
		(mid 134.262325 -373.608568)
		(end 134.27202 -373.657368)
		(width 0.1016)
		(layer "F.Cu")
		(net "P5E_CPU1_P3_TX_C_DP<12>")
	)
	(arc
		(start 132.562346 -371.5385)
		(mid 132.62789 -371.868013)
		(end 132.814568 -372.147338)
		(width 0.1016)
		(layer "F.Cu")
		(net "P5E_CPU1_P3_TX_C_DP<12>")
	)
	(segment
		(start 130.511296 -373.30253)
		(end 130.860546 -373.65178)
		(width 0.1016)
		(layer "F.Cu")
		(net "P5E_CPU1_P3_TX_C_DP<11>")
	)
	(segment
		(start 127.341376 -383.596896)
		(end 127.41783 -383.520442)
		(width 0.1016)
		(layer "F.Cu")
		(net "P5E_CPU1_P3_TX_C_DP<11>")
	)
	(segment
		(start 127.115824 -383.2352)
		(end 127.115824 -383.50571)
		(width 0.1016)
		(layer "F.Cu")
		(net "P5E_CPU1_P3_TX_C_DP<11>")
	)
	(segment
		(start 127.408432 -382.942592)
		(end 127.115824 -383.2352)
		(width 0.1016)
		(layer "F.Cu")
		(net "P5E_CPU1_P3_TX_C_DP<11>")
	)
	(segment
		(start 130.860546 -373.65178)
		(end 130.860546 -376.236484)
		(width 0.1016)
		(layer "F.Cu")
		(net "P5E_CPU1_P3_TX_C_DP<11>")
	)
	(segment
		(start 127.408432 -379.884178)
		(end 127.408432 -382.942592)
		(width 0.1016)
		(layer "F.Cu")
		(net "P5E_CPU1_P3_TX_C_DP<11>")
	)
	(segment
		(start 130.823208 -376.326654)
		(end 127.507746 -379.642116)
		(width 0.1016)
		(layer "F.Cu")
		(net "P5E_CPU1_P3_TX_C_DP<11>")
	)
	(segment
		(start 127.41783 -383.520442)
		(end 127.41783 -383.402586)
		(width 0.1016)
		(layer "F.Cu")
		(net "P5E_CPU1_P3_TX_C_DP<11>")
	)
	(segment
		(start 127.20701 -383.596896)
		(end 127.341376 -383.596896)
		(width 0.1016)
		(layer "F.Cu")
		(net "P5E_CPU1_P3_TX_C_DP<11>")
	)
	(segment
		(start 127.115824 -383.50571)
		(end 127.20701 -383.596896)
		(width 0.1016)
		(layer "F.Cu")
		(net "P5E_CPU1_P3_TX_C_DP<11>")
	)
	(arc
		(start 127.507746 -379.642116)
		(mid 127.434185 -379.753332)
		(end 127.408432 -379.884178)
		(width 0.1016)
		(layer "F.Cu")
		(net "P5E_CPU1_P3_TX_C_DP<11>")
	)
	(arc
		(start 130.860546 -376.236484)
		(mid 130.85084 -376.285279)
		(end 130.823208 -376.326654)
		(width 0.1016)
		(layer "F.Cu")
		(net "P5E_CPU1_P3_TX_C_DP<11>")
	)
	(segment
		(start 127.541274 -377.429522)
		(end 126.487936 -378.48286)
		(width 0.1016)
		(layer "F.Cu")
		(net "P5E_CPU1_P3_TX_C_DP<10>")
	)
	(segment
		(start 126.007114 -383.596896)
		(end 126.14148 -383.596896)
		(width 0.1016)
		(layer "F.Cu")
		(net "P5E_CPU1_P3_TX_C_DP<10>")
	)
	(segment
		(start 126.14148 -383.596896)
		(end 126.217934 -383.520442)
		(width 0.1016)
		(layer "F.Cu")
		(net "P5E_CPU1_P3_TX_C_DP<10>")
	)
	(segment
		(start 126.208536 -378.904754)
		(end 126.208536 -382.942592)
		(width 0.1016)
		(layer "F.Cu")
		(net "P5E_CPU1_P3_TX_C_DP<10>")
	)
	(segment
		(start 126.208536 -382.942592)
		(end 125.915928 -383.2352)
		(width 0.1016)
		(layer "F.Cu")
		(net "P5E_CPU1_P3_TX_C_DP<10>")
	)
	(segment
		(start 129.120392 -376.292872)
		(end 128.138936 -377.274328)
		(width 0.1016)
		(layer "F.Cu")
		(net "P5E_CPU1_P3_TX_C_DP<10>")
	)
	(segment
		(start 126.217934 -383.520442)
		(end 126.217934 -383.402586)
		(width 0.1016)
		(layer "F.Cu")
		(net "P5E_CPU1_P3_TX_C_DP<10>")
	)
	(segment
		(start 125.915928 -383.50571)
		(end 126.007114 -383.596896)
		(width 0.1016)
		(layer "F.Cu")
		(net "P5E_CPU1_P3_TX_C_DP<10>")
	)
	(segment
		(start 129.15773 -376.114564)
		(end 129.15773 -376.202702)
		(width 0.1016)
		(layer "F.Cu")
		(net "P5E_CPU1_P3_TX_C_DP<10>")
	)
	(segment
		(start 126.487682 -378.48286)
		(end 126.308866 -378.661676)
		(width 0.1016)
		(layer "F.Cu")
		(net "P5E_CPU1_P3_TX_C_DP<10>")
	)
	(segment
		(start 128.024636 -377.321572)
		(end 127.801878 -377.321572)
		(width 0.1016)
		(layer "F.Cu")
		(net "P5E_CPU1_P3_TX_C_DP<10>")
	)
	(segment
		(start 126.487936 -378.48286)
		(end 126.487682 -378.48286)
		(width 0.1016)
		(layer "F.Cu")
		(net "P5E_CPU1_P3_TX_C_DP<10>")
	)
	(segment
		(start 128.809496 -375.76633)
		(end 129.15773 -376.114564)
		(width 0.1016)
		(layer "F.Cu")
		(net "P5E_CPU1_P3_TX_C_DP<10>")
	)
	(segment
		(start 125.915928 -383.2352)
		(end 125.915928 -383.50571)
		(width 0.1016)
		(layer "F.Cu")
		(net "P5E_CPU1_P3_TX_C_DP<10>")
	)
	(arc
		(start 127.801878 -377.321572)
		(mid 127.660838 -377.349627)
		(end 127.541274 -377.429522)
		(width 0.1016)
		(layer "F.Cu")
		(net "P5E_CPU1_P3_TX_C_DP<10>")
	)
	(arc
		(start 129.15773 -376.202702)
		(mid 129.148024 -376.251497)
		(end 129.120392 -376.292872)
		(width 0.1016)
		(layer "F.Cu")
		(net "P5E_CPU1_P3_TX_C_DP<10>")
	)
	(arc
		(start 128.138936 -377.274328)
		(mid 128.086481 -377.309315)
		(end 128.024636 -377.321572)
		(width 0.1016)
		(layer "F.Cu")
		(net "P5E_CPU1_P3_TX_C_DP<10>")
	)
	(arc
		(start 126.308866 -378.661676)
		(mid 126.234567 -378.773245)
		(end 126.208536 -378.904754)
		(width 0.1016)
		(layer "F.Cu")
		(net "P5E_CPU1_P3_TX_C_DP<10>")
	)
	(segment
		(start 111.518192 -382.043432)
		(end 111.822992 -382.043432)
		(width 0.1016)
		(layer "F.Cu")
		(net "P5E_CPU1_P3_TX_C_DP<0>")
	)
	(segment
		(start 112.239552 -382.155192)
		(end 112.351312 -382.043432)
		(width 0.1016)
		(layer "F.Cu")
		(net "P5E_CPU1_P3_TX_C_DP<0>")
	)
	(segment
		(start 114.217958 -383.520442)
		(end 114.217958 -383.402586)
		(width 0.1016)
		(layer "F.Cu")
		(net "P5E_CPU1_P3_TX_C_DP<0>")
	)
	(segment
		(start 114.141504 -383.596896)
		(end 114.217958 -383.520442)
		(width 0.1016)
		(layer "F.Cu")
		(net "P5E_CPU1_P3_TX_C_DP<0>")
	)
	(segment
		(start 112.351312 -382.043432)
		(end 112.852454 -382.043432)
		(width 0.1016)
		(layer "F.Cu")
		(net "P5E_CPU1_P3_TX_C_DP<0>")
	)
	(segment
		(start 111.406432 -382.155192)
		(end 111.518192 -382.043432)
		(width 0.1016)
		(layer "F.Cu")
		(net "P5E_CPU1_P3_TX_C_DP<0>")
	)
	(segment
		(start 113.915952 -383.2352)
		(end 113.915952 -383.50571)
		(width 0.1016)
		(layer "F.Cu")
		(net "P5E_CPU1_P3_TX_C_DP<0>")
	)
	(segment
		(start 110.685072 -382.043432)
		(end 110.989872 -382.043432)
		(width 0.1016)
		(layer "F.Cu")
		(net "P5E_CPU1_P3_TX_C_DP<0>")
	)
	(segment
		(start 114.007138 -383.596896)
		(end 114.141504 -383.596896)
		(width 0.1016)
		(layer "F.Cu")
		(net "P5E_CPU1_P3_TX_C_DP<0>")
	)
	(segment
		(start 113.867184 -382.47447)
		(end 114.20856 -382.817624)
		(width 0.1016)
		(layer "F.Cu")
		(net "P5E_CPU1_P3_TX_C_DP<0>")
	)
	(segment
		(start 110.334044 -382.39446)
		(end 110.685072 -382.043432)
		(width 0.1016)
		(layer "F.Cu")
		(net "P5E_CPU1_P3_TX_C_DP<0>")
	)
	(segment
		(start 111.934752 -382.155192)
		(end 112.239552 -382.155192)
		(width 0.1016)
		(layer "F.Cu")
		(net "P5E_CPU1_P3_TX_C_DP<0>")
	)
	(segment
		(start 113.05032 -382.082802)
		(end 113.655602 -382.332738)
		(width 0.1016)
		(layer "F.Cu")
		(net "P5E_CPU1_P3_TX_C_DP<0>")
	)
	(segment
		(start 111.822992 -382.043432)
		(end 111.934752 -382.155192)
		(width 0.1016)
		(layer "F.Cu")
		(net "P5E_CPU1_P3_TX_C_DP<0>")
	)
	(segment
		(start 114.20856 -382.942592)
		(end 113.915952 -383.2352)
		(width 0.1016)
		(layer "F.Cu")
		(net "P5E_CPU1_P3_TX_C_DP<0>")
	)
	(segment
		(start 111.101632 -382.155192)
		(end 111.406432 -382.155192)
		(width 0.1016)
		(layer "F.Cu")
		(net "P5E_CPU1_P3_TX_C_DP<0>")
	)
	(segment
		(start 113.915952 -383.50571)
		(end 114.007138 -383.596896)
		(width 0.1016)
		(layer "F.Cu")
		(net "P5E_CPU1_P3_TX_C_DP<0>")
	)
	(segment
		(start 114.20856 -382.817624)
		(end 114.20856 -382.942592)
		(width 0.1016)
		(layer "F.Cu")
		(net "P5E_CPU1_P3_TX_C_DP<0>")
	)
	(segment
		(start 110.989872 -382.043432)
		(end 111.101632 -382.155192)
		(width 0.1016)
		(layer "F.Cu")
		(net "P5E_CPU1_P3_TX_C_DP<0>")
	)
	(arc
		(start 112.852454 -382.043432)
		(mid 112.953319 -382.053399)
		(end 113.05032 -382.082802)
		(width 0.1016)
		(layer "F.Cu")
		(net "P5E_CPU1_P3_TX_C_DP<0>")
	)
	(arc
		(start 113.655602 -382.332738)
		(mid 113.768433 -382.393093)
		(end 113.867184 -382.47447)
		(width 0.1016)
		(layer "F.Cu")
		(net "P5E_CPU1_P3_TX_C_DP<0>")
	)
	(segment
		(start 125.318012 -383.230882)
		(end 125.318012 -383.92227)
		(width 0.1016)
		(layer "F.Cu")
		(net "P5E_CPU1_P3_TX_C_DN<9>")
	)
	(segment
		(start 127.515112 -375.31929)
		(end 126.654306 -376.180096)
		(width 0.1016)
		(layer "F.Cu")
		(net "P5E_CPU1_P3_TX_C_DN<9>")
	)
	(segment
		(start 126.223522 -372.136162)
		(end 127.386588 -373.299228)
		(width 0.1016)
		(layer "F.Cu")
		(net "P5E_CPU1_P3_TX_C_DN<9>")
	)
	(segment
		(start 126.280418 -376.553984)
		(end 125.305312 -377.52909)
		(width 0.1016)
		(layer "F.Cu")
		(net "P5E_CPU1_P3_TX_C_DN<9>")
	)
	(segment
		(start 126.438406 -376.553984)
		(end 126.280418 -376.553984)
		(width 0.1016)
		(layer "F.Cu")
		(net "P5E_CPU1_P3_TX_C_DN<9>")
	)
	(segment
		(start 126.654306 -376.338084)
		(end 126.438406 -376.553984)
		(width 0.1016)
		(layer "F.Cu")
		(net "P5E_CPU1_P3_TX_C_DN<9>")
	)
	(segment
		(start 125.971046 -371.18798)
		(end 125.971046 -371.527324)
		(width 0.1016)
		(layer "F.Cu")
		(net "P5E_CPU1_P3_TX_C_DN<9>")
	)
	(segment
		(start 127.649478 -373.933466)
		(end 127.649478 -374.994932)
		(width 0.1016)
		(layer "F.Cu")
		(net "P5E_CPU1_P3_TX_C_DN<9>")
	)
	(segment
		(start 126.320296 -370.83873)
		(end 125.971046 -371.18798)
		(width 0.1016)
		(layer "F.Cu")
		(net "P5E_CPU1_P3_TX_C_DN<9>")
	)
	(segment
		(start 126.654306 -376.180096)
		(end 126.654306 -376.338084)
		(width 0.1016)
		(layer "F.Cu")
		(net "P5E_CPU1_P3_TX_C_DN<9>")
	)
	(segment
		(start 125.22454 -383.13741)
		(end 125.318012 -383.230882)
		(width 0.1016)
		(layer "F.Cu")
		(net "P5E_CPU1_P3_TX_C_DN<9>")
	)
	(segment
		(start 125.22454 -377.723908)
		(end 125.22454 -383.13741)
		(width 0.1016)
		(layer "F.Cu")
		(net "P5E_CPU1_P3_TX_C_DN<9>")
	)
	(arc
		(start 127.649478 -374.994932)
		(mid 127.61456 -375.170478)
		(end 127.515112 -375.31929)
		(width 0.1016)
		(layer "F.Cu")
		(net "P5E_CPU1_P3_TX_C_DN<9>")
	)
	(arc
		(start 125.305312 -377.52909)
		(mid 125.245534 -377.618459)
		(end 125.22454 -377.723908)
		(width 0.1016)
		(layer "F.Cu")
		(net "P5E_CPU1_P3_TX_C_DN<9>")
	)
	(arc
		(start 127.386588 -373.299228)
		(mid 127.581105 -373.590204)
		(end 127.649478 -373.933466)
		(width 0.1016)
		(layer "F.Cu")
		(net "P5E_CPU1_P3_TX_C_DN<9>")
	)
	(arc
		(start 125.971046 -371.527324)
		(mid 126.036776 -371.856827)
		(end 126.223522 -372.136162)
		(width 0.1016)
		(layer "F.Cu")
		(net "P5E_CPU1_P3_TX_C_DN<9>")
	)
	(segment
		(start 124.02439 -383.13741)
		(end 124.117862 -383.230882)
		(width 0.1016)
		(layer "F.Cu")
		(net "P5E_CPU1_P3_TX_C_DN<8>")
	)
	(segment
		(start 124.269246 -375.37136)
		(end 124.269246 -376.616976)
		(width 0.1016)
		(layer "F.Cu")
		(net "P5E_CPU1_P3_TX_C_DN<8>")
	)
	(segment
		(start 124.269246 -373.71909)
		(end 124.269246 -374.84304)
		(width 0.1016)
		(layer "F.Cu")
		(net "P5E_CPU1_P3_TX_C_DN<8>")
	)
	(segment
		(start 124.381006 -375.2596)
		(end 124.269246 -375.37136)
		(width 0.1016)
		(layer "F.Cu")
		(net "P5E_CPU1_P3_TX_C_DN<8>")
	)
	(segment
		(start 124.618496 -373.30253)
		(end 124.316744 -373.604282)
		(width 0.1016)
		(layer "F.Cu")
		(net "P5E_CPU1_P3_TX_C_DN<8>")
	)
	(segment
		(start 124.117862 -383.230882)
		(end 124.117862 -383.92227)
		(width 0.1016)
		(layer "F.Cu")
		(net "P5E_CPU1_P3_TX_C_DN<8>")
	)
	(segment
		(start 124.269246 -374.84304)
		(end 124.381006 -374.9548)
		(width 0.1016)
		(layer "F.Cu")
		(net "P5E_CPU1_P3_TX_C_DN<8>")
	)
	(segment
		(start 124.02439 -377.318016)
		(end 124.02439 -383.13741)
		(width 0.1016)
		(layer "F.Cu")
		(net "P5E_CPU1_P3_TX_C_DN<8>")
	)
	(segment
		(start 124.381006 -374.9548)
		(end 124.381006 -375.2596)
		(width 0.1016)
		(layer "F.Cu")
		(net "P5E_CPU1_P3_TX_C_DN<8>")
	)
	(arc
		(start 124.316744 -373.604282)
		(mid 124.281602 -373.656971)
		(end 124.269246 -373.71909)
		(width 0.1016)
		(layer "F.Cu")
		(net "P5E_CPU1_P3_TX_C_DN<8>")
	)
	(arc
		(start 124.06376 -377.130818)
		(mid 124.034296 -377.222364)
		(end 124.02439 -377.318016)
		(width 0.1016)
		(layer "F.Cu")
		(net "P5E_CPU1_P3_TX_C_DN<8>")
	)
	(arc
		(start 124.269246 -376.616976)
		(mid 124.233249 -376.831347)
		(end 124.129038 -377.022106)
		(width 0.1016)
		(layer "F.Cu")
		(net "P5E_CPU1_P3_TX_C_DN<8>")
	)
	(arc
		(start 124.129038 -377.022106)
		(mid 124.092974 -377.074405)
		(end 124.06376 -377.130818)
		(width 0.1016)
		(layer "F.Cu")
		(net "P5E_CPU1_P3_TX_C_DN<8>")
	)
	(segment
		(start 122.679206 -377.18619)
		(end 122.679206 -377.49099)
		(width 0.1016)
		(layer "F.Cu")
		(net "P5E_CPU1_P3_TX_C_DN<7>")
	)
	(segment
		(start 122.806714 -378.6632)
		(end 122.824494 -382.94183)
		(width 0.1016)
		(layer "F.Cu")
		(net "P5E_CPU1_P3_TX_C_DN<7>")
	)
	(segment
		(start 122.824494 -383.13741)
		(end 122.917966 -383.230882)
		(width 0.1016)
		(layer "F.Cu")
		(net "P5E_CPU1_P3_TX_C_DN<7>")
	)
	(segment
		(start 122.824494 -382.94183)
		(end 122.824494 -383.13741)
		(width 0.1016)
		(layer "F.Cu")
		(net "P5E_CPU1_P3_TX_C_DN<7>")
	)
	(segment
		(start 122.567446 -377.60275)
		(end 122.567446 -377.90755)
		(width 0.1016)
		(layer "F.Cu")
		(net "P5E_CPU1_P3_TX_C_DN<7>")
	)
	(segment
		(start 122.679206 -377.49099)
		(end 122.567446 -377.60275)
		(width 0.1016)
		(layer "F.Cu")
		(net "P5E_CPU1_P3_TX_C_DN<7>")
	)
	(segment
		(start 122.917966 -383.230882)
		(end 122.917966 -383.92227)
		(width 0.1016)
		(layer "F.Cu")
		(net "P5E_CPU1_P3_TX_C_DN<7>")
	)
	(segment
		(start 122.567446 -376.182636)
		(end 122.567446 -377.07443)
		(width 0.1016)
		(layer "F.Cu")
		(net "P5E_CPU1_P3_TX_C_DN<7>")
	)
	(segment
		(start 122.567446 -377.07443)
		(end 122.679206 -377.18619)
		(width 0.1016)
		(layer "F.Cu")
		(net "P5E_CPU1_P3_TX_C_DN<7>")
	)
	(segment
		(start 122.916696 -375.76633)
		(end 122.61469 -376.068336)
		(width 0.1016)
		(layer "F.Cu")
		(net "P5E_CPU1_P3_TX_C_DN<7>")
	)
	(arc
		(start 122.567446 -377.90755)
		(mid 122.597988 -378.106219)
		(end 122.686826 -378.286518)
		(width 0.1016)
		(layer "F.Cu")
		(net "P5E_CPU1_P3_TX_C_DN<7>")
	)
	(arc
		(start 122.686826 -378.286518)
		(mid 122.775525 -378.465706)
		(end 122.806714 -378.6632)
		(width 0.1016)
		(layer "F.Cu")
		(net "P5E_CPU1_P3_TX_C_DN<7>")
	)
	(arc
		(start 122.61469 -376.068336)
		(mid 122.579703 -376.120791)
		(end 122.567446 -376.182636)
		(width 0.1016)
		(layer "F.Cu")
		(net "P5E_CPU1_P3_TX_C_DN<7>")
	)
	(segment
		(start 120.994932 -374.960896)
		(end 120.994932 -375.265696)
		(width 0.1016)
		(layer "F.Cu")
		(net "P5E_CPU1_P3_TX_C_DN<6>")
	)
	(segment
		(start 121.624344 -381.694182)
		(end 121.624344 -383.13741)
		(width 0.1016)
		(layer "F.Cu")
		(net "P5E_CPU1_P3_TX_C_DN<6>")
	)
	(segment
		(start 120.994932 -375.265696)
		(end 120.883172 -375.377456)
		(width 0.1016)
		(layer "F.Cu")
		(net "P5E_CPU1_P3_TX_C_DN<6>")
	)
	(segment
		(start 119.163846 -371.18798)
		(end 119.163846 -371.479826)
		(width 0.1016)
		(layer "F.Cu")
		(net "P5E_CPU1_P3_TX_C_DN<6>")
	)
	(segment
		(start 119.513096 -370.83873)
		(end 119.163846 -371.18798)
		(width 0.1016)
		(layer "F.Cu")
		(net "P5E_CPU1_P3_TX_C_DN<6>")
	)
	(segment
		(start 120.883172 -374.849136)
		(end 120.994932 -374.960896)
		(width 0.1016)
		(layer "F.Cu")
		(net "P5E_CPU1_P3_TX_C_DN<6>")
	)
	(segment
		(start 121.00941 -378.652278)
		(end 121.045986 -378.742194)
		(width 0.1016)
		(layer "F.Cu")
		(net "P5E_CPU1_P3_TX_C_DN<6>")
	)
	(segment
		(start 121.71807 -383.231136)
		(end 121.71807 -383.92227)
		(width 0.1016)
		(layer "F.Cu")
		(net "P5E_CPU1_P3_TX_C_DN<6>")
	)
	(segment
		(start 120.883172 -373.88673)
		(end 120.883172 -374.849136)
		(width 0.1016)
		(layer "F.Cu")
		(net "P5E_CPU1_P3_TX_C_DN<6>")
	)
	(segment
		(start 120.883172 -375.377456)
		(end 120.883172 -378.006356)
		(width 0.1016)
		(layer "F.Cu")
		(net "P5E_CPU1_P3_TX_C_DN<6>")
	)
	(segment
		(start 119.427244 -372.114826)
		(end 120.659652 -373.347234)
		(width 0.1016)
		(layer "F.Cu")
		(net "P5E_CPU1_P3_TX_C_DN<6>")
	)
	(segment
		(start 121.624344 -383.13741)
		(end 121.71807 -383.231136)
		(width 0.1016)
		(layer "F.Cu")
		(net "P5E_CPU1_P3_TX_C_DN<6>")
	)
	(arc
		(start 121.045986 -378.742194)
		(mid 121.478352 -380.190135)
		(end 121.624344 -381.694182)
		(width 0.1016)
		(layer "F.Cu")
		(net "P5E_CPU1_P3_TX_C_DN<6>")
	)
	(arc
		(start 120.883172 -378.006356)
		(mid 120.915045 -378.335425)
		(end 121.00941 -378.652278)
		(width 0.1016)
		(layer "F.Cu")
		(net "P5E_CPU1_P3_TX_C_DN<6>")
	)
	(arc
		(start 120.659652 -373.347234)
		(mid 120.825017 -373.59477)
		(end 120.883172 -373.88673)
		(width 0.1016)
		(layer "F.Cu")
		(net "P5E_CPU1_P3_TX_C_DN<6>")
	)
	(arc
		(start 119.163846 -371.479826)
		(mid 119.232413 -371.823506)
		(end 119.427244 -372.114826)
		(width 0.1016)
		(layer "F.Cu")
		(net "P5E_CPU1_P3_TX_C_DN<6>")
	)
	(segment
		(start 120.51792 -383.230882)
		(end 120.51792 -383.92227)
		(width 0.1016)
		(layer "F.Cu")
		(net "P5E_CPU1_P3_TX_C_DN<5>")
	)
	(segment
		(start 117.573806 -374.945656)
		(end 117.462046 -375.057416)
		(width 0.1016)
		(layer "F.Cu")
		(net "P5E_CPU1_P3_TX_C_DN<5>")
	)
	(segment
		(start 117.573806 -374.640856)
		(end 117.573806 -374.945656)
		(width 0.1016)
		(layer "F.Cu")
		(net "P5E_CPU1_P3_TX_C_DN<5>")
	)
	(segment
		(start 117.811296 -373.30253)
		(end 117.462046 -373.65178)
		(width 0.1016)
		(layer "F.Cu")
		(net "P5E_CPU1_P3_TX_C_DN<5>")
	)
	(segment
		(start 117.462046 -373.65178)
		(end 117.462046 -374.529096)
		(width 0.1016)
		(layer "F.Cu")
		(net "P5E_CPU1_P3_TX_C_DN<5>")
	)
	(segment
		(start 117.462046 -374.529096)
		(end 117.573806 -374.640856)
		(width 0.1016)
		(layer "F.Cu")
		(net "P5E_CPU1_P3_TX_C_DN<5>")
	)
	(segment
		(start 117.789706 -376.44197)
		(end 119.719598 -379.328934)
		(width 0.1016)
		(layer "F.Cu")
		(net "P5E_CPU1_P3_TX_C_DN<5>")
	)
	(segment
		(start 120.424448 -383.13741)
		(end 120.51792 -383.230882)
		(width 0.1016)
		(layer "F.Cu")
		(net "P5E_CPU1_P3_TX_C_DN<5>")
	)
	(segment
		(start 120.424448 -381.651764)
		(end 120.424448 -383.13741)
		(width 0.1016)
		(layer "F.Cu")
		(net "P5E_CPU1_P3_TX_C_DN<5>")
	)
	(segment
		(start 117.462046 -375.057416)
		(end 117.462046 -375.362216)
		(width 0.1016)
		(layer "F.Cu")
		(net "P5E_CPU1_P3_TX_C_DN<5>")
	)
	(arc
		(start 117.462046 -375.362216)
		(mid 117.545767 -375.926402)
		(end 117.789706 -376.44197)
		(width 0.1016)
		(layer "F.Cu")
		(net "P5E_CPU1_P3_TX_C_DN<5>")
	)
	(arc
		(start 119.719598 -379.328934)
		(mid 120.244361 -380.438055)
		(end 120.424448 -381.651764)
		(width 0.1016)
		(layer "F.Cu")
		(net "P5E_CPU1_P3_TX_C_DN<5>")
	)
	(segment
		(start 116.109496 -375.76633)
		(end 115.760246 -376.11558)
		(width 0.1016)
		(layer "F.Cu")
		(net "P5E_CPU1_P3_TX_C_DN<4>")
	)
	(segment
		(start 116.853462 -377.878594)
		(end 118.851426 -380.31293)
		(width 0.1016)
		(layer "F.Cu")
		(net "P5E_CPU1_P3_TX_C_DN<4>")
	)
	(segment
		(start 119.318024 -383.230882)
		(end 119.318024 -383.92227)
		(width 0.1016)
		(layer "F.Cu")
		(net "P5E_CPU1_P3_TX_C_DN<4>")
	)
	(segment
		(start 115.975892 -376.809508)
		(end 116.517928 -377.469908)
		(width 0.1016)
		(layer "F.Cu")
		(net "P5E_CPU1_P3_TX_C_DN<4>")
	)
	(segment
		(start 115.760246 -376.11558)
		(end 115.760246 -376.28957)
		(width 0.1016)
		(layer "F.Cu")
		(net "P5E_CPU1_P3_TX_C_DN<4>")
	)
	(segment
		(start 116.517928 -377.469908)
		(end 116.675154 -377.485402)
		(width 0.1016)
		(layer "F.Cu")
		(net "P5E_CPU1_P3_TX_C_DN<4>")
	)
	(segment
		(start 119.224552 -383.13741)
		(end 119.318024 -383.230882)
		(width 0.1016)
		(layer "F.Cu")
		(net "P5E_CPU1_P3_TX_C_DN<4>")
	)
	(segment
		(start 116.675154 -377.485402)
		(end 116.868702 -377.721114)
		(width 0.1016)
		(layer "F.Cu")
		(net "P5E_CPU1_P3_TX_C_DN<4>")
	)
	(segment
		(start 115.760246 -376.28957)
		(end 115.975892 -376.809508)
		(width 0.1016)
		(layer "F.Cu")
		(net "P5E_CPU1_P3_TX_C_DN<4>")
	)
	(segment
		(start 116.868702 -377.721114)
		(end 116.853462 -377.878594)
		(width 0.1016)
		(layer "F.Cu")
		(net "P5E_CPU1_P3_TX_C_DN<4>")
	)
	(segment
		(start 119.224552 -381.573278)
		(end 119.224552 -383.13741)
		(width 0.1016)
		(layer "F.Cu")
		(net "P5E_CPU1_P3_TX_C_DN<4>")
	)
	(arc
		(start 119.224552 -381.572262)
		(mid 119.224552 -381.57277)
		(end 119.224552 -381.573278)
		(width 0.1016)
		(layer "F.Cu")
		(net "P5E_CPU1_P3_TX_C_DN<4>")
	)
	(arc
		(start 118.851426 -380.31293)
		(mid 119.129078 -380.915208)
		(end 119.224552 -381.5715)
		(width 0.1016)
		(layer "F.Cu")
		(net "P5E_CPU1_P3_TX_C_DN<4>")
	)
	(arc
		(start 119.224552 -381.5715)
		(mid 119.224552 -381.571881)
		(end 119.224552 -381.572262)
		(width 0.1016)
		(layer "F.Cu")
		(net "P5E_CPU1_P3_TX_C_DN<4>")
	)
	(segment
		(start 118.117874 -383.230882)
		(end 118.117874 -383.92227)
		(width 0.1016)
		(layer "F.Cu")
		(net "P5E_CPU1_P3_TX_C_DN<3>")
	)
	(segment
		(start 114.06632 -373.738902)
		(end 114.06632 -375.203466)
		(width 0.1016)
		(layer "F.Cu")
		(net "P5E_CPU1_P3_TX_C_DN<3>")
	)
	(segment
		(start 113.292128 -372.768114)
		(end 113.450116 -372.768114)
		(width 0.1016)
		(layer "F.Cu")
		(net "P5E_CPU1_P3_TX_C_DN<3>")
	)
	(segment
		(start 114.115596 -375.452132)
		(end 114.969544 -377.514358)
		(width 0.1016)
		(layer "F.Cu")
		(net "P5E_CPU1_P3_TX_C_DN<3>")
	)
	(segment
		(start 113.450116 -372.768114)
		(end 113.666016 -372.984014)
		(width 0.1016)
		(layer "F.Cu")
		(net "P5E_CPU1_P3_TX_C_DN<3>")
	)
	(segment
		(start 114.969544 -377.514358)
		(end 115.224052 -377.9393)
		(width 0.1016)
		(layer "F.Cu")
		(net "P5E_CPU1_P3_TX_C_DN<3>")
	)
	(segment
		(start 115.224052 -377.9393)
		(end 117.857016 -381.147574)
		(width 0.1016)
		(layer "F.Cu")
		(net "P5E_CPU1_P3_TX_C_DN<3>")
	)
	(segment
		(start 118.024402 -383.13741)
		(end 118.117874 -383.230882)
		(width 0.1016)
		(layer "F.Cu")
		(net "P5E_CPU1_P3_TX_C_DN<3>")
	)
	(segment
		(start 113.666016 -372.984014)
		(end 113.666016 -373.142002)
		(width 0.1016)
		(layer "F.Cu")
		(net "P5E_CPU1_P3_TX_C_DN<3>")
	)
	(segment
		(start 112.541304 -372.01729)
		(end 113.292128 -372.768114)
		(width 0.1016)
		(layer "F.Cu")
		(net "P5E_CPU1_P3_TX_C_DN<3>")
	)
	(segment
		(start 118.024402 -381.614426)
		(end 118.024402 -383.13741)
		(width 0.1016)
		(layer "F.Cu")
		(net "P5E_CPU1_P3_TX_C_DN<3>")
	)
	(segment
		(start 113.666016 -373.142002)
		(end 113.927128 -373.403114)
		(width 0.1016)
		(layer "F.Cu")
		(net "P5E_CPU1_P3_TX_C_DN<3>")
	)
	(segment
		(start 112.705896 -370.83873)
		(end 112.356646 -371.18798)
		(width 0.1016)
		(layer "F.Cu")
		(net "P5E_CPU1_P3_TX_C_DN<3>")
	)
	(segment
		(start 112.356646 -371.18798)
		(end 112.356646 -371.57152)
		(width 0.1016)
		(layer "F.Cu")
		(net "P5E_CPU1_P3_TX_C_DN<3>")
	)
	(arc
		(start 114.06632 -375.203466)
		(mid 114.0787 -375.33023)
		(end 114.115596 -375.452132)
		(width 0.1016)
		(layer "F.Cu")
		(net "P5E_CPU1_P3_TX_C_DN<3>")
	)
	(arc
		(start 113.927128 -373.403114)
		(mid 114.030122 -373.557161)
		(end 114.06632 -373.738902)
		(width 0.1016)
		(layer "F.Cu")
		(net "P5E_CPU1_P3_TX_C_DN<3>")
	)
	(arc
		(start 117.857016 -381.147574)
		(mid 117.981234 -381.366463)
		(end 118.024402 -381.614426)
		(width 0.1016)
		(layer "F.Cu")
		(net "P5E_CPU1_P3_TX_C_DN<3>")
	)
	(arc
		(start 112.356646 -371.57152)
		(mid 112.404634 -371.812774)
		(end 112.541304 -372.01729)
		(width 0.1016)
		(layer "F.Cu")
		(net "P5E_CPU1_P3_TX_C_DN<3>")
	)
	(segment
		(start 111.004096 -373.30253)
		(end 110.654846 -373.65178)
		(width 0.1016)
		(layer "F.Cu")
		(net "P5E_CPU1_P3_TX_C_DN<2>")
	)
	(segment
		(start 113.288572 -376.599704)
		(end 114.00409 -378.32792)
		(width 0.1016)
		(layer "F.Cu")
		(net "P5E_CPU1_P3_TX_C_DN<2>")
	)
	(segment
		(start 112.953292 -376.00509)
		(end 112.953292 -376.163078)
		(width 0.1016)
		(layer "F.Cu")
		(net "P5E_CPU1_P3_TX_C_DN<2>")
	)
	(segment
		(start 116.917978 -383.230882)
		(end 116.917978 -383.92227)
		(width 0.1016)
		(layer "F.Cu")
		(net "P5E_CPU1_P3_TX_C_DN<2>")
	)
	(segment
		(start 116.824506 -383.13741)
		(end 116.917978 -383.230882)
		(width 0.1016)
		(layer "F.Cu")
		(net "P5E_CPU1_P3_TX_C_DN<2>")
	)
	(segment
		(start 110.849664 -374.751854)
		(end 110.89767 -374.79986)
		(width 0.1016)
		(layer "F.Cu")
		(net "P5E_CPU1_P3_TX_C_DN<2>")
	)
	(segment
		(start 112.579404 -375.78919)
		(end 112.737392 -375.78919)
		(width 0.1016)
		(layer "F.Cu")
		(net "P5E_CPU1_P3_TX_C_DN<2>")
	)
	(segment
		(start 110.654846 -373.65178)
		(end 110.654846 -374.282208)
		(width 0.1016)
		(layer "F.Cu")
		(net "P5E_CPU1_P3_TX_C_DN<2>")
	)
	(segment
		(start 114.00409 -378.32792)
		(end 114.138456 -378.55144)
		(width 0.1016)
		(layer "F.Cu")
		(net "P5E_CPU1_P3_TX_C_DN<2>")
	)
	(segment
		(start 112.284764 -375.49455)
		(end 112.579404 -375.78919)
		(width 0.1016)
		(layer "F.Cu")
		(net "P5E_CPU1_P3_TX_C_DN<2>")
	)
	(segment
		(start 112.737392 -375.78919)
		(end 112.953292 -376.00509)
		(width 0.1016)
		(layer "F.Cu")
		(net "P5E_CPU1_P3_TX_C_DN<2>")
	)
	(segment
		(start 111.248444 -375.034556)
		(end 112.163352 -375.413524)
		(width 0.1016)
		(layer "F.Cu")
		(net "P5E_CPU1_P3_TX_C_DN<2>")
	)
	(segment
		(start 114.398298 -378.919994)
		(end 116.604288 -381.605536)
		(width 0.1016)
		(layer "F.Cu")
		(net "P5E_CPU1_P3_TX_C_DN<2>")
	)
	(segment
		(start 112.953292 -376.163078)
		(end 113.084356 -376.294142)
		(width 0.1016)
		(layer "F.Cu")
		(net "P5E_CPU1_P3_TX_C_DN<2>")
	)
	(segment
		(start 116.824506 -382.220216)
		(end 116.824506 -383.13741)
		(width 0.1016)
		(layer "F.Cu")
		(net "P5E_CPU1_P3_TX_C_DN<2>")
	)
	(arc
		(start 110.89767 -374.79986)
		(mid 111.061508 -374.934467)
		(end 111.248444 -375.034556)
		(width 0.1016)
		(layer "F.Cu")
		(net "P5E_CPU1_P3_TX_C_DN<2>")
	)
	(arc
		(start 116.604288 -381.605536)
		(mid 116.767777 -381.893755)
		(end 116.824506 -382.220216)
		(width 0.1016)
		(layer "F.Cu")
		(net "P5E_CPU1_P3_TX_C_DN<2>")
	)
	(arc
		(start 114.138456 -378.55144)
		(mid 114.261615 -378.740484)
		(end 114.398298 -378.919994)
		(width 0.1016)
		(layer "F.Cu")
		(net "P5E_CPU1_P3_TX_C_DN<2>")
	)
	(arc
		(start 112.163352 -375.413524)
		(mid 112.228059 -375.448045)
		(end 112.284764 -375.49455)
		(width 0.1016)
		(layer "F.Cu")
		(net "P5E_CPU1_P3_TX_C_DN<2>")
	)
	(arc
		(start 113.084356 -376.294142)
		(mid 113.201521 -376.436861)
		(end 113.288572 -376.599704)
		(width 0.1016)
		(layer "F.Cu")
		(net "P5E_CPU1_P3_TX_C_DN<2>")
	)
	(arc
		(start 110.654846 -374.282208)
		(mid 110.705591 -374.53638)
		(end 110.849664 -374.751854)
		(width 0.1016)
		(layer "F.Cu")
		(net "P5E_CPU1_P3_TX_C_DN<2>")
	)
	(segment
		(start 113.14938 -379.883162)
		(end 113.304574 -379.91415)
		(width 0.1016)
		(layer "F.Cu")
		(net "P5E_CPU1_P3_TX_C_DN<1>")
	)
	(segment
		(start 115.181126 -382.100836)
		(end 115.307618 -382.311656)
		(width 0.1016)
		(layer "F.Cu")
		(net "P5E_CPU1_P3_TX_C_DN<1>")
	)
	(segment
		(start 114.16919 -380.867412)
		(end 115.181126 -382.100836)
		(width 0.1016)
		(layer "F.Cu")
		(net "P5E_CPU1_P3_TX_C_DN<1>")
	)
	(segment
		(start 112.04575 -377.298966)
		(end 112.495838 -378.386594)
		(width 0.1016)
		(layer "F.Cu")
		(net "P5E_CPU1_P3_TX_C_DN<1>")
	)
	(segment
		(start 112.698276 -378.874782)
		(end 112.841532 -379.221238)
		(width 0.1016)
		(layer "F.Cu")
		(net "P5E_CPU1_P3_TX_C_DN<1>")
	)
	(segment
		(start 115.307618 -382.311656)
		(end 115.408456 -382.554734)
		(width 0.1016)
		(layer "F.Cu")
		(net "P5E_CPU1_P3_TX_C_DN<1>")
	)
	(segment
		(start 115.408456 -382.554734)
		(end 115.408456 -382.942592)
		(width 0.1016)
		(layer "F.Cu")
		(net "P5E_CPU1_P3_TX_C_DN<1>")
	)
	(segment
		(start 111.626142 -376.832876)
		(end 111.952278 -377.159012)
		(width 0.1016)
		(layer "F.Cu")
		(net "P5E_CPU1_P3_TX_C_DN<1>")
	)
	(segment
		(start 112.495838 -378.386594)
		(end 112.435386 -378.53239)
		(width 0.1016)
		(layer "F.Cu")
		(net "P5E_CPU1_P3_TX_C_DN<1>")
	)
	(segment
		(start 115.115848 -383.2352)
		(end 115.115848 -383.50571)
		(width 0.1016)
		(layer "F.Cu")
		(net "P5E_CPU1_P3_TX_C_DN<1>")
	)
	(segment
		(start 112.979962 -379.62967)
		(end 113.14938 -379.883162)
		(width 0.1016)
		(layer "F.Cu")
		(net "P5E_CPU1_P3_TX_C_DN<1>")
	)
	(segment
		(start 115.3414 -383.596896)
		(end 115.417854 -383.520442)
		(width 0.1016)
		(layer "F.Cu")
		(net "P5E_CPU1_P3_TX_C_DN<1>")
	)
	(segment
		(start 110.705138 -376.486166)
		(end 110.789212 -376.486166)
		(width 0.1016)
		(layer "F.Cu")
		(net "P5E_CPU1_P3_TX_C_DN<1>")
	)
	(segment
		(start 115.408456 -382.942592)
		(end 115.115848 -383.2352)
		(width 0.1016)
		(layer "F.Cu")
		(net "P5E_CPU1_P3_TX_C_DN<1>")
	)
	(segment
		(start 110.334044 -376.85726)
		(end 110.705138 -376.486166)
		(width 0.1016)
		(layer "F.Cu")
		(net "P5E_CPU1_P3_TX_C_DN<1>")
	)
	(segment
		(start 112.841532 -379.221238)
		(end 113.010696 -379.474476)
		(width 0.1016)
		(layer "F.Cu")
		(net "P5E_CPU1_P3_TX_C_DN<1>")
	)
	(segment
		(start 113.010696 -379.474476)
		(end 112.979962 -379.62967)
		(width 0.1016)
		(layer "F.Cu")
		(net "P5E_CPU1_P3_TX_C_DN<1>")
	)
	(segment
		(start 115.207034 -383.596896)
		(end 115.3414 -383.596896)
		(width 0.1016)
		(layer "F.Cu")
		(net "P5E_CPU1_P3_TX_C_DN<1>")
	)
	(segment
		(start 113.304574 -379.91415)
		(end 113.418366 -380.08433)
		(width 0.1016)
		(layer "F.Cu")
		(net "P5E_CPU1_P3_TX_C_DN<1>")
	)
	(segment
		(start 112.551972 -378.81433)
		(end 112.698276 -378.874782)
		(width 0.1016)
		(layer "F.Cu")
		(net "P5E_CPU1_P3_TX_C_DN<1>")
	)
	(segment
		(start 115.115848 -383.50571)
		(end 115.207034 -383.596896)
		(width 0.1016)
		(layer "F.Cu")
		(net "P5E_CPU1_P3_TX_C_DN<1>")
	)
	(segment
		(start 115.417854 -383.520442)
		(end 115.417854 -383.402586)
		(width 0.1016)
		(layer "F.Cu")
		(net "P5E_CPU1_P3_TX_C_DN<1>")
	)
	(segment
		(start 113.56594 -380.264162)
		(end 114.16919 -380.867412)
		(width 0.1016)
		(layer "F.Cu")
		(net "P5E_CPU1_P3_TX_C_DN<1>")
	)
	(segment
		(start 112.435386 -378.53239)
		(end 112.551972 -378.81433)
		(width 0.1016)
		(layer "F.Cu")
		(net "P5E_CPU1_P3_TX_C_DN<1>")
	)
	(arc
		(start 111.952278 -377.159012)
		(mid 112.005917 -377.22438)
		(end 112.04575 -377.298966)
		(width 0.1016)
		(layer "F.Cu")
		(net "P5E_CPU1_P3_TX_C_DN<1>")
	)
	(arc
		(start 113.418366 -380.08433)
		(mid 113.487737 -380.17787)
		(end 113.56594 -380.264162)
		(width 0.1016)
		(layer "F.Cu")
		(net "P5E_CPU1_P3_TX_C_DN<1>")
	)
	(arc
		(start 110.789212 -376.486166)
		(mid 111.242157 -376.57628)
		(end 111.626142 -376.832876)
		(width 0.1016)
		(layer "F.Cu")
		(net "P5E_CPU1_P3_TX_C_DN<1>")
	)
	(segment
		(start 134.419086 -380.078488)
		(end 132.51815 -381.979424)
		(width 0.1016)
		(layer "F.Cu")
		(net "P5E_CPU1_P3_TX_C_DN<15>")
	)
	(segment
		(start 132.424424 -382.92659)
		(end 132.518404 -383.02057)
		(width 0.1016)
		(layer "F.Cu")
		(net "P5E_CPU1_P3_TX_C_DN<15>")
	)
	(segment
		(start 136.574276 -380.385828)
		(end 136.225026 -380.036578)
		(width 0.1016)
		(layer "F.Cu")
		(net "P5E_CPU1_P3_TX_C_DN<15>")
	)
	(segment
		(start 132.424424 -382.205484)
		(end 132.424424 -382.92659)
		(width 0.1016)
		(layer "F.Cu")
		(net "P5E_CPU1_P3_TX_C_DN<15>")
	)
	(segment
		(start 136.225026 -380.036578)
		(end 134.520178 -380.036578)
		(width 0.1016)
		(layer "F.Cu")
		(net "P5E_CPU1_P3_TX_C_DN<15>")
	)
	(segment
		(start 132.518404 -383.921762)
		(end 132.517896 -383.92227)
		(width 0.1016)
		(layer "F.Cu")
		(net "P5E_CPU1_P3_TX_C_DN<15>")
	)
	(segment
		(start 132.518404 -383.02057)
		(end 132.518404 -383.921762)
		(width 0.1016)
		(layer "F.Cu")
		(net "P5E_CPU1_P3_TX_C_DN<15>")
	)
	(arc
		(start 132.51815 -381.979424)
		(mid 132.448795 -382.083127)
		(end 132.424424 -382.205484)
		(width 0.1016)
		(layer "F.Cu")
		(net "P5E_CPU1_P3_TX_C_DN<15>")
	)
	(arc
		(start 134.520178 -380.036578)
		(mid 134.465454 -380.047463)
		(end 134.419086 -380.078488)
		(width 0.1016)
		(layer "F.Cu")
		(net "P5E_CPU1_P3_TX_C_DN<15>")
	)
	(segment
		(start 131.102608 -383.110232)
		(end 131.102608 -383.318004)
		(width 0.1016)
		(layer "F.Cu")
		(net "P5E_CPU1_P3_TX_C_DN<14>")
	)
	(segment
		(start 136.574276 -376.067828)
		(end 136.139174 -376.50293)
		(width 0.1016)
		(layer "F.Cu")
		(net "P5E_CPU1_P3_TX_C_DN<14>")
	)
	(segment
		(start 135.824976 -376.50293)
		(end 131.269486 -381.05842)
		(width 0.1016)
		(layer "F.Cu")
		(net "P5E_CPU1_P3_TX_C_DN<14>")
	)
	(segment
		(start 131.008628 -381.689102)
		(end 131.008628 -383.016252)
		(width 0.1016)
		(layer "F.Cu")
		(net "P5E_CPU1_P3_TX_C_DN<14>")
	)
	(segment
		(start 131.102608 -383.318004)
		(end 131.018026 -383.402586)
		(width 0.1016)
		(layer "F.Cu")
		(net "P5E_CPU1_P3_TX_C_DN<14>")
	)
	(segment
		(start 136.139174 -376.50293)
		(end 135.824976 -376.50293)
		(width 0.1016)
		(layer "F.Cu")
		(net "P5E_CPU1_P3_TX_C_DN<14>")
	)
	(segment
		(start 131.008628 -383.016252)
		(end 131.102608 -383.110232)
		(width 0.1016)
		(layer "F.Cu")
		(net "P5E_CPU1_P3_TX_C_DN<14>")
	)
	(arc
		(start 131.269486 -381.05842)
		(mid 131.076362 -381.347824)
		(end 131.008628 -381.689102)
		(width 0.1016)
		(layer "F.Cu")
		(net "P5E_CPU1_P3_TX_C_DN<14>")
	)
	(segment
		(start 137.049256 -372.75135)
		(end 137.207244 -372.75135)
		(width 0.1016)
		(layer "F.Cu")
		(net "P5E_CPU1_P3_TX_C_DN<13>")
	)
	(segment
		(start 137.207244 -372.75135)
		(end 137.423144 -372.96725)
		(width 0.1016)
		(layer "F.Cu")
		(net "P5E_CPU1_P3_TX_C_DN<13>")
	)
	(segment
		(start 136.531096 -370.83873)
		(end 136.181846 -371.18798)
		(width 0.1016)
		(layer "F.Cu")
		(net "P5E_CPU1_P3_TX_C_DN<13>")
	)
	(segment
		(start 137.85596 -373.866156)
		(end 137.85596 -374.136666)
		(width 0.1016)
		(layer "F.Cu")
		(net "P5E_CPU1_P3_TX_C_DN<13>")
	)
	(segment
		(start 136.181846 -371.527832)
		(end 136.1821 -371.527578)
		(width 0.1016)
		(layer "F.Cu")
		(net "P5E_CPU1_P3_TX_C_DN<13>")
	)
	(segment
		(start 137.423144 -372.96725)
		(end 137.423144 -373.125238)
		(width 0.1016)
		(layer "F.Cu")
		(net "P5E_CPU1_P3_TX_C_DN<13>")
	)
	(segment
		(start 136.433814 -372.135908)
		(end 137.049256 -372.75135)
		(width 0.1016)
		(layer "F.Cu")
		(net "P5E_CPU1_P3_TX_C_DN<13>")
	)
	(segment
		(start 136.756902 -375.31294)
		(end 135.87603 -375.31294)
		(width 0.1016)
		(layer "F.Cu")
		(net "P5E_CPU1_P3_TX_C_DN<13>")
	)
	(segment
		(start 137.423144 -373.125238)
		(end 137.638536 -373.34063)
		(width 0.1016)
		(layer "F.Cu")
		(net "P5E_CPU1_P3_TX_C_DN<13>")
	)
	(segment
		(start 135.458454 -375.485914)
		(end 130.061716 -380.882652)
		(width 0.1016)
		(layer "F.Cu")
		(net "P5E_CPU1_P3_TX_C_DN<13>")
	)
	(segment
		(start 130.024378 -383.13741)
		(end 130.11785 -383.230882)
		(width 0.1016)
		(layer "F.Cu")
		(net "P5E_CPU1_P3_TX_C_DN<13>")
	)
	(segment
		(start 130.11785 -383.230882)
		(end 130.11785 -383.92227)
		(width 0.1016)
		(layer "F.Cu")
		(net "P5E_CPU1_P3_TX_C_DN<13>")
	)
	(segment
		(start 130.024378 -380.972822)
		(end 130.024378 -383.13741)
		(width 0.1016)
		(layer "F.Cu")
		(net "P5E_CPU1_P3_TX_C_DN<13>")
	)
	(segment
		(start 136.181846 -371.18798)
		(end 136.181846 -371.527832)
		(width 0.1016)
		(layer "F.Cu")
		(net "P5E_CPU1_P3_TX_C_DN<13>")
	)
	(segment
		(start 137.620248 -374.706388)
		(end 137.194798 -375.131838)
		(width 0.1016)
		(layer "F.Cu")
		(net "P5E_CPU1_P3_TX_C_DN<13>")
	)
	(arc
		(start 137.194798 -375.131838)
		(mid 136.99386 -375.265915)
		(end 136.756902 -375.31294)
		(width 0.1016)
		(layer "F.Cu")
		(net "P5E_CPU1_P3_TX_C_DN<13>")
	)
	(arc
		(start 135.87603 -375.31294)
		(mid 135.650036 -375.357893)
		(end 135.458454 -375.485914)
		(width 0.1016)
		(layer "F.Cu")
		(net "P5E_CPU1_P3_TX_C_DN<13>")
	)
	(arc
		(start 137.85596 -374.136666)
		(mid 137.794816 -374.445)
		(end 137.620248 -374.706388)
		(width 0.1016)
		(layer "F.Cu")
		(net "P5E_CPU1_P3_TX_C_DN<13>")
	)
	(arc
		(start 137.638536 -373.34063)
		(mid 137.799531 -373.581759)
		(end 137.85596 -373.866156)
		(width 0.1016)
		(layer "F.Cu")
		(net "P5E_CPU1_P3_TX_C_DN<13>")
	)
	(arc
		(start 136.1821 -371.527578)
		(mid 136.247469 -371.856771)
		(end 136.433814 -372.135908)
		(width 0.1016)
		(layer "F.Cu")
		(net "P5E_CPU1_P3_TX_C_DN<13>")
	)
	(arc
		(start 130.061716 -380.882652)
		(mid 130.034073 -380.924022)
		(end 130.024378 -380.972822)
		(width 0.1016)
		(layer "F.Cu")
		(net "P5E_CPU1_P3_TX_C_DN<13>")
	)
	(segment
		(start 134.056628 -372.925594)
		(end 134.272528 -373.141494)
		(width 0.1016)
		(layer "F.Cu")
		(net "P5E_CPU1_P3_TX_C_DN<12>")
	)
	(segment
		(start 132.967476 -371.99443)
		(end 133.89864 -372.925594)
		(width 0.1016)
		(layer "F.Cu")
		(net "P5E_CPU1_P3_TX_C_DN<12>")
	)
	(segment
		(start 134.272528 -373.299482)
		(end 134.38759 -373.414544)
		(width 0.1016)
		(layer "F.Cu")
		(net "P5E_CPU1_P3_TX_C_DN<12>")
	)
	(segment
		(start 133.127496 -370.83873)
		(end 132.778246 -371.18798)
		(width 0.1016)
		(layer "F.Cu")
		(net "P5E_CPU1_P3_TX_C_DN<12>")
	)
	(segment
		(start 128.824482 -383.13741)
		(end 128.917954 -383.230882)
		(width 0.1016)
		(layer "F.Cu")
		(net "P5E_CPU1_P3_TX_C_DN<12>")
	)
	(segment
		(start 128.824482 -380.734062)
		(end 128.824482 -383.13741)
		(width 0.1016)
		(layer "F.Cu")
		(net "P5E_CPU1_P3_TX_C_DN<12>")
	)
	(segment
		(start 134.48792 -373.657368)
		(end 134.48792 -374.563132)
		(width 0.1016)
		(layer "F.Cu")
		(net "P5E_CPU1_P3_TX_C_DN<12>")
	)
	(segment
		(start 128.917954 -383.230882)
		(end 128.917954 -383.92227)
		(width 0.1016)
		(layer "F.Cu")
		(net "P5E_CPU1_P3_TX_C_DN<12>")
	)
	(segment
		(start 134.35203 -374.890284)
		(end 129.04851 -380.194058)
		(width 0.1016)
		(layer "F.Cu")
		(net "P5E_CPU1_P3_TX_C_DN<12>")
	)
	(segment
		(start 132.778246 -371.18798)
		(end 132.778246 -371.5385)
		(width 0.1016)
		(layer "F.Cu")
		(net "P5E_CPU1_P3_TX_C_DN<12>")
	)
	(segment
		(start 133.89864 -372.925594)
		(end 134.056628 -372.925594)
		(width 0.1016)
		(layer "F.Cu")
		(net "P5E_CPU1_P3_TX_C_DN<12>")
	)
	(segment
		(start 134.272528 -373.141494)
		(end 134.272528 -373.299482)
		(width 0.1016)
		(layer "F.Cu")
		(net "P5E_CPU1_P3_TX_C_DN<12>")
	)
	(arc
		(start 132.778246 -371.5385)
		(mid 132.827537 -371.78527)
		(end 132.967476 -371.99443)
		(width 0.1016)
		(layer "F.Cu")
		(net "P5E_CPU1_P3_TX_C_DN<12>")
	)
	(arc
		(start 134.48792 -374.563132)
		(mid 134.452492 -374.740209)
		(end 134.35203 -374.890284)
		(width 0.1016)
		(layer "F.Cu")
		(net "P5E_CPU1_P3_TX_C_DN<12>")
	)
	(arc
		(start 134.38759 -373.414544)
		(mid 134.461894 -373.525982)
		(end 134.48792 -373.657368)
		(width 0.1016)
		(layer "F.Cu")
		(net "P5E_CPU1_P3_TX_C_DN<12>")
	)
	(arc
		(start 129.04851 -380.194058)
		(mid 128.882745 -380.44177)
		(end 128.824482 -380.734062)
		(width 0.1016)
		(layer "F.Cu")
		(net "P5E_CPU1_P3_TX_C_DN<12>")
	)
	(segment
		(start 131.076446 -375.550176)
		(end 131.076446 -376.236484)
		(width 0.1016)
		(layer "F.Cu")
		(net "P5E_CPU1_P3_TX_C_DN<11>")
	)
	(segment
		(start 131.425696 -373.30253)
		(end 131.076446 -373.65178)
		(width 0.1016)
		(layer "F.Cu")
		(net "P5E_CPU1_P3_TX_C_DN<11>")
	)
	(segment
		(start 130.976116 -376.479562)
		(end 127.66167 -379.794008)
		(width 0.1016)
		(layer "F.Cu")
		(net "P5E_CPU1_P3_TX_C_DN<11>")
	)
	(segment
		(start 131.076446 -373.65178)
		(end 131.076446 -375.021856)
		(width 0.1016)
		(layer "F.Cu")
		(net "P5E_CPU1_P3_TX_C_DN<11>")
	)
	(segment
		(start 131.076446 -375.021856)
		(end 131.188206 -375.133616)
		(width 0.1016)
		(layer "F.Cu")
		(net "P5E_CPU1_P3_TX_C_DN<11>")
	)
	(segment
		(start 131.188206 -375.438416)
		(end 131.076446 -375.550176)
		(width 0.1016)
		(layer "F.Cu")
		(net "P5E_CPU1_P3_TX_C_DN<11>")
	)
	(segment
		(start 127.624332 -379.884178)
		(end 127.624332 -383.13741)
		(width 0.1016)
		(layer "F.Cu")
		(net "P5E_CPU1_P3_TX_C_DN<11>")
	)
	(segment
		(start 127.624332 -383.13741)
		(end 127.718058 -383.231136)
		(width 0.1016)
		(layer "F.Cu")
		(net "P5E_CPU1_P3_TX_C_DN<11>")
	)
	(segment
		(start 131.188206 -375.133616)
		(end 131.188206 -375.438416)
		(width 0.1016)
		(layer "F.Cu")
		(net "P5E_CPU1_P3_TX_C_DN<11>")
	)
	(segment
		(start 127.718058 -383.231136)
		(end 127.718058 -383.92227)
		(width 0.1016)
		(layer "F.Cu")
		(net "P5E_CPU1_P3_TX_C_DN<11>")
	)
	(arc
		(start 131.076446 -376.236484)
		(mid 131.050487 -376.368022)
		(end 130.976116 -376.479562)
		(width 0.1016)
		(layer "F.Cu")
		(net "P5E_CPU1_P3_TX_C_DN<11>")
	)
	(arc
		(start 127.66167 -379.794008)
		(mid 127.634027 -379.835378)
		(end 127.624332 -379.884178)
		(width 0.1016)
		(layer "F.Cu")
		(net "P5E_CPU1_P3_TX_C_DN<11>")
	)
	(segment
		(start 126.424436 -378.904754)
		(end 126.424436 -383.13741)
		(width 0.1016)
		(layer "F.Cu")
		(net "P5E_CPU1_P3_TX_C_DN<10>")
	)
	(segment
		(start 126.798578 -378.635768)
		(end 126.64059 -378.635768)
		(width 0.1016)
		(layer "F.Cu")
		(net "P5E_CPU1_P3_TX_C_DN<10>")
	)
	(segment
		(start 127.014224 -378.262388)
		(end 127.014224 -378.420122)
		(width 0.1016)
		(layer "F.Cu")
		(net "P5E_CPU1_P3_TX_C_DN<10>")
	)
	(segment
		(start 126.64059 -378.635768)
		(end 126.461774 -378.814584)
		(width 0.1016)
		(layer "F.Cu")
		(net "P5E_CPU1_P3_TX_C_DN<10>")
	)
	(segment
		(start 129.723896 -375.76633)
		(end 129.37363 -376.116596)
		(width 0.1016)
		(layer "F.Cu")
		(net "P5E_CPU1_P3_TX_C_DN<10>")
	)
	(segment
		(start 126.424436 -383.13741)
		(end 126.517908 -383.230882)
		(width 0.1016)
		(layer "F.Cu")
		(net "P5E_CPU1_P3_TX_C_DN<10>")
	)
	(segment
		(start 127.014224 -378.420122)
		(end 126.798578 -378.635768)
		(width 0.1016)
		(layer "F.Cu")
		(net "P5E_CPU1_P3_TX_C_DN<10>")
	)
	(segment
		(start 126.517908 -383.230882)
		(end 126.517908 -383.92227)
		(width 0.1016)
		(layer "F.Cu")
		(net "P5E_CPU1_P3_TX_C_DN<10>")
	)
	(segment
		(start 129.37363 -376.116596)
		(end 129.37363 -376.202702)
		(width 0.1016)
		(layer "F.Cu")
		(net "P5E_CPU1_P3_TX_C_DN<10>")
	)
	(segment
		(start 129.2733 -376.44578)
		(end 128.29159 -377.427236)
		(width 0.1016)
		(layer "F.Cu")
		(net "P5E_CPU1_P3_TX_C_DN<10>")
	)
	(segment
		(start 128.024382 -377.537472)
		(end 127.802132 -377.537472)
		(width 0.1016)
		(layer "F.Cu")
		(net "P5E_CPU1_P3_TX_C_DN<10>")
	)
	(segment
		(start 127.693928 -377.58243)
		(end 127.014224 -378.262388)
		(width 0.1016)
		(layer "F.Cu")
		(net "P5E_CPU1_P3_TX_C_DN<10>")
	)
	(arc
		(start 126.461774 -378.814584)
		(mid 126.434131 -378.855954)
		(end 126.424436 -378.904754)
		(width 0.1016)
		(layer "F.Cu")
		(net "P5E_CPU1_P3_TX_C_DN<10>")
	)
	(arc
		(start 127.802132 -377.537472)
		(mid 127.743548 -377.549161)
		(end 127.693928 -377.58243)
		(width 0.1016)
		(layer "F.Cu")
		(net "P5E_CPU1_P3_TX_C_DN<10>")
	)
	(arc
		(start 128.29159 -377.427236)
		(mid 128.16895 -377.508932)
		(end 128.024382 -377.537472)
		(width 0.1016)
		(layer "F.Cu")
		(net "P5E_CPU1_P3_TX_C_DN<10>")
	)
	(arc
		(start 129.37363 -376.202702)
		(mid 129.347671 -376.33424)
		(end 129.2733 -376.44578)
		(width 0.1016)
		(layer "F.Cu")
		(net "P5E_CPU1_P3_TX_C_DN<10>")
	)
	(segment
		(start 114.42446 -382.727708)
		(end 114.42446 -383.13741)
		(width 0.1016)
		(layer "F.Cu")
		(net "P5E_CPU1_P3_TX_C_DN<0>")
	)
	(segment
		(start 114.517932 -383.230882)
		(end 114.517932 -383.92227)
		(width 0.1016)
		(layer "F.Cu")
		(net "P5E_CPU1_P3_TX_C_DN<0>")
	)
	(segment
		(start 114.42446 -383.13741)
		(end 114.517932 -383.230882)
		(width 0.1016)
		(layer "F.Cu")
		(net "P5E_CPU1_P3_TX_C_DN<0>")
	)
	(segment
		(start 110.334044 -381.48006)
		(end 110.681516 -381.827532)
		(width 0.1016)
		(layer "F.Cu")
		(net "P5E_CPU1_P3_TX_C_DN<0>")
	)
	(segment
		(start 110.681516 -381.827532)
		(end 112.852708 -381.827532)
		(width 0.1016)
		(layer "F.Cu")
		(net "P5E_CPU1_P3_TX_C_DN<0>")
	)
	(segment
		(start 114.020346 -382.32207)
		(end 114.42446 -382.727708)
		(width 0.1016)
		(layer "F.Cu")
		(net "P5E_CPU1_P3_TX_C_DN<0>")
	)
	(segment
		(start 113.13287 -381.883158)
		(end 113.737898 -382.133094)
		(width 0.1016)
		(layer "F.Cu")
		(net "P5E_CPU1_P3_TX_C_DN<0>")
	)
	(arc
		(start 112.852708 -381.827532)
		(mid 112.995527 -381.841564)
		(end 113.13287 -381.883158)
		(width 0.1016)
		(layer "F.Cu")
		(net "P5E_CPU1_P3_TX_C_DN<0>")
	)
	(arc
		(start 113.737898 -382.133094)
		(mid 113.88853 -382.213523)
		(end 114.020346 -382.32207)
		(width 0.1016)
		(layer "F.Cu")
		(net "P5E_CPU1_P3_TX_C_DN<0>")
	)
	(segment
		(start 158.598362 -372.28907)
		(end 159.761428 -373.452136)
		(width 0.1016)
		(layer "F.Cu")
		(net "P5E_CPU1_P2_TX_C_DP<9>")
	)
	(segment
		(start 157.24378 -383.2352)
		(end 157.24378 -383.50571)
		(width 0.1016)
		(layer "F.Cu")
		(net "P5E_CPU1_P2_TX_C_DP<9>")
	)
	(segment
		(start 157.469332 -383.596896)
		(end 157.545786 -383.520442)
		(width 0.1016)
		(layer "F.Cu")
		(net "P5E_CPU1_P2_TX_C_DP<9>")
	)
	(segment
		(start 157.334966 -383.596896)
		(end 157.469332 -383.596896)
		(width 0.1016)
		(layer "F.Cu")
		(net "P5E_CPU1_P2_TX_C_DP<9>")
	)
	(segment
		(start 158.282894 -371.18798)
		(end 158.282894 -371.527578)
		(width 0.1016)
		(layer "F.Cu")
		(net "P5E_CPU1_P2_TX_C_DP<9>")
	)
	(segment
		(start 159.961326 -373.933466)
		(end 159.961326 -374.994932)
		(width 0.1016)
		(layer "F.Cu")
		(net "P5E_CPU1_P2_TX_C_DP<9>")
	)
	(segment
		(start 157.24378 -383.50571)
		(end 157.334966 -383.596896)
		(width 0.1016)
		(layer "F.Cu")
		(net "P5E_CPU1_P2_TX_C_DP<9>")
	)
	(segment
		(start 157.933644 -370.83873)
		(end 158.282894 -371.18798)
		(width 0.1016)
		(layer "F.Cu")
		(net "P5E_CPU1_P2_TX_C_DP<9>")
	)
	(segment
		(start 157.536388 -382.942592)
		(end 157.24378 -383.2352)
		(width 0.1016)
		(layer "F.Cu")
		(net "P5E_CPU1_P2_TX_C_DP<9>")
	)
	(segment
		(start 157.545786 -383.520442)
		(end 157.545786 -383.402586)
		(width 0.1016)
		(layer "F.Cu")
		(net "P5E_CPU1_P2_TX_C_DP<9>")
	)
	(segment
		(start 157.536388 -377.723908)
		(end 157.536388 -382.942592)
		(width 0.1016)
		(layer "F.Cu")
		(net "P5E_CPU1_P2_TX_C_DP<9>")
	)
	(segment
		(start 159.889952 -375.166382)
		(end 157.680152 -377.376182)
		(width 0.1016)
		(layer "F.Cu")
		(net "P5E_CPU1_P2_TX_C_DP<9>")
	)
	(arc
		(start 158.282894 -371.527578)
		(mid 158.364926 -371.939688)
		(end 158.598362 -372.28907)
		(width 0.1016)
		(layer "F.Cu")
		(net "P5E_CPU1_P2_TX_C_DP<9>")
	)
	(arc
		(start 159.961326 -374.994932)
		(mid 159.942661 -375.087735)
		(end 159.889952 -375.166382)
		(width 0.1016)
		(layer "F.Cu")
		(net "P5E_CPU1_P2_TX_C_DP<9>")
	)
	(arc
		(start 159.761428 -373.452136)
		(mid 159.909289 -373.672913)
		(end 159.961326 -373.933466)
		(width 0.1016)
		(layer "F.Cu")
		(net "P5E_CPU1_P2_TX_C_DP<9>")
	)
	(arc
		(start 157.680152 -377.376182)
		(mid 157.573718 -377.53575)
		(end 157.536388 -377.723908)
		(width 0.1016)
		(layer "F.Cu")
		(net "P5E_CPU1_P2_TX_C_DP<9>")
	)
	(segment
		(start 156.336238 -382.942592)
		(end 156.04363 -383.2352)
		(width 0.1016)
		(layer "F.Cu")
		(net "P5E_CPU1_P2_TX_C_DP<8>")
	)
	(segment
		(start 156.134816 -383.596896)
		(end 156.269182 -383.596896)
		(width 0.1016)
		(layer "F.Cu")
		(net "P5E_CPU1_P2_TX_C_DP<8>")
	)
	(segment
		(start 156.345636 -383.520442)
		(end 156.345636 -383.402586)
		(width 0.1016)
		(layer "F.Cu")
		(net "P5E_CPU1_P2_TX_C_DP<8>")
	)
	(segment
		(start 156.04363 -383.2352)
		(end 156.04363 -383.50571)
		(width 0.1016)
		(layer "F.Cu")
		(net "P5E_CPU1_P2_TX_C_DP<8>")
	)
	(segment
		(start 156.231844 -373.30253)
		(end 156.533596 -373.604282)
		(width 0.1016)
		(layer "F.Cu")
		(net "P5E_CPU1_P2_TX_C_DP<8>")
	)
	(segment
		(start 156.269182 -383.596896)
		(end 156.345636 -383.520442)
		(width 0.1016)
		(layer "F.Cu")
		(net "P5E_CPU1_P2_TX_C_DP<8>")
	)
	(segment
		(start 156.336238 -377.31827)
		(end 156.336238 -382.942592)
		(width 0.1016)
		(layer "F.Cu")
		(net "P5E_CPU1_P2_TX_C_DP<8>")
	)
	(segment
		(start 156.04363 -383.50571)
		(end 156.134816 -383.596896)
		(width 0.1016)
		(layer "F.Cu")
		(net "P5E_CPU1_P2_TX_C_DP<8>")
	)
	(segment
		(start 156.581094 -373.71909)
		(end 156.581094 -376.61723)
		(width 0.1016)
		(layer "F.Cu")
		(net "P5E_CPU1_P2_TX_C_DP<8>")
	)
	(arc
		(start 156.581094 -376.61723)
		(mid 156.556878 -376.76075)
		(end 156.487114 -376.888502)
		(width 0.1016)
		(layer "F.Cu")
		(net "P5E_CPU1_P2_TX_C_DP<8>")
	)
	(arc
		(start 156.487114 -376.888502)
		(mid 156.435618 -376.963163)
		(end 156.393896 -377.043696)
		(width 0.1016)
		(layer "F.Cu")
		(net "P5E_CPU1_P2_TX_C_DP<8>")
	)
	(arc
		(start 156.533596 -373.604282)
		(mid 156.568738 -373.656971)
		(end 156.581094 -373.71909)
		(width 0.1016)
		(layer "F.Cu")
		(net "P5E_CPU1_P2_TX_C_DP<8>")
	)
	(arc
		(start 156.393896 -377.043696)
		(mid 156.350742 -377.177976)
		(end 156.336238 -377.31827)
		(width 0.1016)
		(layer "F.Cu")
		(net "P5E_CPU1_P2_TX_C_DP<8>")
	)
	(segment
		(start 155.136342 -382.942592)
		(end 154.843734 -383.2352)
		(width 0.1016)
		(layer "F.Cu")
		(net "P5E_CPU1_P2_TX_C_DP<7>")
	)
	(segment
		(start 155.118562 -378.664216)
		(end 155.136342 -382.942592)
		(width 0.1016)
		(layer "F.Cu")
		(net "P5E_CPU1_P2_TX_C_DP<7>")
	)
	(segment
		(start 155.14574 -383.520442)
		(end 155.14574 -383.402586)
		(width 0.1016)
		(layer "F.Cu")
		(net "P5E_CPU1_P2_TX_C_DP<7>")
	)
	(segment
		(start 154.93492 -383.596896)
		(end 155.069286 -383.596896)
		(width 0.1016)
		(layer "F.Cu")
		(net "P5E_CPU1_P2_TX_C_DP<7>")
	)
	(segment
		(start 155.069286 -383.596896)
		(end 155.14574 -383.520442)
		(width 0.1016)
		(layer "F.Cu")
		(net "P5E_CPU1_P2_TX_C_DP<7>")
	)
	(segment
		(start 154.843734 -383.2352)
		(end 154.843734 -383.50571)
		(width 0.1016)
		(layer "F.Cu")
		(net "P5E_CPU1_P2_TX_C_DP<7>")
	)
	(segment
		(start 154.879294 -376.18289)
		(end 154.879294 -377.907804)
		(width 0.1016)
		(layer "F.Cu")
		(net "P5E_CPU1_P2_TX_C_DP<7>")
	)
	(segment
		(start 154.530044 -375.76633)
		(end 154.831796 -376.068082)
		(width 0.1016)
		(layer "F.Cu")
		(net "P5E_CPU1_P2_TX_C_DP<7>")
	)
	(segment
		(start 154.843734 -383.50571)
		(end 154.93492 -383.596896)
		(width 0.1016)
		(layer "F.Cu")
		(net "P5E_CPU1_P2_TX_C_DP<7>")
	)
	(arc
		(start 154.879294 -377.907804)
		(mid 154.919972 -378.171596)
		(end 155.038044 -378.410978)
		(width 0.1016)
		(layer "F.Cu")
		(net "P5E_CPU1_P2_TX_C_DP<7>")
	)
	(arc
		(start 155.038044 -378.410978)
		(mid 155.097606 -378.531463)
		(end 155.118562 -378.664216)
		(width 0.1016)
		(layer "F.Cu")
		(net "P5E_CPU1_P2_TX_C_DP<7>")
	)
	(arc
		(start 154.831796 -376.068082)
		(mid 154.866938 -376.120771)
		(end 154.879294 -376.18289)
		(width 0.1016)
		(layer "F.Cu")
		(net "P5E_CPU1_P2_TX_C_DP<7>")
	)
	(segment
		(start 153.643584 -383.50571)
		(end 153.73477 -383.596896)
		(width 0.1016)
		(layer "F.Cu")
		(net "P5E_CPU1_P2_TX_C_DP<6>")
	)
	(segment
		(start 151.126444 -370.83873)
		(end 151.475694 -371.18798)
		(width 0.1016)
		(layer "F.Cu")
		(net "P5E_CPU1_P2_TX_C_DP<6>")
	)
	(segment
		(start 153.94559 -383.520442)
		(end 153.94559 -383.402586)
		(width 0.1016)
		(layer "F.Cu")
		(net "P5E_CPU1_P2_TX_C_DP<6>")
	)
	(segment
		(start 153.73477 -383.596896)
		(end 153.869136 -383.596896)
		(width 0.1016)
		(layer "F.Cu")
		(net "P5E_CPU1_P2_TX_C_DP<6>")
	)
	(segment
		(start 153.337006 -378.733558)
		(end 153.373582 -378.823474)
		(width 0.1016)
		(layer "F.Cu")
		(net "P5E_CPU1_P2_TX_C_DP<6>")
	)
	(segment
		(start 151.802084 -372.267734)
		(end 153.034492 -373.500142)
		(width 0.1016)
		(layer "F.Cu")
		(net "P5E_CPU1_P2_TX_C_DP<6>")
	)
	(segment
		(start 153.936192 -381.694436)
		(end 153.936192 -382.942592)
		(width 0.1016)
		(layer "F.Cu")
		(net "P5E_CPU1_P2_TX_C_DP<6>")
	)
	(segment
		(start 151.475694 -371.18798)
		(end 151.475694 -371.48008)
		(width 0.1016)
		(layer "F.Cu")
		(net "P5E_CPU1_P2_TX_C_DP<6>")
	)
	(segment
		(start 153.869136 -383.596896)
		(end 153.94559 -383.520442)
		(width 0.1016)
		(layer "F.Cu")
		(net "P5E_CPU1_P2_TX_C_DP<6>")
	)
	(segment
		(start 153.19502 -373.886984)
		(end 153.19502 -378.006102)
		(width 0.1016)
		(layer "F.Cu")
		(net "P5E_CPU1_P2_TX_C_DP<6>")
	)
	(segment
		(start 153.643584 -383.2352)
		(end 153.643584 -383.50571)
		(width 0.1016)
		(layer "F.Cu")
		(net "P5E_CPU1_P2_TX_C_DP<6>")
	)
	(segment
		(start 153.936192 -382.942592)
		(end 153.643584 -383.2352)
		(width 0.1016)
		(layer "F.Cu")
		(net "P5E_CPU1_P2_TX_C_DP<6>")
	)
	(arc
		(start 153.034492 -373.500142)
		(mid 153.153249 -373.677597)
		(end 153.19502 -373.886984)
		(width 0.1016)
		(layer "F.Cu")
		(net "P5E_CPU1_P2_TX_C_DP<6>")
	)
	(arc
		(start 153.373582 -378.823474)
		(mid 153.794151 -380.231663)
		(end 153.936192 -381.694436)
		(width 0.1016)
		(layer "F.Cu")
		(net "P5E_CPU1_P2_TX_C_DP<6>")
	)
	(arc
		(start 153.19502 -378.006102)
		(mid 153.230825 -378.376698)
		(end 153.337006 -378.733558)
		(width 0.1016)
		(layer "F.Cu")
		(net "P5E_CPU1_P2_TX_C_DP<6>")
	)
	(arc
		(start 151.475694 -371.48008)
		(mid 151.560563 -371.906367)
		(end 151.802084 -372.267734)
		(width 0.1016)
		(layer "F.Cu")
		(net "P5E_CPU1_P2_TX_C_DP<6>")
	)
	(segment
		(start 152.66924 -383.596896)
		(end 152.745694 -383.520442)
		(width 0.1016)
		(layer "F.Cu")
		(net "P5E_CPU1_P2_TX_C_DP<5>")
	)
	(segment
		(start 150.137876 -376.561858)
		(end 152.067768 -379.448822)
		(width 0.1016)
		(layer "F.Cu")
		(net "P5E_CPU1_P2_TX_C_DP<5>")
	)
	(segment
		(start 152.443688 -383.50571)
		(end 152.534874 -383.596896)
		(width 0.1016)
		(layer "F.Cu")
		(net "P5E_CPU1_P2_TX_C_DP<5>")
	)
	(segment
		(start 149.773894 -373.65178)
		(end 149.773894 -375.362216)
		(width 0.1016)
		(layer "F.Cu")
		(net "P5E_CPU1_P2_TX_C_DP<5>")
	)
	(segment
		(start 152.736296 -382.942592)
		(end 152.443688 -383.2352)
		(width 0.1016)
		(layer "F.Cu")
		(net "P5E_CPU1_P2_TX_C_DP<5>")
	)
	(segment
		(start 152.736296 -381.651764)
		(end 152.736296 -382.942592)
		(width 0.1016)
		(layer "F.Cu")
		(net "P5E_CPU1_P2_TX_C_DP<5>")
	)
	(segment
		(start 152.534874 -383.596896)
		(end 152.66924 -383.596896)
		(width 0.1016)
		(layer "F.Cu")
		(net "P5E_CPU1_P2_TX_C_DP<5>")
	)
	(segment
		(start 152.745694 -383.520442)
		(end 152.745694 -383.402586)
		(width 0.1016)
		(layer "F.Cu")
		(net "P5E_CPU1_P2_TX_C_DP<5>")
	)
	(segment
		(start 149.424644 -373.30253)
		(end 149.773894 -373.65178)
		(width 0.1016)
		(layer "F.Cu")
		(net "P5E_CPU1_P2_TX_C_DP<5>")
	)
	(segment
		(start 152.443688 -383.2352)
		(end 152.443688 -383.50571)
		(width 0.1016)
		(layer "F.Cu")
		(net "P5E_CPU1_P2_TX_C_DP<5>")
	)
	(arc
		(start 152.067768 -379.448822)
		(mid 152.565474 -380.500692)
		(end 152.736296 -381.651764)
		(width 0.1016)
		(layer "F.Cu")
		(net "P5E_CPU1_P2_TX_C_DP<5>")
	)
	(arc
		(start 149.773894 -375.362216)
		(mid 149.866899 -375.989034)
		(end 150.137876 -376.561858)
		(width 0.1016)
		(layer "F.Cu")
		(net "P5E_CPU1_P2_TX_C_DP<5>")
	)
	(segment
		(start 151.545798 -383.520442)
		(end 151.545798 -383.402586)
		(width 0.1016)
		(layer "F.Cu")
		(net "P5E_CPU1_P2_TX_C_DP<4>")
	)
	(segment
		(start 148.072094 -376.33275)
		(end 148.316442 -376.921776)
		(width 0.1016)
		(layer "F.Cu")
		(net "P5E_CPU1_P2_TX_C_DP<4>")
	)
	(segment
		(start 151.243792 -383.50571)
		(end 151.334978 -383.596896)
		(width 0.1016)
		(layer "F.Cu")
		(net "P5E_CPU1_P2_TX_C_DP<4>")
	)
	(segment
		(start 151.243792 -383.2352)
		(end 151.243792 -383.50571)
		(width 0.1016)
		(layer "F.Cu")
		(net "P5E_CPU1_P2_TX_C_DP<4>")
	)
	(segment
		(start 151.334978 -383.596896)
		(end 151.469344 -383.596896)
		(width 0.1016)
		(layer "F.Cu")
		(net "P5E_CPU1_P2_TX_C_DP<4>")
	)
	(segment
		(start 148.072094 -376.11558)
		(end 148.072094 -376.33275)
		(width 0.1016)
		(layer "F.Cu")
		(net "P5E_CPU1_P2_TX_C_DP<4>")
	)
	(segment
		(start 151.469344 -383.596896)
		(end 151.545798 -383.520442)
		(width 0.1016)
		(layer "F.Cu")
		(net "P5E_CPU1_P2_TX_C_DP<4>")
	)
	(segment
		(start 151.5364 -382.942592)
		(end 151.243792 -383.2352)
		(width 0.1016)
		(layer "F.Cu")
		(net "P5E_CPU1_P2_TX_C_DP<4>")
	)
	(segment
		(start 151.5364 -381.572008)
		(end 151.5364 -382.942592)
		(width 0.1016)
		(layer "F.Cu")
		(net "P5E_CPU1_P2_TX_C_DP<4>")
	)
	(segment
		(start 147.722844 -375.76633)
		(end 148.072094 -376.11558)
		(width 0.1016)
		(layer "F.Cu")
		(net "P5E_CPU1_P2_TX_C_DP<4>")
	)
	(segment
		(start 148.316442 -376.921776)
		(end 151.204422 -380.440438)
		(width 0.1016)
		(layer "F.Cu")
		(net "P5E_CPU1_P2_TX_C_DP<4>")
	)
	(arc
		(start 151.204422 -380.440438)
		(mid 151.451551 -380.982422)
		(end 151.5364 -381.572008)
		(width 0.1016)
		(layer "F.Cu")
		(net "P5E_CPU1_P2_TX_C_DP<4>")
	)
	(segment
		(start 146.4437 -375.534682)
		(end 147.303744 -377.61164)
		(width 0.1016)
		(layer "F.Cu")
		(net "P5E_CPU1_P2_TX_C_DP<3>")
	)
	(segment
		(start 150.134828 -383.596896)
		(end 150.269194 -383.596896)
		(width 0.1016)
		(layer "F.Cu")
		(net "P5E_CPU1_P2_TX_C_DP<3>")
	)
	(segment
		(start 150.269194 -383.596896)
		(end 150.345648 -383.520442)
		(width 0.1016)
		(layer "F.Cu")
		(net "P5E_CPU1_P2_TX_C_DP<3>")
	)
	(segment
		(start 146.040856 -373.294656)
		(end 146.040856 -373.29491)
		(width 0.1016)
		(layer "F.Cu")
		(net "P5E_CPU1_P2_TX_C_DP<3>")
	)
	(segment
		(start 150.043642 -383.2352)
		(end 150.043642 -383.50571)
		(width 0.1016)
		(layer "F.Cu")
		(net "P5E_CPU1_P2_TX_C_DP<3>")
	)
	(segment
		(start 146.040856 -373.29491)
		(end 146.301968 -373.556022)
		(width 0.1016)
		(layer "F.Cu")
		(net "P5E_CPU1_P2_TX_C_DP<3>")
	)
	(segment
		(start 144.668494 -371.18798)
		(end 144.668494 -371.57152)
		(width 0.1016)
		(layer "F.Cu")
		(net "P5E_CPU1_P2_TX_C_DP<3>")
	)
	(segment
		(start 150.345648 -383.520442)
		(end 150.345648 -383.402586)
		(width 0.1016)
		(layer "F.Cu")
		(net "P5E_CPU1_P2_TX_C_DP<3>")
	)
	(segment
		(start 146.378168 -373.738902)
		(end 146.378168 -375.203466)
		(width 0.1016)
		(layer "F.Cu")
		(net "P5E_CPU1_P2_TX_C_DP<3>")
	)
	(segment
		(start 144.916144 -372.170198)
		(end 146.040856 -373.294656)
		(width 0.1016)
		(layer "F.Cu")
		(net "P5E_CPU1_P2_TX_C_DP<3>")
	)
	(segment
		(start 150.043642 -383.50571)
		(end 150.134828 -383.596896)
		(width 0.1016)
		(layer "F.Cu")
		(net "P5E_CPU1_P2_TX_C_DP<3>")
	)
	(segment
		(start 147.574762 -378.064014)
		(end 150.217886 -381.284734)
		(width 0.1016)
		(layer "F.Cu")
		(net "P5E_CPU1_P2_TX_C_DP<3>")
	)
	(segment
		(start 150.33625 -382.942592)
		(end 150.043642 -383.2352)
		(width 0.1016)
		(layer "F.Cu")
		(net "P5E_CPU1_P2_TX_C_DP<3>")
	)
	(segment
		(start 150.33625 -381.61468)
		(end 150.33625 -382.942592)
		(width 0.1016)
		(layer "F.Cu")
		(net "P5E_CPU1_P2_TX_C_DP<3>")
	)
	(segment
		(start 147.303744 -377.61164)
		(end 147.574762 -378.064014)
		(width 0.1016)
		(layer "F.Cu")
		(net "P5E_CPU1_P2_TX_C_DP<3>")
	)
	(segment
		(start 144.319244 -370.83873)
		(end 144.668494 -371.18798)
		(width 0.1016)
		(layer "F.Cu")
		(net "P5E_CPU1_P2_TX_C_DP<3>")
	)
	(arc
		(start 146.378168 -375.203466)
		(mid 146.394636 -375.372298)
		(end 146.4437 -375.534682)
		(width 0.1016)
		(layer "F.Cu")
		(net "P5E_CPU1_P2_TX_C_DP<3>")
	)
	(arc
		(start 146.301968 -373.556022)
		(mid 146.358306 -373.639869)
		(end 146.378168 -373.738902)
		(width 0.1016)
		(layer "F.Cu")
		(net "P5E_CPU1_P2_TX_C_DP<3>")
	)
	(arc
		(start 150.217886 -381.284734)
		(mid 150.305743 -381.439418)
		(end 150.33625 -381.61468)
		(width 0.1016)
		(layer "F.Cu")
		(net "P5E_CPU1_P2_TX_C_DP<3>")
	)
	(arc
		(start 144.668494 -371.57152)
		(mid 144.732751 -371.895503)
		(end 144.916144 -372.170198)
		(width 0.1016)
		(layer "F.Cu")
		(net "P5E_CPU1_P2_TX_C_DP<3>")
	)
	(segment
		(start 143.693388 -375.2342)
		(end 144.608296 -375.613168)
		(width 0.1016)
		(layer "F.Cu")
		(net "P5E_CPU1_P2_TX_C_DP<2>")
	)
	(segment
		(start 149.136354 -382.942592)
		(end 148.843746 -383.2352)
		(width 0.1016)
		(layer "F.Cu")
		(net "P5E_CPU1_P2_TX_C_DP<2>")
	)
	(segment
		(start 146.758914 -379.057154)
		(end 148.965158 -381.742696)
		(width 0.1016)
		(layer "F.Cu")
		(net "P5E_CPU1_P2_TX_C_DP<2>")
	)
	(segment
		(start 148.843746 -383.2352)
		(end 148.843746 -383.50571)
		(width 0.1016)
		(layer "F.Cu")
		(net "P5E_CPU1_P2_TX_C_DP<2>")
	)
	(segment
		(start 148.934932 -383.596896)
		(end 149.069298 -383.596896)
		(width 0.1016)
		(layer "F.Cu")
		(net "P5E_CPU1_P2_TX_C_DP<2>")
	)
	(segment
		(start 148.843746 -383.50571)
		(end 148.934932 -383.596896)
		(width 0.1016)
		(layer "F.Cu")
		(net "P5E_CPU1_P2_TX_C_DP<2>")
	)
	(segment
		(start 144.659604 -375.647458)
		(end 145.459196 -376.44705)
		(width 0.1016)
		(layer "F.Cu")
		(net "P5E_CPU1_P2_TX_C_DP<2>")
	)
	(segment
		(start 142.617444 -373.30253)
		(end 142.966694 -373.65178)
		(width 0.1016)
		(layer "F.Cu")
		(net "P5E_CPU1_P2_TX_C_DP<2>")
	)
	(segment
		(start 149.136354 -382.22047)
		(end 149.136354 -382.942592)
		(width 0.1016)
		(layer "F.Cu")
		(net "P5E_CPU1_P2_TX_C_DP<2>")
	)
	(segment
		(start 145.616676 -376.682508)
		(end 146.338544 -378.425456)
		(width 0.1016)
		(layer "F.Cu")
		(net "P5E_CPU1_P2_TX_C_DP<2>")
	)
	(segment
		(start 149.069298 -383.596896)
		(end 149.145752 -383.520442)
		(width 0.1016)
		(layer "F.Cu")
		(net "P5E_CPU1_P2_TX_C_DP<2>")
	)
	(segment
		(start 149.145752 -383.520442)
		(end 149.145752 -383.402586)
		(width 0.1016)
		(layer "F.Cu")
		(net "P5E_CPU1_P2_TX_C_DP<2>")
	)
	(segment
		(start 142.966694 -373.65178)
		(end 142.966694 -374.282208)
		(width 0.1016)
		(layer "F.Cu")
		(net "P5E_CPU1_P2_TX_C_DP<2>")
	)
	(segment
		(start 146.338544 -378.425456)
		(end 146.481038 -378.662692)
		(width 0.1016)
		(layer "F.Cu")
		(net "P5E_CPU1_P2_TX_C_DP<2>")
	)
	(segment
		(start 143.224504 -374.904762)
		(end 143.27251 -374.952768)
		(width 0.1016)
		(layer "F.Cu")
		(net "P5E_CPU1_P2_TX_C_DP<2>")
	)
	(arc
		(start 144.608296 -375.613168)
		(mid 144.635644 -375.627779)
		(end 144.659604 -375.647458)
		(width 0.1016)
		(layer "F.Cu")
		(net "P5E_CPU1_P2_TX_C_DP<2>")
	)
	(arc
		(start 145.459196 -376.44705)
		(mid 145.549558 -376.557008)
		(end 145.616676 -376.682508)
		(width 0.1016)
		(layer "F.Cu")
		(net "P5E_CPU1_P2_TX_C_DP<2>")
	)
	(arc
		(start 142.966694 -374.282208)
		(mid 143.033693 -374.619123)
		(end 143.224504 -374.904762)
		(width 0.1016)
		(layer "F.Cu")
		(net "P5E_CPU1_P2_TX_C_DP<2>")
	)
	(arc
		(start 146.481038 -378.662692)
		(mid 146.61273 -378.865028)
		(end 146.758914 -379.057154)
		(width 0.1016)
		(layer "F.Cu")
		(net "P5E_CPU1_P2_TX_C_DP<2>")
	)
	(arc
		(start 143.27251 -374.952768)
		(mid 143.469094 -375.114205)
		(end 143.693388 -375.2342)
		(width 0.1016)
		(layer "F.Cu")
		(net "P5E_CPU1_P2_TX_C_DP<2>")
	)
	(arc
		(start 148.965158 -381.742696)
		(mid 149.09221 -381.966722)
		(end 149.136354 -382.22047)
		(width 0.1016)
		(layer "F.Cu")
		(net "P5E_CPU1_P2_TX_C_DP<2>")
	)
	(segment
		(start 145.560796 -379.118876)
		(end 145.718022 -379.354588)
		(width 0.1016)
		(layer "F.Cu")
		(net "P5E_CPU1_P2_TX_C_DP<1>")
	)
	(segment
		(start 146.0119 -379.794262)
		(end 146.125692 -379.964442)
		(width 0.1016)
		(layer "F.Cu")
		(net "P5E_CPU1_P2_TX_C_DP<1>")
	)
	(segment
		(start 143.189198 -376.270266)
		(end 143.31696 -376.270266)
		(width 0.1016)
		(layer "F.Cu")
		(net "P5E_CPU1_P2_TX_C_DP<1>")
	)
	(segment
		(start 146.0119 -379.794008)
		(end 146.0119 -379.794262)
		(width 0.1016)
		(layer "F.Cu")
		(net "P5E_CPU1_P2_TX_C_DP<1>")
	)
	(segment
		(start 146.246596 -380.111254)
		(end 146.857212 -380.722124)
		(width 0.1016)
		(layer "F.Cu")
		(net "P5E_CPU1_P2_TX_C_DP<1>")
	)
	(segment
		(start 147.885912 -381.976122)
		(end 148.028914 -382.21412)
		(width 0.1016)
		(layer "F.Cu")
		(net "P5E_CPU1_P2_TX_C_DP<1>")
	)
	(segment
		(start 148.152104 -383.13741)
		(end 148.245576 -383.230882)
		(width 0.1016)
		(layer "F.Cu")
		(net "P5E_CPU1_P2_TX_C_DP<1>")
	)
	(segment
		(start 142.861792 -375.94286)
		(end 143.189198 -376.270266)
		(width 0.1016)
		(layer "F.Cu")
		(net "P5E_CPU1_P2_TX_C_DP<1>")
	)
	(segment
		(start 148.152104 -382.511808)
		(end 148.152104 -383.13741)
		(width 0.1016)
		(layer "F.Cu")
		(net "P5E_CPU1_P2_TX_C_DP<1>")
	)
	(segment
		(start 148.245576 -383.230882)
		(end 148.245576 -383.92227)
		(width 0.1016)
		(layer "F.Cu")
		(net "P5E_CPU1_P2_TX_C_DP<1>")
	)
	(segment
		(start 144.773142 -377.216416)
		(end 145.560796 -379.118876)
		(width 0.1016)
		(layer "F.Cu")
		(net "P5E_CPU1_P2_TX_C_DP<1>")
	)
	(segment
		(start 148.028914 -382.21412)
		(end 148.152104 -382.511808)
		(width 0.1016)
		(layer "F.Cu")
		(net "P5E_CPU1_P2_TX_C_DP<1>")
	)
	(segment
		(start 145.718276 -379.354588)
		(end 146.0119 -379.794008)
		(width 0.1016)
		(layer "F.Cu")
		(net "P5E_CPU1_P2_TX_C_DP<1>")
	)
	(segment
		(start 144.306798 -376.679968)
		(end 144.632934 -377.006104)
		(width 0.1016)
		(layer "F.Cu")
		(net "P5E_CPU1_P2_TX_C_DP<1>")
	)
	(segment
		(start 145.718022 -379.354588)
		(end 145.718276 -379.354588)
		(width 0.1016)
		(layer "F.Cu")
		(net "P5E_CPU1_P2_TX_C_DP<1>")
	)
	(segment
		(start 146.857212 -380.722124)
		(end 147.885912 -381.976122)
		(width 0.1016)
		(layer "F.Cu")
		(net "P5E_CPU1_P2_TX_C_DP<1>")
	)
	(arc
		(start 144.632934 -377.006104)
		(mid 144.713406 -377.104348)
		(end 144.773142 -377.216416)
		(width 0.1016)
		(layer "F.Cu")
		(net "P5E_CPU1_P2_TX_C_DP<1>")
	)
	(arc
		(start 146.125692 -379.964442)
		(mid 146.182538 -380.040818)
		(end 146.246596 -380.111254)
		(width 0.1016)
		(layer "F.Cu")
		(net "P5E_CPU1_P2_TX_C_DP<1>")
	)
	(arc
		(start 143.31696 -376.270266)
		(mid 143.852648 -376.376634)
		(end 144.306798 -376.679968)
		(width 0.1016)
		(layer "F.Cu")
		(net "P5E_CPU1_P2_TX_C_DP<1>")
	)
	(segment
		(start 164.830252 -383.110232)
		(end 164.830252 -383.318004)
		(width 0.1016)
		(layer "F.Cu")
		(net "P5E_CPU1_P2_TX_C_DP<15>")
	)
	(segment
		(start 168.291002 -379.820678)
		(end 168.179242 -379.708918)
		(width 0.1016)
		(layer "F.Cu")
		(net "P5E_CPU1_P2_TX_C_DP<15>")
	)
	(segment
		(start 164.736272 -382.205484)
		(end 164.736272 -383.016252)
		(width 0.1016)
		(layer "F.Cu")
		(net "P5E_CPU1_P2_TX_C_DP<15>")
	)
	(segment
		(start 167.762682 -379.820678)
		(end 167.047926 -379.820678)
		(width 0.1016)
		(layer "F.Cu")
		(net "P5E_CPU1_P2_TX_C_DP<15>")
	)
	(segment
		(start 166.793926 -379.92558)
		(end 164.89299 -381.826516)
		(width 0.1016)
		(layer "F.Cu")
		(net "P5E_CPU1_P2_TX_C_DP<15>")
	)
	(segment
		(start 164.736272 -383.016252)
		(end 164.830252 -383.110232)
		(width 0.1016)
		(layer "F.Cu")
		(net "P5E_CPU1_P2_TX_C_DP<15>")
	)
	(segment
		(start 169.102024 -379.471428)
		(end 168.752774 -379.820678)
		(width 0.1016)
		(layer "F.Cu")
		(net "P5E_CPU1_P2_TX_C_DP<15>")
	)
	(segment
		(start 164.830252 -383.318004)
		(end 164.74567 -383.402586)
		(width 0.1016)
		(layer "F.Cu")
		(net "P5E_CPU1_P2_TX_C_DP<15>")
	)
	(segment
		(start 168.179242 -379.708918)
		(end 167.874442 -379.708918)
		(width 0.1016)
		(layer "F.Cu")
		(net "P5E_CPU1_P2_TX_C_DP<15>")
	)
	(segment
		(start 168.752774 -379.820678)
		(end 168.291002 -379.820678)
		(width 0.1016)
		(layer "F.Cu")
		(net "P5E_CPU1_P2_TX_C_DP<15>")
	)
	(segment
		(start 167.874442 -379.708918)
		(end 167.762682 -379.820678)
		(width 0.1016)
		(layer "F.Cu")
		(net "P5E_CPU1_P2_TX_C_DP<15>")
	)
	(arc
		(start 164.89299 -381.826516)
		(mid 164.776925 -382.000404)
		(end 164.736272 -382.205484)
		(width 0.1016)
		(layer "F.Cu")
		(net "P5E_CPU1_P2_TX_C_DP<15>")
	)
	(arc
		(start 167.047926 -379.820678)
		(mid 166.910473 -379.847832)
		(end 166.793926 -379.92558)
		(width 0.1016)
		(layer "F.Cu")
		(net "P5E_CPU1_P2_TX_C_DP<15>")
	)
	(segment
		(start 168.352724 -376.50293)
		(end 163.797234 -381.05842)
		(width 0.1016)
		(layer "F.Cu")
		(net "P5E_CPU1_P2_TX_C_DP<14>")
	)
	(segment
		(start 168.666922 -376.50293)
		(end 168.352724 -376.50293)
		(width 0.1016)
		(layer "F.Cu")
		(net "P5E_CPU1_P2_TX_C_DP<14>")
	)
	(segment
		(start 163.536376 -383.016252)
		(end 163.630356 -383.110232)
		(width 0.1016)
		(layer "F.Cu")
		(net "P5E_CPU1_P2_TX_C_DP<14>")
	)
	(segment
		(start 163.536376 -381.689102)
		(end 163.536376 -383.016252)
		(width 0.1016)
		(layer "F.Cu")
		(net "P5E_CPU1_P2_TX_C_DP<14>")
	)
	(segment
		(start 163.630356 -383.318004)
		(end 163.545774 -383.402586)
		(width 0.1016)
		(layer "F.Cu")
		(net "P5E_CPU1_P2_TX_C_DP<14>")
	)
	(segment
		(start 169.102024 -376.067828)
		(end 168.666922 -376.50293)
		(width 0.1016)
		(layer "F.Cu")
		(net "P5E_CPU1_P2_TX_C_DP<14>")
	)
	(segment
		(start 163.630356 -383.110232)
		(end 163.630356 -383.318004)
		(width 0.1016)
		(layer "F.Cu")
		(net "P5E_CPU1_P2_TX_C_DP<14>")
	)
	(arc
		(start 163.797234 -381.05842)
		(mid 163.60411 -381.347824)
		(end 163.536376 -381.689102)
		(width 0.1016)
		(layer "F.Cu")
		(net "P5E_CPU1_P2_TX_C_DP<14>")
	)
	(segment
		(start 170.167808 -373.866156)
		(end 170.167808 -374.136666)
		(width 0.1016)
		(layer "F.Cu")
		(net "P5E_CPU1_P2_TX_C_DP<13>")
	)
	(segment
		(start 162.345624 -383.520442)
		(end 162.345624 -383.402586)
		(width 0.1016)
		(layer "F.Cu")
		(net "P5E_CPU1_P2_TX_C_DP<13>")
	)
	(segment
		(start 169.28465 -375.09704)
		(end 168.403778 -375.09704)
		(width 0.1016)
		(layer "F.Cu")
		(net "P5E_CPU1_P2_TX_C_DP<13>")
	)
	(segment
		(start 168.493694 -371.18798)
		(end 168.493694 -371.527578)
		(width 0.1016)
		(layer "F.Cu")
		(net "P5E_CPU1_P2_TX_C_DP<13>")
	)
	(segment
		(start 162.043618 -383.2352)
		(end 162.043618 -383.50571)
		(width 0.1016)
		(layer "F.Cu")
		(net "P5E_CPU1_P2_TX_C_DP<13>")
	)
	(segment
		(start 168.144444 -370.83873)
		(end 168.493694 -371.18798)
		(width 0.1016)
		(layer "F.Cu")
		(net "P5E_CPU1_P2_TX_C_DP<13>")
	)
	(segment
		(start 162.134804 -383.596896)
		(end 162.26917 -383.596896)
		(width 0.1016)
		(layer "F.Cu")
		(net "P5E_CPU1_P2_TX_C_DP<13>")
	)
	(segment
		(start 168.808654 -372.288816)
		(end 170.013376 -373.493538)
		(width 0.1016)
		(layer "F.Cu")
		(net "P5E_CPU1_P2_TX_C_DP<13>")
	)
	(segment
		(start 167.833294 -375.333006)
		(end 162.436556 -380.729744)
		(width 0.1016)
		(layer "F.Cu")
		(net "P5E_CPU1_P2_TX_C_DP<13>")
	)
	(segment
		(start 162.336226 -380.972822)
		(end 162.336226 -382.942592)
		(width 0.1016)
		(layer "F.Cu")
		(net "P5E_CPU1_P2_TX_C_DP<13>")
	)
	(segment
		(start 162.26917 -383.596896)
		(end 162.345624 -383.520442)
		(width 0.1016)
		(layer "F.Cu")
		(net "P5E_CPU1_P2_TX_C_DP<13>")
	)
	(segment
		(start 162.336226 -382.942592)
		(end 162.043618 -383.2352)
		(width 0.1016)
		(layer "F.Cu")
		(net "P5E_CPU1_P2_TX_C_DP<13>")
	)
	(segment
		(start 169.995088 -374.55348)
		(end 169.569638 -374.97893)
		(width 0.1016)
		(layer "F.Cu")
		(net "P5E_CPU1_P2_TX_C_DP<13>")
	)
	(segment
		(start 162.043618 -383.50571)
		(end 162.134804 -383.596896)
		(width 0.1016)
		(layer "F.Cu")
		(net "P5E_CPU1_P2_TX_C_DP<13>")
	)
	(arc
		(start 168.493694 -371.527578)
		(mid 168.575434 -371.939543)
		(end 168.808654 -372.288816)
		(width 0.1016)
		(layer "F.Cu")
		(net "P5E_CPU1_P2_TX_C_DP<13>")
	)
	(arc
		(start 170.013376 -373.493538)
		(mid 170.127661 -373.664482)
		(end 170.167808 -373.866156)
		(width 0.1016)
		(layer "F.Cu")
		(net "P5E_CPU1_P2_TX_C_DP<13>")
	)
	(arc
		(start 169.569638 -374.97893)
		(mid 169.438899 -375.06635)
		(end 169.28465 -375.09704)
		(width 0.1016)
		(layer "F.Cu")
		(net "P5E_CPU1_P2_TX_C_DP<13>")
	)
	(arc
		(start 162.436556 -380.729744)
		(mid 162.362257 -380.841313)
		(end 162.336226 -380.972822)
		(width 0.1016)
		(layer "F.Cu")
		(net "P5E_CPU1_P2_TX_C_DP<13>")
	)
	(arc
		(start 168.403778 -375.09704)
		(mid 168.095041 -375.158246)
		(end 167.833294 -375.333006)
		(width 0.1016)
		(layer "F.Cu")
		(net "P5E_CPU1_P2_TX_C_DP<13>")
	)
	(arc
		(start 170.167808 -374.136666)
		(mid 170.122917 -374.362257)
		(end 169.995088 -374.55348)
		(width 0.1016)
		(layer "F.Cu")
		(net "P5E_CPU1_P2_TX_C_DP<13>")
	)
	(segment
		(start 164.740844 -370.83873)
		(end 165.090094 -371.18798)
		(width 0.1016)
		(layer "F.Cu")
		(net "P5E_CPU1_P2_TX_C_DP<12>")
	)
	(segment
		(start 161.069274 -383.596896)
		(end 161.145728 -383.520442)
		(width 0.1016)
		(layer "F.Cu")
		(net "P5E_CPU1_P2_TX_C_DP<12>")
	)
	(segment
		(start 165.342316 -372.147338)
		(end 166.76243 -373.567198)
		(width 0.1016)
		(layer "F.Cu")
		(net "P5E_CPU1_P2_TX_C_DP<12>")
	)
	(segment
		(start 165.090094 -371.18798)
		(end 165.090094 -371.5385)
		(width 0.1016)
		(layer "F.Cu")
		(net "P5E_CPU1_P2_TX_C_DP<12>")
	)
	(segment
		(start 160.934908 -383.596896)
		(end 161.069274 -383.596896)
		(width 0.1016)
		(layer "F.Cu")
		(net "P5E_CPU1_P2_TX_C_DP<12>")
	)
	(segment
		(start 161.13633 -380.734062)
		(end 161.13633 -382.942592)
		(width 0.1016)
		(layer "F.Cu")
		(net "P5E_CPU1_P2_TX_C_DP<12>")
	)
	(segment
		(start 160.843722 -383.2352)
		(end 160.843722 -383.50571)
		(width 0.1016)
		(layer "F.Cu")
		(net "P5E_CPU1_P2_TX_C_DP<12>")
	)
	(segment
		(start 166.799768 -373.657368)
		(end 166.799768 -374.562878)
		(width 0.1016)
		(layer "F.Cu")
		(net "P5E_CPU1_P2_TX_C_DP<12>")
	)
	(segment
		(start 161.145728 -383.520442)
		(end 161.145728 -383.402586)
		(width 0.1016)
		(layer "F.Cu")
		(net "P5E_CPU1_P2_TX_C_DP<12>")
	)
	(segment
		(start 160.843722 -383.50571)
		(end 160.934908 -383.596896)
		(width 0.1016)
		(layer "F.Cu")
		(net "P5E_CPU1_P2_TX_C_DP<12>")
	)
	(segment
		(start 161.13633 -382.942592)
		(end 160.843722 -383.2352)
		(width 0.1016)
		(layer "F.Cu")
		(net "P5E_CPU1_P2_TX_C_DP<12>")
	)
	(segment
		(start 166.727124 -374.737376)
		(end 161.42335 -380.04115)
		(width 0.1016)
		(layer "F.Cu")
		(net "P5E_CPU1_P2_TX_C_DP<12>")
	)
	(arc
		(start 161.42335 -380.04115)
		(mid 161.210929 -380.359061)
		(end 161.13633 -380.734062)
		(width 0.1016)
		(layer "F.Cu")
		(net "P5E_CPU1_P2_TX_C_DP<12>")
	)
	(arc
		(start 166.76243 -373.567198)
		(mid 166.790073 -373.608568)
		(end 166.799768 -373.657368)
		(width 0.1016)
		(layer "F.Cu")
		(net "P5E_CPU1_P2_TX_C_DP<12>")
	)
	(arc
		(start 165.090094 -371.5385)
		(mid 165.155638 -371.868013)
		(end 165.342316 -372.147338)
		(width 0.1016)
		(layer "F.Cu")
		(net "P5E_CPU1_P2_TX_C_DP<12>")
	)
	(arc
		(start 166.799768 -374.562878)
		(mid 166.780774 -374.657333)
		(end 166.727124 -374.737376)
		(width 0.1016)
		(layer "F.Cu")
		(net "P5E_CPU1_P2_TX_C_DP<12>")
	)
	(segment
		(start 159.734758 -383.596896)
		(end 159.869124 -383.596896)
		(width 0.1016)
		(layer "F.Cu")
		(net "P5E_CPU1_P2_TX_C_DP<11>")
	)
	(segment
		(start 159.945578 -383.520442)
		(end 159.945578 -383.402586)
		(width 0.1016)
		(layer "F.Cu")
		(net "P5E_CPU1_P2_TX_C_DP<11>")
	)
	(segment
		(start 159.643572 -383.50571)
		(end 159.734758 -383.596896)
		(width 0.1016)
		(layer "F.Cu")
		(net "P5E_CPU1_P2_TX_C_DP<11>")
	)
	(segment
		(start 159.93618 -382.942592)
		(end 159.643572 -383.2352)
		(width 0.1016)
		(layer "F.Cu")
		(net "P5E_CPU1_P2_TX_C_DP<11>")
	)
	(segment
		(start 159.643572 -383.2352)
		(end 159.643572 -383.50571)
		(width 0.1016)
		(layer "F.Cu")
		(net "P5E_CPU1_P2_TX_C_DP<11>")
	)
	(segment
		(start 159.93618 -379.884178)
		(end 159.93618 -382.942592)
		(width 0.1016)
		(layer "F.Cu")
		(net "P5E_CPU1_P2_TX_C_DP<11>")
	)
	(segment
		(start 159.869124 -383.596896)
		(end 159.945578 -383.520442)
		(width 0.1016)
		(layer "F.Cu")
		(net "P5E_CPU1_P2_TX_C_DP<11>")
	)
	(segment
		(start 163.350956 -376.326654)
		(end 160.035494 -379.642116)
		(width 0.1016)
		(layer "F.Cu")
		(net "P5E_CPU1_P2_TX_C_DP<11>")
	)
	(segment
		(start 163.039044 -373.30253)
		(end 163.388294 -373.65178)
		(width 0.1016)
		(layer "F.Cu")
		(net "P5E_CPU1_P2_TX_C_DP<11>")
	)
	(segment
		(start 163.388294 -373.65178)
		(end 163.388294 -376.236484)
		(width 0.1016)
		(layer "F.Cu")
		(net "P5E_CPU1_P2_TX_C_DP<11>")
	)
	(arc
		(start 163.388294 -376.236484)
		(mid 163.378588 -376.285279)
		(end 163.350956 -376.326654)
		(width 0.1016)
		(layer "F.Cu")
		(net "P5E_CPU1_P2_TX_C_DP<11>")
	)
	(arc
		(start 160.035494 -379.642116)
		(mid 159.961933 -379.753332)
		(end 159.93618 -379.884178)
		(width 0.1016)
		(layer "F.Cu")
		(net "P5E_CPU1_P2_TX_C_DP<11>")
	)
	(segment
		(start 161.685478 -376.114564)
		(end 161.685478 -376.202702)
		(width 0.1016)
		(layer "F.Cu")
		(net "P5E_CPU1_P2_TX_C_DP<10>")
	)
	(segment
		(start 158.736284 -378.904754)
		(end 158.736284 -382.942592)
		(width 0.1016)
		(layer "F.Cu")
		(net "P5E_CPU1_P2_TX_C_DP<10>")
	)
	(segment
		(start 160.552384 -377.321572)
		(end 160.329626 -377.321572)
		(width 0.1016)
		(layer "F.Cu")
		(net "P5E_CPU1_P2_TX_C_DP<10>")
	)
	(segment
		(start 161.64814 -376.292872)
		(end 160.666684 -377.274328)
		(width 0.1016)
		(layer "F.Cu")
		(net "P5E_CPU1_P2_TX_C_DP<10>")
	)
	(segment
		(start 159.015684 -378.48286)
		(end 159.01543 -378.48286)
		(width 0.1016)
		(layer "F.Cu")
		(net "P5E_CPU1_P2_TX_C_DP<10>")
	)
	(segment
		(start 160.069022 -377.429522)
		(end 159.015684 -378.48286)
		(width 0.1016)
		(layer "F.Cu")
		(net "P5E_CPU1_P2_TX_C_DP<10>")
	)
	(segment
		(start 158.745682 -383.520442)
		(end 158.745682 -383.402586)
		(width 0.1016)
		(layer "F.Cu")
		(net "P5E_CPU1_P2_TX_C_DP<10>")
	)
	(segment
		(start 159.01543 -378.48286)
		(end 158.836614 -378.661676)
		(width 0.1016)
		(layer "F.Cu")
		(net "P5E_CPU1_P2_TX_C_DP<10>")
	)
	(segment
		(start 158.443676 -383.2352)
		(end 158.443676 -383.50571)
		(width 0.1016)
		(layer "F.Cu")
		(net "P5E_CPU1_P2_TX_C_DP<10>")
	)
	(segment
		(start 158.534862 -383.596896)
		(end 158.669228 -383.596896)
		(width 0.1016)
		(layer "F.Cu")
		(net "P5E_CPU1_P2_TX_C_DP<10>")
	)
	(segment
		(start 161.337244 -375.76633)
		(end 161.685478 -376.114564)
		(width 0.1016)
		(layer "F.Cu")
		(net "P5E_CPU1_P2_TX_C_DP<10>")
	)
	(segment
		(start 158.443676 -383.50571)
		(end 158.534862 -383.596896)
		(width 0.1016)
		(layer "F.Cu")
		(net "P5E_CPU1_P2_TX_C_DP<10>")
	)
	(segment
		(start 158.736284 -382.942592)
		(end 158.443676 -383.2352)
		(width 0.1016)
		(layer "F.Cu")
		(net "P5E_CPU1_P2_TX_C_DP<10>")
	)
	(segment
		(start 158.669228 -383.596896)
		(end 158.745682 -383.520442)
		(width 0.1016)
		(layer "F.Cu")
		(net "P5E_CPU1_P2_TX_C_DP<10>")
	)
	(arc
		(start 158.836614 -378.661676)
		(mid 158.762315 -378.773245)
		(end 158.736284 -378.904754)
		(width 0.1016)
		(layer "F.Cu")
		(net "P5E_CPU1_P2_TX_C_DP<10>")
	)
	(arc
		(start 160.329626 -377.321572)
		(mid 160.188586 -377.349627)
		(end 160.069022 -377.429522)
		(width 0.1016)
		(layer "F.Cu")
		(net "P5E_CPU1_P2_TX_C_DP<10>")
	)
	(arc
		(start 160.666684 -377.274328)
		(mid 160.614229 -377.309315)
		(end 160.552384 -377.321572)
		(width 0.1016)
		(layer "F.Cu")
		(net "P5E_CPU1_P2_TX_C_DP<10>")
	)
	(arc
		(start 161.685478 -376.202702)
		(mid 161.675772 -376.251497)
		(end 161.64814 -376.292872)
		(width 0.1016)
		(layer "F.Cu")
		(net "P5E_CPU1_P2_TX_C_DP<10>")
	)
	(segment
		(start 144.4625 -382.155192)
		(end 144.7673 -382.155192)
		(width 0.1016)
		(layer "F.Cu")
		(net "P5E_CPU1_P2_TX_C_DP<0>")
	)
	(segment
		(start 144.87906 -382.043432)
		(end 145.380202 -382.043432)
		(width 0.1016)
		(layer "F.Cu")
		(net "P5E_CPU1_P2_TX_C_DP<0>")
	)
	(segment
		(start 143.62938 -382.155192)
		(end 143.93418 -382.155192)
		(width 0.1016)
		(layer "F.Cu")
		(net "P5E_CPU1_P2_TX_C_DP<0>")
	)
	(segment
		(start 146.4437 -383.50571)
		(end 146.534886 -383.596896)
		(width 0.1016)
		(layer "F.Cu")
		(net "P5E_CPU1_P2_TX_C_DP<0>")
	)
	(segment
		(start 146.534886 -383.596896)
		(end 146.669252 -383.596896)
		(width 0.1016)
		(layer "F.Cu")
		(net "P5E_CPU1_P2_TX_C_DP<0>")
	)
	(segment
		(start 143.21282 -382.043432)
		(end 143.51762 -382.043432)
		(width 0.1016)
		(layer "F.Cu")
		(net "P5E_CPU1_P2_TX_C_DP<0>")
	)
	(segment
		(start 142.861792 -382.39446)
		(end 143.21282 -382.043432)
		(width 0.1016)
		(layer "F.Cu")
		(net "P5E_CPU1_P2_TX_C_DP<0>")
	)
	(segment
		(start 144.35074 -382.043432)
		(end 144.4625 -382.155192)
		(width 0.1016)
		(layer "F.Cu")
		(net "P5E_CPU1_P2_TX_C_DP<0>")
	)
	(segment
		(start 146.4437 -383.2352)
		(end 146.4437 -383.50571)
		(width 0.1016)
		(layer "F.Cu")
		(net "P5E_CPU1_P2_TX_C_DP<0>")
	)
	(segment
		(start 145.578068 -382.082802)
		(end 146.18335 -382.332738)
		(width 0.1016)
		(layer "F.Cu")
		(net "P5E_CPU1_P2_TX_C_DP<0>")
	)
	(segment
		(start 143.93418 -382.155192)
		(end 144.04594 -382.043432)
		(width 0.1016)
		(layer "F.Cu")
		(net "P5E_CPU1_P2_TX_C_DP<0>")
	)
	(segment
		(start 143.51762 -382.043432)
		(end 143.62938 -382.155192)
		(width 0.1016)
		(layer "F.Cu")
		(net "P5E_CPU1_P2_TX_C_DP<0>")
	)
	(segment
		(start 146.736308 -382.817624)
		(end 146.736308 -382.942592)
		(width 0.1016)
		(layer "F.Cu")
		(net "P5E_CPU1_P2_TX_C_DP<0>")
	)
	(segment
		(start 146.736308 -382.942592)
		(end 146.4437 -383.2352)
		(width 0.1016)
		(layer "F.Cu")
		(net "P5E_CPU1_P2_TX_C_DP<0>")
	)
	(segment
		(start 146.745706 -383.520442)
		(end 146.745706 -383.402586)
		(width 0.1016)
		(layer "F.Cu")
		(net "P5E_CPU1_P2_TX_C_DP<0>")
	)
	(segment
		(start 146.669252 -383.596896)
		(end 146.745706 -383.520442)
		(width 0.1016)
		(layer "F.Cu")
		(net "P5E_CPU1_P2_TX_C_DP<0>")
	)
	(segment
		(start 146.394932 -382.47447)
		(end 146.736308 -382.817624)
		(width 0.1016)
		(layer "F.Cu")
		(net "P5E_CPU1_P2_TX_C_DP<0>")
	)
	(segment
		(start 144.7673 -382.155192)
		(end 144.87906 -382.043432)
		(width 0.1016)
		(layer "F.Cu")
		(net "P5E_CPU1_P2_TX_C_DP<0>")
	)
	(segment
		(start 144.04594 -382.043432)
		(end 144.35074 -382.043432)
		(width 0.1016)
		(layer "F.Cu")
		(net "P5E_CPU1_P2_TX_C_DP<0>")
	)
	(arc
		(start 146.18335 -382.332738)
		(mid 146.296181 -382.393093)
		(end 146.394932 -382.47447)
		(width 0.1016)
		(layer "F.Cu")
		(net "P5E_CPU1_P2_TX_C_DP<0>")
	)
	(arc
		(start 145.380202 -382.043432)
		(mid 145.481067 -382.053399)
		(end 145.578068 -382.082802)
		(width 0.1016)
		(layer "F.Cu")
		(net "P5E_CPU1_P2_TX_C_DP<0>")
	)
	(segment
		(start 158.808166 -376.553984)
		(end 157.83306 -377.52909)
		(width 0.1016)
		(layer "F.Cu")
		(net "P5E_CPU1_P2_TX_C_DN<9>")
	)
	(segment
		(start 158.75127 -372.136162)
		(end 159.914336 -373.299228)
		(width 0.1016)
		(layer "F.Cu")
		(net "P5E_CPU1_P2_TX_C_DN<9>")
	)
	(segment
		(start 160.177226 -373.933466)
		(end 160.177226 -374.994932)
		(width 0.1016)
		(layer "F.Cu")
		(net "P5E_CPU1_P2_TX_C_DN<9>")
	)
	(segment
		(start 158.848044 -370.83873)
		(end 158.498794 -371.18798)
		(width 0.1016)
		(layer "F.Cu")
		(net "P5E_CPU1_P2_TX_C_DN<9>")
	)
	(segment
		(start 159.182054 -376.338084)
		(end 158.966154 -376.553984)
		(width 0.1016)
		(layer "F.Cu")
		(net "P5E_CPU1_P2_TX_C_DN<9>")
	)
	(segment
		(start 158.966154 -376.553984)
		(end 158.808166 -376.553984)
		(width 0.1016)
		(layer "F.Cu")
		(net "P5E_CPU1_P2_TX_C_DN<9>")
	)
	(segment
		(start 157.752288 -383.13741)
		(end 157.84576 -383.230882)
		(width 0.1016)
		(layer "F.Cu")
		(net "P5E_CPU1_P2_TX_C_DN<9>")
	)
	(segment
		(start 157.752288 -377.723908)
		(end 157.752288 -383.13741)
		(width 0.1016)
		(layer "F.Cu")
		(net "P5E_CPU1_P2_TX_C_DN<9>")
	)
	(segment
		(start 158.498794 -371.18798)
		(end 158.498794 -371.527324)
		(width 0.1016)
		(layer "F.Cu")
		(net "P5E_CPU1_P2_TX_C_DN<9>")
	)
	(segment
		(start 159.182054 -376.180096)
		(end 159.182054 -376.338084)
		(width 0.1016)
		(layer "F.Cu")
		(net "P5E_CPU1_P2_TX_C_DN<9>")
	)
	(segment
		(start 157.84576 -383.230882)
		(end 157.84576 -383.92227)
		(width 0.1016)
		(layer "F.Cu")
		(net "P5E_CPU1_P2_TX_C_DN<9>")
	)
	(segment
		(start 160.04286 -375.31929)
		(end 159.182054 -376.180096)
		(width 0.1016)
		(layer "F.Cu")
		(net "P5E_CPU1_P2_TX_C_DN<9>")
	)
	(arc
		(start 157.83306 -377.52909)
		(mid 157.773282 -377.618459)
		(end 157.752288 -377.723908)
		(width 0.1016)
		(layer "F.Cu")
		(net "P5E_CPU1_P2_TX_C_DN<9>")
	)
	(arc
		(start 159.914336 -373.299228)
		(mid 160.108853 -373.590204)
		(end 160.177226 -373.933466)
		(width 0.1016)
		(layer "F.Cu")
		(net "P5E_CPU1_P2_TX_C_DN<9>")
	)
	(arc
		(start 158.498794 -371.527324)
		(mid 158.564524 -371.856827)
		(end 158.75127 -372.136162)
		(width 0.1016)
		(layer "F.Cu")
		(net "P5E_CPU1_P2_TX_C_DN<9>")
	)
	(arc
		(start 160.177226 -374.994932)
		(mid 160.142308 -375.170478)
		(end 160.04286 -375.31929)
		(width 0.1016)
		(layer "F.Cu")
		(net "P5E_CPU1_P2_TX_C_DN<9>")
	)
	(segment
		(start 156.796994 -374.84304)
		(end 156.908754 -374.9548)
		(width 0.1016)
		(layer "F.Cu")
		(net "P5E_CPU1_P2_TX_C_DN<8>")
	)
	(segment
		(start 156.552138 -377.318016)
		(end 156.552138 -383.13741)
		(width 0.1016)
		(layer "F.Cu")
		(net "P5E_CPU1_P2_TX_C_DN<8>")
	)
	(segment
		(start 156.908754 -374.9548)
		(end 156.908754 -375.2596)
		(width 0.1016)
		(layer "F.Cu")
		(net "P5E_CPU1_P2_TX_C_DN<8>")
	)
	(segment
		(start 156.908754 -375.2596)
		(end 156.796994 -375.37136)
		(width 0.1016)
		(layer "F.Cu")
		(net "P5E_CPU1_P2_TX_C_DN<8>")
	)
	(segment
		(start 156.796994 -373.71909)
		(end 156.796994 -374.84304)
		(width 0.1016)
		(layer "F.Cu")
		(net "P5E_CPU1_P2_TX_C_DN<8>")
	)
	(segment
		(start 156.552138 -383.13741)
		(end 156.64561 -383.230882)
		(width 0.1016)
		(layer "F.Cu")
		(net "P5E_CPU1_P2_TX_C_DN<8>")
	)
	(segment
		(start 156.796994 -375.37136)
		(end 156.796994 -376.616976)
		(width 0.1016)
		(layer "F.Cu")
		(net "P5E_CPU1_P2_TX_C_DN<8>")
	)
	(segment
		(start 157.146244 -373.30253)
		(end 156.844492 -373.604282)
		(width 0.1016)
		(layer "F.Cu")
		(net "P5E_CPU1_P2_TX_C_DN<8>")
	)
	(segment
		(start 156.64561 -383.230882)
		(end 156.64561 -383.92227)
		(width 0.1016)
		(layer "F.Cu")
		(net "P5E_CPU1_P2_TX_C_DN<8>")
	)
	(arc
		(start 156.844492 -373.604282)
		(mid 156.80935 -373.656971)
		(end 156.796994 -373.71909)
		(width 0.1016)
		(layer "F.Cu")
		(net "P5E_CPU1_P2_TX_C_DN<8>")
	)
	(arc
		(start 156.656786 -377.022106)
		(mid 156.620722 -377.074405)
		(end 156.591508 -377.130818)
		(width 0.1016)
		(layer "F.Cu")
		(net "P5E_CPU1_P2_TX_C_DN<8>")
	)
	(arc
		(start 156.796994 -376.616976)
		(mid 156.760997 -376.831347)
		(end 156.656786 -377.022106)
		(width 0.1016)
		(layer "F.Cu")
		(net "P5E_CPU1_P2_TX_C_DN<8>")
	)
	(arc
		(start 156.591508 -377.130818)
		(mid 156.562044 -377.222364)
		(end 156.552138 -377.318016)
		(width 0.1016)
		(layer "F.Cu")
		(net "P5E_CPU1_P2_TX_C_DN<8>")
	)
	(segment
		(start 155.352242 -382.94183)
		(end 155.352242 -383.13741)
		(width 0.1016)
		(layer "F.Cu")
		(net "P5E_CPU1_P2_TX_C_DN<7>")
	)
	(segment
		(start 155.206954 -377.18619)
		(end 155.206954 -377.49099)
		(width 0.1016)
		(layer "F.Cu")
		(net "P5E_CPU1_P2_TX_C_DN<7>")
	)
	(segment
		(start 155.334462 -378.6632)
		(end 155.352242 -382.94183)
		(width 0.1016)
		(layer "F.Cu")
		(net "P5E_CPU1_P2_TX_C_DN<7>")
	)
	(segment
		(start 155.095194 -376.182636)
		(end 155.095194 -377.07443)
		(width 0.1016)
		(layer "F.Cu")
		(net "P5E_CPU1_P2_TX_C_DN<7>")
	)
	(segment
		(start 155.445714 -383.230882)
		(end 155.445714 -383.92227)
		(width 0.1016)
		(layer "F.Cu")
		(net "P5E_CPU1_P2_TX_C_DN<7>")
	)
	(segment
		(start 155.352242 -383.13741)
		(end 155.445714 -383.230882)
		(width 0.1016)
		(layer "F.Cu")
		(net "P5E_CPU1_P2_TX_C_DN<7>")
	)
	(segment
		(start 155.206954 -377.49099)
		(end 155.095194 -377.60275)
		(width 0.1016)
		(layer "F.Cu")
		(net "P5E_CPU1_P2_TX_C_DN<7>")
	)
	(segment
		(start 155.444444 -375.76633)
		(end 155.142438 -376.068336)
		(width 0.1016)
		(layer "F.Cu")
		(net "P5E_CPU1_P2_TX_C_DN<7>")
	)
	(segment
		(start 155.095194 -377.60275)
		(end 155.095194 -377.90755)
		(width 0.1016)
		(layer "F.Cu")
		(net "P5E_CPU1_P2_TX_C_DN<7>")
	)
	(segment
		(start 155.095194 -377.07443)
		(end 155.206954 -377.18619)
		(width 0.1016)
		(layer "F.Cu")
		(net "P5E_CPU1_P2_TX_C_DN<7>")
	)
	(arc
		(start 155.142438 -376.068336)
		(mid 155.107451 -376.120791)
		(end 155.095194 -376.182636)
		(width 0.1016)
		(layer "F.Cu")
		(net "P5E_CPU1_P2_TX_C_DN<7>")
	)
	(arc
		(start 155.095194 -377.90755)
		(mid 155.125736 -378.106219)
		(end 155.214574 -378.286518)
		(width 0.1016)
		(layer "F.Cu")
		(net "P5E_CPU1_P2_TX_C_DN<7>")
	)
	(arc
		(start 155.214574 -378.286518)
		(mid 155.303273 -378.465706)
		(end 155.334462 -378.6632)
		(width 0.1016)
		(layer "F.Cu")
		(net "P5E_CPU1_P2_TX_C_DN<7>")
	)
	(segment
		(start 153.41092 -375.377456)
		(end 153.41092 -378.006356)
		(width 0.1016)
		(layer "F.Cu")
		(net "P5E_CPU1_P2_TX_C_DN<6>")
	)
	(segment
		(start 153.537158 -378.652278)
		(end 153.573734 -378.742194)
		(width 0.1016)
		(layer "F.Cu")
		(net "P5E_CPU1_P2_TX_C_DN<6>")
	)
	(segment
		(start 151.954992 -372.114826)
		(end 153.1874 -373.347234)
		(width 0.1016)
		(layer "F.Cu")
		(net "P5E_CPU1_P2_TX_C_DN<6>")
	)
	(segment
		(start 154.245818 -383.231136)
		(end 154.245818 -383.92227)
		(width 0.1016)
		(layer "F.Cu")
		(net "P5E_CPU1_P2_TX_C_DN<6>")
	)
	(segment
		(start 153.52268 -375.265696)
		(end 153.41092 -375.377456)
		(width 0.1016)
		(layer "F.Cu")
		(net "P5E_CPU1_P2_TX_C_DN<6>")
	)
	(segment
		(start 154.152092 -381.694182)
		(end 154.152092 -383.13741)
		(width 0.1016)
		(layer "F.Cu")
		(net "P5E_CPU1_P2_TX_C_DN<6>")
	)
	(segment
		(start 154.152092 -383.13741)
		(end 154.245818 -383.231136)
		(width 0.1016)
		(layer "F.Cu")
		(net "P5E_CPU1_P2_TX_C_DN<6>")
	)
	(segment
		(start 153.52268 -374.960896)
		(end 153.52268 -375.265696)
		(width 0.1016)
		(layer "F.Cu")
		(net "P5E_CPU1_P2_TX_C_DN<6>")
	)
	(segment
		(start 153.41092 -373.88673)
		(end 153.41092 -374.849136)
		(width 0.1016)
		(layer "F.Cu")
		(net "P5E_CPU1_P2_TX_C_DN<6>")
	)
	(segment
		(start 152.040844 -370.83873)
		(end 151.691594 -371.18798)
		(width 0.1016)
		(layer "F.Cu")
		(net "P5E_CPU1_P2_TX_C_DN<6>")
	)
	(segment
		(start 151.691594 -371.18798)
		(end 151.691594 -371.479826)
		(width 0.1016)
		(layer "F.Cu")
		(net "P5E_CPU1_P2_TX_C_DN<6>")
	)
	(segment
		(start 153.41092 -374.849136)
		(end 153.52268 -374.960896)
		(width 0.1016)
		(layer "F.Cu")
		(net "P5E_CPU1_P2_TX_C_DN<6>")
	)
	(arc
		(start 153.1874 -373.347234)
		(mid 153.352765 -373.59477)
		(end 153.41092 -373.88673)
		(width 0.1016)
		(layer "F.Cu")
		(net "P5E_CPU1_P2_TX_C_DN<6>")
	)
	(arc
		(start 153.573734 -378.742194)
		(mid 154.0061 -380.190135)
		(end 154.152092 -381.694182)
		(width 0.1016)
		(layer "F.Cu")
		(net "P5E_CPU1_P2_TX_C_DN<6>")
	)
	(arc
		(start 151.691594 -371.479826)
		(mid 151.760161 -371.823506)
		(end 151.954992 -372.114826)
		(width 0.1016)
		(layer "F.Cu")
		(net "P5E_CPU1_P2_TX_C_DN<6>")
	)
	(arc
		(start 153.41092 -378.006356)
		(mid 153.442793 -378.335425)
		(end 153.537158 -378.652278)
		(width 0.1016)
		(layer "F.Cu")
		(net "P5E_CPU1_P2_TX_C_DN<6>")
	)
	(segment
		(start 150.339044 -373.30253)
		(end 149.989794 -373.65178)
		(width 0.1016)
		(layer "F.Cu")
		(net "P5E_CPU1_P2_TX_C_DN<5>")
	)
	(segment
		(start 149.989794 -375.057416)
		(end 149.989794 -375.362216)
		(width 0.1016)
		(layer "F.Cu")
		(net "P5E_CPU1_P2_TX_C_DN<5>")
	)
	(segment
		(start 150.101554 -374.945656)
		(end 149.989794 -375.057416)
		(width 0.1016)
		(layer "F.Cu")
		(net "P5E_CPU1_P2_TX_C_DN<5>")
	)
	(segment
		(start 149.989794 -373.65178)
		(end 149.989794 -374.529096)
		(width 0.1016)
		(layer "F.Cu")
		(net "P5E_CPU1_P2_TX_C_DN<5>")
	)
	(segment
		(start 150.101554 -374.640856)
		(end 150.101554 -374.945656)
		(width 0.1016)
		(layer "F.Cu")
		(net "P5E_CPU1_P2_TX_C_DN<5>")
	)
	(segment
		(start 150.317454 -376.44197)
		(end 152.247346 -379.328934)
		(width 0.1016)
		(layer "F.Cu")
		(net "P5E_CPU1_P2_TX_C_DN<5>")
	)
	(segment
		(start 149.989794 -374.529096)
		(end 150.101554 -374.640856)
		(width 0.1016)
		(layer "F.Cu")
		(net "P5E_CPU1_P2_TX_C_DN<5>")
	)
	(segment
		(start 152.952196 -383.13741)
		(end 153.045668 -383.230882)
		(width 0.1016)
		(layer "F.Cu")
		(net "P5E_CPU1_P2_TX_C_DN<5>")
	)
	(segment
		(start 153.045668 -383.230882)
		(end 153.045668 -383.92227)
		(width 0.1016)
		(layer "F.Cu")
		(net "P5E_CPU1_P2_TX_C_DN<5>")
	)
	(segment
		(start 152.952196 -381.651764)
		(end 152.952196 -383.13741)
		(width 0.1016)
		(layer "F.Cu")
		(net "P5E_CPU1_P2_TX_C_DN<5>")
	)
	(arc
		(start 149.989794 -375.362216)
		(mid 150.073515 -375.926402)
		(end 150.317454 -376.44197)
		(width 0.1016)
		(layer "F.Cu")
		(net "P5E_CPU1_P2_TX_C_DN<5>")
	)
	(arc
		(start 152.247346 -379.328934)
		(mid 152.772109 -380.438055)
		(end 152.952196 -381.651764)
		(width 0.1016)
		(layer "F.Cu")
		(net "P5E_CPU1_P2_TX_C_DN<5>")
	)
	(segment
		(start 151.845772 -383.230882)
		(end 151.845772 -383.92227)
		(width 0.1016)
		(layer "F.Cu")
		(net "P5E_CPU1_P2_TX_C_DN<4>")
	)
	(segment
		(start 151.7523 -383.13741)
		(end 151.845772 -383.230882)
		(width 0.1016)
		(layer "F.Cu")
		(net "P5E_CPU1_P2_TX_C_DN<4>")
	)
	(segment
		(start 149.38121 -377.878594)
		(end 151.379174 -380.31293)
		(width 0.1016)
		(layer "F.Cu")
		(net "P5E_CPU1_P2_TX_C_DN<4>")
	)
	(segment
		(start 148.637244 -375.76633)
		(end 148.287994 -376.11558)
		(width 0.1016)
		(layer "F.Cu")
		(net "P5E_CPU1_P2_TX_C_DN<4>")
	)
	(segment
		(start 148.287994 -376.28957)
		(end 148.50364 -376.809508)
		(width 0.1016)
		(layer "F.Cu")
		(net "P5E_CPU1_P2_TX_C_DN<4>")
	)
	(segment
		(start 148.287994 -376.11558)
		(end 148.287994 -376.28957)
		(width 0.1016)
		(layer "F.Cu")
		(net "P5E_CPU1_P2_TX_C_DN<4>")
	)
	(segment
		(start 149.202902 -377.485402)
		(end 149.39645 -377.721114)
		(width 0.1016)
		(layer "F.Cu")
		(net "P5E_CPU1_P2_TX_C_DN<4>")
	)
	(segment
		(start 148.50364 -376.809508)
		(end 149.045676 -377.469908)
		(width 0.1016)
		(layer "F.Cu")
		(net "P5E_CPU1_P2_TX_C_DN<4>")
	)
	(segment
		(start 151.7523 -381.573278)
		(end 151.7523 -383.13741)
		(width 0.1016)
		(layer "F.Cu")
		(net "P5E_CPU1_P2_TX_C_DN<4>")
	)
	(segment
		(start 149.045676 -377.469908)
		(end 149.202902 -377.485402)
		(width 0.1016)
		(layer "F.Cu")
		(net "P5E_CPU1_P2_TX_C_DN<4>")
	)
	(segment
		(start 149.39645 -377.721114)
		(end 149.38121 -377.878594)
		(width 0.1016)
		(layer "F.Cu")
		(net "P5E_CPU1_P2_TX_C_DN<4>")
	)
	(arc
		(start 151.7523 -381.572262)
		(mid 151.7523 -381.57277)
		(end 151.7523 -381.573278)
		(width 0.1016)
		(layer "F.Cu")
		(net "P5E_CPU1_P2_TX_C_DN<4>")
	)
	(arc
		(start 151.379174 -380.31293)
		(mid 151.656826 -380.915208)
		(end 151.7523 -381.5715)
		(width 0.1016)
		(layer "F.Cu")
		(net "P5E_CPU1_P2_TX_C_DN<4>")
	)
	(arc
		(start 151.7523 -381.5715)
		(mid 151.7523 -381.571881)
		(end 151.7523 -381.572262)
		(width 0.1016)
		(layer "F.Cu")
		(net "P5E_CPU1_P2_TX_C_DN<4>")
	)
	(segment
		(start 147.497292 -377.514358)
		(end 147.7518 -377.9393)
		(width 0.1016)
		(layer "F.Cu")
		(net "P5E_CPU1_P2_TX_C_DN<3>")
	)
	(segment
		(start 146.643344 -375.452132)
		(end 147.497292 -377.514358)
		(width 0.1016)
		(layer "F.Cu")
		(net "P5E_CPU1_P2_TX_C_DN<3>")
	)
	(segment
		(start 145.233644 -370.83873)
		(end 144.884394 -371.18798)
		(width 0.1016)
		(layer "F.Cu")
		(net "P5E_CPU1_P2_TX_C_DN<3>")
	)
	(segment
		(start 150.55215 -383.13741)
		(end 150.645622 -383.230882)
		(width 0.1016)
		(layer "F.Cu")
		(net "P5E_CPU1_P2_TX_C_DN<3>")
	)
	(segment
		(start 146.594068 -373.738902)
		(end 146.594068 -375.203466)
		(width 0.1016)
		(layer "F.Cu")
		(net "P5E_CPU1_P2_TX_C_DN<3>")
	)
	(segment
		(start 144.884394 -371.18798)
		(end 144.884394 -371.57152)
		(width 0.1016)
		(layer "F.Cu")
		(net "P5E_CPU1_P2_TX_C_DN<3>")
	)
	(segment
		(start 145.069052 -372.01729)
		(end 145.819876 -372.768114)
		(width 0.1016)
		(layer "F.Cu")
		(net "P5E_CPU1_P2_TX_C_DN<3>")
	)
	(segment
		(start 146.193764 -373.142002)
		(end 146.454876 -373.403114)
		(width 0.1016)
		(layer "F.Cu")
		(net "P5E_CPU1_P2_TX_C_DN<3>")
	)
	(segment
		(start 150.55215 -381.614426)
		(end 150.55215 -383.13741)
		(width 0.1016)
		(layer "F.Cu")
		(net "P5E_CPU1_P2_TX_C_DN<3>")
	)
	(segment
		(start 146.193764 -372.984014)
		(end 146.193764 -373.142002)
		(width 0.1016)
		(layer "F.Cu")
		(net "P5E_CPU1_P2_TX_C_DN<3>")
	)
	(segment
		(start 147.7518 -377.9393)
		(end 150.384764 -381.147574)
		(width 0.1016)
		(layer "F.Cu")
		(net "P5E_CPU1_P2_TX_C_DN<3>")
	)
	(segment
		(start 150.645622 -383.230882)
		(end 150.645622 -383.92227)
		(width 0.1016)
		(layer "F.Cu")
		(net "P5E_CPU1_P2_TX_C_DN<3>")
	)
	(segment
		(start 145.819876 -372.768114)
		(end 145.977864 -372.768114)
		(width 0.1016)
		(layer "F.Cu")
		(net "P5E_CPU1_P2_TX_C_DN<3>")
	)
	(segment
		(start 145.977864 -372.768114)
		(end 146.193764 -372.984014)
		(width 0.1016)
		(layer "F.Cu")
		(net "P5E_CPU1_P2_TX_C_DN<3>")
	)
	(arc
		(start 144.884394 -371.57152)
		(mid 144.932382 -371.812774)
		(end 145.069052 -372.01729)
		(width 0.1016)
		(layer "F.Cu")
		(net "P5E_CPU1_P2_TX_C_DN<3>")
	)
	(arc
		(start 150.384764 -381.147574)
		(mid 150.508982 -381.366463)
		(end 150.55215 -381.614426)
		(width 0.1016)
		(layer "F.Cu")
		(net "P5E_CPU1_P2_TX_C_DN<3>")
	)
	(arc
		(start 146.594068 -375.203466)
		(mid 146.606448 -375.33023)
		(end 146.643344 -375.452132)
		(width 0.1016)
		(layer "F.Cu")
		(net "P5E_CPU1_P2_TX_C_DN<3>")
	)
	(arc
		(start 146.454876 -373.403114)
		(mid 146.55787 -373.557161)
		(end 146.594068 -373.738902)
		(width 0.1016)
		(layer "F.Cu")
		(net "P5E_CPU1_P2_TX_C_DN<3>")
	)
	(segment
		(start 149.352254 -383.13741)
		(end 149.445726 -383.230882)
		(width 0.1016)
		(layer "F.Cu")
		(net "P5E_CPU1_P2_TX_C_DN<2>")
	)
	(segment
		(start 149.352254 -382.220216)
		(end 149.352254 -383.13741)
		(width 0.1016)
		(layer "F.Cu")
		(net "P5E_CPU1_P2_TX_C_DN<2>")
	)
	(segment
		(start 146.531838 -378.32792)
		(end 146.666204 -378.55144)
		(width 0.1016)
		(layer "F.Cu")
		(net "P5E_CPU1_P2_TX_C_DN<2>")
	)
	(segment
		(start 143.377412 -374.751854)
		(end 143.425418 -374.79986)
		(width 0.1016)
		(layer "F.Cu")
		(net "P5E_CPU1_P2_TX_C_DN<2>")
	)
	(segment
		(start 145.48104 -376.00509)
		(end 145.48104 -376.163078)
		(width 0.1016)
		(layer "F.Cu")
		(net "P5E_CPU1_P2_TX_C_DN<2>")
	)
	(segment
		(start 149.445726 -383.230882)
		(end 149.445726 -383.92227)
		(width 0.1016)
		(layer "F.Cu")
		(net "P5E_CPU1_P2_TX_C_DN<2>")
	)
	(segment
		(start 143.182594 -373.65178)
		(end 143.182594 -374.282208)
		(width 0.1016)
		(layer "F.Cu")
		(net "P5E_CPU1_P2_TX_C_DN<2>")
	)
	(segment
		(start 145.26514 -375.78919)
		(end 145.48104 -376.00509)
		(width 0.1016)
		(layer "F.Cu")
		(net "P5E_CPU1_P2_TX_C_DN<2>")
	)
	(segment
		(start 145.107152 -375.78919)
		(end 145.26514 -375.78919)
		(width 0.1016)
		(layer "F.Cu")
		(net "P5E_CPU1_P2_TX_C_DN<2>")
	)
	(segment
		(start 145.81632 -376.599704)
		(end 146.531838 -378.32792)
		(width 0.1016)
		(layer "F.Cu")
		(net "P5E_CPU1_P2_TX_C_DN<2>")
	)
	(segment
		(start 145.48104 -376.163078)
		(end 145.612104 -376.294142)
		(width 0.1016)
		(layer "F.Cu")
		(net "P5E_CPU1_P2_TX_C_DN<2>")
	)
	(segment
		(start 146.926046 -378.919994)
		(end 149.132036 -381.605536)
		(width 0.1016)
		(layer "F.Cu")
		(net "P5E_CPU1_P2_TX_C_DN<2>")
	)
	(segment
		(start 143.531844 -373.30253)
		(end 143.182594 -373.65178)
		(width 0.1016)
		(layer "F.Cu")
		(net "P5E_CPU1_P2_TX_C_DN<2>")
	)
	(segment
		(start 143.776192 -375.034556)
		(end 144.6911 -375.413524)
		(width 0.1016)
		(layer "F.Cu")
		(net "P5E_CPU1_P2_TX_C_DN<2>")
	)
	(segment
		(start 144.812512 -375.49455)
		(end 145.107152 -375.78919)
		(width 0.1016)
		(layer "F.Cu")
		(net "P5E_CPU1_P2_TX_C_DN<2>")
	)
	(arc
		(start 149.132036 -381.605536)
		(mid 149.295525 -381.893755)
		(end 149.352254 -382.220216)
		(width 0.1016)
		(layer "F.Cu")
		(net "P5E_CPU1_P2_TX_C_DN<2>")
	)
	(arc
		(start 143.425418 -374.79986)
		(mid 143.589256 -374.934467)
		(end 143.776192 -375.034556)
		(width 0.1016)
		(layer "F.Cu")
		(net "P5E_CPU1_P2_TX_C_DN<2>")
	)
	(arc
		(start 146.666204 -378.55144)
		(mid 146.789363 -378.740484)
		(end 146.926046 -378.919994)
		(width 0.1016)
		(layer "F.Cu")
		(net "P5E_CPU1_P2_TX_C_DN<2>")
	)
	(arc
		(start 143.182594 -374.282208)
		(mid 143.233339 -374.53638)
		(end 143.377412 -374.751854)
		(width 0.1016)
		(layer "F.Cu")
		(net "P5E_CPU1_P2_TX_C_DN<2>")
	)
	(arc
		(start 145.612104 -376.294142)
		(mid 145.729269 -376.436861)
		(end 145.81632 -376.599704)
		(width 0.1016)
		(layer "F.Cu")
		(net "P5E_CPU1_P2_TX_C_DN<2>")
	)
	(arc
		(start 144.6911 -375.413524)
		(mid 144.755807 -375.448045)
		(end 144.812512 -375.49455)
		(width 0.1016)
		(layer "F.Cu")
		(net "P5E_CPU1_P2_TX_C_DN<2>")
	)
	(segment
		(start 145.226024 -378.874782)
		(end 145.36928 -379.221238)
		(width 0.1016)
		(layer "F.Cu")
		(net "P5E_CPU1_P2_TX_C_DN<1>")
	)
	(segment
		(start 142.861792 -376.85726)
		(end 143.232886 -376.486166)
		(width 0.1016)
		(layer "F.Cu")
		(net "P5E_CPU1_P2_TX_C_DN<1>")
	)
	(segment
		(start 147.936204 -382.554734)
		(end 147.936204 -382.942592)
		(width 0.1016)
		(layer "F.Cu")
		(net "P5E_CPU1_P2_TX_C_DN<1>")
	)
	(segment
		(start 147.945602 -383.520442)
		(end 147.945602 -383.402586)
		(width 0.1016)
		(layer "F.Cu")
		(net "P5E_CPU1_P2_TX_C_DN<1>")
	)
	(segment
		(start 147.734782 -383.596896)
		(end 147.869148 -383.596896)
		(width 0.1016)
		(layer "F.Cu")
		(net "P5E_CPU1_P2_TX_C_DN<1>")
	)
	(segment
		(start 147.936204 -382.942592)
		(end 147.643596 -383.2352)
		(width 0.1016)
		(layer "F.Cu")
		(net "P5E_CPU1_P2_TX_C_DN<1>")
	)
	(segment
		(start 145.538444 -379.474476)
		(end 145.50771 -379.62967)
		(width 0.1016)
		(layer "F.Cu")
		(net "P5E_CPU1_P2_TX_C_DN<1>")
	)
	(segment
		(start 145.023586 -378.386594)
		(end 144.963134 -378.53239)
		(width 0.1016)
		(layer "F.Cu")
		(net "P5E_CPU1_P2_TX_C_DN<1>")
	)
	(segment
		(start 144.573498 -377.298966)
		(end 145.023586 -378.386594)
		(width 0.1016)
		(layer "F.Cu")
		(net "P5E_CPU1_P2_TX_C_DN<1>")
	)
	(segment
		(start 145.832322 -379.91415)
		(end 145.946114 -380.08433)
		(width 0.1016)
		(layer "F.Cu")
		(net "P5E_CPU1_P2_TX_C_DN<1>")
	)
	(segment
		(start 145.07972 -378.81433)
		(end 145.226024 -378.874782)
		(width 0.1016)
		(layer "F.Cu")
		(net "P5E_CPU1_P2_TX_C_DN<1>")
	)
	(segment
		(start 144.963134 -378.53239)
		(end 145.07972 -378.81433)
		(width 0.1016)
		(layer "F.Cu")
		(net "P5E_CPU1_P2_TX_C_DN<1>")
	)
	(segment
		(start 147.869148 -383.596896)
		(end 147.945602 -383.520442)
		(width 0.1016)
		(layer "F.Cu")
		(net "P5E_CPU1_P2_TX_C_DN<1>")
	)
	(segment
		(start 147.643596 -383.2352)
		(end 147.643596 -383.50571)
		(width 0.1016)
		(layer "F.Cu")
		(net "P5E_CPU1_P2_TX_C_DN<1>")
	)
	(segment
		(start 143.232886 -376.486166)
		(end 143.31696 -376.486166)
		(width 0.1016)
		(layer "F.Cu")
		(net "P5E_CPU1_P2_TX_C_DN<1>")
	)
	(segment
		(start 146.696938 -380.867412)
		(end 147.708874 -382.100836)
		(width 0.1016)
		(layer "F.Cu")
		(net "P5E_CPU1_P2_TX_C_DN<1>")
	)
	(segment
		(start 147.835366 -382.311656)
		(end 147.936204 -382.554734)
		(width 0.1016)
		(layer "F.Cu")
		(net "P5E_CPU1_P2_TX_C_DN<1>")
	)
	(segment
		(start 145.36928 -379.221238)
		(end 145.538444 -379.474476)
		(width 0.1016)
		(layer "F.Cu")
		(net "P5E_CPU1_P2_TX_C_DN<1>")
	)
	(segment
		(start 147.708874 -382.100836)
		(end 147.835366 -382.311656)
		(width 0.1016)
		(layer "F.Cu")
		(net "P5E_CPU1_P2_TX_C_DN<1>")
	)
	(segment
		(start 146.093688 -380.264162)
		(end 146.696938 -380.867412)
		(width 0.1016)
		(layer "F.Cu")
		(net "P5E_CPU1_P2_TX_C_DN<1>")
	)
	(segment
		(start 145.50771 -379.62967)
		(end 145.677128 -379.883162)
		(width 0.1016)
		(layer "F.Cu")
		(net "P5E_CPU1_P2_TX_C_DN<1>")
	)
	(segment
		(start 147.643596 -383.50571)
		(end 147.734782 -383.596896)
		(width 0.1016)
		(layer "F.Cu")
		(net "P5E_CPU1_P2_TX_C_DN<1>")
	)
	(segment
		(start 145.677128 -379.883162)
		(end 145.832322 -379.91415)
		(width 0.1016)
		(layer "F.Cu")
		(net "P5E_CPU1_P2_TX_C_DN<1>")
	)
	(segment
		(start 144.15389 -376.832876)
		(end 144.480026 -377.159012)
		(width 0.1016)
		(layer "F.Cu")
		(net "P5E_CPU1_P2_TX_C_DN<1>")
	)
	(arc
		(start 144.480026 -377.159012)
		(mid 144.533665 -377.22438)
		(end 144.573498 -377.298966)
		(width 0.1016)
		(layer "F.Cu")
		(net "P5E_CPU1_P2_TX_C_DN<1>")
	)
	(arc
		(start 145.946114 -380.08433)
		(mid 146.015485 -380.17787)
		(end 146.093688 -380.264162)
		(width 0.1016)
		(layer "F.Cu")
		(net "P5E_CPU1_P2_TX_C_DN<1>")
	)
	(arc
		(start 143.31696 -376.486166)
		(mid 143.769905 -376.57628)
		(end 144.15389 -376.832876)
		(width 0.1016)
		(layer "F.Cu")
		(net "P5E_CPU1_P2_TX_C_DN<1>")
	)
	(segment
		(start 165.046152 -383.02057)
		(end 165.046152 -383.921762)
		(width 0.1016)
		(layer "F.Cu")
		(net "P5E_CPU1_P2_TX_C_DN<15>")
	)
	(segment
		(start 164.952172 -382.205484)
		(end 164.952172 -382.92659)
		(width 0.1016)
		(layer "F.Cu")
		(net "P5E_CPU1_P2_TX_C_DN<15>")
	)
	(segment
		(start 165.046152 -383.921762)
		(end 165.045644 -383.92227)
		(width 0.1016)
		(layer "F.Cu")
		(net "P5E_CPU1_P2_TX_C_DN<15>")
	)
	(segment
		(start 168.752774 -380.036578)
		(end 167.047926 -380.036578)
		(width 0.1016)
		(layer "F.Cu")
		(net "P5E_CPU1_P2_TX_C_DN<15>")
	)
	(segment
		(start 169.102024 -380.385828)
		(end 168.752774 -380.036578)
		(width 0.1016)
		(layer "F.Cu")
		(net "P5E_CPU1_P2_TX_C_DN<15>")
	)
	(segment
		(start 166.946834 -380.078488)
		(end 165.045898 -381.979424)
		(width 0.1016)
		(layer "F.Cu")
		(net "P5E_CPU1_P2_TX_C_DN<15>")
	)
	(segment
		(start 164.952172 -382.92659)
		(end 165.046152 -383.02057)
		(width 0.1016)
		(layer "F.Cu")
		(net "P5E_CPU1_P2_TX_C_DN<15>")
	)
	(arc
		(start 167.047926 -380.036578)
		(mid 166.993202 -380.047463)
		(end 166.946834 -380.078488)
		(width 0.1016)
		(layer "F.Cu")
		(net "P5E_CPU1_P2_TX_C_DN<15>")
	)
	(arc
		(start 165.045898 -381.979424)
		(mid 164.976543 -382.083127)
		(end 164.952172 -382.205484)
		(width 0.1016)
		(layer "F.Cu")
		(net "P5E_CPU1_P2_TX_C_DN<15>")
	)
	(segment
		(start 163.846256 -383.02057)
		(end 163.846256 -383.921762)
		(width 0.1016)
		(layer "F.Cu")
		(net "P5E_CPU1_P2_TX_C_DN<14>")
	)
	(segment
		(start 168.756838 -376.71883)
		(end 168.442386 -376.71883)
		(width 0.1016)
		(layer "F.Cu")
		(net "P5E_CPU1_P2_TX_C_DN<14>")
	)
	(segment
		(start 163.752276 -381.688848)
		(end 163.752276 -382.92659)
		(width 0.1016)
		(layer "F.Cu")
		(net "P5E_CPU1_P2_TX_C_DN<14>")
	)
	(segment
		(start 169.102024 -376.982228)
		(end 168.896538 -376.776742)
		(width 0.1016)
		(layer "F.Cu")
		(net "P5E_CPU1_P2_TX_C_DN<14>")
	)
	(segment
		(start 163.846256 -383.921762)
		(end 163.845748 -383.92227)
		(width 0.1016)
		(layer "F.Cu")
		(net "P5E_CPU1_P2_TX_C_DN<14>")
	)
	(segment
		(start 163.752276 -382.92659)
		(end 163.846256 -383.02057)
		(width 0.1016)
		(layer "F.Cu")
		(net "P5E_CPU1_P2_TX_C_DN<14>")
	)
	(segment
		(start 163.75253 -381.689102)
		(end 163.752276 -381.688848)
		(width 0.1016)
		(layer "F.Cu")
		(net "P5E_CPU1_P2_TX_C_DN<14>")
	)
	(segment
		(start 168.896538 -376.776742)
		(end 168.756838 -376.71883)
		(width 0.1016)
		(layer "F.Cu")
		(net "P5E_CPU1_P2_TX_C_DN<14>")
	)
	(segment
		(start 168.442386 -376.71883)
		(end 163.950142 -381.211074)
		(width 0.1016)
		(layer "F.Cu")
		(net "P5E_CPU1_P2_TX_C_DN<14>")
	)
	(arc
		(start 163.950142 -381.211074)
		(mid 163.803816 -381.430439)
		(end 163.75253 -381.689102)
		(width 0.1016)
		(layer "F.Cu")
		(net "P5E_CPU1_P2_TX_C_DN<14>")
	)
	(segment
		(start 170.147996 -374.706388)
		(end 169.722546 -375.131838)
		(width 0.1016)
		(layer "F.Cu")
		(net "P5E_CPU1_P2_TX_C_DN<13>")
	)
	(segment
		(start 162.645598 -383.230882)
		(end 162.645598 -383.92227)
		(width 0.1016)
		(layer "F.Cu")
		(net "P5E_CPU1_P2_TX_C_DN<13>")
	)
	(segment
		(start 169.950892 -373.125238)
		(end 170.166284 -373.34063)
		(width 0.1016)
		(layer "F.Cu")
		(net "P5E_CPU1_P2_TX_C_DN<13>")
	)
	(segment
		(start 162.552126 -383.13741)
		(end 162.645598 -383.230882)
		(width 0.1016)
		(layer "F.Cu")
		(net "P5E_CPU1_P2_TX_C_DN<13>")
	)
	(segment
		(start 169.28465 -375.31294)
		(end 168.403778 -375.31294)
		(width 0.1016)
		(layer "F.Cu")
		(net "P5E_CPU1_P2_TX_C_DN<13>")
	)
	(segment
		(start 167.986202 -375.485914)
		(end 162.589464 -380.882652)
		(width 0.1016)
		(layer "F.Cu")
		(net "P5E_CPU1_P2_TX_C_DN<13>")
	)
	(segment
		(start 169.734992 -372.75135)
		(end 169.950892 -372.96725)
		(width 0.1016)
		(layer "F.Cu")
		(net "P5E_CPU1_P2_TX_C_DN<13>")
	)
	(segment
		(start 168.709594 -371.527832)
		(end 168.709848 -371.527578)
		(width 0.1016)
		(layer "F.Cu")
		(net "P5E_CPU1_P2_TX_C_DN<13>")
	)
	(segment
		(start 170.383708 -373.866156)
		(end 170.383708 -374.136666)
		(width 0.1016)
		(layer "F.Cu")
		(net "P5E_CPU1_P2_TX_C_DN<13>")
	)
	(segment
		(start 168.961562 -372.135908)
		(end 169.577004 -372.75135)
		(width 0.1016)
		(layer "F.Cu")
		(net "P5E_CPU1_P2_TX_C_DN<13>")
	)
	(segment
		(start 169.577004 -372.75135)
		(end 169.734992 -372.75135)
		(width 0.1016)
		(layer "F.Cu")
		(net "P5E_CPU1_P2_TX_C_DN<13>")
	)
	(segment
		(start 169.950892 -372.96725)
		(end 169.950892 -373.125238)
		(width 0.1016)
		(layer "F.Cu")
		(net "P5E_CPU1_P2_TX_C_DN<13>")
	)
	(segment
		(start 169.058844 -370.83873)
		(end 168.709594 -371.18798)
		(width 0.1016)
		(layer "F.Cu")
		(net "P5E_CPU1_P2_TX_C_DN<13>")
	)
	(segment
		(start 168.709594 -371.18798)
		(end 168.709594 -371.527832)
		(width 0.1016)
		(layer "F.Cu")
		(net "P5E_CPU1_P2_TX_C_DN<13>")
	)
	(segment
		(start 162.552126 -380.972822)
		(end 162.552126 -383.13741)
		(width 0.1016)
		(layer "F.Cu")
		(net "P5E_CPU1_P2_TX_C_DN<13>")
	)
	(arc
		(start 168.403778 -375.31294)
		(mid 168.177784 -375.357893)
		(end 167.986202 -375.485914)
		(width 0.1016)
		(layer "F.Cu")
		(net "P5E_CPU1_P2_TX_C_DN<13>")
	)
	(arc
		(start 169.722546 -375.131838)
		(mid 169.521608 -375.265915)
		(end 169.28465 -375.31294)
		(width 0.1016)
		(layer "F.Cu")
		(net "P5E_CPU1_P2_TX_C_DN<13>")
	)
	(arc
		(start 170.383708 -374.136666)
		(mid 170.322564 -374.445)
		(end 170.147996 -374.706388)
		(width 0.1016)
		(layer "F.Cu")
		(net "P5E_CPU1_P2_TX_C_DN<13>")
	)
	(arc
		(start 162.589464 -380.882652)
		(mid 162.561821 -380.924022)
		(end 162.552126 -380.972822)
		(width 0.1016)
		(layer "F.Cu")
		(net "P5E_CPU1_P2_TX_C_DN<13>")
	)
	(arc
		(start 168.709848 -371.527578)
		(mid 168.775217 -371.856771)
		(end 168.961562 -372.135908)
		(width 0.1016)
		(layer "F.Cu")
		(net "P5E_CPU1_P2_TX_C_DN<13>")
	)
	(arc
		(start 170.166284 -373.34063)
		(mid 170.327279 -373.581759)
		(end 170.383708 -373.866156)
		(width 0.1016)
		(layer "F.Cu")
		(net "P5E_CPU1_P2_TX_C_DN<13>")
	)
	(segment
		(start 165.305994 -371.18798)
		(end 165.305994 -371.5385)
		(width 0.1016)
		(layer "F.Cu")
		(net "P5E_CPU1_P2_TX_C_DN<12>")
	)
	(segment
		(start 161.35223 -383.13741)
		(end 161.445702 -383.230882)
		(width 0.1016)
		(layer "F.Cu")
		(net "P5E_CPU1_P2_TX_C_DN<12>")
	)
	(segment
		(start 166.584376 -372.925594)
		(end 166.800276 -373.141494)
		(width 0.1016)
		(layer "F.Cu")
		(net "P5E_CPU1_P2_TX_C_DN<12>")
	)
	(segment
		(start 166.879778 -374.890284)
		(end 161.576258 -380.194058)
		(width 0.1016)
		(layer "F.Cu")
		(net "P5E_CPU1_P2_TX_C_DN<12>")
	)
	(segment
		(start 165.495224 -371.99443)
		(end 166.426388 -372.925594)
		(width 0.1016)
		(layer "F.Cu")
		(net "P5E_CPU1_P2_TX_C_DN<12>")
	)
	(segment
		(start 161.35223 -380.734062)
		(end 161.35223 -383.13741)
		(width 0.1016)
		(layer "F.Cu")
		(net "P5E_CPU1_P2_TX_C_DN<12>")
	)
	(segment
		(start 166.800276 -373.299482)
		(end 166.915338 -373.414544)
		(width 0.1016)
		(layer "F.Cu")
		(net "P5E_CPU1_P2_TX_C_DN<12>")
	)
	(segment
		(start 166.800276 -373.141494)
		(end 166.800276 -373.299482)
		(width 0.1016)
		(layer "F.Cu")
		(net "P5E_CPU1_P2_TX_C_DN<12>")
	)
	(segment
		(start 161.445702 -383.230882)
		(end 161.445702 -383.92227)
		(width 0.1016)
		(layer "F.Cu")
		(net "P5E_CPU1_P2_TX_C_DN<12>")
	)
	(segment
		(start 166.426388 -372.925594)
		(end 166.584376 -372.925594)
		(width 0.1016)
		(layer "F.Cu")
		(net "P5E_CPU1_P2_TX_C_DN<12>")
	)
	(segment
		(start 165.655244 -370.83873)
		(end 165.305994 -371.18798)
		(width 0.1016)
		(layer "F.Cu")
		(net "P5E_CPU1_P2_TX_C_DN<12>")
	)
	(segment
		(start 167.015668 -373.657368)
		(end 167.015668 -374.563132)
		(width 0.1016)
		(layer "F.Cu")
		(net "P5E_CPU1_P2_TX_C_DN<12>")
	)
	(arc
		(start 161.576258 -380.194058)
		(mid 161.410493 -380.44177)
		(end 161.35223 -380.734062)
		(width 0.1016)
		(layer "F.Cu")
		(net "P5E_CPU1_P2_TX_C_DN<12>")
	)
	(arc
		(start 166.915338 -373.414544)
		(mid 166.989642 -373.525982)
		(end 167.015668 -373.657368)
		(width 0.1016)
		(layer "F.Cu")
		(net "P5E_CPU1_P2_TX_C_DN<12>")
	)
	(arc
		(start 165.305994 -371.5385)
		(mid 165.355285 -371.78527)
		(end 165.495224 -371.99443)
		(width 0.1016)
		(layer "F.Cu")
		(net "P5E_CPU1_P2_TX_C_DN<12>")
	)
	(arc
		(start 167.015668 -374.563132)
		(mid 166.98024 -374.740209)
		(end 166.879778 -374.890284)
		(width 0.1016)
		(layer "F.Cu")
		(net "P5E_CPU1_P2_TX_C_DN<12>")
	)
	(segment
		(start 163.604194 -375.021856)
		(end 163.715954 -375.133616)
		(width 0.1016)
		(layer "F.Cu")
		(net "P5E_CPU1_P2_TX_C_DN<11>")
	)
	(segment
		(start 160.15208 -379.884178)
		(end 160.15208 -383.13741)
		(width 0.1016)
		(layer "F.Cu")
		(net "P5E_CPU1_P2_TX_C_DN<11>")
	)
	(segment
		(start 163.953444 -373.30253)
		(end 163.604194 -373.65178)
		(width 0.1016)
		(layer "F.Cu")
		(net "P5E_CPU1_P2_TX_C_DN<11>")
	)
	(segment
		(start 163.503864 -376.479562)
		(end 160.189418 -379.794008)
		(width 0.1016)
		(layer "F.Cu")
		(net "P5E_CPU1_P2_TX_C_DN<11>")
	)
	(segment
		(start 160.15208 -383.13741)
		(end 160.245806 -383.231136)
		(width 0.1016)
		(layer "F.Cu")
		(net "P5E_CPU1_P2_TX_C_DN<11>")
	)
	(segment
		(start 163.604194 -373.65178)
		(end 163.604194 -375.021856)
		(width 0.1016)
		(layer "F.Cu")
		(net "P5E_CPU1_P2_TX_C_DN<11>")
	)
	(segment
		(start 163.715954 -375.133616)
		(end 163.715954 -375.438416)
		(width 0.1016)
		(layer "F.Cu")
		(net "P5E_CPU1_P2_TX_C_DN<11>")
	)
	(segment
		(start 160.245806 -383.231136)
		(end 160.245806 -383.92227)
		(width 0.1016)
		(layer "F.Cu")
		(net "P5E_CPU1_P2_TX_C_DN<11>")
	)
	(segment
		(start 163.604194 -375.550176)
		(end 163.604194 -376.236484)
		(width 0.1016)
		(layer "F.Cu")
		(net "P5E_CPU1_P2_TX_C_DN<11>")
	)
	(segment
		(start 163.715954 -375.438416)
		(end 163.604194 -375.550176)
		(width 0.1016)
		(layer "F.Cu")
		(net "P5E_CPU1_P2_TX_C_DN<11>")
	)
	(arc
		(start 163.604194 -376.236484)
		(mid 163.578235 -376.368022)
		(end 163.503864 -376.479562)
		(width 0.1016)
		(layer "F.Cu")
		(net "P5E_CPU1_P2_TX_C_DN<11>")
	)
	(arc
		(start 160.189418 -379.794008)
		(mid 160.161775 -379.835378)
		(end 160.15208 -379.884178)
		(width 0.1016)
		(layer "F.Cu")
		(net "P5E_CPU1_P2_TX_C_DN<11>")
	)
	(segment
		(start 158.952184 -378.904754)
		(end 158.952184 -383.13741)
		(width 0.1016)
		(layer "F.Cu")
		(net "P5E_CPU1_P2_TX_C_DN<10>")
	)
	(segment
		(start 158.952184 -383.13741)
		(end 159.045656 -383.230882)
		(width 0.1016)
		(layer "F.Cu")
		(net "P5E_CPU1_P2_TX_C_DN<10>")
	)
	(segment
		(start 159.045656 -383.230882)
		(end 159.045656 -383.92227)
		(width 0.1016)
		(layer "F.Cu")
		(net "P5E_CPU1_P2_TX_C_DN<10>")
	)
	(segment
		(start 159.541972 -378.420122)
		(end 159.326326 -378.635768)
		(width 0.1016)
		(layer "F.Cu")
		(net "P5E_CPU1_P2_TX_C_DN<10>")
	)
	(segment
		(start 159.326326 -378.635768)
		(end 159.168338 -378.635768)
		(width 0.1016)
		(layer "F.Cu")
		(net "P5E_CPU1_P2_TX_C_DN<10>")
	)
	(segment
		(start 161.801048 -376.44578)
		(end 160.819338 -377.427236)
		(width 0.1016)
		(layer "F.Cu")
		(net "P5E_CPU1_P2_TX_C_DN<10>")
	)
	(segment
		(start 160.55213 -377.537472)
		(end 160.32988 -377.537472)
		(width 0.1016)
		(layer "F.Cu")
		(net "P5E_CPU1_P2_TX_C_DN<10>")
	)
	(segment
		(start 160.221676 -377.58243)
		(end 159.541972 -378.262388)
		(width 0.1016)
		(layer "F.Cu")
		(net "P5E_CPU1_P2_TX_C_DN<10>")
	)
	(segment
		(start 159.541972 -378.262388)
		(end 159.541972 -378.420122)
		(width 0.1016)
		(layer "F.Cu")
		(net "P5E_CPU1_P2_TX_C_DN<10>")
	)
	(segment
		(start 162.251644 -375.76633)
		(end 161.901378 -376.116596)
		(width 0.1016)
		(layer "F.Cu")
		(net "P5E_CPU1_P2_TX_C_DN<10>")
	)
	(segment
		(start 159.168338 -378.635768)
		(end 158.989522 -378.814584)
		(width 0.1016)
		(layer "F.Cu")
		(net "P5E_CPU1_P2_TX_C_DN<10>")
	)
	(segment
		(start 161.901378 -376.116596)
		(end 161.901378 -376.202702)
		(width 0.1016)
		(layer "F.Cu")
		(net "P5E_CPU1_P2_TX_C_DN<10>")
	)
	(arc
		(start 160.819338 -377.427236)
		(mid 160.696698 -377.508932)
		(end 160.55213 -377.537472)
		(width 0.1016)
		(layer "F.Cu")
		(net "P5E_CPU1_P2_TX_C_DN<10>")
	)
	(arc
		(start 158.989522 -378.814584)
		(mid 158.961879 -378.855954)
		(end 158.952184 -378.904754)
		(width 0.1016)
		(layer "F.Cu")
		(net "P5E_CPU1_P2_TX_C_DN<10>")
	)
	(arc
		(start 160.32988 -377.537472)
		(mid 160.271296 -377.549161)
		(end 160.221676 -377.58243)
		(width 0.1016)
		(layer "F.Cu")
		(net "P5E_CPU1_P2_TX_C_DN<10>")
	)
	(arc
		(start 161.901378 -376.202702)
		(mid 161.875419 -376.33424)
		(end 161.801048 -376.44578)
		(width 0.1016)
		(layer "F.Cu")
		(net "P5E_CPU1_P2_TX_C_DN<10>")
	)
	(segment
		(start 146.952208 -383.13741)
		(end 147.04568 -383.230882)
		(width 0.1016)
		(layer "F.Cu")
		(net "P5E_CPU1_P2_TX_C_DN<0>")
	)
	(segment
		(start 145.660618 -381.883158)
		(end 146.265646 -382.133094)
		(width 0.1016)
		(layer "F.Cu")
		(net "P5E_CPU1_P2_TX_C_DN<0>")
	)
	(segment
		(start 142.861792 -381.48006)
		(end 143.209264 -381.827532)
		(width 0.1016)
		(layer "F.Cu")
		(net "P5E_CPU1_P2_TX_C_DN<0>")
	)
	(segment
		(start 146.952208 -382.727708)
		(end 146.952208 -383.13741)
		(width 0.1016)
		(layer "F.Cu")
		(net "P5E_CPU1_P2_TX_C_DN<0>")
	)
	(segment
		(start 146.548094 -382.32207)
		(end 146.952208 -382.727708)
		(width 0.1016)
		(layer "F.Cu")
		(net "P5E_CPU1_P2_TX_C_DN<0>")
	)
	(segment
		(start 143.209264 -381.827532)
		(end 145.380456 -381.827532)
		(width 0.1016)
		(layer "F.Cu")
		(net "P5E_CPU1_P2_TX_C_DN<0>")
	)
	(segment
		(start 147.04568 -383.230882)
		(end 147.04568 -383.92227)
		(width 0.1016)
		(layer "F.Cu")
		(net "P5E_CPU1_P2_TX_C_DN<0>")
	)
	(arc
		(start 146.265646 -382.133094)
		(mid 146.416278 -382.213523)
		(end 146.548094 -382.32207)
		(width 0.1016)
		(layer "F.Cu")
		(net "P5E_CPU1_P2_TX_C_DN<0>")
	)
	(arc
		(start 145.380456 -381.827532)
		(mid 145.523275 -381.841564)
		(end 145.660618 -381.883158)
		(width 0.1016)
		(layer "F.Cu")
		(net "P5E_CPU1_P2_TX_C_DN<0>")
	)
	(segment
		(start 92.861384 -373.933466)
		(end 92.861384 -374.994932)
		(width 0.1016)
		(layer "F.Cu")
		(net "P5E_CPU1_P1_TX_C_DP<9>")
	)
	(segment
		(start 90.445844 -383.520442)
		(end 90.445844 -383.402586)
		(width 0.1016)
		(layer "F.Cu")
		(net "P5E_CPU1_P1_TX_C_DP<9>")
	)
	(segment
		(start 90.143838 -383.50571)
		(end 90.235024 -383.596896)
		(width 0.1016)
		(layer "F.Cu")
		(net "P5E_CPU1_P1_TX_C_DP<9>")
	)
	(segment
		(start 92.79001 -375.166382)
		(end 90.58021 -377.376182)
		(width 0.1016)
		(layer "F.Cu")
		(net "P5E_CPU1_P1_TX_C_DP<9>")
	)
	(segment
		(start 90.143838 -383.2352)
		(end 90.143838 -383.50571)
		(width 0.1016)
		(layer "F.Cu")
		(net "P5E_CPU1_P1_TX_C_DP<9>")
	)
	(segment
		(start 91.49842 -372.28907)
		(end 92.661486 -373.452136)
		(width 0.1016)
		(layer "F.Cu")
		(net "P5E_CPU1_P1_TX_C_DP<9>")
	)
	(segment
		(start 90.833702 -370.83873)
		(end 91.182952 -371.18798)
		(width 0.1016)
		(layer "F.Cu")
		(net "P5E_CPU1_P1_TX_C_DP<9>")
	)
	(segment
		(start 91.182952 -371.18798)
		(end 91.182952 -371.527578)
		(width 0.1016)
		(layer "F.Cu")
		(net "P5E_CPU1_P1_TX_C_DP<9>")
	)
	(segment
		(start 90.36939 -383.596896)
		(end 90.445844 -383.520442)
		(width 0.1016)
		(layer "F.Cu")
		(net "P5E_CPU1_P1_TX_C_DP<9>")
	)
	(segment
		(start 90.235024 -383.596896)
		(end 90.36939 -383.596896)
		(width 0.1016)
		(layer "F.Cu")
		(net "P5E_CPU1_P1_TX_C_DP<9>")
	)
	(segment
		(start 90.436446 -377.723908)
		(end 90.436446 -382.942592)
		(width 0.1016)
		(layer "F.Cu")
		(net "P5E_CPU1_P1_TX_C_DP<9>")
	)
	(segment
		(start 90.436446 -382.942592)
		(end 90.143838 -383.2352)
		(width 0.1016)
		(layer "F.Cu")
		(net "P5E_CPU1_P1_TX_C_DP<9>")
	)
	(arc
		(start 91.182952 -371.527578)
		(mid 91.264984 -371.939688)
		(end 91.49842 -372.28907)
		(width 0.1016)
		(layer "F.Cu")
		(net "P5E_CPU1_P1_TX_C_DP<9>")
	)
	(arc
		(start 92.861384 -374.994932)
		(mid 92.842719 -375.087735)
		(end 92.79001 -375.166382)
		(width 0.1016)
		(layer "F.Cu")
		(net "P5E_CPU1_P1_TX_C_DP<9>")
	)
	(arc
		(start 92.661486 -373.452136)
		(mid 92.809347 -373.672913)
		(end 92.861384 -373.933466)
		(width 0.1016)
		(layer "F.Cu")
		(net "P5E_CPU1_P1_TX_C_DP<9>")
	)
	(arc
		(start 90.58021 -377.376182)
		(mid 90.473776 -377.53575)
		(end 90.436446 -377.723908)
		(width 0.1016)
		(layer "F.Cu")
		(net "P5E_CPU1_P1_TX_C_DP<9>")
	)
	(segment
		(start 88.943688 -383.2352)
		(end 88.943688 -383.50571)
		(width 0.1016)
		(layer "F.Cu")
		(net "P5E_CPU1_P1_TX_C_DP<8>")
	)
	(segment
		(start 89.245694 -383.520442)
		(end 89.245694 -383.402586)
		(width 0.1016)
		(layer "F.Cu")
		(net "P5E_CPU1_P1_TX_C_DP<8>")
	)
	(segment
		(start 89.034874 -383.596896)
		(end 89.16924 -383.596896)
		(width 0.1016)
		(layer "F.Cu")
		(net "P5E_CPU1_P1_TX_C_DP<8>")
	)
	(segment
		(start 89.131902 -373.30253)
		(end 89.433654 -373.604282)
		(width 0.1016)
		(layer "F.Cu")
		(net "P5E_CPU1_P1_TX_C_DP<8>")
	)
	(segment
		(start 89.16924 -383.596896)
		(end 89.245694 -383.520442)
		(width 0.1016)
		(layer "F.Cu")
		(net "P5E_CPU1_P1_TX_C_DP<8>")
	)
	(segment
		(start 89.236296 -382.942592)
		(end 88.943688 -383.2352)
		(width 0.1016)
		(layer "F.Cu")
		(net "P5E_CPU1_P1_TX_C_DP<8>")
	)
	(segment
		(start 89.481152 -373.71909)
		(end 89.481152 -376.61723)
		(width 0.1016)
		(layer "F.Cu")
		(net "P5E_CPU1_P1_TX_C_DP<8>")
	)
	(segment
		(start 88.943688 -383.50571)
		(end 89.034874 -383.596896)
		(width 0.1016)
		(layer "F.Cu")
		(net "P5E_CPU1_P1_TX_C_DP<8>")
	)
	(segment
		(start 89.236296 -377.31827)
		(end 89.236296 -382.942592)
		(width 0.1016)
		(layer "F.Cu")
		(net "P5E_CPU1_P1_TX_C_DP<8>")
	)
	(arc
		(start 89.293954 -377.043696)
		(mid 89.2508 -377.177976)
		(end 89.236296 -377.31827)
		(width 0.1016)
		(layer "F.Cu")
		(net "P5E_CPU1_P1_TX_C_DP<8>")
	)
	(arc
		(start 89.433654 -373.604282)
		(mid 89.468796 -373.656971)
		(end 89.481152 -373.71909)
		(width 0.1016)
		(layer "F.Cu")
		(net "P5E_CPU1_P1_TX_C_DP<8>")
	)
	(arc
		(start 89.387172 -376.888502)
		(mid 89.335676 -376.963163)
		(end 89.293954 -377.043696)
		(width 0.1016)
		(layer "F.Cu")
		(net "P5E_CPU1_P1_TX_C_DP<8>")
	)
	(arc
		(start 89.481152 -376.61723)
		(mid 89.456936 -376.76075)
		(end 89.387172 -376.888502)
		(width 0.1016)
		(layer "F.Cu")
		(net "P5E_CPU1_P1_TX_C_DP<8>")
	)
	(segment
		(start 88.045798 -383.520442)
		(end 88.045798 -383.402586)
		(width 0.1016)
		(layer "F.Cu")
		(net "P5E_CPU1_P1_TX_C_DP<7>")
	)
	(segment
		(start 88.0364 -382.942592)
		(end 87.743792 -383.2352)
		(width 0.1016)
		(layer "F.Cu")
		(net "P5E_CPU1_P1_TX_C_DP<7>")
	)
	(segment
		(start 87.779352 -376.18289)
		(end 87.779352 -377.907804)
		(width 0.1016)
		(layer "F.Cu")
		(net "P5E_CPU1_P1_TX_C_DP<7>")
	)
	(segment
		(start 87.969344 -383.596896)
		(end 88.045798 -383.520442)
		(width 0.1016)
		(layer "F.Cu")
		(net "P5E_CPU1_P1_TX_C_DP<7>")
	)
	(segment
		(start 87.743792 -383.2352)
		(end 87.743792 -383.50571)
		(width 0.1016)
		(layer "F.Cu")
		(net "P5E_CPU1_P1_TX_C_DP<7>")
	)
	(segment
		(start 87.743792 -383.50571)
		(end 87.834978 -383.596896)
		(width 0.1016)
		(layer "F.Cu")
		(net "P5E_CPU1_P1_TX_C_DP<7>")
	)
	(segment
		(start 88.01862 -378.664216)
		(end 88.0364 -382.942592)
		(width 0.1016)
		(layer "F.Cu")
		(net "P5E_CPU1_P1_TX_C_DP<7>")
	)
	(segment
		(start 87.834978 -383.596896)
		(end 87.969344 -383.596896)
		(width 0.1016)
		(layer "F.Cu")
		(net "P5E_CPU1_P1_TX_C_DP<7>")
	)
	(segment
		(start 87.430102 -375.76633)
		(end 87.731854 -376.068082)
		(width 0.1016)
		(layer "F.Cu")
		(net "P5E_CPU1_P1_TX_C_DP<7>")
	)
	(arc
		(start 87.779352 -377.907804)
		(mid 87.82003 -378.171596)
		(end 87.938102 -378.410978)
		(width 0.1016)
		(layer "F.Cu")
		(net "P5E_CPU1_P1_TX_C_DP<7>")
	)
	(arc
		(start 87.938102 -378.410978)
		(mid 87.997664 -378.531463)
		(end 88.01862 -378.664216)
		(width 0.1016)
		(layer "F.Cu")
		(net "P5E_CPU1_P1_TX_C_DP<7>")
	)
	(arc
		(start 87.731854 -376.068082)
		(mid 87.766996 -376.120771)
		(end 87.779352 -376.18289)
		(width 0.1016)
		(layer "F.Cu")
		(net "P5E_CPU1_P1_TX_C_DP<7>")
	)
	(segment
		(start 86.83625 -381.694436)
		(end 86.83625 -382.942592)
		(width 0.1016)
		(layer "F.Cu")
		(net "P5E_CPU1_P1_TX_C_DP<6>")
	)
	(segment
		(start 86.237064 -378.733558)
		(end 86.27364 -378.823474)
		(width 0.1016)
		(layer "F.Cu")
		(net "P5E_CPU1_P1_TX_C_DP<6>")
	)
	(segment
		(start 86.634828 -383.596896)
		(end 86.769194 -383.596896)
		(width 0.1016)
		(layer "F.Cu")
		(net "P5E_CPU1_P1_TX_C_DP<6>")
	)
	(segment
		(start 84.375752 -371.18798)
		(end 84.375752 -371.48008)
		(width 0.1016)
		(layer "F.Cu")
		(net "P5E_CPU1_P1_TX_C_DP<6>")
	)
	(segment
		(start 84.702142 -372.267734)
		(end 85.93455 -373.500142)
		(width 0.1016)
		(layer "F.Cu")
		(net "P5E_CPU1_P1_TX_C_DP<6>")
	)
	(segment
		(start 86.543642 -383.2352)
		(end 86.543642 -383.50571)
		(width 0.1016)
		(layer "F.Cu")
		(net "P5E_CPU1_P1_TX_C_DP<6>")
	)
	(segment
		(start 86.83625 -382.942592)
		(end 86.543642 -383.2352)
		(width 0.1016)
		(layer "F.Cu")
		(net "P5E_CPU1_P1_TX_C_DP<6>")
	)
	(segment
		(start 86.095078 -373.886984)
		(end 86.095078 -378.006102)
		(width 0.1016)
		(layer "F.Cu")
		(net "P5E_CPU1_P1_TX_C_DP<6>")
	)
	(segment
		(start 86.543642 -383.50571)
		(end 86.634828 -383.596896)
		(width 0.1016)
		(layer "F.Cu")
		(net "P5E_CPU1_P1_TX_C_DP<6>")
	)
	(segment
		(start 86.845648 -383.520442)
		(end 86.845648 -383.402586)
		(width 0.1016)
		(layer "F.Cu")
		(net "P5E_CPU1_P1_TX_C_DP<6>")
	)
	(segment
		(start 86.769194 -383.596896)
		(end 86.845648 -383.520442)
		(width 0.1016)
		(layer "F.Cu")
		(net "P5E_CPU1_P1_TX_C_DP<6>")
	)
	(segment
		(start 84.026502 -370.83873)
		(end 84.375752 -371.18798)
		(width 0.1016)
		(layer "F.Cu")
		(net "P5E_CPU1_P1_TX_C_DP<6>")
	)
	(arc
		(start 86.095078 -378.006102)
		(mid 86.130883 -378.376698)
		(end 86.237064 -378.733558)
		(width 0.1016)
		(layer "F.Cu")
		(net "P5E_CPU1_P1_TX_C_DP<6>")
	)
	(arc
		(start 85.93455 -373.500142)
		(mid 86.053307 -373.677597)
		(end 86.095078 -373.886984)
		(width 0.1016)
		(layer "F.Cu")
		(net "P5E_CPU1_P1_TX_C_DP<6>")
	)
	(arc
		(start 86.27364 -378.823474)
		(mid 86.694209 -380.231663)
		(end 86.83625 -381.694436)
		(width 0.1016)
		(layer "F.Cu")
		(net "P5E_CPU1_P1_TX_C_DP<6>")
	)
	(arc
		(start 84.375752 -371.48008)
		(mid 84.460621 -371.906367)
		(end 84.702142 -372.267734)
		(width 0.1016)
		(layer "F.Cu")
		(net "P5E_CPU1_P1_TX_C_DP<6>")
	)
	(segment
		(start 85.636354 -381.651764)
		(end 85.636354 -382.942592)
		(width 0.1016)
		(layer "F.Cu")
		(net "P5E_CPU1_P1_TX_C_DP<5>")
	)
	(segment
		(start 82.324702 -373.30253)
		(end 82.673952 -373.65178)
		(width 0.1016)
		(layer "F.Cu")
		(net "P5E_CPU1_P1_TX_C_DP<5>")
	)
	(segment
		(start 85.636354 -382.942592)
		(end 85.343746 -383.2352)
		(width 0.1016)
		(layer "F.Cu")
		(net "P5E_CPU1_P1_TX_C_DP<5>")
	)
	(segment
		(start 82.673952 -373.65178)
		(end 82.673952 -375.362216)
		(width 0.1016)
		(layer "F.Cu")
		(net "P5E_CPU1_P1_TX_C_DP<5>")
	)
	(segment
		(start 83.037934 -376.561858)
		(end 84.967826 -379.448822)
		(width 0.1016)
		(layer "F.Cu")
		(net "P5E_CPU1_P1_TX_C_DP<5>")
	)
	(segment
		(start 85.434932 -383.596896)
		(end 85.569298 -383.596896)
		(width 0.1016)
		(layer "F.Cu")
		(net "P5E_CPU1_P1_TX_C_DP<5>")
	)
	(segment
		(start 85.569298 -383.596896)
		(end 85.645752 -383.520442)
		(width 0.1016)
		(layer "F.Cu")
		(net "P5E_CPU1_P1_TX_C_DP<5>")
	)
	(segment
		(start 85.645752 -383.520442)
		(end 85.645752 -383.402586)
		(width 0.1016)
		(layer "F.Cu")
		(net "P5E_CPU1_P1_TX_C_DP<5>")
	)
	(segment
		(start 85.343746 -383.2352)
		(end 85.343746 -383.50571)
		(width 0.1016)
		(layer "F.Cu")
		(net "P5E_CPU1_P1_TX_C_DP<5>")
	)
	(segment
		(start 85.343746 -383.50571)
		(end 85.434932 -383.596896)
		(width 0.1016)
		(layer "F.Cu")
		(net "P5E_CPU1_P1_TX_C_DP<5>")
	)
	(arc
		(start 84.967826 -379.448822)
		(mid 85.465532 -380.500692)
		(end 85.636354 -381.651764)
		(width 0.1016)
		(layer "F.Cu")
		(net "P5E_CPU1_P1_TX_C_DP<5>")
	)
	(arc
		(start 82.673952 -375.362216)
		(mid 82.766957 -375.989034)
		(end 83.037934 -376.561858)
		(width 0.1016)
		(layer "F.Cu")
		(net "P5E_CPU1_P1_TX_C_DP<5>")
	)
	(segment
		(start 84.235036 -383.596896)
		(end 84.369402 -383.596896)
		(width 0.1016)
		(layer "F.Cu")
		(net "P5E_CPU1_P1_TX_C_DP<4>")
	)
	(segment
		(start 84.445856 -383.520442)
		(end 84.445856 -383.402586)
		(width 0.1016)
		(layer "F.Cu")
		(net "P5E_CPU1_P1_TX_C_DP<4>")
	)
	(segment
		(start 84.369402 -383.596896)
		(end 84.445856 -383.520442)
		(width 0.1016)
		(layer "F.Cu")
		(net "P5E_CPU1_P1_TX_C_DP<4>")
	)
	(segment
		(start 84.436458 -381.572008)
		(end 84.436458 -382.942592)
		(width 0.1016)
		(layer "F.Cu")
		(net "P5E_CPU1_P1_TX_C_DP<4>")
	)
	(segment
		(start 80.972152 -376.11558)
		(end 80.972152 -376.33275)
		(width 0.1016)
		(layer "F.Cu")
		(net "P5E_CPU1_P1_TX_C_DP<4>")
	)
	(segment
		(start 84.14385 -383.2352)
		(end 84.14385 -383.50571)
		(width 0.1016)
		(layer "F.Cu")
		(net "P5E_CPU1_P1_TX_C_DP<4>")
	)
	(segment
		(start 81.2165 -376.921776)
		(end 84.10448 -380.440438)
		(width 0.1016)
		(layer "F.Cu")
		(net "P5E_CPU1_P1_TX_C_DP<4>")
	)
	(segment
		(start 80.972152 -376.33275)
		(end 81.2165 -376.921776)
		(width 0.1016)
		(layer "F.Cu")
		(net "P5E_CPU1_P1_TX_C_DP<4>")
	)
	(segment
		(start 80.622902 -375.76633)
		(end 80.972152 -376.11558)
		(width 0.1016)
		(layer "F.Cu")
		(net "P5E_CPU1_P1_TX_C_DP<4>")
	)
	(segment
		(start 84.436458 -382.942592)
		(end 84.14385 -383.2352)
		(width 0.1016)
		(layer "F.Cu")
		(net "P5E_CPU1_P1_TX_C_DP<4>")
	)
	(segment
		(start 84.14385 -383.50571)
		(end 84.235036 -383.596896)
		(width 0.1016)
		(layer "F.Cu")
		(net "P5E_CPU1_P1_TX_C_DP<4>")
	)
	(arc
		(start 84.10448 -380.440438)
		(mid 84.351609 -380.982422)
		(end 84.436458 -381.572008)
		(width 0.1016)
		(layer "F.Cu")
		(net "P5E_CPU1_P1_TX_C_DP<4>")
	)
	(segment
		(start 83.034886 -383.596896)
		(end 83.169252 -383.596896)
		(width 0.1016)
		(layer "F.Cu")
		(net "P5E_CPU1_P1_TX_C_DP<3>")
	)
	(segment
		(start 79.278226 -373.738902)
		(end 79.278226 -375.203466)
		(width 0.1016)
		(layer "F.Cu")
		(net "P5E_CPU1_P1_TX_C_DP<3>")
	)
	(segment
		(start 80.203802 -377.61164)
		(end 80.47482 -378.064014)
		(width 0.1016)
		(layer "F.Cu")
		(net "P5E_CPU1_P1_TX_C_DP<3>")
	)
	(segment
		(start 82.9437 -383.2352)
		(end 82.9437 -383.50571)
		(width 0.1016)
		(layer "F.Cu")
		(net "P5E_CPU1_P1_TX_C_DP<3>")
	)
	(segment
		(start 80.47482 -378.064014)
		(end 83.117944 -381.284734)
		(width 0.1016)
		(layer "F.Cu")
		(net "P5E_CPU1_P1_TX_C_DP<3>")
	)
	(segment
		(start 83.245706 -383.520442)
		(end 83.245706 -383.402586)
		(width 0.1016)
		(layer "F.Cu")
		(net "P5E_CPU1_P1_TX_C_DP<3>")
	)
	(segment
		(start 83.236308 -382.942592)
		(end 82.9437 -383.2352)
		(width 0.1016)
		(layer "F.Cu")
		(net "P5E_CPU1_P1_TX_C_DP<3>")
	)
	(segment
		(start 79.343758 -375.534682)
		(end 80.203802 -377.61164)
		(width 0.1016)
		(layer "F.Cu")
		(net "P5E_CPU1_P1_TX_C_DP<3>")
	)
	(segment
		(start 77.219302 -370.83873)
		(end 77.568552 -371.18798)
		(width 0.1016)
		(layer "F.Cu")
		(net "P5E_CPU1_P1_TX_C_DP<3>")
	)
	(segment
		(start 77.816202 -372.170198)
		(end 78.940914 -373.294656)
		(width 0.1016)
		(layer "F.Cu")
		(net "P5E_CPU1_P1_TX_C_DP<3>")
	)
	(segment
		(start 78.940914 -373.294656)
		(end 78.940914 -373.29491)
		(width 0.1016)
		(layer "F.Cu")
		(net "P5E_CPU1_P1_TX_C_DP<3>")
	)
	(segment
		(start 78.940914 -373.29491)
		(end 79.202026 -373.556022)
		(width 0.1016)
		(layer "F.Cu")
		(net "P5E_CPU1_P1_TX_C_DP<3>")
	)
	(segment
		(start 82.9437 -383.50571)
		(end 83.034886 -383.596896)
		(width 0.1016)
		(layer "F.Cu")
		(net "P5E_CPU1_P1_TX_C_DP<3>")
	)
	(segment
		(start 77.568552 -371.18798)
		(end 77.568552 -371.57152)
		(width 0.1016)
		(layer "F.Cu")
		(net "P5E_CPU1_P1_TX_C_DP<3>")
	)
	(segment
		(start 83.236308 -381.61468)
		(end 83.236308 -382.942592)
		(width 0.1016)
		(layer "F.Cu")
		(net "P5E_CPU1_P1_TX_C_DP<3>")
	)
	(segment
		(start 83.169252 -383.596896)
		(end 83.245706 -383.520442)
		(width 0.1016)
		(layer "F.Cu")
		(net "P5E_CPU1_P1_TX_C_DP<3>")
	)
	(arc
		(start 83.117944 -381.284734)
		(mid 83.205801 -381.439418)
		(end 83.236308 -381.61468)
		(width 0.1016)
		(layer "F.Cu")
		(net "P5E_CPU1_P1_TX_C_DP<3>")
	)
	(arc
		(start 77.568552 -371.57152)
		(mid 77.632809 -371.895503)
		(end 77.816202 -372.170198)
		(width 0.1016)
		(layer "F.Cu")
		(net "P5E_CPU1_P1_TX_C_DP<3>")
	)
	(arc
		(start 79.202026 -373.556022)
		(mid 79.258364 -373.639869)
		(end 79.278226 -373.738902)
		(width 0.1016)
		(layer "F.Cu")
		(net "P5E_CPU1_P1_TX_C_DP<3>")
	)
	(arc
		(start 79.278226 -375.203466)
		(mid 79.294694 -375.372298)
		(end 79.343758 -375.534682)
		(width 0.1016)
		(layer "F.Cu")
		(net "P5E_CPU1_P1_TX_C_DP<3>")
	)
	(segment
		(start 81.743804 -383.2352)
		(end 81.743804 -383.50571)
		(width 0.1016)
		(layer "F.Cu")
		(net "P5E_CPU1_P1_TX_C_DP<2>")
	)
	(segment
		(start 82.04581 -383.520442)
		(end 82.04581 -383.402586)
		(width 0.1016)
		(layer "F.Cu")
		(net "P5E_CPU1_P1_TX_C_DP<2>")
	)
	(segment
		(start 75.866752 -373.65178)
		(end 75.866752 -374.282208)
		(width 0.1016)
		(layer "F.Cu")
		(net "P5E_CPU1_P1_TX_C_DP<2>")
	)
	(segment
		(start 82.036412 -382.22047)
		(end 82.036412 -382.942592)
		(width 0.1016)
		(layer "F.Cu")
		(net "P5E_CPU1_P1_TX_C_DP<2>")
	)
	(segment
		(start 78.516734 -376.682508)
		(end 79.238602 -378.425456)
		(width 0.1016)
		(layer "F.Cu")
		(net "P5E_CPU1_P1_TX_C_DP<2>")
	)
	(segment
		(start 76.124562 -374.904762)
		(end 76.172568 -374.952768)
		(width 0.1016)
		(layer "F.Cu")
		(net "P5E_CPU1_P1_TX_C_DP<2>")
	)
	(segment
		(start 81.969356 -383.596896)
		(end 82.04581 -383.520442)
		(width 0.1016)
		(layer "F.Cu")
		(net "P5E_CPU1_P1_TX_C_DP<2>")
	)
	(segment
		(start 79.658972 -379.057154)
		(end 81.865216 -381.742696)
		(width 0.1016)
		(layer "F.Cu")
		(net "P5E_CPU1_P1_TX_C_DP<2>")
	)
	(segment
		(start 82.036412 -382.942592)
		(end 81.743804 -383.2352)
		(width 0.1016)
		(layer "F.Cu")
		(net "P5E_CPU1_P1_TX_C_DP<2>")
	)
	(segment
		(start 81.743804 -383.50571)
		(end 81.83499 -383.596896)
		(width 0.1016)
		(layer "F.Cu")
		(net "P5E_CPU1_P1_TX_C_DP<2>")
	)
	(segment
		(start 75.517502 -373.30253)
		(end 75.866752 -373.65178)
		(width 0.1016)
		(layer "F.Cu")
		(net "P5E_CPU1_P1_TX_C_DP<2>")
	)
	(segment
		(start 79.238602 -378.425456)
		(end 79.381096 -378.662692)
		(width 0.1016)
		(layer "F.Cu")
		(net "P5E_CPU1_P1_TX_C_DP<2>")
	)
	(segment
		(start 77.559662 -375.647458)
		(end 78.359254 -376.44705)
		(width 0.1016)
		(layer "F.Cu")
		(net "P5E_CPU1_P1_TX_C_DP<2>")
	)
	(segment
		(start 81.83499 -383.596896)
		(end 81.969356 -383.596896)
		(width 0.1016)
		(layer "F.Cu")
		(net "P5E_CPU1_P1_TX_C_DP<2>")
	)
	(segment
		(start 76.593446 -375.2342)
		(end 77.508354 -375.613168)
		(width 0.1016)
		(layer "F.Cu")
		(net "P5E_CPU1_P1_TX_C_DP<2>")
	)
	(arc
		(start 78.359254 -376.44705)
		(mid 78.449616 -376.557008)
		(end 78.516734 -376.682508)
		(width 0.1016)
		(layer "F.Cu")
		(net "P5E_CPU1_P1_TX_C_DP<2>")
	)
	(arc
		(start 75.866752 -374.282208)
		(mid 75.933751 -374.619123)
		(end 76.124562 -374.904762)
		(width 0.1016)
		(layer "F.Cu")
		(net "P5E_CPU1_P1_TX_C_DP<2>")
	)
	(arc
		(start 77.508354 -375.613168)
		(mid 77.535702 -375.627779)
		(end 77.559662 -375.647458)
		(width 0.1016)
		(layer "F.Cu")
		(net "P5E_CPU1_P1_TX_C_DP<2>")
	)
	(arc
		(start 81.865216 -381.742696)
		(mid 81.992268 -381.966722)
		(end 82.036412 -382.22047)
		(width 0.1016)
		(layer "F.Cu")
		(net "P5E_CPU1_P1_TX_C_DP<2>")
	)
	(arc
		(start 79.381096 -378.662692)
		(mid 79.512788 -378.865028)
		(end 79.658972 -379.057154)
		(width 0.1016)
		(layer "F.Cu")
		(net "P5E_CPU1_P1_TX_C_DP<2>")
	)
	(arc
		(start 76.172568 -374.952768)
		(mid 76.369152 -375.114205)
		(end 76.593446 -375.2342)
		(width 0.1016)
		(layer "F.Cu")
		(net "P5E_CPU1_P1_TX_C_DP<2>")
	)
	(segment
		(start 78.618334 -379.354588)
		(end 78.911958 -379.794008)
		(width 0.1016)
		(layer "F.Cu")
		(net "P5E_CPU1_P1_TX_C_DP<1>")
	)
	(segment
		(start 80.928972 -382.21412)
		(end 81.052162 -382.511808)
		(width 0.1016)
		(layer "F.Cu")
		(net "P5E_CPU1_P1_TX_C_DP<1>")
	)
	(segment
		(start 78.911958 -379.794008)
		(end 78.911958 -379.794262)
		(width 0.1016)
		(layer "F.Cu")
		(net "P5E_CPU1_P1_TX_C_DP<1>")
	)
	(segment
		(start 79.146654 -380.111254)
		(end 79.75727 -380.722124)
		(width 0.1016)
		(layer "F.Cu")
		(net "P5E_CPU1_P1_TX_C_DP<1>")
	)
	(segment
		(start 77.6732 -377.216416)
		(end 78.460854 -379.118876)
		(width 0.1016)
		(layer "F.Cu")
		(net "P5E_CPU1_P1_TX_C_DP<1>")
	)
	(segment
		(start 79.75727 -380.722124)
		(end 80.78597 -381.976122)
		(width 0.1016)
		(layer "F.Cu")
		(net "P5E_CPU1_P1_TX_C_DP<1>")
	)
	(segment
		(start 78.61808 -379.354588)
		(end 78.618334 -379.354588)
		(width 0.1016)
		(layer "F.Cu")
		(net "P5E_CPU1_P1_TX_C_DP<1>")
	)
	(segment
		(start 81.145634 -383.230882)
		(end 81.145634 -383.92227)
		(width 0.1016)
		(layer "F.Cu")
		(net "P5E_CPU1_P1_TX_C_DP<1>")
	)
	(segment
		(start 80.78597 -381.976122)
		(end 80.928972 -382.21412)
		(width 0.1016)
		(layer "F.Cu")
		(net "P5E_CPU1_P1_TX_C_DP<1>")
	)
	(segment
		(start 76.089256 -376.270266)
		(end 76.217018 -376.270266)
		(width 0.1016)
		(layer "F.Cu")
		(net "P5E_CPU1_P1_TX_C_DP<1>")
	)
	(segment
		(start 77.206856 -376.679968)
		(end 77.532992 -377.006104)
		(width 0.1016)
		(layer "F.Cu")
		(net "P5E_CPU1_P1_TX_C_DP<1>")
	)
	(segment
		(start 81.052162 -383.13741)
		(end 81.145634 -383.230882)
		(width 0.1016)
		(layer "F.Cu")
		(net "P5E_CPU1_P1_TX_C_DP<1>")
	)
	(segment
		(start 78.911958 -379.794262)
		(end 79.02575 -379.964442)
		(width 0.1016)
		(layer "F.Cu")
		(net "P5E_CPU1_P1_TX_C_DP<1>")
	)
	(segment
		(start 78.460854 -379.118876)
		(end 78.61808 -379.354588)
		(width 0.1016)
		(layer "F.Cu")
		(net "P5E_CPU1_P1_TX_C_DP<1>")
	)
	(segment
		(start 75.76185 -375.94286)
		(end 76.089256 -376.270266)
		(width 0.1016)
		(layer "F.Cu")
		(net "P5E_CPU1_P1_TX_C_DP<1>")
	)
	(segment
		(start 81.052162 -382.511808)
		(end 81.052162 -383.13741)
		(width 0.1016)
		(layer "F.Cu")
		(net "P5E_CPU1_P1_TX_C_DP<1>")
	)
	(arc
		(start 76.217018 -376.270266)
		(mid 76.752706 -376.376634)
		(end 77.206856 -376.679968)
		(width 0.1016)
		(layer "F.Cu")
		(net "P5E_CPU1_P1_TX_C_DP<1>")
	)
	(arc
		(start 77.532992 -377.006104)
		(mid 77.613464 -377.104348)
		(end 77.6732 -377.216416)
		(width 0.1016)
		(layer "F.Cu")
		(net "P5E_CPU1_P1_TX_C_DP<1>")
	)
	(arc
		(start 79.02575 -379.964442)
		(mid 79.082596 -380.040818)
		(end 79.146654 -380.111254)
		(width 0.1016)
		(layer "F.Cu")
		(net "P5E_CPU1_P1_TX_C_DP<1>")
	)
	(segment
		(start 97.73031 -383.110232)
		(end 97.73031 -383.318004)
		(width 0.1016)
		(layer "F.Cu")
		(net "P5E_CPU1_P1_TX_C_DP<15>")
	)
	(segment
		(start 97.73031 -383.318004)
		(end 97.645728 -383.402586)
		(width 0.1016)
		(layer "F.Cu")
		(net "P5E_CPU1_P1_TX_C_DP<15>")
	)
	(segment
		(start 102.002082 -379.471428)
		(end 101.652832 -379.820678)
		(width 0.1016)
		(layer "F.Cu")
		(net "P5E_CPU1_P1_TX_C_DP<15>")
	)
	(segment
		(start 101.19106 -379.820678)
		(end 101.0793 -379.708918)
		(width 0.1016)
		(layer "F.Cu")
		(net "P5E_CPU1_P1_TX_C_DP<15>")
	)
	(segment
		(start 97.63633 -382.205484)
		(end 97.63633 -383.016252)
		(width 0.1016)
		(layer "F.Cu")
		(net "P5E_CPU1_P1_TX_C_DP<15>")
	)
	(segment
		(start 101.0793 -379.708918)
		(end 100.7745 -379.708918)
		(width 0.1016)
		(layer "F.Cu")
		(net "P5E_CPU1_P1_TX_C_DP<15>")
	)
	(segment
		(start 97.63633 -383.016252)
		(end 97.73031 -383.110232)
		(width 0.1016)
		(layer "F.Cu")
		(net "P5E_CPU1_P1_TX_C_DP<15>")
	)
	(segment
		(start 100.7745 -379.708918)
		(end 100.66274 -379.820678)
		(width 0.1016)
		(layer "F.Cu")
		(net "P5E_CPU1_P1_TX_C_DP<15>")
	)
	(segment
		(start 101.652832 -379.820678)
		(end 101.19106 -379.820678)
		(width 0.1016)
		(layer "F.Cu")
		(net "P5E_CPU1_P1_TX_C_DP<15>")
	)
	(segment
		(start 99.693984 -379.92558)
		(end 97.793048 -381.826516)
		(width 0.1016)
		(layer "F.Cu")
		(net "P5E_CPU1_P1_TX_C_DP<15>")
	)
	(segment
		(start 100.66274 -379.820678)
		(end 99.947984 -379.820678)
		(width 0.1016)
		(layer "F.Cu")
		(net "P5E_CPU1_P1_TX_C_DP<15>")
	)
	(arc
		(start 97.793048 -381.826516)
		(mid 97.676983 -382.000404)
		(end 97.63633 -382.205484)
		(width 0.1016)
		(layer "F.Cu")
		(net "P5E_CPU1_P1_TX_C_DP<15>")
	)
	(arc
		(start 99.947984 -379.820678)
		(mid 99.810531 -379.847832)
		(end 99.693984 -379.92558)
		(width 0.1016)
		(layer "F.Cu")
		(net "P5E_CPU1_P1_TX_C_DP<15>")
	)
	(segment
		(start 96.652588 -381.689102)
		(end 96.652334 -381.688848)
		(width 0.1016)
		(layer "F.Cu")
		(net "P5E_CPU1_P1_TX_C_DP<14>")
	)
	(segment
		(start 101.796596 -376.776742)
		(end 101.656896 -376.71883)
		(width 0.1016)
		(layer "F.Cu")
		(net "P5E_CPU1_P1_TX_C_DP<14>")
	)
	(segment
		(start 96.652334 -381.688848)
		(end 96.652334 -382.92659)
		(width 0.1016)
		(layer "F.Cu")
		(net "P5E_CPU1_P1_TX_C_DP<14>")
	)
	(segment
		(start 101.656896 -376.71883)
		(end 101.342444 -376.71883)
		(width 0.1016)
		(layer "F.Cu")
		(net "P5E_CPU1_P1_TX_C_DP<14>")
	)
	(segment
		(start 101.342444 -376.71883)
		(end 96.8502 -381.211074)
		(width 0.1016)
		(layer "F.Cu")
		(net "P5E_CPU1_P1_TX_C_DP<14>")
	)
	(segment
		(start 96.746314 -383.02057)
		(end 96.746314 -383.921762)
		(width 0.1016)
		(layer "F.Cu")
		(net "P5E_CPU1_P1_TX_C_DP<14>")
	)
	(segment
		(start 102.002082 -376.982228)
		(end 101.796596 -376.776742)
		(width 0.1016)
		(layer "F.Cu")
		(net "P5E_CPU1_P1_TX_C_DP<14>")
	)
	(segment
		(start 96.652334 -382.92659)
		(end 96.746314 -383.02057)
		(width 0.1016)
		(layer "F.Cu")
		(net "P5E_CPU1_P1_TX_C_DP<14>")
	)
	(segment
		(start 96.746314 -383.921762)
		(end 96.745806 -383.92227)
		(width 0.1016)
		(layer "F.Cu")
		(net "P5E_CPU1_P1_TX_C_DP<14>")
	)
	(arc
		(start 96.8502 -381.211074)
		(mid 96.703874 -381.430439)
		(end 96.652588 -381.689102)
		(width 0.1016)
		(layer "F.Cu")
		(net "P5E_CPU1_P1_TX_C_DP<14>")
	)
	(segment
		(start 95.236284 -382.942592)
		(end 94.943676 -383.2352)
		(width 0.1016)
		(layer "F.Cu")
		(net "P5E_CPU1_P1_TX_C_DP<13>")
	)
	(segment
		(start 101.393752 -371.18798)
		(end 101.393752 -371.527578)
		(width 0.1016)
		(layer "F.Cu")
		(net "P5E_CPU1_P1_TX_C_DP<13>")
	)
	(segment
		(start 95.169228 -383.596896)
		(end 95.245682 -383.520442)
		(width 0.1016)
		(layer "F.Cu")
		(net "P5E_CPU1_P1_TX_C_DP<13>")
	)
	(segment
		(start 101.044502 -370.83873)
		(end 101.393752 -371.18798)
		(width 0.1016)
		(layer "F.Cu")
		(net "P5E_CPU1_P1_TX_C_DP<13>")
	)
	(segment
		(start 100.733352 -375.333006)
		(end 95.336614 -380.729744)
		(width 0.1016)
		(layer "F.Cu")
		(net "P5E_CPU1_P1_TX_C_DP<13>")
	)
	(segment
		(start 95.245682 -383.520442)
		(end 95.245682 -383.402586)
		(width 0.1016)
		(layer "F.Cu")
		(net "P5E_CPU1_P1_TX_C_DP<13>")
	)
	(segment
		(start 102.184708 -375.09704)
		(end 101.303836 -375.09704)
		(width 0.1016)
		(layer "F.Cu")
		(net "P5E_CPU1_P1_TX_C_DP<13>")
	)
	(segment
		(start 94.943676 -383.2352)
		(end 94.943676 -383.50571)
		(width 0.1016)
		(layer "F.Cu")
		(net "P5E_CPU1_P1_TX_C_DP<13>")
	)
	(segment
		(start 94.943676 -383.50571)
		(end 95.034862 -383.596896)
		(width 0.1016)
		(layer "F.Cu")
		(net "P5E_CPU1_P1_TX_C_DP<13>")
	)
	(segment
		(start 101.708712 -372.288816)
		(end 102.913434 -373.493538)
		(width 0.1016)
		(layer "F.Cu")
		(net "P5E_CPU1_P1_TX_C_DP<13>")
	)
	(segment
		(start 103.067866 -373.866156)
		(end 103.067866 -374.136666)
		(width 0.1016)
		(layer "F.Cu")
		(net "P5E_CPU1_P1_TX_C_DP<13>")
	)
	(segment
		(start 102.895146 -374.55348)
		(end 102.469696 -374.97893)
		(width 0.1016)
		(layer "F.Cu")
		(net "P5E_CPU1_P1_TX_C_DP<13>")
	)
	(segment
		(start 95.034862 -383.596896)
		(end 95.169228 -383.596896)
		(width 0.1016)
		(layer "F.Cu")
		(net "P5E_CPU1_P1_TX_C_DP<13>")
	)
	(segment
		(start 95.236284 -380.972822)
		(end 95.236284 -382.942592)
		(width 0.1016)
		(layer "F.Cu")
		(net "P5E_CPU1_P1_TX_C_DP<13>")
	)
	(arc
		(start 103.067866 -374.136666)
		(mid 103.022975 -374.362257)
		(end 102.895146 -374.55348)
		(width 0.1016)
		(layer "F.Cu")
		(net "P5E_CPU1_P1_TX_C_DP<13>")
	)
	(arc
		(start 95.336614 -380.729744)
		(mid 95.262315 -380.841313)
		(end 95.236284 -380.972822)
		(width 0.1016)
		(layer "F.Cu")
		(net "P5E_CPU1_P1_TX_C_DP<13>")
	)
	(arc
		(start 101.393752 -371.527578)
		(mid 101.475492 -371.939543)
		(end 101.708712 -372.288816)
		(width 0.1016)
		(layer "F.Cu")
		(net "P5E_CPU1_P1_TX_C_DP<13>")
	)
	(arc
		(start 102.469696 -374.97893)
		(mid 102.338957 -375.06635)
		(end 102.184708 -375.09704)
		(width 0.1016)
		(layer "F.Cu")
		(net "P5E_CPU1_P1_TX_C_DP<13>")
	)
	(arc
		(start 101.303836 -375.09704)
		(mid 100.995099 -375.158246)
		(end 100.733352 -375.333006)
		(width 0.1016)
		(layer "F.Cu")
		(net "P5E_CPU1_P1_TX_C_DP<13>")
	)
	(arc
		(start 102.913434 -373.493538)
		(mid 103.027719 -373.664482)
		(end 103.067866 -373.866156)
		(width 0.1016)
		(layer "F.Cu")
		(net "P5E_CPU1_P1_TX_C_DP<13>")
	)
	(segment
		(start 94.036388 -380.734062)
		(end 94.036388 -382.942592)
		(width 0.1016)
		(layer "F.Cu")
		(net "P5E_CPU1_P1_TX_C_DP<12>")
	)
	(segment
		(start 93.74378 -383.2352)
		(end 93.74378 -383.50571)
		(width 0.1016)
		(layer "F.Cu")
		(net "P5E_CPU1_P1_TX_C_DP<12>")
	)
	(segment
		(start 97.640902 -370.83873)
		(end 97.990152 -371.18798)
		(width 0.1016)
		(layer "F.Cu")
		(net "P5E_CPU1_P1_TX_C_DP<12>")
	)
	(segment
		(start 93.969332 -383.596896)
		(end 94.045786 -383.520442)
		(width 0.1016)
		(layer "F.Cu")
		(net "P5E_CPU1_P1_TX_C_DP<12>")
	)
	(segment
		(start 98.242374 -372.147338)
		(end 99.662488 -373.567198)
		(width 0.1016)
		(layer "F.Cu")
		(net "P5E_CPU1_P1_TX_C_DP<12>")
	)
	(segment
		(start 93.834966 -383.596896)
		(end 93.969332 -383.596896)
		(width 0.1016)
		(layer "F.Cu")
		(net "P5E_CPU1_P1_TX_C_DP<12>")
	)
	(segment
		(start 93.74378 -383.50571)
		(end 93.834966 -383.596896)
		(width 0.1016)
		(layer "F.Cu")
		(net "P5E_CPU1_P1_TX_C_DP<12>")
	)
	(segment
		(start 99.699826 -373.657368)
		(end 99.699826 -374.562878)
		(width 0.1016)
		(layer "F.Cu")
		(net "P5E_CPU1_P1_TX_C_DP<12>")
	)
	(segment
		(start 97.990152 -371.18798)
		(end 97.990152 -371.5385)
		(width 0.1016)
		(layer "F.Cu")
		(net "P5E_CPU1_P1_TX_C_DP<12>")
	)
	(segment
		(start 94.036388 -382.942592)
		(end 93.74378 -383.2352)
		(width 0.1016)
		(layer "F.Cu")
		(net "P5E_CPU1_P1_TX_C_DP<12>")
	)
	(segment
		(start 99.627182 -374.737376)
		(end 94.323408 -380.04115)
		(width 0.1016)
		(layer "F.Cu")
		(net "P5E_CPU1_P1_TX_C_DP<12>")
	)
	(segment
		(start 94.045786 -383.520442)
		(end 94.045786 -383.402586)
		(width 0.1016)
		(layer "F.Cu")
		(net "P5E_CPU1_P1_TX_C_DP<12>")
	)
	(arc
		(start 99.662488 -373.567198)
		(mid 99.690131 -373.608568)
		(end 99.699826 -373.657368)
		(width 0.1016)
		(layer "F.Cu")
		(net "P5E_CPU1_P1_TX_C_DP<12>")
	)
	(arc
		(start 97.990152 -371.5385)
		(mid 98.055696 -371.868013)
		(end 98.242374 -372.147338)
		(width 0.1016)
		(layer "F.Cu")
		(net "P5E_CPU1_P1_TX_C_DP<12>")
	)
	(arc
		(start 94.323408 -380.04115)
		(mid 94.110987 -380.359061)
		(end 94.036388 -380.734062)
		(width 0.1016)
		(layer "F.Cu")
		(net "P5E_CPU1_P1_TX_C_DP<12>")
	)
	(arc
		(start 99.699826 -374.562878)
		(mid 99.680832 -374.657333)
		(end 99.627182 -374.737376)
		(width 0.1016)
		(layer "F.Cu")
		(net "P5E_CPU1_P1_TX_C_DP<12>")
	)
	(segment
		(start 92.845636 -383.520442)
		(end 92.845636 -383.402586)
		(width 0.1016)
		(layer "F.Cu")
		(net "P5E_CPU1_P1_TX_C_DP<11>")
	)
	(segment
		(start 92.836238 -382.942592)
		(end 92.54363 -383.2352)
		(width 0.1016)
		(layer "F.Cu")
		(net "P5E_CPU1_P1_TX_C_DP<11>")
	)
	(segment
		(start 92.634816 -383.596896)
		(end 92.769182 -383.596896)
		(width 0.1016)
		(layer "F.Cu")
		(net "P5E_CPU1_P1_TX_C_DP<11>")
	)
	(segment
		(start 95.939102 -373.30253)
		(end 96.288352 -373.65178)
		(width 0.1016)
		(layer "F.Cu")
		(net "P5E_CPU1_P1_TX_C_DP<11>")
	)
	(segment
		(start 92.769182 -383.596896)
		(end 92.845636 -383.520442)
		(width 0.1016)
		(layer "F.Cu")
		(net "P5E_CPU1_P1_TX_C_DP<11>")
	)
	(segment
		(start 92.54363 -383.2352)
		(end 92.54363 -383.50571)
		(width 0.1016)
		(layer "F.Cu")
		(net "P5E_CPU1_P1_TX_C_DP<11>")
	)
	(segment
		(start 92.54363 -383.50571)
		(end 92.634816 -383.596896)
		(width 0.1016)
		(layer "F.Cu")
		(net "P5E_CPU1_P1_TX_C_DP<11>")
	)
	(segment
		(start 92.836238 -379.884178)
		(end 92.836238 -382.942592)
		(width 0.1016)
		(layer "F.Cu")
		(net "P5E_CPU1_P1_TX_C_DP<11>")
	)
	(segment
		(start 96.251014 -376.326654)
		(end 92.935552 -379.642116)
		(width 0.1016)
		(layer "F.Cu")
		(net "P5E_CPU1_P1_TX_C_DP<11>")
	)
	(segment
		(start 96.288352 -373.65178)
		(end 96.288352 -376.236484)
		(width 0.1016)
		(layer "F.Cu")
		(net "P5E_CPU1_P1_TX_C_DP<11>")
	)
	(arc
		(start 96.288352 -376.236484)
		(mid 96.278646 -376.285279)
		(end 96.251014 -376.326654)
		(width 0.1016)
		(layer "F.Cu")
		(net "P5E_CPU1_P1_TX_C_DP<11>")
	)
	(arc
		(start 92.935552 -379.642116)
		(mid 92.861991 -379.753332)
		(end 92.836238 -379.884178)
		(width 0.1016)
		(layer "F.Cu")
		(net "P5E_CPU1_P1_TX_C_DP<11>")
	)
	(segment
		(start 91.636342 -382.942592)
		(end 91.343734 -383.2352)
		(width 0.1016)
		(layer "F.Cu")
		(net "P5E_CPU1_P1_TX_C_DP<10>")
	)
	(segment
		(start 93.452442 -377.321572)
		(end 93.229684 -377.321572)
		(width 0.1016)
		(layer "F.Cu")
		(net "P5E_CPU1_P1_TX_C_DP<10>")
	)
	(segment
		(start 92.96908 -377.429522)
		(end 91.915742 -378.48286)
		(width 0.1016)
		(layer "F.Cu")
		(net "P5E_CPU1_P1_TX_C_DP<10>")
	)
	(segment
		(start 91.343734 -383.2352)
		(end 91.343734 -383.50571)
		(width 0.1016)
		(layer "F.Cu")
		(net "P5E_CPU1_P1_TX_C_DP<10>")
	)
	(segment
		(start 94.237302 -375.76633)
		(end 94.585536 -376.114564)
		(width 0.1016)
		(layer "F.Cu")
		(net "P5E_CPU1_P1_TX_C_DP<10>")
	)
	(segment
		(start 91.43492 -383.596896)
		(end 91.569286 -383.596896)
		(width 0.1016)
		(layer "F.Cu")
		(net "P5E_CPU1_P1_TX_C_DP<10>")
	)
	(segment
		(start 94.585536 -376.114564)
		(end 94.585536 -376.202702)
		(width 0.1016)
		(layer "F.Cu")
		(net "P5E_CPU1_P1_TX_C_DP<10>")
	)
	(segment
		(start 91.636342 -378.904754)
		(end 91.636342 -382.942592)
		(width 0.1016)
		(layer "F.Cu")
		(net "P5E_CPU1_P1_TX_C_DP<10>")
	)
	(segment
		(start 91.915742 -378.48286)
		(end 91.915488 -378.48286)
		(width 0.1016)
		(layer "F.Cu")
		(net "P5E_CPU1_P1_TX_C_DP<10>")
	)
	(segment
		(start 91.343734 -383.50571)
		(end 91.43492 -383.596896)
		(width 0.1016)
		(layer "F.Cu")
		(net "P5E_CPU1_P1_TX_C_DP<10>")
	)
	(segment
		(start 91.64574 -383.520442)
		(end 91.64574 -383.402586)
		(width 0.1016)
		(layer "F.Cu")
		(net "P5E_CPU1_P1_TX_C_DP<10>")
	)
	(segment
		(start 91.915488 -378.48286)
		(end 91.736672 -378.661676)
		(width 0.1016)
		(layer "F.Cu")
		(net "P5E_CPU1_P1_TX_C_DP<10>")
	)
	(segment
		(start 91.569286 -383.596896)
		(end 91.64574 -383.520442)
		(width 0.1016)
		(layer "F.Cu")
		(net "P5E_CPU1_P1_TX_C_DP<10>")
	)
	(segment
		(start 94.548198 -376.292872)
		(end 93.566742 -377.274328)
		(width 0.1016)
		(layer "F.Cu")
		(net "P5E_CPU1_P1_TX_C_DP<10>")
	)
	(arc
		(start 94.585536 -376.202702)
		(mid 94.57583 -376.251497)
		(end 94.548198 -376.292872)
		(width 0.1016)
		(layer "F.Cu")
		(net "P5E_CPU1_P1_TX_C_DP<10>")
	)
	(arc
		(start 91.736672 -378.661676)
		(mid 91.662373 -378.773245)
		(end 91.636342 -378.904754)
		(width 0.1016)
		(layer "F.Cu")
		(net "P5E_CPU1_P1_TX_C_DP<10>")
	)
	(arc
		(start 93.229684 -377.321572)
		(mid 93.088644 -377.349627)
		(end 92.96908 -377.429522)
		(width 0.1016)
		(layer "F.Cu")
		(net "P5E_CPU1_P1_TX_C_DP<10>")
	)
	(arc
		(start 93.566742 -377.274328)
		(mid 93.514287 -377.309315)
		(end 93.452442 -377.321572)
		(width 0.1016)
		(layer "F.Cu")
		(net "P5E_CPU1_P1_TX_C_DP<10>")
	)
	(segment
		(start 79.29499 -382.47447)
		(end 79.636366 -382.817624)
		(width 0.1016)
		(layer "F.Cu")
		(net "P5E_CPU1_P1_TX_C_DP<0>")
	)
	(segment
		(start 77.667358 -382.155192)
		(end 77.779118 -382.043432)
		(width 0.1016)
		(layer "F.Cu")
		(net "P5E_CPU1_P1_TX_C_DP<0>")
	)
	(segment
		(start 77.362558 -382.155192)
		(end 77.667358 -382.155192)
		(width 0.1016)
		(layer "F.Cu")
		(net "P5E_CPU1_P1_TX_C_DP<0>")
	)
	(segment
		(start 75.76185 -382.39446)
		(end 76.112878 -382.043432)
		(width 0.1016)
		(layer "F.Cu")
		(net "P5E_CPU1_P1_TX_C_DP<0>")
	)
	(segment
		(start 76.112878 -382.043432)
		(end 76.417678 -382.043432)
		(width 0.1016)
		(layer "F.Cu")
		(net "P5E_CPU1_P1_TX_C_DP<0>")
	)
	(segment
		(start 77.250798 -382.043432)
		(end 77.362558 -382.155192)
		(width 0.1016)
		(layer "F.Cu")
		(net "P5E_CPU1_P1_TX_C_DP<0>")
	)
	(segment
		(start 77.779118 -382.043432)
		(end 78.28026 -382.043432)
		(width 0.1016)
		(layer "F.Cu")
		(net "P5E_CPU1_P1_TX_C_DP<0>")
	)
	(segment
		(start 78.478126 -382.082802)
		(end 79.083408 -382.332738)
		(width 0.1016)
		(layer "F.Cu")
		(net "P5E_CPU1_P1_TX_C_DP<0>")
	)
	(segment
		(start 76.417678 -382.043432)
		(end 76.529438 -382.155192)
		(width 0.1016)
		(layer "F.Cu")
		(net "P5E_CPU1_P1_TX_C_DP<0>")
	)
	(segment
		(start 79.636366 -382.942592)
		(end 79.343758 -383.2352)
		(width 0.1016)
		(layer "F.Cu")
		(net "P5E_CPU1_P1_TX_C_DP<0>")
	)
	(segment
		(start 79.434944 -383.596896)
		(end 79.56931 -383.596896)
		(width 0.1016)
		(layer "F.Cu")
		(net "P5E_CPU1_P1_TX_C_DP<0>")
	)
	(segment
		(start 79.645764 -383.520442)
		(end 79.645764 -383.402586)
		(width 0.1016)
		(layer "F.Cu")
		(net "P5E_CPU1_P1_TX_C_DP<0>")
	)
	(segment
		(start 76.529438 -382.155192)
		(end 76.834238 -382.155192)
		(width 0.1016)
		(layer "F.Cu")
		(net "P5E_CPU1_P1_TX_C_DP<0>")
	)
	(segment
		(start 79.343758 -383.2352)
		(end 79.343758 -383.50571)
		(width 0.1016)
		(layer "F.Cu")
		(net "P5E_CPU1_P1_TX_C_DP<0>")
	)
	(segment
		(start 76.945998 -382.043432)
		(end 77.250798 -382.043432)
		(width 0.1016)
		(layer "F.Cu")
		(net "P5E_CPU1_P1_TX_C_DP<0>")
	)
	(segment
		(start 79.56931 -383.596896)
		(end 79.645764 -383.520442)
		(width 0.1016)
		(layer "F.Cu")
		(net "P5E_CPU1_P1_TX_C_DP<0>")
	)
	(segment
		(start 79.343758 -383.50571)
		(end 79.434944 -383.596896)
		(width 0.1016)
		(layer "F.Cu")
		(net "P5E_CPU1_P1_TX_C_DP<0>")
	)
	(segment
		(start 76.834238 -382.155192)
		(end 76.945998 -382.043432)
		(width 0.1016)
		(layer "F.Cu")
		(net "P5E_CPU1_P1_TX_C_DP<0>")
	)
	(segment
		(start 79.636366 -382.817624)
		(end 79.636366 -382.942592)
		(width 0.1016)
		(layer "F.Cu")
		(net "P5E_CPU1_P1_TX_C_DP<0>")
	)
	(arc
		(start 79.083408 -382.332738)
		(mid 79.196239 -382.393093)
		(end 79.29499 -382.47447)
		(width 0.1016)
		(layer "F.Cu")
		(net "P5E_CPU1_P1_TX_C_DP<0>")
	)
	(arc
		(start 78.28026 -382.043432)
		(mid 78.381125 -382.053399)
		(end 78.478126 -382.082802)
		(width 0.1016)
		(layer "F.Cu")
		(net "P5E_CPU1_P1_TX_C_DP<0>")
	)
	(segment
		(start 91.398852 -371.18798)
		(end 91.398852 -371.527324)
		(width 0.1016)
		(layer "F.Cu")
		(net "P5E_CPU1_P1_TX_C_DN<9>")
	)
	(segment
		(start 92.942918 -375.31929)
		(end 92.082112 -376.180096)
		(width 0.1016)
		(layer "F.Cu")
		(net "P5E_CPU1_P1_TX_C_DN<9>")
	)
	(segment
		(start 91.866212 -376.553984)
		(end 91.708224 -376.553984)
		(width 0.1016)
		(layer "F.Cu")
		(net "P5E_CPU1_P1_TX_C_DN<9>")
	)
	(segment
		(start 91.708224 -376.553984)
		(end 90.733118 -377.52909)
		(width 0.1016)
		(layer "F.Cu")
		(net "P5E_CPU1_P1_TX_C_DN<9>")
	)
	(segment
		(start 90.652346 -377.723908)
		(end 90.652346 -383.13741)
		(width 0.1016)
		(layer "F.Cu")
		(net "P5E_CPU1_P1_TX_C_DN<9>")
	)
	(segment
		(start 90.652346 -383.13741)
		(end 90.745818 -383.230882)
		(width 0.1016)
		(layer "F.Cu")
		(net "P5E_CPU1_P1_TX_C_DN<9>")
	)
	(segment
		(start 92.082112 -376.180096)
		(end 92.082112 -376.338084)
		(width 0.1016)
		(layer "F.Cu")
		(net "P5E_CPU1_P1_TX_C_DN<9>")
	)
	(segment
		(start 90.745818 -383.230882)
		(end 90.745818 -383.92227)
		(width 0.1016)
		(layer "F.Cu")
		(net "P5E_CPU1_P1_TX_C_DN<9>")
	)
	(segment
		(start 91.651328 -372.136162)
		(end 92.814394 -373.299228)
		(width 0.1016)
		(layer "F.Cu")
		(net "P5E_CPU1_P1_TX_C_DN<9>")
	)
	(segment
		(start 92.082112 -376.338084)
		(end 91.866212 -376.553984)
		(width 0.1016)
		(layer "F.Cu")
		(net "P5E_CPU1_P1_TX_C_DN<9>")
	)
	(segment
		(start 93.077284 -373.933466)
		(end 93.077284 -374.994932)
		(width 0.1016)
		(layer "F.Cu")
		(net "P5E_CPU1_P1_TX_C_DN<9>")
	)
	(segment
		(start 91.748102 -370.83873)
		(end 91.398852 -371.18798)
		(width 0.1016)
		(layer "F.Cu")
		(net "P5E_CPU1_P1_TX_C_DN<9>")
	)
	(arc
		(start 93.077284 -374.994932)
		(mid 93.042366 -375.170478)
		(end 92.942918 -375.31929)
		(width 0.1016)
		(layer "F.Cu")
		(net "P5E_CPU1_P1_TX_C_DN<9>")
	)
	(arc
		(start 92.814394 -373.299228)
		(mid 93.008911 -373.590204)
		(end 93.077284 -373.933466)
		(width 0.1016)
		(layer "F.Cu")
		(net "P5E_CPU1_P1_TX_C_DN<9>")
	)
	(arc
		(start 91.398852 -371.527324)
		(mid 91.464582 -371.856827)
		(end 91.651328 -372.136162)
		(width 0.1016)
		(layer "F.Cu")
		(net "P5E_CPU1_P1_TX_C_DN<9>")
	)
	(arc
		(start 90.733118 -377.52909)
		(mid 90.67334 -377.618459)
		(end 90.652346 -377.723908)
		(width 0.1016)
		(layer "F.Cu")
		(net "P5E_CPU1_P1_TX_C_DN<9>")
	)
	(segment
		(start 89.697052 -374.84304)
		(end 89.808812 -374.9548)
		(width 0.1016)
		(layer "F.Cu")
		(net "P5E_CPU1_P1_TX_C_DN<8>")
	)
	(segment
		(start 89.808812 -374.9548)
		(end 89.808812 -375.2596)
		(width 0.1016)
		(layer "F.Cu")
		(net "P5E_CPU1_P1_TX_C_DN<8>")
	)
	(segment
		(start 89.808812 -375.2596)
		(end 89.697052 -375.37136)
		(width 0.1016)
		(layer "F.Cu")
		(net "P5E_CPU1_P1_TX_C_DN<8>")
	)
	(segment
		(start 89.697052 -373.71909)
		(end 89.697052 -374.84304)
		(width 0.1016)
		(layer "F.Cu")
		(net "P5E_CPU1_P1_TX_C_DN<8>")
	)
	(segment
		(start 89.697052 -375.37136)
		(end 89.697052 -376.616976)
		(width 0.1016)
		(layer "F.Cu")
		(net "P5E_CPU1_P1_TX_C_DN<8>")
	)
	(segment
		(start 89.545668 -383.230882)
		(end 89.545668 -383.92227)
		(width 0.1016)
		(layer "F.Cu")
		(net "P5E_CPU1_P1_TX_C_DN<8>")
	)
	(segment
		(start 90.046302 -373.30253)
		(end 89.74455 -373.604282)
		(width 0.1016)
		(layer "F.Cu")
		(net "P5E_CPU1_P1_TX_C_DN<8>")
	)
	(segment
		(start 89.452196 -383.13741)
		(end 89.545668 -383.230882)
		(width 0.1016)
		(layer "F.Cu")
		(net "P5E_CPU1_P1_TX_C_DN<8>")
	)
	(segment
		(start 89.452196 -377.318016)
		(end 89.452196 -383.13741)
		(width 0.1016)
		(layer "F.Cu")
		(net "P5E_CPU1_P1_TX_C_DN<8>")
	)
	(arc
		(start 89.697052 -376.616976)
		(mid 89.661055 -376.831347)
		(end 89.556844 -377.022106)
		(width 0.1016)
		(layer "F.Cu")
		(net "P5E_CPU1_P1_TX_C_DN<8>")
	)
	(arc
		(start 89.74455 -373.604282)
		(mid 89.709408 -373.656971)
		(end 89.697052 -373.71909)
		(width 0.1016)
		(layer "F.Cu")
		(net "P5E_CPU1_P1_TX_C_DN<8>")
	)
	(arc
		(start 89.556844 -377.022106)
		(mid 89.52078 -377.074405)
		(end 89.491566 -377.130818)
		(width 0.1016)
		(layer "F.Cu")
		(net "P5E_CPU1_P1_TX_C_DN<8>")
	)
	(arc
		(start 89.491566 -377.130818)
		(mid 89.462102 -377.222364)
		(end 89.452196 -377.318016)
		(width 0.1016)
		(layer "F.Cu")
		(net "P5E_CPU1_P1_TX_C_DN<8>")
	)
	(segment
		(start 88.344502 -375.76633)
		(end 88.042496 -376.068336)
		(width 0.1016)
		(layer "F.Cu")
		(net "P5E_CPU1_P1_TX_C_DN<7>")
	)
	(segment
		(start 88.345772 -383.230882)
		(end 88.345772 -383.92227)
		(width 0.1016)
		(layer "F.Cu")
		(net "P5E_CPU1_P1_TX_C_DN<7>")
	)
	(segment
		(start 87.995252 -376.182636)
		(end 87.995252 -377.07443)
		(width 0.1016)
		(layer "F.Cu")
		(net "P5E_CPU1_P1_TX_C_DN<7>")
	)
	(segment
		(start 87.995252 -377.07443)
		(end 88.107012 -377.18619)
		(width 0.1016)
		(layer "F.Cu")
		(net "P5E_CPU1_P1_TX_C_DN<7>")
	)
	(segment
		(start 88.2523 -382.94183)
		(end 88.2523 -383.13741)
		(width 0.1016)
		(layer "F.Cu")
		(net "P5E_CPU1_P1_TX_C_DN<7>")
	)
	(segment
		(start 87.995252 -377.60275)
		(end 87.995252 -377.90755)
		(width 0.1016)
		(layer "F.Cu")
		(net "P5E_CPU1_P1_TX_C_DN<7>")
	)
	(segment
		(start 88.2523 -383.13741)
		(end 88.345772 -383.230882)
		(width 0.1016)
		(layer "F.Cu")
		(net "P5E_CPU1_P1_TX_C_DN<7>")
	)
	(segment
		(start 88.107012 -377.18619)
		(end 88.107012 -377.49099)
		(width 0.1016)
		(layer "F.Cu")
		(net "P5E_CPU1_P1_TX_C_DN<7>")
	)
	(segment
		(start 88.23452 -378.6632)
		(end 88.2523 -382.94183)
		(width 0.1016)
		(layer "F.Cu")
		(net "P5E_CPU1_P1_TX_C_DN<7>")
	)
	(segment
		(start 88.107012 -377.49099)
		(end 87.995252 -377.60275)
		(width 0.1016)
		(layer "F.Cu")
		(net "P5E_CPU1_P1_TX_C_DN<7>")
	)
	(arc
		(start 87.995252 -377.90755)
		(mid 88.025794 -378.106219)
		(end 88.114632 -378.286518)
		(width 0.1016)
		(layer "F.Cu")
		(net "P5E_CPU1_P1_TX_C_DN<7>")
	)
	(arc
		(start 88.042496 -376.068336)
		(mid 88.007509 -376.120791)
		(end 87.995252 -376.182636)
		(width 0.1016)
		(layer "F.Cu")
		(net "P5E_CPU1_P1_TX_C_DN<7>")
	)
	(arc
		(start 88.114632 -378.286518)
		(mid 88.203331 -378.465706)
		(end 88.23452 -378.6632)
		(width 0.1016)
		(layer "F.Cu")
		(net "P5E_CPU1_P1_TX_C_DN<7>")
	)
	(segment
		(start 87.05215 -383.13741)
		(end 87.145876 -383.231136)
		(width 0.1016)
		(layer "F.Cu")
		(net "P5E_CPU1_P1_TX_C_DN<6>")
	)
	(segment
		(start 84.591652 -371.18798)
		(end 84.591652 -371.479826)
		(width 0.1016)
		(layer "F.Cu")
		(net "P5E_CPU1_P1_TX_C_DN<6>")
	)
	(segment
		(start 87.05215 -381.694182)
		(end 87.05215 -383.13741)
		(width 0.1016)
		(layer "F.Cu")
		(net "P5E_CPU1_P1_TX_C_DN<6>")
	)
	(segment
		(start 86.437216 -378.652278)
		(end 86.473792 -378.742194)
		(width 0.1016)
		(layer "F.Cu")
		(net "P5E_CPU1_P1_TX_C_DN<6>")
	)
	(segment
		(start 84.85505 -372.114826)
		(end 86.087458 -373.347234)
		(width 0.1016)
		(layer "F.Cu")
		(net "P5E_CPU1_P1_TX_C_DN<6>")
	)
	(segment
		(start 86.310978 -374.849136)
		(end 86.422738 -374.960896)
		(width 0.1016)
		(layer "F.Cu")
		(net "P5E_CPU1_P1_TX_C_DN<6>")
	)
	(segment
		(start 86.422738 -375.265696)
		(end 86.310978 -375.377456)
		(width 0.1016)
		(layer "F.Cu")
		(net "P5E_CPU1_P1_TX_C_DN<6>")
	)
	(segment
		(start 87.145876 -383.231136)
		(end 87.145876 -383.92227)
		(width 0.1016)
		(layer "F.Cu")
		(net "P5E_CPU1_P1_TX_C_DN<6>")
	)
	(segment
		(start 84.940902 -370.83873)
		(end 84.591652 -371.18798)
		(width 0.1016)
		(layer "F.Cu")
		(net "P5E_CPU1_P1_TX_C_DN<6>")
	)
	(segment
		(start 86.310978 -373.88673)
		(end 86.310978 -374.849136)
		(width 0.1016)
		(layer "F.Cu")
		(net "P5E_CPU1_P1_TX_C_DN<6>")
	)
	(segment
		(start 86.422738 -374.960896)
		(end 86.422738 -375.265696)
		(width 0.1016)
		(layer "F.Cu")
		(net "P5E_CPU1_P1_TX_C_DN<6>")
	)
	(segment
		(start 86.310978 -375.377456)
		(end 86.310978 -378.006356)
		(width 0.1016)
		(layer "F.Cu")
		(net "P5E_CPU1_P1_TX_C_DN<6>")
	)
	(arc
		(start 86.310978 -378.006356)
		(mid 86.342851 -378.335425)
		(end 86.437216 -378.652278)
		(width 0.1016)
		(layer "F.Cu")
		(net "P5E_CPU1_P1_TX_C_DN<6>")
	)
	(arc
		(start 86.087458 -373.347234)
		(mid 86.252823 -373.59477)
		(end 86.310978 -373.88673)
		(width 0.1016)
		(layer "F.Cu")
		(net "P5E_CPU1_P1_TX_C_DN<6>")
	)
	(arc
		(start 84.591652 -371.479826)
		(mid 84.660219 -371.823506)
		(end 84.85505 -372.114826)
		(width 0.1016)
		(layer "F.Cu")
		(net "P5E_CPU1_P1_TX_C_DN<6>")
	)
	(arc
		(start 86.473792 -378.742194)
		(mid 86.906158 -380.190135)
		(end 87.05215 -381.694182)
		(width 0.1016)
		(layer "F.Cu")
		(net "P5E_CPU1_P1_TX_C_DN<6>")
	)
	(segment
		(start 83.217512 -376.44197)
		(end 85.147404 -379.328934)
		(width 0.1016)
		(layer "F.Cu")
		(net "P5E_CPU1_P1_TX_C_DN<5>")
	)
	(segment
		(start 83.239102 -373.30253)
		(end 82.889852 -373.65178)
		(width 0.1016)
		(layer "F.Cu")
		(net "P5E_CPU1_P1_TX_C_DN<5>")
	)
	(segment
		(start 82.889852 -374.529096)
		(end 83.001612 -374.640856)
		(width 0.1016)
		(layer "F.Cu")
		(net "P5E_CPU1_P1_TX_C_DN<5>")
	)
	(segment
		(start 83.001612 -374.640856)
		(end 83.001612 -374.945656)
		(width 0.1016)
		(layer "F.Cu")
		(net "P5E_CPU1_P1_TX_C_DN<5>")
	)
	(segment
		(start 85.852254 -383.13741)
		(end 85.945726 -383.230882)
		(width 0.1016)
		(layer "F.Cu")
		(net "P5E_CPU1_P1_TX_C_DN<5>")
	)
	(segment
		(start 83.001612 -374.945656)
		(end 82.889852 -375.057416)
		(width 0.1016)
		(layer "F.Cu")
		(net "P5E_CPU1_P1_TX_C_DN<5>")
	)
	(segment
		(start 85.852254 -381.651764)
		(end 85.852254 -383.13741)
		(width 0.1016)
		(layer "F.Cu")
		(net "P5E_CPU1_P1_TX_C_DN<5>")
	)
	(segment
		(start 82.889852 -375.057416)
		(end 82.889852 -375.362216)
		(width 0.1016)
		(layer "F.Cu")
		(net "P5E_CPU1_P1_TX_C_DN<5>")
	)
	(segment
		(start 82.889852 -373.65178)
		(end 82.889852 -374.529096)
		(width 0.1016)
		(layer "F.Cu")
		(net "P5E_CPU1_P1_TX_C_DN<5>")
	)
	(segment
		(start 85.945726 -383.230882)
		(end 85.945726 -383.92227)
		(width 0.1016)
		(layer "F.Cu")
		(net "P5E_CPU1_P1_TX_C_DN<5>")
	)
	(arc
		(start 85.147404 -379.328934)
		(mid 85.672167 -380.438055)
		(end 85.852254 -381.651764)
		(width 0.1016)
		(layer "F.Cu")
		(net "P5E_CPU1_P1_TX_C_DN<5>")
	)
	(arc
		(start 82.889852 -375.362216)
		(mid 82.973573 -375.926402)
		(end 83.217512 -376.44197)
		(width 0.1016)
		(layer "F.Cu")
		(net "P5E_CPU1_P1_TX_C_DN<5>")
	)
	(segment
		(start 81.403698 -376.809508)
		(end 81.945734 -377.469908)
		(width 0.1016)
		(layer "F.Cu")
		(net "P5E_CPU1_P1_TX_C_DN<4>")
	)
	(segment
		(start 81.188052 -376.11558)
		(end 81.188052 -376.28957)
		(width 0.1016)
		(layer "F.Cu")
		(net "P5E_CPU1_P1_TX_C_DN<4>")
	)
	(segment
		(start 81.537302 -375.76633)
		(end 81.188052 -376.11558)
		(width 0.1016)
		(layer "F.Cu")
		(net "P5E_CPU1_P1_TX_C_DN<4>")
	)
	(segment
		(start 81.188052 -376.28957)
		(end 81.403698 -376.809508)
		(width 0.1016)
		(layer "F.Cu")
		(net "P5E_CPU1_P1_TX_C_DN<4>")
	)
	(segment
		(start 82.296508 -377.721114)
		(end 82.281268 -377.878594)
		(width 0.1016)
		(layer "F.Cu")
		(net "P5E_CPU1_P1_TX_C_DN<4>")
	)
	(segment
		(start 84.652358 -381.573278)
		(end 84.652358 -383.13741)
		(width 0.1016)
		(layer "F.Cu")
		(net "P5E_CPU1_P1_TX_C_DN<4>")
	)
	(segment
		(start 81.945734 -377.469908)
		(end 82.10296 -377.485402)
		(width 0.1016)
		(layer "F.Cu")
		(net "P5E_CPU1_P1_TX_C_DN<4>")
	)
	(segment
		(start 84.652358 -383.13741)
		(end 84.74583 -383.230882)
		(width 0.1016)
		(layer "F.Cu")
		(net "P5E_CPU1_P1_TX_C_DN<4>")
	)
	(segment
		(start 82.10296 -377.485402)
		(end 82.296508 -377.721114)
		(width 0.1016)
		(layer "F.Cu")
		(net "P5E_CPU1_P1_TX_C_DN<4>")
	)
	(segment
		(start 82.281268 -377.878594)
		(end 84.279232 -380.31293)
		(width 0.1016)
		(layer "F.Cu")
		(net "P5E_CPU1_P1_TX_C_DN<4>")
	)
	(segment
		(start 84.74583 -383.230882)
		(end 84.74583 -383.92227)
		(width 0.1016)
		(layer "F.Cu")
		(net "P5E_CPU1_P1_TX_C_DN<4>")
	)
	(arc
		(start 84.652358 -381.5715)
		(mid 84.652358 -381.571881)
		(end 84.652358 -381.572262)
		(width 0.1016)
		(layer "F.Cu")
		(net "P5E_CPU1_P1_TX_C_DN<4>")
	)
	(arc
		(start 84.279232 -380.31293)
		(mid 84.556884 -380.915208)
		(end 84.652358 -381.5715)
		(width 0.1016)
		(layer "F.Cu")
		(net "P5E_CPU1_P1_TX_C_DN<4>")
	)
	(arc
		(start 84.652358 -381.572262)
		(mid 84.652358 -381.57277)
		(end 84.652358 -381.573278)
		(width 0.1016)
		(layer "F.Cu")
		(net "P5E_CPU1_P1_TX_C_DN<4>")
	)
	(segment
		(start 79.543402 -375.452132)
		(end 80.39735 -377.514358)
		(width 0.1016)
		(layer "F.Cu")
		(net "P5E_CPU1_P1_TX_C_DN<3>")
	)
	(segment
		(start 83.54568 -383.230882)
		(end 83.54568 -383.92227)
		(width 0.1016)
		(layer "F.Cu")
		(net "P5E_CPU1_P1_TX_C_DN<3>")
	)
	(segment
		(start 83.452208 -383.13741)
		(end 83.54568 -383.230882)
		(width 0.1016)
		(layer "F.Cu")
		(net "P5E_CPU1_P1_TX_C_DN<3>")
	)
	(segment
		(start 77.784452 -371.18798)
		(end 77.784452 -371.57152)
		(width 0.1016)
		(layer "F.Cu")
		(net "P5E_CPU1_P1_TX_C_DN<3>")
	)
	(segment
		(start 78.719934 -372.768114)
		(end 78.877922 -372.768114)
		(width 0.1016)
		(layer "F.Cu")
		(net "P5E_CPU1_P1_TX_C_DN<3>")
	)
	(segment
		(start 78.133702 -370.83873)
		(end 77.784452 -371.18798)
		(width 0.1016)
		(layer "F.Cu")
		(net "P5E_CPU1_P1_TX_C_DN<3>")
	)
	(segment
		(start 80.39735 -377.514358)
		(end 80.651858 -377.9393)
		(width 0.1016)
		(layer "F.Cu")
		(net "P5E_CPU1_P1_TX_C_DN<3>")
	)
	(segment
		(start 77.96911 -372.01729)
		(end 78.719934 -372.768114)
		(width 0.1016)
		(layer "F.Cu")
		(net "P5E_CPU1_P1_TX_C_DN<3>")
	)
	(segment
		(start 78.877922 -372.768114)
		(end 79.093822 -372.984014)
		(width 0.1016)
		(layer "F.Cu")
		(net "P5E_CPU1_P1_TX_C_DN<3>")
	)
	(segment
		(start 79.093822 -372.984014)
		(end 79.093822 -373.142002)
		(width 0.1016)
		(layer "F.Cu")
		(net "P5E_CPU1_P1_TX_C_DN<3>")
	)
	(segment
		(start 80.651858 -377.9393)
		(end 83.284822 -381.147574)
		(width 0.1016)
		(layer "F.Cu")
		(net "P5E_CPU1_P1_TX_C_DN<3>")
	)
	(segment
		(start 79.093822 -373.142002)
		(end 79.354934 -373.403114)
		(width 0.1016)
		(layer "F.Cu")
		(net "P5E_CPU1_P1_TX_C_DN<3>")
	)
	(segment
		(start 83.452208 -381.614426)
		(end 83.452208 -383.13741)
		(width 0.1016)
		(layer "F.Cu")
		(net "P5E_CPU1_P1_TX_C_DN<3>")
	)
	(segment
		(start 79.494126 -373.738902)
		(end 79.494126 -375.203466)
		(width 0.1016)
		(layer "F.Cu")
		(net "P5E_CPU1_P1_TX_C_DN<3>")
	)
	(arc
		(start 79.354934 -373.403114)
		(mid 79.457928 -373.557161)
		(end 79.494126 -373.738902)
		(width 0.1016)
		(layer "F.Cu")
		(net "P5E_CPU1_P1_TX_C_DN<3>")
	)
	(arc
		(start 77.784452 -371.57152)
		(mid 77.83244 -371.812774)
		(end 77.96911 -372.01729)
		(width 0.1016)
		(layer "F.Cu")
		(net "P5E_CPU1_P1_TX_C_DN<3>")
	)
	(arc
		(start 83.284822 -381.147574)
		(mid 83.40904 -381.366463)
		(end 83.452208 -381.614426)
		(width 0.1016)
		(layer "F.Cu")
		(net "P5E_CPU1_P1_TX_C_DN<3>")
	)
	(arc
		(start 79.494126 -375.203466)
		(mid 79.506506 -375.33023)
		(end 79.543402 -375.452132)
		(width 0.1016)
		(layer "F.Cu")
		(net "P5E_CPU1_P1_TX_C_DN<3>")
	)
	(segment
		(start 82.252312 -382.220216)
		(end 82.252312 -383.13741)
		(width 0.1016)
		(layer "F.Cu")
		(net "P5E_CPU1_P1_TX_C_DN<2>")
	)
	(segment
		(start 78.381098 -376.00509)
		(end 78.381098 -376.163078)
		(width 0.1016)
		(layer "F.Cu")
		(net "P5E_CPU1_P1_TX_C_DN<2>")
	)
	(segment
		(start 78.00721 -375.78919)
		(end 78.165198 -375.78919)
		(width 0.1016)
		(layer "F.Cu")
		(net "P5E_CPU1_P1_TX_C_DN<2>")
	)
	(segment
		(start 78.381098 -376.163078)
		(end 78.512162 -376.294142)
		(width 0.1016)
		(layer "F.Cu")
		(net "P5E_CPU1_P1_TX_C_DN<2>")
	)
	(segment
		(start 79.431896 -378.32792)
		(end 79.566262 -378.55144)
		(width 0.1016)
		(layer "F.Cu")
		(net "P5E_CPU1_P1_TX_C_DN<2>")
	)
	(segment
		(start 78.165198 -375.78919)
		(end 78.381098 -376.00509)
		(width 0.1016)
		(layer "F.Cu")
		(net "P5E_CPU1_P1_TX_C_DN<2>")
	)
	(segment
		(start 78.716378 -376.599704)
		(end 79.431896 -378.32792)
		(width 0.1016)
		(layer "F.Cu")
		(net "P5E_CPU1_P1_TX_C_DN<2>")
	)
	(segment
		(start 82.345784 -383.230882)
		(end 82.345784 -383.92227)
		(width 0.1016)
		(layer "F.Cu")
		(net "P5E_CPU1_P1_TX_C_DN<2>")
	)
	(segment
		(start 79.826104 -378.919994)
		(end 82.032094 -381.605536)
		(width 0.1016)
		(layer "F.Cu")
		(net "P5E_CPU1_P1_TX_C_DN<2>")
	)
	(segment
		(start 76.082652 -373.65178)
		(end 76.082652 -374.282208)
		(width 0.1016)
		(layer "F.Cu")
		(net "P5E_CPU1_P1_TX_C_DN<2>")
	)
	(segment
		(start 76.67625 -375.034556)
		(end 77.591158 -375.413524)
		(width 0.1016)
		(layer "F.Cu")
		(net "P5E_CPU1_P1_TX_C_DN<2>")
	)
	(segment
		(start 76.431902 -373.30253)
		(end 76.082652 -373.65178)
		(width 0.1016)
		(layer "F.Cu")
		(net "P5E_CPU1_P1_TX_C_DN<2>")
	)
	(segment
		(start 82.252312 -383.13741)
		(end 82.345784 -383.230882)
		(width 0.1016)
		(layer "F.Cu")
		(net "P5E_CPU1_P1_TX_C_DN<2>")
	)
	(segment
		(start 76.27747 -374.751854)
		(end 76.325476 -374.79986)
		(width 0.1016)
		(layer "F.Cu")
		(net "P5E_CPU1_P1_TX_C_DN<2>")
	)
	(segment
		(start 77.71257 -375.49455)
		(end 78.00721 -375.78919)
		(width 0.1016)
		(layer "F.Cu")
		(net "P5E_CPU1_P1_TX_C_DN<2>")
	)
	(arc
		(start 76.325476 -374.79986)
		(mid 76.489314 -374.934467)
		(end 76.67625 -375.034556)
		(width 0.1016)
		(layer "F.Cu")
		(net "P5E_CPU1_P1_TX_C_DN<2>")
	)
	(arc
		(start 79.566262 -378.55144)
		(mid 79.689421 -378.740484)
		(end 79.826104 -378.919994)
		(width 0.1016)
		(layer "F.Cu")
		(net "P5E_CPU1_P1_TX_C_DN<2>")
	)
	(arc
		(start 77.591158 -375.413524)
		(mid 77.655865 -375.448045)
		(end 77.71257 -375.49455)
		(width 0.1016)
		(layer "F.Cu")
		(net "P5E_CPU1_P1_TX_C_DN<2>")
	)
	(arc
		(start 78.512162 -376.294142)
		(mid 78.629327 -376.436861)
		(end 78.716378 -376.599704)
		(width 0.1016)
		(layer "F.Cu")
		(net "P5E_CPU1_P1_TX_C_DN<2>")
	)
	(arc
		(start 76.082652 -374.282208)
		(mid 76.133397 -374.53638)
		(end 76.27747 -374.751854)
		(width 0.1016)
		(layer "F.Cu")
		(net "P5E_CPU1_P1_TX_C_DN<2>")
	)
	(arc
		(start 82.032094 -381.605536)
		(mid 82.195583 -381.893755)
		(end 82.252312 -382.220216)
		(width 0.1016)
		(layer "F.Cu")
		(net "P5E_CPU1_P1_TX_C_DN<2>")
	)
	(segment
		(start 77.473556 -377.298966)
		(end 77.923644 -378.386594)
		(width 0.1016)
		(layer "F.Cu")
		(net "P5E_CPU1_P1_TX_C_DN<1>")
	)
	(segment
		(start 77.053948 -376.832876)
		(end 77.380084 -377.159012)
		(width 0.1016)
		(layer "F.Cu")
		(net "P5E_CPU1_P1_TX_C_DN<1>")
	)
	(segment
		(start 80.543654 -383.50571)
		(end 80.63484 -383.596896)
		(width 0.1016)
		(layer "F.Cu")
		(net "P5E_CPU1_P1_TX_C_DN<1>")
	)
	(segment
		(start 78.269338 -379.221238)
		(end 78.438502 -379.474476)
		(width 0.1016)
		(layer "F.Cu")
		(net "P5E_CPU1_P1_TX_C_DN<1>")
	)
	(segment
		(start 78.126082 -378.874782)
		(end 78.269338 -379.221238)
		(width 0.1016)
		(layer "F.Cu")
		(net "P5E_CPU1_P1_TX_C_DN<1>")
	)
	(segment
		(start 80.735424 -382.311656)
		(end 80.836262 -382.554734)
		(width 0.1016)
		(layer "F.Cu")
		(net "P5E_CPU1_P1_TX_C_DN<1>")
	)
	(segment
		(start 80.63484 -383.596896)
		(end 80.769206 -383.596896)
		(width 0.1016)
		(layer "F.Cu")
		(net "P5E_CPU1_P1_TX_C_DN<1>")
	)
	(segment
		(start 80.543654 -383.2352)
		(end 80.543654 -383.50571)
		(width 0.1016)
		(layer "F.Cu")
		(net "P5E_CPU1_P1_TX_C_DN<1>")
	)
	(segment
		(start 77.923644 -378.386594)
		(end 77.863192 -378.53239)
		(width 0.1016)
		(layer "F.Cu")
		(net "P5E_CPU1_P1_TX_C_DN<1>")
	)
	(segment
		(start 80.836262 -382.942592)
		(end 80.543654 -383.2352)
		(width 0.1016)
		(layer "F.Cu")
		(net "P5E_CPU1_P1_TX_C_DN<1>")
	)
	(segment
		(start 78.407768 -379.62967)
		(end 78.577186 -379.883162)
		(width 0.1016)
		(layer "F.Cu")
		(net "P5E_CPU1_P1_TX_C_DN<1>")
	)
	(segment
		(start 78.438502 -379.474476)
		(end 78.407768 -379.62967)
		(width 0.1016)
		(layer "F.Cu")
		(net "P5E_CPU1_P1_TX_C_DN<1>")
	)
	(segment
		(start 76.132944 -376.486166)
		(end 76.217018 -376.486166)
		(width 0.1016)
		(layer "F.Cu")
		(net "P5E_CPU1_P1_TX_C_DN<1>")
	)
	(segment
		(start 80.608932 -382.100836)
		(end 80.735424 -382.311656)
		(width 0.1016)
		(layer "F.Cu")
		(net "P5E_CPU1_P1_TX_C_DN<1>")
	)
	(segment
		(start 78.577186 -379.883162)
		(end 78.73238 -379.91415)
		(width 0.1016)
		(layer "F.Cu")
		(net "P5E_CPU1_P1_TX_C_DN<1>")
	)
	(segment
		(start 77.979778 -378.81433)
		(end 78.126082 -378.874782)
		(width 0.1016)
		(layer "F.Cu")
		(net "P5E_CPU1_P1_TX_C_DN<1>")
	)
	(segment
		(start 80.84566 -383.520442)
		(end 80.84566 -383.402586)
		(width 0.1016)
		(layer "F.Cu")
		(net "P5E_CPU1_P1_TX_C_DN<1>")
	)
	(segment
		(start 78.73238 -379.91415)
		(end 78.846172 -380.08433)
		(width 0.1016)
		(layer "F.Cu")
		(net "P5E_CPU1_P1_TX_C_DN<1>")
	)
	(segment
		(start 79.596996 -380.867412)
		(end 80.608932 -382.100836)
		(width 0.1016)
		(layer "F.Cu")
		(net "P5E_CPU1_P1_TX_C_DN<1>")
	)
	(segment
		(start 78.993746 -380.264162)
		(end 79.596996 -380.867412)
		(width 0.1016)
		(layer "F.Cu")
		(net "P5E_CPU1_P1_TX_C_DN<1>")
	)
	(segment
		(start 77.863192 -378.53239)
		(end 77.979778 -378.81433)
		(width 0.1016)
		(layer "F.Cu")
		(net "P5E_CPU1_P1_TX_C_DN<1>")
	)
	(segment
		(start 75.76185 -376.85726)
		(end 76.132944 -376.486166)
		(width 0.1016)
		(layer "F.Cu")
		(net "P5E_CPU1_P1_TX_C_DN<1>")
	)
	(segment
		(start 80.836262 -382.554734)
		(end 80.836262 -382.942592)
		(width 0.1016)
		(layer "F.Cu")
		(net "P5E_CPU1_P1_TX_C_DN<1>")
	)
	(segment
		(start 80.769206 -383.596896)
		(end 80.84566 -383.520442)
		(width 0.1016)
		(layer "F.Cu")
		(net "P5E_CPU1_P1_TX_C_DN<1>")
	)
	(arc
		(start 77.380084 -377.159012)
		(mid 77.433723 -377.22438)
		(end 77.473556 -377.298966)
		(width 0.1016)
		(layer "F.Cu")
		(net "P5E_CPU1_P1_TX_C_DN<1>")
	)
	(arc
		(start 76.217018 -376.486166)
		(mid 76.669963 -376.57628)
		(end 77.053948 -376.832876)
		(width 0.1016)
		(layer "F.Cu")
		(net "P5E_CPU1_P1_TX_C_DN<1>")
	)
	(arc
		(start 78.846172 -380.08433)
		(mid 78.915543 -380.17787)
		(end 78.993746 -380.264162)
		(width 0.1016)
		(layer "F.Cu")
		(net "P5E_CPU1_P1_TX_C_DN<1>")
	)
	(segment
		(start 99.846892 -380.078488)
		(end 97.945956 -381.979424)
		(width 0.1016)
		(layer "F.Cu")
		(net "P5E_CPU1_P1_TX_C_DN<15>")
	)
	(segment
		(start 97.85223 -382.205484)
		(end 97.85223 -382.92659)
		(width 0.1016)
		(layer "F.Cu")
		(net "P5E_CPU1_P1_TX_C_DN<15>")
	)
	(segment
		(start 97.85223 -382.92659)
		(end 97.94621 -383.02057)
		(width 0.1016)
		(layer "F.Cu")
		(net "P5E_CPU1_P1_TX_C_DN<15>")
	)
	(segment
		(start 97.94621 -383.921762)
		(end 97.945702 -383.92227)
		(width 0.1016)
		(layer "F.Cu")
		(net "P5E_CPU1_P1_TX_C_DN<15>")
	)
	(segment
		(start 101.652832 -380.036578)
		(end 99.947984 -380.036578)
		(width 0.1016)
		(layer "F.Cu")
		(net "P5E_CPU1_P1_TX_C_DN<15>")
	)
	(segment
		(start 97.94621 -383.02057)
		(end 97.94621 -383.921762)
		(width 0.1016)
		(layer "F.Cu")
		(net "P5E_CPU1_P1_TX_C_DN<15>")
	)
	(segment
		(start 102.002082 -380.385828)
		(end 101.652832 -380.036578)
		(width 0.1016)
		(layer "F.Cu")
		(net "P5E_CPU1_P1_TX_C_DN<15>")
	)
	(arc
		(start 97.945956 -381.979424)
		(mid 97.876601 -382.083127)
		(end 97.85223 -382.205484)
		(width 0.1016)
		(layer "F.Cu")
		(net "P5E_CPU1_P1_TX_C_DN<15>")
	)
	(arc
		(start 99.947984 -380.036578)
		(mid 99.89326 -380.047463)
		(end 99.846892 -380.078488)
		(width 0.1016)
		(layer "F.Cu")
		(net "P5E_CPU1_P1_TX_C_DN<15>")
	)
	(segment
		(start 102.002082 -376.067828)
		(end 101.56698 -376.50293)
		(width 0.1016)
		(layer "F.Cu")
		(net "P5E_CPU1_P1_TX_C_DN<14>")
	)
	(segment
		(start 101.252782 -376.50293)
		(end 96.697292 -381.05842)
		(width 0.1016)
		(layer "F.Cu")
		(net "P5E_CPU1_P1_TX_C_DN<14>")
	)
	(segment
		(start 96.436434 -381.689102)
		(end 96.436434 -383.016252)
		(width 0.1016)
		(layer "F.Cu")
		(net "P5E_CPU1_P1_TX_C_DN<14>")
	)
	(segment
		(start 96.436434 -383.016252)
		(end 96.530414 -383.110232)
		(width 0.1016)
		(layer "F.Cu")
		(net "P5E_CPU1_P1_TX_C_DN<14>")
	)
	(segment
		(start 101.56698 -376.50293)
		(end 101.252782 -376.50293)
		(width 0.1016)
		(layer "F.Cu")
		(net "P5E_CPU1_P1_TX_C_DN<14>")
	)
	(segment
		(start 96.530414 -383.110232)
		(end 96.530414 -383.318004)
		(width 0.1016)
		(layer "F.Cu")
		(net "P5E_CPU1_P1_TX_C_DN<14>")
	)
	(segment
		(start 96.530414 -383.318004)
		(end 96.445832 -383.402586)
		(width 0.1016)
		(layer "F.Cu")
		(net "P5E_CPU1_P1_TX_C_DN<14>")
	)
	(arc
		(start 96.697292 -381.05842)
		(mid 96.504168 -381.347824)
		(end 96.436434 -381.689102)
		(width 0.1016)
		(layer "F.Cu")
		(net "P5E_CPU1_P1_TX_C_DN<14>")
	)
	(segment
		(start 103.283766 -373.866156)
		(end 103.283766 -374.136666)
		(width 0.1016)
		(layer "F.Cu")
		(net "P5E_CPU1_P1_TX_C_DN<13>")
	)
	(segment
		(start 102.63505 -372.75135)
		(end 102.85095 -372.96725)
		(width 0.1016)
		(layer "F.Cu")
		(net "P5E_CPU1_P1_TX_C_DN<13>")
	)
	(segment
		(start 100.88626 -375.485914)
		(end 95.489522 -380.882652)
		(width 0.1016)
		(layer "F.Cu")
		(net "P5E_CPU1_P1_TX_C_DN<13>")
	)
	(segment
		(start 103.048054 -374.706388)
		(end 102.622604 -375.131838)
		(width 0.1016)
		(layer "F.Cu")
		(net "P5E_CPU1_P1_TX_C_DN<13>")
	)
	(segment
		(start 101.609652 -371.18798)
		(end 101.609652 -371.527832)
		(width 0.1016)
		(layer "F.Cu")
		(net "P5E_CPU1_P1_TX_C_DN<13>")
	)
	(segment
		(start 102.85095 -373.125238)
		(end 103.066342 -373.34063)
		(width 0.1016)
		(layer "F.Cu")
		(net "P5E_CPU1_P1_TX_C_DN<13>")
	)
	(segment
		(start 95.452184 -380.972822)
		(end 95.452184 -383.13741)
		(width 0.1016)
		(layer "F.Cu")
		(net "P5E_CPU1_P1_TX_C_DN<13>")
	)
	(segment
		(start 101.86162 -372.135908)
		(end 102.477062 -372.75135)
		(width 0.1016)
		(layer "F.Cu")
		(net "P5E_CPU1_P1_TX_C_DN<13>")
	)
	(segment
		(start 102.184708 -375.31294)
		(end 101.303836 -375.31294)
		(width 0.1016)
		(layer "F.Cu")
		(net "P5E_CPU1_P1_TX_C_DN<13>")
	)
	(segment
		(start 101.609652 -371.527832)
		(end 101.609906 -371.527578)
		(width 0.1016)
		(layer "F.Cu")
		(net "P5E_CPU1_P1_TX_C_DN<13>")
	)
	(segment
		(start 102.85095 -372.96725)
		(end 102.85095 -373.125238)
		(width 0.1016)
		(layer "F.Cu")
		(net "P5E_CPU1_P1_TX_C_DN<13>")
	)
	(segment
		(start 102.477062 -372.75135)
		(end 102.63505 -372.75135)
		(width 0.1016)
		(layer "F.Cu")
		(net "P5E_CPU1_P1_TX_C_DN<13>")
	)
	(segment
		(start 95.545656 -383.230882)
		(end 95.545656 -383.92227)
		(width 0.1016)
		(layer "F.Cu")
		(net "P5E_CPU1_P1_TX_C_DN<13>")
	)
	(segment
		(start 101.958902 -370.83873)
		(end 101.609652 -371.18798)
		(width 0.1016)
		(layer "F.Cu")
		(net "P5E_CPU1_P1_TX_C_DN<13>")
	)
	(segment
		(start 95.452184 -383.13741)
		(end 95.545656 -383.230882)
		(width 0.1016)
		(layer "F.Cu")
		(net "P5E_CPU1_P1_TX_C_DN<13>")
	)
	(arc
		(start 102.622604 -375.131838)
		(mid 102.421666 -375.265915)
		(end 102.184708 -375.31294)
		(width 0.1016)
		(layer "F.Cu")
		(net "P5E_CPU1_P1_TX_C_DN<13>")
	)
	(arc
		(start 103.283766 -374.136666)
		(mid 103.222622 -374.445)
		(end 103.048054 -374.706388)
		(width 0.1016)
		(layer "F.Cu")
		(net "P5E_CPU1_P1_TX_C_DN<13>")
	)
	(arc
		(start 103.066342 -373.34063)
		(mid 103.227337 -373.581759)
		(end 103.283766 -373.866156)
		(width 0.1016)
		(layer "F.Cu")
		(net "P5E_CPU1_P1_TX_C_DN<13>")
	)
	(arc
		(start 101.303836 -375.31294)
		(mid 101.077842 -375.357893)
		(end 100.88626 -375.485914)
		(width 0.1016)
		(layer "F.Cu")
		(net "P5E_CPU1_P1_TX_C_DN<13>")
	)
	(arc
		(start 101.609906 -371.527578)
		(mid 101.675275 -371.856771)
		(end 101.86162 -372.135908)
		(width 0.1016)
		(layer "F.Cu")
		(net "P5E_CPU1_P1_TX_C_DN<13>")
	)
	(arc
		(start 95.489522 -380.882652)
		(mid 95.461879 -380.924022)
		(end 95.452184 -380.972822)
		(width 0.1016)
		(layer "F.Cu")
		(net "P5E_CPU1_P1_TX_C_DN<13>")
	)
	(segment
		(start 94.252288 -380.734062)
		(end 94.252288 -383.13741)
		(width 0.1016)
		(layer "F.Cu")
		(net "P5E_CPU1_P1_TX_C_DN<12>")
	)
	(segment
		(start 99.915726 -373.657368)
		(end 99.915726 -374.563132)
		(width 0.1016)
		(layer "F.Cu")
		(net "P5E_CPU1_P1_TX_C_DN<12>")
	)
	(segment
		(start 99.779836 -374.890284)
		(end 94.476316 -380.194058)
		(width 0.1016)
		(layer "F.Cu")
		(net "P5E_CPU1_P1_TX_C_DN<12>")
	)
	(segment
		(start 99.700334 -373.141494)
		(end 99.700334 -373.299482)
		(width 0.1016)
		(layer "F.Cu")
		(net "P5E_CPU1_P1_TX_C_DN<12>")
	)
	(segment
		(start 98.555302 -370.83873)
		(end 98.206052 -371.18798)
		(width 0.1016)
		(layer "F.Cu")
		(net "P5E_CPU1_P1_TX_C_DN<12>")
	)
	(segment
		(start 99.700334 -373.299482)
		(end 99.815396 -373.414544)
		(width 0.1016)
		(layer "F.Cu")
		(net "P5E_CPU1_P1_TX_C_DN<12>")
	)
	(segment
		(start 94.34576 -383.230882)
		(end 94.34576 -383.92227)
		(width 0.1016)
		(layer "F.Cu")
		(net "P5E_CPU1_P1_TX_C_DN<12>")
	)
	(segment
		(start 98.206052 -371.18798)
		(end 98.206052 -371.5385)
		(width 0.1016)
		(layer "F.Cu")
		(net "P5E_CPU1_P1_TX_C_DN<12>")
	)
	(segment
		(start 98.395282 -371.99443)
		(end 99.326446 -372.925594)
		(width 0.1016)
		(layer "F.Cu")
		(net "P5E_CPU1_P1_TX_C_DN<12>")
	)
	(segment
		(start 99.484434 -372.925594)
		(end 99.700334 -373.141494)
		(width 0.1016)
		(layer "F.Cu")
		(net "P5E_CPU1_P1_TX_C_DN<12>")
	)
	(segment
		(start 99.326446 -372.925594)
		(end 99.484434 -372.925594)
		(width 0.1016)
		(layer "F.Cu")
		(net "P5E_CPU1_P1_TX_C_DN<12>")
	)
	(segment
		(start 94.252288 -383.13741)
		(end 94.34576 -383.230882)
		(width 0.1016)
		(layer "F.Cu")
		(net "P5E_CPU1_P1_TX_C_DN<12>")
	)
	(arc
		(start 99.915726 -374.563132)
		(mid 99.880298 -374.740209)
		(end 99.779836 -374.890284)
		(width 0.1016)
		(layer "F.Cu")
		(net "P5E_CPU1_P1_TX_C_DN<12>")
	)
	(arc
		(start 94.476316 -380.194058)
		(mid 94.310551 -380.44177)
		(end 94.252288 -380.734062)
		(width 0.1016)
		(layer "F.Cu")
		(net "P5E_CPU1_P1_TX_C_DN<12>")
	)
	(arc
		(start 98.206052 -371.5385)
		(mid 98.255343 -371.78527)
		(end 98.395282 -371.99443)
		(width 0.1016)
		(layer "F.Cu")
		(net "P5E_CPU1_P1_TX_C_DN<12>")
	)
	(arc
		(start 99.815396 -373.414544)
		(mid 99.8897 -373.525982)
		(end 99.915726 -373.657368)
		(width 0.1016)
		(layer "F.Cu")
		(net "P5E_CPU1_P1_TX_C_DN<12>")
	)
	(segment
		(start 96.504252 -375.021856)
		(end 96.616012 -375.133616)
		(width 0.1016)
		(layer "F.Cu")
		(net "P5E_CPU1_P1_TX_C_DN<11>")
	)
	(segment
		(start 96.616012 -375.133616)
		(end 96.616012 -375.438416)
		(width 0.1016)
		(layer "F.Cu")
		(net "P5E_CPU1_P1_TX_C_DN<11>")
	)
	(segment
		(start 93.052138 -379.884178)
		(end 93.052138 -383.13741)
		(width 0.1016)
		(layer "F.Cu")
		(net "P5E_CPU1_P1_TX_C_DN<11>")
	)
	(segment
		(start 96.504252 -373.65178)
		(end 96.504252 -375.021856)
		(width 0.1016)
		(layer "F.Cu")
		(net "P5E_CPU1_P1_TX_C_DN<11>")
	)
	(segment
		(start 93.145864 -383.231136)
		(end 93.145864 -383.92227)
		(width 0.1016)
		(layer "F.Cu")
		(net "P5E_CPU1_P1_TX_C_DN<11>")
	)
	(segment
		(start 96.853502 -373.30253)
		(end 96.504252 -373.65178)
		(width 0.1016)
		(layer "F.Cu")
		(net "P5E_CPU1_P1_TX_C_DN<11>")
	)
	(segment
		(start 96.616012 -375.438416)
		(end 96.504252 -375.550176)
		(width 0.1016)
		(layer "F.Cu")
		(net "P5E_CPU1_P1_TX_C_DN<11>")
	)
	(segment
		(start 96.504252 -375.550176)
		(end 96.504252 -376.236484)
		(width 0.1016)
		(layer "F.Cu")
		(net "P5E_CPU1_P1_TX_C_DN<11>")
	)
	(segment
		(start 93.052138 -383.13741)
		(end 93.145864 -383.231136)
		(width 0.1016)
		(layer "F.Cu")
		(net "P5E_CPU1_P1_TX_C_DN<11>")
	)
	(segment
		(start 96.403922 -376.479562)
		(end 93.089476 -379.794008)
		(width 0.1016)
		(layer "F.Cu")
		(net "P5E_CPU1_P1_TX_C_DN<11>")
	)
	(arc
		(start 96.504252 -376.236484)
		(mid 96.478293 -376.368022)
		(end 96.403922 -376.479562)
		(width 0.1016)
		(layer "F.Cu")
		(net "P5E_CPU1_P1_TX_C_DN<11>")
	)
	(arc
		(start 93.089476 -379.794008)
		(mid 93.061833 -379.835378)
		(end 93.052138 -379.884178)
		(width 0.1016)
		(layer "F.Cu")
		(net "P5E_CPU1_P1_TX_C_DN<11>")
	)
	(segment
		(start 92.226384 -378.635768)
		(end 92.068396 -378.635768)
		(width 0.1016)
		(layer "F.Cu")
		(net "P5E_CPU1_P1_TX_C_DN<10>")
	)
	(segment
		(start 94.701106 -376.44578)
		(end 93.719396 -377.427236)
		(width 0.1016)
		(layer "F.Cu")
		(net "P5E_CPU1_P1_TX_C_DN<10>")
	)
	(segment
		(start 91.852242 -378.904754)
		(end 91.852242 -383.13741)
		(width 0.1016)
		(layer "F.Cu")
		(net "P5E_CPU1_P1_TX_C_DN<10>")
	)
	(segment
		(start 91.945714 -383.230882)
		(end 91.945714 -383.92227)
		(width 0.1016)
		(layer "F.Cu")
		(net "P5E_CPU1_P1_TX_C_DN<10>")
	)
	(segment
		(start 93.121734 -377.58243)
		(end 92.44203 -378.262388)
		(width 0.1016)
		(layer "F.Cu")
		(net "P5E_CPU1_P1_TX_C_DN<10>")
	)
	(segment
		(start 92.068396 -378.635768)
		(end 91.88958 -378.814584)
		(width 0.1016)
		(layer "F.Cu")
		(net "P5E_CPU1_P1_TX_C_DN<10>")
	)
	(segment
		(start 92.44203 -378.262388)
		(end 92.44203 -378.420122)
		(width 0.1016)
		(layer "F.Cu")
		(net "P5E_CPU1_P1_TX_C_DN<10>")
	)
	(segment
		(start 95.151702 -375.76633)
		(end 94.801436 -376.116596)
		(width 0.1016)
		(layer "F.Cu")
		(net "P5E_CPU1_P1_TX_C_DN<10>")
	)
	(segment
		(start 94.801436 -376.116596)
		(end 94.801436 -376.202702)
		(width 0.1016)
		(layer "F.Cu")
		(net "P5E_CPU1_P1_TX_C_DN<10>")
	)
	(segment
		(start 91.852242 -383.13741)
		(end 91.945714 -383.230882)
		(width 0.1016)
		(layer "F.Cu")
		(net "P5E_CPU1_P1_TX_C_DN<10>")
	)
	(segment
		(start 93.452188 -377.537472)
		(end 93.229938 -377.537472)
		(width 0.1016)
		(layer "F.Cu")
		(net "P5E_CPU1_P1_TX_C_DN<10>")
	)
	(segment
		(start 92.44203 -378.420122)
		(end 92.226384 -378.635768)
		(width 0.1016)
		(layer "F.Cu")
		(net "P5E_CPU1_P1_TX_C_DN<10>")
	)
	(arc
		(start 94.801436 -376.202702)
		(mid 94.775477 -376.33424)
		(end 94.701106 -376.44578)
		(width 0.1016)
		(layer "F.Cu")
		(net "P5E_CPU1_P1_TX_C_DN<10>")
	)
	(arc
		(start 93.719396 -377.427236)
		(mid 93.596756 -377.508932)
		(end 93.452188 -377.537472)
		(width 0.1016)
		(layer "F.Cu")
		(net "P5E_CPU1_P1_TX_C_DN<10>")
	)
	(arc
		(start 93.229938 -377.537472)
		(mid 93.171354 -377.549161)
		(end 93.121734 -377.58243)
		(width 0.1016)
		(layer "F.Cu")
		(net "P5E_CPU1_P1_TX_C_DN<10>")
	)
	(arc
		(start 91.88958 -378.814584)
		(mid 91.861937 -378.855954)
		(end 91.852242 -378.904754)
		(width 0.1016)
		(layer "F.Cu")
		(net "P5E_CPU1_P1_TX_C_DN<10>")
	)
	(segment
		(start 75.76185 -381.48006)
		(end 76.109322 -381.827532)
		(width 0.1016)
		(layer "F.Cu")
		(net "P5E_CPU1_P1_TX_C_DN<0>")
	)
	(segment
		(start 79.945738 -383.230882)
		(end 79.945738 -383.92227)
		(width 0.1016)
		(layer "F.Cu")
		(net "P5E_CPU1_P1_TX_C_DN<0>")
	)
	(segment
		(start 76.109322 -381.827532)
		(end 78.280514 -381.827532)
		(width 0.1016)
		(layer "F.Cu")
		(net "P5E_CPU1_P1_TX_C_DN<0>")
	)
	(segment
		(start 79.448152 -382.32207)
		(end 79.852266 -382.727708)
		(width 0.1016)
		(layer "F.Cu")
		(net "P5E_CPU1_P1_TX_C_DN<0>")
	)
	(segment
		(start 79.852266 -383.13741)
		(end 79.945738 -383.230882)
		(width 0.1016)
		(layer "F.Cu")
		(net "P5E_CPU1_P1_TX_C_DN<0>")
	)
	(segment
		(start 78.560676 -381.883158)
		(end 79.165704 -382.133094)
		(width 0.1016)
		(layer "F.Cu")
		(net "P5E_CPU1_P1_TX_C_DN<0>")
	)
	(segment
		(start 79.852266 -382.727708)
		(end 79.852266 -383.13741)
		(width 0.1016)
		(layer "F.Cu")
		(net "P5E_CPU1_P1_TX_C_DN<0>")
	)
	(arc
		(start 79.165704 -382.133094)
		(mid 79.316336 -382.213523)
		(end 79.448152 -382.32207)
		(width 0.1016)
		(layer "F.Cu")
		(net "P5E_CPU1_P1_TX_C_DN<0>")
	)
	(arc
		(start 78.280514 -381.827532)
		(mid 78.423333 -381.841564)
		(end 78.560676 -381.883158)
		(width 0.1016)
		(layer "F.Cu")
		(net "P5E_CPU1_P1_TX_C_DN<0>")
	)
	(segment
		(start 58.655204 -371.18798)
		(end 58.655204 -371.527578)
		(width 0.1016)
		(layer "F.Cu")
		(net "P5E_CPU1_P0_TX_C_DP<9>")
	)
	(segment
		(start 57.61609 -383.50571)
		(end 57.707276 -383.596896)
		(width 0.1016)
		(layer "F.Cu")
		(net "P5E_CPU1_P0_TX_C_DP<9>")
	)
	(segment
		(start 57.908698 -377.723908)
		(end 57.908698 -382.942592)
		(width 0.1016)
		(layer "F.Cu")
		(net "P5E_CPU1_P0_TX_C_DP<9>")
	)
	(segment
		(start 60.262262 -375.166382)
		(end 58.052462 -377.376182)
		(width 0.1016)
		(layer "F.Cu")
		(net "P5E_CPU1_P0_TX_C_DP<9>")
	)
	(segment
		(start 57.707276 -383.596896)
		(end 57.841642 -383.596896)
		(width 0.1016)
		(layer "F.Cu")
		(net "P5E_CPU1_P0_TX_C_DP<9>")
	)
	(segment
		(start 60.333636 -373.933466)
		(end 60.333636 -374.994932)
		(width 0.1016)
		(layer "F.Cu")
		(net "P5E_CPU1_P0_TX_C_DP<9>")
	)
	(segment
		(start 57.908698 -382.942592)
		(end 57.61609 -383.2352)
		(width 0.1016)
		(layer "F.Cu")
		(net "P5E_CPU1_P0_TX_C_DP<9>")
	)
	(segment
		(start 57.61609 -383.2352)
		(end 57.61609 -383.50571)
		(width 0.1016)
		(layer "F.Cu")
		(net "P5E_CPU1_P0_TX_C_DP<9>")
	)
	(segment
		(start 57.841642 -383.596896)
		(end 57.918096 -383.520442)
		(width 0.1016)
		(layer "F.Cu")
		(net "P5E_CPU1_P0_TX_C_DP<9>")
	)
	(segment
		(start 58.970672 -372.28907)
		(end 60.133738 -373.452136)
		(width 0.1016)
		(layer "F.Cu")
		(net "P5E_CPU1_P0_TX_C_DP<9>")
	)
	(segment
		(start 57.918096 -383.520442)
		(end 57.918096 -383.402586)
		(width 0.1016)
		(layer "F.Cu")
		(net "P5E_CPU1_P0_TX_C_DP<9>")
	)
	(segment
		(start 58.305954 -370.83873)
		(end 58.655204 -371.18798)
		(width 0.1016)
		(layer "F.Cu")
		(net "P5E_CPU1_P0_TX_C_DP<9>")
	)
	(arc
		(start 60.133738 -373.452136)
		(mid 60.281599 -373.672913)
		(end 60.333636 -373.933466)
		(width 0.1016)
		(layer "F.Cu")
		(net "P5E_CPU1_P0_TX_C_DP<9>")
	)
	(arc
		(start 58.052462 -377.376182)
		(mid 57.946028 -377.53575)
		(end 57.908698 -377.723908)
		(width 0.1016)
		(layer "F.Cu")
		(net "P5E_CPU1_P0_TX_C_DP<9>")
	)
	(arc
		(start 60.333636 -374.994932)
		(mid 60.314971 -375.087735)
		(end 60.262262 -375.166382)
		(width 0.1016)
		(layer "F.Cu")
		(net "P5E_CPU1_P0_TX_C_DP<9>")
	)
	(arc
		(start 58.655204 -371.527578)
		(mid 58.737236 -371.939688)
		(end 58.970672 -372.28907)
		(width 0.1016)
		(layer "F.Cu")
		(net "P5E_CPU1_P0_TX_C_DP<9>")
	)
	(segment
		(start 56.41594 -383.50571)
		(end 56.507126 -383.596896)
		(width 0.1016)
		(layer "F.Cu")
		(net "P5E_CPU1_P0_TX_C_DP<8>")
	)
	(segment
		(start 56.717946 -383.520442)
		(end 56.717946 -383.402586)
		(width 0.1016)
		(layer "F.Cu")
		(net "P5E_CPU1_P0_TX_C_DP<8>")
	)
	(segment
		(start 56.41594 -383.2352)
		(end 56.41594 -383.50571)
		(width 0.1016)
		(layer "F.Cu")
		(net "P5E_CPU1_P0_TX_C_DP<8>")
	)
	(segment
		(start 56.708548 -382.942592)
		(end 56.41594 -383.2352)
		(width 0.1016)
		(layer "F.Cu")
		(net "P5E_CPU1_P0_TX_C_DP<8>")
	)
	(segment
		(start 56.507126 -383.596896)
		(end 56.641492 -383.596896)
		(width 0.1016)
		(layer "F.Cu")
		(net "P5E_CPU1_P0_TX_C_DP<8>")
	)
	(segment
		(start 56.708548 -377.31827)
		(end 56.708548 -382.942592)
		(width 0.1016)
		(layer "F.Cu")
		(net "P5E_CPU1_P0_TX_C_DP<8>")
	)
	(segment
		(start 56.604154 -373.30253)
		(end 56.905906 -373.604282)
		(width 0.1016)
		(layer "F.Cu")
		(net "P5E_CPU1_P0_TX_C_DP<8>")
	)
	(segment
		(start 56.953404 -373.71909)
		(end 56.953404 -376.61723)
		(width 0.1016)
		(layer "F.Cu")
		(net "P5E_CPU1_P0_TX_C_DP<8>")
	)
	(segment
		(start 56.641492 -383.596896)
		(end 56.717946 -383.520442)
		(width 0.1016)
		(layer "F.Cu")
		(net "P5E_CPU1_P0_TX_C_DP<8>")
	)
	(arc
		(start 56.953404 -376.61723)
		(mid 56.929188 -376.76075)
		(end 56.859424 -376.888502)
		(width 0.1016)
		(layer "F.Cu")
		(net "P5E_CPU1_P0_TX_C_DP<8>")
	)
	(arc
		(start 56.905906 -373.604282)
		(mid 56.941048 -373.656971)
		(end 56.953404 -373.71909)
		(width 0.1016)
		(layer "F.Cu")
		(net "P5E_CPU1_P0_TX_C_DP<8>")
	)
	(arc
		(start 56.766206 -377.043696)
		(mid 56.723052 -377.177976)
		(end 56.708548 -377.31827)
		(width 0.1016)
		(layer "F.Cu")
		(net "P5E_CPU1_P0_TX_C_DP<8>")
	)
	(arc
		(start 56.859424 -376.888502)
		(mid 56.807928 -376.963163)
		(end 56.766206 -377.043696)
		(width 0.1016)
		(layer "F.Cu")
		(net "P5E_CPU1_P0_TX_C_DP<8>")
	)
	(segment
		(start 54.902354 -375.76633)
		(end 55.204106 -376.068082)
		(width 0.1016)
		(layer "F.Cu")
		(net "P5E_CPU1_P0_TX_C_DP<7>")
	)
	(segment
		(start 55.216044 -383.50571)
		(end 55.30723 -383.596896)
		(width 0.1016)
		(layer "F.Cu")
		(net "P5E_CPU1_P0_TX_C_DP<7>")
	)
	(segment
		(start 55.508652 -382.942592)
		(end 55.216044 -383.2352)
		(width 0.1016)
		(layer "F.Cu")
		(net "P5E_CPU1_P0_TX_C_DP<7>")
	)
	(segment
		(start 55.216044 -383.2352)
		(end 55.216044 -383.50571)
		(width 0.1016)
		(layer "F.Cu")
		(net "P5E_CPU1_P0_TX_C_DP<7>")
	)
	(segment
		(start 55.490872 -378.664216)
		(end 55.508652 -382.942592)
		(width 0.1016)
		(layer "F.Cu")
		(net "P5E_CPU1_P0_TX_C_DP<7>")
	)
	(segment
		(start 55.30723 -383.596896)
		(end 55.441596 -383.596896)
		(width 0.1016)
		(layer "F.Cu")
		(net "P5E_CPU1_P0_TX_C_DP<7>")
	)
	(segment
		(start 55.251604 -376.18289)
		(end 55.251604 -377.907804)
		(width 0.1016)
		(layer "F.Cu")
		(net "P5E_CPU1_P0_TX_C_DP<7>")
	)
	(segment
		(start 55.51805 -383.520442)
		(end 55.51805 -383.402586)
		(width 0.1016)
		(layer "F.Cu")
		(net "P5E_CPU1_P0_TX_C_DP<7>")
	)
	(segment
		(start 55.441596 -383.596896)
		(end 55.51805 -383.520442)
		(width 0.1016)
		(layer "F.Cu")
		(net "P5E_CPU1_P0_TX_C_DP<7>")
	)
	(arc
		(start 55.204106 -376.068082)
		(mid 55.239248 -376.120771)
		(end 55.251604 -376.18289)
		(width 0.1016)
		(layer "F.Cu")
		(net "P5E_CPU1_P0_TX_C_DP<7>")
	)
	(arc
		(start 55.410354 -378.410978)
		(mid 55.469916 -378.531463)
		(end 55.490872 -378.664216)
		(width 0.1016)
		(layer "F.Cu")
		(net "P5E_CPU1_P0_TX_C_DP<7>")
	)
	(arc
		(start 55.251604 -377.907804)
		(mid 55.292282 -378.171596)
		(end 55.410354 -378.410978)
		(width 0.1016)
		(layer "F.Cu")
		(net "P5E_CPU1_P0_TX_C_DP<7>")
	)
	(segment
		(start 53.709316 -378.733558)
		(end 53.745892 -378.823474)
		(width 0.1016)
		(layer "F.Cu")
		(net "P5E_CPU1_P0_TX_C_DP<6>")
	)
	(segment
		(start 54.3179 -383.520442)
		(end 54.3179 -383.402586)
		(width 0.1016)
		(layer "F.Cu")
		(net "P5E_CPU1_P0_TX_C_DP<6>")
	)
	(segment
		(start 54.015894 -383.50571)
		(end 54.10708 -383.596896)
		(width 0.1016)
		(layer "F.Cu")
		(net "P5E_CPU1_P0_TX_C_DP<6>")
	)
	(segment
		(start 51.848004 -371.18798)
		(end 51.848004 -371.48008)
		(width 0.1016)
		(layer "F.Cu")
		(net "P5E_CPU1_P0_TX_C_DP<6>")
	)
	(segment
		(start 52.174394 -372.267734)
		(end 53.406802 -373.500142)
		(width 0.1016)
		(layer "F.Cu")
		(net "P5E_CPU1_P0_TX_C_DP<6>")
	)
	(segment
		(start 54.308502 -382.942592)
		(end 54.015894 -383.2352)
		(width 0.1016)
		(layer "F.Cu")
		(net "P5E_CPU1_P0_TX_C_DP<6>")
	)
	(segment
		(start 54.015894 -383.2352)
		(end 54.015894 -383.50571)
		(width 0.1016)
		(layer "F.Cu")
		(net "P5E_CPU1_P0_TX_C_DP<6>")
	)
	(segment
		(start 54.10708 -383.596896)
		(end 54.241446 -383.596896)
		(width 0.1016)
		(layer "F.Cu")
		(net "P5E_CPU1_P0_TX_C_DP<6>")
	)
	(segment
		(start 51.498754 -370.83873)
		(end 51.848004 -371.18798)
		(width 0.1016)
		(layer "F.Cu")
		(net "P5E_CPU1_P0_TX_C_DP<6>")
	)
	(segment
		(start 54.308502 -381.694436)
		(end 54.308502 -382.942592)
		(width 0.1016)
		(layer "F.Cu")
		(net "P5E_CPU1_P0_TX_C_DP<6>")
	)
	(segment
		(start 54.241446 -383.596896)
		(end 54.3179 -383.520442)
		(width 0.1016)
		(layer "F.Cu")
		(net "P5E_CPU1_P0_TX_C_DP<6>")
	)
	(segment
		(start 53.56733 -373.886984)
		(end 53.56733 -378.006102)
		(width 0.1016)
		(layer "F.Cu")
		(net "P5E_CPU1_P0_TX_C_DP<6>")
	)
	(arc
		(start 53.406802 -373.500142)
		(mid 53.525559 -373.677597)
		(end 53.56733 -373.886984)
		(width 0.1016)
		(layer "F.Cu")
		(net "P5E_CPU1_P0_TX_C_DP<6>")
	)
	(arc
		(start 53.56733 -378.006102)
		(mid 53.603135 -378.376698)
		(end 53.709316 -378.733558)
		(width 0.1016)
		(layer "F.Cu")
		(net "P5E_CPU1_P0_TX_C_DP<6>")
	)
	(arc
		(start 53.745892 -378.823474)
		(mid 54.166461 -380.231663)
		(end 54.308502 -381.694436)
		(width 0.1016)
		(layer "F.Cu")
		(net "P5E_CPU1_P0_TX_C_DP<6>")
	)
	(arc
		(start 51.848004 -371.48008)
		(mid 51.932873 -371.906367)
		(end 52.174394 -372.267734)
		(width 0.1016)
		(layer "F.Cu")
		(net "P5E_CPU1_P0_TX_C_DP<6>")
	)
	(segment
		(start 50.146204 -373.65178)
		(end 50.146204 -375.362216)
		(width 0.1016)
		(layer "F.Cu")
		(net "P5E_CPU1_P0_TX_C_DP<5>")
	)
	(segment
		(start 52.907184 -383.596896)
		(end 53.04155 -383.596896)
		(width 0.1016)
		(layer "F.Cu")
		(net "P5E_CPU1_P0_TX_C_DP<5>")
	)
	(segment
		(start 50.510186 -376.561858)
		(end 52.440078 -379.448822)
		(width 0.1016)
		(layer "F.Cu")
		(net "P5E_CPU1_P0_TX_C_DP<5>")
	)
	(segment
		(start 53.108606 -381.651764)
		(end 53.108606 -382.942592)
		(width 0.1016)
		(layer "F.Cu")
		(net "P5E_CPU1_P0_TX_C_DP<5>")
	)
	(segment
		(start 53.108606 -382.942592)
		(end 52.815998 -383.2352)
		(width 0.1016)
		(layer "F.Cu")
		(net "P5E_CPU1_P0_TX_C_DP<5>")
	)
	(segment
		(start 52.815998 -383.50571)
		(end 52.907184 -383.596896)
		(width 0.1016)
		(layer "F.Cu")
		(net "P5E_CPU1_P0_TX_C_DP<5>")
	)
	(segment
		(start 49.796954 -373.30253)
		(end 50.146204 -373.65178)
		(width 0.1016)
		(layer "F.Cu")
		(net "P5E_CPU1_P0_TX_C_DP<5>")
	)
	(segment
		(start 53.04155 -383.596896)
		(end 53.118004 -383.520442)
		(width 0.1016)
		(layer "F.Cu")
		(net "P5E_CPU1_P0_TX_C_DP<5>")
	)
	(segment
		(start 53.118004 -383.520442)
		(end 53.118004 -383.402586)
		(width 0.1016)
		(layer "F.Cu")
		(net "P5E_CPU1_P0_TX_C_DP<5>")
	)
	(segment
		(start 52.815998 -383.2352)
		(end 52.815998 -383.50571)
		(width 0.1016)
		(layer "F.Cu")
		(net "P5E_CPU1_P0_TX_C_DP<5>")
	)
	(arc
		(start 50.146204 -375.362216)
		(mid 50.239209 -375.989034)
		(end 50.510186 -376.561858)
		(width 0.1016)
		(layer "F.Cu")
		(net "P5E_CPU1_P0_TX_C_DP<5>")
	)
	(arc
		(start 52.440078 -379.448822)
		(mid 52.937784 -380.500692)
		(end 53.108606 -381.651764)
		(width 0.1016)
		(layer "F.Cu")
		(net "P5E_CPU1_P0_TX_C_DP<5>")
	)
	(segment
		(start 48.095154 -375.76633)
		(end 48.444404 -376.11558)
		(width 0.1016)
		(layer "F.Cu")
		(net "P5E_CPU1_P0_TX_C_DP<4>")
	)
	(segment
		(start 51.90871 -382.942592)
		(end 51.616102 -383.2352)
		(width 0.1016)
		(layer "F.Cu")
		(net "P5E_CPU1_P0_TX_C_DP<4>")
	)
	(segment
		(start 51.616102 -383.50571)
		(end 51.707288 -383.596896)
		(width 0.1016)
		(layer "F.Cu")
		(net "P5E_CPU1_P0_TX_C_DP<4>")
	)
	(segment
		(start 51.918108 -383.520442)
		(end 51.918108 -383.402586)
		(width 0.1016)
		(layer "F.Cu")
		(net "P5E_CPU1_P0_TX_C_DP<4>")
	)
	(segment
		(start 48.688752 -376.921776)
		(end 51.576732 -380.440438)
		(width 0.1016)
		(layer "F.Cu")
		(net "P5E_CPU1_P0_TX_C_DP<4>")
	)
	(segment
		(start 51.90871 -381.572008)
		(end 51.90871 -382.942592)
		(width 0.1016)
		(layer "F.Cu")
		(net "P5E_CPU1_P0_TX_C_DP<4>")
	)
	(segment
		(start 48.444404 -376.11558)
		(end 48.444404 -376.33275)
		(width 0.1016)
		(layer "F.Cu")
		(net "P5E_CPU1_P0_TX_C_DP<4>")
	)
	(segment
		(start 51.616102 -383.2352)
		(end 51.616102 -383.50571)
		(width 0.1016)
		(layer "F.Cu")
		(net "P5E_CPU1_P0_TX_C_DP<4>")
	)
	(segment
		(start 51.841654 -383.596896)
		(end 51.918108 -383.520442)
		(width 0.1016)
		(layer "F.Cu")
		(net "P5E_CPU1_P0_TX_C_DP<4>")
	)
	(segment
		(start 51.707288 -383.596896)
		(end 51.841654 -383.596896)
		(width 0.1016)
		(layer "F.Cu")
		(net "P5E_CPU1_P0_TX_C_DP<4>")
	)
	(segment
		(start 48.444404 -376.33275)
		(end 48.688752 -376.921776)
		(width 0.1016)
		(layer "F.Cu")
		(net "P5E_CPU1_P0_TX_C_DP<4>")
	)
	(arc
		(start 51.576732 -380.440438)
		(mid 51.823861 -380.982422)
		(end 51.90871 -381.572008)
		(width 0.1016)
		(layer "F.Cu")
		(net "P5E_CPU1_P0_TX_C_DP<4>")
	)
	(segment
		(start 46.413166 -373.29491)
		(end 46.674278 -373.556022)
		(width 0.1016)
		(layer "F.Cu")
		(net "P5E_CPU1_P0_TX_C_DP<3>")
	)
	(segment
		(start 50.70856 -382.942592)
		(end 50.415952 -383.2352)
		(width 0.1016)
		(layer "F.Cu")
		(net "P5E_CPU1_P0_TX_C_DP<3>")
	)
	(segment
		(start 47.947072 -378.064014)
		(end 50.590196 -381.284734)
		(width 0.1016)
		(layer "F.Cu")
		(net "P5E_CPU1_P0_TX_C_DP<3>")
	)
	(segment
		(start 45.288454 -372.170198)
		(end 46.413166 -373.294656)
		(width 0.1016)
		(layer "F.Cu")
		(net "P5E_CPU1_P0_TX_C_DP<3>")
	)
	(segment
		(start 50.70856 -381.61468)
		(end 50.70856 -382.942592)
		(width 0.1016)
		(layer "F.Cu")
		(net "P5E_CPU1_P0_TX_C_DP<3>")
	)
	(segment
		(start 46.81601 -375.534682)
		(end 47.676054 -377.61164)
		(width 0.1016)
		(layer "F.Cu")
		(net "P5E_CPU1_P0_TX_C_DP<3>")
	)
	(segment
		(start 50.415952 -383.2352)
		(end 50.415952 -383.50571)
		(width 0.1016)
		(layer "F.Cu")
		(net "P5E_CPU1_P0_TX_C_DP<3>")
	)
	(segment
		(start 46.413166 -373.294656)
		(end 46.413166 -373.29491)
		(width 0.1016)
		(layer "F.Cu")
		(net "P5E_CPU1_P0_TX_C_DP<3>")
	)
	(segment
		(start 46.750478 -373.738902)
		(end 46.750478 -375.203466)
		(width 0.1016)
		(layer "F.Cu")
		(net "P5E_CPU1_P0_TX_C_DP<3>")
	)
	(segment
		(start 50.717958 -383.520442)
		(end 50.717958 -383.402586)
		(width 0.1016)
		(layer "F.Cu")
		(net "P5E_CPU1_P0_TX_C_DP<3>")
	)
	(segment
		(start 44.691554 -370.83873)
		(end 45.040804 -371.18798)
		(width 0.1016)
		(layer "F.Cu")
		(net "P5E_CPU1_P0_TX_C_DP<3>")
	)
	(segment
		(start 50.507138 -383.596896)
		(end 50.641504 -383.596896)
		(width 0.1016)
		(layer "F.Cu")
		(net "P5E_CPU1_P0_TX_C_DP<3>")
	)
	(segment
		(start 50.641504 -383.596896)
		(end 50.717958 -383.520442)
		(width 0.1016)
		(layer "F.Cu")
		(net "P5E_CPU1_P0_TX_C_DP<3>")
	)
	(segment
		(start 47.676054 -377.61164)
		(end 47.947072 -378.064014)
		(width 0.1016)
		(layer "F.Cu")
		(net "P5E_CPU1_P0_TX_C_DP<3>")
	)
	(segment
		(start 45.040804 -371.18798)
		(end 45.040804 -371.57152)
		(width 0.1016)
		(layer "F.Cu")
		(net "P5E_CPU1_P0_TX_C_DP<3>")
	)
	(segment
		(start 50.415952 -383.50571)
		(end 50.507138 -383.596896)
		(width 0.1016)
		(layer "F.Cu")
		(net "P5E_CPU1_P0_TX_C_DP<3>")
	)
	(arc
		(start 46.750478 -375.203466)
		(mid 46.766946 -375.372298)
		(end 46.81601 -375.534682)
		(width 0.1016)
		(layer "F.Cu")
		(net "P5E_CPU1_P0_TX_C_DP<3>")
	)
	(arc
		(start 45.040804 -371.57152)
		(mid 45.105061 -371.895503)
		(end 45.288454 -372.170198)
		(width 0.1016)
		(layer "F.Cu")
		(net "P5E_CPU1_P0_TX_C_DP<3>")
	)
	(arc
		(start 50.590196 -381.284734)
		(mid 50.678053 -381.439418)
		(end 50.70856 -381.61468)
		(width 0.1016)
		(layer "F.Cu")
		(net "P5E_CPU1_P0_TX_C_DP<3>")
	)
	(arc
		(start 46.674278 -373.556022)
		(mid 46.730616 -373.639869)
		(end 46.750478 -373.738902)
		(width 0.1016)
		(layer "F.Cu")
		(net "P5E_CPU1_P0_TX_C_DP<3>")
	)
	(segment
		(start 45.988986 -376.682508)
		(end 46.710854 -378.425456)
		(width 0.1016)
		(layer "F.Cu")
		(net "P5E_CPU1_P0_TX_C_DP<2>")
	)
	(segment
		(start 49.216056 -383.2352)
		(end 49.216056 -383.50571)
		(width 0.1016)
		(layer "F.Cu")
		(net "P5E_CPU1_P0_TX_C_DP<2>")
	)
	(segment
		(start 49.508664 -382.942592)
		(end 49.216056 -383.2352)
		(width 0.1016)
		(layer "F.Cu")
		(net "P5E_CPU1_P0_TX_C_DP<2>")
	)
	(segment
		(start 43.339004 -373.65178)
		(end 43.339004 -374.282208)
		(width 0.1016)
		(layer "F.Cu")
		(net "P5E_CPU1_P0_TX_C_DP<2>")
	)
	(segment
		(start 49.508664 -382.22047)
		(end 49.508664 -382.942592)
		(width 0.1016)
		(layer "F.Cu")
		(net "P5E_CPU1_P0_TX_C_DP<2>")
	)
	(segment
		(start 47.131224 -379.057154)
		(end 49.337468 -381.742696)
		(width 0.1016)
		(layer "F.Cu")
		(net "P5E_CPU1_P0_TX_C_DP<2>")
	)
	(segment
		(start 42.989754 -373.30253)
		(end 43.339004 -373.65178)
		(width 0.1016)
		(layer "F.Cu")
		(net "P5E_CPU1_P0_TX_C_DP<2>")
	)
	(segment
		(start 44.065698 -375.2342)
		(end 44.980606 -375.613168)
		(width 0.1016)
		(layer "F.Cu")
		(net "P5E_CPU1_P0_TX_C_DP<2>")
	)
	(segment
		(start 49.441608 -383.596896)
		(end 49.518062 -383.520442)
		(width 0.1016)
		(layer "F.Cu")
		(net "P5E_CPU1_P0_TX_C_DP<2>")
	)
	(segment
		(start 49.307242 -383.596896)
		(end 49.441608 -383.596896)
		(width 0.1016)
		(layer "F.Cu")
		(net "P5E_CPU1_P0_TX_C_DP<2>")
	)
	(segment
		(start 49.518062 -383.520442)
		(end 49.518062 -383.402586)
		(width 0.1016)
		(layer "F.Cu")
		(net "P5E_CPU1_P0_TX_C_DP<2>")
	)
	(segment
		(start 43.596814 -374.904762)
		(end 43.64482 -374.952768)
		(width 0.1016)
		(layer "F.Cu")
		(net "P5E_CPU1_P0_TX_C_DP<2>")
	)
	(segment
		(start 45.031914 -375.647458)
		(end 45.831506 -376.44705)
		(width 0.1016)
		(layer "F.Cu")
		(net "P5E_CPU1_P0_TX_C_DP<2>")
	)
	(segment
		(start 46.710854 -378.425456)
		(end 46.853348 -378.662692)
		(width 0.1016)
		(layer "F.Cu")
		(net "P5E_CPU1_P0_TX_C_DP<2>")
	)
	(segment
		(start 49.216056 -383.50571)
		(end 49.307242 -383.596896)
		(width 0.1016)
		(layer "F.Cu")
		(net "P5E_CPU1_P0_TX_C_DP<2>")
	)
	(arc
		(start 43.339004 -374.282208)
		(mid 43.406003 -374.619123)
		(end 43.596814 -374.904762)
		(width 0.1016)
		(layer "F.Cu")
		(net "P5E_CPU1_P0_TX_C_DP<2>")
	)
	(arc
		(start 46.853348 -378.662692)
		(mid 46.98504 -378.865028)
		(end 47.131224 -379.057154)
		(width 0.1016)
		(layer "F.Cu")
		(net "P5E_CPU1_P0_TX_C_DP<2>")
	)
	(arc
		(start 45.831506 -376.44705)
		(mid 45.921868 -376.557008)
		(end 45.988986 -376.682508)
		(width 0.1016)
		(layer "F.Cu")
		(net "P5E_CPU1_P0_TX_C_DP<2>")
	)
	(arc
		(start 49.337468 -381.742696)
		(mid 49.46452 -381.966722)
		(end 49.508664 -382.22047)
		(width 0.1016)
		(layer "F.Cu")
		(net "P5E_CPU1_P0_TX_C_DP<2>")
	)
	(arc
		(start 44.980606 -375.613168)
		(mid 45.007954 -375.627779)
		(end 45.031914 -375.647458)
		(width 0.1016)
		(layer "F.Cu")
		(net "P5E_CPU1_P0_TX_C_DP<2>")
	)
	(arc
		(start 43.64482 -374.952768)
		(mid 43.841404 -375.114205)
		(end 44.065698 -375.2342)
		(width 0.1016)
		(layer "F.Cu")
		(net "P5E_CPU1_P0_TX_C_DP<2>")
	)
	(segment
		(start 48.524414 -383.13741)
		(end 48.617886 -383.230882)
		(width 0.1016)
		(layer "F.Cu")
		(net "P5E_CPU1_P0_TX_C_DP<1>")
	)
	(segment
		(start 46.38421 -379.794262)
		(end 46.498002 -379.964442)
		(width 0.1016)
		(layer "F.Cu")
		(net "P5E_CPU1_P0_TX_C_DP<1>")
	)
	(segment
		(start 48.401224 -382.21412)
		(end 48.524414 -382.511808)
		(width 0.1016)
		(layer "F.Cu")
		(net "P5E_CPU1_P0_TX_C_DP<1>")
	)
	(segment
		(start 46.618906 -380.111254)
		(end 47.229522 -380.722124)
		(width 0.1016)
		(layer "F.Cu")
		(net "P5E_CPU1_P0_TX_C_DP<1>")
	)
	(segment
		(start 44.679108 -376.679968)
		(end 45.005244 -377.006104)
		(width 0.1016)
		(layer "F.Cu")
		(net "P5E_CPU1_P0_TX_C_DP<1>")
	)
	(segment
		(start 46.090332 -379.354588)
		(end 46.090586 -379.354588)
		(width 0.1016)
		(layer "F.Cu")
		(net "P5E_CPU1_P0_TX_C_DP<1>")
	)
	(segment
		(start 45.933106 -379.118876)
		(end 46.090332 -379.354588)
		(width 0.1016)
		(layer "F.Cu")
		(net "P5E_CPU1_P0_TX_C_DP<1>")
	)
	(segment
		(start 48.258222 -381.976122)
		(end 48.401224 -382.21412)
		(width 0.1016)
		(layer "F.Cu")
		(net "P5E_CPU1_P0_TX_C_DP<1>")
	)
	(segment
		(start 46.090586 -379.354588)
		(end 46.38421 -379.794008)
		(width 0.1016)
		(layer "F.Cu")
		(net "P5E_CPU1_P0_TX_C_DP<1>")
	)
	(segment
		(start 43.561508 -376.270266)
		(end 43.68927 -376.270266)
		(width 0.1016)
		(layer "F.Cu")
		(net "P5E_CPU1_P0_TX_C_DP<1>")
	)
	(segment
		(start 48.524414 -382.511808)
		(end 48.524414 -383.13741)
		(width 0.1016)
		(layer "F.Cu")
		(net "P5E_CPU1_P0_TX_C_DP<1>")
	)
	(segment
		(start 47.229522 -380.722124)
		(end 48.258222 -381.976122)
		(width 0.1016)
		(layer "F.Cu")
		(net "P5E_CPU1_P0_TX_C_DP<1>")
	)
	(segment
		(start 48.617886 -383.230882)
		(end 48.617886 -383.92227)
		(width 0.1016)
		(layer "F.Cu")
		(net "P5E_CPU1_P0_TX_C_DP<1>")
	)
	(segment
		(start 45.145452 -377.216416)
		(end 45.933106 -379.118876)
		(width 0.1016)
		(layer "F.Cu")
		(net "P5E_CPU1_P0_TX_C_DP<1>")
	)
	(segment
		(start 46.38421 -379.794008)
		(end 46.38421 -379.794262)
		(width 0.1016)
		(layer "F.Cu")
		(net "P5E_CPU1_P0_TX_C_DP<1>")
	)
	(segment
		(start 43.234102 -375.94286)
		(end 43.561508 -376.270266)
		(width 0.1016)
		(layer "F.Cu")
		(net "P5E_CPU1_P0_TX_C_DP<1>")
	)
	(arc
		(start 43.68927 -376.270266)
		(mid 44.224958 -376.376634)
		(end 44.679108 -376.679968)
		(width 0.1016)
		(layer "F.Cu")
		(net "P5E_CPU1_P0_TX_C_DP<1>")
	)
	(arc
		(start 45.005244 -377.006104)
		(mid 45.085716 -377.104348)
		(end 45.145452 -377.216416)
		(width 0.1016)
		(layer "F.Cu")
		(net "P5E_CPU1_P0_TX_C_DP<1>")
	)
	(arc
		(start 46.498002 -379.964442)
		(mid 46.554848 -380.040818)
		(end 46.618906 -380.111254)
		(width 0.1016)
		(layer "F.Cu")
		(net "P5E_CPU1_P0_TX_C_DP<1>")
	)
	(segment
		(start 65.202562 -383.110232)
		(end 65.202562 -383.318004)
		(width 0.1016)
		(layer "F.Cu")
		(net "P5E_CPU1_P0_TX_C_DP<15>")
	)
	(segment
		(start 68.246752 -379.708918)
		(end 68.134992 -379.820678)
		(width 0.1016)
		(layer "F.Cu")
		(net "P5E_CPU1_P0_TX_C_DP<15>")
	)
	(segment
		(start 67.166236 -379.92558)
		(end 65.2653 -381.826516)
		(width 0.1016)
		(layer "F.Cu")
		(net "P5E_CPU1_P0_TX_C_DP<15>")
	)
	(segment
		(start 68.663312 -379.820678)
		(end 68.551552 -379.708918)
		(width 0.1016)
		(layer "F.Cu")
		(net "P5E_CPU1_P0_TX_C_DP<15>")
	)
	(segment
		(start 69.125084 -379.820678)
		(end 68.663312 -379.820678)
		(width 0.1016)
		(layer "F.Cu")
		(net "P5E_CPU1_P0_TX_C_DP<15>")
	)
	(segment
		(start 68.134992 -379.820678)
		(end 67.420236 -379.820678)
		(width 0.1016)
		(layer "F.Cu")
		(net "P5E_CPU1_P0_TX_C_DP<15>")
	)
	(segment
		(start 69.474334 -379.471428)
		(end 69.125084 -379.820678)
		(width 0.1016)
		(layer "F.Cu")
		(net "P5E_CPU1_P0_TX_C_DP<15>")
	)
	(segment
		(start 65.108582 -383.016252)
		(end 65.202562 -383.110232)
		(width 0.1016)
		(layer "F.Cu")
		(net "P5E_CPU1_P0_TX_C_DP<15>")
	)
	(segment
		(start 65.202562 -383.318004)
		(end 65.11798 -383.402586)
		(width 0.1016)
		(layer "F.Cu")
		(net "P5E_CPU1_P0_TX_C_DP<15>")
	)
	(segment
		(start 68.551552 -379.708918)
		(end 68.246752 -379.708918)
		(width 0.1016)
		(layer "F.Cu")
		(net "P5E_CPU1_P0_TX_C_DP<15>")
	)
	(segment
		(start 65.108582 -382.205484)
		(end 65.108582 -383.016252)
		(width 0.1016)
		(layer "F.Cu")
		(net "P5E_CPU1_P0_TX_C_DP<15>")
	)
	(arc
		(start 65.2653 -381.826516)
		(mid 65.149235 -382.000404)
		(end 65.108582 -382.205484)
		(width 0.1016)
		(layer "F.Cu")
		(net "P5E_CPU1_P0_TX_C_DP<15>")
	)
	(arc
		(start 67.420236 -379.820678)
		(mid 67.282783 -379.847832)
		(end 67.166236 -379.92558)
		(width 0.1016)
		(layer "F.Cu")
		(net "P5E_CPU1_P0_TX_C_DP<15>")
	)
	(segment
		(start 63.908686 -381.689102)
		(end 63.908686 -383.016252)
		(width 0.1016)
		(layer "F.Cu")
		(net "P5E_CPU1_P0_TX_C_DP<14>")
	)
	(segment
		(start 69.474334 -376.067828)
		(end 69.039232 -376.50293)
		(width 0.1016)
		(layer "F.Cu")
		(net "P5E_CPU1_P0_TX_C_DP<14>")
	)
	(segment
		(start 63.908686 -383.016252)
		(end 64.002666 -383.110232)
		(width 0.1016)
		(layer "F.Cu")
		(net "P5E_CPU1_P0_TX_C_DP<14>")
	)
	(segment
		(start 69.039232 -376.50293)
		(end 68.725034 -376.50293)
		(width 0.1016)
		(layer "F.Cu")
		(net "P5E_CPU1_P0_TX_C_DP<14>")
	)
	(segment
		(start 68.725034 -376.50293)
		(end 64.169544 -381.05842)
		(width 0.1016)
		(layer "F.Cu")
		(net "P5E_CPU1_P0_TX_C_DP<14>")
	)
	(segment
		(start 64.002666 -383.110232)
		(end 64.002666 -383.318004)
		(width 0.1016)
		(layer "F.Cu")
		(net "P5E_CPU1_P0_TX_C_DP<14>")
	)
	(segment
		(start 64.002666 -383.318004)
		(end 63.918084 -383.402586)
		(width 0.1016)
		(layer "F.Cu")
		(net "P5E_CPU1_P0_TX_C_DP<14>")
	)
	(arc
		(start 64.169544 -381.05842)
		(mid 63.97642 -381.347824)
		(end 63.908686 -381.689102)
		(width 0.1016)
		(layer "F.Cu")
		(net "P5E_CPU1_P0_TX_C_DP<14>")
	)
	(segment
		(start 69.65696 -375.31294)
		(end 68.776088 -375.31294)
		(width 0.1016)
		(layer "F.Cu")
		(net "P5E_CPU1_P0_TX_C_DP<13>")
	)
	(segment
		(start 70.323202 -372.96725)
		(end 70.323202 -373.125238)
		(width 0.1016)
		(layer "F.Cu")
		(net "P5E_CPU1_P0_TX_C_DP<13>")
	)
	(segment
		(start 69.949314 -372.75135)
		(end 70.107302 -372.75135)
		(width 0.1016)
		(layer "F.Cu")
		(net "P5E_CPU1_P0_TX_C_DP<13>")
	)
	(segment
		(start 69.431154 -370.83873)
		(end 69.081904 -371.18798)
		(width 0.1016)
		(layer "F.Cu")
		(net "P5E_CPU1_P0_TX_C_DP<13>")
	)
	(segment
		(start 68.358512 -375.485914)
		(end 62.961774 -380.882652)
		(width 0.1016)
		(layer "F.Cu")
		(net "P5E_CPU1_P0_TX_C_DP<13>")
	)
	(segment
		(start 69.081904 -371.527832)
		(end 69.082158 -371.527578)
		(width 0.1016)
		(layer "F.Cu")
		(net "P5E_CPU1_P0_TX_C_DP<13>")
	)
	(segment
		(start 70.323202 -373.125238)
		(end 70.538594 -373.34063)
		(width 0.1016)
		(layer "F.Cu")
		(net "P5E_CPU1_P0_TX_C_DP<13>")
	)
	(segment
		(start 62.924436 -380.972822)
		(end 62.924436 -383.13741)
		(width 0.1016)
		(layer "F.Cu")
		(net "P5E_CPU1_P0_TX_C_DP<13>")
	)
	(segment
		(start 69.081904 -371.18798)
		(end 69.081904 -371.527832)
		(width 0.1016)
		(layer "F.Cu")
		(net "P5E_CPU1_P0_TX_C_DP<13>")
	)
	(segment
		(start 70.107302 -372.75135)
		(end 70.323202 -372.96725)
		(width 0.1016)
		(layer "F.Cu")
		(net "P5E_CPU1_P0_TX_C_DP<13>")
	)
	(segment
		(start 62.924436 -383.13741)
		(end 63.017908 -383.230882)
		(width 0.1016)
		(layer "F.Cu")
		(net "P5E_CPU1_P0_TX_C_DP<13>")
	)
	(segment
		(start 70.520306 -374.706388)
		(end 70.094856 -375.131838)
		(width 0.1016)
		(layer "F.Cu")
		(net "P5E_CPU1_P0_TX_C_DP<13>")
	)
	(segment
		(start 63.017908 -383.230882)
		(end 63.017908 -383.92227)
		(width 0.1016)
		(layer "F.Cu")
		(net "P5E_CPU1_P0_TX_C_DP<13>")
	)
	(segment
		(start 70.756018 -373.866156)
		(end 70.756018 -374.136666)
		(width 0.1016)
		(layer "F.Cu")
		(net "P5E_CPU1_P0_TX_C_DP<13>")
	)
	(segment
		(start 69.333872 -372.135908)
		(end 69.949314 -372.75135)
		(width 0.1016)
		(layer "F.Cu")
		(net "P5E_CPU1_P0_TX_C_DP<13>")
	)
	(arc
		(start 70.094856 -375.131838)
		(mid 69.893918 -375.265915)
		(end 69.65696 -375.31294)
		(width 0.1016)
		(layer "F.Cu")
		(net "P5E_CPU1_P0_TX_C_DP<13>")
	)
	(arc
		(start 69.082158 -371.527578)
		(mid 69.147527 -371.856771)
		(end 69.333872 -372.135908)
		(width 0.1016)
		(layer "F.Cu")
		(net "P5E_CPU1_P0_TX_C_DP<13>")
	)
	(arc
		(start 62.961774 -380.882652)
		(mid 62.934131 -380.924022)
		(end 62.924436 -380.972822)
		(width 0.1016)
		(layer "F.Cu")
		(net "P5E_CPU1_P0_TX_C_DP<13>")
	)
	(arc
		(start 70.756018 -374.136666)
		(mid 70.694874 -374.445)
		(end 70.520306 -374.706388)
		(width 0.1016)
		(layer "F.Cu")
		(net "P5E_CPU1_P0_TX_C_DP<13>")
	)
	(arc
		(start 68.776088 -375.31294)
		(mid 68.550094 -375.357893)
		(end 68.358512 -375.485914)
		(width 0.1016)
		(layer "F.Cu")
		(net "P5E_CPU1_P0_TX_C_DP<13>")
	)
	(arc
		(start 70.538594 -373.34063)
		(mid 70.699589 -373.581759)
		(end 70.756018 -373.866156)
		(width 0.1016)
		(layer "F.Cu")
		(net "P5E_CPU1_P0_TX_C_DP<13>")
	)
	(segment
		(start 65.113154 -370.83873)
		(end 65.462404 -371.18798)
		(width 0.1016)
		(layer "F.Cu")
		(net "P5E_CPU1_P0_TX_C_DP<12>")
	)
	(segment
		(start 67.099434 -374.737376)
		(end 61.79566 -380.04115)
		(width 0.1016)
		(layer "F.Cu")
		(net "P5E_CPU1_P0_TX_C_DP<12>")
	)
	(segment
		(start 61.50864 -380.734062)
		(end 61.50864 -382.942592)
		(width 0.1016)
		(layer "F.Cu")
		(net "P5E_CPU1_P0_TX_C_DP<12>")
	)
	(segment
		(start 61.518038 -383.520442)
		(end 61.518038 -383.402586)
		(width 0.1016)
		(layer "F.Cu")
		(net "P5E_CPU1_P0_TX_C_DP<12>")
	)
	(segment
		(start 61.441584 -383.596896)
		(end 61.518038 -383.520442)
		(width 0.1016)
		(layer "F.Cu")
		(net "P5E_CPU1_P0_TX_C_DP<12>")
	)
	(segment
		(start 61.50864 -382.942592)
		(end 61.216032 -383.2352)
		(width 0.1016)
		(layer "F.Cu")
		(net "P5E_CPU1_P0_TX_C_DP<12>")
	)
	(segment
		(start 65.462404 -371.18798)
		(end 65.462404 -371.5385)
		(width 0.1016)
		(layer "F.Cu")
		(net "P5E_CPU1_P0_TX_C_DP<12>")
	)
	(segment
		(start 61.216032 -383.2352)
		(end 61.216032 -383.50571)
		(width 0.1016)
		(layer "F.Cu")
		(net "P5E_CPU1_P0_TX_C_DP<12>")
	)
	(segment
		(start 61.216032 -383.50571)
		(end 61.307218 -383.596896)
		(width 0.1016)
		(layer "F.Cu")
		(net "P5E_CPU1_P0_TX_C_DP<12>")
	)
	(segment
		(start 65.714626 -372.147338)
		(end 67.13474 -373.567198)
		(width 0.1016)
		(layer "F.Cu")
		(net "P5E_CPU1_P0_TX_C_DP<12>")
	)
	(segment
		(start 61.307218 -383.596896)
		(end 61.441584 -383.596896)
		(width 0.1016)
		(layer "F.Cu")
		(net "P5E_CPU1_P0_TX_C_DP<12>")
	)
	(segment
		(start 67.172078 -373.657368)
		(end 67.172078 -374.562878)
		(width 0.1016)
		(layer "F.Cu")
		(net "P5E_CPU1_P0_TX_C_DP<12>")
	)
	(arc
		(start 65.462404 -371.5385)
		(mid 65.527948 -371.868013)
		(end 65.714626 -372.147338)
		(width 0.1016)
		(layer "F.Cu")
		(net "P5E_CPU1_P0_TX_C_DP<12>")
	)
	(arc
		(start 67.13474 -373.567198)
		(mid 67.162383 -373.608568)
		(end 67.172078 -373.657368)
		(width 0.1016)
		(layer "F.Cu")
		(net "P5E_CPU1_P0_TX_C_DP<12>")
	)
	(arc
		(start 67.172078 -374.562878)
		(mid 67.153084 -374.657333)
		(end 67.099434 -374.737376)
		(width 0.1016)
		(layer "F.Cu")
		(net "P5E_CPU1_P0_TX_C_DP<12>")
	)
	(arc
		(start 61.79566 -380.04115)
		(mid 61.583239 -380.359061)
		(end 61.50864 -380.734062)
		(width 0.1016)
		(layer "F.Cu")
		(net "P5E_CPU1_P0_TX_C_DP<12>")
	)
	(segment
		(start 60.015882 -383.50571)
		(end 60.107068 -383.596896)
		(width 0.1016)
		(layer "F.Cu")
		(net "P5E_CPU1_P0_TX_C_DP<11>")
	)
	(segment
		(start 63.411354 -373.30253)
		(end 63.760604 -373.65178)
		(width 0.1016)
		(layer "F.Cu")
		(net "P5E_CPU1_P0_TX_C_DP<11>")
	)
	(segment
		(start 63.760604 -373.65178)
		(end 63.760604 -376.236484)
		(width 0.1016)
		(layer "F.Cu")
		(net "P5E_CPU1_P0_TX_C_DP<11>")
	)
	(segment
		(start 60.015882 -383.2352)
		(end 60.015882 -383.50571)
		(width 0.1016)
		(layer "F.Cu")
		(net "P5E_CPU1_P0_TX_C_DP<11>")
	)
	(segment
		(start 63.723266 -376.326654)
		(end 60.407804 -379.642116)
		(width 0.1016)
		(layer "F.Cu")
		(net "P5E_CPU1_P0_TX_C_DP<11>")
	)
	(segment
		(start 60.241434 -383.596896)
		(end 60.317888 -383.520442)
		(width 0.1016)
		(layer "F.Cu")
		(net "P5E_CPU1_P0_TX_C_DP<11>")
	)
	(segment
		(start 60.317888 -383.520442)
		(end 60.317888 -383.402586)
		(width 0.1016)
		(layer "F.Cu")
		(net "P5E_CPU1_P0_TX_C_DP<11>")
	)
	(segment
		(start 60.107068 -383.596896)
		(end 60.241434 -383.596896)
		(width 0.1016)
		(layer "F.Cu")
		(net "P5E_CPU1_P0_TX_C_DP<11>")
	)
	(segment
		(start 60.30849 -382.942592)
		(end 60.015882 -383.2352)
		(width 0.1016)
		(layer "F.Cu")
		(net "P5E_CPU1_P0_TX_C_DP<11>")
	)
	(segment
		(start 60.30849 -379.884178)
		(end 60.30849 -382.942592)
		(width 0.1016)
		(layer "F.Cu")
		(net "P5E_CPU1_P0_TX_C_DP<11>")
	)
	(arc
		(start 63.760604 -376.236484)
		(mid 63.750898 -376.285279)
		(end 63.723266 -376.326654)
		(width 0.1016)
		(layer "F.Cu")
		(net "P5E_CPU1_P0_TX_C_DP<11>")
	)
	(arc
		(start 60.407804 -379.642116)
		(mid 60.334243 -379.753332)
		(end 60.30849 -379.884178)
		(width 0.1016)
		(layer "F.Cu")
		(net "P5E_CPU1_P0_TX_C_DP<11>")
	)
	(segment
		(start 61.709554 -375.76633)
		(end 62.057788 -376.114564)
		(width 0.1016)
		(layer "F.Cu")
		(net "P5E_CPU1_P0_TX_C_DP<10>")
	)
	(segment
		(start 62.02045 -376.292872)
		(end 61.038994 -377.274328)
		(width 0.1016)
		(layer "F.Cu")
		(net "P5E_CPU1_P0_TX_C_DP<10>")
	)
	(segment
		(start 59.108594 -378.904754)
		(end 59.108594 -382.942592)
		(width 0.1016)
		(layer "F.Cu")
		(net "P5E_CPU1_P0_TX_C_DP<10>")
	)
	(segment
		(start 58.815986 -383.2352)
		(end 58.815986 -383.50571)
		(width 0.1016)
		(layer "F.Cu")
		(net "P5E_CPU1_P0_TX_C_DP<10>")
	)
	(segment
		(start 59.041538 -383.596896)
		(end 59.117992 -383.520442)
		(width 0.1016)
		(layer "F.Cu")
		(net "P5E_CPU1_P0_TX_C_DP<10>")
	)
	(segment
		(start 62.057788 -376.114564)
		(end 62.057788 -376.202702)
		(width 0.1016)
		(layer "F.Cu")
		(net "P5E_CPU1_P0_TX_C_DP<10>")
	)
	(segment
		(start 60.441332 -377.429522)
		(end 59.387994 -378.48286)
		(width 0.1016)
		(layer "F.Cu")
		(net "P5E_CPU1_P0_TX_C_DP<10>")
	)
	(segment
		(start 59.108594 -382.942592)
		(end 58.815986 -383.2352)
		(width 0.1016)
		(layer "F.Cu")
		(net "P5E_CPU1_P0_TX_C_DP<10>")
	)
	(segment
		(start 59.387994 -378.48286)
		(end 59.38774 -378.48286)
		(width 0.1016)
		(layer "F.Cu")
		(net "P5E_CPU1_P0_TX_C_DP<10>")
	)
	(segment
		(start 58.907172 -383.596896)
		(end 59.041538 -383.596896)
		(width 0.1016)
		(layer "F.Cu")
		(net "P5E_CPU1_P0_TX_C_DP<10>")
	)
	(segment
		(start 58.815986 -383.50571)
		(end 58.907172 -383.596896)
		(width 0.1016)
		(layer "F.Cu")
		(net "P5E_CPU1_P0_TX_C_DP<10>")
	)
	(segment
		(start 59.117992 -383.520442)
		(end 59.117992 -383.402586)
		(width 0.1016)
		(layer "F.Cu")
		(net "P5E_CPU1_P0_TX_C_DP<10>")
	)
	(segment
		(start 60.924694 -377.321572)
		(end 60.701936 -377.321572)
		(width 0.1016)
		(layer "F.Cu")
		(net "P5E_CPU1_P0_TX_C_DP<10>")
	)
	(segment
		(start 59.38774 -378.48286)
		(end 59.208924 -378.661676)
		(width 0.1016)
		(layer "F.Cu")
		(net "P5E_CPU1_P0_TX_C_DP<10>")
	)
	(arc
		(start 62.057788 -376.202702)
		(mid 62.048082 -376.251497)
		(end 62.02045 -376.292872)
		(width 0.1016)
		(layer "F.Cu")
		(net "P5E_CPU1_P0_TX_C_DP<10>")
	)
	(arc
		(start 59.208924 -378.661676)
		(mid 59.134625 -378.773245)
		(end 59.108594 -378.904754)
		(width 0.1016)
		(layer "F.Cu")
		(net "P5E_CPU1_P0_TX_C_DP<10>")
	)
	(arc
		(start 61.038994 -377.274328)
		(mid 60.986539 -377.309315)
		(end 60.924694 -377.321572)
		(width 0.1016)
		(layer "F.Cu")
		(net "P5E_CPU1_P0_TX_C_DP<10>")
	)
	(arc
		(start 60.701936 -377.321572)
		(mid 60.560896 -377.349627)
		(end 60.441332 -377.429522)
		(width 0.1016)
		(layer "F.Cu")
		(net "P5E_CPU1_P0_TX_C_DP<10>")
	)
	(segment
		(start 43.88993 -382.043432)
		(end 44.00169 -382.155192)
		(width 0.1016)
		(layer "F.Cu")
		(net "P5E_CPU1_P0_TX_C_DP<0>")
	)
	(segment
		(start 43.58513 -382.043432)
		(end 43.88993 -382.043432)
		(width 0.1016)
		(layer "F.Cu")
		(net "P5E_CPU1_P0_TX_C_DP<0>")
	)
	(segment
		(start 44.83481 -382.155192)
		(end 45.13961 -382.155192)
		(width 0.1016)
		(layer "F.Cu")
		(net "P5E_CPU1_P0_TX_C_DP<0>")
	)
	(segment
		(start 47.108618 -382.817624)
		(end 47.108618 -382.942592)
		(width 0.1016)
		(layer "F.Cu")
		(net "P5E_CPU1_P0_TX_C_DP<0>")
	)
	(segment
		(start 45.25137 -382.043432)
		(end 45.752512 -382.043432)
		(width 0.1016)
		(layer "F.Cu")
		(net "P5E_CPU1_P0_TX_C_DP<0>")
	)
	(segment
		(start 45.950378 -382.082802)
		(end 46.55566 -382.332738)
		(width 0.1016)
		(layer "F.Cu")
		(net "P5E_CPU1_P0_TX_C_DP<0>")
	)
	(segment
		(start 46.81601 -383.50571)
		(end 46.907196 -383.596896)
		(width 0.1016)
		(layer "F.Cu")
		(net "P5E_CPU1_P0_TX_C_DP<0>")
	)
	(segment
		(start 44.41825 -382.043432)
		(end 44.72305 -382.043432)
		(width 0.1016)
		(layer "F.Cu")
		(net "P5E_CPU1_P0_TX_C_DP<0>")
	)
	(segment
		(start 43.234102 -382.39446)
		(end 43.58513 -382.043432)
		(width 0.1016)
		(layer "F.Cu")
		(net "P5E_CPU1_P0_TX_C_DP<0>")
	)
	(segment
		(start 46.81601 -383.2352)
		(end 46.81601 -383.50571)
		(width 0.1016)
		(layer "F.Cu")
		(net "P5E_CPU1_P0_TX_C_DP<0>")
	)
	(segment
		(start 44.30649 -382.155192)
		(end 44.41825 -382.043432)
		(width 0.1016)
		(layer "F.Cu")
		(net "P5E_CPU1_P0_TX_C_DP<0>")
	)
	(segment
		(start 44.00169 -382.155192)
		(end 44.30649 -382.155192)
		(width 0.1016)
		(layer "F.Cu")
		(net "P5E_CPU1_P0_TX_C_DP<0>")
	)
	(segment
		(start 47.041562 -383.596896)
		(end 47.118016 -383.520442)
		(width 0.1016)
		(layer "F.Cu")
		(net "P5E_CPU1_P0_TX_C_DP<0>")
	)
	(segment
		(start 46.907196 -383.596896)
		(end 47.041562 -383.596896)
		(width 0.1016)
		(layer "F.Cu")
		(net "P5E_CPU1_P0_TX_C_DP<0>")
	)
	(segment
		(start 47.108618 -382.942592)
		(end 46.81601 -383.2352)
		(width 0.1016)
		(layer "F.Cu")
		(net "P5E_CPU1_P0_TX_C_DP<0>")
	)
	(segment
		(start 47.118016 -383.520442)
		(end 47.118016 -383.402586)
		(width 0.1016)
		(layer "F.Cu")
		(net "P5E_CPU1_P0_TX_C_DP<0>")
	)
	(segment
		(start 44.72305 -382.043432)
		(end 44.83481 -382.155192)
		(width 0.1016)
		(layer "F.Cu")
		(net "P5E_CPU1_P0_TX_C_DP<0>")
	)
	(segment
		(start 45.13961 -382.155192)
		(end 45.25137 -382.043432)
		(width 0.1016)
		(layer "F.Cu")
		(net "P5E_CPU1_P0_TX_C_DP<0>")
	)
	(segment
		(start 46.767242 -382.47447)
		(end 47.108618 -382.817624)
		(width 0.1016)
		(layer "F.Cu")
		(net "P5E_CPU1_P0_TX_C_DP<0>")
	)
	(arc
		(start 45.752512 -382.043432)
		(mid 45.853377 -382.053399)
		(end 45.950378 -382.082802)
		(width 0.1016)
		(layer "F.Cu")
		(net "P5E_CPU1_P0_TX_C_DP<0>")
	)
	(arc
		(start 46.55566 -382.332738)
		(mid 46.668491 -382.393093)
		(end 46.767242 -382.47447)
		(width 0.1016)
		(layer "F.Cu")
		(net "P5E_CPU1_P0_TX_C_DP<0>")
	)
	(segment
		(start 59.220354 -370.83873)
		(end 58.871104 -371.18798)
		(width 0.1016)
		(layer "F.Cu")
		(net "P5E_CPU1_P0_TX_C_DN<9>")
	)
	(segment
		(start 60.41517 -375.31929)
		(end 59.554364 -376.180096)
		(width 0.1016)
		(layer "F.Cu")
		(net "P5E_CPU1_P0_TX_C_DN<9>")
	)
	(segment
		(start 59.12358 -372.136162)
		(end 60.286646 -373.299228)
		(width 0.1016)
		(layer "F.Cu")
		(net "P5E_CPU1_P0_TX_C_DN<9>")
	)
	(segment
		(start 59.338464 -376.553984)
		(end 59.180476 -376.553984)
		(width 0.1016)
		(layer "F.Cu")
		(net "P5E_CPU1_P0_TX_C_DN<9>")
	)
	(segment
		(start 59.554364 -376.338084)
		(end 59.338464 -376.553984)
		(width 0.1016)
		(layer "F.Cu")
		(net "P5E_CPU1_P0_TX_C_DN<9>")
	)
	(segment
		(start 60.549536 -373.933466)
		(end 60.549536 -374.994932)
		(width 0.1016)
		(layer "F.Cu")
		(net "P5E_CPU1_P0_TX_C_DN<9>")
	)
	(segment
		(start 58.124598 -377.723908)
		(end 58.124598 -383.13741)
		(width 0.1016)
		(layer "F.Cu")
		(net "P5E_CPU1_P0_TX_C_DN<9>")
	)
	(segment
		(start 59.180476 -376.553984)
		(end 58.20537 -377.52909)
		(width 0.1016)
		(layer "F.Cu")
		(net "P5E_CPU1_P0_TX_C_DN<9>")
	)
	(segment
		(start 59.554364 -376.180096)
		(end 59.554364 -376.338084)
		(width 0.1016)
		(layer "F.Cu")
		(net "P5E_CPU1_P0_TX_C_DN<9>")
	)
	(segment
		(start 58.21807 -383.230882)
		(end 58.21807 -383.92227)
		(width 0.1016)
		(layer "F.Cu")
		(net "P5E_CPU1_P0_TX_C_DN<9>")
	)
	(segment
		(start 58.871104 -371.18798)
		(end 58.871104 -371.527324)
		(width 0.1016)
		(layer "F.Cu")
		(net "P5E_CPU1_P0_TX_C_DN<9>")
	)
	(segment
		(start 58.124598 -383.13741)
		(end 58.21807 -383.230882)
		(width 0.1016)
		(layer "F.Cu")
		(net "P5E_CPU1_P0_TX_C_DN<9>")
	)
	(arc
		(start 60.286646 -373.299228)
		(mid 60.481163 -373.590204)
		(end 60.549536 -373.933466)
		(width 0.1016)
		(layer "F.Cu")
		(net "P5E_CPU1_P0_TX_C_DN<9>")
	)
	(arc
		(start 58.20537 -377.52909)
		(mid 58.145592 -377.618459)
		(end 58.124598 -377.723908)
		(width 0.1016)
		(layer "F.Cu")
		(net "P5E_CPU1_P0_TX_C_DN<9>")
	)
	(arc
		(start 58.871104 -371.527324)
		(mid 58.936834 -371.856827)
		(end 59.12358 -372.136162)
		(width 0.1016)
		(layer "F.Cu")
		(net "P5E_CPU1_P0_TX_C_DN<9>")
	)
	(arc
		(start 60.549536 -374.994932)
		(mid 60.514618 -375.170478)
		(end 60.41517 -375.31929)
		(width 0.1016)
		(layer "F.Cu")
		(net "P5E_CPU1_P0_TX_C_DN<9>")
	)
	(segment
		(start 57.169304 -375.37136)
		(end 57.169304 -376.616976)
		(width 0.1016)
		(layer "F.Cu")
		(net "P5E_CPU1_P0_TX_C_DN<8>")
	)
	(segment
		(start 57.01792 -383.230882)
		(end 57.01792 -383.92227)
		(width 0.1016)
		(layer "F.Cu")
		(net "P5E_CPU1_P0_TX_C_DN<8>")
	)
	(segment
		(start 57.169304 -373.71909)
		(end 57.169304 -374.84304)
		(width 0.1016)
		(layer "F.Cu")
		(net "P5E_CPU1_P0_TX_C_DN<8>")
	)
	(segment
		(start 56.924448 -377.318016)
		(end 56.924448 -383.13741)
		(width 0.1016)
		(layer "F.Cu")
		(net "P5E_CPU1_P0_TX_C_DN<8>")
	)
	(segment
		(start 57.518554 -373.30253)
		(end 57.216802 -373.604282)
		(width 0.1016)
		(layer "F.Cu")
		(net "P5E_CPU1_P0_TX_C_DN<8>")
	)
	(segment
		(start 57.281064 -375.2596)
		(end 57.169304 -375.37136)
		(width 0.1016)
		(layer "F.Cu")
		(net "P5E_CPU1_P0_TX_C_DN<8>")
	)
	(segment
		(start 57.281064 -374.9548)
		(end 57.281064 -375.2596)
		(width 0.1016)
		(layer "F.Cu")
		(net "P5E_CPU1_P0_TX_C_DN<8>")
	)
	(segment
		(start 57.169304 -374.84304)
		(end 57.281064 -374.9548)
		(width 0.1016)
		(layer "F.Cu")
		(net "P5E_CPU1_P0_TX_C_DN<8>")
	)
	(segment
		(start 56.924448 -383.13741)
		(end 57.01792 -383.230882)
		(width 0.1016)
		(layer "F.Cu")
		(net "P5E_CPU1_P0_TX_C_DN<8>")
	)
	(arc
		(start 56.963818 -377.130818)
		(mid 56.934354 -377.222364)
		(end 56.924448 -377.318016)
		(width 0.1016)
		(layer "F.Cu")
		(net "P5E_CPU1_P0_TX_C_DN<8>")
	)
	(arc
		(start 57.169304 -376.616976)
		(mid 57.133307 -376.831347)
		(end 57.029096 -377.022106)
		(width 0.1016)
		(layer "F.Cu")
		(net "P5E_CPU1_P0_TX_C_DN<8>")
	)
	(arc
		(start 57.216802 -373.604282)
		(mid 57.18166 -373.656971)
		(end 57.169304 -373.71909)
		(width 0.1016)
		(layer "F.Cu")
		(net "P5E_CPU1_P0_TX_C_DN<8>")
	)
	(arc
		(start 57.029096 -377.022106)
		(mid 56.993032 -377.074405)
		(end 56.963818 -377.130818)
		(width 0.1016)
		(layer "F.Cu")
		(net "P5E_CPU1_P0_TX_C_DN<8>")
	)
	(segment
		(start 55.579264 -377.49099)
		(end 55.467504 -377.60275)
		(width 0.1016)
		(layer "F.Cu")
		(net "P5E_CPU1_P0_TX_C_DN<7>")
	)
	(segment
		(start 55.467504 -376.182636)
		(end 55.467504 -377.07443)
		(width 0.1016)
		(layer "F.Cu")
		(net "P5E_CPU1_P0_TX_C_DN<7>")
	)
	(segment
		(start 55.818024 -383.230882)
		(end 55.818024 -383.92227)
		(width 0.1016)
		(layer "F.Cu")
		(net "P5E_CPU1_P0_TX_C_DN<7>")
	)
	(segment
		(start 55.724552 -382.94183)
		(end 55.724552 -383.13741)
		(width 0.1016)
		(layer "F.Cu")
		(net "P5E_CPU1_P0_TX_C_DN<7>")
	)
	(segment
		(start 55.467504 -377.07443)
		(end 55.579264 -377.18619)
		(width 0.1016)
		(layer "F.Cu")
		(net "P5E_CPU1_P0_TX_C_DN<7>")
	)
	(segment
		(start 55.579264 -377.18619)
		(end 55.579264 -377.49099)
		(width 0.1016)
		(layer "F.Cu")
		(net "P5E_CPU1_P0_TX_C_DN<7>")
	)
	(segment
		(start 55.724552 -383.13741)
		(end 55.818024 -383.230882)
		(width 0.1016)
		(layer "F.Cu")
		(net "P5E_CPU1_P0_TX_C_DN<7>")
	)
	(segment
		(start 55.706772 -378.6632)
		(end 55.724552 -382.94183)
		(width 0.1016)
		(layer "F.Cu")
		(net "P5E_CPU1_P0_TX_C_DN<7>")
	)
	(segment
		(start 55.816754 -375.76633)
		(end 55.514748 -376.068336)
		(width 0.1016)
		(layer "F.Cu")
		(net "P5E_CPU1_P0_TX_C_DN<7>")
	)
	(segment
		(start 55.467504 -377.60275)
		(end 55.467504 -377.90755)
		(width 0.1016)
		(layer "F.Cu")
		(net "P5E_CPU1_P0_TX_C_DN<7>")
	)
	(arc
		(start 55.467504 -377.90755)
		(mid 55.498046 -378.106219)
		(end 55.586884 -378.286518)
		(width 0.1016)
		(layer "F.Cu")
		(net "P5E_CPU1_P0_TX_C_DN<7>")
	)
	(arc
		(start 55.514748 -376.068336)
		(mid 55.479761 -376.120791)
		(end 55.467504 -376.182636)
		(width 0.1016)
		(layer "F.Cu")
		(net "P5E_CPU1_P0_TX_C_DN<7>")
	)
	(arc
		(start 55.586884 -378.286518)
		(mid 55.675583 -378.465706)
		(end 55.706772 -378.6632)
		(width 0.1016)
		(layer "F.Cu")
		(net "P5E_CPU1_P0_TX_C_DN<7>")
	)
	(segment
		(start 52.413154 -370.83873)
		(end 52.063904 -371.18798)
		(width 0.1016)
		(layer "F.Cu")
		(net "P5E_CPU1_P0_TX_C_DN<6>")
	)
	(segment
		(start 52.063904 -371.18798)
		(end 52.063904 -371.479826)
		(width 0.1016)
		(layer "F.Cu")
		(net "P5E_CPU1_P0_TX_C_DN<6>")
	)
	(segment
		(start 54.524402 -381.694182)
		(end 54.524402 -383.13741)
		(width 0.1016)
		(layer "F.Cu")
		(net "P5E_CPU1_P0_TX_C_DN<6>")
	)
	(segment
		(start 54.524402 -383.13741)
		(end 54.618128 -383.231136)
		(width 0.1016)
		(layer "F.Cu")
		(net "P5E_CPU1_P0_TX_C_DN<6>")
	)
	(segment
		(start 53.89499 -374.960896)
		(end 53.89499 -375.265696)
		(width 0.1016)
		(layer "F.Cu")
		(net "P5E_CPU1_P0_TX_C_DN<6>")
	)
	(segment
		(start 53.89499 -375.265696)
		(end 53.78323 -375.377456)
		(width 0.1016)
		(layer "F.Cu")
		(net "P5E_CPU1_P0_TX_C_DN<6>")
	)
	(segment
		(start 54.618128 -383.231136)
		(end 54.618128 -383.92227)
		(width 0.1016)
		(layer "F.Cu")
		(net "P5E_CPU1_P0_TX_C_DN<6>")
	)
	(segment
		(start 53.78323 -373.88673)
		(end 53.78323 -374.849136)
		(width 0.1016)
		(layer "F.Cu")
		(net "P5E_CPU1_P0_TX_C_DN<6>")
	)
	(segment
		(start 53.78323 -375.377456)
		(end 53.78323 -378.006356)
		(width 0.1016)
		(layer "F.Cu")
		(net "P5E_CPU1_P0_TX_C_DN<6>")
	)
	(segment
		(start 53.909468 -378.652278)
		(end 53.946044 -378.742194)
		(width 0.1016)
		(layer "F.Cu")
		(net "P5E_CPU1_P0_TX_C_DN<6>")
	)
	(segment
		(start 52.327302 -372.114826)
		(end 53.55971 -373.347234)
		(width 0.1016)
		(layer "F.Cu")
		(net "P5E_CPU1_P0_TX_C_DN<6>")
	)
	(segment
		(start 53.78323 -374.849136)
		(end 53.89499 -374.960896)
		(width 0.1016)
		(layer "F.Cu")
		(net "P5E_CPU1_P0_TX_C_DN<6>")
	)
	(arc
		(start 53.55971 -373.347234)
		(mid 53.725075 -373.59477)
		(end 53.78323 -373.88673)
		(width 0.1016)
		(layer "F.Cu")
		(net "P5E_CPU1_P0_TX_C_DN<6>")
	)
	(arc
		(start 52.063904 -371.479826)
		(mid 52.132471 -371.823506)
		(end 52.327302 -372.114826)
		(width 0.1016)
		(layer "F.Cu")
		(net "P5E_CPU1_P0_TX_C_DN<6>")
	)
	(arc
		(start 53.946044 -378.742194)
		(mid 54.37841 -380.190135)
		(end 54.524402 -381.694182)
		(width 0.1016)
		(layer "F.Cu")
		(net "P5E_CPU1_P0_TX_C_DN<6>")
	)
	(arc
		(start 53.78323 -378.006356)
		(mid 53.815103 -378.335425)
		(end 53.909468 -378.652278)
		(width 0.1016)
		(layer "F.Cu")
		(net "P5E_CPU1_P0_TX_C_DN<6>")
	)
	(segment
		(start 50.362104 -374.529096)
		(end 50.473864 -374.640856)
		(width 0.1016)
		(layer "F.Cu")
		(net "P5E_CPU1_P0_TX_C_DN<5>")
	)
	(segment
		(start 53.417978 -383.230882)
		(end 53.417978 -383.92227)
		(width 0.1016)
		(layer "F.Cu")
		(net "P5E_CPU1_P0_TX_C_DN<5>")
	)
	(segment
		(start 50.689764 -376.44197)
		(end 52.619656 -379.328934)
		(width 0.1016)
		(layer "F.Cu")
		(net "P5E_CPU1_P0_TX_C_DN<5>")
	)
	(segment
		(start 53.324506 -381.651764)
		(end 53.324506 -383.13741)
		(width 0.1016)
		(layer "F.Cu")
		(net "P5E_CPU1_P0_TX_C_DN<5>")
	)
	(segment
		(start 50.362104 -375.057416)
		(end 50.362104 -375.362216)
		(width 0.1016)
		(layer "F.Cu")
		(net "P5E_CPU1_P0_TX_C_DN<5>")
	)
	(segment
		(start 50.362104 -373.65178)
		(end 50.362104 -374.529096)
		(width 0.1016)
		(layer "F.Cu")
		(net "P5E_CPU1_P0_TX_C_DN<5>")
	)
	(segment
		(start 50.711354 -373.30253)
		(end 50.362104 -373.65178)
		(width 0.1016)
		(layer "F.Cu")
		(net "P5E_CPU1_P0_TX_C_DN<5>")
	)
	(segment
		(start 53.324506 -383.13741)
		(end 53.417978 -383.230882)
		(width 0.1016)
		(layer "F.Cu")
		(net "P5E_CPU1_P0_TX_C_DN<5>")
	)
	(segment
		(start 50.473864 -374.945656)
		(end 50.362104 -375.057416)
		(width 0.1016)
		(layer "F.Cu")
		(net "P5E_CPU1_P0_TX_C_DN<5>")
	)
	(segment
		(start 50.473864 -374.640856)
		(end 50.473864 -374.945656)
		(width 0.1016)
		(layer "F.Cu")
		(net "P5E_CPU1_P0_TX_C_DN<5>")
	)
	(arc
		(start 50.362104 -375.362216)
		(mid 50.445825 -375.926402)
		(end 50.689764 -376.44197)
		(width 0.1016)
		(layer "F.Cu")
		(net "P5E_CPU1_P0_TX_C_DN<5>")
	)
	(arc
		(start 52.619656 -379.328934)
		(mid 53.144419 -380.438055)
		(end 53.324506 -381.651764)
		(width 0.1016)
		(layer "F.Cu")
		(net "P5E_CPU1_P0_TX_C_DN<5>")
	)
	(segment
		(start 52.12461 -381.573278)
		(end 52.12461 -383.13741)
		(width 0.1016)
		(layer "F.Cu")
		(net "P5E_CPU1_P0_TX_C_DN<4>")
	)
	(segment
		(start 49.76876 -377.721114)
		(end 49.75352 -377.878594)
		(width 0.1016)
		(layer "F.Cu")
		(net "P5E_CPU1_P0_TX_C_DN<4>")
	)
	(segment
		(start 49.417986 -377.469908)
		(end 49.575212 -377.485402)
		(width 0.1016)
		(layer "F.Cu")
		(net "P5E_CPU1_P0_TX_C_DN<4>")
	)
	(segment
		(start 48.660304 -376.11558)
		(end 48.660304 -376.28957)
		(width 0.1016)
		(layer "F.Cu")
		(net "P5E_CPU1_P0_TX_C_DN<4>")
	)
	(segment
		(start 49.75352 -377.878594)
		(end 51.751484 -380.31293)
		(width 0.1016)
		(layer "F.Cu")
		(net "P5E_CPU1_P0_TX_C_DN<4>")
	)
	(segment
		(start 48.87595 -376.809508)
		(end 49.417986 -377.469908)
		(width 0.1016)
		(layer "F.Cu")
		(net "P5E_CPU1_P0_TX_C_DN<4>")
	)
	(segment
		(start 49.009554 -375.76633)
		(end 48.660304 -376.11558)
		(width 0.1016)
		(layer "F.Cu")
		(net "P5E_CPU1_P0_TX_C_DN<4>")
	)
	(segment
		(start 52.218082 -383.230882)
		(end 52.218082 -383.92227)
		(width 0.1016)
		(layer "F.Cu")
		(net "P5E_CPU1_P0_TX_C_DN<4>")
	)
	(segment
		(start 48.660304 -376.28957)
		(end 48.87595 -376.809508)
		(width 0.1016)
		(layer "F.Cu")
		(net "P5E_CPU1_P0_TX_C_DN<4>")
	)
	(segment
		(start 52.12461 -383.13741)
		(end 52.218082 -383.230882)
		(width 0.1016)
		(layer "F.Cu")
		(net "P5E_CPU1_P0_TX_C_DN<4>")
	)
	(segment
		(start 49.575212 -377.485402)
		(end 49.76876 -377.721114)
		(width 0.1016)
		(layer "F.Cu")
		(net "P5E_CPU1_P0_TX_C_DN<4>")
	)
	(arc
		(start 52.12461 -381.572262)
		(mid 52.12461 -381.57277)
		(end 52.12461 -381.573278)
		(width 0.1016)
		(layer "F.Cu")
		(net "P5E_CPU1_P0_TX_C_DN<4>")
	)
	(arc
		(start 51.751484 -380.31293)
		(mid 52.029136 -380.915208)
		(end 52.12461 -381.5715)
		(width 0.1016)
		(layer "F.Cu")
		(net "P5E_CPU1_P0_TX_C_DN<4>")
	)
	(arc
		(start 52.12461 -381.5715)
		(mid 52.12461 -381.571881)
		(end 52.12461 -381.572262)
		(width 0.1016)
		(layer "F.Cu")
		(net "P5E_CPU1_P0_TX_C_DN<4>")
	)
	(segment
		(start 45.441362 -372.01729)
		(end 46.192186 -372.768114)
		(width 0.1016)
		(layer "F.Cu")
		(net "P5E_CPU1_P0_TX_C_DN<3>")
	)
	(segment
		(start 50.92446 -383.13741)
		(end 51.017932 -383.230882)
		(width 0.1016)
		(layer "F.Cu")
		(net "P5E_CPU1_P0_TX_C_DN<3>")
	)
	(segment
		(start 46.192186 -372.768114)
		(end 46.350174 -372.768114)
		(width 0.1016)
		(layer "F.Cu")
		(net "P5E_CPU1_P0_TX_C_DN<3>")
	)
	(segment
		(start 47.869602 -377.514358)
		(end 48.12411 -377.9393)
		(width 0.1016)
		(layer "F.Cu")
		(net "P5E_CPU1_P0_TX_C_DN<3>")
	)
	(segment
		(start 45.256704 -371.18798)
		(end 45.256704 -371.57152)
		(width 0.1016)
		(layer "F.Cu")
		(net "P5E_CPU1_P0_TX_C_DN<3>")
	)
	(segment
		(start 48.12411 -377.9393)
		(end 50.757074 -381.147574)
		(width 0.1016)
		(layer "F.Cu")
		(net "P5E_CPU1_P0_TX_C_DN<3>")
	)
	(segment
		(start 46.566074 -373.142002)
		(end 46.827186 -373.403114)
		(width 0.1016)
		(layer "F.Cu")
		(net "P5E_CPU1_P0_TX_C_DN<3>")
	)
	(segment
		(start 51.017932 -383.230882)
		(end 51.017932 -383.92227)
		(width 0.1016)
		(layer "F.Cu")
		(net "P5E_CPU1_P0_TX_C_DN<3>")
	)
	(segment
		(start 47.015654 -375.452132)
		(end 47.869602 -377.514358)
		(width 0.1016)
		(layer "F.Cu")
		(net "P5E_CPU1_P0_TX_C_DN<3>")
	)
	(segment
		(start 50.92446 -381.614426)
		(end 50.92446 -383.13741)
		(width 0.1016)
		(layer "F.Cu")
		(net "P5E_CPU1_P0_TX_C_DN<3>")
	)
	(segment
		(start 45.605954 -370.83873)
		(end 45.256704 -371.18798)
		(width 0.1016)
		(layer "F.Cu")
		(net "P5E_CPU1_P0_TX_C_DN<3>")
	)
	(segment
		(start 46.566074 -372.984014)
		(end 46.566074 -373.142002)
		(width 0.1016)
		(layer "F.Cu")
		(net "P5E_CPU1_P0_TX_C_DN<3>")
	)
	(segment
		(start 46.966378 -373.738902)
		(end 46.966378 -375.203466)
		(width 0.1016)
		(layer "F.Cu")
		(net "P5E_CPU1_P0_TX_C_DN<3>")
	)
	(segment
		(start 46.350174 -372.768114)
		(end 46.566074 -372.984014)
		(width 0.1016)
		(layer "F.Cu")
		(net "P5E_CPU1_P0_TX_C_DN<3>")
	)
	(arc
		(start 46.827186 -373.403114)
		(mid 46.93018 -373.557161)
		(end 46.966378 -373.738902)
		(width 0.1016)
		(layer "F.Cu")
		(net "P5E_CPU1_P0_TX_C_DN<3>")
	)
	(arc
		(start 46.966378 -375.203466)
		(mid 46.978758 -375.33023)
		(end 47.015654 -375.452132)
		(width 0.1016)
		(layer "F.Cu")
		(net "P5E_CPU1_P0_TX_C_DN<3>")
	)
	(arc
		(start 45.256704 -371.57152)
		(mid 45.304692 -371.812774)
		(end 45.441362 -372.01729)
		(width 0.1016)
		(layer "F.Cu")
		(net "P5E_CPU1_P0_TX_C_DN<3>")
	)
	(arc
		(start 50.757074 -381.147574)
		(mid 50.881292 -381.366463)
		(end 50.92446 -381.614426)
		(width 0.1016)
		(layer "F.Cu")
		(net "P5E_CPU1_P0_TX_C_DN<3>")
	)
	(segment
		(start 49.818036 -383.230882)
		(end 49.818036 -383.92227)
		(width 0.1016)
		(layer "F.Cu")
		(net "P5E_CPU1_P0_TX_C_DN<2>")
	)
	(segment
		(start 45.63745 -375.78919)
		(end 45.85335 -376.00509)
		(width 0.1016)
		(layer "F.Cu")
		(net "P5E_CPU1_P0_TX_C_DN<2>")
	)
	(segment
		(start 45.85335 -376.00509)
		(end 45.85335 -376.163078)
		(width 0.1016)
		(layer "F.Cu")
		(net "P5E_CPU1_P0_TX_C_DN<2>")
	)
	(segment
		(start 45.85335 -376.163078)
		(end 45.984414 -376.294142)
		(width 0.1016)
		(layer "F.Cu")
		(net "P5E_CPU1_P0_TX_C_DN<2>")
	)
	(segment
		(start 43.554904 -373.65178)
		(end 43.554904 -374.282208)
		(width 0.1016)
		(layer "F.Cu")
		(net "P5E_CPU1_P0_TX_C_DN<2>")
	)
	(segment
		(start 45.184822 -375.49455)
		(end 45.479462 -375.78919)
		(width 0.1016)
		(layer "F.Cu")
		(net "P5E_CPU1_P0_TX_C_DN<2>")
	)
	(segment
		(start 44.148502 -375.034556)
		(end 45.06341 -375.413524)
		(width 0.1016)
		(layer "F.Cu")
		(net "P5E_CPU1_P0_TX_C_DN<2>")
	)
	(segment
		(start 47.298356 -378.919994)
		(end 49.504346 -381.605536)
		(width 0.1016)
		(layer "F.Cu")
		(net "P5E_CPU1_P0_TX_C_DN<2>")
	)
	(segment
		(start 49.724564 -382.220216)
		(end 49.724564 -383.13741)
		(width 0.1016)
		(layer "F.Cu")
		(net "P5E_CPU1_P0_TX_C_DN<2>")
	)
	(segment
		(start 43.904154 -373.30253)
		(end 43.554904 -373.65178)
		(width 0.1016)
		(layer "F.Cu")
		(net "P5E_CPU1_P0_TX_C_DN<2>")
	)
	(segment
		(start 46.904148 -378.32792)
		(end 47.038514 -378.55144)
		(width 0.1016)
		(layer "F.Cu")
		(net "P5E_CPU1_P0_TX_C_DN<2>")
	)
	(segment
		(start 49.724564 -383.13741)
		(end 49.818036 -383.230882)
		(width 0.1016)
		(layer "F.Cu")
		(net "P5E_CPU1_P0_TX_C_DN<2>")
	)
	(segment
		(start 46.18863 -376.599704)
		(end 46.904148 -378.32792)
		(width 0.1016)
		(layer "F.Cu")
		(net "P5E_CPU1_P0_TX_C_DN<2>")
	)
	(segment
		(start 43.749722 -374.751854)
		(end 43.797728 -374.79986)
		(width 0.1016)
		(layer "F.Cu")
		(net "P5E_CPU1_P0_TX_C_DN<2>")
	)
	(segment
		(start 45.479462 -375.78919)
		(end 45.63745 -375.78919)
		(width 0.1016)
		(layer "F.Cu")
		(net "P5E_CPU1_P0_TX_C_DN<2>")
	)
	(arc
		(start 45.06341 -375.413524)
		(mid 45.128117 -375.448045)
		(end 45.184822 -375.49455)
		(width 0.1016)
		(layer "F.Cu")
		(net "P5E_CPU1_P0_TX_C_DN<2>")
	)
	(arc
		(start 43.554904 -374.282208)
		(mid 43.605649 -374.53638)
		(end 43.749722 -374.751854)
		(width 0.1016)
		(layer "F.Cu")
		(net "P5E_CPU1_P0_TX_C_DN<2>")
	)
	(arc
		(start 43.797728 -374.79986)
		(mid 43.961566 -374.934467)
		(end 44.148502 -375.034556)
		(width 0.1016)
		(layer "F.Cu")
		(net "P5E_CPU1_P0_TX_C_DN<2>")
	)
	(arc
		(start 47.038514 -378.55144)
		(mid 47.161673 -378.740484)
		(end 47.298356 -378.919994)
		(width 0.1016)
		(layer "F.Cu")
		(net "P5E_CPU1_P0_TX_C_DN<2>")
	)
	(arc
		(start 49.504346 -381.605536)
		(mid 49.667835 -381.893755)
		(end 49.724564 -382.220216)
		(width 0.1016)
		(layer "F.Cu")
		(net "P5E_CPU1_P0_TX_C_DN<2>")
	)
	(arc
		(start 45.984414 -376.294142)
		(mid 46.101579 -376.436861)
		(end 46.18863 -376.599704)
		(width 0.1016)
		(layer "F.Cu")
		(net "P5E_CPU1_P0_TX_C_DN<2>")
	)
	(segment
		(start 47.069248 -380.867412)
		(end 48.081184 -382.100836)
		(width 0.1016)
		(layer "F.Cu")
		(net "P5E_CPU1_P0_TX_C_DN<1>")
	)
	(segment
		(start 45.910754 -379.474476)
		(end 45.88002 -379.62967)
		(width 0.1016)
		(layer "F.Cu")
		(net "P5E_CPU1_P0_TX_C_DN<1>")
	)
	(segment
		(start 48.317912 -383.520442)
		(end 48.317912 -383.402586)
		(width 0.1016)
		(layer "F.Cu")
		(net "P5E_CPU1_P0_TX_C_DN<1>")
	)
	(segment
		(start 46.465998 -380.264162)
		(end 47.069248 -380.867412)
		(width 0.1016)
		(layer "F.Cu")
		(net "P5E_CPU1_P0_TX_C_DN<1>")
	)
	(segment
		(start 43.234102 -376.85726)
		(end 43.605196 -376.486166)
		(width 0.1016)
		(layer "F.Cu")
		(net "P5E_CPU1_P0_TX_C_DN<1>")
	)
	(segment
		(start 45.45203 -378.81433)
		(end 45.598334 -378.874782)
		(width 0.1016)
		(layer "F.Cu")
		(net "P5E_CPU1_P0_TX_C_DN<1>")
	)
	(segment
		(start 48.015906 -383.2352)
		(end 48.015906 -383.50571)
		(width 0.1016)
		(layer "F.Cu")
		(net "P5E_CPU1_P0_TX_C_DN<1>")
	)
	(segment
		(start 48.015906 -383.50571)
		(end 48.107092 -383.596896)
		(width 0.1016)
		(layer "F.Cu")
		(net "P5E_CPU1_P0_TX_C_DN<1>")
	)
	(segment
		(start 45.88002 -379.62967)
		(end 46.049438 -379.883162)
		(width 0.1016)
		(layer "F.Cu")
		(net "P5E_CPU1_P0_TX_C_DN<1>")
	)
	(segment
		(start 48.107092 -383.596896)
		(end 48.241458 -383.596896)
		(width 0.1016)
		(layer "F.Cu")
		(net "P5E_CPU1_P0_TX_C_DN<1>")
	)
	(segment
		(start 48.207676 -382.311656)
		(end 48.308514 -382.554734)
		(width 0.1016)
		(layer "F.Cu")
		(net "P5E_CPU1_P0_TX_C_DN<1>")
	)
	(segment
		(start 48.308514 -382.942592)
		(end 48.015906 -383.2352)
		(width 0.1016)
		(layer "F.Cu")
		(net "P5E_CPU1_P0_TX_C_DN<1>")
	)
	(segment
		(start 48.241458 -383.596896)
		(end 48.317912 -383.520442)
		(width 0.1016)
		(layer "F.Cu")
		(net "P5E_CPU1_P0_TX_C_DN<1>")
	)
	(segment
		(start 43.605196 -376.486166)
		(end 43.68927 -376.486166)
		(width 0.1016)
		(layer "F.Cu")
		(net "P5E_CPU1_P0_TX_C_DN<1>")
	)
	(segment
		(start 45.598334 -378.874782)
		(end 45.74159 -379.221238)
		(width 0.1016)
		(layer "F.Cu")
		(net "P5E_CPU1_P0_TX_C_DN<1>")
	)
	(segment
		(start 46.049438 -379.883162)
		(end 46.204632 -379.91415)
		(width 0.1016)
		(layer "F.Cu")
		(net "P5E_CPU1_P0_TX_C_DN<1>")
	)
	(segment
		(start 48.308514 -382.554734)
		(end 48.308514 -382.942592)
		(width 0.1016)
		(layer "F.Cu")
		(net "P5E_CPU1_P0_TX_C_DN<1>")
	)
	(segment
		(start 45.395896 -378.386594)
		(end 45.335444 -378.53239)
		(width 0.1016)
		(layer "F.Cu")
		(net "P5E_CPU1_P0_TX_C_DN<1>")
	)
	(segment
		(start 44.5262 -376.832876)
		(end 44.852336 -377.159012)
		(width 0.1016)
		(layer "F.Cu")
		(net "P5E_CPU1_P0_TX_C_DN<1>")
	)
	(segment
		(start 45.74159 -379.221238)
		(end 45.910754 -379.474476)
		(width 0.1016)
		(layer "F.Cu")
		(net "P5E_CPU1_P0_TX_C_DN<1>")
	)
	(segment
		(start 45.335444 -378.53239)
		(end 45.45203 -378.81433)
		(width 0.1016)
		(layer "F.Cu")
		(net "P5E_CPU1_P0_TX_C_DN<1>")
	)
	(segment
		(start 48.081184 -382.100836)
		(end 48.207676 -382.311656)
		(width 0.1016)
		(layer "F.Cu")
		(net "P5E_CPU1_P0_TX_C_DN<1>")
	)
	(segment
		(start 46.204632 -379.91415)
		(end 46.318424 -380.08433)
		(width 0.1016)
		(layer "F.Cu")
		(net "P5E_CPU1_P0_TX_C_DN<1>")
	)
	(segment
		(start 44.945808 -377.298966)
		(end 45.395896 -378.386594)
		(width 0.1016)
		(layer "F.Cu")
		(net "P5E_CPU1_P0_TX_C_DN<1>")
	)
	(arc
		(start 43.68927 -376.486166)
		(mid 44.142215 -376.57628)
		(end 44.5262 -376.832876)
		(width 0.1016)
		(layer "F.Cu")
		(net "P5E_CPU1_P0_TX_C_DN<1>")
	)
	(arc
		(start 44.852336 -377.159012)
		(mid 44.905975 -377.22438)
		(end 44.945808 -377.298966)
		(width 0.1016)
		(layer "F.Cu")
		(net "P5E_CPU1_P0_TX_C_DN<1>")
	)
	(arc
		(start 46.318424 -380.08433)
		(mid 46.387795 -380.17787)
		(end 46.465998 -380.264162)
		(width 0.1016)
		(layer "F.Cu")
		(net "P5E_CPU1_P0_TX_C_DN<1>")
	)
	(segment
		(start 65.324482 -382.205484)
		(end 65.324482 -382.92659)
		(width 0.1016)
		(layer "F.Cu")
		(net "P5E_CPU1_P0_TX_C_DN<15>")
	)
	(segment
		(start 65.418462 -383.02057)
		(end 65.418462 -383.921762)
		(width 0.1016)
		(layer "F.Cu")
		(net "P5E_CPU1_P0_TX_C_DN<15>")
	)
	(segment
		(start 69.125084 -380.036578)
		(end 67.420236 -380.036578)
		(width 0.1016)
		(layer "F.Cu")
		(net "P5E_CPU1_P0_TX_C_DN<15>")
	)
	(segment
		(start 65.324482 -382.92659)
		(end 65.418462 -383.02057)
		(width 0.1016)
		(layer "F.Cu")
		(net "P5E_CPU1_P0_TX_C_DN<15>")
	)
	(segment
		(start 69.474334 -380.385828)
		(end 69.125084 -380.036578)
		(width 0.1016)
		(layer "F.Cu")
		(net "P5E_CPU1_P0_TX_C_DN<15>")
	)
	(segment
		(start 67.319144 -380.078488)
		(end 65.418208 -381.979424)
		(width 0.1016)
		(layer "F.Cu")
		(net "P5E_CPU1_P0_TX_C_DN<15>")
	)
	(segment
		(start 65.418462 -383.921762)
		(end 65.417954 -383.92227)
		(width 0.1016)
		(layer "F.Cu")
		(net "P5E_CPU1_P0_TX_C_DN<15>")
	)
	(arc
		(start 67.420236 -380.036578)
		(mid 67.365512 -380.047463)
		(end 67.319144 -380.078488)
		(width 0.1016)
		(layer "F.Cu")
		(net "P5E_CPU1_P0_TX_C_DN<15>")
	)
	(arc
		(start 65.418208 -381.979424)
		(mid 65.348853 -382.083127)
		(end 65.324482 -382.205484)
		(width 0.1016)
		(layer "F.Cu")
		(net "P5E_CPU1_P0_TX_C_DN<15>")
	)
	(segment
		(start 64.124586 -382.92659)
		(end 64.218566 -383.02057)
		(width 0.1016)
		(layer "F.Cu")
		(net "P5E_CPU1_P0_TX_C_DN<14>")
	)
	(segment
		(start 68.814696 -376.71883)
		(end 64.322452 -381.211074)
		(width 0.1016)
		(layer "F.Cu")
		(net "P5E_CPU1_P0_TX_C_DN<14>")
	)
	(segment
		(start 69.129148 -376.71883)
		(end 68.814696 -376.71883)
		(width 0.1016)
		(layer "F.Cu")
		(net "P5E_CPU1_P0_TX_C_DN<14>")
	)
	(segment
		(start 69.474334 -376.982228)
		(end 69.268848 -376.776742)
		(width 0.1016)
		(layer "F.Cu")
		(net "P5E_CPU1_P0_TX_C_DN<14>")
	)
	(segment
		(start 64.218566 -383.02057)
		(end 64.218566 -383.921762)
		(width 0.1016)
		(layer "F.Cu")
		(net "P5E_CPU1_P0_TX_C_DN<14>")
	)
	(segment
		(start 64.218566 -383.921762)
		(end 64.218058 -383.92227)
		(width 0.1016)
		(layer "F.Cu")
		(net "P5E_CPU1_P0_TX_C_DN<14>")
	)
	(segment
		(start 64.12484 -381.689102)
		(end 64.124586 -381.688848)
		(width 0.1016)
		(layer "F.Cu")
		(net "P5E_CPU1_P0_TX_C_DN<14>")
	)
	(segment
		(start 64.124586 -381.688848)
		(end 64.124586 -382.92659)
		(width 0.1016)
		(layer "F.Cu")
		(net "P5E_CPU1_P0_TX_C_DN<14>")
	)
	(segment
		(start 69.268848 -376.776742)
		(end 69.129148 -376.71883)
		(width 0.1016)
		(layer "F.Cu")
		(net "P5E_CPU1_P0_TX_C_DN<14>")
	)
	(arc
		(start 64.322452 -381.211074)
		(mid 64.176126 -381.430439)
		(end 64.12484 -381.689102)
		(width 0.1016)
		(layer "F.Cu")
		(net "P5E_CPU1_P0_TX_C_DN<14>")
	)
	(segment
		(start 69.180964 -372.288816)
		(end 70.385686 -373.493538)
		(width 0.1016)
		(layer "F.Cu")
		(net "P5E_CPU1_P0_TX_C_DN<13>")
	)
	(segment
		(start 68.516754 -370.83873)
		(end 68.866004 -371.18798)
		(width 0.1016)
		(layer "F.Cu")
		(net "P5E_CPU1_P0_TX_C_DN<13>")
	)
	(segment
		(start 62.415928 -383.50571)
		(end 62.507114 -383.596896)
		(width 0.1016)
		(layer "F.Cu")
		(net "P5E_CPU1_P0_TX_C_DN<13>")
	)
	(segment
		(start 62.415928 -383.2352)
		(end 62.415928 -383.50571)
		(width 0.1016)
		(layer "F.Cu")
		(net "P5E_CPU1_P0_TX_C_DN<13>")
	)
	(segment
		(start 62.708536 -382.942592)
		(end 62.415928 -383.2352)
		(width 0.1016)
		(layer "F.Cu")
		(net "P5E_CPU1_P0_TX_C_DN<13>")
	)
	(segment
		(start 68.866004 -371.18798)
		(end 68.866004 -371.527578)
		(width 0.1016)
		(layer "F.Cu")
		(net "P5E_CPU1_P0_TX_C_DN<13>")
	)
	(segment
		(start 62.708536 -380.972822)
		(end 62.708536 -382.942592)
		(width 0.1016)
		(layer "F.Cu")
		(net "P5E_CPU1_P0_TX_C_DN<13>")
	)
	(segment
		(start 62.507114 -383.596896)
		(end 62.64148 -383.596896)
		(width 0.1016)
		(layer "F.Cu")
		(net "P5E_CPU1_P0_TX_C_DN<13>")
	)
	(segment
		(start 62.717934 -383.520442)
		(end 62.717934 -383.402586)
		(width 0.1016)
		(layer "F.Cu")
		(net "P5E_CPU1_P0_TX_C_DN<13>")
	)
	(segment
		(start 62.64148 -383.596896)
		(end 62.717934 -383.520442)
		(width 0.1016)
		(layer "F.Cu")
		(net "P5E_CPU1_P0_TX_C_DN<13>")
	)
	(segment
		(start 70.367398 -374.55348)
		(end 69.941948 -374.97893)
		(width 0.1016)
		(layer "F.Cu")
		(net "P5E_CPU1_P0_TX_C_DN<13>")
	)
	(segment
		(start 69.65696 -375.09704)
		(end 68.776088 -375.09704)
		(width 0.1016)
		(layer "F.Cu")
		(net "P5E_CPU1_P0_TX_C_DN<13>")
	)
	(segment
		(start 68.205604 -375.333006)
		(end 62.808866 -380.729744)
		(width 0.1016)
		(layer "F.Cu")
		(net "P5E_CPU1_P0_TX_C_DN<13>")
	)
	(segment
		(start 70.540118 -373.866156)
		(end 70.540118 -374.136666)
		(width 0.1016)
		(layer "F.Cu")
		(net "P5E_CPU1_P0_TX_C_DN<13>")
	)
	(arc
		(start 70.540118 -374.136666)
		(mid 70.495227 -374.362257)
		(end 70.367398 -374.55348)
		(width 0.1016)
		(layer "F.Cu")
		(net "P5E_CPU1_P0_TX_C_DN<13>")
	)
	(arc
		(start 68.866004 -371.527578)
		(mid 68.947744 -371.939543)
		(end 69.180964 -372.288816)
		(width 0.1016)
		(layer "F.Cu")
		(net "P5E_CPU1_P0_TX_C_DN<13>")
	)
	(arc
		(start 68.776088 -375.09704)
		(mid 68.467351 -375.158246)
		(end 68.205604 -375.333006)
		(width 0.1016)
		(layer "F.Cu")
		(net "P5E_CPU1_P0_TX_C_DN<13>")
	)
	(arc
		(start 62.808866 -380.729744)
		(mid 62.734567 -380.841313)
		(end 62.708536 -380.972822)
		(width 0.1016)
		(layer "F.Cu")
		(net "P5E_CPU1_P0_TX_C_DN<13>")
	)
	(arc
		(start 69.941948 -374.97893)
		(mid 69.811209 -375.06635)
		(end 69.65696 -375.09704)
		(width 0.1016)
		(layer "F.Cu")
		(net "P5E_CPU1_P0_TX_C_DN<13>")
	)
	(arc
		(start 70.385686 -373.493538)
		(mid 70.499971 -373.664482)
		(end 70.540118 -373.866156)
		(width 0.1016)
		(layer "F.Cu")
		(net "P5E_CPU1_P0_TX_C_DN<13>")
	)
	(segment
		(start 61.818012 -383.230882)
		(end 61.818012 -383.92227)
		(width 0.1016)
		(layer "F.Cu")
		(net "P5E_CPU1_P0_TX_C_DN<12>")
	)
	(segment
		(start 66.956686 -372.925594)
		(end 67.172586 -373.141494)
		(width 0.1016)
		(layer "F.Cu")
		(net "P5E_CPU1_P0_TX_C_DN<12>")
	)
	(segment
		(start 67.172586 -373.299482)
		(end 67.287648 -373.414544)
		(width 0.1016)
		(layer "F.Cu")
		(net "P5E_CPU1_P0_TX_C_DN<12>")
	)
	(segment
		(start 65.867534 -371.99443)
		(end 66.798698 -372.925594)
		(width 0.1016)
		(layer "F.Cu")
		(net "P5E_CPU1_P0_TX_C_DN<12>")
	)
	(segment
		(start 65.678304 -371.18798)
		(end 65.678304 -371.5385)
		(width 0.1016)
		(layer "F.Cu")
		(net "P5E_CPU1_P0_TX_C_DN<12>")
	)
	(segment
		(start 67.172586 -373.141494)
		(end 67.172586 -373.299482)
		(width 0.1016)
		(layer "F.Cu")
		(net "P5E_CPU1_P0_TX_C_DN<12>")
	)
	(segment
		(start 61.72454 -383.13741)
		(end 61.818012 -383.230882)
		(width 0.1016)
		(layer "F.Cu")
		(net "P5E_CPU1_P0_TX_C_DN<12>")
	)
	(segment
		(start 67.387978 -373.657368)
		(end 67.387978 -374.563132)
		(width 0.1016)
		(layer "F.Cu")
		(net "P5E_CPU1_P0_TX_C_DN<12>")
	)
	(segment
		(start 61.72454 -380.734062)
		(end 61.72454 -383.13741)
		(width 0.1016)
		(layer "F.Cu")
		(net "P5E_CPU1_P0_TX_C_DN<12>")
	)
	(segment
		(start 66.027554 -370.83873)
		(end 65.678304 -371.18798)
		(width 0.1016)
		(layer "F.Cu")
		(net "P5E_CPU1_P0_TX_C_DN<12>")
	)
	(segment
		(start 66.798698 -372.925594)
		(end 66.956686 -372.925594)
		(width 0.1016)
		(layer "F.Cu")
		(net "P5E_CPU1_P0_TX_C_DN<12>")
	)
	(segment
		(start 67.252088 -374.890284)
		(end 61.948568 -380.194058)
		(width 0.1016)
		(layer "F.Cu")
		(net "P5E_CPU1_P0_TX_C_DN<12>")
	)
	(arc
		(start 65.678304 -371.5385)
		(mid 65.727595 -371.78527)
		(end 65.867534 -371.99443)
		(width 0.1016)
		(layer "F.Cu")
		(net "P5E_CPU1_P0_TX_C_DN<12>")
	)
	(arc
		(start 61.948568 -380.194058)
		(mid 61.782803 -380.44177)
		(end 61.72454 -380.734062)
		(width 0.1016)
		(layer "F.Cu")
		(net "P5E_CPU1_P0_TX_C_DN<12>")
	)
	(arc
		(start 67.287648 -373.414544)
		(mid 67.361952 -373.525982)
		(end 67.387978 -373.657368)
		(width 0.1016)
		(layer "F.Cu")
		(net "P5E_CPU1_P0_TX_C_DN<12>")
	)
	(arc
		(start 67.387978 -374.563132)
		(mid 67.35255 -374.740209)
		(end 67.252088 -374.890284)
		(width 0.1016)
		(layer "F.Cu")
		(net "P5E_CPU1_P0_TX_C_DN<12>")
	)
	(segment
		(start 60.52439 -383.13741)
		(end 60.618116 -383.231136)
		(width 0.1016)
		(layer "F.Cu")
		(net "P5E_CPU1_P0_TX_C_DN<11>")
	)
	(segment
		(start 63.976504 -375.021856)
		(end 64.088264 -375.133616)
		(width 0.1016)
		(layer "F.Cu")
		(net "P5E_CPU1_P0_TX_C_DN<11>")
	)
	(segment
		(start 63.876174 -376.479562)
		(end 60.561728 -379.794008)
		(width 0.1016)
		(layer "F.Cu")
		(net "P5E_CPU1_P0_TX_C_DN<11>")
	)
	(segment
		(start 60.618116 -383.231136)
		(end 60.618116 -383.92227)
		(width 0.1016)
		(layer "F.Cu")
		(net "P5E_CPU1_P0_TX_C_DN<11>")
	)
	(segment
		(start 64.088264 -375.133616)
		(end 64.088264 -375.438416)
		(width 0.1016)
		(layer "F.Cu")
		(net "P5E_CPU1_P0_TX_C_DN<11>")
	)
	(segment
		(start 63.976504 -375.550176)
		(end 63.976504 -376.236484)
		(width 0.1016)
		(layer "F.Cu")
		(net "P5E_CPU1_P0_TX_C_DN<11>")
	)
	(segment
		(start 64.325754 -373.30253)
		(end 63.976504 -373.65178)
		(width 0.1016)
		(layer "F.Cu")
		(net "P5E_CPU1_P0_TX_C_DN<11>")
	)
	(segment
		(start 64.088264 -375.438416)
		(end 63.976504 -375.550176)
		(width 0.1016)
		(layer "F.Cu")
		(net "P5E_CPU1_P0_TX_C_DN<11>")
	)
	(segment
		(start 60.52439 -379.884178)
		(end 60.52439 -383.13741)
		(width 0.1016)
		(layer "F.Cu")
		(net "P5E_CPU1_P0_TX_C_DN<11>")
	)
	(segment
		(start 63.976504 -373.65178)
		(end 63.976504 -375.021856)
		(width 0.1016)
		(layer "F.Cu")
		(net "P5E_CPU1_P0_TX_C_DN<11>")
	)
	(arc
		(start 60.561728 -379.794008)
		(mid 60.534085 -379.835378)
		(end 60.52439 -379.884178)
		(width 0.1016)
		(layer "F.Cu")
		(net "P5E_CPU1_P0_TX_C_DN<11>")
	)
	(arc
		(start 63.976504 -376.236484)
		(mid 63.950545 -376.368022)
		(end 63.876174 -376.479562)
		(width 0.1016)
		(layer "F.Cu")
		(net "P5E_CPU1_P0_TX_C_DN<11>")
	)
	(segment
		(start 59.324494 -383.13741)
		(end 59.417966 -383.230882)
		(width 0.1016)
		(layer "F.Cu")
		(net "P5E_CPU1_P0_TX_C_DN<10>")
	)
	(segment
		(start 59.914282 -378.262388)
		(end 59.914282 -378.420122)
		(width 0.1016)
		(layer "F.Cu")
		(net "P5E_CPU1_P0_TX_C_DN<10>")
	)
	(segment
		(start 59.324494 -378.904754)
		(end 59.324494 -383.13741)
		(width 0.1016)
		(layer "F.Cu")
		(net "P5E_CPU1_P0_TX_C_DN<10>")
	)
	(segment
		(start 62.623954 -375.76633)
		(end 62.273688 -376.116596)
		(width 0.1016)
		(layer "F.Cu")
		(net "P5E_CPU1_P0_TX_C_DN<10>")
	)
	(segment
		(start 60.593986 -377.58243)
		(end 59.914282 -378.262388)
		(width 0.1016)
		(layer "F.Cu")
		(net "P5E_CPU1_P0_TX_C_DN<10>")
	)
	(segment
		(start 62.173358 -376.44578)
		(end 61.191648 -377.427236)
		(width 0.1016)
		(layer "F.Cu")
		(net "P5E_CPU1_P0_TX_C_DN<10>")
	)
	(segment
		(start 62.273688 -376.116596)
		(end 62.273688 -376.202702)
		(width 0.1016)
		(layer "F.Cu")
		(net "P5E_CPU1_P0_TX_C_DN<10>")
	)
	(segment
		(start 59.540648 -378.635768)
		(end 59.361832 -378.814584)
		(width 0.1016)
		(layer "F.Cu")
		(net "P5E_CPU1_P0_TX_C_DN<10>")
	)
	(segment
		(start 60.92444 -377.537472)
		(end 60.70219 -377.537472)
		(width 0.1016)
		(layer "F.Cu")
		(net "P5E_CPU1_P0_TX_C_DN<10>")
	)
	(segment
		(start 59.417966 -383.230882)
		(end 59.417966 -383.92227)
		(width 0.1016)
		(layer "F.Cu")
		(net "P5E_CPU1_P0_TX_C_DN<10>")
	)
	(segment
		(start 59.914282 -378.420122)
		(end 59.698636 -378.635768)
		(width 0.1016)
		(layer "F.Cu")
		(net "P5E_CPU1_P0_TX_C_DN<10>")
	)
	(segment
		(start 59.698636 -378.635768)
		(end 59.540648 -378.635768)
		(width 0.1016)
		(layer "F.Cu")
		(net "P5E_CPU1_P0_TX_C_DN<10>")
	)
	(arc
		(start 60.70219 -377.537472)
		(mid 60.643606 -377.549161)
		(end 60.593986 -377.58243)
		(width 0.1016)
		(layer "F.Cu")
		(net "P5E_CPU1_P0_TX_C_DN<10>")
	)
	(arc
		(start 59.361832 -378.814584)
		(mid 59.334189 -378.855954)
		(end 59.324494 -378.904754)
		(width 0.1016)
		(layer "F.Cu")
		(net "P5E_CPU1_P0_TX_C_DN<10>")
	)
	(arc
		(start 61.191648 -377.427236)
		(mid 61.069008 -377.508932)
		(end 60.92444 -377.537472)
		(width 0.1016)
		(layer "F.Cu")
		(net "P5E_CPU1_P0_TX_C_DN<10>")
	)
	(arc
		(start 62.273688 -376.202702)
		(mid 62.247729 -376.33424)
		(end 62.173358 -376.44578)
		(width 0.1016)
		(layer "F.Cu")
		(net "P5E_CPU1_P0_TX_C_DN<10>")
	)
	(segment
		(start 46.032928 -381.883158)
		(end 46.637956 -382.133094)
		(width 0.1016)
		(layer "F.Cu")
		(net "P5E_CPU1_P0_TX_C_DN<0>")
	)
	(segment
		(start 47.324518 -383.13741)
		(end 47.41799 -383.230882)
		(width 0.1016)
		(layer "F.Cu")
		(net "P5E_CPU1_P0_TX_C_DN<0>")
	)
	(segment
		(start 43.581574 -381.827532)
		(end 45.752766 -381.827532)
		(width 0.1016)
		(layer "F.Cu")
		(net "P5E_CPU1_P0_TX_C_DN<0>")
	)
	(segment
		(start 43.234102 -381.48006)
		(end 43.581574 -381.827532)
		(width 0.1016)
		(layer "F.Cu")
		(net "P5E_CPU1_P0_TX_C_DN<0>")
	)
	(segment
		(start 47.324518 -382.727708)
		(end 47.324518 -383.13741)
		(width 0.1016)
		(layer "F.Cu")
		(net "P5E_CPU1_P0_TX_C_DN<0>")
	)
	(segment
		(start 47.41799 -383.230882)
		(end 47.41799 -383.92227)
		(width 0.1016)
		(layer "F.Cu")
		(net "P5E_CPU1_P0_TX_C_DN<0>")
	)
	(segment
		(start 46.920404 -382.32207)
		(end 47.324518 -382.727708)
		(width 0.1016)
		(layer "F.Cu")
		(net "P5E_CPU1_P0_TX_C_DN<0>")
	)
	(arc
		(start 45.752766 -381.827532)
		(mid 45.895585 -381.841564)
		(end 46.032928 -381.883158)
		(width 0.1016)
		(layer "F.Cu")
		(net "P5E_CPU1_P0_TX_C_DN<0>")
	)
	(arc
		(start 46.637956 -382.133094)
		(mid 46.788588 -382.213523)
		(end 46.920404 -382.32207)
		(width 0.1016)
		(layer "F.Cu")
		(net "P5E_CPU1_P0_TX_C_DN<0>")
	)
	(segment
		(start 32.890968 -17.343628)
		(end 33.160462 -17.613122)
		(width 0.12954)
		(layer "F.Cu")
		(net "P5E_CPU1_G1_TX_DP<9>")
	)
	(segment
		(start 33.186878 -16.366236)
		(end 32.890968 -16.662146)
		(width 0.12954)
		(layer "F.Cu")
		(net "P5E_CPU1_G1_TX_DP<9>")
	)
	(segment
		(start 32.890968 -16.662146)
		(end 32.890968 -17.343628)
		(width 0.12954)
		(layer "F.Cu")
		(net "P5E_CPU1_G1_TX_DP<9>")
	)
	(segment
		(start 104.72801 -246.370348)
		(end 104.261158 -246.10441)
		(width 0.12954)
		(layer "F.Cu")
		(net "P5E_CPU1_G1_TX_DP<9>")
	)
	(segment
		(start 102.703122 -231.988868)
		(end 102.664006 -232.011728)
		(width 0.1143)
		(layer "In11.Cu")
		(net "P5E_CPU1_G1_TX_DP<9>")
	)
	(segment
		(start 102.664006 -232.011728)
		(end 102.633526 -232.029508)
		(width 0.1143)
		(layer "In11.Cu")
		(net "P5E_CPU1_G1_TX_DP<9>")
	)
	(segment
		(start 150.778718 -159.936688)
		(end 150.778718 -163.40963)
		(width 0.14224)
		(layer "In11.Cu")
		(net "P5E_CPU1_G1_TX_DP<9>")
	)
	(segment
		(start 102.664006 -229.416864)
		(end 102.703122 -229.439724)
		(width 0.1143)
		(layer "In11.Cu")
		(net "P5E_CPU1_G1_TX_DP<9>")
	)
	(segment
		(start 149.1615 -168.15943)
		(end 145.695924 -173.147736)
		(width 0.14224)
		(layer "In11.Cu")
		(net "P5E_CPU1_G1_TX_DP<9>")
	)
	(segment
		(start 102.700582 -230.370634)
		(end 102.633526 -230.40975)
		(width 0.1143)
		(layer "In11.Cu")
		(net "P5E_CPU1_G1_TX_DP<9>")
	)
	(segment
		(start 102.664006 -228.771958)
		(end 102.633526 -228.789738)
		(width 0.1143)
		(layer "In11.Cu")
		(net "P5E_CPU1_G1_TX_DP<9>")
	)
	(segment
		(start 102.194106 -225.367088)
		(end 102.195122 -225.367596)
		(width 0.1143)
		(layer "In11.Cu")
		(net "P5E_CPU1_G1_TX_DP<9>")
	)
	(segment
		(start 102.186994 -225.363024)
		(end 102.18801 -225.363532)
		(width 0.1143)
		(layer "In11.Cu")
		(net "P5E_CPU1_G1_TX_DP<9>")
	)
	(segment
		(start 102.633526 -242.35918)
		(end 102.664006 -242.37696)
		(width 0.1143)
		(layer "In11.Cu")
		(net "P5E_CPU1_G1_TX_DP<9>")
	)
	(segment
		(start 102.664006 -237.516924)
		(end 102.703122 -237.539784)
		(width 0.1143)
		(layer "In11.Cu")
		(net "P5E_CPU1_G1_TX_DP<9>")
	)
	(segment
		(start 102.664006 -234.2769)
		(end 102.703122 -234.29976)
		(width 0.1143)
		(layer "In11.Cu")
		(net "P5E_CPU1_G1_TX_DP<9>")
	)
	(segment
		(start 101.066346 -221.339918)
		(end 101.066346 -221.804484)
		(width 0.1143)
		(layer "In11.Cu")
		(net "P5E_CPU1_G1_TX_DP<9>")
	)
	(segment
		(start 102.664006 -232.656888)
		(end 102.703122 -232.679748)
		(width 0.1143)
		(layer "In11.Cu")
		(net "P5E_CPU1_G1_TX_DP<9>")
	)
	(segment
		(start 102.633526 -226.159314)
		(end 102.664006 -226.177094)
		(width 0.1143)
		(layer "In11.Cu")
		(net "P5E_CPU1_G1_TX_DP<9>")
	)
	(segment
		(start 102.664006 -233.63174)
		(end 102.633526 -233.64952)
		(width 0.1143)
		(layer "In11.Cu")
		(net "P5E_CPU1_G1_TX_DP<9>")
	)
	(segment
		(start 101.081332 -215.516206)
		(end 101.081078 -215.51646)
		(width 0.14224)
		(layer "In11.Cu")
		(net "P5E_CPU1_G1_TX_DP<9>")
	)
	(segment
		(start 103.880412 -246.021606)
		(end 103.963216 -246.10441)
		(width 0.1143)
		(layer "In11.Cu")
		(net "P5E_CPU1_G1_TX_DP<9>")
	)
	(segment
		(start 101.693472 -222.91929)
		(end 101.723952 -222.93707)
		(width 0.1143)
		(layer "In11.Cu")
		(net "P5E_CPU1_G1_TX_DP<9>")
	)
	(segment
		(start 102.703122 -243.328952)
		(end 102.664006 -243.351812)
		(width 0.1143)
		(layer "In11.Cu")
		(net "P5E_CPU1_G1_TX_DP<9>")
	)
	(segment
		(start 103.603552 -245.61673)
		(end 103.642414 -245.639336)
		(width 0.1143)
		(layer "In11.Cu")
		(net "P5E_CPU1_G1_TX_DP<9>")
	)
	(segment
		(start 101.693472 -224.539302)
		(end 101.723952 -224.557082)
		(width 0.1143)
		(layer "In11.Cu")
		(net "P5E_CPU1_G1_TX_DP<9>")
	)
	(segment
		(start 102.703122 -227.129086)
		(end 102.664006 -227.151946)
		(width 0.1143)
		(layer "In11.Cu")
		(net "P5E_CPU1_G1_TX_DP<9>")
	)
	(segment
		(start 102.703122 -240.088928)
		(end 102.664006 -240.111788)
		(width 0.1143)
		(layer "In11.Cu")
		(net "P5E_CPU1_G1_TX_DP<9>")
	)
	(segment
		(start 102.702614 -228.749352)
		(end 102.664006 -228.771958)
		(width 0.1143)
		(layer "In11.Cu")
		(net "P5E_CPU1_G1_TX_DP<9>")
	)
	(segment
		(start 102.633526 -234.25912)
		(end 102.664006 -234.2769)
		(width 0.1143)
		(layer "In11.Cu")
		(net "P5E_CPU1_G1_TX_DP<9>")
	)
	(segment
		(start 102.633526 -227.779326)
		(end 102.664006 -227.797106)
		(width 0.1143)
		(layer "In11.Cu")
		(net "P5E_CPU1_G1_TX_DP<9>")
	)
	(segment
		(start 101.723952 -222.93707)
		(end 101.763068 -222.95993)
		(width 0.1143)
		(layer "In11.Cu")
		(net "P5E_CPU1_G1_TX_DP<9>")
	)
	(segment
		(start 33.160462 -17.613122)
		(end 32.869632 -17.903952)
		(width 0.14224)
		(layer "In11.Cu")
		(net "P5E_CPU1_G1_TX_DP<9>")
	)
	(segment
		(start 101.22281 -222.10903)
		(end 101.223064 -222.10903)
		(width 0.1143)
		(layer "In11.Cu")
		(net "P5E_CPU1_G1_TX_DP<9>")
	)
	(segment
		(start 149.960838 -146.863816)
		(end 150.778718 -159.936688)
		(width 0.14224)
		(layer "In11.Cu")
		(net "P5E_CPU1_G1_TX_DP<9>")
	)
	(segment
		(start 102.193344 -225.36658)
		(end 102.194106 -225.367088)
		(width 0.1143)
		(layer "In11.Cu")
		(net "P5E_CPU1_G1_TX_DP<9>")
	)
	(segment
		(start 102.633526 -240.739168)
		(end 102.664006 -240.756948)
		(width 0.1143)
		(layer "In11.Cu")
		(net "P5E_CPU1_G1_TX_DP<9>")
	)
	(segment
		(start 102.664006 -242.37696)
		(end 102.703122 -242.39982)
		(width 0.1143)
		(layer "In11.Cu")
		(net "P5E_CPU1_G1_TX_DP<9>")
	)
	(segment
		(start 107.71759 -204.272896)
		(end 101.081332 -215.516206)
		(width 0.14224)
		(layer "In11.Cu")
		(net "P5E_CPU1_G1_TX_DP<9>")
	)
	(segment
		(start 102.18801 -225.363532)
		(end 102.189534 -225.364548)
		(width 0.1143)
		(layer "In11.Cu")
		(net "P5E_CPU1_G1_TX_DP<9>")
	)
	(segment
		(start 102.664006 -235.251752)
		(end 102.633526 -235.269532)
		(width 0.1143)
		(layer "In11.Cu")
		(net "P5E_CPU1_G1_TX_DP<9>")
	)
	(segment
		(start 53.747924 -56.125872)
		(end 54.383686 -56.655716)
		(width 0.14224)
		(layer "In11.Cu")
		(net "P5E_CPU1_G1_TX_DP<9>")
	)
	(segment
		(start 102.162356 -225.3488)
		(end 102.186994 -225.363024)
		(width 0.1143)
		(layer "In11.Cu")
		(net "P5E_CPU1_G1_TX_DP<9>")
	)
	(segment
		(start 101.723952 -223.911922)
		(end 101.693472 -223.929702)
		(width 0.1143)
		(layer "In11.Cu")
		(net "P5E_CPU1_G1_TX_DP<9>")
	)
	(segment
		(start 32.869632 -20.192746)
		(end 46.116748 -46.514512)
		(width 0.14224)
		(layer "In11.Cu")
		(net "P5E_CPU1_G1_TX_DP<9>")
	)
	(segment
		(start 102.664006 -231.036876)
		(end 102.703122 -231.059736)
		(width 0.1143)
		(layer "In11.Cu")
		(net "P5E_CPU1_G1_TX_DP<9>")
	)
	(segment
		(start 102.664006 -238.491776)
		(end 102.633526 -238.509556)
		(width 0.1143)
		(layer "In11.Cu")
		(net "P5E_CPU1_G1_TX_DP<9>")
	)
	(segment
		(start 102.664006 -239.136936)
		(end 102.703122 -239.159796)
		(width 0.1143)
		(layer "In11.Cu")
		(net "P5E_CPU1_G1_TX_DP<9>")
	)
	(segment
		(start 102.664006 -243.351812)
		(end 102.633526 -243.369592)
		(width 0.1143)
		(layer "In11.Cu")
		(net "P5E_CPU1_G1_TX_DP<9>")
	)
	(segment
		(start 103.963216 -246.10441)
		(end 104.261158 -246.10441)
		(width 0.1143)
		(layer "In11.Cu")
		(net "P5E_CPU1_G1_TX_DP<9>")
	)
	(segment
		(start 102.664006 -227.151946)
		(end 102.633526 -227.169726)
		(width 0.1143)
		(layer "In11.Cu")
		(net "P5E_CPU1_G1_TX_DP<9>")
	)
	(segment
		(start 102.703122 -235.228892)
		(end 102.664006 -235.251752)
		(width 0.1143)
		(layer "In11.Cu")
		(net "P5E_CPU1_G1_TX_DP<9>")
	)
	(segment
		(start 101.081078 -215.51646)
		(end 101.081078 -221.05493)
		(width 0.14224)
		(layer "In11.Cu")
		(net "P5E_CPU1_G1_TX_DP<9>")
	)
	(segment
		(start 102.703122 -238.468916)
		(end 102.664006 -238.491776)
		(width 0.1143)
		(layer "In11.Cu")
		(net "P5E_CPU1_G1_TX_DP<9>")
	)
	(segment
		(start 32.869632 -17.903952)
		(end 32.869632 -20.192746)
		(width 0.14224)
		(layer "In11.Cu")
		(net "P5E_CPU1_G1_TX_DP<9>")
	)
	(segment
		(start 103.4288 -245.303802)
		(end 103.4288 -245.313454)
		(width 0.1143)
		(layer "In11.Cu")
		(net "P5E_CPU1_G1_TX_DP<9>")
	)
	(segment
		(start 54.383686 -56.655716)
		(end 146.31416 -139.323318)
		(width 0.14224)
		(layer "In11.Cu")
		(net "P5E_CPU1_G1_TX_DP<9>")
	)
	(segment
		(start 102.633526 -237.499144)
		(end 102.664006 -237.516924)
		(width 0.1143)
		(layer "In11.Cu")
		(net "P5E_CPU1_G1_TX_DP<9>")
	)
	(segment
		(start 102.633526 -235.879132)
		(end 102.664006 -235.896912)
		(width 0.1143)
		(layer "In11.Cu")
		(net "P5E_CPU1_G1_TX_DP<9>")
	)
	(segment
		(start 102.664006 -241.7318)
		(end 102.633526 -241.74958)
		(width 0.1143)
		(layer "In11.Cu")
		(net "P5E_CPU1_G1_TX_DP<9>")
	)
	(segment
		(start 102.633526 -239.119156)
		(end 102.664006 -239.136936)
		(width 0.1143)
		(layer "In11.Cu")
		(net "P5E_CPU1_G1_TX_DP<9>")
	)
	(segment
		(start 101.763068 -223.889062)
		(end 101.723952 -223.911922)
		(width 0.1143)
		(layer "In11.Cu")
		(net "P5E_CPU1_G1_TX_DP<9>")
	)
	(segment
		(start 102.664006 -226.177094)
		(end 102.703122 -226.199954)
		(width 0.1143)
		(layer "In11.Cu")
		(net "P5E_CPU1_G1_TX_DP<9>")
	)
	(segment
		(start 101.081078 -221.05493)
		(end 101.081078 -221.083378)
		(width 0.1143)
		(layer "In11.Cu")
		(net "P5E_CPU1_G1_TX_DP<9>")
	)
	(segment
		(start 102.631494 -229.398068)
		(end 102.664006 -229.416864)
		(width 0.1143)
		(layer "In11.Cu")
		(net "P5E_CPU1_G1_TX_DP<9>")
	)
	(segment
		(start 102.664006 -235.896912)
		(end 102.703122 -235.919772)
		(width 0.1143)
		(layer "In11.Cu")
		(net "P5E_CPU1_G1_TX_DP<9>")
	)
	(segment
		(start 146.31416 -139.323318)
		(end 149.960838 -146.863816)
		(width 0.14224)
		(layer "In11.Cu")
		(net "P5E_CPU1_G1_TX_DP<9>")
	)
	(segment
		(start 102.703122 -236.848904)
		(end 102.664006 -236.871764)
		(width 0.1143)
		(layer "In11.Cu")
		(net "P5E_CPU1_G1_TX_DP<9>")
	)
	(segment
		(start 102.192074 -225.365818)
		(end 102.193344 -225.36658)
		(width 0.1143)
		(layer "In11.Cu")
		(net "P5E_CPU1_G1_TX_DP<9>")
	)
	(segment
		(start 102.664006 -227.797106)
		(end 102.703122 -227.819966)
		(width 0.1143)
		(layer "In11.Cu")
		(net "P5E_CPU1_G1_TX_DP<9>")
	)
	(segment
		(start 102.664006 -240.111788)
		(end 102.633526 -240.129568)
		(width 0.1143)
		(layer "In11.Cu")
		(net "P5E_CPU1_G1_TX_DP<9>")
	)
	(segment
		(start 102.196646 -225.368612)
		(end 102.233222 -225.389948)
		(width 0.1143)
		(layer "In11.Cu")
		(net "P5E_CPU1_G1_TX_DP<9>")
	)
	(segment
		(start 101.723952 -224.557082)
		(end 101.763068 -224.579942)
		(width 0.1143)
		(layer "In11.Cu")
		(net "P5E_CPU1_G1_TX_DP<9>")
	)
	(segment
		(start 102.703122 -241.70894)
		(end 102.664006 -241.7318)
		(width 0.1143)
		(layer "In11.Cu")
		(net "P5E_CPU1_G1_TX_DP<9>")
	)
	(segment
		(start 102.703122 -233.60888)
		(end 102.664006 -233.63174)
		(width 0.1143)
		(layer "In11.Cu")
		(net "P5E_CPU1_G1_TX_DP<9>")
	)
	(segment
		(start 145.695924 -173.147736)
		(end 107.71759 -204.272896)
		(width 0.14224)
		(layer "In11.Cu")
		(net "P5E_CPU1_G1_TX_DP<9>")
	)
	(segment
		(start 102.664006 -236.871764)
		(end 102.633526 -236.889544)
		(width 0.1143)
		(layer "In11.Cu")
		(net "P5E_CPU1_G1_TX_DP<9>")
	)
	(segment
		(start 102.703122 -228.749098)
		(end 102.702614 -228.749352)
		(width 0.1143)
		(layer "In11.Cu")
		(net "P5E_CPU1_G1_TX_DP<9>")
	)
	(segment
		(start 102.664006 -243.996972)
		(end 102.703122 -244.019832)
		(width 0.1143)
		(layer "In11.Cu")
		(net "P5E_CPU1_G1_TX_DP<9>")
	)
	(segment
		(start 101.081078 -221.083378)
		(end 101.035358 -221.129098)
		(width 0.1143)
		(layer "In11.Cu")
		(net "P5E_CPU1_G1_TX_DP<9>")
	)
	(segment
		(start 102.664006 -240.756948)
		(end 102.703122 -240.779808)
		(width 0.1143)
		(layer "In11.Cu")
		(net "P5E_CPU1_G1_TX_DP<9>")
	)
	(segment
		(start 102.631494 -231.01808)
		(end 102.664006 -231.036876)
		(width 0.1143)
		(layer "In11.Cu")
		(net "P5E_CPU1_G1_TX_DP<9>")
	)
	(segment
		(start 150.778718 -163.40963)
		(end 149.1615 -168.15943)
		(width 0.14224)
		(layer "In11.Cu")
		(net "P5E_CPU1_G1_TX_DP<9>")
	)
	(segment
		(start 101.223064 -222.10903)
		(end 101.293168 -222.149924)
		(width 0.1143)
		(layer "In11.Cu")
		(net "P5E_CPU1_G1_TX_DP<9>")
	)
	(segment
		(start 102.189534 -225.364548)
		(end 102.192074 -225.365818)
		(width 0.1143)
		(layer "In11.Cu")
		(net "P5E_CPU1_G1_TX_DP<9>")
	)
	(segment
		(start 103.102156 -244.788436)
		(end 103.145336 -244.813582)
		(width 0.1143)
		(layer "In11.Cu")
		(net "P5E_CPU1_G1_TX_DP<9>")
	)
	(segment
		(start 101.035358 -221.30893)
		(end 101.066346 -221.339918)
		(width 0.1143)
		(layer "In11.Cu")
		(net "P5E_CPU1_G1_TX_DP<9>")
	)
	(segment
		(start 102.195122 -225.367596)
		(end 102.196646 -225.368612)
		(width 0.1143)
		(layer "In11.Cu")
		(net "P5E_CPU1_G1_TX_DP<9>")
	)
	(segment
		(start 46.116748 -46.514512)
		(end 53.747924 -56.125872)
		(width 0.14224)
		(layer "In11.Cu")
		(net "P5E_CPU1_G1_TX_DP<9>")
	)
	(segment
		(start 101.035358 -221.129098)
		(end 101.035358 -221.30893)
		(width 0.1143)
		(layer "In11.Cu")
		(net "P5E_CPU1_G1_TX_DP<9>")
	)
	(segment
		(start 102.633526 -232.639108)
		(end 102.664006 -232.656888)
		(width 0.1143)
		(layer "In11.Cu")
		(net "P5E_CPU1_G1_TX_DP<9>")
	)
	(segment
		(start 102.633526 -243.979192)
		(end 102.664006 -243.996972)
		(width 0.1143)
		(layer "In11.Cu")
		(net "P5E_CPU1_G1_TX_DP<9>")
	)
	(arc
		(start 102.703122 -244.019832)
		(mid 102.881935 -244.222182)
		(end 102.946454 -244.484398)
		(width 0.1143)
		(layer "In11.Cu")
		(net "P5E_CPU1_G1_TX_DP<9>")
	)
	(arc
		(start 102.633526 -228.789738)
		(mid 102.518099 -228.923114)
		(end 102.476554 -229.094538)
		(width 0.1143)
		(layer "In11.Cu")
		(net "P5E_CPU1_G1_TX_DP<9>")
	)
	(arc
		(start 101.066346 -221.804484)
		(mid 101.107748 -221.975681)
		(end 101.22281 -222.10903)
		(width 0.1143)
		(layer "In11.Cu")
		(net "P5E_CPU1_G1_TX_DP<9>")
	)
	(arc
		(start 103.643176 -245.639844)
		(mid 103.795163 -245.796352)
		(end 103.876602 -245.998746)
		(width 0.1143)
		(layer "In11.Cu")
		(net "P5E_CPU1_G1_TX_DP<9>")
	)
	(arc
		(start 102.703122 -234.29976)
		(mid 102.946449 -234.764326)
		(end 102.703122 -235.228892)
		(width 0.1143)
		(layer "In11.Cu")
		(net "P5E_CPU1_G1_TX_DP<9>")
	)
	(arc
		(start 102.476554 -229.094538)
		(mid 102.51752 -229.264944)
		(end 102.631494 -229.398068)
		(width 0.1143)
		(layer "In11.Cu")
		(net "P5E_CPU1_G1_TX_DP<9>")
	)
	(arc
		(start 102.0064 -225.044508)
		(mid 102.047655 -225.215479)
		(end 102.162356 -225.3488)
		(width 0.1143)
		(layer "In11.Cu")
		(net "P5E_CPU1_G1_TX_DP<9>")
	)
	(arc
		(start 102.703122 -235.919772)
		(mid 102.946449 -236.384338)
		(end 102.703122 -236.848904)
		(width 0.1143)
		(layer "In11.Cu")
		(net "P5E_CPU1_G1_TX_DP<9>")
	)
	(arc
		(start 102.633526 -233.64952)
		(mid 102.476549 -233.95432)
		(end 102.633526 -234.25912)
		(width 0.1143)
		(layer "In11.Cu")
		(net "P5E_CPU1_G1_TX_DP<9>")
	)
	(arc
		(start 102.633526 -227.169726)
		(mid 102.476549 -227.474526)
		(end 102.633526 -227.779326)
		(width 0.1143)
		(layer "In11.Cu")
		(net "P5E_CPU1_G1_TX_DP<9>")
	)
	(arc
		(start 102.703122 -239.159796)
		(mid 102.946449 -239.624362)
		(end 102.703122 -240.088928)
		(width 0.1143)
		(layer "In11.Cu")
		(net "P5E_CPU1_G1_TX_DP<9>")
	)
	(arc
		(start 102.633526 -241.74958)
		(mid 102.476549 -242.05438)
		(end 102.633526 -242.35918)
		(width 0.1143)
		(layer "In11.Cu")
		(net "P5E_CPU1_G1_TX_DP<9>")
	)
	(arc
		(start 101.293168 -222.149924)
		(mid 101.471981 -222.352274)
		(end 101.5365 -222.61449)
		(width 0.1143)
		(layer "In11.Cu")
		(net "P5E_CPU1_G1_TX_DP<9>")
	)
	(arc
		(start 101.5365 -222.61449)
		(mid 101.578049 -222.785912)
		(end 101.693472 -222.91929)
		(width 0.1143)
		(layer "In11.Cu")
		(net "P5E_CPU1_G1_TX_DP<9>")
	)
	(arc
		(start 101.763068 -222.95993)
		(mid 102.006395 -223.424496)
		(end 101.763068 -223.889062)
		(width 0.1143)
		(layer "In11.Cu")
		(net "P5E_CPU1_G1_TX_DP<9>")
	)
	(arc
		(start 102.476554 -230.71455)
		(mid 102.51752 -230.884956)
		(end 102.631494 -231.01808)
		(width 0.1143)
		(layer "In11.Cu")
		(net "P5E_CPU1_G1_TX_DP<9>")
	)
	(arc
		(start 102.633526 -243.369592)
		(mid 102.476549 -243.674392)
		(end 102.633526 -243.979192)
		(width 0.1143)
		(layer "In11.Cu")
		(net "P5E_CPU1_G1_TX_DP<9>")
	)
	(arc
		(start 102.703122 -232.679748)
		(mid 102.946449 -233.144314)
		(end 102.703122 -233.60888)
		(width 0.1143)
		(layer "In11.Cu")
		(net "P5E_CPU1_G1_TX_DP<9>")
	)
	(arc
		(start 101.763068 -224.579942)
		(mid 101.941881 -224.782292)
		(end 102.0064 -225.044508)
		(width 0.1143)
		(layer "In11.Cu")
		(net "P5E_CPU1_G1_TX_DP<9>")
	)
	(arc
		(start 102.703122 -229.439724)
		(mid 102.881935 -229.642074)
		(end 102.946454 -229.90429)
		(width 0.1143)
		(layer "In11.Cu")
		(net "P5E_CPU1_G1_TX_DP<9>")
	)
	(arc
		(start 103.642414 -245.639336)
		(mid 103.642795 -245.63959)
		(end 103.643176 -245.639844)
		(width 0.1143)
		(layer "In11.Cu")
		(net "P5E_CPU1_G1_TX_DP<9>")
	)
	(arc
		(start 103.876602 -245.998746)
		(mid 103.878625 -246.010156)
		(end 103.880412 -246.021606)
		(width 0.1143)
		(layer "In11.Cu")
		(net "P5E_CPU1_G1_TX_DP<9>")
	)
	(arc
		(start 103.145336 -244.813582)
		(mid 103.35282 -245.020669)
		(end 103.4288 -245.303802)
		(width 0.1143)
		(layer "In11.Cu")
		(net "P5E_CPU1_G1_TX_DP<9>")
	)
	(arc
		(start 102.703122 -242.39982)
		(mid 102.946449 -242.864386)
		(end 102.703122 -243.328952)
		(width 0.1143)
		(layer "In11.Cu")
		(net "P5E_CPU1_G1_TX_DP<9>")
	)
	(arc
		(start 102.946454 -244.484398)
		(mid 102.987647 -244.655187)
		(end 103.102156 -244.788436)
		(width 0.1143)
		(layer "In11.Cu")
		(net "P5E_CPU1_G1_TX_DP<9>")
	)
	(arc
		(start 102.703122 -227.819966)
		(mid 102.946449 -228.284532)
		(end 102.703122 -228.749098)
		(width 0.1143)
		(layer "In11.Cu")
		(net "P5E_CPU1_G1_TX_DP<9>")
	)
	(arc
		(start 102.633526 -240.129568)
		(mid 102.476549 -240.434368)
		(end 102.633526 -240.739168)
		(width 0.1143)
		(layer "In11.Cu")
		(net "P5E_CPU1_G1_TX_DP<9>")
	)
	(arc
		(start 102.476554 -225.854514)
		(mid 102.518103 -226.025936)
		(end 102.633526 -226.159314)
		(width 0.1143)
		(layer "In11.Cu")
		(net "P5E_CPU1_G1_TX_DP<9>")
	)
	(arc
		(start 101.693472 -223.929702)
		(mid 101.536495 -224.234502)
		(end 101.693472 -224.539302)
		(width 0.1143)
		(layer "In11.Cu")
		(net "P5E_CPU1_G1_TX_DP<9>")
	)
	(arc
		(start 102.633526 -232.029508)
		(mid 102.476549 -232.334308)
		(end 102.633526 -232.639108)
		(width 0.1143)
		(layer "In11.Cu")
		(net "P5E_CPU1_G1_TX_DP<9>")
	)
	(arc
		(start 102.633526 -235.269532)
		(mid 102.476549 -235.574332)
		(end 102.633526 -235.879132)
		(width 0.1143)
		(layer "In11.Cu")
		(net "P5E_CPU1_G1_TX_DP<9>")
	)
	(arc
		(start 102.703122 -240.779808)
		(mid 102.946449 -241.244374)
		(end 102.703122 -241.70894)
		(width 0.1143)
		(layer "In11.Cu")
		(net "P5E_CPU1_G1_TX_DP<9>")
	)
	(arc
		(start 102.703122 -237.539784)
		(mid 102.946449 -238.00435)
		(end 102.703122 -238.468916)
		(width 0.1143)
		(layer "In11.Cu")
		(net "P5E_CPU1_G1_TX_DP<9>")
	)
	(arc
		(start 102.633526 -230.40975)
		(mid 102.518099 -230.543126)
		(end 102.476554 -230.71455)
		(width 0.1143)
		(layer "In11.Cu")
		(net "P5E_CPU1_G1_TX_DP<9>")
	)
	(arc
		(start 102.633526 -236.889544)
		(mid 102.476549 -237.194344)
		(end 102.633526 -237.499144)
		(width 0.1143)
		(layer "In11.Cu")
		(net "P5E_CPU1_G1_TX_DP<9>")
	)
	(arc
		(start 102.233222 -225.389948)
		(mid 102.412035 -225.592298)
		(end 102.476554 -225.854514)
		(width 0.1143)
		(layer "In11.Cu")
		(net "P5E_CPU1_G1_TX_DP<9>")
	)
	(arc
		(start 102.633526 -238.509556)
		(mid 102.476549 -238.814356)
		(end 102.633526 -239.119156)
		(width 0.1143)
		(layer "In11.Cu")
		(net "P5E_CPU1_G1_TX_DP<9>")
	)
	(arc
		(start 102.703122 -231.059736)
		(mid 102.946449 -231.524302)
		(end 102.703122 -231.988868)
		(width 0.1143)
		(layer "In11.Cu")
		(net "P5E_CPU1_G1_TX_DP<9>")
	)
	(arc
		(start 102.946454 -229.90429)
		(mid 102.881218 -230.167881)
		(end 102.700582 -230.370634)
		(width 0.1143)
		(layer "In11.Cu")
		(net "P5E_CPU1_G1_TX_DP<9>")
	)
	(arc
		(start 102.703122 -226.199954)
		(mid 102.946449 -226.66452)
		(end 102.703122 -227.129086)
		(width 0.1143)
		(layer "In11.Cu")
		(net "P5E_CPU1_G1_TX_DP<9>")
	)
	(arc
		(start 103.4288 -245.313454)
		(mid 103.47569 -245.488405)
		(end 103.603552 -245.61673)
		(width 0.1143)
		(layer "In11.Cu")
		(net "P5E_CPU1_G1_TX_DP<9>")
	)
	(segment
		(start 104.72801 -244.750336)
		(end 104.261158 -244.484398)
		(width 0.12954)
		(layer "F.Cu")
		(net "P5E_CPU1_G1_TX_DP<8>")
	)
	(segment
		(start 35.684968 -18.86585)
		(end 35.955478 -19.13636)
		(width 0.12954)
		(layer "F.Cu")
		(net "P5E_CPU1_G1_TX_DP<8>")
	)
	(segment
		(start 35.980878 -17.890236)
		(end 35.684968 -18.186146)
		(width 0.12954)
		(layer "F.Cu")
		(net "P5E_CPU1_G1_TX_DP<8>")
	)
	(segment
		(start 35.684968 -18.186146)
		(end 35.684968 -18.86585)
		(width 0.12954)
		(layer "F.Cu")
		(net "P5E_CPU1_G1_TX_DP<8>")
	)
	(segment
		(start 103.880412 -244.401594)
		(end 103.963216 -244.484398)
		(width 0.1143)
		(layer "In11.Cu")
		(net "P5E_CPU1_G1_TX_DP<8>")
	)
	(segment
		(start 103.608632 -235.899452)
		(end 103.609394 -235.89996)
		(width 0.1143)
		(layer "In11.Cu")
		(net "P5E_CPU1_G1_TX_DP<8>")
	)
	(segment
		(start 103.609394 -242.380008)
		(end 103.61041 -242.380516)
		(width 0.1143)
		(layer "In11.Cu")
		(net "P5E_CPU1_G1_TX_DP<8>")
	)
	(segment
		(start 103.60406 -229.416864)
		(end 103.643176 -229.439724)
		(width 0.1143)
		(layer "In11.Cu")
		(net "P5E_CPU1_G1_TX_DP<8>")
	)
	(segment
		(start 102.05212 -221.083378)
		(end 102.0064 -221.129098)
		(width 0.1143)
		(layer "In11.Cu")
		(net "P5E_CPU1_G1_TX_DP<8>")
	)
	(segment
		(start 103.61041 -242.380516)
		(end 103.642414 -242.399312)
		(width 0.1143)
		(layer "In11.Cu")
		(net "P5E_CPU1_G1_TX_DP<8>")
	)
	(segment
		(start 103.57231 -227.778818)
		(end 103.60406 -227.797106)
		(width 0.1143)
		(layer "In11.Cu")
		(net "P5E_CPU1_G1_TX_DP<8>")
	)
	(segment
		(start 103.643176 -227.129086)
		(end 103.640382 -227.131118)
		(width 0.1143)
		(layer "In11.Cu")
		(net "P5E_CPU1_G1_TX_DP<8>")
	)
	(segment
		(start 149.91842 -168.948608)
		(end 146.519646 -173.680374)
		(width 0.14224)
		(layer "In11.Cu")
		(net "P5E_CPU1_G1_TX_DP<8>")
	)
	(segment
		(start 103.605076 -228.77145)
		(end 103.60406 -228.771958)
		(width 0.1143)
		(layer "In11.Cu")
		(net "P5E_CPU1_G1_TX_DP<8>")
	)
	(segment
		(start 54.37886 -55.371492)
		(end 54.380384 -55.372762)
		(width 0.14224)
		(layer "In11.Cu")
		(net "P5E_CPU1_G1_TX_DP<8>")
	)
	(segment
		(start 35.955478 -19.13636)
		(end 35.664648 -19.42719)
		(width 0.14224)
		(layer "In11.Cu")
		(net "P5E_CPU1_G1_TX_DP<8>")
	)
	(segment
		(start 103.640636 -230.370634)
		(end 103.605076 -230.391462)
		(width 0.1143)
		(layer "In11.Cu")
		(net "P5E_CPU1_G1_TX_DP<8>")
	)
	(segment
		(start 103.609394 -237.519972)
		(end 103.61041 -237.52048)
		(width 0.1143)
		(layer "In11.Cu")
		(net "P5E_CPU1_G1_TX_DP<8>")
	)
	(segment
		(start 103.596186 -237.512352)
		(end 103.608632 -237.519464)
		(width 0.1143)
		(layer "In11.Cu")
		(net "P5E_CPU1_G1_TX_DP<8>")
	)
	(segment
		(start 103.61041 -237.52048)
		(end 103.642414 -237.539276)
		(width 0.1143)
		(layer "In11.Cu")
		(net "P5E_CPU1_G1_TX_DP<8>")
	)
	(segment
		(start 108.54309 -204.801978)
		(end 102.052628 -215.734392)
		(width 0.14224)
		(layer "In11.Cu")
		(net "P5E_CPU1_G1_TX_DP<8>")
	)
	(segment
		(start 103.63962 -234.29722)
		(end 103.642414 -234.299252)
		(width 0.1143)
		(layer "In11.Cu")
		(net "P5E_CPU1_G1_TX_DP<8>")
	)
	(segment
		(start 103.643176 -236.848904)
		(end 103.625142 -236.859572)
		(width 0.1143)
		(layer "In11.Cu")
		(net "P5E_CPU1_G1_TX_DP<8>")
	)
	(segment
		(start 103.600504 -230.394002)
		(end 103.57231 -230.410258)
		(width 0.1143)
		(layer "In11.Cu")
		(net "P5E_CPU1_G1_TX_DP<8>")
	)
	(segment
		(start 103.643176 -241.70894)
		(end 103.625142 -241.719608)
		(width 0.1143)
		(layer "In11.Cu")
		(net "P5E_CPU1_G1_TX_DP<8>")
	)
	(segment
		(start 103.643176 -231.988868)
		(end 103.60406 -232.011728)
		(width 0.1143)
		(layer "In11.Cu")
		(net "P5E_CPU1_G1_TX_DP<8>")
	)
	(segment
		(start 103.640382 -227.131118)
		(end 103.60406 -227.151946)
		(width 0.1143)
		(layer "In11.Cu")
		(net "P5E_CPU1_G1_TX_DP<8>")
	)
	(segment
		(start 103.596186 -242.372388)
		(end 103.608632 -242.3795)
		(width 0.1143)
		(layer "In11.Cu")
		(net "P5E_CPU1_G1_TX_DP<8>")
	)
	(segment
		(start 103.625142 -236.859572)
		(end 103.624888 -236.859572)
		(width 0.1143)
		(layer "In11.Cu")
		(net "P5E_CPU1_G1_TX_DP<8>")
	)
	(segment
		(start 103.643176 -233.60888)
		(end 103.60406 -233.63174)
		(width 0.1143)
		(layer "In11.Cu")
		(net "P5E_CPU1_G1_TX_DP<8>")
	)
	(segment
		(start 103.60406 -227.151946)
		(end 103.57231 -227.170234)
		(width 0.1143)
		(layer "In11.Cu")
		(net "P5E_CPU1_G1_TX_DP<8>")
	)
	(segment
		(start 103.60406 -232.011728)
		(end 103.57231 -232.030016)
		(width 0.1143)
		(layer "In11.Cu")
		(net "P5E_CPU1_G1_TX_DP<8>")
	)
	(segment
		(start 103.61041 -240.760504)
		(end 103.642414 -240.7793)
		(width 0.1143)
		(layer "In11.Cu")
		(net "P5E_CPU1_G1_TX_DP<8>")
	)
	(segment
		(start 35.664648 -19.42719)
		(end 35.664648 -20.192746)
		(width 0.14224)
		(layer "In11.Cu")
		(net "P5E_CPU1_G1_TX_DP<8>")
	)
	(segment
		(start 103.608632 -240.759488)
		(end 103.609394 -240.759996)
		(width 0.1143)
		(layer "In11.Cu")
		(net "P5E_CPU1_G1_TX_DP<8>")
	)
	(segment
		(start 103.60406 -233.63174)
		(end 103.57231 -233.650028)
		(width 0.1143)
		(layer "In11.Cu")
		(net "P5E_CPU1_G1_TX_DP<8>")
	)
	(segment
		(start 103.10241 -225.3488)
		(end 103.13416 -225.367088)
		(width 0.1143)
		(layer "In11.Cu")
		(net "P5E_CPU1_G1_TX_DP<8>")
	)
	(segment
		(start 48.508412 -47.642526)
		(end 54.37886 -55.371492)
		(width 0.14224)
		(layer "In11.Cu")
		(net "P5E_CPU1_G1_TX_DP<8>")
	)
	(segment
		(start 103.624888 -235.23956)
		(end 103.603552 -235.252006)
		(width 0.1143)
		(layer "In11.Cu")
		(net "P5E_CPU1_G1_TX_DP<8>")
	)
	(segment
		(start 102.194106 -222.127064)
		(end 102.195122 -222.127572)
		(width 0.1143)
		(layer "In11.Cu")
		(net "P5E_CPU1_G1_TX_DP<8>")
	)
	(segment
		(start 103.624888 -241.719608)
		(end 103.603552 -241.732054)
		(width 0.1143)
		(layer "In11.Cu")
		(net "P5E_CPU1_G1_TX_DP<8>")
	)
	(segment
		(start 103.137462 -225.36912)
		(end 103.170482 -225.38817)
		(width 0.1143)
		(layer "In11.Cu")
		(net "P5E_CPU1_G1_TX_DP<8>")
	)
	(segment
		(start 102.633526 -222.91929)
		(end 102.664006 -222.93707)
		(width 0.1143)
		(layer "In11.Cu")
		(net "P5E_CPU1_G1_TX_DP<8>")
	)
	(segment
		(start 103.61041 -239.140492)
		(end 103.642414 -239.159288)
		(width 0.1143)
		(layer "In11.Cu")
		(net "P5E_CPU1_G1_TX_DP<8>")
	)
	(segment
		(start 102.05212 -221.05493)
		(end 102.05212 -221.083378)
		(width 0.1143)
		(layer "In11.Cu")
		(net "P5E_CPU1_G1_TX_DP<8>")
	)
	(segment
		(start 102.664006 -222.93707)
		(end 102.703122 -222.95993)
		(width 0.1143)
		(layer "In11.Cu")
		(net "P5E_CPU1_G1_TX_DP<8>")
	)
	(segment
		(start 103.635302 -235.914946)
		(end 103.636064 -235.915454)
		(width 0.1143)
		(layer "In11.Cu")
		(net "P5E_CPU1_G1_TX_DP<8>")
	)
	(segment
		(start 103.596186 -240.752376)
		(end 103.608632 -240.759488)
		(width 0.1143)
		(layer "In11.Cu")
		(net "P5E_CPU1_G1_TX_DP<8>")
	)
	(segment
		(start 103.60406 -243.351812)
		(end 103.57231 -243.3701)
		(width 0.1143)
		(layer "In11.Cu")
		(net "P5E_CPU1_G1_TX_DP<8>")
	)
	(segment
		(start 151.729948 -163.547806)
		(end 150.073868 -168.451022)
		(width 0.14224)
		(layer "In11.Cu")
		(net "P5E_CPU1_G1_TX_DP<8>")
	)
	(segment
		(start 102.664006 -223.911922)
		(end 102.633526 -223.929702)
		(width 0.1143)
		(layer "In11.Cu")
		(net "P5E_CPU1_G1_TX_DP<8>")
	)
	(segment
		(start 54.385972 -55.378096)
		(end 147.052284 -138.707876)
		(width 0.14224)
		(layer "In11.Cu")
		(net "P5E_CPU1_G1_TX_DP<8>")
	)
	(segment
		(start 103.614474 -228.765862)
		(end 103.607616 -228.769926)
		(width 0.1143)
		(layer "In11.Cu")
		(net "P5E_CPU1_G1_TX_DP<8>")
	)
	(segment
		(start 103.573326 -226.159314)
		(end 103.60406 -226.177094)
		(width 0.1143)
		(layer "In11.Cu")
		(net "P5E_CPU1_G1_TX_DP<8>")
	)
	(segment
		(start 103.643176 -235.228892)
		(end 103.625142 -235.23956)
		(width 0.1143)
		(layer "In11.Cu")
		(net "P5E_CPU1_G1_TX_DP<8>")
	)
	(segment
		(start 103.570532 -229.397306)
		(end 103.60406 -229.416864)
		(width 0.1143)
		(layer "In11.Cu")
		(net "P5E_CPU1_G1_TX_DP<8>")
	)
	(segment
		(start 102.162356 -222.108776)
		(end 102.185978 -222.122492)
		(width 0.1143)
		(layer "In11.Cu")
		(net "P5E_CPU1_G1_TX_DP<8>")
	)
	(segment
		(start 103.60406 -243.996972)
		(end 103.643176 -244.019832)
		(width 0.1143)
		(layer "In11.Cu")
		(net "P5E_CPU1_G1_TX_DP<8>")
	)
	(segment
		(start 103.5939 -231.031034)
		(end 103.643176 -231.059736)
		(width 0.1143)
		(layer "In11.Cu")
		(net "P5E_CPU1_G1_TX_DP<8>")
	)
	(segment
		(start 103.615236 -228.765354)
		(end 103.614474 -228.765862)
		(width 0.1143)
		(layer "In11.Cu")
		(net "P5E_CPU1_G1_TX_DP<8>")
	)
	(segment
		(start 102.185978 -222.122492)
		(end 102.193344 -222.126556)
		(width 0.1143)
		(layer "In11.Cu")
		(net "P5E_CPU1_G1_TX_DP<8>")
	)
	(segment
		(start 103.57231 -243.978684)
		(end 103.60406 -243.996972)
		(width 0.1143)
		(layer "In11.Cu")
		(net "P5E_CPU1_G1_TX_DP<8>")
	)
	(segment
		(start 103.60406 -226.177094)
		(end 103.643176 -226.199954)
		(width 0.1143)
		(layer "In11.Cu")
		(net "P5E_CPU1_G1_TX_DP<8>")
	)
	(segment
		(start 103.605076 -232.657396)
		(end 103.643176 -232.679748)
		(width 0.1143)
		(layer "In11.Cu")
		(net "P5E_CPU1_G1_TX_DP<8>")
	)
	(segment
		(start 35.664648 -20.192746)
		(end 48.508412 -47.642526)
		(width 0.14224)
		(layer "In11.Cu")
		(net "P5E_CPU1_G1_TX_DP<8>")
	)
	(segment
		(start 103.607616 -228.769926)
		(end 103.6066 -228.770434)
		(width 0.1143)
		(layer "In11.Cu")
		(net "P5E_CPU1_G1_TX_DP<8>")
	)
	(segment
		(start 102.703122 -223.889062)
		(end 102.664006 -223.911922)
		(width 0.1143)
		(layer "In11.Cu")
		(net "P5E_CPU1_G1_TX_DP<8>")
	)
	(segment
		(start 103.624888 -240.099596)
		(end 103.603552 -240.112042)
		(width 0.1143)
		(layer "In11.Cu")
		(net "P5E_CPU1_G1_TX_DP<8>")
	)
	(segment
		(start 103.60406 -230.39197)
		(end 103.603298 -230.392478)
		(width 0.1143)
		(layer "In11.Cu")
		(net "P5E_CPU1_G1_TX_DP<8>")
	)
	(segment
		(start 103.625142 -241.719608)
		(end 103.624888 -241.719608)
		(width 0.1143)
		(layer "In11.Cu")
		(net "P5E_CPU1_G1_TX_DP<8>")
	)
	(segment
		(start 102.195122 -222.127572)
		(end 102.233222 -222.149924)
		(width 0.1143)
		(layer "In11.Cu")
		(net "P5E_CPU1_G1_TX_DP<8>")
	)
	(segment
		(start 103.6066 -228.770434)
		(end 103.605076 -228.77145)
		(width 0.1143)
		(layer "In11.Cu")
		(net "P5E_CPU1_G1_TX_DP<8>")
	)
	(segment
		(start 103.625142 -235.23956)
		(end 103.624888 -235.23956)
		(width 0.1143)
		(layer "In11.Cu")
		(net "P5E_CPU1_G1_TX_DP<8>")
	)
	(segment
		(start 103.603298 -232.65638)
		(end 103.60406 -232.656888)
		(width 0.1143)
		(layer "In11.Cu")
		(net "P5E_CPU1_G1_TX_DP<8>")
	)
	(segment
		(start 54.381146 -55.373524)
		(end 54.38394 -55.37581)
		(width 0.14224)
		(layer "In11.Cu")
		(net "P5E_CPU1_G1_TX_DP<8>")
	)
	(segment
		(start 150.901654 -146.667474)
		(end 151.729948 -159.906716)
		(width 0.14224)
		(layer "In11.Cu")
		(net "P5E_CPU1_G1_TX_DP<8>")
	)
	(segment
		(start 103.603298 -230.392478)
		(end 103.602028 -230.39324)
		(width 0.1143)
		(layer "In11.Cu")
		(net "P5E_CPU1_G1_TX_DP<8>")
	)
	(segment
		(start 102.05212 -215.735154)
		(end 102.05212 -221.05493)
		(width 0.14224)
		(layer "In11.Cu")
		(net "P5E_CPU1_G1_TX_DP<8>")
	)
	(segment
		(start 103.625142 -238.479584)
		(end 103.624888 -238.479584)
		(width 0.1143)
		(layer "In11.Cu")
		(net "P5E_CPU1_G1_TX_DP<8>")
	)
	(segment
		(start 103.608632 -239.139476)
		(end 103.609394 -239.139984)
		(width 0.1143)
		(layer "In11.Cu")
		(net "P5E_CPU1_G1_TX_DP<8>")
	)
	(segment
		(start 103.963216 -244.484398)
		(end 104.261158 -244.484398)
		(width 0.1143)
		(layer "In11.Cu")
		(net "P5E_CPU1_G1_TX_DP<8>")
	)
	(segment
		(start 103.596186 -235.89234)
		(end 103.607108 -235.89869)
		(width 0.1143)
		(layer "In11.Cu")
		(net "P5E_CPU1_G1_TX_DP<8>")
	)
	(segment
		(start 103.624888 -236.859572)
		(end 103.603552 -236.872018)
		(width 0.1143)
		(layer "In11.Cu")
		(net "P5E_CPU1_G1_TX_DP<8>")
	)
	(segment
		(start 103.625142 -240.099596)
		(end 103.624888 -240.099596)
		(width 0.1143)
		(layer "In11.Cu")
		(net "P5E_CPU1_G1_TX_DP<8>")
	)
	(segment
		(start 103.60406 -234.2769)
		(end 103.63962 -234.29722)
		(width 0.1143)
		(layer "In11.Cu")
		(net "P5E_CPU1_G1_TX_DP<8>")
	)
	(segment
		(start 103.643176 -238.468916)
		(end 103.625142 -238.479584)
		(width 0.1143)
		(layer "In11.Cu")
		(net "P5E_CPU1_G1_TX_DP<8>")
	)
	(segment
		(start 102.052628 -215.734392)
		(end 102.05212 -215.735154)
		(width 0.14224)
		(layer "In11.Cu")
		(net "P5E_CPU1_G1_TX_DP<8>")
	)
	(segment
		(start 103.57231 -234.258612)
		(end 103.60406 -234.2769)
		(width 0.1143)
		(layer "In11.Cu")
		(net "P5E_CPU1_G1_TX_DP<8>")
	)
	(segment
		(start 103.608632 -237.519464)
		(end 103.609394 -237.519972)
		(width 0.1143)
		(layer "In11.Cu")
		(net "P5E_CPU1_G1_TX_DP<8>")
	)
	(segment
		(start 103.60406 -232.656888)
		(end 103.605076 -232.657396)
		(width 0.1143)
		(layer "In11.Cu")
		(net "P5E_CPU1_G1_TX_DP<8>")
	)
	(segment
		(start 103.609394 -240.759996)
		(end 103.61041 -240.760504)
		(width 0.1143)
		(layer "In11.Cu")
		(net "P5E_CPU1_G1_TX_DP<8>")
	)
	(segment
		(start 151.729948 -159.906716)
		(end 151.729948 -163.547806)
		(width 0.14224)
		(layer "In11.Cu")
		(net "P5E_CPU1_G1_TX_DP<8>")
	)
	(segment
		(start 103.57231 -232.6386)
		(end 103.603298 -232.65638)
		(width 0.1143)
		(layer "In11.Cu")
		(net "P5E_CPU1_G1_TX_DP<8>")
	)
	(segment
		(start 103.609394 -235.89996)
		(end 103.635302 -235.914946)
		(width 0.1143)
		(layer "In11.Cu")
		(net "P5E_CPU1_G1_TX_DP<8>")
	)
	(segment
		(start 54.38394 -55.37581)
		(end 54.385972 -55.378096)
		(width 0.14224)
		(layer "In11.Cu")
		(net "P5E_CPU1_G1_TX_DP<8>")
	)
	(segment
		(start 103.643176 -228.749098)
		(end 103.615236 -228.765354)
		(width 0.1143)
		(layer "In11.Cu")
		(net "P5E_CPU1_G1_TX_DP<8>")
	)
	(segment
		(start 103.636064 -235.915454)
		(end 103.642414 -235.919264)
		(width 0.1143)
		(layer "In11.Cu")
		(net "P5E_CPU1_G1_TX_DP<8>")
	)
	(segment
		(start 103.602028 -230.39324)
		(end 103.600504 -230.394002)
		(width 0.1143)
		(layer "In11.Cu")
		(net "P5E_CPU1_G1_TX_DP<8>")
	)
	(segment
		(start 103.609394 -239.139984)
		(end 103.61041 -239.140492)
		(width 0.1143)
		(layer "In11.Cu")
		(net "P5E_CPU1_G1_TX_DP<8>")
	)
	(segment
		(start 146.519646 -173.680374)
		(end 108.54309 -204.801978)
		(width 0.14224)
		(layer "In11.Cu")
		(net "P5E_CPU1_G1_TX_DP<8>")
	)
	(segment
		(start 102.633526 -224.539302)
		(end 102.664006 -224.557082)
		(width 0.1143)
		(layer "In11.Cu")
		(net "P5E_CPU1_G1_TX_DP<8>")
	)
	(segment
		(start 147.052284 -138.707876)
		(end 150.901654 -146.667474)
		(width 0.14224)
		(layer "In11.Cu")
		(net "P5E_CPU1_G1_TX_DP<8>")
	)
	(segment
		(start 103.60406 -228.771958)
		(end 103.603298 -228.772466)
		(width 0.1143)
		(layer "In11.Cu")
		(net "P5E_CPU1_G1_TX_DP<8>")
	)
	(segment
		(start 103.60406 -227.797106)
		(end 103.643176 -227.819966)
		(width 0.1143)
		(layer "In11.Cu")
		(net "P5E_CPU1_G1_TX_DP<8>")
	)
	(segment
		(start 102.0064 -221.129098)
		(end 102.0064 -221.804484)
		(width 0.1143)
		(layer "In11.Cu")
		(net "P5E_CPU1_G1_TX_DP<8>")
	)
	(segment
		(start 103.605076 -230.391462)
		(end 103.60406 -230.39197)
		(width 0.1143)
		(layer "In11.Cu")
		(net "P5E_CPU1_G1_TX_DP<8>")
	)
	(segment
		(start 149.937978 -168.890442)
		(end 149.91842 -168.948608)
		(width 0.14224)
		(layer "In11.Cu")
		(net "P5E_CPU1_G1_TX_DP<8>")
	)
	(segment
		(start 103.607108 -235.89869)
		(end 103.608632 -235.899452)
		(width 0.1143)
		(layer "In11.Cu")
		(net "P5E_CPU1_G1_TX_DP<8>")
	)
	(segment
		(start 103.624888 -238.479584)
		(end 103.603552 -238.49203)
		(width 0.1143)
		(layer "In11.Cu")
		(net "P5E_CPU1_G1_TX_DP<8>")
	)
	(segment
		(start 103.643176 -240.088928)
		(end 103.625142 -240.099596)
		(width 0.1143)
		(layer "In11.Cu")
		(net "P5E_CPU1_G1_TX_DP<8>")
	)
	(segment
		(start 102.664006 -224.557082)
		(end 102.703122 -224.579942)
		(width 0.1143)
		(layer "In11.Cu")
		(net "P5E_CPU1_G1_TX_DP<8>")
	)
	(segment
		(start 103.643176 -243.328952)
		(end 103.60406 -243.351812)
		(width 0.1143)
		(layer "In11.Cu")
		(net "P5E_CPU1_G1_TX_DP<8>")
	)
	(segment
		(start 54.380384 -55.372762)
		(end 54.381146 -55.373524)
		(width 0.14224)
		(layer "In11.Cu")
		(net "P5E_CPU1_G1_TX_DP<8>")
	)
	(segment
		(start 102.193344 -222.126556)
		(end 102.194106 -222.127064)
		(width 0.1143)
		(layer "In11.Cu")
		(net "P5E_CPU1_G1_TX_DP<8>")
	)
	(segment
		(start 103.608632 -242.3795)
		(end 103.609394 -242.380008)
		(width 0.1143)
		(layer "In11.Cu")
		(net "P5E_CPU1_G1_TX_DP<8>")
	)
	(segment
		(start 103.13416 -225.367088)
		(end 103.135938 -225.368104)
		(width 0.1143)
		(layer "In11.Cu")
		(net "P5E_CPU1_G1_TX_DP<8>")
	)
	(segment
		(start 103.135938 -225.368104)
		(end 103.137462 -225.36912)
		(width 0.1143)
		(layer "In11.Cu")
		(net "P5E_CPU1_G1_TX_DP<8>")
	)
	(segment
		(start 103.603298 -228.772466)
		(end 103.60279 -228.77272)
		(width 0.1143)
		(layer "In11.Cu")
		(net "P5E_CPU1_G1_TX_DP<8>")
	)
	(segment
		(start 103.596186 -239.132364)
		(end 103.608632 -239.139476)
		(width 0.1143)
		(layer "In11.Cu")
		(net "P5E_CPU1_G1_TX_DP<8>")
	)
	(segment
		(start 150.073868 -168.451022)
		(end 149.937978 -168.890442)
		(width 0.14224)
		(layer "In11.Cu")
		(net "P5E_CPU1_G1_TX_DP<8>")
	)
	(arc
		(start 103.643176 -226.199954)
		(mid 103.886503 -226.66452)
		(end 103.643176 -227.129086)
		(width 0.1143)
		(layer "In11.Cu")
		(net "P5E_CPU1_G1_TX_DP<8>")
	)
	(arc
		(start 103.57231 -232.030016)
		(mid 103.423213 -232.334308)
		(end 103.57231 -232.6386)
		(width 0.1143)
		(layer "In11.Cu")
		(net "P5E_CPU1_G1_TX_DP<8>")
	)
	(arc
		(start 103.416354 -225.86569)
		(mid 103.460418 -226.030913)
		(end 103.573326 -226.159314)
		(width 0.1143)
		(layer "In11.Cu")
		(net "P5E_CPU1_G1_TX_DP<8>")
	)
	(arc
		(start 103.886508 -229.90429)
		(mid 103.821272 -230.167881)
		(end 103.640636 -230.370634)
		(width 0.1143)
		(layer "In11.Cu")
		(net "P5E_CPU1_G1_TX_DP<8>")
	)
	(arc
		(start 103.643176 -237.539784)
		(mid 103.886503 -238.00435)
		(end 103.643176 -238.468916)
		(width 0.1143)
		(layer "In11.Cu")
		(net "P5E_CPU1_G1_TX_DP<8>")
	)
	(arc
		(start 103.201978 -225.412808)
		(mid 103.334396 -225.585989)
		(end 103.40848 -225.791014)
		(width 0.1143)
		(layer "In11.Cu")
		(net "P5E_CPU1_G1_TX_DP<8>")
	)
	(arc
		(start 103.57231 -230.410258)
		(mid 103.45929 -230.544434)
		(end 103.416354 -230.71455)
		(width 0.1143)
		(layer "In11.Cu")
		(net "P5E_CPU1_G1_TX_DP<8>")
	)
	(arc
		(start 102.233222 -222.149924)
		(mid 102.412035 -222.352274)
		(end 102.476554 -222.61449)
		(width 0.1143)
		(layer "In11.Cu")
		(net "P5E_CPU1_G1_TX_DP<8>")
	)
	(arc
		(start 103.643176 -227.819966)
		(mid 103.886503 -228.284532)
		(end 103.643176 -228.749098)
		(width 0.1143)
		(layer "In11.Cu")
		(net "P5E_CPU1_G1_TX_DP<8>")
	)
	(arc
		(start 103.643176 -234.29976)
		(mid 103.886503 -234.764326)
		(end 103.643176 -235.228892)
		(width 0.1143)
		(layer "In11.Cu")
		(net "P5E_CPU1_G1_TX_DP<8>")
	)
	(arc
		(start 103.643176 -235.919772)
		(mid 103.886503 -236.384338)
		(end 103.643176 -236.848904)
		(width 0.1143)
		(layer "In11.Cu")
		(net "P5E_CPU1_G1_TX_DP<8>")
	)
	(arc
		(start 103.57231 -243.3701)
		(mid 103.423213 -243.674392)
		(end 103.57231 -243.978684)
		(width 0.1143)
		(layer "In11.Cu")
		(net "P5E_CPU1_G1_TX_DP<8>")
	)
	(arc
		(start 103.876602 -244.378734)
		(mid 103.878625 -244.390144)
		(end 103.880412 -244.401594)
		(width 0.1143)
		(layer "In11.Cu")
		(net "P5E_CPU1_G1_TX_DP<8>")
	)
	(arc
		(start 103.643176 -240.779808)
		(mid 103.886503 -241.244374)
		(end 103.643176 -241.70894)
		(width 0.1143)
		(layer "In11.Cu")
		(net "P5E_CPU1_G1_TX_DP<8>")
	)
	(arc
		(start 103.642414 -234.299252)
		(mid 103.642795 -234.299506)
		(end 103.643176 -234.29976)
		(width 0.1143)
		(layer "In11.Cu")
		(net "P5E_CPU1_G1_TX_DP<8>")
	)
	(arc
		(start 103.57231 -233.650028)
		(mid 103.420721 -233.95432)
		(end 103.57231 -234.258612)
		(width 0.1143)
		(layer "In11.Cu")
		(net "P5E_CPU1_G1_TX_DP<8>")
	)
	(arc
		(start 103.603552 -241.732054)
		(mid 103.418032 -242.050111)
		(end 103.596186 -242.372388)
		(width 0.1143)
		(layer "In11.Cu")
		(net "P5E_CPU1_G1_TX_DP<8>")
	)
	(arc
		(start 103.643176 -244.019832)
		(mid 103.795163 -244.17634)
		(end 103.876602 -244.378734)
		(width 0.1143)
		(layer "In11.Cu")
		(net "P5E_CPU1_G1_TX_DP<8>")
	)
	(arc
		(start 102.476554 -222.61449)
		(mid 102.518103 -222.785912)
		(end 102.633526 -222.91929)
		(width 0.1143)
		(layer "In11.Cu")
		(net "P5E_CPU1_G1_TX_DP<8>")
	)
	(arc
		(start 102.703122 -222.95993)
		(mid 102.946449 -223.424496)
		(end 102.703122 -223.889062)
		(width 0.1143)
		(layer "In11.Cu")
		(net "P5E_CPU1_G1_TX_DP<8>")
	)
	(arc
		(start 103.57231 -227.170234)
		(mid 103.423213 -227.474526)
		(end 103.57231 -227.778818)
		(width 0.1143)
		(layer "In11.Cu")
		(net "P5E_CPU1_G1_TX_DP<8>")
	)
	(arc
		(start 103.603552 -235.252006)
		(mid 103.418032 -235.570063)
		(end 103.596186 -235.89234)
		(width 0.1143)
		(layer "In11.Cu")
		(net "P5E_CPU1_G1_TX_DP<8>")
	)
	(arc
		(start 103.642414 -235.919264)
		(mid 103.642795 -235.919518)
		(end 103.643176 -235.919772)
		(width 0.1143)
		(layer "In11.Cu")
		(net "P5E_CPU1_G1_TX_DP<8>")
	)
	(arc
		(start 103.40848 -225.791014)
		(mid 103.413959 -225.828189)
		(end 103.416354 -225.86569)
		(width 0.1143)
		(layer "In11.Cu")
		(net "P5E_CPU1_G1_TX_DP<8>")
	)
	(arc
		(start 103.603552 -236.872018)
		(mid 103.418032 -237.190075)
		(end 103.596186 -237.512352)
		(width 0.1143)
		(layer "In11.Cu")
		(net "P5E_CPU1_G1_TX_DP<8>")
	)
	(arc
		(start 103.642414 -239.159288)
		(mid 103.642795 -239.159542)
		(end 103.643176 -239.159796)
		(width 0.1143)
		(layer "In11.Cu")
		(net "P5E_CPU1_G1_TX_DP<8>")
	)
	(arc
		(start 103.170482 -225.38817)
		(mid 103.186451 -225.400207)
		(end 103.201978 -225.412808)
		(width 0.1143)
		(layer "In11.Cu")
		(net "P5E_CPU1_G1_TX_DP<8>")
	)
	(arc
		(start 103.416354 -229.094538)
		(mid 103.457116 -229.264422)
		(end 103.570532 -229.397306)
		(width 0.1143)
		(layer "In11.Cu")
		(net "P5E_CPU1_G1_TX_DP<8>")
	)
	(arc
		(start 102.703122 -224.579942)
		(mid 102.881935 -224.782292)
		(end 102.946454 -225.044508)
		(width 0.1143)
		(layer "In11.Cu")
		(net "P5E_CPU1_G1_TX_DP<8>")
	)
	(arc
		(start 102.0064 -221.804484)
		(mid 102.047655 -221.975455)
		(end 102.162356 -222.108776)
		(width 0.1143)
		(layer "In11.Cu")
		(net "P5E_CPU1_G1_TX_DP<8>")
	)
	(arc
		(start 103.60279 -228.77272)
		(mid 103.466372 -228.908593)
		(end 103.416354 -229.094538)
		(width 0.1143)
		(layer "In11.Cu")
		(net "P5E_CPU1_G1_TX_DP<8>")
	)
	(arc
		(start 103.416354 -230.71455)
		(mid 103.462034 -230.896961)
		(end 103.5939 -231.031034)
		(width 0.1143)
		(layer "In11.Cu")
		(net "P5E_CPU1_G1_TX_DP<8>")
	)
	(arc
		(start 103.643176 -231.059736)
		(mid 103.886503 -231.524302)
		(end 103.643176 -231.988868)
		(width 0.1143)
		(layer "In11.Cu")
		(net "P5E_CPU1_G1_TX_DP<8>")
	)
	(arc
		(start 103.642414 -242.399312)
		(mid 103.642795 -242.399566)
		(end 103.643176 -242.39982)
		(width 0.1143)
		(layer "In11.Cu")
		(net "P5E_CPU1_G1_TX_DP<8>")
	)
	(arc
		(start 102.633526 -223.929702)
		(mid 102.476549 -224.234502)
		(end 102.633526 -224.539302)
		(width 0.1143)
		(layer "In11.Cu")
		(net "P5E_CPU1_G1_TX_DP<8>")
	)
	(arc
		(start 103.642414 -237.539276)
		(mid 103.642795 -237.53953)
		(end 103.643176 -237.539784)
		(width 0.1143)
		(layer "In11.Cu")
		(net "P5E_CPU1_G1_TX_DP<8>")
	)
	(arc
		(start 103.603552 -240.112042)
		(mid 103.418032 -240.430099)
		(end 103.596186 -240.752376)
		(width 0.1143)
		(layer "In11.Cu")
		(net "P5E_CPU1_G1_TX_DP<8>")
	)
	(arc
		(start 103.643176 -239.159796)
		(mid 103.886503 -239.624362)
		(end 103.643176 -240.088928)
		(width 0.1143)
		(layer "In11.Cu")
		(net "P5E_CPU1_G1_TX_DP<8>")
	)
	(arc
		(start 103.642414 -240.7793)
		(mid 103.642795 -240.779554)
		(end 103.643176 -240.779808)
		(width 0.1143)
		(layer "In11.Cu")
		(net "P5E_CPU1_G1_TX_DP<8>")
	)
	(arc
		(start 103.643176 -242.39982)
		(mid 103.886503 -242.864386)
		(end 103.643176 -243.328952)
		(width 0.1143)
		(layer "In11.Cu")
		(net "P5E_CPU1_G1_TX_DP<8>")
	)
	(arc
		(start 103.643176 -229.439724)
		(mid 103.821989 -229.642074)
		(end 103.886508 -229.90429)
		(width 0.1143)
		(layer "In11.Cu")
		(net "P5E_CPU1_G1_TX_DP<8>")
	)
	(arc
		(start 103.643176 -232.679748)
		(mid 103.886503 -233.144314)
		(end 103.643176 -233.60888)
		(width 0.1143)
		(layer "In11.Cu")
		(net "P5E_CPU1_G1_TX_DP<8>")
	)
	(arc
		(start 102.946454 -225.044508)
		(mid 102.987709 -225.215479)
		(end 103.10241 -225.3488)
		(width 0.1143)
		(layer "In11.Cu")
		(net "P5E_CPU1_G1_TX_DP<8>")
	)
	(arc
		(start 103.603552 -238.49203)
		(mid 103.418032 -238.810087)
		(end 103.596186 -239.132364)
		(width 0.1143)
		(layer "In11.Cu")
		(net "P5E_CPU1_G1_TX_DP<8>")
	)
	(segment
		(start 38.478968 -16.662146)
		(end 38.478968 -17.343628)
		(width 0.12954)
		(layer "F.Cu")
		(net "P5E_CPU1_G1_TX_DP<7>")
	)
	(segment
		(start 104.72801 -247.99036)
		(end 104.261158 -247.724422)
		(width 0.12954)
		(layer "F.Cu")
		(net "P5E_CPU1_G1_TX_DP<7>")
	)
	(segment
		(start 38.774878 -16.366236)
		(end 38.478968 -16.662146)
		(width 0.12954)
		(layer "F.Cu")
		(net "P5E_CPU1_G1_TX_DP<7>")
	)
	(segment
		(start 38.478968 -17.343628)
		(end 38.748462 -17.613122)
		(width 0.12954)
		(layer "F.Cu")
		(net "P5E_CPU1_G1_TX_DP<7>")
	)
	(segment
		(start 104.54513 -233.631232)
		(end 104.544114 -233.63174)
		(width 0.1143)
		(layer "In11.Cu")
		(net "P5E_CPU1_G1_TX_DP<7>")
	)
	(segment
		(start 104.58069 -230.370634)
		(end 104.512364 -230.410258)
		(width 0.1143)
		(layer "In11.Cu")
		(net "P5E_CPU1_G1_TX_DP<7>")
	)
	(segment
		(start 104.513634 -226.159314)
		(end 104.58323 -226.199954)
		(width 0.1143)
		(layer "In11.Cu")
		(net "P5E_CPU1_G1_TX_DP<7>")
	)
	(segment
		(start 104.57053 -228.756972)
		(end 104.566466 -228.759004)
		(width 0.1143)
		(layer "In11.Cu")
		(net "P5E_CPU1_G1_TX_DP<7>")
	)
	(segment
		(start 104.542082 -240.755678)
		(end 104.543352 -240.75644)
		(width 0.1143)
		(layer "In11.Cu")
		(net "P5E_CPU1_G1_TX_DP<7>")
	)
	(segment
		(start 103.605076 -223.911414)
		(end 103.599996 -223.914462)
		(width 0.1143)
		(layer "In11.Cu")
		(net "P5E_CPU1_G1_TX_DP<7>")
	)
	(segment
		(start 103.893366 -247.654572)
		(end 103.963216 -247.724422)
		(width 0.1143)
		(layer "In11.Cu")
		(net "P5E_CPU1_G1_TX_DP<7>")
	)
	(segment
		(start 103.85171 -221.129098)
		(end 103.85171 -221.445582)
		(width 0.1143)
		(layer "In11.Cu")
		(net "P5E_CPU1_G1_TX_DP<7>")
	)
	(segment
		(start 104.513634 -227.779326)
		(end 104.58323 -227.819966)
		(width 0.1143)
		(layer "In11.Cu")
		(net "P5E_CPU1_G1_TX_DP<7>")
	)
	(segment
		(start 104.070658 -225.365056)
		(end 104.073452 -225.36658)
		(width 0.1143)
		(layer "In11.Cu")
		(net "P5E_CPU1_G1_TX_DP<7>")
	)
	(segment
		(start 104.512364 -240.73866)
		(end 104.542082 -240.755678)
		(width 0.1143)
		(layer "In11.Cu")
		(net "P5E_CPU1_G1_TX_DP<7>")
	)
	(segment
		(start 104.510586 -231.017318)
		(end 104.58323 -231.059736)
		(width 0.1143)
		(layer "In11.Cu")
		(net "P5E_CPU1_G1_TX_DP<7>")
	)
	(segment
		(start 104.58323 -228.749098)
		(end 104.580436 -228.75113)
		(width 0.1143)
		(layer "In11.Cu")
		(net "P5E_CPU1_G1_TX_DP<7>")
	)
	(segment
		(start 104.544114 -232.011728)
		(end 104.543352 -232.012236)
		(width 0.1143)
		(layer "In11.Cu")
		(net "P5E_CPU1_G1_TX_DP<7>")
	)
	(segment
		(start 104.542082 -239.135666)
		(end 104.543352 -239.136428)
		(width 0.1143)
		(layer "In11.Cu")
		(net "P5E_CPU1_G1_TX_DP<7>")
	)
	(segment
		(start 103.633016 -224.573592)
		(end 103.633778 -224.5741)
		(width 0.1143)
		(layer "In11.Cu")
		(net "P5E_CPU1_G1_TX_DP<7>")
	)
	(segment
		(start 104.543352 -232.65638)
		(end 104.54513 -232.657396)
		(width 0.1143)
		(layer "In11.Cu")
		(net "P5E_CPU1_G1_TX_DP<7>")
	)
	(segment
		(start 103.85171 -221.445582)
		(end 103.548942 -222.176594)
		(width 0.1143)
		(layer "In11.Cu")
		(net "P5E_CPU1_G1_TX_DP<7>")
	)
	(segment
		(start 104.549194 -232.659936)
		(end 104.55021 -232.660444)
		(width 0.1143)
		(layer "In11.Cu")
		(net "P5E_CPU1_G1_TX_DP<7>")
	)
	(segment
		(start 150.752556 -169.398696)
		(end 147.228052 -174.305722)
		(width 0.14224)
		(layer "In11.Cu")
		(net "P5E_CPU1_G1_TX_DP<7>")
	)
	(segment
		(start 104.54513 -246.591328)
		(end 104.544114 -246.591836)
		(width 0.1143)
		(layer "In11.Cu")
		(net "P5E_CPU1_G1_TX_DP<7>")
	)
	(segment
		(start 104.543352 -241.732308)
		(end 104.512364 -241.750088)
		(width 0.1143)
		(layer "In11.Cu")
		(net "P5E_CPU1_G1_TX_DP<7>")
	)
	(segment
		(start 104.566466 -228.759004)
		(end 104.565704 -228.759512)
		(width 0.1143)
		(layer "In11.Cu")
		(net "P5E_CPU1_G1_TX_DP<7>")
	)
	(segment
		(start 104.544114 -233.63174)
		(end 104.543352 -233.632248)
		(width 0.1143)
		(layer "In11.Cu")
		(net "P5E_CPU1_G1_TX_DP<7>")
	)
	(segment
		(start 152.66924 -163.769548)
		(end 150.752556 -169.398696)
		(width 0.14224)
		(layer "In11.Cu")
		(net "P5E_CPU1_G1_TX_DP<7>")
	)
	(segment
		(start 104.10571 -225.385376)
		(end 104.11333 -225.389948)
		(width 0.1143)
		(layer "In11.Cu")
		(net "P5E_CPU1_G1_TX_DP<7>")
	)
	(segment
		(start 104.542082 -243.995702)
		(end 104.543352 -243.996464)
		(width 0.1143)
		(layer "In11.Cu")
		(net "P5E_CPU1_G1_TX_DP<7>")
	)
	(segment
		(start 103.89743 -221.05493)
		(end 103.89743 -221.083378)
		(width 0.1143)
		(layer "In11.Cu")
		(net "P5E_CPU1_G1_TX_DP<7>")
	)
	(segment
		(start 103.633778 -224.5741)
		(end 103.640382 -224.57791)
		(width 0.1143)
		(layer "In11.Cu")
		(net "P5E_CPU1_G1_TX_DP<7>")
	)
	(segment
		(start 104.546654 -246.590312)
		(end 104.54513 -246.591328)
		(width 0.1143)
		(layer "In11.Cu")
		(net "P5E_CPU1_G1_TX_DP<7>")
	)
	(segment
		(start 104.546654 -240.110264)
		(end 104.54513 -240.11128)
		(width 0.1143)
		(layer "In11.Cu")
		(net "P5E_CPU1_G1_TX_DP<7>")
	)
	(segment
		(start 104.543352 -235.25226)
		(end 104.512364 -235.27004)
		(width 0.1143)
		(layer "In11.Cu")
		(net "P5E_CPU1_G1_TX_DP<7>")
	)
	(segment
		(start 104.54513 -243.99748)
		(end 104.549194 -244.00002)
		(width 0.1143)
		(layer "In11.Cu")
		(net "P5E_CPU1_G1_TX_DP<7>")
	)
	(segment
		(start 38.748462 -17.613122)
		(end 38.457632 -17.903952)
		(width 0.14224)
		(layer "In11.Cu")
		(net "P5E_CPU1_G1_TX_DP<7>")
	)
	(segment
		(start 104.512364 -239.118648)
		(end 104.542082 -239.135666)
		(width 0.1143)
		(layer "In11.Cu")
		(net "P5E_CPU1_G1_TX_DP<7>")
	)
	(segment
		(start 104.54513 -243.351304)
		(end 104.544114 -243.351812)
		(width 0.1143)
		(layer "In11.Cu")
		(net "P5E_CPU1_G1_TX_DP<7>")
	)
	(segment
		(start 104.073452 -225.36658)
		(end 104.074214 -225.367088)
		(width 0.1143)
		(layer "In11.Cu")
		(net "P5E_CPU1_G1_TX_DP<7>")
	)
	(segment
		(start 104.58323 -233.60888)
		(end 104.546654 -233.630216)
		(width 0.1143)
		(layer "In11.Cu")
		(net "P5E_CPU1_G1_TX_DP<7>")
	)
	(segment
		(start 104.54513 -240.11128)
		(end 104.544114 -240.111788)
		(width 0.1143)
		(layer "In11.Cu")
		(net "P5E_CPU1_G1_TX_DP<7>")
	)
	(segment
		(start 104.58323 -227.129086)
		(end 104.513634 -227.169726)
		(width 0.1143)
		(layer "In11.Cu")
		(net "P5E_CPU1_G1_TX_DP<7>")
	)
	(segment
		(start 104.55021 -234.280456)
		(end 104.552242 -234.281726)
		(width 0.1143)
		(layer "In11.Cu")
		(net "P5E_CPU1_G1_TX_DP<7>")
	)
	(segment
		(start 104.549194 -239.139984)
		(end 104.55021 -239.140492)
		(width 0.1143)
		(layer "In11.Cu")
		(net "P5E_CPU1_G1_TX_DP<7>")
	)
	(segment
		(start 104.042464 -225.3488)
		(end 104.069896 -225.364548)
		(width 0.1143)
		(layer "In11.Cu")
		(net "P5E_CPU1_G1_TX_DP<7>")
	)
	(segment
		(start 104.55021 -240.760504)
		(end 104.552242 -240.761774)
		(width 0.1143)
		(layer "In11.Cu")
		(net "P5E_CPU1_G1_TX_DP<7>")
	)
	(segment
		(start 104.54513 -235.251244)
		(end 104.544114 -235.251752)
		(width 0.1143)
		(layer "In11.Cu")
		(net "P5E_CPU1_G1_TX_DP<7>")
	)
	(segment
		(start 104.58323 -244.948964)
		(end 104.546654 -244.9703)
		(width 0.1143)
		(layer "In11.Cu")
		(net "P5E_CPU1_G1_TX_DP<7>")
	)
	(segment
		(start 104.54513 -235.89742)
		(end 104.549194 -235.89996)
		(width 0.1143)
		(layer "In11.Cu")
		(net "P5E_CPU1_G1_TX_DP<7>")
	)
	(segment
		(start 104.512364 -235.878624)
		(end 104.542082 -235.895642)
		(width 0.1143)
		(layer "In11.Cu")
		(net "P5E_CPU1_G1_TX_DP<7>")
	)
	(segment
		(start 104.543352 -240.75644)
		(end 104.54513 -240.757456)
		(width 0.1143)
		(layer "In11.Cu")
		(net "P5E_CPU1_G1_TX_DP<7>")
	)
	(segment
		(start 104.54513 -232.657396)
		(end 104.549194 -232.659936)
		(width 0.1143)
		(layer "In11.Cu")
		(net "P5E_CPU1_G1_TX_DP<7>")
	)
	(segment
		(start 103.548942 -222.79737)
		(end 103.597202 -222.913956)
		(width 0.1143)
		(layer "In11.Cu")
		(net "P5E_CPU1_G1_TX_DP<7>")
	)
	(segment
		(start 104.55021 -239.140492)
		(end 104.552242 -239.141762)
		(width 0.1143)
		(layer "In11.Cu")
		(net "P5E_CPU1_G1_TX_DP<7>")
	)
	(segment
		(start 147.804378 -138.120374)
		(end 151.829262 -146.443446)
		(width 0.14224)
		(layer "In11.Cu")
		(net "P5E_CPU1_G1_TX_DP<7>")
	)
	(segment
		(start 104.113076 -247.378982)
		(end 104.04348 -247.419622)
		(width 0.1143)
		(layer "In11.Cu")
		(net "P5E_CPU1_G1_TX_DP<7>")
	)
	(segment
		(start 104.552242 -232.661714)
		(end 104.58323 -232.679748)
		(width 0.1143)
		(layer "In11.Cu")
		(net "P5E_CPU1_G1_TX_DP<7>")
	)
	(segment
		(start 104.54513 -240.757456)
		(end 104.549194 -240.759996)
		(width 0.1143)
		(layer "In11.Cu")
		(net "P5E_CPU1_G1_TX_DP<7>")
	)
	(segment
		(start 104.546654 -236.87024)
		(end 104.54513 -236.871256)
		(width 0.1143)
		(layer "In11.Cu")
		(net "P5E_CPU1_G1_TX_DP<7>")
	)
	(segment
		(start 104.543352 -234.276392)
		(end 104.54513 -234.277408)
		(width 0.1143)
		(layer "In11.Cu")
		(net "P5E_CPU1_G1_TX_DP<7>")
	)
	(segment
		(start 103.89743 -221.083378)
		(end 103.85171 -221.129098)
		(width 0.1143)
		(layer "In11.Cu")
		(net "P5E_CPU1_G1_TX_DP<7>")
	)
	(segment
		(start 104.543352 -233.632248)
		(end 104.512364 -233.650028)
		(width 0.1143)
		(layer "In11.Cu")
		(net "P5E_CPU1_G1_TX_DP<7>")
	)
	(segment
		(start 104.54513 -244.971316)
		(end 104.544114 -244.971824)
		(width 0.1143)
		(layer "In11.Cu")
		(net "P5E_CPU1_G1_TX_DP<7>")
	)
	(segment
		(start 104.544114 -241.7318)
		(end 104.543352 -241.732308)
		(width 0.1143)
		(layer "In11.Cu")
		(net "P5E_CPU1_G1_TX_DP<7>")
	)
	(segment
		(start 103.597202 -222.913956)
		(end 103.64343 -222.960184)
		(width 0.1143)
		(layer "In11.Cu")
		(net "P5E_CPU1_G1_TX_DP<7>")
	)
	(segment
		(start 104.543352 -243.996464)
		(end 104.54513 -243.99748)
		(width 0.1143)
		(layer "In11.Cu")
		(net "P5E_CPU1_G1_TX_DP<7>")
	)
	(segment
		(start 151.829262 -146.443446)
		(end 152.66924 -159.876998)
		(width 0.14224)
		(layer "In11.Cu")
		(net "P5E_CPU1_G1_TX_DP<7>")
	)
	(segment
		(start 103.963216 -247.724422)
		(end 104.261158 -247.724422)
		(width 0.1143)
		(layer "In11.Cu")
		(net "P5E_CPU1_G1_TX_DP<7>")
	)
	(segment
		(start 104.549194 -240.759996)
		(end 104.55021 -240.760504)
		(width 0.1143)
		(layer "In11.Cu")
		(net "P5E_CPU1_G1_TX_DP<7>")
	)
	(segment
		(start 104.546654 -233.630216)
		(end 104.54513 -233.631232)
		(width 0.1143)
		(layer "In11.Cu")
		(net "P5E_CPU1_G1_TX_DP<7>")
	)
	(segment
		(start 104.573832 -228.75494)
		(end 104.57307 -228.755448)
		(width 0.1143)
		(layer "In11.Cu")
		(net "P5E_CPU1_G1_TX_DP<7>")
	)
	(segment
		(start 104.544114 -235.251752)
		(end 104.543352 -235.25226)
		(width 0.1143)
		(layer "In11.Cu")
		(net "P5E_CPU1_G1_TX_DP<7>")
	)
	(segment
		(start 104.542082 -234.27563)
		(end 104.543352 -234.276392)
		(width 0.1143)
		(layer "In11.Cu")
		(net "P5E_CPU1_G1_TX_DP<7>")
	)
	(segment
		(start 104.58323 -243.328952)
		(end 104.546654 -243.350288)
		(width 0.1143)
		(layer "In11.Cu")
		(net "P5E_CPU1_G1_TX_DP<7>")
	)
	(segment
		(start 103.631238 -224.572576)
		(end 103.632 -224.573084)
		(width 0.1143)
		(layer "In11.Cu")
		(net "P5E_CPU1_G1_TX_DP<7>")
	)
	(segment
		(start 104.546654 -235.250228)
		(end 104.54513 -235.251244)
		(width 0.1143)
		(layer "In11.Cu")
		(net "P5E_CPU1_G1_TX_DP<7>")
	)
	(segment
		(start 104.510586 -229.397306)
		(end 104.580436 -229.437946)
		(width 0.1143)
		(layer "In11.Cu")
		(net "P5E_CPU1_G1_TX_DP<7>")
	)
	(segment
		(start 103.632 -224.573084)
		(end 103.633016 -224.573592)
		(width 0.1143)
		(layer "In11.Cu")
		(net "P5E_CPU1_G1_TX_DP<7>")
	)
	(segment
		(start 104.54513 -232.01122)
		(end 104.544114 -232.011728)
		(width 0.1143)
		(layer "In11.Cu")
		(net "P5E_CPU1_G1_TX_DP<7>")
	)
	(segment
		(start 104.55021 -244.000528)
		(end 104.552242 -244.001798)
		(width 0.1143)
		(layer "In11.Cu")
		(net "P5E_CPU1_G1_TX_DP<7>")
	)
	(segment
		(start 104.58323 -246.568976)
		(end 104.546654 -246.590312)
		(width 0.1143)
		(layer "In11.Cu")
		(net "P5E_CPU1_G1_TX_DP<7>")
	)
	(segment
		(start 104.512364 -232.6386)
		(end 104.542082 -232.655618)
		(width 0.1143)
		(layer "In11.Cu")
		(net "P5E_CPU1_G1_TX_DP<7>")
	)
	(segment
		(start 104.543352 -236.872272)
		(end 104.512364 -236.890052)
		(width 0.1143)
		(layer "In11.Cu")
		(net "P5E_CPU1_G1_TX_DP<7>")
	)
	(segment
		(start 104.544114 -236.871764)
		(end 104.543352 -236.872272)
		(width 0.1143)
		(layer "In11.Cu")
		(net "P5E_CPU1_G1_TX_DP<7>")
	)
	(segment
		(start 104.543352 -243.35232)
		(end 104.512364 -243.3701)
		(width 0.1143)
		(layer "In11.Cu")
		(net "P5E_CPU1_G1_TX_DP<7>")
	)
	(segment
		(start 104.544114 -240.111788)
		(end 104.543352 -240.112296)
		(width 0.1143)
		(layer "In11.Cu")
		(net "P5E_CPU1_G1_TX_DP<7>")
	)
	(segment
		(start 147.228052 -174.305722)
		(end 109.261402 -205.418944)
		(width 0.14224)
		(layer "In11.Cu")
		(net "P5E_CPU1_G1_TX_DP<7>")
	)
	(segment
		(start 104.55021 -232.660444)
		(end 104.552242 -232.661714)
		(width 0.1143)
		(layer "In11.Cu")
		(net "P5E_CPU1_G1_TX_DP<7>")
	)
	(segment
		(start 104.542082 -235.895642)
		(end 104.543352 -235.896404)
		(width 0.1143)
		(layer "In11.Cu")
		(net "P5E_CPU1_G1_TX_DP<7>")
	)
	(segment
		(start 104.544114 -246.591836)
		(end 104.543352 -246.592344)
		(width 0.1143)
		(layer "In11.Cu")
		(net "P5E_CPU1_G1_TX_DP<7>")
	)
	(segment
		(start 104.546654 -244.9703)
		(end 104.54513 -244.971316)
		(width 0.1143)
		(layer "In11.Cu")
		(net "P5E_CPU1_G1_TX_DP<7>")
	)
	(segment
		(start 104.512364 -245.598696)
		(end 104.54513 -245.617492)
		(width 0.1143)
		(layer "In11.Cu")
		(net "P5E_CPU1_G1_TX_DP<7>")
	)
	(segment
		(start 55.229506 -54.87035)
		(end 147.804378 -138.120374)
		(width 0.14224)
		(layer "In11.Cu")
		(net "P5E_CPU1_G1_TX_DP<7>")
	)
	(segment
		(start 103.548942 -222.176594)
		(end 103.548942 -222.79737)
		(width 0.1143)
		(layer "In11.Cu")
		(net "P5E_CPU1_G1_TX_DP<7>")
	)
	(segment
		(start 104.552242 -235.901738)
		(end 104.58323 -235.919772)
		(width 0.1143)
		(layer "In11.Cu")
		(net "P5E_CPU1_G1_TX_DP<7>")
	)
	(segment
		(start 103.57231 -224.538794)
		(end 103.631238 -224.572576)
		(width 0.1143)
		(layer "In11.Cu")
		(net "P5E_CPU1_G1_TX_DP<7>")
	)
	(segment
		(start 104.543352 -244.972332)
		(end 104.512364 -244.990112)
		(width 0.1143)
		(layer "In11.Cu")
		(net "P5E_CPU1_G1_TX_DP<7>")
	)
	(segment
		(start 104.54513 -241.731292)
		(end 104.544114 -241.7318)
		(width 0.1143)
		(layer "In11.Cu")
		(net "P5E_CPU1_G1_TX_DP<7>")
	)
	(segment
		(start 104.543352 -232.012236)
		(end 104.512364 -232.030016)
		(width 0.1143)
		(layer "In11.Cu")
		(net "P5E_CPU1_G1_TX_DP<7>")
	)
	(segment
		(start 104.544114 -244.971824)
		(end 104.543352 -244.972332)
		(width 0.1143)
		(layer "In11.Cu")
		(net "P5E_CPU1_G1_TX_DP<7>")
	)
	(segment
		(start 50.138584 -47.735744)
		(end 55.229506 -54.87035)
		(width 0.14224)
		(layer "In11.Cu")
		(net "P5E_CPU1_G1_TX_DP<7>")
	)
	(segment
		(start 104.54513 -245.617492)
		(end 104.58323 -245.639844)
		(width 0.1143)
		(layer "In11.Cu")
		(net "P5E_CPU1_G1_TX_DP<7>")
	)
	(segment
		(start 104.55021 -235.900468)
		(end 104.552242 -235.901738)
		(width 0.1143)
		(layer "In11.Cu")
		(net "P5E_CPU1_G1_TX_DP<7>")
	)
	(segment
		(start 104.546654 -241.730276)
		(end 104.54513 -241.731292)
		(width 0.1143)
		(layer "In11.Cu")
		(net "P5E_CPU1_G1_TX_DP<7>")
	)
	(segment
		(start 104.549194 -244.00002)
		(end 104.55021 -244.000528)
		(width 0.1143)
		(layer "In11.Cu")
		(net "P5E_CPU1_G1_TX_DP<7>")
	)
	(segment
		(start 104.546654 -232.010204)
		(end 104.54513 -232.01122)
		(width 0.1143)
		(layer "In11.Cu")
		(net "P5E_CPU1_G1_TX_DP<7>")
	)
	(segment
		(start 103.643176 -223.889062)
		(end 103.605076 -223.911414)
		(width 0.1143)
		(layer "In11.Cu")
		(net "P5E_CPU1_G1_TX_DP<7>")
	)
	(segment
		(start 104.549194 -234.279948)
		(end 104.55021 -234.280456)
		(width 0.1143)
		(layer "In11.Cu")
		(net "P5E_CPU1_G1_TX_DP<7>")
	)
	(segment
		(start 104.54513 -242.377468)
		(end 104.58323 -242.39982)
		(width 0.1143)
		(layer "In11.Cu")
		(net "P5E_CPU1_G1_TX_DP<7>")
	)
	(segment
		(start 104.54513 -236.871256)
		(end 104.544114 -236.871764)
		(width 0.1143)
		(layer "In11.Cu")
		(net "P5E_CPU1_G1_TX_DP<7>")
	)
	(segment
		(start 104.552242 -239.141762)
		(end 104.58323 -239.159796)
		(width 0.1143)
		(layer "In11.Cu")
		(net "P5E_CPU1_G1_TX_DP<7>")
	)
	(segment
		(start 103.640382 -224.57791)
		(end 103.643176 -224.579942)
		(width 0.1143)
		(layer "In11.Cu")
		(net "P5E_CPU1_G1_TX_DP<7>")
	)
	(segment
		(start 104.543352 -239.136428)
		(end 104.54513 -239.137444)
		(width 0.1143)
		(layer "In11.Cu")
		(net "P5E_CPU1_G1_TX_DP<7>")
	)
	(segment
		(start 104.512364 -242.358672)
		(end 104.54513 -242.377468)
		(width 0.1143)
		(layer "In11.Cu")
		(net "P5E_CPU1_G1_TX_DP<7>")
	)
	(segment
		(start 104.544114 -243.351812)
		(end 104.543352 -243.35232)
		(width 0.1143)
		(layer "In11.Cu")
		(net "P5E_CPU1_G1_TX_DP<7>")
	)
	(segment
		(start 104.565704 -228.759512)
		(end 104.512364 -228.790246)
		(width 0.1143)
		(layer "In11.Cu")
		(net "P5E_CPU1_G1_TX_DP<7>")
	)
	(segment
		(start 104.074214 -225.367088)
		(end 104.10571 -225.385376)
		(width 0.1143)
		(layer "In11.Cu")
		(net "P5E_CPU1_G1_TX_DP<7>")
	)
	(segment
		(start 104.543352 -235.896404)
		(end 104.54513 -235.89742)
		(width 0.1143)
		(layer "In11.Cu")
		(net "P5E_CPU1_G1_TX_DP<7>")
	)
	(segment
		(start 104.552242 -234.281726)
		(end 104.58323 -234.29976)
		(width 0.1143)
		(layer "In11.Cu")
		(net "P5E_CPU1_G1_TX_DP<7>")
	)
	(segment
		(start 38.457632 -20.192746)
		(end 50.138584 -47.735744)
		(width 0.14224)
		(layer "In11.Cu")
		(net "P5E_CPU1_G1_TX_DP<7>")
	)
	(segment
		(start 104.552242 -240.761774)
		(end 104.58323 -240.779808)
		(width 0.1143)
		(layer "In11.Cu")
		(net "P5E_CPU1_G1_TX_DP<7>")
	)
	(segment
		(start 104.543352 -240.112296)
		(end 104.512364 -240.130076)
		(width 0.1143)
		(layer "In11.Cu")
		(net "P5E_CPU1_G1_TX_DP<7>")
	)
	(segment
		(start 104.58323 -241.70894)
		(end 104.546654 -241.730276)
		(width 0.1143)
		(layer "In11.Cu")
		(net "P5E_CPU1_G1_TX_DP<7>")
	)
	(segment
		(start 104.58323 -235.228892)
		(end 104.546654 -235.250228)
		(width 0.1143)
		(layer "In11.Cu")
		(net "P5E_CPU1_G1_TX_DP<7>")
	)
	(segment
		(start 104.58323 -240.088928)
		(end 104.546654 -240.110264)
		(width 0.1143)
		(layer "In11.Cu")
		(net "P5E_CPU1_G1_TX_DP<7>")
	)
	(segment
		(start 104.549194 -235.89996)
		(end 104.55021 -235.900468)
		(width 0.1143)
		(layer "In11.Cu")
		(net "P5E_CPU1_G1_TX_DP<7>")
	)
	(segment
		(start 152.66924 -159.876998)
		(end 152.66924 -163.769548)
		(width 0.14224)
		(layer "In11.Cu")
		(net "P5E_CPU1_G1_TX_DP<7>")
	)
	(segment
		(start 104.58323 -231.988868)
		(end 104.546654 -232.010204)
		(width 0.1143)
		(layer "In11.Cu")
		(net "P5E_CPU1_G1_TX_DP<7>")
	)
	(segment
		(start 104.552242 -244.001798)
		(end 104.58323 -244.019832)
		(width 0.1143)
		(layer "In11.Cu")
		(net "P5E_CPU1_G1_TX_DP<7>")
	)
	(segment
		(start 104.580436 -228.75113)
		(end 104.573832 -228.75494)
		(width 0.1143)
		(layer "In11.Cu")
		(net "P5E_CPU1_G1_TX_DP<7>")
	)
	(segment
		(start 103.89743 -214.453724)
		(end 103.89743 -221.05493)
		(width 0.14224)
		(layer "In11.Cu")
		(net "P5E_CPU1_G1_TX_DP<7>")
	)
	(segment
		(start 104.57307 -228.755448)
		(end 104.57053 -228.756972)
		(width 0.1143)
		(layer "In11.Cu")
		(net "P5E_CPU1_G1_TX_DP<7>")
	)
	(segment
		(start 104.54513 -237.517432)
		(end 104.58323 -237.539784)
		(width 0.1143)
		(layer "In11.Cu")
		(net "P5E_CPU1_G1_TX_DP<7>")
	)
	(segment
		(start 104.512364 -243.978684)
		(end 104.542082 -243.995702)
		(width 0.1143)
		(layer "In11.Cu")
		(net "P5E_CPU1_G1_TX_DP<7>")
	)
	(segment
		(start 104.512364 -234.258612)
		(end 104.542082 -234.27563)
		(width 0.1143)
		(layer "In11.Cu")
		(net "P5E_CPU1_G1_TX_DP<7>")
	)
	(segment
		(start 104.542082 -232.655618)
		(end 104.543352 -232.65638)
		(width 0.1143)
		(layer "In11.Cu")
		(net "P5E_CPU1_G1_TX_DP<7>")
	)
	(segment
		(start 104.543352 -246.592344)
		(end 104.512364 -246.610124)
		(width 0.1143)
		(layer "In11.Cu")
		(net "P5E_CPU1_G1_TX_DP<7>")
	)
	(segment
		(start 38.457632 -17.903952)
		(end 38.457632 -20.192746)
		(width 0.14224)
		(layer "In11.Cu")
		(net "P5E_CPU1_G1_TX_DP<7>")
	)
	(segment
		(start 104.069896 -225.364548)
		(end 104.070658 -225.365056)
		(width 0.1143)
		(layer "In11.Cu")
		(net "P5E_CPU1_G1_TX_DP<7>")
	)
	(segment
		(start 104.546654 -243.350288)
		(end 104.54513 -243.351304)
		(width 0.1143)
		(layer "In11.Cu")
		(net "P5E_CPU1_G1_TX_DP<7>")
	)
	(segment
		(start 103.599996 -223.914462)
		(end 103.57231 -223.93021)
		(width 0.1143)
		(layer "In11.Cu")
		(net "P5E_CPU1_G1_TX_DP<7>")
	)
	(segment
		(start 104.546654 -238.490252)
		(end 104.512364 -238.510064)
		(width 0.1143)
		(layer "In11.Cu")
		(net "P5E_CPU1_G1_TX_DP<7>")
	)
	(segment
		(start 104.58323 -236.848904)
		(end 104.546654 -236.87024)
		(width 0.1143)
		(layer "In11.Cu")
		(net "P5E_CPU1_G1_TX_DP<7>")
	)
	(segment
		(start 104.54513 -239.137444)
		(end 104.549194 -239.139984)
		(width 0.1143)
		(layer "In11.Cu")
		(net "P5E_CPU1_G1_TX_DP<7>")
	)
	(segment
		(start 104.54513 -234.277408)
		(end 104.549194 -234.279948)
		(width 0.1143)
		(layer "In11.Cu")
		(net "P5E_CPU1_G1_TX_DP<7>")
	)
	(segment
		(start 109.261402 -205.418944)
		(end 103.89743 -214.453724)
		(width 0.14224)
		(layer "In11.Cu")
		(net "P5E_CPU1_G1_TX_DP<7>")
	)
	(segment
		(start 104.512364 -237.498636)
		(end 104.54513 -237.517432)
		(width 0.1143)
		(layer "In11.Cu")
		(net "P5E_CPU1_G1_TX_DP<7>")
	)
	(segment
		(start 104.58323 -238.468916)
		(end 104.546654 -238.490252)
		(width 0.1143)
		(layer "In11.Cu")
		(net "P5E_CPU1_G1_TX_DP<7>")
	)
	(arc
		(start 104.512364 -238.510064)
		(mid 104.356436 -238.814356)
		(end 104.512364 -239.118648)
		(width 0.1143)
		(layer "In11.Cu")
		(net "P5E_CPU1_G1_TX_DP<7>")
	)
	(arc
		(start 104.512364 -235.27004)
		(mid 104.356436 -235.574332)
		(end 104.512364 -235.878624)
		(width 0.1143)
		(layer "In11.Cu")
		(net "P5E_CPU1_G1_TX_DP<7>")
	)
	(arc
		(start 104.58323 -227.819966)
		(mid 104.826557 -228.284532)
		(end 104.58323 -228.749098)
		(width 0.1143)
		(layer "In11.Cu")
		(net "P5E_CPU1_G1_TX_DP<7>")
	)
	(arc
		(start 104.04348 -247.419622)
		(mid 103.945715 -247.522598)
		(end 103.893366 -247.654572)
		(width 0.1143)
		(layer "In11.Cu")
		(net "P5E_CPU1_G1_TX_DP<7>")
	)
	(arc
		(start 104.512364 -228.790246)
		(mid 104.397688 -228.92358)
		(end 104.356408 -229.094538)
		(width 0.1143)
		(layer "In11.Cu")
		(net "P5E_CPU1_G1_TX_DP<7>")
	)
	(arc
		(start 104.512364 -233.650028)
		(mid 104.356436 -233.95432)
		(end 104.512364 -234.258612)
		(width 0.1143)
		(layer "In11.Cu")
		(net "P5E_CPU1_G1_TX_DP<7>")
	)
	(arc
		(start 104.512364 -243.3701)
		(mid 104.356436 -243.674392)
		(end 104.512364 -243.978684)
		(width 0.1143)
		(layer "In11.Cu")
		(net "P5E_CPU1_G1_TX_DP<7>")
	)
	(arc
		(start 104.512364 -241.750088)
		(mid 104.356436 -242.05438)
		(end 104.512364 -242.358672)
		(width 0.1143)
		(layer "In11.Cu")
		(net "P5E_CPU1_G1_TX_DP<7>")
	)
	(arc
		(start 104.512364 -230.410258)
		(mid 104.397688 -230.543592)
		(end 104.356408 -230.71455)
		(width 0.1143)
		(layer "In11.Cu")
		(net "P5E_CPU1_G1_TX_DP<7>")
	)
	(arc
		(start 104.356408 -229.094538)
		(mid 104.39717 -229.264422)
		(end 104.510586 -229.397306)
		(width 0.1143)
		(layer "In11.Cu")
		(net "P5E_CPU1_G1_TX_DP<7>")
	)
	(arc
		(start 104.58323 -245.639844)
		(mid 104.826557 -246.10441)
		(end 104.58323 -246.568976)
		(width 0.1143)
		(layer "In11.Cu")
		(net "P5E_CPU1_G1_TX_DP<7>")
	)
	(arc
		(start 104.512364 -232.030016)
		(mid 104.356436 -232.334308)
		(end 104.512364 -232.6386)
		(width 0.1143)
		(layer "In11.Cu")
		(net "P5E_CPU1_G1_TX_DP<7>")
	)
	(arc
		(start 104.512364 -246.610124)
		(mid 104.397688 -246.743458)
		(end 104.356408 -246.914416)
		(width 0.1143)
		(layer "In11.Cu")
		(net "P5E_CPU1_G1_TX_DP<7>")
	)
	(arc
		(start 103.643176 -224.579942)
		(mid 103.821989 -224.782292)
		(end 103.886508 -225.044508)
		(width 0.1143)
		(layer "In11.Cu")
		(net "P5E_CPU1_G1_TX_DP<7>")
	)
	(arc
		(start 104.11333 -225.389948)
		(mid 104.292143 -225.592298)
		(end 104.356662 -225.854514)
		(width 0.1143)
		(layer "In11.Cu")
		(net "P5E_CPU1_G1_TX_DP<7>")
	)
	(arc
		(start 104.58323 -231.059736)
		(mid 104.826557 -231.524302)
		(end 104.58323 -231.988868)
		(width 0.1143)
		(layer "In11.Cu")
		(net "P5E_CPU1_G1_TX_DP<7>")
	)
	(arc
		(start 104.58323 -242.39982)
		(mid 104.826557 -242.864386)
		(end 104.58323 -243.328952)
		(width 0.1143)
		(layer "In11.Cu")
		(net "P5E_CPU1_G1_TX_DP<7>")
	)
	(arc
		(start 104.356662 -225.854514)
		(mid 104.398211 -226.025936)
		(end 104.513634 -226.159314)
		(width 0.1143)
		(layer "In11.Cu")
		(net "P5E_CPU1_G1_TX_DP<7>")
	)
	(arc
		(start 104.513634 -227.169726)
		(mid 104.356657 -227.474526)
		(end 104.513634 -227.779326)
		(width 0.1143)
		(layer "In11.Cu")
		(net "P5E_CPU1_G1_TX_DP<7>")
	)
	(arc
		(start 103.64343 -222.960184)
		(mid 103.886548 -223.424673)
		(end 103.643176 -223.889062)
		(width 0.1143)
		(layer "In11.Cu")
		(net "P5E_CPU1_G1_TX_DP<7>")
	)
	(arc
		(start 104.58323 -226.199954)
		(mid 104.826557 -226.66452)
		(end 104.58323 -227.129086)
		(width 0.1143)
		(layer "In11.Cu")
		(net "P5E_CPU1_G1_TX_DP<7>")
	)
	(arc
		(start 104.512364 -244.990112)
		(mid 104.356436 -245.294404)
		(end 104.512364 -245.598696)
		(width 0.1143)
		(layer "In11.Cu")
		(net "P5E_CPU1_G1_TX_DP<7>")
	)
	(arc
		(start 104.512364 -236.890052)
		(mid 104.356436 -237.194344)
		(end 104.512364 -237.498636)
		(width 0.1143)
		(layer "In11.Cu")
		(net "P5E_CPU1_G1_TX_DP<7>")
	)
	(arc
		(start 103.57231 -223.93021)
		(mid 103.416382 -224.234502)
		(end 103.57231 -224.538794)
		(width 0.1143)
		(layer "In11.Cu")
		(net "P5E_CPU1_G1_TX_DP<7>")
	)
	(arc
		(start 104.58323 -244.019832)
		(mid 104.826557 -244.484398)
		(end 104.58323 -244.948964)
		(width 0.1143)
		(layer "In11.Cu")
		(net "P5E_CPU1_G1_TX_DP<7>")
	)
	(arc
		(start 104.58323 -239.159796)
		(mid 104.826557 -239.624362)
		(end 104.58323 -240.088928)
		(width 0.1143)
		(layer "In11.Cu")
		(net "P5E_CPU1_G1_TX_DP<7>")
	)
	(arc
		(start 103.886508 -225.044508)
		(mid 103.927763 -225.215479)
		(end 104.042464 -225.3488)
		(width 0.1143)
		(layer "In11.Cu")
		(net "P5E_CPU1_G1_TX_DP<7>")
	)
	(arc
		(start 104.356408 -246.914416)
		(mid 104.291893 -247.176635)
		(end 104.113076 -247.378982)
		(width 0.1143)
		(layer "In11.Cu")
		(net "P5E_CPU1_G1_TX_DP<7>")
	)
	(arc
		(start 104.58323 -235.919772)
		(mid 104.826557 -236.384338)
		(end 104.58323 -236.848904)
		(width 0.1143)
		(layer "In11.Cu")
		(net "P5E_CPU1_G1_TX_DP<7>")
	)
	(arc
		(start 104.512364 -240.130076)
		(mid 104.356436 -240.434368)
		(end 104.512364 -240.73866)
		(width 0.1143)
		(layer "In11.Cu")
		(net "P5E_CPU1_G1_TX_DP<7>")
	)
	(arc
		(start 104.58323 -234.29976)
		(mid 104.826557 -234.764326)
		(end 104.58323 -235.228892)
		(width 0.1143)
		(layer "In11.Cu")
		(net "P5E_CPU1_G1_TX_DP<7>")
	)
	(arc
		(start 104.58323 -232.679748)
		(mid 104.826557 -233.144314)
		(end 104.58323 -233.60888)
		(width 0.1143)
		(layer "In11.Cu")
		(net "P5E_CPU1_G1_TX_DP<7>")
	)
	(arc
		(start 104.58323 -237.539784)
		(mid 104.826557 -238.00435)
		(end 104.58323 -238.468916)
		(width 0.1143)
		(layer "In11.Cu")
		(net "P5E_CPU1_G1_TX_DP<7>")
	)
	(arc
		(start 104.58323 -240.779808)
		(mid 104.826557 -241.244374)
		(end 104.58323 -241.70894)
		(width 0.1143)
		(layer "In11.Cu")
		(net "P5E_CPU1_G1_TX_DP<7>")
	)
	(arc
		(start 104.580436 -229.437946)
		(mid 104.826437 -229.904185)
		(end 104.58069 -230.370634)
		(width 0.1143)
		(layer "In11.Cu")
		(net "P5E_CPU1_G1_TX_DP<7>")
	)
	(arc
		(start 104.356408 -230.71455)
		(mid 104.39717 -230.884434)
		(end 104.510586 -231.017318)
		(width 0.1143)
		(layer "In11.Cu")
		(net "P5E_CPU1_G1_TX_DP<7>")
	)
	(segment
		(start 41.874694 -17.890236)
		(end 41.578784 -18.186146)
		(width 0.12954)
		(layer "F.Cu")
		(net "P5E_CPU1_G1_TX_DP<6>")
	)
	(segment
		(start 107.547918 -246.370348)
		(end 107.081066 -246.10441)
		(width 0.12954)
		(layer "F.Cu")
		(net "P5E_CPU1_G1_TX_DP<6>")
	)
	(segment
		(start 41.578784 -18.86585)
		(end 41.849294 -19.13636)
		(width 0.12954)
		(layer "F.Cu")
		(net "P5E_CPU1_G1_TX_DP<6>")
	)
	(segment
		(start 41.578784 -18.186146)
		(end 41.578784 -18.86585)
		(width 0.12954)
		(layer "F.Cu")
		(net "P5E_CPU1_G1_TX_DP<6>")
	)
	(segment
		(start 105.451402 -231.01808)
		(end 105.483914 -231.036876)
		(width 0.1143)
		(layer "In11.Cu")
		(net "P5E_CPU1_G1_TX_DP<6>")
	)
	(segment
		(start 105.483914 -237.516924)
		(end 105.52303 -237.539784)
		(width 0.1143)
		(layer "In11.Cu")
		(net "P5E_CPU1_G1_TX_DP<6>")
	)
	(segment
		(start 104.54386 -224.557082)
		(end 104.582976 -224.579942)
		(width 0.1143)
		(layer "In11.Cu")
		(net "P5E_CPU1_G1_TX_DP<6>")
	)
	(segment
		(start 105.013252 -225.36658)
		(end 105.014014 -225.367088)
		(width 0.1143)
		(layer "In11.Cu")
		(net "P5E_CPU1_G1_TX_DP<6>")
	)
	(segment
		(start 105.52303 -241.70894)
		(end 105.483914 -241.7318)
		(width 0.1143)
		(layer "In11.Cu")
		(net "P5E_CPU1_G1_TX_DP<6>")
	)
	(segment
		(start 105.483914 -232.011728)
		(end 105.453434 -232.029508)
		(width 0.1143)
		(layer "In11.Cu")
		(net "P5E_CPU1_G1_TX_DP<6>")
	)
	(segment
		(start 105.483914 -242.37696)
		(end 105.52303 -242.39982)
		(width 0.1143)
		(layer "In11.Cu")
		(net "P5E_CPU1_G1_TX_DP<6>")
	)
	(segment
		(start 151.511508 -170.109896)
		(end 148.209 -174.70755)
		(width 0.14224)
		(layer "In11.Cu")
		(net "P5E_CPU1_G1_TX_DP<6>")
	)
	(segment
		(start 105.52303 -238.468916)
		(end 105.483914 -238.491776)
		(width 0.1143)
		(layer "In11.Cu")
		(net "P5E_CPU1_G1_TX_DP<6>")
	)
	(segment
		(start 105.52303 -236.848904)
		(end 105.483914 -236.871764)
		(width 0.1143)
		(layer "In11.Cu")
		(net "P5E_CPU1_G1_TX_DP<6>")
	)
	(segment
		(start 104.546146 -222.290386)
		(end 104.543606 -222.29191)
		(width 0.1143)
		(layer "In11.Cu")
		(net "P5E_CPU1_G1_TX_DP<6>")
	)
	(segment
		(start 105.014014 -225.367088)
		(end 105.01503 -225.367596)
		(width 0.1143)
		(layer "In11.Cu")
		(net "P5E_CPU1_G1_TX_DP<6>")
	)
	(segment
		(start 105.453434 -240.739168)
		(end 105.483914 -240.756948)
		(width 0.1143)
		(layer "In11.Cu")
		(net "P5E_CPU1_G1_TX_DP<6>")
	)
	(segment
		(start 105.483914 -241.7318)
		(end 105.453434 -241.74958)
		(width 0.1143)
		(layer "In11.Cu")
		(net "P5E_CPU1_G1_TX_DP<6>")
	)
	(segment
		(start 105.52303 -228.749098)
		(end 105.522522 -228.749352)
		(width 0.1143)
		(layer "In11.Cu")
		(net "P5E_CPU1_G1_TX_DP<6>")
	)
	(segment
		(start 106.70032 -246.021606)
		(end 106.783124 -246.10441)
		(width 0.1143)
		(layer "In11.Cu")
		(net "P5E_CPU1_G1_TX_DP<6>")
	)
	(segment
		(start 106.783124 -246.10441)
		(end 107.081066 -246.10441)
		(width 0.1143)
		(layer "In11.Cu")
		(net "P5E_CPU1_G1_TX_DP<6>")
	)
	(segment
		(start 105.483914 -228.771958)
		(end 105.453434 -228.789738)
		(width 0.1143)
		(layer "In11.Cu")
		(net "P5E_CPU1_G1_TX_DP<6>")
	)
	(segment
		(start 148.551392 -137.520934)
		(end 152.762712 -146.229324)
		(width 0.14224)
		(layer "In11.Cu")
		(net "P5E_CPU1_G1_TX_DP<6>")
	)
	(segment
		(start 41.558464 -20.192746)
		(end 51.656488 -47.890938)
		(width 0.14224)
		(layer "In11.Cu")
		(net "P5E_CPU1_G1_TX_DP<6>")
	)
	(segment
		(start 105.009442 -225.364548)
		(end 105.011982 -225.365818)
		(width 0.1143)
		(layer "In11.Cu")
		(net "P5E_CPU1_G1_TX_DP<6>")
	)
	(segment
		(start 104.847644 -214.680546)
		(end 104.847644 -221.05493)
		(width 0.14224)
		(layer "In11.Cu")
		(net "P5E_CPU1_G1_TX_DP<6>")
	)
	(segment
		(start 148.209 -174.70755)
		(end 109.979206 -206.036418)
		(width 0.14224)
		(layer "In11.Cu")
		(net "P5E_CPU1_G1_TX_DP<6>")
	)
	(segment
		(start 105.483914 -235.251752)
		(end 105.453434 -235.269532)
		(width 0.1143)
		(layer "In11.Cu")
		(net "P5E_CPU1_G1_TX_DP<6>")
	)
	(segment
		(start 106.248708 -245.303802)
		(end 106.248708 -245.313454)
		(width 0.1143)
		(layer "In11.Cu")
		(net "P5E_CPU1_G1_TX_DP<6>")
	)
	(segment
		(start 105.483914 -227.797106)
		(end 105.52303 -227.819966)
		(width 0.1143)
		(layer "In11.Cu")
		(net "P5E_CPU1_G1_TX_DP<6>")
	)
	(segment
		(start 105.483914 -235.896912)
		(end 105.52303 -235.919772)
		(width 0.1143)
		(layer "In11.Cu")
		(net "P5E_CPU1_G1_TX_DP<6>")
	)
	(segment
		(start 105.016554 -225.368612)
		(end 105.05313 -225.389948)
		(width 0.1143)
		(layer "In11.Cu")
		(net "P5E_CPU1_G1_TX_DP<6>")
	)
	(segment
		(start 105.007156 -225.363024)
		(end 105.009442 -225.364548)
		(width 0.1143)
		(layer "In11.Cu")
		(net "P5E_CPU1_G1_TX_DP<6>")
	)
	(segment
		(start 105.483914 -238.491776)
		(end 105.453434 -238.509556)
		(width 0.1143)
		(layer "In11.Cu")
		(net "P5E_CPU1_G1_TX_DP<6>")
	)
	(segment
		(start 105.483914 -233.63174)
		(end 105.453434 -233.64952)
		(width 0.1143)
		(layer "In11.Cu")
		(net "P5E_CPU1_G1_TX_DP<6>")
	)
	(segment
		(start 105.52049 -230.370634)
		(end 105.453434 -230.40975)
		(width 0.1143)
		(layer "In11.Cu")
		(net "P5E_CPU1_G1_TX_DP<6>")
	)
	(segment
		(start 105.453434 -232.639108)
		(end 105.483914 -232.656888)
		(width 0.1143)
		(layer "In11.Cu")
		(net "P5E_CPU1_G1_TX_DP<6>")
	)
	(segment
		(start 105.453434 -227.779326)
		(end 105.483914 -227.797106)
		(width 0.1143)
		(layer "In11.Cu")
		(net "P5E_CPU1_G1_TX_DP<6>")
	)
	(segment
		(start 105.483914 -236.871764)
		(end 105.453434 -236.889544)
		(width 0.1143)
		(layer "In11.Cu")
		(net "P5E_CPU1_G1_TX_DP<6>")
	)
	(segment
		(start 105.453434 -243.979192)
		(end 105.483914 -243.996972)
		(width 0.1143)
		(layer "In11.Cu")
		(net "P5E_CPU1_G1_TX_DP<6>")
	)
	(segment
		(start 105.453434 -234.25912)
		(end 105.483914 -234.2769)
		(width 0.1143)
		(layer "In11.Cu")
		(net "P5E_CPU1_G1_TX_DP<6>")
	)
	(segment
		(start 105.483914 -232.656888)
		(end 105.52303 -232.679748)
		(width 0.1143)
		(layer "In11.Cu")
		(net "P5E_CPU1_G1_TX_DP<6>")
	)
	(segment
		(start 153.61412 -163.990528)
		(end 151.70785 -169.590212)
		(width 0.14224)
		(layer "In11.Cu")
		(net "P5E_CPU1_G1_TX_DP<6>")
	)
	(segment
		(start 106.42346 -245.61673)
		(end 106.462322 -245.639336)
		(width 0.1143)
		(layer "In11.Cu")
		(net "P5E_CPU1_G1_TX_DP<6>")
	)
	(segment
		(start 55.967122 -54.273196)
		(end 148.551392 -137.520934)
		(width 0.14224)
		(layer "In11.Cu")
		(net "P5E_CPU1_G1_TX_DP<6>")
	)
	(segment
		(start 105.483914 -243.351812)
		(end 105.453434 -243.369592)
		(width 0.1143)
		(layer "In11.Cu")
		(net "P5E_CPU1_G1_TX_DP<6>")
	)
	(segment
		(start 104.58323 -223.889062)
		(end 104.544114 -223.911922)
		(width 0.1143)
		(layer "In11.Cu")
		(net "P5E_CPU1_G1_TX_DP<6>")
	)
	(segment
		(start 105.483914 -240.756948)
		(end 105.52303 -240.779808)
		(width 0.1143)
		(layer "In11.Cu")
		(net "P5E_CPU1_G1_TX_DP<6>")
	)
	(segment
		(start 104.51338 -224.539302)
		(end 104.54386 -224.557082)
		(width 0.1143)
		(layer "In11.Cu")
		(net "P5E_CPU1_G1_TX_DP<6>")
	)
	(segment
		(start 105.52303 -235.228892)
		(end 105.483914 -235.251752)
		(width 0.1143)
		(layer "In11.Cu")
		(net "P5E_CPU1_G1_TX_DP<6>")
	)
	(segment
		(start 105.52303 -243.328952)
		(end 105.483914 -243.351812)
		(width 0.1143)
		(layer "In11.Cu")
		(net "P5E_CPU1_G1_TX_DP<6>")
	)
	(segment
		(start 105.922064 -244.788436)
		(end 105.965244 -244.813582)
		(width 0.1143)
		(layer "In11.Cu")
		(net "P5E_CPU1_G1_TX_DP<6>")
	)
	(segment
		(start 105.52303 -240.088928)
		(end 105.483914 -240.111788)
		(width 0.1143)
		(layer "In11.Cu")
		(net "P5E_CPU1_G1_TX_DP<6>")
	)
	(segment
		(start 109.979206 -206.036418)
		(end 104.847644 -214.680546)
		(width 0.14224)
		(layer "In11.Cu")
		(net "P5E_CPU1_G1_TX_DP<6>")
	)
	(segment
		(start 105.483914 -239.136936)
		(end 105.52303 -239.159796)
		(width 0.1143)
		(layer "In11.Cu")
		(net "P5E_CPU1_G1_TX_DP<6>")
	)
	(segment
		(start 51.656488 -47.890938)
		(end 55.967122 -54.273196)
		(width 0.14224)
		(layer "In11.Cu")
		(net "P5E_CPU1_G1_TX_DP<6>")
	)
	(segment
		(start 104.982264 -225.3488)
		(end 105.00614 -225.362516)
		(width 0.1143)
		(layer "In11.Cu")
		(net "P5E_CPU1_G1_TX_DP<6>")
	)
	(segment
		(start 105.483914 -226.177094)
		(end 105.52303 -226.199954)
		(width 0.1143)
		(layer "In11.Cu")
		(net "P5E_CPU1_G1_TX_DP<6>")
	)
	(segment
		(start 105.453434 -237.499144)
		(end 105.483914 -237.516924)
		(width 0.1143)
		(layer "In11.Cu")
		(net "P5E_CPU1_G1_TX_DP<6>")
	)
	(segment
		(start 105.52303 -233.60888)
		(end 105.483914 -233.63174)
		(width 0.1143)
		(layer "In11.Cu")
		(net "P5E_CPU1_G1_TX_DP<6>")
	)
	(segment
		(start 104.560116 -222.946214)
		(end 104.58323 -222.95993)
		(width 0.1143)
		(layer "In11.Cu")
		(net "P5E_CPU1_G1_TX_DP<6>")
	)
	(segment
		(start 104.847644 -221.083378)
		(end 104.801924 -221.129098)
		(width 0.1143)
		(layer "In11.Cu")
		(net "P5E_CPU1_G1_TX_DP<6>")
	)
	(segment
		(start 105.453434 -242.35918)
		(end 105.483914 -242.37696)
		(width 0.1143)
		(layer "In11.Cu")
		(net "P5E_CPU1_G1_TX_DP<6>")
	)
	(segment
		(start 105.483914 -234.2769)
		(end 105.52303 -234.29976)
		(width 0.1143)
		(layer "In11.Cu")
		(net "P5E_CPU1_G1_TX_DP<6>")
	)
	(segment
		(start 104.801924 -221.299278)
		(end 104.826308 -221.700598)
		(width 0.1143)
		(layer "In11.Cu")
		(net "P5E_CPU1_G1_TX_DP<6>")
	)
	(segment
		(start 105.483914 -227.151946)
		(end 105.453434 -227.169726)
		(width 0.1143)
		(layer "In11.Cu")
		(net "P5E_CPU1_G1_TX_DP<6>")
	)
	(segment
		(start 105.483914 -243.996972)
		(end 105.52303 -244.019832)
		(width 0.1143)
		(layer "In11.Cu")
		(net "P5E_CPU1_G1_TX_DP<6>")
	)
	(segment
		(start 104.826308 -221.700598)
		(end 104.826308 -221.804484)
		(width 0.1143)
		(layer "In11.Cu")
		(net "P5E_CPU1_G1_TX_DP<6>")
	)
	(segment
		(start 105.483914 -240.111788)
		(end 105.453434 -240.129568)
		(width 0.1143)
		(layer "In11.Cu")
		(net "P5E_CPU1_G1_TX_DP<6>")
	)
	(segment
		(start 105.522522 -228.749352)
		(end 105.483914 -228.771958)
		(width 0.1143)
		(layer "In11.Cu")
		(net "P5E_CPU1_G1_TX_DP<6>")
	)
	(segment
		(start 105.52303 -231.988868)
		(end 105.483914 -232.011728)
		(width 0.1143)
		(layer "In11.Cu")
		(net "P5E_CPU1_G1_TX_DP<6>")
	)
	(segment
		(start 41.849294 -19.13636)
		(end 41.558464 -19.42719)
		(width 0.14224)
		(layer "In11.Cu")
		(net "P5E_CPU1_G1_TX_DP<6>")
	)
	(segment
		(start 105.483914 -229.416864)
		(end 105.52303 -229.439724)
		(width 0.1143)
		(layer "In11.Cu")
		(net "P5E_CPU1_G1_TX_DP<6>")
	)
	(segment
		(start 104.801924 -221.129098)
		(end 104.801924 -221.299278)
		(width 0.1143)
		(layer "In11.Cu")
		(net "P5E_CPU1_G1_TX_DP<6>")
	)
	(segment
		(start 41.558464 -19.42719)
		(end 41.558464 -20.192746)
		(width 0.14224)
		(layer "In11.Cu")
		(net "P5E_CPU1_G1_TX_DP<6>")
	)
	(segment
		(start 152.762712 -146.229324)
		(end 153.61412 -159.84728)
		(width 0.14224)
		(layer "In11.Cu")
		(net "P5E_CPU1_G1_TX_DP<6>")
	)
	(segment
		(start 105.453434 -239.119156)
		(end 105.483914 -239.136936)
		(width 0.1143)
		(layer "In11.Cu")
		(net "P5E_CPU1_G1_TX_DP<6>")
	)
	(segment
		(start 105.01503 -225.367596)
		(end 105.016554 -225.368612)
		(width 0.1143)
		(layer "In11.Cu")
		(net "P5E_CPU1_G1_TX_DP<6>")
	)
	(segment
		(start 105.00614 -225.362516)
		(end 105.007156 -225.363024)
		(width 0.1143)
		(layer "In11.Cu")
		(net "P5E_CPU1_G1_TX_DP<6>")
	)
	(segment
		(start 105.483914 -231.036876)
		(end 105.52303 -231.059736)
		(width 0.1143)
		(layer "In11.Cu")
		(net "P5E_CPU1_G1_TX_DP<6>")
	)
	(segment
		(start 105.011982 -225.365818)
		(end 105.013252 -225.36658)
		(width 0.1143)
		(layer "In11.Cu")
		(net "P5E_CPU1_G1_TX_DP<6>")
	)
	(segment
		(start 105.451402 -229.398068)
		(end 105.483914 -229.416864)
		(width 0.1143)
		(layer "In11.Cu")
		(net "P5E_CPU1_G1_TX_DP<6>")
	)
	(segment
		(start 104.847644 -221.05493)
		(end 104.847644 -221.083378)
		(width 0.1143)
		(layer "In11.Cu")
		(net "P5E_CPU1_G1_TX_DP<6>")
	)
	(segment
		(start 104.544114 -223.911922)
		(end 104.51338 -223.929702)
		(width 0.1143)
		(layer "In11.Cu")
		(net "P5E_CPU1_G1_TX_DP<6>")
	)
	(segment
		(start 153.61412 -159.84728)
		(end 153.61412 -163.990528)
		(width 0.14224)
		(layer "In11.Cu")
		(net "P5E_CPU1_G1_TX_DP<6>")
	)
	(segment
		(start 151.70785 -169.590212)
		(end 151.511508 -170.109896)
		(width 0.14224)
		(layer "In11.Cu")
		(net "P5E_CPU1_G1_TX_DP<6>")
	)
	(segment
		(start 105.453434 -226.159314)
		(end 105.483914 -226.177094)
		(width 0.1143)
		(layer "In11.Cu")
		(net "P5E_CPU1_G1_TX_DP<6>")
	)
	(segment
		(start 104.543606 -222.936816)
		(end 104.560116 -222.946214)
		(width 0.1143)
		(layer "In11.Cu")
		(net "P5E_CPU1_G1_TX_DP<6>")
	)
	(segment
		(start 105.453434 -235.879132)
		(end 105.483914 -235.896912)
		(width 0.1143)
		(layer "In11.Cu")
		(net "P5E_CPU1_G1_TX_DP<6>")
	)
	(segment
		(start 105.52303 -227.129086)
		(end 105.483914 -227.151946)
		(width 0.1143)
		(layer "In11.Cu")
		(net "P5E_CPU1_G1_TX_DP<6>")
	)
	(arc
		(start 105.52303 -242.39982)
		(mid 105.766357 -242.864386)
		(end 105.52303 -243.328952)
		(width 0.1143)
		(layer "In11.Cu")
		(net "P5E_CPU1_G1_TX_DP<6>")
	)
	(arc
		(start 105.453434 -238.509556)
		(mid 105.296457 -238.814356)
		(end 105.453434 -239.119156)
		(width 0.1143)
		(layer "In11.Cu")
		(net "P5E_CPU1_G1_TX_DP<6>")
	)
	(arc
		(start 105.453434 -232.029508)
		(mid 105.296457 -232.334308)
		(end 105.453434 -232.639108)
		(width 0.1143)
		(layer "In11.Cu")
		(net "P5E_CPU1_G1_TX_DP<6>")
	)
	(arc
		(start 105.52303 -231.059736)
		(mid 105.766357 -231.524302)
		(end 105.52303 -231.988868)
		(width 0.1143)
		(layer "In11.Cu")
		(net "P5E_CPU1_G1_TX_DP<6>")
	)
	(arc
		(start 104.51338 -223.929702)
		(mid 104.356403 -224.234502)
		(end 104.51338 -224.539302)
		(width 0.1143)
		(layer "In11.Cu")
		(net "P5E_CPU1_G1_TX_DP<6>")
	)
	(arc
		(start 105.766362 -244.484398)
		(mid 105.807555 -244.655187)
		(end 105.922064 -244.788436)
		(width 0.1143)
		(layer "In11.Cu")
		(net "P5E_CPU1_G1_TX_DP<6>")
	)
	(arc
		(start 105.52303 -240.779808)
		(mid 105.766357 -241.244374)
		(end 105.52303 -241.70894)
		(width 0.1143)
		(layer "In11.Cu")
		(net "P5E_CPU1_G1_TX_DP<6>")
	)
	(arc
		(start 104.826308 -221.804484)
		(mid 104.751242 -222.084913)
		(end 104.546146 -222.290386)
		(width 0.1143)
		(layer "In11.Cu")
		(net "P5E_CPU1_G1_TX_DP<6>")
	)
	(arc
		(start 105.453434 -235.269532)
		(mid 105.296457 -235.574332)
		(end 105.453434 -235.879132)
		(width 0.1143)
		(layer "In11.Cu")
		(net "P5E_CPU1_G1_TX_DP<6>")
	)
	(arc
		(start 105.52303 -237.539784)
		(mid 105.766357 -238.00435)
		(end 105.52303 -238.468916)
		(width 0.1143)
		(layer "In11.Cu")
		(net "P5E_CPU1_G1_TX_DP<6>")
	)
	(arc
		(start 105.453434 -228.789738)
		(mid 105.338007 -228.923114)
		(end 105.296462 -229.094538)
		(width 0.1143)
		(layer "In11.Cu")
		(net "P5E_CPU1_G1_TX_DP<6>")
	)
	(arc
		(start 106.462322 -245.639336)
		(mid 106.462703 -245.63959)
		(end 106.463084 -245.639844)
		(width 0.1143)
		(layer "In11.Cu")
		(net "P5E_CPU1_G1_TX_DP<6>")
	)
	(arc
		(start 104.826308 -225.044508)
		(mid 104.867563 -225.215479)
		(end 104.982264 -225.3488)
		(width 0.1143)
		(layer "In11.Cu")
		(net "P5E_CPU1_G1_TX_DP<6>")
	)
	(arc
		(start 105.453434 -227.169726)
		(mid 105.296457 -227.474526)
		(end 105.453434 -227.779326)
		(width 0.1143)
		(layer "In11.Cu")
		(net "P5E_CPU1_G1_TX_DP<6>")
	)
	(arc
		(start 105.453434 -240.129568)
		(mid 105.296457 -240.434368)
		(end 105.453434 -240.739168)
		(width 0.1143)
		(layer "In11.Cu")
		(net "P5E_CPU1_G1_TX_DP<6>")
	)
	(arc
		(start 105.52303 -226.199954)
		(mid 105.766357 -226.66452)
		(end 105.52303 -227.129086)
		(width 0.1143)
		(layer "In11.Cu")
		(net "P5E_CPU1_G1_TX_DP<6>")
	)
	(arc
		(start 105.453434 -230.40975)
		(mid 105.338007 -230.543126)
		(end 105.296462 -230.71455)
		(width 0.1143)
		(layer "In11.Cu")
		(net "P5E_CPU1_G1_TX_DP<6>")
	)
	(arc
		(start 104.582976 -224.579942)
		(mid 104.761789 -224.782292)
		(end 104.826308 -225.044508)
		(width 0.1143)
		(layer "In11.Cu")
		(net "P5E_CPU1_G1_TX_DP<6>")
	)
	(arc
		(start 105.453434 -236.889544)
		(mid 105.296457 -237.194344)
		(end 105.453434 -237.499144)
		(width 0.1143)
		(layer "In11.Cu")
		(net "P5E_CPU1_G1_TX_DP<6>")
	)
	(arc
		(start 105.52303 -234.29976)
		(mid 105.766357 -234.764326)
		(end 105.52303 -235.228892)
		(width 0.1143)
		(layer "In11.Cu")
		(net "P5E_CPU1_G1_TX_DP<6>")
	)
	(arc
		(start 106.248708 -245.313454)
		(mid 106.295598 -245.488405)
		(end 106.42346 -245.61673)
		(width 0.1143)
		(layer "In11.Cu")
		(net "P5E_CPU1_G1_TX_DP<6>")
	)
	(arc
		(start 105.453434 -233.64952)
		(mid 105.296457 -233.95432)
		(end 105.453434 -234.25912)
		(width 0.1143)
		(layer "In11.Cu")
		(net "P5E_CPU1_G1_TX_DP<6>")
	)
	(arc
		(start 105.52303 -232.679748)
		(mid 105.766357 -233.144314)
		(end 105.52303 -233.60888)
		(width 0.1143)
		(layer "In11.Cu")
		(net "P5E_CPU1_G1_TX_DP<6>")
	)
	(arc
		(start 104.543606 -222.29191)
		(mid 104.357968 -222.614426)
		(end 104.543606 -222.936816)
		(width 0.1143)
		(layer "In11.Cu")
		(net "P5E_CPU1_G1_TX_DP<6>")
	)
	(arc
		(start 105.296462 -230.71455)
		(mid 105.337428 -230.884956)
		(end 105.451402 -231.01808)
		(width 0.1143)
		(layer "In11.Cu")
		(net "P5E_CPU1_G1_TX_DP<6>")
	)
	(arc
		(start 105.965244 -244.813582)
		(mid 106.172728 -245.020669)
		(end 106.248708 -245.303802)
		(width 0.1143)
		(layer "In11.Cu")
		(net "P5E_CPU1_G1_TX_DP<6>")
	)
	(arc
		(start 105.766362 -229.90429)
		(mid 105.701126 -230.167881)
		(end 105.52049 -230.370634)
		(width 0.1143)
		(layer "In11.Cu")
		(net "P5E_CPU1_G1_TX_DP<6>")
	)
	(arc
		(start 105.52303 -239.159796)
		(mid 105.766357 -239.624362)
		(end 105.52303 -240.088928)
		(width 0.1143)
		(layer "In11.Cu")
		(net "P5E_CPU1_G1_TX_DP<6>")
	)
	(arc
		(start 105.52303 -227.819966)
		(mid 105.766357 -228.284532)
		(end 105.52303 -228.749098)
		(width 0.1143)
		(layer "In11.Cu")
		(net "P5E_CPU1_G1_TX_DP<6>")
	)
	(arc
		(start 105.05313 -225.389948)
		(mid 105.231943 -225.592298)
		(end 105.296462 -225.854514)
		(width 0.1143)
		(layer "In11.Cu")
		(net "P5E_CPU1_G1_TX_DP<6>")
	)
	(arc
		(start 104.58323 -222.95993)
		(mid 104.826557 -223.424496)
		(end 104.58323 -223.889062)
		(width 0.1143)
		(layer "In11.Cu")
		(net "P5E_CPU1_G1_TX_DP<6>")
	)
	(arc
		(start 106.463084 -245.639844)
		(mid 106.615071 -245.796352)
		(end 106.69651 -245.998746)
		(width 0.1143)
		(layer "In11.Cu")
		(net "P5E_CPU1_G1_TX_DP<6>")
	)
	(arc
		(start 105.296462 -225.854514)
		(mid 105.338011 -226.025936)
		(end 105.453434 -226.159314)
		(width 0.1143)
		(layer "In11.Cu")
		(net "P5E_CPU1_G1_TX_DP<6>")
	)
	(arc
		(start 105.52303 -229.439724)
		(mid 105.701843 -229.642074)
		(end 105.766362 -229.90429)
		(width 0.1143)
		(layer "In11.Cu")
		(net "P5E_CPU1_G1_TX_DP<6>")
	)
	(arc
		(start 105.52303 -244.019832)
		(mid 105.701843 -244.222182)
		(end 105.766362 -244.484398)
		(width 0.1143)
		(layer "In11.Cu")
		(net "P5E_CPU1_G1_TX_DP<6>")
	)
	(arc
		(start 105.453434 -241.74958)
		(mid 105.296457 -242.05438)
		(end 105.453434 -242.35918)
		(width 0.1143)
		(layer "In11.Cu")
		(net "P5E_CPU1_G1_TX_DP<6>")
	)
	(arc
		(start 105.52303 -235.919772)
		(mid 105.766357 -236.384338)
		(end 105.52303 -236.848904)
		(width 0.1143)
		(layer "In11.Cu")
		(net "P5E_CPU1_G1_TX_DP<6>")
	)
	(arc
		(start 105.453434 -243.369592)
		(mid 105.296457 -243.674392)
		(end 105.453434 -243.979192)
		(width 0.1143)
		(layer "In11.Cu")
		(net "P5E_CPU1_G1_TX_DP<6>")
	)
	(arc
		(start 105.296462 -229.094538)
		(mid 105.337428 -229.264944)
		(end 105.451402 -229.398068)
		(width 0.1143)
		(layer "In11.Cu")
		(net "P5E_CPU1_G1_TX_DP<6>")
	)
	(arc
		(start 106.69651 -245.998746)
		(mid 106.698533 -246.010156)
		(end 106.70032 -246.021606)
		(width 0.1143)
		(layer "In11.Cu")
		(net "P5E_CPU1_G1_TX_DP<6>")
	)
	(segment
		(start 44.668694 -16.366236)
		(end 44.372784 -16.662146)
		(width 0.12954)
		(layer "F.Cu")
		(net "P5E_CPU1_G1_TX_DP<5>")
	)
	(segment
		(start 44.372784 -16.662146)
		(end 44.372784 -17.34185)
		(width 0.12954)
		(layer "F.Cu")
		(net "P5E_CPU1_G1_TX_DP<5>")
	)
	(segment
		(start 107.547918 -244.750336)
		(end 107.081066 -244.484398)
		(width 0.12954)
		(layer "F.Cu")
		(net "P5E_CPU1_G1_TX_DP<5>")
	)
	(segment
		(start 44.372784 -17.34185)
		(end 44.643294 -17.61236)
		(width 0.12954)
		(layer "F.Cu")
		(net "P5E_CPU1_G1_TX_DP<5>")
	)
	(segment
		(start 106.429302 -239.139984)
		(end 106.430318 -239.140492)
		(width 0.1143)
		(layer "In11.Cu")
		(net "P5E_CPU1_G1_TX_DP<5>")
	)
	(segment
		(start 106.424984 -230.391462)
		(end 106.423968 -230.39197)
		(width 0.1143)
		(layer "In11.Cu")
		(net "P5E_CPU1_G1_TX_DP<5>")
	)
	(segment
		(start 105.453434 -224.539302)
		(end 105.483914 -224.557082)
		(width 0.1143)
		(layer "In11.Cu")
		(net "P5E_CPU1_G1_TX_DP<5>")
	)
	(segment
		(start 106.429302 -242.380008)
		(end 106.430318 -242.380516)
		(width 0.1143)
		(layer "In11.Cu")
		(net "P5E_CPU1_G1_TX_DP<5>")
	)
	(segment
		(start 106.423968 -226.177094)
		(end 106.463084 -226.199954)
		(width 0.1143)
		(layer "In11.Cu")
		(net "P5E_CPU1_G1_TX_DP<5>")
	)
	(segment
		(start 106.70032 -244.401594)
		(end 106.783124 -244.484398)
		(width 0.1143)
		(layer "In11.Cu")
		(net "P5E_CPU1_G1_TX_DP<5>")
	)
	(segment
		(start 148.935948 -175.317912)
		(end 110.697264 -206.653892)
		(width 0.14224)
		(layer "In11.Cu")
		(net "P5E_CPU1_G1_TX_DP<5>")
	)
	(segment
		(start 106.416094 -235.89234)
		(end 106.427016 -235.89869)
		(width 0.1143)
		(layer "In11.Cu")
		(net "P5E_CPU1_G1_TX_DP<5>")
	)
	(segment
		(start 106.423968 -232.656888)
		(end 106.424984 -232.657396)
		(width 0.1143)
		(layer "In11.Cu")
		(net "P5E_CPU1_G1_TX_DP<5>")
	)
	(segment
		(start 106.423968 -232.011728)
		(end 106.392218 -232.030016)
		(width 0.1143)
		(layer "In11.Cu")
		(net "P5E_CPU1_G1_TX_DP<5>")
	)
	(segment
		(start 105.792524 -214.915242)
		(end 105.792524 -221.05493)
		(width 0.14224)
		(layer "In11.Cu")
		(net "P5E_CPU1_G1_TX_DP<5>")
	)
	(segment
		(start 105.482136 -222.9358)
		(end 105.483406 -222.936562)
		(width 0.1143)
		(layer "In11.Cu")
		(net "P5E_CPU1_G1_TX_DP<5>")
	)
	(segment
		(start 154.553666 -164.163248)
		(end 153.626566 -166.886128)
		(width 0.14224)
		(layer "In11.Cu")
		(net "P5E_CPU1_G1_TX_DP<5>")
	)
	(segment
		(start 106.783124 -244.484398)
		(end 107.081066 -244.484398)
		(width 0.1143)
		(layer "In11.Cu")
		(net "P5E_CPU1_G1_TX_DP<5>")
	)
	(segment
		(start 106.416094 -237.512352)
		(end 106.42854 -237.519464)
		(width 0.1143)
		(layer "In11.Cu")
		(net "P5E_CPU1_G1_TX_DP<5>")
	)
	(segment
		(start 106.42854 -235.899452)
		(end 106.429302 -235.89996)
		(width 0.1143)
		(layer "In11.Cu")
		(net "P5E_CPU1_G1_TX_DP<5>")
	)
	(segment
		(start 53.19268 -48.223932)
		(end 56.682132 -53.6448)
		(width 0.14224)
		(layer "In11.Cu")
		(net "P5E_CPU1_G1_TX_DP<5>")
	)
	(segment
		(start 106.42854 -240.759488)
		(end 106.429302 -240.759996)
		(width 0.1143)
		(layer "In11.Cu")
		(net "P5E_CPU1_G1_TX_DP<5>")
	)
	(segment
		(start 106.444796 -235.23956)
		(end 106.42346 -235.252006)
		(width 0.1143)
		(layer "In11.Cu")
		(net "P5E_CPU1_G1_TX_DP<5>")
	)
	(segment
		(start 106.392218 -243.978684)
		(end 106.423968 -243.996972)
		(width 0.1143)
		(layer "In11.Cu")
		(net "P5E_CPU1_G1_TX_DP<5>")
	)
	(segment
		(start 106.430318 -237.52048)
		(end 106.462322 -237.539276)
		(width 0.1143)
		(layer "In11.Cu")
		(net "P5E_CPU1_G1_TX_DP<5>")
	)
	(segment
		(start 152.712674 -169.569384)
		(end 152.321514 -170.604434)
		(width 0.14224)
		(layer "In11.Cu")
		(net "P5E_CPU1_G1_TX_DP<5>")
	)
	(segment
		(start 106.423968 -227.797106)
		(end 106.463084 -227.819966)
		(width 0.1143)
		(layer "In11.Cu")
		(net "P5E_CPU1_G1_TX_DP<5>")
	)
	(segment
		(start 106.463084 -228.749098)
		(end 106.426508 -228.770434)
		(width 0.1143)
		(layer "In11.Cu")
		(net "P5E_CPU1_G1_TX_DP<5>")
	)
	(segment
		(start 106.444796 -240.099596)
		(end 106.42346 -240.112042)
		(width 0.1143)
		(layer "In11.Cu")
		(net "P5E_CPU1_G1_TX_DP<5>")
	)
	(segment
		(start 106.420412 -230.394002)
		(end 106.392218 -230.410258)
		(width 0.1143)
		(layer "In11.Cu")
		(net "P5E_CPU1_G1_TX_DP<5>")
	)
	(segment
		(start 105.477056 -222.933006)
		(end 105.478072 -222.933514)
		(width 0.1143)
		(layer "In11.Cu")
		(net "P5E_CPU1_G1_TX_DP<5>")
	)
	(segment
		(start 105.634282 -223.809306)
		(end 105.523538 -223.889316)
		(width 0.1143)
		(layer "In11.Cu")
		(net "P5E_CPU1_G1_TX_DP<5>")
	)
	(segment
		(start 106.463084 -231.988868)
		(end 106.423968 -232.011728)
		(width 0.1143)
		(layer "In11.Cu")
		(net "P5E_CPU1_G1_TX_DP<5>")
	)
	(segment
		(start 105.455212 -223.928432)
		(end 105.453434 -223.929702)
		(width 0.1143)
		(layer "In11.Cu")
		(net "P5E_CPU1_G1_TX_DP<5>")
	)
	(segment
		(start 105.483914 -222.29191)
		(end 105.453434 -222.30969)
		(width 0.1143)
		(layer "In11.Cu")
		(net "P5E_CPU1_G1_TX_DP<5>")
	)
	(segment
		(start 106.444796 -241.719608)
		(end 106.42346 -241.732054)
		(width 0.1143)
		(layer "In11.Cu")
		(net "P5E_CPU1_G1_TX_DP<5>")
	)
	(segment
		(start 44.352464 -20.192746)
		(end 53.19268 -48.223932)
		(width 0.14224)
		(layer "In11.Cu")
		(net "P5E_CPU1_G1_TX_DP<5>")
	)
	(segment
		(start 106.459528 -234.29722)
		(end 106.462322 -234.299252)
		(width 0.1143)
		(layer "In11.Cu")
		(net "P5E_CPU1_G1_TX_DP<5>")
	)
	(segment
		(start 106.423968 -243.351812)
		(end 106.392218 -243.3701)
		(width 0.1143)
		(layer "In11.Cu")
		(net "P5E_CPU1_G1_TX_DP<5>")
	)
	(segment
		(start 106.463084 -243.328952)
		(end 106.423968 -243.351812)
		(width 0.1143)
		(layer "In11.Cu")
		(net "P5E_CPU1_G1_TX_DP<5>")
	)
	(segment
		(start 106.45521 -235.914946)
		(end 106.455972 -235.915454)
		(width 0.1143)
		(layer "In11.Cu")
		(net "P5E_CPU1_G1_TX_DP<5>")
	)
	(segment
		(start 106.423206 -232.65638)
		(end 106.423968 -232.656888)
		(width 0.1143)
		(layer "In11.Cu")
		(net "P5E_CPU1_G1_TX_DP<5>")
	)
	(segment
		(start 106.430318 -242.380516)
		(end 106.462322 -242.399312)
		(width 0.1143)
		(layer "In11.Cu")
		(net "P5E_CPU1_G1_TX_DP<5>")
	)
	(segment
		(start 105.484168 -222.93707)
		(end 105.486708 -222.938848)
		(width 0.1143)
		(layer "In11.Cu")
		(net "P5E_CPU1_G1_TX_DP<5>")
	)
	(segment
		(start 56.682132 -53.6448)
		(end 149.304502 -136.934448)
		(width 0.14224)
		(layer "In11.Cu")
		(net "P5E_CPU1_G1_TX_DP<5>")
	)
	(segment
		(start 106.430318 -239.140492)
		(end 106.462322 -239.159288)
		(width 0.1143)
		(layer "In11.Cu")
		(net "P5E_CPU1_G1_TX_DP<5>")
	)
	(segment
		(start 105.523538 -223.889316)
		(end 105.455212 -223.928432)
		(width 0.1143)
		(layer "In11.Cu")
		(net "P5E_CPU1_G1_TX_DP<5>")
	)
	(segment
		(start 105.452418 -222.918782)
		(end 105.477056 -222.933006)
		(width 0.1143)
		(layer "In11.Cu")
		(net "P5E_CPU1_G1_TX_DP<5>")
	)
	(segment
		(start 153.626566 -166.886128)
		(end 153.626566 -166.885874)
		(width 0.14224)
		(layer "In11.Cu")
		(net "P5E_CPU1_G1_TX_DP<5>")
	)
	(segment
		(start 106.427016 -235.89869)
		(end 106.42854 -235.899452)
		(width 0.1143)
		(layer "In11.Cu")
		(net "P5E_CPU1_G1_TX_DP<5>")
	)
	(segment
		(start 106.392218 -232.6386)
		(end 106.423206 -232.65638)
		(width 0.1143)
		(layer "In11.Cu")
		(net "P5E_CPU1_G1_TX_DP<5>")
	)
	(segment
		(start 106.44505 -235.23956)
		(end 106.444796 -235.23956)
		(width 0.1143)
		(layer "In11.Cu")
		(net "P5E_CPU1_G1_TX_DP<5>")
	)
	(segment
		(start 106.463084 -236.848904)
		(end 106.44505 -236.859572)
		(width 0.1143)
		(layer "In11.Cu")
		(net "P5E_CPU1_G1_TX_DP<5>")
	)
	(segment
		(start 106.424984 -228.77145)
		(end 106.423968 -228.771958)
		(width 0.1143)
		(layer "In11.Cu")
		(net "P5E_CPU1_G1_TX_DP<5>")
	)
	(segment
		(start 105.483914 -224.557082)
		(end 105.52303 -224.579942)
		(width 0.1143)
		(layer "In11.Cu")
		(net "P5E_CPU1_G1_TX_DP<5>")
	)
	(segment
		(start 106.392218 -234.258612)
		(end 106.423968 -234.2769)
		(width 0.1143)
		(layer "In11.Cu")
		(net "P5E_CPU1_G1_TX_DP<5>")
	)
	(segment
		(start 105.478072 -222.933514)
		(end 105.479596 -222.93453)
		(width 0.1143)
		(layer "In11.Cu")
		(net "P5E_CPU1_G1_TX_DP<5>")
	)
	(segment
		(start 106.429302 -237.519972)
		(end 106.430318 -237.52048)
		(width 0.1143)
		(layer "In11.Cu")
		(net "P5E_CPU1_G1_TX_DP<5>")
	)
	(segment
		(start 105.95737 -225.36912)
		(end 105.99039 -225.38817)
		(width 0.1143)
		(layer "In11.Cu")
		(net "P5E_CPU1_G1_TX_DP<5>")
	)
	(segment
		(start 106.46029 -227.131118)
		(end 106.423968 -227.151946)
		(width 0.1143)
		(layer "In11.Cu")
		(net "P5E_CPU1_G1_TX_DP<5>")
	)
	(segment
		(start 106.423968 -234.2769)
		(end 106.459528 -234.29722)
		(width 0.1143)
		(layer "In11.Cu")
		(net "P5E_CPU1_G1_TX_DP<5>")
	)
	(segment
		(start 44.352464 -17.90319)
		(end 44.352464 -20.192746)
		(width 0.14224)
		(layer "In11.Cu")
		(net "P5E_CPU1_G1_TX_DP<5>")
	)
	(segment
		(start 154.553666 -159.817562)
		(end 154.553666 -164.163248)
		(width 0.14224)
		(layer "In11.Cu")
		(net "P5E_CPU1_G1_TX_DP<5>")
	)
	(segment
		(start 106.416094 -240.752376)
		(end 106.42854 -240.759488)
		(width 0.1143)
		(layer "In11.Cu")
		(net "P5E_CPU1_G1_TX_DP<5>")
	)
	(segment
		(start 106.44505 -236.859572)
		(end 106.444796 -236.859572)
		(width 0.1143)
		(layer "In11.Cu")
		(net "P5E_CPU1_G1_TX_DP<5>")
	)
	(segment
		(start 105.766362 -221.613984)
		(end 105.766362 -221.804484)
		(width 0.1143)
		(layer "In11.Cu")
		(net "P5E_CPU1_G1_TX_DP<5>")
	)
	(segment
		(start 105.746804 -221.30512)
		(end 105.766362 -221.613984)
		(width 0.1143)
		(layer "In11.Cu")
		(net "P5E_CPU1_G1_TX_DP<5>")
	)
	(segment
		(start 106.42854 -237.519464)
		(end 106.429302 -237.519972)
		(width 0.1143)
		(layer "In11.Cu")
		(net "P5E_CPU1_G1_TX_DP<5>")
	)
	(segment
		(start 106.430318 -240.760504)
		(end 106.462322 -240.7793)
		(width 0.1143)
		(layer "In11.Cu")
		(net "P5E_CPU1_G1_TX_DP<5>")
	)
	(segment
		(start 106.463084 -241.70894)
		(end 106.44505 -241.719608)
		(width 0.1143)
		(layer "In11.Cu")
		(net "P5E_CPU1_G1_TX_DP<5>")
	)
	(segment
		(start 106.444796 -236.859572)
		(end 106.42346 -236.872018)
		(width 0.1143)
		(layer "In11.Cu")
		(net "P5E_CPU1_G1_TX_DP<5>")
	)
	(segment
		(start 153.626566 -166.885874)
		(end 152.712674 -169.569384)
		(width 0.14224)
		(layer "In11.Cu")
		(net "P5E_CPU1_G1_TX_DP<5>")
	)
	(segment
		(start 105.52303 -222.26905)
		(end 105.483914 -222.29191)
		(width 0.1143)
		(layer "In11.Cu")
		(net "P5E_CPU1_G1_TX_DP<5>")
	)
	(segment
		(start 106.463084 -240.088928)
		(end 106.44505 -240.099596)
		(width 0.1143)
		(layer "In11.Cu")
		(net "P5E_CPU1_G1_TX_DP<5>")
	)
	(segment
		(start 106.423968 -233.63174)
		(end 106.392218 -233.650028)
		(width 0.1143)
		(layer "In11.Cu")
		(net "P5E_CPU1_G1_TX_DP<5>")
	)
	(segment
		(start 106.393234 -226.159314)
		(end 106.423968 -226.177094)
		(width 0.1143)
		(layer "In11.Cu")
		(net "P5E_CPU1_G1_TX_DP<5>")
	)
	(segment
		(start 105.955846 -225.368104)
		(end 105.95737 -225.36912)
		(width 0.1143)
		(layer "In11.Cu")
		(net "P5E_CPU1_G1_TX_DP<5>")
	)
	(segment
		(start 106.416094 -239.132364)
		(end 106.42854 -239.139476)
		(width 0.1143)
		(layer "In11.Cu")
		(net "P5E_CPU1_G1_TX_DP<5>")
	)
	(segment
		(start 105.922318 -225.3488)
		(end 105.954068 -225.367088)
		(width 0.1143)
		(layer "In11.Cu")
		(net "P5E_CPU1_G1_TX_DP<5>")
	)
	(segment
		(start 106.44505 -240.099596)
		(end 106.444796 -240.099596)
		(width 0.1143)
		(layer "In11.Cu")
		(net "P5E_CPU1_G1_TX_DP<5>")
	)
	(segment
		(start 106.463084 -238.468916)
		(end 106.44505 -238.479584)
		(width 0.1143)
		(layer "In11.Cu")
		(net "P5E_CPU1_G1_TX_DP<5>")
	)
	(segment
		(start 106.44505 -241.719608)
		(end 106.444796 -241.719608)
		(width 0.1143)
		(layer "In11.Cu")
		(net "P5E_CPU1_G1_TX_DP<5>")
	)
	(segment
		(start 106.455972 -235.915454)
		(end 106.462322 -235.919264)
		(width 0.1143)
		(layer "In11.Cu")
		(net "P5E_CPU1_G1_TX_DP<5>")
	)
	(segment
		(start 106.44505 -238.479584)
		(end 106.444796 -238.479584)
		(width 0.1143)
		(layer "In11.Cu")
		(net "P5E_CPU1_G1_TX_DP<5>")
	)
	(segment
		(start 106.416094 -242.372388)
		(end 106.42854 -242.3795)
		(width 0.1143)
		(layer "In11.Cu")
		(net "P5E_CPU1_G1_TX_DP<5>")
	)
	(segment
		(start 106.423206 -228.772466)
		(end 106.422698 -228.77272)
		(width 0.1143)
		(layer "In11.Cu")
		(net "P5E_CPU1_G1_TX_DP<5>")
	)
	(segment
		(start 106.421936 -230.39324)
		(end 106.420412 -230.394002)
		(width 0.1143)
		(layer "In11.Cu")
		(net "P5E_CPU1_G1_TX_DP<5>")
	)
	(segment
		(start 149.304502 -136.934448)
		(end 153.690066 -146.003264)
		(width 0.14224)
		(layer "In11.Cu")
		(net "P5E_CPU1_G1_TX_DP<5>")
	)
	(segment
		(start 106.42854 -239.139476)
		(end 106.429302 -239.139984)
		(width 0.1143)
		(layer "In11.Cu")
		(net "P5E_CPU1_G1_TX_DP<5>")
	)
	(segment
		(start 106.424984 -232.657396)
		(end 106.463084 -232.679748)
		(width 0.1143)
		(layer "In11.Cu")
		(net "P5E_CPU1_G1_TX_DP<5>")
	)
	(segment
		(start 105.483406 -222.936562)
		(end 105.484168 -222.93707)
		(width 0.1143)
		(layer "In11.Cu")
		(net "P5E_CPU1_G1_TX_DP<5>")
	)
	(segment
		(start 106.423968 -227.151946)
		(end 106.392218 -227.170234)
		(width 0.1143)
		(layer "In11.Cu")
		(net "P5E_CPU1_G1_TX_DP<5>")
	)
	(segment
		(start 106.423968 -228.771958)
		(end 106.423206 -228.772466)
		(width 0.1143)
		(layer "In11.Cu")
		(net "P5E_CPU1_G1_TX_DP<5>")
	)
	(segment
		(start 106.39044 -229.397306)
		(end 106.423968 -229.416864)
		(width 0.1143)
		(layer "In11.Cu")
		(net "P5E_CPU1_G1_TX_DP<5>")
	)
	(segment
		(start 105.792524 -221.05493)
		(end 105.792524 -221.083378)
		(width 0.1143)
		(layer "In11.Cu")
		(net "P5E_CPU1_G1_TX_DP<5>")
	)
	(segment
		(start 106.392218 -227.778818)
		(end 106.423968 -227.797106)
		(width 0.1143)
		(layer "In11.Cu")
		(net "P5E_CPU1_G1_TX_DP<5>")
	)
	(segment
		(start 106.413808 -231.031034)
		(end 106.463084 -231.059736)
		(width 0.1143)
		(layer "In11.Cu")
		(net "P5E_CPU1_G1_TX_DP<5>")
	)
	(segment
		(start 105.954068 -225.367088)
		(end 105.955846 -225.368104)
		(width 0.1143)
		(layer "In11.Cu")
		(net "P5E_CPU1_G1_TX_DP<5>")
	)
	(segment
		(start 106.423968 -229.416864)
		(end 106.463084 -229.439724)
		(width 0.1143)
		(layer "In11.Cu")
		(net "P5E_CPU1_G1_TX_DP<5>")
	)
	(segment
		(start 106.460544 -230.370634)
		(end 106.424984 -230.391462)
		(width 0.1143)
		(layer "In11.Cu")
		(net "P5E_CPU1_G1_TX_DP<5>")
	)
	(segment
		(start 106.423968 -230.39197)
		(end 106.423206 -230.392478)
		(width 0.1143)
		(layer "In11.Cu")
		(net "P5E_CPU1_G1_TX_DP<5>")
	)
	(segment
		(start 105.479596 -222.93453)
		(end 105.482136 -222.9358)
		(width 0.1143)
		(layer "In11.Cu")
		(net "P5E_CPU1_G1_TX_DP<5>")
	)
	(segment
		(start 110.697264 -206.653892)
		(end 105.792524 -214.915242)
		(width 0.14224)
		(layer "In11.Cu")
		(net "P5E_CPU1_G1_TX_DP<5>")
	)
	(segment
		(start 106.42854 -242.3795)
		(end 106.429302 -242.380008)
		(width 0.1143)
		(layer "In11.Cu")
		(net "P5E_CPU1_G1_TX_DP<5>")
	)
	(segment
		(start 106.463084 -227.129086)
		(end 106.46029 -227.131118)
		(width 0.1143)
		(layer "In11.Cu")
		(net "P5E_CPU1_G1_TX_DP<5>")
	)
	(segment
		(start 44.643294 -17.61236)
		(end 44.352464 -17.90319)
		(width 0.14224)
		(layer "In11.Cu")
		(net "P5E_CPU1_G1_TX_DP<5>")
	)
	(segment
		(start 105.486708 -222.938848)
		(end 105.523284 -222.959676)
		(width 0.1143)
		(layer "In11.Cu")
		(net "P5E_CPU1_G1_TX_DP<5>")
	)
	(segment
		(start 105.746804 -221.129098)
		(end 105.746804 -221.30512)
		(width 0.1143)
		(layer "In11.Cu")
		(net "P5E_CPU1_G1_TX_DP<5>")
	)
	(segment
		(start 105.523284 -222.959676)
		(end 105.634282 -223.039686)
		(width 0.1143)
		(layer "In11.Cu")
		(net "P5E_CPU1_G1_TX_DP<5>")
	)
	(segment
		(start 106.463084 -235.228892)
		(end 106.44505 -235.23956)
		(width 0.1143)
		(layer "In11.Cu")
		(net "P5E_CPU1_G1_TX_DP<5>")
	)
	(segment
		(start 152.321514 -170.604434)
		(end 148.935948 -175.317912)
		(width 0.14224)
		(layer "In11.Cu")
		(net "P5E_CPU1_G1_TX_DP<5>")
	)
	(segment
		(start 106.429302 -235.89996)
		(end 106.45521 -235.914946)
		(width 0.1143)
		(layer "In11.Cu")
		(net "P5E_CPU1_G1_TX_DP<5>")
	)
	(segment
		(start 106.423206 -230.392478)
		(end 106.421936 -230.39324)
		(width 0.1143)
		(layer "In11.Cu")
		(net "P5E_CPU1_G1_TX_DP<5>")
	)
	(segment
		(start 106.429302 -240.759996)
		(end 106.430318 -240.760504)
		(width 0.1143)
		(layer "In11.Cu")
		(net "P5E_CPU1_G1_TX_DP<5>")
	)
	(segment
		(start 106.444796 -238.479584)
		(end 106.42346 -238.49203)
		(width 0.1143)
		(layer "In11.Cu")
		(net "P5E_CPU1_G1_TX_DP<5>")
	)
	(segment
		(start 106.426508 -228.770434)
		(end 106.424984 -228.77145)
		(width 0.1143)
		(layer "In11.Cu")
		(net "P5E_CPU1_G1_TX_DP<5>")
	)
	(segment
		(start 106.423968 -243.996972)
		(end 106.463084 -244.019832)
		(width 0.1143)
		(layer "In11.Cu")
		(net "P5E_CPU1_G1_TX_DP<5>")
	)
	(segment
		(start 105.792524 -221.083378)
		(end 105.746804 -221.129098)
		(width 0.1143)
		(layer "In11.Cu")
		(net "P5E_CPU1_G1_TX_DP<5>")
	)
	(segment
		(start 106.463084 -233.60888)
		(end 106.423968 -233.63174)
		(width 0.1143)
		(layer "In11.Cu")
		(net "P5E_CPU1_G1_TX_DP<5>")
	)
	(segment
		(start 153.690066 -146.003264)
		(end 154.553666 -159.817562)
		(width 0.14224)
		(layer "In11.Cu")
		(net "P5E_CPU1_G1_TX_DP<5>")
	)
	(arc
		(start 106.462322 -239.159288)
		(mid 106.462703 -239.159542)
		(end 106.463084 -239.159796)
		(width 0.1143)
		(layer "In11.Cu")
		(net "P5E_CPU1_G1_TX_DP<5>")
	)
	(arc
		(start 105.99039 -225.38817)
		(mid 106.006359 -225.400207)
		(end 106.021886 -225.412808)
		(width 0.1143)
		(layer "In11.Cu")
		(net "P5E_CPU1_G1_TX_DP<5>")
	)
	(arc
		(start 106.463084 -229.439724)
		(mid 106.641897 -229.642074)
		(end 106.706416 -229.90429)
		(width 0.1143)
		(layer "In11.Cu")
		(net "P5E_CPU1_G1_TX_DP<5>")
	)
	(arc
		(start 106.706416 -229.90429)
		(mid 106.64118 -230.167881)
		(end 106.460544 -230.370634)
		(width 0.1143)
		(layer "In11.Cu")
		(net "P5E_CPU1_G1_TX_DP<5>")
	)
	(arc
		(start 105.766362 -221.804484)
		(mid 105.701847 -222.066703)
		(end 105.52303 -222.26905)
		(width 0.1143)
		(layer "In11.Cu")
		(net "P5E_CPU1_G1_TX_DP<5>")
	)
	(arc
		(start 106.392218 -232.030016)
		(mid 106.243121 -232.334308)
		(end 106.392218 -232.6386)
		(width 0.1143)
		(layer "In11.Cu")
		(net "P5E_CPU1_G1_TX_DP<5>")
	)
	(arc
		(start 106.462322 -237.539276)
		(mid 106.462703 -237.53953)
		(end 106.463084 -237.539784)
		(width 0.1143)
		(layer "In11.Cu")
		(net "P5E_CPU1_G1_TX_DP<5>")
	)
	(arc
		(start 106.463084 -232.679748)
		(mid 106.706411 -233.144314)
		(end 106.463084 -233.60888)
		(width 0.1143)
		(layer "In11.Cu")
		(net "P5E_CPU1_G1_TX_DP<5>")
	)
	(arc
		(start 106.463084 -239.159796)
		(mid 106.706411 -239.624362)
		(end 106.463084 -240.088928)
		(width 0.1143)
		(layer "In11.Cu")
		(net "P5E_CPU1_G1_TX_DP<5>")
	)
	(arc
		(start 106.236262 -230.71455)
		(mid 106.281942 -230.896961)
		(end 106.413808 -231.031034)
		(width 0.1143)
		(layer "In11.Cu")
		(net "P5E_CPU1_G1_TX_DP<5>")
	)
	(arc
		(start 106.462322 -242.399312)
		(mid 106.462703 -242.399566)
		(end 106.463084 -242.39982)
		(width 0.1143)
		(layer "In11.Cu")
		(net "P5E_CPU1_G1_TX_DP<5>")
	)
	(arc
		(start 106.463084 -235.919772)
		(mid 106.706411 -236.384338)
		(end 106.463084 -236.848904)
		(width 0.1143)
		(layer "In11.Cu")
		(net "P5E_CPU1_G1_TX_DP<5>")
	)
	(arc
		(start 106.42346 -240.112042)
		(mid 106.23794 -240.430099)
		(end 106.416094 -240.752376)
		(width 0.1143)
		(layer "In11.Cu")
		(net "P5E_CPU1_G1_TX_DP<5>")
	)
	(arc
		(start 106.69651 -244.378734)
		(mid 106.698533 -244.390144)
		(end 106.70032 -244.401594)
		(width 0.1143)
		(layer "In11.Cu")
		(net "P5E_CPU1_G1_TX_DP<5>")
	)
	(arc
		(start 106.021886 -225.412808)
		(mid 106.154304 -225.585989)
		(end 106.228388 -225.791014)
		(width 0.1143)
		(layer "In11.Cu")
		(net "P5E_CPU1_G1_TX_DP<5>")
	)
	(arc
		(start 106.228388 -225.791014)
		(mid 106.233867 -225.828189)
		(end 106.236262 -225.86569)
		(width 0.1143)
		(layer "In11.Cu")
		(net "P5E_CPU1_G1_TX_DP<5>")
	)
	(arc
		(start 106.42346 -235.252006)
		(mid 106.23794 -235.570063)
		(end 106.416094 -235.89234)
		(width 0.1143)
		(layer "In11.Cu")
		(net "P5E_CPU1_G1_TX_DP<5>")
	)
	(arc
		(start 106.42346 -238.49203)
		(mid 106.23794 -238.810087)
		(end 106.416094 -239.132364)
		(width 0.1143)
		(layer "In11.Cu")
		(net "P5E_CPU1_G1_TX_DP<5>")
	)
	(arc
		(start 106.392218 -230.410258)
		(mid 106.279198 -230.544434)
		(end 106.236262 -230.71455)
		(width 0.1143)
		(layer "In11.Cu")
		(net "P5E_CPU1_G1_TX_DP<5>")
	)
	(arc
		(start 106.463084 -231.059736)
		(mid 106.706411 -231.524302)
		(end 106.463084 -231.988868)
		(width 0.1143)
		(layer "In11.Cu")
		(net "P5E_CPU1_G1_TX_DP<5>")
	)
	(arc
		(start 105.453434 -223.929702)
		(mid 105.296457 -224.234502)
		(end 105.453434 -224.539302)
		(width 0.1143)
		(layer "In11.Cu")
		(net "P5E_CPU1_G1_TX_DP<5>")
	)
	(arc
		(start 106.463084 -226.199954)
		(mid 106.706411 -226.66452)
		(end 106.463084 -227.129086)
		(width 0.1143)
		(layer "In11.Cu")
		(net "P5E_CPU1_G1_TX_DP<5>")
	)
	(arc
		(start 106.463084 -244.019832)
		(mid 106.615071 -244.17634)
		(end 106.69651 -244.378734)
		(width 0.1143)
		(layer "In11.Cu")
		(net "P5E_CPU1_G1_TX_DP<5>")
	)
	(arc
		(start 106.422698 -228.77272)
		(mid 106.28628 -228.908593)
		(end 106.236262 -229.094538)
		(width 0.1143)
		(layer "In11.Cu")
		(net "P5E_CPU1_G1_TX_DP<5>")
	)
	(arc
		(start 105.52303 -224.579942)
		(mid 105.701843 -224.782292)
		(end 105.766362 -225.044508)
		(width 0.1143)
		(layer "In11.Cu")
		(net "P5E_CPU1_G1_TX_DP<5>")
	)
	(arc
		(start 106.42346 -241.732054)
		(mid 106.23794 -242.050111)
		(end 106.416094 -242.372388)
		(width 0.1143)
		(layer "In11.Cu")
		(net "P5E_CPU1_G1_TX_DP<5>")
	)
	(arc
		(start 106.463084 -227.819966)
		(mid 106.706411 -228.284532)
		(end 106.463084 -228.749098)
		(width 0.1143)
		(layer "In11.Cu")
		(net "P5E_CPU1_G1_TX_DP<5>")
	)
	(arc
		(start 105.296462 -222.61449)
		(mid 105.337717 -222.785461)
		(end 105.452418 -222.918782)
		(width 0.1143)
		(layer "In11.Cu")
		(net "P5E_CPU1_G1_TX_DP<5>")
	)
	(arc
		(start 106.463084 -240.779808)
		(mid 106.706411 -241.244374)
		(end 106.463084 -241.70894)
		(width 0.1143)
		(layer "In11.Cu")
		(net "P5E_CPU1_G1_TX_DP<5>")
	)
	(arc
		(start 106.236262 -229.094538)
		(mid 106.277024 -229.264422)
		(end 106.39044 -229.397306)
		(width 0.1143)
		(layer "In11.Cu")
		(net "P5E_CPU1_G1_TX_DP<5>")
	)
	(arc
		(start 106.463084 -234.29976)
		(mid 106.706411 -234.764326)
		(end 106.463084 -235.228892)
		(width 0.1143)
		(layer "In11.Cu")
		(net "P5E_CPU1_G1_TX_DP<5>")
	)
	(arc
		(start 106.462322 -240.7793)
		(mid 106.462703 -240.779554)
		(end 106.463084 -240.779808)
		(width 0.1143)
		(layer "In11.Cu")
		(net "P5E_CPU1_G1_TX_DP<5>")
	)
	(arc
		(start 106.392218 -233.650028)
		(mid 106.240629 -233.95432)
		(end 106.392218 -234.258612)
		(width 0.1143)
		(layer "In11.Cu")
		(net "P5E_CPU1_G1_TX_DP<5>")
	)
	(arc
		(start 105.766362 -225.044508)
		(mid 105.807617 -225.215479)
		(end 105.922318 -225.3488)
		(width 0.1143)
		(layer "In11.Cu")
		(net "P5E_CPU1_G1_TX_DP<5>")
	)
	(arc
		(start 106.392218 -243.3701)
		(mid 106.243121 -243.674392)
		(end 106.392218 -243.978684)
		(width 0.1143)
		(layer "In11.Cu")
		(net "P5E_CPU1_G1_TX_DP<5>")
	)
	(arc
		(start 106.236262 -225.86569)
		(mid 106.280326 -226.030913)
		(end 106.393234 -226.159314)
		(width 0.1143)
		(layer "In11.Cu")
		(net "P5E_CPU1_G1_TX_DP<5>")
	)
	(arc
		(start 106.462322 -235.919264)
		(mid 106.462703 -235.919518)
		(end 106.463084 -235.919772)
		(width 0.1143)
		(layer "In11.Cu")
		(net "P5E_CPU1_G1_TX_DP<5>")
	)
	(arc
		(start 106.463084 -237.539784)
		(mid 106.706411 -238.00435)
		(end 106.463084 -238.468916)
		(width 0.1143)
		(layer "In11.Cu")
		(net "P5E_CPU1_G1_TX_DP<5>")
	)
	(arc
		(start 106.463084 -242.39982)
		(mid 106.706411 -242.864386)
		(end 106.463084 -243.328952)
		(width 0.1143)
		(layer "In11.Cu")
		(net "P5E_CPU1_G1_TX_DP<5>")
	)
	(arc
		(start 105.453434 -222.30969)
		(mid 105.338007 -222.443066)
		(end 105.296462 -222.61449)
		(width 0.1143)
		(layer "In11.Cu")
		(net "P5E_CPU1_G1_TX_DP<5>")
	)
	(arc
		(start 106.392218 -227.170234)
		(mid 106.243121 -227.474526)
		(end 106.392218 -227.778818)
		(width 0.1143)
		(layer "In11.Cu")
		(net "P5E_CPU1_G1_TX_DP<5>")
	)
	(arc
		(start 106.462322 -234.299252)
		(mid 106.462703 -234.299506)
		(end 106.463084 -234.29976)
		(width 0.1143)
		(layer "In11.Cu")
		(net "P5E_CPU1_G1_TX_DP<5>")
	)
	(arc
		(start 105.634282 -223.039686)
		(mid 105.831479 -223.424496)
		(end 105.634282 -223.809306)
		(width 0.1143)
		(layer "In11.Cu")
		(net "P5E_CPU1_G1_TX_DP<5>")
	)
	(arc
		(start 106.42346 -236.872018)
		(mid 106.23794 -237.190075)
		(end 106.416094 -237.512352)
		(width 0.1143)
		(layer "In11.Cu")
		(net "P5E_CPU1_G1_TX_DP<5>")
	)
	(segment
		(start 47.166784 -18.186146)
		(end 47.166784 -18.867628)
		(width 0.12954)
		(layer "F.Cu")
		(net "P5E_CPU1_G1_TX_DP<4>")
	)
	(segment
		(start 107.547918 -247.99036)
		(end 107.081066 -247.724422)
		(width 0.12954)
		(layer "F.Cu")
		(net "P5E_CPU1_G1_TX_DP<4>")
	)
	(segment
		(start 47.462694 -17.890236)
		(end 47.166784 -18.186146)
		(width 0.12954)
		(layer "F.Cu")
		(net "P5E_CPU1_G1_TX_DP<4>")
	)
	(segment
		(start 47.166784 -18.867628)
		(end 47.436278 -19.137122)
		(width 0.12954)
		(layer "F.Cu")
		(net "P5E_CPU1_G1_TX_DP<4>")
	)
	(segment
		(start 107.364022 -234.2769)
		(end 107.365038 -234.277408)
		(width 0.1143)
		(layer "In11.Cu")
		(net "P5E_CPU1_G1_TX_DP<4>")
	)
	(segment
		(start 107.365038 -237.517432)
		(end 107.403138 -237.539784)
		(width 0.1143)
		(layer "In11.Cu")
		(net "P5E_CPU1_G1_TX_DP<4>")
	)
	(segment
		(start 150.054818 -136.342628)
		(end 154.620214 -145.782538)
		(width 0.14224)
		(layer "In11.Cu")
		(net "P5E_CPU1_G1_TX_DP<4>")
	)
	(segment
		(start 107.36326 -244.972332)
		(end 107.36199 -244.973094)
		(width 0.1143)
		(layer "In11.Cu")
		(net "P5E_CPU1_G1_TX_DP<4>")
	)
	(segment
		(start 107.366562 -241.730276)
		(end 107.365038 -241.731292)
		(width 0.1143)
		(layer "In11.Cu")
		(net "P5E_CPU1_G1_TX_DP<4>")
	)
	(segment
		(start 107.364022 -233.63174)
		(end 107.36326 -233.632248)
		(width 0.1143)
		(layer "In11.Cu")
		(net "P5E_CPU1_G1_TX_DP<4>")
	)
	(segment
		(start 107.37215 -234.281726)
		(end 107.373166 -234.282234)
		(width 0.1143)
		(layer "In11.Cu")
		(net "P5E_CPU1_G1_TX_DP<4>")
	)
	(segment
		(start 107.370626 -234.28071)
		(end 107.37215 -234.281726)
		(width 0.1143)
		(layer "In11.Cu")
		(net "P5E_CPU1_G1_TX_DP<4>")
	)
	(segment
		(start 107.36326 -240.75644)
		(end 107.364022 -240.756948)
		(width 0.1143)
		(layer "In11.Cu")
		(net "P5E_CPU1_G1_TX_DP<4>")
	)
	(segment
		(start 155.495244 -159.787844)
		(end 155.495244 -164.33038)
		(width 0.14224)
		(layer "In11.Cu")
		(net "P5E_CPU1_G1_TX_DP<4>")
	)
	(segment
		(start 107.366562 -235.898436)
		(end 107.370626 -235.900722)
		(width 0.1143)
		(layer "In11.Cu")
		(net "P5E_CPU1_G1_TX_DP<4>")
	)
	(segment
		(start 107.364022 -246.591836)
		(end 107.36326 -246.592344)
		(width 0.1143)
		(layer "In11.Cu")
		(net "P5E_CPU1_G1_TX_DP<4>")
	)
	(segment
		(start 107.332272 -245.598696)
		(end 107.36199 -245.615714)
		(width 0.1143)
		(layer "In11.Cu")
		(net "P5E_CPU1_G1_TX_DP<4>")
	)
	(segment
		(start 107.35691 -234.272836)
		(end 107.357926 -234.273344)
		(width 0.1143)
		(layer "In11.Cu")
		(net "P5E_CPU1_G1_TX_DP<4>")
	)
	(segment
		(start 106.737912 -221.05493)
		(end 106.737912 -221.083378)
		(width 0.1143)
		(layer "In11.Cu")
		(net "P5E_CPU1_G1_TX_DP<4>")
	)
	(segment
		(start 107.403138 -238.468916)
		(end 107.366562 -238.490252)
		(width 0.1143)
		(layer "In11.Cu")
		(net "P5E_CPU1_G1_TX_DP<4>")
	)
	(segment
		(start 107.364022 -231.036876)
		(end 107.403138 -231.059736)
		(width 0.1143)
		(layer "In11.Cu")
		(net "P5E_CPU1_G1_TX_DP<4>")
	)
	(segment
		(start 57.39384 -53.024278)
		(end 150.054818 -136.342628)
		(width 0.14224)
		(layer "In11.Cu")
		(net "P5E_CPU1_G1_TX_DP<4>")
	)
	(segment
		(start 107.403138 -228.749098)
		(end 107.400344 -228.75113)
		(width 0.1143)
		(layer "In11.Cu")
		(net "P5E_CPU1_G1_TX_DP<4>")
	)
	(segment
		(start 107.370626 -240.760758)
		(end 107.37215 -240.761774)
		(width 0.1143)
		(layer "In11.Cu")
		(net "P5E_CPU1_G1_TX_DP<4>")
	)
	(segment
		(start 107.357926 -235.893356)
		(end 107.35945 -235.894372)
		(width 0.1143)
		(layer "In11.Cu")
		(net "P5E_CPU1_G1_TX_DP<4>")
	)
	(segment
		(start 106.423968 -222.29191)
		(end 106.392218 -222.310198)
		(width 0.1143)
		(layer "In11.Cu")
		(net "P5E_CPU1_G1_TX_DP<4>")
	)
	(segment
		(start 107.403138 -236.848904)
		(end 107.366562 -236.87024)
		(width 0.1143)
		(layer "In11.Cu")
		(net "P5E_CPU1_G1_TX_DP<4>")
	)
	(segment
		(start 106.393488 -224.539302)
		(end 106.423968 -224.557082)
		(width 0.1143)
		(layer "In11.Cu")
		(net "P5E_CPU1_G1_TX_DP<4>")
	)
	(segment
		(start 107.35691 -235.892848)
		(end 107.357926 -235.893356)
		(width 0.1143)
		(layer "In11.Cu")
		(net "P5E_CPU1_G1_TX_DP<4>")
	)
	(segment
		(start 107.364022 -237.516924)
		(end 107.365038 -237.517432)
		(width 0.1143)
		(layer "In11.Cu")
		(net "P5E_CPU1_G1_TX_DP<4>")
	)
	(segment
		(start 107.36199 -240.755678)
		(end 107.36326 -240.75644)
		(width 0.1143)
		(layer "In11.Cu")
		(net "P5E_CPU1_G1_TX_DP<4>")
	)
	(segment
		(start 107.364022 -240.111788)
		(end 107.36326 -240.112296)
		(width 0.1143)
		(layer "In11.Cu")
		(net "P5E_CPU1_G1_TX_DP<4>")
	)
	(segment
		(start 107.364022 -228.771958)
		(end 107.332272 -228.790246)
		(width 0.1143)
		(layer "In11.Cu")
		(net "P5E_CPU1_G1_TX_DP<4>")
	)
	(segment
		(start 107.403138 -244.948964)
		(end 107.366562 -244.9703)
		(width 0.1143)
		(layer "In11.Cu")
		(net "P5E_CPU1_G1_TX_DP<4>")
	)
	(segment
		(start 107.37215 -240.761774)
		(end 107.373166 -240.762282)
		(width 0.1143)
		(layer "In11.Cu")
		(net "P5E_CPU1_G1_TX_DP<4>")
	)
	(segment
		(start 107.36199 -237.515654)
		(end 107.36326 -237.516416)
		(width 0.1143)
		(layer "In11.Cu")
		(net "P5E_CPU1_G1_TX_DP<4>")
	)
	(segment
		(start 107.364022 -244.971824)
		(end 107.36326 -244.972332)
		(width 0.1143)
		(layer "In11.Cu")
		(net "P5E_CPU1_G1_TX_DP<4>")
	)
	(segment
		(start 107.360466 -233.633772)
		(end 107.332272 -233.650028)
		(width 0.1143)
		(layer "In11.Cu")
		(net "P5E_CPU1_G1_TX_DP<4>")
	)
	(segment
		(start 106.692192 -221.30512)
		(end 106.706416 -221.700598)
		(width 0.1143)
		(layer "In11.Cu")
		(net "P5E_CPU1_G1_TX_DP<4>")
	)
	(segment
		(start 107.36326 -239.136428)
		(end 107.364022 -239.136936)
		(width 0.1143)
		(layer "In11.Cu")
		(net "P5E_CPU1_G1_TX_DP<4>")
	)
	(segment
		(start 154.620214 -145.782538)
		(end 155.495244 -159.787844)
		(width 0.14224)
		(layer "In11.Cu")
		(net "P5E_CPU1_G1_TX_DP<4>")
	)
	(segment
		(start 107.364022 -232.011728)
		(end 107.36326 -232.012236)
		(width 0.1143)
		(layer "In11.Cu")
		(net "P5E_CPU1_G1_TX_DP<4>")
	)
	(segment
		(start 107.36326 -232.65638)
		(end 107.364022 -232.656888)
		(width 0.1143)
		(layer "In11.Cu")
		(net "P5E_CPU1_G1_TX_DP<4>")
	)
	(segment
		(start 107.37215 -244.001798)
		(end 107.373166 -244.002306)
		(width 0.1143)
		(layer "In11.Cu")
		(net "P5E_CPU1_G1_TX_DP<4>")
	)
	(segment
		(start 107.360466 -241.733832)
		(end 107.332272 -241.750088)
		(width 0.1143)
		(layer "In11.Cu")
		(net "P5E_CPU1_G1_TX_DP<4>")
	)
	(segment
		(start 149.833838 -175.787812)
		(end 130.6322 -191.523366)
		(width 0.14224)
		(layer "In11.Cu")
		(net "P5E_CPU1_G1_TX_DP<4>")
	)
	(segment
		(start 107.364022 -226.177094)
		(end 107.403138 -226.199954)
		(width 0.1143)
		(layer "In11.Cu")
		(net "P5E_CPU1_G1_TX_DP<4>")
	)
	(segment
		(start 107.35945 -235.894372)
		(end 107.36199 -235.895642)
		(width 0.1143)
		(layer "In11.Cu")
		(net "P5E_CPU1_G1_TX_DP<4>")
	)
	(segment
		(start 107.35945 -239.134396)
		(end 107.36199 -239.135666)
		(width 0.1143)
		(layer "In11.Cu")
		(net "P5E_CPU1_G1_TX_DP<4>")
	)
	(segment
		(start 107.360466 -232.01376)
		(end 107.332272 -232.030016)
		(width 0.1143)
		(layer "In11.Cu")
		(net "P5E_CPU1_G1_TX_DP<4>")
	)
	(segment
		(start 107.365038 -242.377468)
		(end 107.403138 -242.39982)
		(width 0.1143)
		(layer "In11.Cu")
		(net "P5E_CPU1_G1_TX_DP<4>")
	)
	(segment
		(start 106.893868 -247.401842)
		(end 106.863388 -247.419622)
		(width 0.1143)
		(layer "In11.Cu")
		(net "P5E_CPU1_G1_TX_DP<4>")
	)
	(segment
		(start 107.370626 -232.660698)
		(end 107.37215 -232.661714)
		(width 0.1143)
		(layer "In11.Cu")
		(net "P5E_CPU1_G1_TX_DP<4>")
	)
	(segment
		(start 107.360466 -243.353844)
		(end 107.332272 -243.3701)
		(width 0.1143)
		(layer "In11.Cu")
		(net "P5E_CPU1_G1_TX_DP<4>")
	)
	(segment
		(start 106.783124 -247.724422)
		(end 107.081066 -247.724422)
		(width 0.1143)
		(layer "In11.Cu")
		(net "P5E_CPU1_G1_TX_DP<4>")
	)
	(segment
		(start 130.6322 -191.52362)
		(end 111.430562 -207.25892)
		(width 0.14224)
		(layer "In11.Cu")
		(net "P5E_CPU1_G1_TX_DP<4>")
	)
	(segment
		(start 107.36326 -242.376452)
		(end 107.364022 -242.37696)
		(width 0.1143)
		(layer "In11.Cu")
		(net "P5E_CPU1_G1_TX_DP<4>")
	)
	(segment
		(start 107.357926 -240.753392)
		(end 107.35945 -240.754408)
		(width 0.1143)
		(layer "In11.Cu")
		(net "P5E_CPU1_G1_TX_DP<4>")
	)
	(segment
		(start 107.403138 -240.088928)
		(end 107.366562 -240.110264)
		(width 0.1143)
		(layer "In11.Cu")
		(net "P5E_CPU1_G1_TX_DP<4>")
	)
	(segment
		(start 107.35945 -234.27436)
		(end 107.36199 -234.27563)
		(width 0.1143)
		(layer "In11.Cu")
		(net "P5E_CPU1_G1_TX_DP<4>")
	)
	(segment
		(start 107.364022 -235.896912)
		(end 107.365038 -235.89742)
		(width 0.1143)
		(layer "In11.Cu")
		(net "P5E_CPU1_G1_TX_DP<4>")
	)
	(segment
		(start 107.36199 -239.135666)
		(end 107.36326 -239.136428)
		(width 0.1143)
		(layer "In11.Cu")
		(net "P5E_CPU1_G1_TX_DP<4>")
	)
	(segment
		(start 107.366562 -243.998496)
		(end 107.370626 -244.000782)
		(width 0.1143)
		(layer "In11.Cu")
		(net "P5E_CPU1_G1_TX_DP<4>")
	)
	(segment
		(start 107.36199 -240.113058)
		(end 107.360466 -240.11382)
		(width 0.1143)
		(layer "In11.Cu")
		(net "P5E_CPU1_G1_TX_DP<4>")
	)
	(segment
		(start 107.365038 -244.971316)
		(end 107.364022 -244.971824)
		(width 0.1143)
		(layer "In11.Cu")
		(net "P5E_CPU1_G1_TX_DP<4>")
	)
	(segment
		(start 107.373166 -239.14227)
		(end 107.403138 -239.159796)
		(width 0.1143)
		(layer "In11.Cu")
		(net "P5E_CPU1_G1_TX_DP<4>")
	)
	(segment
		(start 107.403138 -241.70894)
		(end 107.366562 -241.730276)
		(width 0.1143)
		(layer "In11.Cu")
		(net "P5E_CPU1_G1_TX_DP<4>")
	)
	(segment
		(start 54.64937 -48.534066)
		(end 57.39384 -53.024278)
		(width 0.14224)
		(layer "In11.Cu")
		(net "P5E_CPU1_G1_TX_DP<4>")
	)
	(segment
		(start 107.373166 -235.902246)
		(end 107.403138 -235.919772)
		(width 0.1143)
		(layer "In11.Cu")
		(net "P5E_CPU1_G1_TX_DP<4>")
	)
	(segment
		(start 106.706416 -221.700598)
		(end 106.706416 -221.804484)
		(width 0.1143)
		(layer "In11.Cu")
		(net "P5E_CPU1_G1_TX_DP<4>")
	)
	(segment
		(start 107.403138 -243.328952)
		(end 107.366562 -243.350288)
		(width 0.1143)
		(layer "In11.Cu")
		(net "P5E_CPU1_G1_TX_DP<4>")
	)
	(segment
		(start 107.366562 -232.010204)
		(end 107.365038 -232.01122)
		(width 0.1143)
		(layer "In11.Cu")
		(net "P5E_CPU1_G1_TX_DP<4>")
	)
	(segment
		(start 107.364022 -243.996972)
		(end 107.365038 -243.99748)
		(width 0.1143)
		(layer "In11.Cu")
		(net "P5E_CPU1_G1_TX_DP<4>")
	)
	(segment
		(start 107.366562 -244.9703)
		(end 107.365038 -244.971316)
		(width 0.1143)
		(layer "In11.Cu")
		(net "P5E_CPU1_G1_TX_DP<4>")
	)
	(segment
		(start 107.365038 -239.137444)
		(end 107.366562 -239.13846)
		(width 0.1143)
		(layer "In11.Cu")
		(net "P5E_CPU1_G1_TX_DP<4>")
	)
	(segment
		(start 107.36326 -240.112296)
		(end 107.36199 -240.113058)
		(width 0.1143)
		(layer "In11.Cu")
		(net "P5E_CPU1_G1_TX_DP<4>")
	)
	(segment
		(start 107.646216 -229.90429)
		(end 107.64647 -229.90429)
		(width 0.1143)
		(layer "In11.Cu")
		(net "P5E_CPU1_G1_TX_DP<4>")
	)
	(segment
		(start 47.145448 -20.192746)
		(end 54.64937 -48.534066)
		(width 0.14224)
		(layer "In11.Cu")
		(net "P5E_CPU1_G1_TX_DP<4>")
	)
	(segment
		(start 155.495244 -164.33038)
		(end 153.20518 -171.045632)
		(width 0.14224)
		(layer "In11.Cu")
		(net "P5E_CPU1_G1_TX_DP<4>")
	)
	(segment
		(start 107.36326 -235.896404)
		(end 107.364022 -235.896912)
		(width 0.1143)
		(layer "In11.Cu")
		(net "P5E_CPU1_G1_TX_DP<4>")
	)
	(segment
		(start 106.737912 -215.161876)
		(end 106.737912 -221.05493)
		(width 0.14224)
		(layer "In11.Cu")
		(net "P5E_CPU1_G1_TX_DP<4>")
	)
	(segment
		(start 106.46283 -222.269558)
		(end 106.463084 -222.26905)
		(width 0.1143)
		(layer "In11.Cu")
		(net "P5E_CPU1_G1_TX_DP<4>")
	)
	(segment
		(start 106.423968 -222.93707)
		(end 106.463084 -222.95993)
		(width 0.1143)
		(layer "In11.Cu")
		(net "P5E_CPU1_G1_TX_DP<4>")
	)
	(segment
		(start 107.36326 -236.872272)
		(end 107.36199 -236.873034)
		(width 0.1143)
		(layer "In11.Cu")
		(net "P5E_CPU1_G1_TX_DP<4>")
	)
	(segment
		(start 107.364022 -227.151946)
		(end 107.333542 -227.169726)
		(width 0.1143)
		(layer "In11.Cu")
		(net "P5E_CPU1_G1_TX_DP<4>")
	)
	(segment
		(start 106.89209 -225.365818)
		(end 106.89336 -225.36658)
		(width 0.1143)
		(layer "In11.Cu")
		(net "P5E_CPU1_G1_TX_DP<4>")
	)
	(segment
		(start 107.332272 -232.6386)
		(end 107.35691 -232.652824)
		(width 0.1143)
		(layer "In11.Cu")
		(net "P5E_CPU1_G1_TX_DP<4>")
	)
	(segment
		(start 106.423968 -223.911922)
		(end 106.393488 -223.929702)
		(width 0.1143)
		(layer "In11.Cu")
		(net "P5E_CPU1_G1_TX_DP<4>")
	)
	(segment
		(start 107.332272 -237.498636)
		(end 107.36199 -237.515654)
		(width 0.1143)
		(layer "In11.Cu")
		(net "P5E_CPU1_G1_TX_DP<4>")
	)
	(segment
		(start 107.365038 -236.871256)
		(end 107.364022 -236.871764)
		(width 0.1143)
		(layer "In11.Cu")
		(net "P5E_CPU1_G1_TX_DP<4>")
	)
	(segment
		(start 107.330494 -229.397306)
		(end 107.364022 -229.416864)
		(width 0.1143)
		(layer "In11.Cu")
		(net "P5E_CPU1_G1_TX_DP<4>")
	)
	(segment
		(start 107.36199 -233.63301)
		(end 107.360466 -233.633772)
		(width 0.1143)
		(layer "In11.Cu")
		(net "P5E_CPU1_G1_TX_DP<4>")
	)
	(segment
		(start 107.403138 -233.60888)
		(end 107.366562 -233.630216)
		(width 0.1143)
		(layer "In11.Cu")
		(net "P5E_CPU1_G1_TX_DP<4>")
	)
	(segment
		(start 107.373166 -244.002306)
		(end 107.403138 -244.019832)
		(width 0.1143)
		(layer "In11.Cu")
		(net "P5E_CPU1_G1_TX_DP<4>")
	)
	(segment
		(start 107.37215 -235.901738)
		(end 107.373166 -235.902246)
		(width 0.1143)
		(layer "In11.Cu")
		(net "P5E_CPU1_G1_TX_DP<4>")
	)
	(segment
		(start 107.330494 -231.017318)
		(end 107.364022 -231.036876)
		(width 0.1143)
		(layer "In11.Cu")
		(net "P5E_CPU1_G1_TX_DP<4>")
	)
	(segment
		(start 107.366562 -234.278424)
		(end 107.370626 -234.28071)
		(width 0.1143)
		(layer "In11.Cu")
		(net "P5E_CPU1_G1_TX_DP<4>")
	)
	(segment
		(start 153.20518 -171.045632)
		(end 149.833838 -175.787812)
		(width 0.14224)
		(layer "In11.Cu")
		(net "P5E_CPU1_G1_TX_DP<4>")
	)
	(segment
		(start 107.364022 -230.39197)
		(end 107.332272 -230.410258)
		(width 0.1143)
		(layer "In11.Cu")
		(net "P5E_CPU1_G1_TX_DP<4>")
	)
	(segment
		(start 106.713274 -247.654572)
		(end 106.783124 -247.724422)
		(width 0.1143)
		(layer "In11.Cu")
		(net "P5E_CPU1_G1_TX_DP<4>")
	)
	(segment
		(start 107.36326 -243.35232)
		(end 107.36199 -243.353082)
		(width 0.1143)
		(layer "In11.Cu")
		(net "P5E_CPU1_G1_TX_DP<4>")
	)
	(segment
		(start 107.364022 -240.756948)
		(end 107.365038 -240.757456)
		(width 0.1143)
		(layer "In11.Cu")
		(net "P5E_CPU1_G1_TX_DP<4>")
	)
	(segment
		(start 107.366562 -240.110264)
		(end 107.365038 -240.11128)
		(width 0.1143)
		(layer "In11.Cu")
		(net "P5E_CPU1_G1_TX_DP<4>")
	)
	(segment
		(start 107.366562 -232.658412)
		(end 107.370626 -232.660698)
		(width 0.1143)
		(layer "In11.Cu")
		(net "P5E_CPU1_G1_TX_DP<4>")
	)
	(segment
		(start 106.862372 -225.3488)
		(end 106.89209 -225.365818)
		(width 0.1143)
		(layer "In11.Cu")
		(net "P5E_CPU1_G1_TX_DP<4>")
	)
	(segment
		(start 107.36199 -245.615714)
		(end 107.36326 -245.616476)
		(width 0.1143)
		(layer "In11.Cu")
		(net "P5E_CPU1_G1_TX_DP<4>")
	)
	(segment
		(start 107.366562 -233.630216)
		(end 107.365038 -233.631232)
		(width 0.1143)
		(layer "In11.Cu")
		(net "P5E_CPU1_G1_TX_DP<4>")
	)
	(segment
		(start 107.36199 -234.27563)
		(end 107.36326 -234.276392)
		(width 0.1143)
		(layer "In11.Cu")
		(net "P5E_CPU1_G1_TX_DP<4>")
	)
	(segment
		(start 106.463084 -222.26905)
		(end 106.426508 -222.290386)
		(width 0.1143)
		(layer "In11.Cu")
		(net "P5E_CPU1_G1_TX_DP<4>")
	)
	(segment
		(start 106.692192 -221.129098)
		(end 106.692192 -221.30512)
		(width 0.1143)
		(layer "In11.Cu")
		(net "P5E_CPU1_G1_TX_DP<4>")
	)
	(segment
		(start 107.364022 -239.136936)
		(end 107.365038 -239.137444)
		(width 0.1143)
		(layer "In11.Cu")
		(net "P5E_CPU1_G1_TX_DP<4>")
	)
	(segment
		(start 107.357926 -243.993416)
		(end 107.35945 -243.994432)
		(width 0.1143)
		(layer "In11.Cu")
		(net "P5E_CPU1_G1_TX_DP<4>")
	)
	(segment
		(start 106.737912 -221.083378)
		(end 106.692192 -221.129098)
		(width 0.1143)
		(layer "In11.Cu")
		(net "P5E_CPU1_G1_TX_DP<4>")
	)
	(segment
		(start 107.35691 -240.752884)
		(end 107.357926 -240.753392)
		(width 0.1143)
		(layer "In11.Cu")
		(net "P5E_CPU1_G1_TX_DP<4>")
	)
	(segment
		(start 107.403138 -227.129086)
		(end 107.364022 -227.151946)
		(width 0.1143)
		(layer "In11.Cu")
		(net "P5E_CPU1_G1_TX_DP<4>")
	)
	(segment
		(start 106.932984 -247.378982)
		(end 106.893868 -247.401842)
		(width 0.1143)
		(layer "In11.Cu")
		(net "P5E_CPU1_G1_TX_DP<4>")
	)
	(segment
		(start 107.332272 -240.73866)
		(end 107.35691 -240.752884)
		(width 0.1143)
		(layer "In11.Cu")
		(net "P5E_CPU1_G1_TX_DP<4>")
	)
	(segment
		(start 106.894122 -225.367088)
		(end 106.925618 -225.385376)
		(width 0.1143)
		(layer "In11.Cu")
		(net "P5E_CPU1_G1_TX_DP<4>")
	)
	(segment
		(start 107.332272 -242.358672)
		(end 107.36199 -242.37569)
		(width 0.1143)
		(layer "In11.Cu")
		(net "P5E_CPU1_G1_TX_DP<4>")
	)
	(segment
		(start 107.370626 -235.900722)
		(end 107.37215 -235.901738)
		(width 0.1143)
		(layer "In11.Cu")
		(net "P5E_CPU1_G1_TX_DP<4>")
	)
	(segment
		(start 107.366562 -240.758472)
		(end 107.370626 -240.760758)
		(width 0.1143)
		(layer "In11.Cu")
		(net "P5E_CPU1_G1_TX_DP<4>")
	)
	(segment
		(start 107.36199 -246.593106)
		(end 107.360466 -246.593868)
		(width 0.1143)
		(layer "In11.Cu")
		(net "P5E_CPU1_G1_TX_DP<4>")
	)
	(segment
		(start 107.332272 -234.258612)
		(end 107.35691 -234.272836)
		(width 0.1143)
		(layer "In11.Cu")
		(net "P5E_CPU1_G1_TX_DP<4>")
	)
	(segment
		(start 106.89336 -225.36658)
		(end 106.894122 -225.367088)
		(width 0.1143)
		(layer "In11.Cu")
		(net "P5E_CPU1_G1_TX_DP<4>")
	)
	(segment
		(start 107.357926 -232.653332)
		(end 107.35945 -232.654348)
		(width 0.1143)
		(layer "In11.Cu")
		(net "P5E_CPU1_G1_TX_DP<4>")
	)
	(segment
		(start 107.403138 -231.988868)
		(end 107.366562 -232.010204)
		(width 0.1143)
		(layer "In11.Cu")
		(net "P5E_CPU1_G1_TX_DP<4>")
	)
	(segment
		(start 107.364022 -232.656888)
		(end 107.365038 -232.657396)
		(width 0.1143)
		(layer "In11.Cu")
		(net "P5E_CPU1_G1_TX_DP<4>")
	)
	(segment
		(start 107.365038 -235.251244)
		(end 107.364022 -235.251752)
		(width 0.1143)
		(layer "In11.Cu")
		(net "P5E_CPU1_G1_TX_DP<4>")
	)
	(segment
		(start 107.365038 -243.99748)
		(end 107.366562 -243.998496)
		(width 0.1143)
		(layer "In11.Cu")
		(net "P5E_CPU1_G1_TX_DP<4>")
	)
	(segment
		(start 107.364022 -235.251752)
		(end 107.36326 -235.25226)
		(width 0.1143)
		(layer "In11.Cu")
		(net "P5E_CPU1_G1_TX_DP<4>")
	)
	(segment
		(start 107.365038 -240.11128)
		(end 107.364022 -240.111788)
		(width 0.1143)
		(layer "In11.Cu")
		(net "P5E_CPU1_G1_TX_DP<4>")
	)
	(segment
		(start 107.36326 -232.012236)
		(end 107.36199 -232.012998)
		(width 0.1143)
		(layer "In11.Cu")
		(net "P5E_CPU1_G1_TX_DP<4>")
	)
	(segment
		(start 107.333542 -226.159314)
		(end 107.364022 -226.177094)
		(width 0.1143)
		(layer "In11.Cu")
		(net "P5E_CPU1_G1_TX_DP<4>")
	)
	(segment
		(start 107.35691 -232.652824)
		(end 107.357926 -232.653332)
		(width 0.1143)
		(layer "In11.Cu")
		(net "P5E_CPU1_G1_TX_DP<4>")
	)
	(segment
		(start 107.370626 -244.000782)
		(end 107.37215 -244.001798)
		(width 0.1143)
		(layer "In11.Cu")
		(net "P5E_CPU1_G1_TX_DP<4>")
	)
	(segment
		(start 107.364022 -243.351812)
		(end 107.36326 -243.35232)
		(width 0.1143)
		(layer "In11.Cu")
		(net "P5E_CPU1_G1_TX_DP<4>")
	)
	(segment
		(start 107.366562 -238.490252)
		(end 107.365038 -238.491268)
		(width 0.1143)
		(layer "In11.Cu")
		(net "P5E_CPU1_G1_TX_DP<4>")
	)
	(segment
		(start 107.364022 -241.7318)
		(end 107.36326 -241.732308)
		(width 0.1143)
		(layer "In11.Cu")
		(net "P5E_CPU1_G1_TX_DP<4>")
	)
	(segment
		(start 107.360466 -235.253784)
		(end 107.332272 -235.27004)
		(width 0.1143)
		(layer "In11.Cu")
		(net "P5E_CPU1_G1_TX_DP<4>")
	)
	(segment
		(start 130.6322 -191.523366)
		(end 130.6322 -191.52362)
		(width 0.14224)
		(layer "In11.Cu")
		(net "P5E_CPU1_G1_TX_DP<4>")
	)
	(segment
		(start 107.333542 -227.779326)
		(end 107.364022 -227.797106)
		(width 0.1143)
		(layer "In11.Cu")
		(net "P5E_CPU1_G1_TX_DP<4>")
	)
	(segment
		(start 107.36199 -241.73307)
		(end 107.360466 -241.733832)
		(width 0.1143)
		(layer "In11.Cu")
		(net "P5E_CPU1_G1_TX_DP<4>")
	)
	(segment
		(start 107.365038 -245.617492)
		(end 107.403138 -245.639844)
		(width 0.1143)
		(layer "In11.Cu")
		(net "P5E_CPU1_G1_TX_DP<4>")
	)
	(segment
		(start 107.36326 -235.25226)
		(end 107.36199 -235.253022)
		(width 0.1143)
		(layer "In11.Cu")
		(net "P5E_CPU1_G1_TX_DP<4>")
	)
	(segment
		(start 107.37215 -232.661714)
		(end 107.373166 -232.662222)
		(width 0.1143)
		(layer "In11.Cu")
		(net "P5E_CPU1_G1_TX_DP<4>")
	)
	(segment
		(start 107.373166 -240.762282)
		(end 107.403138 -240.779808)
		(width 0.1143)
		(layer "In11.Cu")
		(net "P5E_CPU1_G1_TX_DP<4>")
	)
	(segment
		(start 107.35945 -240.754408)
		(end 107.36199 -240.755678)
		(width 0.1143)
		(layer "In11.Cu")
		(net "P5E_CPU1_G1_TX_DP<4>")
	)
	(segment
		(start 107.357926 -234.273344)
		(end 107.35945 -234.27436)
		(width 0.1143)
		(layer "In11.Cu")
		(net "P5E_CPU1_G1_TX_DP<4>")
	)
	(segment
		(start 107.365038 -241.731292)
		(end 107.364022 -241.7318)
		(width 0.1143)
		(layer "In11.Cu")
		(net "P5E_CPU1_G1_TX_DP<4>")
	)
	(segment
		(start 107.36199 -243.995702)
		(end 107.36326 -243.996464)
		(width 0.1143)
		(layer "In11.Cu")
		(net "P5E_CPU1_G1_TX_DP<4>")
	)
	(segment
		(start 107.364022 -227.797106)
		(end 107.403138 -227.819966)
		(width 0.1143)
		(layer "In11.Cu")
		(net "P5E_CPU1_G1_TX_DP<4>")
	)
	(segment
		(start 107.366562 -236.87024)
		(end 107.365038 -236.871256)
		(width 0.1143)
		(layer "In11.Cu")
		(net "P5E_CPU1_G1_TX_DP<4>")
	)
	(segment
		(start 107.373166 -232.662222)
		(end 107.403138 -232.679748)
		(width 0.1143)
		(layer "In11.Cu")
		(net "P5E_CPU1_G1_TX_DP<4>")
	)
	(segment
		(start 107.360466 -246.593868)
		(end 107.332272 -246.610124)
		(width 0.1143)
		(layer "In11.Cu")
		(net "P5E_CPU1_G1_TX_DP<4>")
	)
	(segment
		(start 107.373166 -234.282234)
		(end 107.403138 -234.29976)
		(width 0.1143)
		(layer "In11.Cu")
		(net "P5E_CPU1_G1_TX_DP<4>")
	)
	(segment
		(start 107.365038 -234.277408)
		(end 107.366562 -234.278424)
		(width 0.1143)
		(layer "In11.Cu")
		(net "P5E_CPU1_G1_TX_DP<4>")
	)
	(segment
		(start 106.423968 -224.557082)
		(end 106.463084 -224.579942)
		(width 0.1143)
		(layer "In11.Cu")
		(net "P5E_CPU1_G1_TX_DP<4>")
	)
	(segment
		(start 107.35691 -243.992908)
		(end 107.357926 -243.993416)
		(width 0.1143)
		(layer "In11.Cu")
		(net "P5E_CPU1_G1_TX_DP<4>")
	)
	(segment
		(start 107.332272 -239.118648)
		(end 107.35691 -239.132872)
		(width 0.1143)
		(layer "In11.Cu")
		(net "P5E_CPU1_G1_TX_DP<4>")
	)
	(segment
		(start 107.35945 -243.994432)
		(end 107.36199 -243.995702)
		(width 0.1143)
		(layer "In11.Cu")
		(net "P5E_CPU1_G1_TX_DP<4>")
	)
	(segment
		(start 107.365038 -232.01122)
		(end 107.364022 -232.011728)
		(width 0.1143)
		(layer "In11.Cu")
		(net "P5E_CPU1_G1_TX_DP<4>")
	)
	(segment
		(start 107.36326 -233.632248)
		(end 107.36199 -233.63301)
		(width 0.1143)
		(layer "In11.Cu")
		(net "P5E_CPU1_G1_TX_DP<4>")
	)
	(segment
		(start 107.36199 -236.873034)
		(end 107.360466 -236.873796)
		(width 0.1143)
		(layer "In11.Cu")
		(net "P5E_CPU1_G1_TX_DP<4>")
	)
	(segment
		(start 111.430562 -207.25892)
		(end 106.737912 -215.161876)
		(width 0.14224)
		(layer "In11.Cu")
		(net "P5E_CPU1_G1_TX_DP<4>")
	)
	(segment
		(start 107.400598 -230.370634)
		(end 107.364022 -230.39197)
		(width 0.1143)
		(layer "In11.Cu")
		(net "P5E_CPU1_G1_TX_DP<4>")
	)
	(segment
		(start 107.360466 -236.873796)
		(end 107.332272 -236.890052)
		(width 0.1143)
		(layer "In11.Cu")
		(net "P5E_CPU1_G1_TX_DP<4>")
	)
	(segment
		(start 107.365038 -232.657396)
		(end 107.366562 -232.658412)
		(width 0.1143)
		(layer "In11.Cu")
		(net "P5E_CPU1_G1_TX_DP<4>")
	)
	(segment
		(start 107.36199 -242.37569)
		(end 107.36326 -242.376452)
		(width 0.1143)
		(layer "In11.Cu")
		(net "P5E_CPU1_G1_TX_DP<4>")
	)
	(segment
		(start 107.360466 -244.973856)
		(end 107.332272 -244.990112)
		(width 0.1143)
		(layer "In11.Cu")
		(net "P5E_CPU1_G1_TX_DP<4>")
	)
	(segment
		(start 106.393488 -222.91929)
		(end 106.423968 -222.93707)
		(width 0.1143)
		(layer "In11.Cu")
		(net "P5E_CPU1_G1_TX_DP<4>")
	)
	(segment
		(start 107.36199 -243.353082)
		(end 107.360466 -243.353844)
		(width 0.1143)
		(layer "In11.Cu")
		(net "P5E_CPU1_G1_TX_DP<4>")
	)
	(segment
		(start 107.332272 -235.878624)
		(end 107.35691 -235.892848)
		(width 0.1143)
		(layer "In11.Cu")
		(net "P5E_CPU1_G1_TX_DP<4>")
	)
	(segment
		(start 107.370626 -239.140746)
		(end 107.37215 -239.141762)
		(width 0.1143)
		(layer "In11.Cu")
		(net "P5E_CPU1_G1_TX_DP<4>")
	)
	(segment
		(start 107.360466 -240.11382)
		(end 107.332272 -240.130076)
		(width 0.1143)
		(layer "In11.Cu")
		(net "P5E_CPU1_G1_TX_DP<4>")
	)
	(segment
		(start 107.364022 -236.871764)
		(end 107.36326 -236.872272)
		(width 0.1143)
		(layer "In11.Cu")
		(net "P5E_CPU1_G1_TX_DP<4>")
	)
	(segment
		(start 106.424984 -222.291402)
		(end 106.423968 -222.29191)
		(width 0.1143)
		(layer "In11.Cu")
		(net "P5E_CPU1_G1_TX_DP<4>")
	)
	(segment
		(start 107.365038 -235.89742)
		(end 107.366562 -235.898436)
		(width 0.1143)
		(layer "In11.Cu")
		(net "P5E_CPU1_G1_TX_DP<4>")
	)
	(segment
		(start 107.400344 -228.75113)
		(end 107.364022 -228.771958)
		(width 0.1143)
		(layer "In11.Cu")
		(net "P5E_CPU1_G1_TX_DP<4>")
	)
	(segment
		(start 107.364022 -242.37696)
		(end 107.365038 -242.377468)
		(width 0.1143)
		(layer "In11.Cu")
		(net "P5E_CPU1_G1_TX_DP<4>")
	)
	(segment
		(start 107.36199 -235.253022)
		(end 107.360466 -235.253784)
		(width 0.1143)
		(layer "In11.Cu")
		(net "P5E_CPU1_G1_TX_DP<4>")
	)
	(segment
		(start 107.364022 -245.616984)
		(end 107.365038 -245.617492)
		(width 0.1143)
		(layer "In11.Cu")
		(net "P5E_CPU1_G1_TX_DP<4>")
	)
	(segment
		(start 107.36326 -241.732308)
		(end 107.36199 -241.73307)
		(width 0.1143)
		(layer "In11.Cu")
		(net "P5E_CPU1_G1_TX_DP<4>")
	)
	(segment
		(start 107.365038 -240.757456)
		(end 107.366562 -240.758472)
		(width 0.1143)
		(layer "In11.Cu")
		(net "P5E_CPU1_G1_TX_DP<4>")
	)
	(segment
		(start 107.36199 -232.655618)
		(end 107.36326 -232.65638)
		(width 0.1143)
		(layer "In11.Cu")
		(net "P5E_CPU1_G1_TX_DP<4>")
	)
	(segment
		(start 107.366562 -239.13846)
		(end 107.370626 -239.140746)
		(width 0.1143)
		(layer "In11.Cu")
		(net "P5E_CPU1_G1_TX_DP<4>")
	)
	(segment
		(start 107.36199 -244.973094)
		(end 107.360466 -244.973856)
		(width 0.1143)
		(layer "In11.Cu")
		(net "P5E_CPU1_G1_TX_DP<4>")
	)
	(segment
		(start 107.365038 -243.351304)
		(end 107.364022 -243.351812)
		(width 0.1143)
		(layer "In11.Cu")
		(net "P5E_CPU1_G1_TX_DP<4>")
	)
	(segment
		(start 106.426508 -222.290386)
		(end 106.424984 -222.291402)
		(width 0.1143)
		(layer "In11.Cu")
		(net "P5E_CPU1_G1_TX_DP<4>")
	)
	(segment
		(start 107.366562 -235.250228)
		(end 107.365038 -235.251244)
		(width 0.1143)
		(layer "In11.Cu")
		(net "P5E_CPU1_G1_TX_DP<4>")
	)
	(segment
		(start 107.364022 -229.416864)
		(end 107.400344 -229.437946)
		(width 0.1143)
		(layer "In11.Cu")
		(net "P5E_CPU1_G1_TX_DP<4>")
	)
	(segment
		(start 107.36199 -232.012998)
		(end 107.360466 -232.01376)
		(width 0.1143)
		(layer "In11.Cu")
		(net "P5E_CPU1_G1_TX_DP<4>")
	)
	(segment
		(start 107.332272 -243.978684)
		(end 107.35691 -243.992908)
		(width 0.1143)
		(layer "In11.Cu")
		(net "P5E_CPU1_G1_TX_DP<4>")
	)
	(segment
		(start 107.36326 -237.516416)
		(end 107.364022 -237.516924)
		(width 0.1143)
		(layer "In11.Cu")
		(net "P5E_CPU1_G1_TX_DP<4>")
	)
	(segment
		(start 107.366562 -246.590312)
		(end 107.365038 -246.591328)
		(width 0.1143)
		(layer "In11.Cu")
		(net "P5E_CPU1_G1_TX_DP<4>")
	)
	(segment
		(start 107.364022 -238.491776)
		(end 107.332272 -238.510064)
		(width 0.1143)
		(layer "In11.Cu")
		(net "P5E_CPU1_G1_TX_DP<4>")
	)
	(segment
		(start 47.145448 -19.427952)
		(end 47.145448 -20.192746)
		(width 0.14224)
		(layer "In11.Cu")
		(net "P5E_CPU1_G1_TX_DP<4>")
	)
	(segment
		(start 106.92638 -225.385884)
		(end 106.933238 -225.389948)
		(width 0.1143)
		(layer "In11.Cu")
		(net "P5E_CPU1_G1_TX_DP<4>")
	)
	(segment
		(start 107.403138 -246.568976)
		(end 107.366562 -246.590312)
		(width 0.1143)
		(layer "In11.Cu")
		(net "P5E_CPU1_G1_TX_DP<4>")
	)
	(segment
		(start 107.357926 -239.13338)
		(end 107.35945 -239.134396)
		(width 0.1143)
		(layer "In11.Cu")
		(net "P5E_CPU1_G1_TX_DP<4>")
	)
	(segment
		(start 107.35945 -232.654348)
		(end 107.36199 -232.655618)
		(width 0.1143)
		(layer "In11.Cu")
		(net "P5E_CPU1_G1_TX_DP<4>")
	)
	(segment
		(start 106.925618 -225.385376)
		(end 106.92638 -225.385884)
		(width 0.1143)
		(layer "In11.Cu")
		(net "P5E_CPU1_G1_TX_DP<4>")
	)
	(segment
		(start 107.37215 -239.141762)
		(end 107.373166 -239.14227)
		(width 0.1143)
		(layer "In11.Cu")
		(net "P5E_CPU1_G1_TX_DP<4>")
	)
	(segment
		(start 107.36326 -234.276392)
		(end 107.364022 -234.2769)
		(width 0.1143)
		(layer "In11.Cu")
		(net "P5E_CPU1_G1_TX_DP<4>")
	)
	(segment
		(start 107.36326 -243.996464)
		(end 107.364022 -243.996972)
		(width 0.1143)
		(layer "In11.Cu")
		(net "P5E_CPU1_G1_TX_DP<4>")
	)
	(segment
		(start 107.365038 -233.631232)
		(end 107.364022 -233.63174)
		(width 0.1143)
		(layer "In11.Cu")
		(net "P5E_CPU1_G1_TX_DP<4>")
	)
	(segment
		(start 47.436278 -19.137122)
		(end 47.145448 -19.427952)
		(width 0.14224)
		(layer "In11.Cu")
		(net "P5E_CPU1_G1_TX_DP<4>")
	)
	(segment
		(start 107.36326 -245.616476)
		(end 107.364022 -245.616984)
		(width 0.1143)
		(layer "In11.Cu")
		(net "P5E_CPU1_G1_TX_DP<4>")
	)
	(segment
		(start 107.35691 -239.132872)
		(end 107.357926 -239.13338)
		(width 0.1143)
		(layer "In11.Cu")
		(net "P5E_CPU1_G1_TX_DP<4>")
	)
	(segment
		(start 107.36199 -235.895642)
		(end 107.36326 -235.896404)
		(width 0.1143)
		(layer "In11.Cu")
		(net "P5E_CPU1_G1_TX_DP<4>")
	)
	(segment
		(start 107.365038 -246.591328)
		(end 107.364022 -246.591836)
		(width 0.1143)
		(layer "In11.Cu")
		(net "P5E_CPU1_G1_TX_DP<4>")
	)
	(segment
		(start 106.463084 -223.889062)
		(end 106.423968 -223.911922)
		(width 0.1143)
		(layer "In11.Cu")
		(net "P5E_CPU1_G1_TX_DP<4>")
	)
	(segment
		(start 107.403138 -235.228892)
		(end 107.366562 -235.250228)
		(width 0.1143)
		(layer "In11.Cu")
		(net "P5E_CPU1_G1_TX_DP<4>")
	)
	(segment
		(start 106.236262 -222.61449)
		(end 106.236516 -222.61449)
		(width 0.1143)
		(layer "In11.Cu")
		(net "P5E_CPU1_G1_TX_DP<4>")
	)
	(segment
		(start 107.366562 -243.350288)
		(end 107.365038 -243.351304)
		(width 0.1143)
		(layer "In11.Cu")
		(net "P5E_CPU1_G1_TX_DP<4>")
	)
	(segment
		(start 107.36326 -246.592344)
		(end 107.36199 -246.593106)
		(width 0.1143)
		(layer "In11.Cu")
		(net "P5E_CPU1_G1_TX_DP<4>")
	)
	(segment
		(start 107.365038 -238.491268)
		(end 107.364022 -238.491776)
		(width 0.1143)
		(layer "In11.Cu")
		(net "P5E_CPU1_G1_TX_DP<4>")
	)
	(arc
		(start 106.706416 -221.804484)
		(mid 106.641898 -222.067026)
		(end 106.46283 -222.269558)
		(width 0.1143)
		(layer "In11.Cu")
		(net "P5E_CPU1_G1_TX_DP<4>")
	)
	(arc
		(start 106.706416 -225.044508)
		(mid 106.747671 -225.215479)
		(end 106.862372 -225.3488)
		(width 0.1143)
		(layer "In11.Cu")
		(net "P5E_CPU1_G1_TX_DP<4>")
	)
	(arc
		(start 106.863388 -247.419622)
		(mid 106.765623 -247.522598)
		(end 106.713274 -247.654572)
		(width 0.1143)
		(layer "In11.Cu")
		(net "P5E_CPU1_G1_TX_DP<4>")
	)
	(arc
		(start 107.403138 -237.539784)
		(mid 107.646465 -238.00435)
		(end 107.403138 -238.468916)
		(width 0.1143)
		(layer "In11.Cu")
		(net "P5E_CPU1_G1_TX_DP<4>")
	)
	(arc
		(start 107.332272 -243.3701)
		(mid 107.176344 -243.674392)
		(end 107.332272 -243.978684)
		(width 0.1143)
		(layer "In11.Cu")
		(net "P5E_CPU1_G1_TX_DP<4>")
	)
	(arc
		(start 107.332272 -246.610124)
		(mid 107.217596 -246.743458)
		(end 107.176316 -246.914416)
		(width 0.1143)
		(layer "In11.Cu")
		(net "P5E_CPU1_G1_TX_DP<4>")
	)
	(arc
		(start 107.403138 -227.819966)
		(mid 107.646465 -228.284532)
		(end 107.403138 -228.749098)
		(width 0.1143)
		(layer "In11.Cu")
		(net "P5E_CPU1_G1_TX_DP<4>")
	)
	(arc
		(start 107.332272 -232.030016)
		(mid 107.176344 -232.334308)
		(end 107.332272 -232.6386)
		(width 0.1143)
		(layer "In11.Cu")
		(net "P5E_CPU1_G1_TX_DP<4>")
	)
	(arc
		(start 106.933238 -225.389948)
		(mid 107.112051 -225.592298)
		(end 107.17657 -225.854514)
		(width 0.1143)
		(layer "In11.Cu")
		(net "P5E_CPU1_G1_TX_DP<4>")
	)
	(arc
		(start 107.332272 -240.130076)
		(mid 107.176344 -240.434368)
		(end 107.332272 -240.73866)
		(width 0.1143)
		(layer "In11.Cu")
		(net "P5E_CPU1_G1_TX_DP<4>")
	)
	(arc
		(start 106.463084 -222.95993)
		(mid 106.706411 -223.424496)
		(end 106.463084 -223.889062)
		(width 0.1143)
		(layer "In11.Cu")
		(net "P5E_CPU1_G1_TX_DP<4>")
	)
	(arc
		(start 107.64647 -229.90429)
		(mid 107.581234 -230.167881)
		(end 107.400598 -230.370634)
		(width 0.1143)
		(layer "In11.Cu")
		(net "P5E_CPU1_G1_TX_DP<4>")
	)
	(arc
		(start 106.463084 -224.579942)
		(mid 106.641897 -224.782292)
		(end 106.706416 -225.044508)
		(width 0.1143)
		(layer "In11.Cu")
		(net "P5E_CPU1_G1_TX_DP<4>")
	)
	(arc
		(start 106.392218 -222.310198)
		(mid 106.277542 -222.443532)
		(end 106.236262 -222.61449)
		(width 0.1143)
		(layer "In11.Cu")
		(net "P5E_CPU1_G1_TX_DP<4>")
	)
	(arc
		(start 107.332272 -236.890052)
		(mid 107.176344 -237.194344)
		(end 107.332272 -237.498636)
		(width 0.1143)
		(layer "In11.Cu")
		(net "P5E_CPU1_G1_TX_DP<4>")
	)
	(arc
		(start 107.332272 -238.510064)
		(mid 107.176344 -238.814356)
		(end 107.332272 -239.118648)
		(width 0.1143)
		(layer "In11.Cu")
		(net "P5E_CPU1_G1_TX_DP<4>")
	)
	(arc
		(start 107.332272 -233.650028)
		(mid 107.176344 -233.95432)
		(end 107.332272 -234.258612)
		(width 0.1143)
		(layer "In11.Cu")
		(net "P5E_CPU1_G1_TX_DP<4>")
	)
	(arc
		(start 107.332272 -235.27004)
		(mid 107.176344 -235.574332)
		(end 107.332272 -235.878624)
		(width 0.1143)
		(layer "In11.Cu")
		(net "P5E_CPU1_G1_TX_DP<4>")
	)
	(arc
		(start 107.403138 -226.199954)
		(mid 107.646465 -226.66452)
		(end 107.403138 -227.129086)
		(width 0.1143)
		(layer "In11.Cu")
		(net "P5E_CPU1_G1_TX_DP<4>")
	)
	(arc
		(start 107.176316 -229.094538)
		(mid 107.217078 -229.264422)
		(end 107.330494 -229.397306)
		(width 0.1143)
		(layer "In11.Cu")
		(net "P5E_CPU1_G1_TX_DP<4>")
	)
	(arc
		(start 107.403138 -240.779808)
		(mid 107.646465 -241.244374)
		(end 107.403138 -241.70894)
		(width 0.1143)
		(layer "In11.Cu")
		(net "P5E_CPU1_G1_TX_DP<4>")
	)
	(arc
		(start 107.176316 -246.914416)
		(mid 107.111801 -247.176635)
		(end 106.932984 -247.378982)
		(width 0.1143)
		(layer "In11.Cu")
		(net "P5E_CPU1_G1_TX_DP<4>")
	)
	(arc
		(start 107.403138 -234.29976)
		(mid 107.646465 -234.764326)
		(end 107.403138 -235.228892)
		(width 0.1143)
		(layer "In11.Cu")
		(net "P5E_CPU1_G1_TX_DP<4>")
	)
	(arc
		(start 107.332272 -230.410258)
		(mid 107.217596 -230.543592)
		(end 107.176316 -230.71455)
		(width 0.1143)
		(layer "In11.Cu")
		(net "P5E_CPU1_G1_TX_DP<4>")
	)
	(arc
		(start 107.400344 -229.437946)
		(mid 107.580996 -229.640691)
		(end 107.646216 -229.90429)
		(width 0.1143)
		(layer "In11.Cu")
		(net "P5E_CPU1_G1_TX_DP<4>")
	)
	(arc
		(start 107.332272 -228.790246)
		(mid 107.217596 -228.92358)
		(end 107.176316 -229.094538)
		(width 0.1143)
		(layer "In11.Cu")
		(net "P5E_CPU1_G1_TX_DP<4>")
	)
	(arc
		(start 107.333542 -227.169726)
		(mid 107.176565 -227.474526)
		(end 107.333542 -227.779326)
		(width 0.1143)
		(layer "In11.Cu")
		(net "P5E_CPU1_G1_TX_DP<4>")
	)
	(arc
		(start 107.332272 -244.990112)
		(mid 107.176344 -245.294404)
		(end 107.332272 -245.598696)
		(width 0.1143)
		(layer "In11.Cu")
		(net "P5E_CPU1_G1_TX_DP<4>")
	)
	(arc
		(start 107.17657 -225.854514)
		(mid 107.218119 -226.025936)
		(end 107.333542 -226.159314)
		(width 0.1143)
		(layer "In11.Cu")
		(net "P5E_CPU1_G1_TX_DP<4>")
	)
	(arc
		(start 107.403138 -242.39982)
		(mid 107.646465 -242.864386)
		(end 107.403138 -243.328952)
		(width 0.1143)
		(layer "In11.Cu")
		(net "P5E_CPU1_G1_TX_DP<4>")
	)
	(arc
		(start 107.176316 -230.71455)
		(mid 107.217078 -230.884434)
		(end 107.330494 -231.017318)
		(width 0.1143)
		(layer "In11.Cu")
		(net "P5E_CPU1_G1_TX_DP<4>")
	)
	(arc
		(start 107.332272 -241.750088)
		(mid 107.176344 -242.05438)
		(end 107.332272 -242.358672)
		(width 0.1143)
		(layer "In11.Cu")
		(net "P5E_CPU1_G1_TX_DP<4>")
	)
	(arc
		(start 107.403138 -232.679748)
		(mid 107.646465 -233.144314)
		(end 107.403138 -233.60888)
		(width 0.1143)
		(layer "In11.Cu")
		(net "P5E_CPU1_G1_TX_DP<4>")
	)
	(arc
		(start 107.403138 -239.159796)
		(mid 107.646465 -239.624362)
		(end 107.403138 -240.088928)
		(width 0.1143)
		(layer "In11.Cu")
		(net "P5E_CPU1_G1_TX_DP<4>")
	)
	(arc
		(start 106.393488 -223.929702)
		(mid 106.236511 -224.234502)
		(end 106.393488 -224.539302)
		(width 0.1143)
		(layer "In11.Cu")
		(net "P5E_CPU1_G1_TX_DP<4>")
	)
	(arc
		(start 106.236516 -222.61449)
		(mid 106.278065 -222.785912)
		(end 106.393488 -222.91929)
		(width 0.1143)
		(layer "In11.Cu")
		(net "P5E_CPU1_G1_TX_DP<4>")
	)
	(arc
		(start 107.403138 -235.919772)
		(mid 107.646465 -236.384338)
		(end 107.403138 -236.848904)
		(width 0.1143)
		(layer "In11.Cu")
		(net "P5E_CPU1_G1_TX_DP<4>")
	)
	(arc
		(start 107.403138 -244.019832)
		(mid 107.646465 -244.484398)
		(end 107.403138 -244.948964)
		(width 0.1143)
		(layer "In11.Cu")
		(net "P5E_CPU1_G1_TX_DP<4>")
	)
	(arc
		(start 107.403138 -245.639844)
		(mid 107.646465 -246.10441)
		(end 107.403138 -246.568976)
		(width 0.1143)
		(layer "In11.Cu")
		(net "P5E_CPU1_G1_TX_DP<4>")
	)
	(arc
		(start 107.403138 -231.059736)
		(mid 107.646465 -231.524302)
		(end 107.403138 -231.988868)
		(width 0.1143)
		(layer "In11.Cu")
		(net "P5E_CPU1_G1_TX_DP<4>")
	)
	(segment
		(start 49.960784 -17.34185)
		(end 50.231294 -17.61236)
		(width 0.12954)
		(layer "F.Cu")
		(net "P5E_CPU1_G1_TX_DP<3>")
	)
	(segment
		(start 50.256694 -16.366236)
		(end 49.960784 -16.662146)
		(width 0.12954)
		(layer "F.Cu")
		(net "P5E_CPU1_G1_TX_DP<3>")
	)
	(segment
		(start 49.960784 -16.662146)
		(end 49.960784 -17.34185)
		(width 0.12954)
		(layer "F.Cu")
		(net "P5E_CPU1_G1_TX_DP<3>")
	)
	(segment
		(start 109.897926 -245.560342)
		(end 109.431074 -245.294404)
		(width 0.12954)
		(layer "F.Cu")
		(net "P5E_CPU1_G1_TX_DP<3>")
	)
	(segment
		(start 108.303314 -239.136428)
		(end 108.304076 -239.136936)
		(width 0.1143)
		(layer "In11.Cu")
		(net "P5E_CPU1_G1_TX_DP<3>")
	)
	(segment
		(start 108.306616 -238.490252)
		(end 108.305092 -238.491268)
		(width 0.1143)
		(layer "In11.Cu")
		(net "P5E_CPU1_G1_TX_DP<3>")
	)
	(segment
		(start 107.682538 -215.397842)
		(end 107.682538 -221.05493)
		(width 0.14224)
		(layer "In11.Cu")
		(net "P5E_CPU1_G1_TX_DP<3>")
	)
	(segment
		(start 107.319318 -222.318072)
		(end 107.291632 -222.346266)
		(width 0.1143)
		(layer "In11.Cu")
		(net "P5E_CPU1_G1_TX_DP<3>")
	)
	(segment
		(start 108.306616 -240.110264)
		(end 108.305092 -240.11128)
		(width 0.1143)
		(layer "In11.Cu")
		(net "P5E_CPU1_G1_TX_DP<3>")
	)
	(segment
		(start 108.307632 -235.24972)
		(end 108.306616 -235.250228)
		(width 0.1143)
		(layer "In11.Cu")
		(net "P5E_CPU1_G1_TX_DP<3>")
	)
	(segment
		(start 107.4039 -222.960184)
		(end 107.431586 -222.979996)
		(width 0.1143)
		(layer "In11.Cu")
		(net "P5E_CPU1_G1_TX_DP<3>")
	)
	(segment
		(start 108.305092 -240.757456)
		(end 108.343192 -240.779808)
		(width 0.1143)
		(layer "In11.Cu")
		(net "P5E_CPU1_G1_TX_DP<3>")
	)
	(segment
		(start 108.303314 -243.996464)
		(end 108.304076 -243.996972)
		(width 0.1143)
		(layer "In11.Cu")
		(net "P5E_CPU1_G1_TX_DP<3>")
	)
	(segment
		(start 108.303314 -236.872272)
		(end 108.272326 -236.890052)
		(width 0.1143)
		(layer "In11.Cu")
		(net "P5E_CPU1_G1_TX_DP<3>")
	)
	(segment
		(start 108.307632 -236.869732)
		(end 108.306616 -236.87024)
		(width 0.1143)
		(layer "In11.Cu")
		(net "P5E_CPU1_G1_TX_DP<3>")
	)
	(segment
		(start 108.343192 -236.848904)
		(end 108.310934 -236.8677)
		(width 0.1143)
		(layer "In11.Cu")
		(net "P5E_CPU1_G1_TX_DP<3>")
	)
	(segment
		(start 107.364022 -222.29191)
		(end 107.319318 -222.318072)
		(width 0.1143)
		(layer "In11.Cu")
		(net "P5E_CPU1_G1_TX_DP<3>")
	)
	(segment
		(start 108.302044 -239.135666)
		(end 108.303314 -239.136428)
		(width 0.1143)
		(layer "In11.Cu")
		(net "P5E_CPU1_G1_TX_DP<3>")
	)
	(segment
		(start 108.304076 -241.7318)
		(end 108.303314 -241.732308)
		(width 0.1143)
		(layer "In11.Cu")
		(net "P5E_CPU1_G1_TX_DP<3>")
	)
	(segment
		(start 108.305092 -241.731292)
		(end 108.304076 -241.7318)
		(width 0.1143)
		(layer "In11.Cu")
		(net "P5E_CPU1_G1_TX_DP<3>")
	)
	(segment
		(start 108.304076 -233.63174)
		(end 108.303314 -233.632248)
		(width 0.1143)
		(layer "In11.Cu")
		(net "P5E_CPU1_G1_TX_DP<3>")
	)
	(segment
		(start 108.343192 -241.70894)
		(end 108.310934 -241.727736)
		(width 0.1143)
		(layer "In11.Cu")
		(net "P5E_CPU1_G1_TX_DP<3>")
	)
	(segment
		(start 108.305092 -236.871256)
		(end 108.304076 -236.871764)
		(width 0.1143)
		(layer "In11.Cu")
		(net "P5E_CPU1_G1_TX_DP<3>")
	)
	(segment
		(start 108.773976 -244.806978)
		(end 108.813092 -244.829838)
		(width 0.1143)
		(layer "In11.Cu")
		(net "P5E_CPU1_G1_TX_DP<3>")
	)
	(segment
		(start 108.305092 -232.01122)
		(end 108.304076 -232.011728)
		(width 0.1143)
		(layer "In11.Cu")
		(net "P5E_CPU1_G1_TX_DP<3>")
	)
	(segment
		(start 109.91215 -211.642198)
		(end 107.682538 -215.397334)
		(width 0.14224)
		(layer "In11.Cu")
		(net "P5E_CPU1_G1_TX_DP<3>")
	)
	(segment
		(start 108.340652 -230.370634)
		(end 108.304076 -230.39197)
		(width 0.1143)
		(layer "In11.Cu")
		(net "P5E_CPU1_G1_TX_DP<3>")
	)
	(segment
		(start 108.303314 -240.112296)
		(end 108.272326 -240.130076)
		(width 0.1143)
		(layer "In11.Cu")
		(net "P5E_CPU1_G1_TX_DP<3>")
	)
	(segment
		(start 108.272326 -243.978684)
		(end 108.299504 -243.994432)
		(width 0.1143)
		(layer "In11.Cu")
		(net "P5E_CPU1_G1_TX_DP<3>")
	)
	(segment
		(start 108.307632 -238.489744)
		(end 108.306616 -238.490252)
		(width 0.1143)
		(layer "In11.Cu")
		(net "P5E_CPU1_G1_TX_DP<3>")
	)
	(segment
		(start 108.310934 -233.627676)
		(end 108.310172 -233.628184)
		(width 0.1143)
		(layer "In11.Cu")
		(net "P5E_CPU1_G1_TX_DP<3>")
	)
	(segment
		(start 49.940464 -20.192746)
		(end 55.978298 -48.680116)
		(width 0.14224)
		(layer "In11.Cu")
		(net "P5E_CPU1_G1_TX_DP<3>")
	)
	(segment
		(start 108.299504 -242.37442)
		(end 108.302044 -242.37569)
		(width 0.1143)
		(layer "In11.Cu")
		(net "P5E_CPU1_G1_TX_DP<3>")
	)
	(segment
		(start 108.304076 -231.036876)
		(end 108.343192 -231.059736)
		(width 0.1143)
		(layer "In11.Cu")
		(net "P5E_CPU1_G1_TX_DP<3>")
	)
	(segment
		(start 154.16403 -171.147232)
		(end 154.16403 -171.147486)
		(width 0.14224)
		(layer "In11.Cu")
		(net "P5E_CPU1_G1_TX_DP<3>")
	)
	(segment
		(start 108.304076 -237.516924)
		(end 108.305092 -237.517432)
		(width 0.1143)
		(layer "In11.Cu")
		(net "P5E_CPU1_G1_TX_DP<3>")
	)
	(segment
		(start 112.141762 -207.887316)
		(end 109.912404 -211.641944)
		(width 0.14224)
		(layer "In11.Cu")
		(net "P5E_CPU1_G1_TX_DP<3>")
	)
	(segment
		(start 108.310172 -236.868208)
		(end 108.307632 -236.869732)
		(width 0.1143)
		(layer "In11.Cu")
		(net "P5E_CPU1_G1_TX_DP<3>")
	)
	(segment
		(start 108.343192 -231.988868)
		(end 108.306616 -232.010204)
		(width 0.1143)
		(layer "In11.Cu")
		(net "P5E_CPU1_G1_TX_DP<3>")
	)
	(segment
		(start 108.304076 -232.011728)
		(end 108.272326 -232.030016)
		(width 0.1143)
		(layer "In11.Cu")
		(net "P5E_CPU1_G1_TX_DP<3>")
	)
	(segment
		(start 107.833922 -225.367088)
		(end 107.873038 -225.389948)
		(width 0.1143)
		(layer "In11.Cu")
		(net "P5E_CPU1_G1_TX_DP<3>")
	)
	(segment
		(start 108.302044 -243.995702)
		(end 108.303314 -243.996464)
		(width 0.1143)
		(layer "In11.Cu")
		(net "P5E_CPU1_G1_TX_DP<3>")
	)
	(segment
		(start 108.296202 -226.172522)
		(end 108.297472 -226.173284)
		(width 0.1143)
		(layer "In11.Cu")
		(net "P5E_CPU1_G1_TX_DP<3>")
	)
	(segment
		(start 108.305092 -240.11128)
		(end 108.304076 -240.111788)
		(width 0.1143)
		(layer "In11.Cu")
		(net "P5E_CPU1_G1_TX_DP<3>")
	)
	(segment
		(start 108.306616 -241.730276)
		(end 108.305092 -241.731292)
		(width 0.1143)
		(layer "In11.Cu")
		(net "P5E_CPU1_G1_TX_DP<3>")
	)
	(segment
		(start 108.305092 -239.137444)
		(end 108.343192 -239.159796)
		(width 0.1143)
		(layer "In11.Cu")
		(net "P5E_CPU1_G1_TX_DP<3>")
	)
	(segment
		(start 58.142632 -52.42814)
		(end 150.815548 -135.761984)
		(width 0.14224)
		(layer "In11.Cu")
		(net "P5E_CPU1_G1_TX_DP<3>")
	)
	(segment
		(start 108.303314 -240.75644)
		(end 108.304076 -240.756948)
		(width 0.1143)
		(layer "In11.Cu")
		(net "P5E_CPU1_G1_TX_DP<3>")
	)
	(segment
		(start 108.272326 -235.878624)
		(end 108.299504 -235.894372)
		(width 0.1143)
		(layer "In11.Cu")
		(net "P5E_CPU1_G1_TX_DP<3>")
	)
	(segment
		(start 108.306616 -226.178618)
		(end 108.30941 -226.180142)
		(width 0.1143)
		(layer "In11.Cu")
		(net "P5E_CPU1_G1_TX_DP<3>")
	)
	(segment
		(start 155.88615 -166.116254)
		(end 154.28214 -170.825668)
		(width 0.14224)
		(layer "In11.Cu")
		(net "P5E_CPU1_G1_TX_DP<3>")
	)
	(segment
		(start 108.304076 -229.416864)
		(end 108.342684 -229.43947)
		(width 0.1143)
		(layer "In11.Cu")
		(net "P5E_CPU1_G1_TX_DP<3>")
	)
	(segment
		(start 107.176824 -224.22612)
		(end 107.177586 -224.241106)
		(width 0.1143)
		(layer "In11.Cu")
		(net "P5E_CPU1_G1_TX_DP<3>")
	)
	(segment
		(start 150.542244 -176.413668)
		(end 112.141762 -207.887316)
		(width 0.14224)
		(layer "In11.Cu")
		(net "P5E_CPU1_G1_TX_DP<3>")
	)
	(segment
		(start 107.682284 -215.397588)
		(end 107.682538 -215.397842)
		(width 0.14224)
		(layer "In11.Cu")
		(net "P5E_CPU1_G1_TX_DP<3>")
	)
	(segment
		(start 108.299504 -240.754408)
		(end 108.302044 -240.755678)
		(width 0.1143)
		(layer "In11.Cu")
		(net "P5E_CPU1_G1_TX_DP<3>")
	)
	(segment
		(start 154.163776 -171.148248)
		(end 154.033982 -171.501562)
		(width 0.14224)
		(layer "In11.Cu")
		(net "P5E_CPU1_G1_TX_DP<3>")
	)
	(segment
		(start 108.302044 -232.655618)
		(end 108.303314 -232.65638)
		(width 0.1143)
		(layer "In11.Cu")
		(net "P5E_CPU1_G1_TX_DP<3>")
	)
	(segment
		(start 108.310172 -241.728244)
		(end 108.307632 -241.729768)
		(width 0.1143)
		(layer "In11.Cu")
		(net "P5E_CPU1_G1_TX_DP<3>")
	)
	(segment
		(start 108.304076 -242.37696)
		(end 108.305092 -242.377468)
		(width 0.1143)
		(layer "In11.Cu")
		(net "P5E_CPU1_G1_TX_DP<3>")
	)
	(segment
		(start 108.307632 -240.109756)
		(end 108.306616 -240.110264)
		(width 0.1143)
		(layer "In11.Cu")
		(net "P5E_CPU1_G1_TX_DP<3>")
	)
	(segment
		(start 108.310172 -233.628184)
		(end 108.307632 -233.629708)
		(width 0.1143)
		(layer "In11.Cu")
		(net "P5E_CPU1_G1_TX_DP<3>")
	)
	(segment
		(start 108.343192 -228.749098)
		(end 108.307632 -228.769926)
		(width 0.1143)
		(layer "In11.Cu")
		(net "P5E_CPU1_G1_TX_DP<3>")
	)
	(segment
		(start 108.310172 -235.248196)
		(end 108.307632 -235.24972)
		(width 0.1143)
		(layer "In11.Cu")
		(net "P5E_CPU1_G1_TX_DP<3>")
	)
	(segment
		(start 108.310934 -235.247688)
		(end 108.310172 -235.248196)
		(width 0.1143)
		(layer "In11.Cu")
		(net "P5E_CPU1_G1_TX_DP<3>")
	)
	(segment
		(start 107.332272 -222.918782)
		(end 107.332272 -222.918528)
		(width 0.1143)
		(layer "In11.Cu")
		(net "P5E_CPU1_G1_TX_DP<3>")
	)
	(segment
		(start 109.912404 -211.641944)
		(end 109.91215 -211.642198)
		(width 0.14224)
		(layer "In11.Cu")
		(net "P5E_CPU1_G1_TX_DP<3>")
	)
	(segment
		(start 108.304076 -238.491776)
		(end 108.303314 -238.492284)
		(width 0.1143)
		(layer "In11.Cu")
		(net "P5E_CPU1_G1_TX_DP<3>")
	)
	(segment
		(start 108.306616 -233.630216)
		(end 108.305092 -233.631232)
		(width 0.1143)
		(layer "In11.Cu")
		(net "P5E_CPU1_G1_TX_DP<3>")
	)
	(segment
		(start 108.306616 -236.87024)
		(end 108.305092 -236.871256)
		(width 0.1143)
		(layer "In11.Cu")
		(net "P5E_CPU1_G1_TX_DP<3>")
	)
	(segment
		(start 108.272326 -240.73866)
		(end 108.299504 -240.754408)
		(width 0.1143)
		(layer "In11.Cu")
		(net "P5E_CPU1_G1_TX_DP<3>")
	)
	(segment
		(start 108.305092 -227.797614)
		(end 108.343192 -227.819966)
		(width 0.1143)
		(layer "In11.Cu")
		(net "P5E_CPU1_G1_TX_DP<3>")
	)
	(segment
		(start 108.304076 -239.136936)
		(end 108.305092 -239.137444)
		(width 0.1143)
		(layer "In11.Cu")
		(net "P5E_CPU1_G1_TX_DP<3>")
	)
	(segment
		(start 108.343192 -240.088928)
		(end 108.310934 -240.107724)
		(width 0.1143)
		(layer "In11.Cu")
		(net "P5E_CPU1_G1_TX_DP<3>")
	)
	(segment
		(start 154.16403 -171.147486)
		(end 154.163776 -171.148248)
		(width 0.14224)
		(layer "In11.Cu")
		(net "P5E_CPU1_G1_TX_DP<3>")
	)
	(segment
		(start 108.304076 -226.177094)
		(end 108.305092 -226.177602)
		(width 0.1143)
		(layer "In11.Cu")
		(net "P5E_CPU1_G1_TX_DP<3>")
	)
	(segment
		(start 108.303314 -232.65638)
		(end 108.304076 -232.656888)
		(width 0.1143)
		(layer "In11.Cu")
		(net "P5E_CPU1_G1_TX_DP<3>")
	)
	(segment
		(start 108.310934 -236.8677)
		(end 108.310172 -236.868208)
		(width 0.1143)
		(layer "In11.Cu")
		(net "P5E_CPU1_G1_TX_DP<3>")
	)
	(segment
		(start 108.304076 -230.39197)
		(end 108.272326 -230.410258)
		(width 0.1143)
		(layer "In11.Cu")
		(net "P5E_CPU1_G1_TX_DP<3>")
	)
	(segment
		(start 155.88615 -166.116508)
		(end 155.88615 -166.116254)
		(width 0.14224)
		(layer "In11.Cu")
		(net "P5E_CPU1_G1_TX_DP<3>")
	)
	(segment
		(start 107.682538 -221.083378)
		(end 107.636818 -221.129098)
		(width 0.1143)
		(layer "In11.Cu")
		(net "P5E_CPU1_G1_TX_DP<3>")
	)
	(segment
		(start 108.303314 -242.376452)
		(end 108.304076 -242.37696)
		(width 0.1143)
		(layer "In11.Cu")
		(net "P5E_CPU1_G1_TX_DP<3>")
	)
	(segment
		(start 156.435298 -159.758126)
		(end 156.435298 -164.503862)
		(width 0.14224)
		(layer "In11.Cu")
		(net "P5E_CPU1_G1_TX_DP<3>")
	)
	(segment
		(start 108.299504 -234.27436)
		(end 108.302044 -234.27563)
		(width 0.1143)
		(layer "In11.Cu")
		(net "P5E_CPU1_G1_TX_DP<3>")
	)
	(segment
		(start 150.815548 -135.761984)
		(end 155.547314 -145.54708)
		(width 0.14224)
		(layer "In11.Cu")
		(net "P5E_CPU1_G1_TX_DP<3>")
	)
	(segment
		(start 55.978298 -48.680116)
		(end 58.142632 -52.42814)
		(width 0.14224)
		(layer "In11.Cu")
		(net "P5E_CPU1_G1_TX_DP<3>")
	)
	(segment
		(start 107.636818 -221.30512)
		(end 107.64647 -221.613984)
		(width 0.1143)
		(layer "In11.Cu")
		(net "P5E_CPU1_G1_TX_DP<3>")
	)
	(segment
		(start 108.303314 -226.176586)
		(end 108.304076 -226.177094)
		(width 0.1143)
		(layer "In11.Cu")
		(net "P5E_CPU1_G1_TX_DP<3>")
	)
	(segment
		(start 107.333034 -222.919036)
		(end 107.4039 -222.960184)
		(width 0.1143)
		(layer "In11.Cu")
		(net "P5E_CPU1_G1_TX_DP<3>")
	)
	(segment
		(start 50.231294 -17.61236)
		(end 49.940464 -17.90319)
		(width 0.14224)
		(layer "In11.Cu")
		(net "P5E_CPU1_G1_TX_DP<3>")
	)
	(segment
		(start 108.310934 -241.727736)
		(end 108.310172 -241.728244)
		(width 0.1143)
		(layer "In11.Cu")
		(net "P5E_CPU1_G1_TX_DP<3>")
	)
	(segment
		(start 108.306616 -228.770434)
		(end 108.305092 -228.77145)
		(width 0.1143)
		(layer "In11.Cu")
		(net "P5E_CPU1_G1_TX_DP<3>")
	)
	(segment
		(start 49.940464 -17.90319)
		(end 49.940464 -20.192746)
		(width 0.14224)
		(layer "In11.Cu")
		(net "P5E_CPU1_G1_TX_DP<3>")
	)
	(segment
		(start 108.30941 -226.180142)
		(end 108.343192 -226.199954)
		(width 0.1143)
		(layer "In11.Cu")
		(net "P5E_CPU1_G1_TX_DP<3>")
	)
	(segment
		(start 108.310172 -240.108232)
		(end 108.307632 -240.109756)
		(width 0.1143)
		(layer "In11.Cu")
		(net "P5E_CPU1_G1_TX_DP<3>")
	)
	(segment
		(start 108.304076 -227.797106)
		(end 108.305092 -227.797614)
		(width 0.1143)
		(layer "In11.Cu")
		(net "P5E_CPU1_G1_TX_DP<3>")
	)
	(segment
		(start 107.332272 -222.918528)
		(end 107.333034 -222.919036)
		(width 0.1143)
		(layer "In11.Cu")
		(net "P5E_CPU1_G1_TX_DP<3>")
	)
	(segment
		(start 108.310934 -238.487712)
		(end 108.310172 -238.48822)
		(width 0.1143)
		(layer "In11.Cu")
		(net "P5E_CPU1_G1_TX_DP<3>")
	)
	(segment
		(start 108.272326 -242.358672)
		(end 108.299504 -242.37442)
		(width 0.1143)
		(layer "In11.Cu")
		(net "P5E_CPU1_G1_TX_DP<3>")
	)
	(segment
		(start 108.304076 -232.656888)
		(end 108.305092 -232.657396)
		(width 0.1143)
		(layer "In11.Cu")
		(net "P5E_CPU1_G1_TX_DP<3>")
	)
	(segment
		(start 108.302044 -235.895642)
		(end 108.303314 -235.896404)
		(width 0.1143)
		(layer "In11.Cu")
		(net "P5E_CPU1_G1_TX_DP<3>")
	)
	(segment
		(start 108.299504 -237.514384)
		(end 108.302044 -237.515654)
		(width 0.1143)
		(layer "In11.Cu")
		(net "P5E_CPU1_G1_TX_DP<3>")
	)
	(segment
		(start 108.299504 -239.134396)
		(end 108.302044 -239.135666)
		(width 0.1143)
		(layer "In11.Cu")
		(net "P5E_CPU1_G1_TX_DP<3>")
	)
	(segment
		(start 108.305092 -235.89742)
		(end 108.343192 -235.919772)
		(width 0.1143)
		(layer "In11.Cu")
		(net "P5E_CPU1_G1_TX_DP<3>")
	)
	(segment
		(start 108.302044 -237.515654)
		(end 108.303314 -237.516416)
		(width 0.1143)
		(layer "In11.Cu")
		(net "P5E_CPU1_G1_TX_DP<3>")
	)
	(segment
		(start 108.272326 -226.158806)
		(end 108.293662 -226.171252)
		(width 0.1143)
		(layer "In11.Cu")
		(net "P5E_CPU1_G1_TX_DP<3>")
	)
	(segment
		(start 108.304076 -227.151946)
		(end 108.303314 -227.152454)
		(width 0.1143)
		(layer "In11.Cu")
		(net "P5E_CPU1_G1_TX_DP<3>")
	)
	(segment
		(start 108.343192 -238.468916)
		(end 108.310934 -238.487712)
		(width 0.1143)
		(layer "In11.Cu")
		(net "P5E_CPU1_G1_TX_DP<3>")
	)
	(segment
		(start 108.297472 -226.173284)
		(end 108.298234 -226.173792)
		(width 0.1143)
		(layer "In11.Cu")
		(net "P5E_CPU1_G1_TX_DP<3>")
	)
	(segment
		(start 108.305092 -242.377468)
		(end 108.343192 -242.39982)
		(width 0.1143)
		(layer "In11.Cu")
		(net "P5E_CPU1_G1_TX_DP<3>")
	)
	(segment
		(start 108.343192 -227.129086)
		(end 108.340398 -227.131118)
		(width 0.1143)
		(layer "In11.Cu")
		(net "P5E_CPU1_G1_TX_DP<3>")
	)
	(segment
		(start 108.272326 -237.498636)
		(end 108.299504 -237.514384)
		(width 0.1143)
		(layer "In11.Cu")
		(net "P5E_CPU1_G1_TX_DP<3>")
	)
	(segment
		(start 108.304076 -240.111788)
		(end 108.303314 -240.112296)
		(width 0.1143)
		(layer "In11.Cu")
		(net "P5E_CPU1_G1_TX_DP<3>")
	)
	(segment
		(start 107.403138 -222.26905)
		(end 107.364022 -222.29191)
		(width 0.1143)
		(layer "In11.Cu")
		(net "P5E_CPU1_G1_TX_DP<3>")
	)
	(segment
		(start 107.636818 -221.129098)
		(end 107.636818 -221.30512)
		(width 0.1143)
		(layer "In11.Cu")
		(net "P5E_CPU1_G1_TX_DP<3>")
	)
	(segment
		(start 108.305092 -233.631232)
		(end 108.304076 -233.63174)
		(width 0.1143)
		(layer "In11.Cu")
		(net "P5E_CPU1_G1_TX_DP<3>")
	)
	(segment
		(start 108.299504 -243.994432)
		(end 108.302044 -243.995702)
		(width 0.1143)
		(layer "In11.Cu")
		(net "P5E_CPU1_G1_TX_DP<3>")
	)
	(segment
		(start 108.299758 -226.174554)
		(end 108.30052 -226.175062)
		(width 0.1143)
		(layer "In11.Cu")
		(net "P5E_CPU1_G1_TX_DP<3>")
	)
	(segment
		(start 108.304076 -228.771958)
		(end 108.272326 -228.790246)
		(width 0.1143)
		(layer "In11.Cu")
		(net "P5E_CPU1_G1_TX_DP<3>")
	)
	(segment
		(start 108.304076 -236.871764)
		(end 108.303314 -236.872272)
		(width 0.1143)
		(layer "In11.Cu")
		(net "P5E_CPU1_G1_TX_DP<3>")
	)
	(segment
		(start 108.743496 -244.789198)
		(end 108.773976 -244.806978)
		(width 0.1143)
		(layer "In11.Cu")
		(net "P5E_CPU1_G1_TX_DP<3>")
	)
	(segment
		(start 108.302044 -234.27563)
		(end 108.303314 -234.276392)
		(width 0.1143)
		(layer "In11.Cu")
		(net "P5E_CPU1_G1_TX_DP<3>")
	)
	(segment
		(start 108.304076 -240.756948)
		(end 108.305092 -240.757456)
		(width 0.1143)
		(layer "In11.Cu")
		(net "P5E_CPU1_G1_TX_DP<3>")
	)
	(segment
		(start 108.303314 -233.632248)
		(end 108.272326 -233.650028)
		(width 0.1143)
		(layer "In11.Cu")
		(net "P5E_CPU1_G1_TX_DP<3>")
	)
	(segment
		(start 108.310172 -238.48822)
		(end 108.307632 -238.489744)
		(width 0.1143)
		(layer "In11.Cu")
		(net "P5E_CPU1_G1_TX_DP<3>")
	)
	(segment
		(start 108.298234 -226.173792)
		(end 108.299758 -226.174554)
		(width 0.1143)
		(layer "In11.Cu")
		(net "P5E_CPU1_G1_TX_DP<3>")
	)
	(segment
		(start 107.364276 -223.911922)
		(end 107.332526 -223.93021)
		(width 0.1143)
		(layer "In11.Cu")
		(net "P5E_CPU1_G1_TX_DP<3>")
	)
	(segment
		(start 107.431586 -223.868996)
		(end 107.402376 -223.889824)
		(width 0.1143)
		(layer "In11.Cu")
		(net "P5E_CPU1_G1_TX_DP<3>")
	)
	(segment
		(start 108.305092 -232.657396)
		(end 108.343192 -232.679748)
		(width 0.1143)
		(layer "In11.Cu")
		(net "P5E_CPU1_G1_TX_DP<3>")
	)
	(segment
		(start 108.305092 -238.491268)
		(end 108.304076 -238.491776)
		(width 0.1143)
		(layer "In11.Cu")
		(net "P5E_CPU1_G1_TX_DP<3>")
	)
	(segment
		(start 108.304076 -243.996972)
		(end 108.305092 -243.99748)
		(width 0.1143)
		(layer "In11.Cu")
		(net "P5E_CPU1_G1_TX_DP<3>")
	)
	(segment
		(start 108.303314 -238.492284)
		(end 108.272326 -238.510064)
		(width 0.1143)
		(layer "In11.Cu")
		(net "P5E_CPU1_G1_TX_DP<3>")
	)
	(segment
		(start 108.270548 -231.017318)
		(end 108.304076 -231.036876)
		(width 0.1143)
		(layer "In11.Cu")
		(net "P5E_CPU1_G1_TX_DP<3>")
	)
	(segment
		(start 108.293662 -226.171252)
		(end 108.296202 -226.172522)
		(width 0.1143)
		(layer "In11.Cu")
		(net "P5E_CPU1_G1_TX_DP<3>")
	)
	(segment
		(start 107.365292 -223.911414)
		(end 107.364276 -223.911922)
		(width 0.1143)
		(layer "In11.Cu")
		(net "P5E_CPU1_G1_TX_DP<3>")
	)
	(segment
		(start 108.305092 -235.251244)
		(end 108.304076 -235.251752)
		(width 0.1143)
		(layer "In11.Cu")
		(net "P5E_CPU1_G1_TX_DP<3>")
	)
	(segment
		(start 107.334812 -224.53981)
		(end 107.400598 -224.578164)
		(width 0.1143)
		(layer "In11.Cu")
		(net "P5E_CPU1_G1_TX_DP<3>")
	)
	(segment
		(start 155.547314 -145.54708)
		(end 156.435298 -159.758126)
		(width 0.14224)
		(layer "In11.Cu")
		(net "P5E_CPU1_G1_TX_DP<3>")
	)
	(segment
		(start 108.305092 -237.517432)
		(end 108.343192 -237.539784)
		(width 0.1143)
		(layer "In11.Cu")
		(net "P5E_CPU1_G1_TX_DP<3>")
	)
	(segment
		(start 108.302044 -240.755678)
		(end 108.303314 -240.75644)
		(width 0.1143)
		(layer "In11.Cu")
		(net "P5E_CPU1_G1_TX_DP<3>")
	)
	(segment
		(start 108.303314 -235.25226)
		(end 108.272326 -235.27004)
		(width 0.1143)
		(layer "In11.Cu")
		(net "P5E_CPU1_G1_TX_DP<3>")
	)
	(segment
		(start 154.28214 -170.825668)
		(end 154.16403 -171.147232)
		(width 0.14224)
		(layer "In11.Cu")
		(net "P5E_CPU1_G1_TX_DP<3>")
	)
	(segment
		(start 108.305092 -243.99748)
		(end 108.343192 -244.019832)
		(width 0.1143)
		(layer "In11.Cu")
		(net "P5E_CPU1_G1_TX_DP<3>")
	)
	(segment
		(start 108.343192 -235.228892)
		(end 108.310934 -235.247688)
		(width 0.1143)
		(layer "In11.Cu")
		(net "P5E_CPU1_G1_TX_DP<3>")
	)
	(segment
		(start 108.307632 -243.34978)
		(end 108.306616 -243.350288)
		(width 0.1143)
		(layer "In11.Cu")
		(net "P5E_CPU1_G1_TX_DP<3>")
	)
	(segment
		(start 108.304076 -243.351812)
		(end 108.303314 -243.35232)
		(width 0.1143)
		(layer "In11.Cu")
		(net "P5E_CPU1_G1_TX_DP<3>")
	)
	(segment
		(start 108.272326 -232.6386)
		(end 108.299504 -232.654348)
		(width 0.1143)
		(layer "In11.Cu")
		(net "P5E_CPU1_G1_TX_DP<3>")
	)
	(segment
		(start 108.272326 -239.118648)
		(end 108.299504 -239.134396)
		(width 0.1143)
		(layer "In11.Cu")
		(net "P5E_CPU1_G1_TX_DP<3>")
	)
	(segment
		(start 108.306616 -235.250228)
		(end 108.305092 -235.251244)
		(width 0.1143)
		(layer "In11.Cu")
		(net "P5E_CPU1_G1_TX_DP<3>")
	)
	(segment
		(start 108.303314 -243.35232)
		(end 108.272326 -243.3701)
		(width 0.1143)
		(layer "In11.Cu")
		(net "P5E_CPU1_G1_TX_DP<3>")
	)
	(segment
		(start 108.305092 -243.351304)
		(end 108.304076 -243.351812)
		(width 0.1143)
		(layer "In11.Cu")
		(net "P5E_CPU1_G1_TX_DP<3>")
	)
	(segment
		(start 108.304076 -235.896912)
		(end 108.305092 -235.89742)
		(width 0.1143)
		(layer "In11.Cu")
		(net "P5E_CPU1_G1_TX_DP<3>")
	)
	(segment
		(start 108.304076 -234.2769)
		(end 108.305092 -234.277408)
		(width 0.1143)
		(layer "In11.Cu")
		(net "P5E_CPU1_G1_TX_DP<3>")
	)
	(segment
		(start 109.133132 -245.294404)
		(end 109.431074 -245.294404)
		(width 0.1143)
		(layer "In11.Cu")
		(net "P5E_CPU1_G1_TX_DP<3>")
	)
	(segment
		(start 108.272326 -227.778818)
		(end 108.304076 -227.797106)
		(width 0.1143)
		(layer "In11.Cu")
		(net "P5E_CPU1_G1_TX_DP<3>")
	)
	(segment
		(start 108.306616 -232.010204)
		(end 108.305092 -232.01122)
		(width 0.1143)
		(layer "In11.Cu")
		(net "P5E_CPU1_G1_TX_DP<3>")
	)
	(segment
		(start 108.310172 -243.348256)
		(end 108.307632 -243.34978)
		(width 0.1143)
		(layer "In11.Cu")
		(net "P5E_CPU1_G1_TX_DP<3>")
	)
	(segment
		(start 108.303314 -234.276392)
		(end 108.304076 -234.2769)
		(width 0.1143)
		(layer "In11.Cu")
		(net "P5E_CPU1_G1_TX_DP<3>")
	)
	(segment
		(start 108.272326 -234.258612)
		(end 108.299504 -234.27436)
		(width 0.1143)
		(layer "In11.Cu")
		(net "P5E_CPU1_G1_TX_DP<3>")
	)
	(segment
		(start 108.299504 -232.654348)
		(end 108.302044 -232.655618)
		(width 0.1143)
		(layer "In11.Cu")
		(net "P5E_CPU1_G1_TX_DP<3>")
	)
	(segment
		(start 107.402376 -223.889824)
		(end 107.367578 -223.90989)
		(width 0.1143)
		(layer "In11.Cu")
		(net "P5E_CPU1_G1_TX_DP<3>")
	)
	(segment
		(start 108.303314 -235.896404)
		(end 108.304076 -235.896912)
		(width 0.1143)
		(layer "In11.Cu")
		(net "P5E_CPU1_G1_TX_DP<3>")
	)
	(segment
		(start 108.307632 -241.729768)
		(end 108.306616 -241.730276)
		(width 0.1143)
		(layer "In11.Cu")
		(net "P5E_CPU1_G1_TX_DP<3>")
	)
	(segment
		(start 108.303314 -237.516416)
		(end 108.304076 -237.516924)
		(width 0.1143)
		(layer "In11.Cu")
		(net "P5E_CPU1_G1_TX_DP<3>")
	)
	(segment
		(start 108.343192 -233.60888)
		(end 108.310934 -233.627676)
		(width 0.1143)
		(layer "In11.Cu")
		(net "P5E_CPU1_G1_TX_DP<3>")
	)
	(segment
		(start 108.343192 -243.328952)
		(end 108.310934 -243.347748)
		(width 0.1143)
		(layer "In11.Cu")
		(net "P5E_CPU1_G1_TX_DP<3>")
	)
	(segment
		(start 109.050328 -245.2116)
		(end 109.133132 -245.294404)
		(width 0.1143)
		(layer "In11.Cu")
		(net "P5E_CPU1_G1_TX_DP<3>")
	)
	(segment
		(start 108.303314 -227.152454)
		(end 108.272326 -227.170234)
		(width 0.1143)
		(layer "In11.Cu")
		(net "P5E_CPU1_G1_TX_DP<3>")
	)
	(segment
		(start 107.64647 -221.613984)
		(end 107.64647 -221.804484)
		(width 0.1143)
		(layer "In11.Cu")
		(net "P5E_CPU1_G1_TX_DP<3>")
	)
	(segment
		(start 108.310934 -243.347748)
		(end 108.310172 -243.348256)
		(width 0.1143)
		(layer "In11.Cu")
		(net "P5E_CPU1_G1_TX_DP<3>")
	)
	(segment
		(start 108.30052 -226.175062)
		(end 108.303314 -226.176586)
		(width 0.1143)
		(layer "In11.Cu")
		(net "P5E_CPU1_G1_TX_DP<3>")
	)
	(segment
		(start 108.307632 -228.769926)
		(end 108.306616 -228.770434)
		(width 0.1143)
		(layer "In11.Cu")
		(net "P5E_CPU1_G1_TX_DP<3>")
	)
	(segment
		(start 108.305092 -228.77145)
		(end 108.304076 -228.771958)
		(width 0.1143)
		(layer "In11.Cu")
		(net "P5E_CPU1_G1_TX_DP<3>")
	)
	(segment
		(start 108.304076 -235.251752)
		(end 108.303314 -235.25226)
		(width 0.1143)
		(layer "In11.Cu")
		(net "P5E_CPU1_G1_TX_DP<3>")
	)
	(segment
		(start 108.342684 -229.43947)
		(end 108.343192 -229.439724)
		(width 0.1143)
		(layer "In11.Cu")
		(net "P5E_CPU1_G1_TX_DP<3>")
	)
	(segment
		(start 107.682538 -221.05493)
		(end 107.682538 -221.083378)
		(width 0.1143)
		(layer "In11.Cu")
		(net "P5E_CPU1_G1_TX_DP<3>")
	)
	(segment
		(start 107.682538 -215.397334)
		(end 107.682284 -215.397588)
		(width 0.14224)
		(layer "In11.Cu")
		(net "P5E_CPU1_G1_TX_DP<3>")
	)
	(segment
		(start 108.340398 -227.131118)
		(end 108.304076 -227.151946)
		(width 0.1143)
		(layer "In11.Cu")
		(net "P5E_CPU1_G1_TX_DP<3>")
	)
	(segment
		(start 108.305092 -226.177602)
		(end 108.306616 -226.178618)
		(width 0.1143)
		(layer "In11.Cu")
		(net "P5E_CPU1_G1_TX_DP<3>")
	)
	(segment
		(start 108.299504 -235.894372)
		(end 108.302044 -235.895642)
		(width 0.1143)
		(layer "In11.Cu")
		(net "P5E_CPU1_G1_TX_DP<3>")
	)
	(segment
		(start 108.270548 -229.397306)
		(end 108.304076 -229.416864)
		(width 0.1143)
		(layer "In11.Cu")
		(net "P5E_CPU1_G1_TX_DP<3>")
	)
	(segment
		(start 108.303314 -241.732308)
		(end 108.272326 -241.750088)
		(width 0.1143)
		(layer "In11.Cu")
		(net "P5E_CPU1_G1_TX_DP<3>")
	)
	(segment
		(start 108.305092 -234.277408)
		(end 108.343192 -234.29976)
		(width 0.1143)
		(layer "In11.Cu")
		(net "P5E_CPU1_G1_TX_DP<3>")
	)
	(segment
		(start 107.367578 -223.90989)
		(end 107.365292 -223.911414)
		(width 0.1143)
		(layer "In11.Cu")
		(net "P5E_CPU1_G1_TX_DP<3>")
	)
	(segment
		(start 108.310934 -240.107724)
		(end 108.310172 -240.108232)
		(width 0.1143)
		(layer "In11.Cu")
		(net "P5E_CPU1_G1_TX_DP<3>")
	)
	(segment
		(start 107.803442 -225.349308)
		(end 107.833922 -225.367088)
		(width 0.1143)
		(layer "In11.Cu")
		(net "P5E_CPU1_G1_TX_DP<3>")
	)
	(segment
		(start 154.033982 -171.501562)
		(end 150.542244 -176.413668)
		(width 0.14224)
		(layer "In11.Cu")
		(net "P5E_CPU1_G1_TX_DP<3>")
	)
	(segment
		(start 156.435298 -164.503862)
		(end 155.88615 -166.116508)
		(width 0.14224)
		(layer "In11.Cu")
		(net "P5E_CPU1_G1_TX_DP<3>")
	)
	(segment
		(start 108.307632 -233.629708)
		(end 108.306616 -233.630216)
		(width 0.1143)
		(layer "In11.Cu")
		(net "P5E_CPU1_G1_TX_DP<3>")
	)
	(segment
		(start 108.306616 -243.350288)
		(end 108.305092 -243.351304)
		(width 0.1143)
		(layer "In11.Cu")
		(net "P5E_CPU1_G1_TX_DP<3>")
	)
	(segment
		(start 108.302044 -242.37569)
		(end 108.303314 -242.376452)
		(width 0.1143)
		(layer "In11.Cu")
		(net "P5E_CPU1_G1_TX_DP<3>")
	)
	(arc
		(start 108.343192 -240.779808)
		(mid 108.586519 -241.244374)
		(end 108.343192 -241.70894)
		(width 0.1143)
		(layer "In11.Cu")
		(net "P5E_CPU1_G1_TX_DP<3>")
	)
	(arc
		(start 109.046518 -245.18874)
		(mid 109.048541 -245.20015)
		(end 109.050328 -245.2116)
		(width 0.1143)
		(layer "In11.Cu")
		(net "P5E_CPU1_G1_TX_DP<3>")
	)
	(arc
		(start 108.343192 -227.819966)
		(mid 108.586519 -228.284532)
		(end 108.343192 -228.749098)
		(width 0.1143)
		(layer "In11.Cu")
		(net "P5E_CPU1_G1_TX_DP<3>")
	)
	(arc
		(start 108.272326 -227.170234)
		(mid 108.116398 -227.474526)
		(end 108.272326 -227.778818)
		(width 0.1143)
		(layer "In11.Cu")
		(net "P5E_CPU1_G1_TX_DP<3>")
	)
	(arc
		(start 107.64647 -225.044508)
		(mid 107.688019 -225.21593)
		(end 107.803442 -225.349308)
		(width 0.1143)
		(layer "In11.Cu")
		(net "P5E_CPU1_G1_TX_DP<3>")
	)
	(arc
		(start 108.11637 -230.71455)
		(mid 108.157132 -230.884434)
		(end 108.270548 -231.017318)
		(width 0.1143)
		(layer "In11.Cu")
		(net "P5E_CPU1_G1_TX_DP<3>")
	)
	(arc
		(start 108.586524 -244.484398)
		(mid 108.628073 -244.65582)
		(end 108.743496 -244.789198)
		(width 0.1143)
		(layer "In11.Cu")
		(net "P5E_CPU1_G1_TX_DP<3>")
	)
	(arc
		(start 108.11637 -229.094538)
		(mid 108.157132 -229.264422)
		(end 108.270548 -229.397306)
		(width 0.1143)
		(layer "In11.Cu")
		(net "P5E_CPU1_G1_TX_DP<3>")
	)
	(arc
		(start 108.272326 -238.510064)
		(mid 108.116398 -238.814356)
		(end 108.272326 -239.118648)
		(width 0.1143)
		(layer "In11.Cu")
		(net "P5E_CPU1_G1_TX_DP<3>")
	)
	(arc
		(start 108.343192 -239.159796)
		(mid 108.586519 -239.624362)
		(end 108.343192 -240.088928)
		(width 0.1143)
		(layer "In11.Cu")
		(net "P5E_CPU1_G1_TX_DP<3>")
	)
	(arc
		(start 108.272326 -235.27004)
		(mid 108.116398 -235.574332)
		(end 108.272326 -235.878624)
		(width 0.1143)
		(layer "In11.Cu")
		(net "P5E_CPU1_G1_TX_DP<3>")
	)
	(arc
		(start 108.343192 -242.39982)
		(mid 108.586519 -242.864386)
		(end 108.343192 -243.328952)
		(width 0.1143)
		(layer "In11.Cu")
		(net "P5E_CPU1_G1_TX_DP<3>")
	)
	(arc
		(start 108.343192 -234.29976)
		(mid 108.586519 -234.764326)
		(end 108.343192 -235.228892)
		(width 0.1143)
		(layer "In11.Cu")
		(net "P5E_CPU1_G1_TX_DP<3>")
	)
	(arc
		(start 108.272326 -243.3701)
		(mid 108.116398 -243.674392)
		(end 108.272326 -243.978684)
		(width 0.1143)
		(layer "In11.Cu")
		(net "P5E_CPU1_G1_TX_DP<3>")
	)
	(arc
		(start 107.873038 -225.389948)
		(mid 108.051851 -225.592298)
		(end 108.11637 -225.854514)
		(width 0.1143)
		(layer "In11.Cu")
		(net "P5E_CPU1_G1_TX_DP<3>")
	)
	(arc
		(start 107.332526 -223.93021)
		(mid 107.219872 -224.059843)
		(end 107.176824 -224.22612)
		(width 0.1143)
		(layer "In11.Cu")
		(net "P5E_CPU1_G1_TX_DP<3>")
	)
	(arc
		(start 108.11637 -225.854514)
		(mid 108.157625 -226.025485)
		(end 108.272326 -226.158806)
		(width 0.1143)
		(layer "In11.Cu")
		(net "P5E_CPU1_G1_TX_DP<3>")
	)
	(arc
		(start 107.291632 -222.346266)
		(mid 107.183038 -222.641655)
		(end 107.332272 -222.918782)
		(width 0.1143)
		(layer "In11.Cu")
		(net "P5E_CPU1_G1_TX_DP<3>")
	)
	(arc
		(start 107.431586 -222.979996)
		(mid 107.659274 -223.424496)
		(end 107.431586 -223.868996)
		(width 0.1143)
		(layer "In11.Cu")
		(net "P5E_CPU1_G1_TX_DP<3>")
	)
	(arc
		(start 108.272326 -241.750088)
		(mid 108.116398 -242.05438)
		(end 108.272326 -242.358672)
		(width 0.1143)
		(layer "In11.Cu")
		(net "P5E_CPU1_G1_TX_DP<3>")
	)
	(arc
		(start 108.343192 -226.199954)
		(mid 108.586519 -226.66452)
		(end 108.343192 -227.129086)
		(width 0.1143)
		(layer "In11.Cu")
		(net "P5E_CPU1_G1_TX_DP<3>")
	)
	(arc
		(start 108.272326 -240.130076)
		(mid 108.116398 -240.434368)
		(end 108.272326 -240.73866)
		(width 0.1143)
		(layer "In11.Cu")
		(net "P5E_CPU1_G1_TX_DP<3>")
	)
	(arc
		(start 107.327192 -224.533714)
		(mid 107.330982 -224.536786)
		(end 107.334812 -224.53981)
		(width 0.1143)
		(layer "In11.Cu")
		(net "P5E_CPU1_G1_TX_DP<3>")
	)
	(arc
		(start 108.272326 -230.410258)
		(mid 108.15765 -230.543592)
		(end 108.11637 -230.71455)
		(width 0.1143)
		(layer "In11.Cu")
		(net "P5E_CPU1_G1_TX_DP<3>")
	)
	(arc
		(start 108.343192 -237.539784)
		(mid 108.586519 -238.00435)
		(end 108.343192 -238.468916)
		(width 0.1143)
		(layer "In11.Cu")
		(net "P5E_CPU1_G1_TX_DP<3>")
	)
	(arc
		(start 108.272326 -228.790246)
		(mid 108.15765 -228.92358)
		(end 108.11637 -229.094538)
		(width 0.1143)
		(layer "In11.Cu")
		(net "P5E_CPU1_G1_TX_DP<3>")
	)
	(arc
		(start 108.272326 -233.650028)
		(mid 108.116398 -233.95432)
		(end 108.272326 -234.258612)
		(width 0.1143)
		(layer "In11.Cu")
		(net "P5E_CPU1_G1_TX_DP<3>")
	)
	(arc
		(start 108.272326 -232.030016)
		(mid 108.116398 -232.334308)
		(end 108.272326 -232.6386)
		(width 0.1143)
		(layer "In11.Cu")
		(net "P5E_CPU1_G1_TX_DP<3>")
	)
	(arc
		(start 108.343192 -231.059736)
		(mid 108.586519 -231.524302)
		(end 108.343192 -231.988868)
		(width 0.1143)
		(layer "In11.Cu")
		(net "P5E_CPU1_G1_TX_DP<3>")
	)
	(arc
		(start 108.343192 -244.019832)
		(mid 108.522005 -244.222182)
		(end 108.586524 -244.484398)
		(width 0.1143)
		(layer "In11.Cu")
		(net "P5E_CPU1_G1_TX_DP<3>")
	)
	(arc
		(start 107.64647 -221.804484)
		(mid 107.581955 -222.066703)
		(end 107.403138 -222.26905)
		(width 0.1143)
		(layer "In11.Cu")
		(net "P5E_CPU1_G1_TX_DP<3>")
	)
	(arc
		(start 107.400598 -224.578164)
		(mid 107.58125 -224.780909)
		(end 107.64647 -225.044508)
		(width 0.1143)
		(layer "In11.Cu")
		(net "P5E_CPU1_G1_TX_DP<3>")
	)
	(arc
		(start 108.343192 -229.439724)
		(mid 108.522005 -229.642074)
		(end 108.586524 -229.90429)
		(width 0.1143)
		(layer "In11.Cu")
		(net "P5E_CPU1_G1_TX_DP<3>")
	)
	(arc
		(start 108.343192 -232.679748)
		(mid 108.586519 -233.144314)
		(end 108.343192 -233.60888)
		(width 0.1143)
		(layer "In11.Cu")
		(net "P5E_CPU1_G1_TX_DP<3>")
	)
	(arc
		(start 108.272326 -236.890052)
		(mid 108.116398 -237.194344)
		(end 108.272326 -237.498636)
		(width 0.1143)
		(layer "In11.Cu")
		(net "P5E_CPU1_G1_TX_DP<3>")
	)
	(arc
		(start 108.586524 -229.90429)
		(mid 108.521288 -230.167881)
		(end 108.340652 -230.370634)
		(width 0.1143)
		(layer "In11.Cu")
		(net "P5E_CPU1_G1_TX_DP<3>")
	)
	(arc
		(start 107.177586 -224.241106)
		(mid 107.228101 -224.399832)
		(end 107.327192 -224.533714)
		(width 0.1143)
		(layer "In11.Cu")
		(net "P5E_CPU1_G1_TX_DP<3>")
	)
	(arc
		(start 108.343192 -235.919772)
		(mid 108.586519 -236.384338)
		(end 108.343192 -236.848904)
		(width 0.1143)
		(layer "In11.Cu")
		(net "P5E_CPU1_G1_TX_DP<3>")
	)
	(arc
		(start 108.813092 -244.829838)
		(mid 108.965079 -244.986346)
		(end 109.046518 -245.18874)
		(width 0.1143)
		(layer "In11.Cu")
		(net "P5E_CPU1_G1_TX_DP<3>")
	)
	(segment
		(start 52.78882 -18.86585)
		(end 53.05933 -19.13636)
		(width 0.12954)
		(layer "F.Cu")
		(net "P5E_CPU1_G1_TX_DP<2>")
	)
	(segment
		(start 52.78882 -18.186146)
		(end 52.78882 -18.86585)
		(width 0.12954)
		(layer "F.Cu")
		(net "P5E_CPU1_G1_TX_DP<2>")
	)
	(segment
		(start 109.897926 -243.94033)
		(end 109.431074 -243.674392)
		(width 0.12954)
		(layer "F.Cu")
		(net "P5E_CPU1_G1_TX_DP<2>")
	)
	(segment
		(start 53.08473 -17.890236)
		(end 52.78882 -18.186146)
		(width 0.12954)
		(layer "F.Cu")
		(net "P5E_CPU1_G1_TX_DP<2>")
	)
	(segment
		(start 109.239558 -239.134396)
		(end 109.242098 -239.135666)
		(width 0.1143)
		(layer "In11.Cu")
		(net "P5E_CPU1_G1_TX_DP<2>")
	)
	(segment
		(start 109.243368 -227.796598)
		(end 109.24413 -227.797106)
		(width 0.1143)
		(layer "In11.Cu")
		(net "P5E_CPU1_G1_TX_DP<2>")
	)
	(segment
		(start 108.627164 -221.05493)
		(end 108.627164 -221.083378)
		(width 0.1143)
		(layer "In11.Cu")
		(net "P5E_CPU1_G1_TX_DP<2>")
	)
	(segment
		(start 109.242098 -240.113058)
		(end 109.21238 -240.130076)
		(width 0.1143)
		(layer "In11.Cu")
		(net "P5E_CPU1_G1_TX_DP<2>")
	)
	(segment
		(start 109.24413 -231.036876)
		(end 109.280452 -231.057958)
		(width 0.1143)
		(layer "In11.Cu")
		(net "P5E_CPU1_G1_TX_DP<2>")
	)
	(segment
		(start 109.238034 -232.653332)
		(end 109.239558 -232.654348)
		(width 0.1143)
		(layer "In11.Cu")
		(net "P5E_CPU1_G1_TX_DP<2>")
	)
	(segment
		(start 109.24413 -232.011728)
		(end 109.243368 -232.012236)
		(width 0.1143)
		(layer "In11.Cu")
		(net "P5E_CPU1_G1_TX_DP<2>")
	)
	(segment
		(start 57.005474 -48.34636)
		(end 58.888376 -51.811682)
		(width 0.14224)
		(layer "In11.Cu")
		(net "P5E_CPU1_G1_TX_DP<2>")
	)
	(segment
		(start 109.228636 -227.788216)
		(end 109.229652 -227.788724)
		(width 0.1143)
		(layer "In11.Cu")
		(net "P5E_CPU1_G1_TX_DP<2>")
	)
	(segment
		(start 109.282992 -242.399566)
		(end 109.310932 -242.419632)
		(width 0.1143)
		(layer "In11.Cu")
		(net "P5E_CPU1_G1_TX_DP<2>")
	)
	(segment
		(start 155.04668 -171.547282)
		(end 154.931872 -171.885102)
		(width 0.14224)
		(layer "In11.Cu")
		(net "P5E_CPU1_G1_TX_DP<2>")
	)
	(segment
		(start 109.238034 -242.373404)
		(end 109.239558 -242.37442)
		(width 0.1143)
		(layer "In11.Cu")
		(net "P5E_CPU1_G1_TX_DP<2>")
	)
	(segment
		(start 109.243368 -235.25226)
		(end 109.242098 -235.253022)
		(width 0.1143)
		(layer "In11.Cu")
		(net "P5E_CPU1_G1_TX_DP<2>")
	)
	(segment
		(start 109.246924 -242.378738)
		(end 109.282992 -242.399566)
		(width 0.1143)
		(layer "In11.Cu")
		(net "P5E_CPU1_G1_TX_DP<2>")
	)
	(segment
		(start 109.242098 -233.63301)
		(end 109.21238 -233.650028)
		(width 0.1143)
		(layer "In11.Cu")
		(net "P5E_CPU1_G1_TX_DP<2>")
	)
	(segment
		(start 109.24413 -227.151946)
		(end 109.21238 -227.170234)
		(width 0.1143)
		(layer "In11.Cu")
		(net "P5E_CPU1_G1_TX_DP<2>")
	)
	(segment
		(start 109.212126 -229.398322)
		(end 109.273086 -229.434136)
		(width 0.1143)
		(layer "In11.Cu")
		(net "P5E_CPU1_G1_TX_DP<2>")
	)
	(segment
		(start 109.242098 -237.515654)
		(end 109.243368 -237.516416)
		(width 0.1143)
		(layer "In11.Cu")
		(net "P5E_CPU1_G1_TX_DP<2>")
	)
	(segment
		(start 109.243368 -239.136428)
		(end 109.24413 -239.136936)
		(width 0.1143)
		(layer "In11.Cu")
		(net "P5E_CPU1_G1_TX_DP<2>")
	)
	(segment
		(start 109.24032 -227.79482)
		(end 109.24159 -227.795582)
		(width 0.1143)
		(layer "In11.Cu")
		(net "P5E_CPU1_G1_TX_DP<2>")
	)
	(segment
		(start 109.24413 -242.37696)
		(end 109.246924 -242.378738)
		(width 0.1143)
		(layer "In11.Cu")
		(net "P5E_CPU1_G1_TX_DP<2>")
	)
	(segment
		(start 109.282992 -240.779554)
		(end 109.308646 -240.797842)
		(width 0.1143)
		(layer "In11.Cu")
		(net "P5E_CPU1_G1_TX_DP<2>")
	)
	(segment
		(start 109.238034 -240.753392)
		(end 109.239558 -240.754408)
		(width 0.1143)
		(layer "In11.Cu")
		(net "P5E_CPU1_G1_TX_DP<2>")
	)
	(segment
		(start 109.280452 -238.470694)
		(end 109.24413 -238.491776)
		(width 0.1143)
		(layer "In11.Cu")
		(net "P5E_CPU1_G1_TX_DP<2>")
	)
	(segment
		(start 108.272326 -222.310198)
		(end 108.269278 -222.312484)
		(width 0.1143)
		(layer "In11.Cu")
		(net "P5E_CPU1_G1_TX_DP<2>")
	)
	(segment
		(start 109.245654 -243.350796)
		(end 109.243368 -243.35232)
		(width 0.1143)
		(layer "In11.Cu")
		(net "P5E_CPU1_G1_TX_DP<2>")
	)
	(segment
		(start 108.306616 -222.290386)
		(end 108.305092 -222.291402)
		(width 0.1143)
		(layer "In11.Cu")
		(net "P5E_CPU1_G1_TX_DP<2>")
	)
	(segment
		(start 109.24413 -237.516924)
		(end 109.280452 -237.538006)
		(width 0.1143)
		(layer "In11.Cu")
		(net "P5E_CPU1_G1_TX_DP<2>")
	)
	(segment
		(start 109.242098 -235.895642)
		(end 109.243368 -235.896404)
		(width 0.1143)
		(layer "In11.Cu")
		(net "P5E_CPU1_G1_TX_DP<2>")
	)
	(segment
		(start 108.581444 -221.61246)
		(end 108.585508 -221.787212)
		(width 0.1143)
		(layer "In11.Cu")
		(net "P5E_CPU1_G1_TX_DP<2>")
	)
	(segment
		(start 109.282992 -241.709194)
		(end 109.245654 -241.730784)
		(width 0.1143)
		(layer "In11.Cu")
		(net "P5E_CPU1_G1_TX_DP<2>")
	)
	(segment
		(start 108.300012 -224.55505)
		(end 108.30052 -224.555304)
		(width 0.1143)
		(layer "In11.Cu")
		(net "P5E_CPU1_G1_TX_DP<2>")
	)
	(segment
		(start 109.24413 -234.2769)
		(end 109.280452 -234.297982)
		(width 0.1143)
		(layer "In11.Cu")
		(net "P5E_CPU1_G1_TX_DP<2>")
	)
	(segment
		(start 109.242098 -239.135666)
		(end 109.243368 -239.136428)
		(width 0.1143)
		(layer "In11.Cu")
		(net "P5E_CPU1_G1_TX_DP<2>")
	)
	(segment
		(start 109.239558 -237.514384)
		(end 109.242098 -237.515654)
		(width 0.1143)
		(layer "In11.Cu")
		(net "P5E_CPU1_G1_TX_DP<2>")
	)
	(segment
		(start 108.269278 -222.916496)
		(end 108.272326 -222.918782)
		(width 0.1143)
		(layer "In11.Cu")
		(net "P5E_CPU1_G1_TX_DP<2>")
	)
	(segment
		(start 52.7685 -19.42719)
		(end 52.7685 -21.624798)
		(width 0.14224)
		(layer "In11.Cu")
		(net "P5E_CPU1_G1_TX_DP<2>")
	)
	(segment
		(start 109.229652 -227.788724)
		(end 109.230922 -227.789486)
		(width 0.1143)
		(layer "In11.Cu")
		(net "P5E_CPU1_G1_TX_DP<2>")
	)
	(segment
		(start 109.234986 -227.791772)
		(end 109.236764 -227.792788)
		(width 0.1143)
		(layer "In11.Cu")
		(net "P5E_CPU1_G1_TX_DP<2>")
	)
	(segment
		(start 108.627164 -221.083378)
		(end 108.581444 -221.129098)
		(width 0.1143)
		(layer "In11.Cu")
		(net "P5E_CPU1_G1_TX_DP<2>")
	)
	(segment
		(start 109.21238 -235.878624)
		(end 109.238034 -235.893356)
		(width 0.1143)
		(layer "In11.Cu")
		(net "P5E_CPU1_G1_TX_DP<2>")
	)
	(segment
		(start 109.242098 -236.873034)
		(end 109.21238 -236.890052)
		(width 0.1143)
		(layer "In11.Cu")
		(net "P5E_CPU1_G1_TX_DP<2>")
	)
	(segment
		(start 109.24413 -238.491776)
		(end 109.243368 -238.492284)
		(width 0.1143)
		(layer "In11.Cu")
		(net "P5E_CPU1_G1_TX_DP<2>")
	)
	(segment
		(start 108.344462 -223.8883)
		(end 108.344462 -223.888554)
		(width 0.1143)
		(layer "In11.Cu")
		(net "P5E_CPU1_G1_TX_DP<2>")
	)
	(segment
		(start 109.239558 -234.27436)
		(end 109.242098 -234.27563)
		(width 0.1143)
		(layer "In11.Cu")
		(net "P5E_CPU1_G1_TX_DP<2>")
	)
	(segment
		(start 109.21238 -242.358672)
		(end 109.238034 -242.373404)
		(width 0.1143)
		(layer "In11.Cu")
		(net "P5E_CPU1_G1_TX_DP<2>")
	)
	(segment
		(start 109.230922 -227.789486)
		(end 109.231938 -227.789994)
		(width 0.1143)
		(layer "In11.Cu")
		(net "P5E_CPU1_G1_TX_DP<2>")
	)
	(segment
		(start 108.34243 -223.889824)
		(end 108.274104 -223.929194)
		(width 0.1143)
		(layer "In11.Cu")
		(net "P5E_CPU1_G1_TX_DP<2>")
	)
	(segment
		(start 109.280452 -231.990646)
		(end 109.24413 -232.011728)
		(width 0.1143)
		(layer "In11.Cu")
		(net "P5E_CPU1_G1_TX_DP<2>")
	)
	(segment
		(start 109.237526 -227.793296)
		(end 109.238542 -227.793804)
		(width 0.1143)
		(layer "In11.Cu")
		(net "P5E_CPU1_G1_TX_DP<2>")
	)
	(segment
		(start 109.243368 -228.772466)
		(end 109.242098 -228.773228)
		(width 0.1143)
		(layer "In11.Cu")
		(net "P5E_CPU1_G1_TX_DP<2>")
	)
	(segment
		(start 109.246924 -235.89869)
		(end 109.282992 -235.919518)
		(width 0.1143)
		(layer "In11.Cu")
		(net "P5E_CPU1_G1_TX_DP<2>")
	)
	(segment
		(start 157.393894 -164.617908)
		(end 155.304236 -170.75404)
		(width 0.14224)
		(layer "In11.Cu")
		(net "P5E_CPU1_G1_TX_DP<2>")
	)
	(segment
		(start 108.58627 -225.042476)
		(end 108.58627 -225.044508)
		(width 0.1143)
		(layer "In11.Cu")
		(net "P5E_CPU1_G1_TX_DP<2>")
	)
	(segment
		(start 109.282992 -243.329206)
		(end 109.245654 -243.350796)
		(width 0.1143)
		(layer "In11.Cu")
		(net "P5E_CPU1_G1_TX_DP<2>")
	)
	(segment
		(start 109.243368 -232.65638)
		(end 109.24413 -232.656888)
		(width 0.1143)
		(layer "In11.Cu")
		(net "P5E_CPU1_G1_TX_DP<2>")
	)
	(segment
		(start 109.24413 -235.896912)
		(end 109.246924 -235.89869)
		(width 0.1143)
		(layer "In11.Cu")
		(net "P5E_CPU1_G1_TX_DP<2>")
	)
	(segment
		(start 109.24413 -232.656888)
		(end 109.280452 -232.67797)
		(width 0.1143)
		(layer "In11.Cu")
		(net "P5E_CPU1_G1_TX_DP<2>")
	)
	(segment
		(start 109.238034 -234.273344)
		(end 109.239558 -234.27436)
		(width 0.1143)
		(layer "In11.Cu")
		(net "P5E_CPU1_G1_TX_DP<2>")
	)
	(segment
		(start 108.304076 -222.93707)
		(end 108.344462 -222.960692)
		(width 0.1143)
		(layer "In11.Cu")
		(net "P5E_CPU1_G1_TX_DP<2>")
	)
	(segment
		(start 109.310932 -236.829092)
		(end 109.282992 -236.849158)
		(width 0.1143)
		(layer "In11.Cu")
		(net "P5E_CPU1_G1_TX_DP<2>")
	)
	(segment
		(start 109.239304 -226.1743)
		(end 109.24413 -226.177094)
		(width 0.1143)
		(layer "In11.Cu")
		(net "P5E_CPU1_G1_TX_DP<2>")
	)
	(segment
		(start 109.243368 -242.376452)
		(end 109.24413 -242.37696)
		(width 0.1143)
		(layer "In11.Cu")
		(net "P5E_CPU1_G1_TX_DP<2>")
	)
	(segment
		(start 151.288242 -177.00879)
		(end 112.846104 -208.529936)
		(width 0.14224)
		(layer "In11.Cu")
		(net "P5E_CPU1_G1_TX_DP<2>")
	)
	(segment
		(start 109.231938 -227.789994)
		(end 109.2327 -227.790502)
		(width 0.1143)
		(layer "In11.Cu")
		(net "P5E_CPU1_G1_TX_DP<2>")
	)
	(segment
		(start 108.274104 -223.929194)
		(end 108.272326 -223.930464)
		(width 0.1143)
		(layer "In11.Cu")
		(net "P5E_CPU1_G1_TX_DP<2>")
	)
	(segment
		(start 108.11637 -224.233232)
		(end 108.11637 -224.234502)
		(width 0.1143)
		(layer "In11.Cu")
		(net "P5E_CPU1_G1_TX_DP<2>")
	)
	(segment
		(start 109.238034 -237.513368)
		(end 109.239558 -237.514384)
		(width 0.1143)
		(layer "In11.Cu")
		(net "P5E_CPU1_G1_TX_DP<2>")
	)
	(segment
		(start 109.24413 -226.177094)
		(end 109.244892 -226.177602)
		(width 0.1143)
		(layer "In11.Cu")
		(net "P5E_CPU1_G1_TX_DP<2>")
	)
	(segment
		(start 109.21238 -240.73866)
		(end 109.238034 -240.753392)
		(width 0.1143)
		(layer "In11.Cu")
		(net "P5E_CPU1_G1_TX_DP<2>")
	)
	(segment
		(start 109.245654 -236.870748)
		(end 109.243368 -236.872272)
		(width 0.1143)
		(layer "In11.Cu")
		(net "P5E_CPU1_G1_TX_DP<2>")
	)
	(segment
		(start 109.237526 -226.173284)
		(end 109.238542 -226.173792)
		(width 0.1143)
		(layer "In11.Cu")
		(net "P5E_CPU1_G1_TX_DP<2>")
	)
	(segment
		(start 109.242098 -242.37569)
		(end 109.243368 -242.376452)
		(width 0.1143)
		(layer "In11.Cu")
		(net "P5E_CPU1_G1_TX_DP<2>")
	)
	(segment
		(start 109.24413 -233.63174)
		(end 109.243368 -233.632248)
		(width 0.1143)
		(layer "In11.Cu")
		(net "P5E_CPU1_G1_TX_DP<2>")
	)
	(segment
		(start 155.046934 -171.547282)
		(end 155.04668 -171.547282)
		(width 0.14224)
		(layer "In11.Cu")
		(net "P5E_CPU1_G1_TX_DP<2>")
	)
	(segment
		(start 109.282992 -235.919518)
		(end 109.310932 -235.939584)
		(width 0.1143)
		(layer "In11.Cu")
		(net "P5E_CPU1_G1_TX_DP<2>")
	)
	(segment
		(start 109.210348 -231.017318)
		(end 109.210602 -231.017318)
		(width 0.1143)
		(layer "In11.Cu")
		(net "P5E_CPU1_G1_TX_DP<2>")
	)
	(segment
		(start 109.242098 -238.493046)
		(end 109.21238 -238.510064)
		(width 0.1143)
		(layer "In11.Cu")
		(net "P5E_CPU1_G1_TX_DP<2>")
	)
	(segment
		(start 108.30052 -224.555304)
		(end 108.303314 -224.556574)
		(width 0.1143)
		(layer "In11.Cu")
		(net "P5E_CPU1_G1_TX_DP<2>")
	)
	(segment
		(start 109.24413 -235.251752)
		(end 109.243368 -235.25226)
		(width 0.1143)
		(layer "In11.Cu")
		(net "P5E_CPU1_G1_TX_DP<2>")
	)
	(segment
		(start 109.210602 -231.017318)
		(end 109.24413 -231.036876)
		(width 0.1143)
		(layer "In11.Cu")
		(net "P5E_CPU1_G1_TX_DP<2>")
	)
	(segment
		(start 109.24413 -239.136936)
		(end 109.280452 -239.158018)
		(width 0.1143)
		(layer "In11.Cu")
		(net "P5E_CPU1_G1_TX_DP<2>")
	)
	(segment
		(start 52.7685 -21.624798)
		(end 57.005474 -48.34636)
		(width 0.14224)
		(layer "In11.Cu")
		(net "P5E_CPU1_G1_TX_DP<2>")
	)
	(segment
		(start 108.581444 -221.129098)
		(end 108.581444 -221.61246)
		(width 0.1143)
		(layer "In11.Cu")
		(net "P5E_CPU1_G1_TX_DP<2>")
	)
	(segment
		(start 58.888376 -51.811682)
		(end 151.54783 -135.131302)
		(width 0.14224)
		(layer "In11.Cu")
		(net "P5E_CPU1_G1_TX_DP<2>")
	)
	(segment
		(start 109.246924 -240.758726)
		(end 109.282992 -240.779554)
		(width 0.1143)
		(layer "In11.Cu")
		(net "P5E_CPU1_G1_TX_DP<2>")
	)
	(segment
		(start 109.308646 -241.690906)
		(end 109.282992 -241.709194)
		(width 0.1143)
		(layer "In11.Cu")
		(net "P5E_CPU1_G1_TX_DP<2>")
	)
	(segment
		(start 154.931872 -171.885102)
		(end 151.288242 -177.00879)
		(width 0.14224)
		(layer "In11.Cu")
		(net "P5E_CPU1_G1_TX_DP<2>")
	)
	(segment
		(start 109.21238 -232.6386)
		(end 109.238034 -232.653332)
		(width 0.1143)
		(layer "In11.Cu")
		(net "P5E_CPU1_G1_TX_DP<2>")
	)
	(segment
		(start 112.846104 -208.529936)
		(end 108.627164 -215.635586)
		(width 0.14224)
		(layer "In11.Cu")
		(net "P5E_CPU1_G1_TX_DP<2>")
	)
	(segment
		(start 109.243368 -232.012236)
		(end 109.242098 -232.012998)
		(width 0.1143)
		(layer "In11.Cu")
		(net "P5E_CPU1_G1_TX_DP<2>")
	)
	(segment
		(start 109.245654 -241.730784)
		(end 109.243368 -241.732308)
		(width 0.1143)
		(layer "In11.Cu")
		(net "P5E_CPU1_G1_TX_DP<2>")
	)
	(segment
		(start 109.243368 -240.75644)
		(end 109.24413 -240.756948)
		(width 0.1143)
		(layer "In11.Cu")
		(net "P5E_CPU1_G1_TX_DP<2>")
	)
	(segment
		(start 156.496512 -145.364454)
		(end 157.393894 -159.7279)
		(width 0.14224)
		(layer "In11.Cu")
		(net "P5E_CPU1_G1_TX_DP<2>")
	)
	(segment
		(start 109.24413 -228.771958)
		(end 109.243368 -228.772466)
		(width 0.1143)
		(layer "In11.Cu")
		(net "P5E_CPU1_G1_TX_DP<2>")
	)
	(segment
		(start 108.343192 -222.26905)
		(end 108.306616 -222.290386)
		(width 0.1143)
		(layer "In11.Cu")
		(net "P5E_CPU1_G1_TX_DP<2>")
	)
	(segment
		(start 155.304236 -170.75404)
		(end 155.14955 -171.24553)
		(width 0.14224)
		(layer "In11.Cu")
		(net "P5E_CPU1_G1_TX_DP<2>")
	)
	(segment
		(start 109.238034 -239.13338)
		(end 109.239558 -239.134396)
		(width 0.1143)
		(layer "In11.Cu")
		(net "P5E_CPU1_G1_TX_DP<2>")
	)
	(segment
		(start 109.280452 -233.610658)
		(end 109.24413 -233.63174)
		(width 0.1143)
		(layer "In11.Cu")
		(net "P5E_CPU1_G1_TX_DP<2>")
	)
	(segment
		(start 109.239558 -232.654348)
		(end 109.242098 -232.655618)
		(width 0.1143)
		(layer "In11.Cu")
		(net "P5E_CPU1_G1_TX_DP<2>")
	)
	(segment
		(start 109.24413 -240.756948)
		(end 109.246924 -240.758726)
		(width 0.1143)
		(layer "In11.Cu")
		(net "P5E_CPU1_G1_TX_DP<2>")
	)
	(segment
		(start 109.24413 -227.797106)
		(end 109.244638 -227.797106)
		(width 0.1143)
		(layer "In11.Cu")
		(net "P5E_CPU1_G1_TX_DP<2>")
	)
	(segment
		(start 109.239558 -235.894372)
		(end 109.242098 -235.895642)
		(width 0.1143)
		(layer "In11.Cu")
		(net "P5E_CPU1_G1_TX_DP<2>")
	)
	(segment
		(start 109.24413 -240.111788)
		(end 109.243368 -240.112296)
		(width 0.1143)
		(layer "In11.Cu")
		(net "P5E_CPU1_G1_TX_DP<2>")
	)
	(segment
		(start 109.243368 -237.516416)
		(end 109.24413 -237.516924)
		(width 0.1143)
		(layer "In11.Cu")
		(net "P5E_CPU1_G1_TX_DP<2>")
	)
	(segment
		(start 109.210602 -229.397306)
		(end 109.212126 -229.398322)
		(width 0.1143)
		(layer "In11.Cu")
		(net "P5E_CPU1_G1_TX_DP<2>")
	)
	(segment
		(start 109.21238 -227.778818)
		(end 109.228636 -227.788216)
		(width 0.1143)
		(layer "In11.Cu")
		(net "P5E_CPU1_G1_TX_DP<2>")
	)
	(segment
		(start 109.243368 -236.872272)
		(end 109.242098 -236.873034)
		(width 0.1143)
		(layer "In11.Cu")
		(net "P5E_CPU1_G1_TX_DP<2>")
	)
	(segment
		(start 109.21238 -239.118648)
		(end 109.238034 -239.13338)
		(width 0.1143)
		(layer "In11.Cu")
		(net "P5E_CPU1_G1_TX_DP<2>")
	)
	(segment
		(start 109.280452 -240.090706)
		(end 109.24413 -240.111788)
		(width 0.1143)
		(layer "In11.Cu")
		(net "P5E_CPU1_G1_TX_DP<2>")
	)
	(segment
		(start 108.74248 -225.348546)
		(end 108.813092 -225.389948)
		(width 0.1143)
		(layer "In11.Cu")
		(net "P5E_CPU1_G1_TX_DP<2>")
	)
	(segment
		(start 109.242098 -241.73307)
		(end 109.21238 -241.750088)
		(width 0.1143)
		(layer "In11.Cu")
		(net "P5E_CPU1_G1_TX_DP<2>")
	)
	(segment
		(start 109.398562 -229.54615)
		(end 109.398562 -229.546404)
		(width 0.1143)
		(layer "In11.Cu")
		(net "P5E_CPU1_G1_TX_DP<2>")
	)
	(segment
		(start 109.242098 -243.353082)
		(end 109.21238 -243.3701)
		(width 0.1143)
		(layer "In11.Cu")
		(net "P5E_CPU1_G1_TX_DP<2>")
	)
	(segment
		(start 108.342938 -224.579688)
		(end 108.35259 -224.586546)
		(width 0.1143)
		(layer "In11.Cu")
		(net "P5E_CPU1_G1_TX_DP<2>")
	)
	(segment
		(start 109.242098 -234.27563)
		(end 109.243368 -234.276392)
		(width 0.1143)
		(layer "In11.Cu")
		(net "P5E_CPU1_G1_TX_DP<2>")
	)
	(segment
		(start 108.272326 -222.918782)
		(end 108.304076 -222.93707)
		(width 0.1143)
		(layer "In11.Cu")
		(net "P5E_CPU1_G1_TX_DP<2>")
	)
	(segment
		(start 109.242098 -235.253022)
		(end 109.21238 -235.27004)
		(width 0.1143)
		(layer "In11.Cu")
		(net "P5E_CPU1_G1_TX_DP<2>")
	)
	(segment
		(start 109.282992 -236.849158)
		(end 109.245654 -236.870748)
		(width 0.1143)
		(layer "In11.Cu")
		(net "P5E_CPU1_G1_TX_DP<2>")
	)
	(segment
		(start 108.3056 -224.558098)
		(end 108.342938 -224.579688)
		(width 0.1143)
		(layer "In11.Cu")
		(net "P5E_CPU1_G1_TX_DP<2>")
	)
	(segment
		(start 108.627164 -215.635586)
		(end 108.627164 -221.05493)
		(width 0.14224)
		(layer "In11.Cu")
		(net "P5E_CPU1_G1_TX_DP<2>")
	)
	(segment
		(start 53.05933 -19.13636)
		(end 52.7685 -19.42719)
		(width 0.14224)
		(layer "In11.Cu")
		(net "P5E_CPU1_G1_TX_DP<2>")
	)
	(segment
		(start 109.239558 -240.754408)
		(end 109.242098 -240.755678)
		(width 0.1143)
		(layer "In11.Cu")
		(net "P5E_CPU1_G1_TX_DP<2>")
	)
	(segment
		(start 108.305092 -222.291402)
		(end 108.304076 -222.29191)
		(width 0.1143)
		(layer "In11.Cu")
		(net "P5E_CPU1_G1_TX_DP<2>")
	)
	(segment
		(start 155.14955 -171.24553)
		(end 155.046934 -171.547282)
		(width 0.14224)
		(layer "In11.Cu")
		(net "P5E_CPU1_G1_TX_DP<2>")
	)
	(segment
		(start 109.243368 -240.112296)
		(end 109.242098 -240.113058)
		(width 0.1143)
		(layer "In11.Cu")
		(net "P5E_CPU1_G1_TX_DP<2>")
	)
	(segment
		(start 109.24159 -227.795582)
		(end 109.242352 -227.79609)
		(width 0.1143)
		(layer "In11.Cu")
		(net "P5E_CPU1_G1_TX_DP<2>")
	)
	(segment
		(start 109.242098 -232.655618)
		(end 109.243368 -232.65638)
		(width 0.1143)
		(layer "In11.Cu")
		(net "P5E_CPU1_G1_TX_DP<2>")
	)
	(segment
		(start 109.289596 -230.365554)
		(end 109.214158 -230.409242)
		(width 0.1143)
		(layer "In11.Cu")
		(net "P5E_CPU1_G1_TX_DP<2>")
	)
	(segment
		(start 109.243368 -243.35232)
		(end 109.242098 -243.353082)
		(width 0.1143)
		(layer "In11.Cu")
		(net "P5E_CPU1_G1_TX_DP<2>")
	)
	(segment
		(start 109.244638 -228.771958)
		(end 109.24413 -228.771958)
		(width 0.1143)
		(layer "In11.Cu")
		(net "P5E_CPU1_G1_TX_DP<2>")
	)
	(segment
		(start 109.243368 -233.632248)
		(end 109.242098 -233.63301)
		(width 0.1143)
		(layer "In11.Cu")
		(net "P5E_CPU1_G1_TX_DP<2>")
	)
	(segment
		(start 151.54783 -135.131302)
		(end 156.496512 -145.364454)
		(width 0.14224)
		(layer "In11.Cu")
		(net "P5E_CPU1_G1_TX_DP<2>")
	)
	(segment
		(start 109.21238 -226.158806)
		(end 109.237526 -226.173284)
		(width 0.1143)
		(layer "In11.Cu")
		(net "P5E_CPU1_G1_TX_DP<2>")
	)
	(segment
		(start 109.243368 -234.276392)
		(end 109.24413 -234.2769)
		(width 0.1143)
		(layer "In11.Cu")
		(net "P5E_CPU1_G1_TX_DP<2>")
	)
	(segment
		(start 109.21238 -237.498636)
		(end 109.238034 -237.513368)
		(width 0.1143)
		(layer "In11.Cu")
		(net "P5E_CPU1_G1_TX_DP<2>")
	)
	(segment
		(start 109.239558 -242.37442)
		(end 109.242098 -242.37569)
		(width 0.1143)
		(layer "In11.Cu")
		(net "P5E_CPU1_G1_TX_DP<2>")
	)
	(segment
		(start 109.242098 -228.773228)
		(end 109.21238 -228.790246)
		(width 0.1143)
		(layer "In11.Cu")
		(net "P5E_CPU1_G1_TX_DP<2>")
	)
	(segment
		(start 109.243368 -238.492284)
		(end 109.242098 -238.493046)
		(width 0.1143)
		(layer "In11.Cu")
		(net "P5E_CPU1_G1_TX_DP<2>")
	)
	(segment
		(start 109.243368 -241.732308)
		(end 109.242098 -241.73307)
		(width 0.1143)
		(layer "In11.Cu")
		(net "P5E_CPU1_G1_TX_DP<2>")
	)
	(segment
		(start 109.242098 -240.755678)
		(end 109.243368 -240.75644)
		(width 0.1143)
		(layer "In11.Cu")
		(net "P5E_CPU1_G1_TX_DP<2>")
	)
	(segment
		(start 157.393894 -159.7279)
		(end 157.393894 -164.617908)
		(width 0.14224)
		(layer "In11.Cu")
		(net "P5E_CPU1_G1_TX_DP<2>")
	)
	(segment
		(start 109.242098 -232.012998)
		(end 109.21238 -232.030016)
		(width 0.1143)
		(layer "In11.Cu")
		(net "P5E_CPU1_G1_TX_DP<2>")
	)
	(segment
		(start 109.234224 -227.791264)
		(end 109.234986 -227.791772)
		(width 0.1143)
		(layer "In11.Cu")
		(net "P5E_CPU1_G1_TX_DP<2>")
	)
	(segment
		(start 109.2327 -227.790502)
		(end 109.234224 -227.791264)
		(width 0.1143)
		(layer "In11.Cu")
		(net "P5E_CPU1_G1_TX_DP<2>")
	)
	(segment
		(start 108.304076 -222.29191)
		(end 108.272326 -222.310198)
		(width 0.1143)
		(layer "In11.Cu")
		(net "P5E_CPU1_G1_TX_DP<2>")
	)
	(segment
		(start 109.238034 -235.893356)
		(end 109.239558 -235.894372)
		(width 0.1143)
		(layer "In11.Cu")
		(net "P5E_CPU1_G1_TX_DP<2>")
	)
	(segment
		(start 109.242352 -227.79609)
		(end 109.243368 -227.796598)
		(width 0.1143)
		(layer "In11.Cu")
		(net "P5E_CPU1_G1_TX_DP<2>")
	)
	(segment
		(start 109.280452 -235.23067)
		(end 109.24413 -235.251752)
		(width 0.1143)
		(layer "In11.Cu")
		(net "P5E_CPU1_G1_TX_DP<2>")
	)
	(segment
		(start 109.238542 -227.793804)
		(end 109.24032 -227.79482)
		(width 0.1143)
		(layer "In11.Cu")
		(net "P5E_CPU1_G1_TX_DP<2>")
	)
	(segment
		(start 109.243368 -235.896404)
		(end 109.24413 -235.896912)
		(width 0.1143)
		(layer "In11.Cu")
		(net "P5E_CPU1_G1_TX_DP<2>")
	)
	(segment
		(start 109.236764 -227.792788)
		(end 109.237526 -227.793296)
		(width 0.1143)
		(layer "In11.Cu")
		(net "P5E_CPU1_G1_TX_DP<2>")
	)
	(segment
		(start 109.244892 -227.151438)
		(end 109.24413 -227.151946)
		(width 0.1143)
		(layer "In11.Cu")
		(net "P5E_CPU1_G1_TX_DP<2>")
	)
	(segment
		(start 109.063282 -243.604542)
		(end 109.133132 -243.674392)
		(width 0.1143)
		(layer "In11.Cu")
		(net "P5E_CPU1_G1_TX_DP<2>")
	)
	(segment
		(start 109.21238 -234.258612)
		(end 109.238034 -234.273344)
		(width 0.1143)
		(layer "In11.Cu")
		(net "P5E_CPU1_G1_TX_DP<2>")
	)
	(segment
		(start 108.303314 -224.556574)
		(end 108.3056 -224.558098)
		(width 0.1143)
		(layer "In11.Cu")
		(net "P5E_CPU1_G1_TX_DP<2>")
	)
	(segment
		(start 109.238542 -226.173792)
		(end 109.239304 -226.1743)
		(width 0.1143)
		(layer "In11.Cu")
		(net "P5E_CPU1_G1_TX_DP<2>")
	)
	(segment
		(start 108.116624 -224.2312)
		(end 108.11637 -224.233232)
		(width 0.1143)
		(layer "In11.Cu")
		(net "P5E_CPU1_G1_TX_DP<2>")
	)
	(segment
		(start 109.133132 -243.674392)
		(end 109.431074 -243.674392)
		(width 0.1143)
		(layer "In11.Cu")
		(net "P5E_CPU1_G1_TX_DP<2>")
	)
	(segment
		(start 109.310932 -243.30914)
		(end 109.282992 -243.329206)
		(width 0.1143)
		(layer "In11.Cu")
		(net "P5E_CPU1_G1_TX_DP<2>")
	)
	(arc
		(start 108.344462 -222.960692)
		(mid 108.522527 -223.162869)
		(end 108.586778 -223.424496)
		(width 0.1143)
		(layer "In11.Cu")
		(net "P5E_CPU1_G1_TX_DP<2>")
	)
	(arc
		(start 109.294676 -240.0808)
		(mid 109.287602 -240.085807)
		(end 109.280452 -240.090706)
		(width 0.1143)
		(layer "In11.Cu")
		(net "P5E_CPU1_G1_TX_DP<2>")
	)
	(arc
		(start 108.585508 -221.787212)
		(mid 108.563551 -221.964212)
		(end 108.486956 -222.125286)
		(width 0.1143)
		(layer "In11.Cu")
		(net "P5E_CPU1_G1_TX_DP<2>")
	)
	(arc
		(start 109.294676 -237.547912)
		(mid 109.522059 -238.00435)
		(end 109.294676 -238.460788)
		(width 0.1143)
		(layer "In11.Cu")
		(net "P5E_CPU1_G1_TX_DP<2>")
	)
	(arc
		(start 108.586778 -223.424496)
		(mid 108.522485 -223.686101)
		(end 108.344462 -223.8883)
		(width 0.1143)
		(layer "In11.Cu")
		(net "P5E_CPU1_G1_TX_DP<2>")
	)
	(arc
		(start 109.296708 -234.309412)
		(mid 109.519592 -234.764326)
		(end 109.296708 -235.21924)
		(width 0.1143)
		(layer "In11.Cu")
		(net "P5E_CPU1_G1_TX_DP<2>")
	)
	(arc
		(start 109.296708 -231.979216)
		(mid 109.28863 -231.985002)
		(end 109.280452 -231.990646)
		(width 0.1143)
		(layer "In11.Cu")
		(net "P5E_CPU1_G1_TX_DP<2>")
	)
	(arc
		(start 109.21238 -228.790246)
		(mid 109.097704 -228.92358)
		(end 109.056424 -229.094538)
		(width 0.1143)
		(layer "In11.Cu")
		(net "P5E_CPU1_G1_TX_DP<2>")
	)
	(arc
		(start 109.21238 -233.650028)
		(mid 109.056452 -233.95432)
		(end 109.21238 -234.258612)
		(width 0.1143)
		(layer "In11.Cu")
		(net "P5E_CPU1_G1_TX_DP<2>")
	)
	(arc
		(start 109.21238 -235.27004)
		(mid 109.056452 -235.574332)
		(end 109.21238 -235.878624)
		(width 0.1143)
		(layer "In11.Cu")
		(net "P5E_CPU1_G1_TX_DP<2>")
	)
	(arc
		(start 109.310932 -235.939584)
		(mid 109.538932 -236.384338)
		(end 109.310932 -236.829092)
		(width 0.1143)
		(layer "In11.Cu")
		(net "P5E_CPU1_G1_TX_DP<2>")
	)
	(arc
		(start 109.294676 -239.167924)
		(mid 109.522059 -239.624362)
		(end 109.294676 -240.0808)
		(width 0.1143)
		(layer "In11.Cu")
		(net "P5E_CPU1_G1_TX_DP<2>")
	)
	(arc
		(start 109.21238 -241.750088)
		(mid 109.056452 -242.05438)
		(end 109.21238 -242.358672)
		(width 0.1143)
		(layer "In11.Cu")
		(net "P5E_CPU1_G1_TX_DP<2>")
	)
	(arc
		(start 108.813092 -225.389948)
		(mid 108.991905 -225.592298)
		(end 109.056424 -225.854514)
		(width 0.1143)
		(layer "In11.Cu")
		(net "P5E_CPU1_G1_TX_DP<2>")
	)
	(arc
		(start 109.526324 -231.530906)
		(mid 109.461452 -231.780648)
		(end 109.296708 -231.979216)
		(width 0.1143)
		(layer "In11.Cu")
		(net "P5E_CPU1_G1_TX_DP<2>")
	)
	(arc
		(start 109.244638 -227.797106)
		(mid 109.525285 -228.284532)
		(end 109.244638 -228.771958)
		(width 0.1143)
		(layer "In11.Cu")
		(net "P5E_CPU1_G1_TX_DP<2>")
	)
	(arc
		(start 108.11637 -224.234502)
		(mid 108.165531 -224.419218)
		(end 108.300012 -224.55505)
		(width 0.1143)
		(layer "In11.Cu")
		(net "P5E_CPU1_G1_TX_DP<2>")
	)
	(arc
		(start 109.280452 -231.057958)
		(mid 109.461104 -231.260703)
		(end 109.526324 -231.524302)
		(width 0.1143)
		(layer "In11.Cu")
		(net "P5E_CPU1_G1_TX_DP<2>")
	)
	(arc
		(start 109.280452 -237.538006)
		(mid 109.287601 -237.542906)
		(end 109.294676 -237.547912)
		(width 0.1143)
		(layer "In11.Cu")
		(net "P5E_CPU1_G1_TX_DP<2>")
	)
	(arc
		(start 109.21238 -240.130076)
		(mid 109.056452 -240.434368)
		(end 109.21238 -240.73866)
		(width 0.1143)
		(layer "In11.Cu")
		(net "P5E_CPU1_G1_TX_DP<2>")
	)
	(arc
		(start 109.214158 -230.409242)
		(mid 109.056454 -230.712262)
		(end 109.210348 -231.017318)
		(width 0.1143)
		(layer "In11.Cu")
		(net "P5E_CPU1_G1_TX_DP<2>")
	)
	(arc
		(start 109.308646 -240.797842)
		(mid 109.537666 -241.244374)
		(end 109.308646 -241.690906)
		(width 0.1143)
		(layer "In11.Cu")
		(net "P5E_CPU1_G1_TX_DP<2>")
	)
	(arc
		(start 109.244892 -226.177602)
		(mid 109.525226 -226.66452)
		(end 109.244892 -227.151438)
		(width 0.1143)
		(layer "In11.Cu")
		(net "P5E_CPU1_G1_TX_DP<2>")
	)
	(arc
		(start 109.296708 -233.599228)
		(mid 109.28863 -233.605014)
		(end 109.280452 -233.610658)
		(width 0.1143)
		(layer "In11.Cu")
		(net "P5E_CPU1_G1_TX_DP<2>")
	)
	(arc
		(start 109.273086 -229.434136)
		(mid 109.341397 -229.483899)
		(end 109.398562 -229.54615)
		(width 0.1143)
		(layer "In11.Cu")
		(net "P5E_CPU1_G1_TX_DP<2>")
	)
	(arc
		(start 108.272326 -223.930464)
		(mid 108.161821 -224.06393)
		(end 108.116624 -224.2312)
		(width 0.1143)
		(layer "In11.Cu")
		(net "P5E_CPU1_G1_TX_DP<2>")
	)
	(arc
		(start 108.35259 -224.586546)
		(mid 108.524455 -224.78631)
		(end 108.58627 -225.042476)
		(width 0.1143)
		(layer "In11.Cu")
		(net "P5E_CPU1_G1_TX_DP<2>")
	)
	(arc
		(start 109.056424 -229.094538)
		(mid 109.097186 -229.264422)
		(end 109.210602 -229.397306)
		(width 0.1143)
		(layer "In11.Cu")
		(net "P5E_CPU1_G1_TX_DP<2>")
	)
	(arc
		(start 109.21238 -238.510064)
		(mid 109.056452 -238.814356)
		(end 109.21238 -239.118648)
		(width 0.1143)
		(layer "In11.Cu")
		(net "P5E_CPU1_G1_TX_DP<2>")
	)
	(arc
		(start 109.398562 -229.546404)
		(mid 109.491432 -229.722505)
		(end 109.5248 -229.918768)
		(width 0.1143)
		(layer "In11.Cu")
		(net "P5E_CPU1_G1_TX_DP<2>")
	)
	(arc
		(start 109.21238 -232.030016)
		(mid 109.056452 -232.334308)
		(end 109.21238 -232.6386)
		(width 0.1143)
		(layer "In11.Cu")
		(net "P5E_CPU1_G1_TX_DP<2>")
	)
	(arc
		(start 109.21238 -243.3701)
		(mid 109.115245 -243.472969)
		(end 109.063282 -243.604542)
		(width 0.1143)
		(layer "In11.Cu")
		(net "P5E_CPU1_G1_TX_DP<2>")
	)
	(arc
		(start 109.526324 -231.524302)
		(mid 109.526334 -231.527604)
		(end 109.526324 -231.530906)
		(width 0.1143)
		(layer "In11.Cu")
		(net "P5E_CPU1_G1_TX_DP<2>")
	)
	(arc
		(start 109.310932 -242.419632)
		(mid 109.538932 -242.864386)
		(end 109.310932 -243.30914)
		(width 0.1143)
		(layer "In11.Cu")
		(net "P5E_CPU1_G1_TX_DP<2>")
	)
	(arc
		(start 109.294676 -238.460788)
		(mid 109.287602 -238.465795)
		(end 109.280452 -238.470694)
		(width 0.1143)
		(layer "In11.Cu")
		(net "P5E_CPU1_G1_TX_DP<2>")
	)
	(arc
		(start 109.056424 -225.854514)
		(mid 109.097679 -226.025485)
		(end 109.21238 -226.158806)
		(width 0.1143)
		(layer "In11.Cu")
		(net "P5E_CPU1_G1_TX_DP<2>")
	)
	(arc
		(start 109.5248 -229.918768)
		(mid 109.449069 -230.164201)
		(end 109.289596 -230.365554)
		(width 0.1143)
		(layer "In11.Cu")
		(net "P5E_CPU1_G1_TX_DP<2>")
	)
	(arc
		(start 108.486956 -222.125286)
		(mid 108.421591 -222.203685)
		(end 108.343192 -222.26905)
		(width 0.1143)
		(layer "In11.Cu")
		(net "P5E_CPU1_G1_TX_DP<2>")
	)
	(arc
		(start 109.21238 -236.890052)
		(mid 109.056452 -237.194344)
		(end 109.21238 -237.498636)
		(width 0.1143)
		(layer "In11.Cu")
		(net "P5E_CPU1_G1_TX_DP<2>")
	)
	(arc
		(start 109.280452 -239.158018)
		(mid 109.287601 -239.162918)
		(end 109.294676 -239.167924)
		(width 0.1143)
		(layer "In11.Cu")
		(net "P5E_CPU1_G1_TX_DP<2>")
	)
	(arc
		(start 108.344462 -223.888554)
		(mid 108.343447 -223.88919)
		(end 108.34243 -223.889824)
		(width 0.1143)
		(layer "In11.Cu")
		(net "P5E_CPU1_G1_TX_DP<2>")
	)
	(arc
		(start 109.280452 -232.67797)
		(mid 109.28863 -232.683613)
		(end 109.296708 -232.6894)
		(width 0.1143)
		(layer "In11.Cu")
		(net "P5E_CPU1_G1_TX_DP<2>")
	)
	(arc
		(start 108.269278 -222.312484)
		(mid 108.114466 -222.61449)
		(end 108.269278 -222.916496)
		(width 0.1143)
		(layer "In11.Cu")
		(net "P5E_CPU1_G1_TX_DP<2>")
	)
	(arc
		(start 109.280452 -234.297982)
		(mid 109.28863 -234.303625)
		(end 109.296708 -234.309412)
		(width 0.1143)
		(layer "In11.Cu")
		(net "P5E_CPU1_G1_TX_DP<2>")
	)
	(arc
		(start 108.58627 -225.044508)
		(mid 108.627668 -225.215382)
		(end 108.74248 -225.348546)
		(width 0.1143)
		(layer "In11.Cu")
		(net "P5E_CPU1_G1_TX_DP<2>")
	)
	(arc
		(start 109.296708 -232.6894)
		(mid 109.519592 -233.144314)
		(end 109.296708 -233.599228)
		(width 0.1143)
		(layer "In11.Cu")
		(net "P5E_CPU1_G1_TX_DP<2>")
	)
	(arc
		(start 109.296708 -235.21924)
		(mid 109.28863 -235.225026)
		(end 109.280452 -235.23067)
		(width 0.1143)
		(layer "In11.Cu")
		(net "P5E_CPU1_G1_TX_DP<2>")
	)
	(arc
		(start 109.21238 -227.170234)
		(mid 109.056452 -227.474526)
		(end 109.21238 -227.778818)
		(width 0.1143)
		(layer "In11.Cu")
		(net "P5E_CPU1_G1_TX_DP<2>")
	)
	(segment
		(start 55.58282 -16.662146)
		(end 55.58282 -17.343628)
		(width 0.12954)
		(layer "F.Cu")
		(net "P5E_CPU1_G1_TX_DP<1>")
	)
	(segment
		(start 109.897926 -247.180354)
		(end 109.431074 -246.914416)
		(width 0.12954)
		(layer "F.Cu")
		(net "P5E_CPU1_G1_TX_DP<1>")
	)
	(segment
		(start 55.58282 -17.343628)
		(end 55.852314 -17.613122)
		(width 0.12954)
		(layer "F.Cu")
		(net "P5E_CPU1_G1_TX_DP<1>")
	)
	(segment
		(start 55.87873 -16.366236)
		(end 55.58282 -16.662146)
		(width 0.12954)
		(layer "F.Cu")
		(net "P5E_CPU1_G1_TX_DP<1>")
	)
	(segment
		(start 154.866594 -139.840208)
		(end 157.42031 -145.121884)
		(width 0.14224)
		(layer "In11.Cu")
		(net "P5E_CPU1_G1_TX_DP<1>")
	)
	(segment
		(start 110.236254 -233.599736)
		(end 110.226348 -233.607102)
		(width 0.1143)
		(layer "In11.Cu")
		(net "P5E_CPU1_G1_TX_DP<1>")
	)
	(segment
		(start 110.15345 -239.119156)
		(end 110.226348 -239.161574)
		(width 0.1143)
		(layer "In11.Cu")
		(net "P5E_CPU1_G1_TX_DP<1>")
	)
	(segment
		(start 110.236254 -240.079784)
		(end 110.226348 -240.08715)
		(width 0.1143)
		(layer "In11.Cu")
		(net "P5E_CPU1_G1_TX_DP<1>")
	)
	(segment
		(start 110.18393 -228.771958)
		(end 110.15345 -228.789738)
		(width 0.1143)
		(layer "In11.Cu")
		(net "P5E_CPU1_G1_TX_DP<1>")
	)
	(segment
		(start 155.771088 -172.3136)
		(end 155.770834 -172.3136)
		(width 0.14224)
		(layer "In11.Cu")
		(net "P5E_CPU1_G1_TX_DP<1>")
	)
	(segment
		(start 110.232952 -243.32184)
		(end 110.223046 -243.328952)
		(width 0.1143)
		(layer "In11.Cu")
		(net "P5E_CPU1_G1_TX_DP<1>")
	)
	(segment
		(start 158.3309 -159.698436)
		(end 158.3309 -164.797994)
		(width 0.14224)
		(layer "In11.Cu")
		(net "P5E_CPU1_G1_TX_DP<1>")
	)
	(segment
		(start 109.71403 -225.367088)
		(end 109.753146 -225.389948)
		(width 0.1143)
		(layer "In11.Cu")
		(net "P5E_CPU1_G1_TX_DP<1>")
	)
	(segment
		(start 158.3309 -164.797994)
		(end 155.771088 -172.3136)
		(width 0.14224)
		(layer "In11.Cu")
		(net "P5E_CPU1_G1_TX_DP<1>")
	)
	(segment
		(start 110.18393 -232.011728)
		(end 110.15345 -232.029508)
		(width 0.1143)
		(layer "In11.Cu")
		(net "P5E_CPU1_G1_TX_DP<1>")
	)
	(segment
		(start 110.224062 -241.708432)
		(end 110.15345 -241.74958)
		(width 0.1143)
		(layer "In11.Cu")
		(net "P5E_CPU1_G1_TX_DP<1>")
	)
	(segment
		(start 110.236254 -238.459772)
		(end 110.226348 -238.467138)
		(width 0.1143)
		(layer "In11.Cu")
		(net "P5E_CPU1_G1_TX_DP<1>")
	)
	(segment
		(start 110.15345 -235.269786)
		(end 110.15345 -235.269532)
		(width 0.1143)
		(layer "In11.Cu")
		(net "P5E_CPU1_G1_TX_DP<1>")
	)
	(segment
		(start 109.063282 -246.844566)
		(end 109.133132 -246.914416)
		(width 0.1143)
		(layer "In11.Cu")
		(net "P5E_CPU1_G1_TX_DP<1>")
	)
	(segment
		(start 110.15345 -242.35918)
		(end 110.224062 -242.400074)
		(width 0.1143)
		(layer "In11.Cu")
		(net "P5E_CPU1_G1_TX_DP<1>")
	)
	(segment
		(start 109.239812 -224.554542)
		(end 109.240574 -224.55505)
		(width 0.1143)
		(layer "In11.Cu")
		(net "P5E_CPU1_G1_TX_DP<1>")
	)
	(segment
		(start 110.15345 -227.779326)
		(end 110.18393 -227.797106)
		(width 0.1143)
		(layer "In11.Cu")
		(net "P5E_CPU1_G1_TX_DP<1>")
	)
	(segment
		(start 110.236254 -235.219748)
		(end 110.226348 -235.227114)
		(width 0.1143)
		(layer "In11.Cu")
		(net "P5E_CPU1_G1_TX_DP<1>")
	)
	(segment
		(start 55.852314 -17.613122)
		(end 55.561484 -17.903952)
		(width 0.14224)
		(layer "In11.Cu")
		(net "P5E_CPU1_G1_TX_DP<1>")
	)
	(segment
		(start 110.463838 -229.875334)
		(end 110.465616 -229.888542)
		(width 0.1143)
		(layer "In11.Cu")
		(net "P5E_CPU1_G1_TX_DP<1>")
	)
	(segment
		(start 109.572044 -221.083378)
		(end 109.526324 -221.129098)
		(width 0.1143)
		(layer "In11.Cu")
		(net "P5E_CPU1_G1_TX_DP<1>")
	)
	(segment
		(start 110.18393 -226.177094)
		(end 110.220252 -226.198176)
		(width 0.1143)
		(layer "In11.Cu")
		(net "P5E_CPU1_G1_TX_DP<1>")
	)
	(segment
		(start 109.237526 -224.553272)
		(end 109.238288 -224.55378)
		(width 0.1143)
		(layer "In11.Cu")
		(net "P5E_CPU1_G1_TX_DP<1>")
	)
	(segment
		(start 110.226348 -234.301538)
		(end 110.236254 -234.308904)
		(width 0.1143)
		(layer "In11.Cu")
		(net "P5E_CPU1_G1_TX_DP<1>")
	)
	(segment
		(start 110.15345 -243.369846)
		(end 110.15345 -243.369592)
		(width 0.1143)
		(layer "In11.Cu")
		(net "P5E_CPU1_G1_TX_DP<1>")
	)
	(segment
		(start 55.561484 -24.402288)
		(end 58.00344 -47.971202)
		(width 0.14224)
		(layer "In11.Cu")
		(net "P5E_CPU1_G1_TX_DP<1>")
	)
	(segment
		(start 110.226348 -232.681526)
		(end 110.236254 -232.688892)
		(width 0.1143)
		(layer "In11.Cu")
		(net "P5E_CPU1_G1_TX_DP<1>")
	)
	(segment
		(start 110.226348 -238.467138)
		(end 110.15345 -238.50981)
		(width 0.1143)
		(layer "In11.Cu")
		(net "P5E_CPU1_G1_TX_DP<1>")
	)
	(segment
		(start 110.18393 -231.036876)
		(end 110.223046 -231.059736)
		(width 0.1143)
		(layer "In11.Cu")
		(net "P5E_CPU1_G1_TX_DP<1>")
	)
	(segment
		(start 110.226348 -233.607102)
		(end 110.15345 -233.649774)
		(width 0.1143)
		(layer "In11.Cu")
		(net "P5E_CPU1_G1_TX_DP<1>")
	)
	(segment
		(start 110.15345 -240.129822)
		(end 110.15345 -240.129568)
		(width 0.1143)
		(layer "In11.Cu")
		(net "P5E_CPU1_G1_TX_DP<1>")
	)
	(segment
		(start 110.465616 -229.888542)
		(end 110.465616 -229.896924)
		(width 0.1143)
		(layer "In11.Cu")
		(net "P5E_CPU1_G1_TX_DP<1>")
	)
	(segment
		(start 152.31237 -134.558024)
		(end 154.866086 -139.839954)
		(width 0.14224)
		(layer "In11.Cu")
		(net "P5E_CPU1_G1_TX_DP<1>")
	)
	(segment
		(start 109.526324 -221.30893)
		(end 109.52734 -221.309946)
		(width 0.1143)
		(layer "In11.Cu")
		(net "P5E_CPU1_G1_TX_DP<1>")
	)
	(segment
		(start 110.18393 -227.151946)
		(end 110.15345 -227.169726)
		(width 0.1143)
		(layer "In11.Cu")
		(net "P5E_CPU1_G1_TX_DP<1>")
	)
	(segment
		(start 110.226348 -235.92155)
		(end 110.236254 -235.928916)
		(width 0.1143)
		(layer "In11.Cu")
		(net "P5E_CPU1_G1_TX_DP<1>")
	)
	(segment
		(start 109.133132 -246.914416)
		(end 109.431074 -246.914416)
		(width 0.1143)
		(layer "In11.Cu")
		(net "P5E_CPU1_G1_TX_DP<1>")
	)
	(segment
		(start 109.282738 -223.88957)
		(end 109.210856 -223.93148)
		(width 0.1143)
		(layer "In11.Cu")
		(net "P5E_CPU1_G1_TX_DP<1>")
	)
	(segment
		(start 109.526324 -221.129098)
		(end 109.526324 -221.30893)
		(width 0.1143)
		(layer "In11.Cu")
		(net "P5E_CPU1_G1_TX_DP<1>")
	)
	(segment
		(start 155.667964 -172.593254)
		(end 152.206198 -177.461926)
		(width 0.14224)
		(layer "In11.Cu")
		(net "P5E_CPU1_G1_TX_DP<1>")
	)
	(segment
		(start 55.561484 -17.903952)
		(end 55.561484 -24.402288)
		(width 0.14224)
		(layer "In11.Cu")
		(net "P5E_CPU1_G1_TX_DP<1>")
	)
	(segment
		(start 110.15345 -235.879132)
		(end 110.226348 -235.92155)
		(width 0.1143)
		(layer "In11.Cu")
		(net "P5E_CPU1_G1_TX_DP<1>")
	)
	(segment
		(start 109.572044 -215.963754)
		(end 109.572044 -221.05493)
		(width 0.14224)
		(layer "In11.Cu")
		(net "P5E_CPU1_G1_TX_DP<1>")
	)
	(segment
		(start 110.15345 -232.639108)
		(end 110.226348 -232.681526)
		(width 0.1143)
		(layer "In11.Cu")
		(net "P5E_CPU1_G1_TX_DP<1>")
	)
	(segment
		(start 109.24667 -224.558606)
		(end 109.283246 -224.579942)
		(width 0.1143)
		(layer "In11.Cu")
		(net "P5E_CPU1_G1_TX_DP<1>")
	)
	(segment
		(start 113.671604 -209.058764)
		(end 109.572044 -215.963754)
		(width 0.14224)
		(layer "In11.Cu")
		(net "P5E_CPU1_G1_TX_DP<1>")
	)
	(segment
		(start 110.466124 -229.90429)
		(end 110.466378 -229.90429)
		(width 0.1143)
		(layer "In11.Cu")
		(net "P5E_CPU1_G1_TX_DP<1>")
	)
	(segment
		(start 152.206198 -177.461926)
		(end 113.671604 -209.058764)
		(width 0.14224)
		(layer "In11.Cu")
		(net "P5E_CPU1_G1_TX_DP<1>")
	)
	(segment
		(start 155.770834 -172.3136)
		(end 155.667964 -172.593254)
		(width 0.14224)
		(layer "In11.Cu")
		(net "P5E_CPU1_G1_TX_DP<1>")
	)
	(segment
		(start 109.52734 -221.804484)
		(end 109.525054 -223.42856)
		(width 0.1143)
		(layer "In11.Cu")
		(net "P5E_CPU1_G1_TX_DP<1>")
	)
	(segment
		(start 109.572044 -221.05493)
		(end 109.572044 -221.083378)
		(width 0.1143)
		(layer "In11.Cu")
		(net "P5E_CPU1_G1_TX_DP<1>")
	)
	(segment
		(start 109.246416 -246.590312)
		(end 109.243622 -246.59209)
		(width 0.1143)
		(layer "In11.Cu")
		(net "P5E_CPU1_G1_TX_DP<1>")
	)
	(segment
		(start 110.223046 -231.988868)
		(end 110.18393 -232.011728)
		(width 0.1143)
		(layer "In11.Cu")
		(net "P5E_CPU1_G1_TX_DP<1>")
	)
	(segment
		(start 109.71403 -244.161818)
		(end 109.68228 -244.180106)
		(width 0.1143)
		(layer "In11.Cu")
		(net "P5E_CPU1_G1_TX_DP<1>")
	)
	(segment
		(start 110.18393 -240.756948)
		(end 110.224062 -240.780316)
		(width 0.1143)
		(layer "In11.Cu")
		(net "P5E_CPU1_G1_TX_DP<1>")
	)
	(segment
		(start 109.238288 -224.55378)
		(end 109.239812 -224.554542)
		(width 0.1143)
		(layer "In11.Cu")
		(net "P5E_CPU1_G1_TX_DP<1>")
	)
	(segment
		(start 110.226348 -235.227114)
		(end 110.15345 -235.269786)
		(width 0.1143)
		(layer "In11.Cu")
		(net "P5E_CPU1_G1_TX_DP<1>")
	)
	(segment
		(start 109.52734 -221.309946)
		(end 109.52734 -221.804484)
		(width 0.1143)
		(layer "In11.Cu")
		(net "P5E_CPU1_G1_TX_DP<1>")
	)
	(segment
		(start 110.15345 -238.50981)
		(end 110.15345 -238.509556)
		(width 0.1143)
		(layer "In11.Cu")
		(net "P5E_CPU1_G1_TX_DP<1>")
	)
	(segment
		(start 110.236254 -236.83976)
		(end 110.226348 -236.847126)
		(width 0.1143)
		(layer "In11.Cu")
		(net "P5E_CPU1_G1_TX_DP<1>")
	)
	(segment
		(start 110.220506 -230.370634)
		(end 110.15345 -230.40975)
		(width 0.1143)
		(layer "In11.Cu")
		(net "P5E_CPU1_G1_TX_DP<1>")
	)
	(segment
		(start 110.151418 -229.398068)
		(end 110.185708 -229.41788)
		(width 0.1143)
		(layer "In11.Cu")
		(net "P5E_CPU1_G1_TX_DP<1>")
	)
	(segment
		(start 109.240574 -224.55505)
		(end 109.243368 -224.556574)
		(width 0.1143)
		(layer "In11.Cu")
		(net "P5E_CPU1_G1_TX_DP<1>")
	)
	(segment
		(start 109.245146 -224.55759)
		(end 109.24667 -224.558606)
		(width 0.1143)
		(layer "In11.Cu")
		(net "P5E_CPU1_G1_TX_DP<1>")
	)
	(segment
		(start 110.226348 -236.847126)
		(end 110.15345 -236.889798)
		(width 0.1143)
		(layer "In11.Cu")
		(net "P5E_CPU1_G1_TX_DP<1>")
	)
	(segment
		(start 110.15345 -240.739168)
		(end 110.18393 -240.756948)
		(width 0.1143)
		(layer "In11.Cu")
		(net "P5E_CPU1_G1_TX_DP<1>")
	)
	(segment
		(start 110.15345 -236.889798)
		(end 110.15345 -236.889544)
		(width 0.1143)
		(layer "In11.Cu")
		(net "P5E_CPU1_G1_TX_DP<1>")
	)
	(segment
		(start 109.753146 -244.138958)
		(end 109.71403 -244.161818)
		(width 0.1143)
		(layer "In11.Cu")
		(net "P5E_CPU1_G1_TX_DP<1>")
	)
	(segment
		(start 157.42031 -145.121884)
		(end 158.3309 -159.698436)
		(width 0.14224)
		(layer "In11.Cu")
		(net "P5E_CPU1_G1_TX_DP<1>")
	)
	(segment
		(start 109.753146 -245.75897)
		(end 109.709966 -245.784116)
		(width 0.1143)
		(layer "In11.Cu")
		(net "P5E_CPU1_G1_TX_DP<1>")
	)
	(segment
		(start 154.866086 -139.839954)
		(end 154.866594 -139.840208)
		(width 0.14224)
		(layer "In11.Cu")
		(net "P5E_CPU1_G1_TX_DP<1>")
	)
	(segment
		(start 109.24413 -224.557082)
		(end 109.245146 -224.55759)
		(width 0.1143)
		(layer "In11.Cu")
		(net "P5E_CPU1_G1_TX_DP<1>")
	)
	(segment
		(start 110.465616 -229.896924)
		(end 110.466124 -229.90429)
		(width 0.1143)
		(layer "In11.Cu")
		(net "P5E_CPU1_G1_TX_DP<1>")
	)
	(segment
		(start 110.151418 -231.01808)
		(end 110.18393 -231.036876)
		(width 0.1143)
		(layer "In11.Cu")
		(net "P5E_CPU1_G1_TX_DP<1>")
	)
	(segment
		(start 110.220252 -227.130864)
		(end 110.18393 -227.151946)
		(width 0.1143)
		(layer "In11.Cu")
		(net "P5E_CPU1_G1_TX_DP<1>")
	)
	(segment
		(start 110.15345 -237.499144)
		(end 110.226348 -237.541562)
		(width 0.1143)
		(layer "In11.Cu")
		(net "P5E_CPU1_G1_TX_DP<1>")
	)
	(segment
		(start 109.68228 -244.180106)
		(end 109.672628 -244.187218)
		(width 0.1143)
		(layer "In11.Cu")
		(net "P5E_CPU1_G1_TX_DP<1>")
	)
	(segment
		(start 110.220252 -228.750876)
		(end 110.18393 -228.771958)
		(width 0.1143)
		(layer "In11.Cu")
		(net "P5E_CPU1_G1_TX_DP<1>")
	)
	(segment
		(start 109.23651 -224.552764)
		(end 109.237526 -224.553272)
		(width 0.1143)
		(layer "In11.Cu")
		(net "P5E_CPU1_G1_TX_DP<1>")
	)
	(segment
		(start 110.15345 -226.159314)
		(end 110.18393 -226.177094)
		(width 0.1143)
		(layer "In11.Cu")
		(net "P5E_CPU1_G1_TX_DP<1>")
	)
	(segment
		(start 109.68228 -244.78869)
		(end 109.753146 -244.829838)
		(width 0.1143)
		(layer "In11.Cu")
		(net "P5E_CPU1_G1_TX_DP<1>")
	)
	(segment
		(start 110.185708 -229.41788)
		(end 110.219236 -229.437438)
		(width 0.1143)
		(layer "In11.Cu")
		(net "P5E_CPU1_G1_TX_DP<1>")
	)
	(segment
		(start 110.15345 -234.25912)
		(end 110.226348 -234.301538)
		(width 0.1143)
		(layer "In11.Cu")
		(net "P5E_CPU1_G1_TX_DP<1>")
	)
	(segment
		(start 109.672628 -244.781578)
		(end 109.68228 -244.78869)
		(width 0.1143)
		(layer "In11.Cu")
		(net "P5E_CPU1_G1_TX_DP<1>")
	)
	(segment
		(start 110.223046 -243.328952)
		(end 110.15345 -243.369846)
		(width 0.1143)
		(layer "In11.Cu")
		(net "P5E_CPU1_G1_TX_DP<1>")
	)
	(segment
		(start 109.68355 -225.349308)
		(end 109.71403 -225.367088)
		(width 0.1143)
		(layer "In11.Cu")
		(net "P5E_CPU1_G1_TX_DP<1>")
	)
	(segment
		(start 110.226348 -240.08715)
		(end 110.15345 -240.129822)
		(width 0.1143)
		(layer "In11.Cu")
		(net "P5E_CPU1_G1_TX_DP<1>")
	)
	(segment
		(start 110.226348 -239.161574)
		(end 110.236254 -239.16894)
		(width 0.1143)
		(layer "In11.Cu")
		(net "P5E_CPU1_G1_TX_DP<1>")
	)
	(segment
		(start 110.226348 -237.541562)
		(end 110.236254 -237.548928)
		(width 0.1143)
		(layer "In11.Cu")
		(net "P5E_CPU1_G1_TX_DP<1>")
	)
	(segment
		(start 110.15345 -233.649774)
		(end 110.15345 -233.64952)
		(width 0.1143)
		(layer "In11.Cu")
		(net "P5E_CPU1_G1_TX_DP<1>")
	)
	(segment
		(start 109.21238 -224.538794)
		(end 109.23651 -224.552764)
		(width 0.1143)
		(layer "In11.Cu")
		(net "P5E_CPU1_G1_TX_DP<1>")
	)
	(segment
		(start 110.18393 -227.797106)
		(end 110.220252 -227.818188)
		(width 0.1143)
		(layer "In11.Cu")
		(net "P5E_CPU1_G1_TX_DP<1>")
	)
	(segment
		(start 109.243368 -224.556574)
		(end 109.24413 -224.557082)
		(width 0.1143)
		(layer "In11.Cu")
		(net "P5E_CPU1_G1_TX_DP<1>")
	)
	(segment
		(start 58.00344 -47.971202)
		(end 59.676284 -51.257454)
		(width 0.14224)
		(layer "In11.Cu")
		(net "P5E_CPU1_G1_TX_DP<1>")
	)
	(segment
		(start 59.676284 -51.257454)
		(end 152.31237 -134.558024)
		(width 0.14224)
		(layer "In11.Cu")
		(net "P5E_CPU1_G1_TX_DP<1>")
	)
	(segment
		(start 109.243622 -246.59209)
		(end 109.21238 -246.610378)
		(width 0.1143)
		(layer "In11.Cu")
		(net "P5E_CPU1_G1_TX_DP<1>")
	)
	(arc
		(start 110.15345 -235.269532)
		(mid 109.996473 -235.574332)
		(end 110.15345 -235.879132)
		(width 0.1143)
		(layer "In11.Cu")
		(net "P5E_CPU1_G1_TX_DP<1>")
	)
	(arc
		(start 109.525054 -223.42856)
		(mid 109.460634 -223.688899)
		(end 109.282738 -223.88957)
		(width 0.1143)
		(layer "In11.Cu")
		(net "P5E_CPU1_G1_TX_DP<1>")
	)
	(arc
		(start 110.466378 -242.864386)
		(mid 110.465884 -242.888792)
		(end 110.464346 -242.913154)
		(width 0.1143)
		(layer "In11.Cu")
		(net "P5E_CPU1_G1_TX_DP<1>")
	)
	(arc
		(start 109.996478 -230.71455)
		(mid 110.037444 -230.884956)
		(end 110.151418 -231.01808)
		(width 0.1143)
		(layer "In11.Cu")
		(net "P5E_CPU1_G1_TX_DP<1>")
	)
	(arc
		(start 110.220252 -227.818188)
		(mid 110.466142 -228.284532)
		(end 110.220252 -228.750876)
		(width 0.1143)
		(layer "In11.Cu")
		(net "P5E_CPU1_G1_TX_DP<1>")
	)
	(arc
		(start 110.15345 -233.64952)
		(mid 109.996473 -233.95432)
		(end 110.15345 -234.25912)
		(width 0.1143)
		(layer "In11.Cu")
		(net "P5E_CPU1_G1_TX_DP<1>")
	)
	(arc
		(start 109.996478 -243.674392)
		(mid 109.931963 -243.936611)
		(end 109.753146 -244.138958)
		(width 0.1143)
		(layer "In11.Cu")
		(net "P5E_CPU1_G1_TX_DP<1>")
	)
	(arc
		(start 110.224062 -240.780316)
		(mid 110.49032 -241.244374)
		(end 110.224062 -241.708432)
		(width 0.1143)
		(layer "In11.Cu")
		(net "P5E_CPU1_G1_TX_DP<1>")
	)
	(arc
		(start 110.236254 -235.928916)
		(mid 110.467853 -236.384338)
		(end 110.236254 -236.83976)
		(width 0.1143)
		(layer "In11.Cu")
		(net "P5E_CPU1_G1_TX_DP<1>")
	)
	(arc
		(start 109.283246 -224.579942)
		(mid 109.462059 -224.782292)
		(end 109.526578 -225.044508)
		(width 0.1143)
		(layer "In11.Cu")
		(net "P5E_CPU1_G1_TX_DP<1>")
	)
	(arc
		(start 109.709966 -245.784116)
		(mid 109.578085 -245.918412)
		(end 109.52988 -246.100346)
		(width 0.1143)
		(layer "In11.Cu")
		(net "P5E_CPU1_G1_TX_DP<1>")
	)
	(arc
		(start 110.15345 -241.74958)
		(mid 109.996473 -242.05438)
		(end 110.15345 -242.35918)
		(width 0.1143)
		(layer "In11.Cu")
		(net "P5E_CPU1_G1_TX_DP<1>")
	)
	(arc
		(start 110.15345 -238.509556)
		(mid 109.996473 -238.814356)
		(end 110.15345 -239.119156)
		(width 0.1143)
		(layer "In11.Cu")
		(net "P5E_CPU1_G1_TX_DP<1>")
	)
	(arc
		(start 110.223046 -231.059736)
		(mid 110.466373 -231.524302)
		(end 110.223046 -231.988868)
		(width 0.1143)
		(layer "In11.Cu")
		(net "P5E_CPU1_G1_TX_DP<1>")
	)
	(arc
		(start 109.21238 -246.610378)
		(mid 109.181533 -246.635117)
		(end 109.153452 -246.662956)
		(width 0.1143)
		(layer "In11.Cu")
		(net "P5E_CPU1_G1_TX_DP<1>")
	)
	(arc
		(start 110.219236 -229.437438)
		(mid 110.235192 -229.449102)
		(end 110.250732 -229.461314)
		(width 0.1143)
		(layer "In11.Cu")
		(net "P5E_CPU1_G1_TX_DP<1>")
	)
	(arc
		(start 109.753146 -244.829838)
		(mid 109.996473 -245.294404)
		(end 109.753146 -245.75897)
		(width 0.1143)
		(layer "In11.Cu")
		(net "P5E_CPU1_G1_TX_DP<1>")
	)
	(arc
		(start 110.250732 -229.461314)
		(mid 110.392255 -229.650327)
		(end 110.463838 -229.875334)
		(width 0.1143)
		(layer "In11.Cu")
		(net "P5E_CPU1_G1_TX_DP<1>")
	)
	(arc
		(start 110.236254 -237.548928)
		(mid 110.467853 -238.00435)
		(end 110.236254 -238.459772)
		(width 0.1143)
		(layer "In11.Cu")
		(net "P5E_CPU1_G1_TX_DP<1>")
	)
	(arc
		(start 109.753146 -225.389948)
		(mid 109.931959 -225.592298)
		(end 109.996478 -225.854514)
		(width 0.1143)
		(layer "In11.Cu")
		(net "P5E_CPU1_G1_TX_DP<1>")
	)
	(arc
		(start 110.15345 -240.129568)
		(mid 109.996473 -240.434368)
		(end 110.15345 -240.739168)
		(width 0.1143)
		(layer "In11.Cu")
		(net "P5E_CPU1_G1_TX_DP<1>")
	)
	(arc
		(start 110.220252 -226.198176)
		(mid 110.466142 -226.66452)
		(end 110.220252 -227.130864)
		(width 0.1143)
		(layer "In11.Cu")
		(net "P5E_CPU1_G1_TX_DP<1>")
	)
	(arc
		(start 110.224062 -242.400074)
		(mid 110.402244 -242.602477)
		(end 110.466378 -242.864386)
		(width 0.1143)
		(layer "In11.Cu")
		(net "P5E_CPU1_G1_TX_DP<1>")
	)
	(arc
		(start 110.15345 -232.029508)
		(mid 109.996473 -232.334308)
		(end 110.15345 -232.639108)
		(width 0.1143)
		(layer "In11.Cu")
		(net "P5E_CPU1_G1_TX_DP<1>")
	)
	(arc
		(start 110.236254 -239.16894)
		(mid 110.467853 -239.624362)
		(end 110.236254 -240.079784)
		(width 0.1143)
		(layer "In11.Cu")
		(net "P5E_CPU1_G1_TX_DP<1>")
	)
	(arc
		(start 109.210856 -223.93148)
		(mid 109.056484 -224.235491)
		(end 109.21238 -224.538794)
		(width 0.1143)
		(layer "In11.Cu")
		(net "P5E_CPU1_G1_TX_DP<1>")
	)
	(arc
		(start 110.464346 -242.913154)
		(mid 110.39374 -243.143044)
		(end 110.232952 -243.32184)
		(width 0.1143)
		(layer "In11.Cu")
		(net "P5E_CPU1_G1_TX_DP<1>")
	)
	(arc
		(start 110.466378 -229.90429)
		(mid 110.401142 -230.167881)
		(end 110.220506 -230.370634)
		(width 0.1143)
		(layer "In11.Cu")
		(net "P5E_CPU1_G1_TX_DP<1>")
	)
	(arc
		(start 109.996478 -229.094538)
		(mid 110.037444 -229.264944)
		(end 110.151418 -229.398068)
		(width 0.1143)
		(layer "In11.Cu")
		(net "P5E_CPU1_G1_TX_DP<1>")
	)
	(arc
		(start 110.15345 -243.369592)
		(mid 110.038023 -243.502968)
		(end 109.996478 -243.674392)
		(width 0.1143)
		(layer "In11.Cu")
		(net "P5E_CPU1_G1_TX_DP<1>")
	)
	(arc
		(start 109.526578 -225.044508)
		(mid 109.568127 -225.21593)
		(end 109.68355 -225.349308)
		(width 0.1143)
		(layer "In11.Cu")
		(net "P5E_CPU1_G1_TX_DP<1>")
	)
	(arc
		(start 109.153452 -246.662956)
		(mid 109.095833 -246.74754)
		(end 109.063282 -246.844566)
		(width 0.1143)
		(layer "In11.Cu")
		(net "P5E_CPU1_G1_TX_DP<1>")
	)
	(arc
		(start 110.15345 -227.169726)
		(mid 109.996473 -227.474526)
		(end 110.15345 -227.779326)
		(width 0.1143)
		(layer "In11.Cu")
		(net "P5E_CPU1_G1_TX_DP<1>")
	)
	(arc
		(start 110.15345 -236.889544)
		(mid 109.996473 -237.194344)
		(end 110.15345 -237.499144)
		(width 0.1143)
		(layer "In11.Cu")
		(net "P5E_CPU1_G1_TX_DP<1>")
	)
	(arc
		(start 109.52988 -246.100346)
		(mid 109.453905 -246.383369)
		(end 109.246416 -246.590312)
		(width 0.1143)
		(layer "In11.Cu")
		(net "P5E_CPU1_G1_TX_DP<1>")
	)
	(arc
		(start 110.15345 -230.40975)
		(mid 110.038023 -230.543126)
		(end 109.996478 -230.71455)
		(width 0.1143)
		(layer "In11.Cu")
		(net "P5E_CPU1_G1_TX_DP<1>")
	)
	(arc
		(start 109.672628 -244.187218)
		(mid 109.52036 -244.484398)
		(end 109.672628 -244.781578)
		(width 0.1143)
		(layer "In11.Cu")
		(net "P5E_CPU1_G1_TX_DP<1>")
	)
	(arc
		(start 109.996478 -225.854514)
		(mid 110.038027 -226.025936)
		(end 110.15345 -226.159314)
		(width 0.1143)
		(layer "In11.Cu")
		(net "P5E_CPU1_G1_TX_DP<1>")
	)
	(arc
		(start 110.15345 -228.789738)
		(mid 110.038023 -228.923114)
		(end 109.996478 -229.094538)
		(width 0.1143)
		(layer "In11.Cu")
		(net "P5E_CPU1_G1_TX_DP<1>")
	)
	(arc
		(start 110.236254 -234.308904)
		(mid 110.467853 -234.764326)
		(end 110.236254 -235.219748)
		(width 0.1143)
		(layer "In11.Cu")
		(net "P5E_CPU1_G1_TX_DP<1>")
	)
	(arc
		(start 110.236254 -232.688892)
		(mid 110.467853 -233.144314)
		(end 110.236254 -233.599736)
		(width 0.1143)
		(layer "In11.Cu")
		(net "P5E_CPU1_G1_TX_DP<1>")
	)
	(segment
		(start 16.422878 -16.366236)
		(end 16.126968 -16.662146)
		(width 0.12954)
		(layer "F.Cu")
		(net "P5E_CPU1_G1_TX_DP<15>")
	)
	(segment
		(start 99.08794 -246.370348)
		(end 98.621088 -246.10441)
		(width 0.12954)
		(layer "F.Cu")
		(net "P5E_CPU1_G1_TX_DP<15>")
	)
	(segment
		(start 16.126968 -16.662146)
		(end 16.126968 -17.34185)
		(width 0.12954)
		(layer "F.Cu")
		(net "P5E_CPU1_G1_TX_DP<15>")
	)
	(segment
		(start 16.126968 -17.34185)
		(end 16.397478 -17.61236)
		(width 0.12954)
		(layer "F.Cu")
		(net "P5E_CPU1_G1_TX_DP<15>")
	)
	(segment
		(start 96.993456 -240.739168)
		(end 97.023936 -240.756948)
		(width 0.1143)
		(layer "In11.Cu")
		(net "P5E_CPU1_G1_TX_DP<15>")
	)
	(segment
		(start 96.555052 -225.367596)
		(end 96.556576 -225.368612)
		(width 0.1143)
		(layer "In11.Cu")
		(net "P5E_CPU1_G1_TX_DP<15>")
	)
	(segment
		(start 97.023936 -231.036876)
		(end 97.063052 -231.059736)
		(width 0.1143)
		(layer "In11.Cu")
		(net "P5E_CPU1_G1_TX_DP<15>")
	)
	(segment
		(start 96.546924 -225.363024)
		(end 96.54794 -225.363532)
		(width 0.1143)
		(layer "In11.Cu")
		(net "P5E_CPU1_G1_TX_DP<15>")
	)
	(segment
		(start 96.993456 -227.779326)
		(end 97.023936 -227.797106)
		(width 0.1143)
		(layer "In11.Cu")
		(net "P5E_CPU1_G1_TX_DP<15>")
	)
	(segment
		(start 97.023936 -238.491776)
		(end 96.993456 -238.509556)
		(width 0.1143)
		(layer "In11.Cu")
		(net "P5E_CPU1_G1_TX_DP<15>")
	)
	(segment
		(start 95.582232 -222.108776)
		(end 95.613982 -222.127064)
		(width 0.1143)
		(layer "In11.Cu")
		(net "P5E_CPU1_G1_TX_DP<15>")
	)
	(segment
		(start 144.230598 -147.893532)
		(end 144.99717 -160.118806)
		(width 0.14224)
		(layer "In11.Cu")
		(net "P5E_CPU1_G1_TX_DP<15>")
	)
	(segment
		(start 96.993456 -243.979192)
		(end 97.023936 -243.996972)
		(width 0.1143)
		(layer "In11.Cu")
		(net "P5E_CPU1_G1_TX_DP<15>")
	)
	(segment
		(start 96.053402 -222.91929)
		(end 96.083882 -222.93707)
		(width 0.1143)
		(layer "In11.Cu")
		(net "P5E_CPU1_G1_TX_DP<15>")
	)
	(segment
		(start 97.063052 -228.749098)
		(end 97.062544 -228.749352)
		(width 0.1143)
		(layer "In11.Cu")
		(net "P5E_CPU1_G1_TX_DP<15>")
	)
	(segment
		(start 97.963482 -245.61673)
		(end 98.002344 -245.639336)
		(width 0.1143)
		(layer "In11.Cu")
		(net "P5E_CPU1_G1_TX_DP<15>")
	)
	(segment
		(start 97.78873 -245.303802)
		(end 97.78873 -245.313454)
		(width 0.1143)
		(layer "In11.Cu")
		(net "P5E_CPU1_G1_TX_DP<15>")
	)
	(segment
		(start 97.023936 -236.871764)
		(end 96.993456 -236.889544)
		(width 0.1143)
		(layer "In11.Cu")
		(net "P5E_CPU1_G1_TX_DP<15>")
	)
	(segment
		(start 97.063052 -235.228892)
		(end 97.023936 -235.251752)
		(width 0.1143)
		(layer "In11.Cu")
		(net "P5E_CPU1_G1_TX_DP<15>")
	)
	(segment
		(start 96.122998 -223.889062)
		(end 96.083882 -223.911922)
		(width 0.1143)
		(layer "In11.Cu")
		(net "P5E_CPU1_G1_TX_DP<15>")
	)
	(segment
		(start 141.949424 -143.176752)
		(end 144.230598 -147.893532)
		(width 0.14224)
		(layer "In11.Cu")
		(net "P5E_CPU1_G1_TX_DP<15>")
	)
	(segment
		(start 95.406972 -213.75116)
		(end 95.406972 -221.05493)
		(width 0.14224)
		(layer "In11.Cu")
		(net "P5E_CPU1_G1_TX_DP<15>")
	)
	(segment
		(start 97.023936 -227.797106)
		(end 97.063052 -227.819966)
		(width 0.1143)
		(layer "In11.Cu")
		(net "P5E_CPU1_G1_TX_DP<15>")
	)
	(segment
		(start 16.106648 -20.192746)
		(end 32.437578 -42.135806)
		(width 0.14224)
		(layer "In11.Cu")
		(net "P5E_CPU1_G1_TX_DP<15>")
	)
	(segment
		(start 97.023936 -228.771958)
		(end 96.993456 -228.789738)
		(width 0.1143)
		(layer "In11.Cu")
		(net "P5E_CPU1_G1_TX_DP<15>")
	)
	(segment
		(start 96.053402 -224.539302)
		(end 96.083882 -224.557082)
		(width 0.1143)
		(layer "In11.Cu")
		(net "P5E_CPU1_G1_TX_DP<15>")
	)
	(segment
		(start 96.554036 -225.367088)
		(end 96.555052 -225.367596)
		(width 0.1143)
		(layer "In11.Cu")
		(net "P5E_CPU1_G1_TX_DP<15>")
	)
	(segment
		(start 97.063052 -243.328952)
		(end 97.023936 -243.351812)
		(width 0.1143)
		(layer "In11.Cu")
		(net "P5E_CPU1_G1_TX_DP<15>")
	)
	(segment
		(start 96.993456 -237.499144)
		(end 97.023936 -237.516924)
		(width 0.1143)
		(layer "In11.Cu")
		(net "P5E_CPU1_G1_TX_DP<15>")
	)
	(segment
		(start 97.063052 -231.988868)
		(end 97.023936 -232.011728)
		(width 0.1143)
		(layer "In11.Cu")
		(net "P5E_CPU1_G1_TX_DP<15>")
	)
	(segment
		(start 97.063052 -241.70894)
		(end 97.023936 -241.7318)
		(width 0.1143)
		(layer "In11.Cu")
		(net "P5E_CPU1_G1_TX_DP<15>")
	)
	(segment
		(start 96.522286 -225.3488)
		(end 96.546924 -225.363024)
		(width 0.1143)
		(layer "In11.Cu")
		(net "P5E_CPU1_G1_TX_DP<15>")
	)
	(segment
		(start 32.437578 -42.135806)
		(end 51.414426 -62.003432)
		(width 0.14224)
		(layer "In11.Cu")
		(net "P5E_CPU1_G1_TX_DP<15>")
	)
	(segment
		(start 97.063052 -227.129086)
		(end 97.023936 -227.151946)
		(width 0.1143)
		(layer "In11.Cu")
		(net "P5E_CPU1_G1_TX_DP<15>")
	)
	(segment
		(start 96.552004 -225.365818)
		(end 96.553274 -225.36658)
		(width 0.1143)
		(layer "In11.Cu")
		(net "P5E_CPU1_G1_TX_DP<15>")
	)
	(segment
		(start 96.993456 -235.879132)
		(end 97.023936 -235.896912)
		(width 0.1143)
		(layer "In11.Cu")
		(net "P5E_CPU1_G1_TX_DP<15>")
	)
	(segment
		(start 97.023936 -243.351812)
		(end 96.993456 -243.369592)
		(width 0.1143)
		(layer "In11.Cu")
		(net "P5E_CPU1_G1_TX_DP<15>")
	)
	(segment
		(start 97.023936 -232.011728)
		(end 96.993456 -232.029508)
		(width 0.1143)
		(layer "In11.Cu")
		(net "P5E_CPU1_G1_TX_DP<15>")
	)
	(segment
		(start 97.023936 -235.896912)
		(end 97.063052 -235.919772)
		(width 0.1143)
		(layer "In11.Cu")
		(net "P5E_CPU1_G1_TX_DP<15>")
	)
	(segment
		(start 97.023936 -232.656888)
		(end 97.063052 -232.679748)
		(width 0.1143)
		(layer "In11.Cu")
		(net "P5E_CPU1_G1_TX_DP<15>")
	)
	(segment
		(start 97.063052 -236.848904)
		(end 97.023936 -236.871764)
		(width 0.1143)
		(layer "In11.Cu")
		(net "P5E_CPU1_G1_TX_DP<15>")
	)
	(segment
		(start 97.063052 -240.088928)
		(end 97.023936 -240.111788)
		(width 0.1143)
		(layer "In11.Cu")
		(net "P5E_CPU1_G1_TX_DP<15>")
	)
	(segment
		(start 144.99717 -162.126168)
		(end 144.143222 -164.634926)
		(width 0.14224)
		(layer "In11.Cu")
		(net "P5E_CPU1_G1_TX_DP<15>")
	)
	(segment
		(start 97.462086 -244.788436)
		(end 97.505266 -244.813582)
		(width 0.1143)
		(layer "In11.Cu")
		(net "P5E_CPU1_G1_TX_DP<15>")
	)
	(segment
		(start 97.060512 -230.370634)
		(end 96.993456 -230.40975)
		(width 0.1143)
		(layer "In11.Cu")
		(net "P5E_CPU1_G1_TX_DP<15>")
	)
	(segment
		(start 97.023936 -241.7318)
		(end 96.993456 -241.74958)
		(width 0.1143)
		(layer "In11.Cu")
		(net "P5E_CPU1_G1_TX_DP<15>")
	)
	(segment
		(start 96.993456 -239.119156)
		(end 97.023936 -239.136936)
		(width 0.1143)
		(layer "In11.Cu")
		(net "P5E_CPU1_G1_TX_DP<15>")
	)
	(segment
		(start 140.436854 -170.218354)
		(end 103.022146 -200.861422)
		(width 0.14224)
		(layer "In11.Cu")
		(net "P5E_CPU1_G1_TX_DP<15>")
	)
	(segment
		(start 16.106648 -17.90319)
		(end 16.106648 -20.192746)
		(width 0.14224)
		(layer "In11.Cu")
		(net "P5E_CPU1_G1_TX_DP<15>")
	)
	(segment
		(start 103.022146 -200.861422)
		(end 95.406972 -213.75116)
		(width 0.14224)
		(layer "In11.Cu")
		(net "P5E_CPU1_G1_TX_DP<15>")
	)
	(segment
		(start 96.991424 -229.398068)
		(end 97.023936 -229.416864)
		(width 0.1143)
		(layer "In11.Cu")
		(net "P5E_CPU1_G1_TX_DP<15>")
	)
	(segment
		(start 97.023936 -229.416864)
		(end 97.063052 -229.439724)
		(width 0.1143)
		(layer "In11.Cu")
		(net "P5E_CPU1_G1_TX_DP<15>")
	)
	(segment
		(start 97.023936 -243.996972)
		(end 97.063052 -244.019832)
		(width 0.1143)
		(layer "In11.Cu")
		(net "P5E_CPU1_G1_TX_DP<15>")
	)
	(segment
		(start 95.361252 -221.129098)
		(end 95.361252 -221.30893)
		(width 0.1143)
		(layer "In11.Cu")
		(net "P5E_CPU1_G1_TX_DP<15>")
	)
	(segment
		(start 98.323146 -246.10441)
		(end 98.621088 -246.10441)
		(width 0.1143)
		(layer "In11.Cu")
		(net "P5E_CPU1_G1_TX_DP<15>")
	)
	(segment
		(start 97.023936 -235.251752)
		(end 96.993456 -235.269532)
		(width 0.1143)
		(layer "In11.Cu")
		(net "P5E_CPU1_G1_TX_DP<15>")
	)
	(segment
		(start 96.083882 -224.557082)
		(end 96.122998 -224.579942)
		(width 0.1143)
		(layer "In11.Cu")
		(net "P5E_CPU1_G1_TX_DP<15>")
	)
	(segment
		(start 96.553274 -225.36658)
		(end 96.554036 -225.367088)
		(width 0.1143)
		(layer "In11.Cu")
		(net "P5E_CPU1_G1_TX_DP<15>")
	)
	(segment
		(start 96.549464 -225.364548)
		(end 96.552004 -225.365818)
		(width 0.1143)
		(layer "In11.Cu")
		(net "P5E_CPU1_G1_TX_DP<15>")
	)
	(segment
		(start 98.240342 -246.021606)
		(end 98.323146 -246.10441)
		(width 0.1143)
		(layer "In11.Cu")
		(net "P5E_CPU1_G1_TX_DP<15>")
	)
	(segment
		(start 97.062544 -228.749352)
		(end 97.023936 -228.771958)
		(width 0.1143)
		(layer "In11.Cu")
		(net "P5E_CPU1_G1_TX_DP<15>")
	)
	(segment
		(start 96.993456 -242.35918)
		(end 97.023936 -242.37696)
		(width 0.1143)
		(layer "In11.Cu")
		(net "P5E_CPU1_G1_TX_DP<15>")
	)
	(segment
		(start 97.023936 -237.516924)
		(end 97.063052 -237.539784)
		(width 0.1143)
		(layer "In11.Cu")
		(net "P5E_CPU1_G1_TX_DP<15>")
	)
	(segment
		(start 95.361252 -221.30893)
		(end 95.426276 -221.373954)
		(width 0.1143)
		(layer "In11.Cu")
		(net "P5E_CPU1_G1_TX_DP<15>")
	)
	(segment
		(start 97.023936 -227.151946)
		(end 96.993456 -227.169726)
		(width 0.1143)
		(layer "In11.Cu")
		(net "P5E_CPU1_G1_TX_DP<15>")
	)
	(segment
		(start 54.382924 -64.431926)
		(end 141.949424 -143.176752)
		(width 0.14224)
		(layer "In11.Cu")
		(net "P5E_CPU1_G1_TX_DP<15>")
	)
	(segment
		(start 97.023936 -234.2769)
		(end 97.063052 -234.29976)
		(width 0.1143)
		(layer "In11.Cu")
		(net "P5E_CPU1_G1_TX_DP<15>")
	)
	(segment
		(start 97.023936 -233.63174)
		(end 96.993456 -233.64952)
		(width 0.1143)
		(layer "In11.Cu")
		(net "P5E_CPU1_G1_TX_DP<15>")
	)
	(segment
		(start 97.023936 -226.177094)
		(end 97.063052 -226.199954)
		(width 0.1143)
		(layer "In11.Cu")
		(net "P5E_CPU1_G1_TX_DP<15>")
	)
	(segment
		(start 96.54794 -225.363532)
		(end 96.549464 -225.364548)
		(width 0.1143)
		(layer "In11.Cu")
		(net "P5E_CPU1_G1_TX_DP<15>")
	)
	(segment
		(start 95.406972 -221.05493)
		(end 95.406972 -221.083378)
		(width 0.1143)
		(layer "In11.Cu")
		(net "P5E_CPU1_G1_TX_DP<15>")
	)
	(segment
		(start 96.993456 -234.25912)
		(end 97.023936 -234.2769)
		(width 0.1143)
		(layer "In11.Cu")
		(net "P5E_CPU1_G1_TX_DP<15>")
	)
	(segment
		(start 95.406972 -221.083378)
		(end 95.361252 -221.129098)
		(width 0.1143)
		(layer "In11.Cu")
		(net "P5E_CPU1_G1_TX_DP<15>")
	)
	(segment
		(start 96.083882 -222.93707)
		(end 96.122998 -222.95993)
		(width 0.1143)
		(layer "In11.Cu")
		(net "P5E_CPU1_G1_TX_DP<15>")
	)
	(segment
		(start 97.063052 -233.60888)
		(end 97.023936 -233.63174)
		(width 0.1143)
		(layer "In11.Cu")
		(net "P5E_CPU1_G1_TX_DP<15>")
	)
	(segment
		(start 96.993456 -226.159314)
		(end 97.023936 -226.177094)
		(width 0.1143)
		(layer "In11.Cu")
		(net "P5E_CPU1_G1_TX_DP<15>")
	)
	(segment
		(start 144.143222 -164.634926)
		(end 140.436854 -170.218354)
		(width 0.14224)
		(layer "In11.Cu")
		(net "P5E_CPU1_G1_TX_DP<15>")
	)
	(segment
		(start 96.991424 -231.01808)
		(end 97.023936 -231.036876)
		(width 0.1143)
		(layer "In11.Cu")
		(net "P5E_CPU1_G1_TX_DP<15>")
	)
	(segment
		(start 97.023936 -240.756948)
		(end 97.063052 -240.779808)
		(width 0.1143)
		(layer "In11.Cu")
		(net "P5E_CPU1_G1_TX_DP<15>")
	)
	(segment
		(start 16.397478 -17.61236)
		(end 16.106648 -17.90319)
		(width 0.14224)
		(layer "In11.Cu")
		(net "P5E_CPU1_G1_TX_DP<15>")
	)
	(segment
		(start 97.023936 -242.37696)
		(end 97.063052 -242.39982)
		(width 0.1143)
		(layer "In11.Cu")
		(net "P5E_CPU1_G1_TX_DP<15>")
	)
	(segment
		(start 97.023936 -240.111788)
		(end 96.993456 -240.129568)
		(width 0.1143)
		(layer "In11.Cu")
		(net "P5E_CPU1_G1_TX_DP<15>")
	)
	(segment
		(start 144.99717 -160.118806)
		(end 144.99717 -162.126168)
		(width 0.14224)
		(layer "In11.Cu")
		(net "P5E_CPU1_G1_TX_DP<15>")
	)
	(segment
		(start 97.023936 -239.136936)
		(end 97.063052 -239.159796)
		(width 0.1143)
		(layer "In11.Cu")
		(net "P5E_CPU1_G1_TX_DP<15>")
	)
	(segment
		(start 95.426276 -221.373954)
		(end 95.426276 -221.804484)
		(width 0.1143)
		(layer "In11.Cu")
		(net "P5E_CPU1_G1_TX_DP<15>")
	)
	(segment
		(start 95.613982 -222.127064)
		(end 95.653098 -222.149924)
		(width 0.1143)
		(layer "In11.Cu")
		(net "P5E_CPU1_G1_TX_DP<15>")
	)
	(segment
		(start 97.063052 -238.468916)
		(end 97.023936 -238.491776)
		(width 0.1143)
		(layer "In11.Cu")
		(net "P5E_CPU1_G1_TX_DP<15>")
	)
	(segment
		(start 51.414426 -62.003432)
		(end 54.382924 -64.431926)
		(width 0.14224)
		(layer "In11.Cu")
		(net "P5E_CPU1_G1_TX_DP<15>")
	)
	(segment
		(start 96.083882 -223.911922)
		(end 96.053402 -223.929702)
		(width 0.1143)
		(layer "In11.Cu")
		(net "P5E_CPU1_G1_TX_DP<15>")
	)
	(segment
		(start 96.993456 -232.639108)
		(end 97.023936 -232.656888)
		(width 0.1143)
		(layer "In11.Cu")
		(net "P5E_CPU1_G1_TX_DP<15>")
	)
	(segment
		(start 96.556576 -225.368612)
		(end 96.593152 -225.389948)
		(width 0.1143)
		(layer "In11.Cu")
		(net "P5E_CPU1_G1_TX_DP<15>")
	)
	(arc
		(start 97.306384 -229.90429)
		(mid 97.241148 -230.167881)
		(end 97.060512 -230.370634)
		(width 0.1143)
		(layer "In11.Cu")
		(net "P5E_CPU1_G1_TX_DP<15>")
	)
	(arc
		(start 96.836484 -225.854514)
		(mid 96.878033 -226.025936)
		(end 96.993456 -226.159314)
		(width 0.1143)
		(layer "In11.Cu")
		(net "P5E_CPU1_G1_TX_DP<15>")
	)
	(arc
		(start 97.063052 -242.39982)
		(mid 97.306379 -242.864386)
		(end 97.063052 -243.328952)
		(width 0.1143)
		(layer "In11.Cu")
		(net "P5E_CPU1_G1_TX_DP<15>")
	)
	(arc
		(start 96.122998 -224.579942)
		(mid 96.301811 -224.782292)
		(end 96.36633 -225.044508)
		(width 0.1143)
		(layer "In11.Cu")
		(net "P5E_CPU1_G1_TX_DP<15>")
	)
	(arc
		(start 96.993456 -233.64952)
		(mid 96.836479 -233.95432)
		(end 96.993456 -234.25912)
		(width 0.1143)
		(layer "In11.Cu")
		(net "P5E_CPU1_G1_TX_DP<15>")
	)
	(arc
		(start 97.063052 -226.199954)
		(mid 97.306379 -226.66452)
		(end 97.063052 -227.129086)
		(width 0.1143)
		(layer "In11.Cu")
		(net "P5E_CPU1_G1_TX_DP<15>")
	)
	(arc
		(start 96.36633 -225.044508)
		(mid 96.407585 -225.215479)
		(end 96.522286 -225.3488)
		(width 0.1143)
		(layer "In11.Cu")
		(net "P5E_CPU1_G1_TX_DP<15>")
	)
	(arc
		(start 96.993456 -241.74958)
		(mid 96.836479 -242.05438)
		(end 96.993456 -242.35918)
		(width 0.1143)
		(layer "In11.Cu")
		(net "P5E_CPU1_G1_TX_DP<15>")
	)
	(arc
		(start 96.993456 -236.889544)
		(mid 96.836479 -237.194344)
		(end 96.993456 -237.499144)
		(width 0.1143)
		(layer "In11.Cu")
		(net "P5E_CPU1_G1_TX_DP<15>")
	)
	(arc
		(start 95.426276 -221.804484)
		(mid 95.467531 -221.975455)
		(end 95.582232 -222.108776)
		(width 0.1143)
		(layer "In11.Cu")
		(net "P5E_CPU1_G1_TX_DP<15>")
	)
	(arc
		(start 98.002344 -245.639336)
		(mid 98.002725 -245.63959)
		(end 98.003106 -245.639844)
		(width 0.1143)
		(layer "In11.Cu")
		(net "P5E_CPU1_G1_TX_DP<15>")
	)
	(arc
		(start 97.063052 -235.919772)
		(mid 97.306379 -236.384338)
		(end 97.063052 -236.848904)
		(width 0.1143)
		(layer "In11.Cu")
		(net "P5E_CPU1_G1_TX_DP<15>")
	)
	(arc
		(start 97.063052 -229.439724)
		(mid 97.241865 -229.642074)
		(end 97.306384 -229.90429)
		(width 0.1143)
		(layer "In11.Cu")
		(net "P5E_CPU1_G1_TX_DP<15>")
	)
	(arc
		(start 97.505266 -244.813582)
		(mid 97.71275 -245.020669)
		(end 97.78873 -245.303802)
		(width 0.1143)
		(layer "In11.Cu")
		(net "P5E_CPU1_G1_TX_DP<15>")
	)
	(arc
		(start 96.993456 -243.369592)
		(mid 96.836479 -243.674392)
		(end 96.993456 -243.979192)
		(width 0.1143)
		(layer "In11.Cu")
		(net "P5E_CPU1_G1_TX_DP<15>")
	)
	(arc
		(start 96.993456 -228.789738)
		(mid 96.878029 -228.923114)
		(end 96.836484 -229.094538)
		(width 0.1143)
		(layer "In11.Cu")
		(net "P5E_CPU1_G1_TX_DP<15>")
	)
	(arc
		(start 95.89643 -222.61449)
		(mid 95.937979 -222.785912)
		(end 96.053402 -222.91929)
		(width 0.1143)
		(layer "In11.Cu")
		(net "P5E_CPU1_G1_TX_DP<15>")
	)
	(arc
		(start 98.003106 -245.639844)
		(mid 98.155093 -245.796352)
		(end 98.236532 -245.998746)
		(width 0.1143)
		(layer "In11.Cu")
		(net "P5E_CPU1_G1_TX_DP<15>")
	)
	(arc
		(start 96.836484 -230.71455)
		(mid 96.87745 -230.884956)
		(end 96.991424 -231.01808)
		(width 0.1143)
		(layer "In11.Cu")
		(net "P5E_CPU1_G1_TX_DP<15>")
	)
	(arc
		(start 96.993456 -230.40975)
		(mid 96.878029 -230.543126)
		(end 96.836484 -230.71455)
		(width 0.1143)
		(layer "In11.Cu")
		(net "P5E_CPU1_G1_TX_DP<15>")
	)
	(arc
		(start 96.993456 -238.509556)
		(mid 96.836479 -238.814356)
		(end 96.993456 -239.119156)
		(width 0.1143)
		(layer "In11.Cu")
		(net "P5E_CPU1_G1_TX_DP<15>")
	)
	(arc
		(start 97.306384 -244.484398)
		(mid 97.347577 -244.655187)
		(end 97.462086 -244.788436)
		(width 0.1143)
		(layer "In11.Cu")
		(net "P5E_CPU1_G1_TX_DP<15>")
	)
	(arc
		(start 96.993456 -235.269532)
		(mid 96.836479 -235.574332)
		(end 96.993456 -235.879132)
		(width 0.1143)
		(layer "In11.Cu")
		(net "P5E_CPU1_G1_TX_DP<15>")
	)
	(arc
		(start 96.993456 -232.029508)
		(mid 96.836479 -232.334308)
		(end 96.993456 -232.639108)
		(width 0.1143)
		(layer "In11.Cu")
		(net "P5E_CPU1_G1_TX_DP<15>")
	)
	(arc
		(start 96.993456 -227.169726)
		(mid 96.836479 -227.474526)
		(end 96.993456 -227.779326)
		(width 0.1143)
		(layer "In11.Cu")
		(net "P5E_CPU1_G1_TX_DP<15>")
	)
	(arc
		(start 97.063052 -240.779808)
		(mid 97.306379 -241.244374)
		(end 97.063052 -241.70894)
		(width 0.1143)
		(layer "In11.Cu")
		(net "P5E_CPU1_G1_TX_DP<15>")
	)
	(arc
		(start 96.836484 -229.094538)
		(mid 96.87745 -229.264944)
		(end 96.991424 -229.398068)
		(width 0.1143)
		(layer "In11.Cu")
		(net "P5E_CPU1_G1_TX_DP<15>")
	)
	(arc
		(start 97.063052 -231.059736)
		(mid 97.306379 -231.524302)
		(end 97.063052 -231.988868)
		(width 0.1143)
		(layer "In11.Cu")
		(net "P5E_CPU1_G1_TX_DP<15>")
	)
	(arc
		(start 96.993456 -240.129568)
		(mid 96.836479 -240.434368)
		(end 96.993456 -240.739168)
		(width 0.1143)
		(layer "In11.Cu")
		(net "P5E_CPU1_G1_TX_DP<15>")
	)
	(arc
		(start 96.053402 -223.929702)
		(mid 95.896425 -224.234502)
		(end 96.053402 -224.539302)
		(width 0.1143)
		(layer "In11.Cu")
		(net "P5E_CPU1_G1_TX_DP<15>")
	)
	(arc
		(start 98.236532 -245.998746)
		(mid 98.238555 -246.010156)
		(end 98.240342 -246.021606)
		(width 0.1143)
		(layer "In11.Cu")
		(net "P5E_CPU1_G1_TX_DP<15>")
	)
	(arc
		(start 97.063052 -244.019832)
		(mid 97.241865 -244.222182)
		(end 97.306384 -244.484398)
		(width 0.1143)
		(layer "In11.Cu")
		(net "P5E_CPU1_G1_TX_DP<15>")
	)
	(arc
		(start 97.063052 -237.539784)
		(mid 97.306379 -238.00435)
		(end 97.063052 -238.468916)
		(width 0.1143)
		(layer "In11.Cu")
		(net "P5E_CPU1_G1_TX_DP<15>")
	)
	(arc
		(start 97.063052 -234.29976)
		(mid 97.306379 -234.764326)
		(end 97.063052 -235.228892)
		(width 0.1143)
		(layer "In11.Cu")
		(net "P5E_CPU1_G1_TX_DP<15>")
	)
	(arc
		(start 97.78873 -245.313454)
		(mid 97.83562 -245.488405)
		(end 97.963482 -245.61673)
		(width 0.1143)
		(layer "In11.Cu")
		(net "P5E_CPU1_G1_TX_DP<15>")
	)
	(arc
		(start 95.653098 -222.149924)
		(mid 95.831911 -222.352274)
		(end 95.89643 -222.61449)
		(width 0.1143)
		(layer "In11.Cu")
		(net "P5E_CPU1_G1_TX_DP<15>")
	)
	(arc
		(start 96.593152 -225.389948)
		(mid 96.771965 -225.592298)
		(end 96.836484 -225.854514)
		(width 0.1143)
		(layer "In11.Cu")
		(net "P5E_CPU1_G1_TX_DP<15>")
	)
	(arc
		(start 97.063052 -239.159796)
		(mid 97.306379 -239.624362)
		(end 97.063052 -240.088928)
		(width 0.1143)
		(layer "In11.Cu")
		(net "P5E_CPU1_G1_TX_DP<15>")
	)
	(arc
		(start 97.063052 -227.819966)
		(mid 97.306379 -228.284532)
		(end 97.063052 -228.749098)
		(width 0.1143)
		(layer "In11.Cu")
		(net "P5E_CPU1_G1_TX_DP<15>")
	)
	(arc
		(start 97.063052 -232.679748)
		(mid 97.306379 -233.144314)
		(end 97.063052 -233.60888)
		(width 0.1143)
		(layer "In11.Cu")
		(net "P5E_CPU1_G1_TX_DP<15>")
	)
	(arc
		(start 96.122998 -222.95993)
		(mid 96.366325 -223.424496)
		(end 96.122998 -223.889062)
		(width 0.1143)
		(layer "In11.Cu")
		(net "P5E_CPU1_G1_TX_DP<15>")
	)
	(segment
		(start 18.920968 -18.186146)
		(end 18.920968 -18.867628)
		(width 0.12954)
		(layer "F.Cu")
		(net "P5E_CPU1_G1_TX_DP<14>")
	)
	(segment
		(start 19.216878 -17.890236)
		(end 18.920968 -18.186146)
		(width 0.12954)
		(layer "F.Cu")
		(net "P5E_CPU1_G1_TX_DP<14>")
	)
	(segment
		(start 99.08794 -244.750336)
		(end 98.621088 -244.484398)
		(width 0.12954)
		(layer "F.Cu")
		(net "P5E_CPU1_G1_TX_DP<14>")
	)
	(segment
		(start 18.920968 -18.867628)
		(end 19.190462 -19.137122)
		(width 0.12954)
		(layer "F.Cu")
		(net "P5E_CPU1_G1_TX_DP<14>")
	)
	(segment
		(start 98.003106 -243.328952)
		(end 97.96399 -243.351812)
		(width 0.1143)
		(layer "In11.Cu")
		(net "P5E_CPU1_G1_TX_DP<14>")
	)
	(segment
		(start 97.023936 -223.911922)
		(end 96.993456 -223.929702)
		(width 0.1143)
		(layer "In11.Cu")
		(net "P5E_CPU1_G1_TX_DP<14>")
	)
	(segment
		(start 96.351852 -213.990936)
		(end 96.351852 -221.05493)
		(width 0.14224)
		(layer "In11.Cu")
		(net "P5E_CPU1_G1_TX_DP<14>")
	)
	(segment
		(start 97.93224 -243.978684)
		(end 97.96399 -243.996972)
		(width 0.1143)
		(layer "In11.Cu")
		(net "P5E_CPU1_G1_TX_DP<14>")
	)
	(segment
		(start 54.383432 -63.130684)
		(end 142.668498 -142.52194)
		(width 0.14224)
		(layer "In11.Cu")
		(net "P5E_CPU1_G1_TX_DP<14>")
	)
	(segment
		(start 97.968562 -239.139476)
		(end 97.969324 -239.139984)
		(width 0.1143)
		(layer "In11.Cu")
		(net "P5E_CPU1_G1_TX_DP<14>")
	)
	(segment
		(start 97.96399 -229.416864)
		(end 98.003106 -229.439724)
		(width 0.1143)
		(layer "In11.Cu")
		(net "P5E_CPU1_G1_TX_DP<14>")
	)
	(segment
		(start 97.96399 -233.63174)
		(end 97.93224 -233.650028)
		(width 0.1143)
		(layer "In11.Cu")
		(net "P5E_CPU1_G1_TX_DP<14>")
	)
	(segment
		(start 98.000566 -230.370634)
		(end 97.965006 -230.391462)
		(width 0.1143)
		(layer "In11.Cu")
		(net "P5E_CPU1_G1_TX_DP<14>")
	)
	(segment
		(start 51.551586 -60.7949)
		(end 54.383432 -63.130684)
		(width 0.14224)
		(layer "In11.Cu")
		(net "P5E_CPU1_G1_TX_DP<14>")
	)
	(segment
		(start 97.969324 -240.759996)
		(end 97.97034 -240.760504)
		(width 0.1143)
		(layer "In11.Cu")
		(net "P5E_CPU1_G1_TX_DP<14>")
	)
	(segment
		(start 97.96399 -227.797106)
		(end 98.003106 -227.819966)
		(width 0.1143)
		(layer "In11.Cu")
		(net "P5E_CPU1_G1_TX_DP<14>")
	)
	(segment
		(start 97.975166 -228.765354)
		(end 97.974404 -228.765862)
		(width 0.1143)
		(layer "In11.Cu")
		(net "P5E_CPU1_G1_TX_DP<14>")
	)
	(segment
		(start 97.49409 -225.367088)
		(end 97.495868 -225.368104)
		(width 0.1143)
		(layer "In11.Cu")
		(net "P5E_CPU1_G1_TX_DP<14>")
	)
	(segment
		(start 35.14598 -43.136312)
		(end 51.551586 -60.7949)
		(width 0.14224)
		(layer "In11.Cu")
		(net "P5E_CPU1_G1_TX_DP<14>")
	)
	(segment
		(start 18.899632 -19.427952)
		(end 18.899632 -20.192746)
		(width 0.14224)
		(layer "In11.Cu")
		(net "P5E_CPU1_G1_TX_DP<14>")
	)
	(segment
		(start 97.956116 -242.372388)
		(end 97.968562 -242.3795)
		(width 0.1143)
		(layer "In11.Cu")
		(net "P5E_CPU1_G1_TX_DP<14>")
	)
	(segment
		(start 97.99955 -234.29722)
		(end 98.002344 -234.299252)
		(width 0.1143)
		(layer "In11.Cu")
		(net "P5E_CPU1_G1_TX_DP<14>")
	)
	(segment
		(start 97.961958 -230.39324)
		(end 97.960434 -230.394002)
		(width 0.1143)
		(layer "In11.Cu")
		(net "P5E_CPU1_G1_TX_DP<14>")
	)
	(segment
		(start 145.964656 -160.088326)
		(end 145.964656 -162.191192)
		(width 0.14224)
		(layer "In11.Cu")
		(net "P5E_CPU1_G1_TX_DP<14>")
	)
	(segment
		(start 97.97034 -237.52048)
		(end 98.002344 -237.539276)
		(width 0.1143)
		(layer "In11.Cu")
		(net "P5E_CPU1_G1_TX_DP<14>")
	)
	(segment
		(start 145.190718 -147.736814)
		(end 145.964656 -160.088326)
		(width 0.14224)
		(layer "In11.Cu")
		(net "P5E_CPU1_G1_TX_DP<14>")
	)
	(segment
		(start 97.969324 -237.519972)
		(end 97.97034 -237.52048)
		(width 0.1143)
		(layer "In11.Cu")
		(net "P5E_CPU1_G1_TX_DP<14>")
	)
	(segment
		(start 97.023936 -224.557082)
		(end 97.063052 -224.579942)
		(width 0.1143)
		(layer "In11.Cu")
		(net "P5E_CPU1_G1_TX_DP<14>")
	)
	(segment
		(start 144.995646 -165.067488)
		(end 141.499844 -170.552872)
		(width 0.14224)
		(layer "In11.Cu")
		(net "P5E_CPU1_G1_TX_DP<14>")
	)
	(segment
		(start 97.985072 -241.719608)
		(end 97.984818 -241.719608)
		(width 0.1143)
		(layer "In11.Cu")
		(net "P5E_CPU1_G1_TX_DP<14>")
	)
	(segment
		(start 97.96399 -230.39197)
		(end 97.963228 -230.392478)
		(width 0.1143)
		(layer "In11.Cu")
		(net "P5E_CPU1_G1_TX_DP<14>")
	)
	(segment
		(start 97.023936 -222.93707)
		(end 97.063052 -222.95993)
		(width 0.1143)
		(layer "In11.Cu")
		(net "P5E_CPU1_G1_TX_DP<14>")
	)
	(segment
		(start 97.965006 -228.77145)
		(end 97.96399 -228.771958)
		(width 0.1143)
		(layer "In11.Cu")
		(net "P5E_CPU1_G1_TX_DP<14>")
	)
	(segment
		(start 97.96653 -228.770434)
		(end 97.965006 -228.77145)
		(width 0.1143)
		(layer "In11.Cu")
		(net "P5E_CPU1_G1_TX_DP<14>")
	)
	(segment
		(start 96.306132 -221.30893)
		(end 96.36633 -221.369128)
		(width 0.1143)
		(layer "In11.Cu")
		(net "P5E_CPU1_G1_TX_DP<14>")
	)
	(segment
		(start 97.96399 -232.011728)
		(end 97.93224 -232.030016)
		(width 0.1143)
		(layer "In11.Cu")
		(net "P5E_CPU1_G1_TX_DP<14>")
	)
	(segment
		(start 98.003106 -231.988868)
		(end 97.96399 -232.011728)
		(width 0.1143)
		(layer "In11.Cu")
		(net "P5E_CPU1_G1_TX_DP<14>")
	)
	(segment
		(start 97.95383 -231.031034)
		(end 98.003106 -231.059736)
		(width 0.1143)
		(layer "In11.Cu")
		(net "P5E_CPU1_G1_TX_DP<14>")
	)
	(segment
		(start 97.963228 -228.772466)
		(end 97.96272 -228.77272)
		(width 0.1143)
		(layer "In11.Cu")
		(net "P5E_CPU1_G1_TX_DP<14>")
	)
	(segment
		(start 98.003106 -228.749098)
		(end 97.975166 -228.765354)
		(width 0.1143)
		(layer "In11.Cu")
		(net "P5E_CPU1_G1_TX_DP<14>")
	)
	(segment
		(start 96.554036 -222.127064)
		(end 96.555052 -222.127572)
		(width 0.1143)
		(layer "In11.Cu")
		(net "P5E_CPU1_G1_TX_DP<14>")
	)
	(segment
		(start 97.96399 -234.2769)
		(end 97.99955 -234.29722)
		(width 0.1143)
		(layer "In11.Cu")
		(net "P5E_CPU1_G1_TX_DP<14>")
	)
	(segment
		(start 97.46234 -225.3488)
		(end 97.49409 -225.367088)
		(width 0.1143)
		(layer "In11.Cu")
		(net "P5E_CPU1_G1_TX_DP<14>")
	)
	(segment
		(start 97.984818 -238.479584)
		(end 97.963482 -238.49203)
		(width 0.1143)
		(layer "In11.Cu")
		(net "P5E_CPU1_G1_TX_DP<14>")
	)
	(segment
		(start 97.956116 -239.132364)
		(end 97.968562 -239.139476)
		(width 0.1143)
		(layer "In11.Cu")
		(net "P5E_CPU1_G1_TX_DP<14>")
	)
	(segment
		(start 97.96399 -227.151946)
		(end 97.93224 -227.170234)
		(width 0.1143)
		(layer "In11.Cu")
		(net "P5E_CPU1_G1_TX_DP<14>")
	)
	(segment
		(start 97.96399 -243.996972)
		(end 98.003106 -244.019832)
		(width 0.1143)
		(layer "In11.Cu")
		(net "P5E_CPU1_G1_TX_DP<14>")
	)
	(segment
		(start 96.555052 -222.127572)
		(end 96.593152 -222.149924)
		(width 0.1143)
		(layer "In11.Cu")
		(net "P5E_CPU1_G1_TX_DP<14>")
	)
	(segment
		(start 98.003106 -240.088928)
		(end 97.985072 -240.099596)
		(width 0.1143)
		(layer "In11.Cu")
		(net "P5E_CPU1_G1_TX_DP<14>")
	)
	(segment
		(start 97.93224 -232.6386)
		(end 97.963228 -232.65638)
		(width 0.1143)
		(layer "In11.Cu")
		(net "P5E_CPU1_G1_TX_DP<14>")
	)
	(segment
		(start 97.93224 -227.778818)
		(end 97.96399 -227.797106)
		(width 0.1143)
		(layer "In11.Cu")
		(net "P5E_CPU1_G1_TX_DP<14>")
	)
	(segment
		(start 97.995232 -235.914946)
		(end 97.995994 -235.915454)
		(width 0.1143)
		(layer "In11.Cu")
		(net "P5E_CPU1_G1_TX_DP<14>")
	)
	(segment
		(start 97.930462 -229.397306)
		(end 97.96399 -229.416864)
		(width 0.1143)
		(layer "In11.Cu")
		(net "P5E_CPU1_G1_TX_DP<14>")
	)
	(segment
		(start 97.984818 -235.23956)
		(end 97.963482 -235.252006)
		(width 0.1143)
		(layer "In11.Cu")
		(net "P5E_CPU1_G1_TX_DP<14>")
	)
	(segment
		(start 97.974404 -228.765862)
		(end 97.967546 -228.769926)
		(width 0.1143)
		(layer "In11.Cu")
		(net "P5E_CPU1_G1_TX_DP<14>")
	)
	(segment
		(start 97.965006 -232.657396)
		(end 98.003106 -232.679748)
		(width 0.1143)
		(layer "In11.Cu")
		(net "P5E_CPU1_G1_TX_DP<14>")
	)
	(segment
		(start 96.351852 -221.05493)
		(end 96.351852 -221.083378)
		(width 0.1143)
		(layer "In11.Cu")
		(net "P5E_CPU1_G1_TX_DP<14>")
	)
	(segment
		(start 97.969324 -242.380008)
		(end 97.97034 -242.380516)
		(width 0.1143)
		(layer "In11.Cu")
		(net "P5E_CPU1_G1_TX_DP<14>")
	)
	(segment
		(start 97.93224 -234.258612)
		(end 97.96399 -234.2769)
		(width 0.1143)
		(layer "In11.Cu")
		(net "P5E_CPU1_G1_TX_DP<14>")
	)
	(segment
		(start 97.984818 -236.859572)
		(end 97.963482 -236.872018)
		(width 0.1143)
		(layer "In11.Cu")
		(net "P5E_CPU1_G1_TX_DP<14>")
	)
	(segment
		(start 97.97034 -240.760504)
		(end 98.002344 -240.7793)
		(width 0.1143)
		(layer "In11.Cu")
		(net "P5E_CPU1_G1_TX_DP<14>")
	)
	(segment
		(start 97.984818 -240.099596)
		(end 97.963482 -240.112042)
		(width 0.1143)
		(layer "In11.Cu")
		(net "P5E_CPU1_G1_TX_DP<14>")
	)
	(segment
		(start 97.995994 -235.915454)
		(end 98.002344 -235.919264)
		(width 0.1143)
		(layer "In11.Cu")
		(net "P5E_CPU1_G1_TX_DP<14>")
	)
	(segment
		(start 96.993456 -222.91929)
		(end 97.023936 -222.93707)
		(width 0.1143)
		(layer "In11.Cu")
		(net "P5E_CPU1_G1_TX_DP<14>")
	)
	(segment
		(start 18.899632 -20.192746)
		(end 35.14598 -43.136312)
		(width 0.14224)
		(layer "In11.Cu")
		(net "P5E_CPU1_G1_TX_DP<14>")
	)
	(segment
		(start 97.985072 -238.479584)
		(end 97.984818 -238.479584)
		(width 0.1143)
		(layer "In11.Cu")
		(net "P5E_CPU1_G1_TX_DP<14>")
	)
	(segment
		(start 97.968562 -240.759488)
		(end 97.969324 -240.759996)
		(width 0.1143)
		(layer "In11.Cu")
		(net "P5E_CPU1_G1_TX_DP<14>")
	)
	(segment
		(start 97.063052 -223.889062)
		(end 97.023936 -223.911922)
		(width 0.1143)
		(layer "In11.Cu")
		(net "P5E_CPU1_G1_TX_DP<14>")
	)
	(segment
		(start 97.967038 -235.89869)
		(end 97.968562 -235.899452)
		(width 0.1143)
		(layer "In11.Cu")
		(net "P5E_CPU1_G1_TX_DP<14>")
	)
	(segment
		(start 97.985072 -235.23956)
		(end 97.984818 -235.23956)
		(width 0.1143)
		(layer "In11.Cu")
		(net "P5E_CPU1_G1_TX_DP<14>")
	)
	(segment
		(start 98.240342 -244.401594)
		(end 98.323146 -244.484398)
		(width 0.1143)
		(layer "In11.Cu")
		(net "P5E_CPU1_G1_TX_DP<14>")
	)
	(segment
		(start 96.545908 -222.122492)
		(end 96.553274 -222.126556)
		(width 0.1143)
		(layer "In11.Cu")
		(net "P5E_CPU1_G1_TX_DP<14>")
	)
	(segment
		(start 97.963228 -232.65638)
		(end 97.96399 -232.656888)
		(width 0.1143)
		(layer "In11.Cu")
		(net "P5E_CPU1_G1_TX_DP<14>")
	)
	(segment
		(start 97.967546 -228.769926)
		(end 97.96653 -228.770434)
		(width 0.1143)
		(layer "In11.Cu")
		(net "P5E_CPU1_G1_TX_DP<14>")
	)
	(segment
		(start 145.964656 -162.191192)
		(end 144.995646 -165.067488)
		(width 0.14224)
		(layer "In11.Cu")
		(net "P5E_CPU1_G1_TX_DP<14>")
	)
	(segment
		(start 98.003106 -238.468916)
		(end 97.985072 -238.479584)
		(width 0.1143)
		(layer "In11.Cu")
		(net "P5E_CPU1_G1_TX_DP<14>")
	)
	(segment
		(start 96.993456 -224.539302)
		(end 97.023936 -224.557082)
		(width 0.1143)
		(layer "In11.Cu")
		(net "P5E_CPU1_G1_TX_DP<14>")
	)
	(segment
		(start 97.984818 -241.719608)
		(end 97.963482 -241.732054)
		(width 0.1143)
		(layer "In11.Cu")
		(net "P5E_CPU1_G1_TX_DP<14>")
	)
	(segment
		(start 97.96399 -228.771958)
		(end 97.963228 -228.772466)
		(width 0.1143)
		(layer "In11.Cu")
		(net "P5E_CPU1_G1_TX_DP<14>")
	)
	(segment
		(start 97.968562 -237.519464)
		(end 97.969324 -237.519972)
		(width 0.1143)
		(layer "In11.Cu")
		(net "P5E_CPU1_G1_TX_DP<14>")
	)
	(segment
		(start 96.36633 -221.369128)
		(end 96.36633 -221.804484)
		(width 0.1143)
		(layer "In11.Cu")
		(net "P5E_CPU1_G1_TX_DP<14>")
	)
	(segment
		(start 97.96399 -232.656888)
		(end 97.965006 -232.657396)
		(width 0.1143)
		(layer "In11.Cu")
		(net "P5E_CPU1_G1_TX_DP<14>")
	)
	(segment
		(start 98.003106 -233.60888)
		(end 97.96399 -233.63174)
		(width 0.1143)
		(layer "In11.Cu")
		(net "P5E_CPU1_G1_TX_DP<14>")
	)
	(segment
		(start 97.956116 -237.512352)
		(end 97.968562 -237.519464)
		(width 0.1143)
		(layer "In11.Cu")
		(net "P5E_CPU1_G1_TX_DP<14>")
	)
	(segment
		(start 97.96399 -226.177094)
		(end 98.003106 -226.199954)
		(width 0.1143)
		(layer "In11.Cu")
		(net "P5E_CPU1_G1_TX_DP<14>")
	)
	(segment
		(start 97.969324 -235.89996)
		(end 97.995232 -235.914946)
		(width 0.1143)
		(layer "In11.Cu")
		(net "P5E_CPU1_G1_TX_DP<14>")
	)
	(segment
		(start 97.985072 -240.099596)
		(end 97.984818 -240.099596)
		(width 0.1143)
		(layer "In11.Cu")
		(net "P5E_CPU1_G1_TX_DP<14>")
	)
	(segment
		(start 141.499844 -170.552872)
		(end 103.788464 -201.439272)
		(width 0.14224)
		(layer "In11.Cu")
		(net "P5E_CPU1_G1_TX_DP<14>")
	)
	(segment
		(start 97.933256 -226.159314)
		(end 97.96399 -226.177094)
		(width 0.1143)
		(layer "In11.Cu")
		(net "P5E_CPU1_G1_TX_DP<14>")
	)
	(segment
		(start 97.963228 -230.392478)
		(end 97.961958 -230.39324)
		(width 0.1143)
		(layer "In11.Cu")
		(net "P5E_CPU1_G1_TX_DP<14>")
	)
	(segment
		(start 97.97034 -242.380516)
		(end 98.002344 -242.399312)
		(width 0.1143)
		(layer "In11.Cu")
		(net "P5E_CPU1_G1_TX_DP<14>")
	)
	(segment
		(start 97.956116 -240.752376)
		(end 97.968562 -240.759488)
		(width 0.1143)
		(layer "In11.Cu")
		(net "P5E_CPU1_G1_TX_DP<14>")
	)
	(segment
		(start 97.956116 -235.89234)
		(end 97.967038 -235.89869)
		(width 0.1143)
		(layer "In11.Cu")
		(net "P5E_CPU1_G1_TX_DP<14>")
	)
	(segment
		(start 97.985072 -236.859572)
		(end 97.984818 -236.859572)
		(width 0.1143)
		(layer "In11.Cu")
		(net "P5E_CPU1_G1_TX_DP<14>")
	)
	(segment
		(start 98.000312 -227.131118)
		(end 97.96399 -227.151946)
		(width 0.1143)
		(layer "In11.Cu")
		(net "P5E_CPU1_G1_TX_DP<14>")
	)
	(segment
		(start 97.96399 -243.351812)
		(end 97.93224 -243.3701)
		(width 0.1143)
		(layer "In11.Cu")
		(net "P5E_CPU1_G1_TX_DP<14>")
	)
	(segment
		(start 97.968562 -242.3795)
		(end 97.969324 -242.380008)
		(width 0.1143)
		(layer "In11.Cu")
		(net "P5E_CPU1_G1_TX_DP<14>")
	)
	(segment
		(start 98.003106 -241.70894)
		(end 97.985072 -241.719608)
		(width 0.1143)
		(layer "In11.Cu")
		(net "P5E_CPU1_G1_TX_DP<14>")
	)
	(segment
		(start 103.788464 -201.439272)
		(end 96.351852 -213.990936)
		(width 0.14224)
		(layer "In11.Cu")
		(net "P5E_CPU1_G1_TX_DP<14>")
	)
	(segment
		(start 98.003106 -236.848904)
		(end 97.985072 -236.859572)
		(width 0.1143)
		(layer "In11.Cu")
		(net "P5E_CPU1_G1_TX_DP<14>")
	)
	(segment
		(start 97.969324 -239.139984)
		(end 97.97034 -239.140492)
		(width 0.1143)
		(layer "In11.Cu")
		(net "P5E_CPU1_G1_TX_DP<14>")
	)
	(segment
		(start 98.003106 -235.228892)
		(end 97.985072 -235.23956)
		(width 0.1143)
		(layer "In11.Cu")
		(net "P5E_CPU1_G1_TX_DP<14>")
	)
	(segment
		(start 96.351852 -221.083378)
		(end 96.306132 -221.129098)
		(width 0.1143)
		(layer "In11.Cu")
		(net "P5E_CPU1_G1_TX_DP<14>")
	)
	(segment
		(start 97.960434 -230.394002)
		(end 97.93224 -230.410258)
		(width 0.1143)
		(layer "In11.Cu")
		(net "P5E_CPU1_G1_TX_DP<14>")
	)
	(segment
		(start 96.306132 -221.129098)
		(end 96.306132 -221.30893)
		(width 0.1143)
		(layer "In11.Cu")
		(net "P5E_CPU1_G1_TX_DP<14>")
	)
	(segment
		(start 97.497392 -225.36912)
		(end 97.530412 -225.38817)
		(width 0.1143)
		(layer "In11.Cu")
		(net "P5E_CPU1_G1_TX_DP<14>")
	)
	(segment
		(start 96.553274 -222.126556)
		(end 96.554036 -222.127064)
		(width 0.1143)
		(layer "In11.Cu")
		(net "P5E_CPU1_G1_TX_DP<14>")
	)
	(segment
		(start 96.522286 -222.108776)
		(end 96.545908 -222.122492)
		(width 0.1143)
		(layer "In11.Cu")
		(net "P5E_CPU1_G1_TX_DP<14>")
	)
	(segment
		(start 19.190462 -19.137122)
		(end 18.899632 -19.427952)
		(width 0.14224)
		(layer "In11.Cu")
		(net "P5E_CPU1_G1_TX_DP<14>")
	)
	(segment
		(start 142.668498 -142.52194)
		(end 145.190718 -147.736814)
		(width 0.14224)
		(layer "In11.Cu")
		(net "P5E_CPU1_G1_TX_DP<14>")
	)
	(segment
		(start 97.495868 -225.368104)
		(end 97.497392 -225.36912)
		(width 0.1143)
		(layer "In11.Cu")
		(net "P5E_CPU1_G1_TX_DP<14>")
	)
	(segment
		(start 97.965006 -230.391462)
		(end 97.96399 -230.39197)
		(width 0.1143)
		(layer "In11.Cu")
		(net "P5E_CPU1_G1_TX_DP<14>")
	)
	(segment
		(start 98.003106 -227.129086)
		(end 98.000312 -227.131118)
		(width 0.1143)
		(layer "In11.Cu")
		(net "P5E_CPU1_G1_TX_DP<14>")
	)
	(segment
		(start 98.323146 -244.484398)
		(end 98.621088 -244.484398)
		(width 0.1143)
		(layer "In11.Cu")
		(net "P5E_CPU1_G1_TX_DP<14>")
	)
	(segment
		(start 97.968562 -235.899452)
		(end 97.969324 -235.89996)
		(width 0.1143)
		(layer "In11.Cu")
		(net "P5E_CPU1_G1_TX_DP<14>")
	)
	(segment
		(start 97.97034 -239.140492)
		(end 98.002344 -239.159288)
		(width 0.1143)
		(layer "In11.Cu")
		(net "P5E_CPU1_G1_TX_DP<14>")
	)
	(arc
		(start 97.963482 -238.49203)
		(mid 97.777962 -238.810087)
		(end 97.956116 -239.132364)
		(width 0.1143)
		(layer "In11.Cu")
		(net "P5E_CPU1_G1_TX_DP<14>")
	)
	(arc
		(start 98.003106 -232.679748)
		(mid 98.246433 -233.144314)
		(end 98.003106 -233.60888)
		(width 0.1143)
		(layer "In11.Cu")
		(net "P5E_CPU1_G1_TX_DP<14>")
	)
	(arc
		(start 98.003106 -231.059736)
		(mid 98.246433 -231.524302)
		(end 98.003106 -231.988868)
		(width 0.1143)
		(layer "In11.Cu")
		(net "P5E_CPU1_G1_TX_DP<14>")
	)
	(arc
		(start 97.963482 -240.112042)
		(mid 97.777962 -240.430099)
		(end 97.956116 -240.752376)
		(width 0.1143)
		(layer "In11.Cu")
		(net "P5E_CPU1_G1_TX_DP<14>")
	)
	(arc
		(start 98.236532 -244.378734)
		(mid 98.238555 -244.390144)
		(end 98.240342 -244.401594)
		(width 0.1143)
		(layer "In11.Cu")
		(net "P5E_CPU1_G1_TX_DP<14>")
	)
	(arc
		(start 98.002344 -237.539276)
		(mid 98.002725 -237.53953)
		(end 98.003106 -237.539784)
		(width 0.1143)
		(layer "In11.Cu")
		(net "P5E_CPU1_G1_TX_DP<14>")
	)
	(arc
		(start 97.93224 -230.410258)
		(mid 97.81922 -230.544434)
		(end 97.776284 -230.71455)
		(width 0.1143)
		(layer "In11.Cu")
		(net "P5E_CPU1_G1_TX_DP<14>")
	)
	(arc
		(start 98.002344 -239.159288)
		(mid 98.002725 -239.159542)
		(end 98.003106 -239.159796)
		(width 0.1143)
		(layer "In11.Cu")
		(net "P5E_CPU1_G1_TX_DP<14>")
	)
	(arc
		(start 97.063052 -224.579942)
		(mid 97.241865 -224.782292)
		(end 97.306384 -225.044508)
		(width 0.1143)
		(layer "In11.Cu")
		(net "P5E_CPU1_G1_TX_DP<14>")
	)
	(arc
		(start 97.93224 -243.3701)
		(mid 97.783143 -243.674392)
		(end 97.93224 -243.978684)
		(width 0.1143)
		(layer "In11.Cu")
		(net "P5E_CPU1_G1_TX_DP<14>")
	)
	(arc
		(start 97.76841 -225.791014)
		(mid 97.773889 -225.828189)
		(end 97.776284 -225.86569)
		(width 0.1143)
		(layer "In11.Cu")
		(net "P5E_CPU1_G1_TX_DP<14>")
	)
	(arc
		(start 98.246438 -229.90429)
		(mid 98.181202 -230.167881)
		(end 98.000566 -230.370634)
		(width 0.1143)
		(layer "In11.Cu")
		(net "P5E_CPU1_G1_TX_DP<14>")
	)
	(arc
		(start 96.836484 -222.61449)
		(mid 96.878033 -222.785912)
		(end 96.993456 -222.91929)
		(width 0.1143)
		(layer "In11.Cu")
		(net "P5E_CPU1_G1_TX_DP<14>")
	)
	(arc
		(start 97.93224 -232.030016)
		(mid 97.783143 -232.334308)
		(end 97.93224 -232.6386)
		(width 0.1143)
		(layer "In11.Cu")
		(net "P5E_CPU1_G1_TX_DP<14>")
	)
	(arc
		(start 98.003106 -244.019832)
		(mid 98.155093 -244.17634)
		(end 98.236532 -244.378734)
		(width 0.1143)
		(layer "In11.Cu")
		(net "P5E_CPU1_G1_TX_DP<14>")
	)
	(arc
		(start 96.993456 -223.929702)
		(mid 96.836479 -224.234502)
		(end 96.993456 -224.539302)
		(width 0.1143)
		(layer "In11.Cu")
		(net "P5E_CPU1_G1_TX_DP<14>")
	)
	(arc
		(start 98.002344 -242.399312)
		(mid 98.002725 -242.399566)
		(end 98.003106 -242.39982)
		(width 0.1143)
		(layer "In11.Cu")
		(net "P5E_CPU1_G1_TX_DP<14>")
	)
	(arc
		(start 96.36633 -221.804484)
		(mid 96.407585 -221.975455)
		(end 96.522286 -222.108776)
		(width 0.1143)
		(layer "In11.Cu")
		(net "P5E_CPU1_G1_TX_DP<14>")
	)
	(arc
		(start 98.003106 -234.29976)
		(mid 98.246433 -234.764326)
		(end 98.003106 -235.228892)
		(width 0.1143)
		(layer "In11.Cu")
		(net "P5E_CPU1_G1_TX_DP<14>")
	)
	(arc
		(start 98.003106 -242.39982)
		(mid 98.246433 -242.864386)
		(end 98.003106 -243.328952)
		(width 0.1143)
		(layer "In11.Cu")
		(net "P5E_CPU1_G1_TX_DP<14>")
	)
	(arc
		(start 98.002344 -234.299252)
		(mid 98.002725 -234.299506)
		(end 98.003106 -234.29976)
		(width 0.1143)
		(layer "In11.Cu")
		(net "P5E_CPU1_G1_TX_DP<14>")
	)
	(arc
		(start 98.002344 -235.919264)
		(mid 98.002725 -235.919518)
		(end 98.003106 -235.919772)
		(width 0.1143)
		(layer "In11.Cu")
		(net "P5E_CPU1_G1_TX_DP<14>")
	)
	(arc
		(start 97.93224 -227.170234)
		(mid 97.783143 -227.474526)
		(end 97.93224 -227.778818)
		(width 0.1143)
		(layer "In11.Cu")
		(net "P5E_CPU1_G1_TX_DP<14>")
	)
	(arc
		(start 97.96272 -228.77272)
		(mid 97.826302 -228.908593)
		(end 97.776284 -229.094538)
		(width 0.1143)
		(layer "In11.Cu")
		(net "P5E_CPU1_G1_TX_DP<14>")
	)
	(arc
		(start 98.003106 -237.539784)
		(mid 98.246433 -238.00435)
		(end 98.003106 -238.468916)
		(width 0.1143)
		(layer "In11.Cu")
		(net "P5E_CPU1_G1_TX_DP<14>")
	)
	(arc
		(start 97.93224 -233.650028)
		(mid 97.780651 -233.95432)
		(end 97.93224 -234.258612)
		(width 0.1143)
		(layer "In11.Cu")
		(net "P5E_CPU1_G1_TX_DP<14>")
	)
	(arc
		(start 97.776284 -230.71455)
		(mid 97.821964 -230.896961)
		(end 97.95383 -231.031034)
		(width 0.1143)
		(layer "In11.Cu")
		(net "P5E_CPU1_G1_TX_DP<14>")
	)
	(arc
		(start 97.963482 -236.872018)
		(mid 97.777962 -237.190075)
		(end 97.956116 -237.512352)
		(width 0.1143)
		(layer "In11.Cu")
		(net "P5E_CPU1_G1_TX_DP<14>")
	)
	(arc
		(start 98.003106 -239.159796)
		(mid 98.246433 -239.624362)
		(end 98.003106 -240.088928)
		(width 0.1143)
		(layer "In11.Cu")
		(net "P5E_CPU1_G1_TX_DP<14>")
	)
	(arc
		(start 97.776284 -225.86569)
		(mid 97.820348 -226.030913)
		(end 97.933256 -226.159314)
		(width 0.1143)
		(layer "In11.Cu")
		(net "P5E_CPU1_G1_TX_DP<14>")
	)
	(arc
		(start 96.593152 -222.149924)
		(mid 96.771965 -222.352274)
		(end 96.836484 -222.61449)
		(width 0.1143)
		(layer "In11.Cu")
		(net "P5E_CPU1_G1_TX_DP<14>")
	)
	(arc
		(start 97.530412 -225.38817)
		(mid 97.546381 -225.400207)
		(end 97.561908 -225.412808)
		(width 0.1143)
		(layer "In11.Cu")
		(net "P5E_CPU1_G1_TX_DP<14>")
	)
	(arc
		(start 97.063052 -222.95993)
		(mid 97.306379 -223.424496)
		(end 97.063052 -223.889062)
		(width 0.1143)
		(layer "In11.Cu")
		(net "P5E_CPU1_G1_TX_DP<14>")
	)
	(arc
		(start 98.002344 -240.7793)
		(mid 98.002725 -240.779554)
		(end 98.003106 -240.779808)
		(width 0.1143)
		(layer "In11.Cu")
		(net "P5E_CPU1_G1_TX_DP<14>")
	)
	(arc
		(start 97.306384 -225.044508)
		(mid 97.347639 -225.215479)
		(end 97.46234 -225.3488)
		(width 0.1143)
		(layer "In11.Cu")
		(net "P5E_CPU1_G1_TX_DP<14>")
	)
	(arc
		(start 98.003106 -235.919772)
		(mid 98.246433 -236.384338)
		(end 98.003106 -236.848904)
		(width 0.1143)
		(layer "In11.Cu")
		(net "P5E_CPU1_G1_TX_DP<14>")
	)
	(arc
		(start 98.003106 -226.199954)
		(mid 98.246433 -226.66452)
		(end 98.003106 -227.129086)
		(width 0.1143)
		(layer "In11.Cu")
		(net "P5E_CPU1_G1_TX_DP<14>")
	)
	(arc
		(start 98.003106 -240.779808)
		(mid 98.246433 -241.244374)
		(end 98.003106 -241.70894)
		(width 0.1143)
		(layer "In11.Cu")
		(net "P5E_CPU1_G1_TX_DP<14>")
	)
	(arc
		(start 97.776284 -229.094538)
		(mid 97.817046 -229.264422)
		(end 97.930462 -229.397306)
		(width 0.1143)
		(layer "In11.Cu")
		(net "P5E_CPU1_G1_TX_DP<14>")
	)
	(arc
		(start 97.963482 -235.252006)
		(mid 97.777962 -235.570063)
		(end 97.956116 -235.89234)
		(width 0.1143)
		(layer "In11.Cu")
		(net "P5E_CPU1_G1_TX_DP<14>")
	)
	(arc
		(start 98.003106 -229.439724)
		(mid 98.181919 -229.642074)
		(end 98.246438 -229.90429)
		(width 0.1143)
		(layer "In11.Cu")
		(net "P5E_CPU1_G1_TX_DP<14>")
	)
	(arc
		(start 98.003106 -227.819966)
		(mid 98.246433 -228.284532)
		(end 98.003106 -228.749098)
		(width 0.1143)
		(layer "In11.Cu")
		(net "P5E_CPU1_G1_TX_DP<14>")
	)
	(arc
		(start 97.963482 -241.732054)
		(mid 97.777962 -242.050111)
		(end 97.956116 -242.372388)
		(width 0.1143)
		(layer "In11.Cu")
		(net "P5E_CPU1_G1_TX_DP<14>")
	)
	(arc
		(start 97.561908 -225.412808)
		(mid 97.694326 -225.585989)
		(end 97.76841 -225.791014)
		(width 0.1143)
		(layer "In11.Cu")
		(net "P5E_CPU1_G1_TX_DP<14>")
	)
	(segment
		(start 99.08794 -247.99036)
		(end 98.621088 -247.724422)
		(width 0.12954)
		(layer "F.Cu")
		(net "P5E_CPU1_G1_TX_DP<13>")
	)
	(segment
		(start 21.714968 -17.34185)
		(end 21.985478 -17.61236)
		(width 0.12954)
		(layer "F.Cu")
		(net "P5E_CPU1_G1_TX_DP<13>")
	)
	(segment
		(start 21.714968 -16.662146)
		(end 21.714968 -17.34185)
		(width 0.12954)
		(layer "F.Cu")
		(net "P5E_CPU1_G1_TX_DP<13>")
	)
	(segment
		(start 22.010878 -16.366236)
		(end 21.714968 -16.662146)
		(width 0.12954)
		(layer "F.Cu")
		(net "P5E_CPU1_G1_TX_DP<13>")
	)
	(segment
		(start 97.96399 -222.93707)
		(end 97.995486 -222.955358)
		(width 0.1143)
		(layer "In11.Cu")
		(net "P5E_CPU1_G1_TX_DP<13>")
	)
	(segment
		(start 97.296732 -221.05493)
		(end 97.296732 -221.083378)
		(width 0.1143)
		(layer "In11.Cu")
		(net "P5E_CPU1_G1_TX_DP<13>")
	)
	(segment
		(start 97.983802 -223.900492)
		(end 97.982786 -223.901)
		(width 0.1143)
		(layer "In11.Cu")
		(net "P5E_CPU1_G1_TX_DP<13>")
	)
	(segment
		(start 98.872294 -237.498636)
		(end 98.902012 -237.515654)
		(width 0.1143)
		(layer "In11.Cu")
		(net "P5E_CPU1_G1_TX_DP<13>")
	)
	(segment
		(start 98.904044 -236.871764)
		(end 98.903282 -236.872272)
		(width 0.1143)
		(layer "In11.Cu")
		(net "P5E_CPU1_G1_TX_DP<13>")
	)
	(segment
		(start 98.904044 -240.756948)
		(end 98.90506 -240.757456)
		(width 0.1143)
		(layer "In11.Cu")
		(net "P5E_CPU1_G1_TX_DP<13>")
	)
	(segment
		(start 98.903282 -241.732308)
		(end 98.872294 -241.750088)
		(width 0.1143)
		(layer "In11.Cu")
		(net "P5E_CPU1_G1_TX_DP<13>")
	)
	(segment
		(start 98.473006 -247.378982)
		(end 98.43389 -247.401842)
		(width 0.1143)
		(layer "In11.Cu")
		(net "P5E_CPU1_G1_TX_DP<13>")
	)
	(segment
		(start 98.94316 -238.468916)
		(end 98.906584 -238.490252)
		(width 0.1143)
		(layer "In11.Cu")
		(net "P5E_CPU1_G1_TX_DP<13>")
	)
	(segment
		(start 98.903282 -239.136428)
		(end 98.904044 -239.136936)
		(width 0.1143)
		(layer "In11.Cu")
		(net "P5E_CPU1_G1_TX_DP<13>")
	)
	(segment
		(start 98.872294 -234.258612)
		(end 98.902012 -234.27563)
		(width 0.1143)
		(layer "In11.Cu")
		(net "P5E_CPU1_G1_TX_DP<13>")
	)
	(segment
		(start 97.96399 -223.911922)
		(end 97.963228 -223.91243)
		(width 0.1143)
		(layer "In11.Cu")
		(net "P5E_CPU1_G1_TX_DP<13>")
	)
	(segment
		(start 146.971258 -162.43427)
		(end 145.74266 -166.042086)
		(width 0.14224)
		(layer "In11.Cu")
		(net "P5E_CPU1_G1_TX_DP<13>")
	)
	(segment
		(start 98.904044 -238.491776)
		(end 98.872294 -238.510064)
		(width 0.1143)
		(layer "In11.Cu")
		(net "P5E_CPU1_G1_TX_DP<13>")
	)
	(segment
		(start 98.903282 -240.112296)
		(end 98.872294 -240.130076)
		(width 0.1143)
		(layer "In11.Cu")
		(net "P5E_CPU1_G1_TX_DP<13>")
	)
	(segment
		(start 97.96272 -222.936308)
		(end 97.963228 -222.936562)
		(width 0.1143)
		(layer "In11.Cu")
		(net "P5E_CPU1_G1_TX_DP<13>")
	)
	(segment
		(start 98.906584 -243.350288)
		(end 98.90506 -243.351304)
		(width 0.1143)
		(layer "In11.Cu")
		(net "P5E_CPU1_G1_TX_DP<13>")
	)
	(segment
		(start 98.94316 -243.328952)
		(end 98.906584 -243.350288)
		(width 0.1143)
		(layer "In11.Cu")
		(net "P5E_CPU1_G1_TX_DP<13>")
	)
	(segment
		(start 98.323146 -247.724422)
		(end 98.621088 -247.724422)
		(width 0.1143)
		(layer "In11.Cu")
		(net "P5E_CPU1_G1_TX_DP<13>")
	)
	(segment
		(start 98.902012 -234.27563)
		(end 98.903282 -234.276392)
		(width 0.1143)
		(layer "In11.Cu")
		(net "P5E_CPU1_G1_TX_DP<13>")
	)
	(segment
		(start 97.46234 -222.108776)
		(end 97.496376 -222.128334)
		(width 0.1143)
		(layer "In11.Cu")
		(net "P5E_CPU1_G1_TX_DP<13>")
	)
	(segment
		(start 98.903282 -243.996464)
		(end 98.904044 -243.996972)
		(width 0.1143)
		(layer "In11.Cu")
		(net "P5E_CPU1_G1_TX_DP<13>")
	)
	(segment
		(start 97.251012 -221.129098)
		(end 97.251012 -221.30893)
		(width 0.1143)
		(layer "In11.Cu")
		(net "P5E_CPU1_G1_TX_DP<13>")
	)
	(segment
		(start 98.914458 -228.765862)
		(end 98.9076 -228.769926)
		(width 0.1143)
		(layer "In11.Cu")
		(net "P5E_CPU1_G1_TX_DP<13>")
	)
	(segment
		(start 98.904044 -235.251752)
		(end 98.903282 -235.25226)
		(width 0.1143)
		(layer "In11.Cu")
		(net "P5E_CPU1_G1_TX_DP<13>")
	)
	(segment
		(start 98.40341 -225.349308)
		(end 98.43389 -225.367088)
		(width 0.1143)
		(layer "In11.Cu")
		(net "P5E_CPU1_G1_TX_DP<13>")
	)
	(segment
		(start 98.906584 -236.87024)
		(end 98.90506 -236.871256)
		(width 0.1143)
		(layer "In11.Cu")
		(net "P5E_CPU1_G1_TX_DP<13>")
	)
	(segment
		(start 98.872294 -226.158806)
		(end 98.895916 -226.172522)
		(width 0.1143)
		(layer "In11.Cu")
		(net "P5E_CPU1_G1_TX_DP<13>")
	)
	(segment
		(start 98.904044 -239.136936)
		(end 98.90506 -239.137444)
		(width 0.1143)
		(layer "In11.Cu")
		(net "P5E_CPU1_G1_TX_DP<13>")
	)
	(segment
		(start 98.906584 -240.110264)
		(end 98.90506 -240.11128)
		(width 0.1143)
		(layer "In11.Cu")
		(net "P5E_CPU1_G1_TX_DP<13>")
	)
	(segment
		(start 98.904044 -226.177094)
		(end 98.93554 -226.195382)
		(width 0.1143)
		(layer "In11.Cu")
		(net "P5E_CPU1_G1_TX_DP<13>")
	)
	(segment
		(start 98.902012 -245.615714)
		(end 98.903282 -245.616476)
		(width 0.1143)
		(layer "In11.Cu")
		(net "P5E_CPU1_G1_TX_DP<13>")
	)
	(segment
		(start 98.904044 -243.351812)
		(end 98.903282 -243.35232)
		(width 0.1143)
		(layer "In11.Cu")
		(net "P5E_CPU1_G1_TX_DP<13>")
	)
	(segment
		(start 98.870516 -231.017318)
		(end 98.904044 -231.036876)
		(width 0.1143)
		(layer "In11.Cu")
		(net "P5E_CPU1_G1_TX_DP<13>")
	)
	(segment
		(start 98.90506 -243.99748)
		(end 98.94316 -244.019832)
		(width 0.1143)
		(layer "In11.Cu")
		(net "P5E_CPU1_G1_TX_DP<13>")
	)
	(segment
		(start 98.902012 -235.895642)
		(end 98.903282 -235.896404)
		(width 0.1143)
		(layer "In11.Cu")
		(net "P5E_CPU1_G1_TX_DP<13>")
	)
	(segment
		(start 98.904044 -233.63174)
		(end 98.903282 -233.632248)
		(width 0.1143)
		(layer "In11.Cu")
		(net "P5E_CPU1_G1_TX_DP<13>")
	)
	(segment
		(start 98.903282 -234.276392)
		(end 98.904044 -234.2769)
		(width 0.1143)
		(layer "In11.Cu")
		(net "P5E_CPU1_G1_TX_DP<13>")
	)
	(segment
		(start 98.942652 -229.43947)
		(end 98.94316 -229.439724)
		(width 0.1143)
		(layer "In11.Cu")
		(net "P5E_CPU1_G1_TX_DP<13>")
	)
	(segment
		(start 98.904044 -227.151946)
		(end 98.903282 -227.152454)
		(width 0.1143)
		(layer "In11.Cu")
		(net "P5E_CPU1_G1_TX_DP<13>")
	)
	(segment
		(start 98.90506 -235.251244)
		(end 98.904044 -235.251752)
		(width 0.1143)
		(layer "In11.Cu")
		(net "P5E_CPU1_G1_TX_DP<13>")
	)
	(segment
		(start 98.93554 -226.195382)
		(end 98.936302 -226.19589)
		(width 0.1143)
		(layer "In11.Cu")
		(net "P5E_CPU1_G1_TX_DP<13>")
	)
	(segment
		(start 97.996248 -224.575878)
		(end 98.003106 -224.579942)
		(width 0.1143)
		(layer "In11.Cu")
		(net "P5E_CPU1_G1_TX_DP<13>")
	)
	(segment
		(start 98.904044 -235.896912)
		(end 98.90506 -235.89742)
		(width 0.1143)
		(layer "In11.Cu")
		(net "P5E_CPU1_G1_TX_DP<13>")
	)
	(segment
		(start 97.978976 -223.903286)
		(end 97.974404 -223.905826)
		(width 0.1143)
		(layer "In11.Cu")
		(net "P5E_CPU1_G1_TX_DP<13>")
	)
	(segment
		(start 98.906584 -241.730276)
		(end 98.90506 -241.731292)
		(width 0.1143)
		(layer "In11.Cu")
		(net "P5E_CPU1_G1_TX_DP<13>")
	)
	(segment
		(start 97.987612 -223.898206)
		(end 97.985326 -223.899476)
		(width 0.1143)
		(layer "In11.Cu")
		(net "P5E_CPU1_G1_TX_DP<13>")
	)
	(segment
		(start 37.75329 -44.180506)
		(end 51.702462 -59.572144)
		(width 0.14224)
		(layer "In11.Cu")
		(net "P5E_CPU1_G1_TX_DP<13>")
	)
	(segment
		(start 98.903282 -244.972332)
		(end 98.872294 -244.990112)
		(width 0.1143)
		(layer "In11.Cu")
		(net "P5E_CPU1_G1_TX_DP<13>")
	)
	(segment
		(start 98.90506 -240.757456)
		(end 98.94316 -240.779808)
		(width 0.1143)
		(layer "In11.Cu")
		(net "P5E_CPU1_G1_TX_DP<13>")
	)
	(segment
		(start 98.90506 -236.871256)
		(end 98.904044 -236.871764)
		(width 0.1143)
		(layer "In11.Cu")
		(net "P5E_CPU1_G1_TX_DP<13>")
	)
	(segment
		(start 98.870516 -229.397306)
		(end 98.904044 -229.416864)
		(width 0.1143)
		(layer "In11.Cu")
		(net "P5E_CPU1_G1_TX_DP<13>")
	)
	(segment
		(start 98.903282 -233.632248)
		(end 98.872294 -233.650028)
		(width 0.1143)
		(layer "In11.Cu")
		(net "P5E_CPU1_G1_TX_DP<13>")
	)
	(segment
		(start 98.872294 -245.598696)
		(end 98.902012 -245.615714)
		(width 0.1143)
		(layer "In11.Cu")
		(net "P5E_CPU1_G1_TX_DP<13>")
	)
	(segment
		(start 98.903282 -232.65638)
		(end 98.904044 -232.656888)
		(width 0.1143)
		(layer "In11.Cu")
		(net "P5E_CPU1_G1_TX_DP<13>")
	)
	(segment
		(start 97.963228 -223.91243)
		(end 97.93224 -223.93021)
		(width 0.1143)
		(layer "In11.Cu")
		(net "P5E_CPU1_G1_TX_DP<13>")
	)
	(segment
		(start 98.90506 -244.971316)
		(end 98.904044 -244.971824)
		(width 0.1143)
		(layer "In11.Cu")
		(net "P5E_CPU1_G1_TX_DP<13>")
	)
	(segment
		(start 98.904044 -232.011728)
		(end 98.903282 -232.012236)
		(width 0.1143)
		(layer "In11.Cu")
		(net "P5E_CPU1_G1_TX_DP<13>")
	)
	(segment
		(start 98.904044 -240.111788)
		(end 98.903282 -240.112296)
		(width 0.1143)
		(layer "In11.Cu")
		(net "P5E_CPU1_G1_TX_DP<13>")
	)
	(segment
		(start 98.904044 -228.771958)
		(end 98.872294 -228.790246)
		(width 0.1143)
		(layer "In11.Cu")
		(net "P5E_CPU1_G1_TX_DP<13>")
	)
	(segment
		(start 98.90506 -227.797614)
		(end 98.94316 -227.819966)
		(width 0.1143)
		(layer "In11.Cu")
		(net "P5E_CPU1_G1_TX_DP<13>")
	)
	(segment
		(start 98.906584 -232.010204)
		(end 98.90506 -232.01122)
		(width 0.1143)
		(layer "In11.Cu")
		(net "P5E_CPU1_G1_TX_DP<13>")
	)
	(segment
		(start 98.872294 -239.118648)
		(end 98.902012 -239.135666)
		(width 0.1143)
		(layer "In11.Cu")
		(net "P5E_CPU1_G1_TX_DP<13>")
	)
	(segment
		(start 97.963228 -222.936562)
		(end 97.96399 -222.93707)
		(width 0.1143)
		(layer "In11.Cu")
		(net "P5E_CPU1_G1_TX_DP<13>")
	)
	(segment
		(start 98.90506 -241.731292)
		(end 98.904044 -241.7318)
		(width 0.1143)
		(layer "In11.Cu")
		(net "P5E_CPU1_G1_TX_DP<13>")
	)
	(segment
		(start 21.985478 -17.61236)
		(end 21.694648 -17.90319)
		(width 0.14224)
		(layer "In11.Cu")
		(net "P5E_CPU1_G1_TX_DP<13>")
	)
	(segment
		(start 98.90506 -232.657396)
		(end 98.94316 -232.679748)
		(width 0.1143)
		(layer "In11.Cu")
		(net "P5E_CPU1_G1_TX_DP<13>")
	)
	(segment
		(start 98.906584 -228.770434)
		(end 98.90506 -228.77145)
		(width 0.1143)
		(layer "In11.Cu")
		(net "P5E_CPU1_G1_TX_DP<13>")
	)
	(segment
		(start 97.982024 -223.901508)
		(end 97.981008 -223.902016)
		(width 0.1143)
		(layer "In11.Cu")
		(net "P5E_CPU1_G1_TX_DP<13>")
	)
	(segment
		(start 97.996248 -222.955866)
		(end 98.003106 -222.95993)
		(width 0.1143)
		(layer "In11.Cu")
		(net "P5E_CPU1_G1_TX_DP<13>")
	)
	(segment
		(start 143.34236 -141.773656)
		(end 146.195796 -147.67306)
		(width 0.14224)
		(layer "In11.Cu")
		(net "P5E_CPU1_G1_TX_DP<13>")
	)
	(segment
		(start 98.904044 -237.516924)
		(end 98.90506 -237.517432)
		(width 0.1143)
		(layer "In11.Cu")
		(net "P5E_CPU1_G1_TX_DP<13>")
	)
	(segment
		(start 98.91522 -228.765354)
		(end 98.914458 -228.765862)
		(width 0.1143)
		(layer "In11.Cu")
		(net "P5E_CPU1_G1_TX_DP<13>")
	)
	(segment
		(start 97.967546 -223.90989)
		(end 97.96653 -223.910398)
		(width 0.1143)
		(layer "In11.Cu")
		(net "P5E_CPU1_G1_TX_DP<13>")
	)
	(segment
		(start 98.906584 -246.590312)
		(end 98.90506 -246.591328)
		(width 0.1143)
		(layer "In11.Cu")
		(net "P5E_CPU1_G1_TX_DP<13>")
	)
	(segment
		(start 142.334234 -171.07535)
		(end 104.50703 -202.055984)
		(width 0.14224)
		(layer "In11.Cu")
		(net "P5E_CPU1_G1_TX_DP<13>")
	)
	(segment
		(start 104.50703 -202.055984)
		(end 97.296732 -214.2617)
		(width 0.14224)
		(layer "In11.Cu")
		(net "P5E_CPU1_G1_TX_DP<13>")
	)
	(segment
		(start 98.90506 -245.617492)
		(end 98.94316 -245.639844)
		(width 0.1143)
		(layer "In11.Cu")
		(net "P5E_CPU1_G1_TX_DP<13>")
	)
	(segment
		(start 98.90506 -235.89742)
		(end 98.94316 -235.919772)
		(width 0.1143)
		(layer "In11.Cu")
		(net "P5E_CPU1_G1_TX_DP<13>")
	)
	(segment
		(start 98.90506 -233.631232)
		(end 98.904044 -233.63174)
		(width 0.1143)
		(layer "In11.Cu")
		(net "P5E_CPU1_G1_TX_DP<13>")
	)
	(segment
		(start 98.94062 -230.370634)
		(end 98.904044 -230.39197)
		(width 0.1143)
		(layer "In11.Cu")
		(net "P5E_CPU1_G1_TX_DP<13>")
	)
	(segment
		(start 98.43389 -247.401842)
		(end 98.40341 -247.419622)
		(width 0.1143)
		(layer "In11.Cu")
		(net "P5E_CPU1_G1_TX_DP<13>")
	)
	(segment
		(start 97.988374 -223.897698)
		(end 97.987612 -223.898206)
		(width 0.1143)
		(layer "In11.Cu")
		(net "P5E_CPU1_G1_TX_DP<13>")
	)
	(segment
		(start 98.903282 -235.896404)
		(end 98.904044 -235.896912)
		(width 0.1143)
		(layer "In11.Cu")
		(net "P5E_CPU1_G1_TX_DP<13>")
	)
	(segment
		(start 98.936302 -226.19589)
		(end 98.94316 -226.199954)
		(width 0.1143)
		(layer "In11.Cu")
		(net "P5E_CPU1_G1_TX_DP<13>")
	)
	(segment
		(start 98.903282 -227.152454)
		(end 98.872294 -227.170234)
		(width 0.1143)
		(layer "In11.Cu")
		(net "P5E_CPU1_G1_TX_DP<13>")
	)
	(segment
		(start 98.872294 -242.358672)
		(end 98.902012 -242.37569)
		(width 0.1143)
		(layer "In11.Cu")
		(net "P5E_CPU1_G1_TX_DP<13>")
	)
	(segment
		(start 98.872294 -243.978684)
		(end 98.902012 -243.995702)
		(width 0.1143)
		(layer "In11.Cu")
		(net "P5E_CPU1_G1_TX_DP<13>")
	)
	(segment
		(start 98.872294 -232.6386)
		(end 98.902012 -232.655618)
		(width 0.1143)
		(layer "In11.Cu")
		(net "P5E_CPU1_G1_TX_DP<13>")
	)
	(segment
		(start 54.383432 -61.77661)
		(end 143.34236 -141.773656)
		(width 0.14224)
		(layer "In11.Cu")
		(net "P5E_CPU1_G1_TX_DP<13>")
	)
	(segment
		(start 98.902012 -232.655618)
		(end 98.903282 -232.65638)
		(width 0.1143)
		(layer "In11.Cu")
		(net "P5E_CPU1_G1_TX_DP<13>")
	)
	(segment
		(start 98.902012 -242.37569)
		(end 98.903282 -242.376452)
		(width 0.1143)
		(layer "In11.Cu")
		(net "P5E_CPU1_G1_TX_DP<13>")
	)
	(segment
		(start 98.90506 -246.591328)
		(end 98.904044 -246.591836)
		(width 0.1143)
		(layer "In11.Cu")
		(net "P5E_CPU1_G1_TX_DP<13>")
	)
	(segment
		(start 97.306384 -221.364302)
		(end 97.306384 -221.804484)
		(width 0.1143)
		(layer "In11.Cu")
		(net "P5E_CPU1_G1_TX_DP<13>")
	)
	(segment
		(start 98.906584 -238.490252)
		(end 98.90506 -238.491268)
		(width 0.1143)
		(layer "In11.Cu")
		(net "P5E_CPU1_G1_TX_DP<13>")
	)
	(segment
		(start 98.872294 -227.778818)
		(end 98.904044 -227.797106)
		(width 0.1143)
		(layer "In11.Cu")
		(net "P5E_CPU1_G1_TX_DP<13>")
	)
	(segment
		(start 98.94316 -241.70894)
		(end 98.906584 -241.730276)
		(width 0.1143)
		(layer "In11.Cu")
		(net "P5E_CPU1_G1_TX_DP<13>")
	)
	(segment
		(start 98.903282 -236.872272)
		(end 98.872294 -236.890052)
		(width 0.1143)
		(layer "In11.Cu")
		(net "P5E_CPU1_G1_TX_DP<13>")
	)
	(segment
		(start 98.253296 -247.654572)
		(end 98.323146 -247.724422)
		(width 0.1143)
		(layer "In11.Cu")
		(net "P5E_CPU1_G1_TX_DP<13>")
	)
	(segment
		(start 97.963228 -224.556574)
		(end 97.96399 -224.557082)
		(width 0.1143)
		(layer "In11.Cu")
		(net "P5E_CPU1_G1_TX_DP<13>")
	)
	(segment
		(start 98.90506 -237.517432)
		(end 98.94316 -237.539784)
		(width 0.1143)
		(layer "In11.Cu")
		(net "P5E_CPU1_G1_TX_DP<13>")
	)
	(segment
		(start 98.90506 -234.277408)
		(end 98.94316 -234.29976)
		(width 0.1143)
		(layer "In11.Cu")
		(net "P5E_CPU1_G1_TX_DP<13>")
	)
	(segment
		(start 145.74266 -166.042086)
		(end 142.334234 -171.07535)
		(width 0.14224)
		(layer "In11.Cu")
		(net "P5E_CPU1_G1_TX_DP<13>")
	)
	(segment
		(start 98.94316 -244.948964)
		(end 98.906584 -244.9703)
		(width 0.1143)
		(layer "In11.Cu")
		(net "P5E_CPU1_G1_TX_DP<13>")
	)
	(segment
		(start 146.971258 -160.056576)
		(end 146.971258 -162.43427)
		(width 0.14224)
		(layer "In11.Cu")
		(net "P5E_CPU1_G1_TX_DP<13>")
	)
	(segment
		(start 98.94316 -236.848904)
		(end 98.906584 -236.87024)
		(width 0.1143)
		(layer "In11.Cu")
		(net "P5E_CPU1_G1_TX_DP<13>")
	)
	(segment
		(start 98.872294 -235.878624)
		(end 98.902012 -235.895642)
		(width 0.1143)
		(layer "In11.Cu")
		(net "P5E_CPU1_G1_TX_DP<13>")
	)
	(segment
		(start 98.90506 -242.377468)
		(end 98.94316 -242.39982)
		(width 0.1143)
		(layer "In11.Cu")
		(net "P5E_CPU1_G1_TX_DP<13>")
	)
	(segment
		(start 97.981008 -223.902016)
		(end 97.978976 -223.903286)
		(width 0.1143)
		(layer "In11.Cu")
		(net "P5E_CPU1_G1_TX_DP<13>")
	)
	(segment
		(start 97.972372 -223.907096)
		(end 97.969578 -223.90862)
		(width 0.1143)
		(layer "In11.Cu")
		(net "P5E_CPU1_G1_TX_DP<13>")
	)
	(segment
		(start 98.94316 -233.60888)
		(end 98.906584 -233.630216)
		(width 0.1143)
		(layer "In11.Cu")
		(net "P5E_CPU1_G1_TX_DP<13>")
	)
	(segment
		(start 98.904044 -244.971824)
		(end 98.903282 -244.972332)
		(width 0.1143)
		(layer "In11.Cu")
		(net "P5E_CPU1_G1_TX_DP<13>")
	)
	(segment
		(start 98.904044 -234.2769)
		(end 98.90506 -234.277408)
		(width 0.1143)
		(layer "In11.Cu")
		(net "P5E_CPU1_G1_TX_DP<13>")
	)
	(segment
		(start 98.906584 -244.9703)
		(end 98.90506 -244.971316)
		(width 0.1143)
		(layer "In11.Cu")
		(net "P5E_CPU1_G1_TX_DP<13>")
	)
	(segment
		(start 98.904044 -241.7318)
		(end 98.903282 -241.732308)
		(width 0.1143)
		(layer "In11.Cu")
		(net "P5E_CPU1_G1_TX_DP<13>")
	)
	(segment
		(start 98.902012 -243.995702)
		(end 98.903282 -243.996464)
		(width 0.1143)
		(layer "In11.Cu")
		(net "P5E_CPU1_G1_TX_DP<13>")
	)
	(segment
		(start 98.895916 -226.172522)
		(end 98.903282 -226.176586)
		(width 0.1143)
		(layer "In11.Cu")
		(net "P5E_CPU1_G1_TX_DP<13>")
	)
	(segment
		(start 97.96653 -223.910398)
		(end 97.965006 -223.911414)
		(width 0.1143)
		(layer "In11.Cu")
		(net "P5E_CPU1_G1_TX_DP<13>")
	)
	(segment
		(start 98.003106 -223.889062)
		(end 97.988374 -223.897698)
		(width 0.1143)
		(layer "In11.Cu")
		(net "P5E_CPU1_G1_TX_DP<13>")
	)
	(segment
		(start 97.985326 -223.899476)
		(end 97.983802 -223.900492)
		(width 0.1143)
		(layer "In11.Cu")
		(net "P5E_CPU1_G1_TX_DP<13>")
	)
	(segment
		(start 97.995486 -222.955358)
		(end 97.996248 -222.955866)
		(width 0.1143)
		(layer "In11.Cu")
		(net "P5E_CPU1_G1_TX_DP<13>")
	)
	(segment
		(start 98.90506 -240.11128)
		(end 98.904044 -240.111788)
		(width 0.1143)
		(layer "In11.Cu")
		(net "P5E_CPU1_G1_TX_DP<13>")
	)
	(segment
		(start 98.94316 -240.088928)
		(end 98.906584 -240.110264)
		(width 0.1143)
		(layer "In11.Cu")
		(net "P5E_CPU1_G1_TX_DP<13>")
	)
	(segment
		(start 98.90506 -232.01122)
		(end 98.904044 -232.011728)
		(width 0.1143)
		(layer "In11.Cu")
		(net "P5E_CPU1_G1_TX_DP<13>")
	)
	(segment
		(start 98.90506 -228.77145)
		(end 98.904044 -228.771958)
		(width 0.1143)
		(layer "In11.Cu")
		(net "P5E_CPU1_G1_TX_DP<13>")
	)
	(segment
		(start 97.251012 -221.30893)
		(end 97.306384 -221.364302)
		(width 0.1143)
		(layer "In11.Cu")
		(net "P5E_CPU1_G1_TX_DP<13>")
	)
	(segment
		(start 98.903282 -232.012236)
		(end 98.872294 -232.030016)
		(width 0.1143)
		(layer "In11.Cu")
		(net "P5E_CPU1_G1_TX_DP<13>")
	)
	(segment
		(start 97.982786 -223.901)
		(end 97.982024 -223.901508)
		(width 0.1143)
		(layer "In11.Cu")
		(net "P5E_CPU1_G1_TX_DP<13>")
	)
	(segment
		(start 98.904044 -242.37696)
		(end 98.90506 -242.377468)
		(width 0.1143)
		(layer "In11.Cu")
		(net "P5E_CPU1_G1_TX_DP<13>")
	)
	(segment
		(start 98.872294 -240.73866)
		(end 98.902012 -240.755678)
		(width 0.1143)
		(layer "In11.Cu")
		(net "P5E_CPU1_G1_TX_DP<13>")
	)
	(segment
		(start 97.965006 -223.911414)
		(end 97.96399 -223.911922)
		(width 0.1143)
		(layer "In11.Cu")
		(net "P5E_CPU1_G1_TX_DP<13>")
	)
	(segment
		(start 98.94316 -228.749098)
		(end 98.91522 -228.765354)
		(width 0.1143)
		(layer "In11.Cu")
		(net "P5E_CPU1_G1_TX_DP<13>")
	)
	(segment
		(start 98.90506 -243.351304)
		(end 98.904044 -243.351812)
		(width 0.1143)
		(layer "In11.Cu")
		(net "P5E_CPU1_G1_TX_DP<13>")
	)
	(segment
		(start 98.94316 -231.988868)
		(end 98.906584 -232.010204)
		(width 0.1143)
		(layer "In11.Cu")
		(net "P5E_CPU1_G1_TX_DP<13>")
	)
	(segment
		(start 98.9076 -228.769926)
		(end 98.906584 -228.770434)
		(width 0.1143)
		(layer "In11.Cu")
		(net "P5E_CPU1_G1_TX_DP<13>")
	)
	(segment
		(start 98.94316 -235.228892)
		(end 98.906584 -235.250228)
		(width 0.1143)
		(layer "In11.Cu")
		(net "P5E_CPU1_G1_TX_DP<13>")
	)
	(segment
		(start 98.903282 -226.176586)
		(end 98.904044 -226.177094)
		(width 0.1143)
		(layer "In11.Cu")
		(net "P5E_CPU1_G1_TX_DP<13>")
	)
	(segment
		(start 98.903282 -243.35232)
		(end 98.872294 -243.3701)
		(width 0.1143)
		(layer "In11.Cu")
		(net "P5E_CPU1_G1_TX_DP<13>")
	)
	(segment
		(start 98.904044 -232.656888)
		(end 98.90506 -232.657396)
		(width 0.1143)
		(layer "In11.Cu")
		(net "P5E_CPU1_G1_TX_DP<13>")
	)
	(segment
		(start 98.904044 -246.591836)
		(end 98.903282 -246.592344)
		(width 0.1143)
		(layer "In11.Cu")
		(net "P5E_CPU1_G1_TX_DP<13>")
	)
	(segment
		(start 98.904044 -227.797106)
		(end 98.90506 -227.797614)
		(width 0.1143)
		(layer "In11.Cu")
		(net "P5E_CPU1_G1_TX_DP<13>")
	)
	(segment
		(start 98.90506 -239.137444)
		(end 98.94316 -239.159796)
		(width 0.1143)
		(layer "In11.Cu")
		(net "P5E_CPU1_G1_TX_DP<13>")
	)
	(segment
		(start 21.694648 -17.90319)
		(end 21.694648 -20.192746)
		(width 0.14224)
		(layer "In11.Cu")
		(net "P5E_CPU1_G1_TX_DP<13>")
	)
	(segment
		(start 97.296732 -221.083378)
		(end 97.251012 -221.129098)
		(width 0.1143)
		(layer "In11.Cu")
		(net "P5E_CPU1_G1_TX_DP<13>")
	)
	(segment
		(start 98.903282 -235.25226)
		(end 98.872294 -235.27004)
		(width 0.1143)
		(layer "In11.Cu")
		(net "P5E_CPU1_G1_TX_DP<13>")
	)
	(segment
		(start 97.296732 -214.2617)
		(end 97.296732 -221.05493)
		(width 0.14224)
		(layer "In11.Cu")
		(net "P5E_CPU1_G1_TX_DP<13>")
	)
	(segment
		(start 98.902012 -240.755678)
		(end 98.903282 -240.75644)
		(width 0.1143)
		(layer "In11.Cu")
		(net "P5E_CPU1_G1_TX_DP<13>")
	)
	(segment
		(start 98.903282 -242.376452)
		(end 98.904044 -242.37696)
		(width 0.1143)
		(layer "In11.Cu")
		(net "P5E_CPU1_G1_TX_DP<13>")
	)
	(segment
		(start 97.974404 -223.905826)
		(end 97.972372 -223.907096)
		(width 0.1143)
		(layer "In11.Cu")
		(net "P5E_CPU1_G1_TX_DP<13>")
	)
	(segment
		(start 98.904044 -230.39197)
		(end 98.872294 -230.410258)
		(width 0.1143)
		(layer "In11.Cu")
		(net "P5E_CPU1_G1_TX_DP<13>")
	)
	(segment
		(start 98.94316 -246.568976)
		(end 98.906584 -246.590312)
		(width 0.1143)
		(layer "In11.Cu")
		(net "P5E_CPU1_G1_TX_DP<13>")
	)
	(segment
		(start 98.903282 -240.75644)
		(end 98.904044 -240.756948)
		(width 0.1143)
		(layer "In11.Cu")
		(net "P5E_CPU1_G1_TX_DP<13>")
	)
	(segment
		(start 98.904044 -231.036876)
		(end 98.94316 -231.059736)
		(width 0.1143)
		(layer "In11.Cu")
		(net "P5E_CPU1_G1_TX_DP<13>")
	)
	(segment
		(start 97.969578 -223.90862)
		(end 97.968816 -223.909128)
		(width 0.1143)
		(layer "In11.Cu")
		(net "P5E_CPU1_G1_TX_DP<13>")
	)
	(segment
		(start 98.94316 -227.129086)
		(end 98.940366 -227.131118)
		(width 0.1143)
		(layer "In11.Cu")
		(net "P5E_CPU1_G1_TX_DP<13>")
	)
	(segment
		(start 98.904044 -245.616984)
		(end 98.90506 -245.617492)
		(width 0.1143)
		(layer "In11.Cu")
		(net "P5E_CPU1_G1_TX_DP<13>")
	)
	(segment
		(start 98.902012 -239.135666)
		(end 98.903282 -239.136428)
		(width 0.1143)
		(layer "In11.Cu")
		(net "P5E_CPU1_G1_TX_DP<13>")
	)
	(segment
		(start 98.904044 -229.416864)
		(end 98.942652 -229.43947)
		(width 0.1143)
		(layer "In11.Cu")
		(net "P5E_CPU1_G1_TX_DP<13>")
	)
	(segment
		(start 146.195796 -147.67306)
		(end 146.971258 -160.056576)
		(width 0.14224)
		(layer "In11.Cu")
		(net "P5E_CPU1_G1_TX_DP<13>")
	)
	(segment
		(start 98.904044 -243.996972)
		(end 98.90506 -243.99748)
		(width 0.1143)
		(layer "In11.Cu")
		(net "P5E_CPU1_G1_TX_DP<13>")
	)
	(segment
		(start 98.902012 -237.515654)
		(end 98.903282 -237.516416)
		(width 0.1143)
		(layer "In11.Cu")
		(net "P5E_CPU1_G1_TX_DP<13>")
	)
	(segment
		(start 97.968816 -223.909128)
		(end 97.967546 -223.90989)
		(width 0.1143)
		(layer "In11.Cu")
		(net "P5E_CPU1_G1_TX_DP<13>")
	)
	(segment
		(start 51.702462 -59.572144)
		(end 54.383432 -61.77661)
		(width 0.14224)
		(layer "In11.Cu")
		(net "P5E_CPU1_G1_TX_DP<13>")
	)
	(segment
		(start 97.96399 -224.557082)
		(end 97.995486 -224.57537)
		(width 0.1143)
		(layer "In11.Cu")
		(net "P5E_CPU1_G1_TX_DP<13>")
	)
	(segment
		(start 98.940366 -227.131118)
		(end 98.904044 -227.151946)
		(width 0.1143)
		(layer "In11.Cu")
		(net "P5E_CPU1_G1_TX_DP<13>")
	)
	(segment
		(start 98.906584 -235.250228)
		(end 98.90506 -235.251244)
		(width 0.1143)
		(layer "In11.Cu")
		(net "P5E_CPU1_G1_TX_DP<13>")
	)
	(segment
		(start 98.903282 -245.616476)
		(end 98.904044 -245.616984)
		(width 0.1143)
		(layer "In11.Cu")
		(net "P5E_CPU1_G1_TX_DP<13>")
	)
	(segment
		(start 97.995486 -224.57537)
		(end 97.996248 -224.575878)
		(width 0.1143)
		(layer "In11.Cu")
		(net "P5E_CPU1_G1_TX_DP<13>")
	)
	(segment
		(start 97.93224 -224.538794)
		(end 97.963228 -224.556574)
		(width 0.1143)
		(layer "In11.Cu")
		(net "P5E_CPU1_G1_TX_DP<13>")
	)
	(segment
		(start 98.903282 -237.516416)
		(end 98.904044 -237.516924)
		(width 0.1143)
		(layer "In11.Cu")
		(net "P5E_CPU1_G1_TX_DP<13>")
	)
	(segment
		(start 98.906584 -233.630216)
		(end 98.90506 -233.631232)
		(width 0.1143)
		(layer "In11.Cu")
		(net "P5E_CPU1_G1_TX_DP<13>")
	)
	(segment
		(start 98.43389 -225.367088)
		(end 98.473006 -225.389948)
		(width 0.1143)
		(layer "In11.Cu")
		(net "P5E_CPU1_G1_TX_DP<13>")
	)
	(segment
		(start 98.903282 -246.592344)
		(end 98.872294 -246.610124)
		(width 0.1143)
		(layer "In11.Cu")
		(net "P5E_CPU1_G1_TX_DP<13>")
	)
	(segment
		(start 98.90506 -238.491268)
		(end 98.904044 -238.491776)
		(width 0.1143)
		(layer "In11.Cu")
		(net "P5E_CPU1_G1_TX_DP<13>")
	)
	(segment
		(start 21.694648 -20.192746)
		(end 37.75329 -44.180506)
		(width 0.14224)
		(layer "In11.Cu")
		(net "P5E_CPU1_G1_TX_DP<13>")
	)
	(arc
		(start 98.872294 -243.3701)
		(mid 98.716366 -243.674392)
		(end 98.872294 -243.978684)
		(width 0.1143)
		(layer "In11.Cu")
		(net "P5E_CPU1_G1_TX_DP<13>")
	)
	(arc
		(start 97.496376 -222.128334)
		(mid 97.701321 -222.333996)
		(end 97.776284 -222.61449)
		(width 0.1143)
		(layer "In11.Cu")
		(net "P5E_CPU1_G1_TX_DP<13>")
	)
	(arc
		(start 98.872294 -233.650028)
		(mid 98.716366 -233.95432)
		(end 98.872294 -234.258612)
		(width 0.1143)
		(layer "In11.Cu")
		(net "P5E_CPU1_G1_TX_DP<13>")
	)
	(arc
		(start 98.473006 -225.389948)
		(mid 98.651819 -225.592298)
		(end 98.716338 -225.854514)
		(width 0.1143)
		(layer "In11.Cu")
		(net "P5E_CPU1_G1_TX_DP<13>")
	)
	(arc
		(start 98.94316 -226.199954)
		(mid 99.186487 -226.66452)
		(end 98.94316 -227.129086)
		(width 0.1143)
		(layer "In11.Cu")
		(net "P5E_CPU1_G1_TX_DP<13>")
	)
	(arc
		(start 98.94316 -227.819966)
		(mid 99.186487 -228.284532)
		(end 98.94316 -228.749098)
		(width 0.1143)
		(layer "In11.Cu")
		(net "P5E_CPU1_G1_TX_DP<13>")
	)
	(arc
		(start 97.776284 -222.61449)
		(mid 97.826249 -222.800466)
		(end 97.96272 -222.936308)
		(width 0.1143)
		(layer "In11.Cu")
		(net "P5E_CPU1_G1_TX_DP<13>")
	)
	(arc
		(start 98.872294 -246.610124)
		(mid 98.757618 -246.743458)
		(end 98.716338 -246.914416)
		(width 0.1143)
		(layer "In11.Cu")
		(net "P5E_CPU1_G1_TX_DP<13>")
	)
	(arc
		(start 98.40341 -247.419622)
		(mid 98.305645 -247.522598)
		(end 98.253296 -247.654572)
		(width 0.1143)
		(layer "In11.Cu")
		(net "P5E_CPU1_G1_TX_DP<13>")
	)
	(arc
		(start 97.93224 -223.93021)
		(mid 97.781855 -224.234502)
		(end 97.93224 -224.538794)
		(width 0.1143)
		(layer "In11.Cu")
		(net "P5E_CPU1_G1_TX_DP<13>")
	)
	(arc
		(start 98.872294 -228.790246)
		(mid 98.757618 -228.92358)
		(end 98.716338 -229.094538)
		(width 0.1143)
		(layer "In11.Cu")
		(net "P5E_CPU1_G1_TX_DP<13>")
	)
	(arc
		(start 98.94316 -235.919772)
		(mid 99.186487 -236.384338)
		(end 98.94316 -236.848904)
		(width 0.1143)
		(layer "In11.Cu")
		(net "P5E_CPU1_G1_TX_DP<13>")
	)
	(arc
		(start 98.94316 -237.539784)
		(mid 99.186487 -238.00435)
		(end 98.94316 -238.468916)
		(width 0.1143)
		(layer "In11.Cu")
		(net "P5E_CPU1_G1_TX_DP<13>")
	)
	(arc
		(start 98.872294 -235.27004)
		(mid 98.716366 -235.574332)
		(end 98.872294 -235.878624)
		(width 0.1143)
		(layer "In11.Cu")
		(net "P5E_CPU1_G1_TX_DP<13>")
	)
	(arc
		(start 98.872294 -227.170234)
		(mid 98.716366 -227.474526)
		(end 98.872294 -227.778818)
		(width 0.1143)
		(layer "In11.Cu")
		(net "P5E_CPU1_G1_TX_DP<13>")
	)
	(arc
		(start 98.872294 -241.750088)
		(mid 98.716366 -242.05438)
		(end 98.872294 -242.358672)
		(width 0.1143)
		(layer "In11.Cu")
		(net "P5E_CPU1_G1_TX_DP<13>")
	)
	(arc
		(start 98.716338 -246.914416)
		(mid 98.651823 -247.176635)
		(end 98.473006 -247.378982)
		(width 0.1143)
		(layer "In11.Cu")
		(net "P5E_CPU1_G1_TX_DP<13>")
	)
	(arc
		(start 98.716338 -225.854514)
		(mid 98.757593 -226.025485)
		(end 98.872294 -226.158806)
		(width 0.1143)
		(layer "In11.Cu")
		(net "P5E_CPU1_G1_TX_DP<13>")
	)
	(arc
		(start 98.872294 -236.890052)
		(mid 98.716366 -237.194344)
		(end 98.872294 -237.498636)
		(width 0.1143)
		(layer "In11.Cu")
		(net "P5E_CPU1_G1_TX_DP<13>")
	)
	(arc
		(start 98.872294 -244.990112)
		(mid 98.716366 -245.294404)
		(end 98.872294 -245.598696)
		(width 0.1143)
		(layer "In11.Cu")
		(net "P5E_CPU1_G1_TX_DP<13>")
	)
	(arc
		(start 98.94316 -234.29976)
		(mid 99.186487 -234.764326)
		(end 98.94316 -235.228892)
		(width 0.1143)
		(layer "In11.Cu")
		(net "P5E_CPU1_G1_TX_DP<13>")
	)
	(arc
		(start 98.716338 -230.71455)
		(mid 98.7571 -230.884434)
		(end 98.870516 -231.017318)
		(width 0.1143)
		(layer "In11.Cu")
		(net "P5E_CPU1_G1_TX_DP<13>")
	)
	(arc
		(start 98.246438 -225.044508)
		(mid 98.287987 -225.21593)
		(end 98.40341 -225.349308)
		(width 0.1143)
		(layer "In11.Cu")
		(net "P5E_CPU1_G1_TX_DP<13>")
	)
	(arc
		(start 98.94316 -231.059736)
		(mid 99.186487 -231.524302)
		(end 98.94316 -231.988868)
		(width 0.1143)
		(layer "In11.Cu")
		(net "P5E_CPU1_G1_TX_DP<13>")
	)
	(arc
		(start 98.872294 -230.410258)
		(mid 98.757618 -230.543592)
		(end 98.716338 -230.71455)
		(width 0.1143)
		(layer "In11.Cu")
		(net "P5E_CPU1_G1_TX_DP<13>")
	)
	(arc
		(start 98.716338 -229.094538)
		(mid 98.7571 -229.264422)
		(end 98.870516 -229.397306)
		(width 0.1143)
		(layer "In11.Cu")
		(net "P5E_CPU1_G1_TX_DP<13>")
	)
	(arc
		(start 98.003106 -224.579942)
		(mid 98.181919 -224.782292)
		(end 98.246438 -225.044508)
		(width 0.1143)
		(layer "In11.Cu")
		(net "P5E_CPU1_G1_TX_DP<13>")
	)
	(arc
		(start 98.94316 -245.639844)
		(mid 99.186487 -246.10441)
		(end 98.94316 -246.568976)
		(width 0.1143)
		(layer "In11.Cu")
		(net "P5E_CPU1_G1_TX_DP<13>")
	)
	(arc
		(start 98.872294 -240.130076)
		(mid 98.716366 -240.434368)
		(end 98.872294 -240.73866)
		(width 0.1143)
		(layer "In11.Cu")
		(net "P5E_CPU1_G1_TX_DP<13>")
	)
	(arc
		(start 98.94316 -242.39982)
		(mid 99.186487 -242.864386)
		(end 98.94316 -243.328952)
		(width 0.1143)
		(layer "In11.Cu")
		(net "P5E_CPU1_G1_TX_DP<13>")
	)
	(arc
		(start 98.94316 -239.159796)
		(mid 99.186487 -239.624362)
		(end 98.94316 -240.088928)
		(width 0.1143)
		(layer "In11.Cu")
		(net "P5E_CPU1_G1_TX_DP<13>")
	)
	(arc
		(start 98.94316 -244.019832)
		(mid 99.186487 -244.484398)
		(end 98.94316 -244.948964)
		(width 0.1143)
		(layer "In11.Cu")
		(net "P5E_CPU1_G1_TX_DP<13>")
	)
	(arc
		(start 98.872294 -238.510064)
		(mid 98.716366 -238.814356)
		(end 98.872294 -239.118648)
		(width 0.1143)
		(layer "In11.Cu")
		(net "P5E_CPU1_G1_TX_DP<13>")
	)
	(arc
		(start 99.186492 -229.90429)
		(mid 99.121256 -230.167881)
		(end 98.94062 -230.370634)
		(width 0.1143)
		(layer "In11.Cu")
		(net "P5E_CPU1_G1_TX_DP<13>")
	)
	(arc
		(start 98.872294 -232.030016)
		(mid 98.716366 -232.334308)
		(end 98.872294 -232.6386)
		(width 0.1143)
		(layer "In11.Cu")
		(net "P5E_CPU1_G1_TX_DP<13>")
	)
	(arc
		(start 97.306384 -221.804484)
		(mid 97.347639 -221.975455)
		(end 97.46234 -222.108776)
		(width 0.1143)
		(layer "In11.Cu")
		(net "P5E_CPU1_G1_TX_DP<13>")
	)
	(arc
		(start 98.94316 -240.779808)
		(mid 99.186487 -241.244374)
		(end 98.94316 -241.70894)
		(width 0.1143)
		(layer "In11.Cu")
		(net "P5E_CPU1_G1_TX_DP<13>")
	)
	(arc
		(start 98.94316 -229.439724)
		(mid 99.121973 -229.642074)
		(end 99.186492 -229.90429)
		(width 0.1143)
		(layer "In11.Cu")
		(net "P5E_CPU1_G1_TX_DP<13>")
	)
	(arc
		(start 98.94316 -232.679748)
		(mid 99.186487 -233.144314)
		(end 98.94316 -233.60888)
		(width 0.1143)
		(layer "In11.Cu")
		(net "P5E_CPU1_G1_TX_DP<13>")
	)
	(arc
		(start 98.003106 -222.95993)
		(mid 98.246433 -223.424496)
		(end 98.003106 -223.889062)
		(width 0.1143)
		(layer "In11.Cu")
		(net "P5E_CPU1_G1_TX_DP<13>")
	)
	(segment
		(start 101.907848 -246.370348)
		(end 101.440996 -246.10441)
		(width 0.12954)
		(layer "F.Cu")
		(net "P5E_CPU1_G1_TX_DP<12>")
	)
	(segment
		(start 24.508968 -18.86585)
		(end 24.779478 -19.13636)
		(width 0.12954)
		(layer "F.Cu")
		(net "P5E_CPU1_G1_TX_DP<12>")
	)
	(segment
		(start 24.804878 -17.890236)
		(end 24.508968 -18.186146)
		(width 0.12954)
		(layer "F.Cu")
		(net "P5E_CPU1_G1_TX_DP<12>")
	)
	(segment
		(start 24.508968 -18.186146)
		(end 24.508968 -18.86585)
		(width 0.12954)
		(layer "F.Cu")
		(net "P5E_CPU1_G1_TX_DP<12>")
	)
	(segment
		(start 99.813364 -235.879132)
		(end 99.843844 -235.896912)
		(width 0.1143)
		(layer "In11.Cu")
		(net "P5E_CPU1_G1_TX_DP<12>")
	)
	(segment
		(start 99.843844 -235.896912)
		(end 99.88296 -235.919772)
		(width 0.1143)
		(layer "In11.Cu")
		(net "P5E_CPU1_G1_TX_DP<12>")
	)
	(segment
		(start 144.095216 -141.181582)
		(end 147.12696 -147.450048)
		(width 0.14224)
		(layer "In11.Cu")
		(net "P5E_CPU1_G1_TX_DP<12>")
	)
	(segment
		(start 99.843844 -239.136936)
		(end 99.88296 -239.159796)
		(width 0.1143)
		(layer "In11.Cu")
		(net "P5E_CPU1_G1_TX_DP<12>")
	)
	(segment
		(start 99.843844 -231.036876)
		(end 99.88296 -231.059736)
		(width 0.1143)
		(layer "In11.Cu")
		(net "P5E_CPU1_G1_TX_DP<12>")
	)
	(segment
		(start 98.402902 -222.10903)
		(end 98.473006 -222.149924)
		(width 0.1143)
		(layer "In11.Cu")
		(net "P5E_CPU1_G1_TX_DP<12>")
	)
	(segment
		(start 99.37496 -225.367596)
		(end 99.376484 -225.368612)
		(width 0.1143)
		(layer "In11.Cu")
		(net "P5E_CPU1_G1_TX_DP<12>")
	)
	(segment
		(start 98.87331 -222.91929)
		(end 98.90379 -222.93707)
		(width 0.1143)
		(layer "In11.Cu")
		(net "P5E_CPU1_G1_TX_DP<12>")
	)
	(segment
		(start 143.476472 -171.347384)
		(end 105.281222 -202.62723)
		(width 0.14224)
		(layer "In11.Cu")
		(net "P5E_CPU1_G1_TX_DP<12>")
	)
	(segment
		(start 99.373944 -225.367088)
		(end 99.37496 -225.367596)
		(width 0.1143)
		(layer "In11.Cu")
		(net "P5E_CPU1_G1_TX_DP<12>")
	)
	(segment
		(start 98.241612 -221.05493)
		(end 98.241612 -221.083378)
		(width 0.1143)
		(layer "In11.Cu")
		(net "P5E_CPU1_G1_TX_DP<12>")
	)
	(segment
		(start 99.813364 -232.639108)
		(end 99.843844 -232.656888)
		(width 0.1143)
		(layer "In11.Cu")
		(net "P5E_CPU1_G1_TX_DP<12>")
	)
	(segment
		(start 99.88296 -231.988868)
		(end 99.843844 -232.011728)
		(width 0.1143)
		(layer "In11.Cu")
		(net "P5E_CPU1_G1_TX_DP<12>")
	)
	(segment
		(start 99.843844 -238.491776)
		(end 99.813364 -238.509556)
		(width 0.1143)
		(layer "In11.Cu")
		(net "P5E_CPU1_G1_TX_DP<12>")
	)
	(segment
		(start 101.06025 -246.021606)
		(end 101.143054 -246.10441)
		(width 0.1143)
		(layer "In11.Cu")
		(net "P5E_CPU1_G1_TX_DP<12>")
	)
	(segment
		(start 99.843844 -226.177094)
		(end 99.88296 -226.199954)
		(width 0.1143)
		(layer "In11.Cu")
		(net "P5E_CPU1_G1_TX_DP<12>")
	)
	(segment
		(start 98.241612 -214.546434)
		(end 98.241612 -221.05493)
		(width 0.14224)
		(layer "In11.Cu")
		(net "P5E_CPU1_G1_TX_DP<12>")
	)
	(segment
		(start 147.12696 -147.450048)
		(end 147.914614 -160.026858)
		(width 0.14224)
		(layer "In11.Cu")
		(net "P5E_CPU1_G1_TX_DP<12>")
	)
	(segment
		(start 98.195892 -221.30893)
		(end 98.246184 -221.359222)
		(width 0.1143)
		(layer "In11.Cu")
		(net "P5E_CPU1_G1_TX_DP<12>")
	)
	(segment
		(start 99.843844 -229.416864)
		(end 99.88296 -229.439724)
		(width 0.1143)
		(layer "In11.Cu")
		(net "P5E_CPU1_G1_TX_DP<12>")
	)
	(segment
		(start 100.281994 -244.788436)
		(end 100.325174 -244.813582)
		(width 0.1143)
		(layer "In11.Cu")
		(net "P5E_CPU1_G1_TX_DP<12>")
	)
	(segment
		(start 146.617436 -166.499794)
		(end 143.476472 -171.347384)
		(width 0.14224)
		(layer "In11.Cu")
		(net "P5E_CPU1_G1_TX_DP<12>")
	)
	(segment
		(start 99.88296 -227.129086)
		(end 99.843844 -227.151946)
		(width 0.1143)
		(layer "In11.Cu")
		(net "P5E_CPU1_G1_TX_DP<12>")
	)
	(segment
		(start 98.241612 -221.083378)
		(end 98.195892 -221.129098)
		(width 0.1143)
		(layer "In11.Cu")
		(net "P5E_CPU1_G1_TX_DP<12>")
	)
	(segment
		(start 99.88296 -236.848904)
		(end 99.843844 -236.871764)
		(width 0.1143)
		(layer "In11.Cu")
		(net "P5E_CPU1_G1_TX_DP<12>")
	)
	(segment
		(start 99.843844 -237.516924)
		(end 99.88296 -237.539784)
		(width 0.1143)
		(layer "In11.Cu")
		(net "P5E_CPU1_G1_TX_DP<12>")
	)
	(segment
		(start 98.195892 -221.129098)
		(end 98.195892 -221.30893)
		(width 0.1143)
		(layer "In11.Cu")
		(net "P5E_CPU1_G1_TX_DP<12>")
	)
	(segment
		(start 99.371912 -225.365818)
		(end 99.373182 -225.36658)
		(width 0.1143)
		(layer "In11.Cu")
		(net "P5E_CPU1_G1_TX_DP<12>")
	)
	(segment
		(start 99.88042 -230.370634)
		(end 99.813364 -230.40975)
		(width 0.1143)
		(layer "In11.Cu")
		(net "P5E_CPU1_G1_TX_DP<12>")
	)
	(segment
		(start 100.78339 -245.61673)
		(end 100.822252 -245.639336)
		(width 0.1143)
		(layer "In11.Cu")
		(net "P5E_CPU1_G1_TX_DP<12>")
	)
	(segment
		(start 147.914614 -160.026858)
		(end 147.914614 -162.663378)
		(width 0.14224)
		(layer "In11.Cu")
		(net "P5E_CPU1_G1_TX_DP<12>")
	)
	(segment
		(start 99.813364 -240.739168)
		(end 99.843844 -240.756948)
		(width 0.1143)
		(layer "In11.Cu")
		(net "P5E_CPU1_G1_TX_DP<12>")
	)
	(segment
		(start 99.843844 -242.37696)
		(end 99.88296 -242.39982)
		(width 0.1143)
		(layer "In11.Cu")
		(net "P5E_CPU1_G1_TX_DP<12>")
	)
	(segment
		(start 99.813364 -237.499144)
		(end 99.843844 -237.516924)
		(width 0.1143)
		(layer "In11.Cu")
		(net "P5E_CPU1_G1_TX_DP<12>")
	)
	(segment
		(start 99.843844 -241.7318)
		(end 99.813364 -241.74958)
		(width 0.1143)
		(layer "In11.Cu")
		(net "P5E_CPU1_G1_TX_DP<12>")
	)
	(segment
		(start 99.811332 -231.01808)
		(end 99.843844 -231.036876)
		(width 0.1143)
		(layer "In11.Cu")
		(net "P5E_CPU1_G1_TX_DP<12>")
	)
	(segment
		(start 99.369372 -225.364548)
		(end 99.371912 -225.365818)
		(width 0.1143)
		(layer "In11.Cu")
		(net "P5E_CPU1_G1_TX_DP<12>")
	)
	(segment
		(start 99.843844 -227.151946)
		(end 99.813364 -227.169726)
		(width 0.1143)
		(layer "In11.Cu")
		(net "P5E_CPU1_G1_TX_DP<12>")
	)
	(segment
		(start 99.88296 -240.088928)
		(end 99.843844 -240.111788)
		(width 0.1143)
		(layer "In11.Cu")
		(net "P5E_CPU1_G1_TX_DP<12>")
	)
	(segment
		(start 99.882452 -228.749352)
		(end 99.843844 -228.771958)
		(width 0.1143)
		(layer "In11.Cu")
		(net "P5E_CPU1_G1_TX_DP<12>")
	)
	(segment
		(start 98.402648 -222.10903)
		(end 98.402902 -222.10903)
		(width 0.1143)
		(layer "In11.Cu")
		(net "P5E_CPU1_G1_TX_DP<12>")
	)
	(segment
		(start 99.843844 -240.756948)
		(end 99.88296 -240.779808)
		(width 0.1143)
		(layer "In11.Cu")
		(net "P5E_CPU1_G1_TX_DP<12>")
	)
	(segment
		(start 99.88296 -238.468916)
		(end 99.843844 -238.491776)
		(width 0.1143)
		(layer "In11.Cu")
		(net "P5E_CPU1_G1_TX_DP<12>")
	)
	(segment
		(start 99.813364 -226.159314)
		(end 99.843844 -226.177094)
		(width 0.1143)
		(layer "In11.Cu")
		(net "P5E_CPU1_G1_TX_DP<12>")
	)
	(segment
		(start 99.88296 -228.749098)
		(end 99.882452 -228.749352)
		(width 0.1143)
		(layer "In11.Cu")
		(net "P5E_CPU1_G1_TX_DP<12>")
	)
	(segment
		(start 99.813364 -239.119156)
		(end 99.843844 -239.136936)
		(width 0.1143)
		(layer "In11.Cu")
		(net "P5E_CPU1_G1_TX_DP<12>")
	)
	(segment
		(start 99.342194 -225.3488)
		(end 99.366832 -225.363024)
		(width 0.1143)
		(layer "In11.Cu")
		(net "P5E_CPU1_G1_TX_DP<12>")
	)
	(segment
		(start 54.383432 -60.507626)
		(end 144.095216 -141.181582)
		(width 0.14224)
		(layer "In11.Cu")
		(net "P5E_CPU1_G1_TX_DP<12>")
	)
	(segment
		(start 24.488648 -19.42719)
		(end 24.488648 -20.192746)
		(width 0.14224)
		(layer "In11.Cu")
		(net "P5E_CPU1_G1_TX_DP<12>")
	)
	(segment
		(start 98.246184 -221.359222)
		(end 98.246184 -221.804484)
		(width 0.1143)
		(layer "In11.Cu")
		(net "P5E_CPU1_G1_TX_DP<12>")
	)
	(segment
		(start 100.608638 -245.303802)
		(end 100.608638 -245.313454)
		(width 0.1143)
		(layer "In11.Cu")
		(net "P5E_CPU1_G1_TX_DP<12>")
	)
	(segment
		(start 101.143054 -246.10441)
		(end 101.440996 -246.10441)
		(width 0.1143)
		(layer "In11.Cu")
		(net "P5E_CPU1_G1_TX_DP<12>")
	)
	(segment
		(start 99.813364 -243.979192)
		(end 99.843844 -243.996972)
		(width 0.1143)
		(layer "In11.Cu")
		(net "P5E_CPU1_G1_TX_DP<12>")
	)
	(segment
		(start 99.366832 -225.363024)
		(end 99.367848 -225.363532)
		(width 0.1143)
		(layer "In11.Cu")
		(net "P5E_CPU1_G1_TX_DP<12>")
	)
	(segment
		(start 99.843844 -233.63174)
		(end 99.813364 -233.64952)
		(width 0.1143)
		(layer "In11.Cu")
		(net "P5E_CPU1_G1_TX_DP<12>")
	)
	(segment
		(start 99.843844 -232.656888)
		(end 99.88296 -232.679748)
		(width 0.1143)
		(layer "In11.Cu")
		(net "P5E_CPU1_G1_TX_DP<12>")
	)
	(segment
		(start 147.914614 -162.663378)
		(end 146.617436 -166.499794)
		(width 0.14224)
		(layer "In11.Cu")
		(net "P5E_CPU1_G1_TX_DP<12>")
	)
	(segment
		(start 98.942906 -223.889062)
		(end 98.90379 -223.911922)
		(width 0.1143)
		(layer "In11.Cu")
		(net "P5E_CPU1_G1_TX_DP<12>")
	)
	(segment
		(start 24.779478 -19.13636)
		(end 24.488648 -19.42719)
		(width 0.14224)
		(layer "In11.Cu")
		(net "P5E_CPU1_G1_TX_DP<12>")
	)
	(segment
		(start 52.243482 -58.750962)
		(end 54.383432 -60.507626)
		(width 0.14224)
		(layer "In11.Cu")
		(net "P5E_CPU1_G1_TX_DP<12>")
	)
	(segment
		(start 99.88296 -243.328952)
		(end 99.843844 -243.351812)
		(width 0.1143)
		(layer "In11.Cu")
		(net "P5E_CPU1_G1_TX_DP<12>")
	)
	(segment
		(start 99.843844 -243.351812)
		(end 99.813364 -243.369592)
		(width 0.1143)
		(layer "In11.Cu")
		(net "P5E_CPU1_G1_TX_DP<12>")
	)
	(segment
		(start 99.813364 -242.35918)
		(end 99.843844 -242.37696)
		(width 0.1143)
		(layer "In11.Cu")
		(net "P5E_CPU1_G1_TX_DP<12>")
	)
	(segment
		(start 99.843844 -234.2769)
		(end 99.88296 -234.29976)
		(width 0.1143)
		(layer "In11.Cu")
		(net "P5E_CPU1_G1_TX_DP<12>")
	)
	(segment
		(start 99.843844 -232.011728)
		(end 99.813364 -232.029508)
		(width 0.1143)
		(layer "In11.Cu")
		(net "P5E_CPU1_G1_TX_DP<12>")
	)
	(segment
		(start 98.90379 -224.557082)
		(end 98.942906 -224.579942)
		(width 0.1143)
		(layer "In11.Cu")
		(net "P5E_CPU1_G1_TX_DP<12>")
	)
	(segment
		(start 99.373182 -225.36658)
		(end 99.373944 -225.367088)
		(width 0.1143)
		(layer "In11.Cu")
		(net "P5E_CPU1_G1_TX_DP<12>")
	)
	(segment
		(start 99.88296 -233.60888)
		(end 99.843844 -233.63174)
		(width 0.1143)
		(layer "In11.Cu")
		(net "P5E_CPU1_G1_TX_DP<12>")
	)
	(segment
		(start 99.843844 -243.996972)
		(end 99.88296 -244.019832)
		(width 0.1143)
		(layer "In11.Cu")
		(net "P5E_CPU1_G1_TX_DP<12>")
	)
	(segment
		(start 99.813364 -227.779326)
		(end 99.843844 -227.797106)
		(width 0.1143)
		(layer "In11.Cu")
		(net "P5E_CPU1_G1_TX_DP<12>")
	)
	(segment
		(start 98.90379 -223.911922)
		(end 98.87331 -223.929702)
		(width 0.1143)
		(layer "In11.Cu")
		(net "P5E_CPU1_G1_TX_DP<12>")
	)
	(segment
		(start 99.843844 -235.251752)
		(end 99.813364 -235.269532)
		(width 0.1143)
		(layer "In11.Cu")
		(net "P5E_CPU1_G1_TX_DP<12>")
	)
	(segment
		(start 99.367848 -225.363532)
		(end 99.369372 -225.364548)
		(width 0.1143)
		(layer "In11.Cu")
		(net "P5E_CPU1_G1_TX_DP<12>")
	)
	(segment
		(start 99.843844 -228.771958)
		(end 99.813364 -228.789738)
		(width 0.1143)
		(layer "In11.Cu")
		(net "P5E_CPU1_G1_TX_DP<12>")
	)
	(segment
		(start 98.87331 -224.539302)
		(end 98.90379 -224.557082)
		(width 0.1143)
		(layer "In11.Cu")
		(net "P5E_CPU1_G1_TX_DP<12>")
	)
	(segment
		(start 24.488648 -20.192746)
		(end 39.701216 -44.49064)
		(width 0.14224)
		(layer "In11.Cu")
		(net "P5E_CPU1_G1_TX_DP<12>")
	)
	(segment
		(start 99.843844 -227.797106)
		(end 99.88296 -227.819966)
		(width 0.1143)
		(layer "In11.Cu")
		(net "P5E_CPU1_G1_TX_DP<12>")
	)
	(segment
		(start 99.813364 -234.25912)
		(end 99.843844 -234.2769)
		(width 0.1143)
		(layer "In11.Cu")
		(net "P5E_CPU1_G1_TX_DP<12>")
	)
	(segment
		(start 99.376484 -225.368612)
		(end 99.41306 -225.389948)
		(width 0.1143)
		(layer "In11.Cu")
		(net "P5E_CPU1_G1_TX_DP<12>")
	)
	(segment
		(start 98.90379 -222.93707)
		(end 98.942906 -222.95993)
		(width 0.1143)
		(layer "In11.Cu")
		(net "P5E_CPU1_G1_TX_DP<12>")
	)
	(segment
		(start 105.281222 -202.62723)
		(end 98.241612 -214.546434)
		(width 0.14224)
		(layer "In11.Cu")
		(net "P5E_CPU1_G1_TX_DP<12>")
	)
	(segment
		(start 99.843844 -236.871764)
		(end 99.813364 -236.889544)
		(width 0.1143)
		(layer "In11.Cu")
		(net "P5E_CPU1_G1_TX_DP<12>")
	)
	(segment
		(start 99.843844 -240.111788)
		(end 99.813364 -240.129568)
		(width 0.1143)
		(layer "In11.Cu")
		(net "P5E_CPU1_G1_TX_DP<12>")
	)
	(segment
		(start 99.88296 -241.70894)
		(end 99.843844 -241.7318)
		(width 0.1143)
		(layer "In11.Cu")
		(net "P5E_CPU1_G1_TX_DP<12>")
	)
	(segment
		(start 99.811332 -229.398068)
		(end 99.843844 -229.416864)
		(width 0.1143)
		(layer "In11.Cu")
		(net "P5E_CPU1_G1_TX_DP<12>")
	)
	(segment
		(start 99.88296 -235.228892)
		(end 99.843844 -235.251752)
		(width 0.1143)
		(layer "In11.Cu")
		(net "P5E_CPU1_G1_TX_DP<12>")
	)
	(segment
		(start 39.701216 -44.49064)
		(end 52.243482 -58.750962)
		(width 0.14224)
		(layer "In11.Cu")
		(net "P5E_CPU1_G1_TX_DP<12>")
	)
	(arc
		(start 99.88296 -231.059736)
		(mid 100.126287 -231.524302)
		(end 99.88296 -231.988868)
		(width 0.1143)
		(layer "In11.Cu")
		(net "P5E_CPU1_G1_TX_DP<12>")
	)
	(arc
		(start 99.41306 -225.389948)
		(mid 99.591873 -225.592298)
		(end 99.656392 -225.854514)
		(width 0.1143)
		(layer "In11.Cu")
		(net "P5E_CPU1_G1_TX_DP<12>")
	)
	(arc
		(start 99.813364 -238.509556)
		(mid 99.656387 -238.814356)
		(end 99.813364 -239.119156)
		(width 0.1143)
		(layer "In11.Cu")
		(net "P5E_CPU1_G1_TX_DP<12>")
	)
	(arc
		(start 99.813364 -227.169726)
		(mid 99.656387 -227.474526)
		(end 99.813364 -227.779326)
		(width 0.1143)
		(layer "In11.Cu")
		(net "P5E_CPU1_G1_TX_DP<12>")
	)
	(arc
		(start 99.813364 -236.889544)
		(mid 99.656387 -237.194344)
		(end 99.813364 -237.499144)
		(width 0.1143)
		(layer "In11.Cu")
		(net "P5E_CPU1_G1_TX_DP<12>")
	)
	(arc
		(start 99.656392 -229.094538)
		(mid 99.697358 -229.264944)
		(end 99.811332 -229.398068)
		(width 0.1143)
		(layer "In11.Cu")
		(net "P5E_CPU1_G1_TX_DP<12>")
	)
	(arc
		(start 99.88296 -226.199954)
		(mid 100.126287 -226.66452)
		(end 99.88296 -227.129086)
		(width 0.1143)
		(layer "In11.Cu")
		(net "P5E_CPU1_G1_TX_DP<12>")
	)
	(arc
		(start 99.88296 -239.159796)
		(mid 100.126287 -239.624362)
		(end 99.88296 -240.088928)
		(width 0.1143)
		(layer "In11.Cu")
		(net "P5E_CPU1_G1_TX_DP<12>")
	)
	(arc
		(start 99.813364 -235.269532)
		(mid 99.656387 -235.574332)
		(end 99.813364 -235.879132)
		(width 0.1143)
		(layer "In11.Cu")
		(net "P5E_CPU1_G1_TX_DP<12>")
	)
	(arc
		(start 100.126292 -244.484398)
		(mid 100.167485 -244.655187)
		(end 100.281994 -244.788436)
		(width 0.1143)
		(layer "In11.Cu")
		(net "P5E_CPU1_G1_TX_DP<12>")
	)
	(arc
		(start 99.813364 -230.40975)
		(mid 99.697937 -230.543126)
		(end 99.656392 -230.71455)
		(width 0.1143)
		(layer "In11.Cu")
		(net "P5E_CPU1_G1_TX_DP<12>")
	)
	(arc
		(start 100.823014 -245.639844)
		(mid 100.975001 -245.796352)
		(end 101.05644 -245.998746)
		(width 0.1143)
		(layer "In11.Cu")
		(net "P5E_CPU1_G1_TX_DP<12>")
	)
	(arc
		(start 99.88296 -240.779808)
		(mid 100.126287 -241.244374)
		(end 99.88296 -241.70894)
		(width 0.1143)
		(layer "In11.Cu")
		(net "P5E_CPU1_G1_TX_DP<12>")
	)
	(arc
		(start 99.813364 -232.029508)
		(mid 99.656387 -232.334308)
		(end 99.813364 -232.639108)
		(width 0.1143)
		(layer "In11.Cu")
		(net "P5E_CPU1_G1_TX_DP<12>")
	)
	(arc
		(start 99.88296 -234.29976)
		(mid 100.126287 -234.764326)
		(end 99.88296 -235.228892)
		(width 0.1143)
		(layer "In11.Cu")
		(net "P5E_CPU1_G1_TX_DP<12>")
	)
	(arc
		(start 99.656392 -230.71455)
		(mid 99.697358 -230.884956)
		(end 99.811332 -231.01808)
		(width 0.1143)
		(layer "In11.Cu")
		(net "P5E_CPU1_G1_TX_DP<12>")
	)
	(arc
		(start 99.656392 -225.854514)
		(mid 99.697941 -226.025936)
		(end 99.813364 -226.159314)
		(width 0.1143)
		(layer "In11.Cu")
		(net "P5E_CPU1_G1_TX_DP<12>")
	)
	(arc
		(start 99.186238 -225.044508)
		(mid 99.227493 -225.215479)
		(end 99.342194 -225.3488)
		(width 0.1143)
		(layer "In11.Cu")
		(net "P5E_CPU1_G1_TX_DP<12>")
	)
	(arc
		(start 99.88296 -232.679748)
		(mid 100.126287 -233.144314)
		(end 99.88296 -233.60888)
		(width 0.1143)
		(layer "In11.Cu")
		(net "P5E_CPU1_G1_TX_DP<12>")
	)
	(arc
		(start 101.05644 -245.998746)
		(mid 101.058463 -246.010156)
		(end 101.06025 -246.021606)
		(width 0.1143)
		(layer "In11.Cu")
		(net "P5E_CPU1_G1_TX_DP<12>")
	)
	(arc
		(start 99.813364 -240.129568)
		(mid 99.656387 -240.434368)
		(end 99.813364 -240.739168)
		(width 0.1143)
		(layer "In11.Cu")
		(net "P5E_CPU1_G1_TX_DP<12>")
	)
	(arc
		(start 99.88296 -237.539784)
		(mid 100.126287 -238.00435)
		(end 99.88296 -238.468916)
		(width 0.1143)
		(layer "In11.Cu")
		(net "P5E_CPU1_G1_TX_DP<12>")
	)
	(arc
		(start 99.813364 -228.789738)
		(mid 99.697937 -228.923114)
		(end 99.656392 -229.094538)
		(width 0.1143)
		(layer "In11.Cu")
		(net "P5E_CPU1_G1_TX_DP<12>")
	)
	(arc
		(start 99.88296 -244.019832)
		(mid 100.061773 -244.222182)
		(end 100.126292 -244.484398)
		(width 0.1143)
		(layer "In11.Cu")
		(net "P5E_CPU1_G1_TX_DP<12>")
	)
	(arc
		(start 99.813364 -233.64952)
		(mid 99.656387 -233.95432)
		(end 99.813364 -234.25912)
		(width 0.1143)
		(layer "In11.Cu")
		(net "P5E_CPU1_G1_TX_DP<12>")
	)
	(arc
		(start 100.325174 -244.813582)
		(mid 100.532658 -245.020669)
		(end 100.608638 -245.303802)
		(width 0.1143)
		(layer "In11.Cu")
		(net "P5E_CPU1_G1_TX_DP<12>")
	)
	(arc
		(start 98.942906 -222.95993)
		(mid 99.186233 -223.424496)
		(end 98.942906 -223.889062)
		(width 0.1143)
		(layer "In11.Cu")
		(net "P5E_CPU1_G1_TX_DP<12>")
	)
	(arc
		(start 99.88296 -227.819966)
		(mid 100.126287 -228.284532)
		(end 99.88296 -228.749098)
		(width 0.1143)
		(layer "In11.Cu")
		(net "P5E_CPU1_G1_TX_DP<12>")
	)
	(arc
		(start 98.246184 -221.804484)
		(mid 98.287586 -221.975681)
		(end 98.402648 -222.10903)
		(width 0.1143)
		(layer "In11.Cu")
		(net "P5E_CPU1_G1_TX_DP<12>")
	)
	(arc
		(start 99.88296 -235.919772)
		(mid 100.126287 -236.384338)
		(end 99.88296 -236.848904)
		(width 0.1143)
		(layer "In11.Cu")
		(net "P5E_CPU1_G1_TX_DP<12>")
	)
	(arc
		(start 100.822252 -245.639336)
		(mid 100.822633 -245.63959)
		(end 100.823014 -245.639844)
		(width 0.1143)
		(layer "In11.Cu")
		(net "P5E_CPU1_G1_TX_DP<12>")
	)
	(arc
		(start 99.813364 -243.369592)
		(mid 99.656387 -243.674392)
		(end 99.813364 -243.979192)
		(width 0.1143)
		(layer "In11.Cu")
		(net "P5E_CPU1_G1_TX_DP<12>")
	)
	(arc
		(start 98.473006 -222.149924)
		(mid 98.651819 -222.352274)
		(end 98.716338 -222.61449)
		(width 0.1143)
		(layer "In11.Cu")
		(net "P5E_CPU1_G1_TX_DP<12>")
	)
	(arc
		(start 99.813364 -241.74958)
		(mid 99.656387 -242.05438)
		(end 99.813364 -242.35918)
		(width 0.1143)
		(layer "In11.Cu")
		(net "P5E_CPU1_G1_TX_DP<12>")
	)
	(arc
		(start 98.87331 -223.929702)
		(mid 98.716333 -224.234502)
		(end 98.87331 -224.539302)
		(width 0.1143)
		(layer "In11.Cu")
		(net "P5E_CPU1_G1_TX_DP<12>")
	)
	(arc
		(start 100.126292 -229.90429)
		(mid 100.061056 -230.167881)
		(end 99.88042 -230.370634)
		(width 0.1143)
		(layer "In11.Cu")
		(net "P5E_CPU1_G1_TX_DP<12>")
	)
	(arc
		(start 99.88296 -229.439724)
		(mid 100.061773 -229.642074)
		(end 100.126292 -229.90429)
		(width 0.1143)
		(layer "In11.Cu")
		(net "P5E_CPU1_G1_TX_DP<12>")
	)
	(arc
		(start 99.88296 -242.39982)
		(mid 100.126287 -242.864386)
		(end 99.88296 -243.328952)
		(width 0.1143)
		(layer "In11.Cu")
		(net "P5E_CPU1_G1_TX_DP<12>")
	)
	(arc
		(start 98.942906 -224.579942)
		(mid 99.121719 -224.782292)
		(end 99.186238 -225.044508)
		(width 0.1143)
		(layer "In11.Cu")
		(net "P5E_CPU1_G1_TX_DP<12>")
	)
	(arc
		(start 100.608638 -245.313454)
		(mid 100.655528 -245.488405)
		(end 100.78339 -245.61673)
		(width 0.1143)
		(layer "In11.Cu")
		(net "P5E_CPU1_G1_TX_DP<12>")
	)
	(arc
		(start 98.716338 -222.61449)
		(mid 98.757887 -222.785912)
		(end 98.87331 -222.91929)
		(width 0.1143)
		(layer "In11.Cu")
		(net "P5E_CPU1_G1_TX_DP<12>")
	)
	(segment
		(start 27.302968 -16.662146)
		(end 27.302968 -17.34185)
		(width 0.12954)
		(layer "F.Cu")
		(net "P5E_CPU1_G1_TX_DP<11>")
	)
	(segment
		(start 27.598878 -16.366236)
		(end 27.302968 -16.662146)
		(width 0.12954)
		(layer "F.Cu")
		(net "P5E_CPU1_G1_TX_DP<11>")
	)
	(segment
		(start 101.907848 -244.750336)
		(end 101.440996 -244.484398)
		(width 0.12954)
		(layer "F.Cu")
		(net "P5E_CPU1_G1_TX_DP<11>")
	)
	(segment
		(start 27.302968 -17.34185)
		(end 27.573478 -17.61236)
		(width 0.12954)
		(layer "F.Cu")
		(net "P5E_CPU1_G1_TX_DP<11>")
	)
	(segment
		(start 100.820474 -230.370634)
		(end 100.784914 -230.391462)
		(width 0.1143)
		(layer "In11.Cu")
		(net "P5E_CPU1_G1_TX_DP<11>")
	)
	(segment
		(start 100.752148 -227.778818)
		(end 100.783898 -227.797106)
		(width 0.1143)
		(layer "In11.Cu")
		(net "P5E_CPU1_G1_TX_DP<11>")
	)
	(segment
		(start 100.783898 -234.2769)
		(end 100.819458 -234.29722)
		(width 0.1143)
		(layer "In11.Cu")
		(net "P5E_CPU1_G1_TX_DP<11>")
	)
	(segment
		(start 101.143054 -244.484398)
		(end 101.440996 -244.484398)
		(width 0.1143)
		(layer "In11.Cu")
		(net "P5E_CPU1_G1_TX_DP<11>")
	)
	(segment
		(start 100.789232 -235.89996)
		(end 100.81514 -235.914946)
		(width 0.1143)
		(layer "In11.Cu")
		(net "P5E_CPU1_G1_TX_DP<11>")
	)
	(segment
		(start 100.75037 -229.397306)
		(end 100.783898 -229.416864)
		(width 0.1143)
		(layer "In11.Cu")
		(net "P5E_CPU1_G1_TX_DP<11>")
	)
	(segment
		(start 100.752148 -243.978684)
		(end 100.783898 -243.996972)
		(width 0.1143)
		(layer "In11.Cu")
		(net "P5E_CPU1_G1_TX_DP<11>")
	)
	(segment
		(start 27.573478 -17.61236)
		(end 27.282648 -17.90319)
		(width 0.14224)
		(layer "In11.Cu")
		(net "P5E_CPU1_G1_TX_DP<11>")
	)
	(segment
		(start 100.795074 -228.765354)
		(end 100.794312 -228.765862)
		(width 0.1143)
		(layer "In11.Cu")
		(net "P5E_CPU1_G1_TX_DP<11>")
	)
	(segment
		(start 100.786438 -228.770434)
		(end 100.784914 -228.77145)
		(width 0.1143)
		(layer "In11.Cu")
		(net "P5E_CPU1_G1_TX_DP<11>")
	)
	(segment
		(start 147.539456 -166.80688)
		(end 144.23009 -171.936664)
		(width 0.14224)
		(layer "In11.Cu")
		(net "P5E_CPU1_G1_TX_DP<11>")
	)
	(segment
		(start 100.823014 -241.70894)
		(end 100.80498 -241.719608)
		(width 0.1143)
		(layer "In11.Cu")
		(net "P5E_CPU1_G1_TX_DP<11>")
	)
	(segment
		(start 100.819458 -234.29722)
		(end 100.822252 -234.299252)
		(width 0.1143)
		(layer "In11.Cu")
		(net "P5E_CPU1_G1_TX_DP<11>")
	)
	(segment
		(start 99.186492 -221.05493)
		(end 99.186492 -221.083378)
		(width 0.1143)
		(layer "In11.Cu")
		(net "P5E_CPU1_G1_TX_DP<11>")
	)
	(segment
		(start 100.3173 -225.36912)
		(end 100.35032 -225.38817)
		(width 0.1143)
		(layer "In11.Cu")
		(net "P5E_CPU1_G1_TX_DP<11>")
	)
	(segment
		(start 100.783136 -232.65638)
		(end 100.783898 -232.656888)
		(width 0.1143)
		(layer "In11.Cu")
		(net "P5E_CPU1_G1_TX_DP<11>")
	)
	(segment
		(start 100.804726 -240.099596)
		(end 100.78339 -240.112042)
		(width 0.1143)
		(layer "In11.Cu")
		(net "P5E_CPU1_G1_TX_DP<11>")
	)
	(segment
		(start 100.794312 -228.765862)
		(end 100.787454 -228.769926)
		(width 0.1143)
		(layer "In11.Cu")
		(net "P5E_CPU1_G1_TX_DP<11>")
	)
	(segment
		(start 144.23009 -171.936664)
		(end 106.16819 -203.119736)
		(width 0.14224)
		(layer "In11.Cu")
		(net "P5E_CPU1_G1_TX_DP<11>")
	)
	(segment
		(start 100.783136 -228.772466)
		(end 100.782628 -228.77272)
		(width 0.1143)
		(layer "In11.Cu")
		(net "P5E_CPU1_G1_TX_DP<11>")
	)
	(segment
		(start 100.80498 -238.479584)
		(end 100.804726 -238.479584)
		(width 0.1143)
		(layer "In11.Cu")
		(net "P5E_CPU1_G1_TX_DP<11>")
	)
	(segment
		(start 100.823014 -233.60888)
		(end 100.783898 -233.63174)
		(width 0.1143)
		(layer "In11.Cu")
		(net "P5E_CPU1_G1_TX_DP<11>")
	)
	(segment
		(start 100.776024 -240.752376)
		(end 100.78847 -240.759488)
		(width 0.1143)
		(layer "In11.Cu")
		(net "P5E_CPU1_G1_TX_DP<11>")
	)
	(segment
		(start 99.186492 -214.878666)
		(end 99.186492 -221.05493)
		(width 0.14224)
		(layer "In11.Cu")
		(net "P5E_CPU1_G1_TX_DP<11>")
	)
	(segment
		(start 100.823014 -227.129086)
		(end 100.82022 -227.131118)
		(width 0.1143)
		(layer "In11.Cu")
		(net "P5E_CPU1_G1_TX_DP<11>")
	)
	(segment
		(start 100.752148 -232.6386)
		(end 100.783136 -232.65638)
		(width 0.1143)
		(layer "In11.Cu")
		(net "P5E_CPU1_G1_TX_DP<11>")
	)
	(segment
		(start 100.81514 -235.914946)
		(end 100.815902 -235.915454)
		(width 0.1143)
		(layer "In11.Cu")
		(net "P5E_CPU1_G1_TX_DP<11>")
	)
	(segment
		(start 100.783898 -227.151946)
		(end 100.752148 -227.170234)
		(width 0.1143)
		(layer "In11.Cu")
		(net "P5E_CPU1_G1_TX_DP<11>")
	)
	(segment
		(start 100.783898 -233.63174)
		(end 100.752148 -233.650028)
		(width 0.1143)
		(layer "In11.Cu")
		(net "P5E_CPU1_G1_TX_DP<11>")
	)
	(segment
		(start 99.843844 -222.93707)
		(end 99.88296 -222.95993)
		(width 0.1143)
		(layer "In11.Cu")
		(net "P5E_CPU1_G1_TX_DP<11>")
	)
	(segment
		(start 100.783898 -227.797106)
		(end 100.823014 -227.819966)
		(width 0.1143)
		(layer "In11.Cu")
		(net "P5E_CPU1_G1_TX_DP<11>")
	)
	(segment
		(start 100.784914 -228.77145)
		(end 100.783898 -228.771958)
		(width 0.1143)
		(layer "In11.Cu")
		(net "P5E_CPU1_G1_TX_DP<11>")
	)
	(segment
		(start 100.80498 -241.719608)
		(end 100.804726 -241.719608)
		(width 0.1143)
		(layer "In11.Cu")
		(net "P5E_CPU1_G1_TX_DP<11>")
	)
	(segment
		(start 100.783136 -230.392478)
		(end 100.781866 -230.39324)
		(width 0.1143)
		(layer "In11.Cu")
		(net "P5E_CPU1_G1_TX_DP<11>")
	)
	(segment
		(start 27.282648 -20.192746)
		(end 41.989248 -45.305218)
		(width 0.14224)
		(layer "In11.Cu")
		(net "P5E_CPU1_G1_TX_DP<11>")
	)
	(segment
		(start 100.787454 -228.769926)
		(end 100.786438 -228.770434)
		(width 0.1143)
		(layer "In11.Cu")
		(net "P5E_CPU1_G1_TX_DP<11>")
	)
	(segment
		(start 100.776024 -237.512352)
		(end 100.78847 -237.519464)
		(width 0.1143)
		(layer "In11.Cu")
		(net "P5E_CPU1_G1_TX_DP<11>")
	)
	(segment
		(start 100.823014 -240.088928)
		(end 100.80498 -240.099596)
		(width 0.1143)
		(layer "In11.Cu")
		(net "P5E_CPU1_G1_TX_DP<11>")
	)
	(segment
		(start 100.78847 -235.899452)
		(end 100.789232 -235.89996)
		(width 0.1143)
		(layer "In11.Cu")
		(net "P5E_CPU1_G1_TX_DP<11>")
	)
	(segment
		(start 99.813364 -222.91929)
		(end 99.843844 -222.93707)
		(width 0.1143)
		(layer "In11.Cu")
		(net "P5E_CPU1_G1_TX_DP<11>")
	)
	(segment
		(start 100.783898 -226.177094)
		(end 100.823014 -226.199954)
		(width 0.1143)
		(layer "In11.Cu")
		(net "P5E_CPU1_G1_TX_DP<11>")
	)
	(segment
		(start 100.823014 -243.328952)
		(end 100.783898 -243.351812)
		(width 0.1143)
		(layer "In11.Cu")
		(net "P5E_CPU1_G1_TX_DP<11>")
	)
	(segment
		(start 100.78847 -242.3795)
		(end 100.789232 -242.380008)
		(width 0.1143)
		(layer "In11.Cu")
		(net "P5E_CPU1_G1_TX_DP<11>")
	)
	(segment
		(start 100.773738 -231.031034)
		(end 100.823014 -231.059736)
		(width 0.1143)
		(layer "In11.Cu")
		(net "P5E_CPU1_G1_TX_DP<11>")
	)
	(segment
		(start 100.790248 -239.140492)
		(end 100.822252 -239.159288)
		(width 0.1143)
		(layer "In11.Cu")
		(net "P5E_CPU1_G1_TX_DP<11>")
	)
	(segment
		(start 148.9075 -162.788346)
		(end 147.539456 -166.80688)
		(width 0.14224)
		(layer "In11.Cu")
		(net "P5E_CPU1_G1_TX_DP<11>")
	)
	(segment
		(start 100.823014 -238.468916)
		(end 100.80498 -238.479584)
		(width 0.1143)
		(layer "In11.Cu")
		(net "P5E_CPU1_G1_TX_DP<11>")
	)
	(segment
		(start 100.823014 -231.988868)
		(end 100.783898 -232.011728)
		(width 0.1143)
		(layer "In11.Cu")
		(net "P5E_CPU1_G1_TX_DP<11>")
	)
	(segment
		(start 99.843844 -223.911922)
		(end 99.813364 -223.929702)
		(width 0.1143)
		(layer "In11.Cu")
		(net "P5E_CPU1_G1_TX_DP<11>")
	)
	(segment
		(start 99.813364 -224.539302)
		(end 99.843844 -224.557082)
		(width 0.1143)
		(layer "In11.Cu")
		(net "P5E_CPU1_G1_TX_DP<11>")
	)
	(segment
		(start 100.78847 -237.519464)
		(end 100.789232 -237.519972)
		(width 0.1143)
		(layer "In11.Cu")
		(net "P5E_CPU1_G1_TX_DP<11>")
	)
	(segment
		(start 100.282248 -225.3488)
		(end 100.313998 -225.367088)
		(width 0.1143)
		(layer "In11.Cu")
		(net "P5E_CPU1_G1_TX_DP<11>")
	)
	(segment
		(start 99.843844 -224.557082)
		(end 99.88296 -224.579942)
		(width 0.1143)
		(layer "In11.Cu")
		(net "P5E_CPU1_G1_TX_DP<11>")
	)
	(segment
		(start 144.78889 -140.469366)
		(end 148.116036 -147.348702)
		(width 0.14224)
		(layer "In11.Cu")
		(net "P5E_CPU1_G1_TX_DP<11>")
	)
	(segment
		(start 100.789232 -239.139984)
		(end 100.790248 -239.140492)
		(width 0.1143)
		(layer "In11.Cu")
		(net "P5E_CPU1_G1_TX_DP<11>")
	)
	(segment
		(start 100.789232 -240.759996)
		(end 100.790248 -240.760504)
		(width 0.1143)
		(layer "In11.Cu")
		(net "P5E_CPU1_G1_TX_DP<11>")
	)
	(segment
		(start 100.784914 -232.657396)
		(end 100.823014 -232.679748)
		(width 0.1143)
		(layer "In11.Cu")
		(net "P5E_CPU1_G1_TX_DP<11>")
	)
	(segment
		(start 99.140772 -221.30893)
		(end 99.186238 -221.354396)
		(width 0.1143)
		(layer "In11.Cu")
		(net "P5E_CPU1_G1_TX_DP<11>")
	)
	(segment
		(start 100.804726 -238.479584)
		(end 100.78339 -238.49203)
		(width 0.1143)
		(layer "In11.Cu")
		(net "P5E_CPU1_G1_TX_DP<11>")
	)
	(segment
		(start 100.790248 -242.380516)
		(end 100.822252 -242.399312)
		(width 0.1143)
		(layer "In11.Cu")
		(net "P5E_CPU1_G1_TX_DP<11>")
	)
	(segment
		(start 106.16819 -203.119736)
		(end 99.186492 -214.878666)
		(width 0.14224)
		(layer "In11.Cu")
		(net "P5E_CPU1_G1_TX_DP<11>")
	)
	(segment
		(start 100.783898 -229.416864)
		(end 100.823014 -229.439724)
		(width 0.1143)
		(layer "In11.Cu")
		(net "P5E_CPU1_G1_TX_DP<11>")
	)
	(segment
		(start 100.783898 -232.011728)
		(end 100.752148 -232.030016)
		(width 0.1143)
		(layer "In11.Cu")
		(net "P5E_CPU1_G1_TX_DP<11>")
	)
	(segment
		(start 99.88296 -223.889062)
		(end 99.843844 -223.911922)
		(width 0.1143)
		(layer "In11.Cu")
		(net "P5E_CPU1_G1_TX_DP<11>")
	)
	(segment
		(start 100.815902 -235.915454)
		(end 100.822252 -235.919264)
		(width 0.1143)
		(layer "In11.Cu")
		(net "P5E_CPU1_G1_TX_DP<11>")
	)
	(segment
		(start 100.823014 -236.848904)
		(end 100.80498 -236.859572)
		(width 0.1143)
		(layer "In11.Cu")
		(net "P5E_CPU1_G1_TX_DP<11>")
	)
	(segment
		(start 99.186238 -221.354396)
		(end 99.186238 -221.804484)
		(width 0.1143)
		(layer "In11.Cu")
		(net "P5E_CPU1_G1_TX_DP<11>")
	)
	(segment
		(start 100.804726 -236.859572)
		(end 100.78339 -236.872018)
		(width 0.1143)
		(layer "In11.Cu")
		(net "P5E_CPU1_G1_TX_DP<11>")
	)
	(segment
		(start 99.365816 -222.122492)
		(end 99.373182 -222.126556)
		(width 0.1143)
		(layer "In11.Cu")
		(net "P5E_CPU1_G1_TX_DP<11>")
	)
	(segment
		(start 100.78847 -240.759488)
		(end 100.789232 -240.759996)
		(width 0.1143)
		(layer "In11.Cu")
		(net "P5E_CPU1_G1_TX_DP<11>")
	)
	(segment
		(start 54.383686 -59.172348)
		(end 144.78889 -140.469366)
		(width 0.14224)
		(layer "In11.Cu")
		(net "P5E_CPU1_G1_TX_DP<11>")
	)
	(segment
		(start 100.790248 -240.760504)
		(end 100.822252 -240.7793)
		(width 0.1143)
		(layer "In11.Cu")
		(net "P5E_CPU1_G1_TX_DP<11>")
	)
	(segment
		(start 100.80498 -236.859572)
		(end 100.804726 -236.859572)
		(width 0.1143)
		(layer "In11.Cu")
		(net "P5E_CPU1_G1_TX_DP<11>")
	)
	(segment
		(start 100.786946 -235.89869)
		(end 100.78847 -235.899452)
		(width 0.1143)
		(layer "In11.Cu")
		(net "P5E_CPU1_G1_TX_DP<11>")
	)
	(segment
		(start 41.989248 -45.305218)
		(end 52.63007 -57.739788)
		(width 0.14224)
		(layer "In11.Cu")
		(net "P5E_CPU1_G1_TX_DP<11>")
	)
	(segment
		(start 101.06025 -244.401594)
		(end 101.143054 -244.484398)
		(width 0.1143)
		(layer "In11.Cu")
		(net "P5E_CPU1_G1_TX_DP<11>")
	)
	(segment
		(start 100.823014 -228.749098)
		(end 100.795074 -228.765354)
		(width 0.1143)
		(layer "In11.Cu")
		(net "P5E_CPU1_G1_TX_DP<11>")
	)
	(segment
		(start 100.315776 -225.368104)
		(end 100.3173 -225.36912)
		(width 0.1143)
		(layer "In11.Cu")
		(net "P5E_CPU1_G1_TX_DP<11>")
	)
	(segment
		(start 100.804726 -235.23956)
		(end 100.78339 -235.252006)
		(width 0.1143)
		(layer "In11.Cu")
		(net "P5E_CPU1_G1_TX_DP<11>")
	)
	(segment
		(start 100.783898 -243.351812)
		(end 100.752148 -243.3701)
		(width 0.1143)
		(layer "In11.Cu")
		(net "P5E_CPU1_G1_TX_DP<11>")
	)
	(segment
		(start 100.82022 -227.131118)
		(end 100.783898 -227.151946)
		(width 0.1143)
		(layer "In11.Cu")
		(net "P5E_CPU1_G1_TX_DP<11>")
	)
	(segment
		(start 100.776024 -242.372388)
		(end 100.78847 -242.3795)
		(width 0.1143)
		(layer "In11.Cu")
		(net "P5E_CPU1_G1_TX_DP<11>")
	)
	(segment
		(start 100.776024 -239.132364)
		(end 100.78847 -239.139476)
		(width 0.1143)
		(layer "In11.Cu")
		(net "P5E_CPU1_G1_TX_DP<11>")
	)
	(segment
		(start 99.373944 -222.127064)
		(end 99.37496 -222.127572)
		(width 0.1143)
		(layer "In11.Cu")
		(net "P5E_CPU1_G1_TX_DP<11>")
	)
	(segment
		(start 148.116036 -147.348702)
		(end 148.9075 -159.995616)
		(width 0.14224)
		(layer "In11.Cu")
		(net "P5E_CPU1_G1_TX_DP<11>")
	)
	(segment
		(start 100.313998 -225.367088)
		(end 100.315776 -225.368104)
		(width 0.1143)
		(layer "In11.Cu")
		(net "P5E_CPU1_G1_TX_DP<11>")
	)
	(segment
		(start 100.80498 -235.23956)
		(end 100.804726 -235.23956)
		(width 0.1143)
		(layer "In11.Cu")
		(net "P5E_CPU1_G1_TX_DP<11>")
	)
	(segment
		(start 27.282648 -17.90319)
		(end 27.282648 -20.192746)
		(width 0.14224)
		(layer "In11.Cu")
		(net "P5E_CPU1_G1_TX_DP<11>")
	)
	(segment
		(start 99.342194 -222.108776)
		(end 99.365816 -222.122492)
		(width 0.1143)
		(layer "In11.Cu")
		(net "P5E_CPU1_G1_TX_DP<11>")
	)
	(segment
		(start 100.789232 -242.380008)
		(end 100.790248 -242.380516)
		(width 0.1143)
		(layer "In11.Cu")
		(net "P5E_CPU1_G1_TX_DP<11>")
	)
	(segment
		(start 99.140772 -221.129098)
		(end 99.140772 -221.30893)
		(width 0.1143)
		(layer "In11.Cu")
		(net "P5E_CPU1_G1_TX_DP<11>")
	)
	(segment
		(start 100.752148 -234.258612)
		(end 100.783898 -234.2769)
		(width 0.1143)
		(layer "In11.Cu")
		(net "P5E_CPU1_G1_TX_DP<11>")
	)
	(segment
		(start 100.780342 -230.394002)
		(end 100.752148 -230.410258)
		(width 0.1143)
		(layer "In11.Cu")
		(net "P5E_CPU1_G1_TX_DP<11>")
	)
	(segment
		(start 100.78847 -239.139476)
		(end 100.789232 -239.139984)
		(width 0.1143)
		(layer "In11.Cu")
		(net "P5E_CPU1_G1_TX_DP<11>")
	)
	(segment
		(start 148.9075 -159.995616)
		(end 148.9075 -162.788346)
		(width 0.14224)
		(layer "In11.Cu")
		(net "P5E_CPU1_G1_TX_DP<11>")
	)
	(segment
		(start 100.823014 -235.228892)
		(end 100.80498 -235.23956)
		(width 0.1143)
		(layer "In11.Cu")
		(net "P5E_CPU1_G1_TX_DP<11>")
	)
	(segment
		(start 52.63007 -57.739788)
		(end 54.383686 -59.172348)
		(width 0.14224)
		(layer "In11.Cu")
		(net "P5E_CPU1_G1_TX_DP<11>")
	)
	(segment
		(start 100.80498 -240.099596)
		(end 100.804726 -240.099596)
		(width 0.1143)
		(layer "In11.Cu")
		(net "P5E_CPU1_G1_TX_DP<11>")
	)
	(segment
		(start 100.784914 -230.391462)
		(end 100.783898 -230.39197)
		(width 0.1143)
		(layer "In11.Cu")
		(net "P5E_CPU1_G1_TX_DP<11>")
	)
	(segment
		(start 100.789232 -237.519972)
		(end 100.790248 -237.52048)
		(width 0.1143)
		(layer "In11.Cu")
		(net "P5E_CPU1_G1_TX_DP<11>")
	)
	(segment
		(start 99.37496 -222.127572)
		(end 99.41306 -222.149924)
		(width 0.1143)
		(layer "In11.Cu")
		(net "P5E_CPU1_G1_TX_DP<11>")
	)
	(segment
		(start 100.783898 -230.39197)
		(end 100.783136 -230.392478)
		(width 0.1143)
		(layer "In11.Cu")
		(net "P5E_CPU1_G1_TX_DP<11>")
	)
	(segment
		(start 99.373182 -222.126556)
		(end 99.373944 -222.127064)
		(width 0.1143)
		(layer "In11.Cu")
		(net "P5E_CPU1_G1_TX_DP<11>")
	)
	(segment
		(start 100.776024 -235.89234)
		(end 100.786946 -235.89869)
		(width 0.1143)
		(layer "In11.Cu")
		(net "P5E_CPU1_G1_TX_DP<11>")
	)
	(segment
		(start 100.783898 -232.656888)
		(end 100.784914 -232.657396)
		(width 0.1143)
		(layer "In11.Cu")
		(net "P5E_CPU1_G1_TX_DP<11>")
	)
	(segment
		(start 100.804726 -241.719608)
		(end 100.78339 -241.732054)
		(width 0.1143)
		(layer "In11.Cu")
		(net "P5E_CPU1_G1_TX_DP<11>")
	)
	(segment
		(start 100.781866 -230.39324)
		(end 100.780342 -230.394002)
		(width 0.1143)
		(layer "In11.Cu")
		(net "P5E_CPU1_G1_TX_DP<11>")
	)
	(segment
		(start 100.753164 -226.159314)
		(end 100.783898 -226.177094)
		(width 0.1143)
		(layer "In11.Cu")
		(net "P5E_CPU1_G1_TX_DP<11>")
	)
	(segment
		(start 99.186492 -221.083378)
		(end 99.140772 -221.129098)
		(width 0.1143)
		(layer "In11.Cu")
		(net "P5E_CPU1_G1_TX_DP<11>")
	)
	(segment
		(start 100.783898 -243.996972)
		(end 100.823014 -244.019832)
		(width 0.1143)
		(layer "In11.Cu")
		(net "P5E_CPU1_G1_TX_DP<11>")
	)
	(segment
		(start 100.783898 -228.771958)
		(end 100.783136 -228.772466)
		(width 0.1143)
		(layer "In11.Cu")
		(net "P5E_CPU1_G1_TX_DP<11>")
	)
	(segment
		(start 100.790248 -237.52048)
		(end 100.822252 -237.539276)
		(width 0.1143)
		(layer "In11.Cu")
		(net "P5E_CPU1_G1_TX_DP<11>")
	)
	(arc
		(start 99.88296 -224.579942)
		(mid 100.061773 -224.782292)
		(end 100.126292 -225.044508)
		(width 0.1143)
		(layer "In11.Cu")
		(net "P5E_CPU1_G1_TX_DP<11>")
	)
	(arc
		(start 100.782628 -228.77272)
		(mid 100.64621 -228.908593)
		(end 100.596192 -229.094538)
		(width 0.1143)
		(layer "In11.Cu")
		(net "P5E_CPU1_G1_TX_DP<11>")
	)
	(arc
		(start 100.752148 -232.030016)
		(mid 100.603051 -232.334308)
		(end 100.752148 -232.6386)
		(width 0.1143)
		(layer "In11.Cu")
		(net "P5E_CPU1_G1_TX_DP<11>")
	)
	(arc
		(start 100.596192 -230.71455)
		(mid 100.641872 -230.896961)
		(end 100.773738 -231.031034)
		(width 0.1143)
		(layer "In11.Cu")
		(net "P5E_CPU1_G1_TX_DP<11>")
	)
	(arc
		(start 100.78339 -238.49203)
		(mid 100.59787 -238.810087)
		(end 100.776024 -239.132364)
		(width 0.1143)
		(layer "In11.Cu")
		(net "P5E_CPU1_G1_TX_DP<11>")
	)
	(arc
		(start 100.78339 -240.112042)
		(mid 100.59787 -240.430099)
		(end 100.776024 -240.752376)
		(width 0.1143)
		(layer "In11.Cu")
		(net "P5E_CPU1_G1_TX_DP<11>")
	)
	(arc
		(start 100.823014 -237.539784)
		(mid 101.066341 -238.00435)
		(end 100.823014 -238.468916)
		(width 0.1143)
		(layer "In11.Cu")
		(net "P5E_CPU1_G1_TX_DP<11>")
	)
	(arc
		(start 100.588318 -225.791014)
		(mid 100.593797 -225.828189)
		(end 100.596192 -225.86569)
		(width 0.1143)
		(layer "In11.Cu")
		(net "P5E_CPU1_G1_TX_DP<11>")
	)
	(arc
		(start 100.752148 -230.410258)
		(mid 100.639128 -230.544434)
		(end 100.596192 -230.71455)
		(width 0.1143)
		(layer "In11.Cu")
		(net "P5E_CPU1_G1_TX_DP<11>")
	)
	(arc
		(start 100.822252 -239.159288)
		(mid 100.822633 -239.159542)
		(end 100.823014 -239.159796)
		(width 0.1143)
		(layer "In11.Cu")
		(net "P5E_CPU1_G1_TX_DP<11>")
	)
	(arc
		(start 100.823014 -226.199954)
		(mid 101.066341 -226.66452)
		(end 100.823014 -227.129086)
		(width 0.1143)
		(layer "In11.Cu")
		(net "P5E_CPU1_G1_TX_DP<11>")
	)
	(arc
		(start 100.823014 -239.159796)
		(mid 101.066341 -239.624362)
		(end 100.823014 -240.088928)
		(width 0.1143)
		(layer "In11.Cu")
		(net "P5E_CPU1_G1_TX_DP<11>")
	)
	(arc
		(start 99.88296 -222.95993)
		(mid 100.126287 -223.424496)
		(end 99.88296 -223.889062)
		(width 0.1143)
		(layer "In11.Cu")
		(net "P5E_CPU1_G1_TX_DP<11>")
	)
	(arc
		(start 100.823014 -235.919772)
		(mid 101.066341 -236.384338)
		(end 100.823014 -236.848904)
		(width 0.1143)
		(layer "In11.Cu")
		(net "P5E_CPU1_G1_TX_DP<11>")
	)
	(arc
		(start 100.126292 -225.044508)
		(mid 100.167547 -225.215479)
		(end 100.282248 -225.3488)
		(width 0.1143)
		(layer "In11.Cu")
		(net "P5E_CPU1_G1_TX_DP<11>")
	)
	(arc
		(start 100.823014 -240.779808)
		(mid 101.066341 -241.244374)
		(end 100.823014 -241.70894)
		(width 0.1143)
		(layer "In11.Cu")
		(net "P5E_CPU1_G1_TX_DP<11>")
	)
	(arc
		(start 100.823014 -231.059736)
		(mid 101.066341 -231.524302)
		(end 100.823014 -231.988868)
		(width 0.1143)
		(layer "In11.Cu")
		(net "P5E_CPU1_G1_TX_DP<11>")
	)
	(arc
		(start 100.35032 -225.38817)
		(mid 100.366289 -225.400207)
		(end 100.381816 -225.412808)
		(width 0.1143)
		(layer "In11.Cu")
		(net "P5E_CPU1_G1_TX_DP<11>")
	)
	(arc
		(start 100.822252 -237.539276)
		(mid 100.822633 -237.53953)
		(end 100.823014 -237.539784)
		(width 0.1143)
		(layer "In11.Cu")
		(net "P5E_CPU1_G1_TX_DP<11>")
	)
	(arc
		(start 100.78339 -235.252006)
		(mid 100.59787 -235.570063)
		(end 100.776024 -235.89234)
		(width 0.1143)
		(layer "In11.Cu")
		(net "P5E_CPU1_G1_TX_DP<11>")
	)
	(arc
		(start 100.752148 -243.3701)
		(mid 100.603051 -243.674392)
		(end 100.752148 -243.978684)
		(width 0.1143)
		(layer "In11.Cu")
		(net "P5E_CPU1_G1_TX_DP<11>")
	)
	(arc
		(start 100.78339 -236.872018)
		(mid 100.59787 -237.190075)
		(end 100.776024 -237.512352)
		(width 0.1143)
		(layer "In11.Cu")
		(net "P5E_CPU1_G1_TX_DP<11>")
	)
	(arc
		(start 100.822252 -235.919264)
		(mid 100.822633 -235.919518)
		(end 100.823014 -235.919772)
		(width 0.1143)
		(layer "In11.Cu")
		(net "P5E_CPU1_G1_TX_DP<11>")
	)
	(arc
		(start 100.596192 -229.094538)
		(mid 100.636954 -229.264422)
		(end 100.75037 -229.397306)
		(width 0.1143)
		(layer "In11.Cu")
		(net "P5E_CPU1_G1_TX_DP<11>")
	)
	(arc
		(start 100.823014 -234.29976)
		(mid 101.066341 -234.764326)
		(end 100.823014 -235.228892)
		(width 0.1143)
		(layer "In11.Cu")
		(net "P5E_CPU1_G1_TX_DP<11>")
	)
	(arc
		(start 100.596192 -225.86569)
		(mid 100.640256 -226.030913)
		(end 100.753164 -226.159314)
		(width 0.1143)
		(layer "In11.Cu")
		(net "P5E_CPU1_G1_TX_DP<11>")
	)
	(arc
		(start 100.752148 -233.650028)
		(mid 100.600559 -233.95432)
		(end 100.752148 -234.258612)
		(width 0.1143)
		(layer "In11.Cu")
		(net "P5E_CPU1_G1_TX_DP<11>")
	)
	(arc
		(start 100.822252 -240.7793)
		(mid 100.822633 -240.779554)
		(end 100.823014 -240.779808)
		(width 0.1143)
		(layer "In11.Cu")
		(net "P5E_CPU1_G1_TX_DP<11>")
	)
	(arc
		(start 100.823014 -227.819966)
		(mid 101.066341 -228.284532)
		(end 100.823014 -228.749098)
		(width 0.1143)
		(layer "In11.Cu")
		(net "P5E_CPU1_G1_TX_DP<11>")
	)
	(arc
		(start 100.752148 -227.170234)
		(mid 100.603051 -227.474526)
		(end 100.752148 -227.778818)
		(width 0.1143)
		(layer "In11.Cu")
		(net "P5E_CPU1_G1_TX_DP<11>")
	)
	(arc
		(start 100.823014 -242.39982)
		(mid 101.066341 -242.864386)
		(end 100.823014 -243.328952)
		(width 0.1143)
		(layer "In11.Cu")
		(net "P5E_CPU1_G1_TX_DP<11>")
	)
	(arc
		(start 100.822252 -234.299252)
		(mid 100.822633 -234.299506)
		(end 100.823014 -234.29976)
		(width 0.1143)
		(layer "In11.Cu")
		(net "P5E_CPU1_G1_TX_DP<11>")
	)
	(arc
		(start 99.656392 -222.61449)
		(mid 99.697941 -222.785912)
		(end 99.813364 -222.91929)
		(width 0.1143)
		(layer "In11.Cu")
		(net "P5E_CPU1_G1_TX_DP<11>")
	)
	(arc
		(start 100.78339 -241.732054)
		(mid 100.59787 -242.050111)
		(end 100.776024 -242.372388)
		(width 0.1143)
		(layer "In11.Cu")
		(net "P5E_CPU1_G1_TX_DP<11>")
	)
	(arc
		(start 101.05644 -244.378734)
		(mid 101.058463 -244.390144)
		(end 101.06025 -244.401594)
		(width 0.1143)
		(layer "In11.Cu")
		(net "P5E_CPU1_G1_TX_DP<11>")
	)
	(arc
		(start 100.823014 -229.439724)
		(mid 101.001827 -229.642074)
		(end 101.066346 -229.90429)
		(width 0.1143)
		(layer "In11.Cu")
		(net "P5E_CPU1_G1_TX_DP<11>")
	)
	(arc
		(start 100.823014 -244.019832)
		(mid 100.975001 -244.17634)
		(end 101.05644 -244.378734)
		(width 0.1143)
		(layer "In11.Cu")
		(net "P5E_CPU1_G1_TX_DP<11>")
	)
	(arc
		(start 99.186238 -221.804484)
		(mid 99.227493 -221.975455)
		(end 99.342194 -222.108776)
		(width 0.1143)
		(layer "In11.Cu")
		(net "P5E_CPU1_G1_TX_DP<11>")
	)
	(arc
		(start 99.813364 -223.929702)
		(mid 99.656387 -224.234502)
		(end 99.813364 -224.539302)
		(width 0.1143)
		(layer "In11.Cu")
		(net "P5E_CPU1_G1_TX_DP<11>")
	)
	(arc
		(start 99.41306 -222.149924)
		(mid 99.591873 -222.352274)
		(end 99.656392 -222.61449)
		(width 0.1143)
		(layer "In11.Cu")
		(net "P5E_CPU1_G1_TX_DP<11>")
	)
	(arc
		(start 100.822252 -242.399312)
		(mid 100.822633 -242.399566)
		(end 100.823014 -242.39982)
		(width 0.1143)
		(layer "In11.Cu")
		(net "P5E_CPU1_G1_TX_DP<11>")
	)
	(arc
		(start 100.823014 -232.679748)
		(mid 101.066341 -233.144314)
		(end 100.823014 -233.60888)
		(width 0.1143)
		(layer "In11.Cu")
		(net "P5E_CPU1_G1_TX_DP<11>")
	)
	(arc
		(start 100.381816 -225.412808)
		(mid 100.514234 -225.585989)
		(end 100.588318 -225.791014)
		(width 0.1143)
		(layer "In11.Cu")
		(net "P5E_CPU1_G1_TX_DP<11>")
	)
	(arc
		(start 101.066346 -229.90429)
		(mid 101.00111 -230.167881)
		(end 100.820474 -230.370634)
		(width 0.1143)
		(layer "In11.Cu")
		(net "P5E_CPU1_G1_TX_DP<11>")
	)
	(segment
		(start 30.096968 -18.86585)
		(end 30.367478 -19.13636)
		(width 0.12954)
		(layer "F.Cu")
		(net "P5E_CPU1_G1_TX_DP<10>")
	)
	(segment
		(start 101.907848 -247.99036)
		(end 101.440996 -247.724422)
		(width 0.12954)
		(layer "F.Cu")
		(net "P5E_CPU1_G1_TX_DP<10>")
	)
	(segment
		(start 30.096968 -18.186146)
		(end 30.096968 -18.86585)
		(width 0.12954)
		(layer "F.Cu")
		(net "P5E_CPU1_G1_TX_DP<10>")
	)
	(segment
		(start 30.392878 -17.890236)
		(end 30.096968 -18.186146)
		(width 0.12954)
		(layer "F.Cu")
		(net "P5E_CPU1_G1_TX_DP<10>")
	)
	(segment
		(start 101.71938 -243.994432)
		(end 101.72192 -243.995702)
		(width 0.1143)
		(layer "In11.Cu")
		(net "P5E_CPU1_G1_TX_DP<10>")
	)
	(segment
		(start 106.876088 -203.754482)
		(end 100.136198 -215.105488)
		(width 0.14224)
		(layer "In11.Cu")
		(net "P5E_CPU1_G1_TX_DP<10>")
	)
	(segment
		(start 101.71938 -235.894372)
		(end 101.72192 -235.895642)
		(width 0.1143)
		(layer "In11.Cu")
		(net "P5E_CPU1_G1_TX_DP<10>")
	)
	(segment
		(start 101.692202 -245.598696)
		(end 101.72192 -245.615714)
		(width 0.1143)
		(layer "In11.Cu")
		(net "P5E_CPU1_G1_TX_DP<10>")
	)
	(segment
		(start 101.723952 -244.971824)
		(end 101.72319 -244.972332)
		(width 0.1143)
		(layer "In11.Cu")
		(net "P5E_CPU1_G1_TX_DP<10>")
	)
	(segment
		(start 101.724968 -236.871256)
		(end 101.723952 -236.871764)
		(width 0.1143)
		(layer "In11.Cu")
		(net "P5E_CPU1_G1_TX_DP<10>")
	)
	(segment
		(start 101.72319 -236.872272)
		(end 101.692202 -236.890052)
		(width 0.1143)
		(layer "In11.Cu")
		(net "P5E_CPU1_G1_TX_DP<10>")
	)
	(segment
		(start 101.726492 -233.630216)
		(end 101.724968 -233.631232)
		(width 0.1143)
		(layer "In11.Cu")
		(net "P5E_CPU1_G1_TX_DP<10>")
	)
	(segment
		(start 101.723952 -227.151946)
		(end 101.693472 -227.169726)
		(width 0.1143)
		(layer "In11.Cu")
		(net "P5E_CPU1_G1_TX_DP<10>")
	)
	(segment
		(start 100.136198 -221.05493)
		(end 100.136198 -221.083378)
		(width 0.1143)
		(layer "In11.Cu")
		(net "P5E_CPU1_G1_TX_DP<10>")
	)
	(segment
		(start 101.727508 -232.009696)
		(end 101.726492 -232.010204)
		(width 0.1143)
		(layer "In11.Cu")
		(net "P5E_CPU1_G1_TX_DP<10>")
	)
	(segment
		(start 100.136198 -215.105488)
		(end 100.136198 -221.05493)
		(width 0.14224)
		(layer "In11.Cu")
		(net "P5E_CPU1_G1_TX_DP<10>")
	)
	(segment
		(start 101.72319 -241.732308)
		(end 101.692202 -241.750088)
		(width 0.1143)
		(layer "In11.Cu")
		(net "P5E_CPU1_G1_TX_DP<10>")
	)
	(segment
		(start 101.724968 -232.01122)
		(end 101.723952 -232.011728)
		(width 0.1143)
		(layer "In11.Cu")
		(net "P5E_CPU1_G1_TX_DP<10>")
	)
	(segment
		(start 101.724968 -243.99748)
		(end 101.763068 -244.019832)
		(width 0.1143)
		(layer "In11.Cu")
		(net "P5E_CPU1_G1_TX_DP<10>")
	)
	(segment
		(start 101.717856 -240.753392)
		(end 101.71938 -240.754408)
		(width 0.1143)
		(layer "In11.Cu")
		(net "P5E_CPU1_G1_TX_DP<10>")
	)
	(segment
		(start 101.763068 -243.328952)
		(end 101.727508 -243.34978)
		(width 0.1143)
		(layer "In11.Cu")
		(net "P5E_CPU1_G1_TX_DP<10>")
	)
	(segment
		(start 101.24694 -225.363024)
		(end 101.247956 -225.363532)
		(width 0.1143)
		(layer "In11.Cu")
		(net "P5E_CPU1_G1_TX_DP<10>")
	)
	(segment
		(start 101.72319 -240.112296)
		(end 101.692202 -240.130076)
		(width 0.1143)
		(layer "In11.Cu")
		(net "P5E_CPU1_G1_TX_DP<10>")
	)
	(segment
		(start 101.723952 -246.591836)
		(end 101.72319 -246.592344)
		(width 0.1143)
		(layer "In11.Cu")
		(net "P5E_CPU1_G1_TX_DP<10>")
	)
	(segment
		(start 101.692202 -242.358672)
		(end 101.72192 -242.37569)
		(width 0.1143)
		(layer "In11.Cu")
		(net "P5E_CPU1_G1_TX_DP<10>")
	)
	(segment
		(start 101.72319 -235.896404)
		(end 101.723952 -235.896912)
		(width 0.1143)
		(layer "In11.Cu")
		(net "P5E_CPU1_G1_TX_DP<10>")
	)
	(segment
		(start 101.724968 -241.731292)
		(end 101.723952 -241.7318)
		(width 0.1143)
		(layer "In11.Cu")
		(net "P5E_CPU1_G1_TX_DP<10>")
	)
	(segment
		(start 101.72319 -244.972332)
		(end 101.692202 -244.990112)
		(width 0.1143)
		(layer "In11.Cu")
		(net "P5E_CPU1_G1_TX_DP<10>")
	)
	(segment
		(start 101.717856 -234.273344)
		(end 101.71938 -234.27436)
		(width 0.1143)
		(layer "In11.Cu")
		(net "P5E_CPU1_G1_TX_DP<10>")
	)
	(segment
		(start 101.723952 -227.797106)
		(end 101.763068 -227.819966)
		(width 0.1143)
		(layer "In11.Cu")
		(net "P5E_CPU1_G1_TX_DP<10>")
	)
	(segment
		(start 149.839934 -163.234878)
		(end 148.321268 -167.69588)
		(width 0.14224)
		(layer "In11.Cu")
		(net "P5E_CPU1_G1_TX_DP<10>")
	)
	(segment
		(start 101.724968 -235.251244)
		(end 101.723952 -235.251752)
		(width 0.1143)
		(layer "In11.Cu")
		(net "P5E_CPU1_G1_TX_DP<10>")
	)
	(segment
		(start 101.723952 -231.036876)
		(end 101.763068 -231.059736)
		(width 0.1143)
		(layer "In11.Cu")
		(net "P5E_CPU1_G1_TX_DP<10>")
	)
	(segment
		(start 101.69144 -229.398068)
		(end 101.723952 -229.416864)
		(width 0.1143)
		(layer "In11.Cu")
		(net "P5E_CPU1_G1_TX_DP<10>")
	)
	(segment
		(start 101.727508 -233.629708)
		(end 101.726492 -233.630216)
		(width 0.1143)
		(layer "In11.Cu")
		(net "P5E_CPU1_G1_TX_DP<10>")
	)
	(segment
		(start 101.723952 -245.616984)
		(end 101.724968 -245.617492)
		(width 0.1143)
		(layer "In11.Cu")
		(net "P5E_CPU1_G1_TX_DP<10>")
	)
	(segment
		(start 101.763068 -228.749098)
		(end 101.76256 -228.749352)
		(width 0.1143)
		(layer "In11.Cu")
		(net "P5E_CPU1_G1_TX_DP<10>")
	)
	(segment
		(start 101.690424 -231.017318)
		(end 101.723952 -231.036876)
		(width 0.1143)
		(layer "In11.Cu")
		(net "P5E_CPU1_G1_TX_DP<10>")
	)
	(segment
		(start 101.724968 -235.89742)
		(end 101.763068 -235.919772)
		(width 0.1143)
		(layer "In11.Cu")
		(net "P5E_CPU1_G1_TX_DP<10>")
	)
	(segment
		(start 101.723952 -240.756948)
		(end 101.724968 -240.757456)
		(width 0.1143)
		(layer "In11.Cu")
		(net "P5E_CPU1_G1_TX_DP<10>")
	)
	(segment
		(start 149.034754 -147.097242)
		(end 149.839934 -159.966152)
		(width 0.14224)
		(layer "In11.Cu")
		(net "P5E_CPU1_G1_TX_DP<10>")
	)
	(segment
		(start 101.723952 -243.351812)
		(end 101.72319 -243.35232)
		(width 0.1143)
		(layer "In11.Cu")
		(net "P5E_CPU1_G1_TX_DP<10>")
	)
	(segment
		(start 101.72319 -243.996464)
		(end 101.723952 -243.996972)
		(width 0.1143)
		(layer "In11.Cu")
		(net "P5E_CPU1_G1_TX_DP<10>")
	)
	(segment
		(start 101.723952 -237.516924)
		(end 101.724968 -237.517432)
		(width 0.1143)
		(layer "In11.Cu")
		(net "P5E_CPU1_G1_TX_DP<10>")
	)
	(segment
		(start 101.763068 -233.60888)
		(end 101.727508 -233.629708)
		(width 0.1143)
		(layer "In11.Cu")
		(net "P5E_CPU1_G1_TX_DP<10>")
	)
	(segment
		(start 54.383432 -57.91835)
		(end 145.55597 -139.904978)
		(width 0.14224)
		(layer "In11.Cu")
		(net "P5E_CPU1_G1_TX_DP<10>")
	)
	(segment
		(start 101.255068 -225.367596)
		(end 101.256592 -225.368612)
		(width 0.1143)
		(layer "In11.Cu")
		(net "P5E_CPU1_G1_TX_DP<10>")
	)
	(segment
		(start 101.72319 -246.592344)
		(end 101.692202 -246.610124)
		(width 0.1143)
		(layer "In11.Cu")
		(net "P5E_CPU1_G1_TX_DP<10>")
	)
	(segment
		(start 101.723952 -233.63174)
		(end 101.72319 -233.632248)
		(width 0.1143)
		(layer "In11.Cu")
		(net "P5E_CPU1_G1_TX_DP<10>")
	)
	(segment
		(start 149.839934 -159.966152)
		(end 149.839934 -163.234878)
		(width 0.14224)
		(layer "In11.Cu")
		(net "P5E_CPU1_G1_TX_DP<10>")
	)
	(segment
		(start 53.15458 -56.90489)
		(end 54.383432 -57.91835)
		(width 0.14224)
		(layer "In11.Cu")
		(net "P5E_CPU1_G1_TX_DP<10>")
	)
	(segment
		(start 101.693472 -226.159314)
		(end 101.723952 -226.177094)
		(width 0.1143)
		(layer "In11.Cu")
		(net "P5E_CPU1_G1_TX_DP<10>")
	)
	(segment
		(start 101.727508 -240.109756)
		(end 101.726492 -240.110264)
		(width 0.1143)
		(layer "In11.Cu")
		(net "P5E_CPU1_G1_TX_DP<10>")
	)
	(segment
		(start 101.724968 -237.517432)
		(end 101.763068 -237.539784)
		(width 0.1143)
		(layer "In11.Cu")
		(net "P5E_CPU1_G1_TX_DP<10>")
	)
	(segment
		(start 101.72192 -242.37569)
		(end 101.72319 -242.376452)
		(width 0.1143)
		(layer "In11.Cu")
		(net "P5E_CPU1_G1_TX_DP<10>")
	)
	(segment
		(start 101.763068 -235.228892)
		(end 101.727508 -235.24972)
		(width 0.1143)
		(layer "In11.Cu")
		(net "P5E_CPU1_G1_TX_DP<10>")
	)
	(segment
		(start 101.726492 -236.87024)
		(end 101.724968 -236.871256)
		(width 0.1143)
		(layer "In11.Cu")
		(net "P5E_CPU1_G1_TX_DP<10>")
	)
	(segment
		(start 101.723952 -230.39197)
		(end 101.692202 -230.410258)
		(width 0.1143)
		(layer "In11.Cu")
		(net "P5E_CPU1_G1_TX_DP<10>")
	)
	(segment
		(start 100.136198 -221.083378)
		(end 100.090478 -221.129098)
		(width 0.1143)
		(layer "In11.Cu")
		(net "P5E_CPU1_G1_TX_DP<10>")
	)
	(segment
		(start 101.724968 -246.591328)
		(end 101.723952 -246.591836)
		(width 0.1143)
		(layer "In11.Cu")
		(net "P5E_CPU1_G1_TX_DP<10>")
	)
	(segment
		(start 101.72319 -245.616476)
		(end 101.723952 -245.616984)
		(width 0.1143)
		(layer "In11.Cu")
		(net "P5E_CPU1_G1_TX_DP<10>")
	)
	(segment
		(start 101.692202 -243.978684)
		(end 101.717856 -243.993416)
		(width 0.1143)
		(layer "In11.Cu")
		(net "P5E_CPU1_G1_TX_DP<10>")
	)
	(segment
		(start 101.763068 -240.088928)
		(end 101.727508 -240.109756)
		(width 0.1143)
		(layer "In11.Cu")
		(net "P5E_CPU1_G1_TX_DP<10>")
	)
	(segment
		(start 101.724968 -245.617492)
		(end 101.763068 -245.639844)
		(width 0.1143)
		(layer "In11.Cu")
		(net "P5E_CPU1_G1_TX_DP<10>")
	)
	(segment
		(start 101.763068 -241.70894)
		(end 101.727508 -241.729768)
		(width 0.1143)
		(layer "In11.Cu")
		(net "P5E_CPU1_G1_TX_DP<10>")
	)
	(segment
		(start 101.71938 -234.27436)
		(end 101.72192 -234.27563)
		(width 0.1143)
		(layer "In11.Cu")
		(net "P5E_CPU1_G1_TX_DP<10>")
	)
	(segment
		(start 101.717856 -235.893356)
		(end 101.71938 -235.894372)
		(width 0.1143)
		(layer "In11.Cu")
		(net "P5E_CPU1_G1_TX_DP<10>")
	)
	(segment
		(start 101.727508 -246.589804)
		(end 101.726492 -246.590312)
		(width 0.1143)
		(layer "In11.Cu")
		(net "P5E_CPU1_G1_TX_DP<10>")
	)
	(segment
		(start 100.753418 -224.539302)
		(end 100.783898 -224.557082)
		(width 0.1143)
		(layer "In11.Cu")
		(net "P5E_CPU1_G1_TX_DP<10>")
	)
	(segment
		(start 43.778678 -45.51172)
		(end 53.15458 -56.90489)
		(width 0.14224)
		(layer "In11.Cu")
		(net "P5E_CPU1_G1_TX_DP<10>")
	)
	(segment
		(start 101.692202 -235.878624)
		(end 101.717856 -235.893356)
		(width 0.1143)
		(layer "In11.Cu")
		(net "P5E_CPU1_G1_TX_DP<10>")
	)
	(segment
		(start 101.724968 -242.377468)
		(end 101.763068 -242.39982)
		(width 0.1143)
		(layer "In11.Cu")
		(net "P5E_CPU1_G1_TX_DP<10>")
	)
	(segment
		(start 101.692202 -237.498636)
		(end 101.72192 -237.515654)
		(width 0.1143)
		(layer "In11.Cu")
		(net "P5E_CPU1_G1_TX_DP<10>")
	)
	(segment
		(start 101.24948 -225.364548)
		(end 101.25202 -225.365818)
		(width 0.1143)
		(layer "In11.Cu")
		(net "P5E_CPU1_G1_TX_DP<10>")
	)
	(segment
		(start 101.726492 -241.730276)
		(end 101.724968 -241.731292)
		(width 0.1143)
		(layer "In11.Cu")
		(net "P5E_CPU1_G1_TX_DP<10>")
	)
	(segment
		(start 101.693472 -227.779326)
		(end 101.723952 -227.797106)
		(width 0.1143)
		(layer "In11.Cu")
		(net "P5E_CPU1_G1_TX_DP<10>")
	)
	(segment
		(start 100.090478 -221.129098)
		(end 100.090478 -221.30893)
		(width 0.1143)
		(layer "In11.Cu")
		(net "P5E_CPU1_G1_TX_DP<10>")
	)
	(segment
		(start 101.763068 -236.848904)
		(end 101.727508 -236.869732)
		(width 0.1143)
		(layer "In11.Cu")
		(net "P5E_CPU1_G1_TX_DP<10>")
	)
	(segment
		(start 101.72319 -232.012236)
		(end 101.692202 -232.030016)
		(width 0.1143)
		(layer "In11.Cu")
		(net "P5E_CPU1_G1_TX_DP<10>")
	)
	(segment
		(start 101.726492 -243.350288)
		(end 101.724968 -243.351304)
		(width 0.1143)
		(layer "In11.Cu")
		(net "P5E_CPU1_G1_TX_DP<10>")
	)
	(segment
		(start 101.723952 -239.136936)
		(end 101.724968 -239.137444)
		(width 0.1143)
		(layer "In11.Cu")
		(net "P5E_CPU1_G1_TX_DP<10>")
	)
	(segment
		(start 101.724968 -238.491268)
		(end 101.723952 -238.491776)
		(width 0.1143)
		(layer "In11.Cu")
		(net "P5E_CPU1_G1_TX_DP<10>")
	)
	(segment
		(start 101.726492 -244.9703)
		(end 101.724968 -244.971316)
		(width 0.1143)
		(layer "In11.Cu")
		(net "P5E_CPU1_G1_TX_DP<10>")
	)
	(segment
		(start 101.25329 -225.36658)
		(end 101.254052 -225.367088)
		(width 0.1143)
		(layer "In11.Cu")
		(net "P5E_CPU1_G1_TX_DP<10>")
	)
	(segment
		(start 101.723952 -242.37696)
		(end 101.724968 -242.377468)
		(width 0.1143)
		(layer "In11.Cu")
		(net "P5E_CPU1_G1_TX_DP<10>")
	)
	(segment
		(start 101.723952 -238.491776)
		(end 101.692202 -238.510064)
		(width 0.1143)
		(layer "In11.Cu")
		(net "P5E_CPU1_G1_TX_DP<10>")
	)
	(segment
		(start 101.763068 -246.568976)
		(end 101.727508 -246.589804)
		(width 0.1143)
		(layer "In11.Cu")
		(net "P5E_CPU1_G1_TX_DP<10>")
	)
	(segment
		(start 101.247956 -225.363532)
		(end 101.24948 -225.364548)
		(width 0.1143)
		(layer "In11.Cu")
		(net "P5E_CPU1_G1_TX_DP<10>")
	)
	(segment
		(start 100.823014 -223.889062)
		(end 100.783898 -223.911922)
		(width 0.1143)
		(layer "In11.Cu")
		(net "P5E_CPU1_G1_TX_DP<10>")
	)
	(segment
		(start 101.717856 -243.993416)
		(end 101.71938 -243.994432)
		(width 0.1143)
		(layer "In11.Cu")
		(net "P5E_CPU1_G1_TX_DP<10>")
	)
	(segment
		(start 101.726492 -232.010204)
		(end 101.724968 -232.01122)
		(width 0.1143)
		(layer "In11.Cu")
		(net "P5E_CPU1_G1_TX_DP<10>")
	)
	(segment
		(start 101.723952 -241.7318)
		(end 101.72319 -241.732308)
		(width 0.1143)
		(layer "In11.Cu")
		(net "P5E_CPU1_G1_TX_DP<10>")
	)
	(segment
		(start 101.723952 -228.771958)
		(end 101.693472 -228.789738)
		(width 0.1143)
		(layer "In11.Cu")
		(net "P5E_CPU1_G1_TX_DP<10>")
	)
	(segment
		(start 101.724968 -239.137444)
		(end 101.763068 -239.159796)
		(width 0.1143)
		(layer "In11.Cu")
		(net "P5E_CPU1_G1_TX_DP<10>")
	)
	(segment
		(start 101.253798 -247.401842)
		(end 101.223318 -247.419622)
		(width 0.1143)
		(layer "In11.Cu")
		(net "P5E_CPU1_G1_TX_DP<10>")
	)
	(segment
		(start 101.25202 -225.365818)
		(end 101.25329 -225.36658)
		(width 0.1143)
		(layer "In11.Cu")
		(net "P5E_CPU1_G1_TX_DP<10>")
	)
	(segment
		(start 101.763068 -244.948964)
		(end 101.727508 -244.969792)
		(width 0.1143)
		(layer "In11.Cu")
		(net "P5E_CPU1_G1_TX_DP<10>")
	)
	(segment
		(start 101.763068 -231.988868)
		(end 101.727508 -232.009696)
		(width 0.1143)
		(layer "In11.Cu")
		(net "P5E_CPU1_G1_TX_DP<10>")
	)
	(segment
		(start 101.72192 -243.995702)
		(end 101.72319 -243.996464)
		(width 0.1143)
		(layer "In11.Cu")
		(net "P5E_CPU1_G1_TX_DP<10>")
	)
	(segment
		(start 30.076648 -20.192746)
		(end 43.778678 -45.51172)
		(width 0.14224)
		(layer "In11.Cu")
		(net "P5E_CPU1_G1_TX_DP<10>")
	)
	(segment
		(start 101.727508 -235.24972)
		(end 101.726492 -235.250228)
		(width 0.1143)
		(layer "In11.Cu")
		(net "P5E_CPU1_G1_TX_DP<10>")
	)
	(segment
		(start 101.72192 -245.615714)
		(end 101.72319 -245.616476)
		(width 0.1143)
		(layer "In11.Cu")
		(net "P5E_CPU1_G1_TX_DP<10>")
	)
	(segment
		(start 101.723952 -234.2769)
		(end 101.724968 -234.277408)
		(width 0.1143)
		(layer "In11.Cu")
		(net "P5E_CPU1_G1_TX_DP<10>")
	)
	(segment
		(start 101.723952 -232.656888)
		(end 101.724968 -232.657396)
		(width 0.1143)
		(layer "In11.Cu")
		(net "P5E_CPU1_G1_TX_DP<10>")
	)
	(segment
		(start 100.313998 -222.127064)
		(end 100.353114 -222.149924)
		(width 0.1143)
		(layer "In11.Cu")
		(net "P5E_CPU1_G1_TX_DP<10>")
	)
	(segment
		(start 101.72192 -234.27563)
		(end 101.72319 -234.276392)
		(width 0.1143)
		(layer "In11.Cu")
		(net "P5E_CPU1_G1_TX_DP<10>")
	)
	(segment
		(start 101.760528 -230.370634)
		(end 101.723952 -230.39197)
		(width 0.1143)
		(layer "In11.Cu")
		(net "P5E_CPU1_G1_TX_DP<10>")
	)
	(segment
		(start 101.723952 -232.011728)
		(end 101.72319 -232.012236)
		(width 0.1143)
		(layer "In11.Cu")
		(net "P5E_CPU1_G1_TX_DP<10>")
	)
	(segment
		(start 101.692202 -234.258612)
		(end 101.717856 -234.273344)
		(width 0.1143)
		(layer "In11.Cu")
		(net "P5E_CPU1_G1_TX_DP<10>")
	)
	(segment
		(start 101.724968 -232.657396)
		(end 101.763068 -232.679748)
		(width 0.1143)
		(layer "In11.Cu")
		(net "P5E_CPU1_G1_TX_DP<10>")
	)
	(segment
		(start 101.727508 -236.869732)
		(end 101.726492 -236.87024)
		(width 0.1143)
		(layer "In11.Cu")
		(net "P5E_CPU1_G1_TX_DP<10>")
	)
	(segment
		(start 100.783898 -224.557082)
		(end 100.823014 -224.579942)
		(width 0.1143)
		(layer "In11.Cu")
		(net "P5E_CPU1_G1_TX_DP<10>")
	)
	(segment
		(start 101.727508 -243.34978)
		(end 101.726492 -243.350288)
		(width 0.1143)
		(layer "In11.Cu")
		(net "P5E_CPU1_G1_TX_DP<10>")
	)
	(segment
		(start 100.753418 -222.91929)
		(end 100.783898 -222.93707)
		(width 0.1143)
		(layer "In11.Cu")
		(net "P5E_CPU1_G1_TX_DP<10>")
	)
	(segment
		(start 148.321268 -167.69588)
		(end 144.94256 -172.559472)
		(width 0.14224)
		(layer "In11.Cu")
		(net "P5E_CPU1_G1_TX_DP<10>")
	)
	(segment
		(start 144.94256 -172.559472)
		(end 106.876088 -203.754482)
		(width 0.14224)
		(layer "In11.Cu")
		(net "P5E_CPU1_G1_TX_DP<10>")
	)
	(segment
		(start 100.282248 -222.108776)
		(end 100.313998 -222.127064)
		(width 0.1143)
		(layer "In11.Cu")
		(net "P5E_CPU1_G1_TX_DP<10>")
	)
	(segment
		(start 101.292914 -247.378982)
		(end 101.253798 -247.401842)
		(width 0.1143)
		(layer "In11.Cu")
		(net "P5E_CPU1_G1_TX_DP<10>")
	)
	(segment
		(start 101.723952 -226.177094)
		(end 101.763068 -226.199954)
		(width 0.1143)
		(layer "In11.Cu")
		(net "P5E_CPU1_G1_TX_DP<10>")
	)
	(segment
		(start 101.72192 -235.895642)
		(end 101.72319 -235.896404)
		(width 0.1143)
		(layer "In11.Cu")
		(net "P5E_CPU1_G1_TX_DP<10>")
	)
	(segment
		(start 101.143054 -247.724422)
		(end 101.440996 -247.724422)
		(width 0.1143)
		(layer "In11.Cu")
		(net "P5E_CPU1_G1_TX_DP<10>")
	)
	(segment
		(start 101.72319 -235.25226)
		(end 101.692202 -235.27004)
		(width 0.1143)
		(layer "In11.Cu")
		(net "P5E_CPU1_G1_TX_DP<10>")
	)
	(segment
		(start 101.71938 -240.754408)
		(end 101.72192 -240.755678)
		(width 0.1143)
		(layer "In11.Cu")
		(net "P5E_CPU1_G1_TX_DP<10>")
	)
	(segment
		(start 101.76256 -228.749352)
		(end 101.723952 -228.771958)
		(width 0.1143)
		(layer "In11.Cu")
		(net "P5E_CPU1_G1_TX_DP<10>")
	)
	(segment
		(start 101.72192 -232.655618)
		(end 101.72319 -232.65638)
		(width 0.1143)
		(layer "In11.Cu")
		(net "P5E_CPU1_G1_TX_DP<10>")
	)
	(segment
		(start 101.726492 -246.590312)
		(end 101.724968 -246.591328)
		(width 0.1143)
		(layer "In11.Cu")
		(net "P5E_CPU1_G1_TX_DP<10>")
	)
	(segment
		(start 101.073204 -247.654572)
		(end 101.143054 -247.724422)
		(width 0.1143)
		(layer "In11.Cu")
		(net "P5E_CPU1_G1_TX_DP<10>")
	)
	(segment
		(start 101.763068 -238.468916)
		(end 101.726492 -238.490252)
		(width 0.1143)
		(layer "In11.Cu")
		(net "P5E_CPU1_G1_TX_DP<10>")
	)
	(segment
		(start 101.723952 -229.416864)
		(end 101.763068 -229.439724)
		(width 0.1143)
		(layer "In11.Cu")
		(net "P5E_CPU1_G1_TX_DP<10>")
	)
	(segment
		(start 101.724968 -244.971316)
		(end 101.723952 -244.971824)
		(width 0.1143)
		(layer "In11.Cu")
		(net "P5E_CPU1_G1_TX_DP<10>")
	)
	(segment
		(start 101.72319 -234.276392)
		(end 101.723952 -234.2769)
		(width 0.1143)
		(layer "In11.Cu")
		(net "P5E_CPU1_G1_TX_DP<10>")
	)
	(segment
		(start 101.72319 -232.65638)
		(end 101.723952 -232.656888)
		(width 0.1143)
		(layer "In11.Cu")
		(net "P5E_CPU1_G1_TX_DP<10>")
	)
	(segment
		(start 145.55597 -139.904978)
		(end 149.034754 -147.097242)
		(width 0.14224)
		(layer "In11.Cu")
		(net "P5E_CPU1_G1_TX_DP<10>")
	)
	(segment
		(start 101.724968 -233.631232)
		(end 101.723952 -233.63174)
		(width 0.1143)
		(layer "In11.Cu")
		(net "P5E_CPU1_G1_TX_DP<10>")
	)
	(segment
		(start 101.72192 -237.515654)
		(end 101.72319 -237.516416)
		(width 0.1143)
		(layer "In11.Cu")
		(net "P5E_CPU1_G1_TX_DP<10>")
	)
	(segment
		(start 101.717856 -239.13338)
		(end 101.71938 -239.134396)
		(width 0.1143)
		(layer "In11.Cu")
		(net "P5E_CPU1_G1_TX_DP<10>")
	)
	(segment
		(start 101.726492 -238.490252)
		(end 101.724968 -238.491268)
		(width 0.1143)
		(layer "In11.Cu")
		(net "P5E_CPU1_G1_TX_DP<10>")
	)
	(segment
		(start 101.72319 -237.516416)
		(end 101.723952 -237.516924)
		(width 0.1143)
		(layer "In11.Cu")
		(net "P5E_CPU1_G1_TX_DP<10>")
	)
	(segment
		(start 100.783898 -222.93707)
		(end 100.823014 -222.95993)
		(width 0.1143)
		(layer "In11.Cu")
		(net "P5E_CPU1_G1_TX_DP<10>")
	)
	(segment
		(start 101.724968 -240.11128)
		(end 101.723952 -240.111788)
		(width 0.1143)
		(layer "In11.Cu")
		(net "P5E_CPU1_G1_TX_DP<10>")
	)
	(segment
		(start 101.692202 -240.73866)
		(end 101.717856 -240.753392)
		(width 0.1143)
		(layer "In11.Cu")
		(net "P5E_CPU1_G1_TX_DP<10>")
	)
	(segment
		(start 100.126292 -221.344744)
		(end 100.126292 -221.804484)
		(width 0.1143)
		(layer "In11.Cu")
		(net "P5E_CPU1_G1_TX_DP<10>")
	)
	(segment
		(start 101.692202 -232.6386)
		(end 101.717856 -232.653332)
		(width 0.1143)
		(layer "In11.Cu")
		(net "P5E_CPU1_G1_TX_DP<10>")
	)
	(segment
		(start 101.72192 -239.135666)
		(end 101.72319 -239.136428)
		(width 0.1143)
		(layer "In11.Cu")
		(net "P5E_CPU1_G1_TX_DP<10>")
	)
	(segment
		(start 30.367478 -19.13636)
		(end 30.076648 -19.42719)
		(width 0.14224)
		(layer "In11.Cu")
		(net "P5E_CPU1_G1_TX_DP<10>")
	)
	(segment
		(start 101.726492 -235.250228)
		(end 101.724968 -235.251244)
		(width 0.1143)
		(layer "In11.Cu")
		(net "P5E_CPU1_G1_TX_DP<10>")
	)
	(segment
		(start 101.692202 -239.118648)
		(end 101.717856 -239.13338)
		(width 0.1143)
		(layer "In11.Cu")
		(net "P5E_CPU1_G1_TX_DP<10>")
	)
	(segment
		(start 101.724968 -234.277408)
		(end 101.763068 -234.29976)
		(width 0.1143)
		(layer "In11.Cu")
		(net "P5E_CPU1_G1_TX_DP<10>")
	)
	(segment
		(start 101.723952 -235.251752)
		(end 101.72319 -235.25226)
		(width 0.1143)
		(layer "In11.Cu")
		(net "P5E_CPU1_G1_TX_DP<10>")
	)
	(segment
		(start 101.71938 -239.134396)
		(end 101.72192 -239.135666)
		(width 0.1143)
		(layer "In11.Cu")
		(net "P5E_CPU1_G1_TX_DP<10>")
	)
	(segment
		(start 101.72319 -233.632248)
		(end 101.692202 -233.650028)
		(width 0.1143)
		(layer "In11.Cu")
		(net "P5E_CPU1_G1_TX_DP<10>")
	)
	(segment
		(start 101.222302 -225.3488)
		(end 101.24694 -225.363024)
		(width 0.1143)
		(layer "In11.Cu")
		(net "P5E_CPU1_G1_TX_DP<10>")
	)
	(segment
		(start 101.72319 -240.75644)
		(end 101.723952 -240.756948)
		(width 0.1143)
		(layer "In11.Cu")
		(net "P5E_CPU1_G1_TX_DP<10>")
	)
	(segment
		(start 101.254052 -225.367088)
		(end 101.255068 -225.367596)
		(width 0.1143)
		(layer "In11.Cu")
		(net "P5E_CPU1_G1_TX_DP<10>")
	)
	(segment
		(start 101.723952 -243.996972)
		(end 101.724968 -243.99748)
		(width 0.1143)
		(layer "In11.Cu")
		(net "P5E_CPU1_G1_TX_DP<10>")
	)
	(segment
		(start 101.727508 -244.969792)
		(end 101.726492 -244.9703)
		(width 0.1143)
		(layer "In11.Cu")
		(net "P5E_CPU1_G1_TX_DP<10>")
	)
	(segment
		(start 101.717856 -232.653332)
		(end 101.71938 -232.654348)
		(width 0.1143)
		(layer "In11.Cu")
		(net "P5E_CPU1_G1_TX_DP<10>")
	)
	(segment
		(start 100.090478 -221.30893)
		(end 100.126292 -221.344744)
		(width 0.1143)
		(layer "In11.Cu")
		(net "P5E_CPU1_G1_TX_DP<10>")
	)
	(segment
		(start 101.724968 -240.757456)
		(end 101.763068 -240.779808)
		(width 0.1143)
		(layer "In11.Cu")
		(net "P5E_CPU1_G1_TX_DP<10>")
	)
	(segment
		(start 101.256592 -225.368612)
		(end 101.293168 -225.389948)
		(width 0.1143)
		(layer "In11.Cu")
		(net "P5E_CPU1_G1_TX_DP<10>")
	)
	(segment
		(start 30.076648 -19.42719)
		(end 30.076648 -20.192746)
		(width 0.14224)
		(layer "In11.Cu")
		(net "P5E_CPU1_G1_TX_DP<10>")
	)
	(segment
		(start 101.724968 -243.351304)
		(end 101.723952 -243.351812)
		(width 0.1143)
		(layer "In11.Cu")
		(net "P5E_CPU1_G1_TX_DP<10>")
	)
	(segment
		(start 101.727508 -241.729768)
		(end 101.726492 -241.730276)
		(width 0.1143)
		(layer "In11.Cu")
		(net "P5E_CPU1_G1_TX_DP<10>")
	)
	(segment
		(start 101.72319 -242.376452)
		(end 101.723952 -242.37696)
		(width 0.1143)
		(layer "In11.Cu")
		(net "P5E_CPU1_G1_TX_DP<10>")
	)
	(segment
		(start 101.72319 -239.136428)
		(end 101.723952 -239.136936)
		(width 0.1143)
		(layer "In11.Cu")
		(net "P5E_CPU1_G1_TX_DP<10>")
	)
	(segment
		(start 101.723952 -235.896912)
		(end 101.724968 -235.89742)
		(width 0.1143)
		(layer "In11.Cu")
		(net "P5E_CPU1_G1_TX_DP<10>")
	)
	(segment
		(start 101.763068 -227.129086)
		(end 101.723952 -227.151946)
		(width 0.1143)
		(layer "In11.Cu")
		(net "P5E_CPU1_G1_TX_DP<10>")
	)
	(segment
		(start 101.723952 -240.111788)
		(end 101.72319 -240.112296)
		(width 0.1143)
		(layer "In11.Cu")
		(net "P5E_CPU1_G1_TX_DP<10>")
	)
	(segment
		(start 101.72192 -240.755678)
		(end 101.72319 -240.75644)
		(width 0.1143)
		(layer "In11.Cu")
		(net "P5E_CPU1_G1_TX_DP<10>")
	)
	(segment
		(start 100.783898 -223.911922)
		(end 100.753418 -223.929702)
		(width 0.1143)
		(layer "In11.Cu")
		(net "P5E_CPU1_G1_TX_DP<10>")
	)
	(segment
		(start 101.726492 -240.110264)
		(end 101.724968 -240.11128)
		(width 0.1143)
		(layer "In11.Cu")
		(net "P5E_CPU1_G1_TX_DP<10>")
	)
	(segment
		(start 101.72319 -243.35232)
		(end 101.692202 -243.3701)
		(width 0.1143)
		(layer "In11.Cu")
		(net "P5E_CPU1_G1_TX_DP<10>")
	)
	(segment
		(start 101.723952 -236.871764)
		(end 101.72319 -236.872272)
		(width 0.1143)
		(layer "In11.Cu")
		(net "P5E_CPU1_G1_TX_DP<10>")
	)
	(segment
		(start 101.71938 -232.654348)
		(end 101.72192 -232.655618)
		(width 0.1143)
		(layer "In11.Cu")
		(net "P5E_CPU1_G1_TX_DP<10>")
	)
	(arc
		(start 101.692202 -230.410258)
		(mid 101.577526 -230.543592)
		(end 101.536246 -230.71455)
		(width 0.1143)
		(layer "In11.Cu")
		(net "P5E_CPU1_G1_TX_DP<10>")
	)
	(arc
		(start 101.763068 -237.539784)
		(mid 102.006395 -238.00435)
		(end 101.763068 -238.468916)
		(width 0.1143)
		(layer "In11.Cu")
		(net "P5E_CPU1_G1_TX_DP<10>")
	)
	(arc
		(start 101.066346 -225.044508)
		(mid 101.107601 -225.215479)
		(end 101.222302 -225.3488)
		(width 0.1143)
		(layer "In11.Cu")
		(net "P5E_CPU1_G1_TX_DP<10>")
	)
	(arc
		(start 101.763068 -239.159796)
		(mid 102.006395 -239.624362)
		(end 101.763068 -240.088928)
		(width 0.1143)
		(layer "In11.Cu")
		(net "P5E_CPU1_G1_TX_DP<10>")
	)
	(arc
		(start 100.596446 -222.61449)
		(mid 100.637995 -222.785912)
		(end 100.753418 -222.91929)
		(width 0.1143)
		(layer "In11.Cu")
		(net "P5E_CPU1_G1_TX_DP<10>")
	)
	(arc
		(start 101.692202 -246.610124)
		(mid 101.577526 -246.743458)
		(end 101.536246 -246.914416)
		(width 0.1143)
		(layer "In11.Cu")
		(net "P5E_CPU1_G1_TX_DP<10>")
	)
	(arc
		(start 101.692202 -235.27004)
		(mid 101.536274 -235.574332)
		(end 101.692202 -235.878624)
		(width 0.1143)
		(layer "In11.Cu")
		(net "P5E_CPU1_G1_TX_DP<10>")
	)
	(arc
		(start 101.763068 -244.019832)
		(mid 102.006395 -244.484398)
		(end 101.763068 -244.948964)
		(width 0.1143)
		(layer "In11.Cu")
		(net "P5E_CPU1_G1_TX_DP<10>")
	)
	(arc
		(start 100.753418 -223.929702)
		(mid 100.596441 -224.234502)
		(end 100.753418 -224.539302)
		(width 0.1143)
		(layer "In11.Cu")
		(net "P5E_CPU1_G1_TX_DP<10>")
	)
	(arc
		(start 101.763068 -240.779808)
		(mid 102.006395 -241.244374)
		(end 101.763068 -241.70894)
		(width 0.1143)
		(layer "In11.Cu")
		(net "P5E_CPU1_G1_TX_DP<10>")
	)
	(arc
		(start 101.693472 -228.789738)
		(mid 101.578045 -228.923114)
		(end 101.5365 -229.094538)
		(width 0.1143)
		(layer "In11.Cu")
		(net "P5E_CPU1_G1_TX_DP<10>")
	)
	(arc
		(start 101.692202 -244.990112)
		(mid 101.536274 -245.294404)
		(end 101.692202 -245.598696)
		(width 0.1143)
		(layer "In11.Cu")
		(net "P5E_CPU1_G1_TX_DP<10>")
	)
	(arc
		(start 101.536246 -246.914416)
		(mid 101.471731 -247.176635)
		(end 101.292914 -247.378982)
		(width 0.1143)
		(layer "In11.Cu")
		(net "P5E_CPU1_G1_TX_DP<10>")
	)
	(arc
		(start 101.763068 -242.39982)
		(mid 102.006395 -242.864386)
		(end 101.763068 -243.328952)
		(width 0.1143)
		(layer "In11.Cu")
		(net "P5E_CPU1_G1_TX_DP<10>")
	)
	(arc
		(start 101.693472 -227.169726)
		(mid 101.536495 -227.474526)
		(end 101.693472 -227.779326)
		(width 0.1143)
		(layer "In11.Cu")
		(net "P5E_CPU1_G1_TX_DP<10>")
	)
	(arc
		(start 101.763068 -245.639844)
		(mid 102.006395 -246.10441)
		(end 101.763068 -246.568976)
		(width 0.1143)
		(layer "In11.Cu")
		(net "P5E_CPU1_G1_TX_DP<10>")
	)
	(arc
		(start 101.5365 -225.854514)
		(mid 101.578049 -226.025936)
		(end 101.693472 -226.159314)
		(width 0.1143)
		(layer "In11.Cu")
		(net "P5E_CPU1_G1_TX_DP<10>")
	)
	(arc
		(start 100.353114 -222.149924)
		(mid 100.531927 -222.352274)
		(end 100.596446 -222.61449)
		(width 0.1143)
		(layer "In11.Cu")
		(net "P5E_CPU1_G1_TX_DP<10>")
	)
	(arc
		(start 101.223318 -247.419622)
		(mid 101.125553 -247.522598)
		(end 101.073204 -247.654572)
		(width 0.1143)
		(layer "In11.Cu")
		(net "P5E_CPU1_G1_TX_DP<10>")
	)
	(arc
		(start 101.5365 -229.094538)
		(mid 101.577466 -229.264944)
		(end 101.69144 -229.398068)
		(width 0.1143)
		(layer "In11.Cu")
		(net "P5E_CPU1_G1_TX_DP<10>")
	)
	(arc
		(start 101.763068 -226.199954)
		(mid 102.006395 -226.66452)
		(end 101.763068 -227.129086)
		(width 0.1143)
		(layer "In11.Cu")
		(net "P5E_CPU1_G1_TX_DP<10>")
	)
	(arc
		(start 101.692202 -232.030016)
		(mid 101.536274 -232.334308)
		(end 101.692202 -232.6386)
		(width 0.1143)
		(layer "In11.Cu")
		(net "P5E_CPU1_G1_TX_DP<10>")
	)
	(arc
		(start 101.692202 -238.510064)
		(mid 101.536274 -238.814356)
		(end 101.692202 -239.118648)
		(width 0.1143)
		(layer "In11.Cu")
		(net "P5E_CPU1_G1_TX_DP<10>")
	)
	(arc
		(start 101.763068 -231.059736)
		(mid 102.006395 -231.524302)
		(end 101.763068 -231.988868)
		(width 0.1143)
		(layer "In11.Cu")
		(net "P5E_CPU1_G1_TX_DP<10>")
	)
	(arc
		(start 101.763068 -229.439724)
		(mid 101.941881 -229.642074)
		(end 102.0064 -229.90429)
		(width 0.1143)
		(layer "In11.Cu")
		(net "P5E_CPU1_G1_TX_DP<10>")
	)
	(arc
		(start 101.763068 -227.819966)
		(mid 102.006395 -228.284532)
		(end 101.763068 -228.749098)
		(width 0.1143)
		(layer "In11.Cu")
		(net "P5E_CPU1_G1_TX_DP<10>")
	)
	(arc
		(start 101.692202 -241.750088)
		(mid 101.536274 -242.05438)
		(end 101.692202 -242.358672)
		(width 0.1143)
		(layer "In11.Cu")
		(net "P5E_CPU1_G1_TX_DP<10>")
	)
	(arc
		(start 100.823014 -224.579942)
		(mid 101.001827 -224.782292)
		(end 101.066346 -225.044508)
		(width 0.1143)
		(layer "In11.Cu")
		(net "P5E_CPU1_G1_TX_DP<10>")
	)
	(arc
		(start 101.536246 -230.71455)
		(mid 101.577008 -230.884434)
		(end 101.690424 -231.017318)
		(width 0.1143)
		(layer "In11.Cu")
		(net "P5E_CPU1_G1_TX_DP<10>")
	)
	(arc
		(start 101.692202 -233.650028)
		(mid 101.536274 -233.95432)
		(end 101.692202 -234.258612)
		(width 0.1143)
		(layer "In11.Cu")
		(net "P5E_CPU1_G1_TX_DP<10>")
	)
	(arc
		(start 101.293168 -225.389948)
		(mid 101.471981 -225.592298)
		(end 101.5365 -225.854514)
		(width 0.1143)
		(layer "In11.Cu")
		(net "P5E_CPU1_G1_TX_DP<10>")
	)
	(arc
		(start 100.823014 -222.95993)
		(mid 101.066341 -223.424496)
		(end 100.823014 -223.889062)
		(width 0.1143)
		(layer "In11.Cu")
		(net "P5E_CPU1_G1_TX_DP<10>")
	)
	(arc
		(start 102.0064 -229.90429)
		(mid 101.941164 -230.167881)
		(end 101.760528 -230.370634)
		(width 0.1143)
		(layer "In11.Cu")
		(net "P5E_CPU1_G1_TX_DP<10>")
	)
	(arc
		(start 101.763068 -235.919772)
		(mid 102.006395 -236.384338)
		(end 101.763068 -236.848904)
		(width 0.1143)
		(layer "In11.Cu")
		(net "P5E_CPU1_G1_TX_DP<10>")
	)
	(arc
		(start 100.126292 -221.804484)
		(mid 100.167547 -221.975455)
		(end 100.282248 -222.108776)
		(width 0.1143)
		(layer "In11.Cu")
		(net "P5E_CPU1_G1_TX_DP<10>")
	)
	(arc
		(start 101.692202 -236.890052)
		(mid 101.536274 -237.194344)
		(end 101.692202 -237.498636)
		(width 0.1143)
		(layer "In11.Cu")
		(net "P5E_CPU1_G1_TX_DP<10>")
	)
	(arc
		(start 101.692202 -240.130076)
		(mid 101.536274 -240.434368)
		(end 101.692202 -240.73866)
		(width 0.1143)
		(layer "In11.Cu")
		(net "P5E_CPU1_G1_TX_DP<10>")
	)
	(arc
		(start 101.763068 -234.29976)
		(mid 102.006395 -234.764326)
		(end 101.763068 -235.228892)
		(width 0.1143)
		(layer "In11.Cu")
		(net "P5E_CPU1_G1_TX_DP<10>")
	)
	(arc
		(start 101.692202 -243.3701)
		(mid 101.536274 -243.674392)
		(end 101.692202 -243.978684)
		(width 0.1143)
		(layer "In11.Cu")
		(net "P5E_CPU1_G1_TX_DP<10>")
	)
	(arc
		(start 101.763068 -232.679748)
		(mid 102.006395 -233.144314)
		(end 101.763068 -233.60888)
		(width 0.1143)
		(layer "In11.Cu")
		(net "P5E_CPU1_G1_TX_DP<10>")
	)
	(segment
		(start 58.37682 -18.86585)
		(end 58.64733 -19.13636)
		(width 0.12954)
		(layer "F.Cu")
		(net "P5E_CPU1_G1_TX_DP<0>")
	)
	(segment
		(start 58.37682 -18.186146)
		(end 58.37682 -18.86585)
		(width 0.12954)
		(layer "F.Cu")
		(net "P5E_CPU1_G1_TX_DP<0>")
	)
	(segment
		(start 58.67273 -17.890236)
		(end 58.37682 -18.186146)
		(width 0.12954)
		(layer "F.Cu")
		(net "P5E_CPU1_G1_TX_DP<0>")
	)
	(segment
		(start 109.897926 -248.800366)
		(end 109.431074 -248.534428)
		(width 0.12954)
		(layer "F.Cu")
		(net "P5E_CPU1_G1_TX_DP<0>")
	)
	(segment
		(start 110.858808 -245.943628)
		(end 110.2995 -246.502936)
		(width 0.1143)
		(layer "In11.Cu")
		(net "P5E_CPU1_G1_TX_DP<0>")
	)
	(segment
		(start 156.479748 -173.0883)
		(end 152.939496 -178.066446)
		(width 0.14224)
		(layer "In11.Cu")
		(net "P5E_CPU1_G1_TX_DP<0>")
	)
	(segment
		(start 110.18393 -246.591836)
		(end 110.15345 -246.609616)
		(width 0.1143)
		(layer "In11.Cu")
		(net "P5E_CPU1_G1_TX_DP<0>")
	)
	(segment
		(start 159.26435 -159.66186)
		(end 159.26435 -164.989764)
		(width 0.14224)
		(layer "In11.Cu")
		(net "P5E_CPU1_G1_TX_DP<0>")
	)
	(segment
		(start 58.3565 -29.013658)
		(end 59.16168 -48.080168)
		(width 0.14224)
		(layer "In11.Cu")
		(net "P5E_CPU1_G1_TX_DP<0>")
	)
	(segment
		(start 110.923832 -245.943628)
		(end 110.858808 -245.943628)
		(width 0.1143)
		(layer "In11.Cu")
		(net "P5E_CPU1_G1_TX_DP<0>")
	)
	(segment
		(start 109.133132 -248.534428)
		(end 109.431074 -248.534428)
		(width 0.1143)
		(layer "In11.Cu")
		(net "P5E_CPU1_G1_TX_DP<0>")
	)
	(segment
		(start 156.661104 -172.594524)
		(end 156.661104 -172.594778)
		(width 0.14224)
		(layer "In11.Cu")
		(net "P5E_CPU1_G1_TX_DP<0>")
	)
	(segment
		(start 110.588044 -220.574108)
		(end 110.588044 -221.418658)
		(width 0.14224)
		(layer "In11.Cu")
		(net "P5E_CPU1_G1_TX_DP<0>")
	)
	(segment
		(start 111.15421 -245.71325)
		(end 110.943898 -245.923562)
		(width 0.14224)
		(layer "In11.Cu")
		(net "P5E_CPU1_G1_TX_DP<0>")
	)
	(segment
		(start 158.429706 -146.327368)
		(end 159.26435 -159.66186)
		(width 0.14224)
		(layer "In11.Cu")
		(net "P5E_CPU1_G1_TX_DP<0>")
	)
	(segment
		(start 109.713522 -247.401842)
		(end 109.685582 -247.418098)
		(width 0.1143)
		(layer "In11.Cu")
		(net "P5E_CPU1_G1_TX_DP<0>")
	)
	(segment
		(start 156.661358 -172.594524)
		(end 156.661104 -172.594524)
		(width 0.14224)
		(layer "In11.Cu")
		(net "P5E_CPU1_G1_TX_DP<0>")
	)
	(segment
		(start 158.411672 -145.032222)
		(end 158.429706 -145.360644)
		(width 0.14224)
		(layer "In11.Cu")
		(net "P5E_CPU1_G1_TX_DP<0>")
	)
	(segment
		(start 106.416348 -92.03055)
		(end 106.416348 -92.030042)
		(width 0.14224)
		(layer "In11.Cu")
		(net "P5E_CPU1_G1_TX_DP<0>")
	)
	(segment
		(start 111.15421 -222.785686)
		(end 111.15421 -245.71325)
		(width 0.14224)
		(layer "In11.Cu")
		(net "P5E_CPU1_G1_TX_DP<0>")
	)
	(segment
		(start 156.661104 -172.594778)
		(end 156.479748 -173.0883)
		(width 0.14224)
		(layer "In11.Cu")
		(net "P5E_CPU1_G1_TX_DP<0>")
	)
	(segment
		(start 58.64733 -19.13636)
		(end 58.3565 -19.42719)
		(width 0.14224)
		(layer "In11.Cu")
		(net "P5E_CPU1_G1_TX_DP<0>")
	)
	(segment
		(start 110.58779 -220.573854)
		(end 110.588044 -220.574108)
		(width 0.14224)
		(layer "In11.Cu")
		(net "P5E_CPU1_G1_TX_DP<0>")
	)
	(segment
		(start 153.145236 -134.050024)
		(end 158.411672 -145.032222)
		(width 0.14224)
		(layer "In11.Cu")
		(net "P5E_CPU1_G1_TX_DP<0>")
	)
	(segment
		(start 60.5282 -50.766218)
		(end 106.416348 -92.03055)
		(width 0.14224)
		(layer "In11.Cu")
		(net "P5E_CPU1_G1_TX_DP<0>")
	)
	(segment
		(start 110.588044 -216.114884)
		(end 110.58779 -216.115392)
		(width 0.14224)
		(layer "In11.Cu")
		(net "P5E_CPU1_G1_TX_DP<0>")
	)
	(segment
		(start 109.063282 -248.464578)
		(end 109.133132 -248.534428)
		(width 0.1143)
		(layer "In11.Cu")
		(net "P5E_CPU1_G1_TX_DP<0>")
	)
	(segment
		(start 109.753146 -247.378982)
		(end 109.71657 -247.400318)
		(width 0.1143)
		(layer "In11.Cu")
		(net "P5E_CPU1_G1_TX_DP<0>")
	)
	(segment
		(start 159.26435 -164.989764)
		(end 156.830776 -172.133514)
		(width 0.14224)
		(layer "In11.Cu")
		(net "P5E_CPU1_G1_TX_DP<0>")
	)
	(segment
		(start 59.16168 -48.080168)
		(end 60.5282 -50.766218)
		(width 0.14224)
		(layer "In11.Cu")
		(net "P5E_CPU1_G1_TX_DP<0>")
	)
	(segment
		(start 106.416348 -92.030042)
		(end 153.145236 -134.050024)
		(width 0.14224)
		(layer "In11.Cu")
		(net "P5E_CPU1_G1_TX_DP<0>")
	)
	(segment
		(start 156.830776 -172.133514)
		(end 156.661358 -172.594524)
		(width 0.14224)
		(layer "In11.Cu")
		(net "P5E_CPU1_G1_TX_DP<0>")
	)
	(segment
		(start 109.715046 -247.401334)
		(end 109.71403 -247.401842)
		(width 0.1143)
		(layer "In11.Cu")
		(net "P5E_CPU1_G1_TX_DP<0>")
	)
	(segment
		(start 110.588044 -221.418658)
		(end 111.15421 -222.785686)
		(width 0.14224)
		(layer "In11.Cu")
		(net "P5E_CPU1_G1_TX_DP<0>")
	)
	(segment
		(start 109.71403 -247.401842)
		(end 109.713522 -247.401842)
		(width 0.1143)
		(layer "In11.Cu")
		(net "P5E_CPU1_G1_TX_DP<0>")
	)
	(segment
		(start 109.71657 -247.400318)
		(end 109.715046 -247.401334)
		(width 0.1143)
		(layer "In11.Cu")
		(net "P5E_CPU1_G1_TX_DP<0>")
	)
	(segment
		(start 152.939496 -178.066446)
		(end 114.431318 -209.641948)
		(width 0.14224)
		(layer "In11.Cu")
		(net "P5E_CPU1_G1_TX_DP<0>")
	)
	(segment
		(start 109.280452 -248.190766)
		(end 109.24413 -248.211848)
		(width 0.1143)
		(layer "In11.Cu")
		(net "P5E_CPU1_G1_TX_DP<0>")
	)
	(segment
		(start 110.943898 -245.923562)
		(end 110.923832 -245.943628)
		(width 0.1143)
		(layer "In11.Cu")
		(net "P5E_CPU1_G1_TX_DP<0>")
	)
	(segment
		(start 109.24413 -248.211848)
		(end 109.21238 -248.230136)
		(width 0.1143)
		(layer "In11.Cu")
		(net "P5E_CPU1_G1_TX_DP<0>")
	)
	(segment
		(start 110.58779 -216.115392)
		(end 110.58779 -220.573854)
		(width 0.14224)
		(layer "In11.Cu")
		(net "P5E_CPU1_G1_TX_DP<0>")
	)
	(segment
		(start 158.429706 -145.360644)
		(end 158.429706 -146.327368)
		(width 0.14224)
		(layer "In11.Cu")
		(net "P5E_CPU1_G1_TX_DP<0>")
	)
	(segment
		(start 58.3565 -19.42719)
		(end 58.3565 -29.013658)
		(width 0.14224)
		(layer "In11.Cu")
		(net "P5E_CPU1_G1_TX_DP<0>")
	)
	(segment
		(start 114.431318 -209.641948)
		(end 110.588044 -216.114884)
		(width 0.14224)
		(layer "In11.Cu")
		(net "P5E_CPU1_G1_TX_DP<0>")
	)
	(arc
		(start 110.15345 -246.609616)
		(mid 110.038023 -246.742992)
		(end 109.996478 -246.914416)
		(width 0.1143)
		(layer "In11.Cu")
		(net "P5E_CPU1_G1_TX_DP<0>")
	)
	(arc
		(start 109.678216 -247.423686)
		(mid 109.578471 -247.553454)
		(end 109.528102 -247.709182)
		(width 0.1143)
		(layer "In11.Cu")
		(net "P5E_CPU1_G1_TX_DP<0>")
	)
	(arc
		(start 109.52607 -247.73382)
		(mid 109.460679 -247.981946)
		(end 109.296708 -248.179336)
		(width 0.1143)
		(layer "In11.Cu")
		(net "P5E_CPU1_G1_TX_DP<0>")
	)
	(arc
		(start 109.296708 -248.179336)
		(mid 109.28863 -248.185122)
		(end 109.280452 -248.190766)
		(width 0.1143)
		(layer "In11.Cu")
		(net "P5E_CPU1_G1_TX_DP<0>")
	)
	(arc
		(start 109.685582 -247.418098)
		(mid 109.681882 -247.420869)
		(end 109.678216 -247.423686)
		(width 0.1143)
		(layer "In11.Cu")
		(net "P5E_CPU1_G1_TX_DP<0>")
	)
	(arc
		(start 109.996478 -246.914416)
		(mid 109.931963 -247.176635)
		(end 109.753146 -247.378982)
		(width 0.1143)
		(layer "In11.Cu")
		(net "P5E_CPU1_G1_TX_DP<0>")
	)
	(arc
		(start 109.21238 -248.230136)
		(mid 109.115245 -248.333005)
		(end 109.063282 -248.464578)
		(width 0.1143)
		(layer "In11.Cu")
		(net "P5E_CPU1_G1_TX_DP<0>")
	)
	(arc
		(start 109.528102 -247.709182)
		(mid 109.52677 -247.721475)
		(end 109.52607 -247.73382)
		(width 0.1143)
		(layer "In11.Cu")
		(net "P5E_CPU1_G1_TX_DP<0>")
	)
	(arc
		(start 110.2995 -246.502936)
		(mid 110.244601 -246.551138)
		(end 110.18393 -246.591836)
		(width 0.1143)
		(layer "In11.Cu")
		(net "P5E_CPU1_G1_TX_DP<0>")
	)
	(segment
		(start 32.272478 -16.366236)
		(end 32.568388 -16.662146)
		(width 0.12954)
		(layer "F.Cu")
		(net "P5E_CPU1_G1_TX_DN<9>")
	)
	(segment
		(start 32.568388 -17.341596)
		(end 32.296862 -17.613122)
		(width 0.12954)
		(layer "F.Cu")
		(net "P5E_CPU1_G1_TX_DN<9>")
	)
	(segment
		(start 103.787956 -246.370348)
		(end 103.321104 -246.10441)
		(width 0.12954)
		(layer "F.Cu")
		(net "P5E_CPU1_G1_TX_DN<9>")
	)
	(segment
		(start 32.568388 -16.662146)
		(end 32.568388 -17.341596)
		(width 0.12954)
		(layer "F.Cu")
		(net "P5E_CPU1_G1_TX_DN<9>")
	)
	(segment
		(start 102.598728 -236.689138)
		(end 102.568248 -236.706918)
		(width 0.1143)
		(layer "In11.Cu")
		(net "P5E_CPU1_G1_TX_DN<9>")
	)
	(segment
		(start 102.529132 -231.179116)
		(end 102.568248 -231.201976)
		(width 0.1143)
		(layer "In11.Cu")
		(net "P5E_CPU1_G1_TX_DN<9>")
	)
	(segment
		(start 102.058978 -225.509074)
		(end 102.065836 -225.513138)
		(width 0.1143)
		(layer "In11.Cu")
		(net "P5E_CPU1_G1_TX_DN<9>")
	)
	(segment
		(start 102.568248 -231.201976)
		(end 102.60076 -231.220772)
		(width 0.1143)
		(layer "In11.Cu")
		(net "P5E_CPU1_G1_TX_DN<9>")
	)
	(segment
		(start 102.598728 -238.30915)
		(end 102.568248 -238.32693)
		(width 0.1143)
		(layer "In11.Cu")
		(net "P5E_CPU1_G1_TX_DN<9>")
	)
	(segment
		(start 100.799138 -221.083378)
		(end 100.844858 -221.129098)
		(width 0.1143)
		(layer "In11.Cu")
		(net "P5E_CPU1_G1_TX_DN<9>")
	)
	(segment
		(start 149.682708 -146.936714)
		(end 150.496778 -159.945578)
		(width 0.14224)
		(layer "In11.Cu")
		(net "P5E_CPU1_G1_TX_DN<9>")
	)
	(segment
		(start 102.568248 -226.34194)
		(end 102.598728 -226.35972)
		(width 0.1143)
		(layer "In11.Cu")
		(net "P5E_CPU1_G1_TX_DN<9>")
	)
	(segment
		(start 102.100126 -225.533204)
		(end 102.129844 -225.550222)
		(width 0.1143)
		(layer "In11.Cu")
		(net "P5E_CPU1_G1_TX_DN<9>")
	)
	(segment
		(start 101.658674 -223.729296)
		(end 101.628194 -223.747076)
		(width 0.1143)
		(layer "In11.Cu")
		(net "P5E_CPU1_G1_TX_DN<9>")
	)
	(segment
		(start 102.531164 -229.560628)
		(end 102.568248 -229.581964)
		(width 0.1143)
		(layer "In11.Cu")
		(net "P5E_CPU1_G1_TX_DN<9>")
	)
	(segment
		(start 101.628194 -223.101916)
		(end 101.658674 -223.119696)
		(width 0.1143)
		(layer "In11.Cu")
		(net "P5E_CPU1_G1_TX_DN<9>")
	)
	(segment
		(start 146.08429 -139.496038)
		(end 149.682708 -146.936714)
		(width 0.14224)
		(layer "In11.Cu")
		(net "P5E_CPU1_G1_TX_DN<9>")
	)
	(segment
		(start 102.568248 -229.581964)
		(end 102.60076 -229.60076)
		(width 0.1143)
		(layer "In11.Cu")
		(net "P5E_CPU1_G1_TX_DN<9>")
	)
	(segment
		(start 102.568248 -226.9871)
		(end 102.529132 -227.00996)
		(width 0.1143)
		(layer "In11.Cu")
		(net "P5E_CPU1_G1_TX_DN<9>")
	)
	(segment
		(start 102.529132 -244.138958)
		(end 102.568248 -244.161818)
		(width 0.1143)
		(layer "In11.Cu")
		(net "P5E_CPU1_G1_TX_DN<9>")
	)
	(segment
		(start 102.093776 -225.529394)
		(end 102.0953 -225.53041)
		(width 0.1143)
		(layer "In11.Cu")
		(net "P5E_CPU1_G1_TX_DN<9>")
	)
	(segment
		(start 54.199028 -56.869076)
		(end 146.08429 -139.496038)
		(width 0.14224)
		(layer "In11.Cu")
		(net "P5E_CPU1_G1_TX_DN<9>")
	)
	(segment
		(start 107.500166 -204.08646)
		(end 100.838508 -215.372696)
		(width 0.14224)
		(layer "In11.Cu")
		(net "P5E_CPU1_G1_TX_DN<9>")
	)
	(segment
		(start 102.529132 -227.939092)
		(end 102.568248 -227.961952)
		(width 0.1143)
		(layer "In11.Cu")
		(net "P5E_CPU1_G1_TX_DN<9>")
	)
	(segment
		(start 103.2383 -245.303802)
		(end 103.2383 -245.313454)
		(width 0.1143)
		(layer "In11.Cu")
		(net "P5E_CPU1_G1_TX_DN<9>")
	)
	(segment
		(start 102.568248 -236.061758)
		(end 102.598728 -236.079538)
		(width 0.1143)
		(layer "In11.Cu")
		(net "P5E_CPU1_G1_TX_DN<9>")
	)
	(segment
		(start 102.568248 -236.706918)
		(end 102.529132 -236.729778)
		(width 0.1143)
		(layer "In11.Cu")
		(net "P5E_CPU1_G1_TX_DN<9>")
	)
	(segment
		(start 102.529132 -242.518946)
		(end 102.568248 -242.541806)
		(width 0.1143)
		(layer "In11.Cu")
		(net "P5E_CPU1_G1_TX_DN<9>")
	)
	(segment
		(start 102.529132 -240.898934)
		(end 102.568248 -240.921794)
		(width 0.1143)
		(layer "In11.Cu")
		(net "P5E_CPU1_G1_TX_DN<9>")
	)
	(segment
		(start 32.587692 -17.903952)
		(end 32.587692 -20.259802)
		(width 0.14224)
		(layer "In11.Cu")
		(net "P5E_CPU1_G1_TX_DN<9>")
	)
	(segment
		(start 102.098856 -225.532442)
		(end 102.100126 -225.533204)
		(width 0.1143)
		(layer "In11.Cu")
		(net "P5E_CPU1_G1_TX_DN<9>")
	)
	(segment
		(start 102.568248 -228.607112)
		(end 102.529132 -228.629972)
		(width 0.1143)
		(layer "In11.Cu")
		(net "P5E_CPU1_G1_TX_DN<9>")
	)
	(segment
		(start 102.091236 -225.52787)
		(end 102.09276 -225.528886)
		(width 0.1143)
		(layer "In11.Cu")
		(net "P5E_CPU1_G1_TX_DN<9>")
	)
	(segment
		(start 102.568248 -237.68177)
		(end 102.598728 -237.69955)
		(width 0.1143)
		(layer "In11.Cu")
		(net "P5E_CPU1_G1_TX_DN<9>")
	)
	(segment
		(start 101.589078 -224.699068)
		(end 101.628194 -224.721928)
		(width 0.1143)
		(layer "In11.Cu")
		(net "P5E_CPU1_G1_TX_DN<9>")
	)
	(segment
		(start 102.0953 -225.53041)
		(end 102.097078 -225.531426)
		(width 0.1143)
		(layer "In11.Cu")
		(net "P5E_CPU1_G1_TX_DN<9>")
	)
	(segment
		(start 102.568248 -241.566954)
		(end 102.529132 -241.589814)
		(width 0.1143)
		(layer "In11.Cu")
		(net "P5E_CPU1_G1_TX_DN<9>")
	)
	(segment
		(start 102.568248 -232.821734)
		(end 102.598728 -232.839514)
		(width 0.1143)
		(layer "In11.Cu")
		(net "P5E_CPU1_G1_TX_DN<9>")
	)
	(segment
		(start 102.529132 -234.418886)
		(end 102.568248 -234.441746)
		(width 0.1143)
		(layer "In11.Cu")
		(net "P5E_CPU1_G1_TX_DN<9>")
	)
	(segment
		(start 101.120702 -222.27032)
		(end 101.121718 -222.270828)
		(width 0.1143)
		(layer "In11.Cu")
		(net "P5E_CPU1_G1_TX_DN<9>")
	)
	(segment
		(start 101.628194 -223.747076)
		(end 101.589078 -223.769936)
		(width 0.1143)
		(layer "In11.Cu")
		(net "P5E_CPU1_G1_TX_DN<9>")
	)
	(segment
		(start 102.529132 -229.559104)
		(end 102.531164 -229.560628)
		(width 0.1143)
		(layer "In11.Cu")
		(net "P5E_CPU1_G1_TX_DN<9>")
	)
	(segment
		(start 102.568248 -244.161818)
		(end 102.598728 -244.179598)
		(width 0.1143)
		(layer "In11.Cu")
		(net "P5E_CPU1_G1_TX_DN<9>")
	)
	(segment
		(start 102.09276 -225.528886)
		(end 102.093776 -225.529394)
		(width 0.1143)
		(layer "In11.Cu")
		(net "P5E_CPU1_G1_TX_DN<9>")
	)
	(segment
		(start 102.598728 -228.589332)
		(end 102.568248 -228.607112)
		(width 0.1143)
		(layer "In11.Cu")
		(net "P5E_CPU1_G1_TX_DN<9>")
	)
	(segment
		(start 102.598728 -233.449114)
		(end 102.568248 -233.466894)
		(width 0.1143)
		(layer "In11.Cu")
		(net "P5E_CPU1_G1_TX_DN<9>")
	)
	(segment
		(start 102.529132 -237.65891)
		(end 102.568248 -237.68177)
		(width 0.1143)
		(layer "In11.Cu")
		(net "P5E_CPU1_G1_TX_DN<9>")
	)
	(segment
		(start 102.097078 -225.531426)
		(end 102.098094 -225.531934)
		(width 0.1143)
		(layer "In11.Cu")
		(net "P5E_CPU1_G1_TX_DN<9>")
	)
	(segment
		(start 102.598728 -231.829102)
		(end 102.568248 -231.846882)
		(width 0.1143)
		(layer "In11.Cu")
		(net "P5E_CPU1_G1_TX_DN<9>")
	)
	(segment
		(start 102.066598 -225.513646)
		(end 102.091236 -225.52787)
		(width 0.1143)
		(layer "In11.Cu")
		(net "P5E_CPU1_G1_TX_DN<9>")
	)
	(segment
		(start 101.119686 -222.269558)
		(end 101.120702 -222.27032)
		(width 0.1143)
		(layer "In11.Cu")
		(net "P5E_CPU1_G1_TX_DN<9>")
	)
	(segment
		(start 102.568248 -242.541806)
		(end 102.598728 -242.559586)
		(width 0.1143)
		(layer "In11.Cu")
		(net "P5E_CPU1_G1_TX_DN<9>")
	)
	(segment
		(start 102.568248 -231.846882)
		(end 102.529132 -231.869742)
		(width 0.1143)
		(layer "In11.Cu")
		(net "P5E_CPU1_G1_TX_DN<9>")
	)
	(segment
		(start 150.496778 -163.362894)
		(end 148.907246 -168.03116)
		(width 0.14224)
		(layer "In11.Cu")
		(net "P5E_CPU1_G1_TX_DN<9>")
	)
	(segment
		(start 32.296862 -17.613122)
		(end 32.587692 -17.903952)
		(width 0.14224)
		(layer "In11.Cu")
		(net "P5E_CPU1_G1_TX_DN<9>")
	)
	(segment
		(start 102.568248 -239.301782)
		(end 102.598728 -239.319562)
		(width 0.1143)
		(layer "In11.Cu")
		(net "P5E_CPU1_G1_TX_DN<9>")
	)
	(segment
		(start 148.907246 -168.03116)
		(end 145.486628 -172.954442)
		(width 0.14224)
		(layer "In11.Cu")
		(net "P5E_CPU1_G1_TX_DN<9>")
	)
	(segment
		(start 102.598728 -226.96932)
		(end 102.568248 -226.9871)
		(width 0.1143)
		(layer "In11.Cu")
		(net "P5E_CPU1_G1_TX_DN<9>")
	)
	(segment
		(start 102.598728 -239.929162)
		(end 102.568248 -239.946942)
		(width 0.1143)
		(layer "In11.Cu")
		(net "P5E_CPU1_G1_TX_DN<9>")
	)
	(segment
		(start 102.598728 -241.549174)
		(end 102.568248 -241.566954)
		(width 0.1143)
		(layer "In11.Cu")
		(net "P5E_CPU1_G1_TX_DN<9>")
	)
	(segment
		(start 102.999032 -244.948964)
		(end 103.050594 -244.978936)
		(width 0.1143)
		(layer "In11.Cu")
		(net "P5E_CPU1_G1_TX_DN<9>")
	)
	(segment
		(start 102.568248 -235.086906)
		(end 102.529132 -235.109766)
		(width 0.1143)
		(layer "In11.Cu")
		(net "P5E_CPU1_G1_TX_DN<9>")
	)
	(segment
		(start 102.568248 -227.961952)
		(end 102.598728 -227.979732)
		(width 0.1143)
		(layer "In11.Cu")
		(net "P5E_CPU1_G1_TX_DN<9>")
	)
	(segment
		(start 101.589078 -223.079056)
		(end 101.628194 -223.101916)
		(width 0.1143)
		(layer "In11.Cu")
		(net "P5E_CPU1_G1_TX_DN<9>")
	)
	(segment
		(start 102.598728 -230.20909)
		(end 102.531672 -230.248206)
		(width 0.1143)
		(layer "In11.Cu")
		(net "P5E_CPU1_G1_TX_DN<9>")
	)
	(segment
		(start 102.529132 -239.278922)
		(end 102.568248 -239.301782)
		(width 0.1143)
		(layer "In11.Cu")
		(net "P5E_CPU1_G1_TX_DN<9>")
	)
	(segment
		(start 101.628194 -224.721928)
		(end 101.658674 -224.739708)
		(width 0.1143)
		(layer "In11.Cu")
		(net "P5E_CPU1_G1_TX_DN<9>")
	)
	(segment
		(start 145.486628 -172.954442)
		(end 107.500166 -204.08646)
		(width 0.14224)
		(layer "In11.Cu")
		(net "P5E_CPU1_G1_TX_DN<9>")
	)
	(segment
		(start 102.529132 -236.038898)
		(end 102.568248 -236.061758)
		(width 0.1143)
		(layer "In11.Cu")
		(net "P5E_CPU1_G1_TX_DN<9>")
	)
	(segment
		(start 102.568248 -233.466894)
		(end 102.529132 -233.489754)
		(width 0.1143)
		(layer "In11.Cu")
		(net "P5E_CPU1_G1_TX_DN<9>")
	)
	(segment
		(start 102.065836 -225.513138)
		(end 102.066598 -225.513646)
		(width 0.1143)
		(layer "In11.Cu")
		(net "P5E_CPU1_G1_TX_DN<9>")
	)
	(segment
		(start 53.544978 -56.323992)
		(end 54.199028 -56.869076)
		(width 0.14224)
		(layer "In11.Cu")
		(net "P5E_CPU1_G1_TX_DN<9>")
	)
	(segment
		(start 102.568248 -243.186966)
		(end 102.529132 -243.209826)
		(width 0.1143)
		(layer "In11.Cu")
		(net "P5E_CPU1_G1_TX_DN<9>")
	)
	(segment
		(start 45.877734 -46.667166)
		(end 53.544978 -56.323992)
		(width 0.14224)
		(layer "In11.Cu")
		(net "P5E_CPU1_G1_TX_DN<9>")
	)
	(segment
		(start 103.688896 -246.03456)
		(end 103.619046 -246.10441)
		(width 0.1143)
		(layer "In11.Cu")
		(net "P5E_CPU1_G1_TX_DN<9>")
	)
	(segment
		(start 101.121718 -222.270828)
		(end 101.18979 -222.310198)
		(width 0.1143)
		(layer "In11.Cu")
		(net "P5E_CPU1_G1_TX_DN<9>")
	)
	(segment
		(start 102.598728 -235.069126)
		(end 102.568248 -235.086906)
		(width 0.1143)
		(layer "In11.Cu")
		(net "P5E_CPU1_G1_TX_DN<9>")
	)
	(segment
		(start 100.799138 -215.43899)
		(end 100.799138 -221.05493)
		(width 0.14224)
		(layer "In11.Cu")
		(net "P5E_CPU1_G1_TX_DN<9>")
	)
	(segment
		(start 32.587692 -20.259802)
		(end 45.877734 -46.667166)
		(width 0.14224)
		(layer "In11.Cu")
		(net "P5E_CPU1_G1_TX_DN<9>")
	)
	(segment
		(start 100.838508 -215.372696)
		(end 100.838254 -215.372696)
		(width 0.14224)
		(layer "In11.Cu")
		(net "P5E_CPU1_G1_TX_DN<9>")
	)
	(segment
		(start 102.598728 -243.169186)
		(end 102.568248 -243.186966)
		(width 0.1143)
		(layer "In11.Cu")
		(net "P5E_CPU1_G1_TX_DN<9>")
	)
	(segment
		(start 103.508048 -245.78183)
		(end 103.539798 -245.800118)
		(width 0.1143)
		(layer "In11.Cu")
		(net "P5E_CPU1_G1_TX_DN<9>")
	)
	(segment
		(start 100.838254 -215.372696)
		(end 100.799138 -215.43899)
		(width 0.14224)
		(layer "In11.Cu")
		(net "P5E_CPU1_G1_TX_DN<9>")
	)
	(segment
		(start 100.799138 -221.05493)
		(end 100.799138 -221.083378)
		(width 0.1143)
		(layer "In11.Cu")
		(net "P5E_CPU1_G1_TX_DN<9>")
	)
	(segment
		(start 100.875846 -221.418912)
		(end 100.875846 -221.804484)
		(width 0.1143)
		(layer "In11.Cu")
		(net "P5E_CPU1_G1_TX_DN<9>")
	)
	(segment
		(start 102.568248 -238.32693)
		(end 102.529132 -238.34979)
		(width 0.1143)
		(layer "In11.Cu")
		(net "P5E_CPU1_G1_TX_DN<9>")
	)
	(segment
		(start 102.529132 -226.31908)
		(end 102.568248 -226.34194)
		(width 0.1143)
		(layer "In11.Cu")
		(net "P5E_CPU1_G1_TX_DN<9>")
	)
	(segment
		(start 102.568248 -239.946942)
		(end 102.529132 -239.969802)
		(width 0.1143)
		(layer "In11.Cu")
		(net "P5E_CPU1_G1_TX_DN<9>")
	)
	(segment
		(start 100.844858 -221.387924)
		(end 100.875846 -221.418912)
		(width 0.1143)
		(layer "In11.Cu")
		(net "P5E_CPU1_G1_TX_DN<9>")
	)
	(segment
		(start 102.529132 -232.798874)
		(end 102.568248 -232.821734)
		(width 0.1143)
		(layer "In11.Cu")
		(net "P5E_CPU1_G1_TX_DN<9>")
	)
	(segment
		(start 150.496778 -159.945578)
		(end 150.496778 -163.362894)
		(width 0.14224)
		(layer "In11.Cu")
		(net "P5E_CPU1_G1_TX_DN<9>")
	)
	(segment
		(start 102.568248 -240.921794)
		(end 102.598728 -240.939574)
		(width 0.1143)
		(layer "In11.Cu")
		(net "P5E_CPU1_G1_TX_DN<9>")
	)
	(segment
		(start 102.568248 -234.441746)
		(end 102.598728 -234.459526)
		(width 0.1143)
		(layer "In11.Cu")
		(net "P5E_CPU1_G1_TX_DN<9>")
	)
	(segment
		(start 100.844858 -221.129098)
		(end 100.844858 -221.387924)
		(width 0.1143)
		(layer "In11.Cu")
		(net "P5E_CPU1_G1_TX_DN<9>")
	)
	(segment
		(start 102.098094 -225.531934)
		(end 102.098856 -225.532442)
		(width 0.1143)
		(layer "In11.Cu")
		(net "P5E_CPU1_G1_TX_DN<9>")
	)
	(segment
		(start 103.619046 -246.10441)
		(end 103.321104 -246.10441)
		(width 0.1143)
		(layer "In11.Cu")
		(net "P5E_CPU1_G1_TX_DN<9>")
	)
	(arc
		(start 102.598728 -232.839514)
		(mid 102.755705 -233.144314)
		(end 102.598728 -233.449114)
		(width 0.1143)
		(layer "In11.Cu")
		(net "P5E_CPU1_G1_TX_DN<9>")
	)
	(arc
		(start 102.7557 -244.484398)
		(mid 102.820215 -244.746617)
		(end 102.999032 -244.948964)
		(width 0.1143)
		(layer "In11.Cu")
		(net "P5E_CPU1_G1_TX_DN<9>")
	)
	(arc
		(start 101.18979 -222.310198)
		(mid 101.304466 -222.443532)
		(end 101.345746 -222.61449)
		(width 0.1143)
		(layer "In11.Cu")
		(net "P5E_CPU1_G1_TX_DN<9>")
	)
	(arc
		(start 102.598728 -227.979732)
		(mid 102.755705 -228.284532)
		(end 102.598728 -228.589332)
		(width 0.1143)
		(layer "In11.Cu")
		(net "P5E_CPU1_G1_TX_DN<9>")
	)
	(arc
		(start 102.531672 -230.248206)
		(mid 102.35102 -230.450951)
		(end 102.2858 -230.71455)
		(width 0.1143)
		(layer "In11.Cu")
		(net "P5E_CPU1_G1_TX_DN<9>")
	)
	(arc
		(start 100.875846 -221.804484)
		(mid 100.940505 -222.067041)
		(end 101.119686 -222.269558)
		(width 0.1143)
		(layer "In11.Cu")
		(net "P5E_CPU1_G1_TX_DN<9>")
	)
	(arc
		(start 102.598728 -242.559586)
		(mid 102.755705 -242.864386)
		(end 102.598728 -243.169186)
		(width 0.1143)
		(layer "In11.Cu")
		(net "P5E_CPU1_G1_TX_DN<9>")
	)
	(arc
		(start 102.2858 -230.71455)
		(mid 102.350315 -230.976769)
		(end 102.529132 -231.179116)
		(width 0.1143)
		(layer "In11.Cu")
		(net "P5E_CPU1_G1_TX_DN<9>")
	)
	(arc
		(start 102.529132 -231.869742)
		(mid 102.285805 -232.334308)
		(end 102.529132 -232.798874)
		(width 0.1143)
		(layer "In11.Cu")
		(net "P5E_CPU1_G1_TX_DN<9>")
	)
	(arc
		(start 102.60076 -231.220772)
		(mid 102.714689 -231.353919)
		(end 102.7557 -231.524302)
		(width 0.1143)
		(layer "In11.Cu")
		(net "P5E_CPU1_G1_TX_DN<9>")
	)
	(arc
		(start 101.589078 -223.769936)
		(mid 101.345751 -224.234502)
		(end 101.589078 -224.699068)
		(width 0.1143)
		(layer "In11.Cu")
		(net "P5E_CPU1_G1_TX_DN<9>")
	)
	(arc
		(start 102.7557 -231.524302)
		(mid 102.714151 -231.695724)
		(end 102.598728 -231.829102)
		(width 0.1143)
		(layer "In11.Cu")
		(net "P5E_CPU1_G1_TX_DN<9>")
	)
	(arc
		(start 102.60076 -229.60076)
		(mid 102.714689 -229.733907)
		(end 102.7557 -229.90429)
		(width 0.1143)
		(layer "In11.Cu")
		(net "P5E_CPU1_G1_TX_DN<9>")
	)
	(arc
		(start 102.529132 -241.589814)
		(mid 102.285805 -242.05438)
		(end 102.529132 -242.518946)
		(width 0.1143)
		(layer "In11.Cu")
		(net "P5E_CPU1_G1_TX_DN<9>")
	)
	(arc
		(start 102.598728 -226.35972)
		(mid 102.755705 -226.66452)
		(end 102.598728 -226.96932)
		(width 0.1143)
		(layer "In11.Cu")
		(net "P5E_CPU1_G1_TX_DN<9>")
	)
	(arc
		(start 103.2383 -245.313454)
		(mid 103.310556 -245.583707)
		(end 103.508048 -245.78183)
		(width 0.1143)
		(layer "In11.Cu")
		(net "P5E_CPU1_G1_TX_DN<9>")
	)
	(arc
		(start 103.539798 -245.800118)
		(mid 103.636933 -245.902987)
		(end 103.688896 -246.03456)
		(width 0.1143)
		(layer "In11.Cu")
		(net "P5E_CPU1_G1_TX_DN<9>")
	)
	(arc
		(start 102.529132 -238.34979)
		(mid 102.285805 -238.814356)
		(end 102.529132 -239.278922)
		(width 0.1143)
		(layer "In11.Cu")
		(net "P5E_CPU1_G1_TX_DN<9>")
	)
	(arc
		(start 103.050594 -244.978936)
		(mid 103.188026 -245.116195)
		(end 103.2383 -245.303802)
		(width 0.1143)
		(layer "In11.Cu")
		(net "P5E_CPU1_G1_TX_DN<9>")
	)
	(arc
		(start 101.658674 -223.119696)
		(mid 101.815651 -223.424496)
		(end 101.658674 -223.729296)
		(width 0.1143)
		(layer "In11.Cu")
		(net "P5E_CPU1_G1_TX_DN<9>")
	)
	(arc
		(start 102.598728 -239.319562)
		(mid 102.755705 -239.624362)
		(end 102.598728 -239.929162)
		(width 0.1143)
		(layer "In11.Cu")
		(net "P5E_CPU1_G1_TX_DN<9>")
	)
	(arc
		(start 102.529132 -243.209826)
		(mid 102.285805 -243.674392)
		(end 102.529132 -244.138958)
		(width 0.1143)
		(layer "In11.Cu")
		(net "P5E_CPU1_G1_TX_DN<9>")
	)
	(arc
		(start 102.129844 -225.550222)
		(mid 102.24452 -225.683556)
		(end 102.2858 -225.854514)
		(width 0.1143)
		(layer "In11.Cu")
		(net "P5E_CPU1_G1_TX_DN<9>")
	)
	(arc
		(start 102.529132 -235.109766)
		(mid 102.285805 -235.574332)
		(end 102.529132 -236.038898)
		(width 0.1143)
		(layer "In11.Cu")
		(net "P5E_CPU1_G1_TX_DN<9>")
	)
	(arc
		(start 102.598728 -234.459526)
		(mid 102.755705 -234.764326)
		(end 102.598728 -235.069126)
		(width 0.1143)
		(layer "In11.Cu")
		(net "P5E_CPU1_G1_TX_DN<9>")
	)
	(arc
		(start 102.598728 -240.939574)
		(mid 102.755705 -241.244374)
		(end 102.598728 -241.549174)
		(width 0.1143)
		(layer "In11.Cu")
		(net "P5E_CPU1_G1_TX_DN<9>")
	)
	(arc
		(start 102.529132 -236.729778)
		(mid 102.285805 -237.194344)
		(end 102.529132 -237.65891)
		(width 0.1143)
		(layer "In11.Cu")
		(net "P5E_CPU1_G1_TX_DN<9>")
	)
	(arc
		(start 102.2858 -225.854514)
		(mid 102.350315 -226.116733)
		(end 102.529132 -226.31908)
		(width 0.1143)
		(layer "In11.Cu")
		(net "P5E_CPU1_G1_TX_DN<9>")
	)
	(arc
		(start 102.7557 -229.90429)
		(mid 102.714151 -230.075712)
		(end 102.598728 -230.20909)
		(width 0.1143)
		(layer "In11.Cu")
		(net "P5E_CPU1_G1_TX_DN<9>")
	)
	(arc
		(start 102.598728 -236.079538)
		(mid 102.755705 -236.384338)
		(end 102.598728 -236.689138)
		(width 0.1143)
		(layer "In11.Cu")
		(net "P5E_CPU1_G1_TX_DN<9>")
	)
	(arc
		(start 101.815646 -225.044508)
		(mid 101.880161 -225.306727)
		(end 102.058978 -225.509074)
		(width 0.1143)
		(layer "In11.Cu")
		(net "P5E_CPU1_G1_TX_DN<9>")
	)
	(arc
		(start 102.529132 -228.629972)
		(mid 102.285805 -229.094538)
		(end 102.529132 -229.559104)
		(width 0.1143)
		(layer "In11.Cu")
		(net "P5E_CPU1_G1_TX_DN<9>")
	)
	(arc
		(start 102.529132 -233.489754)
		(mid 102.285805 -233.95432)
		(end 102.529132 -234.418886)
		(width 0.1143)
		(layer "In11.Cu")
		(net "P5E_CPU1_G1_TX_DN<9>")
	)
	(arc
		(start 102.598728 -237.69955)
		(mid 102.755705 -238.00435)
		(end 102.598728 -238.30915)
		(width 0.1143)
		(layer "In11.Cu")
		(net "P5E_CPU1_G1_TX_DN<9>")
	)
	(arc
		(start 101.345746 -222.61449)
		(mid 101.410261 -222.876709)
		(end 101.589078 -223.079056)
		(width 0.1143)
		(layer "In11.Cu")
		(net "P5E_CPU1_G1_TX_DN<9>")
	)
	(arc
		(start 102.598728 -244.179598)
		(mid 102.714155 -244.312974)
		(end 102.7557 -244.484398)
		(width 0.1143)
		(layer "In11.Cu")
		(net "P5E_CPU1_G1_TX_DN<9>")
	)
	(arc
		(start 102.529132 -239.969802)
		(mid 102.285805 -240.434368)
		(end 102.529132 -240.898934)
		(width 0.1143)
		(layer "In11.Cu")
		(net "P5E_CPU1_G1_TX_DN<9>")
	)
	(arc
		(start 102.529132 -227.00996)
		(mid 102.285805 -227.474526)
		(end 102.529132 -227.939092)
		(width 0.1143)
		(layer "In11.Cu")
		(net "P5E_CPU1_G1_TX_DN<9>")
	)
	(arc
		(start 101.658674 -224.739708)
		(mid 101.774101 -224.873084)
		(end 101.815646 -225.044508)
		(width 0.1143)
		(layer "In11.Cu")
		(net "P5E_CPU1_G1_TX_DN<9>")
	)
	(segment
		(start 103.787956 -244.750336)
		(end 103.321104 -244.484398)
		(width 0.12954)
		(layer "F.Cu")
		(net "P5E_CPU1_G1_TX_DN<8>")
	)
	(segment
		(start 35.362388 -18.86585)
		(end 35.091878 -19.13636)
		(width 0.12954)
		(layer "F.Cu")
		(net "P5E_CPU1_G1_TX_DN<8>")
	)
	(segment
		(start 35.362388 -18.186146)
		(end 35.362388 -18.86585)
		(width 0.12954)
		(layer "F.Cu")
		(net "P5E_CPU1_G1_TX_DN<8>")
	)
	(segment
		(start 35.066478 -17.890236)
		(end 35.362388 -18.186146)
		(width 0.12954)
		(layer "F.Cu")
		(net "P5E_CPU1_G1_TX_DN<8>")
	)
	(segment
		(start 48.265588 -47.789338)
		(end 54.173628 -55.56758)
		(width 0.14224)
		(layer "In11.Cu")
		(net "P5E_CPU1_G1_TX_DN<8>")
	)
	(segment
		(start 103.529892 -238.31423)
		(end 103.52913 -238.314738)
		(width 0.1143)
		(layer "In11.Cu")
		(net "P5E_CPU1_G1_TX_DN<8>")
	)
	(segment
		(start 103.515414 -242.546124)
		(end 103.539798 -242.560094)
		(width 0.1143)
		(layer "In11.Cu")
		(net "P5E_CPU1_G1_TX_DN<8>")
	)
	(segment
		(start 54.194964 -55.585614)
		(end 54.195726 -55.586376)
		(width 0.14224)
		(layer "In11.Cu")
		(net "P5E_CPU1_G1_TX_DN<8>")
	)
	(segment
		(start 103.510588 -242.54333)
		(end 103.511604 -242.543838)
		(width 0.1143)
		(layer "In11.Cu")
		(net "P5E_CPU1_G1_TX_DN<8>")
	)
	(segment
		(start 103.471726 -244.140736)
		(end 103.508048 -244.161818)
		(width 0.1143)
		(layer "In11.Cu")
		(net "P5E_CPU1_G1_TX_DN<8>")
	)
	(segment
		(start 103.539798 -241.548666)
		(end 103.529892 -241.554254)
		(width 0.1143)
		(layer "In11.Cu")
		(net "P5E_CPU1_G1_TX_DN<8>")
	)
	(segment
		(start 54.194456 -55.58536)
		(end 54.194964 -55.585614)
		(width 0.14224)
		(layer "In11.Cu")
		(net "P5E_CPU1_G1_TX_DN<8>")
	)
	(segment
		(start 103.508048 -230.22687)
		(end 103.507032 -230.227378)
		(width 0.1143)
		(layer "In11.Cu")
		(net "P5E_CPU1_G1_TX_DN<8>")
	)
	(segment
		(start 102.091998 -222.288354)
		(end 102.093014 -222.288862)
		(width 0.1143)
		(layer "In11.Cu")
		(net "P5E_CPU1_G1_TX_DN<8>")
	)
	(segment
		(start 103.688896 -244.414548)
		(end 103.619046 -244.484398)
		(width 0.1143)
		(layer "In11.Cu")
		(net "P5E_CPU1_G1_TX_DN<8>")
	)
	(segment
		(start 103.512366 -239.304322)
		(end 103.513382 -239.30483)
		(width 0.1143)
		(layer "In11.Cu")
		(net "P5E_CPU1_G1_TX_DN<8>")
	)
	(segment
		(start 103.510588 -240.923318)
		(end 103.511604 -240.923826)
		(width 0.1143)
		(layer "In11.Cu")
		(net "P5E_CPU1_G1_TX_DN<8>")
	)
	(segment
		(start 103.512366 -240.924334)
		(end 103.513382 -240.924842)
		(width 0.1143)
		(layer "In11.Cu")
		(net "P5E_CPU1_G1_TX_DN<8>")
	)
	(segment
		(start 54.190138 -55.58155)
		(end 54.194456 -55.58536)
		(width 0.14224)
		(layer "In11.Cu")
		(net "P5E_CPU1_G1_TX_DN<8>")
	)
	(segment
		(start 102.095554 -222.290386)
		(end 102.097078 -222.291402)
		(width 0.1143)
		(layer "In11.Cu")
		(net "P5E_CPU1_G1_TX_DN<8>")
	)
	(segment
		(start 103.513382 -237.684818)
		(end 103.514144 -237.685326)
		(width 0.1143)
		(layer "In11.Cu")
		(net "P5E_CPU1_G1_TX_DN<8>")
	)
	(segment
		(start 103.512366 -236.064298)
		(end 103.514398 -236.065568)
		(width 0.1143)
		(layer "In11.Cu")
		(net "P5E_CPU1_G1_TX_DN<8>")
	)
	(segment
		(start 103.511604 -240.923826)
		(end 103.512366 -240.924334)
		(width 0.1143)
		(layer "In11.Cu")
		(net "P5E_CPU1_G1_TX_DN<8>")
	)
	(segment
		(start 103.50881 -236.062266)
		(end 103.509826 -236.062774)
		(width 0.1143)
		(layer "In11.Cu")
		(net "P5E_CPU1_G1_TX_DN<8>")
	)
	(segment
		(start 102.999032 -225.509074)
		(end 103.037132 -225.531426)
		(width 0.1143)
		(layer "In11.Cu")
		(net "P5E_CPU1_G1_TX_DN<8>")
	)
	(segment
		(start 103.514652 -228.603302)
		(end 103.51389 -228.60381)
		(width 0.1143)
		(layer "In11.Cu")
		(net "P5E_CPU1_G1_TX_DN<8>")
	)
	(segment
		(start 103.505508 -230.228394)
		(end 103.504492 -230.228902)
		(width 0.1143)
		(layer "In11.Cu")
		(net "P5E_CPU1_G1_TX_DN<8>")
	)
	(segment
		(start 103.529892 -236.694218)
		(end 103.52913 -236.694726)
		(width 0.1143)
		(layer "In11.Cu")
		(net "P5E_CPU1_G1_TX_DN<8>")
	)
	(segment
		(start 103.511604 -228.60508)
		(end 103.50881 -228.606604)
		(width 0.1143)
		(layer "In11.Cu")
		(net "P5E_CPU1_G1_TX_DN<8>")
	)
	(segment
		(start 103.471726 -234.420664)
		(end 103.508048 -234.441746)
		(width 0.1143)
		(layer "In11.Cu")
		(net "P5E_CPU1_G1_TX_DN<8>")
	)
	(segment
		(start 103.539798 -239.928654)
		(end 103.529892 -239.934242)
		(width 0.1143)
		(layer "In11.Cu")
		(net "P5E_CPU1_G1_TX_DN<8>")
	)
	(segment
		(start 103.47325 -226.321874)
		(end 103.508048 -226.34194)
		(width 0.1143)
		(layer "In11.Cu")
		(net "P5E_CPU1_G1_TX_DN<8>")
	)
	(segment
		(start 149.80539 -168.364154)
		(end 149.664674 -168.81856)
		(width 0.14224)
		(layer "In11.Cu")
		(net "P5E_CPU1_G1_TX_DN<8>")
	)
	(segment
		(start 103.508048 -235.086906)
		(end 103.507794 -235.08716)
		(width 0.1143)
		(layer "In11.Cu")
		(net "P5E_CPU1_G1_TX_DN<8>")
	)
	(segment
		(start 103.512366 -237.68431)
		(end 103.513382 -237.684818)
		(width 0.1143)
		(layer "In11.Cu")
		(net "P5E_CPU1_G1_TX_DN<8>")
	)
	(segment
		(start 103.508048 -227.961952)
		(end 103.539798 -227.98024)
		(width 0.1143)
		(layer "In11.Cu")
		(net "P5E_CPU1_G1_TX_DN<8>")
	)
	(segment
		(start 103.515414 -239.3061)
		(end 103.539798 -239.32007)
		(width 0.1143)
		(layer "In11.Cu")
		(net "P5E_CPU1_G1_TX_DN<8>")
	)
	(segment
		(start 103.497888 -231.195626)
		(end 103.538782 -231.219502)
		(width 0.1143)
		(layer "In11.Cu")
		(net "P5E_CPU1_G1_TX_DN<8>")
	)
	(segment
		(start 103.508048 -238.32693)
		(end 103.507794 -238.327184)
		(width 0.1143)
		(layer "In11.Cu")
		(net "P5E_CPU1_G1_TX_DN<8>")
	)
	(segment
		(start 103.508048 -239.301782)
		(end 103.50881 -239.30229)
		(width 0.1143)
		(layer "In11.Cu")
		(net "P5E_CPU1_G1_TX_DN<8>")
	)
	(segment
		(start 108.32592 -204.615288)
		(end 101.77018 -215.657684)
		(width 0.14224)
		(layer "In11.Cu")
		(net "P5E_CPU1_G1_TX_DN<8>")
	)
	(segment
		(start 102.568248 -223.101916)
		(end 102.598728 -223.119696)
		(width 0.1143)
		(layer "In11.Cu")
		(net "P5E_CPU1_G1_TX_DN<8>")
	)
	(segment
		(start 103.509826 -236.062774)
		(end 103.510588 -236.063282)
		(width 0.1143)
		(layer "In11.Cu")
		(net "P5E_CPU1_G1_TX_DN<8>")
	)
	(segment
		(start 103.037132 -225.531426)
		(end 103.038148 -225.531934)
		(width 0.1143)
		(layer "In11.Cu")
		(net "P5E_CPU1_G1_TX_DN<8>")
	)
	(segment
		(start 103.504492 -230.228902)
		(end 103.476044 -230.245412)
		(width 0.1143)
		(layer "In11.Cu")
		(net "P5E_CPU1_G1_TX_DN<8>")
	)
	(segment
		(start 102.089712 -222.287084)
		(end 102.091998 -222.288354)
		(width 0.1143)
		(layer "In11.Cu")
		(net "P5E_CPU1_G1_TX_DN<8>")
	)
	(segment
		(start 103.508048 -226.9871)
		(end 103.471726 -227.008182)
		(width 0.1143)
		(layer "In11.Cu")
		(net "P5E_CPU1_G1_TX_DN<8>")
	)
	(segment
		(start 103.510588 -236.063282)
		(end 103.511604 -236.06379)
		(width 0.1143)
		(layer "In11.Cu")
		(net "P5E_CPU1_G1_TX_DN<8>")
	)
	(segment
		(start 103.619046 -244.484398)
		(end 103.321104 -244.484398)
		(width 0.1143)
		(layer "In11.Cu")
		(net "P5E_CPU1_G1_TX_DN<8>")
	)
	(segment
		(start 35.382708 -19.42719)
		(end 35.382708 -20.255484)
		(width 0.14224)
		(layer "In11.Cu")
		(net "P5E_CPU1_G1_TX_DN<8>")
	)
	(segment
		(start 103.509826 -237.682786)
		(end 103.510588 -237.683294)
		(width 0.1143)
		(layer "In11.Cu")
		(net "P5E_CPU1_G1_TX_DN<8>")
	)
	(segment
		(start 103.511604 -237.683802)
		(end 103.512366 -237.68431)
		(width 0.1143)
		(layer "In11.Cu")
		(net "P5E_CPU1_G1_TX_DN<8>")
	)
	(segment
		(start 103.515414 -240.926112)
		(end 103.539798 -240.940082)
		(width 0.1143)
		(layer "In11.Cu")
		(net "P5E_CPU1_G1_TX_DN<8>")
	)
	(segment
		(start 54.197504 -55.5879)
		(end 146.822414 -138.880596)
		(width 0.14224)
		(layer "In11.Cu")
		(net "P5E_CPU1_G1_TX_DN<8>")
	)
	(segment
		(start 103.471726 -232.800652)
		(end 103.508048 -232.821734)
		(width 0.1143)
		(layer "In11.Cu")
		(net "P5E_CPU1_G1_TX_DN<8>")
	)
	(segment
		(start 103.50881 -237.682278)
		(end 103.509826 -237.682786)
		(width 0.1143)
		(layer "In11.Cu")
		(net "P5E_CPU1_G1_TX_DN<8>")
	)
	(segment
		(start 102.094538 -222.289878)
		(end 102.095554 -222.290386)
		(width 0.1143)
		(layer "In11.Cu")
		(net "P5E_CPU1_G1_TX_DN<8>")
	)
	(segment
		(start 103.52913 -235.074714)
		(end 103.508048 -235.086906)
		(width 0.1143)
		(layer "In11.Cu")
		(net "P5E_CPU1_G1_TX_DN<8>")
	)
	(segment
		(start 103.511604 -239.303814)
		(end 103.512366 -239.304322)
		(width 0.1143)
		(layer "In11.Cu")
		(net "P5E_CPU1_G1_TX_DN<8>")
	)
	(segment
		(start 54.196742 -55.587138)
		(end 54.197504 -55.5879)
		(width 0.14224)
		(layer "In11.Cu")
		(net "P5E_CPU1_G1_TX_DN<8>")
	)
	(segment
		(start 103.539798 -236.68863)
		(end 103.529892 -236.694218)
		(width 0.1143)
		(layer "In11.Cu")
		(net "P5E_CPU1_G1_TX_DN<8>")
	)
	(segment
		(start 103.52913 -239.93475)
		(end 103.508048 -239.946942)
		(width 0.1143)
		(layer "In11.Cu")
		(net "P5E_CPU1_G1_TX_DN<8>")
	)
	(segment
		(start 103.539798 -230.208582)
		(end 103.508048 -230.22687)
		(width 0.1143)
		(layer "In11.Cu")
		(net "P5E_CPU1_G1_TX_DN<8>")
	)
	(segment
		(start 103.47452 -229.562406)
		(end 103.508048 -229.581964)
		(width 0.1143)
		(layer "In11.Cu")
		(net "P5E_CPU1_G1_TX_DN<8>")
	)
	(segment
		(start 103.225854 -225.870516)
		(end 103.225854 -225.87077)
		(width 0.1143)
		(layer "In11.Cu")
		(net "P5E_CPU1_G1_TX_DN<8>")
	)
	(segment
		(start 103.517446 -228.601778)
		(end 103.515922 -228.60254)
		(width 0.1143)
		(layer "In11.Cu")
		(net "P5E_CPU1_G1_TX_DN<8>")
	)
	(segment
		(start 103.471726 -229.560882)
		(end 103.47452 -229.562406)
		(width 0.1143)
		(layer "In11.Cu")
		(net "P5E_CPU1_G1_TX_DN<8>")
	)
	(segment
		(start 54.195726 -55.586376)
		(end 54.196742 -55.587138)
		(width 0.14224)
		(layer "In11.Cu")
		(net "P5E_CPU1_G1_TX_DN<8>")
	)
	(segment
		(start 103.52913 -238.314738)
		(end 103.508048 -238.32693)
		(width 0.1143)
		(layer "In11.Cu")
		(net "P5E_CPU1_G1_TX_DN<8>")
	)
	(segment
		(start 103.50881 -240.922302)
		(end 103.509826 -240.92281)
		(width 0.1143)
		(layer "In11.Cu")
		(net "P5E_CPU1_G1_TX_DN<8>")
	)
	(segment
		(start 103.510588 -237.683294)
		(end 103.511604 -237.683802)
		(width 0.1143)
		(layer "In11.Cu")
		(net "P5E_CPU1_G1_TX_DN<8>")
	)
	(segment
		(start 103.50881 -239.30229)
		(end 103.509826 -239.302798)
		(width 0.1143)
		(layer "In11.Cu")
		(net "P5E_CPU1_G1_TX_DN<8>")
	)
	(segment
		(start 103.471726 -227.94087)
		(end 103.508048 -227.961952)
		(width 0.1143)
		(layer "In11.Cu")
		(net "P5E_CPU1_G1_TX_DN<8>")
	)
	(segment
		(start 150.623524 -146.740372)
		(end 151.448008 -159.915606)
		(width 0.14224)
		(layer "In11.Cu")
		(net "P5E_CPU1_G1_TX_DN<8>")
	)
	(segment
		(start 102.529132 -223.079056)
		(end 102.568248 -223.101916)
		(width 0.1143)
		(layer "In11.Cu")
		(net "P5E_CPU1_G1_TX_DN<8>")
	)
	(segment
		(start 102.058978 -222.26905)
		(end 102.089712 -222.287084)
		(width 0.1143)
		(layer "In11.Cu")
		(net "P5E_CPU1_G1_TX_DN<8>")
	)
	(segment
		(start 103.510588 -239.303306)
		(end 103.511604 -239.303814)
		(width 0.1143)
		(layer "In11.Cu")
		(net "P5E_CPU1_G1_TX_DN<8>")
	)
	(segment
		(start 103.50881 -228.606604)
		(end 103.508048 -228.607112)
		(width 0.1143)
		(layer "In11.Cu")
		(net "P5E_CPU1_G1_TX_DN<8>")
	)
	(segment
		(start 103.038148 -225.531934)
		(end 103.04145 -225.533712)
		(width 0.1143)
		(layer "In11.Cu")
		(net "P5E_CPU1_G1_TX_DN<8>")
	)
	(segment
		(start 103.513382 -242.544854)
		(end 103.514144 -242.545362)
		(width 0.1143)
		(layer "In11.Cu")
		(net "P5E_CPU1_G1_TX_DN<8>")
	)
	(segment
		(start 103.540814 -229.601014)
		(end 103.541576 -229.601522)
		(width 0.1143)
		(layer "In11.Cu")
		(net "P5E_CPU1_G1_TX_DN<8>")
	)
	(segment
		(start 101.77018 -215.657684)
		(end 101.77018 -221.05493)
		(width 0.14224)
		(layer "In11.Cu")
		(net "P5E_CPU1_G1_TX_DN<8>")
	)
	(segment
		(start 151.448008 -159.915606)
		(end 151.448008 -163.501324)
		(width 0.14224)
		(layer "In11.Cu")
		(net "P5E_CPU1_G1_TX_DN<8>")
	)
	(segment
		(start 102.098094 -222.29191)
		(end 102.129844 -222.310198)
		(width 0.1143)
		(layer "In11.Cu")
		(net "P5E_CPU1_G1_TX_DN<8>")
	)
	(segment
		(start 103.515414 -237.686088)
		(end 103.539798 -237.700058)
		(width 0.1143)
		(layer "In11.Cu")
		(net "P5E_CPU1_G1_TX_DN<8>")
	)
	(segment
		(start 103.539798 -233.448606)
		(end 103.508048 -233.466894)
		(width 0.1143)
		(layer "In11.Cu")
		(net "P5E_CPU1_G1_TX_DN<8>")
	)
	(segment
		(start 103.06431 -225.547174)
		(end 103.065326 -225.547682)
		(width 0.1143)
		(layer "In11.Cu")
		(net "P5E_CPU1_G1_TX_DN<8>")
	)
	(segment
		(start 103.508048 -232.821734)
		(end 103.539798 -232.840022)
		(width 0.1143)
		(layer "In11.Cu")
		(net "P5E_CPU1_G1_TX_DN<8>")
	)
	(segment
		(start 103.511604 -236.06379)
		(end 103.512366 -236.064298)
		(width 0.1143)
		(layer "In11.Cu")
		(net "P5E_CPU1_G1_TX_DN<8>")
	)
	(segment
		(start 103.507794 -239.301782)
		(end 103.508048 -239.301782)
		(width 0.1143)
		(layer "In11.Cu")
		(net "P5E_CPU1_G1_TX_DN<8>")
	)
	(segment
		(start 103.471726 -226.320858)
		(end 103.47325 -226.321874)
		(width 0.1143)
		(layer "In11.Cu")
		(net "P5E_CPU1_G1_TX_DN<8>")
	)
	(segment
		(start 103.529892 -241.554254)
		(end 103.52913 -241.554762)
		(width 0.1143)
		(layer "In11.Cu")
		(net "P5E_CPU1_G1_TX_DN<8>")
	)
	(segment
		(start 103.508048 -244.161818)
		(end 103.539798 -244.180106)
		(width 0.1143)
		(layer "In11.Cu")
		(net "P5E_CPU1_G1_TX_DN<8>")
	)
	(segment
		(start 101.8159 -221.129098)
		(end 101.8159 -221.804484)
		(width 0.1143)
		(layer "In11.Cu")
		(net "P5E_CPU1_G1_TX_DN<8>")
	)
	(segment
		(start 54.173628 -55.56758)
		(end 54.190138 -55.58155)
		(width 0.14224)
		(layer "In11.Cu")
		(net "P5E_CPU1_G1_TX_DN<8>")
	)
	(segment
		(start 103.508048 -226.34194)
		(end 103.539798 -226.360228)
		(width 0.1143)
		(layer "In11.Cu")
		(net "P5E_CPU1_G1_TX_DN<8>")
	)
	(segment
		(start 103.508048 -231.846882)
		(end 103.471726 -231.867964)
		(width 0.1143)
		(layer "In11.Cu")
		(net "P5E_CPU1_G1_TX_DN<8>")
	)
	(segment
		(start 103.507794 -240.921794)
		(end 103.508048 -240.921794)
		(width 0.1143)
		(layer "In11.Cu")
		(net "P5E_CPU1_G1_TX_DN<8>")
	)
	(segment
		(start 103.52913 -236.694726)
		(end 103.508048 -236.706918)
		(width 0.1143)
		(layer "In11.Cu")
		(net "P5E_CPU1_G1_TX_DN<8>")
	)
	(segment
		(start 103.513382 -239.30483)
		(end 103.514144 -239.305338)
		(width 0.1143)
		(layer "In11.Cu")
		(net "P5E_CPU1_G1_TX_DN<8>")
	)
	(segment
		(start 103.507794 -236.061758)
		(end 103.508048 -236.061758)
		(width 0.1143)
		(layer "In11.Cu")
		(net "P5E_CPU1_G1_TX_DN<8>")
	)
	(segment
		(start 103.512366 -228.604572)
		(end 103.511604 -228.60508)
		(width 0.1143)
		(layer "In11.Cu")
		(net "P5E_CPU1_G1_TX_DN<8>")
	)
	(segment
		(start 103.538782 -231.219502)
		(end 103.541576 -231.221534)
		(width 0.1143)
		(layer "In11.Cu")
		(net "P5E_CPU1_G1_TX_DN<8>")
	)
	(segment
		(start 102.097078 -222.291402)
		(end 102.098094 -222.29191)
		(width 0.1143)
		(layer "In11.Cu")
		(net "P5E_CPU1_G1_TX_DN<8>")
	)
	(segment
		(start 103.539798 -243.168678)
		(end 103.508048 -243.186966)
		(width 0.1143)
		(layer "In11.Cu")
		(net "P5E_CPU1_G1_TX_DN<8>")
	)
	(segment
		(start 102.093014 -222.288862)
		(end 102.094538 -222.289878)
		(width 0.1143)
		(layer "In11.Cu")
		(net "P5E_CPU1_G1_TX_DN<8>")
	)
	(segment
		(start 103.514144 -239.305338)
		(end 103.515414 -239.3061)
		(width 0.1143)
		(layer "In11.Cu")
		(net "P5E_CPU1_G1_TX_DN<8>")
	)
	(segment
		(start 103.509826 -242.542822)
		(end 103.510588 -242.54333)
		(width 0.1143)
		(layer "In11.Cu")
		(net "P5E_CPU1_G1_TX_DN<8>")
	)
	(segment
		(start 146.312128 -173.485556)
		(end 108.32592 -204.615288)
		(width 0.14224)
		(layer "In11.Cu")
		(net "P5E_CPU1_G1_TX_DN<8>")
	)
	(segment
		(start 146.822414 -138.880596)
		(end 150.623524 -146.740372)
		(width 0.14224)
		(layer "In11.Cu")
		(net "P5E_CPU1_G1_TX_DN<8>")
	)
	(segment
		(start 103.507794 -237.68177)
		(end 103.508048 -237.68177)
		(width 0.1143)
		(layer "In11.Cu")
		(net "P5E_CPU1_G1_TX_DN<8>")
	)
	(segment
		(start 103.514144 -242.545362)
		(end 103.515414 -242.546124)
		(width 0.1143)
		(layer "In11.Cu")
		(net "P5E_CPU1_G1_TX_DN<8>")
	)
	(segment
		(start 103.508048 -229.581964)
		(end 103.540814 -229.601014)
		(width 0.1143)
		(layer "In11.Cu")
		(net "P5E_CPU1_G1_TX_DN<8>")
	)
	(segment
		(start 103.507032 -230.227378)
		(end 103.505508 -230.228394)
		(width 0.1143)
		(layer "In11.Cu")
		(net "P5E_CPU1_G1_TX_DN<8>")
	)
	(segment
		(start 102.529132 -224.699068)
		(end 102.568248 -224.721928)
		(width 0.1143)
		(layer "In11.Cu")
		(net "P5E_CPU1_G1_TX_DN<8>")
	)
	(segment
		(start 103.508048 -241.566954)
		(end 103.507794 -241.567208)
		(width 0.1143)
		(layer "In11.Cu")
		(net "P5E_CPU1_G1_TX_DN<8>")
	)
	(segment
		(start 103.508048 -236.061758)
		(end 103.50881 -236.062266)
		(width 0.1143)
		(layer "In11.Cu")
		(net "P5E_CPU1_G1_TX_DN<8>")
	)
	(segment
		(start 35.382708 -20.255484)
		(end 48.265588 -47.789338)
		(width 0.14224)
		(layer "In11.Cu")
		(net "P5E_CPU1_G1_TX_DN<8>")
	)
	(segment
		(start 102.568248 -223.747076)
		(end 102.529132 -223.769936)
		(width 0.1143)
		(layer "In11.Cu")
		(net "P5E_CPU1_G1_TX_DN<8>")
	)
	(segment
		(start 103.539798 -235.068618)
		(end 103.529892 -235.074206)
		(width 0.1143)
		(layer "In11.Cu")
		(net "P5E_CPU1_G1_TX_DN<8>")
	)
	(segment
		(start 103.539798 -231.828594)
		(end 103.508048 -231.846882)
		(width 0.1143)
		(layer "In11.Cu")
		(net "P5E_CPU1_G1_TX_DN<8>")
	)
	(segment
		(start 103.476044 -230.245412)
		(end 103.47452 -230.246428)
		(width 0.1143)
		(layer "In11.Cu")
		(net "P5E_CPU1_G1_TX_DN<8>")
	)
	(segment
		(start 103.062024 -225.54565)
		(end 103.06431 -225.547174)
		(width 0.1143)
		(layer "In11.Cu")
		(net "P5E_CPU1_G1_TX_DN<8>")
	)
	(segment
		(start 101.77018 -221.083378)
		(end 101.8159 -221.129098)
		(width 0.1143)
		(layer "In11.Cu")
		(net "P5E_CPU1_G1_TX_DN<8>")
	)
	(segment
		(start 35.091878 -19.13636)
		(end 35.382708 -19.42719)
		(width 0.14224)
		(layer "In11.Cu")
		(net "P5E_CPU1_G1_TX_DN<8>")
	)
	(segment
		(start 103.508048 -233.466894)
		(end 103.471726 -233.487976)
		(width 0.1143)
		(layer "In11.Cu")
		(net "P5E_CPU1_G1_TX_DN<8>")
	)
	(segment
		(start 103.508048 -243.186966)
		(end 103.471726 -243.208048)
		(width 0.1143)
		(layer "In11.Cu")
		(net "P5E_CPU1_G1_TX_DN<8>")
	)
	(segment
		(start 103.539798 -226.968812)
		(end 103.508048 -226.9871)
		(width 0.1143)
		(layer "In11.Cu")
		(net "P5E_CPU1_G1_TX_DN<8>")
	)
	(segment
		(start 102.568248 -224.721928)
		(end 102.598728 -224.739708)
		(width 0.1143)
		(layer "In11.Cu")
		(net "P5E_CPU1_G1_TX_DN<8>")
	)
	(segment
		(start 103.507794 -242.541806)
		(end 103.508048 -242.541806)
		(width 0.1143)
		(layer "In11.Cu")
		(net "P5E_CPU1_G1_TX_DN<8>")
	)
	(segment
		(start 103.508048 -242.541806)
		(end 103.50881 -242.542314)
		(width 0.1143)
		(layer "In11.Cu")
		(net "P5E_CPU1_G1_TX_DN<8>")
	)
	(segment
		(start 103.539798 -228.588824)
		(end 103.518208 -228.60127)
		(width 0.1143)
		(layer "In11.Cu")
		(net "P5E_CPU1_G1_TX_DN<8>")
	)
	(segment
		(start 103.50881 -242.542314)
		(end 103.509826 -242.542822)
		(width 0.1143)
		(layer "In11.Cu")
		(net "P5E_CPU1_G1_TX_DN<8>")
	)
	(segment
		(start 103.509826 -240.92281)
		(end 103.510588 -240.923318)
		(width 0.1143)
		(layer "In11.Cu")
		(net "P5E_CPU1_G1_TX_DN<8>")
	)
	(segment
		(start 103.511604 -242.543838)
		(end 103.512366 -242.544346)
		(width 0.1143)
		(layer "In11.Cu")
		(net "P5E_CPU1_G1_TX_DN<8>")
	)
	(segment
		(start 103.04145 -225.533712)
		(end 103.062024 -225.54565)
		(width 0.1143)
		(layer "In11.Cu")
		(net "P5E_CPU1_G1_TX_DN<8>")
	)
	(segment
		(start 103.512366 -242.544346)
		(end 103.513382 -242.544854)
		(width 0.1143)
		(layer "In11.Cu")
		(net "P5E_CPU1_G1_TX_DN<8>")
	)
	(segment
		(start 103.508048 -237.68177)
		(end 103.50881 -237.682278)
		(width 0.1143)
		(layer "In11.Cu")
		(net "P5E_CPU1_G1_TX_DN<8>")
	)
	(segment
		(start 103.51389 -228.60381)
		(end 103.512366 -228.604572)
		(width 0.1143)
		(layer "In11.Cu")
		(net "P5E_CPU1_G1_TX_DN<8>")
	)
	(segment
		(start 102.598728 -223.729296)
		(end 102.568248 -223.747076)
		(width 0.1143)
		(layer "In11.Cu")
		(net "P5E_CPU1_G1_TX_DN<8>")
	)
	(segment
		(start 103.513382 -240.924842)
		(end 103.514144 -240.92535)
		(width 0.1143)
		(layer "In11.Cu")
		(net "P5E_CPU1_G1_TX_DN<8>")
	)
	(segment
		(start 103.508048 -234.441746)
		(end 103.539798 -234.460034)
		(width 0.1143)
		(layer "In11.Cu")
		(net "P5E_CPU1_G1_TX_DN<8>")
	)
	(segment
		(start 103.514144 -240.92535)
		(end 103.515414 -240.926112)
		(width 0.1143)
		(layer "In11.Cu")
		(net "P5E_CPU1_G1_TX_DN<8>")
	)
	(segment
		(start 103.514144 -237.685326)
		(end 103.515414 -237.686088)
		(width 0.1143)
		(layer "In11.Cu")
		(net "P5E_CPU1_G1_TX_DN<8>")
	)
	(segment
		(start 103.508048 -239.946942)
		(end 103.507794 -239.947196)
		(width 0.1143)
		(layer "In11.Cu")
		(net "P5E_CPU1_G1_TX_DN<8>")
	)
	(segment
		(start 103.518208 -228.60127)
		(end 103.517446 -228.601778)
		(width 0.1143)
		(layer "In11.Cu")
		(net "P5E_CPU1_G1_TX_DN<8>")
	)
	(segment
		(start 103.509826 -239.302798)
		(end 103.510588 -239.303306)
		(width 0.1143)
		(layer "In11.Cu")
		(net "P5E_CPU1_G1_TX_DN<8>")
	)
	(segment
		(start 103.515922 -228.60254)
		(end 103.514652 -228.603302)
		(width 0.1143)
		(layer "In11.Cu")
		(net "P5E_CPU1_G1_TX_DN<8>")
	)
	(segment
		(start 103.508048 -240.921794)
		(end 103.50881 -240.922302)
		(width 0.1143)
		(layer "In11.Cu")
		(net "P5E_CPU1_G1_TX_DN<8>")
	)
	(segment
		(start 103.52913 -241.554762)
		(end 103.508048 -241.566954)
		(width 0.1143)
		(layer "In11.Cu")
		(net "P5E_CPU1_G1_TX_DN<8>")
	)
	(segment
		(start 151.448008 -163.501324)
		(end 149.80539 -168.364154)
		(width 0.14224)
		(layer "In11.Cu")
		(net "P5E_CPU1_G1_TX_DN<8>")
	)
	(segment
		(start 149.664674 -168.81856)
		(end 146.312128 -173.485556)
		(width 0.14224)
		(layer "In11.Cu")
		(net "P5E_CPU1_G1_TX_DN<8>")
	)
	(segment
		(start 103.529892 -239.934242)
		(end 103.52913 -239.93475)
		(width 0.1143)
		(layer "In11.Cu")
		(net "P5E_CPU1_G1_TX_DN<8>")
	)
	(segment
		(start 103.514398 -236.065568)
		(end 103.539798 -236.080046)
		(width 0.1143)
		(layer "In11.Cu")
		(net "P5E_CPU1_G1_TX_DN<8>")
	)
	(segment
		(start 103.539798 -238.308642)
		(end 103.529892 -238.31423)
		(width 0.1143)
		(layer "In11.Cu")
		(net "P5E_CPU1_G1_TX_DN<8>")
	)
	(segment
		(start 101.77018 -221.05493)
		(end 101.77018 -221.083378)
		(width 0.1143)
		(layer "In11.Cu")
		(net "P5E_CPU1_G1_TX_DN<8>")
	)
	(segment
		(start 103.529892 -235.074206)
		(end 103.52913 -235.074714)
		(width 0.1143)
		(layer "In11.Cu")
		(net "P5E_CPU1_G1_TX_DN<8>")
	)
	(segment
		(start 103.508048 -236.706918)
		(end 103.507794 -236.707172)
		(width 0.1143)
		(layer "In11.Cu")
		(net "P5E_CPU1_G1_TX_DN<8>")
	)
	(arc
		(start 103.45547 -227.019612)
		(mid 103.232586 -227.474526)
		(end 103.45547 -227.92944)
		(width 0.1143)
		(layer "In11.Cu")
		(net "P5E_CPU1_G1_TX_DN<8>")
	)
	(arc
		(start 103.539798 -237.700058)
		(mid 103.695726 -238.00435)
		(end 103.539798 -238.308642)
		(width 0.1143)
		(layer "In11.Cu")
		(net "P5E_CPU1_G1_TX_DN<8>")
	)
	(arc
		(start 103.225854 -225.87077)
		(mid 103.294815 -226.125301)
		(end 103.471726 -226.320858)
		(width 0.1143)
		(layer "In11.Cu")
		(net "P5E_CPU1_G1_TX_DN<8>")
	)
	(arc
		(start 103.471726 -227.008182)
		(mid 103.463548 -227.013825)
		(end 103.45547 -227.019612)
		(width 0.1143)
		(layer "In11.Cu")
		(net "P5E_CPU1_G1_TX_DN<8>")
	)
	(arc
		(start 103.695754 -229.90429)
		(mid 103.654499 -230.075261)
		(end 103.539798 -230.208582)
		(width 0.1143)
		(layer "In11.Cu")
		(net "P5E_CPU1_G1_TX_DN<8>")
	)
	(arc
		(start 102.2858 -222.61449)
		(mid 102.350315 -222.876709)
		(end 102.529132 -223.079056)
		(width 0.1143)
		(layer "In11.Cu")
		(net "P5E_CPU1_G1_TX_DN<8>")
	)
	(arc
		(start 103.507794 -235.08716)
		(mid 103.227147 -235.574522)
		(end 103.507794 -236.061758)
		(width 0.1143)
		(layer "In11.Cu")
		(net "P5E_CPU1_G1_TX_DN<8>")
	)
	(arc
		(start 103.539798 -240.940082)
		(mid 103.695726 -241.244374)
		(end 103.539798 -241.548666)
		(width 0.1143)
		(layer "In11.Cu")
		(net "P5E_CPU1_G1_TX_DN<8>")
	)
	(arc
		(start 103.539798 -227.98024)
		(mid 103.695726 -228.284532)
		(end 103.539798 -228.588824)
		(width 0.1143)
		(layer "In11.Cu")
		(net "P5E_CPU1_G1_TX_DN<8>")
	)
	(arc
		(start 103.507794 -236.707172)
		(mid 103.227147 -237.194534)
		(end 103.507794 -237.68177)
		(width 0.1143)
		(layer "In11.Cu")
		(net "P5E_CPU1_G1_TX_DN<8>")
	)
	(arc
		(start 103.539798 -239.32007)
		(mid 103.695726 -239.624362)
		(end 103.539798 -239.928654)
		(width 0.1143)
		(layer "In11.Cu")
		(net "P5E_CPU1_G1_TX_DN<8>")
	)
	(arc
		(start 103.539798 -236.080046)
		(mid 103.695726 -236.384338)
		(end 103.539798 -236.68863)
		(width 0.1143)
		(layer "In11.Cu")
		(net "P5E_CPU1_G1_TX_DN<8>")
	)
	(arc
		(start 103.471726 -243.208048)
		(mid 103.463548 -243.213691)
		(end 103.45547 -243.219478)
		(width 0.1143)
		(layer "In11.Cu")
		(net "P5E_CPU1_G1_TX_DN<8>")
	)
	(arc
		(start 103.539798 -242.560094)
		(mid 103.695726 -242.864386)
		(end 103.539798 -243.168678)
		(width 0.1143)
		(layer "In11.Cu")
		(net "P5E_CPU1_G1_TX_DN<8>")
	)
	(arc
		(start 103.07447 -225.554794)
		(mid 103.168387 -225.679878)
		(end 103.221282 -225.827082)
		(width 0.1143)
		(layer "In11.Cu")
		(net "P5E_CPU1_G1_TX_DN<8>")
	)
	(arc
		(start 103.539798 -232.840022)
		(mid 103.695726 -233.144314)
		(end 103.539798 -233.448606)
		(width 0.1143)
		(layer "In11.Cu")
		(net "P5E_CPU1_G1_TX_DN<8>")
	)
	(arc
		(start 103.508048 -228.607112)
		(mid 103.301425 -228.812891)
		(end 103.225854 -229.094538)
		(width 0.1143)
		(layer "In11.Cu")
		(net "P5E_CPU1_G1_TX_DN<8>")
	)
	(arc
		(start 103.47452 -230.246428)
		(mid 103.466087 -230.252068)
		(end 103.457756 -230.257858)
		(width 0.1143)
		(layer "In11.Cu")
		(net "P5E_CPU1_G1_TX_DN<8>")
	)
	(arc
		(start 103.225854 -229.094538)
		(mid 103.287299 -229.35075)
		(end 103.458264 -229.55123)
		(width 0.1143)
		(layer "In11.Cu")
		(net "P5E_CPU1_G1_TX_DN<8>")
	)
	(arc
		(start 103.45547 -231.879394)
		(mid 103.232586 -232.334308)
		(end 103.45547 -232.789222)
		(width 0.1143)
		(layer "In11.Cu")
		(net "P5E_CPU1_G1_TX_DN<8>")
	)
	(arc
		(start 102.529132 -223.769936)
		(mid 102.285805 -224.234502)
		(end 102.529132 -224.699068)
		(width 0.1143)
		(layer "In11.Cu")
		(net "P5E_CPU1_G1_TX_DN<8>")
	)
	(arc
		(start 103.221282 -225.827082)
		(mid 103.224467 -225.848704)
		(end 103.225854 -225.870516)
		(width 0.1143)
		(layer "In11.Cu")
		(net "P5E_CPU1_G1_TX_DN<8>")
	)
	(arc
		(start 103.45547 -244.129306)
		(mid 103.463548 -244.135092)
		(end 103.471726 -244.140736)
		(width 0.1143)
		(layer "In11.Cu")
		(net "P5E_CPU1_G1_TX_DN<8>")
	)
	(arc
		(start 103.539798 -244.180106)
		(mid 103.636933 -244.282975)
		(end 103.688896 -244.414548)
		(width 0.1143)
		(layer "In11.Cu")
		(net "P5E_CPU1_G1_TX_DN<8>")
	)
	(arc
		(start 103.45547 -227.92944)
		(mid 103.463548 -227.935226)
		(end 103.471726 -227.94087)
		(width 0.1143)
		(layer "In11.Cu")
		(net "P5E_CPU1_G1_TX_DN<8>")
	)
	(arc
		(start 102.129844 -222.310198)
		(mid 102.24452 -222.443532)
		(end 102.2858 -222.61449)
		(width 0.1143)
		(layer "In11.Cu")
		(net "P5E_CPU1_G1_TX_DN<8>")
	)
	(arc
		(start 103.507794 -238.327184)
		(mid 103.227147 -238.814546)
		(end 103.507794 -239.301782)
		(width 0.1143)
		(layer "In11.Cu")
		(net "P5E_CPU1_G1_TX_DN<8>")
	)
	(arc
		(start 103.507794 -239.947196)
		(mid 103.227147 -240.434558)
		(end 103.507794 -240.921794)
		(width 0.1143)
		(layer "In11.Cu")
		(net "P5E_CPU1_G1_TX_DN<8>")
	)
	(arc
		(start 103.539798 -226.360228)
		(mid 103.695726 -226.66452)
		(end 103.539798 -226.968812)
		(width 0.1143)
		(layer "In11.Cu")
		(net "P5E_CPU1_G1_TX_DN<8>")
	)
	(arc
		(start 103.065326 -225.547682)
		(mid 103.069926 -225.551203)
		(end 103.07447 -225.554794)
		(width 0.1143)
		(layer "In11.Cu")
		(net "P5E_CPU1_G1_TX_DN<8>")
	)
	(arc
		(start 103.457502 -234.410758)
		(mid 103.464576 -234.415765)
		(end 103.471726 -234.420664)
		(width 0.1143)
		(layer "In11.Cu")
		(net "P5E_CPU1_G1_TX_DN<8>")
	)
	(arc
		(start 103.695754 -231.524302)
		(mid 103.654499 -231.695273)
		(end 103.539798 -231.828594)
		(width 0.1143)
		(layer "In11.Cu")
		(net "P5E_CPU1_G1_TX_DN<8>")
	)
	(arc
		(start 103.541576 -231.221534)
		(mid 103.654983 -231.354423)
		(end 103.695754 -231.524302)
		(width 0.1143)
		(layer "In11.Cu")
		(net "P5E_CPU1_G1_TX_DN<8>")
	)
	(arc
		(start 103.45547 -232.789222)
		(mid 103.463548 -232.795008)
		(end 103.471726 -232.800652)
		(width 0.1143)
		(layer "In11.Cu")
		(net "P5E_CPU1_G1_TX_DN<8>")
	)
	(arc
		(start 101.8159 -221.804484)
		(mid 101.843816 -221.98046)
		(end 101.92512 -222.139002)
		(width 0.1143)
		(layer "In11.Cu")
		(net "P5E_CPU1_G1_TX_DN<8>")
	)
	(arc
		(start 103.457756 -230.257858)
		(mid 103.28958 -230.457561)
		(end 103.225854 -230.71074)
		(width 0.1143)
		(layer "In11.Cu")
		(net "P5E_CPU1_G1_TX_DN<8>")
	)
	(arc
		(start 103.458264 -229.55123)
		(mid 103.464959 -229.556106)
		(end 103.471726 -229.560882)
		(width 0.1143)
		(layer "In11.Cu")
		(net "P5E_CPU1_G1_TX_DN<8>")
	)
	(arc
		(start 103.45547 -243.219478)
		(mid 103.232586 -243.674392)
		(end 103.45547 -244.129306)
		(width 0.1143)
		(layer "In11.Cu")
		(net "P5E_CPU1_G1_TX_DN<8>")
	)
	(arc
		(start 102.598728 -224.739708)
		(mid 102.714155 -224.873084)
		(end 102.7557 -225.044508)
		(width 0.1143)
		(layer "In11.Cu")
		(net "P5E_CPU1_G1_TX_DN<8>")
	)
	(arc
		(start 102.598728 -223.119696)
		(mid 102.755705 -223.424496)
		(end 102.598728 -223.729296)
		(width 0.1143)
		(layer "In11.Cu")
		(net "P5E_CPU1_G1_TX_DN<8>")
	)
	(arc
		(start 103.225854 -230.71074)
		(mid 103.295869 -230.990203)
		(end 103.497888 -231.195626)
		(width 0.1143)
		(layer "In11.Cu")
		(net "P5E_CPU1_G1_TX_DN<8>")
	)
	(arc
		(start 103.541576 -229.601522)
		(mid 103.654983 -229.734411)
		(end 103.695754 -229.90429)
		(width 0.1143)
		(layer "In11.Cu")
		(net "P5E_CPU1_G1_TX_DN<8>")
	)
	(arc
		(start 103.507794 -241.567208)
		(mid 103.227147 -242.05457)
		(end 103.507794 -242.541806)
		(width 0.1143)
		(layer "In11.Cu")
		(net "P5E_CPU1_G1_TX_DN<8>")
	)
	(arc
		(start 103.539798 -234.460034)
		(mid 103.695726 -234.764326)
		(end 103.539798 -235.068618)
		(width 0.1143)
		(layer "In11.Cu")
		(net "P5E_CPU1_G1_TX_DN<8>")
	)
	(arc
		(start 101.92512 -222.139002)
		(mid 101.986639 -222.209596)
		(end 102.058978 -222.26905)
		(width 0.1143)
		(layer "In11.Cu")
		(net "P5E_CPU1_G1_TX_DN<8>")
	)
	(arc
		(start 103.457502 -233.497882)
		(mid 103.230119 -233.95432)
		(end 103.457502 -234.410758)
		(width 0.1143)
		(layer "In11.Cu")
		(net "P5E_CPU1_G1_TX_DN<8>")
	)
	(arc
		(start 103.471726 -233.487976)
		(mid 103.464577 -233.492876)
		(end 103.457502 -233.497882)
		(width 0.1143)
		(layer "In11.Cu")
		(net "P5E_CPU1_G1_TX_DN<8>")
	)
	(arc
		(start 103.471726 -231.867964)
		(mid 103.463548 -231.873607)
		(end 103.45547 -231.879394)
		(width 0.1143)
		(layer "In11.Cu")
		(net "P5E_CPU1_G1_TX_DN<8>")
	)
	(arc
		(start 102.7557 -225.044508)
		(mid 102.820215 -225.306727)
		(end 102.999032 -225.509074)
		(width 0.1143)
		(layer "In11.Cu")
		(net "P5E_CPU1_G1_TX_DN<8>")
	)
	(segment
		(start 38.156388 -16.662146)
		(end 38.156388 -17.341596)
		(width 0.12954)
		(layer "F.Cu")
		(net "P5E_CPU1_G1_TX_DN<7>")
	)
	(segment
		(start 103.787956 -247.99036)
		(end 103.321104 -247.724422)
		(width 0.12954)
		(layer "F.Cu")
		(net "P5E_CPU1_G1_TX_DN<7>")
	)
	(segment
		(start 37.860478 -16.366236)
		(end 38.156388 -16.662146)
		(width 0.12954)
		(layer "F.Cu")
		(net "P5E_CPU1_G1_TX_DN<7>")
	)
	(segment
		(start 38.156388 -17.341596)
		(end 37.884862 -17.613122)
		(width 0.12954)
		(layer "F.Cu")
		(net "P5E_CPU1_G1_TX_DN<7>")
	)
	(segment
		(start 104.447086 -238.327438)
		(end 104.408986 -238.34979)
		(width 0.1143)
		(layer "In11.Cu")
		(net "P5E_CPU1_G1_TX_DN<7>")
	)
	(segment
		(start 104.447086 -239.301274)
		(end 104.448102 -239.301782)
		(width 0.1143)
		(layer "In11.Cu")
		(net "P5E_CPU1_G1_TX_DN<7>")
	)
	(segment
		(start 103.505508 -223.7486)
		(end 103.468932 -223.769936)
		(width 0.1143)
		(layer "In11.Cu")
		(net "P5E_CPU1_G1_TX_DN<7>")
	)
	(segment
		(start 104.456738 -236.066584)
		(end 104.479852 -236.080046)
		(width 0.1143)
		(layer "In11.Cu")
		(net "P5E_CPU1_G1_TX_DN<7>")
	)
	(segment
		(start 104.454198 -236.065314)
		(end 104.456738 -236.066584)
		(width 0.1143)
		(layer "In11.Cu")
		(net "P5E_CPU1_G1_TX_DN<7>")
	)
	(segment
		(start 104.438958 -244.812312)
		(end 104.437688 -244.813074)
		(width 0.1143)
		(layer "In11.Cu")
		(net "P5E_CPU1_G1_TX_DN<7>")
	)
	(segment
		(start 103.537004 -224.738692)
		(end 103.538782 -224.739708)
		(width 0.1143)
		(layer "In11.Cu")
		(net "P5E_CPU1_G1_TX_DN<7>")
	)
	(segment
		(start 104.472486 -228.592888)
		(end 104.408986 -228.629972)
		(width 0.1143)
		(layer "In11.Cu")
		(net "P5E_CPU1_G1_TX_DN<7>")
	)
	(segment
		(start 104.445562 -237.680246)
		(end 104.479852 -237.700058)
		(width 0.1143)
		(layer "In11.Cu")
		(net "P5E_CPU1_G1_TX_DN<7>")
	)
	(segment
		(start 104.437688 -246.433086)
		(end 104.436926 -246.433594)
		(width 0.1143)
		(layer "In11.Cu")
		(net "P5E_CPU1_G1_TX_DN<7>")
	)
	(segment
		(start 104.439974 -236.711744)
		(end 104.438958 -236.712252)
		(width 0.1143)
		(layer "In11.Cu")
		(net "P5E_CPU1_G1_TX_DN<7>")
	)
	(segment
		(start 104.448864 -232.822242)
		(end 104.450134 -232.823004)
		(width 0.1143)
		(layer "In11.Cu")
		(net "P5E_CPU1_G1_TX_DN<7>")
	)
	(segment
		(start 104.436926 -246.433594)
		(end 104.43591 -246.434102)
		(width 0.1143)
		(layer "In11.Cu")
		(net "P5E_CPU1_G1_TX_DN<7>")
	)
	(segment
		(start 104.43591 -236.71403)
		(end 104.408986 -236.729778)
		(width 0.1143)
		(layer "In11.Cu")
		(net "P5E_CPU1_G1_TX_DN<7>")
	)
	(segment
		(start 104.445562 -236.060234)
		(end 104.447086 -236.06125)
		(width 0.1143)
		(layer "In11.Cu")
		(net "P5E_CPU1_G1_TX_DN<7>")
	)
	(segment
		(start 104.450134 -236.063028)
		(end 104.451658 -236.06379)
		(width 0.1143)
		(layer "In11.Cu")
		(net "P5E_CPU1_G1_TX_DN<7>")
	)
	(segment
		(start 104.43591 -246.434102)
		(end 104.408986 -246.44985)
		(width 0.1143)
		(layer "In11.Cu")
		(net "P5E_CPU1_G1_TX_DN<7>")
	)
	(segment
		(start 104.445562 -232.82021)
		(end 104.447086 -232.821226)
		(width 0.1143)
		(layer "In11.Cu")
		(net "P5E_CPU1_G1_TX_DN<7>")
	)
	(segment
		(start 104.408986 -237.65891)
		(end 104.445562 -237.680246)
		(width 0.1143)
		(layer "In11.Cu")
		(net "P5E_CPU1_G1_TX_DN<7>")
	)
	(segment
		(start 104.440736 -239.95126)
		(end 104.439974 -239.951768)
		(width 0.1143)
		(layer "In11.Cu")
		(net "P5E_CPU1_G1_TX_DN<7>")
	)
	(segment
		(start 104.448102 -232.821734)
		(end 104.448864 -232.822242)
		(width 0.1143)
		(layer "In11.Cu")
		(net "P5E_CPU1_G1_TX_DN<7>")
	)
	(segment
		(start 104.448864 -234.442254)
		(end 104.450134 -234.443016)
		(width 0.1143)
		(layer "In11.Cu")
		(net "P5E_CPU1_G1_TX_DN<7>")
	)
	(segment
		(start 103.978964 -225.532442)
		(end 104.009952 -225.550222)
		(width 0.1143)
		(layer "In11.Cu")
		(net "P5E_CPU1_G1_TX_DN<7>")
	)
	(segment
		(start 104.456738 -232.82656)
		(end 104.479852 -232.840022)
		(width 0.1143)
		(layer "In11.Cu")
		(net "P5E_CPU1_G1_TX_DN<7>")
	)
	(segment
		(start 104.479852 -233.448606)
		(end 104.440736 -233.471212)
		(width 0.1143)
		(layer "In11.Cu")
		(net "P5E_CPU1_G1_TX_DN<7>")
	)
	(segment
		(start 104.479852 -246.408702)
		(end 104.440736 -246.431308)
		(width 0.1143)
		(layer "In11.Cu")
		(net "P5E_CPU1_G1_TX_DN<7>")
	)
	(segment
		(start 103.619046 -247.724422)
		(end 103.321104 -247.724422)
		(width 0.1143)
		(layer "In11.Cu")
		(net "P5E_CPU1_G1_TX_DN<7>")
	)
	(segment
		(start 104.440736 -243.191284)
		(end 104.439974 -243.191792)
		(width 0.1143)
		(layer "In11.Cu")
		(net "P5E_CPU1_G1_TX_DN<7>")
	)
	(segment
		(start 104.451658 -234.443778)
		(end 104.454198 -234.445302)
		(width 0.1143)
		(layer "In11.Cu")
		(net "P5E_CPU1_G1_TX_DN<7>")
	)
	(segment
		(start 104.408986 -245.75897)
		(end 104.445562 -245.780306)
		(width 0.1143)
		(layer "In11.Cu")
		(net "P5E_CPU1_G1_TX_DN<7>")
	)
	(segment
		(start 104.454198 -232.82529)
		(end 104.456738 -232.82656)
		(width 0.1143)
		(layer "In11.Cu")
		(net "P5E_CPU1_G1_TX_DN<7>")
	)
	(segment
		(start 103.539798 -223.728788)
		(end 103.508048 -223.747076)
		(width 0.1143)
		(layer "In11.Cu")
		(net "P5E_CPU1_G1_TX_DN<7>")
	)
	(segment
		(start 103.66121 -221.407482)
		(end 103.358442 -222.138494)
		(width 0.1143)
		(layer "In11.Cu")
		(net "P5E_CPU1_G1_TX_DN<7>")
	)
	(segment
		(start 104.439974 -244.811804)
		(end 104.438958 -244.812312)
		(width 0.1143)
		(layer "In11.Cu")
		(net "P5E_CPU1_G1_TX_DN<7>")
	)
	(segment
		(start 104.479852 -243.168678)
		(end 104.440736 -243.191284)
		(width 0.1143)
		(layer "In11.Cu")
		(net "P5E_CPU1_G1_TX_DN<7>")
	)
	(segment
		(start 104.436926 -239.953546)
		(end 104.43591 -239.954054)
		(width 0.1143)
		(layer "In11.Cu")
		(net "P5E_CPU1_G1_TX_DN<7>")
	)
	(segment
		(start 104.479852 -231.828594)
		(end 104.440736 -231.8512)
		(width 0.1143)
		(layer "In11.Cu")
		(net "P5E_CPU1_G1_TX_DN<7>")
	)
	(segment
		(start 104.454198 -240.92535)
		(end 104.456738 -240.92662)
		(width 0.1143)
		(layer "In11.Cu")
		(net "P5E_CPU1_G1_TX_DN<7>")
	)
	(segment
		(start 104.479852 -238.308642)
		(end 104.447086 -238.327438)
		(width 0.1143)
		(layer "In11.Cu")
		(net "P5E_CPU1_G1_TX_DN<7>")
	)
	(segment
		(start 104.408986 -240.898934)
		(end 104.445562 -240.92027)
		(width 0.1143)
		(layer "In11.Cu")
		(net "P5E_CPU1_G1_TX_DN<7>")
	)
	(segment
		(start 104.43591 -244.81409)
		(end 104.408986 -244.829838)
		(width 0.1143)
		(layer "In11.Cu")
		(net "P5E_CPU1_G1_TX_DN<7>")
	)
	(segment
		(start 104.408986 -231.179116)
		(end 104.48163 -231.221534)
		(width 0.1143)
		(layer "In11.Cu")
		(net "P5E_CPU1_G1_TX_DN<7>")
	)
	(segment
		(start 104.440736 -244.811296)
		(end 104.439974 -244.811804)
		(width 0.1143)
		(layer "In11.Cu")
		(net "P5E_CPU1_G1_TX_DN<7>")
	)
	(segment
		(start 104.47401 -228.591872)
		(end 104.472486 -228.592888)
		(width 0.1143)
		(layer "In11.Cu")
		(net "P5E_CPU1_G1_TX_DN<7>")
	)
	(segment
		(start 104.43591 -241.574066)
		(end 104.408986 -241.589814)
		(width 0.1143)
		(layer "In11.Cu")
		(net "P5E_CPU1_G1_TX_DN<7>")
	)
	(segment
		(start 104.454198 -239.305338)
		(end 104.456738 -239.306608)
		(width 0.1143)
		(layer "In11.Cu")
		(net "P5E_CPU1_G1_TX_DN<7>")
	)
	(segment
		(start 103.975662 -225.53041)
		(end 103.978202 -225.531934)
		(width 0.1143)
		(layer "In11.Cu")
		(net "P5E_CPU1_G1_TX_DN<7>")
	)
	(segment
		(start 104.448864 -236.062266)
		(end 104.450134 -236.063028)
		(width 0.1143)
		(layer "In11.Cu")
		(net "P5E_CPU1_G1_TX_DN<7>")
	)
	(segment
		(start 104.448102 -240.921794)
		(end 104.448864 -240.922302)
		(width 0.1143)
		(layer "In11.Cu")
		(net "P5E_CPU1_G1_TX_DN<7>")
	)
	(segment
		(start 104.436926 -236.713522)
		(end 104.43591 -236.71403)
		(width 0.1143)
		(layer "In11.Cu")
		(net "P5E_CPU1_G1_TX_DN<7>")
	)
	(segment
		(start 104.445562 -244.160294)
		(end 104.447086 -244.16131)
		(width 0.1143)
		(layer "In11.Cu")
		(net "P5E_CPU1_G1_TX_DN<7>")
	)
	(segment
		(start 104.440736 -233.471212)
		(end 104.439974 -233.47172)
		(width 0.1143)
		(layer "In11.Cu")
		(net "P5E_CPU1_G1_TX_DN<7>")
	)
	(segment
		(start 104.437688 -243.193062)
		(end 104.436926 -243.19357)
		(width 0.1143)
		(layer "In11.Cu")
		(net "P5E_CPU1_G1_TX_DN<7>")
	)
	(segment
		(start 49.890934 -47.874428)
		(end 55.017924 -55.059326)
		(width 0.14224)
		(layer "In11.Cu")
		(net "P5E_CPU1_G1_TX_DN<7>")
	)
	(segment
		(start 104.438958 -233.472228)
		(end 104.437688 -233.47299)
		(width 0.1143)
		(layer "In11.Cu")
		(net "P5E_CPU1_G1_TX_DN<7>")
	)
	(segment
		(start 104.43591 -239.954054)
		(end 104.408986 -239.969802)
		(width 0.1143)
		(layer "In11.Cu")
		(net "P5E_CPU1_G1_TX_DN<7>")
	)
	(segment
		(start 152.3873 -163.722812)
		(end 150.499064 -169.26814)
		(width 0.14224)
		(layer "In11.Cu")
		(net "P5E_CPU1_G1_TX_DN<7>")
	)
	(segment
		(start 104.451658 -244.16385)
		(end 104.454198 -244.165374)
		(width 0.1143)
		(layer "In11.Cu")
		(net "P5E_CPU1_G1_TX_DN<7>")
	)
	(segment
		(start 104.447086 -232.821226)
		(end 104.448102 -232.821734)
		(width 0.1143)
		(layer "In11.Cu")
		(net "P5E_CPU1_G1_TX_DN<7>")
	)
	(segment
		(start 104.439974 -233.47172)
		(end 104.438958 -233.472228)
		(width 0.1143)
		(layer "In11.Cu")
		(net "P5E_CPU1_G1_TX_DN<7>")
	)
	(segment
		(start 103.66121 -221.129098)
		(end 103.66121 -221.407482)
		(width 0.1143)
		(layer "In11.Cu")
		(net "P5E_CPU1_G1_TX_DN<7>")
	)
	(segment
		(start 104.479852 -230.208582)
		(end 104.411526 -230.248206)
		(width 0.1143)
		(layer "In11.Cu")
		(net "P5E_CPU1_G1_TX_DN<7>")
	)
	(segment
		(start 103.468932 -224.699068)
		(end 103.535988 -224.738184)
		(width 0.1143)
		(layer "In11.Cu")
		(net "P5E_CPU1_G1_TX_DN<7>")
	)
	(segment
		(start 104.438958 -235.09224)
		(end 104.437688 -235.093002)
		(width 0.1143)
		(layer "In11.Cu")
		(net "P5E_CPU1_G1_TX_DN<7>")
	)
	(segment
		(start 103.939086 -225.509074)
		(end 103.975662 -225.53041)
		(width 0.1143)
		(layer "In11.Cu")
		(net "P5E_CPU1_G1_TX_DN<7>")
	)
	(segment
		(start 104.438958 -241.572288)
		(end 104.437688 -241.57305)
		(width 0.1143)
		(layer "In11.Cu")
		(net "P5E_CPU1_G1_TX_DN<7>")
	)
	(segment
		(start 104.450134 -232.823004)
		(end 104.451658 -232.823766)
		(width 0.1143)
		(layer "In11.Cu")
		(net "P5E_CPU1_G1_TX_DN<7>")
	)
	(segment
		(start 147.574508 -138.293094)
		(end 151.551132 -146.516344)
		(width 0.14224)
		(layer "In11.Cu")
		(net "P5E_CPU1_G1_TX_DN<7>")
	)
	(segment
		(start 104.438958 -243.1923)
		(end 104.437688 -243.193062)
		(width 0.1143)
		(layer "In11.Cu")
		(net "P5E_CPU1_G1_TX_DN<7>")
	)
	(segment
		(start 104.436926 -244.813582)
		(end 104.43591 -244.81409)
		(width 0.1143)
		(layer "In11.Cu")
		(net "P5E_CPU1_G1_TX_DN<7>")
	)
	(segment
		(start 104.408986 -244.138958)
		(end 104.445562 -244.160294)
		(width 0.1143)
		(layer "In11.Cu")
		(net "P5E_CPU1_G1_TX_DN<7>")
	)
	(segment
		(start 104.408986 -236.038898)
		(end 104.445562 -236.060234)
		(width 0.1143)
		(layer "In11.Cu")
		(net "P5E_CPU1_G1_TX_DN<7>")
	)
	(segment
		(start 104.408986 -232.798874)
		(end 104.445562 -232.82021)
		(width 0.1143)
		(layer "In11.Cu")
		(net "P5E_CPU1_G1_TX_DN<7>")
	)
	(segment
		(start 104.451658 -239.303814)
		(end 104.454198 -239.305338)
		(width 0.1143)
		(layer "In11.Cu")
		(net "P5E_CPU1_G1_TX_DN<7>")
	)
	(segment
		(start 104.456738 -244.166644)
		(end 104.479852 -244.180106)
		(width 0.1143)
		(layer "In11.Cu")
		(net "P5E_CPU1_G1_TX_DN<7>")
	)
	(segment
		(start 104.43591 -231.853994)
		(end 104.408986 -231.869742)
		(width 0.1143)
		(layer "In11.Cu")
		(net "P5E_CPU1_G1_TX_DN<7>")
	)
	(segment
		(start 104.40924 -226.31908)
		(end 104.478836 -226.35972)
		(width 0.1143)
		(layer "In11.Cu")
		(net "P5E_CPU1_G1_TX_DN<7>")
	)
	(segment
		(start 104.408986 -242.518946)
		(end 104.445562 -242.540282)
		(width 0.1143)
		(layer "In11.Cu")
		(net "P5E_CPU1_G1_TX_DN<7>")
	)
	(segment
		(start 151.551132 -146.516344)
		(end 152.3873 -159.885888)
		(width 0.14224)
		(layer "In11.Cu")
		(net "P5E_CPU1_G1_TX_DN<7>")
	)
	(segment
		(start 104.440736 -246.431308)
		(end 104.439974 -246.431816)
		(width 0.1143)
		(layer "In11.Cu")
		(net "P5E_CPU1_G1_TX_DN<7>")
	)
	(segment
		(start 104.439974 -231.851708)
		(end 104.438958 -231.852216)
		(width 0.1143)
		(layer "In11.Cu")
		(net "P5E_CPU1_G1_TX_DN<7>")
	)
	(segment
		(start 104.436926 -243.19357)
		(end 104.43591 -243.194078)
		(width 0.1143)
		(layer "In11.Cu")
		(net "P5E_CPU1_G1_TX_DN<7>")
	)
	(segment
		(start 104.440736 -236.711236)
		(end 104.439974 -236.711744)
		(width 0.1143)
		(layer "In11.Cu")
		(net "P5E_CPU1_G1_TX_DN<7>")
	)
	(segment
		(start 104.445562 -245.780306)
		(end 104.479852 -245.800118)
		(width 0.1143)
		(layer "In11.Cu")
		(net "P5E_CPU1_G1_TX_DN<7>")
	)
	(segment
		(start 104.479852 -241.548666)
		(end 104.440736 -241.571272)
		(width 0.1143)
		(layer "In11.Cu")
		(net "P5E_CPU1_G1_TX_DN<7>")
	)
	(segment
		(start 103.508048 -223.747076)
		(end 103.507032 -223.747584)
		(width 0.1143)
		(layer "In11.Cu")
		(net "P5E_CPU1_G1_TX_DN<7>")
	)
	(segment
		(start 104.437688 -231.852978)
		(end 104.436926 -231.853486)
		(width 0.1143)
		(layer "In11.Cu")
		(net "P5E_CPU1_G1_TX_DN<7>")
	)
	(segment
		(start 104.40924 -227.939092)
		(end 104.478836 -227.979732)
		(width 0.1143)
		(layer "In11.Cu")
		(net "P5E_CPU1_G1_TX_DN<7>")
	)
	(segment
		(start 104.479852 -244.78869)
		(end 104.440736 -244.811296)
		(width 0.1143)
		(layer "In11.Cu")
		(net "P5E_CPU1_G1_TX_DN<7>")
	)
	(segment
		(start 103.520494 -223.106742)
		(end 103.534718 -223.116648)
		(width 0.1143)
		(layer "In11.Cu")
		(net "P5E_CPU1_G1_TX_DN<7>")
	)
	(segment
		(start 104.447086 -244.16131)
		(end 104.448102 -244.161818)
		(width 0.1143)
		(layer "In11.Cu")
		(net "P5E_CPU1_G1_TX_DN<7>")
	)
	(segment
		(start 104.456738 -234.446572)
		(end 104.479852 -234.460034)
		(width 0.1143)
		(layer "In11.Cu")
		(net "P5E_CPU1_G1_TX_DN<7>")
	)
	(segment
		(start 104.43591 -243.194078)
		(end 104.408986 -243.209826)
		(width 0.1143)
		(layer "In11.Cu")
		(net "P5E_CPU1_G1_TX_DN<7>")
	)
	(segment
		(start 104.438958 -246.432324)
		(end 104.437688 -246.433086)
		(width 0.1143)
		(layer "In11.Cu")
		(net "P5E_CPU1_G1_TX_DN<7>")
	)
	(segment
		(start 104.436926 -241.573558)
		(end 104.43591 -241.574066)
		(width 0.1143)
		(layer "In11.Cu")
		(net "P5E_CPU1_G1_TX_DN<7>")
	)
	(segment
		(start 109.044232 -205.232254)
		(end 103.61549 -214.376254)
		(width 0.14224)
		(layer "In11.Cu")
		(net "P5E_CPU1_G1_TX_DN<7>")
	)
	(segment
		(start 103.61549 -214.376254)
		(end 103.61549 -221.05493)
		(width 0.14224)
		(layer "In11.Cu")
		(net "P5E_CPU1_G1_TX_DN<7>")
	)
	(segment
		(start 104.440736 -241.571272)
		(end 104.439974 -241.57178)
		(width 0.1143)
		(layer "In11.Cu")
		(net "P5E_CPU1_G1_TX_DN<7>")
	)
	(segment
		(start 38.175692 -17.903952)
		(end 38.175692 -20.25015)
		(width 0.14224)
		(layer "In11.Cu")
		(net "P5E_CPU1_G1_TX_DN<7>")
	)
	(segment
		(start 104.448102 -239.301782)
		(end 104.448864 -239.30229)
		(width 0.1143)
		(layer "In11.Cu")
		(net "P5E_CPU1_G1_TX_DN<7>")
	)
	(segment
		(start 104.450134 -234.443016)
		(end 104.451658 -234.443778)
		(width 0.1143)
		(layer "In11.Cu")
		(net "P5E_CPU1_G1_TX_DN<7>")
	)
	(segment
		(start 104.456738 -239.306608)
		(end 104.479852 -239.32007)
		(width 0.1143)
		(layer "In11.Cu")
		(net "P5E_CPU1_G1_TX_DN<7>")
	)
	(segment
		(start 104.445562 -240.92027)
		(end 104.447086 -240.921286)
		(width 0.1143)
		(layer "In11.Cu")
		(net "P5E_CPU1_G1_TX_DN<7>")
	)
	(segment
		(start 104.479852 -236.68863)
		(end 104.440736 -236.711236)
		(width 0.1143)
		(layer "In11.Cu")
		(net "P5E_CPU1_G1_TX_DN<7>")
	)
	(segment
		(start 104.43591 -233.474006)
		(end 104.408986 -233.489754)
		(width 0.1143)
		(layer "In11.Cu")
		(net "P5E_CPU1_G1_TX_DN<7>")
	)
	(segment
		(start 104.447086 -236.06125)
		(end 104.448102 -236.061758)
		(width 0.1143)
		(layer "In11.Cu")
		(net "P5E_CPU1_G1_TX_DN<7>")
	)
	(segment
		(start 104.408986 -229.559104)
		(end 104.48163 -229.601522)
		(width 0.1143)
		(layer "In11.Cu")
		(net "P5E_CPU1_G1_TX_DN<7>")
	)
	(segment
		(start 38.175692 -20.25015)
		(end 49.890934 -47.874428)
		(width 0.14224)
		(layer "In11.Cu")
		(net "P5E_CPU1_G1_TX_DN<7>")
	)
	(segment
		(start 104.456738 -240.92662)
		(end 104.479852 -240.940082)
		(width 0.1143)
		(layer "In11.Cu")
		(net "P5E_CPU1_G1_TX_DN<7>")
	)
	(segment
		(start 104.008682 -247.219216)
		(end 103.939086 -247.259856)
		(width 0.1143)
		(layer "In11.Cu")
		(net "P5E_CPU1_G1_TX_DN<7>")
	)
	(segment
		(start 104.451658 -236.06379)
		(end 104.454198 -236.065314)
		(width 0.1143)
		(layer "In11.Cu")
		(net "P5E_CPU1_G1_TX_DN<7>")
	)
	(segment
		(start 103.358442 -222.138494)
		(end 103.358442 -222.83547)
		(width 0.1143)
		(layer "In11.Cu")
		(net "P5E_CPU1_G1_TX_DN<7>")
	)
	(segment
		(start 103.507032 -223.747584)
		(end 103.505508 -223.7486)
		(width 0.1143)
		(layer "In11.Cu")
		(net "P5E_CPU1_G1_TX_DN<7>")
	)
	(segment
		(start 104.450134 -240.923064)
		(end 104.451658 -240.923826)
		(width 0.1143)
		(layer "In11.Cu")
		(net "P5E_CPU1_G1_TX_DN<7>")
	)
	(segment
		(start 104.454198 -234.445302)
		(end 104.456738 -234.446572)
		(width 0.1143)
		(layer "In11.Cu")
		(net "P5E_CPU1_G1_TX_DN<7>")
	)
	(segment
		(start 104.448864 -240.922302)
		(end 104.450134 -240.923064)
		(width 0.1143)
		(layer "In11.Cu")
		(net "P5E_CPU1_G1_TX_DN<7>")
	)
	(segment
		(start 104.439974 -241.57178)
		(end 104.438958 -241.572288)
		(width 0.1143)
		(layer "In11.Cu")
		(net "P5E_CPU1_G1_TX_DN<7>")
	)
	(segment
		(start 104.43591 -235.094018)
		(end 104.408986 -235.109766)
		(width 0.1143)
		(layer "In11.Cu")
		(net "P5E_CPU1_G1_TX_DN<7>")
	)
	(segment
		(start 103.358442 -222.83547)
		(end 103.435658 -223.021906)
		(width 0.1143)
		(layer "In11.Cu")
		(net "P5E_CPU1_G1_TX_DN<7>")
	)
	(segment
		(start 147.020534 -174.110904)
		(end 109.044232 -205.232254)
		(width 0.14224)
		(layer "In11.Cu")
		(net "P5E_CPU1_G1_TX_DN<7>")
	)
	(segment
		(start 104.437688 -244.813074)
		(end 104.436926 -244.813582)
		(width 0.1143)
		(layer "In11.Cu")
		(net "P5E_CPU1_G1_TX_DN<7>")
	)
	(segment
		(start 104.447086 -240.921286)
		(end 104.448102 -240.921794)
		(width 0.1143)
		(layer "In11.Cu")
		(net "P5E_CPU1_G1_TX_DN<7>")
	)
	(segment
		(start 104.439974 -239.951768)
		(end 104.438958 -239.952276)
		(width 0.1143)
		(layer "In11.Cu")
		(net "P5E_CPU1_G1_TX_DN<7>")
	)
	(segment
		(start 104.454198 -244.165374)
		(end 104.456738 -244.166644)
		(width 0.1143)
		(layer "In11.Cu")
		(net "P5E_CPU1_G1_TX_DN<7>")
	)
	(segment
		(start 152.3873 -159.885888)
		(end 152.3873 -163.722812)
		(width 0.14224)
		(layer "In11.Cu")
		(net "P5E_CPU1_G1_TX_DN<7>")
	)
	(segment
		(start 103.535988 -224.738184)
		(end 103.537004 -224.738692)
		(width 0.1143)
		(layer "In11.Cu")
		(net "P5E_CPU1_G1_TX_DN<7>")
	)
	(segment
		(start 37.884862 -17.613122)
		(end 38.175692 -17.903952)
		(width 0.14224)
		(layer "In11.Cu")
		(net "P5E_CPU1_G1_TX_DN<7>")
	)
	(segment
		(start 150.499064 -169.26814)
		(end 147.020534 -174.110904)
		(width 0.14224)
		(layer "In11.Cu")
		(net "P5E_CPU1_G1_TX_DN<7>")
	)
	(segment
		(start 103.435658 -223.021906)
		(end 103.520494 -223.106742)
		(width 0.1143)
		(layer "In11.Cu")
		(net "P5E_CPU1_G1_TX_DN<7>")
	)
	(segment
		(start 104.439974 -235.091732)
		(end 104.438958 -235.09224)
		(width 0.1143)
		(layer "In11.Cu")
		(net "P5E_CPU1_G1_TX_DN<7>")
	)
	(segment
		(start 103.978202 -225.531934)
		(end 103.978964 -225.532442)
		(width 0.1143)
		(layer "In11.Cu")
		(net "P5E_CPU1_G1_TX_DN<7>")
	)
	(segment
		(start 104.479852 -235.068618)
		(end 104.440736 -235.091224)
		(width 0.1143)
		(layer "In11.Cu")
		(net "P5E_CPU1_G1_TX_DN<7>")
	)
	(segment
		(start 104.448102 -244.161818)
		(end 104.448864 -244.162326)
		(width 0.1143)
		(layer "In11.Cu")
		(net "P5E_CPU1_G1_TX_DN<7>")
	)
	(segment
		(start 104.440736 -235.091224)
		(end 104.439974 -235.091732)
		(width 0.1143)
		(layer "In11.Cu")
		(net "P5E_CPU1_G1_TX_DN<7>")
	)
	(segment
		(start 104.445562 -234.440222)
		(end 104.447086 -234.441238)
		(width 0.1143)
		(layer "In11.Cu")
		(net "P5E_CPU1_G1_TX_DN<7>")
	)
	(segment
		(start 104.479852 -239.928654)
		(end 104.440736 -239.95126)
		(width 0.1143)
		(layer "In11.Cu")
		(net "P5E_CPU1_G1_TX_DN<7>")
	)
	(segment
		(start 104.476804 -228.590348)
		(end 104.47401 -228.591872)
		(width 0.1143)
		(layer "In11.Cu")
		(net "P5E_CPU1_G1_TX_DN<7>")
	)
	(segment
		(start 104.447086 -234.441238)
		(end 104.448102 -234.441746)
		(width 0.1143)
		(layer "In11.Cu")
		(net "P5E_CPU1_G1_TX_DN<7>")
	)
	(segment
		(start 104.448102 -234.441746)
		(end 104.448864 -234.442254)
		(width 0.1143)
		(layer "In11.Cu")
		(net "P5E_CPU1_G1_TX_DN<7>")
	)
	(segment
		(start 104.437688 -235.093002)
		(end 104.436926 -235.09351)
		(width 0.1143)
		(layer "In11.Cu")
		(net "P5E_CPU1_G1_TX_DN<7>")
	)
	(segment
		(start 104.445562 -242.540282)
		(end 104.479852 -242.560094)
		(width 0.1143)
		(layer "In11.Cu")
		(net "P5E_CPU1_G1_TX_DN<7>")
	)
	(segment
		(start 104.437688 -236.713014)
		(end 104.436926 -236.713522)
		(width 0.1143)
		(layer "In11.Cu")
		(net "P5E_CPU1_G1_TX_DN<7>")
	)
	(segment
		(start 104.437688 -239.953038)
		(end 104.436926 -239.953546)
		(width 0.1143)
		(layer "In11.Cu")
		(net "P5E_CPU1_G1_TX_DN<7>")
	)
	(segment
		(start 104.478836 -226.96932)
		(end 104.40924 -227.00996)
		(width 0.1143)
		(layer "In11.Cu")
		(net "P5E_CPU1_G1_TX_DN<7>")
	)
	(segment
		(start 103.61549 -221.05493)
		(end 103.61549 -221.083378)
		(width 0.1143)
		(layer "In11.Cu")
		(net "P5E_CPU1_G1_TX_DN<7>")
	)
	(segment
		(start 104.436926 -231.853486)
		(end 104.43591 -231.853994)
		(width 0.1143)
		(layer "In11.Cu")
		(net "P5E_CPU1_G1_TX_DN<7>")
	)
	(segment
		(start 104.450134 -244.163088)
		(end 104.451658 -244.16385)
		(width 0.1143)
		(layer "In11.Cu")
		(net "P5E_CPU1_G1_TX_DN<7>")
	)
	(segment
		(start 55.017924 -55.059326)
		(end 147.574508 -138.293094)
		(width 0.14224)
		(layer "In11.Cu")
		(net "P5E_CPU1_G1_TX_DN<7>")
	)
	(segment
		(start 104.439974 -243.191792)
		(end 104.438958 -243.1923)
		(width 0.1143)
		(layer "In11.Cu")
		(net "P5E_CPU1_G1_TX_DN<7>")
	)
	(segment
		(start 104.439974 -246.431816)
		(end 104.438958 -246.432324)
		(width 0.1143)
		(layer "In11.Cu")
		(net "P5E_CPU1_G1_TX_DN<7>")
	)
	(segment
		(start 104.450134 -239.303052)
		(end 104.451658 -239.303814)
		(width 0.1143)
		(layer "In11.Cu")
		(net "P5E_CPU1_G1_TX_DN<7>")
	)
	(segment
		(start 104.448864 -244.162326)
		(end 104.450134 -244.163088)
		(width 0.1143)
		(layer "In11.Cu")
		(net "P5E_CPU1_G1_TX_DN<7>")
	)
	(segment
		(start 104.445562 -239.300258)
		(end 104.447086 -239.301274)
		(width 0.1143)
		(layer "In11.Cu")
		(net "P5E_CPU1_G1_TX_DN<7>")
	)
	(segment
		(start 104.436926 -235.09351)
		(end 104.43591 -235.094018)
		(width 0.1143)
		(layer "In11.Cu")
		(net "P5E_CPU1_G1_TX_DN<7>")
	)
	(segment
		(start 104.436926 -233.473498)
		(end 104.43591 -233.474006)
		(width 0.1143)
		(layer "In11.Cu")
		(net "P5E_CPU1_G1_TX_DN<7>")
	)
	(segment
		(start 104.451658 -232.823766)
		(end 104.454198 -232.82529)
		(width 0.1143)
		(layer "In11.Cu")
		(net "P5E_CPU1_G1_TX_DN<7>")
	)
	(segment
		(start 104.438958 -239.952276)
		(end 104.437688 -239.953038)
		(width 0.1143)
		(layer "In11.Cu")
		(net "P5E_CPU1_G1_TX_DN<7>")
	)
	(segment
		(start 104.448864 -239.30229)
		(end 104.450134 -239.303052)
		(width 0.1143)
		(layer "In11.Cu")
		(net "P5E_CPU1_G1_TX_DN<7>")
	)
	(segment
		(start 104.438958 -236.712252)
		(end 104.437688 -236.713014)
		(width 0.1143)
		(layer "In11.Cu")
		(net "P5E_CPU1_G1_TX_DN<7>")
	)
	(segment
		(start 104.440736 -231.8512)
		(end 104.439974 -231.851708)
		(width 0.1143)
		(layer "In11.Cu")
		(net "P5E_CPU1_G1_TX_DN<7>")
	)
	(segment
		(start 104.408986 -239.278922)
		(end 104.445562 -239.300258)
		(width 0.1143)
		(layer "In11.Cu")
		(net "P5E_CPU1_G1_TX_DN<7>")
	)
	(segment
		(start 104.438958 -231.852216)
		(end 104.437688 -231.852978)
		(width 0.1143)
		(layer "In11.Cu")
		(net "P5E_CPU1_G1_TX_DN<7>")
	)
	(segment
		(start 104.478836 -228.589332)
		(end 104.476804 -228.590348)
		(width 0.1143)
		(layer "In11.Cu")
		(net "P5E_CPU1_G1_TX_DN<7>")
	)
	(segment
		(start 104.408986 -234.418886)
		(end 104.445562 -234.440222)
		(width 0.1143)
		(layer "In11.Cu")
		(net "P5E_CPU1_G1_TX_DN<7>")
	)
	(segment
		(start 104.437688 -233.47299)
		(end 104.436926 -233.473498)
		(width 0.1143)
		(layer "In11.Cu")
		(net "P5E_CPU1_G1_TX_DN<7>")
	)
	(segment
		(start 103.61549 -221.083378)
		(end 103.66121 -221.129098)
		(width 0.1143)
		(layer "In11.Cu")
		(net "P5E_CPU1_G1_TX_DN<7>")
	)
	(segment
		(start 104.448102 -236.061758)
		(end 104.448864 -236.062266)
		(width 0.1143)
		(layer "In11.Cu")
		(net "P5E_CPU1_G1_TX_DN<7>")
	)
	(segment
		(start 103.70185 -247.641618)
		(end 103.619046 -247.724422)
		(width 0.1143)
		(layer "In11.Cu")
		(net "P5E_CPU1_G1_TX_DN<7>")
	)
	(segment
		(start 104.451658 -240.923826)
		(end 104.454198 -240.92535)
		(width 0.1143)
		(layer "In11.Cu")
		(net "P5E_CPU1_G1_TX_DN<7>")
	)
	(segment
		(start 104.437688 -241.57305)
		(end 104.436926 -241.573558)
		(width 0.1143)
		(layer "In11.Cu")
		(net "P5E_CPU1_G1_TX_DN<7>")
	)
	(arc
		(start 104.408986 -231.869742)
		(mid 104.165659 -232.334308)
		(end 104.408986 -232.798874)
		(width 0.1143)
		(layer "In11.Cu")
		(net "P5E_CPU1_G1_TX_DN<7>")
	)
	(arc
		(start 104.408986 -238.34979)
		(mid 104.165659 -238.814356)
		(end 104.408986 -239.278922)
		(width 0.1143)
		(layer "In11.Cu")
		(net "P5E_CPU1_G1_TX_DN<7>")
	)
	(arc
		(start 104.48163 -231.221534)
		(mid 104.595037 -231.354423)
		(end 104.635808 -231.524302)
		(width 0.1143)
		(layer "In11.Cu")
		(net "P5E_CPU1_G1_TX_DN<7>")
	)
	(arc
		(start 103.695754 -223.424496)
		(mid 103.654499 -223.595467)
		(end 103.539798 -223.728788)
		(width 0.1143)
		(layer "In11.Cu")
		(net "P5E_CPU1_G1_TX_DN<7>")
	)
	(arc
		(start 103.534718 -223.116648)
		(mid 103.536755 -223.118166)
		(end 103.538782 -223.119696)
		(width 0.1143)
		(layer "In11.Cu")
		(net "P5E_CPU1_G1_TX_DN<7>")
	)
	(arc
		(start 104.479852 -234.460034)
		(mid 104.63578 -234.764326)
		(end 104.479852 -235.068618)
		(width 0.1143)
		(layer "In11.Cu")
		(net "P5E_CPU1_G1_TX_DN<7>")
	)
	(arc
		(start 104.478836 -226.35972)
		(mid 104.635813 -226.66452)
		(end 104.478836 -226.96932)
		(width 0.1143)
		(layer "In11.Cu")
		(net "P5E_CPU1_G1_TX_DN<7>")
	)
	(arc
		(start 104.479852 -236.080046)
		(mid 104.63578 -236.384338)
		(end 104.479852 -236.68863)
		(width 0.1143)
		(layer "In11.Cu")
		(net "P5E_CPU1_G1_TX_DN<7>")
	)
	(arc
		(start 103.695754 -225.044508)
		(mid 103.760269 -225.306727)
		(end 103.939086 -225.509074)
		(width 0.1143)
		(layer "In11.Cu")
		(net "P5E_CPU1_G1_TX_DN<7>")
	)
	(arc
		(start 103.538782 -223.119696)
		(mid 103.654209 -223.253072)
		(end 103.695754 -223.424496)
		(width 0.1143)
		(layer "In11.Cu")
		(net "P5E_CPU1_G1_TX_DN<7>")
	)
	(arc
		(start 104.165908 -225.854514)
		(mid 104.230423 -226.116733)
		(end 104.40924 -226.31908)
		(width 0.1143)
		(layer "In11.Cu")
		(net "P5E_CPU1_G1_TX_DN<7>")
	)
	(arc
		(start 103.939086 -247.259856)
		(mid 103.787099 -247.416364)
		(end 103.70566 -247.618758)
		(width 0.1143)
		(layer "In11.Cu")
		(net "P5E_CPU1_G1_TX_DN<7>")
	)
	(arc
		(start 104.408986 -241.589814)
		(mid 104.165659 -242.05438)
		(end 104.408986 -242.518946)
		(width 0.1143)
		(layer "In11.Cu")
		(net "P5E_CPU1_G1_TX_DN<7>")
	)
	(arc
		(start 103.70566 -247.618758)
		(mid 103.703637 -247.630168)
		(end 103.70185 -247.641618)
		(width 0.1143)
		(layer "In11.Cu")
		(net "P5E_CPU1_G1_TX_DN<7>")
	)
	(arc
		(start 104.411526 -230.248206)
		(mid 104.165638 -230.713)
		(end 104.408986 -231.179116)
		(width 0.1143)
		(layer "In11.Cu")
		(net "P5E_CPU1_G1_TX_DN<7>")
	)
	(arc
		(start 103.468932 -223.769936)
		(mid 103.225605 -224.234502)
		(end 103.468932 -224.699068)
		(width 0.1143)
		(layer "In11.Cu")
		(net "P5E_CPU1_G1_TX_DN<7>")
	)
	(arc
		(start 104.40924 -227.00996)
		(mid 104.165913 -227.474526)
		(end 104.40924 -227.939092)
		(width 0.1143)
		(layer "In11.Cu")
		(net "P5E_CPU1_G1_TX_DN<7>")
	)
	(arc
		(start 104.009952 -225.550222)
		(mid 104.124628 -225.683556)
		(end 104.165908 -225.854514)
		(width 0.1143)
		(layer "In11.Cu")
		(net "P5E_CPU1_G1_TX_DN<7>")
	)
	(arc
		(start 104.408986 -243.209826)
		(mid 104.165659 -243.674392)
		(end 104.408986 -244.138958)
		(width 0.1143)
		(layer "In11.Cu")
		(net "P5E_CPU1_G1_TX_DN<7>")
	)
	(arc
		(start 104.408986 -244.829838)
		(mid 104.165659 -245.294404)
		(end 104.408986 -245.75897)
		(width 0.1143)
		(layer "In11.Cu")
		(net "P5E_CPU1_G1_TX_DN<7>")
	)
	(arc
		(start 104.479852 -232.840022)
		(mid 104.63578 -233.144314)
		(end 104.479852 -233.448606)
		(width 0.1143)
		(layer "In11.Cu")
		(net "P5E_CPU1_G1_TX_DN<7>")
	)
	(arc
		(start 103.538782 -224.739708)
		(mid 103.654209 -224.873084)
		(end 103.695754 -225.044508)
		(width 0.1143)
		(layer "In11.Cu")
		(net "P5E_CPU1_G1_TX_DN<7>")
	)
	(arc
		(start 104.408986 -236.729778)
		(mid 104.165659 -237.194344)
		(end 104.408986 -237.65891)
		(width 0.1143)
		(layer "In11.Cu")
		(net "P5E_CPU1_G1_TX_DN<7>")
	)
	(arc
		(start 104.479852 -244.180106)
		(mid 104.63578 -244.484398)
		(end 104.479852 -244.78869)
		(width 0.1143)
		(layer "In11.Cu")
		(net "P5E_CPU1_G1_TX_DN<7>")
	)
	(arc
		(start 104.479852 -239.32007)
		(mid 104.63578 -239.624362)
		(end 104.479852 -239.928654)
		(width 0.1143)
		(layer "In11.Cu")
		(net "P5E_CPU1_G1_TX_DN<7>")
	)
	(arc
		(start 104.479852 -237.700058)
		(mid 104.63578 -238.00435)
		(end 104.479852 -238.308642)
		(width 0.1143)
		(layer "In11.Cu")
		(net "P5E_CPU1_G1_TX_DN<7>")
	)
	(arc
		(start 104.479852 -245.800118)
		(mid 104.63578 -246.10441)
		(end 104.479852 -246.408702)
		(width 0.1143)
		(layer "In11.Cu")
		(net "P5E_CPU1_G1_TX_DN<7>")
	)
	(arc
		(start 104.48163 -229.601522)
		(mid 104.595037 -229.734411)
		(end 104.635808 -229.90429)
		(width 0.1143)
		(layer "In11.Cu")
		(net "P5E_CPU1_G1_TX_DN<7>")
	)
	(arc
		(start 104.479852 -242.560094)
		(mid 104.63578 -242.864386)
		(end 104.479852 -243.168678)
		(width 0.1143)
		(layer "In11.Cu")
		(net "P5E_CPU1_G1_TX_DN<7>")
	)
	(arc
		(start 104.408986 -233.489754)
		(mid 104.165659 -233.95432)
		(end 104.408986 -234.418886)
		(width 0.1143)
		(layer "In11.Cu")
		(net "P5E_CPU1_G1_TX_DN<7>")
	)
	(arc
		(start 104.408986 -246.44985)
		(mid 104.230173 -246.6522)
		(end 104.165654 -246.914416)
		(width 0.1143)
		(layer "In11.Cu")
		(net "P5E_CPU1_G1_TX_DN<7>")
	)
	(arc
		(start 104.478836 -227.979732)
		(mid 104.635813 -228.284532)
		(end 104.478836 -228.589332)
		(width 0.1143)
		(layer "In11.Cu")
		(net "P5E_CPU1_G1_TX_DN<7>")
	)
	(arc
		(start 104.408986 -228.629972)
		(mid 104.165659 -229.094538)
		(end 104.408986 -229.559104)
		(width 0.1143)
		(layer "In11.Cu")
		(net "P5E_CPU1_G1_TX_DN<7>")
	)
	(arc
		(start 104.408986 -239.969802)
		(mid 104.165659 -240.434368)
		(end 104.408986 -240.898934)
		(width 0.1143)
		(layer "In11.Cu")
		(net "P5E_CPU1_G1_TX_DN<7>")
	)
	(arc
		(start 104.635808 -231.524302)
		(mid 104.594553 -231.695273)
		(end 104.479852 -231.828594)
		(width 0.1143)
		(layer "In11.Cu")
		(net "P5E_CPU1_G1_TX_DN<7>")
	)
	(arc
		(start 104.408986 -235.109766)
		(mid 104.165659 -235.574332)
		(end 104.408986 -236.038898)
		(width 0.1143)
		(layer "In11.Cu")
		(net "P5E_CPU1_G1_TX_DN<7>")
	)
	(arc
		(start 104.635808 -229.90429)
		(mid 104.594553 -230.075261)
		(end 104.479852 -230.208582)
		(width 0.1143)
		(layer "In11.Cu")
		(net "P5E_CPU1_G1_TX_DN<7>")
	)
	(arc
		(start 104.165654 -246.914416)
		(mid 104.124105 -247.085838)
		(end 104.008682 -247.219216)
		(width 0.1143)
		(layer "In11.Cu")
		(net "P5E_CPU1_G1_TX_DN<7>")
	)
	(arc
		(start 104.479852 -240.940082)
		(mid 104.63578 -241.244374)
		(end 104.479852 -241.548666)
		(width 0.1143)
		(layer "In11.Cu")
		(net "P5E_CPU1_G1_TX_DN<7>")
	)
	(segment
		(start 41.256204 -18.186146)
		(end 41.256204 -18.86585)
		(width 0.12954)
		(layer "F.Cu")
		(net "P5E_CPU1_G1_TX_DN<6>")
	)
	(segment
		(start 41.256204 -18.86585)
		(end 40.985694 -19.13636)
		(width 0.12954)
		(layer "F.Cu")
		(net "P5E_CPU1_G1_TX_DN<6>")
	)
	(segment
		(start 40.960294 -17.890236)
		(end 41.256204 -18.186146)
		(width 0.12954)
		(layer "F.Cu")
		(net "P5E_CPU1_G1_TX_DN<6>")
	)
	(segment
		(start 106.607864 -246.370348)
		(end 106.141012 -246.10441)
		(width 0.12954)
		(layer "F.Cu")
		(net "P5E_CPU1_G1_TX_DN<6>")
	)
	(segment
		(start 104.448102 -224.721928)
		(end 104.478582 -224.739708)
		(width 0.1143)
		(layer "In11.Cu")
		(net "P5E_CPU1_G1_TX_DN<6>")
	)
	(segment
		(start 105.34904 -239.278922)
		(end 105.388156 -239.301782)
		(width 0.1143)
		(layer "In11.Cu")
		(net "P5E_CPU1_G1_TX_DN<6>")
	)
	(segment
		(start 151.44242 -169.494962)
		(end 151.26081 -169.97553)
		(width 0.14224)
		(layer "In11.Cu")
		(net "P5E_CPU1_G1_TX_DN<6>")
	)
	(segment
		(start 105.418636 -236.689138)
		(end 105.388156 -236.706918)
		(width 0.1143)
		(layer "In11.Cu")
		(net "P5E_CPU1_G1_TX_DN<6>")
	)
	(segment
		(start 104.915208 -225.53041)
		(end 104.916986 -225.531426)
		(width 0.1143)
		(layer "In11.Cu")
		(net "P5E_CPU1_G1_TX_DN<6>")
	)
	(segment
		(start 104.41178 -223.767904)
		(end 104.408986 -223.769936)
		(width 0.1143)
		(layer "In11.Cu")
		(net "P5E_CPU1_G1_TX_DN<6>")
	)
	(segment
		(start 40.985694 -19.13636)
		(end 41.276524 -19.42719)
		(width 0.14224)
		(layer "In11.Cu")
		(net "P5E_CPU1_G1_TX_DN<6>")
	)
	(segment
		(start 106.058208 -245.303802)
		(end 106.058208 -245.313454)
		(width 0.1143)
		(layer "In11.Cu")
		(net "P5E_CPU1_G1_TX_DN<6>")
	)
	(segment
		(start 105.34904 -237.65891)
		(end 105.388156 -237.68177)
		(width 0.1143)
		(layer "In11.Cu")
		(net "P5E_CPU1_G1_TX_DN<6>")
	)
	(segment
		(start 104.565704 -214.603076)
		(end 104.565704 -221.05493)
		(width 0.14224)
		(layer "In11.Cu")
		(net "P5E_CPU1_G1_TX_DN<6>")
	)
	(segment
		(start 105.388156 -242.541806)
		(end 105.418636 -242.559586)
		(width 0.1143)
		(layer "In11.Cu")
		(net "P5E_CPU1_G1_TX_DN<6>")
	)
	(segment
		(start 105.418636 -235.069126)
		(end 105.388156 -235.086906)
		(width 0.1143)
		(layer "In11.Cu")
		(net "P5E_CPU1_G1_TX_DN<6>")
	)
	(segment
		(start 104.565704 -221.05493)
		(end 104.565704 -221.083378)
		(width 0.1143)
		(layer "In11.Cu")
		(net "P5E_CPU1_G1_TX_DN<6>")
	)
	(segment
		(start 105.388156 -239.946942)
		(end 105.34904 -239.969802)
		(width 0.1143)
		(layer "In11.Cu")
		(net "P5E_CPU1_G1_TX_DN<6>")
	)
	(segment
		(start 148.321522 -137.693654)
		(end 152.484582 -146.302222)
		(width 0.14224)
		(layer "In11.Cu")
		(net "P5E_CPU1_G1_TX_DN<6>")
	)
	(segment
		(start 105.418636 -226.96932)
		(end 105.388156 -226.9871)
		(width 0.1143)
		(layer "In11.Cu")
		(net "P5E_CPU1_G1_TX_DN<6>")
	)
	(segment
		(start 104.479852 -223.728788)
		(end 104.448102 -223.747076)
		(width 0.1143)
		(layer "In11.Cu")
		(net "P5E_CPU1_G1_TX_DN<6>")
	)
	(segment
		(start 104.472232 -223.115632)
		(end 104.479852 -223.120204)
		(width 0.1143)
		(layer "In11.Cu")
		(net "P5E_CPU1_G1_TX_DN<6>")
	)
	(segment
		(start 106.438954 -246.10441)
		(end 106.141012 -246.10441)
		(width 0.1143)
		(layer "In11.Cu")
		(net "P5E_CPU1_G1_TX_DN<6>")
	)
	(segment
		(start 104.408986 -224.699068)
		(end 104.448102 -224.721928)
		(width 0.1143)
		(layer "In11.Cu")
		(net "P5E_CPU1_G1_TX_DN<6>")
	)
	(segment
		(start 105.388156 -236.061758)
		(end 105.418636 -236.079538)
		(width 0.1143)
		(layer "In11.Cu")
		(net "P5E_CPU1_G1_TX_DN<6>")
	)
	(segment
		(start 109.762036 -205.849728)
		(end 104.565704 -214.603076)
		(width 0.14224)
		(layer "In11.Cu")
		(net "P5E_CPU1_G1_TX_DN<6>")
	)
	(segment
		(start 105.418636 -233.449114)
		(end 105.388156 -233.466894)
		(width 0.1143)
		(layer "In11.Cu")
		(net "P5E_CPU1_G1_TX_DN<6>")
	)
	(segment
		(start 105.34904 -231.179116)
		(end 105.388156 -231.201976)
		(width 0.1143)
		(layer "In11.Cu")
		(net "P5E_CPU1_G1_TX_DN<6>")
	)
	(segment
		(start 105.388156 -226.9871)
		(end 105.34904 -227.00996)
		(width 0.1143)
		(layer "In11.Cu")
		(net "P5E_CPU1_G1_TX_DN<6>")
	)
	(segment
		(start 104.44861 -223.10217)
		(end 104.472232 -223.115632)
		(width 0.1143)
		(layer "In11.Cu")
		(net "P5E_CPU1_G1_TX_DN<6>")
	)
	(segment
		(start 105.418636 -243.169186)
		(end 105.388156 -243.186966)
		(width 0.1143)
		(layer "In11.Cu")
		(net "P5E_CPU1_G1_TX_DN<6>")
	)
	(segment
		(start 104.450642 -222.12554)
		(end 104.449372 -222.126048)
		(width 0.1143)
		(layer "In11.Cu")
		(net "P5E_CPU1_G1_TX_DN<6>")
	)
	(segment
		(start 105.388156 -229.581964)
		(end 105.420668 -229.60076)
		(width 0.1143)
		(layer "In11.Cu")
		(net "P5E_CPU1_G1_TX_DN<6>")
	)
	(segment
		(start 105.34904 -244.138958)
		(end 105.388156 -244.161818)
		(width 0.1143)
		(layer "In11.Cu")
		(net "P5E_CPU1_G1_TX_DN<6>")
	)
	(segment
		(start 104.918002 -225.531934)
		(end 104.918764 -225.532442)
		(width 0.1143)
		(layer "In11.Cu")
		(net "P5E_CPU1_G1_TX_DN<6>")
	)
	(segment
		(start 105.418636 -231.829102)
		(end 105.388156 -231.846882)
		(width 0.1143)
		(layer "In11.Cu")
		(net "P5E_CPU1_G1_TX_DN<6>")
	)
	(segment
		(start 105.351072 -229.560628)
		(end 105.388156 -229.581964)
		(width 0.1143)
		(layer "In11.Cu")
		(net "P5E_CPU1_G1_TX_DN<6>")
	)
	(segment
		(start 106.327956 -245.78183)
		(end 106.359706 -245.800118)
		(width 0.1143)
		(layer "In11.Cu")
		(net "P5E_CPU1_G1_TX_DN<6>")
	)
	(segment
		(start 105.418636 -230.20909)
		(end 105.35158 -230.248206)
		(width 0.1143)
		(layer "In11.Cu")
		(net "P5E_CPU1_G1_TX_DN<6>")
	)
	(segment
		(start 104.913684 -225.529394)
		(end 104.915208 -225.53041)
		(width 0.1143)
		(layer "In11.Cu")
		(net "P5E_CPU1_G1_TX_DN<6>")
	)
	(segment
		(start 105.388156 -238.32693)
		(end 105.34904 -238.34979)
		(width 0.1143)
		(layer "In11.Cu")
		(net "P5E_CPU1_G1_TX_DN<6>")
	)
	(segment
		(start 105.34904 -232.798874)
		(end 105.388156 -232.821734)
		(width 0.1143)
		(layer "In11.Cu")
		(net "P5E_CPU1_G1_TX_DN<6>")
	)
	(segment
		(start 104.918764 -225.532442)
		(end 104.920034 -225.533204)
		(width 0.1143)
		(layer "In11.Cu")
		(net "P5E_CPU1_G1_TX_DN<6>")
	)
	(segment
		(start 104.611424 -221.129098)
		(end 104.611424 -221.30512)
		(width 0.1143)
		(layer "In11.Cu")
		(net "P5E_CPU1_G1_TX_DN<6>")
	)
	(segment
		(start 105.388156 -240.921794)
		(end 105.418636 -240.939574)
		(width 0.1143)
		(layer "In11.Cu")
		(net "P5E_CPU1_G1_TX_DN<6>")
	)
	(segment
		(start 105.388156 -233.466894)
		(end 105.34904 -233.489754)
		(width 0.1143)
		(layer "In11.Cu")
		(net "P5E_CPU1_G1_TX_DN<6>")
	)
	(segment
		(start 105.388156 -234.441746)
		(end 105.418636 -234.459526)
		(width 0.1143)
		(layer "In11.Cu")
		(net "P5E_CPU1_G1_TX_DN<6>")
	)
	(segment
		(start 105.34904 -236.038898)
		(end 105.388156 -236.061758)
		(width 0.1143)
		(layer "In11.Cu")
		(net "P5E_CPU1_G1_TX_DN<6>")
	)
	(segment
		(start 55.752746 -54.459632)
		(end 148.321522 -137.693654)
		(width 0.14224)
		(layer "In11.Cu")
		(net "P5E_CPU1_G1_TX_DN<6>")
	)
	(segment
		(start 105.388156 -244.161818)
		(end 105.418636 -244.179598)
		(width 0.1143)
		(layer "In11.Cu")
		(net "P5E_CPU1_G1_TX_DN<6>")
	)
	(segment
		(start 105.388156 -237.68177)
		(end 105.418636 -237.69955)
		(width 0.1143)
		(layer "In11.Cu")
		(net "P5E_CPU1_G1_TX_DN<6>")
	)
	(segment
		(start 152.484582 -146.302222)
		(end 153.33218 -159.85617)
		(width 0.14224)
		(layer "In11.Cu")
		(net "P5E_CPU1_G1_TX_DN<6>")
	)
	(segment
		(start 105.34904 -226.31908)
		(end 105.388156 -226.34194)
		(width 0.1143)
		(layer "In11.Cu")
		(net "P5E_CPU1_G1_TX_DN<6>")
	)
	(segment
		(start 105.34904 -227.939092)
		(end 105.388156 -227.961952)
		(width 0.1143)
		(layer "In11.Cu")
		(net "P5E_CPU1_G1_TX_DN<6>")
	)
	(segment
		(start 105.388156 -231.201976)
		(end 105.420668 -231.220772)
		(width 0.1143)
		(layer "In11.Cu")
		(net "P5E_CPU1_G1_TX_DN<6>")
	)
	(segment
		(start 105.388156 -231.846882)
		(end 105.34904 -231.869742)
		(width 0.1143)
		(layer "In11.Cu")
		(net "P5E_CPU1_G1_TX_DN<6>")
	)
	(segment
		(start 104.448102 -223.747076)
		(end 104.41178 -223.767904)
		(width 0.1143)
		(layer "In11.Cu")
		(net "P5E_CPU1_G1_TX_DN<6>")
	)
	(segment
		(start 105.34904 -242.518946)
		(end 105.388156 -242.541806)
		(width 0.1143)
		(layer "In11.Cu")
		(net "P5E_CPU1_G1_TX_DN<6>")
	)
	(segment
		(start 104.635808 -221.70644)
		(end 104.635808 -221.804484)
		(width 0.1143)
		(layer "In11.Cu")
		(net "P5E_CPU1_G1_TX_DN<6>")
	)
	(segment
		(start 104.878886 -225.509074)
		(end 104.885744 -225.513138)
		(width 0.1143)
		(layer "In11.Cu")
		(net "P5E_CPU1_G1_TX_DN<6>")
	)
	(segment
		(start 105.34904 -234.418886)
		(end 105.388156 -234.441746)
		(width 0.1143)
		(layer "In11.Cu")
		(net "P5E_CPU1_G1_TX_DN<6>")
	)
	(segment
		(start 105.81894 -244.948964)
		(end 105.870502 -244.978936)
		(width 0.1143)
		(layer "In11.Cu")
		(net "P5E_CPU1_G1_TX_DN<6>")
	)
	(segment
		(start 105.388156 -232.821734)
		(end 105.418636 -232.839514)
		(width 0.1143)
		(layer "In11.Cu")
		(net "P5E_CPU1_G1_TX_DN<6>")
	)
	(segment
		(start 151.26081 -169.97553)
		(end 148.001482 -174.512732)
		(width 0.14224)
		(layer "In11.Cu")
		(net "P5E_CPU1_G1_TX_DN<6>")
	)
	(segment
		(start 104.916986 -225.531426)
		(end 104.918002 -225.531934)
		(width 0.1143)
		(layer "In11.Cu")
		(net "P5E_CPU1_G1_TX_DN<6>")
	)
	(segment
		(start 104.920034 -225.533204)
		(end 104.949752 -225.550222)
		(width 0.1143)
		(layer "In11.Cu")
		(net "P5E_CPU1_G1_TX_DN<6>")
	)
	(segment
		(start 105.388156 -235.086906)
		(end 105.34904 -235.109766)
		(width 0.1143)
		(layer "In11.Cu")
		(net "P5E_CPU1_G1_TX_DN<6>")
	)
	(segment
		(start 153.33218 -159.85617)
		(end 153.33218 -163.943792)
		(width 0.14224)
		(layer "In11.Cu")
		(net "P5E_CPU1_G1_TX_DN<6>")
	)
	(segment
		(start 104.611424 -221.30512)
		(end 104.635808 -221.70644)
		(width 0.1143)
		(layer "In11.Cu")
		(net "P5E_CPU1_G1_TX_DN<6>")
	)
	(segment
		(start 105.388156 -236.706918)
		(end 105.34904 -236.729778)
		(width 0.1143)
		(layer "In11.Cu")
		(net "P5E_CPU1_G1_TX_DN<6>")
	)
	(segment
		(start 105.418636 -238.30915)
		(end 105.388156 -238.32693)
		(width 0.1143)
		(layer "In11.Cu")
		(net "P5E_CPU1_G1_TX_DN<6>")
	)
	(segment
		(start 104.449372 -222.126048)
		(end 104.446578 -222.127826)
		(width 0.1143)
		(layer "In11.Cu")
		(net "P5E_CPU1_G1_TX_DN<6>")
	)
	(segment
		(start 51.40325 -48.020224)
		(end 55.752746 -54.459632)
		(width 0.14224)
		(layer "In11.Cu")
		(net "P5E_CPU1_G1_TX_DN<6>")
	)
	(segment
		(start 105.388156 -228.607112)
		(end 105.34904 -228.629972)
		(width 0.1143)
		(layer "In11.Cu")
		(net "P5E_CPU1_G1_TX_DN<6>")
	)
	(segment
		(start 105.418636 -241.549174)
		(end 105.388156 -241.566954)
		(width 0.1143)
		(layer "In11.Cu")
		(net "P5E_CPU1_G1_TX_DN<6>")
	)
	(segment
		(start 104.565704 -221.083378)
		(end 104.611424 -221.129098)
		(width 0.1143)
		(layer "In11.Cu")
		(net "P5E_CPU1_G1_TX_DN<6>")
	)
	(segment
		(start 106.508804 -246.03456)
		(end 106.438954 -246.10441)
		(width 0.1143)
		(layer "In11.Cu")
		(net "P5E_CPU1_G1_TX_DN<6>")
	)
	(segment
		(start 105.388156 -239.301782)
		(end 105.418636 -239.319562)
		(width 0.1143)
		(layer "In11.Cu")
		(net "P5E_CPU1_G1_TX_DN<6>")
	)
	(segment
		(start 105.388156 -241.566954)
		(end 105.34904 -241.589814)
		(width 0.1143)
		(layer "In11.Cu")
		(net "P5E_CPU1_G1_TX_DN<6>")
	)
	(segment
		(start 104.886506 -225.513646)
		(end 104.913684 -225.529394)
		(width 0.1143)
		(layer "In11.Cu")
		(net "P5E_CPU1_G1_TX_DN<6>")
	)
	(segment
		(start 105.388156 -226.34194)
		(end 105.418636 -226.35972)
		(width 0.1143)
		(layer "In11.Cu")
		(net "P5E_CPU1_G1_TX_DN<6>")
	)
	(segment
		(start 153.33218 -163.943792)
		(end 151.44242 -169.494962)
		(width 0.14224)
		(layer "In11.Cu")
		(net "P5E_CPU1_G1_TX_DN<6>")
	)
	(segment
		(start 41.276524 -19.42719)
		(end 41.276524 -20.242784)
		(width 0.14224)
		(layer "In11.Cu")
		(net "P5E_CPU1_G1_TX_DN<6>")
	)
	(segment
		(start 105.418636 -228.589332)
		(end 105.388156 -228.607112)
		(width 0.1143)
		(layer "In11.Cu")
		(net "P5E_CPU1_G1_TX_DN<6>")
	)
	(segment
		(start 41.276524 -20.242784)
		(end 51.40325 -48.020224)
		(width 0.14224)
		(layer "In11.Cu")
		(net "P5E_CPU1_G1_TX_DN<6>")
	)
	(segment
		(start 104.885744 -225.513138)
		(end 104.886506 -225.513646)
		(width 0.1143)
		(layer "In11.Cu")
		(net "P5E_CPU1_G1_TX_DN<6>")
	)
	(segment
		(start 105.34904 -229.559104)
		(end 105.351072 -229.560628)
		(width 0.1143)
		(layer "In11.Cu")
		(net "P5E_CPU1_G1_TX_DN<6>")
	)
	(segment
		(start 105.388156 -227.961952)
		(end 105.418636 -227.979732)
		(width 0.1143)
		(layer "In11.Cu")
		(net "P5E_CPU1_G1_TX_DN<6>")
	)
	(segment
		(start 105.418636 -239.929162)
		(end 105.388156 -239.946942)
		(width 0.1143)
		(layer "In11.Cu")
		(net "P5E_CPU1_G1_TX_DN<6>")
	)
	(segment
		(start 148.001482 -174.512732)
		(end 109.762036 -205.849728)
		(width 0.14224)
		(layer "In11.Cu")
		(net "P5E_CPU1_G1_TX_DN<6>")
	)
	(segment
		(start 105.388156 -243.186966)
		(end 105.34904 -243.209826)
		(width 0.1143)
		(layer "In11.Cu")
		(net "P5E_CPU1_G1_TX_DN<6>")
	)
	(segment
		(start 105.34904 -240.898934)
		(end 105.388156 -240.921794)
		(width 0.1143)
		(layer "In11.Cu")
		(net "P5E_CPU1_G1_TX_DN<6>")
	)
	(arc
		(start 105.418636 -226.35972)
		(mid 105.575613 -226.66452)
		(end 105.418636 -226.96932)
		(width 0.1143)
		(layer "In11.Cu")
		(net "P5E_CPU1_G1_TX_DN<6>")
	)
	(arc
		(start 105.418636 -239.319562)
		(mid 105.575613 -239.624362)
		(end 105.418636 -239.929162)
		(width 0.1143)
		(layer "In11.Cu")
		(net "P5E_CPU1_G1_TX_DN<6>")
	)
	(arc
		(start 105.34904 -227.00996)
		(mid 105.105713 -227.474526)
		(end 105.34904 -227.939092)
		(width 0.1143)
		(layer "In11.Cu")
		(net "P5E_CPU1_G1_TX_DN<6>")
	)
	(arc
		(start 105.575608 -229.90429)
		(mid 105.534059 -230.075712)
		(end 105.418636 -230.20909)
		(width 0.1143)
		(layer "In11.Cu")
		(net "P5E_CPU1_G1_TX_DN<6>")
	)
	(arc
		(start 105.418636 -232.839514)
		(mid 105.575613 -233.144314)
		(end 105.418636 -233.449114)
		(width 0.1143)
		(layer "In11.Cu")
		(net "P5E_CPU1_G1_TX_DN<6>")
	)
	(arc
		(start 105.34904 -243.209826)
		(mid 105.105713 -243.674392)
		(end 105.34904 -244.138958)
		(width 0.1143)
		(layer "In11.Cu")
		(net "P5E_CPU1_G1_TX_DN<6>")
	)
	(arc
		(start 104.635808 -221.804484)
		(mid 104.586192 -221.989787)
		(end 104.450642 -222.12554)
		(width 0.1143)
		(layer "In11.Cu")
		(net "P5E_CPU1_G1_TX_DN<6>")
	)
	(arc
		(start 105.418636 -242.559586)
		(mid 105.575613 -242.864386)
		(end 105.418636 -243.169186)
		(width 0.1143)
		(layer "In11.Cu")
		(net "P5E_CPU1_G1_TX_DN<6>")
	)
	(arc
		(start 104.949752 -225.550222)
		(mid 105.064428 -225.683556)
		(end 105.105708 -225.854514)
		(width 0.1143)
		(layer "In11.Cu")
		(net "P5E_CPU1_G1_TX_DN<6>")
	)
	(arc
		(start 105.105708 -230.71455)
		(mid 105.170223 -230.976769)
		(end 105.34904 -231.179116)
		(width 0.1143)
		(layer "In11.Cu")
		(net "P5E_CPU1_G1_TX_DN<6>")
	)
	(arc
		(start 105.34904 -228.629972)
		(mid 105.105713 -229.094538)
		(end 105.34904 -229.559104)
		(width 0.1143)
		(layer "In11.Cu")
		(net "P5E_CPU1_G1_TX_DN<6>")
	)
	(arc
		(start 104.408986 -223.769936)
		(mid 104.165659 -224.234502)
		(end 104.408986 -224.699068)
		(width 0.1143)
		(layer "In11.Cu")
		(net "P5E_CPU1_G1_TX_DN<6>")
	)
	(arc
		(start 105.34904 -241.589814)
		(mid 105.105713 -242.05438)
		(end 105.34904 -242.518946)
		(width 0.1143)
		(layer "In11.Cu")
		(net "P5E_CPU1_G1_TX_DN<6>")
	)
	(arc
		(start 105.418636 -227.979732)
		(mid 105.575613 -228.284532)
		(end 105.418636 -228.589332)
		(width 0.1143)
		(layer "In11.Cu")
		(net "P5E_CPU1_G1_TX_DN<6>")
	)
	(arc
		(start 104.446578 -222.127826)
		(mid 104.167348 -222.615624)
		(end 104.44861 -223.10217)
		(width 0.1143)
		(layer "In11.Cu")
		(net "P5E_CPU1_G1_TX_DN<6>")
	)
	(arc
		(start 105.35158 -230.248206)
		(mid 105.170928 -230.450951)
		(end 105.105708 -230.71455)
		(width 0.1143)
		(layer "In11.Cu")
		(net "P5E_CPU1_G1_TX_DN<6>")
	)
	(arc
		(start 105.420668 -231.220772)
		(mid 105.534597 -231.353919)
		(end 105.575608 -231.524302)
		(width 0.1143)
		(layer "In11.Cu")
		(net "P5E_CPU1_G1_TX_DN<6>")
	)
	(arc
		(start 106.058208 -245.313454)
		(mid 106.130464 -245.583707)
		(end 106.327956 -245.78183)
		(width 0.1143)
		(layer "In11.Cu")
		(net "P5E_CPU1_G1_TX_DN<6>")
	)
	(arc
		(start 104.635554 -225.044508)
		(mid 104.700069 -225.306727)
		(end 104.878886 -225.509074)
		(width 0.1143)
		(layer "In11.Cu")
		(net "P5E_CPU1_G1_TX_DN<6>")
	)
	(arc
		(start 105.575608 -244.484398)
		(mid 105.640123 -244.746617)
		(end 105.81894 -244.948964)
		(width 0.1143)
		(layer "In11.Cu")
		(net "P5E_CPU1_G1_TX_DN<6>")
	)
	(arc
		(start 105.105708 -225.854514)
		(mid 105.170223 -226.116733)
		(end 105.34904 -226.31908)
		(width 0.1143)
		(layer "In11.Cu")
		(net "P5E_CPU1_G1_TX_DN<6>")
	)
	(arc
		(start 105.418636 -237.69955)
		(mid 105.575613 -238.00435)
		(end 105.418636 -238.30915)
		(width 0.1143)
		(layer "In11.Cu")
		(net "P5E_CPU1_G1_TX_DN<6>")
	)
	(arc
		(start 105.34904 -235.109766)
		(mid 105.105713 -235.574332)
		(end 105.34904 -236.038898)
		(width 0.1143)
		(layer "In11.Cu")
		(net "P5E_CPU1_G1_TX_DN<6>")
	)
	(arc
		(start 106.359706 -245.800118)
		(mid 106.456841 -245.902987)
		(end 106.508804 -246.03456)
		(width 0.1143)
		(layer "In11.Cu")
		(net "P5E_CPU1_G1_TX_DN<6>")
	)
	(arc
		(start 105.34904 -231.869742)
		(mid 105.105713 -232.334308)
		(end 105.34904 -232.798874)
		(width 0.1143)
		(layer "In11.Cu")
		(net "P5E_CPU1_G1_TX_DN<6>")
	)
	(arc
		(start 105.420668 -229.60076)
		(mid 105.534597 -229.733907)
		(end 105.575608 -229.90429)
		(width 0.1143)
		(layer "In11.Cu")
		(net "P5E_CPU1_G1_TX_DN<6>")
	)
	(arc
		(start 104.479852 -223.120204)
		(mid 104.63578 -223.424496)
		(end 104.479852 -223.728788)
		(width 0.1143)
		(layer "In11.Cu")
		(net "P5E_CPU1_G1_TX_DN<6>")
	)
	(arc
		(start 105.34904 -236.729778)
		(mid 105.105713 -237.194344)
		(end 105.34904 -237.65891)
		(width 0.1143)
		(layer "In11.Cu")
		(net "P5E_CPU1_G1_TX_DN<6>")
	)
	(arc
		(start 105.34904 -239.969802)
		(mid 105.105713 -240.434368)
		(end 105.34904 -240.898934)
		(width 0.1143)
		(layer "In11.Cu")
		(net "P5E_CPU1_G1_TX_DN<6>")
	)
	(arc
		(start 105.418636 -234.459526)
		(mid 105.575613 -234.764326)
		(end 105.418636 -235.069126)
		(width 0.1143)
		(layer "In11.Cu")
		(net "P5E_CPU1_G1_TX_DN<6>")
	)
	(arc
		(start 105.418636 -244.179598)
		(mid 105.534063 -244.312974)
		(end 105.575608 -244.484398)
		(width 0.1143)
		(layer "In11.Cu")
		(net "P5E_CPU1_G1_TX_DN<6>")
	)
	(arc
		(start 105.34904 -233.489754)
		(mid 105.105713 -233.95432)
		(end 105.34904 -234.418886)
		(width 0.1143)
		(layer "In11.Cu")
		(net "P5E_CPU1_G1_TX_DN<6>")
	)
	(arc
		(start 105.34904 -238.34979)
		(mid 105.105713 -238.814356)
		(end 105.34904 -239.278922)
		(width 0.1143)
		(layer "In11.Cu")
		(net "P5E_CPU1_G1_TX_DN<6>")
	)
	(arc
		(start 104.478582 -224.739708)
		(mid 104.594009 -224.873084)
		(end 104.635554 -225.044508)
		(width 0.1143)
		(layer "In11.Cu")
		(net "P5E_CPU1_G1_TX_DN<6>")
	)
	(arc
		(start 105.418636 -240.939574)
		(mid 105.575613 -241.244374)
		(end 105.418636 -241.549174)
		(width 0.1143)
		(layer "In11.Cu")
		(net "P5E_CPU1_G1_TX_DN<6>")
	)
	(arc
		(start 105.870502 -244.978936)
		(mid 106.007934 -245.116195)
		(end 106.058208 -245.303802)
		(width 0.1143)
		(layer "In11.Cu")
		(net "P5E_CPU1_G1_TX_DN<6>")
	)
	(arc
		(start 105.418636 -236.079538)
		(mid 105.575613 -236.384338)
		(end 105.418636 -236.689138)
		(width 0.1143)
		(layer "In11.Cu")
		(net "P5E_CPU1_G1_TX_DN<6>")
	)
	(arc
		(start 105.575608 -231.524302)
		(mid 105.534059 -231.695724)
		(end 105.418636 -231.829102)
		(width 0.1143)
		(layer "In11.Cu")
		(net "P5E_CPU1_G1_TX_DN<6>")
	)
	(segment
		(start 44.050204 -16.662146)
		(end 44.050204 -17.34185)
		(width 0.12954)
		(layer "F.Cu")
		(net "P5E_CPU1_G1_TX_DN<5>")
	)
	(segment
		(start 44.050204 -17.34185)
		(end 43.779694 -17.61236)
		(width 0.12954)
		(layer "F.Cu")
		(net "P5E_CPU1_G1_TX_DN<5>")
	)
	(segment
		(start 43.754294 -16.366236)
		(end 44.050204 -16.662146)
		(width 0.12954)
		(layer "F.Cu")
		(net "P5E_CPU1_G1_TX_DN<5>")
	)
	(segment
		(start 106.607864 -244.750336)
		(end 106.141012 -244.484398)
		(width 0.12954)
		(layer "F.Cu")
		(net "P5E_CPU1_G1_TX_DN<5>")
	)
	(segment
		(start 106.359706 -226.968812)
		(end 106.327956 -226.9871)
		(width 0.1143)
		(layer "In11.Cu")
		(net "P5E_CPU1_G1_TX_DN<5>")
	)
	(segment
		(start 44.070524 -17.90319)
		(end 44.070524 -20.23618)
		(width 0.14224)
		(layer "In11.Cu")
		(net "P5E_CPU1_G1_TX_DN<5>")
	)
	(segment
		(start 152.447244 -169.474134)
		(end 152.070816 -170.470068)
		(width 0.14224)
		(layer "In11.Cu")
		(net "P5E_CPU1_G1_TX_DN<5>")
	)
	(segment
		(start 106.349038 -235.074714)
		(end 106.327956 -235.086906)
		(width 0.1143)
		(layer "In11.Cu")
		(net "P5E_CPU1_G1_TX_DN<5>")
	)
	(segment
		(start 106.335322 -237.686088)
		(end 106.359706 -237.700058)
		(width 0.1143)
		(layer "In11.Cu")
		(net "P5E_CPU1_G1_TX_DN<5>")
	)
	(segment
		(start 106.327956 -236.706918)
		(end 106.327702 -236.707172)
		(width 0.1143)
		(layer "In11.Cu")
		(net "P5E_CPU1_G1_TX_DN<5>")
	)
	(segment
		(start 106.3498 -239.934242)
		(end 106.349038 -239.93475)
		(width 0.1143)
		(layer "In11.Cu")
		(net "P5E_CPU1_G1_TX_DN<5>")
	)
	(segment
		(start 106.330496 -242.54333)
		(end 106.331512 -242.543838)
		(width 0.1143)
		(layer "In11.Cu")
		(net "P5E_CPU1_G1_TX_DN<5>")
	)
	(segment
		(start 106.359706 -239.928654)
		(end 106.3498 -239.934242)
		(width 0.1143)
		(layer "In11.Cu")
		(net "P5E_CPU1_G1_TX_DN<5>")
	)
	(segment
		(start 151.243284 -141.591792)
		(end 153.411936 -146.076162)
		(width 0.14224)
		(layer "In11.Cu")
		(net "P5E_CPU1_G1_TX_DN<5>")
	)
	(segment
		(start 106.33329 -242.544854)
		(end 106.334052 -242.545362)
		(width 0.1143)
		(layer "In11.Cu")
		(net "P5E_CPU1_G1_TX_DN<5>")
	)
	(segment
		(start 106.327956 -230.22687)
		(end 106.32694 -230.227378)
		(width 0.1143)
		(layer "In11.Cu")
		(net "P5E_CPU1_G1_TX_DN<5>")
	)
	(segment
		(start 106.359706 -231.828594)
		(end 106.327956 -231.846882)
		(width 0.1143)
		(layer "In11.Cu")
		(net "P5E_CPU1_G1_TX_DN<5>")
	)
	(segment
		(start 106.291634 -227.94087)
		(end 106.327956 -227.961952)
		(width 0.1143)
		(layer "In11.Cu")
		(net "P5E_CPU1_G1_TX_DN<5>")
	)
	(segment
		(start 106.35869 -231.219502)
		(end 106.361484 -231.221534)
		(width 0.1143)
		(layer "In11.Cu")
		(net "P5E_CPU1_G1_TX_DN<5>")
	)
	(segment
		(start 106.327956 -235.086906)
		(end 106.327702 -235.08716)
		(width 0.1143)
		(layer "In11.Cu")
		(net "P5E_CPU1_G1_TX_DN<5>")
	)
	(segment
		(start 106.3498 -238.31423)
		(end 106.349038 -238.314738)
		(width 0.1143)
		(layer "In11.Cu")
		(net "P5E_CPU1_G1_TX_DN<5>")
	)
	(segment
		(start 106.330496 -240.923318)
		(end 106.331512 -240.923826)
		(width 0.1143)
		(layer "In11.Cu")
		(net "P5E_CPU1_G1_TX_DN<5>")
	)
	(segment
		(start 105.35666 -223.083628)
		(end 105.381298 -223.097852)
		(width 0.1143)
		(layer "In11.Cu")
		(net "P5E_CPU1_G1_TX_DN<5>")
	)
	(segment
		(start 106.359706 -228.588824)
		(end 106.329988 -228.605842)
		(width 0.1143)
		(layer "In11.Cu")
		(net "P5E_CPU1_G1_TX_DN<5>")
	)
	(segment
		(start 106.327956 -236.061758)
		(end 106.328718 -236.062266)
		(width 0.1143)
		(layer "In11.Cu")
		(net "P5E_CPU1_G1_TX_DN<5>")
	)
	(segment
		(start 106.332274 -236.064298)
		(end 106.334306 -236.065568)
		(width 0.1143)
		(layer "In11.Cu")
		(net "P5E_CPU1_G1_TX_DN<5>")
	)
	(segment
		(start 106.328718 -237.682278)
		(end 106.329734 -237.682786)
		(width 0.1143)
		(layer "In11.Cu")
		(net "P5E_CPU1_G1_TX_DN<5>")
	)
	(segment
		(start 105.510584 -221.083378)
		(end 105.556304 -221.129098)
		(width 0.1143)
		(layer "In11.Cu")
		(net "P5E_CPU1_G1_TX_DN<5>")
	)
	(segment
		(start 105.34904 -224.699068)
		(end 105.388156 -224.721928)
		(width 0.1143)
		(layer "In11.Cu")
		(net "P5E_CPU1_G1_TX_DN<5>")
	)
	(segment
		(start 106.329734 -236.062774)
		(end 106.330496 -236.063282)
		(width 0.1143)
		(layer "In11.Cu")
		(net "P5E_CPU1_G1_TX_DN<5>")
	)
	(segment
		(start 106.33329 -237.684818)
		(end 106.334052 -237.685326)
		(width 0.1143)
		(layer "In11.Cu")
		(net "P5E_CPU1_G1_TX_DN<5>")
	)
	(segment
		(start 105.510584 -221.05493)
		(end 105.510584 -221.083378)
		(width 0.1143)
		(layer "In11.Cu")
		(net "P5E_CPU1_G1_TX_DN<5>")
	)
	(segment
		(start 105.381298 -223.097852)
		(end 105.382822 -223.098868)
		(width 0.1143)
		(layer "In11.Cu")
		(net "P5E_CPU1_G1_TX_DN<5>")
	)
	(segment
		(start 106.327956 -232.821734)
		(end 106.359706 -232.840022)
		(width 0.1143)
		(layer "In11.Cu")
		(net "P5E_CPU1_G1_TX_DN<5>")
	)
	(segment
		(start 106.328718 -228.606604)
		(end 106.327956 -228.607112)
		(width 0.1143)
		(layer "In11.Cu")
		(net "P5E_CPU1_G1_TX_DN<5>")
	)
	(segment
		(start 106.331512 -242.543838)
		(end 106.332274 -242.544346)
		(width 0.1143)
		(layer "In11.Cu")
		(net "P5E_CPU1_G1_TX_DN<5>")
	)
	(segment
		(start 106.359706 -238.308642)
		(end 106.3498 -238.31423)
		(width 0.1143)
		(layer "In11.Cu")
		(net "P5E_CPU1_G1_TX_DN<5>")
	)
	(segment
		(start 106.327956 -237.68177)
		(end 106.328718 -237.682278)
		(width 0.1143)
		(layer "In11.Cu")
		(net "P5E_CPU1_G1_TX_DN<5>")
	)
	(segment
		(start 106.327956 -238.32693)
		(end 106.327702 -238.327184)
		(width 0.1143)
		(layer "In11.Cu")
		(net "P5E_CPU1_G1_TX_DN<5>")
	)
	(segment
		(start 106.291634 -229.560882)
		(end 106.294428 -229.562406)
		(width 0.1143)
		(layer "In11.Cu")
		(net "P5E_CPU1_G1_TX_DN<5>")
	)
	(segment
		(start 106.327956 -226.9871)
		(end 106.291634 -227.008182)
		(width 0.1143)
		(layer "In11.Cu")
		(net "P5E_CPU1_G1_TX_DN<5>")
	)
	(segment
		(start 106.293158 -226.321874)
		(end 106.327956 -226.34194)
		(width 0.1143)
		(layer "In11.Cu")
		(net "P5E_CPU1_G1_TX_DN<5>")
	)
	(segment
		(start 106.329734 -242.542822)
		(end 106.330496 -242.54333)
		(width 0.1143)
		(layer "In11.Cu")
		(net "P5E_CPU1_G1_TX_DN<5>")
	)
	(segment
		(start 106.359706 -235.068618)
		(end 106.3498 -235.074206)
		(width 0.1143)
		(layer "In11.Cu")
		(net "P5E_CPU1_G1_TX_DN<5>")
	)
	(segment
		(start 106.327956 -239.301782)
		(end 106.328718 -239.30229)
		(width 0.1143)
		(layer "In11.Cu")
		(net "P5E_CPU1_G1_TX_DN<5>")
	)
	(segment
		(start 43.779694 -17.61236)
		(end 44.070524 -17.90319)
		(width 0.14224)
		(layer "In11.Cu")
		(net "P5E_CPU1_G1_TX_DN<5>")
	)
	(segment
		(start 106.335322 -242.546124)
		(end 106.359706 -242.560094)
		(width 0.1143)
		(layer "In11.Cu")
		(net "P5E_CPU1_G1_TX_DN<5>")
	)
	(segment
		(start 106.332274 -240.924334)
		(end 106.33329 -240.924842)
		(width 0.1143)
		(layer "In11.Cu")
		(net "P5E_CPU1_G1_TX_DN<5>")
	)
	(segment
		(start 110.480094 -206.467202)
		(end 105.510584 -214.837772)
		(width 0.14224)
		(layer "In11.Cu")
		(net "P5E_CPU1_G1_TX_DN<5>")
	)
	(segment
		(start 106.327702 -240.921794)
		(end 106.327956 -240.921794)
		(width 0.1143)
		(layer "In11.Cu")
		(net "P5E_CPU1_G1_TX_DN<5>")
	)
	(segment
		(start 106.332274 -237.68431)
		(end 106.33329 -237.684818)
		(width 0.1143)
		(layer "In11.Cu")
		(net "P5E_CPU1_G1_TX_DN<5>")
	)
	(segment
		(start 105.52303 -223.65462)
		(end 105.419906 -223.728788)
		(width 0.1143)
		(layer "In11.Cu")
		(net "P5E_CPU1_G1_TX_DN<5>")
	)
	(segment
		(start 106.327956 -231.846882)
		(end 106.291634 -231.867964)
		(width 0.1143)
		(layer "In11.Cu")
		(net "P5E_CPU1_G1_TX_DN<5>")
	)
	(segment
		(start 106.327956 -239.946942)
		(end 106.327702 -239.947196)
		(width 0.1143)
		(layer "In11.Cu")
		(net "P5E_CPU1_G1_TX_DN<5>")
	)
	(segment
		(start 106.329734 -240.92281)
		(end 106.330496 -240.923318)
		(width 0.1143)
		(layer "In11.Cu")
		(net "P5E_CPU1_G1_TX_DN<5>")
	)
	(segment
		(start 44.070524 -20.23618)
		(end 52.935124 -48.344836)
		(width 0.14224)
		(layer "In11.Cu")
		(net "P5E_CPU1_G1_TX_DN<5>")
	)
	(segment
		(start 105.85704 -225.531426)
		(end 105.858056 -225.531934)
		(width 0.1143)
		(layer "In11.Cu")
		(net "P5E_CPU1_G1_TX_DN<5>")
	)
	(segment
		(start 105.861358 -225.533712)
		(end 105.881932 -225.54565)
		(width 0.1143)
		(layer "In11.Cu")
		(net "P5E_CPU1_G1_TX_DN<5>")
	)
	(segment
		(start 106.291634 -232.800652)
		(end 106.327956 -232.821734)
		(width 0.1143)
		(layer "In11.Cu")
		(net "P5E_CPU1_G1_TX_DN<5>")
	)
	(segment
		(start 105.881932 -225.54565)
		(end 105.884218 -225.547174)
		(width 0.1143)
		(layer "In11.Cu")
		(net "P5E_CPU1_G1_TX_DN<5>")
	)
	(segment
		(start 106.3498 -241.554254)
		(end 106.349038 -241.554762)
		(width 0.1143)
		(layer "In11.Cu")
		(net "P5E_CPU1_G1_TX_DN<5>")
	)
	(segment
		(start 106.327702 -239.301782)
		(end 106.327956 -239.301782)
		(width 0.1143)
		(layer "In11.Cu")
		(net "P5E_CPU1_G1_TX_DN<5>")
	)
	(segment
		(start 106.327702 -236.061758)
		(end 106.327956 -236.061758)
		(width 0.1143)
		(layer "In11.Cu")
		(net "P5E_CPU1_G1_TX_DN<5>")
	)
	(segment
		(start 105.81894 -225.509074)
		(end 105.85704 -225.531426)
		(width 0.1143)
		(layer "In11.Cu")
		(net "P5E_CPU1_G1_TX_DN<5>")
	)
	(segment
		(start 106.32694 -230.227378)
		(end 106.325416 -230.228394)
		(width 0.1143)
		(layer "In11.Cu")
		(net "P5E_CPU1_G1_TX_DN<5>")
	)
	(segment
		(start 106.332274 -242.544346)
		(end 106.33329 -242.544854)
		(width 0.1143)
		(layer "In11.Cu")
		(net "P5E_CPU1_G1_TX_DN<5>")
	)
	(segment
		(start 106.330496 -237.683294)
		(end 106.331512 -237.683802)
		(width 0.1143)
		(layer "In11.Cu")
		(net "P5E_CPU1_G1_TX_DN<5>")
	)
	(segment
		(start 105.355898 -223.08312)
		(end 105.35666 -223.083628)
		(width 0.1143)
		(layer "In11.Cu")
		(net "P5E_CPU1_G1_TX_DN<5>")
	)
	(segment
		(start 106.327956 -233.466894)
		(end 106.291634 -233.487976)
		(width 0.1143)
		(layer "In11.Cu")
		(net "P5E_CPU1_G1_TX_DN<5>")
	)
	(segment
		(start 105.38714 -223.101408)
		(end 105.388156 -223.101916)
		(width 0.1143)
		(layer "In11.Cu")
		(net "P5E_CPU1_G1_TX_DN<5>")
	)
	(segment
		(start 106.359706 -243.168678)
		(end 106.327956 -243.186966)
		(width 0.1143)
		(layer "In11.Cu")
		(net "P5E_CPU1_G1_TX_DN<5>")
	)
	(segment
		(start 105.388156 -224.721928)
		(end 105.418636 -224.739708)
		(width 0.1143)
		(layer "In11.Cu")
		(net "P5E_CPU1_G1_TX_DN<5>")
	)
	(segment
		(start 106.334052 -237.685326)
		(end 106.335322 -237.686088)
		(width 0.1143)
		(layer "In11.Cu")
		(net "P5E_CPU1_G1_TX_DN<5>")
	)
	(segment
		(start 105.388156 -223.101916)
		(end 105.388918 -223.102424)
		(width 0.1143)
		(layer "In11.Cu")
		(net "P5E_CPU1_G1_TX_DN<5>")
	)
	(segment
		(start 106.335322 -239.3061)
		(end 106.359706 -239.32007)
		(width 0.1143)
		(layer "In11.Cu")
		(net "P5E_CPU1_G1_TX_DN<5>")
	)
	(segment
		(start 105.556304 -221.311216)
		(end 105.575862 -221.62008)
		(width 0.1143)
		(layer "In11.Cu")
		(net "P5E_CPU1_G1_TX_DN<5>")
	)
	(segment
		(start 106.327956 -242.541806)
		(end 106.328718 -242.542314)
		(width 0.1143)
		(layer "In11.Cu")
		(net "P5E_CPU1_G1_TX_DN<5>")
	)
	(segment
		(start 149.074632 -137.107168)
		(end 151.243284 -141.591792)
		(width 0.14224)
		(layer "In11.Cu")
		(net "P5E_CPU1_G1_TX_DN<5>")
	)
	(segment
		(start 106.359706 -236.68863)
		(end 106.3498 -236.694218)
		(width 0.1143)
		(layer "In11.Cu")
		(net "P5E_CPU1_G1_TX_DN<5>")
	)
	(segment
		(start 106.328718 -242.542314)
		(end 106.329734 -242.542822)
		(width 0.1143)
		(layer "In11.Cu")
		(net "P5E_CPU1_G1_TX_DN<5>")
	)
	(segment
		(start 105.383838 -223.099376)
		(end 105.385362 -223.100392)
		(width 0.1143)
		(layer "In11.Cu")
		(net "P5E_CPU1_G1_TX_DN<5>")
	)
	(segment
		(start 106.349038 -238.314738)
		(end 106.327956 -238.32693)
		(width 0.1143)
		(layer "In11.Cu")
		(net "P5E_CPU1_G1_TX_DN<5>")
	)
	(segment
		(start 106.327956 -226.34194)
		(end 106.359706 -226.360228)
		(width 0.1143)
		(layer "In11.Cu")
		(net "P5E_CPU1_G1_TX_DN<5>")
	)
	(segment
		(start 106.327956 -240.921794)
		(end 106.328718 -240.922302)
		(width 0.1143)
		(layer "In11.Cu")
		(net "P5E_CPU1_G1_TX_DN<5>")
	)
	(segment
		(start 106.329734 -237.682786)
		(end 106.330496 -237.683294)
		(width 0.1143)
		(layer "In11.Cu")
		(net "P5E_CPU1_G1_TX_DN<5>")
	)
	(segment
		(start 106.327702 -237.68177)
		(end 106.327956 -237.68177)
		(width 0.1143)
		(layer "In11.Cu")
		(net "P5E_CPU1_G1_TX_DN<5>")
	)
	(segment
		(start 106.349038 -239.93475)
		(end 106.327956 -239.946942)
		(width 0.1143)
		(layer "In11.Cu")
		(net "P5E_CPU1_G1_TX_DN<5>")
	)
	(segment
		(start 154.271726 -164.116512)
		(end 152.447244 -169.474134)
		(width 0.14224)
		(layer "In11.Cu")
		(net "P5E_CPU1_G1_TX_DN<5>")
	)
	(segment
		(start 105.556304 -221.129098)
		(end 105.556304 -221.311216)
		(width 0.1143)
		(layer "In11.Cu")
		(net "P5E_CPU1_G1_TX_DN<5>")
	)
	(segment
		(start 154.271726 -159.826452)
		(end 154.271726 -164.116512)
		(width 0.14224)
		(layer "In11.Cu")
		(net "P5E_CPU1_G1_TX_DN<5>")
	)
	(segment
		(start 105.419906 -223.728788)
		(end 105.351834 -223.767904)
		(width 0.1143)
		(layer "In11.Cu")
		(net "P5E_CPU1_G1_TX_DN<5>")
	)
	(segment
		(start 106.33329 -240.924842)
		(end 106.334052 -240.92535)
		(width 0.1143)
		(layer "In11.Cu")
		(net "P5E_CPU1_G1_TX_DN<5>")
	)
	(segment
		(start 106.3498 -236.694218)
		(end 106.349038 -236.694726)
		(width 0.1143)
		(layer "In11.Cu")
		(net "P5E_CPU1_G1_TX_DN<5>")
	)
	(segment
		(start 106.349038 -241.554762)
		(end 106.327956 -241.566954)
		(width 0.1143)
		(layer "In11.Cu")
		(net "P5E_CPU1_G1_TX_DN<5>")
	)
	(segment
		(start 106.359706 -233.448606)
		(end 106.327956 -233.466894)
		(width 0.1143)
		(layer "In11.Cu")
		(net "P5E_CPU1_G1_TX_DN<5>")
	)
	(segment
		(start 106.359706 -230.208582)
		(end 106.327956 -230.22687)
		(width 0.1143)
		(layer "In11.Cu")
		(net "P5E_CPU1_G1_TX_DN<5>")
	)
	(segment
		(start 152.070816 -170.470068)
		(end 148.72843 -175.123094)
		(width 0.14224)
		(layer "In11.Cu")
		(net "P5E_CPU1_G1_TX_DN<5>")
	)
	(segment
		(start 106.045762 -225.870516)
		(end 106.045762 -225.87077)
		(width 0.1143)
		(layer "In11.Cu")
		(net "P5E_CPU1_G1_TX_DN<5>")
	)
	(segment
		(start 106.291634 -234.420664)
		(end 106.327956 -234.441746)
		(width 0.1143)
		(layer "In11.Cu")
		(net "P5E_CPU1_G1_TX_DN<5>")
	)
	(segment
		(start 105.575862 -221.62008)
		(end 105.575862 -221.804484)
		(width 0.1143)
		(layer "In11.Cu")
		(net "P5E_CPU1_G1_TX_DN<5>")
	)
	(segment
		(start 106.291634 -226.320858)
		(end 106.293158 -226.321874)
		(width 0.1143)
		(layer "In11.Cu")
		(net "P5E_CPU1_G1_TX_DN<5>")
	)
	(segment
		(start 105.385362 -223.100392)
		(end 105.38714 -223.101408)
		(width 0.1143)
		(layer "In11.Cu")
		(net "P5E_CPU1_G1_TX_DN<5>")
	)
	(segment
		(start 105.382822 -223.098868)
		(end 105.383838 -223.099376)
		(width 0.1143)
		(layer "In11.Cu")
		(net "P5E_CPU1_G1_TX_DN<5>")
	)
	(segment
		(start 105.351834 -223.767904)
		(end 105.34904 -223.769936)
		(width 0.1143)
		(layer "In11.Cu")
		(net "P5E_CPU1_G1_TX_DN<5>")
	)
	(segment
		(start 106.438954 -244.484398)
		(end 106.141012 -244.484398)
		(width 0.1143)
		(layer "In11.Cu")
		(net "P5E_CPU1_G1_TX_DN<5>")
	)
	(segment
		(start 106.334052 -239.305338)
		(end 106.335322 -239.3061)
		(width 0.1143)
		(layer "In11.Cu")
		(net "P5E_CPU1_G1_TX_DN<5>")
	)
	(segment
		(start 106.325416 -230.228394)
		(end 106.3244 -230.228902)
		(width 0.1143)
		(layer "In11.Cu")
		(net "P5E_CPU1_G1_TX_DN<5>")
	)
	(segment
		(start 105.884218 -225.547174)
		(end 105.885234 -225.547682)
		(width 0.1143)
		(layer "In11.Cu")
		(net "P5E_CPU1_G1_TX_DN<5>")
	)
	(segment
		(start 105.388918 -223.102424)
		(end 105.419906 -223.120204)
		(width 0.1143)
		(layer "In11.Cu")
		(net "P5E_CPU1_G1_TX_DN<5>")
	)
	(segment
		(start 106.327956 -241.566954)
		(end 106.327702 -241.567208)
		(width 0.1143)
		(layer "In11.Cu")
		(net "P5E_CPU1_G1_TX_DN<5>")
	)
	(segment
		(start 153.411936 -146.076162)
		(end 154.271726 -159.826452)
		(width 0.14224)
		(layer "In11.Cu")
		(net "P5E_CPU1_G1_TX_DN<5>")
	)
	(segment
		(start 106.334306 -236.065568)
		(end 106.359706 -236.080046)
		(width 0.1143)
		(layer "In11.Cu")
		(net "P5E_CPU1_G1_TX_DN<5>")
	)
	(segment
		(start 106.327956 -243.186966)
		(end 106.291634 -243.208048)
		(width 0.1143)
		(layer "In11.Cu")
		(net "P5E_CPU1_G1_TX_DN<5>")
	)
	(segment
		(start 106.327956 -244.161818)
		(end 106.359706 -244.180106)
		(width 0.1143)
		(layer "In11.Cu")
		(net "P5E_CPU1_G1_TX_DN<5>")
	)
	(segment
		(start 106.3244 -230.228902)
		(end 106.295952 -230.245412)
		(width 0.1143)
		(layer "In11.Cu")
		(net "P5E_CPU1_G1_TX_DN<5>")
	)
	(segment
		(start 106.3498 -235.074206)
		(end 106.349038 -235.074714)
		(width 0.1143)
		(layer "In11.Cu")
		(net "P5E_CPU1_G1_TX_DN<5>")
	)
	(segment
		(start 106.329734 -239.302798)
		(end 106.330496 -239.303306)
		(width 0.1143)
		(layer "In11.Cu")
		(net "P5E_CPU1_G1_TX_DN<5>")
	)
	(segment
		(start 105.419906 -223.120204)
		(end 105.52303 -223.194372)
		(width 0.1143)
		(layer "In11.Cu")
		(net "P5E_CPU1_G1_TX_DN<5>")
	)
	(segment
		(start 106.335322 -240.926112)
		(end 106.359706 -240.940082)
		(width 0.1143)
		(layer "In11.Cu")
		(net "P5E_CPU1_G1_TX_DN<5>")
	)
	(segment
		(start 105.420922 -222.108014)
		(end 105.34904 -222.149924)
		(width 0.1143)
		(layer "In11.Cu")
		(net "P5E_CPU1_G1_TX_DN<5>")
	)
	(segment
		(start 106.331512 -236.06379)
		(end 106.332274 -236.064298)
		(width 0.1143)
		(layer "In11.Cu")
		(net "P5E_CPU1_G1_TX_DN<5>")
	)
	(segment
		(start 106.359706 -241.548666)
		(end 106.3498 -241.554254)
		(width 0.1143)
		(layer "In11.Cu")
		(net "P5E_CPU1_G1_TX_DN<5>")
	)
	(segment
		(start 106.329988 -228.605842)
		(end 106.328718 -228.606604)
		(width 0.1143)
		(layer "In11.Cu")
		(net "P5E_CPU1_G1_TX_DN<5>")
	)
	(segment
		(start 105.34904 -223.079056)
		(end 105.355898 -223.08312)
		(width 0.1143)
		(layer "In11.Cu")
		(net "P5E_CPU1_G1_TX_DN<5>")
	)
	(segment
		(start 106.327702 -242.541806)
		(end 106.327956 -242.541806)
		(width 0.1143)
		(layer "In11.Cu")
		(net "P5E_CPU1_G1_TX_DN<5>")
	)
	(segment
		(start 106.294428 -229.562406)
		(end 106.327956 -229.581964)
		(width 0.1143)
		(layer "In11.Cu")
		(net "P5E_CPU1_G1_TX_DN<5>")
	)
	(segment
		(start 105.510584 -214.837772)
		(end 105.510584 -221.05493)
		(width 0.14224)
		(layer "In11.Cu")
		(net "P5E_CPU1_G1_TX_DN<5>")
	)
	(segment
		(start 106.328718 -236.062266)
		(end 106.329734 -236.062774)
		(width 0.1143)
		(layer "In11.Cu")
		(net "P5E_CPU1_G1_TX_DN<5>")
	)
	(segment
		(start 106.33329 -239.30483)
		(end 106.334052 -239.305338)
		(width 0.1143)
		(layer "In11.Cu")
		(net "P5E_CPU1_G1_TX_DN<5>")
	)
	(segment
		(start 106.508804 -244.414548)
		(end 106.438954 -244.484398)
		(width 0.1143)
		(layer "In11.Cu")
		(net "P5E_CPU1_G1_TX_DN<5>")
	)
	(segment
		(start 106.334052 -240.92535)
		(end 106.335322 -240.926112)
		(width 0.1143)
		(layer "In11.Cu")
		(net "P5E_CPU1_G1_TX_DN<5>")
	)
	(segment
		(start 106.328718 -240.922302)
		(end 106.329734 -240.92281)
		(width 0.1143)
		(layer "In11.Cu")
		(net "P5E_CPU1_G1_TX_DN<5>")
	)
	(segment
		(start 106.328718 -239.30229)
		(end 106.329734 -239.302798)
		(width 0.1143)
		(layer "In11.Cu")
		(net "P5E_CPU1_G1_TX_DN<5>")
	)
	(segment
		(start 106.330496 -239.303306)
		(end 106.331512 -239.303814)
		(width 0.1143)
		(layer "In11.Cu")
		(net "P5E_CPU1_G1_TX_DN<5>")
	)
	(segment
		(start 106.331512 -240.923826)
		(end 106.332274 -240.924334)
		(width 0.1143)
		(layer "In11.Cu")
		(net "P5E_CPU1_G1_TX_DN<5>")
	)
	(segment
		(start 106.360722 -229.601014)
		(end 106.361484 -229.601522)
		(width 0.1143)
		(layer "In11.Cu")
		(net "P5E_CPU1_G1_TX_DN<5>")
	)
	(segment
		(start 106.332274 -239.304322)
		(end 106.33329 -239.30483)
		(width 0.1143)
		(layer "In11.Cu")
		(net "P5E_CPU1_G1_TX_DN<5>")
	)
	(segment
		(start 106.327956 -234.441746)
		(end 106.359706 -234.460034)
		(width 0.1143)
		(layer "In11.Cu")
		(net "P5E_CPU1_G1_TX_DN<5>")
	)
	(segment
		(start 106.317796 -231.195626)
		(end 106.35869 -231.219502)
		(width 0.1143)
		(layer "In11.Cu")
		(net "P5E_CPU1_G1_TX_DN<5>")
	)
	(segment
		(start 106.295952 -230.245412)
		(end 106.294428 -230.246428)
		(width 0.1143)
		(layer "In11.Cu")
		(net "P5E_CPU1_G1_TX_DN<5>")
	)
	(segment
		(start 106.331512 -239.303814)
		(end 106.332274 -239.304322)
		(width 0.1143)
		(layer "In11.Cu")
		(net "P5E_CPU1_G1_TX_DN<5>")
	)
	(segment
		(start 56.46547 -53.829204)
		(end 149.074632 -137.107168)
		(width 0.14224)
		(layer "In11.Cu")
		(net "P5E_CPU1_G1_TX_DN<5>")
	)
	(segment
		(start 106.349038 -236.694726)
		(end 106.327956 -236.706918)
		(width 0.1143)
		(layer "In11.Cu")
		(net "P5E_CPU1_G1_TX_DN<5>")
	)
	(segment
		(start 106.330496 -236.063282)
		(end 106.331512 -236.06379)
		(width 0.1143)
		(layer "In11.Cu")
		(net "P5E_CPU1_G1_TX_DN<5>")
	)
	(segment
		(start 106.331512 -237.683802)
		(end 106.332274 -237.68431)
		(width 0.1143)
		(layer "In11.Cu")
		(net "P5E_CPU1_G1_TX_DN<5>")
	)
	(segment
		(start 106.327956 -227.961952)
		(end 106.359706 -227.98024)
		(width 0.1143)
		(layer "In11.Cu")
		(net "P5E_CPU1_G1_TX_DN<5>")
	)
	(segment
		(start 148.72843 -175.123094)
		(end 110.480094 -206.467202)
		(width 0.14224)
		(layer "In11.Cu")
		(net "P5E_CPU1_G1_TX_DN<5>")
	)
	(segment
		(start 106.334052 -242.545362)
		(end 106.335322 -242.546124)
		(width 0.1143)
		(layer "In11.Cu")
		(net "P5E_CPU1_G1_TX_DN<5>")
	)
	(segment
		(start 106.327956 -229.581964)
		(end 106.360722 -229.601014)
		(width 0.1143)
		(layer "In11.Cu")
		(net "P5E_CPU1_G1_TX_DN<5>")
	)
	(segment
		(start 106.291634 -244.140736)
		(end 106.327956 -244.161818)
		(width 0.1143)
		(layer "In11.Cu")
		(net "P5E_CPU1_G1_TX_DN<5>")
	)
	(segment
		(start 105.858056 -225.531934)
		(end 105.861358 -225.533712)
		(width 0.1143)
		(layer "In11.Cu")
		(net "P5E_CPU1_G1_TX_DN<5>")
	)
	(segment
		(start 52.935124 -48.344836)
		(end 56.46547 -53.829204)
		(width 0.14224)
		(layer "In11.Cu")
		(net "P5E_CPU1_G1_TX_DN<5>")
	)
	(arc
		(start 105.885234 -225.547682)
		(mid 105.889834 -225.551203)
		(end 105.894378 -225.554794)
		(width 0.1143)
		(layer "In11.Cu")
		(net "P5E_CPU1_G1_TX_DN<5>")
	)
	(arc
		(start 106.291634 -231.867964)
		(mid 106.283456 -231.873607)
		(end 106.275378 -231.879394)
		(width 0.1143)
		(layer "In11.Cu")
		(net "P5E_CPU1_G1_TX_DN<5>")
	)
	(arc
		(start 106.045762 -230.71074)
		(mid 106.115777 -230.990203)
		(end 106.317796 -231.195626)
		(width 0.1143)
		(layer "In11.Cu")
		(net "P5E_CPU1_G1_TX_DN<5>")
	)
	(arc
		(start 106.27741 -233.497882)
		(mid 106.050027 -233.95432)
		(end 106.27741 -234.410758)
		(width 0.1143)
		(layer "In11.Cu")
		(net "P5E_CPU1_G1_TX_DN<5>")
	)
	(arc
		(start 106.294428 -230.246428)
		(mid 106.285995 -230.252068)
		(end 106.277664 -230.257858)
		(width 0.1143)
		(layer "In11.Cu")
		(net "P5E_CPU1_G1_TX_DN<5>")
	)
	(arc
		(start 106.359706 -240.940082)
		(mid 106.515634 -241.244374)
		(end 106.359706 -241.548666)
		(width 0.1143)
		(layer "In11.Cu")
		(net "P5E_CPU1_G1_TX_DN<5>")
	)
	(arc
		(start 106.291634 -243.208048)
		(mid 106.283456 -243.213691)
		(end 106.275378 -243.219478)
		(width 0.1143)
		(layer "In11.Cu")
		(net "P5E_CPU1_G1_TX_DN<5>")
	)
	(arc
		(start 106.359706 -234.460034)
		(mid 106.515634 -234.764326)
		(end 106.359706 -235.068618)
		(width 0.1143)
		(layer "In11.Cu")
		(net "P5E_CPU1_G1_TX_DN<5>")
	)
	(arc
		(start 106.359706 -227.98024)
		(mid 106.515634 -228.284532)
		(end 106.359706 -228.588824)
		(width 0.1143)
		(layer "In11.Cu")
		(net "P5E_CPU1_G1_TX_DN<5>")
	)
	(arc
		(start 106.359706 -242.560094)
		(mid 106.515634 -242.864386)
		(end 106.359706 -243.168678)
		(width 0.1143)
		(layer "In11.Cu")
		(net "P5E_CPU1_G1_TX_DN<5>")
	)
	(arc
		(start 105.34904 -222.149924)
		(mid 105.105713 -222.61449)
		(end 105.34904 -223.079056)
		(width 0.1143)
		(layer "In11.Cu")
		(net "P5E_CPU1_G1_TX_DN<5>")
	)
	(arc
		(start 106.291634 -233.487976)
		(mid 106.284485 -233.492876)
		(end 106.27741 -233.497882)
		(width 0.1143)
		(layer "In11.Cu")
		(net "P5E_CPU1_G1_TX_DN<5>")
	)
	(arc
		(start 106.045762 -225.87077)
		(mid 106.114723 -226.125301)
		(end 106.291634 -226.320858)
		(width 0.1143)
		(layer "In11.Cu")
		(net "P5E_CPU1_G1_TX_DN<5>")
	)
	(arc
		(start 106.327956 -228.607112)
		(mid 106.121333 -228.812891)
		(end 106.045762 -229.094538)
		(width 0.1143)
		(layer "In11.Cu")
		(net "P5E_CPU1_G1_TX_DN<5>")
	)
	(arc
		(start 106.359706 -226.360228)
		(mid 106.515634 -226.66452)
		(end 106.359706 -226.968812)
		(width 0.1143)
		(layer "In11.Cu")
		(net "P5E_CPU1_G1_TX_DN<5>")
	)
	(arc
		(start 106.275378 -244.129306)
		(mid 106.283456 -244.135092)
		(end 106.291634 -244.140736)
		(width 0.1143)
		(layer "In11.Cu")
		(net "P5E_CPU1_G1_TX_DN<5>")
	)
	(arc
		(start 106.275378 -231.879394)
		(mid 106.052494 -232.334308)
		(end 106.275378 -232.789222)
		(width 0.1143)
		(layer "In11.Cu")
		(net "P5E_CPU1_G1_TX_DN<5>")
	)
	(arc
		(start 106.291634 -227.008182)
		(mid 106.283456 -227.013825)
		(end 106.275378 -227.019612)
		(width 0.1143)
		(layer "In11.Cu")
		(net "P5E_CPU1_G1_TX_DN<5>")
	)
	(arc
		(start 106.359706 -244.180106)
		(mid 106.456841 -244.282975)
		(end 106.508804 -244.414548)
		(width 0.1143)
		(layer "In11.Cu")
		(net "P5E_CPU1_G1_TX_DN<5>")
	)
	(arc
		(start 105.52303 -223.194372)
		(mid 105.640941 -223.424496)
		(end 105.52303 -223.65462)
		(width 0.1143)
		(layer "In11.Cu")
		(net "P5E_CPU1_G1_TX_DN<5>")
	)
	(arc
		(start 105.575608 -225.044508)
		(mid 105.640123 -225.306727)
		(end 105.81894 -225.509074)
		(width 0.1143)
		(layer "In11.Cu")
		(net "P5E_CPU1_G1_TX_DN<5>")
	)
	(arc
		(start 106.277664 -230.257858)
		(mid 106.109488 -230.457561)
		(end 106.045762 -230.71074)
		(width 0.1143)
		(layer "In11.Cu")
		(net "P5E_CPU1_G1_TX_DN<5>")
	)
	(arc
		(start 106.359706 -236.080046)
		(mid 106.515634 -236.384338)
		(end 106.359706 -236.68863)
		(width 0.1143)
		(layer "In11.Cu")
		(net "P5E_CPU1_G1_TX_DN<5>")
	)
	(arc
		(start 105.34904 -223.769936)
		(mid 105.105713 -224.234502)
		(end 105.34904 -224.699068)
		(width 0.1143)
		(layer "In11.Cu")
		(net "P5E_CPU1_G1_TX_DN<5>")
	)
	(arc
		(start 106.359706 -239.32007)
		(mid 106.515634 -239.624362)
		(end 106.359706 -239.928654)
		(width 0.1143)
		(layer "In11.Cu")
		(net "P5E_CPU1_G1_TX_DN<5>")
	)
	(arc
		(start 106.275378 -227.019612)
		(mid 106.052494 -227.474526)
		(end 106.275378 -227.92944)
		(width 0.1143)
		(layer "In11.Cu")
		(net "P5E_CPU1_G1_TX_DN<5>")
	)
	(arc
		(start 106.27741 -234.410758)
		(mid 106.284484 -234.415765)
		(end 106.291634 -234.420664)
		(width 0.1143)
		(layer "In11.Cu")
		(net "P5E_CPU1_G1_TX_DN<5>")
	)
	(arc
		(start 106.327702 -241.567208)
		(mid 106.047055 -242.05457)
		(end 106.327702 -242.541806)
		(width 0.1143)
		(layer "In11.Cu")
		(net "P5E_CPU1_G1_TX_DN<5>")
	)
	(arc
		(start 105.894378 -225.554794)
		(mid 105.988295 -225.679878)
		(end 106.04119 -225.827082)
		(width 0.1143)
		(layer "In11.Cu")
		(net "P5E_CPU1_G1_TX_DN<5>")
	)
	(arc
		(start 106.515662 -231.524302)
		(mid 106.474407 -231.695273)
		(end 106.359706 -231.828594)
		(width 0.1143)
		(layer "In11.Cu")
		(net "P5E_CPU1_G1_TX_DN<5>")
	)
	(arc
		(start 106.515662 -229.90429)
		(mid 106.474407 -230.075261)
		(end 106.359706 -230.208582)
		(width 0.1143)
		(layer "In11.Cu")
		(net "P5E_CPU1_G1_TX_DN<5>")
	)
	(arc
		(start 106.327702 -239.947196)
		(mid 106.047055 -240.434558)
		(end 106.327702 -240.921794)
		(width 0.1143)
		(layer "In11.Cu")
		(net "P5E_CPU1_G1_TX_DN<5>")
	)
	(arc
		(start 106.359706 -232.840022)
		(mid 106.515634 -233.144314)
		(end 106.359706 -233.448606)
		(width 0.1143)
		(layer "In11.Cu")
		(net "P5E_CPU1_G1_TX_DN<5>")
	)
	(arc
		(start 106.327702 -236.707172)
		(mid 106.047055 -237.194534)
		(end 106.327702 -237.68177)
		(width 0.1143)
		(layer "In11.Cu")
		(net "P5E_CPU1_G1_TX_DN<5>")
	)
	(arc
		(start 105.575862 -221.804484)
		(mid 105.534896 -221.97489)
		(end 105.420922 -222.108014)
		(width 0.1143)
		(layer "In11.Cu")
		(net "P5E_CPU1_G1_TX_DN<5>")
	)
	(arc
		(start 106.327702 -235.08716)
		(mid 106.047055 -235.574522)
		(end 106.327702 -236.061758)
		(width 0.1143)
		(layer "In11.Cu")
		(net "P5E_CPU1_G1_TX_DN<5>")
	)
	(arc
		(start 105.418636 -224.739708)
		(mid 105.534063 -224.873084)
		(end 105.575608 -225.044508)
		(width 0.1143)
		(layer "In11.Cu")
		(net "P5E_CPU1_G1_TX_DN<5>")
	)
	(arc
		(start 106.275378 -232.789222)
		(mid 106.283456 -232.795008)
		(end 106.291634 -232.800652)
		(width 0.1143)
		(layer "In11.Cu")
		(net "P5E_CPU1_G1_TX_DN<5>")
	)
	(arc
		(start 106.361484 -229.601522)
		(mid 106.474891 -229.734411)
		(end 106.515662 -229.90429)
		(width 0.1143)
		(layer "In11.Cu")
		(net "P5E_CPU1_G1_TX_DN<5>")
	)
	(arc
		(start 106.04119 -225.827082)
		(mid 106.044375 -225.848704)
		(end 106.045762 -225.870516)
		(width 0.1143)
		(layer "In11.Cu")
		(net "P5E_CPU1_G1_TX_DN<5>")
	)
	(arc
		(start 106.278172 -229.55123)
		(mid 106.284867 -229.556106)
		(end 106.291634 -229.560882)
		(width 0.1143)
		(layer "In11.Cu")
		(net "P5E_CPU1_G1_TX_DN<5>")
	)
	(arc
		(start 106.361484 -231.221534)
		(mid 106.474891 -231.354423)
		(end 106.515662 -231.524302)
		(width 0.1143)
		(layer "In11.Cu")
		(net "P5E_CPU1_G1_TX_DN<5>")
	)
	(arc
		(start 106.327702 -238.327184)
		(mid 106.047055 -238.814546)
		(end 106.327702 -239.301782)
		(width 0.1143)
		(layer "In11.Cu")
		(net "P5E_CPU1_G1_TX_DN<5>")
	)
	(arc
		(start 106.275378 -227.92944)
		(mid 106.283456 -227.935226)
		(end 106.291634 -227.94087)
		(width 0.1143)
		(layer "In11.Cu")
		(net "P5E_CPU1_G1_TX_DN<5>")
	)
	(arc
		(start 106.275378 -243.219478)
		(mid 106.052494 -243.674392)
		(end 106.275378 -244.129306)
		(width 0.1143)
		(layer "In11.Cu")
		(net "P5E_CPU1_G1_TX_DN<5>")
	)
	(arc
		(start 106.045762 -229.094538)
		(mid 106.107207 -229.35075)
		(end 106.278172 -229.55123)
		(width 0.1143)
		(layer "In11.Cu")
		(net "P5E_CPU1_G1_TX_DN<5>")
	)
	(arc
		(start 106.359706 -237.700058)
		(mid 106.515634 -238.00435)
		(end 106.359706 -238.308642)
		(width 0.1143)
		(layer "In11.Cu")
		(net "P5E_CPU1_G1_TX_DN<5>")
	)
	(segment
		(start 46.548294 -17.890236)
		(end 46.844204 -18.186146)
		(width 0.12954)
		(layer "F.Cu")
		(net "P5E_CPU1_G1_TX_DN<4>")
	)
	(segment
		(start 46.844204 -18.186146)
		(end 46.844204 -18.865596)
		(width 0.12954)
		(layer "F.Cu")
		(net "P5E_CPU1_G1_TX_DN<4>")
	)
	(segment
		(start 106.607864 -247.99036)
		(end 106.141012 -247.724422)
		(width 0.12954)
		(layer "F.Cu")
		(net "P5E_CPU1_G1_TX_DN<4>")
	)
	(segment
		(start 46.844204 -18.865596)
		(end 46.572678 -19.137122)
		(width 0.12954)
		(layer "F.Cu")
		(net "P5E_CPU1_G1_TX_DN<4>")
	)
	(segment
		(start 107.268772 -239.946434)
		(end 107.26801 -239.946942)
		(width 0.1143)
		(layer "In11.Cu")
		(net "P5E_CPU1_G1_TX_DN<4>")
	)
	(segment
		(start 107.29976 -243.168678)
		(end 107.27436 -243.18341)
		(width 0.1143)
		(layer "In11.Cu")
		(net "P5E_CPU1_G1_TX_DN<4>")
	)
	(segment
		(start 107.263438 -233.469688)
		(end 107.228894 -233.489754)
		(width 0.1143)
		(layer "In11.Cu")
		(net "P5E_CPU1_G1_TX_DN<4>")
	)
	(segment
		(start 107.236514 -234.423458)
		(end 107.261152 -234.437682)
		(width 0.1143)
		(layer "In11.Cu")
		(net "P5E_CPU1_G1_TX_DN<4>")
	)
	(segment
		(start 107.235752 -240.902998)
		(end 107.236514 -240.903506)
		(width 0.1143)
		(layer "In11.Cu")
		(net "P5E_CPU1_G1_TX_DN<4>")
	)
	(segment
		(start 107.266994 -239.94745)
		(end 107.265724 -239.948212)
		(width 0.1143)
		(layer "In11.Cu")
		(net "P5E_CPU1_G1_TX_DN<4>")
	)
	(segment
		(start 107.278424 -236.067854)
		(end 107.29976 -236.080046)
		(width 0.1143)
		(layer "In11.Cu")
		(net "P5E_CPU1_G1_TX_DN<4>")
	)
	(segment
		(start 107.265216 -234.440222)
		(end 107.266994 -234.441238)
		(width 0.1143)
		(layer "In11.Cu")
		(net "P5E_CPU1_G1_TX_DN<4>")
	)
	(segment
		(start 107.228894 -242.518946)
		(end 107.26547 -242.540282)
		(width 0.1143)
		(layer "In11.Cu")
		(net "P5E_CPU1_G1_TX_DN<4>")
	)
	(segment
		(start 107.271566 -236.704886)
		(end 107.268772 -236.70641)
		(width 0.1143)
		(layer "In11.Cu")
		(net "P5E_CPU1_G1_TX_DN<4>")
	)
	(segment
		(start 111.213392 -207.07223)
		(end 106.455972 -215.084406)
		(width 0.14224)
		(layer "In11.Cu")
		(net "P5E_CPU1_G1_TX_DN<4>")
	)
	(segment
		(start 46.572678 -19.137122)
		(end 46.863508 -19.427952)
		(width 0.14224)
		(layer "In11.Cu")
		(net "P5E_CPU1_G1_TX_DN<4>")
	)
	(segment
		(start 106.501692 -221.129098)
		(end 106.501692 -221.308676)
		(width 0.1143)
		(layer "In11.Cu")
		(net "P5E_CPU1_G1_TX_DN<4>")
	)
	(segment
		(start 107.228894 -236.038898)
		(end 107.235752 -236.042962)
		(width 0.1143)
		(layer "In11.Cu")
		(net "P5E_CPU1_G1_TX_DN<4>")
	)
	(segment
		(start 107.265724 -235.088176)
		(end 107.263438 -235.0897)
		(width 0.1143)
		(layer "In11.Cu")
		(net "P5E_CPU1_G1_TX_DN<4>")
	)
	(segment
		(start 106.758994 -225.509074)
		(end 106.79557 -225.53041)
		(width 0.1143)
		(layer "In11.Cu")
		(net "P5E_CPU1_G1_TX_DN<4>")
	)
	(segment
		(start 107.26801 -245.78183)
		(end 107.29976 -245.800118)
		(width 0.1143)
		(layer "In11.Cu")
		(net "P5E_CPU1_G1_TX_DN<4>")
	)
	(segment
		(start 107.262676 -236.05871)
		(end 107.263692 -236.059218)
		(width 0.1143)
		(layer "In11.Cu")
		(net "P5E_CPU1_G1_TX_DN<4>")
	)
	(segment
		(start 107.271566 -234.443778)
		(end 107.272328 -234.444286)
		(width 0.1143)
		(layer "In11.Cu")
		(net "P5E_CPU1_G1_TX_DN<4>")
	)
	(segment
		(start 106.798872 -225.532442)
		(end 106.82986 -225.550222)
		(width 0.1143)
		(layer "In11.Cu")
		(net "P5E_CPU1_G1_TX_DN<4>")
	)
	(segment
		(start 107.29976 -233.448606)
		(end 107.27436 -233.463338)
		(width 0.1143)
		(layer "In11.Cu")
		(net "P5E_CPU1_G1_TX_DN<4>")
	)
	(segment
		(start 107.228894 -232.798874)
		(end 107.235752 -232.802938)
		(width 0.1143)
		(layer "In11.Cu")
		(net "P5E_CPU1_G1_TX_DN<4>")
	)
	(segment
		(start 107.268772 -239.30229)
		(end 107.271566 -239.303814)
		(width 0.1143)
		(layer "In11.Cu")
		(net "P5E_CPU1_G1_TX_DN<4>")
	)
	(segment
		(start 107.268772 -235.086398)
		(end 107.26801 -235.086906)
		(width 0.1143)
		(layer "In11.Cu")
		(net "P5E_CPU1_G1_TX_DN<4>")
	)
	(segment
		(start 107.266994 -238.327438)
		(end 107.228894 -238.34979)
		(width 0.1143)
		(layer "In11.Cu")
		(net "P5E_CPU1_G1_TX_DN<4>")
	)
	(segment
		(start 107.266994 -242.541298)
		(end 107.26801 -242.541806)
		(width 0.1143)
		(layer "In11.Cu")
		(net "P5E_CPU1_G1_TX_DN<4>")
	)
	(segment
		(start 107.268772 -236.062266)
		(end 107.271566 -236.06379)
		(width 0.1143)
		(layer "In11.Cu")
		(net "P5E_CPU1_G1_TX_DN<4>")
	)
	(segment
		(start 107.271566 -239.94491)
		(end 107.268772 -239.946434)
		(width 0.1143)
		(layer "In11.Cu")
		(net "P5E_CPU1_G1_TX_DN<4>")
	)
	(segment
		(start 106.455972 -221.05493)
		(end 106.455972 -221.083378)
		(width 0.1143)
		(layer "In11.Cu")
		(net "P5E_CPU1_G1_TX_DN<4>")
	)
	(segment
		(start 107.266994 -239.301274)
		(end 107.26801 -239.301782)
		(width 0.1143)
		(layer "In11.Cu")
		(net "P5E_CPU1_G1_TX_DN<4>")
	)
	(segment
		(start 107.29976 -246.408702)
		(end 107.27436 -246.423434)
		(width 0.1143)
		(layer "In11.Cu")
		(net "P5E_CPU1_G1_TX_DN<4>")
	)
	(segment
		(start 107.26801 -237.68177)
		(end 107.29976 -237.700058)
		(width 0.1143)
		(layer "In11.Cu")
		(net "P5E_CPU1_G1_TX_DN<4>")
	)
	(segment
		(start 107.266994 -231.84739)
		(end 107.265724 -231.848152)
		(width 0.1143)
		(layer "In11.Cu")
		(net "P5E_CPU1_G1_TX_DN<4>")
	)
	(segment
		(start 107.26801 -231.846882)
		(end 107.266994 -231.84739)
		(width 0.1143)
		(layer "In11.Cu")
		(net "P5E_CPU1_G1_TX_DN<4>")
	)
	(segment
		(start 107.27436 -233.463338)
		(end 107.272328 -233.464354)
		(width 0.1143)
		(layer "In11.Cu")
		(net "P5E_CPU1_G1_TX_DN<4>")
	)
	(segment
		(start 107.271566 -241.564922)
		(end 107.268772 -241.566446)
		(width 0.1143)
		(layer "In11.Cu")
		(net "P5E_CPU1_G1_TX_DN<4>")
	)
	(segment
		(start 46.863508 -19.427952)
		(end 46.863508 -20.229576)
		(width 0.14224)
		(layer "In11.Cu")
		(net "P5E_CPU1_G1_TX_DN<4>")
	)
	(segment
		(start 107.26801 -239.301782)
		(end 107.268772 -239.30229)
		(width 0.1143)
		(layer "In11.Cu")
		(net "P5E_CPU1_G1_TX_DN<4>")
	)
	(segment
		(start 107.263692 -240.919254)
		(end 107.265216 -240.92027)
		(width 0.1143)
		(layer "In11.Cu")
		(net "P5E_CPU1_G1_TX_DN<4>")
	)
	(segment
		(start 107.272328 -234.444286)
		(end 107.273344 -234.444794)
		(width 0.1143)
		(layer "In11.Cu")
		(net "P5E_CPU1_G1_TX_DN<4>")
	)
	(segment
		(start 107.266994 -236.707426)
		(end 107.265724 -236.708188)
		(width 0.1143)
		(layer "In11.Cu")
		(net "P5E_CPU1_G1_TX_DN<4>")
	)
	(segment
		(start 107.298744 -226.96932)
		(end 107.268264 -226.9871)
		(width 0.1143)
		(layer "In11.Cu")
		(net "P5E_CPU1_G1_TX_DN<4>")
	)
	(segment
		(start 107.271566 -243.184934)
		(end 107.268772 -243.186458)
		(width 0.1143)
		(layer "In11.Cu")
		(net "P5E_CPU1_G1_TX_DN<4>")
	)
	(segment
		(start 107.263692 -232.819194)
		(end 107.265216 -232.82021)
		(width 0.1143)
		(layer "In11.Cu")
		(net "P5E_CPU1_G1_TX_DN<4>")
	)
	(segment
		(start 107.27436 -241.563398)
		(end 107.272328 -241.564414)
		(width 0.1143)
		(layer "In11.Cu")
		(net "P5E_CPU1_G1_TX_DN<4>")
	)
	(segment
		(start 106.455972 -221.083378)
		(end 106.501692 -221.129098)
		(width 0.1143)
		(layer "In11.Cu")
		(net "P5E_CPU1_G1_TX_DN<4>")
	)
	(segment
		(start 106.79811 -225.531934)
		(end 106.798872 -225.532442)
		(width 0.1143)
		(layer "In11.Cu")
		(net "P5E_CPU1_G1_TX_DN<4>")
	)
	(segment
		(start 107.268772 -238.326422)
		(end 107.26801 -238.32693)
		(width 0.1143)
		(layer "In11.Cu")
		(net "P5E_CPU1_G1_TX_DN<4>")
	)
	(segment
		(start 107.26801 -242.541806)
		(end 107.29976 -242.560094)
		(width 0.1143)
		(layer "In11.Cu")
		(net "P5E_CPU1_G1_TX_DN<4>")
	)
	(segment
		(start 107.228894 -229.559104)
		(end 107.26801 -229.581964)
		(width 0.1143)
		(layer "In11.Cu")
		(net "P5E_CPU1_G1_TX_DN<4>")
	)
	(segment
		(start 107.263692 -236.059218)
		(end 107.265216 -236.060234)
		(width 0.1143)
		(layer "In11.Cu")
		(net "P5E_CPU1_G1_TX_DN<4>")
	)
	(segment
		(start 107.262676 -232.818686)
		(end 107.263692 -232.819194)
		(width 0.1143)
		(layer "In11.Cu")
		(net "P5E_CPU1_G1_TX_DN<4>")
	)
	(segment
		(start 106.455972 -215.084406)
		(end 106.455972 -221.05493)
		(width 0.14224)
		(layer "In11.Cu")
		(net "P5E_CPU1_G1_TX_DN<4>")
	)
	(segment
		(start 107.272328 -243.184426)
		(end 107.271566 -243.184934)
		(width 0.1143)
		(layer "In11.Cu")
		(net "P5E_CPU1_G1_TX_DN<4>")
	)
	(segment
		(start 106.289094 -223.079056)
		(end 106.32821 -223.101916)
		(width 0.1143)
		(layer "In11.Cu")
		(net "P5E_CPU1_G1_TX_DN<4>")
	)
	(segment
		(start 107.27436 -243.18341)
		(end 107.272328 -243.184426)
		(width 0.1143)
		(layer "In11.Cu")
		(net "P5E_CPU1_G1_TX_DN<4>")
	)
	(segment
		(start 107.29976 -241.548666)
		(end 107.27436 -241.563398)
		(width 0.1143)
		(layer "In11.Cu")
		(net "P5E_CPU1_G1_TX_DN<4>")
	)
	(segment
		(start 107.271566 -240.923826)
		(end 107.272328 -240.924334)
		(width 0.1143)
		(layer "In11.Cu")
		(net "P5E_CPU1_G1_TX_DN<4>")
	)
	(segment
		(start 107.298744 -228.589332)
		(end 107.26801 -228.607112)
		(width 0.1143)
		(layer "In11.Cu")
		(net "P5E_CPU1_G1_TX_DN<4>")
	)
	(segment
		(start 107.235752 -232.802938)
		(end 107.236514 -232.803446)
		(width 0.1143)
		(layer "In11.Cu")
		(net "P5E_CPU1_G1_TX_DN<4>")
	)
	(segment
		(start 107.236514 -240.903506)
		(end 107.261152 -240.91773)
		(width 0.1143)
		(layer "In11.Cu")
		(net "P5E_CPU1_G1_TX_DN<4>")
	)
	(segment
		(start 106.32821 -224.721928)
		(end 106.35869 -224.739708)
		(width 0.1143)
		(layer "In11.Cu")
		(net "P5E_CPU1_G1_TX_DN<4>")
	)
	(segment
		(start 107.277154 -244.167152)
		(end 107.278424 -244.167914)
		(width 0.1143)
		(layer "In11.Cu")
		(net "P5E_CPU1_G1_TX_DN<4>")
	)
	(segment
		(start 107.268772 -244.162326)
		(end 107.271566 -244.16385)
		(width 0.1143)
		(layer "In11.Cu")
		(net "P5E_CPU1_G1_TX_DN<4>")
	)
	(segment
		(start 107.261152 -236.057694)
		(end 107.262676 -236.05871)
		(width 0.1143)
		(layer "In11.Cu")
		(net "P5E_CPU1_G1_TX_DN<4>")
	)
	(segment
		(start 107.266994 -241.567462)
		(end 107.265724 -241.568224)
		(width 0.1143)
		(layer "In11.Cu")
		(net "P5E_CPU1_G1_TX_DN<4>")
	)
	(segment
		(start 107.228894 -234.418886)
		(end 107.235752 -234.42295)
		(width 0.1143)
		(layer "In11.Cu")
		(net "P5E_CPU1_G1_TX_DN<4>")
	)
	(segment
		(start 107.276138 -232.82656)
		(end 107.277154 -232.827068)
		(width 0.1143)
		(layer "In11.Cu")
		(net "P5E_CPU1_G1_TX_DN<4>")
	)
	(segment
		(start 107.272328 -231.844342)
		(end 107.271566 -231.84485)
		(width 0.1143)
		(layer "In11.Cu")
		(net "P5E_CPU1_G1_TX_DN<4>")
	)
	(segment
		(start 46.863508 -20.229576)
		(end 54.387242 -48.64608)
		(width 0.14224)
		(layer "In11.Cu")
		(net "P5E_CPU1_G1_TX_DN<4>")
	)
	(segment
		(start 106.82859 -247.219216)
		(end 106.79811 -247.236996)
		(width 0.1143)
		(layer "In11.Cu")
		(net "P5E_CPU1_G1_TX_DN<4>")
	)
	(segment
		(start 107.262676 -244.15877)
		(end 107.263692 -244.159278)
		(width 0.1143)
		(layer "In11.Cu")
		(net "P5E_CPU1_G1_TX_DN<4>")
	)
	(segment
		(start 107.268772 -246.426482)
		(end 107.26801 -246.42699)
		(width 0.1143)
		(layer "In11.Cu")
		(net "P5E_CPU1_G1_TX_DN<4>")
	)
	(segment
		(start 107.263438 -241.569748)
		(end 107.228894 -241.589814)
		(width 0.1143)
		(layer "In11.Cu")
		(net "P5E_CPU1_G1_TX_DN<4>")
	)
	(segment
		(start 107.261152 -240.91773)
		(end 107.262676 -240.918746)
		(width 0.1143)
		(layer "In11.Cu")
		(net "P5E_CPU1_G1_TX_DN<4>")
	)
	(segment
		(start 107.272328 -244.804438)
		(end 107.271566 -244.804946)
		(width 0.1143)
		(layer "In11.Cu")
		(net "P5E_CPU1_G1_TX_DN<4>")
	)
	(segment
		(start 107.26801 -244.161818)
		(end 107.268772 -244.162326)
		(width 0.1143)
		(layer "In11.Cu")
		(net "P5E_CPU1_G1_TX_DN<4>")
	)
	(segment
		(start 107.268264 -226.9871)
		(end 107.229148 -227.00996)
		(width 0.1143)
		(layer "In11.Cu")
		(net "P5E_CPU1_G1_TX_DN<4>")
	)
	(segment
		(start 107.26801 -232.821734)
		(end 107.268772 -232.822242)
		(width 0.1143)
		(layer "In11.Cu")
		(net "P5E_CPU1_G1_TX_DN<4>")
	)
	(segment
		(start 106.32821 -223.747076)
		(end 106.289094 -223.769936)
		(width 0.1143)
		(layer "In11.Cu")
		(net "P5E_CPU1_G1_TX_DN<4>")
	)
	(segment
		(start 107.26801 -244.806978)
		(end 107.266994 -244.807486)
		(width 0.1143)
		(layer "In11.Cu")
		(net "P5E_CPU1_G1_TX_DN<4>")
	)
	(segment
		(start 107.262676 -234.438698)
		(end 107.263692 -234.439206)
		(width 0.1143)
		(layer "In11.Cu")
		(net "P5E_CPU1_G1_TX_DN<4>")
	)
	(segment
		(start 107.272328 -239.304322)
		(end 107.273344 -239.30483)
		(width 0.1143)
		(layer "In11.Cu")
		(net "P5E_CPU1_G1_TX_DN<4>")
	)
	(segment
		(start 107.228894 -237.65891)
		(end 107.26547 -237.680246)
		(width 0.1143)
		(layer "In11.Cu")
		(net "P5E_CPU1_G1_TX_DN<4>")
	)
	(segment
		(start 107.29976 -239.928654)
		(end 107.27436 -239.943386)
		(width 0.1143)
		(layer "In11.Cu")
		(net "P5E_CPU1_G1_TX_DN<4>")
	)
	(segment
		(start 107.266994 -243.187474)
		(end 107.265724 -243.188236)
		(width 0.1143)
		(layer "In11.Cu")
		(net "P5E_CPU1_G1_TX_DN<4>")
	)
	(segment
		(start 107.272328 -239.944402)
		(end 107.271566 -239.94491)
		(width 0.1143)
		(layer "In11.Cu")
		(net "P5E_CPU1_G1_TX_DN<4>")
	)
	(segment
		(start 107.272328 -244.164358)
		(end 107.273344 -244.164866)
		(width 0.1143)
		(layer "In11.Cu")
		(net "P5E_CPU1_G1_TX_DN<4>")
	)
	(segment
		(start 107.274106 -239.305338)
		(end 107.276138 -239.306608)
		(width 0.1143)
		(layer "In11.Cu")
		(net "P5E_CPU1_G1_TX_DN<4>")
	)
	(segment
		(start 107.274106 -240.92535)
		(end 107.276138 -240.92662)
		(width 0.1143)
		(layer "In11.Cu")
		(net "P5E_CPU1_G1_TX_DN<4>")
	)
	(segment
		(start 107.274106 -244.165374)
		(end 107.276138 -244.166644)
		(width 0.1143)
		(layer "In11.Cu")
		(net "P5E_CPU1_G1_TX_DN<4>")
	)
	(segment
		(start 107.273344 -236.064806)
		(end 107.274106 -236.065314)
		(width 0.1143)
		(layer "In11.Cu")
		(net "P5E_CPU1_G1_TX_DN<4>")
	)
	(segment
		(start 106.32821 -223.101916)
		(end 106.35869 -223.119696)
		(width 0.1143)
		(layer "In11.Cu")
		(net "P5E_CPU1_G1_TX_DN<4>")
	)
	(segment
		(start 107.272328 -236.064298)
		(end 107.273344 -236.064806)
		(width 0.1143)
		(layer "In11.Cu")
		(net "P5E_CPU1_G1_TX_DN<4>")
	)
	(segment
		(start 107.271566 -246.424958)
		(end 107.268772 -246.426482)
		(width 0.1143)
		(layer "In11.Cu")
		(net "P5E_CPU1_G1_TX_DN<4>")
	)
	(segment
		(start 107.26801 -234.441746)
		(end 107.268772 -234.442254)
		(width 0.1143)
		(layer "In11.Cu")
		(net "P5E_CPU1_G1_TX_DN<4>")
	)
	(segment
		(start 107.228894 -245.75897)
		(end 107.26547 -245.780306)
		(width 0.1143)
		(layer "In11.Cu")
		(net "P5E_CPU1_G1_TX_DN<4>")
	)
	(segment
		(start 107.265216 -232.82021)
		(end 107.266994 -232.821226)
		(width 0.1143)
		(layer "In11.Cu")
		(net "P5E_CPU1_G1_TX_DN<4>")
	)
	(segment
		(start 107.263692 -239.299242)
		(end 107.265216 -239.300258)
		(width 0.1143)
		(layer "In11.Cu")
		(net "P5E_CPU1_G1_TX_DN<4>")
	)
	(segment
		(start 107.271566 -233.464862)
		(end 107.268772 -233.466386)
		(width 0.1143)
		(layer "In11.Cu")
		(net "P5E_CPU1_G1_TX_DN<4>")
	)
	(segment
		(start 107.268772 -233.466386)
		(end 107.26801 -233.466894)
		(width 0.1143)
		(layer "In11.Cu")
		(net "P5E_CPU1_G1_TX_DN<4>")
	)
	(segment
		(start 107.271566 -244.16385)
		(end 107.272328 -244.164358)
		(width 0.1143)
		(layer "In11.Cu")
		(net "P5E_CPU1_G1_TX_DN<4>")
	)
	(segment
		(start 107.29976 -244.78869)
		(end 107.27436 -244.803422)
		(width 0.1143)
		(layer "In11.Cu")
		(net "P5E_CPU1_G1_TX_DN<4>")
	)
	(segment
		(start 107.263438 -236.709712)
		(end 107.228894 -236.729778)
		(width 0.1143)
		(layer "In11.Cu")
		(net "P5E_CPU1_G1_TX_DN<4>")
	)
	(segment
		(start 107.229148 -227.939092)
		(end 107.268264 -227.961952)
		(width 0.1143)
		(layer "In11.Cu")
		(net "P5E_CPU1_G1_TX_DN<4>")
	)
	(segment
		(start 107.271566 -232.823766)
		(end 107.272328 -232.824274)
		(width 0.1143)
		(layer "In11.Cu")
		(net "P5E_CPU1_G1_TX_DN<4>")
	)
	(segment
		(start 107.266994 -244.16131)
		(end 107.26801 -244.161818)
		(width 0.1143)
		(layer "In11.Cu")
		(net "P5E_CPU1_G1_TX_DN<4>")
	)
	(segment
		(start 107.261152 -244.157754)
		(end 107.262676 -244.15877)
		(width 0.1143)
		(layer "In11.Cu")
		(net "P5E_CPU1_G1_TX_DN<4>")
	)
	(segment
		(start 106.79557 -225.53041)
		(end 106.797094 -225.531426)
		(width 0.1143)
		(layer "In11.Cu")
		(net "P5E_CPU1_G1_TX_DN<4>")
	)
	(segment
		(start 107.276138 -234.446572)
		(end 107.277154 -234.44708)
		(width 0.1143)
		(layer "In11.Cu")
		(net "P5E_CPU1_G1_TX_DN<4>")
	)
	(segment
		(start 107.29976 -231.828594)
		(end 107.27436 -231.843326)
		(width 0.1143)
		(layer "In11.Cu")
		(net "P5E_CPU1_G1_TX_DN<4>")
	)
	(segment
		(start 107.26801 -236.061758)
		(end 107.268772 -236.062266)
		(width 0.1143)
		(layer "In11.Cu")
		(net "P5E_CPU1_G1_TX_DN<4>")
	)
	(segment
		(start 107.273344 -240.924842)
		(end 107.274106 -240.92535)
		(width 0.1143)
		(layer "In11.Cu")
		(net "P5E_CPU1_G1_TX_DN<4>")
	)
	(segment
		(start 107.26801 -230.22687)
		(end 107.231434 -230.248206)
		(width 0.1143)
		(layer "In11.Cu")
		(net "P5E_CPU1_G1_TX_DN<4>")
	)
	(segment
		(start 107.266994 -237.681262)
		(end 107.26801 -237.68177)
		(width 0.1143)
		(layer "In11.Cu")
		(net "P5E_CPU1_G1_TX_DN<4>")
	)
	(segment
		(start 107.26801 -235.086906)
		(end 107.266994 -235.087414)
		(width 0.1143)
		(layer "In11.Cu")
		(net "P5E_CPU1_G1_TX_DN<4>")
	)
	(segment
		(start 107.265216 -240.92027)
		(end 107.266994 -240.921286)
		(width 0.1143)
		(layer "In11.Cu")
		(net "P5E_CPU1_G1_TX_DN<4>")
	)
	(segment
		(start 107.278424 -244.167914)
		(end 107.29976 -244.180106)
		(width 0.1143)
		(layer "In11.Cu")
		(net "P5E_CPU1_G1_TX_DN<4>")
	)
	(segment
		(start 107.274106 -234.445302)
		(end 107.276138 -234.446572)
		(width 0.1143)
		(layer "In11.Cu")
		(net "P5E_CPU1_G1_TX_DN<4>")
	)
	(segment
		(start 107.271566 -235.084874)
		(end 107.268772 -235.086398)
		(width 0.1143)
		(layer "In11.Cu")
		(net "P5E_CPU1_G1_TX_DN<4>")
	)
	(segment
		(start 106.797094 -225.531426)
		(end 106.79811 -225.531934)
		(width 0.1143)
		(layer "In11.Cu")
		(net "P5E_CPU1_G1_TX_DN<4>")
	)
	(segment
		(start 107.266994 -246.427498)
		(end 107.265724 -246.42826)
		(width 0.1143)
		(layer "In11.Cu")
		(net "P5E_CPU1_G1_TX_DN<4>")
	)
	(segment
		(start 107.235752 -239.282986)
		(end 107.236514 -239.283494)
		(width 0.1143)
		(layer "In11.Cu")
		(net "P5E_CPU1_G1_TX_DN<4>")
	)
	(segment
		(start 107.235752 -234.42295)
		(end 107.236514 -234.423458)
		(width 0.1143)
		(layer "In11.Cu")
		(net "P5E_CPU1_G1_TX_DN<4>")
	)
	(segment
		(start 107.272328 -233.464354)
		(end 107.271566 -233.464862)
		(width 0.1143)
		(layer "In11.Cu")
		(net "P5E_CPU1_G1_TX_DN<4>")
	)
	(segment
		(start 107.266994 -235.087414)
		(end 107.265724 -235.088176)
		(width 0.1143)
		(layer "In11.Cu")
		(net "P5E_CPU1_G1_TX_DN<4>")
	)
	(segment
		(start 107.278424 -232.82783)
		(end 107.29976 -232.840022)
		(width 0.1143)
		(layer "In11.Cu")
		(net "P5E_CPU1_G1_TX_DN<4>")
	)
	(segment
		(start 107.228894 -240.898934)
		(end 107.235752 -240.902998)
		(width 0.1143)
		(layer "In11.Cu")
		(net "P5E_CPU1_G1_TX_DN<4>")
	)
	(segment
		(start 107.271566 -236.06379)
		(end 107.272328 -236.064298)
		(width 0.1143)
		(layer "In11.Cu")
		(net "P5E_CPU1_G1_TX_DN<4>")
	)
	(segment
		(start 107.236514 -232.803446)
		(end 107.261152 -232.81767)
		(width 0.1143)
		(layer "In11.Cu")
		(net "P5E_CPU1_G1_TX_DN<4>")
	)
	(segment
		(start 149.625812 -175.593756)
		(end 111.213392 -207.07223)
		(width 0.14224)
		(layer "In11.Cu")
		(net "P5E_CPU1_G1_TX_DN<4>")
	)
	(segment
		(start 107.26801 -241.566954)
		(end 107.266994 -241.567462)
		(width 0.1143)
		(layer "In11.Cu")
		(net "P5E_CPU1_G1_TX_DN<4>")
	)
	(segment
		(start 107.265216 -239.300258)
		(end 107.266994 -239.301274)
		(width 0.1143)
		(layer "In11.Cu")
		(net "P5E_CPU1_G1_TX_DN<4>")
	)
	(segment
		(start 107.26801 -228.607112)
		(end 107.228894 -228.629972)
		(width 0.1143)
		(layer "In11.Cu")
		(net "P5E_CPU1_G1_TX_DN<4>")
	)
	(segment
		(start 107.277154 -232.827068)
		(end 107.278424 -232.82783)
		(width 0.1143)
		(layer "In11.Cu")
		(net "P5E_CPU1_G1_TX_DN<4>")
	)
	(segment
		(start 107.276138 -236.066584)
		(end 107.277154 -236.067092)
		(width 0.1143)
		(layer "In11.Cu")
		(net "P5E_CPU1_G1_TX_DN<4>")
	)
	(segment
		(start 107.268264 -227.961952)
		(end 107.298744 -227.979732)
		(width 0.1143)
		(layer "In11.Cu")
		(net "P5E_CPU1_G1_TX_DN<4>")
	)
	(segment
		(start 107.26547 -245.780306)
		(end 107.266994 -245.781322)
		(width 0.1143)
		(layer "In11.Cu")
		(net "P5E_CPU1_G1_TX_DN<4>")
	)
	(segment
		(start 107.27436 -235.08335)
		(end 107.272328 -235.084366)
		(width 0.1143)
		(layer "In11.Cu")
		(net "P5E_CPU1_G1_TX_DN<4>")
	)
	(segment
		(start 107.26547 -237.680246)
		(end 107.266994 -237.681262)
		(width 0.1143)
		(layer "In11.Cu")
		(net "P5E_CPU1_G1_TX_DN<4>")
	)
	(segment
		(start 106.501692 -221.308676)
		(end 106.515916 -221.707202)
		(width 0.1143)
		(layer "In11.Cu")
		(net "P5E_CPU1_G1_TX_DN<4>")
	)
	(segment
		(start 107.271566 -244.804946)
		(end 107.268772 -244.80647)
		(width 0.1143)
		(layer "In11.Cu")
		(net "P5E_CPU1_G1_TX_DN<4>")
	)
	(segment
		(start 152.951434 -170.915584)
		(end 149.625812 -175.593756)
		(width 0.14224)
		(layer "In11.Cu")
		(net "P5E_CPU1_G1_TX_DN<4>")
	)
	(segment
		(start 106.35996 -222.108776)
		(end 106.28884 -222.149924)
		(width 0.1143)
		(layer "In11.Cu")
		(net "P5E_CPU1_G1_TX_DN<4>")
	)
	(segment
		(start 107.278424 -239.307878)
		(end 107.29976 -239.32007)
		(width 0.1143)
		(layer "In11.Cu")
		(net "P5E_CPU1_G1_TX_DN<4>")
	)
	(segment
		(start 107.29976 -235.068618)
		(end 107.27436 -235.08335)
		(width 0.1143)
		(layer "In11.Cu")
		(net "P5E_CPU1_G1_TX_DN<4>")
	)
	(segment
		(start 155.213304 -159.796734)
		(end 155.213304 -164.28339)
		(width 0.14224)
		(layer "In11.Cu")
		(net "P5E_CPU1_G1_TX_DN<4>")
	)
	(segment
		(start 107.236514 -244.14353)
		(end 107.261152 -244.157754)
		(width 0.1143)
		(layer "In11.Cu")
		(net "P5E_CPU1_G1_TX_DN<4>")
	)
	(segment
		(start 154.342084 -145.855436)
		(end 155.213304 -159.796734)
		(width 0.14224)
		(layer "In11.Cu")
		(net "P5E_CPU1_G1_TX_DN<4>")
	)
	(segment
		(start 107.278424 -234.447842)
		(end 107.29976 -234.460034)
		(width 0.1143)
		(layer "In11.Cu")
		(net "P5E_CPU1_G1_TX_DN<4>")
	)
	(segment
		(start 107.273344 -234.444794)
		(end 107.274106 -234.445302)
		(width 0.1143)
		(layer "In11.Cu")
		(net "P5E_CPU1_G1_TX_DN<4>")
	)
	(segment
		(start 54.387242 -48.64608)
		(end 57.174638 -53.206396)
		(width 0.14224)
		(layer "In11.Cu")
		(net "P5E_CPU1_G1_TX_DN<4>")
	)
	(segment
		(start 106.438954 -247.724422)
		(end 106.141012 -247.724422)
		(width 0.1143)
		(layer "In11.Cu")
		(net "P5E_CPU1_G1_TX_DN<4>")
	)
	(segment
		(start 107.29976 -230.208582)
		(end 107.26801 -230.22687)
		(width 0.1143)
		(layer "In11.Cu")
		(net "P5E_CPU1_G1_TX_DN<4>")
	)
	(segment
		(start 107.26801 -240.921794)
		(end 107.268772 -240.922302)
		(width 0.1143)
		(layer "In11.Cu")
		(net "P5E_CPU1_G1_TX_DN<4>")
	)
	(segment
		(start 107.26801 -231.201976)
		(end 107.301538 -231.221534)
		(width 0.1143)
		(layer "In11.Cu")
		(net "P5E_CPU1_G1_TX_DN<4>")
	)
	(segment
		(start 107.228894 -231.179116)
		(end 107.26801 -231.201976)
		(width 0.1143)
		(layer "In11.Cu")
		(net "P5E_CPU1_G1_TX_DN<4>")
	)
	(segment
		(start 107.276138 -240.92662)
		(end 107.277154 -240.927128)
		(width 0.1143)
		(layer "In11.Cu")
		(net "P5E_CPU1_G1_TX_DN<4>")
	)
	(segment
		(start 107.263438 -231.849676)
		(end 107.228894 -231.869742)
		(width 0.1143)
		(layer "In11.Cu")
		(net "P5E_CPU1_G1_TX_DN<4>")
	)
	(segment
		(start 107.27436 -239.943386)
		(end 107.272328 -239.944402)
		(width 0.1143)
		(layer "In11.Cu")
		(net "P5E_CPU1_G1_TX_DN<4>")
	)
	(segment
		(start 107.268772 -236.70641)
		(end 107.26801 -236.706918)
		(width 0.1143)
		(layer "In11.Cu")
		(net "P5E_CPU1_G1_TX_DN<4>")
	)
	(segment
		(start 107.263692 -244.159278)
		(end 107.265216 -244.160294)
		(width 0.1143)
		(layer "In11.Cu")
		(net "P5E_CPU1_G1_TX_DN<4>")
	)
	(segment
		(start 107.278424 -240.92789)
		(end 107.29976 -240.940082)
		(width 0.1143)
		(layer "In11.Cu")
		(net "P5E_CPU1_G1_TX_DN<4>")
	)
	(segment
		(start 107.265724 -233.468164)
		(end 107.263438 -233.469688)
		(width 0.1143)
		(layer "In11.Cu")
		(net "P5E_CPU1_G1_TX_DN<4>")
	)
	(segment
		(start 107.268772 -232.822242)
		(end 107.271566 -232.823766)
		(width 0.1143)
		(layer "In11.Cu")
		(net "P5E_CPU1_G1_TX_DN<4>")
	)
	(segment
		(start 107.266994 -236.06125)
		(end 107.26801 -236.061758)
		(width 0.1143)
		(layer "In11.Cu")
		(net "P5E_CPU1_G1_TX_DN<4>")
	)
	(segment
		(start 107.266994 -233.467402)
		(end 107.265724 -233.468164)
		(width 0.1143)
		(layer "In11.Cu")
		(net "P5E_CPU1_G1_TX_DN<4>")
	)
	(segment
		(start 107.229148 -226.31908)
		(end 107.268264 -226.34194)
		(width 0.1143)
		(layer "In11.Cu")
		(net "P5E_CPU1_G1_TX_DN<4>")
	)
	(segment
		(start 106.79811 -247.236996)
		(end 106.758994 -247.259856)
		(width 0.1143)
		(layer "In11.Cu")
		(net "P5E_CPU1_G1_TX_DN<4>")
	)
	(segment
		(start 107.272328 -236.704378)
		(end 107.271566 -236.704886)
		(width 0.1143)
		(layer "In11.Cu")
		(net "P5E_CPU1_G1_TX_DN<4>")
	)
	(segment
		(start 107.272328 -246.42445)
		(end 107.271566 -246.424958)
		(width 0.1143)
		(layer "In11.Cu")
		(net "P5E_CPU1_G1_TX_DN<4>")
	)
	(segment
		(start 107.268772 -241.566446)
		(end 107.26801 -241.566954)
		(width 0.1143)
		(layer "In11.Cu")
		(net "P5E_CPU1_G1_TX_DN<4>")
	)
	(segment
		(start 107.272328 -235.084366)
		(end 107.271566 -235.084874)
		(width 0.1143)
		(layer "In11.Cu")
		(net "P5E_CPU1_G1_TX_DN<4>")
	)
	(segment
		(start 107.277154 -236.067092)
		(end 107.278424 -236.067854)
		(width 0.1143)
		(layer "In11.Cu")
		(net "P5E_CPU1_G1_TX_DN<4>")
	)
	(segment
		(start 107.265216 -236.060234)
		(end 107.266994 -236.06125)
		(width 0.1143)
		(layer "In11.Cu")
		(net "P5E_CPU1_G1_TX_DN<4>")
	)
	(segment
		(start 107.265724 -244.808248)
		(end 107.263438 -244.809772)
		(width 0.1143)
		(layer "In11.Cu")
		(net "P5E_CPU1_G1_TX_DN<4>")
	)
	(segment
		(start 107.265724 -236.708188)
		(end 107.263438 -236.709712)
		(width 0.1143)
		(layer "In11.Cu")
		(net "P5E_CPU1_G1_TX_DN<4>")
	)
	(segment
		(start 107.274106 -236.065314)
		(end 107.276138 -236.066584)
		(width 0.1143)
		(layer "In11.Cu")
		(net "P5E_CPU1_G1_TX_DN<4>")
	)
	(segment
		(start 107.263438 -243.18976)
		(end 107.228894 -243.209826)
		(width 0.1143)
		(layer "In11.Cu")
		(net "P5E_CPU1_G1_TX_DN<4>")
	)
	(segment
		(start 107.272328 -240.924334)
		(end 107.273344 -240.924842)
		(width 0.1143)
		(layer "In11.Cu")
		(net "P5E_CPU1_G1_TX_DN<4>")
	)
	(segment
		(start 107.268772 -240.922302)
		(end 107.271566 -240.923826)
		(width 0.1143)
		(layer "In11.Cu")
		(net "P5E_CPU1_G1_TX_DN<4>")
	)
	(segment
		(start 107.276138 -244.166644)
		(end 107.277154 -244.167152)
		(width 0.1143)
		(layer "In11.Cu")
		(net "P5E_CPU1_G1_TX_DN<4>")
	)
	(segment
		(start 107.228894 -239.278922)
		(end 107.235752 -239.282986)
		(width 0.1143)
		(layer "In11.Cu")
		(net "P5E_CPU1_G1_TX_DN<4>")
	)
	(segment
		(start 149.824948 -136.515348)
		(end 154.342084 -145.855436)
		(width 0.14224)
		(layer "In11.Cu")
		(net "P5E_CPU1_G1_TX_DN<4>")
	)
	(segment
		(start 106.289094 -224.699068)
		(end 106.32821 -224.721928)
		(width 0.1143)
		(layer "In11.Cu")
		(net "P5E_CPU1_G1_TX_DN<4>")
	)
	(segment
		(start 106.045508 -222.61449)
		(end 106.045762 -222.61449)
		(width 0.1143)
		(layer "In11.Cu")
		(net "P5E_CPU1_G1_TX_DN<4>")
	)
	(segment
		(start 107.272328 -241.564414)
		(end 107.271566 -241.564922)
		(width 0.1143)
		(layer "In11.Cu")
		(net "P5E_CPU1_G1_TX_DN<4>")
	)
	(segment
		(start 107.235752 -236.042962)
		(end 107.236514 -236.04347)
		(width 0.1143)
		(layer "In11.Cu")
		(net "P5E_CPU1_G1_TX_DN<4>")
	)
	(segment
		(start 107.271566 -231.84485)
		(end 107.268772 -231.846374)
		(width 0.1143)
		(layer "In11.Cu")
		(net "P5E_CPU1_G1_TX_DN<4>")
	)
	(segment
		(start 106.515916 -221.707202)
		(end 106.515916 -221.804484)
		(width 0.1143)
		(layer "In11.Cu")
		(net "P5E_CPU1_G1_TX_DN<4>")
	)
	(segment
		(start 107.276138 -239.306608)
		(end 107.277154 -239.307116)
		(width 0.1143)
		(layer "In11.Cu")
		(net "P5E_CPU1_G1_TX_DN<4>")
	)
	(segment
		(start 107.265724 -231.848152)
		(end 107.263438 -231.849676)
		(width 0.1143)
		(layer "In11.Cu")
		(net "P5E_CPU1_G1_TX_DN<4>")
	)
	(segment
		(start 107.263692 -234.439206)
		(end 107.265216 -234.440222)
		(width 0.1143)
		(layer "In11.Cu")
		(net "P5E_CPU1_G1_TX_DN<4>")
	)
	(segment
		(start 107.263438 -239.949736)
		(end 107.228894 -239.969802)
		(width 0.1143)
		(layer "In11.Cu")
		(net "P5E_CPU1_G1_TX_DN<4>")
	)
	(segment
		(start 107.265724 -243.188236)
		(end 107.263438 -243.18976)
		(width 0.1143)
		(layer "In11.Cu")
		(net "P5E_CPU1_G1_TX_DN<4>")
	)
	(segment
		(start 107.27436 -244.803422)
		(end 107.272328 -244.804438)
		(width 0.1143)
		(layer "In11.Cu")
		(net "P5E_CPU1_G1_TX_DN<4>")
	)
	(segment
		(start 107.29976 -238.308642)
		(end 107.270042 -238.32566)
		(width 0.1143)
		(layer "In11.Cu")
		(net "P5E_CPU1_G1_TX_DN<4>")
	)
	(segment
		(start 106.35869 -223.729296)
		(end 106.32821 -223.747076)
		(width 0.1143)
		(layer "In11.Cu")
		(net "P5E_CPU1_G1_TX_DN<4>")
	)
	(segment
		(start 107.266994 -245.781322)
		(end 107.26801 -245.78183)
		(width 0.1143)
		(layer "In11.Cu")
		(net "P5E_CPU1_G1_TX_DN<4>")
	)
	(segment
		(start 107.261152 -239.297718)
		(end 107.262676 -239.298734)
		(width 0.1143)
		(layer "In11.Cu")
		(net "P5E_CPU1_G1_TX_DN<4>")
	)
	(segment
		(start 107.266994 -232.821226)
		(end 107.26801 -232.821734)
		(width 0.1143)
		(layer "In11.Cu")
		(net "P5E_CPU1_G1_TX_DN<4>")
	)
	(segment
		(start 107.277154 -234.44708)
		(end 107.278424 -234.447842)
		(width 0.1143)
		(layer "In11.Cu")
		(net "P5E_CPU1_G1_TX_DN<4>")
	)
	(segment
		(start 107.261152 -232.81767)
		(end 107.262676 -232.818686)
		(width 0.1143)
		(layer "In11.Cu")
		(net "P5E_CPU1_G1_TX_DN<4>")
	)
	(segment
		(start 107.268772 -231.846374)
		(end 107.26801 -231.846882)
		(width 0.1143)
		(layer "In11.Cu")
		(net "P5E_CPU1_G1_TX_DN<4>")
	)
	(segment
		(start 107.268772 -234.442254)
		(end 107.271566 -234.443778)
		(width 0.1143)
		(layer "In11.Cu")
		(net "P5E_CPU1_G1_TX_DN<4>")
	)
	(segment
		(start 107.266994 -234.441238)
		(end 107.26801 -234.441746)
		(width 0.1143)
		(layer "In11.Cu")
		(net "P5E_CPU1_G1_TX_DN<4>")
	)
	(segment
		(start 107.27436 -246.423434)
		(end 107.272328 -246.42445)
		(width 0.1143)
		(layer "In11.Cu")
		(net "P5E_CPU1_G1_TX_DN<4>")
	)
	(segment
		(start 57.174638 -53.206396)
		(end 149.824948 -136.515348)
		(width 0.14224)
		(layer "In11.Cu")
		(net "P5E_CPU1_G1_TX_DN<4>")
	)
	(segment
		(start 107.266994 -244.807486)
		(end 107.265724 -244.808248)
		(width 0.1143)
		(layer "In11.Cu")
		(net "P5E_CPU1_G1_TX_DN<4>")
	)
	(segment
		(start 107.265216 -244.160294)
		(end 107.266994 -244.16131)
		(width 0.1143)
		(layer "In11.Cu")
		(net "P5E_CPU1_G1_TX_DN<4>")
	)
	(segment
		(start 107.263438 -246.429784)
		(end 107.228894 -246.44985)
		(width 0.1143)
		(layer "In11.Cu")
		(net "P5E_CPU1_G1_TX_DN<4>")
	)
	(segment
		(start 107.26801 -238.32693)
		(end 107.266994 -238.327438)
		(width 0.1143)
		(layer "In11.Cu")
		(net "P5E_CPU1_G1_TX_DN<4>")
	)
	(segment
		(start 107.26547 -242.540282)
		(end 107.266994 -242.541298)
		(width 0.1143)
		(layer "In11.Cu")
		(net "P5E_CPU1_G1_TX_DN<4>")
	)
	(segment
		(start 107.277154 -240.927128)
		(end 107.278424 -240.92789)
		(width 0.1143)
		(layer "In11.Cu")
		(net "P5E_CPU1_G1_TX_DN<4>")
	)
	(segment
		(start 107.268772 -244.80647)
		(end 107.26801 -244.806978)
		(width 0.1143)
		(layer "In11.Cu")
		(net "P5E_CPU1_G1_TX_DN<4>")
	)
	(segment
		(start 107.273344 -244.164866)
		(end 107.274106 -244.165374)
		(width 0.1143)
		(layer "In11.Cu")
		(net "P5E_CPU1_G1_TX_DN<4>")
	)
	(segment
		(start 107.268264 -226.34194)
		(end 107.298744 -226.35972)
		(width 0.1143)
		(layer "In11.Cu")
		(net "P5E_CPU1_G1_TX_DN<4>")
	)
	(segment
		(start 107.26801 -236.706918)
		(end 107.266994 -236.707426)
		(width 0.1143)
		(layer "In11.Cu")
		(net "P5E_CPU1_G1_TX_DN<4>")
	)
	(segment
		(start 107.265724 -246.42826)
		(end 107.263438 -246.429784)
		(width 0.1143)
		(layer "In11.Cu")
		(net "P5E_CPU1_G1_TX_DN<4>")
	)
	(segment
		(start 107.29976 -236.68863)
		(end 107.27436 -236.703362)
		(width 0.1143)
		(layer "In11.Cu")
		(net "P5E_CPU1_G1_TX_DN<4>")
	)
	(segment
		(start 107.265724 -241.568224)
		(end 107.263438 -241.569748)
		(width 0.1143)
		(layer "In11.Cu")
		(net "P5E_CPU1_G1_TX_DN<4>")
	)
	(segment
		(start 107.273344 -239.30483)
		(end 107.274106 -239.305338)
		(width 0.1143)
		(layer "In11.Cu")
		(net "P5E_CPU1_G1_TX_DN<4>")
	)
	(segment
		(start 107.27436 -236.703362)
		(end 107.272328 -236.704378)
		(width 0.1143)
		(layer "In11.Cu")
		(net "P5E_CPU1_G1_TX_DN<4>")
	)
	(segment
		(start 107.271566 -239.303814)
		(end 107.272328 -239.304322)
		(width 0.1143)
		(layer "In11.Cu")
		(net "P5E_CPU1_G1_TX_DN<4>")
	)
	(segment
		(start 106.521758 -247.641618)
		(end 106.438954 -247.724422)
		(width 0.1143)
		(layer "In11.Cu")
		(net "P5E_CPU1_G1_TX_DN<4>")
	)
	(segment
		(start 107.235752 -244.143022)
		(end 107.236514 -244.14353)
		(width 0.1143)
		(layer "In11.Cu")
		(net "P5E_CPU1_G1_TX_DN<4>")
	)
	(segment
		(start 107.26801 -243.186966)
		(end 107.266994 -243.187474)
		(width 0.1143)
		(layer "In11.Cu")
		(net "P5E_CPU1_G1_TX_DN<4>")
	)
	(segment
		(start 107.27436 -231.843326)
		(end 107.272328 -231.844342)
		(width 0.1143)
		(layer "In11.Cu")
		(net "P5E_CPU1_G1_TX_DN<4>")
	)
	(segment
		(start 107.26801 -229.581964)
		(end 107.301538 -229.601522)
		(width 0.1143)
		(layer "In11.Cu")
		(net "P5E_CPU1_G1_TX_DN<4>")
	)
	(segment
		(start 107.263438 -244.809772)
		(end 107.228894 -244.829838)
		(width 0.1143)
		(layer "In11.Cu")
		(net "P5E_CPU1_G1_TX_DN<4>")
	)
	(segment
		(start 107.26801 -239.946942)
		(end 107.266994 -239.94745)
		(width 0.1143)
		(layer "In11.Cu")
		(net "P5E_CPU1_G1_TX_DN<4>")
	)
	(segment
		(start 107.26801 -233.466894)
		(end 107.266994 -233.467402)
		(width 0.1143)
		(layer "In11.Cu")
		(net "P5E_CPU1_G1_TX_DN<4>")
	)
	(segment
		(start 155.213304 -164.28339)
		(end 152.951434 -170.915584)
		(width 0.14224)
		(layer "In11.Cu")
		(net "P5E_CPU1_G1_TX_DN<4>")
	)
	(segment
		(start 107.262676 -240.918746)
		(end 107.263692 -240.919254)
		(width 0.1143)
		(layer "In11.Cu")
		(net "P5E_CPU1_G1_TX_DN<4>")
	)
	(segment
		(start 107.273344 -232.824782)
		(end 107.274106 -232.82529)
		(width 0.1143)
		(layer "In11.Cu")
		(net "P5E_CPU1_G1_TX_DN<4>")
	)
	(segment
		(start 107.266994 -240.921286)
		(end 107.26801 -240.921794)
		(width 0.1143)
		(layer "In11.Cu")
		(net "P5E_CPU1_G1_TX_DN<4>")
	)
	(segment
		(start 107.228894 -244.138958)
		(end 107.235752 -244.143022)
		(width 0.1143)
		(layer "In11.Cu")
		(net "P5E_CPU1_G1_TX_DN<4>")
	)
	(segment
		(start 107.265724 -239.948212)
		(end 107.263438 -239.949736)
		(width 0.1143)
		(layer "In11.Cu")
		(net "P5E_CPU1_G1_TX_DN<4>")
	)
	(segment
		(start 107.272328 -232.824274)
		(end 107.273344 -232.824782)
		(width 0.1143)
		(layer "In11.Cu")
		(net "P5E_CPU1_G1_TX_DN<4>")
	)
	(segment
		(start 107.26801 -246.42699)
		(end 107.266994 -246.427498)
		(width 0.1143)
		(layer "In11.Cu")
		(net "P5E_CPU1_G1_TX_DN<4>")
	)
	(segment
		(start 107.236514 -239.283494)
		(end 107.261152 -239.297718)
		(width 0.1143)
		(layer "In11.Cu")
		(net "P5E_CPU1_G1_TX_DN<4>")
	)
	(segment
		(start 107.263438 -235.0897)
		(end 107.228894 -235.109766)
		(width 0.1143)
		(layer "In11.Cu")
		(net "P5E_CPU1_G1_TX_DN<4>")
	)
	(segment
		(start 107.268772 -243.186458)
		(end 107.26801 -243.186966)
		(width 0.1143)
		(layer "In11.Cu")
		(net "P5E_CPU1_G1_TX_DN<4>")
	)
	(segment
		(start 107.262676 -239.298734)
		(end 107.263692 -239.299242)
		(width 0.1143)
		(layer "In11.Cu")
		(net "P5E_CPU1_G1_TX_DN<4>")
	)
	(segment
		(start 107.261152 -234.437682)
		(end 107.262676 -234.438698)
		(width 0.1143)
		(layer "In11.Cu")
		(net "P5E_CPU1_G1_TX_DN<4>")
	)
	(segment
		(start 107.277154 -239.307116)
		(end 107.278424 -239.307878)
		(width 0.1143)
		(layer "In11.Cu")
		(net "P5E_CPU1_G1_TX_DN<4>")
	)
	(segment
		(start 107.274106 -232.82529)
		(end 107.276138 -232.82656)
		(width 0.1143)
		(layer "In11.Cu")
		(net "P5E_CPU1_G1_TX_DN<4>")
	)
	(segment
		(start 107.236514 -236.04347)
		(end 107.261152 -236.057694)
		(width 0.1143)
		(layer "In11.Cu")
		(net "P5E_CPU1_G1_TX_DN<4>")
	)
	(segment
		(start 107.270042 -238.32566)
		(end 107.268772 -238.326422)
		(width 0.1143)
		(layer "In11.Cu")
		(net "P5E_CPU1_G1_TX_DN<4>")
	)
	(arc
		(start 107.298744 -227.979732)
		(mid 107.455721 -228.284532)
		(end 107.298744 -228.589332)
		(width 0.1143)
		(layer "In11.Cu")
		(net "P5E_CPU1_G1_TX_DN<4>")
	)
	(arc
		(start 107.229148 -227.00996)
		(mid 106.985821 -227.474526)
		(end 107.229148 -227.939092)
		(width 0.1143)
		(layer "In11.Cu")
		(net "P5E_CPU1_G1_TX_DN<4>")
	)
	(arc
		(start 107.228894 -233.489754)
		(mid 106.985567 -233.95432)
		(end 107.228894 -234.418886)
		(width 0.1143)
		(layer "In11.Cu")
		(net "P5E_CPU1_G1_TX_DN<4>")
	)
	(arc
		(start 106.758994 -247.259856)
		(mid 106.607007 -247.416364)
		(end 106.525568 -247.618758)
		(width 0.1143)
		(layer "In11.Cu")
		(net "P5E_CPU1_G1_TX_DN<4>")
	)
	(arc
		(start 107.301538 -231.221534)
		(mid 107.414945 -231.354423)
		(end 107.455716 -231.524302)
		(width 0.1143)
		(layer "In11.Cu")
		(net "P5E_CPU1_G1_TX_DN<4>")
	)
	(arc
		(start 106.045762 -222.61449)
		(mid 106.110277 -222.876709)
		(end 106.289094 -223.079056)
		(width 0.1143)
		(layer "In11.Cu")
		(net "P5E_CPU1_G1_TX_DN<4>")
	)
	(arc
		(start 107.228894 -231.869742)
		(mid 106.985567 -232.334308)
		(end 107.228894 -232.798874)
		(width 0.1143)
		(layer "In11.Cu")
		(net "P5E_CPU1_G1_TX_DN<4>")
	)
	(arc
		(start 107.228894 -235.109766)
		(mid 106.985567 -235.574332)
		(end 107.228894 -236.038898)
		(width 0.1143)
		(layer "In11.Cu")
		(net "P5E_CPU1_G1_TX_DN<4>")
	)
	(arc
		(start 107.29976 -237.700058)
		(mid 107.455688 -238.00435)
		(end 107.29976 -238.308642)
		(width 0.1143)
		(layer "In11.Cu")
		(net "P5E_CPU1_G1_TX_DN<4>")
	)
	(arc
		(start 107.29976 -240.940082)
		(mid 107.455688 -241.244374)
		(end 107.29976 -241.548666)
		(width 0.1143)
		(layer "In11.Cu")
		(net "P5E_CPU1_G1_TX_DN<4>")
	)
	(arc
		(start 106.515662 -225.044508)
		(mid 106.580177 -225.306727)
		(end 106.758994 -225.509074)
		(width 0.1143)
		(layer "In11.Cu")
		(net "P5E_CPU1_G1_TX_DN<4>")
	)
	(arc
		(start 107.228894 -246.44985)
		(mid 107.050081 -246.6522)
		(end 106.985562 -246.914416)
		(width 0.1143)
		(layer "In11.Cu")
		(net "P5E_CPU1_G1_TX_DN<4>")
	)
	(arc
		(start 106.985562 -230.71455)
		(mid 107.050077 -230.976769)
		(end 107.228894 -231.179116)
		(width 0.1143)
		(layer "In11.Cu")
		(net "P5E_CPU1_G1_TX_DN<4>")
	)
	(arc
		(start 107.228894 -228.629972)
		(mid 106.985567 -229.094538)
		(end 107.228894 -229.559104)
		(width 0.1143)
		(layer "In11.Cu")
		(net "P5E_CPU1_G1_TX_DN<4>")
	)
	(arc
		(start 106.35869 -223.119696)
		(mid 106.515667 -223.424496)
		(end 106.35869 -223.729296)
		(width 0.1143)
		(layer "In11.Cu")
		(net "P5E_CPU1_G1_TX_DN<4>")
	)
	(arc
		(start 107.455716 -229.90429)
		(mid 107.414461 -230.075261)
		(end 107.29976 -230.208582)
		(width 0.1143)
		(layer "In11.Cu")
		(net "P5E_CPU1_G1_TX_DN<4>")
	)
	(arc
		(start 106.515916 -221.804484)
		(mid 106.474661 -221.975455)
		(end 106.35996 -222.108776)
		(width 0.1143)
		(layer "In11.Cu")
		(net "P5E_CPU1_G1_TX_DN<4>")
	)
	(arc
		(start 107.455716 -231.524302)
		(mid 107.414461 -231.695273)
		(end 107.29976 -231.828594)
		(width 0.1143)
		(layer "In11.Cu")
		(net "P5E_CPU1_G1_TX_DN<4>")
	)
	(arc
		(start 106.985562 -246.914416)
		(mid 106.944013 -247.085838)
		(end 106.82859 -247.219216)
		(width 0.1143)
		(layer "In11.Cu")
		(net "P5E_CPU1_G1_TX_DN<4>")
	)
	(arc
		(start 107.29976 -239.32007)
		(mid 107.455688 -239.624362)
		(end 107.29976 -239.928654)
		(width 0.1143)
		(layer "In11.Cu")
		(net "P5E_CPU1_G1_TX_DN<4>")
	)
	(arc
		(start 107.231434 -230.248206)
		(mid 107.050782 -230.450951)
		(end 106.985562 -230.71455)
		(width 0.1143)
		(layer "In11.Cu")
		(net "P5E_CPU1_G1_TX_DN<4>")
	)
	(arc
		(start 107.29976 -232.840022)
		(mid 107.455688 -233.144314)
		(end 107.29976 -233.448606)
		(width 0.1143)
		(layer "In11.Cu")
		(net "P5E_CPU1_G1_TX_DN<4>")
	)
	(arc
		(start 107.228894 -244.829838)
		(mid 106.985567 -245.294404)
		(end 107.228894 -245.75897)
		(width 0.1143)
		(layer "In11.Cu")
		(net "P5E_CPU1_G1_TX_DN<4>")
	)
	(arc
		(start 107.228894 -238.34979)
		(mid 106.985567 -238.814356)
		(end 107.228894 -239.278922)
		(width 0.1143)
		(layer "In11.Cu")
		(net "P5E_CPU1_G1_TX_DN<4>")
	)
	(arc
		(start 106.35869 -224.739708)
		(mid 106.474117 -224.873084)
		(end 106.515662 -225.044508)
		(width 0.1143)
		(layer "In11.Cu")
		(net "P5E_CPU1_G1_TX_DN<4>")
	)
	(arc
		(start 107.29976 -244.180106)
		(mid 107.455688 -244.484398)
		(end 107.29976 -244.78869)
		(width 0.1143)
		(layer "In11.Cu")
		(net "P5E_CPU1_G1_TX_DN<4>")
	)
	(arc
		(start 106.289094 -223.769936)
		(mid 106.045767 -224.234502)
		(end 106.289094 -224.699068)
		(width 0.1143)
		(layer "In11.Cu")
		(net "P5E_CPU1_G1_TX_DN<4>")
	)
	(arc
		(start 106.82986 -225.550222)
		(mid 106.944536 -225.683556)
		(end 106.985816 -225.854514)
		(width 0.1143)
		(layer "In11.Cu")
		(net "P5E_CPU1_G1_TX_DN<4>")
	)
	(arc
		(start 106.985816 -225.854514)
		(mid 107.050331 -226.116733)
		(end 107.229148 -226.31908)
		(width 0.1143)
		(layer "In11.Cu")
		(net "P5E_CPU1_G1_TX_DN<4>")
	)
	(arc
		(start 107.29976 -245.800118)
		(mid 107.455688 -246.10441)
		(end 107.29976 -246.408702)
		(width 0.1143)
		(layer "In11.Cu")
		(net "P5E_CPU1_G1_TX_DN<4>")
	)
	(arc
		(start 107.29976 -242.560094)
		(mid 107.455688 -242.864386)
		(end 107.29976 -243.168678)
		(width 0.1143)
		(layer "In11.Cu")
		(net "P5E_CPU1_G1_TX_DN<4>")
	)
	(arc
		(start 106.28884 -222.149924)
		(mid 106.110027 -222.352274)
		(end 106.045508 -222.61449)
		(width 0.1143)
		(layer "In11.Cu")
		(net "P5E_CPU1_G1_TX_DN<4>")
	)
	(arc
		(start 107.29976 -236.080046)
		(mid 107.455688 -236.384338)
		(end 107.29976 -236.68863)
		(width 0.1143)
		(layer "In11.Cu")
		(net "P5E_CPU1_G1_TX_DN<4>")
	)
	(arc
		(start 107.228894 -243.209826)
		(mid 106.985567 -243.674392)
		(end 107.228894 -244.138958)
		(width 0.1143)
		(layer "In11.Cu")
		(net "P5E_CPU1_G1_TX_DN<4>")
	)
	(arc
		(start 106.525568 -247.618758)
		(mid 106.523545 -247.630168)
		(end 106.521758 -247.641618)
		(width 0.1143)
		(layer "In11.Cu")
		(net "P5E_CPU1_G1_TX_DN<4>")
	)
	(arc
		(start 107.298744 -226.35972)
		(mid 107.455721 -226.66452)
		(end 107.298744 -226.96932)
		(width 0.1143)
		(layer "In11.Cu")
		(net "P5E_CPU1_G1_TX_DN<4>")
	)
	(arc
		(start 107.228894 -236.729778)
		(mid 106.985567 -237.194344)
		(end 107.228894 -237.65891)
		(width 0.1143)
		(layer "In11.Cu")
		(net "P5E_CPU1_G1_TX_DN<4>")
	)
	(arc
		(start 107.228894 -239.969802)
		(mid 106.985567 -240.434368)
		(end 107.228894 -240.898934)
		(width 0.1143)
		(layer "In11.Cu")
		(net "P5E_CPU1_G1_TX_DN<4>")
	)
	(arc
		(start 107.228894 -241.589814)
		(mid 106.985567 -242.05438)
		(end 107.228894 -242.518946)
		(width 0.1143)
		(layer "In11.Cu")
		(net "P5E_CPU1_G1_TX_DN<4>")
	)
	(arc
		(start 107.301538 -229.601522)
		(mid 107.414945 -229.734411)
		(end 107.455716 -229.90429)
		(width 0.1143)
		(layer "In11.Cu")
		(net "P5E_CPU1_G1_TX_DN<4>")
	)
	(arc
		(start 107.29976 -234.460034)
		(mid 107.455688 -234.764326)
		(end 107.29976 -235.068618)
		(width 0.1143)
		(layer "In11.Cu")
		(net "P5E_CPU1_G1_TX_DN<4>")
	)
	(segment
		(start 49.342294 -16.366236)
		(end 49.638204 -16.662146)
		(width 0.12954)
		(layer "F.Cu")
		(net "P5E_CPU1_G1_TX_DN<3>")
	)
	(segment
		(start 49.638204 -16.662146)
		(end 49.638204 -17.34185)
		(width 0.12954)
		(layer "F.Cu")
		(net "P5E_CPU1_G1_TX_DN<3>")
	)
	(segment
		(start 108.957872 -245.560342)
		(end 108.49102 -245.294404)
		(width 0.12954)
		(layer "F.Cu")
		(net "P5E_CPU1_G1_TX_DN<3>")
	)
	(segment
		(start 49.638204 -17.34185)
		(end 49.367694 -17.61236)
		(width 0.12954)
		(layer "F.Cu")
		(net "P5E_CPU1_G1_TX_DN<3>")
	)
	(segment
		(start 108.21162 -238.324898)
		(end 108.208826 -238.326422)
		(width 0.1143)
		(layer "In11.Cu")
		(net "P5E_CPU1_G1_TX_DN<3>")
	)
	(segment
		(start 108.239814 -228.588824)
		(end 108.215938 -228.60254)
		(width 0.1143)
		(layer "In11.Cu")
		(net "P5E_CPU1_G1_TX_DN<3>")
	)
	(segment
		(start 108.214668 -228.603302)
		(end 108.213906 -228.60381)
		(width 0.1143)
		(layer "In11.Cu")
		(net "P5E_CPU1_G1_TX_DN<3>")
	)
	(segment
		(start 108.215684 -235.082588)
		(end 108.214668 -235.083096)
		(width 0.1143)
		(layer "In11.Cu")
		(net "P5E_CPU1_G1_TX_DN<3>")
	)
	(segment
		(start 108.212382 -232.824274)
		(end 108.239814 -232.840022)
		(width 0.1143)
		(layer "In11.Cu")
		(net "P5E_CPU1_G1_TX_DN<3>")
	)
	(segment
		(start 108.215684 -238.322612)
		(end 108.214668 -238.32312)
		(width 0.1143)
		(layer "In11.Cu")
		(net "P5E_CPU1_G1_TX_DN<3>")
	)
	(segment
		(start 108.208826 -236.70641)
		(end 108.208064 -236.706918)
		(width 0.1143)
		(layer "In11.Cu")
		(net "P5E_CPU1_G1_TX_DN<3>")
	)
	(segment
		(start 108.21162 -241.564922)
		(end 108.208826 -241.566446)
		(width 0.1143)
		(layer "In11.Cu")
		(net "P5E_CPU1_G1_TX_DN<3>")
	)
	(segment
		(start 107.32008 -223.71431)
		(end 107.300014 -223.728788)
		(width 0.1143)
		(layer "In11.Cu")
		(net "P5E_CPU1_G1_TX_DN<3>")
	)
	(segment
		(start 49.367694 -17.61236)
		(end 49.658524 -17.90319)
		(width 0.14224)
		(layer "In11.Cu")
		(net "P5E_CPU1_G1_TX_DN<3>")
	)
	(segment
		(start 108.175806 -232.802938)
		(end 108.176568 -232.803446)
		(width 0.1143)
		(layer "In11.Cu")
		(net "P5E_CPU1_G1_TX_DN<3>")
	)
	(segment
		(start 108.639102 -244.948964)
		(end 108.678218 -244.971824)
		(width 0.1143)
		(layer "In11.Cu")
		(net "P5E_CPU1_G1_TX_DN<3>")
	)
	(segment
		(start 107.268264 -223.747076)
		(end 107.267248 -223.747584)
		(width 0.1143)
		(layer "In11.Cu")
		(net "P5E_CPU1_G1_TX_DN<3>")
	)
	(segment
		(start 108.214668 -239.943132)
		(end 108.213906 -239.94364)
		(width 0.1143)
		(layer "In11.Cu")
		(net "P5E_CPU1_G1_TX_DN<3>")
	)
	(segment
		(start 108.199682 -226.337114)
		(end 108.204508 -226.339908)
		(width 0.1143)
		(layer "In11.Cu")
		(net "P5E_CPU1_G1_TX_DN<3>")
	)
	(segment
		(start 108.212382 -243.184426)
		(end 108.21162 -243.184934)
		(width 0.1143)
		(layer "In11.Cu")
		(net "P5E_CPU1_G1_TX_DN<3>")
	)
	(segment
		(start 108.207048 -228.60762)
		(end 108.168948 -228.629972)
		(width 0.1143)
		(layer "In11.Cu")
		(net "P5E_CPU1_G1_TX_DN<3>")
	)
	(segment
		(start 108.207048 -233.467402)
		(end 108.168948 -233.489754)
		(width 0.1143)
		(layer "In11.Cu")
		(net "P5E_CPU1_G1_TX_DN<3>")
	)
	(segment
		(start 107.237784 -223.08439)
		(end 107.300014 -223.120204)
		(width 0.1143)
		(layer "In11.Cu")
		(net "P5E_CPU1_G1_TX_DN<3>")
	)
	(segment
		(start 108.207048 -232.821226)
		(end 108.208064 -232.821734)
		(width 0.1143)
		(layer "In11.Cu")
		(net "P5E_CPU1_G1_TX_DN<3>")
	)
	(segment
		(start 106.98607 -224.234502)
		(end 106.987594 -224.25914)
		(width 0.1143)
		(layer "In11.Cu")
		(net "P5E_CPU1_G1_TX_DN<3>")
	)
	(segment
		(start 108.213906 -235.083604)
		(end 108.212382 -235.084366)
		(width 0.1143)
		(layer "In11.Cu")
		(net "P5E_CPU1_G1_TX_DN<3>")
	)
	(segment
		(start 108.168948 -234.418886)
		(end 108.175806 -234.42295)
		(width 0.1143)
		(layer "In11.Cu")
		(net "P5E_CPU1_G1_TX_DN<3>")
	)
	(segment
		(start 108.214668 -235.083096)
		(end 108.213906 -235.083604)
		(width 0.1143)
		(layer "In11.Cu")
		(net "P5E_CPU1_G1_TX_DN<3>")
	)
	(segment
		(start 108.212382 -233.464354)
		(end 108.21162 -233.464862)
		(width 0.1143)
		(layer "In11.Cu")
		(net "P5E_CPU1_G1_TX_DN<3>")
	)
	(segment
		(start 108.208064 -238.32693)
		(end 108.207048 -238.327438)
		(width 0.1143)
		(layer "In11.Cu")
		(net "P5E_CPU1_G1_TX_DN<3>")
	)
	(segment
		(start 108.175806 -240.902998)
		(end 108.176568 -240.903506)
		(width 0.1143)
		(layer "In11.Cu")
		(net "P5E_CPU1_G1_TX_DN<3>")
	)
	(segment
		(start 108.239814 -243.168678)
		(end 108.215684 -243.182648)
		(width 0.1143)
		(layer "In11.Cu")
		(net "P5E_CPU1_G1_TX_DN<3>")
	)
	(segment
		(start 108.168948 -231.179116)
		(end 108.208064 -231.201976)
		(width 0.1143)
		(layer "In11.Cu")
		(net "P5E_CPU1_G1_TX_DN<3>")
	)
	(segment
		(start 108.176568 -236.04347)
		(end 108.207048 -236.06125)
		(width 0.1143)
		(layer "In11.Cu")
		(net "P5E_CPU1_G1_TX_DN<3>")
	)
	(segment
		(start 108.212382 -236.704378)
		(end 108.21162 -236.704886)
		(width 0.1143)
		(layer "In11.Cu")
		(net "P5E_CPU1_G1_TX_DN<3>")
	)
	(segment
		(start 108.239814 -235.068618)
		(end 108.215684 -235.082588)
		(width 0.1143)
		(layer "In11.Cu")
		(net "P5E_CPU1_G1_TX_DN<3>")
	)
	(segment
		(start 108.215684 -233.462576)
		(end 108.214668 -233.463084)
		(width 0.1143)
		(layer "In11.Cu")
		(net "P5E_CPU1_G1_TX_DN<3>")
	)
	(segment
		(start 108.208064 -226.34194)
		(end 108.208826 -226.342448)
		(width 0.1143)
		(layer "In11.Cu")
		(net "P5E_CPU1_G1_TX_DN<3>")
	)
	(segment
		(start 108.239814 -231.828594)
		(end 108.210096 -231.845612)
		(width 0.1143)
		(layer "In11.Cu")
		(net "P5E_CPU1_G1_TX_DN<3>")
	)
	(segment
		(start 107.272836 -223.744282)
		(end 107.272074 -223.74479)
		(width 0.1143)
		(layer "In11.Cu")
		(net "P5E_CPU1_G1_TX_DN<3>")
	)
	(segment
		(start 49.658524 -20.222464)
		(end 55.711598 -48.782478)
		(width 0.14224)
		(layer "In11.Cu")
		(net "P5E_CPU1_G1_TX_DN<3>")
	)
	(segment
		(start 108.21416 -226.345496)
		(end 108.2167 -226.346766)
		(width 0.1143)
		(layer "In11.Cu")
		(net "P5E_CPU1_G1_TX_DN<3>")
	)
	(segment
		(start 108.212382 -244.164358)
		(end 108.239814 -244.180106)
		(width 0.1143)
		(layer "In11.Cu")
		(net "P5E_CPU1_G1_TX_DN<3>")
	)
	(segment
		(start 108.168948 -226.31908)
		(end 108.198158 -226.336098)
		(width 0.1143)
		(layer "In11.Cu")
		(net "P5E_CPU1_G1_TX_DN<3>")
	)
	(segment
		(start 108.788962 -245.294404)
		(end 108.49102 -245.294404)
		(width 0.1143)
		(layer "In11.Cu")
		(net "P5E_CPU1_G1_TX_DN<3>")
	)
	(segment
		(start 108.208064 -226.9871)
		(end 108.207048 -226.987608)
		(width 0.1143)
		(layer "In11.Cu")
		(net "P5E_CPU1_G1_TX_DN<3>")
	)
	(segment
		(start 108.215684 -243.182648)
		(end 108.214668 -243.183156)
		(width 0.1143)
		(layer "In11.Cu")
		(net "P5E_CPU1_G1_TX_DN<3>")
	)
	(segment
		(start 108.208064 -240.921794)
		(end 108.208826 -240.922302)
		(width 0.1143)
		(layer "In11.Cu")
		(net "P5E_CPU1_G1_TX_DN<3>")
	)
	(segment
		(start 108.239814 -238.308642)
		(end 108.215684 -238.322612)
		(width 0.1143)
		(layer "In11.Cu")
		(net "P5E_CPU1_G1_TX_DN<3>")
	)
	(segment
		(start 108.215684 -241.562636)
		(end 108.214668 -241.563144)
		(width 0.1143)
		(layer "In11.Cu")
		(net "P5E_CPU1_G1_TX_DN<3>")
	)
	(segment
		(start 108.212382 -226.34448)
		(end 108.213398 -226.344988)
		(width 0.1143)
		(layer "In11.Cu")
		(net "P5E_CPU1_G1_TX_DN<3>")
	)
	(segment
		(start 107.229402 -224.699068)
		(end 107.268518 -224.721928)
		(width 0.1143)
		(layer "In11.Cu")
		(net "P5E_CPU1_G1_TX_DN<3>")
	)
	(segment
		(start 108.207048 -240.921286)
		(end 108.208064 -240.921794)
		(width 0.1143)
		(layer "In11.Cu")
		(net "P5E_CPU1_G1_TX_DN<3>")
	)
	(segment
		(start 108.207048 -244.16131)
		(end 108.208064 -244.161818)
		(width 0.1143)
		(layer "In11.Cu")
		(net "P5E_CPU1_G1_TX_DN<3>")
	)
	(segment
		(start 108.168948 -237.65891)
		(end 108.175806 -237.662974)
		(width 0.1143)
		(layer "In11.Cu")
		(net "P5E_CPU1_G1_TX_DN<3>")
	)
	(segment
		(start 108.212382 -228.604572)
		(end 108.21162 -228.60508)
		(width 0.1143)
		(layer "In11.Cu")
		(net "P5E_CPU1_G1_TX_DN<3>")
	)
	(segment
		(start 108.239814 -236.68863)
		(end 108.215684 -236.7026)
		(width 0.1143)
		(layer "In11.Cu")
		(net "P5E_CPU1_G1_TX_DN<3>")
	)
	(segment
		(start 108.208064 -233.466894)
		(end 108.207048 -233.467402)
		(width 0.1143)
		(layer "In11.Cu")
		(net "P5E_CPU1_G1_TX_DN<3>")
	)
	(segment
		(start 150.585678 -135.934704)
		(end 155.269184 -145.619978)
		(width 0.14224)
		(layer "In11.Cu")
		(net "P5E_CPU1_G1_TX_DN<3>")
	)
	(segment
		(start 108.239814 -233.448606)
		(end 108.215684 -233.462576)
		(width 0.1143)
		(layer "In11.Cu")
		(net "P5E_CPU1_G1_TX_DN<3>")
	)
	(segment
		(start 55.711598 -48.782478)
		(end 57.92089 -52.607972)
		(width 0.14224)
		(layer "In11.Cu")
		(net "P5E_CPU1_G1_TX_DN<3>")
	)
	(segment
		(start 108.678218 -244.971824)
		(end 108.708698 -244.989604)
		(width 0.1143)
		(layer "In11.Cu")
		(net "P5E_CPU1_G1_TX_DN<3>")
	)
	(segment
		(start 108.207048 -226.341432)
		(end 108.208064 -226.34194)
		(width 0.1143)
		(layer "In11.Cu")
		(net "P5E_CPU1_G1_TX_DN<3>")
	)
	(segment
		(start 108.207048 -227.961444)
		(end 108.208064 -227.961952)
		(width 0.1143)
		(layer "In11.Cu")
		(net "P5E_CPU1_G1_TX_DN<3>")
	)
	(segment
		(start 108.207048 -242.541298)
		(end 108.208064 -242.541806)
		(width 0.1143)
		(layer "In11.Cu")
		(net "P5E_CPU1_G1_TX_DN<3>")
	)
	(segment
		(start 108.208064 -242.541806)
		(end 108.208826 -242.542314)
		(width 0.1143)
		(layer "In11.Cu")
		(net "P5E_CPU1_G1_TX_DN<3>")
	)
	(segment
		(start 108.168948 -240.898934)
		(end 108.175806 -240.902998)
		(width 0.1143)
		(layer "In11.Cu")
		(net "P5E_CPU1_G1_TX_DN<3>")
	)
	(segment
		(start 108.214668 -233.463084)
		(end 108.213906 -233.463592)
		(width 0.1143)
		(layer "In11.Cu")
		(net "P5E_CPU1_G1_TX_DN<3>")
	)
	(segment
		(start 108.213906 -236.703616)
		(end 108.212382 -236.704378)
		(width 0.1143)
		(layer "In11.Cu")
		(net "P5E_CPU1_G1_TX_DN<3>")
	)
	(segment
		(start 108.207048 -243.187474)
		(end 108.168948 -243.209826)
		(width 0.1143)
		(layer "In11.Cu")
		(net "P5E_CPU1_G1_TX_DN<3>")
	)
	(segment
		(start 108.21162 -236.704886)
		(end 108.208826 -236.70641)
		(width 0.1143)
		(layer "In11.Cu")
		(net "P5E_CPU1_G1_TX_DN<3>")
	)
	(segment
		(start 108.2167 -226.346766)
		(end 108.239814 -226.360228)
		(width 0.1143)
		(layer "In11.Cu")
		(net "P5E_CPU1_G1_TX_DN<3>")
	)
	(segment
		(start 108.208064 -227.961952)
		(end 108.208826 -227.96246)
		(width 0.1143)
		(layer "In11.Cu")
		(net "P5E_CPU1_G1_TX_DN<3>")
	)
	(segment
		(start 108.168948 -242.518946)
		(end 108.175806 -242.52301)
		(width 0.1143)
		(layer "In11.Cu")
		(net "P5E_CPU1_G1_TX_DN<3>")
	)
	(segment
		(start 108.214668 -243.183156)
		(end 108.213906 -243.183664)
		(width 0.1143)
		(layer "In11.Cu")
		(net "P5E_CPU1_G1_TX_DN<3>")
	)
	(segment
		(start 108.21162 -235.084874)
		(end 108.208826 -235.086398)
		(width 0.1143)
		(layer "In11.Cu")
		(net "P5E_CPU1_G1_TX_DN<3>")
	)
	(segment
		(start 108.208064 -231.201976)
		(end 108.241592 -231.221534)
		(width 0.1143)
		(layer "In11.Cu")
		(net "P5E_CPU1_G1_TX_DN<3>")
	)
	(segment
		(start 108.168948 -232.798874)
		(end 108.175806 -232.802938)
		(width 0.1143)
		(layer "In11.Cu")
		(net "P5E_CPU1_G1_TX_DN<3>")
	)
	(segment
		(start 108.208064 -244.161818)
		(end 108.208826 -244.162326)
		(width 0.1143)
		(layer "In11.Cu")
		(net "P5E_CPU1_G1_TX_DN<3>")
	)
	(segment
		(start 108.213906 -241.563652)
		(end 108.212382 -241.564414)
		(width 0.1143)
		(layer "In11.Cu")
		(net "P5E_CPU1_G1_TX_DN<3>")
	)
	(segment
		(start 108.168948 -236.038898)
		(end 108.175806 -236.042962)
		(width 0.1143)
		(layer "In11.Cu")
		(net "P5E_CPU1_G1_TX_DN<3>")
	)
	(segment
		(start 108.239814 -226.968812)
		(end 108.208826 -226.986592)
		(width 0.1143)
		(layer "In11.Cu")
		(net "P5E_CPU1_G1_TX_DN<3>")
	)
	(segment
		(start 107.400598 -215.319864)
		(end 107.400598 -221.05493)
		(width 0.14224)
		(layer "In11.Cu")
		(net "P5E_CPU1_G1_TX_DN<3>")
	)
	(segment
		(start 108.176568 -232.803446)
		(end 108.207048 -232.821226)
		(width 0.1143)
		(layer "In11.Cu")
		(net "P5E_CPU1_G1_TX_DN<3>")
	)
	(segment
		(start 107.701842 -225.510852)
		(end 107.738164 -225.531934)
		(width 0.1143)
		(layer "In11.Cu")
		(net "P5E_CPU1_G1_TX_DN<3>")
	)
	(segment
		(start 108.198158 -226.336098)
		(end 108.199682 -226.337114)
		(width 0.1143)
		(layer "In11.Cu")
		(net "P5E_CPU1_G1_TX_DN<3>")
	)
	(segment
		(start 108.210096 -227.963222)
		(end 108.21162 -227.963984)
		(width 0.1143)
		(layer "In11.Cu")
		(net "P5E_CPU1_G1_TX_DN<3>")
	)
	(segment
		(start 108.207048 -237.681262)
		(end 108.208064 -237.68177)
		(width 0.1143)
		(layer "In11.Cu")
		(net "P5E_CPU1_G1_TX_DN<3>")
	)
	(segment
		(start 108.208064 -230.22687)
		(end 108.171488 -230.248206)
		(width 0.1143)
		(layer "In11.Cu")
		(net "P5E_CPU1_G1_TX_DN<3>")
	)
	(segment
		(start 108.208826 -243.186458)
		(end 108.208064 -243.186966)
		(width 0.1143)
		(layer "In11.Cu")
		(net "P5E_CPU1_G1_TX_DN<3>")
	)
	(segment
		(start 108.207048 -238.327438)
		(end 108.168948 -238.34979)
		(width 0.1143)
		(layer "In11.Cu")
		(net "P5E_CPU1_G1_TX_DN<3>")
	)
	(segment
		(start 108.212382 -242.544346)
		(end 108.239814 -242.560094)
		(width 0.1143)
		(layer "In11.Cu")
		(net "P5E_CPU1_G1_TX_DN<3>")
	)
	(segment
		(start 108.208826 -239.946434)
		(end 108.208064 -239.946942)
		(width 0.1143)
		(layer "In11.Cu")
		(net "P5E_CPU1_G1_TX_DN<3>")
	)
	(segment
		(start 108.212382 -237.68431)
		(end 108.239814 -237.700058)
		(width 0.1143)
		(layer "In11.Cu")
		(net "P5E_CPU1_G1_TX_DN<3>")
	)
	(segment
		(start 108.21162 -242.543838)
		(end 108.212382 -242.544346)
		(width 0.1143)
		(layer "In11.Cu")
		(net "P5E_CPU1_G1_TX_DN<3>")
	)
	(segment
		(start 108.207048 -236.06125)
		(end 108.208064 -236.061758)
		(width 0.1143)
		(layer "In11.Cu")
		(net "P5E_CPU1_G1_TX_DN<3>")
	)
	(segment
		(start 108.214668 -236.703108)
		(end 108.213906 -236.703616)
		(width 0.1143)
		(layer "In11.Cu")
		(net "P5E_CPU1_G1_TX_DN<3>")
	)
	(segment
		(start 108.207048 -226.987608)
		(end 108.168948 -227.00996)
		(width 0.1143)
		(layer "In11.Cu")
		(net "P5E_CPU1_G1_TX_DN<3>")
	)
	(segment
		(start 107.45597 -221.617032)
		(end 107.45597 -221.804484)
		(width 0.1143)
		(layer "In11.Cu")
		(net "P5E_CPU1_G1_TX_DN<3>")
	)
	(segment
		(start 156.153358 -159.767016)
		(end 156.153358 -164.457126)
		(width 0.14224)
		(layer "In11.Cu")
		(net "P5E_CPU1_G1_TX_DN<3>")
	)
	(segment
		(start 108.239814 -230.208582)
		(end 108.208064 -230.22687)
		(width 0.1143)
		(layer "In11.Cu")
		(net "P5E_CPU1_G1_TX_DN<3>")
	)
	(segment
		(start 108.207048 -234.441238)
		(end 108.208064 -234.441746)
		(width 0.1143)
		(layer "In11.Cu")
		(net "P5E_CPU1_G1_TX_DN<3>")
	)
	(segment
		(start 108.21162 -237.683802)
		(end 108.212382 -237.68431)
		(width 0.1143)
		(layer "In11.Cu")
		(net "P5E_CPU1_G1_TX_DN<3>")
	)
	(segment
		(start 108.208826 -233.466386)
		(end 108.208064 -233.466894)
		(width 0.1143)
		(layer "In11.Cu")
		(net "P5E_CPU1_G1_TX_DN<3>")
	)
	(segment
		(start 108.208064 -229.581964)
		(end 108.241592 -229.601522)
		(width 0.1143)
		(layer "In11.Cu")
		(net "P5E_CPU1_G1_TX_DN<3>")
	)
	(segment
		(start 108.208064 -239.946942)
		(end 108.207048 -239.94745)
		(width 0.1143)
		(layer "In11.Cu")
		(net "P5E_CPU1_G1_TX_DN<3>")
	)
	(segment
		(start 108.214668 -241.563144)
		(end 108.213906 -241.563652)
		(width 0.1143)
		(layer "In11.Cu")
		(net "P5E_CPU1_G1_TX_DN<3>")
	)
	(segment
		(start 108.210096 -244.163088)
		(end 108.21162 -244.16385)
		(width 0.1143)
		(layer "In11.Cu")
		(net "P5E_CPU1_G1_TX_DN<3>")
	)
	(segment
		(start 108.208826 -228.606604)
		(end 108.208064 -228.607112)
		(width 0.1143)
		(layer "In11.Cu")
		(net "P5E_CPU1_G1_TX_DN<3>")
	)
	(segment
		(start 108.208826 -244.162326)
		(end 108.210096 -244.163088)
		(width 0.1143)
		(layer "In11.Cu")
		(net "P5E_CPU1_G1_TX_DN<3>")
	)
	(segment
		(start 108.212382 -236.064298)
		(end 108.239814 -236.080046)
		(width 0.1143)
		(layer "In11.Cu")
		(net "P5E_CPU1_G1_TX_DN<3>")
	)
	(segment
		(start 153.899108 -171.050712)
		(end 153.782268 -171.368974)
		(width 0.14224)
		(layer "In11.Cu")
		(net "P5E_CPU1_G1_TX_DN<3>")
	)
	(segment
		(start 108.214668 -238.32312)
		(end 108.213906 -238.323628)
		(width 0.1143)
		(layer "In11.Cu")
		(net "P5E_CPU1_G1_TX_DN<3>")
	)
	(segment
		(start 107.202986 -222.164402)
		(end 107.155742 -222.212662)
		(width 0.1143)
		(layer "In11.Cu")
		(net "P5E_CPU1_G1_TX_DN<3>")
	)
	(segment
		(start 108.208064 -232.821734)
		(end 108.208826 -232.822242)
		(width 0.1143)
		(layer "In11.Cu")
		(net "P5E_CPU1_G1_TX_DN<3>")
	)
	(segment
		(start 108.176568 -234.423458)
		(end 108.207048 -234.441238)
		(width 0.1143)
		(layer "In11.Cu")
		(net "P5E_CPU1_G1_TX_DN<3>")
	)
	(segment
		(start 108.176568 -244.14353)
		(end 108.207048 -244.16131)
		(width 0.1143)
		(layer "In11.Cu")
		(net "P5E_CPU1_G1_TX_DN<3>")
	)
	(segment
		(start 111.924592 -207.700626)
		(end 107.400598 -215.319864)
		(width 0.14224)
		(layer "In11.Cu")
		(net "P5E_CPU1_G1_TX_DN<3>")
	)
	(segment
		(start 108.208826 -226.986592)
		(end 108.208064 -226.9871)
		(width 0.1143)
		(layer "In11.Cu")
		(net "P5E_CPU1_G1_TX_DN<3>")
	)
	(segment
		(start 108.208064 -236.706918)
		(end 108.207048 -236.707426)
		(width 0.1143)
		(layer "In11.Cu")
		(net "P5E_CPU1_G1_TX_DN<3>")
	)
	(segment
		(start 108.212382 -241.564414)
		(end 108.21162 -241.564922)
		(width 0.1143)
		(layer "In11.Cu")
		(net "P5E_CPU1_G1_TX_DN<3>")
	)
	(segment
		(start 108.205524 -226.340416)
		(end 108.207048 -226.341432)
		(width 0.1143)
		(layer "In11.Cu")
		(net "P5E_CPU1_G1_TX_DN<3>")
	)
	(segment
		(start 108.215938 -228.60254)
		(end 108.214668 -228.603302)
		(width 0.1143)
		(layer "In11.Cu")
		(net "P5E_CPU1_G1_TX_DN<3>")
	)
	(segment
		(start 150.334218 -176.219612)
		(end 111.924592 -207.700626)
		(width 0.14224)
		(layer "In11.Cu")
		(net "P5E_CPU1_G1_TX_DN<3>")
	)
	(segment
		(start 106.985816 -224.234502)
		(end 106.98607 -224.234502)
		(width 0.1143)
		(layer "In11.Cu")
		(net "P5E_CPU1_G1_TX_DN<3>")
	)
	(segment
		(start 107.738164 -225.531934)
		(end 107.768644 -225.549714)
		(width 0.1143)
		(layer "In11.Cu")
		(net "P5E_CPU1_G1_TX_DN<3>")
	)
	(segment
		(start 108.176568 -242.523518)
		(end 108.207048 -242.541298)
		(width 0.1143)
		(layer "In11.Cu")
		(net "P5E_CPU1_G1_TX_DN<3>")
	)
	(segment
		(start 108.212382 -227.964492)
		(end 108.239814 -227.98024)
		(width 0.1143)
		(layer "In11.Cu")
		(net "P5E_CPU1_G1_TX_DN<3>")
	)
	(segment
		(start 108.212382 -234.444286)
		(end 108.239814 -234.460034)
		(width 0.1143)
		(layer "In11.Cu")
		(net "P5E_CPU1_G1_TX_DN<3>")
	)
	(segment
		(start 108.208826 -235.086398)
		(end 108.208064 -235.086906)
		(width 0.1143)
		(layer "In11.Cu")
		(net "P5E_CPU1_G1_TX_DN<3>")
	)
	(segment
		(start 108.207048 -239.94745)
		(end 108.168948 -239.969802)
		(width 0.1143)
		(layer "In11.Cu")
		(net "P5E_CPU1_G1_TX_DN<3>")
	)
	(segment
		(start 108.210096 -239.303052)
		(end 108.21162 -239.303814)
		(width 0.1143)
		(layer "In11.Cu")
		(net "P5E_CPU1_G1_TX_DN<3>")
	)
	(segment
		(start 108.168948 -244.138958)
		(end 108.175806 -244.143022)
		(width 0.1143)
		(layer "In11.Cu")
		(net "P5E_CPU1_G1_TX_DN<3>")
	)
	(segment
		(start 107.300014 -223.728788)
		(end 107.272836 -223.744282)
		(width 0.1143)
		(layer "In11.Cu")
		(net "P5E_CPU1_G1_TX_DN<3>")
	)
	(segment
		(start 108.21162 -233.464862)
		(end 108.208826 -233.466386)
		(width 0.1143)
		(layer "In11.Cu")
		(net "P5E_CPU1_G1_TX_DN<3>")
	)
	(segment
		(start 108.210096 -236.063028)
		(end 108.21162 -236.06379)
		(width 0.1143)
		(layer "In11.Cu")
		(net "P5E_CPU1_G1_TX_DN<3>")
	)
	(segment
		(start 108.213906 -228.60381)
		(end 108.212382 -228.604572)
		(width 0.1143)
		(layer "In11.Cu")
		(net "P5E_CPU1_G1_TX_DN<3>")
	)
	(segment
		(start 108.207048 -241.567462)
		(end 108.168948 -241.589814)
		(width 0.1143)
		(layer "In11.Cu")
		(net "P5E_CPU1_G1_TX_DN<3>")
	)
	(segment
		(start 108.176568 -240.903506)
		(end 108.207048 -240.921286)
		(width 0.1143)
		(layer "In11.Cu")
		(net "P5E_CPU1_G1_TX_DN<3>")
	)
	(segment
		(start 108.175806 -244.143022)
		(end 108.176568 -244.14353)
		(width 0.1143)
		(layer "In11.Cu")
		(net "P5E_CPU1_G1_TX_DN<3>")
	)
	(segment
		(start 107.230418 -223.080072)
		(end 107.237022 -223.083882)
		(width 0.1143)
		(layer "In11.Cu")
		(net "P5E_CPU1_G1_TX_DN<3>")
	)
	(segment
		(start 108.213906 -233.463592)
		(end 108.212382 -233.464354)
		(width 0.1143)
		(layer "In11.Cu")
		(net "P5E_CPU1_G1_TX_DN<3>")
	)
	(segment
		(start 108.208826 -241.566446)
		(end 108.208064 -241.566954)
		(width 0.1143)
		(layer "In11.Cu")
		(net "P5E_CPU1_G1_TX_DN<3>")
	)
	(segment
		(start 108.208064 -236.061758)
		(end 108.208826 -236.062266)
		(width 0.1143)
		(layer "In11.Cu")
		(net "P5E_CPU1_G1_TX_DN<3>")
	)
	(segment
		(start 108.213906 -238.323628)
		(end 108.212382 -238.32439)
		(width 0.1143)
		(layer "In11.Cu")
		(net "P5E_CPU1_G1_TX_DN<3>")
	)
	(segment
		(start 108.207048 -235.087414)
		(end 108.168948 -235.109766)
		(width 0.1143)
		(layer "In11.Cu")
		(net "P5E_CPU1_G1_TX_DN<3>")
	)
	(segment
		(start 107.300014 -223.120204)
		(end 107.32008 -223.134682)
		(width 0.1143)
		(layer "In11.Cu")
		(net "P5E_CPU1_G1_TX_DN<3>")
	)
	(segment
		(start 107.269026 -223.746568)
		(end 107.268264 -223.747076)
		(width 0.1143)
		(layer "In11.Cu")
		(net "P5E_CPU1_G1_TX_DN<3>")
	)
	(segment
		(start 108.208064 -239.301782)
		(end 108.208826 -239.30229)
		(width 0.1143)
		(layer "In11.Cu")
		(net "P5E_CPU1_G1_TX_DN<3>")
	)
	(segment
		(start 108.213398 -226.344988)
		(end 108.21416 -226.345496)
		(width 0.1143)
		(layer "In11.Cu")
		(net "P5E_CPU1_G1_TX_DN<3>")
	)
	(segment
		(start 155.269184 -145.619978)
		(end 156.153358 -159.767016)
		(width 0.14224)
		(layer "In11.Cu")
		(net "P5E_CPU1_G1_TX_DN<3>")
	)
	(segment
		(start 108.176568 -237.663482)
		(end 108.207048 -237.681262)
		(width 0.1143)
		(layer "In11.Cu")
		(net "P5E_CPU1_G1_TX_DN<3>")
	)
	(segment
		(start 108.208826 -234.442254)
		(end 108.210096 -234.443016)
		(width 0.1143)
		(layer "In11.Cu")
		(net "P5E_CPU1_G1_TX_DN<3>")
	)
	(segment
		(start 107.270296 -223.745806)
		(end 107.269026 -223.746568)
		(width 0.1143)
		(layer "In11.Cu")
		(net "P5E_CPU1_G1_TX_DN<3>")
	)
	(segment
		(start 108.21162 -239.303814)
		(end 108.212382 -239.304322)
		(width 0.1143)
		(layer "In11.Cu")
		(net "P5E_CPU1_G1_TX_DN<3>")
	)
	(segment
		(start 108.208826 -226.342448)
		(end 108.21162 -226.343972)
		(width 0.1143)
		(layer "In11.Cu")
		(net "P5E_CPU1_G1_TX_DN<3>")
	)
	(segment
		(start 153.782268 -171.368974)
		(end 150.334218 -176.219612)
		(width 0.14224)
		(layer "In11.Cu")
		(net "P5E_CPU1_G1_TX_DN<3>")
	)
	(segment
		(start 108.208826 -242.542314)
		(end 108.210096 -242.543076)
		(width 0.1143)
		(layer "In11.Cu")
		(net "P5E_CPU1_G1_TX_DN<3>")
	)
	(segment
		(start 107.400598 -221.05493)
		(end 107.400598 -221.083378)
		(width 0.1143)
		(layer "In11.Cu")
		(net "P5E_CPU1_G1_TX_DN<3>")
	)
	(segment
		(start 108.208826 -232.822242)
		(end 108.210096 -232.823004)
		(width 0.1143)
		(layer "In11.Cu")
		(net "P5E_CPU1_G1_TX_DN<3>")
	)
	(segment
		(start 108.208826 -237.682278)
		(end 108.210096 -237.68304)
		(width 0.1143)
		(layer "In11.Cu")
		(net "P5E_CPU1_G1_TX_DN<3>")
	)
	(segment
		(start 108.208826 -239.30229)
		(end 108.210096 -239.303052)
		(width 0.1143)
		(layer "In11.Cu")
		(net "P5E_CPU1_G1_TX_DN<3>")
	)
	(segment
		(start 107.446318 -221.129098)
		(end 107.446318 -221.308168)
		(width 0.1143)
		(layer "In11.Cu")
		(net "P5E_CPU1_G1_TX_DN<3>")
	)
	(segment
		(start 108.175806 -239.282986)
		(end 108.176568 -239.283494)
		(width 0.1143)
		(layer "In11.Cu")
		(net "P5E_CPU1_G1_TX_DN<3>")
	)
	(segment
		(start 107.268518 -224.721928)
		(end 107.298998 -224.739708)
		(width 0.1143)
		(layer "In11.Cu")
		(net "P5E_CPU1_G1_TX_DN<3>")
	)
	(segment
		(start 153.899362 -171.04995)
		(end 153.899108 -171.050712)
		(width 0.14224)
		(layer "In11.Cu")
		(net "P5E_CPU1_G1_TX_DN<3>")
	)
	(segment
		(start 108.21162 -243.184934)
		(end 108.208826 -243.186458)
		(width 0.1143)
		(layer "In11.Cu")
		(net "P5E_CPU1_G1_TX_DN<3>")
	)
	(segment
		(start 108.208064 -237.68177)
		(end 108.208826 -237.682278)
		(width 0.1143)
		(layer "In11.Cu")
		(net "P5E_CPU1_G1_TX_DN<3>")
	)
	(segment
		(start 108.168948 -227.939092)
		(end 108.207048 -227.961444)
		(width 0.1143)
		(layer "In11.Cu")
		(net "P5E_CPU1_G1_TX_DN<3>")
	)
	(segment
		(start 108.207048 -239.301274)
		(end 108.208064 -239.301782)
		(width 0.1143)
		(layer "In11.Cu")
		(net "P5E_CPU1_G1_TX_DN<3>")
	)
	(segment
		(start 108.21162 -236.06379)
		(end 108.212382 -236.064298)
		(width 0.1143)
		(layer "In11.Cu")
		(net "P5E_CPU1_G1_TX_DN<3>")
	)
	(segment
		(start 108.208064 -228.607112)
		(end 108.207048 -228.60762)
		(width 0.1143)
		(layer "In11.Cu")
		(net "P5E_CPU1_G1_TX_DN<3>")
	)
	(segment
		(start 108.176568 -239.283494)
		(end 108.207048 -239.301274)
		(width 0.1143)
		(layer "In11.Cu")
		(net "P5E_CPU1_G1_TX_DN<3>")
	)
	(segment
		(start 108.213906 -243.183664)
		(end 108.212382 -243.184426)
		(width 0.1143)
		(layer "In11.Cu")
		(net "P5E_CPU1_G1_TX_DN<3>")
	)
	(segment
		(start 108.208826 -227.96246)
		(end 108.210096 -227.963222)
		(width 0.1143)
		(layer "In11.Cu")
		(net "P5E_CPU1_G1_TX_DN<3>")
	)
	(segment
		(start 154.016202 -170.731688)
		(end 153.899362 -171.04995)
		(width 0.14224)
		(layer "In11.Cu")
		(net "P5E_CPU1_G1_TX_DN<3>")
	)
	(segment
		(start 108.208064 -231.846882)
		(end 108.207048 -231.84739)
		(width 0.1143)
		(layer "In11.Cu")
		(net "P5E_CPU1_G1_TX_DN<3>")
	)
	(segment
		(start 108.175806 -236.042962)
		(end 108.176568 -236.04347)
		(width 0.1143)
		(layer "In11.Cu")
		(net "P5E_CPU1_G1_TX_DN<3>")
	)
	(segment
		(start 108.215684 -236.7026)
		(end 108.214668 -236.703108)
		(width 0.1143)
		(layer "In11.Cu")
		(net "P5E_CPU1_G1_TX_DN<3>")
	)
	(segment
		(start 108.204508 -226.339908)
		(end 108.205524 -226.340416)
		(width 0.1143)
		(layer "In11.Cu")
		(net "P5E_CPU1_G1_TX_DN<3>")
	)
	(segment
		(start 108.208064 -234.441746)
		(end 108.208826 -234.442254)
		(width 0.1143)
		(layer "In11.Cu")
		(net "P5E_CPU1_G1_TX_DN<3>")
	)
	(segment
		(start 107.267248 -223.747584)
		(end 107.229148 -223.769936)
		(width 0.1143)
		(layer "In11.Cu")
		(net "P5E_CPU1_G1_TX_DN<3>")
	)
	(segment
		(start 108.208064 -235.086906)
		(end 108.207048 -235.087414)
		(width 0.1143)
		(layer "In11.Cu")
		(net "P5E_CPU1_G1_TX_DN<3>")
	)
	(segment
		(start 108.239814 -239.928654)
		(end 108.215684 -239.942624)
		(width 0.1143)
		(layer "In11.Cu")
		(net "P5E_CPU1_G1_TX_DN<3>")
	)
	(segment
		(start 108.208064 -241.566954)
		(end 108.207048 -241.567462)
		(width 0.1143)
		(layer "In11.Cu")
		(net "P5E_CPU1_G1_TX_DN<3>")
	)
	(segment
		(start 107.29976 -222.108776)
		(end 107.202986 -222.164402)
		(width 0.1143)
		(layer "In11.Cu")
		(net "P5E_CPU1_G1_TX_DN<3>")
	)
	(segment
		(start 108.21162 -239.94491)
		(end 108.208826 -239.946434)
		(width 0.1143)
		(layer "In11.Cu")
		(net "P5E_CPU1_G1_TX_DN<3>")
	)
	(segment
		(start 57.92089 -52.607972)
		(end 150.585678 -135.934704)
		(width 0.14224)
		(layer "In11.Cu")
		(net "P5E_CPU1_G1_TX_DN<3>")
	)
	(segment
		(start 108.175806 -234.42295)
		(end 108.176568 -234.423458)
		(width 0.1143)
		(layer "In11.Cu")
		(net "P5E_CPU1_G1_TX_DN<3>")
	)
	(segment
		(start 108.858812 -245.224554)
		(end 108.788962 -245.294404)
		(width 0.1143)
		(layer "In11.Cu")
		(net "P5E_CPU1_G1_TX_DN<3>")
	)
	(segment
		(start 108.210096 -232.823004)
		(end 108.21162 -232.823766)
		(width 0.1143)
		(layer "In11.Cu")
		(net "P5E_CPU1_G1_TX_DN<3>")
	)
	(segment
		(start 108.212382 -238.32439)
		(end 108.21162 -238.324898)
		(width 0.1143)
		(layer "In11.Cu")
		(net "P5E_CPU1_G1_TX_DN<3>")
	)
	(segment
		(start 156.153358 -164.457126)
		(end 154.016202 -170.731688)
		(width 0.14224)
		(layer "In11.Cu")
		(net "P5E_CPU1_G1_TX_DN<3>")
	)
	(segment
		(start 108.21162 -228.60508)
		(end 108.208826 -228.606604)
		(width 0.1143)
		(layer "In11.Cu")
		(net "P5E_CPU1_G1_TX_DN<3>")
	)
	(segment
		(start 108.21162 -232.823766)
		(end 108.212382 -232.824274)
		(width 0.1143)
		(layer "In11.Cu")
		(net "P5E_CPU1_G1_TX_DN<3>")
	)
	(segment
		(start 107.272074 -223.74479)
		(end 107.270296 -223.745806)
		(width 0.1143)
		(layer "In11.Cu")
		(net "P5E_CPU1_G1_TX_DN<3>")
	)
	(segment
		(start 108.21162 -226.343972)
		(end 108.212382 -226.34448)
		(width 0.1143)
		(layer "In11.Cu")
		(net "P5E_CPU1_G1_TX_DN<3>")
	)
	(segment
		(start 108.215684 -239.942624)
		(end 108.214668 -239.943132)
		(width 0.1143)
		(layer "In11.Cu")
		(net "P5E_CPU1_G1_TX_DN<3>")
	)
	(segment
		(start 108.208826 -240.922302)
		(end 108.210096 -240.923064)
		(width 0.1143)
		(layer "In11.Cu")
		(net "P5E_CPU1_G1_TX_DN<3>")
	)
	(segment
		(start 108.210096 -234.443016)
		(end 108.21162 -234.443778)
		(width 0.1143)
		(layer "In11.Cu")
		(net "P5E_CPU1_G1_TX_DN<3>")
	)
	(segment
		(start 108.213906 -239.94364)
		(end 108.212382 -239.944402)
		(width 0.1143)
		(layer "In11.Cu")
		(net "P5E_CPU1_G1_TX_DN<3>")
	)
	(segment
		(start 108.208826 -231.846374)
		(end 108.208064 -231.846882)
		(width 0.1143)
		(layer "In11.Cu")
		(net "P5E_CPU1_G1_TX_DN<3>")
	)
	(segment
		(start 108.212382 -235.084366)
		(end 108.21162 -235.084874)
		(width 0.1143)
		(layer "In11.Cu")
		(net "P5E_CPU1_G1_TX_DN<3>")
	)
	(segment
		(start 108.212382 -240.924334)
		(end 108.239814 -240.940082)
		(width 0.1143)
		(layer "In11.Cu")
		(net "P5E_CPU1_G1_TX_DN<3>")
	)
	(segment
		(start 108.208826 -236.062266)
		(end 108.210096 -236.063028)
		(width 0.1143)
		(layer "In11.Cu")
		(net "P5E_CPU1_G1_TX_DN<3>")
	)
	(segment
		(start 108.175806 -237.662974)
		(end 108.176568 -237.663482)
		(width 0.1143)
		(layer "In11.Cu")
		(net "P5E_CPU1_G1_TX_DN<3>")
	)
	(segment
		(start 108.175806 -242.52301)
		(end 108.176568 -242.523518)
		(width 0.1143)
		(layer "In11.Cu")
		(net "P5E_CPU1_G1_TX_DN<3>")
	)
	(segment
		(start 108.208064 -243.186966)
		(end 108.207048 -243.187474)
		(width 0.1143)
		(layer "In11.Cu")
		(net "P5E_CPU1_G1_TX_DN<3>")
	)
	(segment
		(start 108.212382 -239.304322)
		(end 108.239814 -239.32007)
		(width 0.1143)
		(layer "In11.Cu")
		(net "P5E_CPU1_G1_TX_DN<3>")
	)
	(segment
		(start 107.400598 -221.083378)
		(end 107.446318 -221.129098)
		(width 0.1143)
		(layer "In11.Cu")
		(net "P5E_CPU1_G1_TX_DN<3>")
	)
	(segment
		(start 108.210096 -231.845612)
		(end 108.208826 -231.846374)
		(width 0.1143)
		(layer "In11.Cu")
		(net "P5E_CPU1_G1_TX_DN<3>")
	)
	(segment
		(start 108.210096 -242.543076)
		(end 108.21162 -242.543838)
		(width 0.1143)
		(layer "In11.Cu")
		(net "P5E_CPU1_G1_TX_DN<3>")
	)
	(segment
		(start 49.658524 -17.90319)
		(end 49.658524 -20.222464)
		(width 0.14224)
		(layer "In11.Cu")
		(net "P5E_CPU1_G1_TX_DN<3>")
	)
	(segment
		(start 108.21162 -227.963984)
		(end 108.212382 -227.964492)
		(width 0.1143)
		(layer "In11.Cu")
		(net "P5E_CPU1_G1_TX_DN<3>")
	)
	(segment
		(start 108.210096 -240.923064)
		(end 108.21162 -240.923826)
		(width 0.1143)
		(layer "In11.Cu")
		(net "P5E_CPU1_G1_TX_DN<3>")
	)
	(segment
		(start 108.168948 -239.278922)
		(end 108.175806 -239.282986)
		(width 0.1143)
		(layer "In11.Cu")
		(net "P5E_CPU1_G1_TX_DN<3>")
	)
	(segment
		(start 108.207048 -236.707426)
		(end 108.168948 -236.729778)
		(width 0.1143)
		(layer "In11.Cu")
		(net "P5E_CPU1_G1_TX_DN<3>")
	)
	(segment
		(start 108.212382 -239.944402)
		(end 108.21162 -239.94491)
		(width 0.1143)
		(layer "In11.Cu")
		(net "P5E_CPU1_G1_TX_DN<3>")
	)
	(segment
		(start 108.208826 -238.326422)
		(end 108.208064 -238.32693)
		(width 0.1143)
		(layer "In11.Cu")
		(net "P5E_CPU1_G1_TX_DN<3>")
	)
	(segment
		(start 108.21162 -244.16385)
		(end 108.212382 -244.164358)
		(width 0.1143)
		(layer "In11.Cu")
		(net "P5E_CPU1_G1_TX_DN<3>")
	)
	(segment
		(start 108.21162 -240.923826)
		(end 108.212382 -240.924334)
		(width 0.1143)
		(layer "In11.Cu")
		(net "P5E_CPU1_G1_TX_DN<3>")
	)
	(segment
		(start 108.210096 -237.68304)
		(end 108.21162 -237.683802)
		(width 0.1143)
		(layer "In11.Cu")
		(net "P5E_CPU1_G1_TX_DN<3>")
	)
	(segment
		(start 108.207048 -231.84739)
		(end 108.168948 -231.869742)
		(width 0.1143)
		(layer "In11.Cu")
		(net "P5E_CPU1_G1_TX_DN<3>")
	)
	(segment
		(start 108.168948 -229.559104)
		(end 108.208064 -229.581964)
		(width 0.1143)
		(layer "In11.Cu")
		(net "P5E_CPU1_G1_TX_DN<3>")
	)
	(segment
		(start 108.21162 -234.443778)
		(end 108.212382 -234.444286)
		(width 0.1143)
		(layer "In11.Cu")
		(net "P5E_CPU1_G1_TX_DN<3>")
	)
	(segment
		(start 108.239814 -241.548666)
		(end 108.215684 -241.562636)
		(width 0.1143)
		(layer "In11.Cu")
		(net "P5E_CPU1_G1_TX_DN<3>")
	)
	(segment
		(start 107.446318 -221.308168)
		(end 107.45597 -221.617032)
		(width 0.1143)
		(layer "In11.Cu")
		(net "P5E_CPU1_G1_TX_DN<3>")
	)
	(segment
		(start 107.237022 -223.083882)
		(end 107.237784 -223.08439)
		(width 0.1143)
		(layer "In11.Cu")
		(net "P5E_CPU1_G1_TX_DN<3>")
	)
	(arc
		(start 107.216448 -223.070166)
		(mid 107.223395 -223.075172)
		(end 107.230418 -223.080072)
		(width 0.1143)
		(layer "In11.Cu")
		(net "P5E_CPU1_G1_TX_DN<3>")
	)
	(arc
		(start 107.925616 -225.854514)
		(mid 107.990131 -226.116733)
		(end 108.168948 -226.31908)
		(width 0.1143)
		(layer "In11.Cu")
		(net "P5E_CPU1_G1_TX_DN<3>")
	)
	(arc
		(start 108.239814 -232.840022)
		(mid 108.395742 -233.144314)
		(end 108.239814 -233.448606)
		(width 0.1143)
		(layer "In11.Cu")
		(net "P5E_CPU1_G1_TX_DN<3>")
	)
	(arc
		(start 108.39577 -229.90429)
		(mid 108.354515 -230.075261)
		(end 108.239814 -230.208582)
		(width 0.1143)
		(layer "In11.Cu")
		(net "P5E_CPU1_G1_TX_DN<3>")
	)
	(arc
		(start 108.171488 -230.248206)
		(mid 107.990836 -230.450951)
		(end 107.925616 -230.71455)
		(width 0.1143)
		(layer "In11.Cu")
		(net "P5E_CPU1_G1_TX_DN<3>")
	)
	(arc
		(start 107.155742 -222.212662)
		(mid 106.99287 -222.655058)
		(end 107.216448 -223.070166)
		(width 0.1143)
		(layer "In11.Cu")
		(net "P5E_CPU1_G1_TX_DN<3>")
	)
	(arc
		(start 108.708698 -244.989604)
		(mid 108.806463 -245.09258)
		(end 108.858812 -245.224554)
		(width 0.1143)
		(layer "In11.Cu")
		(net "P5E_CPU1_G1_TX_DN<3>")
	)
	(arc
		(start 107.45597 -225.044508)
		(mid 107.521206 -225.308099)
		(end 107.701842 -225.510852)
		(width 0.1143)
		(layer "In11.Cu")
		(net "P5E_CPU1_G1_TX_DN<3>")
	)
	(arc
		(start 108.239814 -234.460034)
		(mid 108.395742 -234.764326)
		(end 108.239814 -235.068618)
		(width 0.1143)
		(layer "In11.Cu")
		(net "P5E_CPU1_G1_TX_DN<3>")
	)
	(arc
		(start 108.239814 -237.700058)
		(mid 108.395742 -238.00435)
		(end 108.239814 -238.308642)
		(width 0.1143)
		(layer "In11.Cu")
		(net "P5E_CPU1_G1_TX_DN<3>")
	)
	(arc
		(start 108.39577 -244.484398)
		(mid 108.460285 -244.746617)
		(end 108.639102 -244.948964)
		(width 0.1143)
		(layer "In11.Cu")
		(net "P5E_CPU1_G1_TX_DN<3>")
	)
	(arc
		(start 107.229148 -223.769936)
		(mid 107.050335 -223.972286)
		(end 106.985816 -224.234502)
		(width 0.1143)
		(layer "In11.Cu")
		(net "P5E_CPU1_G1_TX_DN<3>")
	)
	(arc
		(start 108.239814 -226.360228)
		(mid 108.395742 -226.66452)
		(end 108.239814 -226.968812)
		(width 0.1143)
		(layer "In11.Cu")
		(net "P5E_CPU1_G1_TX_DN<3>")
	)
	(arc
		(start 108.241592 -229.601522)
		(mid 108.354999 -229.734411)
		(end 108.39577 -229.90429)
		(width 0.1143)
		(layer "In11.Cu")
		(net "P5E_CPU1_G1_TX_DN<3>")
	)
	(arc
		(start 107.389676 -222.016828)
		(mid 107.348693 -222.06669)
		(end 107.29976 -222.108776)
		(width 0.1143)
		(layer "In11.Cu")
		(net "P5E_CPU1_G1_TX_DN<3>")
	)
	(arc
		(start 108.168948 -243.209826)
		(mid 107.925621 -243.674392)
		(end 108.168948 -244.138958)
		(width 0.1143)
		(layer "In11.Cu")
		(net "P5E_CPU1_G1_TX_DN<3>")
	)
	(arc
		(start 108.168948 -235.109766)
		(mid 107.925621 -235.574332)
		(end 108.168948 -236.038898)
		(width 0.1143)
		(layer "In11.Cu")
		(net "P5E_CPU1_G1_TX_DN<3>")
	)
	(arc
		(start 106.987594 -224.25914)
		(mid 106.988214 -224.263714)
		(end 106.988864 -224.268284)
		(width 0.1143)
		(layer "In11.Cu")
		(net "P5E_CPU1_G1_TX_DN<3>")
	)
	(arc
		(start 108.168948 -241.589814)
		(mid 107.925621 -242.05438)
		(end 108.168948 -242.518946)
		(width 0.1143)
		(layer "In11.Cu")
		(net "P5E_CPU1_G1_TX_DN<3>")
	)
	(arc
		(start 108.168948 -231.869742)
		(mid 107.925621 -232.334308)
		(end 108.168948 -232.798874)
		(width 0.1143)
		(layer "In11.Cu")
		(net "P5E_CPU1_G1_TX_DN<3>")
	)
	(arc
		(start 108.168948 -233.489754)
		(mid 107.925621 -233.95432)
		(end 108.168948 -234.418886)
		(width 0.1143)
		(layer "In11.Cu")
		(net "P5E_CPU1_G1_TX_DN<3>")
	)
	(arc
		(start 107.768644 -225.549714)
		(mid 107.884071 -225.68309)
		(end 107.925616 -225.854514)
		(width 0.1143)
		(layer "In11.Cu")
		(net "P5E_CPU1_G1_TX_DN<3>")
	)
	(arc
		(start 107.45597 -221.804484)
		(mid 107.43892 -221.915675)
		(end 107.389676 -222.016828)
		(width 0.1143)
		(layer "In11.Cu")
		(net "P5E_CPU1_G1_TX_DN<3>")
	)
	(arc
		(start 107.217718 -224.690178)
		(mid 107.22353 -224.694662)
		(end 107.229402 -224.699068)
		(width 0.1143)
		(layer "In11.Cu")
		(net "P5E_CPU1_G1_TX_DN<3>")
	)
	(arc
		(start 108.241592 -231.221534)
		(mid 108.354999 -231.354423)
		(end 108.39577 -231.524302)
		(width 0.1143)
		(layer "In11.Cu")
		(net "P5E_CPU1_G1_TX_DN<3>")
	)
	(arc
		(start 108.168948 -239.969802)
		(mid 107.925621 -240.434368)
		(end 108.168948 -240.898934)
		(width 0.1143)
		(layer "In11.Cu")
		(net "P5E_CPU1_G1_TX_DN<3>")
	)
	(arc
		(start 108.239814 -239.32007)
		(mid 108.395742 -239.624362)
		(end 108.239814 -239.928654)
		(width 0.1143)
		(layer "In11.Cu")
		(net "P5E_CPU1_G1_TX_DN<3>")
	)
	(arc
		(start 107.925616 -230.71455)
		(mid 107.990131 -230.976769)
		(end 108.168948 -231.179116)
		(width 0.1143)
		(layer "In11.Cu")
		(net "P5E_CPU1_G1_TX_DN<3>")
	)
	(arc
		(start 108.239814 -244.180106)
		(mid 108.35449 -244.31344)
		(end 108.39577 -244.484398)
		(width 0.1143)
		(layer "In11.Cu")
		(net "P5E_CPU1_G1_TX_DN<3>")
	)
	(arc
		(start 108.239814 -242.560094)
		(mid 108.395742 -242.864386)
		(end 108.239814 -243.168678)
		(width 0.1143)
		(layer "In11.Cu")
		(net "P5E_CPU1_G1_TX_DN<3>")
	)
	(arc
		(start 108.39577 -231.524302)
		(mid 108.354515 -231.695273)
		(end 108.239814 -231.828594)
		(width 0.1143)
		(layer "In11.Cu")
		(net "P5E_CPU1_G1_TX_DN<3>")
	)
	(arc
		(start 106.988864 -224.268284)
		(mid 107.060025 -224.489915)
		(end 107.199938 -224.675954)
		(width 0.1143)
		(layer "In11.Cu")
		(net "P5E_CPU1_G1_TX_DN<3>")
	)
	(arc
		(start 107.199938 -224.675954)
		(mid 107.208756 -224.683156)
		(end 107.217718 -224.690178)
		(width 0.1143)
		(layer "In11.Cu")
		(net "P5E_CPU1_G1_TX_DN<3>")
	)
	(arc
		(start 107.298998 -224.739708)
		(mid 107.414425 -224.873084)
		(end 107.45597 -225.044508)
		(width 0.1143)
		(layer "In11.Cu")
		(net "P5E_CPU1_G1_TX_DN<3>")
	)
	(arc
		(start 108.239814 -236.080046)
		(mid 108.395742 -236.384338)
		(end 108.239814 -236.68863)
		(width 0.1143)
		(layer "In11.Cu")
		(net "P5E_CPU1_G1_TX_DN<3>")
	)
	(arc
		(start 108.168948 -236.729778)
		(mid 107.925621 -237.194344)
		(end 108.168948 -237.65891)
		(width 0.1143)
		(layer "In11.Cu")
		(net "P5E_CPU1_G1_TX_DN<3>")
	)
	(arc
		(start 108.239814 -227.98024)
		(mid 108.395742 -228.284532)
		(end 108.239814 -228.588824)
		(width 0.1143)
		(layer "In11.Cu")
		(net "P5E_CPU1_G1_TX_DN<3>")
	)
	(arc
		(start 108.239814 -240.940082)
		(mid 108.395742 -241.244374)
		(end 108.239814 -241.548666)
		(width 0.1143)
		(layer "In11.Cu")
		(net "P5E_CPU1_G1_TX_DN<3>")
	)
	(arc
		(start 108.168948 -228.629972)
		(mid 107.925621 -229.094538)
		(end 108.168948 -229.559104)
		(width 0.1143)
		(layer "In11.Cu")
		(net "P5E_CPU1_G1_TX_DN<3>")
	)
	(arc
		(start 108.168948 -238.34979)
		(mid 107.925621 -238.814356)
		(end 108.168948 -239.278922)
		(width 0.1143)
		(layer "In11.Cu")
		(net "P5E_CPU1_G1_TX_DN<3>")
	)
	(arc
		(start 107.32008 -223.134682)
		(mid 107.468587 -223.424496)
		(end 107.32008 -223.71431)
		(width 0.1143)
		(layer "In11.Cu")
		(net "P5E_CPU1_G1_TX_DN<3>")
	)
	(arc
		(start 108.168948 -227.00996)
		(mid 107.925621 -227.474526)
		(end 108.168948 -227.939092)
		(width 0.1143)
		(layer "In11.Cu")
		(net "P5E_CPU1_G1_TX_DN<3>")
	)
	(segment
		(start 52.46624 -18.186146)
		(end 52.46624 -18.86585)
		(width 0.12954)
		(layer "F.Cu")
		(net "P5E_CPU1_G1_TX_DN<2>")
	)
	(segment
		(start 52.46624 -18.86585)
		(end 52.19573 -19.13636)
		(width 0.12954)
		(layer "F.Cu")
		(net "P5E_CPU1_G1_TX_DN<2>")
	)
	(segment
		(start 108.957872 -243.94033)
		(end 108.49102 -243.674392)
		(width 0.12954)
		(layer "F.Cu")
		(net "P5E_CPU1_G1_TX_DN<2>")
	)
	(segment
		(start 52.17033 -17.890236)
		(end 52.46624 -18.186146)
		(width 0.12954)
		(layer "F.Cu")
		(net "P5E_CPU1_G1_TX_DN<2>")
	)
	(segment
		(start 109.1438 -242.539266)
		(end 109.145324 -242.540282)
		(width 0.1143)
		(layer "In11.Cu")
		(net "P5E_CPU1_G1_TX_DN<2>")
	)
	(segment
		(start 109.147102 -228.60762)
		(end 109.145578 -228.608636)
		(width 0.1143)
		(layer "In11.Cu")
		(net "P5E_CPU1_G1_TX_DN<2>")
	)
	(segment
		(start 109.11586 -232.802938)
		(end 109.116622 -232.803446)
		(width 0.1143)
		(layer "In11.Cu")
		(net "P5E_CPU1_G1_TX_DN<2>")
	)
	(segment
		(start 109.145578 -238.328454)
		(end 109.109002 -238.34979)
		(width 0.1143)
		(layer "In11.Cu")
		(net "P5E_CPU1_G1_TX_DN<2>")
	)
	(segment
		(start 109.147102 -237.681262)
		(end 109.148118 -237.68177)
		(width 0.1143)
		(layer "In11.Cu")
		(net "P5E_CPU1_G1_TX_DN<2>")
	)
	(segment
		(start 109.14126 -240.91773)
		(end 109.142784 -240.918746)
		(width 0.1143)
		(layer "In11.Cu")
		(net "P5E_CPU1_G1_TX_DN<2>")
	)
	(segment
		(start 109.142784 -237.678722)
		(end 109.1438 -237.67923)
		(width 0.1143)
		(layer "In11.Cu")
		(net "P5E_CPU1_G1_TX_DN<2>")
	)
	(segment
		(start 109.149134 -226.986592)
		(end 109.147102 -226.987608)
		(width 0.1143)
		(layer "In11.Cu")
		(net "P5E_CPU1_G1_TX_DN<2>")
	)
	(segment
		(start 109.13364 -227.95357)
		(end 109.135164 -227.954586)
		(width 0.1143)
		(layer "In11.Cu")
		(net "P5E_CPU1_G1_TX_DN<2>")
	)
	(segment
		(start 109.142784 -226.338638)
		(end 109.143546 -226.339146)
		(width 0.1143)
		(layer "In11.Cu")
		(net "P5E_CPU1_G1_TX_DN<2>")
	)
	(segment
		(start 109.145324 -232.82021)
		(end 109.147102 -232.821226)
		(width 0.1143)
		(layer "In11.Cu")
		(net "P5E_CPU1_G1_TX_DN<2>")
	)
	(segment
		(start 109.148118 -232.821734)
		(end 109.14888 -232.822242)
		(width 0.1143)
		(layer "In11.Cu")
		(net "P5E_CPU1_G1_TX_DN<2>")
	)
	(segment
		(start 109.148118 -243.186966)
		(end 109.147102 -243.187474)
		(width 0.1143)
		(layer "In11.Cu")
		(net "P5E_CPU1_G1_TX_DN<2>")
	)
	(segment
		(start 109.117384 -227.944172)
		(end 109.13364 -227.95357)
		(width 0.1143)
		(layer "In11.Cu")
		(net "P5E_CPU1_G1_TX_DN<2>")
	)
	(segment
		(start 109.11586 -234.42295)
		(end 109.116622 -234.423458)
		(width 0.1143)
		(layer "In11.Cu")
		(net "P5E_CPU1_G1_TX_DN<2>")
	)
	(segment
		(start 109.148118 -234.441746)
		(end 109.14888 -234.442254)
		(width 0.1143)
		(layer "In11.Cu")
		(net "P5E_CPU1_G1_TX_DN<2>")
	)
	(segment
		(start 108.166408 -223.770952)
		(end 108.15447 -223.78035)
		(width 0.1143)
		(layer "In11.Cu")
		(net "P5E_CPU1_G1_TX_DN<2>")
	)
	(segment
		(start 52.48656 -19.42719)
		(end 52.48656 -21.64715)
		(width 0.14224)
		(layer "In11.Cu")
		(net "P5E_CPU1_G1_TX_DN<2>")
	)
	(segment
		(start 109.145578 -243.18849)
		(end 109.109002 -243.209826)
		(width 0.1143)
		(layer "In11.Cu")
		(net "P5E_CPU1_G1_TX_DN<2>")
	)
	(segment
		(start 109.14126 -234.437682)
		(end 109.142784 -234.438698)
		(width 0.1143)
		(layer "In11.Cu")
		(net "P5E_CPU1_G1_TX_DN<2>")
	)
	(segment
		(start 109.14888 -231.846374)
		(end 109.148118 -231.846882)
		(width 0.1143)
		(layer "In11.Cu")
		(net "P5E_CPU1_G1_TX_DN<2>")
	)
	(segment
		(start 109.179868 -241.548666)
		(end 109.14888 -241.566446)
		(width 0.1143)
		(layer "In11.Cu")
		(net "P5E_CPU1_G1_TX_DN<2>")
	)
	(segment
		(start 154.678126 -171.755308)
		(end 151.080216 -176.814734)
		(width 0.14224)
		(layer "In11.Cu")
		(net "P5E_CPU1_G1_TX_DN<2>")
	)
	(segment
		(start 109.147102 -235.087414)
		(end 109.145578 -235.08843)
		(width 0.1143)
		(layer "In11.Cu")
		(net "P5E_CPU1_G1_TX_DN<2>")
	)
	(segment
		(start 155.031694 -170.679364)
		(end 154.881326 -171.157646)
		(width 0.14224)
		(layer "In11.Cu")
		(net "P5E_CPU1_G1_TX_DN<2>")
	)
	(segment
		(start 109.14888 -238.326422)
		(end 109.148118 -238.32693)
		(width 0.1143)
		(layer "In11.Cu")
		(net "P5E_CPU1_G1_TX_DN<2>")
	)
	(segment
		(start 109.179868 -236.68863)
		(end 109.14888 -236.70641)
		(width 0.1143)
		(layer "In11.Cu")
		(net "P5E_CPU1_G1_TX_DN<2>")
	)
	(segment
		(start 109.179868 -238.308642)
		(end 109.14888 -238.326422)
		(width 0.1143)
		(layer "In11.Cu")
		(net "P5E_CPU1_G1_TX_DN<2>")
	)
	(segment
		(start 109.179868 -231.828594)
		(end 109.14888 -231.846374)
		(width 0.1143)
		(layer "In11.Cu")
		(net "P5E_CPU1_G1_TX_DN<2>")
	)
	(segment
		(start 109.145324 -242.540282)
		(end 109.147102 -242.541298)
		(width 0.1143)
		(layer "In11.Cu")
		(net "P5E_CPU1_G1_TX_DN<2>")
	)
	(segment
		(start 109.142784 -239.298734)
		(end 109.1438 -239.299242)
		(width 0.1143)
		(layer "In11.Cu")
		(net "P5E_CPU1_G1_TX_DN<2>")
	)
	(segment
		(start 109.14888 -233.466386)
		(end 109.148118 -233.466894)
		(width 0.1143)
		(layer "In11.Cu")
		(net "P5E_CPU1_G1_TX_DN<2>")
	)
	(segment
		(start 109.179868 -233.448606)
		(end 109.14888 -233.466386)
		(width 0.1143)
		(layer "In11.Cu")
		(net "P5E_CPU1_G1_TX_DN<2>")
	)
	(segment
		(start 109.116622 -237.663482)
		(end 109.14126 -237.677706)
		(width 0.1143)
		(layer "In11.Cu")
		(net "P5E_CPU1_G1_TX_DN<2>")
	)
	(segment
		(start 109.148118 -239.301782)
		(end 109.14888 -239.30229)
		(width 0.1143)
		(layer "In11.Cu")
		(net "P5E_CPU1_G1_TX_DN<2>")
	)
	(segment
		(start 109.179868 -242.560094)
		(end 109.19968 -242.574318)
		(width 0.1143)
		(layer "In11.Cu")
		(net "P5E_CPU1_G1_TX_DN<2>")
	)
	(segment
		(start 157.111954 -159.73679)
		(end 157.111954 -164.571172)
		(width 0.14224)
		(layer "In11.Cu")
		(net "P5E_CPU1_G1_TX_DN<2>")
	)
	(segment
		(start 157.111954 -164.571172)
		(end 155.031694 -170.679364)
		(width 0.14224)
		(layer "In11.Cu")
		(net "P5E_CPU1_G1_TX_DN<2>")
	)
	(segment
		(start 108.330238 -222.016828)
		(end 108.32973 -222.016828)
		(width 0.1143)
		(layer "In11.Cu")
		(net "P5E_CPU1_G1_TX_DN<2>")
	)
	(segment
		(start 109.14888 -236.70641)
		(end 109.148118 -236.706918)
		(width 0.1143)
		(layer "In11.Cu")
		(net "P5E_CPU1_G1_TX_DN<2>")
	)
	(segment
		(start 109.159548 -228.600508)
		(end 109.148118 -228.607112)
		(width 0.1143)
		(layer "In11.Cu")
		(net "P5E_CPU1_G1_TX_DN<2>")
	)
	(segment
		(start 109.142784 -234.438698)
		(end 109.1438 -234.439206)
		(width 0.1143)
		(layer "In11.Cu")
		(net "P5E_CPU1_G1_TX_DN<2>")
	)
	(segment
		(start 109.109002 -240.898934)
		(end 109.11586 -240.902998)
		(width 0.1143)
		(layer "In11.Cu")
		(net "P5E_CPU1_G1_TX_DN<2>")
	)
	(segment
		(start 154.881326 -171.157646)
		(end 154.678126 -171.755308)
		(width 0.14224)
		(layer "In11.Cu")
		(net "P5E_CPU1_G1_TX_DN<2>")
	)
	(segment
		(start 109.116622 -227.943664)
		(end 109.117384 -227.944172)
		(width 0.1143)
		(layer "In11.Cu")
		(net "P5E_CPU1_G1_TX_DN<2>")
	)
	(segment
		(start 108.210096 -222.125794)
		(end 108.208826 -222.126556)
		(width 0.1143)
		(layer "In11.Cu")
		(net "P5E_CPU1_G1_TX_DN<2>")
	)
	(segment
		(start 109.109002 -232.798874)
		(end 109.11586 -232.802938)
		(width 0.1143)
		(layer "In11.Cu")
		(net "P5E_CPU1_G1_TX_DN<2>")
	)
	(segment
		(start 108.208064 -222.127064)
		(end 108.207048 -222.127572)
		(width 0.1143)
		(layer "In11.Cu")
		(net "P5E_CPU1_G1_TX_DN<2>")
	)
	(segment
		(start 109.14126 -232.81767)
		(end 109.142784 -232.818686)
		(width 0.1143)
		(layer "In11.Cu")
		(net "P5E_CPU1_G1_TX_DN<2>")
	)
	(segment
		(start 108.345224 -221.083378)
		(end 108.390944 -221.129098)
		(width 0.1143)
		(layer "In11.Cu")
		(net "P5E_CPU1_G1_TX_DN<2>")
	)
	(segment
		(start 108.208064 -224.721928)
		(end 108.208826 -224.722436)
		(width 0.1143)
		(layer "In11.Cu")
		(net "P5E_CPU1_G1_TX_DN<2>")
	)
	(segment
		(start 109.14888 -240.922302)
		(end 109.179868 -240.940082)
		(width 0.1143)
		(layer "In11.Cu")
		(net "P5E_CPU1_G1_TX_DN<2>")
	)
	(segment
		(start 109.1438 -234.439206)
		(end 109.145324 -234.440222)
		(width 0.1143)
		(layer "In11.Cu")
		(net "P5E_CPU1_G1_TX_DN<2>")
	)
	(segment
		(start 109.147102 -227.961444)
		(end 109.159548 -227.968556)
		(width 0.1143)
		(layer "In11.Cu")
		(net "P5E_CPU1_G1_TX_DN<2>")
	)
	(segment
		(start 109.147102 -236.06125)
		(end 109.148118 -236.061758)
		(width 0.1143)
		(layer "In11.Cu")
		(net "P5E_CPU1_G1_TX_DN<2>")
	)
	(segment
		(start 109.148118 -236.706918)
		(end 109.147102 -236.707426)
		(width 0.1143)
		(layer "In11.Cu")
		(net "P5E_CPU1_G1_TX_DN<2>")
	)
	(segment
		(start 109.109002 -234.418886)
		(end 109.11586 -234.42295)
		(width 0.1143)
		(layer "In11.Cu")
		(net "P5E_CPU1_G1_TX_DN<2>")
	)
	(segment
		(start 108.395008 -221.793054)
		(end 108.395008 -221.794324)
		(width 0.1143)
		(layer "In11.Cu")
		(net "P5E_CPU1_G1_TX_DN<2>")
	)
	(segment
		(start 108.639102 -225.509074)
		(end 108.708698 -225.549714)
		(width 0.1143)
		(layer "In11.Cu")
		(net "P5E_CPU1_G1_TX_DN<2>")
	)
	(segment
		(start 108.390944 -221.129098)
		(end 108.390944 -221.614746)
		(width 0.1143)
		(layer "In11.Cu")
		(net "P5E_CPU1_G1_TX_DN<2>")
	)
	(segment
		(start 109.147102 -238.327438)
		(end 109.145578 -238.328454)
		(width 0.1143)
		(layer "In11.Cu")
		(net "P5E_CPU1_G1_TX_DN<2>")
	)
	(segment
		(start 151.080216 -176.814734)
		(end 112.628934 -208.343246)
		(width 0.14224)
		(layer "In11.Cu")
		(net "P5E_CPU1_G1_TX_DN<2>")
	)
	(segment
		(start 109.148118 -242.541806)
		(end 109.14888 -242.542314)
		(width 0.1143)
		(layer "In11.Cu")
		(net "P5E_CPU1_G1_TX_DN<2>")
	)
	(segment
		(start 109.147102 -239.301274)
		(end 109.148118 -239.301782)
		(width 0.1143)
		(layer "In11.Cu")
		(net "P5E_CPU1_G1_TX_DN<2>")
	)
	(segment
		(start 109.142784 -236.05871)
		(end 109.1438 -236.059218)
		(width 0.1143)
		(layer "In11.Cu")
		(net "P5E_CPU1_G1_TX_DN<2>")
	)
	(segment
		(start 109.116622 -242.523518)
		(end 109.14126 -242.537742)
		(width 0.1143)
		(layer "In11.Cu")
		(net "P5E_CPU1_G1_TX_DN<2>")
	)
	(segment
		(start 109.109002 -231.179116)
		(end 109.148118 -231.201976)
		(width 0.1143)
		(layer "In11.Cu")
		(net "P5E_CPU1_G1_TX_DN<2>")
	)
	(segment
		(start 108.871766 -243.591588)
		(end 108.788962 -243.674392)
		(width 0.1143)
		(layer "In11.Cu")
		(net "P5E_CPU1_G1_TX_DN<2>")
	)
	(segment
		(start 109.14126 -237.677706)
		(end 109.142784 -237.678722)
		(width 0.1143)
		(layer "In11.Cu")
		(net "P5E_CPU1_G1_TX_DN<2>")
	)
	(segment
		(start 109.1438 -239.299242)
		(end 109.145324 -239.300258)
		(width 0.1143)
		(layer "In11.Cu")
		(net "P5E_CPU1_G1_TX_DN<2>")
	)
	(segment
		(start 108.390944 -221.614746)
		(end 108.395008 -221.793054)
		(width 0.1143)
		(layer "In11.Cu")
		(net "P5E_CPU1_G1_TX_DN<2>")
	)
	(segment
		(start 109.147102 -232.821226)
		(end 109.148118 -232.821734)
		(width 0.1143)
		(layer "In11.Cu")
		(net "P5E_CPU1_G1_TX_DN<2>")
	)
	(segment
		(start 108.239814 -224.740216)
		(end 108.241592 -224.741486)
		(width 0.1143)
		(layer "In11.Cu")
		(net "P5E_CPU1_G1_TX_DN<2>")
	)
	(segment
		(start 109.14888 -236.062266)
		(end 109.179868 -236.080046)
		(width 0.1143)
		(layer "In11.Cu")
		(net "P5E_CPU1_G1_TX_DN<2>")
	)
	(segment
		(start 109.145578 -228.608636)
		(end 109.109002 -228.629972)
		(width 0.1143)
		(layer "In11.Cu")
		(net "P5E_CPU1_G1_TX_DN<2>")
	)
	(segment
		(start 109.147102 -242.541298)
		(end 109.148118 -242.541806)
		(width 0.1143)
		(layer "In11.Cu")
		(net "P5E_CPU1_G1_TX_DN<2>")
	)
	(segment
		(start 109.148118 -233.466894)
		(end 109.147102 -233.467402)
		(width 0.1143)
		(layer "In11.Cu")
		(net "P5E_CPU1_G1_TX_DN<2>")
	)
	(segment
		(start 109.147102 -236.707426)
		(end 109.145578 -236.708442)
		(width 0.1143)
		(layer "In11.Cu")
		(net "P5E_CPU1_G1_TX_DN<2>")
	)
	(segment
		(start 109.14888 -241.566446)
		(end 109.148118 -241.566954)
		(width 0.1143)
		(layer "In11.Cu")
		(net "P5E_CPU1_G1_TX_DN<2>")
	)
	(segment
		(start 109.145578 -235.08843)
		(end 109.109002 -235.109766)
		(width 0.1143)
		(layer "In11.Cu")
		(net "P5E_CPU1_G1_TX_DN<2>")
	)
	(segment
		(start 109.197648 -241.535966)
		(end 109.179868 -241.548666)
		(width 0.1143)
		(layer "In11.Cu")
		(net "P5E_CPU1_G1_TX_DN<2>")
	)
	(segment
		(start 109.179868 -236.080046)
		(end 109.19968 -236.09427)
		(width 0.1143)
		(layer "In11.Cu")
		(net "P5E_CPU1_G1_TX_DN<2>")
	)
	(segment
		(start 109.148118 -240.921794)
		(end 109.14888 -240.922302)
		(width 0.1143)
		(layer "In11.Cu")
		(net "P5E_CPU1_G1_TX_DN<2>")
	)
	(segment
		(start 109.145324 -240.92027)
		(end 109.147102 -240.921286)
		(width 0.1143)
		(layer "In11.Cu")
		(net "P5E_CPU1_G1_TX_DN<2>")
	)
	(segment
		(start 109.147102 -231.84739)
		(end 109.145578 -231.848406)
		(width 0.1143)
		(layer "In11.Cu")
		(net "P5E_CPU1_G1_TX_DN<2>")
	)
	(segment
		(start 109.1438 -232.819194)
		(end 109.145324 -232.82021)
		(width 0.1143)
		(layer "In11.Cu")
		(net "P5E_CPU1_G1_TX_DN<2>")
	)
	(segment
		(start 109.147102 -233.467402)
		(end 109.145578 -233.468418)
		(width 0.1143)
		(layer "In11.Cu")
		(net "P5E_CPU1_G1_TX_DN<2>")
	)
	(segment
		(start 109.147102 -241.567462)
		(end 109.145578 -241.568478)
		(width 0.1143)
		(layer "In11.Cu")
		(net "P5E_CPU1_G1_TX_DN<2>")
	)
	(segment
		(start 109.14888 -232.822242)
		(end 109.179868 -232.840022)
		(width 0.1143)
		(layer "In11.Cu")
		(net "P5E_CPU1_G1_TX_DN<2>")
	)
	(segment
		(start 109.116622 -236.04347)
		(end 109.14126 -236.057694)
		(width 0.1143)
		(layer "In11.Cu")
		(net "P5E_CPU1_G1_TX_DN<2>")
	)
	(segment
		(start 108.345224 -221.05493)
		(end 108.345224 -221.083378)
		(width 0.1143)
		(layer "In11.Cu")
		(net "P5E_CPU1_G1_TX_DN<2>")
	)
	(segment
		(start 109.116622 -240.903506)
		(end 109.14126 -240.91773)
		(width 0.1143)
		(layer "In11.Cu")
		(net "P5E_CPU1_G1_TX_DN<2>")
	)
	(segment
		(start 109.14126 -236.057694)
		(end 109.142784 -236.05871)
		(width 0.1143)
		(layer "In11.Cu")
		(net "P5E_CPU1_G1_TX_DN<2>")
	)
	(segment
		(start 109.145578 -239.948466)
		(end 109.109002 -239.969802)
		(width 0.1143)
		(layer "In11.Cu")
		(net "P5E_CPU1_G1_TX_DN<2>")
	)
	(segment
		(start 109.148118 -231.846882)
		(end 109.147102 -231.84739)
		(width 0.1143)
		(layer "In11.Cu")
		(net "P5E_CPU1_G1_TX_DN<2>")
	)
	(segment
		(start 109.109002 -239.278922)
		(end 109.11586 -239.282986)
		(width 0.1143)
		(layer "In11.Cu")
		(net "P5E_CPU1_G1_TX_DN<2>")
	)
	(segment
		(start 109.11586 -236.042962)
		(end 109.116622 -236.04347)
		(width 0.1143)
		(layer "In11.Cu")
		(net "P5E_CPU1_G1_TX_DN<2>")
	)
	(segment
		(start 109.1438 -240.919254)
		(end 109.145324 -240.92027)
		(width 0.1143)
		(layer "In11.Cu")
		(net "P5E_CPU1_G1_TX_DN<2>")
	)
	(segment
		(start 109.145324 -237.680246)
		(end 109.147102 -237.681262)
		(width 0.1143)
		(layer "In11.Cu")
		(net "P5E_CPU1_G1_TX_DN<2>")
	)
	(segment
		(start 109.109764 -226.319588)
		(end 109.142784 -226.338638)
		(width 0.1143)
		(layer "In11.Cu")
		(net "P5E_CPU1_G1_TX_DN<2>")
	)
	(segment
		(start 108.16717 -222.150686)
		(end 108.156248 -222.159068)
		(width 0.1143)
		(layer "In11.Cu")
		(net "P5E_CPU1_G1_TX_DN<2>")
	)
	(segment
		(start 109.147102 -226.987608)
		(end 109.109002 -227.00996)
		(width 0.1143)
		(layer "In11.Cu")
		(net "P5E_CPU1_G1_TX_DN<2>")
	)
	(segment
		(start 109.1438 -227.959412)
		(end 109.145324 -227.960428)
		(width 0.1143)
		(layer "In11.Cu")
		(net "P5E_CPU1_G1_TX_DN<2>")
	)
	(segment
		(start 109.19968 -243.154454)
		(end 109.179868 -243.168678)
		(width 0.1143)
		(layer "In11.Cu")
		(net "P5E_CPU1_G1_TX_DN<2>")
	)
	(segment
		(start 109.147102 -240.921286)
		(end 109.148118 -240.921794)
		(width 0.1143)
		(layer "In11.Cu")
		(net "P5E_CPU1_G1_TX_DN<2>")
	)
	(segment
		(start 109.17682 -230.21036)
		(end 109.111542 -230.248206)
		(width 0.1143)
		(layer "In11.Cu")
		(net "P5E_CPU1_G1_TX_DN<2>")
	)
	(segment
		(start 109.14888 -237.682278)
		(end 109.179868 -237.700058)
		(width 0.1143)
		(layer "In11.Cu")
		(net "P5E_CPU1_G1_TX_DN<2>")
	)
	(segment
		(start 109.179868 -239.928654)
		(end 109.14888 -239.946434)
		(width 0.1143)
		(layer "In11.Cu")
		(net "P5E_CPU1_G1_TX_DN<2>")
	)
	(segment
		(start 109.14888 -239.30229)
		(end 109.179868 -239.32007)
		(width 0.1143)
		(layer "In11.Cu")
		(net "P5E_CPU1_G1_TX_DN<2>")
	)
	(segment
		(start 109.14126 -242.537742)
		(end 109.142784 -242.538758)
		(width 0.1143)
		(layer "In11.Cu")
		(net "P5E_CPU1_G1_TX_DN<2>")
	)
	(segment
		(start 109.179868 -243.168678)
		(end 109.14888 -243.186458)
		(width 0.1143)
		(layer "In11.Cu")
		(net "P5E_CPU1_G1_TX_DN<2>")
	)
	(segment
		(start 52.48656 -21.64715)
		(end 56.734456 -48.438562)
		(width 0.14224)
		(layer "In11.Cu")
		(net "P5E_CPU1_G1_TX_DN<2>")
	)
	(segment
		(start 109.14888 -235.086398)
		(end 109.148118 -235.086906)
		(width 0.1143)
		(layer "In11.Cu")
		(net "P5E_CPU1_G1_TX_DN<2>")
	)
	(segment
		(start 151.31796 -135.304022)
		(end 156.218382 -145.437352)
		(width 0.14224)
		(layer "In11.Cu")
		(net "P5E_CPU1_G1_TX_DN<2>")
	)
	(segment
		(start 109.145578 -236.708442)
		(end 109.109002 -236.729778)
		(width 0.1143)
		(layer "In11.Cu")
		(net "P5E_CPU1_G1_TX_DN<2>")
	)
	(segment
		(start 156.218382 -145.437352)
		(end 157.111954 -159.73679)
		(width 0.14224)
		(layer "In11.Cu")
		(net "P5E_CPU1_G1_TX_DN<2>")
	)
	(segment
		(start 109.115352 -229.562914)
		(end 109.176566 -229.598728)
		(width 0.1143)
		(layer "In11.Cu")
		(net "P5E_CPU1_G1_TX_DN<2>")
	)
	(segment
		(start 109.11586 -242.52301)
		(end 109.116622 -242.523518)
		(width 0.1143)
		(layer "In11.Cu")
		(net "P5E_CPU1_G1_TX_DN<2>")
	)
	(segment
		(start 108.207048 -222.127572)
		(end 108.16717 -222.150686)
		(width 0.1143)
		(layer "In11.Cu")
		(net "P5E_CPU1_G1_TX_DN<2>")
	)
	(segment
		(start 109.11586 -240.902998)
		(end 109.116622 -240.903506)
		(width 0.1143)
		(layer "In11.Cu")
		(net "P5E_CPU1_G1_TX_DN<2>")
	)
	(segment
		(start 112.628934 -208.343246)
		(end 108.345224 -215.558116)
		(width 0.14224)
		(layer "In11.Cu")
		(net "P5E_CPU1_G1_TX_DN<2>")
	)
	(segment
		(start 109.148118 -228.607112)
		(end 109.147102 -228.60762)
		(width 0.1143)
		(layer "In11.Cu")
		(net "P5E_CPU1_G1_TX_DN<2>")
	)
	(segment
		(start 109.147102 -243.187474)
		(end 109.145578 -243.18849)
		(width 0.1143)
		(layer "In11.Cu")
		(net "P5E_CPU1_G1_TX_DN<2>")
	)
	(segment
		(start 109.14888 -243.186458)
		(end 109.148118 -243.186966)
		(width 0.1143)
		(layer "In11.Cu")
		(net "P5E_CPU1_G1_TX_DN<2>")
	)
	(segment
		(start 109.19968 -236.674406)
		(end 109.179868 -236.68863)
		(width 0.1143)
		(layer "In11.Cu")
		(net "P5E_CPU1_G1_TX_DN<2>")
	)
	(segment
		(start 109.116622 -232.803446)
		(end 109.14126 -232.81767)
		(width 0.1143)
		(layer "In11.Cu")
		(net "P5E_CPU1_G1_TX_DN<2>")
	)
	(segment
		(start 109.109764 -227.9396)
		(end 109.116622 -227.943664)
		(width 0.1143)
		(layer "In11.Cu")
		(net "P5E_CPU1_G1_TX_DN<2>")
	)
	(segment
		(start 109.14634 -227.960936)
		(end 109.147102 -227.961444)
		(width 0.1143)
		(layer "In11.Cu")
		(net "P5E_CPU1_G1_TX_DN<2>")
	)
	(segment
		(start 109.14126 -239.297718)
		(end 109.142784 -239.298734)
		(width 0.1143)
		(layer "In11.Cu")
		(net "P5E_CPU1_G1_TX_DN<2>")
	)
	(segment
		(start 109.145578 -231.848406)
		(end 109.109002 -231.869742)
		(width 0.1143)
		(layer "In11.Cu")
		(net "P5E_CPU1_G1_TX_DN<2>")
	)
	(segment
		(start 108.39577 -225.042476)
		(end 108.39577 -225.044508)
		(width 0.1143)
		(layer "In11.Cu")
		(net "P5E_CPU1_G1_TX_DN<2>")
	)
	(segment
		(start 109.109002 -236.038898)
		(end 109.11586 -236.042962)
		(width 0.1143)
		(layer "In11.Cu")
		(net "P5E_CPU1_G1_TX_DN<2>")
	)
	(segment
		(start 109.148118 -237.68177)
		(end 109.14888 -237.682278)
		(width 0.1143)
		(layer "In11.Cu")
		(net "P5E_CPU1_G1_TX_DN<2>")
	)
	(segment
		(start 109.148118 -235.086906)
		(end 109.147102 -235.087414)
		(width 0.1143)
		(layer "In11.Cu")
		(net "P5E_CPU1_G1_TX_DN<2>")
	)
	(segment
		(start 109.1438 -237.67923)
		(end 109.145324 -237.680246)
		(width 0.1143)
		(layer "In11.Cu")
		(net "P5E_CPU1_G1_TX_DN<2>")
	)
	(segment
		(start 109.179868 -240.940082)
		(end 109.197648 -240.952782)
		(width 0.1143)
		(layer "In11.Cu")
		(net "P5E_CPU1_G1_TX_DN<2>")
	)
	(segment
		(start 109.144054 -226.3394)
		(end 109.144816 -226.339908)
		(width 0.1143)
		(layer "In11.Cu")
		(net "P5E_CPU1_G1_TX_DN<2>")
	)
	(segment
		(start 109.14888 -242.542314)
		(end 109.179868 -242.560094)
		(width 0.1143)
		(layer "In11.Cu")
		(net "P5E_CPU1_G1_TX_DN<2>")
	)
	(segment
		(start 109.148118 -231.201976)
		(end 109.181646 -231.221534)
		(width 0.1143)
		(layer "In11.Cu")
		(net "P5E_CPU1_G1_TX_DN<2>")
	)
	(segment
		(start 109.109002 -242.518946)
		(end 109.11586 -242.52301)
		(width 0.1143)
		(layer "In11.Cu")
		(net "P5E_CPU1_G1_TX_DN<2>")
	)
	(segment
		(start 52.19573 -19.13636)
		(end 52.48656 -19.42719)
		(width 0.14224)
		(layer "In11.Cu")
		(net "P5E_CPU1_G1_TX_DN<2>")
	)
	(segment
		(start 109.14888 -234.442254)
		(end 109.179868 -234.460034)
		(width 0.1143)
		(layer "In11.Cu")
		(net "P5E_CPU1_G1_TX_DN<2>")
	)
	(segment
		(start 108.788962 -243.674392)
		(end 108.49102 -243.674392)
		(width 0.1143)
		(layer "In11.Cu")
		(net "P5E_CPU1_G1_TX_DN<2>")
	)
	(segment
		(start 109.145578 -241.568478)
		(end 109.109002 -241.589814)
		(width 0.1143)
		(layer "In11.Cu")
		(net "P5E_CPU1_G1_TX_DN<2>")
	)
	(segment
		(start 108.240068 -223.728788)
		(end 108.166408 -223.770952)
		(width 0.1143)
		(layer "In11.Cu")
		(net "P5E_CPU1_G1_TX_DN<2>")
	)
	(segment
		(start 108.208826 -222.126556)
		(end 108.208064 -222.127064)
		(width 0.1143)
		(layer "In11.Cu")
		(net "P5E_CPU1_G1_TX_DN<2>")
	)
	(segment
		(start 109.145324 -236.060234)
		(end 109.147102 -236.06125)
		(width 0.1143)
		(layer "In11.Cu")
		(net "P5E_CPU1_G1_TX_DN<2>")
	)
	(segment
		(start 109.142784 -240.918746)
		(end 109.1438 -240.919254)
		(width 0.1143)
		(layer "In11.Cu")
		(net "P5E_CPU1_G1_TX_DN<2>")
	)
	(segment
		(start 109.148118 -241.566954)
		(end 109.147102 -241.567462)
		(width 0.1143)
		(layer "In11.Cu")
		(net "P5E_CPU1_G1_TX_DN<2>")
	)
	(segment
		(start 109.148118 -236.061758)
		(end 109.14888 -236.062266)
		(width 0.1143)
		(layer "In11.Cu")
		(net "P5E_CPU1_G1_TX_DN<2>")
	)
	(segment
		(start 108.205778 -224.720658)
		(end 108.208064 -224.721928)
		(width 0.1143)
		(layer "In11.Cu")
		(net "P5E_CPU1_G1_TX_DN<2>")
	)
	(segment
		(start 109.1438 -236.059218)
		(end 109.145324 -236.060234)
		(width 0.1143)
		(layer "In11.Cu")
		(net "P5E_CPU1_G1_TX_DN<2>")
	)
	(segment
		(start 109.148118 -239.946942)
		(end 109.147102 -239.94745)
		(width 0.1143)
		(layer "In11.Cu")
		(net "P5E_CPU1_G1_TX_DN<2>")
	)
	(segment
		(start 109.142784 -242.538758)
		(end 109.1438 -242.539266)
		(width 0.1143)
		(layer "In11.Cu")
		(net "P5E_CPU1_G1_TX_DN<2>")
	)
	(segment
		(start 109.116622 -234.423458)
		(end 109.14126 -234.437682)
		(width 0.1143)
		(layer "In11.Cu")
		(net "P5E_CPU1_G1_TX_DN<2>")
	)
	(segment
		(start 58.66384 -51.988974)
		(end 151.31796 -135.304022)
		(width 0.14224)
		(layer "In11.Cu")
		(net "P5E_CPU1_G1_TX_DN<2>")
	)
	(segment
		(start 109.144816 -226.339908)
		(end 109.149388 -226.342448)
		(width 0.1143)
		(layer "In11.Cu")
		(net "P5E_CPU1_G1_TX_DN<2>")
	)
	(segment
		(start 109.11586 -237.662974)
		(end 109.116622 -237.663482)
		(width 0.1143)
		(layer "In11.Cu")
		(net "P5E_CPU1_G1_TX_DN<2>")
	)
	(segment
		(start 108.239814 -222.108776)
		(end 108.210096 -222.125794)
		(width 0.1143)
		(layer "In11.Cu")
		(net "P5E_CPU1_G1_TX_DN<2>")
	)
	(segment
		(start 109.143546 -226.339146)
		(end 109.144054 -226.3394)
		(width 0.1143)
		(layer "In11.Cu")
		(net "P5E_CPU1_G1_TX_DN<2>")
	)
	(segment
		(start 109.142784 -232.818686)
		(end 109.1438 -232.819194)
		(width 0.1143)
		(layer "In11.Cu")
		(net "P5E_CPU1_G1_TX_DN<2>")
	)
	(segment
		(start 108.345224 -215.558116)
		(end 108.345224 -221.05493)
		(width 0.14224)
		(layer "In11.Cu")
		(net "P5E_CPU1_G1_TX_DN<2>")
	)
	(segment
		(start 109.145324 -227.960428)
		(end 109.14634 -227.960936)
		(width 0.1143)
		(layer "In11.Cu")
		(net "P5E_CPU1_G1_TX_DN<2>")
	)
	(segment
		(start 109.145324 -239.300258)
		(end 109.147102 -239.301274)
		(width 0.1143)
		(layer "In11.Cu")
		(net "P5E_CPU1_G1_TX_DN<2>")
	)
	(segment
		(start 108.16717 -223.078294)
		(end 108.241338 -223.12122)
		(width 0.1143)
		(layer "In11.Cu")
		(net "P5E_CPU1_G1_TX_DN<2>")
	)
	(segment
		(start 109.116622 -239.283494)
		(end 109.14126 -239.297718)
		(width 0.1143)
		(layer "In11.Cu")
		(net "P5E_CPU1_G1_TX_DN<2>")
	)
	(segment
		(start 108.156248 -223.069912)
		(end 108.16717 -223.078294)
		(width 0.1143)
		(layer "In11.Cu")
		(net "P5E_CPU1_G1_TX_DN<2>")
	)
	(segment
		(start 109.109002 -229.559104)
		(end 109.115098 -229.56266)
		(width 0.1143)
		(layer "In11.Cu")
		(net "P5E_CPU1_G1_TX_DN<2>")
	)
	(segment
		(start 109.145324 -234.440222)
		(end 109.147102 -234.441238)
		(width 0.1143)
		(layer "In11.Cu")
		(net "P5E_CPU1_G1_TX_DN<2>")
	)
	(segment
		(start 109.148118 -238.32693)
		(end 109.147102 -238.327438)
		(width 0.1143)
		(layer "In11.Cu")
		(net "P5E_CPU1_G1_TX_DN<2>")
	)
	(segment
		(start 109.147102 -234.441238)
		(end 109.148118 -234.441746)
		(width 0.1143)
		(layer "In11.Cu")
		(net "P5E_CPU1_G1_TX_DN<2>")
	)
	(segment
		(start 109.135164 -227.954586)
		(end 109.1438 -227.959412)
		(width 0.1143)
		(layer "In11.Cu")
		(net "P5E_CPU1_G1_TX_DN<2>")
	)
	(segment
		(start 109.115098 -229.56266)
		(end 109.115352 -229.562914)
		(width 0.1143)
		(layer "In11.Cu")
		(net "P5E_CPU1_G1_TX_DN<2>")
	)
	(segment
		(start 109.109002 -237.65891)
		(end 109.11586 -237.662974)
		(width 0.1143)
		(layer "In11.Cu")
		(net "P5E_CPU1_G1_TX_DN<2>")
	)
	(segment
		(start 109.145578 -233.468418)
		(end 109.109002 -233.489754)
		(width 0.1143)
		(layer "In11.Cu")
		(net "P5E_CPU1_G1_TX_DN<2>")
	)
	(segment
		(start 109.179868 -235.068618)
		(end 109.14888 -235.086398)
		(width 0.1143)
		(layer "In11.Cu")
		(net "P5E_CPU1_G1_TX_DN<2>")
	)
	(segment
		(start 109.14888 -239.946434)
		(end 109.148118 -239.946942)
		(width 0.1143)
		(layer "In11.Cu")
		(net "P5E_CPU1_G1_TX_DN<2>")
	)
	(segment
		(start 108.208826 -224.722436)
		(end 108.239814 -224.740216)
		(width 0.1143)
		(layer "In11.Cu")
		(net "P5E_CPU1_G1_TX_DN<2>")
	)
	(segment
		(start 56.734456 -48.438562)
		(end 58.66384 -51.988974)
		(width 0.14224)
		(layer "In11.Cu")
		(net "P5E_CPU1_G1_TX_DN<2>")
	)
	(segment
		(start 109.147102 -239.94745)
		(end 109.145578 -239.948466)
		(width 0.1143)
		(layer "In11.Cu")
		(net "P5E_CPU1_G1_TX_DN<2>")
	)
	(segment
		(start 109.11586 -239.282986)
		(end 109.116622 -239.283494)
		(width 0.1143)
		(layer "In11.Cu")
		(net "P5E_CPU1_G1_TX_DN<2>")
	)
	(arc
		(start 109.109002 -235.109766)
		(mid 108.865675 -235.574332)
		(end 109.109002 -236.038898)
		(width 0.1143)
		(layer "In11.Cu")
		(net "P5E_CPU1_G1_TX_DN<2>")
	)
	(arc
		(start 109.159548 -227.968556)
		(mid 109.334498 -228.284532)
		(end 109.159548 -228.600508)
		(width 0.1143)
		(layer "In11.Cu")
		(net "P5E_CPU1_G1_TX_DN<2>")
	)
	(arc
		(start 109.109002 -241.589814)
		(mid 108.865675 -242.05438)
		(end 109.109002 -242.518946)
		(width 0.1143)
		(layer "In11.Cu")
		(net "P5E_CPU1_G1_TX_DN<2>")
	)
	(arc
		(start 109.109002 -243.209826)
		(mid 108.957015 -243.366334)
		(end 108.875576 -243.568728)
		(width 0.1143)
		(layer "In11.Cu")
		(net "P5E_CPU1_G1_TX_DN<2>")
	)
	(arc
		(start 108.39577 -225.044508)
		(mid 108.460285 -225.306727)
		(end 108.639102 -225.509074)
		(width 0.1143)
		(layer "In11.Cu")
		(net "P5E_CPU1_G1_TX_DN<2>")
	)
	(arc
		(start 109.109002 -227.00996)
		(mid 108.865675 -227.474526)
		(end 109.109002 -227.939092)
		(width 0.1143)
		(layer "In11.Cu")
		(net "P5E_CPU1_G1_TX_DN<2>")
	)
	(arc
		(start 108.156248 -222.159068)
		(mid 107.923917 -222.61449)
		(end 108.156248 -223.069912)
		(width 0.1143)
		(layer "In11.Cu")
		(net "P5E_CPU1_G1_TX_DN<2>")
	)
	(arc
		(start 109.333792 -229.908862)
		(mid 109.281395 -230.073199)
		(end 109.17682 -230.21036)
		(width 0.1143)
		(layer "In11.Cu")
		(net "P5E_CPU1_G1_TX_DN<2>")
	)
	(arc
		(start 109.179868 -232.840022)
		(mid 109.328965 -233.144314)
		(end 109.179868 -233.448606)
		(width 0.1143)
		(layer "In11.Cu")
		(net "P5E_CPU1_G1_TX_DN<2>")
	)
	(arc
		(start 109.197648 -240.952782)
		(mid 109.34707 -241.244374)
		(end 109.197648 -241.535966)
		(width 0.1143)
		(layer "In11.Cu")
		(net "P5E_CPU1_G1_TX_DN<2>")
	)
	(arc
		(start 109.179868 -234.460034)
		(mid 109.328965 -234.764326)
		(end 109.179868 -235.068618)
		(width 0.1143)
		(layer "In11.Cu")
		(net "P5E_CPU1_G1_TX_DN<2>")
	)
	(arc
		(start 109.109002 -239.969802)
		(mid 108.865675 -240.434368)
		(end 109.109002 -240.898934)
		(width 0.1143)
		(layer "In11.Cu")
		(net "P5E_CPU1_G1_TX_DN<2>")
	)
	(arc
		(start 107.92587 -224.226628)
		(mid 107.925855 -224.230565)
		(end 107.92587 -224.234502)
		(width 0.1143)
		(layer "In11.Cu")
		(net "P5E_CPU1_G1_TX_DN<2>")
	)
	(arc
		(start 108.875576 -243.568728)
		(mid 108.873553 -243.580138)
		(end 108.871766 -243.591588)
		(width 0.1143)
		(layer "In11.Cu")
		(net "P5E_CPU1_G1_TX_DN<2>")
	)
	(arc
		(start 109.109002 -231.869742)
		(mid 108.865675 -232.334308)
		(end 109.109002 -232.798874)
		(width 0.1143)
		(layer "In11.Cu")
		(net "P5E_CPU1_G1_TX_DN<2>")
	)
	(arc
		(start 109.245908 -229.66045)
		(mid 109.308864 -229.777934)
		(end 109.333792 -229.908862)
		(width 0.1143)
		(layer "In11.Cu")
		(net "P5E_CPU1_G1_TX_DN<2>")
	)
	(arc
		(start 109.109002 -233.489754)
		(mid 108.865675 -233.95432)
		(end 109.109002 -234.418886)
		(width 0.1143)
		(layer "In11.Cu")
		(net "P5E_CPU1_G1_TX_DN<2>")
	)
	(arc
		(start 108.241338 -223.12122)
		(mid 108.395915 -223.425308)
		(end 108.240068 -223.728788)
		(width 0.1143)
		(layer "In11.Cu")
		(net "P5E_CPU1_G1_TX_DN<2>")
	)
	(arc
		(start 108.708698 -225.549714)
		(mid 108.824125 -225.68309)
		(end 108.86567 -225.854514)
		(width 0.1143)
		(layer "In11.Cu")
		(net "P5E_CPU1_G1_TX_DN<2>")
	)
	(arc
		(start 109.109002 -228.629972)
		(mid 108.865675 -229.094538)
		(end 109.109002 -229.559104)
		(width 0.1143)
		(layer "In11.Cu")
		(net "P5E_CPU1_G1_TX_DN<2>")
	)
	(arc
		(start 108.15447 -223.78035)
		(mid 107.991272 -223.978434)
		(end 107.92587 -224.226628)
		(width 0.1143)
		(layer "In11.Cu")
		(net "P5E_CPU1_G1_TX_DN<2>")
	)
	(arc
		(start 107.92587 -224.234502)
		(mid 108.00085 -224.514986)
		(end 108.205778 -224.720658)
		(width 0.1143)
		(layer "In11.Cu")
		(net "P5E_CPU1_G1_TX_DN<2>")
	)
	(arc
		(start 109.109002 -226.31908)
		(mid 109.109383 -226.319334)
		(end 109.109764 -226.319588)
		(width 0.1143)
		(layer "In11.Cu")
		(net "P5E_CPU1_G1_TX_DN<2>")
	)
	(arc
		(start 109.181646 -231.221534)
		(mid 109.295053 -231.354423)
		(end 109.335824 -231.524302)
		(width 0.1143)
		(layer "In11.Cu")
		(net "P5E_CPU1_G1_TX_DN<2>")
	)
	(arc
		(start 109.179868 -239.32007)
		(mid 109.331457 -239.624362)
		(end 109.179868 -239.928654)
		(width 0.1143)
		(layer "In11.Cu")
		(net "P5E_CPU1_G1_TX_DN<2>")
	)
	(arc
		(start 108.395008 -221.794324)
		(mid 108.380556 -221.910792)
		(end 108.330238 -222.016828)
		(width 0.1143)
		(layer "In11.Cu")
		(net "P5E_CPU1_G1_TX_DN<2>")
	)
	(arc
		(start 109.109002 -238.34979)
		(mid 108.865675 -238.814356)
		(end 109.109002 -239.278922)
		(width 0.1143)
		(layer "In11.Cu")
		(net "P5E_CPU1_G1_TX_DN<2>")
	)
	(arc
		(start 109.335824 -231.524302)
		(mid 109.291753 -231.693838)
		(end 109.179868 -231.828594)
		(width 0.1143)
		(layer "In11.Cu")
		(net "P5E_CPU1_G1_TX_DN<2>")
	)
	(arc
		(start 109.176566 -229.598728)
		(mid 109.214286 -229.62616)
		(end 109.245908 -229.66045)
		(width 0.1143)
		(layer "In11.Cu")
		(net "P5E_CPU1_G1_TX_DN<2>")
	)
	(arc
		(start 108.86567 -225.854514)
		(mid 108.930185 -226.116733)
		(end 109.109002 -226.31908)
		(width 0.1143)
		(layer "In11.Cu")
		(net "P5E_CPU1_G1_TX_DN<2>")
	)
	(arc
		(start 108.241592 -224.741486)
		(mid 108.354997 -224.873381)
		(end 108.39577 -225.042476)
		(width 0.1143)
		(layer "In11.Cu")
		(net "P5E_CPU1_G1_TX_DN<2>")
	)
	(arc
		(start 108.32973 -222.016828)
		(mid 108.288747 -222.06669)
		(end 108.239814 -222.108776)
		(width 0.1143)
		(layer "In11.Cu")
		(net "P5E_CPU1_G1_TX_DN<2>")
	)
	(arc
		(start 109.109002 -227.939092)
		(mid 109.109383 -227.939346)
		(end 109.109764 -227.9396)
		(width 0.1143)
		(layer "In11.Cu")
		(net "P5E_CPU1_G1_TX_DN<2>")
	)
	(arc
		(start 109.109002 -236.729778)
		(mid 108.865675 -237.194344)
		(end 109.109002 -237.65891)
		(width 0.1143)
		(layer "In11.Cu")
		(net "P5E_CPU1_G1_TX_DN<2>")
	)
	(arc
		(start 109.19968 -242.574318)
		(mid 109.348394 -242.864386)
		(end 109.19968 -243.154454)
		(width 0.1143)
		(layer "In11.Cu")
		(net "P5E_CPU1_G1_TX_DN<2>")
	)
	(arc
		(start 109.111542 -230.248206)
		(mid 108.865654 -230.713)
		(end 109.109002 -231.179116)
		(width 0.1143)
		(layer "In11.Cu")
		(net "P5E_CPU1_G1_TX_DN<2>")
	)
	(arc
		(start 109.149388 -226.342448)
		(mid 109.334713 -226.66463)
		(end 109.149134 -226.986592)
		(width 0.1143)
		(layer "In11.Cu")
		(net "P5E_CPU1_G1_TX_DN<2>")
	)
	(arc
		(start 109.179868 -237.700058)
		(mid 109.331457 -238.00435)
		(end 109.179868 -238.308642)
		(width 0.1143)
		(layer "In11.Cu")
		(net "P5E_CPU1_G1_TX_DN<2>")
	)
	(arc
		(start 109.19968 -236.09427)
		(mid 109.348394 -236.384338)
		(end 109.19968 -236.674406)
		(width 0.1143)
		(layer "In11.Cu")
		(net "P5E_CPU1_G1_TX_DN<2>")
	)
	(segment
		(start 55.26024 -16.662146)
		(end 55.26024 -17.341596)
		(width 0.12954)
		(layer "F.Cu")
		(net "P5E_CPU1_G1_TX_DN<1>")
	)
	(segment
		(start 54.96433 -16.366236)
		(end 55.26024 -16.662146)
		(width 0.12954)
		(layer "F.Cu")
		(net "P5E_CPU1_G1_TX_DN<1>")
	)
	(segment
		(start 108.957872 -247.180354)
		(end 108.49102 -246.914416)
		(width 0.12954)
		(layer "F.Cu")
		(net "P5E_CPU1_G1_TX_DN<1>")
	)
	(segment
		(start 55.26024 -17.341596)
		(end 54.988714 -17.613122)
		(width 0.12954)
		(layer "F.Cu")
		(net "P5E_CPU1_G1_TX_DN<1>")
	)
	(segment
		(start 110.118652 -226.96932)
		(end 110.088172 -226.9871)
		(width 0.1143)
		(layer "In11.Cu")
		(net "P5E_CPU1_G1_TX_DN<1>")
	)
	(segment
		(start 109.148118 -224.721928)
		(end 109.14888 -224.722436)
		(width 0.1143)
		(layer "In11.Cu")
		(net "P5E_CPU1_G1_TX_DN<1>")
	)
	(segment
		(start 110.12297 -235.066332)
		(end 110.120938 -235.067856)
		(width 0.1143)
		(layer "In11.Cu")
		(net "P5E_CPU1_G1_TX_DN<1>")
	)
	(segment
		(start 110.120938 -232.840784)
		(end 110.12297 -232.842308)
		(width 0.1143)
		(layer "In11.Cu")
		(net "P5E_CPU1_G1_TX_DN<1>")
	)
	(segment
		(start 109.618018 -245.616984)
		(end 109.61751 -245.617238)
		(width 0.1143)
		(layer "In11.Cu")
		(net "P5E_CPU1_G1_TX_DN<1>")
	)
	(segment
		(start 109.144562 -224.719896)
		(end 109.145578 -224.720404)
		(width 0.1143)
		(layer "In11.Cu")
		(net "P5E_CPU1_G1_TX_DN<1>")
	)
	(segment
		(start 109.290104 -221.05493)
		(end 109.290104 -221.083378)
		(width 0.1143)
		(layer "In11.Cu")
		(net "P5E_CPU1_G1_TX_DN<1>")
	)
	(segment
		(start 154.61234 -139.96289)
		(end 157.14218 -145.194782)
		(width 0.14224)
		(layer "In11.Cu")
		(net "P5E_CPU1_G1_TX_DN<1>")
	)
	(segment
		(start 110.088172 -226.9871)
		(end 110.049056 -227.00996)
		(width 0.1143)
		(layer "In11.Cu")
		(net "P5E_CPU1_G1_TX_DN<1>")
	)
	(segment
		(start 110.088172 -227.961952)
		(end 110.118652 -227.979732)
		(width 0.1143)
		(layer "In11.Cu")
		(net "P5E_CPU1_G1_TX_DN<1>")
	)
	(segment
		(start 157.14218 -145.194782)
		(end 158.04896 -159.707326)
		(width 0.14224)
		(layer "In11.Cu")
		(net "P5E_CPU1_G1_TX_DN<1>")
	)
	(segment
		(start 154.612086 -139.96289)
		(end 154.61234 -139.96289)
		(width 0.14224)
		(layer "In11.Cu")
		(net "P5E_CPU1_G1_TX_DN<1>")
	)
	(segment
		(start 110.049056 -227.939092)
		(end 110.088172 -227.961952)
		(width 0.1143)
		(layer "In11.Cu")
		(net "P5E_CPU1_G1_TX_DN<1>")
	)
	(segment
		(start 155.41625 -172.460666)
		(end 151.998172 -177.26787)
		(width 0.14224)
		(layer "In11.Cu")
		(net "P5E_CPU1_G1_TX_DN<1>")
	)
	(segment
		(start 55.279544 -24.41702)
		(end 57.728358 -48.052482)
		(width 0.14224)
		(layer "In11.Cu")
		(net "P5E_CPU1_G1_TX_DN<1>")
	)
	(segment
		(start 152.0825 -134.730744)
		(end 154.612086 -139.96289)
		(width 0.14224)
		(layer "In11.Cu")
		(net "P5E_CPU1_G1_TX_DN<1>")
	)
	(segment
		(start 109.577886 -244.948456)
		(end 109.649514 -244.990112)
		(width 0.1143)
		(layer "In11.Cu")
		(net "P5E_CPU1_G1_TX_DN<1>")
	)
	(segment
		(start 110.121446 -243.167154)
		(end 110.118652 -243.169186)
		(width 0.1143)
		(layer "In11.Cu")
		(net "P5E_CPU1_G1_TX_DN<1>")
	)
	(segment
		(start 110.118652 -228.589332)
		(end 110.088172 -228.607112)
		(width 0.1143)
		(layer "In11.Cu")
		(net "P5E_CPU1_G1_TX_DN<1>")
	)
	(segment
		(start 108.871766 -246.831612)
		(end 108.788962 -246.914416)
		(width 0.1143)
		(layer "In11.Cu")
		(net "P5E_CPU1_G1_TX_DN<1>")
	)
	(segment
		(start 109.61878 -245.616476)
		(end 109.618018 -245.616984)
		(width 0.1143)
		(layer "In11.Cu")
		(net "P5E_CPU1_G1_TX_DN<1>")
	)
	(segment
		(start 109.290104 -215.886284)
		(end 109.290104 -221.05493)
		(width 0.14224)
		(layer "In11.Cu")
		(net "P5E_CPU1_G1_TX_DN<1>")
	)
	(segment
		(start 109.622336 -245.614444)
		(end 109.621574 -245.614952)
		(width 0.1143)
		(layer "In11.Cu")
		(net "P5E_CPU1_G1_TX_DN<1>")
	)
	(segment
		(start 151.998172 -177.26787)
		(end 113.454434 -208.872074)
		(width 0.14224)
		(layer "In11.Cu")
		(net "P5E_CPU1_G1_TX_DN<1>")
	)
	(segment
		(start 108.788962 -246.914416)
		(end 108.49102 -246.914416)
		(width 0.1143)
		(layer "In11.Cu")
		(net "P5E_CPU1_G1_TX_DN<1>")
	)
	(segment
		(start 110.088172 -239.301782)
		(end 110.120938 -239.320832)
		(width 0.1143)
		(layer "In11.Cu")
		(net "P5E_CPU1_G1_TX_DN<1>")
	)
	(segment
		(start 59.4487 -51.432206)
		(end 152.0825 -134.730744)
		(width 0.14224)
		(layer "In11.Cu")
		(net "P5E_CPU1_G1_TX_DN<1>")
	)
	(segment
		(start 109.624368 -245.613428)
		(end 109.622336 -245.614444)
		(width 0.1143)
		(layer "In11.Cu")
		(net "P5E_CPU1_G1_TX_DN<1>")
	)
	(segment
		(start 110.120938 -239.927892)
		(end 110.049056 -239.969802)
		(width 0.1143)
		(layer "In11.Cu")
		(net "P5E_CPU1_G1_TX_DN<1>")
	)
	(segment
		(start 109.620558 -245.61546)
		(end 109.619796 -245.615968)
		(width 0.1143)
		(layer "In11.Cu")
		(net "P5E_CPU1_G1_TX_DN<1>")
	)
	(segment
		(start 113.454434 -208.872074)
		(end 109.290104 -215.886284)
		(width 0.14224)
		(layer "In11.Cu")
		(net "P5E_CPU1_G1_TX_DN<1>")
	)
	(segment
		(start 110.049056 -232.798874)
		(end 110.088172 -232.821734)
		(width 0.1143)
		(layer "In11.Cu")
		(net "P5E_CPU1_G1_TX_DN<1>")
	)
	(segment
		(start 109.151674 -246.424958)
		(end 109.14761 -246.427244)
		(width 0.1143)
		(layer "In11.Cu")
		(net "P5E_CPU1_G1_TX_DN<1>")
	)
	(segment
		(start 110.049056 -234.418886)
		(end 110.088172 -234.441746)
		(width 0.1143)
		(layer "In11.Cu")
		(net "P5E_CPU1_G1_TX_DN<1>")
	)
	(segment
		(start 109.577886 -244.02034)
		(end 109.56036 -244.033294)
		(width 0.1143)
		(layer "In11.Cu")
		(net "P5E_CPU1_G1_TX_DN<1>")
	)
	(segment
		(start 109.146848 -246.427752)
		(end 109.109002 -246.44985)
		(width 0.1143)
		(layer "In11.Cu")
		(net "P5E_CPU1_G1_TX_DN<1>")
	)
	(segment
		(start 110.088172 -228.607112)
		(end 110.049056 -228.629972)
		(width 0.1143)
		(layer "In11.Cu")
		(net "P5E_CPU1_G1_TX_DN<1>")
	)
	(segment
		(start 110.088172 -237.68177)
		(end 110.120938 -237.70082)
		(width 0.1143)
		(layer "In11.Cu")
		(net "P5E_CPU1_G1_TX_DN<1>")
	)
	(segment
		(start 110.120938 -237.70082)
		(end 110.12297 -237.702344)
		(width 0.1143)
		(layer "In11.Cu")
		(net "P5E_CPU1_G1_TX_DN<1>")
	)
	(segment
		(start 109.179868 -223.728788)
		(end 109.107986 -223.770698)
		(width 0.1143)
		(layer "In11.Cu")
		(net "P5E_CPU1_G1_TX_DN<1>")
	)
	(segment
		(start 110.275116 -229.902004)
		(end 110.274862 -229.902004)
		(width 0.1143)
		(layer "In11.Cu")
		(net "P5E_CPU1_G1_TX_DN<1>")
	)
	(segment
		(start 109.142022 -224.718372)
		(end 109.144562 -224.719896)
		(width 0.1143)
		(layer "In11.Cu")
		(net "P5E_CPU1_G1_TX_DN<1>")
	)
	(segment
		(start 109.335824 -221.129098)
		(end 109.335824 -221.387924)
		(width 0.1143)
		(layer "In11.Cu")
		(net "P5E_CPU1_G1_TX_DN<1>")
	)
	(segment
		(start 109.649514 -244.990112)
		(end 109.649768 -244.990112)
		(width 0.1143)
		(layer "In11.Cu")
		(net "P5E_CPU1_G1_TX_DN<1>")
	)
	(segment
		(start 109.33684 -221.80423)
		(end 109.3343 -223.428306)
		(width 0.1143)
		(layer "In11.Cu")
		(net "P5E_CPU1_G1_TX_DN<1>")
	)
	(segment
		(start 109.56036 -244.935502)
		(end 109.577886 -244.948456)
		(width 0.1143)
		(layer "In11.Cu")
		(net "P5E_CPU1_G1_TX_DN<1>")
	)
	(segment
		(start 110.049056 -236.038898)
		(end 110.088172 -236.061758)
		(width 0.1143)
		(layer "In11.Cu")
		(net "P5E_CPU1_G1_TX_DN<1>")
	)
	(segment
		(start 109.621574 -245.614952)
		(end 109.620558 -245.61546)
		(width 0.1143)
		(layer "In11.Cu")
		(net "P5E_CPU1_G1_TX_DN<1>")
	)
	(segment
		(start 109.33684 -221.38894)
		(end 109.33684 -221.80423)
		(width 0.1143)
		(layer "In11.Cu")
		(net "P5E_CPU1_G1_TX_DN<1>")
	)
	(segment
		(start 109.618272 -225.531934)
		(end 109.648752 -225.549714)
		(width 0.1143)
		(layer "In11.Cu")
		(net "P5E_CPU1_G1_TX_DN<1>")
	)
	(segment
		(start 109.15015 -224.723198)
		(end 109.179868 -224.740216)
		(width 0.1143)
		(layer "In11.Cu")
		(net "P5E_CPU1_G1_TX_DN<1>")
	)
	(segment
		(start 110.118652 -243.169186)
		(end 110.049056 -243.209826)
		(width 0.1143)
		(layer "In11.Cu")
		(net "P5E_CPU1_G1_TX_DN<1>")
	)
	(segment
		(start 110.049056 -240.898934)
		(end 110.12805 -240.944908)
		(width 0.1143)
		(layer "In11.Cu")
		(net "P5E_CPU1_G1_TX_DN<1>")
	)
	(segment
		(start 110.049056 -231.179116)
		(end 110.088172 -231.201976)
		(width 0.1143)
		(layer "In11.Cu")
		(net "P5E_CPU1_G1_TX_DN<1>")
	)
	(segment
		(start 110.049056 -226.31908)
		(end 110.088172 -226.34194)
		(width 0.1143)
		(layer "In11.Cu")
		(net "P5E_CPU1_G1_TX_DN<1>")
	)
	(segment
		(start 110.12297 -238.306356)
		(end 110.120938 -238.30788)
		(width 0.1143)
		(layer "In11.Cu")
		(net "P5E_CPU1_G1_TX_DN<1>")
	)
	(segment
		(start 109.579156 -225.509074)
		(end 109.618272 -225.531934)
		(width 0.1143)
		(layer "In11.Cu")
		(net "P5E_CPU1_G1_TX_DN<1>")
	)
	(segment
		(start 110.120938 -233.447844)
		(end 110.049056 -233.489754)
		(width 0.1143)
		(layer "In11.Cu")
		(net "P5E_CPU1_G1_TX_DN<1>")
	)
	(segment
		(start 110.088172 -231.201976)
		(end 110.120684 -231.220772)
		(width 0.1143)
		(layer "In11.Cu")
		(net "P5E_CPU1_G1_TX_DN<1>")
	)
	(segment
		(start 109.140498 -224.717356)
		(end 109.142022 -224.718372)
		(width 0.1143)
		(layer "In11.Cu")
		(net "P5E_CPU1_G1_TX_DN<1>")
	)
	(segment
		(start 155.506166 -172.216318)
		(end 155.41625 -172.460666)
		(width 0.14224)
		(layer "In11.Cu")
		(net "P5E_CPU1_G1_TX_DN<1>")
	)
	(segment
		(start 110.088172 -232.821734)
		(end 110.120938 -232.840784)
		(width 0.1143)
		(layer "In11.Cu")
		(net "P5E_CPU1_G1_TX_DN<1>")
	)
	(segment
		(start 109.619796 -245.615968)
		(end 109.61878 -245.616476)
		(width 0.1143)
		(layer "In11.Cu")
		(net "P5E_CPU1_G1_TX_DN<1>")
	)
	(segment
		(start 110.049056 -242.518946)
		(end 110.120938 -242.560856)
		(width 0.1143)
		(layer "In11.Cu")
		(net "P5E_CPU1_G1_TX_DN<1>")
	)
	(segment
		(start 110.120938 -234.460796)
		(end 110.12297 -234.46232)
		(width 0.1143)
		(layer "In11.Cu")
		(net "P5E_CPU1_G1_TX_DN<1>")
	)
	(segment
		(start 109.14888 -224.722436)
		(end 109.15015 -224.723198)
		(width 0.1143)
		(layer "In11.Cu")
		(net "P5E_CPU1_G1_TX_DN<1>")
	)
	(segment
		(start 110.088172 -234.441746)
		(end 110.120938 -234.460796)
		(width 0.1143)
		(layer "In11.Cu")
		(net "P5E_CPU1_G1_TX_DN<1>")
	)
	(segment
		(start 109.335824 -221.387924)
		(end 109.33684 -221.38894)
		(width 0.1143)
		(layer "In11.Cu")
		(net "P5E_CPU1_G1_TX_DN<1>")
	)
	(segment
		(start 158.04896 -159.707326)
		(end 158.04896 -164.751258)
		(width 0.14224)
		(layer "In11.Cu")
		(net "P5E_CPU1_G1_TX_DN<1>")
	)
	(segment
		(start 110.120938 -235.067856)
		(end 110.049056 -235.109766)
		(width 0.1143)
		(layer "In11.Cu")
		(net "P5E_CPU1_G1_TX_DN<1>")
	)
	(segment
		(start 110.12297 -233.44632)
		(end 110.120938 -233.447844)
		(width 0.1143)
		(layer "In11.Cu")
		(net "P5E_CPU1_G1_TX_DN<1>")
	)
	(segment
		(start 110.118652 -230.20909)
		(end 110.051596 -230.248206)
		(width 0.1143)
		(layer "In11.Cu")
		(net "P5E_CPU1_G1_TX_DN<1>")
	)
	(segment
		(start 109.147102 -224.72142)
		(end 109.148118 -224.721928)
		(width 0.1143)
		(layer "In11.Cu")
		(net "P5E_CPU1_G1_TX_DN<1>")
	)
	(segment
		(start 109.145578 -224.720404)
		(end 109.147102 -224.72142)
		(width 0.1143)
		(layer "In11.Cu")
		(net "P5E_CPU1_G1_TX_DN<1>")
	)
	(segment
		(start 110.275878 -242.864386)
		(end 110.275624 -242.864386)
		(width 0.1143)
		(layer "In11.Cu")
		(net "P5E_CPU1_G1_TX_DN<1>")
	)
	(segment
		(start 110.12297 -239.926368)
		(end 110.120938 -239.927892)
		(width 0.1143)
		(layer "In11.Cu")
		(net "P5E_CPU1_G1_TX_DN<1>")
	)
	(segment
		(start 55.279544 -17.903952)
		(end 55.279544 -24.41702)
		(width 0.14224)
		(layer "In11.Cu")
		(net "P5E_CPU1_G1_TX_DN<1>")
	)
	(segment
		(start 110.088172 -231.846882)
		(end 110.049056 -231.869742)
		(width 0.1143)
		(layer "In11.Cu")
		(net "P5E_CPU1_G1_TX_DN<1>")
	)
	(segment
		(start 110.120938 -236.080808)
		(end 110.12297 -236.082332)
		(width 0.1143)
		(layer "In11.Cu")
		(net "P5E_CPU1_G1_TX_DN<1>")
	)
	(segment
		(start 158.04896 -164.751258)
		(end 155.506166 -172.216318)
		(width 0.14224)
		(layer "In11.Cu")
		(net "P5E_CPU1_G1_TX_DN<1>")
	)
	(segment
		(start 110.049056 -237.65891)
		(end 110.088172 -237.68177)
		(width 0.1143)
		(layer "In11.Cu")
		(net "P5E_CPU1_G1_TX_DN<1>")
	)
	(segment
		(start 110.088172 -236.061758)
		(end 110.120938 -236.080808)
		(width 0.1143)
		(layer "In11.Cu")
		(net "P5E_CPU1_G1_TX_DN<1>")
	)
	(segment
		(start 110.12297 -236.686344)
		(end 110.120938 -236.687868)
		(width 0.1143)
		(layer "In11.Cu")
		(net "P5E_CPU1_G1_TX_DN<1>")
	)
	(segment
		(start 110.274862 -229.902004)
		(end 110.27537 -229.91191)
		(width 0.1143)
		(layer "In11.Cu")
		(net "P5E_CPU1_G1_TX_DN<1>")
	)
	(segment
		(start 109.649768 -245.598696)
		(end 109.624368 -245.613428)
		(width 0.1143)
		(layer "In11.Cu")
		(net "P5E_CPU1_G1_TX_DN<1>")
	)
	(segment
		(start 110.120938 -236.687868)
		(end 110.049056 -236.729778)
		(width 0.1143)
		(layer "In11.Cu")
		(net "P5E_CPU1_G1_TX_DN<1>")
	)
	(segment
		(start 110.120938 -238.30788)
		(end 110.049056 -238.34979)
		(width 0.1143)
		(layer "In11.Cu")
		(net "P5E_CPU1_G1_TX_DN<1>")
	)
	(segment
		(start 54.988714 -17.613122)
		(end 55.279544 -17.903952)
		(width 0.14224)
		(layer "In11.Cu")
		(net "P5E_CPU1_G1_TX_DN<1>")
	)
	(segment
		(start 110.049056 -229.559104)
		(end 110.11535 -229.597712)
		(width 0.1143)
		(layer "In11.Cu")
		(net "P5E_CPU1_G1_TX_DN<1>")
	)
	(segment
		(start 110.275624 -242.864386)
		(end 110.275624 -242.867688)
		(width 0.1143)
		(layer "In11.Cu")
		(net "P5E_CPU1_G1_TX_DN<1>")
	)
	(segment
		(start 110.118652 -231.829102)
		(end 110.088172 -231.846882)
		(width 0.1143)
		(layer "In11.Cu")
		(net "P5E_CPU1_G1_TX_DN<1>")
	)
	(segment
		(start 110.12805 -241.54384)
		(end 110.049056 -241.589814)
		(width 0.1143)
		(layer "In11.Cu")
		(net "P5E_CPU1_G1_TX_DN<1>")
	)
	(segment
		(start 57.728358 -48.052482)
		(end 59.4487 -51.432206)
		(width 0.14224)
		(layer "In11.Cu")
		(net "P5E_CPU1_G1_TX_DN<1>")
	)
	(segment
		(start 109.290104 -221.083378)
		(end 109.335824 -221.129098)
		(width 0.1143)
		(layer "In11.Cu")
		(net "P5E_CPU1_G1_TX_DN<1>")
	)
	(segment
		(start 109.109002 -224.699068)
		(end 109.140498 -224.717356)
		(width 0.1143)
		(layer "In11.Cu")
		(net "P5E_CPU1_G1_TX_DN<1>")
	)
	(segment
		(start 109.649768 -243.978684)
		(end 109.577886 -244.02034)
		(width 0.1143)
		(layer "In11.Cu")
		(net "P5E_CPU1_G1_TX_DN<1>")
	)
	(segment
		(start 109.14761 -246.427244)
		(end 109.146848 -246.427752)
		(width 0.1143)
		(layer "In11.Cu")
		(net "P5E_CPU1_G1_TX_DN<1>")
	)
	(segment
		(start 110.120938 -239.320832)
		(end 110.12297 -239.322356)
		(width 0.1143)
		(layer "In11.Cu")
		(net "P5E_CPU1_G1_TX_DN<1>")
	)
	(segment
		(start 110.049056 -239.278922)
		(end 110.088172 -239.301782)
		(width 0.1143)
		(layer "In11.Cu")
		(net "P5E_CPU1_G1_TX_DN<1>")
	)
	(segment
		(start 110.088172 -226.34194)
		(end 110.118652 -226.35972)
		(width 0.1143)
		(layer "In11.Cu")
		(net "P5E_CPU1_G1_TX_DN<1>")
	)
	(arc
		(start 109.33938 -246.100346)
		(mid 109.289084 -246.287848)
		(end 109.151674 -246.424958)
		(width 0.1143)
		(layer "In11.Cu")
		(net "P5E_CPU1_G1_TX_DN<1>")
	)
	(arc
		(start 110.049056 -227.00996)
		(mid 109.805729 -227.474526)
		(end 110.049056 -227.939092)
		(width 0.1143)
		(layer "In11.Cu")
		(net "P5E_CPU1_G1_TX_DN<1>")
	)
	(arc
		(start 110.049056 -238.34979)
		(mid 109.805729 -238.814356)
		(end 110.049056 -239.278922)
		(width 0.1143)
		(layer "In11.Cu")
		(net "P5E_CPU1_G1_TX_DN<1>")
	)
	(arc
		(start 109.012228 -246.53494)
		(mid 108.925006 -246.662418)
		(end 108.875576 -246.808752)
		(width 0.1143)
		(layer "In11.Cu")
		(net "P5E_CPU1_G1_TX_DN<1>")
	)
	(arc
		(start 109.109002 -246.44985)
		(mid 109.05819 -246.489636)
		(end 109.012228 -246.53494)
		(width 0.1143)
		(layer "In11.Cu")
		(net "P5E_CPU1_G1_TX_DN<1>")
	)
	(arc
		(start 109.61751 -245.617238)
		(mid 109.413847 -245.82161)
		(end 109.33938 -246.100346)
		(width 0.1143)
		(layer "In11.Cu")
		(net "P5E_CPU1_G1_TX_DN<1>")
	)
	(arc
		(start 110.12297 -234.46232)
		(mid 110.27715 -234.764326)
		(end 110.12297 -235.066332)
		(width 0.1143)
		(layer "In11.Cu")
		(net "P5E_CPU1_G1_TX_DN<1>")
	)
	(arc
		(start 109.3343 -223.428306)
		(mid 109.293327 -223.597177)
		(end 109.179868 -223.728788)
		(width 0.1143)
		(layer "In11.Cu")
		(net "P5E_CPU1_G1_TX_DN<1>")
	)
	(arc
		(start 110.049056 -239.969802)
		(mid 109.805729 -240.434368)
		(end 110.049056 -240.898934)
		(width 0.1143)
		(layer "In11.Cu")
		(net "P5E_CPU1_G1_TX_DN<1>")
	)
	(arc
		(start 108.875576 -246.808752)
		(mid 108.873553 -246.820162)
		(end 108.871766 -246.831612)
		(width 0.1143)
		(layer "In11.Cu")
		(net "P5E_CPU1_G1_TX_DN<1>")
	)
	(arc
		(start 109.805724 -225.854514)
		(mid 109.870239 -226.116733)
		(end 110.049056 -226.31908)
		(width 0.1143)
		(layer "In11.Cu")
		(net "P5E_CPU1_G1_TX_DN<1>")
	)
	(arc
		(start 110.12297 -237.702344)
		(mid 110.27715 -238.00435)
		(end 110.12297 -238.306356)
		(width 0.1143)
		(layer "In11.Cu")
		(net "P5E_CPU1_G1_TX_DN<1>")
	)
	(arc
		(start 110.275624 -242.867688)
		(mid 110.275297 -242.882687)
		(end 110.274354 -242.89766)
		(width 0.1143)
		(layer "In11.Cu")
		(net "P5E_CPU1_G1_TX_DN<1>")
	)
	(arc
		(start 110.118652 -226.35972)
		(mid 110.275629 -226.66452)
		(end 110.118652 -226.96932)
		(width 0.1143)
		(layer "In11.Cu")
		(net "P5E_CPU1_G1_TX_DN<1>")
	)
	(arc
		(start 109.649768 -244.990112)
		(mid 109.805696 -245.294404)
		(end 109.649768 -245.598696)
		(width 0.1143)
		(layer "In11.Cu")
		(net "P5E_CPU1_G1_TX_DN<1>")
	)
	(arc
		(start 109.335824 -225.044508)
		(mid 109.400339 -225.306727)
		(end 109.579156 -225.509074)
		(width 0.1143)
		(layer "In11.Cu")
		(net "P5E_CPU1_G1_TX_DN<1>")
	)
	(arc
		(start 110.12297 -239.322356)
		(mid 110.27715 -239.624362)
		(end 110.12297 -239.926368)
		(width 0.1143)
		(layer "In11.Cu")
		(net "P5E_CPU1_G1_TX_DN<1>")
	)
	(arc
		(start 108.86567 -224.234502)
		(mid 108.930185 -224.496721)
		(end 109.109002 -224.699068)
		(width 0.1143)
		(layer "In11.Cu")
		(net "P5E_CPU1_G1_TX_DN<1>")
	)
	(arc
		(start 109.648752 -225.549714)
		(mid 109.764179 -225.68309)
		(end 109.805724 -225.854514)
		(width 0.1143)
		(layer "In11.Cu")
		(net "P5E_CPU1_G1_TX_DN<1>")
	)
	(arc
		(start 109.56036 -244.033294)
		(mid 109.329846 -244.484398)
		(end 109.56036 -244.935502)
		(width 0.1143)
		(layer "In11.Cu")
		(net "P5E_CPU1_G1_TX_DN<1>")
	)
	(arc
		(start 109.805724 -243.674392)
		(mid 109.764469 -243.845363)
		(end 109.649768 -243.978684)
		(width 0.1143)
		(layer "In11.Cu")
		(net "P5E_CPU1_G1_TX_DN<1>")
	)
	(arc
		(start 110.11535 -229.597712)
		(mid 110.120333 -229.601354)
		(end 110.125256 -229.605078)
		(width 0.1143)
		(layer "In11.Cu")
		(net "P5E_CPU1_G1_TX_DN<1>")
	)
	(arc
		(start 110.27537 -229.91191)
		(mid 110.232265 -230.079108)
		(end 110.118652 -230.20909)
		(width 0.1143)
		(layer "In11.Cu")
		(net "P5E_CPU1_G1_TX_DN<1>")
	)
	(arc
		(start 110.12297 -232.842308)
		(mid 110.27715 -233.144314)
		(end 110.12297 -233.44632)
		(width 0.1143)
		(layer "In11.Cu")
		(net "P5E_CPU1_G1_TX_DN<1>")
	)
	(arc
		(start 110.049056 -231.869742)
		(mid 109.805729 -232.334308)
		(end 110.049056 -232.798874)
		(width 0.1143)
		(layer "In11.Cu")
		(net "P5E_CPU1_G1_TX_DN<1>")
	)
	(arc
		(start 110.051596 -230.248206)
		(mid 109.870944 -230.450951)
		(end 109.805724 -230.71455)
		(width 0.1143)
		(layer "In11.Cu")
		(net "P5E_CPU1_G1_TX_DN<1>")
	)
	(arc
		(start 110.125256 -229.605078)
		(mid 110.224667 -229.741191)
		(end 110.275116 -229.902004)
		(width 0.1143)
		(layer "In11.Cu")
		(net "P5E_CPU1_G1_TX_DN<1>")
	)
	(arc
		(start 110.120938 -242.560856)
		(mid 110.234867 -242.694003)
		(end 110.275878 -242.864386)
		(width 0.1143)
		(layer "In11.Cu")
		(net "P5E_CPU1_G1_TX_DN<1>")
	)
	(arc
		(start 110.049056 -235.109766)
		(mid 109.805729 -235.574332)
		(end 110.049056 -236.038898)
		(width 0.1143)
		(layer "In11.Cu")
		(net "P5E_CPU1_G1_TX_DN<1>")
	)
	(arc
		(start 110.274354 -242.89766)
		(mid 110.227648 -243.049286)
		(end 110.121446 -243.167154)
		(width 0.1143)
		(layer "In11.Cu")
		(net "P5E_CPU1_G1_TX_DN<1>")
	)
	(arc
		(start 110.120684 -231.220772)
		(mid 110.234613 -231.353919)
		(end 110.275624 -231.524302)
		(width 0.1143)
		(layer "In11.Cu")
		(net "P5E_CPU1_G1_TX_DN<1>")
	)
	(arc
		(start 110.049056 -233.489754)
		(mid 109.805729 -233.95432)
		(end 110.049056 -234.418886)
		(width 0.1143)
		(layer "In11.Cu")
		(net "P5E_CPU1_G1_TX_DN<1>")
	)
	(arc
		(start 110.049056 -236.729778)
		(mid 109.805729 -237.194344)
		(end 110.049056 -237.65891)
		(width 0.1143)
		(layer "In11.Cu")
		(net "P5E_CPU1_G1_TX_DN<1>")
	)
	(arc
		(start 109.805724 -230.71455)
		(mid 109.870239 -230.976769)
		(end 110.049056 -231.179116)
		(width 0.1143)
		(layer "In11.Cu")
		(net "P5E_CPU1_G1_TX_DN<1>")
	)
	(arc
		(start 110.275624 -231.524302)
		(mid 110.234075 -231.695724)
		(end 110.118652 -231.829102)
		(width 0.1143)
		(layer "In11.Cu")
		(net "P5E_CPU1_G1_TX_DN<1>")
	)
	(arc
		(start 110.049056 -243.209826)
		(mid 109.870243 -243.412176)
		(end 109.805724 -243.674392)
		(width 0.1143)
		(layer "In11.Cu")
		(net "P5E_CPU1_G1_TX_DN<1>")
	)
	(arc
		(start 110.12805 -240.944908)
		(mid 110.299771 -241.244374)
		(end 110.12805 -241.54384)
		(width 0.1143)
		(layer "In11.Cu")
		(net "P5E_CPU1_G1_TX_DN<1>")
	)
	(arc
		(start 110.049056 -228.629972)
		(mid 109.805729 -229.094538)
		(end 110.049056 -229.559104)
		(width 0.1143)
		(layer "In11.Cu")
		(net "P5E_CPU1_G1_TX_DN<1>")
	)
	(arc
		(start 110.049056 -241.589814)
		(mid 109.805729 -242.05438)
		(end 110.049056 -242.518946)
		(width 0.1143)
		(layer "In11.Cu")
		(net "P5E_CPU1_G1_TX_DN<1>")
	)
	(arc
		(start 109.107986 -223.770698)
		(mid 108.929921 -223.972875)
		(end 108.86567 -224.234502)
		(width 0.1143)
		(layer "In11.Cu")
		(net "P5E_CPU1_G1_TX_DN<1>")
	)
	(arc
		(start 110.12297 -236.082332)
		(mid 110.27715 -236.384338)
		(end 110.12297 -236.686344)
		(width 0.1143)
		(layer "In11.Cu")
		(net "P5E_CPU1_G1_TX_DN<1>")
	)
	(arc
		(start 110.118652 -227.979732)
		(mid 110.275629 -228.284532)
		(end 110.118652 -228.589332)
		(width 0.1143)
		(layer "In11.Cu")
		(net "P5E_CPU1_G1_TX_DN<1>")
	)
	(arc
		(start 109.179868 -224.740216)
		(mid 109.294544 -224.87355)
		(end 109.335824 -225.044508)
		(width 0.1143)
		(layer "In11.Cu")
		(net "P5E_CPU1_G1_TX_DN<1>")
	)
	(segment
		(start 15.508478 -16.366236)
		(end 15.804388 -16.662146)
		(width 0.12954)
		(layer "F.Cu")
		(net "P5E_CPU1_G1_TX_DN<15>")
	)
	(segment
		(start 15.804388 -16.662146)
		(end 15.804388 -17.34185)
		(width 0.12954)
		(layer "F.Cu")
		(net "P5E_CPU1_G1_TX_DN<15>")
	)
	(segment
		(start 15.804388 -17.34185)
		(end 15.533878 -17.61236)
		(width 0.12954)
		(layer "F.Cu")
		(net "P5E_CPU1_G1_TX_DN<15>")
	)
	(segment
		(start 98.147886 -246.370348)
		(end 97.681034 -246.10441)
		(width 0.12954)
		(layer "F.Cu")
		(net "P5E_CPU1_G1_TX_DN<15>")
	)
	(segment
		(start 96.458786 -225.532442)
		(end 96.460056 -225.533204)
		(width 0.1143)
		(layer "In11.Cu")
		(net "P5E_CPU1_G1_TX_DN<15>")
	)
	(segment
		(start 15.824708 -20.286218)
		(end 32.221424 -42.318178)
		(width 0.14224)
		(layer "In11.Cu")
		(net "P5E_CPU1_G1_TX_DN<15>")
	)
	(segment
		(start 96.457008 -225.531426)
		(end 96.458024 -225.531934)
		(width 0.1143)
		(layer "In11.Cu")
		(net "P5E_CPU1_G1_TX_DN<15>")
	)
	(segment
		(start 95.170752 -221.129098)
		(end 95.170752 -221.387924)
		(width 0.1143)
		(layer "In11.Cu")
		(net "P5E_CPU1_G1_TX_DN<15>")
	)
	(segment
		(start 98.048826 -246.03456)
		(end 97.978976 -246.10441)
		(width 0.1143)
		(layer "In11.Cu")
		(net "P5E_CPU1_G1_TX_DN<15>")
	)
	(segment
		(start 96.889062 -237.65891)
		(end 96.928178 -237.68177)
		(width 0.1143)
		(layer "In11.Cu")
		(net "P5E_CPU1_G1_TX_DN<15>")
	)
	(segment
		(start 96.928178 -238.32693)
		(end 96.889062 -238.34979)
		(width 0.1143)
		(layer "In11.Cu")
		(net "P5E_CPU1_G1_TX_DN<15>")
	)
	(segment
		(start 96.425766 -225.513138)
		(end 96.426528 -225.513646)
		(width 0.1143)
		(layer "In11.Cu")
		(net "P5E_CPU1_G1_TX_DN<15>")
	)
	(segment
		(start 96.453706 -225.529394)
		(end 96.45523 -225.53041)
		(width 0.1143)
		(layer "In11.Cu")
		(net "P5E_CPU1_G1_TX_DN<15>")
	)
	(segment
		(start 96.958658 -235.069126)
		(end 96.928178 -235.086906)
		(width 0.1143)
		(layer "In11.Cu")
		(net "P5E_CPU1_G1_TX_DN<15>")
	)
	(segment
		(start 51.222402 -62.210696)
		(end 54.199282 -64.646048)
		(width 0.14224)
		(layer "In11.Cu")
		(net "P5E_CPU1_G1_TX_DN<15>")
	)
	(segment
		(start 96.958658 -230.20909)
		(end 96.891602 -230.248206)
		(width 0.1143)
		(layer "In11.Cu")
		(net "P5E_CPU1_G1_TX_DN<15>")
	)
	(segment
		(start 96.018604 -223.729296)
		(end 95.988124 -223.747076)
		(width 0.1143)
		(layer "In11.Cu")
		(net "P5E_CPU1_G1_TX_DN<15>")
	)
	(segment
		(start 96.958658 -238.30915)
		(end 96.928178 -238.32693)
		(width 0.1143)
		(layer "In11.Cu")
		(net "P5E_CPU1_G1_TX_DN<15>")
	)
	(segment
		(start 96.418908 -225.509074)
		(end 96.425766 -225.513138)
		(width 0.1143)
		(layer "In11.Cu")
		(net "P5E_CPU1_G1_TX_DN<15>")
	)
	(segment
		(start 143.952468 -147.96643)
		(end 144.71523 -160.127696)
		(width 0.14224)
		(layer "In11.Cu")
		(net "P5E_CPU1_G1_TX_DN<15>")
	)
	(segment
		(start 96.928178 -243.186966)
		(end 96.889062 -243.209826)
		(width 0.1143)
		(layer "In11.Cu")
		(net "P5E_CPU1_G1_TX_DN<15>")
	)
	(segment
		(start 15.533878 -17.61236)
		(end 15.824708 -17.90319)
		(width 0.14224)
		(layer "In11.Cu")
		(net "P5E_CPU1_G1_TX_DN<15>")
	)
	(segment
		(start 96.958658 -241.549174)
		(end 96.928178 -241.566954)
		(width 0.1143)
		(layer "In11.Cu")
		(net "P5E_CPU1_G1_TX_DN<15>")
	)
	(segment
		(start 140.225272 -170.026838)
		(end 102.804722 -200.674986)
		(width 0.14224)
		(layer "In11.Cu")
		(net "P5E_CPU1_G1_TX_DN<15>")
	)
	(segment
		(start 96.928178 -236.061758)
		(end 96.958658 -236.079538)
		(width 0.1143)
		(layer "In11.Cu")
		(net "P5E_CPU1_G1_TX_DN<15>")
	)
	(segment
		(start 97.59823 -245.303802)
		(end 97.59823 -245.313454)
		(width 0.1143)
		(layer "In11.Cu")
		(net "P5E_CPU1_G1_TX_DN<15>")
	)
	(segment
		(start 96.958658 -231.829102)
		(end 96.928178 -231.846882)
		(width 0.1143)
		(layer "In11.Cu")
		(net "P5E_CPU1_G1_TX_DN<15>")
	)
	(segment
		(start 95.170752 -221.387924)
		(end 95.235776 -221.452948)
		(width 0.1143)
		(layer "In11.Cu")
		(net "P5E_CPU1_G1_TX_DN<15>")
	)
	(segment
		(start 95.235776 -221.452948)
		(end 95.235776 -221.804484)
		(width 0.1143)
		(layer "In11.Cu")
		(net "P5E_CPU1_G1_TX_DN<15>")
	)
	(segment
		(start 96.928178 -240.921794)
		(end 96.958658 -240.939574)
		(width 0.1143)
		(layer "In11.Cu")
		(net "P5E_CPU1_G1_TX_DN<15>")
	)
	(segment
		(start 96.928178 -239.946942)
		(end 96.889062 -239.969802)
		(width 0.1143)
		(layer "In11.Cu")
		(net "P5E_CPU1_G1_TX_DN<15>")
	)
	(segment
		(start 96.928178 -236.706918)
		(end 96.889062 -236.729778)
		(width 0.1143)
		(layer "In11.Cu")
		(net "P5E_CPU1_G1_TX_DN<15>")
	)
	(segment
		(start 97.978976 -246.10441)
		(end 97.681034 -246.10441)
		(width 0.1143)
		(layer "In11.Cu")
		(net "P5E_CPU1_G1_TX_DN<15>")
	)
	(segment
		(start 96.928178 -237.68177)
		(end 96.958658 -237.69955)
		(width 0.1143)
		(layer "In11.Cu")
		(net "P5E_CPU1_G1_TX_DN<15>")
	)
	(segment
		(start 96.928178 -226.9871)
		(end 96.889062 -227.00996)
		(width 0.1143)
		(layer "In11.Cu")
		(net "P5E_CPU1_G1_TX_DN<15>")
	)
	(segment
		(start 143.887952 -164.50945)
		(end 140.225272 -170.026838)
		(width 0.14224)
		(layer "In11.Cu")
		(net "P5E_CPU1_G1_TX_DN<15>")
	)
	(segment
		(start 96.889062 -244.138958)
		(end 96.928178 -244.161818)
		(width 0.1143)
		(layer "In11.Cu")
		(net "P5E_CPU1_G1_TX_DN<15>")
	)
	(segment
		(start 96.889062 -227.939092)
		(end 96.928178 -227.961952)
		(width 0.1143)
		(layer "In11.Cu")
		(net "P5E_CPU1_G1_TX_DN<15>")
	)
	(segment
		(start 15.824708 -17.90319)
		(end 15.824708 -20.286218)
		(width 0.14224)
		(layer "In11.Cu")
		(net "P5E_CPU1_G1_TX_DN<15>")
	)
	(segment
		(start 95.988124 -223.747076)
		(end 95.949008 -223.769936)
		(width 0.1143)
		(layer "In11.Cu")
		(net "P5E_CPU1_G1_TX_DN<15>")
	)
	(segment
		(start 96.928178 -233.466894)
		(end 96.889062 -233.489754)
		(width 0.1143)
		(layer "In11.Cu")
		(net "P5E_CPU1_G1_TX_DN<15>")
	)
	(segment
		(start 96.958658 -239.929162)
		(end 96.928178 -239.946942)
		(width 0.1143)
		(layer "In11.Cu")
		(net "P5E_CPU1_G1_TX_DN<15>")
	)
	(segment
		(start 96.889062 -229.559104)
		(end 96.891094 -229.560628)
		(width 0.1143)
		(layer "In11.Cu")
		(net "P5E_CPU1_G1_TX_DN<15>")
	)
	(segment
		(start 96.958658 -243.169186)
		(end 96.928178 -243.186966)
		(width 0.1143)
		(layer "In11.Cu")
		(net "P5E_CPU1_G1_TX_DN<15>")
	)
	(segment
		(start 96.928178 -242.541806)
		(end 96.958658 -242.559586)
		(width 0.1143)
		(layer "In11.Cu")
		(net "P5E_CPU1_G1_TX_DN<15>")
	)
	(segment
		(start 95.988124 -223.101916)
		(end 96.018604 -223.119696)
		(width 0.1143)
		(layer "In11.Cu")
		(net "P5E_CPU1_G1_TX_DN<15>")
	)
	(segment
		(start 97.358962 -244.948964)
		(end 97.410524 -244.978936)
		(width 0.1143)
		(layer "In11.Cu")
		(net "P5E_CPU1_G1_TX_DN<15>")
	)
	(segment
		(start 96.45523 -225.53041)
		(end 96.457008 -225.531426)
		(width 0.1143)
		(layer "In11.Cu")
		(net "P5E_CPU1_G1_TX_DN<15>")
	)
	(segment
		(start 96.928178 -241.566954)
		(end 96.889062 -241.589814)
		(width 0.1143)
		(layer "In11.Cu")
		(net "P5E_CPU1_G1_TX_DN<15>")
	)
	(segment
		(start 95.949008 -224.699068)
		(end 95.988124 -224.721928)
		(width 0.1143)
		(layer "In11.Cu")
		(net "P5E_CPU1_G1_TX_DN<15>")
	)
	(segment
		(start 96.928178 -231.846882)
		(end 96.889062 -231.869742)
		(width 0.1143)
		(layer "In11.Cu")
		(net "P5E_CPU1_G1_TX_DN<15>")
	)
	(segment
		(start 96.928178 -234.441746)
		(end 96.958658 -234.459526)
		(width 0.1143)
		(layer "In11.Cu")
		(net "P5E_CPU1_G1_TX_DN<15>")
	)
	(segment
		(start 96.889062 -231.179116)
		(end 96.928178 -231.201976)
		(width 0.1143)
		(layer "In11.Cu")
		(net "P5E_CPU1_G1_TX_DN<15>")
	)
	(segment
		(start 96.958658 -233.449114)
		(end 96.928178 -233.466894)
		(width 0.1143)
		(layer "In11.Cu")
		(net "P5E_CPU1_G1_TX_DN<15>")
	)
	(segment
		(start 96.928178 -235.086906)
		(end 96.889062 -235.109766)
		(width 0.1143)
		(layer "In11.Cu")
		(net "P5E_CPU1_G1_TX_DN<15>")
	)
	(segment
		(start 96.45269 -225.528886)
		(end 96.453706 -225.529394)
		(width 0.1143)
		(layer "In11.Cu")
		(net "P5E_CPU1_G1_TX_DN<15>")
	)
	(segment
		(start 96.889062 -236.038898)
		(end 96.928178 -236.061758)
		(width 0.1143)
		(layer "In11.Cu")
		(net "P5E_CPU1_G1_TX_DN<15>")
	)
	(segment
		(start 141.719554 -143.349472)
		(end 143.952468 -147.96643)
		(width 0.14224)
		(layer "In11.Cu")
		(net "P5E_CPU1_G1_TX_DN<15>")
	)
	(segment
		(start 96.928178 -231.201976)
		(end 96.96069 -231.220772)
		(width 0.1143)
		(layer "In11.Cu")
		(net "P5E_CPU1_G1_TX_DN<15>")
	)
	(segment
		(start 95.125032 -221.05493)
		(end 95.125032 -221.083378)
		(width 0.1143)
		(layer "In11.Cu")
		(net "P5E_CPU1_G1_TX_DN<15>")
	)
	(segment
		(start 96.928178 -227.961952)
		(end 96.958658 -227.979732)
		(width 0.1143)
		(layer "In11.Cu")
		(net "P5E_CPU1_G1_TX_DN<15>")
	)
	(segment
		(start 54.199282 -64.646048)
		(end 141.719554 -143.349472)
		(width 0.14224)
		(layer "In11.Cu")
		(net "P5E_CPU1_G1_TX_DN<15>")
	)
	(segment
		(start 96.889062 -234.418886)
		(end 96.928178 -234.441746)
		(width 0.1143)
		(layer "In11.Cu")
		(net "P5E_CPU1_G1_TX_DN<15>")
	)
	(segment
		(start 96.889062 -242.518946)
		(end 96.928178 -242.541806)
		(width 0.1143)
		(layer "In11.Cu")
		(net "P5E_CPU1_G1_TX_DN<15>")
	)
	(segment
		(start 96.928178 -232.821734)
		(end 96.958658 -232.839514)
		(width 0.1143)
		(layer "In11.Cu")
		(net "P5E_CPU1_G1_TX_DN<15>")
	)
	(segment
		(start 96.426528 -225.513646)
		(end 96.451166 -225.52787)
		(width 0.1143)
		(layer "In11.Cu")
		(net "P5E_CPU1_G1_TX_DN<15>")
	)
	(segment
		(start 97.867978 -245.78183)
		(end 97.899728 -245.800118)
		(width 0.1143)
		(layer "In11.Cu")
		(net "P5E_CPU1_G1_TX_DN<15>")
	)
	(segment
		(start 96.451166 -225.52787)
		(end 96.45269 -225.528886)
		(width 0.1143)
		(layer "In11.Cu")
		(net "P5E_CPU1_G1_TX_DN<15>")
	)
	(segment
		(start 96.928178 -229.581964)
		(end 96.96069 -229.60076)
		(width 0.1143)
		(layer "In11.Cu")
		(net "P5E_CPU1_G1_TX_DN<15>")
	)
	(segment
		(start 96.891094 -229.560628)
		(end 96.928178 -229.581964)
		(width 0.1143)
		(layer "In11.Cu")
		(net "P5E_CPU1_G1_TX_DN<15>")
	)
	(segment
		(start 95.988124 -224.721928)
		(end 96.018604 -224.739708)
		(width 0.1143)
		(layer "In11.Cu")
		(net "P5E_CPU1_G1_TX_DN<15>")
	)
	(segment
		(start 96.958658 -236.689138)
		(end 96.928178 -236.706918)
		(width 0.1143)
		(layer "In11.Cu")
		(net "P5E_CPU1_G1_TX_DN<15>")
	)
	(segment
		(start 96.889062 -239.278922)
		(end 96.928178 -239.301782)
		(width 0.1143)
		(layer "In11.Cu")
		(net "P5E_CPU1_G1_TX_DN<15>")
	)
	(segment
		(start 96.460056 -225.533204)
		(end 96.489774 -225.550222)
		(width 0.1143)
		(layer "In11.Cu")
		(net "P5E_CPU1_G1_TX_DN<15>")
	)
	(segment
		(start 96.889062 -240.898934)
		(end 96.928178 -240.921794)
		(width 0.1143)
		(layer "In11.Cu")
		(net "P5E_CPU1_G1_TX_DN<15>")
	)
	(segment
		(start 95.479616 -222.269558)
		(end 95.480632 -222.27032)
		(width 0.1143)
		(layer "In11.Cu")
		(net "P5E_CPU1_G1_TX_DN<15>")
	)
	(segment
		(start 144.71523 -162.079432)
		(end 143.887952 -164.50945)
		(width 0.14224)
		(layer "In11.Cu")
		(net "P5E_CPU1_G1_TX_DN<15>")
	)
	(segment
		(start 95.125032 -221.083378)
		(end 95.170752 -221.129098)
		(width 0.1143)
		(layer "In11.Cu")
		(net "P5E_CPU1_G1_TX_DN<15>")
	)
	(segment
		(start 32.221424 -42.318178)
		(end 51.222402 -62.210696)
		(width 0.14224)
		(layer "In11.Cu")
		(net "P5E_CPU1_G1_TX_DN<15>")
	)
	(segment
		(start 96.889062 -232.798874)
		(end 96.928178 -232.821734)
		(width 0.1143)
		(layer "In11.Cu")
		(net "P5E_CPU1_G1_TX_DN<15>")
	)
	(segment
		(start 144.71523 -160.127696)
		(end 144.71523 -162.079432)
		(width 0.14224)
		(layer "In11.Cu")
		(net "P5E_CPU1_G1_TX_DN<15>")
	)
	(segment
		(start 95.949008 -223.079056)
		(end 95.988124 -223.101916)
		(width 0.1143)
		(layer "In11.Cu")
		(net "P5E_CPU1_G1_TX_DN<15>")
	)
	(segment
		(start 102.804722 -200.674986)
		(end 95.125032 -213.673944)
		(width 0.14224)
		(layer "In11.Cu")
		(net "P5E_CPU1_G1_TX_DN<15>")
	)
	(segment
		(start 95.125032 -213.673944)
		(end 95.125032 -221.05493)
		(width 0.14224)
		(layer "In11.Cu")
		(net "P5E_CPU1_G1_TX_DN<15>")
	)
	(segment
		(start 95.480632 -222.27032)
		(end 95.481648 -222.270828)
		(width 0.1143)
		(layer "In11.Cu")
		(net "P5E_CPU1_G1_TX_DN<15>")
	)
	(segment
		(start 96.458024 -225.531934)
		(end 96.458786 -225.532442)
		(width 0.1143)
		(layer "In11.Cu")
		(net "P5E_CPU1_G1_TX_DN<15>")
	)
	(segment
		(start 96.958658 -228.589332)
		(end 96.928178 -228.607112)
		(width 0.1143)
		(layer "In11.Cu")
		(net "P5E_CPU1_G1_TX_DN<15>")
	)
	(segment
		(start 96.928178 -244.161818)
		(end 96.958658 -244.179598)
		(width 0.1143)
		(layer "In11.Cu")
		(net "P5E_CPU1_G1_TX_DN<15>")
	)
	(segment
		(start 96.928178 -228.607112)
		(end 96.889062 -228.629972)
		(width 0.1143)
		(layer "In11.Cu")
		(net "P5E_CPU1_G1_TX_DN<15>")
	)
	(segment
		(start 95.481648 -222.270828)
		(end 95.54972 -222.310198)
		(width 0.1143)
		(layer "In11.Cu")
		(net "P5E_CPU1_G1_TX_DN<15>")
	)
	(segment
		(start 96.889062 -226.31908)
		(end 96.928178 -226.34194)
		(width 0.1143)
		(layer "In11.Cu")
		(net "P5E_CPU1_G1_TX_DN<15>")
	)
	(segment
		(start 96.928178 -239.301782)
		(end 96.958658 -239.319562)
		(width 0.1143)
		(layer "In11.Cu")
		(net "P5E_CPU1_G1_TX_DN<15>")
	)
	(segment
		(start 96.928178 -226.34194)
		(end 96.958658 -226.35972)
		(width 0.1143)
		(layer "In11.Cu")
		(net "P5E_CPU1_G1_TX_DN<15>")
	)
	(segment
		(start 96.958658 -226.96932)
		(end 96.928178 -226.9871)
		(width 0.1143)
		(layer "In11.Cu")
		(net "P5E_CPU1_G1_TX_DN<15>")
	)
	(arc
		(start 96.889062 -241.589814)
		(mid 96.645735 -242.05438)
		(end 96.889062 -242.518946)
		(width 0.1143)
		(layer "In11.Cu")
		(net "P5E_CPU1_G1_TX_DN<15>")
	)
	(arc
		(start 96.96069 -231.220772)
		(mid 97.074619 -231.353919)
		(end 97.11563 -231.524302)
		(width 0.1143)
		(layer "In11.Cu")
		(net "P5E_CPU1_G1_TX_DN<15>")
	)
	(arc
		(start 96.889062 -239.969802)
		(mid 96.645735 -240.434368)
		(end 96.889062 -240.898934)
		(width 0.1143)
		(layer "In11.Cu")
		(net "P5E_CPU1_G1_TX_DN<15>")
	)
	(arc
		(start 96.64573 -225.854514)
		(mid 96.710245 -226.116733)
		(end 96.889062 -226.31908)
		(width 0.1143)
		(layer "In11.Cu")
		(net "P5E_CPU1_G1_TX_DN<15>")
	)
	(arc
		(start 96.018604 -224.739708)
		(mid 96.134031 -224.873084)
		(end 96.175576 -225.044508)
		(width 0.1143)
		(layer "In11.Cu")
		(net "P5E_CPU1_G1_TX_DN<15>")
	)
	(arc
		(start 96.889062 -238.34979)
		(mid 96.645735 -238.814356)
		(end 96.889062 -239.278922)
		(width 0.1143)
		(layer "In11.Cu")
		(net "P5E_CPU1_G1_TX_DN<15>")
	)
	(arc
		(start 96.958658 -244.179598)
		(mid 97.074085 -244.312974)
		(end 97.11563 -244.484398)
		(width 0.1143)
		(layer "In11.Cu")
		(net "P5E_CPU1_G1_TX_DN<15>")
	)
	(arc
		(start 96.489774 -225.550222)
		(mid 96.60445 -225.683556)
		(end 96.64573 -225.854514)
		(width 0.1143)
		(layer "In11.Cu")
		(net "P5E_CPU1_G1_TX_DN<15>")
	)
	(arc
		(start 96.018604 -223.119696)
		(mid 96.175581 -223.424496)
		(end 96.018604 -223.729296)
		(width 0.1143)
		(layer "In11.Cu")
		(net "P5E_CPU1_G1_TX_DN<15>")
	)
	(arc
		(start 96.958658 -242.559586)
		(mid 97.115635 -242.864386)
		(end 96.958658 -243.169186)
		(width 0.1143)
		(layer "In11.Cu")
		(net "P5E_CPU1_G1_TX_DN<15>")
	)
	(arc
		(start 96.889062 -231.869742)
		(mid 96.645735 -232.334308)
		(end 96.889062 -232.798874)
		(width 0.1143)
		(layer "In11.Cu")
		(net "P5E_CPU1_G1_TX_DN<15>")
	)
	(arc
		(start 96.958658 -232.839514)
		(mid 97.115635 -233.144314)
		(end 96.958658 -233.449114)
		(width 0.1143)
		(layer "In11.Cu")
		(net "P5E_CPU1_G1_TX_DN<15>")
	)
	(arc
		(start 96.64573 -230.71455)
		(mid 96.710245 -230.976769)
		(end 96.889062 -231.179116)
		(width 0.1143)
		(layer "In11.Cu")
		(net "P5E_CPU1_G1_TX_DN<15>")
	)
	(arc
		(start 97.59823 -245.313454)
		(mid 97.670486 -245.583707)
		(end 97.867978 -245.78183)
		(width 0.1143)
		(layer "In11.Cu")
		(net "P5E_CPU1_G1_TX_DN<15>")
	)
	(arc
		(start 96.958658 -236.079538)
		(mid 97.115635 -236.384338)
		(end 96.958658 -236.689138)
		(width 0.1143)
		(layer "In11.Cu")
		(net "P5E_CPU1_G1_TX_DN<15>")
	)
	(arc
		(start 97.11563 -229.90429)
		(mid 97.074081 -230.075712)
		(end 96.958658 -230.20909)
		(width 0.1143)
		(layer "In11.Cu")
		(net "P5E_CPU1_G1_TX_DN<15>")
	)
	(arc
		(start 96.889062 -227.00996)
		(mid 96.645735 -227.474526)
		(end 96.889062 -227.939092)
		(width 0.1143)
		(layer "In11.Cu")
		(net "P5E_CPU1_G1_TX_DN<15>")
	)
	(arc
		(start 96.958658 -239.319562)
		(mid 97.115635 -239.624362)
		(end 96.958658 -239.929162)
		(width 0.1143)
		(layer "In11.Cu")
		(net "P5E_CPU1_G1_TX_DN<15>")
	)
	(arc
		(start 96.175576 -225.044508)
		(mid 96.240091 -225.306727)
		(end 96.418908 -225.509074)
		(width 0.1143)
		(layer "In11.Cu")
		(net "P5E_CPU1_G1_TX_DN<15>")
	)
	(arc
		(start 96.96069 -229.60076)
		(mid 97.074619 -229.733907)
		(end 97.11563 -229.90429)
		(width 0.1143)
		(layer "In11.Cu")
		(net "P5E_CPU1_G1_TX_DN<15>")
	)
	(arc
		(start 95.235776 -221.804484)
		(mid 95.300435 -222.067041)
		(end 95.479616 -222.269558)
		(width 0.1143)
		(layer "In11.Cu")
		(net "P5E_CPU1_G1_TX_DN<15>")
	)
	(arc
		(start 96.889062 -236.729778)
		(mid 96.645735 -237.194344)
		(end 96.889062 -237.65891)
		(width 0.1143)
		(layer "In11.Cu")
		(net "P5E_CPU1_G1_TX_DN<15>")
	)
	(arc
		(start 96.958658 -237.69955)
		(mid 97.115635 -238.00435)
		(end 96.958658 -238.30915)
		(width 0.1143)
		(layer "In11.Cu")
		(net "P5E_CPU1_G1_TX_DN<15>")
	)
	(arc
		(start 96.889062 -243.209826)
		(mid 96.645735 -243.674392)
		(end 96.889062 -244.138958)
		(width 0.1143)
		(layer "In11.Cu")
		(net "P5E_CPU1_G1_TX_DN<15>")
	)
	(arc
		(start 96.889062 -233.489754)
		(mid 96.645735 -233.95432)
		(end 96.889062 -234.418886)
		(width 0.1143)
		(layer "In11.Cu")
		(net "P5E_CPU1_G1_TX_DN<15>")
	)
	(arc
		(start 96.958658 -240.939574)
		(mid 97.115635 -241.244374)
		(end 96.958658 -241.549174)
		(width 0.1143)
		(layer "In11.Cu")
		(net "P5E_CPU1_G1_TX_DN<15>")
	)
	(arc
		(start 96.889062 -235.109766)
		(mid 96.645735 -235.574332)
		(end 96.889062 -236.038898)
		(width 0.1143)
		(layer "In11.Cu")
		(net "P5E_CPU1_G1_TX_DN<15>")
	)
	(arc
		(start 96.958658 -227.979732)
		(mid 97.115635 -228.284532)
		(end 96.958658 -228.589332)
		(width 0.1143)
		(layer "In11.Cu")
		(net "P5E_CPU1_G1_TX_DN<15>")
	)
	(arc
		(start 96.958658 -226.35972)
		(mid 97.115635 -226.66452)
		(end 96.958658 -226.96932)
		(width 0.1143)
		(layer "In11.Cu")
		(net "P5E_CPU1_G1_TX_DN<15>")
	)
	(arc
		(start 97.899728 -245.800118)
		(mid 97.996863 -245.902987)
		(end 98.048826 -246.03456)
		(width 0.1143)
		(layer "In11.Cu")
		(net "P5E_CPU1_G1_TX_DN<15>")
	)
	(arc
		(start 95.949008 -223.769936)
		(mid 95.705681 -224.234502)
		(end 95.949008 -224.699068)
		(width 0.1143)
		(layer "In11.Cu")
		(net "P5E_CPU1_G1_TX_DN<15>")
	)
	(arc
		(start 97.11563 -231.524302)
		(mid 97.074081 -231.695724)
		(end 96.958658 -231.829102)
		(width 0.1143)
		(layer "In11.Cu")
		(net "P5E_CPU1_G1_TX_DN<15>")
	)
	(arc
		(start 95.54972 -222.310198)
		(mid 95.664396 -222.443532)
		(end 95.705676 -222.61449)
		(width 0.1143)
		(layer "In11.Cu")
		(net "P5E_CPU1_G1_TX_DN<15>")
	)
	(arc
		(start 97.410524 -244.978936)
		(mid 97.547956 -245.116195)
		(end 97.59823 -245.303802)
		(width 0.1143)
		(layer "In11.Cu")
		(net "P5E_CPU1_G1_TX_DN<15>")
	)
	(arc
		(start 95.705676 -222.61449)
		(mid 95.770191 -222.876709)
		(end 95.949008 -223.079056)
		(width 0.1143)
		(layer "In11.Cu")
		(net "P5E_CPU1_G1_TX_DN<15>")
	)
	(arc
		(start 96.891602 -230.248206)
		(mid 96.71095 -230.450951)
		(end 96.64573 -230.71455)
		(width 0.1143)
		(layer "In11.Cu")
		(net "P5E_CPU1_G1_TX_DN<15>")
	)
	(arc
		(start 96.958658 -234.459526)
		(mid 97.115635 -234.764326)
		(end 96.958658 -235.069126)
		(width 0.1143)
		(layer "In11.Cu")
		(net "P5E_CPU1_G1_TX_DN<15>")
	)
	(arc
		(start 97.11563 -244.484398)
		(mid 97.180145 -244.746617)
		(end 97.358962 -244.948964)
		(width 0.1143)
		(layer "In11.Cu")
		(net "P5E_CPU1_G1_TX_DN<15>")
	)
	(arc
		(start 96.889062 -228.629972)
		(mid 96.645735 -229.094538)
		(end 96.889062 -229.559104)
		(width 0.1143)
		(layer "In11.Cu")
		(net "P5E_CPU1_G1_TX_DN<15>")
	)
	(segment
		(start 18.598388 -18.865596)
		(end 18.326862 -19.137122)
		(width 0.12954)
		(layer "F.Cu")
		(net "P5E_CPU1_G1_TX_DN<14>")
	)
	(segment
		(start 18.598388 -18.186146)
		(end 18.598388 -18.865596)
		(width 0.12954)
		(layer "F.Cu")
		(net "P5E_CPU1_G1_TX_DN<14>")
	)
	(segment
		(start 98.147886 -244.750336)
		(end 97.681034 -244.484398)
		(width 0.12954)
		(layer "F.Cu")
		(net "P5E_CPU1_G1_TX_DN<14>")
	)
	(segment
		(start 18.302478 -17.890236)
		(end 18.598388 -18.186146)
		(width 0.12954)
		(layer "F.Cu")
		(net "P5E_CPU1_G1_TX_DN<14>")
	)
	(segment
		(start 97.831656 -244.140736)
		(end 97.867978 -244.161818)
		(width 0.1143)
		(layer "In11.Cu")
		(net "P5E_CPU1_G1_TX_DN<14>")
	)
	(segment
		(start 96.069912 -213.913466)
		(end 96.069912 -221.05493)
		(width 0.14224)
		(layer "In11.Cu")
		(net "P5E_CPU1_G1_TX_DN<14>")
	)
	(segment
		(start 96.457008 -222.291402)
		(end 96.458024 -222.29191)
		(width 0.1143)
		(layer "In11.Cu")
		(net "P5E_CPU1_G1_TX_DN<14>")
	)
	(segment
		(start 97.867724 -237.68177)
		(end 97.867978 -237.68177)
		(width 0.1143)
		(layer "In11.Cu")
		(net "P5E_CPU1_G1_TX_DN<14>")
	)
	(segment
		(start 97.871534 -237.683802)
		(end 97.872296 -237.68431)
		(width 0.1143)
		(layer "In11.Cu")
		(net "P5E_CPU1_G1_TX_DN<14>")
	)
	(segment
		(start 97.867724 -242.541806)
		(end 97.867978 -242.541806)
		(width 0.1143)
		(layer "In11.Cu")
		(net "P5E_CPU1_G1_TX_DN<14>")
	)
	(segment
		(start 97.865438 -230.228394)
		(end 97.864422 -230.228902)
		(width 0.1143)
		(layer "In11.Cu")
		(net "P5E_CPU1_G1_TX_DN<14>")
	)
	(segment
		(start 103.57104 -201.252582)
		(end 96.069912 -213.913466)
		(width 0.14224)
		(layer "In11.Cu")
		(net "P5E_CPU1_G1_TX_DN<14>")
	)
	(segment
		(start 97.872296 -242.544346)
		(end 97.873312 -242.544854)
		(width 0.1143)
		(layer "In11.Cu")
		(net "P5E_CPU1_G1_TX_DN<14>")
	)
	(segment
		(start 97.871534 -236.06379)
		(end 97.872296 -236.064298)
		(width 0.1143)
		(layer "In11.Cu")
		(net "P5E_CPU1_G1_TX_DN<14>")
	)
	(segment
		(start 97.873312 -242.544854)
		(end 97.874074 -242.545362)
		(width 0.1143)
		(layer "In11.Cu")
		(net "P5E_CPU1_G1_TX_DN<14>")
	)
	(segment
		(start 97.872296 -236.064298)
		(end 97.874328 -236.065568)
		(width 0.1143)
		(layer "In11.Cu")
		(net "P5E_CPU1_G1_TX_DN<14>")
	)
	(segment
		(start 97.867978 -226.9871)
		(end 97.831656 -227.008182)
		(width 0.1143)
		(layer "In11.Cu")
		(net "P5E_CPU1_G1_TX_DN<14>")
	)
	(segment
		(start 34.926524 -43.31462)
		(end 51.35753 -61.00064)
		(width 0.14224)
		(layer "In11.Cu")
		(net "P5E_CPU1_G1_TX_DN<14>")
	)
	(segment
		(start 97.872296 -239.304322)
		(end 97.873312 -239.30483)
		(width 0.1143)
		(layer "In11.Cu")
		(net "P5E_CPU1_G1_TX_DN<14>")
	)
	(segment
		(start 97.899728 -226.968812)
		(end 97.867978 -226.9871)
		(width 0.1143)
		(layer "In11.Cu")
		(net "P5E_CPU1_G1_TX_DN<14>")
	)
	(segment
		(start 97.83445 -229.562406)
		(end 97.867978 -229.581964)
		(width 0.1143)
		(layer "In11.Cu")
		(net "P5E_CPU1_G1_TX_DN<14>")
	)
	(segment
		(start 97.875344 -242.546124)
		(end 97.899728 -242.560094)
		(width 0.1143)
		(layer "In11.Cu")
		(net "P5E_CPU1_G1_TX_DN<14>")
	)
	(segment
		(start 97.857818 -231.195626)
		(end 97.898712 -231.219502)
		(width 0.1143)
		(layer "In11.Cu")
		(net "P5E_CPU1_G1_TX_DN<14>")
	)
	(segment
		(start 97.867724 -239.301782)
		(end 97.867978 -239.301782)
		(width 0.1143)
		(layer "In11.Cu")
		(net "P5E_CPU1_G1_TX_DN<14>")
	)
	(segment
		(start 97.869756 -237.682786)
		(end 97.870518 -237.683294)
		(width 0.1143)
		(layer "In11.Cu")
		(net "P5E_CPU1_G1_TX_DN<14>")
	)
	(segment
		(start 97.875344 -240.926112)
		(end 97.899728 -240.940082)
		(width 0.1143)
		(layer "In11.Cu")
		(net "P5E_CPU1_G1_TX_DN<14>")
	)
	(segment
		(start 97.867978 -227.961952)
		(end 97.899728 -227.98024)
		(width 0.1143)
		(layer "In11.Cu")
		(net "P5E_CPU1_G1_TX_DN<14>")
	)
	(segment
		(start 97.874582 -228.603302)
		(end 97.87382 -228.60381)
		(width 0.1143)
		(layer "In11.Cu")
		(net "P5E_CPU1_G1_TX_DN<14>")
	)
	(segment
		(start 97.871534 -242.543838)
		(end 97.872296 -242.544346)
		(width 0.1143)
		(layer "In11.Cu")
		(net "P5E_CPU1_G1_TX_DN<14>")
	)
	(segment
		(start 97.898712 -231.219502)
		(end 97.901506 -231.221534)
		(width 0.1143)
		(layer "In11.Cu")
		(net "P5E_CPU1_G1_TX_DN<14>")
	)
	(segment
		(start 97.867978 -237.68177)
		(end 97.86874 -237.682278)
		(width 0.1143)
		(layer "In11.Cu")
		(net "P5E_CPU1_G1_TX_DN<14>")
	)
	(segment
		(start 97.831656 -234.420664)
		(end 97.867978 -234.441746)
		(width 0.1143)
		(layer "In11.Cu")
		(net "P5E_CPU1_G1_TX_DN<14>")
	)
	(segment
		(start 97.867978 -235.086906)
		(end 97.867724 -235.08716)
		(width 0.1143)
		(layer "In11.Cu")
		(net "P5E_CPU1_G1_TX_DN<14>")
	)
	(segment
		(start 97.878138 -228.60127)
		(end 97.877376 -228.601778)
		(width 0.1143)
		(layer "In11.Cu")
		(net "P5E_CPU1_G1_TX_DN<14>")
	)
	(segment
		(start 97.867978 -234.441746)
		(end 97.899728 -234.460034)
		(width 0.1143)
		(layer "In11.Cu")
		(net "P5E_CPU1_G1_TX_DN<14>")
	)
	(segment
		(start 145.682716 -160.097216)
		(end 145.682716 -162.144964)
		(width 0.14224)
		(layer "In11.Cu")
		(net "P5E_CPU1_G1_TX_DN<14>")
	)
	(segment
		(start 97.867978 -229.581964)
		(end 97.900744 -229.601014)
		(width 0.1143)
		(layer "In11.Cu")
		(net "P5E_CPU1_G1_TX_DN<14>")
	)
	(segment
		(start 97.867978 -232.821734)
		(end 97.899728 -232.840022)
		(width 0.1143)
		(layer "In11.Cu")
		(net "P5E_CPU1_G1_TX_DN<14>")
	)
	(segment
		(start 97.86874 -237.682278)
		(end 97.869756 -237.682786)
		(width 0.1143)
		(layer "In11.Cu")
		(net "P5E_CPU1_G1_TX_DN<14>")
	)
	(segment
		(start 97.869756 -239.302798)
		(end 97.870518 -239.303306)
		(width 0.1143)
		(layer "In11.Cu")
		(net "P5E_CPU1_G1_TX_DN<14>")
	)
	(segment
		(start 97.867978 -240.921794)
		(end 97.86874 -240.922302)
		(width 0.1143)
		(layer "In11.Cu")
		(net "P5E_CPU1_G1_TX_DN<14>")
	)
	(segment
		(start 97.867978 -236.706918)
		(end 97.867724 -236.707172)
		(width 0.1143)
		(layer "In11.Cu")
		(net "P5E_CPU1_G1_TX_DN<14>")
	)
	(segment
		(start 97.831656 -232.800652)
		(end 97.867978 -232.821734)
		(width 0.1143)
		(layer "In11.Cu")
		(net "P5E_CPU1_G1_TX_DN<14>")
	)
	(segment
		(start 97.867978 -230.22687)
		(end 97.866962 -230.227378)
		(width 0.1143)
		(layer "In11.Cu")
		(net "P5E_CPU1_G1_TX_DN<14>")
	)
	(segment
		(start 97.899728 -228.588824)
		(end 97.878138 -228.60127)
		(width 0.1143)
		(layer "In11.Cu")
		(net "P5E_CPU1_G1_TX_DN<14>")
	)
	(segment
		(start 51.35753 -61.00064)
		(end 54.199282 -63.344298)
		(width 0.14224)
		(layer "In11.Cu")
		(net "P5E_CPU1_G1_TX_DN<14>")
	)
	(segment
		(start 96.451928 -222.288354)
		(end 96.452944 -222.288862)
		(width 0.1143)
		(layer "In11.Cu")
		(net "P5E_CPU1_G1_TX_DN<14>")
	)
	(segment
		(start 97.867978 -226.34194)
		(end 97.899728 -226.360228)
		(width 0.1143)
		(layer "In11.Cu")
		(net "P5E_CPU1_G1_TX_DN<14>")
	)
	(segment
		(start 97.88906 -241.554762)
		(end 97.867978 -241.566954)
		(width 0.1143)
		(layer "In11.Cu")
		(net "P5E_CPU1_G1_TX_DN<14>")
	)
	(segment
		(start 97.40138 -225.533712)
		(end 97.421954 -225.54565)
		(width 0.1143)
		(layer "In11.Cu")
		(net "P5E_CPU1_G1_TX_DN<14>")
	)
	(segment
		(start 97.867978 -244.161818)
		(end 97.899728 -244.180106)
		(width 0.1143)
		(layer "In11.Cu")
		(net "P5E_CPU1_G1_TX_DN<14>")
	)
	(segment
		(start 97.86874 -242.542314)
		(end 97.869756 -242.542822)
		(width 0.1143)
		(layer "In11.Cu")
		(net "P5E_CPU1_G1_TX_DN<14>")
	)
	(segment
		(start 97.869756 -240.92281)
		(end 97.870518 -240.923318)
		(width 0.1143)
		(layer "In11.Cu")
		(net "P5E_CPU1_G1_TX_DN<14>")
	)
	(segment
		(start 97.83318 -226.321874)
		(end 97.867978 -226.34194)
		(width 0.1143)
		(layer "In11.Cu")
		(net "P5E_CPU1_G1_TX_DN<14>")
	)
	(segment
		(start 97.867724 -240.921794)
		(end 97.867978 -240.921794)
		(width 0.1143)
		(layer "In11.Cu")
		(net "P5E_CPU1_G1_TX_DN<14>")
	)
	(segment
		(start 97.873312 -237.684818)
		(end 97.874074 -237.685326)
		(width 0.1143)
		(layer "In11.Cu")
		(net "P5E_CPU1_G1_TX_DN<14>")
	)
	(segment
		(start 18.326862 -19.137122)
		(end 18.617692 -19.427952)
		(width 0.14224)
		(layer "In11.Cu")
		(net "P5E_CPU1_G1_TX_DN<14>")
	)
	(segment
		(start 97.867978 -241.566954)
		(end 97.867724 -241.567208)
		(width 0.1143)
		(layer "In11.Cu")
		(net "P5E_CPU1_G1_TX_DN<14>")
	)
	(segment
		(start 97.831656 -226.320858)
		(end 97.83318 -226.321874)
		(width 0.1143)
		(layer "In11.Cu")
		(net "P5E_CPU1_G1_TX_DN<14>")
	)
	(segment
		(start 97.874328 -236.065568)
		(end 97.899728 -236.080046)
		(width 0.1143)
		(layer "In11.Cu")
		(net "P5E_CPU1_G1_TX_DN<14>")
	)
	(segment
		(start 96.928178 -223.747076)
		(end 96.889062 -223.769936)
		(width 0.1143)
		(layer "In11.Cu")
		(net "P5E_CPU1_G1_TX_DN<14>")
	)
	(segment
		(start 144.73936 -164.944806)
		(end 141.28623 -170.363388)
		(width 0.14224)
		(layer "In11.Cu")
		(net "P5E_CPU1_G1_TX_DN<14>")
	)
	(segment
		(start 97.899728 -230.208582)
		(end 97.867978 -230.22687)
		(width 0.1143)
		(layer "In11.Cu")
		(net "P5E_CPU1_G1_TX_DN<14>")
	)
	(segment
		(start 97.874074 -242.545362)
		(end 97.875344 -242.546124)
		(width 0.1143)
		(layer "In11.Cu")
		(net "P5E_CPU1_G1_TX_DN<14>")
	)
	(segment
		(start 97.88906 -238.314738)
		(end 97.867978 -238.32693)
		(width 0.1143)
		(layer "In11.Cu")
		(net "P5E_CPU1_G1_TX_DN<14>")
	)
	(segment
		(start 97.398078 -225.531934)
		(end 97.40138 -225.533712)
		(width 0.1143)
		(layer "In11.Cu")
		(net "P5E_CPU1_G1_TX_DN<14>")
	)
	(segment
		(start 97.875852 -228.60254)
		(end 97.874582 -228.603302)
		(width 0.1143)
		(layer "In11.Cu")
		(net "P5E_CPU1_G1_TX_DN<14>")
	)
	(segment
		(start 97.867978 -231.846882)
		(end 97.831656 -231.867964)
		(width 0.1143)
		(layer "In11.Cu")
		(net "P5E_CPU1_G1_TX_DN<14>")
	)
	(segment
		(start 96.115632 -221.129098)
		(end 96.115632 -221.387924)
		(width 0.1143)
		(layer "In11.Cu")
		(net "P5E_CPU1_G1_TX_DN<14>")
	)
	(segment
		(start 97.831656 -229.560882)
		(end 97.83445 -229.562406)
		(width 0.1143)
		(layer "In11.Cu")
		(net "P5E_CPU1_G1_TX_DN<14>")
	)
	(segment
		(start 97.869756 -236.062774)
		(end 97.870518 -236.063282)
		(width 0.1143)
		(layer "In11.Cu")
		(net "P5E_CPU1_G1_TX_DN<14>")
	)
	(segment
		(start 54.199282 -63.344298)
		(end 142.438628 -142.69466)
		(width 0.14224)
		(layer "In11.Cu")
		(net "P5E_CPU1_G1_TX_DN<14>")
	)
	(segment
		(start 97.869756 -242.542822)
		(end 97.870518 -242.54333)
		(width 0.1143)
		(layer "In11.Cu")
		(net "P5E_CPU1_G1_TX_DN<14>")
	)
	(segment
		(start 96.452944 -222.288862)
		(end 96.454468 -222.289878)
		(width 0.1143)
		(layer "In11.Cu")
		(net "P5E_CPU1_G1_TX_DN<14>")
	)
	(segment
		(start 97.86874 -236.062266)
		(end 97.869756 -236.062774)
		(width 0.1143)
		(layer "In11.Cu")
		(net "P5E_CPU1_G1_TX_DN<14>")
	)
	(segment
		(start 96.928178 -224.721928)
		(end 96.958658 -224.739708)
		(width 0.1143)
		(layer "In11.Cu")
		(net "P5E_CPU1_G1_TX_DN<14>")
	)
	(segment
		(start 96.889062 -224.699068)
		(end 96.928178 -224.721928)
		(width 0.1143)
		(layer "In11.Cu")
		(net "P5E_CPU1_G1_TX_DN<14>")
	)
	(segment
		(start 97.872296 -240.924334)
		(end 97.873312 -240.924842)
		(width 0.1143)
		(layer "In11.Cu")
		(net "P5E_CPU1_G1_TX_DN<14>")
	)
	(segment
		(start 97.899728 -238.308642)
		(end 97.889822 -238.31423)
		(width 0.1143)
		(layer "In11.Cu")
		(net "P5E_CPU1_G1_TX_DN<14>")
	)
	(segment
		(start 97.899728 -236.68863)
		(end 97.889822 -236.694218)
		(width 0.1143)
		(layer "In11.Cu")
		(net "P5E_CPU1_G1_TX_DN<14>")
	)
	(segment
		(start 97.871534 -240.923826)
		(end 97.872296 -240.924334)
		(width 0.1143)
		(layer "In11.Cu")
		(net "P5E_CPU1_G1_TX_DN<14>")
	)
	(segment
		(start 18.617692 -19.427952)
		(end 18.617692 -20.282662)
		(width 0.14224)
		(layer "In11.Cu")
		(net "P5E_CPU1_G1_TX_DN<14>")
	)
	(segment
		(start 97.870518 -237.683294)
		(end 97.871534 -237.683802)
		(width 0.1143)
		(layer "In11.Cu")
		(net "P5E_CPU1_G1_TX_DN<14>")
	)
	(segment
		(start 98.048826 -244.414548)
		(end 97.978976 -244.484398)
		(width 0.1143)
		(layer "In11.Cu")
		(net "P5E_CPU1_G1_TX_DN<14>")
	)
	(segment
		(start 97.585784 -225.870516)
		(end 97.585784 -225.87077)
		(width 0.1143)
		(layer "In11.Cu")
		(net "P5E_CPU1_G1_TX_DN<14>")
	)
	(segment
		(start 97.831656 -227.94087)
		(end 97.867978 -227.961952)
		(width 0.1143)
		(layer "In11.Cu")
		(net "P5E_CPU1_G1_TX_DN<14>")
	)
	(segment
		(start 97.867978 -239.946942)
		(end 97.867724 -239.947196)
		(width 0.1143)
		(layer "In11.Cu")
		(net "P5E_CPU1_G1_TX_DN<14>")
	)
	(segment
		(start 97.867724 -236.061758)
		(end 97.867978 -236.061758)
		(width 0.1143)
		(layer "In11.Cu")
		(net "P5E_CPU1_G1_TX_DN<14>")
	)
	(segment
		(start 97.88906 -235.074714)
		(end 97.867978 -235.086906)
		(width 0.1143)
		(layer "In11.Cu")
		(net "P5E_CPU1_G1_TX_DN<14>")
	)
	(segment
		(start 96.889062 -223.079056)
		(end 96.928178 -223.101916)
		(width 0.1143)
		(layer "In11.Cu")
		(net "P5E_CPU1_G1_TX_DN<14>")
	)
	(segment
		(start 97.86874 -239.30229)
		(end 97.869756 -239.302798)
		(width 0.1143)
		(layer "In11.Cu")
		(net "P5E_CPU1_G1_TX_DN<14>")
	)
	(segment
		(start 97.899728 -243.168678)
		(end 97.867978 -243.186966)
		(width 0.1143)
		(layer "In11.Cu")
		(net "P5E_CPU1_G1_TX_DN<14>")
	)
	(segment
		(start 97.867978 -236.061758)
		(end 97.86874 -236.062266)
		(width 0.1143)
		(layer "In11.Cu")
		(net "P5E_CPU1_G1_TX_DN<14>")
	)
	(segment
		(start 97.88906 -239.93475)
		(end 97.867978 -239.946942)
		(width 0.1143)
		(layer "In11.Cu")
		(net "P5E_CPU1_G1_TX_DN<14>")
	)
	(segment
		(start 97.877376 -228.601778)
		(end 97.875852 -228.60254)
		(width 0.1143)
		(layer "In11.Cu")
		(net "P5E_CPU1_G1_TX_DN<14>")
	)
	(segment
		(start 141.28623 -170.363388)
		(end 103.57104 -201.252582)
		(width 0.14224)
		(layer "In11.Cu")
		(net "P5E_CPU1_G1_TX_DN<14>")
	)
	(segment
		(start 97.870518 -240.923318)
		(end 97.871534 -240.923826)
		(width 0.1143)
		(layer "In11.Cu")
		(net "P5E_CPU1_G1_TX_DN<14>")
	)
	(segment
		(start 97.889822 -236.694218)
		(end 97.88906 -236.694726)
		(width 0.1143)
		(layer "In11.Cu")
		(net "P5E_CPU1_G1_TX_DN<14>")
	)
	(segment
		(start 97.835974 -230.245412)
		(end 97.83445 -230.246428)
		(width 0.1143)
		(layer "In11.Cu")
		(net "P5E_CPU1_G1_TX_DN<14>")
	)
	(segment
		(start 96.449642 -222.287084)
		(end 96.451928 -222.288354)
		(width 0.1143)
		(layer "In11.Cu")
		(net "P5E_CPU1_G1_TX_DN<14>")
	)
	(segment
		(start 97.870518 -242.54333)
		(end 97.871534 -242.543838)
		(width 0.1143)
		(layer "In11.Cu")
		(net "P5E_CPU1_G1_TX_DN<14>")
	)
	(segment
		(start 96.455484 -222.290386)
		(end 96.457008 -222.291402)
		(width 0.1143)
		(layer "In11.Cu")
		(net "P5E_CPU1_G1_TX_DN<14>")
	)
	(segment
		(start 97.866962 -230.227378)
		(end 97.865438 -230.228394)
		(width 0.1143)
		(layer "In11.Cu")
		(net "P5E_CPU1_G1_TX_DN<14>")
	)
	(segment
		(start 97.871534 -228.60508)
		(end 97.86874 -228.606604)
		(width 0.1143)
		(layer "In11.Cu")
		(net "P5E_CPU1_G1_TX_DN<14>")
	)
	(segment
		(start 97.900744 -229.601014)
		(end 97.901506 -229.601522)
		(width 0.1143)
		(layer "In11.Cu")
		(net "P5E_CPU1_G1_TX_DN<14>")
	)
	(segment
		(start 97.872296 -228.604572)
		(end 97.871534 -228.60508)
		(width 0.1143)
		(layer "In11.Cu")
		(net "P5E_CPU1_G1_TX_DN<14>")
	)
	(segment
		(start 97.86874 -240.922302)
		(end 97.869756 -240.92281)
		(width 0.1143)
		(layer "In11.Cu")
		(net "P5E_CPU1_G1_TX_DN<14>")
	)
	(segment
		(start 142.438628 -142.69466)
		(end 144.912588 -147.809712)
		(width 0.14224)
		(layer "In11.Cu")
		(net "P5E_CPU1_G1_TX_DN<14>")
	)
	(segment
		(start 96.454468 -222.289878)
		(end 96.455484 -222.290386)
		(width 0.1143)
		(layer "In11.Cu")
		(net "P5E_CPU1_G1_TX_DN<14>")
	)
	(segment
		(start 97.867978 -233.466894)
		(end 97.831656 -233.487976)
		(width 0.1143)
		(layer "In11.Cu")
		(net "P5E_CPU1_G1_TX_DN<14>")
	)
	(segment
		(start 97.86874 -228.606604)
		(end 97.867978 -228.607112)
		(width 0.1143)
		(layer "In11.Cu")
		(net "P5E_CPU1_G1_TX_DN<14>")
	)
	(segment
		(start 97.889822 -239.934242)
		(end 97.88906 -239.93475)
		(width 0.1143)
		(layer "In11.Cu")
		(net "P5E_CPU1_G1_TX_DN<14>")
	)
	(segment
		(start 97.871534 -239.303814)
		(end 97.872296 -239.304322)
		(width 0.1143)
		(layer "In11.Cu")
		(net "P5E_CPU1_G1_TX_DN<14>")
	)
	(segment
		(start 96.069912 -221.083378)
		(end 96.115632 -221.129098)
		(width 0.1143)
		(layer "In11.Cu")
		(net "P5E_CPU1_G1_TX_DN<14>")
	)
	(segment
		(start 97.899728 -239.928654)
		(end 97.889822 -239.934242)
		(width 0.1143)
		(layer "In11.Cu")
		(net "P5E_CPU1_G1_TX_DN<14>")
	)
	(segment
		(start 97.870518 -236.063282)
		(end 97.871534 -236.06379)
		(width 0.1143)
		(layer "In11.Cu")
		(net "P5E_CPU1_G1_TX_DN<14>")
	)
	(segment
		(start 97.867978 -238.32693)
		(end 97.867724 -238.327184)
		(width 0.1143)
		(layer "In11.Cu")
		(net "P5E_CPU1_G1_TX_DN<14>")
	)
	(segment
		(start 18.617692 -20.282662)
		(end 34.926524 -43.31462)
		(width 0.14224)
		(layer "In11.Cu")
		(net "P5E_CPU1_G1_TX_DN<14>")
	)
	(segment
		(start 97.889822 -238.31423)
		(end 97.88906 -238.314738)
		(width 0.1143)
		(layer "In11.Cu")
		(net "P5E_CPU1_G1_TX_DN<14>")
	)
	(segment
		(start 97.358962 -225.509074)
		(end 97.397062 -225.531426)
		(width 0.1143)
		(layer "In11.Cu")
		(net "P5E_CPU1_G1_TX_DN<14>")
	)
	(segment
		(start 97.889822 -235.074206)
		(end 97.88906 -235.074714)
		(width 0.1143)
		(layer "In11.Cu")
		(net "P5E_CPU1_G1_TX_DN<14>")
	)
	(segment
		(start 97.899728 -235.068618)
		(end 97.889822 -235.074206)
		(width 0.1143)
		(layer "In11.Cu")
		(net "P5E_CPU1_G1_TX_DN<14>")
	)
	(segment
		(start 145.682716 -162.144964)
		(end 144.73936 -164.944806)
		(width 0.14224)
		(layer "In11.Cu")
		(net "P5E_CPU1_G1_TX_DN<14>")
	)
	(segment
		(start 96.115632 -221.387924)
		(end 96.17583 -221.448122)
		(width 0.1143)
		(layer "In11.Cu")
		(net "P5E_CPU1_G1_TX_DN<14>")
	)
	(segment
		(start 97.88906 -236.694726)
		(end 97.867978 -236.706918)
		(width 0.1143)
		(layer "In11.Cu")
		(net "P5E_CPU1_G1_TX_DN<14>")
	)
	(segment
		(start 97.42424 -225.547174)
		(end 97.425256 -225.547682)
		(width 0.1143)
		(layer "In11.Cu")
		(net "P5E_CPU1_G1_TX_DN<14>")
	)
	(segment
		(start 97.421954 -225.54565)
		(end 97.42424 -225.547174)
		(width 0.1143)
		(layer "In11.Cu")
		(net "P5E_CPU1_G1_TX_DN<14>")
	)
	(segment
		(start 97.899728 -233.448606)
		(end 97.867978 -233.466894)
		(width 0.1143)
		(layer "In11.Cu")
		(net "P5E_CPU1_G1_TX_DN<14>")
	)
	(segment
		(start 97.87382 -228.60381)
		(end 97.872296 -228.604572)
		(width 0.1143)
		(layer "In11.Cu")
		(net "P5E_CPU1_G1_TX_DN<14>")
	)
	(segment
		(start 97.870518 -239.303306)
		(end 97.871534 -239.303814)
		(width 0.1143)
		(layer "In11.Cu")
		(net "P5E_CPU1_G1_TX_DN<14>")
	)
	(segment
		(start 97.867978 -239.301782)
		(end 97.86874 -239.30229)
		(width 0.1143)
		(layer "In11.Cu")
		(net "P5E_CPU1_G1_TX_DN<14>")
	)
	(segment
		(start 97.397062 -225.531426)
		(end 97.398078 -225.531934)
		(width 0.1143)
		(layer "In11.Cu")
		(net "P5E_CPU1_G1_TX_DN<14>")
	)
	(segment
		(start 96.458024 -222.29191)
		(end 96.489774 -222.310198)
		(width 0.1143)
		(layer "In11.Cu")
		(net "P5E_CPU1_G1_TX_DN<14>")
	)
	(segment
		(start 97.864422 -230.228902)
		(end 97.835974 -230.245412)
		(width 0.1143)
		(layer "In11.Cu")
		(net "P5E_CPU1_G1_TX_DN<14>")
	)
	(segment
		(start 97.875344 -237.686088)
		(end 97.899728 -237.700058)
		(width 0.1143)
		(layer "In11.Cu")
		(net "P5E_CPU1_G1_TX_DN<14>")
	)
	(segment
		(start 97.874074 -240.92535)
		(end 97.875344 -240.926112)
		(width 0.1143)
		(layer "In11.Cu")
		(net "P5E_CPU1_G1_TX_DN<14>")
	)
	(segment
		(start 97.873312 -239.30483)
		(end 97.874074 -239.305338)
		(width 0.1143)
		(layer "In11.Cu")
		(net "P5E_CPU1_G1_TX_DN<14>")
	)
	(segment
		(start 96.928178 -223.101916)
		(end 96.958658 -223.119696)
		(width 0.1143)
		(layer "In11.Cu")
		(net "P5E_CPU1_G1_TX_DN<14>")
	)
	(segment
		(start 97.867978 -242.541806)
		(end 97.86874 -242.542314)
		(width 0.1143)
		(layer "In11.Cu")
		(net "P5E_CPU1_G1_TX_DN<14>")
	)
	(segment
		(start 96.418908 -222.26905)
		(end 96.449642 -222.287084)
		(width 0.1143)
		(layer "In11.Cu")
		(net "P5E_CPU1_G1_TX_DN<14>")
	)
	(segment
		(start 144.912588 -147.809712)
		(end 145.682716 -160.097216)
		(width 0.14224)
		(layer "In11.Cu")
		(net "P5E_CPU1_G1_TX_DN<14>")
	)
	(segment
		(start 97.978976 -244.484398)
		(end 97.681034 -244.484398)
		(width 0.1143)
		(layer "In11.Cu")
		(net "P5E_CPU1_G1_TX_DN<14>")
	)
	(segment
		(start 97.872296 -237.68431)
		(end 97.873312 -237.684818)
		(width 0.1143)
		(layer "In11.Cu")
		(net "P5E_CPU1_G1_TX_DN<14>")
	)
	(segment
		(start 96.958658 -223.729296)
		(end 96.928178 -223.747076)
		(width 0.1143)
		(layer "In11.Cu")
		(net "P5E_CPU1_G1_TX_DN<14>")
	)
	(segment
		(start 97.873312 -240.924842)
		(end 97.874074 -240.92535)
		(width 0.1143)
		(layer "In11.Cu")
		(net "P5E_CPU1_G1_TX_DN<14>")
	)
	(segment
		(start 97.874074 -239.305338)
		(end 97.875344 -239.3061)
		(width 0.1143)
		(layer "In11.Cu")
		(net "P5E_CPU1_G1_TX_DN<14>")
	)
	(segment
		(start 97.874074 -237.685326)
		(end 97.875344 -237.686088)
		(width 0.1143)
		(layer "In11.Cu")
		(net "P5E_CPU1_G1_TX_DN<14>")
	)
	(segment
		(start 97.899728 -231.828594)
		(end 97.867978 -231.846882)
		(width 0.1143)
		(layer "In11.Cu")
		(net "P5E_CPU1_G1_TX_DN<14>")
	)
	(segment
		(start 96.069912 -221.05493)
		(end 96.069912 -221.083378)
		(width 0.1143)
		(layer "In11.Cu")
		(net "P5E_CPU1_G1_TX_DN<14>")
	)
	(segment
		(start 97.889822 -241.554254)
		(end 97.88906 -241.554762)
		(width 0.1143)
		(layer "In11.Cu")
		(net "P5E_CPU1_G1_TX_DN<14>")
	)
	(segment
		(start 97.867978 -243.186966)
		(end 97.831656 -243.208048)
		(width 0.1143)
		(layer "In11.Cu")
		(net "P5E_CPU1_G1_TX_DN<14>")
	)
	(segment
		(start 97.899728 -241.548666)
		(end 97.889822 -241.554254)
		(width 0.1143)
		(layer "In11.Cu")
		(net "P5E_CPU1_G1_TX_DN<14>")
	)
	(segment
		(start 96.17583 -221.448122)
		(end 96.17583 -221.804484)
		(width 0.1143)
		(layer "In11.Cu")
		(net "P5E_CPU1_G1_TX_DN<14>")
	)
	(segment
		(start 97.875344 -239.3061)
		(end 97.899728 -239.32007)
		(width 0.1143)
		(layer "In11.Cu")
		(net "P5E_CPU1_G1_TX_DN<14>")
	)
	(arc
		(start 98.055684 -231.524302)
		(mid 98.014429 -231.695273)
		(end 97.899728 -231.828594)
		(width 0.1143)
		(layer "In11.Cu")
		(net "P5E_CPU1_G1_TX_DN<14>")
	)
	(arc
		(start 97.585784 -229.094538)
		(mid 97.647229 -229.35075)
		(end 97.818194 -229.55123)
		(width 0.1143)
		(layer "In11.Cu")
		(net "P5E_CPU1_G1_TX_DN<14>")
	)
	(arc
		(start 97.901506 -231.221534)
		(mid 98.014913 -231.354423)
		(end 98.055684 -231.524302)
		(width 0.1143)
		(layer "In11.Cu")
		(net "P5E_CPU1_G1_TX_DN<14>")
	)
	(arc
		(start 97.899728 -240.940082)
		(mid 98.055656 -241.244374)
		(end 97.899728 -241.548666)
		(width 0.1143)
		(layer "In11.Cu")
		(net "P5E_CPU1_G1_TX_DN<14>")
	)
	(arc
		(start 97.899728 -232.840022)
		(mid 98.055656 -233.144314)
		(end 97.899728 -233.448606)
		(width 0.1143)
		(layer "In11.Cu")
		(net "P5E_CPU1_G1_TX_DN<14>")
	)
	(arc
		(start 97.818194 -229.55123)
		(mid 97.824889 -229.556106)
		(end 97.831656 -229.560882)
		(width 0.1143)
		(layer "In11.Cu")
		(net "P5E_CPU1_G1_TX_DN<14>")
	)
	(arc
		(start 97.8154 -244.129306)
		(mid 97.823478 -244.135092)
		(end 97.831656 -244.140736)
		(width 0.1143)
		(layer "In11.Cu")
		(net "P5E_CPU1_G1_TX_DN<14>")
	)
	(arc
		(start 96.889062 -223.769936)
		(mid 96.645735 -224.234502)
		(end 96.889062 -224.699068)
		(width 0.1143)
		(layer "In11.Cu")
		(net "P5E_CPU1_G1_TX_DN<14>")
	)
	(arc
		(start 97.817432 -233.497882)
		(mid 97.590049 -233.95432)
		(end 97.817432 -234.410758)
		(width 0.1143)
		(layer "In11.Cu")
		(net "P5E_CPU1_G1_TX_DN<14>")
	)
	(arc
		(start 97.899728 -244.180106)
		(mid 97.996863 -244.282975)
		(end 98.048826 -244.414548)
		(width 0.1143)
		(layer "In11.Cu")
		(net "P5E_CPU1_G1_TX_DN<14>")
	)
	(arc
		(start 97.867978 -228.607112)
		(mid 97.661355 -228.812891)
		(end 97.585784 -229.094538)
		(width 0.1143)
		(layer "In11.Cu")
		(net "P5E_CPU1_G1_TX_DN<14>")
	)
	(arc
		(start 97.585784 -225.87077)
		(mid 97.654745 -226.125301)
		(end 97.831656 -226.320858)
		(width 0.1143)
		(layer "In11.Cu")
		(net "P5E_CPU1_G1_TX_DN<14>")
	)
	(arc
		(start 97.425256 -225.547682)
		(mid 97.429856 -225.551203)
		(end 97.4344 -225.554794)
		(width 0.1143)
		(layer "In11.Cu")
		(net "P5E_CPU1_G1_TX_DN<14>")
	)
	(arc
		(start 96.64573 -222.61449)
		(mid 96.710245 -222.876709)
		(end 96.889062 -223.079056)
		(width 0.1143)
		(layer "In11.Cu")
		(net "P5E_CPU1_G1_TX_DN<14>")
	)
	(arc
		(start 97.899728 -242.560094)
		(mid 98.055656 -242.864386)
		(end 97.899728 -243.168678)
		(width 0.1143)
		(layer "In11.Cu")
		(net "P5E_CPU1_G1_TX_DN<14>")
	)
	(arc
		(start 97.867724 -239.947196)
		(mid 97.587077 -240.434558)
		(end 97.867724 -240.921794)
		(width 0.1143)
		(layer "In11.Cu")
		(net "P5E_CPU1_G1_TX_DN<14>")
	)
	(arc
		(start 97.817432 -234.410758)
		(mid 97.824506 -234.415765)
		(end 97.831656 -234.420664)
		(width 0.1143)
		(layer "In11.Cu")
		(net "P5E_CPU1_G1_TX_DN<14>")
	)
	(arc
		(start 97.899728 -236.080046)
		(mid 98.055656 -236.384338)
		(end 97.899728 -236.68863)
		(width 0.1143)
		(layer "In11.Cu")
		(net "P5E_CPU1_G1_TX_DN<14>")
	)
	(arc
		(start 96.958658 -223.119696)
		(mid 97.115635 -223.424496)
		(end 96.958658 -223.729296)
		(width 0.1143)
		(layer "In11.Cu")
		(net "P5E_CPU1_G1_TX_DN<14>")
	)
	(arc
		(start 97.8154 -232.789222)
		(mid 97.823478 -232.795008)
		(end 97.831656 -232.800652)
		(width 0.1143)
		(layer "In11.Cu")
		(net "P5E_CPU1_G1_TX_DN<14>")
	)
	(arc
		(start 97.581212 -225.827082)
		(mid 97.584397 -225.848704)
		(end 97.585784 -225.870516)
		(width 0.1143)
		(layer "In11.Cu")
		(net "P5E_CPU1_G1_TX_DN<14>")
	)
	(arc
		(start 97.8154 -227.92944)
		(mid 97.823478 -227.935226)
		(end 97.831656 -227.94087)
		(width 0.1143)
		(layer "In11.Cu")
		(net "P5E_CPU1_G1_TX_DN<14>")
	)
	(arc
		(start 97.867724 -236.707172)
		(mid 97.587077 -237.194534)
		(end 97.867724 -237.68177)
		(width 0.1143)
		(layer "In11.Cu")
		(net "P5E_CPU1_G1_TX_DN<14>")
	)
	(arc
		(start 97.817686 -230.257858)
		(mid 97.64951 -230.457561)
		(end 97.585784 -230.71074)
		(width 0.1143)
		(layer "In11.Cu")
		(net "P5E_CPU1_G1_TX_DN<14>")
	)
	(arc
		(start 96.958658 -224.739708)
		(mid 97.074085 -224.873084)
		(end 97.11563 -225.044508)
		(width 0.1143)
		(layer "In11.Cu")
		(net "P5E_CPU1_G1_TX_DN<14>")
	)
	(arc
		(start 97.899728 -227.98024)
		(mid 98.055656 -228.284532)
		(end 97.899728 -228.588824)
		(width 0.1143)
		(layer "In11.Cu")
		(net "P5E_CPU1_G1_TX_DN<14>")
	)
	(arc
		(start 97.899728 -234.460034)
		(mid 98.055656 -234.764326)
		(end 97.899728 -235.068618)
		(width 0.1143)
		(layer "In11.Cu")
		(net "P5E_CPU1_G1_TX_DN<14>")
	)
	(arc
		(start 97.8154 -227.019612)
		(mid 97.592516 -227.474526)
		(end 97.8154 -227.92944)
		(width 0.1143)
		(layer "In11.Cu")
		(net "P5E_CPU1_G1_TX_DN<14>")
	)
	(arc
		(start 97.831656 -227.008182)
		(mid 97.823478 -227.013825)
		(end 97.8154 -227.019612)
		(width 0.1143)
		(layer "In11.Cu")
		(net "P5E_CPU1_G1_TX_DN<14>")
	)
	(arc
		(start 96.28505 -222.139002)
		(mid 96.346569 -222.209596)
		(end 96.418908 -222.26905)
		(width 0.1143)
		(layer "In11.Cu")
		(net "P5E_CPU1_G1_TX_DN<14>")
	)
	(arc
		(start 97.4344 -225.554794)
		(mid 97.528317 -225.679878)
		(end 97.581212 -225.827082)
		(width 0.1143)
		(layer "In11.Cu")
		(net "P5E_CPU1_G1_TX_DN<14>")
	)
	(arc
		(start 97.901506 -229.601522)
		(mid 98.014913 -229.734411)
		(end 98.055684 -229.90429)
		(width 0.1143)
		(layer "In11.Cu")
		(net "P5E_CPU1_G1_TX_DN<14>")
	)
	(arc
		(start 97.899728 -239.32007)
		(mid 98.055656 -239.624362)
		(end 97.899728 -239.928654)
		(width 0.1143)
		(layer "In11.Cu")
		(net "P5E_CPU1_G1_TX_DN<14>")
	)
	(arc
		(start 97.11563 -225.044508)
		(mid 97.180145 -225.306727)
		(end 97.358962 -225.509074)
		(width 0.1143)
		(layer "In11.Cu")
		(net "P5E_CPU1_G1_TX_DN<14>")
	)
	(arc
		(start 97.83445 -230.246428)
		(mid 97.826017 -230.252068)
		(end 97.817686 -230.257858)
		(width 0.1143)
		(layer "In11.Cu")
		(net "P5E_CPU1_G1_TX_DN<14>")
	)
	(arc
		(start 97.8154 -243.219478)
		(mid 97.592516 -243.674392)
		(end 97.8154 -244.129306)
		(width 0.1143)
		(layer "In11.Cu")
		(net "P5E_CPU1_G1_TX_DN<14>")
	)
	(arc
		(start 98.055684 -229.90429)
		(mid 98.014429 -230.075261)
		(end 97.899728 -230.208582)
		(width 0.1143)
		(layer "In11.Cu")
		(net "P5E_CPU1_G1_TX_DN<14>")
	)
	(arc
		(start 96.489774 -222.310198)
		(mid 96.60445 -222.443532)
		(end 96.64573 -222.61449)
		(width 0.1143)
		(layer "In11.Cu")
		(net "P5E_CPU1_G1_TX_DN<14>")
	)
	(arc
		(start 97.867724 -238.327184)
		(mid 97.587077 -238.814546)
		(end 97.867724 -239.301782)
		(width 0.1143)
		(layer "In11.Cu")
		(net "P5E_CPU1_G1_TX_DN<14>")
	)
	(arc
		(start 97.585784 -230.71074)
		(mid 97.655799 -230.990203)
		(end 97.857818 -231.195626)
		(width 0.1143)
		(layer "In11.Cu")
		(net "P5E_CPU1_G1_TX_DN<14>")
	)
	(arc
		(start 97.899728 -237.700058)
		(mid 98.055656 -238.00435)
		(end 97.899728 -238.308642)
		(width 0.1143)
		(layer "In11.Cu")
		(net "P5E_CPU1_G1_TX_DN<14>")
	)
	(arc
		(start 97.899728 -226.360228)
		(mid 98.055656 -226.66452)
		(end 97.899728 -226.968812)
		(width 0.1143)
		(layer "In11.Cu")
		(net "P5E_CPU1_G1_TX_DN<14>")
	)
	(arc
		(start 96.17583 -221.804484)
		(mid 96.203746 -221.98046)
		(end 96.28505 -222.139002)
		(width 0.1143)
		(layer "In11.Cu")
		(net "P5E_CPU1_G1_TX_DN<14>")
	)
	(arc
		(start 97.831656 -231.867964)
		(mid 97.823478 -231.873607)
		(end 97.8154 -231.879394)
		(width 0.1143)
		(layer "In11.Cu")
		(net "P5E_CPU1_G1_TX_DN<14>")
	)
	(arc
		(start 97.831656 -233.487976)
		(mid 97.824507 -233.492876)
		(end 97.817432 -233.497882)
		(width 0.1143)
		(layer "In11.Cu")
		(net "P5E_CPU1_G1_TX_DN<14>")
	)
	(arc
		(start 97.867724 -241.567208)
		(mid 97.587077 -242.05457)
		(end 97.867724 -242.541806)
		(width 0.1143)
		(layer "In11.Cu")
		(net "P5E_CPU1_G1_TX_DN<14>")
	)
	(arc
		(start 97.831656 -243.208048)
		(mid 97.823478 -243.213691)
		(end 97.8154 -243.219478)
		(width 0.1143)
		(layer "In11.Cu")
		(net "P5E_CPU1_G1_TX_DN<14>")
	)
	(arc
		(start 97.8154 -231.879394)
		(mid 97.592516 -232.334308)
		(end 97.8154 -232.789222)
		(width 0.1143)
		(layer "In11.Cu")
		(net "P5E_CPU1_G1_TX_DN<14>")
	)
	(arc
		(start 97.867724 -235.08716)
		(mid 97.587077 -235.574522)
		(end 97.867724 -236.061758)
		(width 0.1143)
		(layer "In11.Cu")
		(net "P5E_CPU1_G1_TX_DN<14>")
	)
	(segment
		(start 98.147886 -247.99036)
		(end 97.681034 -247.724422)
		(width 0.12954)
		(layer "F.Cu")
		(net "P5E_CPU1_G1_TX_DN<13>")
	)
	(segment
		(start 21.392388 -16.662146)
		(end 21.392388 -17.34185)
		(width 0.12954)
		(layer "F.Cu")
		(net "P5E_CPU1_G1_TX_DN<13>")
	)
	(segment
		(start 21.096478 -16.366236)
		(end 21.392388 -16.662146)
		(width 0.12954)
		(layer "F.Cu")
		(net "P5E_CPU1_G1_TX_DN<13>")
	)
	(segment
		(start 21.392388 -17.34185)
		(end 21.121878 -17.61236)
		(width 0.12954)
		(layer "F.Cu")
		(net "P5E_CPU1_G1_TX_DN<13>")
	)
	(segment
		(start 98.805492 -242.540282)
		(end 98.807016 -242.541298)
		(width 0.1143)
		(layer "In11.Cu")
		(net "P5E_CPU1_G1_TX_DN<13>")
	)
	(segment
		(start 98.368612 -247.219216)
		(end 98.338132 -247.236996)
		(width 0.1143)
		(layer "In11.Cu")
		(net "P5E_CPU1_G1_TX_DN<13>")
	)
	(segment
		(start 98.807016 -226.341432)
		(end 98.808032 -226.34194)
		(width 0.1143)
		(layer "In11.Cu")
		(net "P5E_CPU1_G1_TX_DN<13>")
	)
	(segment
		(start 98.839782 -238.308642)
		(end 98.810064 -238.32566)
		(width 0.1143)
		(layer "In11.Cu")
		(net "P5E_CPU1_G1_TX_DN<13>")
	)
	(segment
		(start 98.808794 -236.062266)
		(end 98.810064 -236.063028)
		(width 0.1143)
		(layer "In11.Cu")
		(net "P5E_CPU1_G1_TX_DN<13>")
	)
	(segment
		(start 98.839782 -226.968812)
		(end 98.808794 -226.986592)
		(width 0.1143)
		(layer "In11.Cu")
		(net "P5E_CPU1_G1_TX_DN<13>")
	)
	(segment
		(start 98.808032 -235.086906)
		(end 98.807016 -235.087414)
		(width 0.1143)
		(layer "In11.Cu")
		(net "P5E_CPU1_G1_TX_DN<13>")
	)
	(segment
		(start 98.810064 -233.465624)
		(end 98.808794 -233.466386)
		(width 0.1143)
		(layer "In11.Cu")
		(net "P5E_CPU1_G1_TX_DN<13>")
	)
	(segment
		(start 98.807016 -234.441238)
		(end 98.808032 -234.441746)
		(width 0.1143)
		(layer "In11.Cu")
		(net "P5E_CPU1_G1_TX_DN<13>")
	)
	(segment
		(start 98.810064 -241.565684)
		(end 98.808794 -241.566446)
		(width 0.1143)
		(layer "In11.Cu")
		(net "P5E_CPU1_G1_TX_DN<13>")
	)
	(segment
		(start 145.917666 -147.745958)
		(end 146.689318 -160.065466)
		(width 0.14224)
		(layer "In11.Cu")
		(net "P5E_CPU1_G1_TX_DN<13>")
	)
	(segment
		(start 97.876106 -223.74225)
		(end 97.873566 -223.743774)
		(width 0.1143)
		(layer "In11.Cu")
		(net "P5E_CPU1_G1_TX_DN<13>")
	)
	(segment
		(start 98.808032 -241.566954)
		(end 98.807016 -241.567462)
		(width 0.1143)
		(layer "In11.Cu")
		(net "P5E_CPU1_G1_TX_DN<13>")
	)
	(segment
		(start 98.808032 -244.161818)
		(end 98.808794 -244.162326)
		(width 0.1143)
		(layer "In11.Cu")
		(net "P5E_CPU1_G1_TX_DN<13>")
	)
	(segment
		(start 54.199536 -61.990478)
		(end 143.11249 -141.946376)
		(width 0.14224)
		(layer "In11.Cu")
		(net "P5E_CPU1_G1_TX_DN<13>")
	)
	(segment
		(start 98.338132 -225.531934)
		(end 98.368612 -225.549714)
		(width 0.1143)
		(layer "In11.Cu")
		(net "P5E_CPU1_G1_TX_DN<13>")
	)
	(segment
		(start 98.768916 -242.518946)
		(end 98.805492 -242.540282)
		(width 0.1143)
		(layer "In11.Cu")
		(net "P5E_CPU1_G1_TX_DN<13>")
	)
	(segment
		(start 98.810064 -243.185696)
		(end 98.808794 -243.186458)
		(width 0.1143)
		(layer "In11.Cu")
		(net "P5E_CPU1_G1_TX_DN<13>")
	)
	(segment
		(start 98.808794 -240.922302)
		(end 98.810064 -240.923064)
		(width 0.1143)
		(layer "In11.Cu")
		(net "P5E_CPU1_G1_TX_DN<13>")
	)
	(segment
		(start 98.808794 -226.342448)
		(end 98.839782 -226.360228)
		(width 0.1143)
		(layer "In11.Cu")
		(net "P5E_CPU1_G1_TX_DN<13>")
	)
	(segment
		(start 98.839782 -233.448606)
		(end 98.810064 -233.465624)
		(width 0.1143)
		(layer "In11.Cu")
		(net "P5E_CPU1_G1_TX_DN<13>")
	)
	(segment
		(start 97.863152 -223.098868)
		(end 97.899728 -223.120204)
		(width 0.1143)
		(layer "In11.Cu")
		(net "P5E_CPU1_G1_TX_DN<13>")
	)
	(segment
		(start 98.810064 -236.063028)
		(end 98.811588 -236.06379)
		(width 0.1143)
		(layer "In11.Cu")
		(net "P5E_CPU1_G1_TX_DN<13>")
	)
	(segment
		(start 98.808032 -229.581964)
		(end 98.84156 -229.601522)
		(width 0.1143)
		(layer "In11.Cu")
		(net "P5E_CPU1_G1_TX_DN<13>")
	)
	(segment
		(start 98.768916 -237.65891)
		(end 98.805492 -237.680246)
		(width 0.1143)
		(layer "In11.Cu")
		(net "P5E_CPU1_G1_TX_DN<13>")
	)
	(segment
		(start 146.689318 -162.387534)
		(end 145.487898 -165.91534)
		(width 0.14224)
		(layer "In11.Cu")
		(net "P5E_CPU1_G1_TX_DN<13>")
	)
	(segment
		(start 98.805492 -239.300258)
		(end 98.807016 -239.301274)
		(width 0.1143)
		(layer "In11.Cu")
		(net "P5E_CPU1_G1_TX_DN<13>")
	)
	(segment
		(start 97.871534 -223.745044)
		(end 97.87001 -223.745806)
		(width 0.1143)
		(layer "In11.Cu")
		(net "P5E_CPU1_G1_TX_DN<13>")
	)
	(segment
		(start 143.11249 -141.946376)
		(end 145.917666 -147.745958)
		(width 0.14224)
		(layer "In11.Cu")
		(net "P5E_CPU1_G1_TX_DN<13>")
	)
	(segment
		(start 97.882456 -223.73844)
		(end 97.879916 -223.739964)
		(width 0.1143)
		(layer "In11.Cu")
		(net "P5E_CPU1_G1_TX_DN<13>")
	)
	(segment
		(start 98.808032 -242.541806)
		(end 98.839782 -242.560094)
		(width 0.1143)
		(layer "In11.Cu")
		(net "P5E_CPU1_G1_TX_DN<13>")
	)
	(segment
		(start 98.808032 -226.9871)
		(end 98.807016 -226.987608)
		(width 0.1143)
		(layer "In11.Cu")
		(net "P5E_CPU1_G1_TX_DN<13>")
	)
	(segment
		(start 98.811588 -244.16385)
		(end 98.839782 -244.180106)
		(width 0.1143)
		(layer "In11.Cu")
		(net "P5E_CPU1_G1_TX_DN<13>")
	)
	(segment
		(start 98.808032 -231.846882)
		(end 98.807016 -231.84739)
		(width 0.1143)
		(layer "In11.Cu")
		(net "P5E_CPU1_G1_TX_DN<13>")
	)
	(segment
		(start 98.808032 -230.22687)
		(end 98.771456 -230.248206)
		(width 0.1143)
		(layer "In11.Cu")
		(net "P5E_CPU1_G1_TX_DN<13>")
	)
	(segment
		(start 98.808032 -227.961952)
		(end 98.808794 -227.96246)
		(width 0.1143)
		(layer "In11.Cu")
		(net "P5E_CPU1_G1_TX_DN<13>")
	)
	(segment
		(start 98.805492 -237.680246)
		(end 98.807016 -237.681262)
		(width 0.1143)
		(layer "In11.Cu")
		(net "P5E_CPU1_G1_TX_DN<13>")
	)
	(segment
		(start 98.810064 -227.963222)
		(end 98.811588 -227.963984)
		(width 0.1143)
		(layer "In11.Cu")
		(net "P5E_CPU1_G1_TX_DN<13>")
	)
	(segment
		(start 51.50739 -59.776868)
		(end 54.199536 -61.990478)
		(width 0.14224)
		(layer "In11.Cu")
		(net "P5E_CPU1_G1_TX_DN<13>")
	)
	(segment
		(start 98.807016 -236.707426)
		(end 98.768916 -236.729778)
		(width 0.1143)
		(layer "In11.Cu")
		(net "P5E_CPU1_G1_TX_DN<13>")
	)
	(segment
		(start 98.810064 -244.163088)
		(end 98.811588 -244.16385)
		(width 0.1143)
		(layer "In11.Cu")
		(net "P5E_CPU1_G1_TX_DN<13>")
	)
	(segment
		(start 146.689318 -160.065466)
		(end 146.689318 -162.387534)
		(width 0.14224)
		(layer "In11.Cu")
		(net "P5E_CPU1_G1_TX_DN<13>")
	)
	(segment
		(start 98.805492 -240.92027)
		(end 98.807016 -240.921286)
		(width 0.1143)
		(layer "In11.Cu")
		(net "P5E_CPU1_G1_TX_DN<13>")
	)
	(segment
		(start 98.811588 -236.06379)
		(end 98.839782 -236.080046)
		(width 0.1143)
		(layer "In11.Cu")
		(net "P5E_CPU1_G1_TX_DN<13>")
	)
	(segment
		(start 97.867978 -223.747076)
		(end 97.831656 -223.768158)
		(width 0.1143)
		(layer "In11.Cu")
		(net "P5E_CPU1_G1_TX_DN<13>")
	)
	(segment
		(start 98.807016 -238.327438)
		(end 98.768916 -238.34979)
		(width 0.1143)
		(layer "In11.Cu")
		(net "P5E_CPU1_G1_TX_DN<13>")
	)
	(segment
		(start 98.808032 -226.34194)
		(end 98.808794 -226.342448)
		(width 0.1143)
		(layer "In11.Cu")
		(net "P5E_CPU1_G1_TX_DN<13>")
	)
	(segment
		(start 98.839782 -246.408702)
		(end 98.810064 -246.42572)
		(width 0.1143)
		(layer "In11.Cu")
		(net "P5E_CPU1_G1_TX_DN<13>")
	)
	(segment
		(start 98.805492 -234.440222)
		(end 98.807016 -234.441238)
		(width 0.1143)
		(layer "In11.Cu")
		(net "P5E_CPU1_G1_TX_DN<13>")
	)
	(segment
		(start 37.530278 -44.35475)
		(end 51.50739 -59.776868)
		(width 0.14224)
		(layer "In11.Cu")
		(net "P5E_CPU1_G1_TX_DN<13>")
	)
	(segment
		(start 98.768916 -244.138958)
		(end 98.805492 -244.160294)
		(width 0.1143)
		(layer "In11.Cu")
		(net "P5E_CPU1_G1_TX_DN<13>")
	)
	(segment
		(start 98.808794 -241.566446)
		(end 98.808032 -241.566954)
		(width 0.1143)
		(layer "In11.Cu")
		(net "P5E_CPU1_G1_TX_DN<13>")
	)
	(segment
		(start 97.873566 -223.743774)
		(end 97.872804 -223.744282)
		(width 0.1143)
		(layer "In11.Cu")
		(net "P5E_CPU1_G1_TX_DN<13>")
	)
	(segment
		(start 98.810064 -236.705648)
		(end 98.808794 -236.70641)
		(width 0.1143)
		(layer "In11.Cu")
		(net "P5E_CPU1_G1_TX_DN<13>")
	)
	(segment
		(start 142.123668 -170.883072)
		(end 104.289606 -201.869548)
		(width 0.14224)
		(layer "In11.Cu")
		(net "P5E_CPU1_G1_TX_DN<13>")
	)
	(segment
		(start 98.810064 -231.845612)
		(end 98.808794 -231.846374)
		(width 0.1143)
		(layer "In11.Cu")
		(net "P5E_CPU1_G1_TX_DN<13>")
	)
	(segment
		(start 98.808794 -238.326422)
		(end 98.808032 -238.32693)
		(width 0.1143)
		(layer "In11.Cu")
		(net "P5E_CPU1_G1_TX_DN<13>")
	)
	(segment
		(start 97.8916 -223.73336)
		(end 97.887282 -223.7359)
		(width 0.1143)
		(layer "In11.Cu")
		(net "P5E_CPU1_G1_TX_DN<13>")
	)
	(segment
		(start 97.86874 -223.746568)
		(end 97.867978 -223.747076)
		(width 0.1143)
		(layer "In11.Cu")
		(net "P5E_CPU1_G1_TX_DN<13>")
	)
	(segment
		(start 98.839782 -231.828594)
		(end 98.810064 -231.845612)
		(width 0.1143)
		(layer "In11.Cu")
		(net "P5E_CPU1_G1_TX_DN<13>")
	)
	(segment
		(start 97.014792 -221.05493)
		(end 97.014792 -221.083378)
		(width 0.1143)
		(layer "In11.Cu")
		(net "P5E_CPU1_G1_TX_DN<13>")
	)
	(segment
		(start 98.06178 -247.641618)
		(end 97.978976 -247.724422)
		(width 0.1143)
		(layer "In11.Cu")
		(net "P5E_CPU1_G1_TX_DN<13>")
	)
	(segment
		(start 98.808794 -226.986592)
		(end 98.808032 -226.9871)
		(width 0.1143)
		(layer "In11.Cu")
		(net "P5E_CPU1_G1_TX_DN<13>")
	)
	(segment
		(start 98.807016 -232.821226)
		(end 98.808032 -232.821734)
		(width 0.1143)
		(layer "In11.Cu")
		(net "P5E_CPU1_G1_TX_DN<13>")
	)
	(segment
		(start 98.813874 -228.60381)
		(end 98.81235 -228.604572)
		(width 0.1143)
		(layer "In11.Cu")
		(net "P5E_CPU1_G1_TX_DN<13>")
	)
	(segment
		(start 98.768916 -227.939092)
		(end 98.807016 -227.961444)
		(width 0.1143)
		(layer "In11.Cu")
		(net "P5E_CPU1_G1_TX_DN<13>")
	)
	(segment
		(start 98.807016 -241.567462)
		(end 98.768916 -241.589814)
		(width 0.1143)
		(layer "In11.Cu")
		(net "P5E_CPU1_G1_TX_DN<13>")
	)
	(segment
		(start 98.805492 -244.160294)
		(end 98.807016 -244.16131)
		(width 0.1143)
		(layer "In11.Cu")
		(net "P5E_CPU1_G1_TX_DN<13>")
	)
	(segment
		(start 97.867978 -224.721928)
		(end 97.86874 -224.722436)
		(width 0.1143)
		(layer "In11.Cu")
		(net "P5E_CPU1_G1_TX_DN<13>")
	)
	(segment
		(start 98.807016 -244.16131)
		(end 98.808032 -244.161818)
		(width 0.1143)
		(layer "In11.Cu")
		(net "P5E_CPU1_G1_TX_DN<13>")
	)
	(segment
		(start 97.014792 -214.184484)
		(end 97.014792 -221.05493)
		(width 0.14224)
		(layer "In11.Cu")
		(net "P5E_CPU1_G1_TX_DN<13>")
	)
	(segment
		(start 98.768916 -229.559104)
		(end 98.808032 -229.581964)
		(width 0.1143)
		(layer "In11.Cu")
		(net "P5E_CPU1_G1_TX_DN<13>")
	)
	(segment
		(start 98.810064 -244.805708)
		(end 98.808794 -244.80647)
		(width 0.1143)
		(layer "In11.Cu")
		(net "P5E_CPU1_G1_TX_DN<13>")
	)
	(segment
		(start 98.807016 -239.301274)
		(end 98.808032 -239.301782)
		(width 0.1143)
		(layer "In11.Cu")
		(net "P5E_CPU1_G1_TX_DN<13>")
	)
	(segment
		(start 98.807016 -243.187474)
		(end 98.768916 -243.209826)
		(width 0.1143)
		(layer "In11.Cu")
		(net "P5E_CPU1_G1_TX_DN<13>")
	)
	(segment
		(start 21.412708 -17.90319)
		(end 21.412708 -20.278598)
		(width 0.14224)
		(layer "In11.Cu")
		(net "P5E_CPU1_G1_TX_DN<13>")
	)
	(segment
		(start 21.121878 -17.61236)
		(end 21.412708 -17.90319)
		(width 0.14224)
		(layer "In11.Cu")
		(net "P5E_CPU1_G1_TX_DN<13>")
	)
	(segment
		(start 98.299016 -225.509074)
		(end 98.338132 -225.531934)
		(width 0.1143)
		(layer "In11.Cu")
		(net "P5E_CPU1_G1_TX_DN<13>")
	)
	(segment
		(start 98.768916 -245.75897)
		(end 98.805492 -245.780306)
		(width 0.1143)
		(layer "In11.Cu")
		(net "P5E_CPU1_G1_TX_DN<13>")
	)
	(segment
		(start 98.808794 -239.30229)
		(end 98.810064 -239.303052)
		(width 0.1143)
		(layer "In11.Cu")
		(net "P5E_CPU1_G1_TX_DN<13>")
	)
	(segment
		(start 98.808032 -233.466894)
		(end 98.807016 -233.467402)
		(width 0.1143)
		(layer "In11.Cu")
		(net "P5E_CPU1_G1_TX_DN<13>")
	)
	(segment
		(start 98.79965 -226.337114)
		(end 98.801936 -226.338384)
		(width 0.1143)
		(layer "In11.Cu")
		(net "P5E_CPU1_G1_TX_DN<13>")
	)
	(segment
		(start 98.808032 -234.441746)
		(end 98.808794 -234.442254)
		(width 0.1143)
		(layer "In11.Cu")
		(net "P5E_CPU1_G1_TX_DN<13>")
	)
	(segment
		(start 98.801936 -226.338384)
		(end 98.802952 -226.338892)
		(width 0.1143)
		(layer "In11.Cu")
		(net "P5E_CPU1_G1_TX_DN<13>")
	)
	(segment
		(start 98.808794 -239.946434)
		(end 98.808032 -239.946942)
		(width 0.1143)
		(layer "In11.Cu")
		(net "P5E_CPU1_G1_TX_DN<13>")
	)
	(segment
		(start 98.807016 -236.06125)
		(end 98.808032 -236.061758)
		(width 0.1143)
		(layer "In11.Cu")
		(net "P5E_CPU1_G1_TX_DN<13>")
	)
	(segment
		(start 98.839782 -236.68863)
		(end 98.810064 -236.705648)
		(width 0.1143)
		(layer "In11.Cu")
		(net "P5E_CPU1_G1_TX_DN<13>")
	)
	(segment
		(start 98.768916 -236.038898)
		(end 98.805492 -236.060234)
		(width 0.1143)
		(layer "In11.Cu")
		(net "P5E_CPU1_G1_TX_DN<13>")
	)
	(segment
		(start 98.815906 -228.60254)
		(end 98.814636 -228.603302)
		(width 0.1143)
		(layer "In11.Cu")
		(net "P5E_CPU1_G1_TX_DN<13>")
	)
	(segment
		(start 98.808032 -245.78183)
		(end 98.839782 -245.800118)
		(width 0.1143)
		(layer "In11.Cu")
		(net "P5E_CPU1_G1_TX_DN<13>")
	)
	(segment
		(start 98.808794 -243.186458)
		(end 98.808032 -243.186966)
		(width 0.1143)
		(layer "In11.Cu")
		(net "P5E_CPU1_G1_TX_DN<13>")
	)
	(segment
		(start 98.814636 -228.603302)
		(end 98.813874 -228.60381)
		(width 0.1143)
		(layer "In11.Cu")
		(net "P5E_CPU1_G1_TX_DN<13>")
	)
	(segment
		(start 98.811588 -232.823766)
		(end 98.839782 -232.840022)
		(width 0.1143)
		(layer "In11.Cu")
		(net "P5E_CPU1_G1_TX_DN<13>")
	)
	(segment
		(start 97.115884 -221.443296)
		(end 97.115884 -221.804484)
		(width 0.1143)
		(layer "In11.Cu")
		(net "P5E_CPU1_G1_TX_DN<13>")
	)
	(segment
		(start 97.87001 -223.745806)
		(end 97.86874 -223.746568)
		(width 0.1143)
		(layer "In11.Cu")
		(net "P5E_CPU1_G1_TX_DN<13>")
	)
	(segment
		(start 98.805492 -245.780306)
		(end 98.807016 -245.781322)
		(width 0.1143)
		(layer "In11.Cu")
		(net "P5E_CPU1_G1_TX_DN<13>")
	)
	(segment
		(start 98.810064 -239.945672)
		(end 98.808794 -239.946434)
		(width 0.1143)
		(layer "In11.Cu")
		(net "P5E_CPU1_G1_TX_DN<13>")
	)
	(segment
		(start 98.807016 -242.541298)
		(end 98.808032 -242.541806)
		(width 0.1143)
		(layer "In11.Cu")
		(net "P5E_CPU1_G1_TX_DN<13>")
	)
	(segment
		(start 98.808794 -244.80647)
		(end 98.808032 -244.806978)
		(width 0.1143)
		(layer "In11.Cu")
		(net "P5E_CPU1_G1_TX_DN<13>")
	)
	(segment
		(start 98.811588 -234.443778)
		(end 98.839782 -234.460034)
		(width 0.1143)
		(layer "In11.Cu")
		(net "P5E_CPU1_G1_TX_DN<13>")
	)
	(segment
		(start 98.808032 -240.921794)
		(end 98.808794 -240.922302)
		(width 0.1143)
		(layer "In11.Cu")
		(net "P5E_CPU1_G1_TX_DN<13>")
	)
	(segment
		(start 98.839782 -239.928654)
		(end 98.810064 -239.945672)
		(width 0.1143)
		(layer "In11.Cu")
		(net "P5E_CPU1_G1_TX_DN<13>")
	)
	(segment
		(start 98.811588 -240.923826)
		(end 98.839782 -240.940082)
		(width 0.1143)
		(layer "In11.Cu")
		(net "P5E_CPU1_G1_TX_DN<13>")
	)
	(segment
		(start 98.802952 -226.338892)
		(end 98.804476 -226.339908)
		(width 0.1143)
		(layer "In11.Cu")
		(net "P5E_CPU1_G1_TX_DN<13>")
	)
	(segment
		(start 97.877884 -223.741234)
		(end 97.876106 -223.74225)
		(width 0.1143)
		(layer "In11.Cu")
		(net "P5E_CPU1_G1_TX_DN<13>")
	)
	(segment
		(start 98.811588 -227.963984)
		(end 98.839782 -227.98024)
		(width 0.1143)
		(layer "In11.Cu")
		(net "P5E_CPU1_G1_TX_DN<13>")
	)
	(segment
		(start 98.808032 -236.706918)
		(end 98.807016 -236.707426)
		(width 0.1143)
		(layer "In11.Cu")
		(net "P5E_CPU1_G1_TX_DN<13>")
	)
	(segment
		(start 97.86874 -224.722436)
		(end 97.899728 -224.740216)
		(width 0.1143)
		(layer "In11.Cu")
		(net "P5E_CPU1_G1_TX_DN<13>")
	)
	(segment
		(start 98.807016 -244.807486)
		(end 98.768916 -244.829838)
		(width 0.1143)
		(layer "In11.Cu")
		(net "P5E_CPU1_G1_TX_DN<13>")
	)
	(segment
		(start 97.831656 -224.700846)
		(end 97.867978 -224.721928)
		(width 0.1143)
		(layer "In11.Cu")
		(net "P5E_CPU1_G1_TX_DN<13>")
	)
	(segment
		(start 98.811588 -239.303814)
		(end 98.839782 -239.32007)
		(width 0.1143)
		(layer "In11.Cu")
		(net "P5E_CPU1_G1_TX_DN<13>")
	)
	(segment
		(start 98.808032 -239.946942)
		(end 98.807016 -239.94745)
		(width 0.1143)
		(layer "In11.Cu")
		(net "P5E_CPU1_G1_TX_DN<13>")
	)
	(segment
		(start 98.807016 -237.681262)
		(end 98.808032 -237.68177)
		(width 0.1143)
		(layer "In11.Cu")
		(net "P5E_CPU1_G1_TX_DN<13>")
	)
	(segment
		(start 98.808794 -228.606604)
		(end 98.808032 -228.607112)
		(width 0.1143)
		(layer "In11.Cu")
		(net "P5E_CPU1_G1_TX_DN<13>")
	)
	(segment
		(start 97.879916 -223.739964)
		(end 97.877884 -223.741234)
		(width 0.1143)
		(layer "In11.Cu")
		(net "P5E_CPU1_G1_TX_DN<13>")
	)
	(segment
		(start 98.768916 -231.179116)
		(end 98.808032 -231.201976)
		(width 0.1143)
		(layer "In11.Cu")
		(net "P5E_CPU1_G1_TX_DN<13>")
	)
	(segment
		(start 97.978976 -247.724422)
		(end 97.681034 -247.724422)
		(width 0.1143)
		(layer "In11.Cu")
		(net "P5E_CPU1_G1_TX_DN<13>")
	)
	(segment
		(start 98.808794 -231.846374)
		(end 98.808032 -231.846882)
		(width 0.1143)
		(layer "In11.Cu")
		(net "P5E_CPU1_G1_TX_DN<13>")
	)
	(segment
		(start 98.807016 -233.467402)
		(end 98.768916 -233.489754)
		(width 0.1143)
		(layer "In11.Cu")
		(net "P5E_CPU1_G1_TX_DN<13>")
	)
	(segment
		(start 98.808794 -246.426482)
		(end 98.808032 -246.42699)
		(width 0.1143)
		(layer "In11.Cu")
		(net "P5E_CPU1_G1_TX_DN<13>")
	)
	(segment
		(start 98.808032 -246.42699)
		(end 98.807016 -246.427498)
		(width 0.1143)
		(layer "In11.Cu")
		(net "P5E_CPU1_G1_TX_DN<13>")
	)
	(segment
		(start 98.808032 -243.186966)
		(end 98.807016 -243.187474)
		(width 0.1143)
		(layer "In11.Cu")
		(net "P5E_CPU1_G1_TX_DN<13>")
	)
	(segment
		(start 98.804476 -226.339908)
		(end 98.805492 -226.340416)
		(width 0.1143)
		(layer "In11.Cu")
		(net "P5E_CPU1_G1_TX_DN<13>")
	)
	(segment
		(start 98.807016 -227.961444)
		(end 98.808032 -227.961952)
		(width 0.1143)
		(layer "In11.Cu")
		(net "P5E_CPU1_G1_TX_DN<13>")
	)
	(segment
		(start 98.808032 -231.201976)
		(end 98.84156 -231.221534)
		(width 0.1143)
		(layer "In11.Cu")
		(net "P5E_CPU1_G1_TX_DN<13>")
	)
	(segment
		(start 98.808032 -237.68177)
		(end 98.839782 -237.700058)
		(width 0.1143)
		(layer "In11.Cu")
		(net "P5E_CPU1_G1_TX_DN<13>")
	)
	(segment
		(start 98.810064 -240.923064)
		(end 98.811588 -240.923826)
		(width 0.1143)
		(layer "In11.Cu")
		(net "P5E_CPU1_G1_TX_DN<13>")
	)
	(segment
		(start 98.839782 -243.168678)
		(end 98.810064 -243.185696)
		(width 0.1143)
		(layer "In11.Cu")
		(net "P5E_CPU1_G1_TX_DN<13>")
	)
	(segment
		(start 98.808032 -232.821734)
		(end 98.808794 -232.822242)
		(width 0.1143)
		(layer "In11.Cu")
		(net "P5E_CPU1_G1_TX_DN<13>")
	)
	(segment
		(start 98.808794 -233.466386)
		(end 98.808032 -233.466894)
		(width 0.1143)
		(layer "In11.Cu")
		(net "P5E_CPU1_G1_TX_DN<13>")
	)
	(segment
		(start 98.768916 -234.418886)
		(end 98.805492 -234.440222)
		(width 0.1143)
		(layer "In11.Cu")
		(net "P5E_CPU1_G1_TX_DN<13>")
	)
	(segment
		(start 98.811588 -228.60508)
		(end 98.808794 -228.606604)
		(width 0.1143)
		(layer "In11.Cu")
		(net "P5E_CPU1_G1_TX_DN<13>")
	)
	(segment
		(start 98.839782 -228.588824)
		(end 98.818192 -228.60127)
		(width 0.1143)
		(layer "In11.Cu")
		(net "P5E_CPU1_G1_TX_DN<13>")
	)
	(segment
		(start 98.808794 -232.822242)
		(end 98.810064 -232.823004)
		(width 0.1143)
		(layer "In11.Cu")
		(net "P5E_CPU1_G1_TX_DN<13>")
	)
	(segment
		(start 98.805492 -236.060234)
		(end 98.807016 -236.06125)
		(width 0.1143)
		(layer "In11.Cu")
		(net "P5E_CPU1_G1_TX_DN<13>")
	)
	(segment
		(start 97.359724 -222.269558)
		(end 97.402142 -222.293942)
		(width 0.1143)
		(layer "In11.Cu")
		(net "P5E_CPU1_G1_TX_DN<13>")
	)
	(segment
		(start 98.81235 -228.604572)
		(end 98.811588 -228.60508)
		(width 0.1143)
		(layer "In11.Cu")
		(net "P5E_CPU1_G1_TX_DN<13>")
	)
	(segment
		(start 97.862644 -223.098868)
		(end 97.863152 -223.098868)
		(width 0.1143)
		(layer "In11.Cu")
		(net "P5E_CPU1_G1_TX_DN<13>")
	)
	(segment
		(start 145.487898 -165.91534)
		(end 142.123668 -170.883072)
		(width 0.14224)
		(layer "In11.Cu")
		(net "P5E_CPU1_G1_TX_DN<13>")
	)
	(segment
		(start 98.805492 -232.82021)
		(end 98.807016 -232.821226)
		(width 0.1143)
		(layer "In11.Cu")
		(net "P5E_CPU1_G1_TX_DN<13>")
	)
	(segment
		(start 98.808794 -236.70641)
		(end 98.808032 -236.706918)
		(width 0.1143)
		(layer "In11.Cu")
		(net "P5E_CPU1_G1_TX_DN<13>")
	)
	(segment
		(start 98.808032 -236.061758)
		(end 98.808794 -236.062266)
		(width 0.1143)
		(layer "In11.Cu")
		(net "P5E_CPU1_G1_TX_DN<13>")
	)
	(segment
		(start 97.060512 -221.129098)
		(end 97.060512 -221.387924)
		(width 0.1143)
		(layer "In11.Cu")
		(net "P5E_CPU1_G1_TX_DN<13>")
	)
	(segment
		(start 98.810064 -232.823004)
		(end 98.811588 -232.823766)
		(width 0.1143)
		(layer "In11.Cu")
		(net "P5E_CPU1_G1_TX_DN<13>")
	)
	(segment
		(start 98.810064 -239.303052)
		(end 98.811588 -239.303814)
		(width 0.1143)
		(layer "In11.Cu")
		(net "P5E_CPU1_G1_TX_DN<13>")
	)
	(segment
		(start 97.887282 -223.7359)
		(end 97.885758 -223.736662)
		(width 0.1143)
		(layer "In11.Cu")
		(net "P5E_CPU1_G1_TX_DN<13>")
	)
	(segment
		(start 98.810064 -235.085636)
		(end 98.808794 -235.086398)
		(width 0.1143)
		(layer "In11.Cu")
		(net "P5E_CPU1_G1_TX_DN<13>")
	)
	(segment
		(start 97.88398 -223.737678)
		(end 97.882456 -223.73844)
		(width 0.1143)
		(layer "In11.Cu")
		(net "P5E_CPU1_G1_TX_DN<13>")
	)
	(segment
		(start 98.808032 -239.301782)
		(end 98.808794 -239.30229)
		(width 0.1143)
		(layer "In11.Cu")
		(net "P5E_CPU1_G1_TX_DN<13>")
	)
	(segment
		(start 98.808794 -227.96246)
		(end 98.810064 -227.963222)
		(width 0.1143)
		(layer "In11.Cu")
		(net "P5E_CPU1_G1_TX_DN<13>")
	)
	(segment
		(start 98.839782 -244.78869)
		(end 98.810064 -244.805708)
		(width 0.1143)
		(layer "In11.Cu")
		(net "P5E_CPU1_G1_TX_DN<13>")
	)
	(segment
		(start 98.839782 -230.208582)
		(end 98.808032 -230.22687)
		(width 0.1143)
		(layer "In11.Cu")
		(net "P5E_CPU1_G1_TX_DN<13>")
	)
	(segment
		(start 97.899728 -223.728788)
		(end 97.8916 -223.73336)
		(width 0.1143)
		(layer "In11.Cu")
		(net "P5E_CPU1_G1_TX_DN<13>")
	)
	(segment
		(start 98.768916 -232.798874)
		(end 98.805492 -232.82021)
		(width 0.1143)
		(layer "In11.Cu")
		(net "P5E_CPU1_G1_TX_DN<13>")
	)
	(segment
		(start 98.810064 -238.32566)
		(end 98.808794 -238.326422)
		(width 0.1143)
		(layer "In11.Cu")
		(net "P5E_CPU1_G1_TX_DN<13>")
	)
	(segment
		(start 98.839782 -241.548666)
		(end 98.810064 -241.565684)
		(width 0.1143)
		(layer "In11.Cu")
		(net "P5E_CPU1_G1_TX_DN<13>")
	)
	(segment
		(start 97.060512 -221.387924)
		(end 97.115884 -221.443296)
		(width 0.1143)
		(layer "In11.Cu")
		(net "P5E_CPU1_G1_TX_DN<13>")
	)
	(segment
		(start 97.872804 -223.744282)
		(end 97.871534 -223.745044)
		(width 0.1143)
		(layer "In11.Cu")
		(net "P5E_CPU1_G1_TX_DN<13>")
	)
	(segment
		(start 98.807016 -235.087414)
		(end 98.768916 -235.109766)
		(width 0.1143)
		(layer "In11.Cu")
		(net "P5E_CPU1_G1_TX_DN<13>")
	)
	(segment
		(start 98.808032 -228.607112)
		(end 98.807016 -228.60762)
		(width 0.1143)
		(layer "In11.Cu")
		(net "P5E_CPU1_G1_TX_DN<13>")
	)
	(segment
		(start 97.014792 -221.083378)
		(end 97.060512 -221.129098)
		(width 0.1143)
		(layer "In11.Cu")
		(net "P5E_CPU1_G1_TX_DN<13>")
	)
	(segment
		(start 98.818192 -228.60127)
		(end 98.81743 -228.601778)
		(width 0.1143)
		(layer "In11.Cu")
		(net "P5E_CPU1_G1_TX_DN<13>")
	)
	(segment
		(start 98.807016 -245.781322)
		(end 98.808032 -245.78183)
		(width 0.1143)
		(layer "In11.Cu")
		(net "P5E_CPU1_G1_TX_DN<13>")
	)
	(segment
		(start 98.807016 -228.60762)
		(end 98.768916 -228.629972)
		(width 0.1143)
		(layer "In11.Cu")
		(net "P5E_CPU1_G1_TX_DN<13>")
	)
	(segment
		(start 98.808032 -238.32693)
		(end 98.807016 -238.327438)
		(width 0.1143)
		(layer "In11.Cu")
		(net "P5E_CPU1_G1_TX_DN<13>")
	)
	(segment
		(start 98.808794 -244.162326)
		(end 98.810064 -244.163088)
		(width 0.1143)
		(layer "In11.Cu")
		(net "P5E_CPU1_G1_TX_DN<13>")
	)
	(segment
		(start 21.412708 -20.278598)
		(end 37.530278 -44.35475)
		(width 0.14224)
		(layer "In11.Cu")
		(net "P5E_CPU1_G1_TX_DN<13>")
	)
	(segment
		(start 98.807016 -240.921286)
		(end 98.808032 -240.921794)
		(width 0.1143)
		(layer "In11.Cu")
		(net "P5E_CPU1_G1_TX_DN<13>")
	)
	(segment
		(start 98.810064 -246.42572)
		(end 98.808794 -246.426482)
		(width 0.1143)
		(layer "In11.Cu")
		(net "P5E_CPU1_G1_TX_DN<13>")
	)
	(segment
		(start 97.885758 -223.736662)
		(end 97.88398 -223.737678)
		(width 0.1143)
		(layer "In11.Cu")
		(net "P5E_CPU1_G1_TX_DN<13>")
	)
	(segment
		(start 98.805492 -226.340416)
		(end 98.807016 -226.341432)
		(width 0.1143)
		(layer "In11.Cu")
		(net "P5E_CPU1_G1_TX_DN<13>")
	)
	(segment
		(start 98.768916 -240.898934)
		(end 98.805492 -240.92027)
		(width 0.1143)
		(layer "In11.Cu")
		(net "P5E_CPU1_G1_TX_DN<13>")
	)
	(segment
		(start 98.810064 -234.443016)
		(end 98.811588 -234.443778)
		(width 0.1143)
		(layer "In11.Cu")
		(net "P5E_CPU1_G1_TX_DN<13>")
	)
	(segment
		(start 98.768916 -226.31908)
		(end 98.79965 -226.337114)
		(width 0.1143)
		(layer "In11.Cu")
		(net "P5E_CPU1_G1_TX_DN<13>")
	)
	(segment
		(start 98.808032 -244.806978)
		(end 98.807016 -244.807486)
		(width 0.1143)
		(layer "In11.Cu")
		(net "P5E_CPU1_G1_TX_DN<13>")
	)
	(segment
		(start 98.807016 -239.94745)
		(end 98.768916 -239.969802)
		(width 0.1143)
		(layer "In11.Cu")
		(net "P5E_CPU1_G1_TX_DN<13>")
	)
	(segment
		(start 98.81743 -228.601778)
		(end 98.815906 -228.60254)
		(width 0.1143)
		(layer "In11.Cu")
		(net "P5E_CPU1_G1_TX_DN<13>")
	)
	(segment
		(start 98.808794 -235.086398)
		(end 98.808032 -235.086906)
		(width 0.1143)
		(layer "In11.Cu")
		(net "P5E_CPU1_G1_TX_DN<13>")
	)
	(segment
		(start 98.808794 -234.442254)
		(end 98.810064 -234.443016)
		(width 0.1143)
		(layer "In11.Cu")
		(net "P5E_CPU1_G1_TX_DN<13>")
	)
	(segment
		(start 98.338132 -247.236996)
		(end 98.299016 -247.259856)
		(width 0.1143)
		(layer "In11.Cu")
		(net "P5E_CPU1_G1_TX_DN<13>")
	)
	(segment
		(start 104.289606 -201.869548)
		(end 97.014792 -214.184484)
		(width 0.14224)
		(layer "In11.Cu")
		(net "P5E_CPU1_G1_TX_DN<13>")
	)
	(segment
		(start 98.807016 -226.987608)
		(end 98.768916 -227.00996)
		(width 0.1143)
		(layer "In11.Cu")
		(net "P5E_CPU1_G1_TX_DN<13>")
	)
	(segment
		(start 98.839782 -235.068618)
		(end 98.810064 -235.085636)
		(width 0.1143)
		(layer "In11.Cu")
		(net "P5E_CPU1_G1_TX_DN<13>")
	)
	(segment
		(start 98.807016 -246.427498)
		(end 98.768916 -246.44985)
		(width 0.1143)
		(layer "In11.Cu")
		(net "P5E_CPU1_G1_TX_DN<13>")
	)
	(segment
		(start 98.768916 -239.278922)
		(end 98.805492 -239.300258)
		(width 0.1143)
		(layer "In11.Cu")
		(net "P5E_CPU1_G1_TX_DN<13>")
	)
	(segment
		(start 98.807016 -231.84739)
		(end 98.768916 -231.869742)
		(width 0.1143)
		(layer "In11.Cu")
		(net "P5E_CPU1_G1_TX_DN<13>")
	)
	(arc
		(start 97.831656 -223.768158)
		(mid 97.823992 -223.773429)
		(end 97.816416 -223.778826)
		(width 0.1143)
		(layer "In11.Cu")
		(net "P5E_CPU1_G1_TX_DN<13>")
	)
	(arc
		(start 98.06559 -247.618758)
		(mid 98.063567 -247.630168)
		(end 98.06178 -247.641618)
		(width 0.1143)
		(layer "In11.Cu")
		(net "P5E_CPU1_G1_TX_DN<13>")
	)
	(arc
		(start 98.768916 -228.629972)
		(mid 98.525589 -229.094538)
		(end 98.768916 -229.559104)
		(width 0.1143)
		(layer "In11.Cu")
		(net "P5E_CPU1_G1_TX_DN<13>")
	)
	(arc
		(start 98.839782 -226.360228)
		(mid 98.99571 -226.66452)
		(end 98.839782 -226.968812)
		(width 0.1143)
		(layer "In11.Cu")
		(net "P5E_CPU1_G1_TX_DN<13>")
	)
	(arc
		(start 98.839782 -242.560094)
		(mid 98.99571 -242.864386)
		(end 98.839782 -243.168678)
		(width 0.1143)
		(layer "In11.Cu")
		(net "P5E_CPU1_G1_TX_DN<13>")
	)
	(arc
		(start 98.839782 -245.800118)
		(mid 98.99571 -246.10441)
		(end 98.839782 -246.408702)
		(width 0.1143)
		(layer "In11.Cu")
		(net "P5E_CPU1_G1_TX_DN<13>")
	)
	(arc
		(start 98.839782 -236.080046)
		(mid 98.99571 -236.384338)
		(end 98.839782 -236.68863)
		(width 0.1143)
		(layer "In11.Cu")
		(net "P5E_CPU1_G1_TX_DN<13>")
	)
	(arc
		(start 97.115884 -221.804484)
		(mid 97.180543 -222.067041)
		(end 97.359724 -222.269558)
		(width 0.1143)
		(layer "In11.Cu")
		(net "P5E_CPU1_G1_TX_DN<13>")
	)
	(arc
		(start 98.525584 -225.854514)
		(mid 98.590099 -226.116733)
		(end 98.768916 -226.31908)
		(width 0.1143)
		(layer "In11.Cu")
		(net "P5E_CPU1_G1_TX_DN<13>")
	)
	(arc
		(start 98.839782 -227.98024)
		(mid 98.99571 -228.284532)
		(end 98.839782 -228.588824)
		(width 0.1143)
		(layer "In11.Cu")
		(net "P5E_CPU1_G1_TX_DN<13>")
	)
	(arc
		(start 97.585784 -222.61449)
		(mid 97.659833 -222.893469)
		(end 97.862644 -223.098868)
		(width 0.1143)
		(layer "In11.Cu")
		(net "P5E_CPU1_G1_TX_DN<13>")
	)
	(arc
		(start 97.899728 -224.740216)
		(mid 98.014404 -224.87355)
		(end 98.055684 -225.044508)
		(width 0.1143)
		(layer "In11.Cu")
		(net "P5E_CPU1_G1_TX_DN<13>")
	)
	(arc
		(start 98.768916 -227.00996)
		(mid 98.525589 -227.474526)
		(end 98.768916 -227.939092)
		(width 0.1143)
		(layer "In11.Cu")
		(net "P5E_CPU1_G1_TX_DN<13>")
	)
	(arc
		(start 98.839782 -240.940082)
		(mid 98.99571 -241.244374)
		(end 98.839782 -241.548666)
		(width 0.1143)
		(layer "In11.Cu")
		(net "P5E_CPU1_G1_TX_DN<13>")
	)
	(arc
		(start 98.839782 -239.32007)
		(mid 98.99571 -239.624362)
		(end 98.839782 -239.928654)
		(width 0.1143)
		(layer "In11.Cu")
		(net "P5E_CPU1_G1_TX_DN<13>")
	)
	(arc
		(start 98.768916 -238.34979)
		(mid 98.525589 -238.814356)
		(end 98.768916 -239.278922)
		(width 0.1143)
		(layer "In11.Cu")
		(net "P5E_CPU1_G1_TX_DN<13>")
	)
	(arc
		(start 98.839782 -234.460034)
		(mid 98.99571 -234.764326)
		(end 98.839782 -235.068618)
		(width 0.1143)
		(layer "In11.Cu")
		(net "P5E_CPU1_G1_TX_DN<13>")
	)
	(arc
		(start 98.84156 -229.601522)
		(mid 98.954967 -229.734411)
		(end 98.995738 -229.90429)
		(width 0.1143)
		(layer "In11.Cu")
		(net "P5E_CPU1_G1_TX_DN<13>")
	)
	(arc
		(start 98.768916 -239.969802)
		(mid 98.525589 -240.434368)
		(end 98.768916 -240.898934)
		(width 0.1143)
		(layer "In11.Cu")
		(net "P5E_CPU1_G1_TX_DN<13>")
	)
	(arc
		(start 98.768916 -235.109766)
		(mid 98.525589 -235.574332)
		(end 98.768916 -236.038898)
		(width 0.1143)
		(layer "In11.Cu")
		(net "P5E_CPU1_G1_TX_DN<13>")
	)
	(arc
		(start 98.995738 -229.90429)
		(mid 98.954483 -230.075261)
		(end 98.839782 -230.208582)
		(width 0.1143)
		(layer "In11.Cu")
		(net "P5E_CPU1_G1_TX_DN<13>")
	)
	(arc
		(start 98.768916 -241.589814)
		(mid 98.525589 -242.05438)
		(end 98.768916 -242.518946)
		(width 0.1143)
		(layer "In11.Cu")
		(net "P5E_CPU1_G1_TX_DN<13>")
	)
	(arc
		(start 98.768916 -243.209826)
		(mid 98.525589 -243.674392)
		(end 98.768916 -244.138958)
		(width 0.1143)
		(layer "In11.Cu")
		(net "P5E_CPU1_G1_TX_DN<13>")
	)
	(arc
		(start 98.768916 -244.829838)
		(mid 98.525589 -245.294404)
		(end 98.768916 -245.75897)
		(width 0.1143)
		(layer "In11.Cu")
		(net "P5E_CPU1_G1_TX_DN<13>")
	)
	(arc
		(start 97.402142 -222.293942)
		(mid 97.536614 -222.42978)
		(end 97.585784 -222.61449)
		(width 0.1143)
		(layer "In11.Cu")
		(net "P5E_CPU1_G1_TX_DN<13>")
	)
	(arc
		(start 98.768916 -233.489754)
		(mid 98.525589 -233.95432)
		(end 98.768916 -234.418886)
		(width 0.1143)
		(layer "In11.Cu")
		(net "P5E_CPU1_G1_TX_DN<13>")
	)
	(arc
		(start 98.839782 -244.180106)
		(mid 98.99571 -244.484398)
		(end 98.839782 -244.78869)
		(width 0.1143)
		(layer "In11.Cu")
		(net "P5E_CPU1_G1_TX_DN<13>")
	)
	(arc
		(start 98.525584 -246.914416)
		(mid 98.484035 -247.085838)
		(end 98.368612 -247.219216)
		(width 0.1143)
		(layer "In11.Cu")
		(net "P5E_CPU1_G1_TX_DN<13>")
	)
	(arc
		(start 98.839782 -232.840022)
		(mid 98.99571 -233.144314)
		(end 98.839782 -233.448606)
		(width 0.1143)
		(layer "In11.Cu")
		(net "P5E_CPU1_G1_TX_DN<13>")
	)
	(arc
		(start 98.368612 -225.549714)
		(mid 98.484039 -225.68309)
		(end 98.525584 -225.854514)
		(width 0.1143)
		(layer "In11.Cu")
		(net "P5E_CPU1_G1_TX_DN<13>")
	)
	(arc
		(start 98.84156 -231.221534)
		(mid 98.954967 -231.354423)
		(end 98.995738 -231.524302)
		(width 0.1143)
		(layer "In11.Cu")
		(net "P5E_CPU1_G1_TX_DN<13>")
	)
	(arc
		(start 98.839782 -237.700058)
		(mid 98.99571 -238.00435)
		(end 98.839782 -238.308642)
		(width 0.1143)
		(layer "In11.Cu")
		(net "P5E_CPU1_G1_TX_DN<13>")
	)
	(arc
		(start 98.055684 -225.044508)
		(mid 98.120199 -225.306727)
		(end 98.299016 -225.509074)
		(width 0.1143)
		(layer "In11.Cu")
		(net "P5E_CPU1_G1_TX_DN<13>")
	)
	(arc
		(start 98.771456 -230.248206)
		(mid 98.590804 -230.450951)
		(end 98.525584 -230.71455)
		(width 0.1143)
		(layer "In11.Cu")
		(net "P5E_CPU1_G1_TX_DN<13>")
	)
	(arc
		(start 98.995738 -231.524302)
		(mid 98.954483 -231.695273)
		(end 98.839782 -231.828594)
		(width 0.1143)
		(layer "In11.Cu")
		(net "P5E_CPU1_G1_TX_DN<13>")
	)
	(arc
		(start 98.768916 -236.729778)
		(mid 98.525589 -237.194344)
		(end 98.768916 -237.65891)
		(width 0.1143)
		(layer "In11.Cu")
		(net "P5E_CPU1_G1_TX_DN<13>")
	)
	(arc
		(start 97.899728 -223.120204)
		(mid 98.055656 -223.424496)
		(end 97.899728 -223.728788)
		(width 0.1143)
		(layer "In11.Cu")
		(net "P5E_CPU1_G1_TX_DN<13>")
	)
	(arc
		(start 97.816416 -224.690178)
		(mid 97.823992 -224.695574)
		(end 97.831656 -224.700846)
		(width 0.1143)
		(layer "In11.Cu")
		(net "P5E_CPU1_G1_TX_DN<13>")
	)
	(arc
		(start 97.816416 -223.778826)
		(mid 97.591245 -224.234502)
		(end 97.816416 -224.690178)
		(width 0.1143)
		(layer "In11.Cu")
		(net "P5E_CPU1_G1_TX_DN<13>")
	)
	(arc
		(start 98.525584 -230.71455)
		(mid 98.590099 -230.976769)
		(end 98.768916 -231.179116)
		(width 0.1143)
		(layer "In11.Cu")
		(net "P5E_CPU1_G1_TX_DN<13>")
	)
	(arc
		(start 98.768916 -231.869742)
		(mid 98.525589 -232.334308)
		(end 98.768916 -232.798874)
		(width 0.1143)
		(layer "In11.Cu")
		(net "P5E_CPU1_G1_TX_DN<13>")
	)
	(arc
		(start 98.768916 -246.44985)
		(mid 98.590103 -246.6522)
		(end 98.525584 -246.914416)
		(width 0.1143)
		(layer "In11.Cu")
		(net "P5E_CPU1_G1_TX_DN<13>")
	)
	(arc
		(start 98.299016 -247.259856)
		(mid 98.147029 -247.416364)
		(end 98.06559 -247.618758)
		(width 0.1143)
		(layer "In11.Cu")
		(net "P5E_CPU1_G1_TX_DN<13>")
	)
	(segment
		(start 24.186388 -18.86585)
		(end 23.915878 -19.13636)
		(width 0.12954)
		(layer "F.Cu")
		(net "P5E_CPU1_G1_TX_DN<12>")
	)
	(segment
		(start 100.967794 -246.370348)
		(end 100.500942 -246.10441)
		(width 0.12954)
		(layer "F.Cu")
		(net "P5E_CPU1_G1_TX_DN<12>")
	)
	(segment
		(start 24.186388 -18.186146)
		(end 24.186388 -18.86585)
		(width 0.12954)
		(layer "F.Cu")
		(net "P5E_CPU1_G1_TX_DN<12>")
	)
	(segment
		(start 23.890478 -17.890236)
		(end 24.186388 -18.186146)
		(width 0.12954)
		(layer "F.Cu")
		(net "P5E_CPU1_G1_TX_DN<12>")
	)
	(segment
		(start 99.748086 -226.34194)
		(end 99.778566 -226.35972)
		(width 0.1143)
		(layer "In11.Cu")
		(net "P5E_CPU1_G1_TX_DN<12>")
	)
	(segment
		(start 99.748086 -229.581964)
		(end 99.780598 -229.60076)
		(width 0.1143)
		(layer "In11.Cu")
		(net "P5E_CPU1_G1_TX_DN<12>")
	)
	(segment
		(start 99.711002 -229.560628)
		(end 99.748086 -229.581964)
		(width 0.1143)
		(layer "In11.Cu")
		(net "P5E_CPU1_G1_TX_DN<12>")
	)
	(segment
		(start 99.246436 -225.513646)
		(end 99.271074 -225.52787)
		(width 0.1143)
		(layer "In11.Cu")
		(net "P5E_CPU1_G1_TX_DN<12>")
	)
	(segment
		(start 99.748086 -240.921794)
		(end 99.778566 -240.939574)
		(width 0.1143)
		(layer "In11.Cu")
		(net "P5E_CPU1_G1_TX_DN<12>")
	)
	(segment
		(start 97.959672 -221.05493)
		(end 97.959672 -221.083378)
		(width 0.1143)
		(layer "In11.Cu")
		(net "P5E_CPU1_G1_TX_DN<12>")
	)
	(segment
		(start 99.238816 -225.509074)
		(end 99.245674 -225.513138)
		(width 0.1143)
		(layer "In11.Cu")
		(net "P5E_CPU1_G1_TX_DN<12>")
	)
	(segment
		(start 99.778566 -243.169186)
		(end 99.748086 -243.186966)
		(width 0.1143)
		(layer "In11.Cu")
		(net "P5E_CPU1_G1_TX_DN<12>")
	)
	(segment
		(start 100.798884 -246.10441)
		(end 100.500942 -246.10441)
		(width 0.1143)
		(layer "In11.Cu")
		(net "P5E_CPU1_G1_TX_DN<12>")
	)
	(segment
		(start 99.748086 -239.301782)
		(end 99.778566 -239.319562)
		(width 0.1143)
		(layer "In11.Cu")
		(net "P5E_CPU1_G1_TX_DN<12>")
	)
	(segment
		(start 54.199536 -60.721494)
		(end 143.865346 -141.354302)
		(width 0.14224)
		(layer "In11.Cu")
		(net "P5E_CPU1_G1_TX_DN<12>")
	)
	(segment
		(start 99.273614 -225.529394)
		(end 99.275138 -225.53041)
		(width 0.1143)
		(layer "In11.Cu")
		(net "P5E_CPU1_G1_TX_DN<12>")
	)
	(segment
		(start 98.808032 -224.721928)
		(end 98.838512 -224.739708)
		(width 0.1143)
		(layer "In11.Cu")
		(net "P5E_CPU1_G1_TX_DN<12>")
	)
	(segment
		(start 24.206708 -20.273772)
		(end 39.47414 -44.659804)
		(width 0.14224)
		(layer "In11.Cu")
		(net "P5E_CPU1_G1_TX_DN<12>")
	)
	(segment
		(start 99.748086 -231.201976)
		(end 99.780598 -231.220772)
		(width 0.1143)
		(layer "In11.Cu")
		(net "P5E_CPU1_G1_TX_DN<12>")
	)
	(segment
		(start 99.70897 -229.559104)
		(end 99.711002 -229.560628)
		(width 0.1143)
		(layer "In11.Cu")
		(net "P5E_CPU1_G1_TX_DN<12>")
	)
	(segment
		(start 98.005392 -221.387924)
		(end 98.055684 -221.438216)
		(width 0.1143)
		(layer "In11.Cu")
		(net "P5E_CPU1_G1_TX_DN<12>")
	)
	(segment
		(start 99.70897 -227.939092)
		(end 99.748086 -227.961952)
		(width 0.1143)
		(layer "In11.Cu")
		(net "P5E_CPU1_G1_TX_DN<12>")
	)
	(segment
		(start 99.748086 -242.541806)
		(end 99.778566 -242.559586)
		(width 0.1143)
		(layer "In11.Cu")
		(net "P5E_CPU1_G1_TX_DN<12>")
	)
	(segment
		(start 97.959672 -221.083378)
		(end 98.005392 -221.129098)
		(width 0.1143)
		(layer "In11.Cu")
		(net "P5E_CPU1_G1_TX_DN<12>")
	)
	(segment
		(start 99.748086 -236.706918)
		(end 99.70897 -236.729778)
		(width 0.1143)
		(layer "In11.Cu")
		(net "P5E_CPU1_G1_TX_DN<12>")
	)
	(segment
		(start 99.748086 -237.68177)
		(end 99.778566 -237.69955)
		(width 0.1143)
		(layer "In11.Cu")
		(net "P5E_CPU1_G1_TX_DN<12>")
	)
	(segment
		(start 23.915878 -19.13636)
		(end 24.206708 -19.42719)
		(width 0.14224)
		(layer "In11.Cu")
		(net "P5E_CPU1_G1_TX_DN<12>")
	)
	(segment
		(start 99.278694 -225.532442)
		(end 99.279964 -225.533204)
		(width 0.1143)
		(layer "In11.Cu")
		(net "P5E_CPU1_G1_TX_DN<12>")
	)
	(segment
		(start 98.808032 -223.747076)
		(end 98.768916 -223.769936)
		(width 0.1143)
		(layer "In11.Cu")
		(net "P5E_CPU1_G1_TX_DN<12>")
	)
	(segment
		(start 99.748086 -232.821734)
		(end 99.778566 -232.839514)
		(width 0.1143)
		(layer "In11.Cu")
		(net "P5E_CPU1_G1_TX_DN<12>")
	)
	(segment
		(start 99.778566 -241.549174)
		(end 99.748086 -241.566954)
		(width 0.1143)
		(layer "In11.Cu")
		(net "P5E_CPU1_G1_TX_DN<12>")
	)
	(segment
		(start 99.70897 -237.65891)
		(end 99.748086 -237.68177)
		(width 0.1143)
		(layer "In11.Cu")
		(net "P5E_CPU1_G1_TX_DN<12>")
	)
	(segment
		(start 143.26362 -171.156884)
		(end 105.063798 -202.440794)
		(width 0.14224)
		(layer "In11.Cu")
		(net "P5E_CPU1_G1_TX_DN<12>")
	)
	(segment
		(start 99.778566 -233.449114)
		(end 99.748086 -233.466894)
		(width 0.1143)
		(layer "In11.Cu")
		(net "P5E_CPU1_G1_TX_DN<12>")
	)
	(segment
		(start 99.748086 -235.086906)
		(end 99.70897 -235.109766)
		(width 0.1143)
		(layer "In11.Cu")
		(net "P5E_CPU1_G1_TX_DN<12>")
	)
	(segment
		(start 99.245674 -225.513138)
		(end 99.246436 -225.513646)
		(width 0.1143)
		(layer "In11.Cu")
		(net "P5E_CPU1_G1_TX_DN<12>")
	)
	(segment
		(start 99.70897 -240.898934)
		(end 99.748086 -240.921794)
		(width 0.1143)
		(layer "In11.Cu")
		(net "P5E_CPU1_G1_TX_DN<12>")
	)
	(segment
		(start 99.70897 -244.138958)
		(end 99.748086 -244.161818)
		(width 0.1143)
		(layer "In11.Cu")
		(net "P5E_CPU1_G1_TX_DN<12>")
	)
	(segment
		(start 99.70897 -232.798874)
		(end 99.748086 -232.821734)
		(width 0.1143)
		(layer "In11.Cu")
		(net "P5E_CPU1_G1_TX_DN<12>")
	)
	(segment
		(start 99.70897 -234.418886)
		(end 99.748086 -234.441746)
		(width 0.1143)
		(layer "In11.Cu")
		(net "P5E_CPU1_G1_TX_DN<12>")
	)
	(segment
		(start 98.808032 -223.101916)
		(end 98.838512 -223.119696)
		(width 0.1143)
		(layer "In11.Cu")
		(net "P5E_CPU1_G1_TX_DN<12>")
	)
	(segment
		(start 105.063798 -202.440794)
		(end 97.959672 -214.469218)
		(width 0.14224)
		(layer "In11.Cu")
		(net "P5E_CPU1_G1_TX_DN<12>")
	)
	(segment
		(start 99.778566 -238.30915)
		(end 99.748086 -238.32693)
		(width 0.1143)
		(layer "In11.Cu")
		(net "P5E_CPU1_G1_TX_DN<12>")
	)
	(segment
		(start 98.055684 -221.438216)
		(end 98.055684 -221.804484)
		(width 0.1143)
		(layer "In11.Cu")
		(net "P5E_CPU1_G1_TX_DN<12>")
	)
	(segment
		(start 146.361404 -166.375842)
		(end 143.26362 -171.156884)
		(width 0.14224)
		(layer "In11.Cu")
		(net "P5E_CPU1_G1_TX_DN<12>")
	)
	(segment
		(start 99.277932 -225.531934)
		(end 99.278694 -225.532442)
		(width 0.1143)
		(layer "In11.Cu")
		(net "P5E_CPU1_G1_TX_DN<12>")
	)
	(segment
		(start 52.046886 -58.954416)
		(end 54.199536 -60.721494)
		(width 0.14224)
		(layer "In11.Cu")
		(net "P5E_CPU1_G1_TX_DN<12>")
	)
	(segment
		(start 147.632674 -160.035748)
		(end 147.632674 -162.616896)
		(width 0.14224)
		(layer "In11.Cu")
		(net "P5E_CPU1_G1_TX_DN<12>")
	)
	(segment
		(start 99.276916 -225.531426)
		(end 99.277932 -225.531934)
		(width 0.1143)
		(layer "In11.Cu")
		(net "P5E_CPU1_G1_TX_DN<12>")
	)
	(segment
		(start 99.748086 -238.32693)
		(end 99.70897 -238.34979)
		(width 0.1143)
		(layer "In11.Cu")
		(net "P5E_CPU1_G1_TX_DN<12>")
	)
	(segment
		(start 99.778566 -235.069126)
		(end 99.748086 -235.086906)
		(width 0.1143)
		(layer "In11.Cu")
		(net "P5E_CPU1_G1_TX_DN<12>")
	)
	(segment
		(start 100.687886 -245.78183)
		(end 100.719636 -245.800118)
		(width 0.1143)
		(layer "In11.Cu")
		(net "P5E_CPU1_G1_TX_DN<12>")
	)
	(segment
		(start 99.748086 -227.961952)
		(end 99.778566 -227.979732)
		(width 0.1143)
		(layer "In11.Cu")
		(net "P5E_CPU1_G1_TX_DN<12>")
	)
	(segment
		(start 99.275138 -225.53041)
		(end 99.276916 -225.531426)
		(width 0.1143)
		(layer "In11.Cu")
		(net "P5E_CPU1_G1_TX_DN<12>")
	)
	(segment
		(start 99.748086 -239.946942)
		(end 99.70897 -239.969802)
		(width 0.1143)
		(layer "In11.Cu")
		(net "P5E_CPU1_G1_TX_DN<12>")
	)
	(segment
		(start 99.748086 -241.566954)
		(end 99.70897 -241.589814)
		(width 0.1143)
		(layer "In11.Cu")
		(net "P5E_CPU1_G1_TX_DN<12>")
	)
	(segment
		(start 98.768916 -223.079056)
		(end 98.808032 -223.101916)
		(width 0.1143)
		(layer "In11.Cu")
		(net "P5E_CPU1_G1_TX_DN<12>")
	)
	(segment
		(start 98.30054 -222.27032)
		(end 98.301556 -222.270828)
		(width 0.1143)
		(layer "In11.Cu")
		(net "P5E_CPU1_G1_TX_DN<12>")
	)
	(segment
		(start 99.748086 -236.061758)
		(end 99.778566 -236.079538)
		(width 0.1143)
		(layer "In11.Cu")
		(net "P5E_CPU1_G1_TX_DN<12>")
	)
	(segment
		(start 99.748086 -233.466894)
		(end 99.70897 -233.489754)
		(width 0.1143)
		(layer "In11.Cu")
		(net "P5E_CPU1_G1_TX_DN<12>")
	)
	(segment
		(start 99.748086 -243.186966)
		(end 99.70897 -243.209826)
		(width 0.1143)
		(layer "In11.Cu")
		(net "P5E_CPU1_G1_TX_DN<12>")
	)
	(segment
		(start 99.271074 -225.52787)
		(end 99.272598 -225.528886)
		(width 0.1143)
		(layer "In11.Cu")
		(net "P5E_CPU1_G1_TX_DN<12>")
	)
	(segment
		(start 146.84883 -147.522946)
		(end 147.632674 -160.035748)
		(width 0.14224)
		(layer "In11.Cu")
		(net "P5E_CPU1_G1_TX_DN<12>")
	)
	(segment
		(start 39.47414 -44.659804)
		(end 52.046886 -58.954416)
		(width 0.14224)
		(layer "In11.Cu")
		(net "P5E_CPU1_G1_TX_DN<12>")
	)
	(segment
		(start 99.778566 -239.929162)
		(end 99.748086 -239.946942)
		(width 0.1143)
		(layer "In11.Cu")
		(net "P5E_CPU1_G1_TX_DN<12>")
	)
	(segment
		(start 98.838512 -223.729296)
		(end 98.808032 -223.747076)
		(width 0.1143)
		(layer "In11.Cu")
		(net "P5E_CPU1_G1_TX_DN<12>")
	)
	(segment
		(start 100.868734 -246.03456)
		(end 100.798884 -246.10441)
		(width 0.1143)
		(layer "In11.Cu")
		(net "P5E_CPU1_G1_TX_DN<12>")
	)
	(segment
		(start 99.70897 -239.278922)
		(end 99.748086 -239.301782)
		(width 0.1143)
		(layer "In11.Cu")
		(net "P5E_CPU1_G1_TX_DN<12>")
	)
	(segment
		(start 99.778566 -231.829102)
		(end 99.748086 -231.846882)
		(width 0.1143)
		(layer "In11.Cu")
		(net "P5E_CPU1_G1_TX_DN<12>")
	)
	(segment
		(start 99.272598 -225.528886)
		(end 99.273614 -225.529394)
		(width 0.1143)
		(layer "In11.Cu")
		(net "P5E_CPU1_G1_TX_DN<12>")
	)
	(segment
		(start 98.005392 -221.129098)
		(end 98.005392 -221.387924)
		(width 0.1143)
		(layer "In11.Cu")
		(net "P5E_CPU1_G1_TX_DN<12>")
	)
	(segment
		(start 98.768916 -224.699068)
		(end 98.808032 -224.721928)
		(width 0.1143)
		(layer "In11.Cu")
		(net "P5E_CPU1_G1_TX_DN<12>")
	)
	(segment
		(start 99.748086 -234.441746)
		(end 99.778566 -234.459526)
		(width 0.1143)
		(layer "In11.Cu")
		(net "P5E_CPU1_G1_TX_DN<12>")
	)
	(segment
		(start 98.301556 -222.270828)
		(end 98.369628 -222.310198)
		(width 0.1143)
		(layer "In11.Cu")
		(net "P5E_CPU1_G1_TX_DN<12>")
	)
	(segment
		(start 99.70897 -226.31908)
		(end 99.748086 -226.34194)
		(width 0.1143)
		(layer "In11.Cu")
		(net "P5E_CPU1_G1_TX_DN<12>")
	)
	(segment
		(start 99.778566 -228.589332)
		(end 99.748086 -228.607112)
		(width 0.1143)
		(layer "In11.Cu")
		(net "P5E_CPU1_G1_TX_DN<12>")
	)
	(segment
		(start 99.778566 -230.20909)
		(end 99.71151 -230.248206)
		(width 0.1143)
		(layer "In11.Cu")
		(net "P5E_CPU1_G1_TX_DN<12>")
	)
	(segment
		(start 98.299524 -222.269558)
		(end 98.30054 -222.27032)
		(width 0.1143)
		(layer "In11.Cu")
		(net "P5E_CPU1_G1_TX_DN<12>")
	)
	(segment
		(start 100.17887 -244.948964)
		(end 100.230432 -244.978936)
		(width 0.1143)
		(layer "In11.Cu")
		(net "P5E_CPU1_G1_TX_DN<12>")
	)
	(segment
		(start 99.70897 -231.179116)
		(end 99.748086 -231.201976)
		(width 0.1143)
		(layer "In11.Cu")
		(net "P5E_CPU1_G1_TX_DN<12>")
	)
	(segment
		(start 99.778566 -236.689138)
		(end 99.748086 -236.706918)
		(width 0.1143)
		(layer "In11.Cu")
		(net "P5E_CPU1_G1_TX_DN<12>")
	)
	(segment
		(start 143.865346 -141.354302)
		(end 146.84883 -147.522946)
		(width 0.14224)
		(layer "In11.Cu")
		(net "P5E_CPU1_G1_TX_DN<12>")
	)
	(segment
		(start 99.748086 -244.161818)
		(end 99.778566 -244.179598)
		(width 0.1143)
		(layer "In11.Cu")
		(net "P5E_CPU1_G1_TX_DN<12>")
	)
	(segment
		(start 99.748086 -228.607112)
		(end 99.70897 -228.629972)
		(width 0.1143)
		(layer "In11.Cu")
		(net "P5E_CPU1_G1_TX_DN<12>")
	)
	(segment
		(start 97.959672 -214.469218)
		(end 97.959672 -221.05493)
		(width 0.14224)
		(layer "In11.Cu")
		(net "P5E_CPU1_G1_TX_DN<12>")
	)
	(segment
		(start 99.778566 -226.96932)
		(end 99.748086 -226.9871)
		(width 0.1143)
		(layer "In11.Cu")
		(net "P5E_CPU1_G1_TX_DN<12>")
	)
	(segment
		(start 99.279964 -225.533204)
		(end 99.309682 -225.550222)
		(width 0.1143)
		(layer "In11.Cu")
		(net "P5E_CPU1_G1_TX_DN<12>")
	)
	(segment
		(start 24.206708 -19.42719)
		(end 24.206708 -20.273772)
		(width 0.14224)
		(layer "In11.Cu")
		(net "P5E_CPU1_G1_TX_DN<12>")
	)
	(segment
		(start 147.632674 -162.616896)
		(end 146.361404 -166.375842)
		(width 0.14224)
		(layer "In11.Cu")
		(net "P5E_CPU1_G1_TX_DN<12>")
	)
	(segment
		(start 99.748086 -226.9871)
		(end 99.70897 -227.00996)
		(width 0.1143)
		(layer "In11.Cu")
		(net "P5E_CPU1_G1_TX_DN<12>")
	)
	(segment
		(start 100.418138 -245.303802)
		(end 100.418138 -245.313454)
		(width 0.1143)
		(layer "In11.Cu")
		(net "P5E_CPU1_G1_TX_DN<12>")
	)
	(segment
		(start 99.70897 -236.038898)
		(end 99.748086 -236.061758)
		(width 0.1143)
		(layer "In11.Cu")
		(net "P5E_CPU1_G1_TX_DN<12>")
	)
	(segment
		(start 99.70897 -242.518946)
		(end 99.748086 -242.541806)
		(width 0.1143)
		(layer "In11.Cu")
		(net "P5E_CPU1_G1_TX_DN<12>")
	)
	(segment
		(start 99.748086 -231.846882)
		(end 99.70897 -231.869742)
		(width 0.1143)
		(layer "In11.Cu")
		(net "P5E_CPU1_G1_TX_DN<12>")
	)
	(arc
		(start 99.778566 -226.35972)
		(mid 99.935543 -226.66452)
		(end 99.778566 -226.96932)
		(width 0.1143)
		(layer "In11.Cu")
		(net "P5E_CPU1_G1_TX_DN<12>")
	)
	(arc
		(start 98.525584 -222.61449)
		(mid 98.590099 -222.876709)
		(end 98.768916 -223.079056)
		(width 0.1143)
		(layer "In11.Cu")
		(net "P5E_CPU1_G1_TX_DN<12>")
	)
	(arc
		(start 99.778566 -240.939574)
		(mid 99.935543 -241.244374)
		(end 99.778566 -241.549174)
		(width 0.1143)
		(layer "In11.Cu")
		(net "P5E_CPU1_G1_TX_DN<12>")
	)
	(arc
		(start 99.465638 -230.71455)
		(mid 99.530153 -230.976769)
		(end 99.70897 -231.179116)
		(width 0.1143)
		(layer "In11.Cu")
		(net "P5E_CPU1_G1_TX_DN<12>")
	)
	(arc
		(start 99.70897 -241.589814)
		(mid 99.465643 -242.05438)
		(end 99.70897 -242.518946)
		(width 0.1143)
		(layer "In11.Cu")
		(net "P5E_CPU1_G1_TX_DN<12>")
	)
	(arc
		(start 99.778566 -227.979732)
		(mid 99.935543 -228.284532)
		(end 99.778566 -228.589332)
		(width 0.1143)
		(layer "In11.Cu")
		(net "P5E_CPU1_G1_TX_DN<12>")
	)
	(arc
		(start 99.309682 -225.550222)
		(mid 99.424358 -225.683556)
		(end 99.465638 -225.854514)
		(width 0.1143)
		(layer "In11.Cu")
		(net "P5E_CPU1_G1_TX_DN<12>")
	)
	(arc
		(start 99.70897 -243.209826)
		(mid 99.465643 -243.674392)
		(end 99.70897 -244.138958)
		(width 0.1143)
		(layer "In11.Cu")
		(net "P5E_CPU1_G1_TX_DN<12>")
	)
	(arc
		(start 98.768916 -223.769936)
		(mid 98.525589 -224.234502)
		(end 98.768916 -224.699068)
		(width 0.1143)
		(layer "In11.Cu")
		(net "P5E_CPU1_G1_TX_DN<12>")
	)
	(arc
		(start 99.778566 -236.079538)
		(mid 99.935543 -236.384338)
		(end 99.778566 -236.689138)
		(width 0.1143)
		(layer "In11.Cu")
		(net "P5E_CPU1_G1_TX_DN<12>")
	)
	(arc
		(start 99.778566 -232.839514)
		(mid 99.935543 -233.144314)
		(end 99.778566 -233.449114)
		(width 0.1143)
		(layer "In11.Cu")
		(net "P5E_CPU1_G1_TX_DN<12>")
	)
	(arc
		(start 98.995484 -225.044508)
		(mid 99.059999 -225.306727)
		(end 99.238816 -225.509074)
		(width 0.1143)
		(layer "In11.Cu")
		(net "P5E_CPU1_G1_TX_DN<12>")
	)
	(arc
		(start 99.70897 -233.489754)
		(mid 99.465643 -233.95432)
		(end 99.70897 -234.418886)
		(width 0.1143)
		(layer "In11.Cu")
		(net "P5E_CPU1_G1_TX_DN<12>")
	)
	(arc
		(start 99.780598 -231.220772)
		(mid 99.894527 -231.353919)
		(end 99.935538 -231.524302)
		(width 0.1143)
		(layer "In11.Cu")
		(net "P5E_CPU1_G1_TX_DN<12>")
	)
	(arc
		(start 99.778566 -239.319562)
		(mid 99.935543 -239.624362)
		(end 99.778566 -239.929162)
		(width 0.1143)
		(layer "In11.Cu")
		(net "P5E_CPU1_G1_TX_DN<12>")
	)
	(arc
		(start 99.70897 -235.109766)
		(mid 99.465643 -235.574332)
		(end 99.70897 -236.038898)
		(width 0.1143)
		(layer "In11.Cu")
		(net "P5E_CPU1_G1_TX_DN<12>")
	)
	(arc
		(start 99.70897 -228.629972)
		(mid 99.465643 -229.094538)
		(end 99.70897 -229.559104)
		(width 0.1143)
		(layer "In11.Cu")
		(net "P5E_CPU1_G1_TX_DN<12>")
	)
	(arc
		(start 99.70897 -239.969802)
		(mid 99.465643 -240.434368)
		(end 99.70897 -240.898934)
		(width 0.1143)
		(layer "In11.Cu")
		(net "P5E_CPU1_G1_TX_DN<12>")
	)
	(arc
		(start 100.719636 -245.800118)
		(mid 100.816771 -245.902987)
		(end 100.868734 -246.03456)
		(width 0.1143)
		(layer "In11.Cu")
		(net "P5E_CPU1_G1_TX_DN<12>")
	)
	(arc
		(start 99.70897 -238.34979)
		(mid 99.465643 -238.814356)
		(end 99.70897 -239.278922)
		(width 0.1143)
		(layer "In11.Cu")
		(net "P5E_CPU1_G1_TX_DN<12>")
	)
	(arc
		(start 99.778566 -237.69955)
		(mid 99.935543 -238.00435)
		(end 99.778566 -238.30915)
		(width 0.1143)
		(layer "In11.Cu")
		(net "P5E_CPU1_G1_TX_DN<12>")
	)
	(arc
		(start 99.465638 -225.854514)
		(mid 99.530153 -226.116733)
		(end 99.70897 -226.31908)
		(width 0.1143)
		(layer "In11.Cu")
		(net "P5E_CPU1_G1_TX_DN<12>")
	)
	(arc
		(start 99.778566 -242.559586)
		(mid 99.935543 -242.864386)
		(end 99.778566 -243.169186)
		(width 0.1143)
		(layer "In11.Cu")
		(net "P5E_CPU1_G1_TX_DN<12>")
	)
	(arc
		(start 99.70897 -227.00996)
		(mid 99.465643 -227.474526)
		(end 99.70897 -227.939092)
		(width 0.1143)
		(layer "In11.Cu")
		(net "P5E_CPU1_G1_TX_DN<12>")
	)
	(arc
		(start 98.838512 -224.739708)
		(mid 98.953939 -224.873084)
		(end 98.995484 -225.044508)
		(width 0.1143)
		(layer "In11.Cu")
		(net "P5E_CPU1_G1_TX_DN<12>")
	)
	(arc
		(start 99.935538 -244.484398)
		(mid 100.000053 -244.746617)
		(end 100.17887 -244.948964)
		(width 0.1143)
		(layer "In11.Cu")
		(net "P5E_CPU1_G1_TX_DN<12>")
	)
	(arc
		(start 98.369628 -222.310198)
		(mid 98.484304 -222.443532)
		(end 98.525584 -222.61449)
		(width 0.1143)
		(layer "In11.Cu")
		(net "P5E_CPU1_G1_TX_DN<12>")
	)
	(arc
		(start 99.780598 -229.60076)
		(mid 99.894527 -229.733907)
		(end 99.935538 -229.90429)
		(width 0.1143)
		(layer "In11.Cu")
		(net "P5E_CPU1_G1_TX_DN<12>")
	)
	(arc
		(start 98.838512 -223.119696)
		(mid 98.995489 -223.424496)
		(end 98.838512 -223.729296)
		(width 0.1143)
		(layer "In11.Cu")
		(net "P5E_CPU1_G1_TX_DN<12>")
	)
	(arc
		(start 100.230432 -244.978936)
		(mid 100.367864 -245.116195)
		(end 100.418138 -245.303802)
		(width 0.1143)
		(layer "In11.Cu")
		(net "P5E_CPU1_G1_TX_DN<12>")
	)
	(arc
		(start 98.055684 -221.804484)
		(mid 98.120343 -222.067041)
		(end 98.299524 -222.269558)
		(width 0.1143)
		(layer "In11.Cu")
		(net "P5E_CPU1_G1_TX_DN<12>")
	)
	(arc
		(start 99.70897 -236.729778)
		(mid 99.465643 -237.194344)
		(end 99.70897 -237.65891)
		(width 0.1143)
		(layer "In11.Cu")
		(net "P5E_CPU1_G1_TX_DN<12>")
	)
	(arc
		(start 99.935538 -231.524302)
		(mid 99.893989 -231.695724)
		(end 99.778566 -231.829102)
		(width 0.1143)
		(layer "In11.Cu")
		(net "P5E_CPU1_G1_TX_DN<12>")
	)
	(arc
		(start 100.418138 -245.313454)
		(mid 100.490394 -245.583707)
		(end 100.687886 -245.78183)
		(width 0.1143)
		(layer "In11.Cu")
		(net "P5E_CPU1_G1_TX_DN<12>")
	)
	(arc
		(start 99.778566 -244.179598)
		(mid 99.893993 -244.312974)
		(end 99.935538 -244.484398)
		(width 0.1143)
		(layer "In11.Cu")
		(net "P5E_CPU1_G1_TX_DN<12>")
	)
	(arc
		(start 99.935538 -229.90429)
		(mid 99.893989 -230.075712)
		(end 99.778566 -230.20909)
		(width 0.1143)
		(layer "In11.Cu")
		(net "P5E_CPU1_G1_TX_DN<12>")
	)
	(arc
		(start 99.778566 -234.459526)
		(mid 99.935543 -234.764326)
		(end 99.778566 -235.069126)
		(width 0.1143)
		(layer "In11.Cu")
		(net "P5E_CPU1_G1_TX_DN<12>")
	)
	(arc
		(start 99.71151 -230.248206)
		(mid 99.530858 -230.450951)
		(end 99.465638 -230.71455)
		(width 0.1143)
		(layer "In11.Cu")
		(net "P5E_CPU1_G1_TX_DN<12>")
	)
	(arc
		(start 99.70897 -231.869742)
		(mid 99.465643 -232.334308)
		(end 99.70897 -232.798874)
		(width 0.1143)
		(layer "In11.Cu")
		(net "P5E_CPU1_G1_TX_DN<12>")
	)
	(segment
		(start 26.684478 -16.366236)
		(end 26.980388 -16.662146)
		(width 0.12954)
		(layer "F.Cu")
		(net "P5E_CPU1_G1_TX_DN<11>")
	)
	(segment
		(start 26.980388 -16.662146)
		(end 26.980388 -17.34185)
		(width 0.12954)
		(layer "F.Cu")
		(net "P5E_CPU1_G1_TX_DN<11>")
	)
	(segment
		(start 100.967794 -244.750336)
		(end 100.500942 -244.484398)
		(width 0.12954)
		(layer "F.Cu")
		(net "P5E_CPU1_G1_TX_DN<11>")
	)
	(segment
		(start 26.980388 -17.34185)
		(end 26.709878 -17.61236)
		(width 0.12954)
		(layer "F.Cu")
		(net "P5E_CPU1_G1_TX_DN<11>")
	)
	(segment
		(start 100.692204 -242.544346)
		(end 100.69322 -242.544854)
		(width 0.1143)
		(layer "In11.Cu")
		(net "P5E_CPU1_G1_TX_DN<11>")
	)
	(segment
		(start 99.748086 -223.101916)
		(end 99.778566 -223.119696)
		(width 0.1143)
		(layer "In11.Cu")
		(net "P5E_CPU1_G1_TX_DN<11>")
	)
	(segment
		(start 100.695252 -240.926112)
		(end 100.719636 -240.940082)
		(width 0.1143)
		(layer "In11.Cu")
		(net "P5E_CPU1_G1_TX_DN<11>")
	)
	(segment
		(start 100.687886 -227.961952)
		(end 100.719636 -227.98024)
		(width 0.1143)
		(layer "In11.Cu")
		(net "P5E_CPU1_G1_TX_DN<11>")
	)
	(segment
		(start 100.244148 -225.547174)
		(end 100.245164 -225.547682)
		(width 0.1143)
		(layer "In11.Cu")
		(net "P5E_CPU1_G1_TX_DN<11>")
	)
	(segment
		(start 100.719636 -228.588824)
		(end 100.698046 -228.60127)
		(width 0.1143)
		(layer "In11.Cu")
		(net "P5E_CPU1_G1_TX_DN<11>")
	)
	(segment
		(start 100.719636 -239.928654)
		(end 100.70973 -239.934242)
		(width 0.1143)
		(layer "In11.Cu")
		(net "P5E_CPU1_G1_TX_DN<11>")
	)
	(segment
		(start 100.691442 -228.60508)
		(end 100.688648 -228.606604)
		(width 0.1143)
		(layer "In11.Cu")
		(net "P5E_CPU1_G1_TX_DN<11>")
	)
	(segment
		(start 100.687886 -238.32693)
		(end 100.687632 -238.327184)
		(width 0.1143)
		(layer "In11.Cu")
		(net "P5E_CPU1_G1_TX_DN<11>")
	)
	(segment
		(start 100.651564 -227.94087)
		(end 100.687886 -227.961952)
		(width 0.1143)
		(layer "In11.Cu")
		(net "P5E_CPU1_G1_TX_DN<11>")
	)
	(segment
		(start 100.69322 -239.30483)
		(end 100.693982 -239.305338)
		(width 0.1143)
		(layer "In11.Cu")
		(net "P5E_CPU1_G1_TX_DN<11>")
	)
	(segment
		(start 100.687886 -243.186966)
		(end 100.651564 -243.208048)
		(width 0.1143)
		(layer "In11.Cu")
		(net "P5E_CPU1_G1_TX_DN<11>")
	)
	(segment
		(start 100.654358 -229.562406)
		(end 100.687886 -229.581964)
		(width 0.1143)
		(layer "In11.Cu")
		(net "P5E_CPU1_G1_TX_DN<11>")
	)
	(segment
		(start 144.55902 -140.642086)
		(end 147.837906 -147.4216)
		(width 0.14224)
		(layer "In11.Cu")
		(net "P5E_CPU1_G1_TX_DN<11>")
	)
	(segment
		(start 100.687632 -239.301782)
		(end 100.687886 -239.301782)
		(width 0.1143)
		(layer "In11.Cu")
		(net "P5E_CPU1_G1_TX_DN<11>")
	)
	(segment
		(start 100.868734 -244.414548)
		(end 100.798884 -244.484398)
		(width 0.1143)
		(layer "In11.Cu")
		(net "P5E_CPU1_G1_TX_DN<11>")
	)
	(segment
		(start 99.275392 -222.290386)
		(end 99.276916 -222.291402)
		(width 0.1143)
		(layer "In11.Cu")
		(net "P5E_CPU1_G1_TX_DN<11>")
	)
	(segment
		(start 100.693728 -228.60381)
		(end 100.692204 -228.604572)
		(width 0.1143)
		(layer "In11.Cu")
		(net "P5E_CPU1_G1_TX_DN<11>")
	)
	(segment
		(start 100.687886 -239.301782)
		(end 100.688648 -239.30229)
		(width 0.1143)
		(layer "In11.Cu")
		(net "P5E_CPU1_G1_TX_DN<11>")
	)
	(segment
		(start 41.758362 -45.469556)
		(end 52.432204 -57.942226)
		(width 0.14224)
		(layer "In11.Cu")
		(net "P5E_CPU1_G1_TX_DN<11>")
	)
	(segment
		(start 26.709878 -17.61236)
		(end 27.000708 -17.90319)
		(width 0.14224)
		(layer "In11.Cu")
		(net "P5E_CPU1_G1_TX_DN<11>")
	)
	(segment
		(start 105.95102 -202.933046)
		(end 98.904552 -214.801196)
		(width 0.14224)
		(layer "In11.Cu")
		(net "P5E_CPU1_G1_TX_DN<11>")
	)
	(segment
		(start 100.690426 -239.303306)
		(end 100.691442 -239.303814)
		(width 0.1143)
		(layer "In11.Cu")
		(net "P5E_CPU1_G1_TX_DN<11>")
	)
	(segment
		(start 100.695252 -239.3061)
		(end 100.719636 -239.32007)
		(width 0.1143)
		(layer "In11.Cu")
		(net "P5E_CPU1_G1_TX_DN<11>")
	)
	(segment
		(start 100.687886 -229.581964)
		(end 100.720652 -229.601014)
		(width 0.1143)
		(layer "In11.Cu")
		(net "P5E_CPU1_G1_TX_DN<11>")
	)
	(segment
		(start 99.748086 -224.721928)
		(end 99.778566 -224.739708)
		(width 0.1143)
		(layer "In11.Cu")
		(net "P5E_CPU1_G1_TX_DN<11>")
	)
	(segment
		(start 100.695252 -237.686088)
		(end 100.719636 -237.700058)
		(width 0.1143)
		(layer "In11.Cu")
		(net "P5E_CPU1_G1_TX_DN<11>")
	)
	(segment
		(start 100.21697 -225.531426)
		(end 100.217986 -225.531934)
		(width 0.1143)
		(layer "In11.Cu")
		(net "P5E_CPU1_G1_TX_DN<11>")
	)
	(segment
		(start 100.70973 -239.934242)
		(end 100.708968 -239.93475)
		(width 0.1143)
		(layer "In11.Cu")
		(net "P5E_CPU1_G1_TX_DN<11>")
	)
	(segment
		(start 99.70897 -224.699068)
		(end 99.748086 -224.721928)
		(width 0.1143)
		(layer "In11.Cu")
		(net "P5E_CPU1_G1_TX_DN<11>")
	)
	(segment
		(start 100.698046 -228.60127)
		(end 100.697284 -228.601778)
		(width 0.1143)
		(layer "In11.Cu")
		(net "P5E_CPU1_G1_TX_DN<11>")
	)
	(segment
		(start 100.693982 -237.685326)
		(end 100.695252 -237.686088)
		(width 0.1143)
		(layer "In11.Cu")
		(net "P5E_CPU1_G1_TX_DN<11>")
	)
	(segment
		(start 100.719636 -241.548666)
		(end 100.70973 -241.554254)
		(width 0.1143)
		(layer "In11.Cu")
		(net "P5E_CPU1_G1_TX_DN<11>")
	)
	(segment
		(start 100.687886 -226.34194)
		(end 100.719636 -226.360228)
		(width 0.1143)
		(layer "In11.Cu")
		(net "P5E_CPU1_G1_TX_DN<11>")
	)
	(segment
		(start 27.000708 -17.90319)
		(end 27.000708 -20.269454)
		(width 0.14224)
		(layer "In11.Cu")
		(net "P5E_CPU1_G1_TX_DN<11>")
	)
	(segment
		(start 100.689664 -239.302798)
		(end 100.690426 -239.303306)
		(width 0.1143)
		(layer "In11.Cu")
		(net "P5E_CPU1_G1_TX_DN<11>")
	)
	(segment
		(start 100.689664 -242.542822)
		(end 100.690426 -242.54333)
		(width 0.1143)
		(layer "In11.Cu")
		(net "P5E_CPU1_G1_TX_DN<11>")
	)
	(segment
		(start 100.708968 -241.554762)
		(end 100.687886 -241.566954)
		(width 0.1143)
		(layer "In11.Cu")
		(net "P5E_CPU1_G1_TX_DN<11>")
	)
	(segment
		(start 100.687632 -236.061758)
		(end 100.687886 -236.061758)
		(width 0.1143)
		(layer "In11.Cu")
		(net "P5E_CPU1_G1_TX_DN<11>")
	)
	(segment
		(start 100.719636 -243.168678)
		(end 100.687886 -243.186966)
		(width 0.1143)
		(layer "In11.Cu")
		(net "P5E_CPU1_G1_TX_DN<11>")
	)
	(segment
		(start 99.277932 -222.29191)
		(end 99.309682 -222.310198)
		(width 0.1143)
		(layer "In11.Cu")
		(net "P5E_CPU1_G1_TX_DN<11>")
	)
	(segment
		(start 100.651564 -226.320858)
		(end 100.653088 -226.321874)
		(width 0.1143)
		(layer "In11.Cu")
		(net "P5E_CPU1_G1_TX_DN<11>")
	)
	(segment
		(start 100.69322 -242.544854)
		(end 100.693982 -242.545362)
		(width 0.1143)
		(layer "In11.Cu")
		(net "P5E_CPU1_G1_TX_DN<11>")
	)
	(segment
		(start 99.276916 -222.291402)
		(end 99.277932 -222.29191)
		(width 0.1143)
		(layer "In11.Cu")
		(net "P5E_CPU1_G1_TX_DN<11>")
	)
	(segment
		(start 100.691442 -242.543838)
		(end 100.692204 -242.544346)
		(width 0.1143)
		(layer "In11.Cu")
		(net "P5E_CPU1_G1_TX_DN<11>")
	)
	(segment
		(start 100.687632 -237.68177)
		(end 100.687886 -237.68177)
		(width 0.1143)
		(layer "In11.Cu")
		(net "P5E_CPU1_G1_TX_DN<11>")
	)
	(segment
		(start 100.687886 -244.161818)
		(end 100.719636 -244.180106)
		(width 0.1143)
		(layer "In11.Cu")
		(net "P5E_CPU1_G1_TX_DN<11>")
	)
	(segment
		(start 100.687886 -239.946942)
		(end 100.687632 -239.947196)
		(width 0.1143)
		(layer "In11.Cu")
		(net "P5E_CPU1_G1_TX_DN<11>")
	)
	(segment
		(start 100.687886 -242.541806)
		(end 100.688648 -242.542314)
		(width 0.1143)
		(layer "In11.Cu")
		(net "P5E_CPU1_G1_TX_DN<11>")
	)
	(segment
		(start 100.719636 -238.308642)
		(end 100.70973 -238.31423)
		(width 0.1143)
		(layer "In11.Cu")
		(net "P5E_CPU1_G1_TX_DN<11>")
	)
	(segment
		(start 52.432204 -57.942226)
		(end 54.200044 -59.38647)
		(width 0.14224)
		(layer "In11.Cu")
		(net "P5E_CPU1_G1_TX_DN<11>")
	)
	(segment
		(start 100.693982 -239.305338)
		(end 100.695252 -239.3061)
		(width 0.1143)
		(layer "In11.Cu")
		(net "P5E_CPU1_G1_TX_DN<11>")
	)
	(segment
		(start 100.708968 -238.314738)
		(end 100.687886 -238.32693)
		(width 0.1143)
		(layer "In11.Cu")
		(net "P5E_CPU1_G1_TX_DN<11>")
	)
	(segment
		(start 100.692204 -239.304322)
		(end 100.69322 -239.30483)
		(width 0.1143)
		(layer "In11.Cu")
		(net "P5E_CPU1_G1_TX_DN<11>")
	)
	(segment
		(start 100.708968 -236.694726)
		(end 100.687886 -236.706918)
		(width 0.1143)
		(layer "In11.Cu")
		(net "P5E_CPU1_G1_TX_DN<11>")
	)
	(segment
		(start 100.693982 -240.92535)
		(end 100.695252 -240.926112)
		(width 0.1143)
		(layer "In11.Cu")
		(net "P5E_CPU1_G1_TX_DN<11>")
	)
	(segment
		(start 100.688648 -242.542314)
		(end 100.689664 -242.542822)
		(width 0.1143)
		(layer "In11.Cu")
		(net "P5E_CPU1_G1_TX_DN<11>")
	)
	(segment
		(start 100.692204 -240.924334)
		(end 100.69322 -240.924842)
		(width 0.1143)
		(layer "In11.Cu")
		(net "P5E_CPU1_G1_TX_DN<11>")
	)
	(segment
		(start 147.837906 -147.4216)
		(end 148.62556 -160.004506)
		(width 0.14224)
		(layer "In11.Cu")
		(net "P5E_CPU1_G1_TX_DN<11>")
	)
	(segment
		(start 100.71862 -231.219502)
		(end 100.721414 -231.221534)
		(width 0.1143)
		(layer "In11.Cu")
		(net "P5E_CPU1_G1_TX_DN<11>")
	)
	(segment
		(start 100.687886 -231.846882)
		(end 100.651564 -231.867964)
		(width 0.1143)
		(layer "In11.Cu")
		(net "P5E_CPU1_G1_TX_DN<11>")
	)
	(segment
		(start 100.687886 -236.061758)
		(end 100.688648 -236.062266)
		(width 0.1143)
		(layer "In11.Cu")
		(net "P5E_CPU1_G1_TX_DN<11>")
	)
	(segment
		(start 100.70973 -235.074206)
		(end 100.708968 -235.074714)
		(width 0.1143)
		(layer "In11.Cu")
		(net "P5E_CPU1_G1_TX_DN<11>")
	)
	(segment
		(start 100.688648 -237.682278)
		(end 100.689664 -237.682786)
		(width 0.1143)
		(layer "In11.Cu")
		(net "P5E_CPU1_G1_TX_DN<11>")
	)
	(segment
		(start 100.798884 -244.484398)
		(end 100.500942 -244.484398)
		(width 0.1143)
		(layer "In11.Cu")
		(net "P5E_CPU1_G1_TX_DN<11>")
	)
	(segment
		(start 100.685346 -230.228394)
		(end 100.68433 -230.228902)
		(width 0.1143)
		(layer "In11.Cu")
		(net "P5E_CPU1_G1_TX_DN<11>")
	)
	(segment
		(start 98.904552 -221.083378)
		(end 98.950272 -221.129098)
		(width 0.1143)
		(layer "In11.Cu")
		(net "P5E_CPU1_G1_TX_DN<11>")
	)
	(segment
		(start 100.693982 -242.545362)
		(end 100.695252 -242.546124)
		(width 0.1143)
		(layer "In11.Cu")
		(net "P5E_CPU1_G1_TX_DN<11>")
	)
	(segment
		(start 99.748086 -223.747076)
		(end 99.70897 -223.769936)
		(width 0.1143)
		(layer "In11.Cu")
		(net "P5E_CPU1_G1_TX_DN<11>")
	)
	(segment
		(start 99.778566 -223.729296)
		(end 99.748086 -223.747076)
		(width 0.1143)
		(layer "In11.Cu")
		(net "P5E_CPU1_G1_TX_DN<11>")
	)
	(segment
		(start 144.016984 -171.746418)
		(end 105.95102 -202.933046)
		(width 0.14224)
		(layer "In11.Cu")
		(net "P5E_CPU1_G1_TX_DN<11>")
	)
	(segment
		(start 100.719636 -231.828594)
		(end 100.687886 -231.846882)
		(width 0.1143)
		(layer "In11.Cu")
		(net "P5E_CPU1_G1_TX_DN<11>")
	)
	(segment
		(start 27.000708 -20.269454)
		(end 41.758362 -45.469556)
		(width 0.14224)
		(layer "In11.Cu")
		(net "P5E_CPU1_G1_TX_DN<11>")
	)
	(segment
		(start 100.692204 -236.064298)
		(end 100.694236 -236.065568)
		(width 0.1143)
		(layer "In11.Cu")
		(net "P5E_CPU1_G1_TX_DN<11>")
	)
	(segment
		(start 100.719636 -236.68863)
		(end 100.70973 -236.694218)
		(width 0.1143)
		(layer "In11.Cu")
		(net "P5E_CPU1_G1_TX_DN<11>")
	)
	(segment
		(start 100.695252 -242.546124)
		(end 100.719636 -242.560094)
		(width 0.1143)
		(layer "In11.Cu")
		(net "P5E_CPU1_G1_TX_DN<11>")
	)
	(segment
		(start 100.687632 -242.541806)
		(end 100.687886 -242.541806)
		(width 0.1143)
		(layer "In11.Cu")
		(net "P5E_CPU1_G1_TX_DN<11>")
	)
	(segment
		(start 100.689664 -237.682786)
		(end 100.690426 -237.683294)
		(width 0.1143)
		(layer "In11.Cu")
		(net "P5E_CPU1_G1_TX_DN<11>")
	)
	(segment
		(start 100.241862 -225.54565)
		(end 100.244148 -225.547174)
		(width 0.1143)
		(layer "In11.Cu")
		(net "P5E_CPU1_G1_TX_DN<11>")
	)
	(segment
		(start 54.200044 -59.38647)
		(end 144.55902 -140.642086)
		(width 0.14224)
		(layer "In11.Cu")
		(net "P5E_CPU1_G1_TX_DN<11>")
	)
	(segment
		(start 100.708968 -235.074714)
		(end 100.687886 -235.086906)
		(width 0.1143)
		(layer "In11.Cu")
		(net "P5E_CPU1_G1_TX_DN<11>")
	)
	(segment
		(start 100.651564 -234.420664)
		(end 100.687886 -234.441746)
		(width 0.1143)
		(layer "In11.Cu")
		(net "P5E_CPU1_G1_TX_DN<11>")
	)
	(segment
		(start 100.69576 -228.60254)
		(end 100.69449 -228.603302)
		(width 0.1143)
		(layer "In11.Cu")
		(net "P5E_CPU1_G1_TX_DN<11>")
	)
	(segment
		(start 100.691442 -237.683802)
		(end 100.692204 -237.68431)
		(width 0.1143)
		(layer "In11.Cu")
		(net "P5E_CPU1_G1_TX_DN<11>")
	)
	(segment
		(start 100.708968 -239.93475)
		(end 100.687886 -239.946942)
		(width 0.1143)
		(layer "In11.Cu")
		(net "P5E_CPU1_G1_TX_DN<11>")
	)
	(segment
		(start 98.995738 -221.43339)
		(end 98.995738 -221.804484)
		(width 0.1143)
		(layer "In11.Cu")
		(net "P5E_CPU1_G1_TX_DN<11>")
	)
	(segment
		(start 100.17887 -225.509074)
		(end 100.21697 -225.531426)
		(width 0.1143)
		(layer "In11.Cu")
		(net "P5E_CPU1_G1_TX_DN<11>")
	)
	(segment
		(start 100.687632 -240.921794)
		(end 100.687886 -240.921794)
		(width 0.1143)
		(layer "In11.Cu")
		(net "P5E_CPU1_G1_TX_DN<11>")
	)
	(segment
		(start 100.719636 -235.068618)
		(end 100.70973 -235.074206)
		(width 0.1143)
		(layer "In11.Cu")
		(net "P5E_CPU1_G1_TX_DN<11>")
	)
	(segment
		(start 100.687886 -237.68177)
		(end 100.688648 -237.682278)
		(width 0.1143)
		(layer "In11.Cu")
		(net "P5E_CPU1_G1_TX_DN<11>")
	)
	(segment
		(start 100.687886 -232.821734)
		(end 100.719636 -232.840022)
		(width 0.1143)
		(layer "In11.Cu")
		(net "P5E_CPU1_G1_TX_DN<11>")
	)
	(segment
		(start 99.70897 -223.079056)
		(end 99.748086 -223.101916)
		(width 0.1143)
		(layer "In11.Cu")
		(net "P5E_CPU1_G1_TX_DN<11>")
	)
	(segment
		(start 100.655882 -230.245412)
		(end 100.654358 -230.246428)
		(width 0.1143)
		(layer "In11.Cu")
		(net "P5E_CPU1_G1_TX_DN<11>")
	)
	(segment
		(start 100.689664 -240.92281)
		(end 100.690426 -240.923318)
		(width 0.1143)
		(layer "In11.Cu")
		(net "P5E_CPU1_G1_TX_DN<11>")
	)
	(segment
		(start 100.692204 -237.68431)
		(end 100.69322 -237.684818)
		(width 0.1143)
		(layer "In11.Cu")
		(net "P5E_CPU1_G1_TX_DN<11>")
	)
	(segment
		(start 100.221288 -225.533712)
		(end 100.241862 -225.54565)
		(width 0.1143)
		(layer "In11.Cu")
		(net "P5E_CPU1_G1_TX_DN<11>")
	)
	(segment
		(start 100.691442 -239.303814)
		(end 100.692204 -239.304322)
		(width 0.1143)
		(layer "In11.Cu")
		(net "P5E_CPU1_G1_TX_DN<11>")
	)
	(segment
		(start 100.651564 -244.140736)
		(end 100.687886 -244.161818)
		(width 0.1143)
		(layer "In11.Cu")
		(net "P5E_CPU1_G1_TX_DN<11>")
	)
	(segment
		(start 100.688648 -239.30229)
		(end 100.689664 -239.302798)
		(width 0.1143)
		(layer "In11.Cu")
		(net "P5E_CPU1_G1_TX_DN<11>")
	)
	(segment
		(start 100.692204 -228.604572)
		(end 100.691442 -228.60508)
		(width 0.1143)
		(layer "In11.Cu")
		(net "P5E_CPU1_G1_TX_DN<11>")
	)
	(segment
		(start 99.238816 -222.26905)
		(end 99.26955 -222.287084)
		(width 0.1143)
		(layer "In11.Cu")
		(net "P5E_CPU1_G1_TX_DN<11>")
	)
	(segment
		(start 99.271836 -222.288354)
		(end 99.272852 -222.288862)
		(width 0.1143)
		(layer "In11.Cu")
		(net "P5E_CPU1_G1_TX_DN<11>")
	)
	(segment
		(start 100.720652 -229.601014)
		(end 100.721414 -229.601522)
		(width 0.1143)
		(layer "In11.Cu")
		(net "P5E_CPU1_G1_TX_DN<11>")
	)
	(segment
		(start 99.274376 -222.289878)
		(end 99.275392 -222.290386)
		(width 0.1143)
		(layer "In11.Cu")
		(net "P5E_CPU1_G1_TX_DN<11>")
	)
	(segment
		(start 100.70973 -236.694218)
		(end 100.708968 -236.694726)
		(width 0.1143)
		(layer "In11.Cu")
		(net "P5E_CPU1_G1_TX_DN<11>")
	)
	(segment
		(start 100.687886 -241.566954)
		(end 100.687632 -241.567208)
		(width 0.1143)
		(layer "In11.Cu")
		(net "P5E_CPU1_G1_TX_DN<11>")
	)
	(segment
		(start 100.687886 -234.441746)
		(end 100.719636 -234.460034)
		(width 0.1143)
		(layer "In11.Cu")
		(net "P5E_CPU1_G1_TX_DN<11>")
	)
	(segment
		(start 148.62556 -162.74161)
		(end 147.283678 -166.683182)
		(width 0.14224)
		(layer "In11.Cu")
		(net "P5E_CPU1_G1_TX_DN<11>")
	)
	(segment
		(start 100.69322 -240.924842)
		(end 100.693982 -240.92535)
		(width 0.1143)
		(layer "In11.Cu")
		(net "P5E_CPU1_G1_TX_DN<11>")
	)
	(segment
		(start 100.689664 -236.062774)
		(end 100.690426 -236.063282)
		(width 0.1143)
		(layer "In11.Cu")
		(net "P5E_CPU1_G1_TX_DN<11>")
	)
	(segment
		(start 100.697284 -228.601778)
		(end 100.69576 -228.60254)
		(width 0.1143)
		(layer "In11.Cu")
		(net "P5E_CPU1_G1_TX_DN<11>")
	)
	(segment
		(start 147.283678 -166.683182)
		(end 144.016984 -171.746418)
		(width 0.14224)
		(layer "In11.Cu")
		(net "P5E_CPU1_G1_TX_DN<11>")
	)
	(segment
		(start 100.691442 -240.923826)
		(end 100.692204 -240.924334)
		(width 0.1143)
		(layer "In11.Cu")
		(net "P5E_CPU1_G1_TX_DN<11>")
	)
	(segment
		(start 100.68687 -230.227378)
		(end 100.685346 -230.228394)
		(width 0.1143)
		(layer "In11.Cu")
		(net "P5E_CPU1_G1_TX_DN<11>")
	)
	(segment
		(start 100.687886 -240.921794)
		(end 100.688648 -240.922302)
		(width 0.1143)
		(layer "In11.Cu")
		(net "P5E_CPU1_G1_TX_DN<11>")
	)
	(segment
		(start 100.694236 -236.065568)
		(end 100.719636 -236.080046)
		(width 0.1143)
		(layer "In11.Cu")
		(net "P5E_CPU1_G1_TX_DN<11>")
	)
	(segment
		(start 100.70973 -241.554254)
		(end 100.708968 -241.554762)
		(width 0.1143)
		(layer "In11.Cu")
		(net "P5E_CPU1_G1_TX_DN<11>")
	)
	(segment
		(start 100.687886 -236.706918)
		(end 100.687632 -236.707172)
		(width 0.1143)
		(layer "In11.Cu")
		(net "P5E_CPU1_G1_TX_DN<11>")
	)
	(segment
		(start 100.687886 -230.22687)
		(end 100.68687 -230.227378)
		(width 0.1143)
		(layer "In11.Cu")
		(net "P5E_CPU1_G1_TX_DN<11>")
	)
	(segment
		(start 100.70973 -238.31423)
		(end 100.708968 -238.314738)
		(width 0.1143)
		(layer "In11.Cu")
		(net "P5E_CPU1_G1_TX_DN<11>")
	)
	(segment
		(start 100.691442 -236.06379)
		(end 100.692204 -236.064298)
		(width 0.1143)
		(layer "In11.Cu")
		(net "P5E_CPU1_G1_TX_DN<11>")
	)
	(segment
		(start 100.69449 -228.603302)
		(end 100.693728 -228.60381)
		(width 0.1143)
		(layer "In11.Cu")
		(net "P5E_CPU1_G1_TX_DN<11>")
	)
	(segment
		(start 100.651564 -232.800652)
		(end 100.687886 -232.821734)
		(width 0.1143)
		(layer "In11.Cu")
		(net "P5E_CPU1_G1_TX_DN<11>")
	)
	(segment
		(start 99.272852 -222.288862)
		(end 99.274376 -222.289878)
		(width 0.1143)
		(layer "In11.Cu")
		(net "P5E_CPU1_G1_TX_DN<11>")
	)
	(segment
		(start 99.26955 -222.287084)
		(end 99.271836 -222.288354)
		(width 0.1143)
		(layer "In11.Cu")
		(net "P5E_CPU1_G1_TX_DN<11>")
	)
	(segment
		(start 100.687886 -226.9871)
		(end 100.651564 -227.008182)
		(width 0.1143)
		(layer "In11.Cu")
		(net "P5E_CPU1_G1_TX_DN<11>")
	)
	(segment
		(start 100.651564 -229.560882)
		(end 100.654358 -229.562406)
		(width 0.1143)
		(layer "In11.Cu")
		(net "P5E_CPU1_G1_TX_DN<11>")
	)
	(segment
		(start 100.688648 -236.062266)
		(end 100.689664 -236.062774)
		(width 0.1143)
		(layer "In11.Cu")
		(net "P5E_CPU1_G1_TX_DN<11>")
	)
	(segment
		(start 100.69322 -237.684818)
		(end 100.693982 -237.685326)
		(width 0.1143)
		(layer "In11.Cu")
		(net "P5E_CPU1_G1_TX_DN<11>")
	)
	(segment
		(start 100.68433 -230.228902)
		(end 100.655882 -230.245412)
		(width 0.1143)
		(layer "In11.Cu")
		(net "P5E_CPU1_G1_TX_DN<11>")
	)
	(segment
		(start 100.719636 -226.968812)
		(end 100.687886 -226.9871)
		(width 0.1143)
		(layer "In11.Cu")
		(net "P5E_CPU1_G1_TX_DN<11>")
	)
	(segment
		(start 100.690426 -242.54333)
		(end 100.691442 -242.543838)
		(width 0.1143)
		(layer "In11.Cu")
		(net "P5E_CPU1_G1_TX_DN<11>")
	)
	(segment
		(start 98.950272 -221.129098)
		(end 98.950272 -221.387924)
		(width 0.1143)
		(layer "In11.Cu")
		(net "P5E_CPU1_G1_TX_DN<11>")
	)
	(segment
		(start 100.719636 -233.448606)
		(end 100.687886 -233.466894)
		(width 0.1143)
		(layer "In11.Cu")
		(net "P5E_CPU1_G1_TX_DN<11>")
	)
	(segment
		(start 100.688648 -228.606604)
		(end 100.687886 -228.607112)
		(width 0.1143)
		(layer "In11.Cu")
		(net "P5E_CPU1_G1_TX_DN<11>")
	)
	(segment
		(start 100.719636 -230.208582)
		(end 100.687886 -230.22687)
		(width 0.1143)
		(layer "In11.Cu")
		(net "P5E_CPU1_G1_TX_DN<11>")
	)
	(segment
		(start 100.653088 -226.321874)
		(end 100.687886 -226.34194)
		(width 0.1143)
		(layer "In11.Cu")
		(net "P5E_CPU1_G1_TX_DN<11>")
	)
	(segment
		(start 100.687886 -233.466894)
		(end 100.651564 -233.487976)
		(width 0.1143)
		(layer "In11.Cu")
		(net "P5E_CPU1_G1_TX_DN<11>")
	)
	(segment
		(start 98.904552 -221.05493)
		(end 98.904552 -221.083378)
		(width 0.1143)
		(layer "In11.Cu")
		(net "P5E_CPU1_G1_TX_DN<11>")
	)
	(segment
		(start 100.690426 -236.063282)
		(end 100.691442 -236.06379)
		(width 0.1143)
		(layer "In11.Cu")
		(net "P5E_CPU1_G1_TX_DN<11>")
	)
	(segment
		(start 100.217986 -225.531934)
		(end 100.221288 -225.533712)
		(width 0.1143)
		(layer "In11.Cu")
		(net "P5E_CPU1_G1_TX_DN<11>")
	)
	(segment
		(start 98.904552 -214.801196)
		(end 98.904552 -221.05493)
		(width 0.14224)
		(layer "In11.Cu")
		(net "P5E_CPU1_G1_TX_DN<11>")
	)
	(segment
		(start 100.688648 -240.922302)
		(end 100.689664 -240.92281)
		(width 0.1143)
		(layer "In11.Cu")
		(net "P5E_CPU1_G1_TX_DN<11>")
	)
	(segment
		(start 100.677726 -231.195626)
		(end 100.71862 -231.219502)
		(width 0.1143)
		(layer "In11.Cu")
		(net "P5E_CPU1_G1_TX_DN<11>")
	)
	(segment
		(start 100.405692 -225.870516)
		(end 100.405692 -225.87077)
		(width 0.1143)
		(layer "In11.Cu")
		(net "P5E_CPU1_G1_TX_DN<11>")
	)
	(segment
		(start 98.950272 -221.387924)
		(end 98.995738 -221.43339)
		(width 0.1143)
		(layer "In11.Cu")
		(net "P5E_CPU1_G1_TX_DN<11>")
	)
	(segment
		(start 148.62556 -160.004506)
		(end 148.62556 -162.74161)
		(width 0.14224)
		(layer "In11.Cu")
		(net "P5E_CPU1_G1_TX_DN<11>")
	)
	(segment
		(start 100.690426 -240.923318)
		(end 100.691442 -240.923826)
		(width 0.1143)
		(layer "In11.Cu")
		(net "P5E_CPU1_G1_TX_DN<11>")
	)
	(segment
		(start 100.690426 -237.683294)
		(end 100.691442 -237.683802)
		(width 0.1143)
		(layer "In11.Cu")
		(net "P5E_CPU1_G1_TX_DN<11>")
	)
	(segment
		(start 100.687886 -235.086906)
		(end 100.687632 -235.08716)
		(width 0.1143)
		(layer "In11.Cu")
		(net "P5E_CPU1_G1_TX_DN<11>")
	)
	(arc
		(start 99.70897 -223.769936)
		(mid 99.465643 -224.234502)
		(end 99.70897 -224.699068)
		(width 0.1143)
		(layer "In11.Cu")
		(net "P5E_CPU1_G1_TX_DN<11>")
	)
	(arc
		(start 100.687886 -228.607112)
		(mid 100.481263 -228.812891)
		(end 100.405692 -229.094538)
		(width 0.1143)
		(layer "In11.Cu")
		(net "P5E_CPU1_G1_TX_DN<11>")
	)
	(arc
		(start 100.719636 -237.700058)
		(mid 100.875564 -238.00435)
		(end 100.719636 -238.308642)
		(width 0.1143)
		(layer "In11.Cu")
		(net "P5E_CPU1_G1_TX_DN<11>")
	)
	(arc
		(start 100.719636 -234.460034)
		(mid 100.875564 -234.764326)
		(end 100.719636 -235.068618)
		(width 0.1143)
		(layer "In11.Cu")
		(net "P5E_CPU1_G1_TX_DN<11>")
	)
	(arc
		(start 100.254308 -225.554794)
		(mid 100.348225 -225.679878)
		(end 100.40112 -225.827082)
		(width 0.1143)
		(layer "In11.Cu")
		(net "P5E_CPU1_G1_TX_DN<11>")
	)
	(arc
		(start 100.63734 -233.497882)
		(mid 100.409957 -233.95432)
		(end 100.63734 -234.410758)
		(width 0.1143)
		(layer "In11.Cu")
		(net "P5E_CPU1_G1_TX_DN<11>")
	)
	(arc
		(start 100.405692 -230.71074)
		(mid 100.475707 -230.990203)
		(end 100.677726 -231.195626)
		(width 0.1143)
		(layer "In11.Cu")
		(net "P5E_CPU1_G1_TX_DN<11>")
	)
	(arc
		(start 100.875592 -229.90429)
		(mid 100.834337 -230.075261)
		(end 100.719636 -230.208582)
		(width 0.1143)
		(layer "In11.Cu")
		(net "P5E_CPU1_G1_TX_DN<11>")
	)
	(arc
		(start 100.405692 -229.094538)
		(mid 100.467137 -229.35075)
		(end 100.638102 -229.55123)
		(width 0.1143)
		(layer "In11.Cu")
		(net "P5E_CPU1_G1_TX_DN<11>")
	)
	(arc
		(start 100.719636 -240.940082)
		(mid 100.875564 -241.244374)
		(end 100.719636 -241.548666)
		(width 0.1143)
		(layer "In11.Cu")
		(net "P5E_CPU1_G1_TX_DN<11>")
	)
	(arc
		(start 100.719636 -236.080046)
		(mid 100.875564 -236.384338)
		(end 100.719636 -236.68863)
		(width 0.1143)
		(layer "In11.Cu")
		(net "P5E_CPU1_G1_TX_DN<11>")
	)
	(arc
		(start 100.405692 -225.87077)
		(mid 100.474653 -226.125301)
		(end 100.651564 -226.320858)
		(width 0.1143)
		(layer "In11.Cu")
		(net "P5E_CPU1_G1_TX_DN<11>")
	)
	(arc
		(start 99.778566 -223.119696)
		(mid 99.935543 -223.424496)
		(end 99.778566 -223.729296)
		(width 0.1143)
		(layer "In11.Cu")
		(net "P5E_CPU1_G1_TX_DN<11>")
	)
	(arc
		(start 100.635308 -227.019612)
		(mid 100.412424 -227.474526)
		(end 100.635308 -227.92944)
		(width 0.1143)
		(layer "In11.Cu")
		(net "P5E_CPU1_G1_TX_DN<11>")
	)
	(arc
		(start 100.638102 -229.55123)
		(mid 100.644797 -229.556106)
		(end 100.651564 -229.560882)
		(width 0.1143)
		(layer "In11.Cu")
		(net "P5E_CPU1_G1_TX_DN<11>")
	)
	(arc
		(start 100.687632 -239.947196)
		(mid 100.406985 -240.434558)
		(end 100.687632 -240.921794)
		(width 0.1143)
		(layer "In11.Cu")
		(net "P5E_CPU1_G1_TX_DN<11>")
	)
	(arc
		(start 100.719636 -242.560094)
		(mid 100.875564 -242.864386)
		(end 100.719636 -243.168678)
		(width 0.1143)
		(layer "In11.Cu")
		(net "P5E_CPU1_G1_TX_DN<11>")
	)
	(arc
		(start 100.635308 -243.219478)
		(mid 100.412424 -243.674392)
		(end 100.635308 -244.129306)
		(width 0.1143)
		(layer "In11.Cu")
		(net "P5E_CPU1_G1_TX_DN<11>")
	)
	(arc
		(start 100.687632 -241.567208)
		(mid 100.406985 -242.05457)
		(end 100.687632 -242.541806)
		(width 0.1143)
		(layer "In11.Cu")
		(net "P5E_CPU1_G1_TX_DN<11>")
	)
	(arc
		(start 100.63734 -234.410758)
		(mid 100.644414 -234.415765)
		(end 100.651564 -234.420664)
		(width 0.1143)
		(layer "In11.Cu")
		(net "P5E_CPU1_G1_TX_DN<11>")
	)
	(arc
		(start 100.687632 -235.08716)
		(mid 100.406985 -235.574522)
		(end 100.687632 -236.061758)
		(width 0.1143)
		(layer "In11.Cu")
		(net "P5E_CPU1_G1_TX_DN<11>")
	)
	(arc
		(start 100.637594 -230.257858)
		(mid 100.469418 -230.457561)
		(end 100.405692 -230.71074)
		(width 0.1143)
		(layer "In11.Cu")
		(net "P5E_CPU1_G1_TX_DN<11>")
	)
	(arc
		(start 99.104958 -222.139002)
		(mid 99.166477 -222.209596)
		(end 99.238816 -222.26905)
		(width 0.1143)
		(layer "In11.Cu")
		(net "P5E_CPU1_G1_TX_DN<11>")
	)
	(arc
		(start 99.935538 -225.044508)
		(mid 100.000053 -225.306727)
		(end 100.17887 -225.509074)
		(width 0.1143)
		(layer "In11.Cu")
		(net "P5E_CPU1_G1_TX_DN<11>")
	)
	(arc
		(start 100.719636 -226.360228)
		(mid 100.875564 -226.66452)
		(end 100.719636 -226.968812)
		(width 0.1143)
		(layer "In11.Cu")
		(net "P5E_CPU1_G1_TX_DN<11>")
	)
	(arc
		(start 100.651564 -243.208048)
		(mid 100.643386 -243.213691)
		(end 100.635308 -243.219478)
		(width 0.1143)
		(layer "In11.Cu")
		(net "P5E_CPU1_G1_TX_DN<11>")
	)
	(arc
		(start 98.995738 -221.804484)
		(mid 99.023654 -221.98046)
		(end 99.104958 -222.139002)
		(width 0.1143)
		(layer "In11.Cu")
		(net "P5E_CPU1_G1_TX_DN<11>")
	)
	(arc
		(start 100.719636 -232.840022)
		(mid 100.875564 -233.144314)
		(end 100.719636 -233.448606)
		(width 0.1143)
		(layer "In11.Cu")
		(net "P5E_CPU1_G1_TX_DN<11>")
	)
	(arc
		(start 100.687632 -238.327184)
		(mid 100.406985 -238.814546)
		(end 100.687632 -239.301782)
		(width 0.1143)
		(layer "In11.Cu")
		(net "P5E_CPU1_G1_TX_DN<11>")
	)
	(arc
		(start 100.635308 -232.789222)
		(mid 100.643386 -232.795008)
		(end 100.651564 -232.800652)
		(width 0.1143)
		(layer "In11.Cu")
		(net "P5E_CPU1_G1_TX_DN<11>")
	)
	(arc
		(start 100.635308 -227.92944)
		(mid 100.643386 -227.935226)
		(end 100.651564 -227.94087)
		(width 0.1143)
		(layer "In11.Cu")
		(net "P5E_CPU1_G1_TX_DN<11>")
	)
	(arc
		(start 100.721414 -231.221534)
		(mid 100.834821 -231.354423)
		(end 100.875592 -231.524302)
		(width 0.1143)
		(layer "In11.Cu")
		(net "P5E_CPU1_G1_TX_DN<11>")
	)
	(arc
		(start 100.651564 -231.867964)
		(mid 100.643386 -231.873607)
		(end 100.635308 -231.879394)
		(width 0.1143)
		(layer "In11.Cu")
		(net "P5E_CPU1_G1_TX_DN<11>")
	)
	(arc
		(start 99.465638 -222.61449)
		(mid 99.530153 -222.876709)
		(end 99.70897 -223.079056)
		(width 0.1143)
		(layer "In11.Cu")
		(net "P5E_CPU1_G1_TX_DN<11>")
	)
	(arc
		(start 100.721414 -229.601522)
		(mid 100.834821 -229.734411)
		(end 100.875592 -229.90429)
		(width 0.1143)
		(layer "In11.Cu")
		(net "P5E_CPU1_G1_TX_DN<11>")
	)
	(arc
		(start 100.245164 -225.547682)
		(mid 100.249764 -225.551203)
		(end 100.254308 -225.554794)
		(width 0.1143)
		(layer "In11.Cu")
		(net "P5E_CPU1_G1_TX_DN<11>")
	)
	(arc
		(start 100.687632 -236.707172)
		(mid 100.406985 -237.194534)
		(end 100.687632 -237.68177)
		(width 0.1143)
		(layer "In11.Cu")
		(net "P5E_CPU1_G1_TX_DN<11>")
	)
	(arc
		(start 100.651564 -227.008182)
		(mid 100.643386 -227.013825)
		(end 100.635308 -227.019612)
		(width 0.1143)
		(layer "In11.Cu")
		(net "P5E_CPU1_G1_TX_DN<11>")
	)
	(arc
		(start 99.309682 -222.310198)
		(mid 99.424358 -222.443532)
		(end 99.465638 -222.61449)
		(width 0.1143)
		(layer "In11.Cu")
		(net "P5E_CPU1_G1_TX_DN<11>")
	)
	(arc
		(start 100.719636 -239.32007)
		(mid 100.875564 -239.624362)
		(end 100.719636 -239.928654)
		(width 0.1143)
		(layer "In11.Cu")
		(net "P5E_CPU1_G1_TX_DN<11>")
	)
	(arc
		(start 100.651564 -233.487976)
		(mid 100.644415 -233.492876)
		(end 100.63734 -233.497882)
		(width 0.1143)
		(layer "In11.Cu")
		(net "P5E_CPU1_G1_TX_DN<11>")
	)
	(arc
		(start 100.719636 -227.98024)
		(mid 100.875564 -228.284532)
		(end 100.719636 -228.588824)
		(width 0.1143)
		(layer "In11.Cu")
		(net "P5E_CPU1_G1_TX_DN<11>")
	)
	(arc
		(start 100.875592 -231.524302)
		(mid 100.834337 -231.695273)
		(end 100.719636 -231.828594)
		(width 0.1143)
		(layer "In11.Cu")
		(net "P5E_CPU1_G1_TX_DN<11>")
	)
	(arc
		(start 100.719636 -244.180106)
		(mid 100.816771 -244.282975)
		(end 100.868734 -244.414548)
		(width 0.1143)
		(layer "In11.Cu")
		(net "P5E_CPU1_G1_TX_DN<11>")
	)
	(arc
		(start 100.40112 -225.827082)
		(mid 100.404305 -225.848704)
		(end 100.405692 -225.870516)
		(width 0.1143)
		(layer "In11.Cu")
		(net "P5E_CPU1_G1_TX_DN<11>")
	)
	(arc
		(start 100.654358 -230.246428)
		(mid 100.645925 -230.252068)
		(end 100.637594 -230.257858)
		(width 0.1143)
		(layer "In11.Cu")
		(net "P5E_CPU1_G1_TX_DN<11>")
	)
	(arc
		(start 100.635308 -231.879394)
		(mid 100.412424 -232.334308)
		(end 100.635308 -232.789222)
		(width 0.1143)
		(layer "In11.Cu")
		(net "P5E_CPU1_G1_TX_DN<11>")
	)
	(arc
		(start 99.778566 -224.739708)
		(mid 99.893993 -224.873084)
		(end 99.935538 -225.044508)
		(width 0.1143)
		(layer "In11.Cu")
		(net "P5E_CPU1_G1_TX_DN<11>")
	)
	(arc
		(start 100.635308 -244.129306)
		(mid 100.643386 -244.135092)
		(end 100.651564 -244.140736)
		(width 0.1143)
		(layer "In11.Cu")
		(net "P5E_CPU1_G1_TX_DN<11>")
	)
	(segment
		(start 29.478478 -17.890236)
		(end 29.774388 -18.186146)
		(width 0.12954)
		(layer "F.Cu")
		(net "P5E_CPU1_G1_TX_DN<10>")
	)
	(segment
		(start 29.774388 -18.86585)
		(end 29.503878 -19.13636)
		(width 0.12954)
		(layer "F.Cu")
		(net "P5E_CPU1_G1_TX_DN<10>")
	)
	(segment
		(start 100.967794 -247.99036)
		(end 100.500942 -247.724422)
		(width 0.12954)
		(layer "F.Cu")
		(net "P5E_CPU1_G1_TX_DN<10>")
	)
	(segment
		(start 29.774388 -18.186146)
		(end 29.774388 -18.86585)
		(width 0.12954)
		(layer "F.Cu")
		(net "P5E_CPU1_G1_TX_DN<10>")
	)
	(segment
		(start 101.633782 -236.703616)
		(end 101.632258 -236.704378)
		(width 0.1143)
		(layer "In11.Cu")
		(net "P5E_CPU1_G1_TX_DN<10>")
	)
	(segment
		(start 101.628702 -236.062266)
		(end 101.629972 -236.063028)
		(width 0.1143)
		(layer "In11.Cu")
		(net "P5E_CPU1_G1_TX_DN<10>")
	)
	(segment
		(start 101.65969 -230.208582)
		(end 101.62794 -230.22687)
		(width 0.1143)
		(layer "In11.Cu")
		(net "P5E_CPU1_G1_TX_DN<10>")
	)
	(segment
		(start 101.633782 -246.423688)
		(end 101.632258 -246.42445)
		(width 0.1143)
		(layer "In11.Cu")
		(net "P5E_CPU1_G1_TX_DN<10>")
	)
	(segment
		(start 101.152706 -225.528886)
		(end 101.153722 -225.529394)
		(width 0.1143)
		(layer "In11.Cu")
		(net "P5E_CPU1_G1_TX_DN<10>")
	)
	(segment
		(start 101.628702 -243.186458)
		(end 101.62794 -243.186966)
		(width 0.1143)
		(layer "In11.Cu")
		(net "P5E_CPU1_G1_TX_DN<10>")
	)
	(segment
		(start 101.626924 -232.821226)
		(end 101.62794 -232.821734)
		(width 0.1143)
		(layer "In11.Cu")
		(net "P5E_CPU1_G1_TX_DN<10>")
	)
	(segment
		(start 101.626924 -243.187474)
		(end 101.588824 -243.209826)
		(width 0.1143)
		(layer "In11.Cu")
		(net "P5E_CPU1_G1_TX_DN<10>")
	)
	(segment
		(start 101.628194 -228.607112)
		(end 101.589078 -228.629972)
		(width 0.1143)
		(layer "In11.Cu")
		(net "P5E_CPU1_G1_TX_DN<10>")
	)
	(segment
		(start 101.626924 -240.921286)
		(end 101.62794 -240.921794)
		(width 0.1143)
		(layer "In11.Cu")
		(net "P5E_CPU1_G1_TX_DN<10>")
	)
	(segment
		(start 101.632258 -235.084366)
		(end 101.631496 -235.084874)
		(width 0.1143)
		(layer "In11.Cu")
		(net "P5E_CPU1_G1_TX_DN<10>")
	)
	(segment
		(start 101.628702 -238.326422)
		(end 101.62794 -238.32693)
		(width 0.1143)
		(layer "In11.Cu")
		(net "P5E_CPU1_G1_TX_DN<10>")
	)
	(segment
		(start 101.658674 -226.96932)
		(end 101.628194 -226.9871)
		(width 0.1143)
		(layer "In11.Cu")
		(net "P5E_CPU1_G1_TX_DN<10>")
	)
	(segment
		(start 101.623622 -239.299242)
		(end 101.625146 -239.300258)
		(width 0.1143)
		(layer "In11.Cu")
		(net "P5E_CPU1_G1_TX_DN<10>")
	)
	(segment
		(start 101.625146 -244.160294)
		(end 101.626924 -244.16131)
		(width 0.1143)
		(layer "In11.Cu")
		(net "P5E_CPU1_G1_TX_DN<10>")
	)
	(segment
		(start 101.626924 -236.06125)
		(end 101.62794 -236.061758)
		(width 0.1143)
		(layer "In11.Cu")
		(net "P5E_CPU1_G1_TX_DN<10>")
	)
	(segment
		(start 43.543728 -45.669962)
		(end 52.95392 -57.105296)
		(width 0.14224)
		(layer "In11.Cu")
		(net "P5E_CPU1_G1_TX_DN<10>")
	)
	(segment
		(start 101.628702 -246.426482)
		(end 101.62794 -246.42699)
		(width 0.1143)
		(layer "In11.Cu")
		(net "P5E_CPU1_G1_TX_DN<10>")
	)
	(segment
		(start 101.596444 -236.04347)
		(end 101.621844 -236.058202)
		(width 0.1143)
		(layer "In11.Cu")
		(net "P5E_CPU1_G1_TX_DN<10>")
	)
	(segment
		(start 101.626924 -246.427498)
		(end 101.588824 -246.44985)
		(width 0.1143)
		(layer "In11.Cu")
		(net "P5E_CPU1_G1_TX_DN<10>")
	)
	(segment
		(start 144.733264 -172.366178)
		(end 106.658918 -203.567792)
		(width 0.14224)
		(layer "In11.Cu")
		(net "P5E_CPU1_G1_TX_DN<10>")
	)
	(segment
		(start 101.59111 -229.560628)
		(end 101.628194 -229.581964)
		(width 0.1143)
		(layer "In11.Cu")
		(net "P5E_CPU1_G1_TX_DN<10>")
	)
	(segment
		(start 149.557994 -163.188142)
		(end 148.067014 -167.56761)
		(width 0.14224)
		(layer "In11.Cu")
		(net "P5E_CPU1_G1_TX_DN<10>")
	)
	(segment
		(start 100.71862 -223.729296)
		(end 100.68814 -223.747076)
		(width 0.1143)
		(layer "In11.Cu")
		(net "P5E_CPU1_G1_TX_DN<10>")
	)
	(segment
		(start 101.158802 -225.532442)
		(end 101.160072 -225.533204)
		(width 0.1143)
		(layer "In11.Cu")
		(net "P5E_CPU1_G1_TX_DN<10>")
	)
	(segment
		(start 99.899978 -221.387924)
		(end 99.935792 -221.423738)
		(width 0.1143)
		(layer "In11.Cu")
		(net "P5E_CPU1_G1_TX_DN<10>")
	)
	(segment
		(start 101.628702 -236.70641)
		(end 101.62794 -236.706918)
		(width 0.1143)
		(layer "In11.Cu")
		(net "P5E_CPU1_G1_TX_DN<10>")
	)
	(segment
		(start 100.68814 -223.747076)
		(end 100.649024 -223.769936)
		(width 0.1143)
		(layer "In11.Cu")
		(net "P5E_CPU1_G1_TX_DN<10>")
	)
	(segment
		(start 101.631496 -244.804946)
		(end 101.628702 -244.80647)
		(width 0.1143)
		(layer "In11.Cu")
		(net "P5E_CPU1_G1_TX_DN<10>")
	)
	(segment
		(start 101.623622 -244.159278)
		(end 101.625146 -244.160294)
		(width 0.1143)
		(layer "In11.Cu")
		(net "P5E_CPU1_G1_TX_DN<10>")
	)
	(segment
		(start 101.629972 -234.443016)
		(end 101.631496 -234.443778)
		(width 0.1143)
		(layer "In11.Cu")
		(net "P5E_CPU1_G1_TX_DN<10>")
	)
	(segment
		(start 101.595682 -236.042962)
		(end 101.596444 -236.04347)
		(width 0.1143)
		(layer "In11.Cu")
		(net "P5E_CPU1_G1_TX_DN<10>")
	)
	(segment
		(start 101.588824 -237.65891)
		(end 101.6254 -237.680246)
		(width 0.1143)
		(layer "In11.Cu")
		(net "P5E_CPU1_G1_TX_DN<10>")
	)
	(segment
		(start 101.588824 -239.278922)
		(end 101.595682 -239.282986)
		(width 0.1143)
		(layer "In11.Cu")
		(net "P5E_CPU1_G1_TX_DN<10>")
	)
	(segment
		(start 101.622606 -234.438698)
		(end 101.623622 -234.439206)
		(width 0.1143)
		(layer "In11.Cu")
		(net "P5E_CPU1_G1_TX_DN<10>")
	)
	(segment
		(start 101.596444 -232.803446)
		(end 101.621844 -232.818178)
		(width 0.1143)
		(layer "In11.Cu")
		(net "P5E_CPU1_G1_TX_DN<10>")
	)
	(segment
		(start 101.62794 -235.086906)
		(end 101.626924 -235.087414)
		(width 0.1143)
		(layer "In11.Cu")
		(net "P5E_CPU1_G1_TX_DN<10>")
	)
	(segment
		(start 29.503878 -19.13636)
		(end 29.794708 -19.42719)
		(width 0.14224)
		(layer "In11.Cu")
		(net "P5E_CPU1_G1_TX_DN<10>")
	)
	(segment
		(start 101.634544 -231.843072)
		(end 101.633782 -231.84358)
		(width 0.1143)
		(layer "In11.Cu")
		(net "P5E_CPU1_G1_TX_DN<10>")
	)
	(segment
		(start 101.632258 -241.564414)
		(end 101.631496 -241.564922)
		(width 0.1143)
		(layer "In11.Cu")
		(net "P5E_CPU1_G1_TX_DN<10>")
	)
	(segment
		(start 101.65969 -238.308642)
		(end 101.629972 -238.32566)
		(width 0.1143)
		(layer "In11.Cu")
		(net "P5E_CPU1_G1_TX_DN<10>")
	)
	(segment
		(start 101.631496 -234.443778)
		(end 101.65969 -234.460034)
		(width 0.1143)
		(layer "In11.Cu")
		(net "P5E_CPU1_G1_TX_DN<10>")
	)
	(segment
		(start 101.623622 -232.819194)
		(end 101.625146 -232.82021)
		(width 0.1143)
		(layer "In11.Cu")
		(net "P5E_CPU1_G1_TX_DN<10>")
	)
	(segment
		(start 101.6254 -245.780306)
		(end 101.626924 -245.781322)
		(width 0.1143)
		(layer "In11.Cu")
		(net "P5E_CPU1_G1_TX_DN<10>")
	)
	(segment
		(start 101.632258 -231.844342)
		(end 101.631496 -231.84485)
		(width 0.1143)
		(layer "In11.Cu")
		(net "P5E_CPU1_G1_TX_DN<10>")
	)
	(segment
		(start 101.589078 -227.939092)
		(end 101.628194 -227.961952)
		(width 0.1143)
		(layer "In11.Cu")
		(net "P5E_CPU1_G1_TX_DN<10>")
	)
	(segment
		(start 101.623622 -236.059218)
		(end 101.625146 -236.060234)
		(width 0.1143)
		(layer "In11.Cu")
		(net "P5E_CPU1_G1_TX_DN<10>")
	)
	(segment
		(start 101.628194 -226.34194)
		(end 101.658674 -226.35972)
		(width 0.1143)
		(layer "In11.Cu")
		(net "P5E_CPU1_G1_TX_DN<10>")
	)
	(segment
		(start 101.631496 -236.06379)
		(end 101.65969 -236.080046)
		(width 0.1143)
		(layer "In11.Cu")
		(net "P5E_CPU1_G1_TX_DN<10>")
	)
	(segment
		(start 101.632258 -246.42445)
		(end 101.631496 -246.424958)
		(width 0.1143)
		(layer "In11.Cu")
		(net "P5E_CPU1_G1_TX_DN<10>")
	)
	(segment
		(start 101.621844 -240.918238)
		(end 101.622606 -240.918746)
		(width 0.1143)
		(layer "In11.Cu")
		(net "P5E_CPU1_G1_TX_DN<10>")
	)
	(segment
		(start 101.622606 -239.298734)
		(end 101.623622 -239.299242)
		(width 0.1143)
		(layer "In11.Cu")
		(net "P5E_CPU1_G1_TX_DN<10>")
	)
	(segment
		(start 101.6254 -242.540282)
		(end 101.626924 -242.541298)
		(width 0.1143)
		(layer "In11.Cu")
		(net "P5E_CPU1_G1_TX_DN<10>")
	)
	(segment
		(start 101.65969 -231.828594)
		(end 101.634544 -231.843072)
		(width 0.1143)
		(layer "In11.Cu")
		(net "P5E_CPU1_G1_TX_DN<10>")
	)
	(segment
		(start 101.632258 -233.464354)
		(end 101.631496 -233.464862)
		(width 0.1143)
		(layer "In11.Cu")
		(net "P5E_CPU1_G1_TX_DN<10>")
	)
	(segment
		(start 101.65969 -244.78869)
		(end 101.634544 -244.803168)
		(width 0.1143)
		(layer "In11.Cu")
		(net "P5E_CPU1_G1_TX_DN<10>")
	)
	(segment
		(start 101.629972 -236.063028)
		(end 101.631496 -236.06379)
		(width 0.1143)
		(layer "In11.Cu")
		(net "P5E_CPU1_G1_TX_DN<10>")
	)
	(segment
		(start 101.157024 -225.531426)
		(end 101.15804 -225.531934)
		(width 0.1143)
		(layer "In11.Cu")
		(net "P5E_CPU1_G1_TX_DN<10>")
	)
	(segment
		(start 101.626924 -233.467402)
		(end 101.588824 -233.489754)
		(width 0.1143)
		(layer "In11.Cu")
		(net "P5E_CPU1_G1_TX_DN<10>")
	)
	(segment
		(start 101.631496 -243.184934)
		(end 101.628702 -243.186458)
		(width 0.1143)
		(layer "In11.Cu")
		(net "P5E_CPU1_G1_TX_DN<10>")
	)
	(segment
		(start 100.68814 -223.101916)
		(end 100.71862 -223.119696)
		(width 0.1143)
		(layer "In11.Cu")
		(net "P5E_CPU1_G1_TX_DN<10>")
	)
	(segment
		(start 101.621844 -244.158262)
		(end 101.622606 -244.15877)
		(width 0.1143)
		(layer "In11.Cu")
		(net "P5E_CPU1_G1_TX_DN<10>")
	)
	(segment
		(start 101.628702 -240.922302)
		(end 101.629972 -240.923064)
		(width 0.1143)
		(layer "In11.Cu")
		(net "P5E_CPU1_G1_TX_DN<10>")
	)
	(segment
		(start 101.65969 -239.928654)
		(end 101.634544 -239.943132)
		(width 0.1143)
		(layer "In11.Cu")
		(net "P5E_CPU1_G1_TX_DN<10>")
	)
	(segment
		(start 101.62794 -242.541806)
		(end 101.65969 -242.560094)
		(width 0.1143)
		(layer "In11.Cu")
		(net "P5E_CPU1_G1_TX_DN<10>")
	)
	(segment
		(start 101.631496 -236.704886)
		(end 101.628702 -236.70641)
		(width 0.1143)
		(layer "In11.Cu")
		(net "P5E_CPU1_G1_TX_DN<10>")
	)
	(segment
		(start 101.588824 -240.898934)
		(end 101.595682 -240.902998)
		(width 0.1143)
		(layer "In11.Cu")
		(net "P5E_CPU1_G1_TX_DN<10>")
	)
	(segment
		(start 101.626924 -231.84739)
		(end 101.588824 -231.869742)
		(width 0.1143)
		(layer "In11.Cu")
		(net "P5E_CPU1_G1_TX_DN<10>")
	)
	(segment
		(start 101.634544 -246.42318)
		(end 101.633782 -246.423688)
		(width 0.1143)
		(layer "In11.Cu")
		(net "P5E_CPU1_G1_TX_DN<10>")
	)
	(segment
		(start 101.62794 -243.186966)
		(end 101.626924 -243.187474)
		(width 0.1143)
		(layer "In11.Cu")
		(net "P5E_CPU1_G1_TX_DN<10>")
	)
	(segment
		(start 101.626924 -242.541298)
		(end 101.62794 -242.541806)
		(width 0.1143)
		(layer "In11.Cu")
		(net "P5E_CPU1_G1_TX_DN<10>")
	)
	(segment
		(start 101.628702 -239.30229)
		(end 101.629972 -239.303052)
		(width 0.1143)
		(layer "In11.Cu")
		(net "P5E_CPU1_G1_TX_DN<10>")
	)
	(segment
		(start 101.589078 -229.559104)
		(end 101.59111 -229.560628)
		(width 0.1143)
		(layer "In11.Cu")
		(net "P5E_CPU1_G1_TX_DN<10>")
	)
	(segment
		(start 100.181664 -222.270828)
		(end 100.249736 -222.310198)
		(width 0.1143)
		(layer "In11.Cu")
		(net "P5E_CPU1_G1_TX_DN<10>")
	)
	(segment
		(start 101.626924 -244.807486)
		(end 101.588824 -244.829838)
		(width 0.1143)
		(layer "In11.Cu")
		(net "P5E_CPU1_G1_TX_DN<10>")
	)
	(segment
		(start 101.621844 -236.058202)
		(end 101.622606 -236.05871)
		(width 0.1143)
		(layer "In11.Cu")
		(net "P5E_CPU1_G1_TX_DN<10>")
	)
	(segment
		(start 148.067014 -167.56761)
		(end 144.733264 -172.366178)
		(width 0.14224)
		(layer "In11.Cu")
		(net "P5E_CPU1_G1_TX_DN<10>")
	)
	(segment
		(start 101.629972 -239.303052)
		(end 101.631496 -239.303814)
		(width 0.1143)
		(layer "In11.Cu")
		(net "P5E_CPU1_G1_TX_DN<10>")
	)
	(segment
		(start 101.629972 -244.163088)
		(end 101.631496 -244.16385)
		(width 0.1143)
		(layer "In11.Cu")
		(net "P5E_CPU1_G1_TX_DN<10>")
	)
	(segment
		(start 101.631496 -246.424958)
		(end 101.628702 -246.426482)
		(width 0.1143)
		(layer "In11.Cu")
		(net "P5E_CPU1_G1_TX_DN<10>")
	)
	(segment
		(start 101.62794 -233.466894)
		(end 101.626924 -233.467402)
		(width 0.1143)
		(layer "In11.Cu")
		(net "P5E_CPU1_G1_TX_DN<10>")
	)
	(segment
		(start 101.588824 -244.138958)
		(end 101.595682 -244.143022)
		(width 0.1143)
		(layer "In11.Cu")
		(net "P5E_CPU1_G1_TX_DN<10>")
	)
	(segment
		(start 101.62794 -237.68177)
		(end 101.65969 -237.700058)
		(width 0.1143)
		(layer "In11.Cu")
		(net "P5E_CPU1_G1_TX_DN<10>")
	)
	(segment
		(start 101.65969 -233.448606)
		(end 101.634544 -233.463084)
		(width 0.1143)
		(layer "In11.Cu")
		(net "P5E_CPU1_G1_TX_DN<10>")
	)
	(segment
		(start 101.631496 -235.084874)
		(end 101.628702 -235.086398)
		(width 0.1143)
		(layer "In11.Cu")
		(net "P5E_CPU1_G1_TX_DN<10>")
	)
	(segment
		(start 101.632258 -239.944402)
		(end 101.631496 -239.94491)
		(width 0.1143)
		(layer "In11.Cu")
		(net "P5E_CPU1_G1_TX_DN<10>")
	)
	(segment
		(start 101.595682 -240.902998)
		(end 101.596444 -240.903506)
		(width 0.1143)
		(layer "In11.Cu")
		(net "P5E_CPU1_G1_TX_DN<10>")
	)
	(segment
		(start 54.199282 -58.131964)
		(end 145.3261 -140.077698)
		(width 0.14224)
		(layer "In11.Cu")
		(net "P5E_CPU1_G1_TX_DN<10>")
	)
	(segment
		(start 101.588824 -236.038898)
		(end 101.595682 -236.042962)
		(width 0.1143)
		(layer "In11.Cu")
		(net "P5E_CPU1_G1_TX_DN<10>")
	)
	(segment
		(start 100.649024 -224.699068)
		(end 100.68814 -224.721928)
		(width 0.1143)
		(layer "In11.Cu")
		(net "P5E_CPU1_G1_TX_DN<10>")
	)
	(segment
		(start 101.125782 -225.513138)
		(end 101.126544 -225.513646)
		(width 0.1143)
		(layer "In11.Cu")
		(net "P5E_CPU1_G1_TX_DN<10>")
	)
	(segment
		(start 101.631496 -239.303814)
		(end 101.65969 -239.32007)
		(width 0.1143)
		(layer "In11.Cu")
		(net "P5E_CPU1_G1_TX_DN<10>")
	)
	(segment
		(start 100.649024 -223.079056)
		(end 100.68814 -223.101916)
		(width 0.1143)
		(layer "In11.Cu")
		(net "P5E_CPU1_G1_TX_DN<10>")
	)
	(segment
		(start 99.854258 -215.028018)
		(end 99.854258 -221.05493)
		(width 0.14224)
		(layer "In11.Cu")
		(net "P5E_CPU1_G1_TX_DN<10>")
	)
	(segment
		(start 101.628194 -229.581964)
		(end 101.660706 -229.60076)
		(width 0.1143)
		(layer "In11.Cu")
		(net "P5E_CPU1_G1_TX_DN<10>")
	)
	(segment
		(start 101.631496 -232.823766)
		(end 101.65969 -232.840022)
		(width 0.1143)
		(layer "In11.Cu")
		(net "P5E_CPU1_G1_TX_DN<10>")
	)
	(segment
		(start 101.62794 -246.42699)
		(end 101.626924 -246.427498)
		(width 0.1143)
		(layer "In11.Cu")
		(net "P5E_CPU1_G1_TX_DN<10>")
	)
	(segment
		(start 101.634544 -241.563144)
		(end 101.633782 -241.563652)
		(width 0.1143)
		(layer "In11.Cu")
		(net "P5E_CPU1_G1_TX_DN<10>")
	)
	(segment
		(start 101.626924 -237.681262)
		(end 101.62794 -237.68177)
		(width 0.1143)
		(layer "In11.Cu")
		(net "P5E_CPU1_G1_TX_DN<10>")
	)
	(segment
		(start 101.625146 -239.300258)
		(end 101.626924 -239.301274)
		(width 0.1143)
		(layer "In11.Cu")
		(net "P5E_CPU1_G1_TX_DN<10>")
	)
	(segment
		(start 101.160072 -225.533204)
		(end 101.18979 -225.550222)
		(width 0.1143)
		(layer "In11.Cu")
		(net "P5E_CPU1_G1_TX_DN<10>")
	)
	(segment
		(start 101.621844 -234.43819)
		(end 101.622606 -234.438698)
		(width 0.1143)
		(layer "In11.Cu")
		(net "P5E_CPU1_G1_TX_DN<10>")
	)
	(segment
		(start 101.595682 -239.282986)
		(end 101.596444 -239.283494)
		(width 0.1143)
		(layer "In11.Cu")
		(net "P5E_CPU1_G1_TX_DN<10>")
	)
	(segment
		(start 101.623622 -234.439206)
		(end 101.625146 -234.440222)
		(width 0.1143)
		(layer "In11.Cu")
		(net "P5E_CPU1_G1_TX_DN<10>")
	)
	(segment
		(start 101.633782 -235.083604)
		(end 101.632258 -235.084366)
		(width 0.1143)
		(layer "In11.Cu")
		(net "P5E_CPU1_G1_TX_DN<10>")
	)
	(segment
		(start 101.629972 -240.923064)
		(end 101.631496 -240.923826)
		(width 0.1143)
		(layer "In11.Cu")
		(net "P5E_CPU1_G1_TX_DN<10>")
	)
	(segment
		(start 101.631496 -244.16385)
		(end 101.65969 -244.180106)
		(width 0.1143)
		(layer "In11.Cu")
		(net "P5E_CPU1_G1_TX_DN<10>")
	)
	(segment
		(start 101.62794 -232.821734)
		(end 101.628702 -232.822242)
		(width 0.1143)
		(layer "In11.Cu")
		(net "P5E_CPU1_G1_TX_DN<10>")
	)
	(segment
		(start 101.634544 -235.083096)
		(end 101.633782 -235.083604)
		(width 0.1143)
		(layer "In11.Cu")
		(net "P5E_CPU1_G1_TX_DN<10>")
	)
	(segment
		(start 100.179632 -222.269558)
		(end 100.180648 -222.27032)
		(width 0.1143)
		(layer "In11.Cu")
		(net "P5E_CPU1_G1_TX_DN<10>")
	)
	(segment
		(start 101.626924 -241.567462)
		(end 101.588824 -241.589814)
		(width 0.1143)
		(layer "In11.Cu")
		(net "P5E_CPU1_G1_TX_DN<10>")
	)
	(segment
		(start 101.62794 -244.806978)
		(end 101.626924 -244.807486)
		(width 0.1143)
		(layer "In11.Cu")
		(net "P5E_CPU1_G1_TX_DN<10>")
	)
	(segment
		(start 99.899978 -221.129098)
		(end 99.899978 -221.387924)
		(width 0.1143)
		(layer "In11.Cu")
		(net "P5E_CPU1_G1_TX_DN<10>")
	)
	(segment
		(start 101.632258 -243.184426)
		(end 101.631496 -243.184934)
		(width 0.1143)
		(layer "In11.Cu")
		(net "P5E_CPU1_G1_TX_DN<10>")
	)
	(segment
		(start 100.881688 -247.641618)
		(end 100.798884 -247.724422)
		(width 0.1143)
		(layer "In11.Cu")
		(net "P5E_CPU1_G1_TX_DN<10>")
	)
	(segment
		(start 99.854258 -221.05493)
		(end 99.854258 -221.083378)
		(width 0.1143)
		(layer "In11.Cu")
		(net "P5E_CPU1_G1_TX_DN<10>")
	)
	(segment
		(start 101.62794 -239.946942)
		(end 101.626924 -239.94745)
		(width 0.1143)
		(layer "In11.Cu")
		(net "P5E_CPU1_G1_TX_DN<10>")
	)
	(segment
		(start 101.633782 -244.803676)
		(end 101.632258 -244.804438)
		(width 0.1143)
		(layer "In11.Cu")
		(net "P5E_CPU1_G1_TX_DN<10>")
	)
	(segment
		(start 101.62794 -236.061758)
		(end 101.628702 -236.062266)
		(width 0.1143)
		(layer "In11.Cu")
		(net "P5E_CPU1_G1_TX_DN<10>")
	)
	(segment
		(start 101.622606 -240.918746)
		(end 101.623622 -240.919254)
		(width 0.1143)
		(layer "In11.Cu")
		(net "P5E_CPU1_G1_TX_DN<10>")
	)
	(segment
		(start 29.794708 -19.42719)
		(end 29.794708 -20.264374)
		(width 0.14224)
		(layer "In11.Cu")
		(net "P5E_CPU1_G1_TX_DN<10>")
	)
	(segment
		(start 101.588824 -234.418886)
		(end 101.595682 -234.42295)
		(width 0.1143)
		(layer "In11.Cu")
		(net "P5E_CPU1_G1_TX_DN<10>")
	)
	(segment
		(start 100.798884 -247.724422)
		(end 100.500942 -247.724422)
		(width 0.1143)
		(layer "In11.Cu")
		(net "P5E_CPU1_G1_TX_DN<10>")
	)
	(segment
		(start 101.62794 -231.846882)
		(end 101.626924 -231.84739)
		(width 0.1143)
		(layer "In11.Cu")
		(net "P5E_CPU1_G1_TX_DN<10>")
	)
	(segment
		(start 101.633782 -231.84358)
		(end 101.632258 -231.844342)
		(width 0.1143)
		(layer "In11.Cu")
		(net "P5E_CPU1_G1_TX_DN<10>")
	)
	(segment
		(start 101.626924 -235.087414)
		(end 101.588824 -235.109766)
		(width 0.1143)
		(layer "In11.Cu")
		(net "P5E_CPU1_G1_TX_DN<10>")
	)
	(segment
		(start 101.634544 -233.463084)
		(end 101.633782 -233.463592)
		(width 0.1143)
		(layer "In11.Cu")
		(net "P5E_CPU1_G1_TX_DN<10>")
	)
	(segment
		(start 101.589078 -226.31908)
		(end 101.628194 -226.34194)
		(width 0.1143)
		(layer "In11.Cu")
		(net "P5E_CPU1_G1_TX_DN<10>")
	)
	(segment
		(start 101.626924 -245.781322)
		(end 101.62794 -245.78183)
		(width 0.1143)
		(layer "In11.Cu")
		(net "P5E_CPU1_G1_TX_DN<10>")
	)
	(segment
		(start 101.62794 -231.201976)
		(end 101.661468 -231.221534)
		(width 0.1143)
		(layer "In11.Cu")
		(net "P5E_CPU1_G1_TX_DN<10>")
	)
	(segment
		(start 101.62794 -241.566954)
		(end 101.626924 -241.567462)
		(width 0.1143)
		(layer "In11.Cu")
		(net "P5E_CPU1_G1_TX_DN<10>")
	)
	(segment
		(start 100.180648 -222.27032)
		(end 100.181664 -222.270828)
		(width 0.1143)
		(layer "In11.Cu")
		(net "P5E_CPU1_G1_TX_DN<10>")
	)
	(segment
		(start 101.588824 -242.518946)
		(end 101.6254 -242.540282)
		(width 0.1143)
		(layer "In11.Cu")
		(net "P5E_CPU1_G1_TX_DN<10>")
	)
	(segment
		(start 101.634544 -236.703108)
		(end 101.633782 -236.703616)
		(width 0.1143)
		(layer "In11.Cu")
		(net "P5E_CPU1_G1_TX_DN<10>")
	)
	(segment
		(start 101.628702 -233.466386)
		(end 101.62794 -233.466894)
		(width 0.1143)
		(layer "In11.Cu")
		(net "P5E_CPU1_G1_TX_DN<10>")
	)
	(segment
		(start 101.15804 -247.236996)
		(end 101.118924 -247.259856)
		(width 0.1143)
		(layer "In11.Cu")
		(net "P5E_CPU1_G1_TX_DN<10>")
	)
	(segment
		(start 101.65969 -241.548666)
		(end 101.634544 -241.563144)
		(width 0.1143)
		(layer "In11.Cu")
		(net "P5E_CPU1_G1_TX_DN<10>")
	)
	(segment
		(start 101.596444 -234.423458)
		(end 101.621844 -234.43819)
		(width 0.1143)
		(layer "In11.Cu")
		(net "P5E_CPU1_G1_TX_DN<10>")
	)
	(segment
		(start 101.626924 -236.707426)
		(end 101.588824 -236.729778)
		(width 0.1143)
		(layer "In11.Cu")
		(net "P5E_CPU1_G1_TX_DN<10>")
	)
	(segment
		(start 101.626924 -234.441238)
		(end 101.62794 -234.441746)
		(width 0.1143)
		(layer "In11.Cu")
		(net "P5E_CPU1_G1_TX_DN<10>")
	)
	(segment
		(start 101.596444 -239.283494)
		(end 101.621844 -239.298226)
		(width 0.1143)
		(layer "In11.Cu")
		(net "P5E_CPU1_G1_TX_DN<10>")
	)
	(segment
		(start 101.595682 -244.143022)
		(end 101.596444 -244.14353)
		(width 0.1143)
		(layer "In11.Cu")
		(net "P5E_CPU1_G1_TX_DN<10>")
	)
	(segment
		(start 101.62794 -239.301782)
		(end 101.628702 -239.30229)
		(width 0.1143)
		(layer "In11.Cu")
		(net "P5E_CPU1_G1_TX_DN<10>")
	)
	(segment
		(start 101.628194 -227.961952)
		(end 101.658674 -227.979732)
		(width 0.1143)
		(layer "In11.Cu")
		(net "P5E_CPU1_G1_TX_DN<10>")
	)
	(segment
		(start 101.65969 -235.068618)
		(end 101.634544 -235.083096)
		(width 0.1143)
		(layer "In11.Cu")
		(net "P5E_CPU1_G1_TX_DN<10>")
	)
	(segment
		(start 52.95392 -57.105296)
		(end 54.199282 -58.131964)
		(width 0.14224)
		(layer "In11.Cu")
		(net "P5E_CPU1_G1_TX_DN<10>")
	)
	(segment
		(start 101.65969 -236.68863)
		(end 101.634544 -236.703108)
		(width 0.1143)
		(layer "In11.Cu")
		(net "P5E_CPU1_G1_TX_DN<10>")
	)
	(segment
		(start 106.658918 -203.567792)
		(end 99.854258 -215.028018)
		(width 0.14224)
		(layer "In11.Cu")
		(net "P5E_CPU1_G1_TX_DN<10>")
	)
	(segment
		(start 148.756624 -147.17014)
		(end 149.557994 -159.975042)
		(width 0.14224)
		(layer "In11.Cu")
		(net "P5E_CPU1_G1_TX_DN<10>")
	)
	(segment
		(start 101.588824 -231.179116)
		(end 101.62794 -231.201976)
		(width 0.1143)
		(layer "In11.Cu")
		(net "P5E_CPU1_G1_TX_DN<10>")
	)
	(segment
		(start 101.633782 -241.563652)
		(end 101.632258 -241.564414)
		(width 0.1143)
		(layer "In11.Cu")
		(net "P5E_CPU1_G1_TX_DN<10>")
	)
	(segment
		(start 99.935792 -221.423738)
		(end 99.935792 -221.804484)
		(width 0.1143)
		(layer "In11.Cu")
		(net "P5E_CPU1_G1_TX_DN<10>")
	)
	(segment
		(start 101.62794 -230.22687)
		(end 101.591364 -230.248206)
		(width 0.1143)
		(layer "In11.Cu")
		(net "P5E_CPU1_G1_TX_DN<10>")
	)
	(segment
		(start 101.634544 -244.803168)
		(end 101.633782 -244.803676)
		(width 0.1143)
		(layer "In11.Cu")
		(net "P5E_CPU1_G1_TX_DN<10>")
	)
	(segment
		(start 101.631496 -240.923826)
		(end 101.65969 -240.940082)
		(width 0.1143)
		(layer "In11.Cu")
		(net "P5E_CPU1_G1_TX_DN<10>")
	)
	(segment
		(start 101.631496 -241.564922)
		(end 101.628702 -241.566446)
		(width 0.1143)
		(layer "In11.Cu")
		(net "P5E_CPU1_G1_TX_DN<10>")
	)
	(segment
		(start 101.625146 -236.060234)
		(end 101.626924 -236.06125)
		(width 0.1143)
		(layer "In11.Cu")
		(net "P5E_CPU1_G1_TX_DN<10>")
	)
	(segment
		(start 101.628702 -244.80647)
		(end 101.62794 -244.806978)
		(width 0.1143)
		(layer "In11.Cu")
		(net "P5E_CPU1_G1_TX_DN<10>")
	)
	(segment
		(start 101.633782 -233.463592)
		(end 101.632258 -233.464354)
		(width 0.1143)
		(layer "In11.Cu")
		(net "P5E_CPU1_G1_TX_DN<10>")
	)
	(segment
		(start 101.626924 -238.327438)
		(end 101.588824 -238.34979)
		(width 0.1143)
		(layer "In11.Cu")
		(net "P5E_CPU1_G1_TX_DN<10>")
	)
	(segment
		(start 101.621844 -232.818178)
		(end 101.622606 -232.818686)
		(width 0.1143)
		(layer "In11.Cu")
		(net "P5E_CPU1_G1_TX_DN<10>")
	)
	(segment
		(start 101.596444 -240.903506)
		(end 101.621844 -240.918238)
		(width 0.1143)
		(layer "In11.Cu")
		(net "P5E_CPU1_G1_TX_DN<10>")
	)
	(segment
		(start 101.633782 -243.183664)
		(end 101.632258 -243.184426)
		(width 0.1143)
		(layer "In11.Cu")
		(net "P5E_CPU1_G1_TX_DN<10>")
	)
	(segment
		(start 101.631496 -233.464862)
		(end 101.628702 -233.466386)
		(width 0.1143)
		(layer "In11.Cu")
		(net "P5E_CPU1_G1_TX_DN<10>")
	)
	(segment
		(start 101.623622 -240.919254)
		(end 101.625146 -240.92027)
		(width 0.1143)
		(layer "In11.Cu")
		(net "P5E_CPU1_G1_TX_DN<10>")
	)
	(segment
		(start 101.634544 -239.943132)
		(end 101.633782 -239.94364)
		(width 0.1143)
		(layer "In11.Cu")
		(net "P5E_CPU1_G1_TX_DN<10>")
	)
	(segment
		(start 101.6254 -237.680246)
		(end 101.626924 -237.681262)
		(width 0.1143)
		(layer "In11.Cu")
		(net "P5E_CPU1_G1_TX_DN<10>")
	)
	(segment
		(start 101.621844 -239.298226)
		(end 101.622606 -239.298734)
		(width 0.1143)
		(layer "In11.Cu")
		(net "P5E_CPU1_G1_TX_DN<10>")
	)
	(segment
		(start 101.62794 -238.32693)
		(end 101.626924 -238.327438)
		(width 0.1143)
		(layer "In11.Cu")
		(net "P5E_CPU1_G1_TX_DN<10>")
	)
	(segment
		(start 101.628194 -226.9871)
		(end 101.589078 -227.00996)
		(width 0.1143)
		(layer "In11.Cu")
		(net "P5E_CPU1_G1_TX_DN<10>")
	)
	(segment
		(start 145.3261 -140.077698)
		(end 148.756624 -147.17014)
		(width 0.14224)
		(layer "In11.Cu")
		(net "P5E_CPU1_G1_TX_DN<10>")
	)
	(segment
		(start 101.629972 -238.32566)
		(end 101.628702 -238.326422)
		(width 0.1143)
		(layer "In11.Cu")
		(net "P5E_CPU1_G1_TX_DN<10>")
	)
	(segment
		(start 101.628702 -231.846374)
		(end 101.62794 -231.846882)
		(width 0.1143)
		(layer "In11.Cu")
		(net "P5E_CPU1_G1_TX_DN<10>")
	)
	(segment
		(start 101.62794 -234.441746)
		(end 101.628702 -234.442254)
		(width 0.1143)
		(layer "In11.Cu")
		(net "P5E_CPU1_G1_TX_DN<10>")
	)
	(segment
		(start 101.153722 -225.529394)
		(end 101.155246 -225.53041)
		(width 0.1143)
		(layer "In11.Cu")
		(net "P5E_CPU1_G1_TX_DN<10>")
	)
	(segment
		(start 101.595682 -232.802938)
		(end 101.596444 -232.803446)
		(width 0.1143)
		(layer "In11.Cu")
		(net "P5E_CPU1_G1_TX_DN<10>")
	)
	(segment
		(start 101.632258 -244.804438)
		(end 101.631496 -244.804946)
		(width 0.1143)
		(layer "In11.Cu")
		(net "P5E_CPU1_G1_TX_DN<10>")
	)
	(segment
		(start 101.622606 -244.15877)
		(end 101.623622 -244.159278)
		(width 0.1143)
		(layer "In11.Cu")
		(net "P5E_CPU1_G1_TX_DN<10>")
	)
	(segment
		(start 101.629972 -232.823004)
		(end 101.631496 -232.823766)
		(width 0.1143)
		(layer "In11.Cu")
		(net "P5E_CPU1_G1_TX_DN<10>")
	)
	(segment
		(start 101.65969 -243.168678)
		(end 101.634544 -243.183156)
		(width 0.1143)
		(layer "In11.Cu")
		(net "P5E_CPU1_G1_TX_DN<10>")
	)
	(segment
		(start 101.631496 -239.94491)
		(end 101.628702 -239.946434)
		(width 0.1143)
		(layer "In11.Cu")
		(net "P5E_CPU1_G1_TX_DN<10>")
	)
	(segment
		(start 101.658674 -228.589332)
		(end 101.628194 -228.607112)
		(width 0.1143)
		(layer "In11.Cu")
		(net "P5E_CPU1_G1_TX_DN<10>")
	)
	(segment
		(start 101.62794 -245.78183)
		(end 101.65969 -245.800118)
		(width 0.1143)
		(layer "In11.Cu")
		(net "P5E_CPU1_G1_TX_DN<10>")
	)
	(segment
		(start 101.633782 -239.94364)
		(end 101.632258 -239.944402)
		(width 0.1143)
		(layer "In11.Cu")
		(net "P5E_CPU1_G1_TX_DN<10>")
	)
	(segment
		(start 101.65969 -246.408702)
		(end 101.634544 -246.42318)
		(width 0.1143)
		(layer "In11.Cu")
		(net "P5E_CPU1_G1_TX_DN<10>")
	)
	(segment
		(start 101.626924 -244.16131)
		(end 101.62794 -244.161818)
		(width 0.1143)
		(layer "In11.Cu")
		(net "P5E_CPU1_G1_TX_DN<10>")
	)
	(segment
		(start 101.625146 -232.82021)
		(end 101.626924 -232.821226)
		(width 0.1143)
		(layer "In11.Cu")
		(net "P5E_CPU1_G1_TX_DN<10>")
	)
	(segment
		(start 101.631496 -231.84485)
		(end 101.628702 -231.846374)
		(width 0.1143)
		(layer "In11.Cu")
		(net "P5E_CPU1_G1_TX_DN<10>")
	)
	(segment
		(start 101.628702 -234.442254)
		(end 101.629972 -234.443016)
		(width 0.1143)
		(layer "In11.Cu")
		(net "P5E_CPU1_G1_TX_DN<10>")
	)
	(segment
		(start 101.118924 -225.509074)
		(end 101.125782 -225.513138)
		(width 0.1143)
		(layer "In11.Cu")
		(net "P5E_CPU1_G1_TX_DN<10>")
	)
	(segment
		(start 101.628702 -239.946434)
		(end 101.62794 -239.946942)
		(width 0.1143)
		(layer "In11.Cu")
		(net "P5E_CPU1_G1_TX_DN<10>")
	)
	(segment
		(start 101.625146 -234.440222)
		(end 101.626924 -234.441238)
		(width 0.1143)
		(layer "In11.Cu")
		(net "P5E_CPU1_G1_TX_DN<10>")
	)
	(segment
		(start 101.15804 -225.531934)
		(end 101.158802 -225.532442)
		(width 0.1143)
		(layer "In11.Cu")
		(net "P5E_CPU1_G1_TX_DN<10>")
	)
	(segment
		(start 101.628702 -244.162326)
		(end 101.629972 -244.163088)
		(width 0.1143)
		(layer "In11.Cu")
		(net "P5E_CPU1_G1_TX_DN<10>")
	)
	(segment
		(start 101.155246 -225.53041)
		(end 101.157024 -225.531426)
		(width 0.1143)
		(layer "In11.Cu")
		(net "P5E_CPU1_G1_TX_DN<10>")
	)
	(segment
		(start 100.68814 -224.721928)
		(end 100.71862 -224.739708)
		(width 0.1143)
		(layer "In11.Cu")
		(net "P5E_CPU1_G1_TX_DN<10>")
	)
	(segment
		(start 101.151182 -225.52787)
		(end 101.152706 -225.528886)
		(width 0.1143)
		(layer "In11.Cu")
		(net "P5E_CPU1_G1_TX_DN<10>")
	)
	(segment
		(start 101.126544 -225.513646)
		(end 101.151182 -225.52787)
		(width 0.1143)
		(layer "In11.Cu")
		(net "P5E_CPU1_G1_TX_DN<10>")
	)
	(segment
		(start 101.628702 -241.566446)
		(end 101.62794 -241.566954)
		(width 0.1143)
		(layer "In11.Cu")
		(net "P5E_CPU1_G1_TX_DN<10>")
	)
	(segment
		(start 101.622606 -236.05871)
		(end 101.623622 -236.059218)
		(width 0.1143)
		(layer "In11.Cu")
		(net "P5E_CPU1_G1_TX_DN<10>")
	)
	(segment
		(start 101.626924 -239.94745)
		(end 101.588824 -239.969802)
		(width 0.1143)
		(layer "In11.Cu")
		(net "P5E_CPU1_G1_TX_DN<10>")
	)
	(segment
		(start 101.62794 -236.706918)
		(end 101.626924 -236.707426)
		(width 0.1143)
		(layer "In11.Cu")
		(net "P5E_CPU1_G1_TX_DN<10>")
	)
	(segment
		(start 101.628702 -232.822242)
		(end 101.629972 -232.823004)
		(width 0.1143)
		(layer "In11.Cu")
		(net "P5E_CPU1_G1_TX_DN<10>")
	)
	(segment
		(start 101.62794 -244.161818)
		(end 101.628702 -244.162326)
		(width 0.1143)
		(layer "In11.Cu")
		(net "P5E_CPU1_G1_TX_DN<10>")
	)
	(segment
		(start 101.588824 -232.798874)
		(end 101.595682 -232.802938)
		(width 0.1143)
		(layer "In11.Cu")
		(net "P5E_CPU1_G1_TX_DN<10>")
	)
	(segment
		(start 101.632258 -236.704378)
		(end 101.631496 -236.704886)
		(width 0.1143)
		(layer "In11.Cu")
		(net "P5E_CPU1_G1_TX_DN<10>")
	)
	(segment
		(start 101.626924 -239.301274)
		(end 101.62794 -239.301782)
		(width 0.1143)
		(layer "In11.Cu")
		(net "P5E_CPU1_G1_TX_DN<10>")
	)
	(segment
		(start 101.625146 -240.92027)
		(end 101.626924 -240.921286)
		(width 0.1143)
		(layer "In11.Cu")
		(net "P5E_CPU1_G1_TX_DN<10>")
	)
	(segment
		(start 29.794708 -20.264374)
		(end 43.543728 -45.669962)
		(width 0.14224)
		(layer "In11.Cu")
		(net "P5E_CPU1_G1_TX_DN<10>")
	)
	(segment
		(start 101.18852 -247.219216)
		(end 101.15804 -247.236996)
		(width 0.1143)
		(layer "In11.Cu")
		(net "P5E_CPU1_G1_TX_DN<10>")
	)
	(segment
		(start 101.62794 -240.921794)
		(end 101.628702 -240.922302)
		(width 0.1143)
		(layer "In11.Cu")
		(net "P5E_CPU1_G1_TX_DN<10>")
	)
	(segment
		(start 101.628702 -235.086398)
		(end 101.62794 -235.086906)
		(width 0.1143)
		(layer "In11.Cu")
		(net "P5E_CPU1_G1_TX_DN<10>")
	)
	(segment
		(start 101.595682 -234.42295)
		(end 101.596444 -234.423458)
		(width 0.1143)
		(layer "In11.Cu")
		(net "P5E_CPU1_G1_TX_DN<10>")
	)
	(segment
		(start 99.854258 -221.083378)
		(end 99.899978 -221.129098)
		(width 0.1143)
		(layer "In11.Cu")
		(net "P5E_CPU1_G1_TX_DN<10>")
	)
	(segment
		(start 101.596444 -244.14353)
		(end 101.621844 -244.158262)
		(width 0.1143)
		(layer "In11.Cu")
		(net "P5E_CPU1_G1_TX_DN<10>")
	)
	(segment
		(start 101.622606 -232.818686)
		(end 101.623622 -232.819194)
		(width 0.1143)
		(layer "In11.Cu")
		(net "P5E_CPU1_G1_TX_DN<10>")
	)
	(segment
		(start 101.634544 -243.183156)
		(end 101.633782 -243.183664)
		(width 0.1143)
		(layer "In11.Cu")
		(net "P5E_CPU1_G1_TX_DN<10>")
	)
	(segment
		(start 101.588824 -245.75897)
		(end 101.6254 -245.780306)
		(width 0.1143)
		(layer "In11.Cu")
		(net "P5E_CPU1_G1_TX_DN<10>")
	)
	(segment
		(start 149.557994 -159.975042)
		(end 149.557994 -163.188142)
		(width 0.14224)
		(layer "In11.Cu")
		(net "P5E_CPU1_G1_TX_DN<10>")
	)
	(arc
		(start 101.588824 -233.489754)
		(mid 101.345497 -233.95432)
		(end 101.588824 -234.418886)
		(width 0.1143)
		(layer "In11.Cu")
		(net "P5E_CPU1_G1_TX_DN<10>")
	)
	(arc
		(start 101.588824 -236.729778)
		(mid 101.345497 -237.194344)
		(end 101.588824 -237.65891)
		(width 0.1143)
		(layer "In11.Cu")
		(net "P5E_CPU1_G1_TX_DN<10>")
	)
	(arc
		(start 101.588824 -239.969802)
		(mid 101.345497 -240.434368)
		(end 101.588824 -240.898934)
		(width 0.1143)
		(layer "In11.Cu")
		(net "P5E_CPU1_G1_TX_DN<10>")
	)
	(arc
		(start 101.658674 -226.35972)
		(mid 101.815651 -226.66452)
		(end 101.658674 -226.96932)
		(width 0.1143)
		(layer "In11.Cu")
		(net "P5E_CPU1_G1_TX_DN<10>")
	)
	(arc
		(start 101.118924 -247.259856)
		(mid 100.966937 -247.416364)
		(end 100.885498 -247.618758)
		(width 0.1143)
		(layer "In11.Cu")
		(net "P5E_CPU1_G1_TX_DN<10>")
	)
	(arc
		(start 101.588824 -238.34979)
		(mid 101.345497 -238.814356)
		(end 101.588824 -239.278922)
		(width 0.1143)
		(layer "In11.Cu")
		(net "P5E_CPU1_G1_TX_DN<10>")
	)
	(arc
		(start 101.591364 -230.248206)
		(mid 101.410712 -230.450951)
		(end 101.345492 -230.71455)
		(width 0.1143)
		(layer "In11.Cu")
		(net "P5E_CPU1_G1_TX_DN<10>")
	)
	(arc
		(start 101.65969 -240.940082)
		(mid 101.815618 -241.244374)
		(end 101.65969 -241.548666)
		(width 0.1143)
		(layer "In11.Cu")
		(net "P5E_CPU1_G1_TX_DN<10>")
	)
	(arc
		(start 101.589078 -228.629972)
		(mid 101.345751 -229.094538)
		(end 101.589078 -229.559104)
		(width 0.1143)
		(layer "In11.Cu")
		(net "P5E_CPU1_G1_TX_DN<10>")
	)
	(arc
		(start 101.65969 -239.32007)
		(mid 101.815618 -239.624362)
		(end 101.65969 -239.928654)
		(width 0.1143)
		(layer "In11.Cu")
		(net "P5E_CPU1_G1_TX_DN<10>")
	)
	(arc
		(start 101.65969 -242.560094)
		(mid 101.815618 -242.864386)
		(end 101.65969 -243.168678)
		(width 0.1143)
		(layer "In11.Cu")
		(net "P5E_CPU1_G1_TX_DN<10>")
	)
	(arc
		(start 101.588824 -241.589814)
		(mid 101.345497 -242.05438)
		(end 101.588824 -242.518946)
		(width 0.1143)
		(layer "In11.Cu")
		(net "P5E_CPU1_G1_TX_DN<10>")
	)
	(arc
		(start 101.18979 -225.550222)
		(mid 101.304466 -225.683556)
		(end 101.345746 -225.854514)
		(width 0.1143)
		(layer "In11.Cu")
		(net "P5E_CPU1_G1_TX_DN<10>")
	)
	(arc
		(start 101.588824 -231.869742)
		(mid 101.345497 -232.334308)
		(end 101.588824 -232.798874)
		(width 0.1143)
		(layer "In11.Cu")
		(net "P5E_CPU1_G1_TX_DN<10>")
	)
	(arc
		(start 101.65969 -244.180106)
		(mid 101.815618 -244.484398)
		(end 101.65969 -244.78869)
		(width 0.1143)
		(layer "In11.Cu")
		(net "P5E_CPU1_G1_TX_DN<10>")
	)
	(arc
		(start 101.589078 -227.00996)
		(mid 101.345751 -227.474526)
		(end 101.589078 -227.939092)
		(width 0.1143)
		(layer "In11.Cu")
		(net "P5E_CPU1_G1_TX_DN<10>")
	)
	(arc
		(start 101.815646 -229.90429)
		(mid 101.774391 -230.075261)
		(end 101.65969 -230.208582)
		(width 0.1143)
		(layer "In11.Cu")
		(net "P5E_CPU1_G1_TX_DN<10>")
	)
	(arc
		(start 100.249736 -222.310198)
		(mid 100.364412 -222.443532)
		(end 100.405692 -222.61449)
		(width 0.1143)
		(layer "In11.Cu")
		(net "P5E_CPU1_G1_TX_DN<10>")
	)
	(arc
		(start 101.345492 -230.71455)
		(mid 101.410007 -230.976769)
		(end 101.588824 -231.179116)
		(width 0.1143)
		(layer "In11.Cu")
		(net "P5E_CPU1_G1_TX_DN<10>")
	)
	(arc
		(start 101.65969 -236.080046)
		(mid 101.815618 -236.384338)
		(end 101.65969 -236.68863)
		(width 0.1143)
		(layer "In11.Cu")
		(net "P5E_CPU1_G1_TX_DN<10>")
	)
	(arc
		(start 101.815646 -231.524302)
		(mid 101.774391 -231.695273)
		(end 101.65969 -231.828594)
		(width 0.1143)
		(layer "In11.Cu")
		(net "P5E_CPU1_G1_TX_DN<10>")
	)
	(arc
		(start 100.875592 -225.044508)
		(mid 100.940107 -225.306727)
		(end 101.118924 -225.509074)
		(width 0.1143)
		(layer "In11.Cu")
		(net "P5E_CPU1_G1_TX_DN<10>")
	)
	(arc
		(start 99.935792 -221.804484)
		(mid 100.000451 -222.067041)
		(end 100.179632 -222.269558)
		(width 0.1143)
		(layer "In11.Cu")
		(net "P5E_CPU1_G1_TX_DN<10>")
	)
	(arc
		(start 101.658674 -227.979732)
		(mid 101.815651 -228.284532)
		(end 101.658674 -228.589332)
		(width 0.1143)
		(layer "In11.Cu")
		(net "P5E_CPU1_G1_TX_DN<10>")
	)
	(arc
		(start 101.345746 -225.854514)
		(mid 101.410261 -226.116733)
		(end 101.589078 -226.31908)
		(width 0.1143)
		(layer "In11.Cu")
		(net "P5E_CPU1_G1_TX_DN<10>")
	)
	(arc
		(start 100.71862 -224.739708)
		(mid 100.834047 -224.873084)
		(end 100.875592 -225.044508)
		(width 0.1143)
		(layer "In11.Cu")
		(net "P5E_CPU1_G1_TX_DN<10>")
	)
	(arc
		(start 100.649024 -223.769936)
		(mid 100.405697 -224.234502)
		(end 100.649024 -224.699068)
		(width 0.1143)
		(layer "In11.Cu")
		(net "P5E_CPU1_G1_TX_DN<10>")
	)
	(arc
		(start 101.65969 -237.700058)
		(mid 101.815618 -238.00435)
		(end 101.65969 -238.308642)
		(width 0.1143)
		(layer "In11.Cu")
		(net "P5E_CPU1_G1_TX_DN<10>")
	)
	(arc
		(start 100.885498 -247.618758)
		(mid 100.883475 -247.630168)
		(end 100.881688 -247.641618)
		(width 0.1143)
		(layer "In11.Cu")
		(net "P5E_CPU1_G1_TX_DN<10>")
	)
	(arc
		(start 101.65969 -232.840022)
		(mid 101.815618 -233.144314)
		(end 101.65969 -233.448606)
		(width 0.1143)
		(layer "In11.Cu")
		(net "P5E_CPU1_G1_TX_DN<10>")
	)
	(arc
		(start 101.588824 -244.829838)
		(mid 101.345497 -245.294404)
		(end 101.588824 -245.75897)
		(width 0.1143)
		(layer "In11.Cu")
		(net "P5E_CPU1_G1_TX_DN<10>")
	)
	(arc
		(start 101.660706 -229.60076)
		(mid 101.774635 -229.733907)
		(end 101.815646 -229.90429)
		(width 0.1143)
		(layer "In11.Cu")
		(net "P5E_CPU1_G1_TX_DN<10>")
	)
	(arc
		(start 101.661468 -231.221534)
		(mid 101.774875 -231.354423)
		(end 101.815646 -231.524302)
		(width 0.1143)
		(layer "In11.Cu")
		(net "P5E_CPU1_G1_TX_DN<10>")
	)
	(arc
		(start 101.345492 -246.914416)
		(mid 101.303943 -247.085838)
		(end 101.18852 -247.219216)
		(width 0.1143)
		(layer "In11.Cu")
		(net "P5E_CPU1_G1_TX_DN<10>")
	)
	(arc
		(start 101.588824 -235.109766)
		(mid 101.345497 -235.574332)
		(end 101.588824 -236.038898)
		(width 0.1143)
		(layer "In11.Cu")
		(net "P5E_CPU1_G1_TX_DN<10>")
	)
	(arc
		(start 100.71862 -223.119696)
		(mid 100.875597 -223.424496)
		(end 100.71862 -223.729296)
		(width 0.1143)
		(layer "In11.Cu")
		(net "P5E_CPU1_G1_TX_DN<10>")
	)
	(arc
		(start 100.405692 -222.61449)
		(mid 100.470207 -222.876709)
		(end 100.649024 -223.079056)
		(width 0.1143)
		(layer "In11.Cu")
		(net "P5E_CPU1_G1_TX_DN<10>")
	)
	(arc
		(start 101.65969 -234.460034)
		(mid 101.815618 -234.764326)
		(end 101.65969 -235.068618)
		(width 0.1143)
		(layer "In11.Cu")
		(net "P5E_CPU1_G1_TX_DN<10>")
	)
	(arc
		(start 101.65969 -245.800118)
		(mid 101.815618 -246.10441)
		(end 101.65969 -246.408702)
		(width 0.1143)
		(layer "In11.Cu")
		(net "P5E_CPU1_G1_TX_DN<10>")
	)
	(arc
		(start 101.588824 -246.44985)
		(mid 101.410011 -246.6522)
		(end 101.345492 -246.914416)
		(width 0.1143)
		(layer "In11.Cu")
		(net "P5E_CPU1_G1_TX_DN<10>")
	)
	(arc
		(start 101.588824 -243.209826)
		(mid 101.345497 -243.674392)
		(end 101.588824 -244.138958)
		(width 0.1143)
		(layer "In11.Cu")
		(net "P5E_CPU1_G1_TX_DN<10>")
	)
	(segment
		(start 57.75833 -17.890236)
		(end 58.05424 -18.186146)
		(width 0.12954)
		(layer "F.Cu")
		(net "P5E_CPU1_G1_TX_DN<0>")
	)
	(segment
		(start 108.957872 -248.800366)
		(end 108.49102 -248.534428)
		(width 0.12954)
		(layer "F.Cu")
		(net "P5E_CPU1_G1_TX_DN<0>")
	)
	(segment
		(start 58.05424 -18.86585)
		(end 57.78373 -19.13636)
		(width 0.12954)
		(layer "F.Cu")
		(net "P5E_CPU1_G1_TX_DN<0>")
	)
	(segment
		(start 58.05424 -18.186146)
		(end 58.05424 -18.86585)
		(width 0.12954)
		(layer "F.Cu")
		(net "P5E_CPU1_G1_TX_DN<0>")
	)
	(segment
		(start 109.624368 -247.23344)
		(end 109.622336 -247.234456)
		(width 0.1143)
		(layer "In11.Cu")
		(net "P5E_CPU1_G1_TX_DN<0>")
	)
	(segment
		(start 110.724442 -245.744238)
		(end 110.724442 -245.808246)
		(width 0.1143)
		(layer "In11.Cu")
		(net "P5E_CPU1_G1_TX_DN<0>")
	)
	(segment
		(start 152.914858 -134.22249)
		(end 158.133034 -145.10385)
		(width 0.14224)
		(layer "In11.Cu")
		(net "P5E_CPU1_G1_TX_DN<0>")
	)
	(segment
		(start 129.57175 -113.231422)
		(end 129.57175 -113.231676)
		(width 0.14224)
		(layer "In11.Cu")
		(net "P5E_CPU1_G1_TX_DN<0>")
	)
	(segment
		(start 110.088172 -246.42699)
		(end 110.049056 -246.44985)
		(width 0.1143)
		(layer "In11.Cu")
		(net "P5E_CPU1_G1_TX_DN<0>")
	)
	(segment
		(start 109.147102 -248.04751)
		(end 109.109002 -248.069862)
		(width 0.1143)
		(layer "In11.Cu")
		(net "P5E_CPU1_G1_TX_DN<0>")
	)
	(segment
		(start 158.98241 -164.943028)
		(end 156.564838 -172.03928)
		(width 0.14224)
		(layer "In11.Cu")
		(net "P5E_CPU1_G1_TX_DN<0>")
	)
	(segment
		(start 110.30585 -216.037668)
		(end 110.30585 -220.632274)
		(width 0.14224)
		(layer "In11.Cu")
		(net "P5E_CPU1_G1_TX_DN<0>")
	)
	(segment
		(start 108.788962 -248.534428)
		(end 108.49102 -248.534428)
		(width 0.1143)
		(layer "In11.Cu")
		(net "P5E_CPU1_G1_TX_DN<0>")
	)
	(segment
		(start 109.621574 -247.234964)
		(end 109.61878 -247.236488)
		(width 0.1143)
		(layer "In11.Cu")
		(net "P5E_CPU1_G1_TX_DN<0>")
	)
	(segment
		(start 129.57175 -113.231676)
		(end 152.914858 -134.22249)
		(width 0.14224)
		(layer "In11.Cu")
		(net "P5E_CPU1_G1_TX_DN<0>")
	)
	(segment
		(start 109.179868 -248.028714)
		(end 109.14888 -248.046494)
		(width 0.1143)
		(layer "In11.Cu")
		(net "P5E_CPU1_G1_TX_DN<0>")
	)
	(segment
		(start 156.228034 -172.955458)
		(end 152.73147 -177.87239)
		(width 0.14224)
		(layer "In11.Cu")
		(net "P5E_CPU1_G1_TX_DN<0>")
	)
	(segment
		(start 57.78373 -19.13636)
		(end 58.07456 -19.42719)
		(width 0.14224)
		(layer "In11.Cu")
		(net "P5E_CPU1_G1_TX_DN<0>")
	)
	(segment
		(start 58.07456 -19.42719)
		(end 58.07456 -29.019754)
		(width 0.14224)
		(layer "In11.Cu")
		(net "P5E_CPU1_G1_TX_DN<0>")
	)
	(segment
		(start 110.87227 -245.59641)
		(end 110.744508 -245.724172)
		(width 0.14224)
		(layer "In11.Cu")
		(net "P5E_CPU1_G1_TX_DN<0>")
	)
	(segment
		(start 106.698288 -92.662756)
		(end 129.57175 -113.231422)
		(width 0.14224)
		(layer "In11.Cu")
		(net "P5E_CPU1_G1_TX_DN<0>")
	)
	(segment
		(start 158.147766 -146.336258)
		(end 158.98241 -159.67075)
		(width 0.14224)
		(layer "In11.Cu")
		(net "P5E_CPU1_G1_TX_DN<0>")
	)
	(segment
		(start 158.133034 -145.10385)
		(end 158.147766 -145.368518)
		(width 0.14224)
		(layer "In11.Cu")
		(net "P5E_CPU1_G1_TX_DN<0>")
	)
	(segment
		(start 114.214148 -209.455258)
		(end 110.306104 -216.037414)
		(width 0.14224)
		(layer "In11.Cu")
		(net "P5E_CPU1_G1_TX_DN<0>")
	)
	(segment
		(start 109.61751 -247.23725)
		(end 109.581696 -247.258078)
		(width 0.1143)
		(layer "In11.Cu")
		(net "P5E_CPU1_G1_TX_DN<0>")
	)
	(segment
		(start 110.87227 -222.84182)
		(end 110.87227 -245.59641)
		(width 0.14224)
		(layer "In11.Cu")
		(net "P5E_CPU1_G1_TX_DN<0>")
	)
	(segment
		(start 156.564838 -172.03928)
		(end 156.228034 -172.955458)
		(width 0.14224)
		(layer "In11.Cu")
		(net "P5E_CPU1_G1_TX_DN<0>")
	)
	(segment
		(start 152.73147 -177.87239)
		(end 114.214148 -209.455258)
		(width 0.14224)
		(layer "In11.Cu")
		(net "P5E_CPU1_G1_TX_DN<0>")
	)
	(segment
		(start 109.14888 -248.046494)
		(end 109.148118 -248.047002)
		(width 0.1143)
		(layer "In11.Cu")
		(net "P5E_CPU1_G1_TX_DN<0>")
	)
	(segment
		(start 109.61878 -247.236488)
		(end 109.618018 -247.236996)
		(width 0.1143)
		(layer "In11.Cu")
		(net "P5E_CPU1_G1_TX_DN<0>")
	)
	(segment
		(start 108.871766 -248.451624)
		(end 108.788962 -248.534428)
		(width 0.1143)
		(layer "In11.Cu")
		(net "P5E_CPU1_G1_TX_DN<0>")
	)
	(segment
		(start 110.744508 -245.724172)
		(end 110.724442 -245.744238)
		(width 0.1143)
		(layer "In11.Cu")
		(net "P5E_CPU1_G1_TX_DN<0>")
	)
	(segment
		(start 110.30585 -220.632274)
		(end 110.306104 -220.632528)
		(width 0.14224)
		(layer "In11.Cu")
		(net "P5E_CPU1_G1_TX_DN<0>")
	)
	(segment
		(start 60.300362 -50.94097)
		(end 106.698288 -92.663264)
		(width 0.14224)
		(layer "In11.Cu")
		(net "P5E_CPU1_G1_TX_DN<0>")
	)
	(segment
		(start 106.698288 -92.663264)
		(end 106.698288 -92.662756)
		(width 0.14224)
		(layer "In11.Cu")
		(net "P5E_CPU1_G1_TX_DN<0>")
	)
	(segment
		(start 158.98241 -159.67075)
		(end 158.98241 -164.943028)
		(width 0.14224)
		(layer "In11.Cu")
		(net "P5E_CPU1_G1_TX_DN<0>")
	)
	(segment
		(start 109.618018 -247.236996)
		(end 109.61751 -247.23725)
		(width 0.1143)
		(layer "In11.Cu")
		(net "P5E_CPU1_G1_TX_DN<0>")
	)
	(segment
		(start 58.07456 -29.019754)
		(end 58.882534 -48.15332)
		(width 0.14224)
		(layer "In11.Cu")
		(net "P5E_CPU1_G1_TX_DN<0>")
	)
	(segment
		(start 109.649768 -247.218708)
		(end 109.624368 -247.23344)
		(width 0.1143)
		(layer "In11.Cu")
		(net "P5E_CPU1_G1_TX_DN<0>")
	)
	(segment
		(start 158.147766 -145.368518)
		(end 158.147766 -146.336258)
		(width 0.14224)
		(layer "In11.Cu")
		(net "P5E_CPU1_G1_TX_DN<0>")
	)
	(segment
		(start 58.882534 -48.15332)
		(end 60.300362 -50.94097)
		(width 0.14224)
		(layer "In11.Cu")
		(net "P5E_CPU1_G1_TX_DN<0>")
	)
	(segment
		(start 110.724442 -245.808246)
		(end 110.164626 -246.368062)
		(width 0.1143)
		(layer "In11.Cu")
		(net "P5E_CPU1_G1_TX_DN<0>")
	)
	(segment
		(start 109.622336 -247.234456)
		(end 109.621574 -247.234964)
		(width 0.1143)
		(layer "In11.Cu")
		(net "P5E_CPU1_G1_TX_DN<0>")
	)
	(segment
		(start 110.306104 -221.474792)
		(end 110.87227 -222.84182)
		(width 0.14224)
		(layer "In11.Cu")
		(net "P5E_CPU1_G1_TX_DN<0>")
	)
	(segment
		(start 110.306104 -216.037414)
		(end 110.30585 -216.037668)
		(width 0.14224)
		(layer "In11.Cu")
		(net "P5E_CPU1_G1_TX_DN<0>")
	)
	(segment
		(start 110.306104 -220.632528)
		(end 110.306104 -221.474792)
		(width 0.14224)
		(layer "In11.Cu")
		(net "P5E_CPU1_G1_TX_DN<0>")
	)
	(segment
		(start 109.148118 -248.047002)
		(end 109.147102 -248.04751)
		(width 0.1143)
		(layer "In11.Cu")
		(net "P5E_CPU1_G1_TX_DN<0>")
	)
	(arc
		(start 109.554772 -247.278398)
		(mid 109.411432 -247.461737)
		(end 109.33938 -247.68302)
		(width 0.1143)
		(layer "In11.Cu")
		(net "P5E_CPU1_G1_TX_DN<0>")
	)
	(arc
		(start 110.049056 -246.44985)
		(mid 109.870243 -246.6522)
		(end 109.805724 -246.914416)
		(width 0.1143)
		(layer "In11.Cu")
		(net "P5E_CPU1_G1_TX_DN<0>")
	)
	(arc
		(start 110.164626 -246.368062)
		(mid 110.128311 -246.400006)
		(end 110.088172 -246.42699)
		(width 0.1143)
		(layer "In11.Cu")
		(net "P5E_CPU1_G1_TX_DN<0>")
	)
	(arc
		(start 108.875576 -248.428764)
		(mid 108.873553 -248.440174)
		(end 108.871766 -248.451624)
		(width 0.1143)
		(layer "In11.Cu")
		(net "P5E_CPU1_G1_TX_DN<0>")
	)
	(arc
		(start 109.581696 -247.258078)
		(mid 109.568083 -247.268038)
		(end 109.554772 -247.278398)
		(width 0.1143)
		(layer "In11.Cu")
		(net "P5E_CPU1_G1_TX_DN<0>")
	)
	(arc
		(start 109.33557 -247.725438)
		(mid 109.291326 -247.894315)
		(end 109.179868 -248.028714)
		(width 0.1143)
		(layer "In11.Cu")
		(net "P5E_CPU1_G1_TX_DN<0>")
	)
	(arc
		(start 109.33938 -247.68302)
		(mid 109.33695 -247.704182)
		(end 109.33557 -247.725438)
		(width 0.1143)
		(layer "In11.Cu")
		(net "P5E_CPU1_G1_TX_DN<0>")
	)
	(arc
		(start 109.109002 -248.069862)
		(mid 108.957015 -248.22637)
		(end 108.875576 -248.428764)
		(width 0.1143)
		(layer "In11.Cu")
		(net "P5E_CPU1_G1_TX_DN<0>")
	)
	(arc
		(start 109.805724 -246.914416)
		(mid 109.764469 -247.085387)
		(end 109.649768 -247.218708)
		(width 0.1143)
		(layer "In11.Cu")
		(net "P5E_CPU1_G1_TX_DN<0>")
	)
	(segment
		(start 30.408372 -12.019788)
		(end 30.547056 -11.881104)
		(width 0.12954)
		(layer "F.Cu")
		(net "P5E_CPU1_G1_TX_C_DP<9>")
	)
	(segment
		(start 30.710886 -12.992862)
		(end 30.617414 -12.852908)
		(width 0.12954)
		(layer "F.Cu")
		(net "P5E_CPU1_G1_TX_C_DP<9>")
	)
	(segment
		(start 32.890968 -15.310358)
		(end 32.793432 -15.075154)
		(width 0.12954)
		(layer "F.Cu")
		(net "P5E_CPU1_G1_TX_C_DP<9>")
	)
	(segment
		(start 32.793432 -15.075154)
		(end 30.710886 -12.992862)
		(width 0.12954)
		(layer "F.Cu")
		(net "P5E_CPU1_G1_TX_C_DP<9>")
	)
	(segment
		(start 33.186878 -15.832836)
		(end 32.890968 -15.536926)
		(width 0.12954)
		(layer "F.Cu")
		(net "P5E_CPU1_G1_TX_C_DP<9>")
	)
	(segment
		(start 30.547056 -11.881104)
		(end 30.547056 -11.26998)
		(width 0.12954)
		(layer "F.Cu")
		(net "P5E_CPU1_G1_TX_C_DP<9>")
	)
	(segment
		(start 32.890968 -15.536926)
		(end 32.890968 -15.310358)
		(width 0.12954)
		(layer "F.Cu")
		(net "P5E_CPU1_G1_TX_C_DP<9>")
	)
	(segment
		(start 30.617414 -12.852908)
		(end 30.408372 -12.348718)
		(width 0.12954)
		(layer "F.Cu")
		(net "P5E_CPU1_G1_TX_C_DP<9>")
	)
	(segment
		(start 30.408372 -12.348718)
		(end 30.408372 -12.019788)
		(width 0.12954)
		(layer "F.Cu")
		(net "P5E_CPU1_G1_TX_C_DP<9>")
	)
	(segment
		(start 35.613594 -16.558768)
		(end 34.971228 -15.59687)
		(width 0.12954)
		(layer "F.Cu")
		(net "P5E_CPU1_G1_TX_C_DP<8>")
	)
	(segment
		(start 33.98774 -14.397228)
		(end 32.425386 -12.832842)
		(width 0.12954)
		(layer "F.Cu")
		(net "P5E_CPU1_G1_TX_C_DP<8>")
	)
	(segment
		(start 32.208216 -12.30757)
		(end 32.208216 -12.019788)
		(width 0.12954)
		(layer "F.Cu")
		(net "P5E_CPU1_G1_TX_C_DP<8>")
	)
	(segment
		(start 32.3469 -11.881104)
		(end 32.3469 -11.26998)
		(width 0.12954)
		(layer "F.Cu")
		(net "P5E_CPU1_G1_TX_C_DP<8>")
	)
	(segment
		(start 35.980878 -17.356836)
		(end 35.684968 -17.060926)
		(width 0.12954)
		(layer "F.Cu")
		(net "P5E_CPU1_G1_TX_C_DP<8>")
	)
	(segment
		(start 35.684968 -16.793972)
		(end 35.613594 -16.558768)
		(width 0.12954)
		(layer "F.Cu")
		(net "P5E_CPU1_G1_TX_C_DP<8>")
	)
	(segment
		(start 32.208216 -12.019788)
		(end 32.3469 -11.881104)
		(width 0.12954)
		(layer "F.Cu")
		(net "P5E_CPU1_G1_TX_C_DP<8>")
	)
	(segment
		(start 32.425386 -12.832842)
		(end 32.208216 -12.30757)
		(width 0.12954)
		(layer "F.Cu")
		(net "P5E_CPU1_G1_TX_C_DP<8>")
	)
	(segment
		(start 34.971228 -15.59687)
		(end 33.98774 -14.397228)
		(width 0.12954)
		(layer "F.Cu")
		(net "P5E_CPU1_G1_TX_C_DP<8>")
	)
	(segment
		(start 35.684968 -17.060926)
		(end 35.684968 -16.793972)
		(width 0.12954)
		(layer "F.Cu")
		(net "P5E_CPU1_G1_TX_C_DP<8>")
	)
	(segment
		(start 39.518336 -12.443714)
		(end 39.518336 -12.019788)
		(width 0.12954)
		(layer "F.Cu")
		(net "P5E_CPU1_G1_TX_C_DP<7>")
	)
	(segment
		(start 38.478968 -15.097506)
		(end 38.53434 -14.819376)
		(width 0.12954)
		(layer "F.Cu")
		(net "P5E_CPU1_G1_TX_C_DP<7>")
	)
	(segment
		(start 39.518336 -12.019788)
		(end 39.65702 -11.881104)
		(width 0.12954)
		(layer "F.Cu")
		(net "P5E_CPU1_G1_TX_C_DP<7>")
	)
	(segment
		(start 39.65702 -11.881104)
		(end 39.65702 -11.26998)
		(width 0.12954)
		(layer "F.Cu")
		(net "P5E_CPU1_G1_TX_C_DP<7>")
	)
	(segment
		(start 38.774878 -15.832836)
		(end 38.478968 -15.536926)
		(width 0.12954)
		(layer "F.Cu")
		(net "P5E_CPU1_G1_TX_C_DP<7>")
	)
	(segment
		(start 38.53434 -14.819376)
		(end 39.518336 -12.443714)
		(width 0.12954)
		(layer "F.Cu")
		(net "P5E_CPU1_G1_TX_C_DP<7>")
	)
	(segment
		(start 38.478968 -15.536926)
		(end 38.478968 -15.097506)
		(width 0.12954)
		(layer "F.Cu")
		(net "P5E_CPU1_G1_TX_C_DP<7>")
	)
	(segment
		(start 41.31818 -12.019788)
		(end 41.456864 -11.881104)
		(width 0.12954)
		(layer "F.Cu")
		(net "P5E_CPU1_G1_TX_C_DP<6>")
	)
	(segment
		(start 41.578784 -17.060926)
		(end 41.578784 -15.877032)
		(width 0.12954)
		(layer "F.Cu")
		(net "P5E_CPU1_G1_TX_C_DP<6>")
	)
	(segment
		(start 41.874694 -17.356836)
		(end 41.578784 -17.060926)
		(width 0.12954)
		(layer "F.Cu")
		(net "P5E_CPU1_G1_TX_C_DP<6>")
	)
	(segment
		(start 41.456864 -11.881104)
		(end 41.456864 -11.26998)
		(width 0.12954)
		(layer "F.Cu")
		(net "P5E_CPU1_G1_TX_C_DP<6>")
	)
	(segment
		(start 41.31818 -13.230352)
		(end 41.31818 -12.019788)
		(width 0.12954)
		(layer "F.Cu")
		(net "P5E_CPU1_G1_TX_C_DP<6>")
	)
	(segment
		(start 41.578784 -15.877032)
		(end 41.31818 -13.230352)
		(width 0.12954)
		(layer "F.Cu")
		(net "P5E_CPU1_G1_TX_C_DP<6>")
	)
	(segment
		(start 43.503596 -13.470636)
		(end 43.118278 -12.540488)
		(width 0.12954)
		(layer "F.Cu")
		(net "P5E_CPU1_G1_TX_C_DP<5>")
	)
	(segment
		(start 43.118278 -12.019788)
		(end 43.256962 -11.881104)
		(width 0.12954)
		(layer "F.Cu")
		(net "P5E_CPU1_G1_TX_C_DP<5>")
	)
	(segment
		(start 44.2214 -14.81328)
		(end 43.503596 -13.470636)
		(width 0.12954)
		(layer "F.Cu")
		(net "P5E_CPU1_G1_TX_C_DP<5>")
	)
	(segment
		(start 43.256962 -11.881104)
		(end 43.256962 -11.26998)
		(width 0.12954)
		(layer "F.Cu")
		(net "P5E_CPU1_G1_TX_C_DP<5>")
	)
	(segment
		(start 43.118278 -12.540488)
		(end 43.118278 -12.019788)
		(width 0.12954)
		(layer "F.Cu")
		(net "P5E_CPU1_G1_TX_C_DP<5>")
	)
	(segment
		(start 44.668694 -15.832836)
		(end 44.372784 -15.536926)
		(width 0.12954)
		(layer "F.Cu")
		(net "P5E_CPU1_G1_TX_C_DP<5>")
	)
	(segment
		(start 44.372784 -15.312644)
		(end 44.2214 -14.81328)
		(width 0.12954)
		(layer "F.Cu")
		(net "P5E_CPU1_G1_TX_C_DP<5>")
	)
	(segment
		(start 44.372784 -15.536926)
		(end 44.372784 -15.312644)
		(width 0.12954)
		(layer "F.Cu")
		(net "P5E_CPU1_G1_TX_C_DP<5>")
	)
	(segment
		(start 45.06595 -12.990576)
		(end 44.918376 -12.431014)
		(width 0.12954)
		(layer "F.Cu")
		(net "P5E_CPU1_G1_TX_C_DP<4>")
	)
	(segment
		(start 47.166784 -16.698722)
		(end 45.06595 -12.990576)
		(width 0.12954)
		(layer "F.Cu")
		(net "P5E_CPU1_G1_TX_C_DP<4>")
	)
	(segment
		(start 45.05706 -11.881104)
		(end 45.05706 -11.26998)
		(width 0.12954)
		(layer "F.Cu")
		(net "P5E_CPU1_G1_TX_C_DP<4>")
	)
	(segment
		(start 47.462694 -17.356836)
		(end 47.166784 -17.060926)
		(width 0.12954)
		(layer "F.Cu")
		(net "P5E_CPU1_G1_TX_C_DP<4>")
	)
	(segment
		(start 47.166784 -17.060926)
		(end 47.166784 -16.698722)
		(width 0.12954)
		(layer "F.Cu")
		(net "P5E_CPU1_G1_TX_C_DP<4>")
	)
	(segment
		(start 44.918376 -12.019788)
		(end 45.05706 -11.881104)
		(width 0.12954)
		(layer "F.Cu")
		(net "P5E_CPU1_G1_TX_C_DP<4>")
	)
	(segment
		(start 44.918376 -12.431014)
		(end 44.918376 -12.019788)
		(width 0.12954)
		(layer "F.Cu")
		(net "P5E_CPU1_G1_TX_C_DP<4>")
	)
	(segment
		(start 50.56251 -13.25372)
		(end 50.728372 -12.419838)
		(width 0.12954)
		(layer "F.Cu")
		(net "P5E_CPU1_G1_TX_C_DP<3>")
	)
	(segment
		(start 50.728372 -12.419838)
		(end 50.728372 -12.019788)
		(width 0.12954)
		(layer "F.Cu")
		(net "P5E_CPU1_G1_TX_C_DP<3>")
	)
	(segment
		(start 49.99609 -14.621256)
		(end 50.56251 -13.25372)
		(width 0.12954)
		(layer "F.Cu")
		(net "P5E_CPU1_G1_TX_C_DP<3>")
	)
	(segment
		(start 50.256694 -15.832836)
		(end 49.960784 -15.536926)
		(width 0.12954)
		(layer "F.Cu")
		(net "P5E_CPU1_G1_TX_C_DP<3>")
	)
	(segment
		(start 50.728372 -12.019788)
		(end 50.867056 -11.881104)
		(width 0.12954)
		(layer "F.Cu")
		(net "P5E_CPU1_G1_TX_C_DP<3>")
	)
	(segment
		(start 49.960784 -14.799056)
		(end 49.99609 -14.621256)
		(width 0.12954)
		(layer "F.Cu")
		(net "P5E_CPU1_G1_TX_C_DP<3>")
	)
	(segment
		(start 49.960784 -15.536926)
		(end 49.960784 -14.799056)
		(width 0.12954)
		(layer "F.Cu")
		(net "P5E_CPU1_G1_TX_C_DP<3>")
	)
	(segment
		(start 50.867056 -11.881104)
		(end 50.867056 -11.26998)
		(width 0.12954)
		(layer "F.Cu")
		(net "P5E_CPU1_G1_TX_C_DP<3>")
	)
	(segment
		(start 52.528216 -12.019788)
		(end 52.6669 -11.881104)
		(width 0.12954)
		(layer "F.Cu")
		(net "P5E_CPU1_G1_TX_C_DP<2>")
	)
	(segment
		(start 52.78882 -16.29029)
		(end 52.528216 -13.64361)
		(width 0.12954)
		(layer "F.Cu")
		(net "P5E_CPU1_G1_TX_C_DP<2>")
	)
	(segment
		(start 53.08473 -17.356836)
		(end 52.78882 -17.060926)
		(width 0.12954)
		(layer "F.Cu")
		(net "P5E_CPU1_G1_TX_C_DP<2>")
	)
	(segment
		(start 52.6669 -11.881104)
		(end 52.6669 -11.26998)
		(width 0.12954)
		(layer "F.Cu")
		(net "P5E_CPU1_G1_TX_C_DP<2>")
	)
	(segment
		(start 52.528216 -13.64361)
		(end 52.528216 -12.019788)
		(width 0.12954)
		(layer "F.Cu")
		(net "P5E_CPU1_G1_TX_C_DP<2>")
	)
	(segment
		(start 52.78882 -17.060926)
		(end 52.78882 -16.29029)
		(width 0.12954)
		(layer "F.Cu")
		(net "P5E_CPU1_G1_TX_C_DP<2>")
	)
	(segment
		(start 54.466998 -11.881104)
		(end 54.466998 -11.26998)
		(width 0.12954)
		(layer "F.Cu")
		(net "P5E_CPU1_G1_TX_C_DP<1>")
	)
	(segment
		(start 55.58282 -15.536926)
		(end 55.58282 -15.282672)
		(width 0.12954)
		(layer "F.Cu")
		(net "P5E_CPU1_G1_TX_C_DP<1>")
	)
	(segment
		(start 54.328314 -12.019788)
		(end 54.466998 -11.881104)
		(width 0.12954)
		(layer "F.Cu")
		(net "P5E_CPU1_G1_TX_C_DP<1>")
	)
	(segment
		(start 54.352698 -12.322302)
		(end 54.328314 -12.20089)
		(width 0.12954)
		(layer "F.Cu")
		(net "P5E_CPU1_G1_TX_C_DP<1>")
	)
	(segment
		(start 55.87873 -15.832836)
		(end 55.58282 -15.536926)
		(width 0.12954)
		(layer "F.Cu")
		(net "P5E_CPU1_G1_TX_C_DP<1>")
	)
	(segment
		(start 54.328314 -12.20089)
		(end 54.328314 -12.019788)
		(width 0.12954)
		(layer "F.Cu")
		(net "P5E_CPU1_G1_TX_C_DP<1>")
	)
	(segment
		(start 55.58282 -15.282672)
		(end 54.352698 -12.322302)
		(width 0.12954)
		(layer "F.Cu")
		(net "P5E_CPU1_G1_TX_C_DP<1>")
	)
	(segment
		(start 16.434562 -14.991334)
		(end 18.818098 -13.3985)
		(width 0.12954)
		(layer "F.Cu")
		(net "P5E_CPU1_G1_TX_C_DP<15>")
	)
	(segment
		(start 19.608292 -12.019788)
		(end 19.746976 -11.881104)
		(width 0.12954)
		(layer "F.Cu")
		(net "P5E_CPU1_G1_TX_C_DP<15>")
	)
	(segment
		(start 16.126968 -15.437104)
		(end 16.225012 -15.200884)
		(width 0.12954)
		(layer "F.Cu")
		(net "P5E_CPU1_G1_TX_C_DP<15>")
	)
	(segment
		(start 19.608292 -12.27201)
		(end 19.608292 -12.019788)
		(width 0.12954)
		(layer "F.Cu")
		(net "P5E_CPU1_G1_TX_C_DP<15>")
	)
	(segment
		(start 16.225012 -15.200884)
		(end 16.434562 -14.991334)
		(width 0.12954)
		(layer "F.Cu")
		(net "P5E_CPU1_G1_TX_C_DP<15>")
	)
	(segment
		(start 18.818098 -13.3985)
		(end 19.370294 -12.846304)
		(width 0.12954)
		(layer "F.Cu")
		(net "P5E_CPU1_G1_TX_C_DP<15>")
	)
	(segment
		(start 16.126968 -15.536926)
		(end 16.126968 -15.437104)
		(width 0.12954)
		(layer "F.Cu")
		(net "P5E_CPU1_G1_TX_C_DP<15>")
	)
	(segment
		(start 19.746976 -11.881104)
		(end 19.746976 -11.26998)
		(width 0.12954)
		(layer "F.Cu")
		(net "P5E_CPU1_G1_TX_C_DP<15>")
	)
	(segment
		(start 19.370294 -12.846304)
		(end 19.608292 -12.27201)
		(width 0.12954)
		(layer "F.Cu")
		(net "P5E_CPU1_G1_TX_C_DP<15>")
	)
	(segment
		(start 16.422878 -15.832836)
		(end 16.126968 -15.536926)
		(width 0.12954)
		(layer "F.Cu")
		(net "P5E_CPU1_G1_TX_C_DP<15>")
	)
	(segment
		(start 18.920968 -17.060926)
		(end 18.920968 -16.777462)
		(width 0.12954)
		(layer "F.Cu")
		(net "P5E_CPU1_G1_TX_C_DP<14>")
	)
	(segment
		(start 21.142706 -13.27531)
		(end 21.408136 -12.400534)
		(width 0.12954)
		(layer "F.Cu")
		(net "P5E_CPU1_G1_TX_C_DP<14>")
	)
	(segment
		(start 19.114008 -16.311118)
		(end 21.142706 -13.27531)
		(width 0.12954)
		(layer "F.Cu")
		(net "P5E_CPU1_G1_TX_C_DP<14>")
	)
	(segment
		(start 18.920968 -16.777462)
		(end 19.114008 -16.311118)
		(width 0.12954)
		(layer "F.Cu")
		(net "P5E_CPU1_G1_TX_C_DP<14>")
	)
	(segment
		(start 19.216878 -17.356836)
		(end 18.920968 -17.060926)
		(width 0.12954)
		(layer "F.Cu")
		(net "P5E_CPU1_G1_TX_C_DP<14>")
	)
	(segment
		(start 21.408136 -12.019788)
		(end 21.547074 -11.88085)
		(width 0.12954)
		(layer "F.Cu")
		(net "P5E_CPU1_G1_TX_C_DP<14>")
	)
	(segment
		(start 21.547074 -11.88085)
		(end 21.547074 -11.26998)
		(width 0.12954)
		(layer "F.Cu")
		(net "P5E_CPU1_G1_TX_C_DP<14>")
	)
	(segment
		(start 21.408136 -12.400534)
		(end 21.408136 -12.019788)
		(width 0.12954)
		(layer "F.Cu")
		(net "P5E_CPU1_G1_TX_C_DP<14>")
	)
	(segment
		(start 21.746972 -15.282418)
		(end 22.593808 -14.014958)
		(width 0.12954)
		(layer "F.Cu")
		(net "P5E_CPU1_G1_TX_C_DP<13>")
	)
	(segment
		(start 22.593808 -14.014958)
		(end 22.943566 -13.275564)
		(width 0.12954)
		(layer "F.Cu")
		(net "P5E_CPU1_G1_TX_C_DP<13>")
	)
	(segment
		(start 23.208234 -12.403074)
		(end 23.208234 -12.019788)
		(width 0.12954)
		(layer "F.Cu")
		(net "P5E_CPU1_G1_TX_C_DP<13>")
	)
	(segment
		(start 22.010878 -15.832836)
		(end 21.714968 -15.536926)
		(width 0.12954)
		(layer "F.Cu")
		(net "P5E_CPU1_G1_TX_C_DP<13>")
	)
	(segment
		(start 21.714968 -15.536926)
		(end 21.714968 -15.359888)
		(width 0.12954)
		(layer "F.Cu")
		(net "P5E_CPU1_G1_TX_C_DP<13>")
	)
	(segment
		(start 23.346918 -11.881104)
		(end 23.346918 -11.26998)
		(width 0.12954)
		(layer "F.Cu")
		(net "P5E_CPU1_G1_TX_C_DP<13>")
	)
	(segment
		(start 21.714968 -15.359888)
		(end 21.746972 -15.282418)
		(width 0.12954)
		(layer "F.Cu")
		(net "P5E_CPU1_G1_TX_C_DP<13>")
	)
	(segment
		(start 23.208234 -12.019788)
		(end 23.346918 -11.881104)
		(width 0.12954)
		(layer "F.Cu")
		(net "P5E_CPU1_G1_TX_C_DP<13>")
	)
	(segment
		(start 22.943566 -13.275564)
		(end 23.208234 -12.403074)
		(width 0.12954)
		(layer "F.Cu")
		(net "P5E_CPU1_G1_TX_C_DP<13>")
	)
	(segment
		(start 25.147016 -11.881104)
		(end 25.147016 -11.26998)
		(width 0.12954)
		(layer "F.Cu")
		(net "P5E_CPU1_G1_TX_C_DP<12>")
	)
	(segment
		(start 25.008332 -14.249654)
		(end 25.008332 -12.019788)
		(width 0.12954)
		(layer "F.Cu")
		(net "P5E_CPU1_G1_TX_C_DP<12>")
	)
	(segment
		(start 25.008332 -12.019788)
		(end 25.147016 -11.881104)
		(width 0.12954)
		(layer "F.Cu")
		(net "P5E_CPU1_G1_TX_C_DP<12>")
	)
	(segment
		(start 24.508968 -16.760698)
		(end 25.008332 -14.249654)
		(width 0.12954)
		(layer "F.Cu")
		(net "P5E_CPU1_G1_TX_C_DP<12>")
	)
	(segment
		(start 24.508968 -17.060926)
		(end 24.508968 -16.760698)
		(width 0.12954)
		(layer "F.Cu")
		(net "P5E_CPU1_G1_TX_C_DP<12>")
	)
	(segment
		(start 24.804878 -17.356836)
		(end 24.508968 -17.060926)
		(width 0.12954)
		(layer "F.Cu")
		(net "P5E_CPU1_G1_TX_C_DP<12>")
	)
	(segment
		(start 26.94686 -11.881104)
		(end 26.94686 -11.26998)
		(width 0.12954)
		(layer "F.Cu")
		(net "P5E_CPU1_G1_TX_C_DP<11>")
	)
	(segment
		(start 26.808176 -12.464796)
		(end 26.808176 -12.019788)
		(width 0.12954)
		(layer "F.Cu")
		(net "P5E_CPU1_G1_TX_C_DP<11>")
	)
	(segment
		(start 27.302968 -14.951456)
		(end 26.808176 -12.464796)
		(width 0.12954)
		(layer "F.Cu")
		(net "P5E_CPU1_G1_TX_C_DP<11>")
	)
	(segment
		(start 26.808176 -12.019788)
		(end 26.94686 -11.881104)
		(width 0.12954)
		(layer "F.Cu")
		(net "P5E_CPU1_G1_TX_C_DP<11>")
	)
	(segment
		(start 27.302968 -15.536926)
		(end 27.302968 -14.951456)
		(width 0.12954)
		(layer "F.Cu")
		(net "P5E_CPU1_G1_TX_C_DP<11>")
	)
	(segment
		(start 27.598878 -15.832836)
		(end 27.302968 -15.536926)
		(width 0.12954)
		(layer "F.Cu")
		(net "P5E_CPU1_G1_TX_C_DP<11>")
	)
	(segment
		(start 30.096968 -17.060926)
		(end 30.096968 -16.686022)
		(width 0.12954)
		(layer "F.Cu")
		(net "P5E_CPU1_G1_TX_C_DP<10>")
	)
	(segment
		(start 30.096968 -16.686022)
		(end 29.447998 -15.11935)
		(width 0.12954)
		(layer "F.Cu")
		(net "P5E_CPU1_G1_TX_C_DP<10>")
	)
	(segment
		(start 29.447998 -15.11935)
		(end 28.608274 -12.352528)
		(width 0.12954)
		(layer "F.Cu")
		(net "P5E_CPU1_G1_TX_C_DP<10>")
	)
	(segment
		(start 28.608274 -12.019788)
		(end 28.746958 -11.881104)
		(width 0.12954)
		(layer "F.Cu")
		(net "P5E_CPU1_G1_TX_C_DP<10>")
	)
	(segment
		(start 30.392878 -17.356836)
		(end 30.096968 -17.060926)
		(width 0.12954)
		(layer "F.Cu")
		(net "P5E_CPU1_G1_TX_C_DP<10>")
	)
	(segment
		(start 28.746958 -11.881104)
		(end 28.746958 -11.26998)
		(width 0.12954)
		(layer "F.Cu")
		(net "P5E_CPU1_G1_TX_C_DP<10>")
	)
	(segment
		(start 28.608274 -12.352528)
		(end 28.608274 -12.019788)
		(width 0.12954)
		(layer "F.Cu")
		(net "P5E_CPU1_G1_TX_C_DP<10>")
	)
	(segment
		(start 56.495442 -13.085064)
		(end 56.128158 -12.198604)
		(width 0.12954)
		(layer "F.Cu")
		(net "P5E_CPU1_G1_TX_C_DP<0>")
	)
	(segment
		(start 56.128158 -12.198604)
		(end 56.128158 -12.019788)
		(width 0.12954)
		(layer "F.Cu")
		(net "P5E_CPU1_G1_TX_C_DP<0>")
	)
	(segment
		(start 58.37682 -16.829532)
		(end 57.962038 -15.828518)
		(width 0.12954)
		(layer "F.Cu")
		(net "P5E_CPU1_G1_TX_C_DP<0>")
	)
	(segment
		(start 56.267096 -11.88085)
		(end 56.267096 -11.26998)
		(width 0.12954)
		(layer "F.Cu")
		(net "P5E_CPU1_G1_TX_C_DP<0>")
	)
	(segment
		(start 56.128158 -12.019788)
		(end 56.267096 -11.88085)
		(width 0.12954)
		(layer "F.Cu")
		(net "P5E_CPU1_G1_TX_C_DP<0>")
	)
	(segment
		(start 57.962038 -15.828518)
		(end 56.495442 -13.085064)
		(width 0.12954)
		(layer "F.Cu")
		(net "P5E_CPU1_G1_TX_C_DP<0>")
	)
	(segment
		(start 58.37682 -17.060926)
		(end 58.37682 -16.829532)
		(width 0.12954)
		(layer "F.Cu")
		(net "P5E_CPU1_G1_TX_C_DP<0>")
	)
	(segment
		(start 58.67273 -17.356836)
		(end 58.37682 -17.060926)
		(width 0.12954)
		(layer "F.Cu")
		(net "P5E_CPU1_G1_TX_C_DP<0>")
	)
	(segment
		(start 30.33141 -13.005816)
		(end 30.085792 -12.41298)
		(width 0.12954)
		(layer "F.Cu")
		(net "P5E_CPU1_G1_TX_C_DN<9>")
	)
	(segment
		(start 30.460188 -13.198602)
		(end 30.33141 -13.005816)
		(width 0.12954)
		(layer "F.Cu")
		(net "P5E_CPU1_G1_TX_C_DN<9>")
	)
	(segment
		(start 30.085792 -12.019788)
		(end 29.947108 -11.881104)
		(width 0.12954)
		(layer "F.Cu")
		(net "P5E_CPU1_G1_TX_C_DN<9>")
	)
	(segment
		(start 32.568388 -15.536926)
		(end 32.568388 -15.374874)
		(width 0.12954)
		(layer "F.Cu")
		(net "P5E_CPU1_G1_TX_C_DN<9>")
	)
	(segment
		(start 32.519874 -15.258288)
		(end 30.460188 -13.198602)
		(width 0.12954)
		(layer "F.Cu")
		(net "P5E_CPU1_G1_TX_C_DN<9>")
	)
	(segment
		(start 32.272478 -15.832836)
		(end 32.568388 -15.536926)
		(width 0.12954)
		(layer "F.Cu")
		(net "P5E_CPU1_G1_TX_C_DN<9>")
	)
	(segment
		(start 29.947108 -11.881104)
		(end 29.947108 -11.26998)
		(width 0.12954)
		(layer "F.Cu")
		(net "P5E_CPU1_G1_TX_C_DN<9>")
	)
	(segment
		(start 30.085792 -12.41298)
		(end 30.085792 -12.019788)
		(width 0.12954)
		(layer "F.Cu")
		(net "P5E_CPU1_G1_TX_C_DN<9>")
	)
	(segment
		(start 32.568388 -15.374874)
		(end 32.519874 -15.258288)
		(width 0.12954)
		(layer "F.Cu")
		(net "P5E_CPU1_G1_TX_C_DN<9>")
	)
	(segment
		(start 33.748218 -14.61389)
		(end 32.151828 -13.015468)
		(width 0.12954)
		(layer "F.Cu")
		(net "P5E_CPU1_G1_TX_C_DN<8>")
	)
	(segment
		(start 35.3187 -16.698214)
		(end 34.71164 -15.789148)
		(width 0.12954)
		(layer "F.Cu")
		(net "P5E_CPU1_G1_TX_C_DN<8>")
	)
	(segment
		(start 31.885636 -12.371832)
		(end 31.885636 -12.019788)
		(width 0.12954)
		(layer "F.Cu")
		(net "P5E_CPU1_G1_TX_C_DN<8>")
	)
	(segment
		(start 35.362388 -16.841978)
		(end 35.3187 -16.698214)
		(width 0.12954)
		(layer "F.Cu")
		(net "P5E_CPU1_G1_TX_C_DN<8>")
	)
	(segment
		(start 32.151828 -13.015468)
		(end 31.885636 -12.371832)
		(width 0.12954)
		(layer "F.Cu")
		(net "P5E_CPU1_G1_TX_C_DN<8>")
	)
	(segment
		(start 35.362388 -17.060926)
		(end 35.362388 -16.841978)
		(width 0.12954)
		(layer "F.Cu")
		(net "P5E_CPU1_G1_TX_C_DN<8>")
	)
	(segment
		(start 31.746952 -11.881104)
		(end 31.746952 -11.26998)
		(width 0.12954)
		(layer "F.Cu")
		(net "P5E_CPU1_G1_TX_C_DN<8>")
	)
	(segment
		(start 34.71164 -15.789148)
		(end 33.748218 -14.61389)
		(width 0.12954)
		(layer "F.Cu")
		(net "P5E_CPU1_G1_TX_C_DN<8>")
	)
	(segment
		(start 35.066478 -17.356836)
		(end 35.362388 -17.060926)
		(width 0.12954)
		(layer "F.Cu")
		(net "P5E_CPU1_G1_TX_C_DN<8>")
	)
	(segment
		(start 31.885636 -12.019788)
		(end 31.746952 -11.881104)
		(width 0.12954)
		(layer "F.Cu")
		(net "P5E_CPU1_G1_TX_C_DN<8>")
	)
	(segment
		(start 38.156388 -15.065502)
		(end 38.223952 -14.725142)
		(width 0.12954)
		(layer "F.Cu")
		(net "P5E_CPU1_G1_TX_C_DN<7>")
	)
	(segment
		(start 38.223952 -14.725142)
		(end 39.195756 -12.379452)
		(width 0.12954)
		(layer "F.Cu")
		(net "P5E_CPU1_G1_TX_C_DN<7>")
	)
	(segment
		(start 37.860478 -15.832836)
		(end 38.156388 -15.536926)
		(width 0.12954)
		(layer "F.Cu")
		(net "P5E_CPU1_G1_TX_C_DN<7>")
	)
	(segment
		(start 39.195756 -12.379452)
		(end 39.195756 -12.019788)
		(width 0.12954)
		(layer "F.Cu")
		(net "P5E_CPU1_G1_TX_C_DN<7>")
	)
	(segment
		(start 38.156388 -15.536926)
		(end 38.156388 -15.065502)
		(width 0.12954)
		(layer "F.Cu")
		(net "P5E_CPU1_G1_TX_C_DN<7>")
	)
	(segment
		(start 39.057072 -11.881104)
		(end 39.057072 -11.26998)
		(width 0.12954)
		(layer "F.Cu")
		(net "P5E_CPU1_G1_TX_C_DN<7>")
	)
	(segment
		(start 39.195756 -12.019788)
		(end 39.057072 -11.881104)
		(width 0.12954)
		(layer "F.Cu")
		(net "P5E_CPU1_G1_TX_C_DN<7>")
	)
	(segment
		(start 40.960294 -17.356836)
		(end 41.256204 -17.060926)
		(width 0.12954)
		(layer "F.Cu")
		(net "P5E_CPU1_G1_TX_C_DN<6>")
	)
	(segment
		(start 40.9956 -13.246354)
		(end 40.9956 -12.019788)
		(width 0.12954)
		(layer "F.Cu")
		(net "P5E_CPU1_G1_TX_C_DN<6>")
	)
	(segment
		(start 41.256204 -15.893034)
		(end 40.9956 -13.246354)
		(width 0.12954)
		(layer "F.Cu")
		(net "P5E_CPU1_G1_TX_C_DN<6>")
	)
	(segment
		(start 40.856916 -11.881104)
		(end 40.856916 -11.26998)
		(width 0.12954)
		(layer "F.Cu")
		(net "P5E_CPU1_G1_TX_C_DN<6>")
	)
	(segment
		(start 41.256204 -17.060926)
		(end 41.256204 -15.893034)
		(width 0.12954)
		(layer "F.Cu")
		(net "P5E_CPU1_G1_TX_C_DN<6>")
	)
	(segment
		(start 40.9956 -12.019788)
		(end 40.856916 -11.881104)
		(width 0.12954)
		(layer "F.Cu")
		(net "P5E_CPU1_G1_TX_C_DN<6>")
	)
	(segment
		(start 42.795698 -12.019788)
		(end 42.657014 -11.881104)
		(width 0.12954)
		(layer "F.Cu")
		(net "P5E_CPU1_G1_TX_C_DN<5>")
	)
	(segment
		(start 43.92168 -14.937486)
		(end 43.211496 -13.608812)
		(width 0.12954)
		(layer "F.Cu")
		(net "P5E_CPU1_G1_TX_C_DN<5>")
	)
	(segment
		(start 44.050204 -15.536926)
		(end 44.050204 -15.36065)
		(width 0.12954)
		(layer "F.Cu")
		(net "P5E_CPU1_G1_TX_C_DN<5>")
	)
	(segment
		(start 43.211496 -13.608812)
		(end 42.795698 -12.60475)
		(width 0.12954)
		(layer "F.Cu")
		(net "P5E_CPU1_G1_TX_C_DN<5>")
	)
	(segment
		(start 42.795698 -12.60475)
		(end 42.795698 -12.019788)
		(width 0.12954)
		(layer "F.Cu")
		(net "P5E_CPU1_G1_TX_C_DN<5>")
	)
	(segment
		(start 43.754294 -15.832836)
		(end 44.050204 -15.536926)
		(width 0.12954)
		(layer "F.Cu")
		(net "P5E_CPU1_G1_TX_C_DN<5>")
	)
	(segment
		(start 44.050204 -15.36065)
		(end 43.92168 -14.937486)
		(width 0.12954)
		(layer "F.Cu")
		(net "P5E_CPU1_G1_TX_C_DN<5>")
	)
	(segment
		(start 42.657014 -11.881104)
		(end 42.657014 -11.26998)
		(width 0.12954)
		(layer "F.Cu")
		(net "P5E_CPU1_G1_TX_C_DN<5>")
	)
	(segment
		(start 46.844204 -17.060926)
		(end 46.844204 -16.783812)
		(width 0.12954)
		(layer "F.Cu")
		(net "P5E_CPU1_G1_TX_C_DN<4>")
	)
	(segment
		(start 46.844204 -16.783812)
		(end 44.764452 -13.113258)
		(width 0.12954)
		(layer "F.Cu")
		(net "P5E_CPU1_G1_TX_C_DN<4>")
	)
	(segment
		(start 46.548294 -17.356836)
		(end 46.844204 -17.060926)
		(width 0.12954)
		(layer "F.Cu")
		(net "P5E_CPU1_G1_TX_C_DN<4>")
	)
	(segment
		(start 44.457112 -11.881104)
		(end 44.457112 -11.26998)
		(width 0.12954)
		(layer "F.Cu")
		(net "P5E_CPU1_G1_TX_C_DN<4>")
	)
	(segment
		(start 44.595796 -12.472924)
		(end 44.595796 -12.019788)
		(width 0.12954)
		(layer "F.Cu")
		(net "P5E_CPU1_G1_TX_C_DN<4>")
	)
	(segment
		(start 44.595796 -12.019788)
		(end 44.457112 -11.881104)
		(width 0.12954)
		(layer "F.Cu")
		(net "P5E_CPU1_G1_TX_C_DN<4>")
	)
	(segment
		(start 44.764452 -13.113258)
		(end 44.595796 -12.472924)
		(width 0.12954)
		(layer "F.Cu")
		(net "P5E_CPU1_G1_TX_C_DN<4>")
	)
	(segment
		(start 49.342294 -15.832836)
		(end 49.638204 -15.536926)
		(width 0.12954)
		(layer "F.Cu")
		(net "P5E_CPU1_G1_TX_C_DN<3>")
	)
	(segment
		(start 49.685702 -14.527022)
		(end 50.252122 -13.159486)
		(width 0.12954)
		(layer "F.Cu")
		(net "P5E_CPU1_G1_TX_C_DN<3>")
	)
	(segment
		(start 49.638204 -15.536926)
		(end 49.638204 -14.767306)
		(width 0.12954)
		(layer "F.Cu")
		(net "P5E_CPU1_G1_TX_C_DN<3>")
	)
	(segment
		(start 50.405792 -12.387834)
		(end 50.405792 -12.019788)
		(width 0.12954)
		(layer "F.Cu")
		(net "P5E_CPU1_G1_TX_C_DN<3>")
	)
	(segment
		(start 50.267108 -11.881104)
		(end 50.267108 -11.26998)
		(width 0.12954)
		(layer "F.Cu")
		(net "P5E_CPU1_G1_TX_C_DN<3>")
	)
	(segment
		(start 50.405792 -12.019788)
		(end 50.267108 -11.881104)
		(width 0.12954)
		(layer "F.Cu")
		(net "P5E_CPU1_G1_TX_C_DN<3>")
	)
	(segment
		(start 49.638204 -14.767306)
		(end 49.685702 -14.527022)
		(width 0.12954)
		(layer "F.Cu")
		(net "P5E_CPU1_G1_TX_C_DN<3>")
	)
	(segment
		(start 50.252122 -13.159486)
		(end 50.405792 -12.387834)
		(width 0.12954)
		(layer "F.Cu")
		(net "P5E_CPU1_G1_TX_C_DN<3>")
	)
	(segment
		(start 52.205636 -12.019788)
		(end 52.066952 -11.881104)
		(width 0.12954)
		(layer "F.Cu")
		(net "P5E_CPU1_G1_TX_C_DN<2>")
	)
	(segment
		(start 52.46624 -17.060926)
		(end 52.46624 -16.306292)
		(width 0.12954)
		(layer "F.Cu")
		(net "P5E_CPU1_G1_TX_C_DN<2>")
	)
	(segment
		(start 52.46624 -16.306292)
		(end 52.205636 -13.659612)
		(width 0.12954)
		(layer "F.Cu")
		(net "P5E_CPU1_G1_TX_C_DN<2>")
	)
	(segment
		(start 52.17033 -17.356836)
		(end 52.46624 -17.060926)
		(width 0.12954)
		(layer "F.Cu")
		(net "P5E_CPU1_G1_TX_C_DN<2>")
	)
	(segment
		(start 52.205636 -13.659612)
		(end 52.205636 -12.019788)
		(width 0.12954)
		(layer "F.Cu")
		(net "P5E_CPU1_G1_TX_C_DN<2>")
	)
	(segment
		(start 52.066952 -11.881104)
		(end 52.066952 -11.26998)
		(width 0.12954)
		(layer "F.Cu")
		(net "P5E_CPU1_G1_TX_C_DN<2>")
	)
	(segment
		(start 54.005734 -12.232894)
		(end 54.005734 -12.019788)
		(width 0.12954)
		(layer "F.Cu")
		(net "P5E_CPU1_G1_TX_C_DN<1>")
	)
	(segment
		(start 55.26024 -15.536926)
		(end 55.26024 -15.347188)
		(width 0.12954)
		(layer "F.Cu")
		(net "P5E_CPU1_G1_TX_C_DN<1>")
	)
	(segment
		(start 55.26024 -15.347188)
		(end 54.042564 -12.41679)
		(width 0.12954)
		(layer "F.Cu")
		(net "P5E_CPU1_G1_TX_C_DN<1>")
	)
	(segment
		(start 54.96433 -15.832836)
		(end 55.26024 -15.536926)
		(width 0.12954)
		(layer "F.Cu")
		(net "P5E_CPU1_G1_TX_C_DN<1>")
	)
	(segment
		(start 53.86705 -11.881104)
		(end 53.86705 -11.26998)
		(width 0.12954)
		(layer "F.Cu")
		(net "P5E_CPU1_G1_TX_C_DN<1>")
	)
	(segment
		(start 54.042564 -12.41679)
		(end 54.005734 -12.232894)
		(width 0.12954)
		(layer "F.Cu")
		(net "P5E_CPU1_G1_TX_C_DN<1>")
	)
	(segment
		(start 54.005734 -12.019788)
		(end 53.86705 -11.881104)
		(width 0.12954)
		(layer "F.Cu")
		(net "P5E_CPU1_G1_TX_C_DN<1>")
	)
	(segment
		(start 15.804388 -15.372842)
		(end 15.951454 -15.018004)
		(width 0.12954)
		(layer "F.Cu")
		(net "P5E_CPU1_G1_TX_C_DN<15>")
	)
	(segment
		(start 15.508478 -15.832836)
		(end 15.804388 -15.536926)
		(width 0.12954)
		(layer "F.Cu")
		(net "P5E_CPU1_G1_TX_C_DN<15>")
	)
	(segment
		(start 19.285712 -12.207748)
		(end 19.285712 -12.019788)
		(width 0.12954)
		(layer "F.Cu")
		(net "P5E_CPU1_G1_TX_C_DN<15>")
	)
	(segment
		(start 19.147028 -11.881104)
		(end 19.147028 -11.26998)
		(width 0.12954)
		(layer "F.Cu")
		(net "P5E_CPU1_G1_TX_C_DN<15>")
	)
	(segment
		(start 19.096736 -12.663424)
		(end 19.285712 -12.207748)
		(width 0.12954)
		(layer "F.Cu")
		(net "P5E_CPU1_G1_TX_C_DN<15>")
	)
	(segment
		(start 19.285712 -12.019788)
		(end 19.147028 -11.881104)
		(width 0.12954)
		(layer "F.Cu")
		(net "P5E_CPU1_G1_TX_C_DN<15>")
	)
	(segment
		(start 18.612358 -13.147802)
		(end 19.096736 -12.663424)
		(width 0.12954)
		(layer "F.Cu")
		(net "P5E_CPU1_G1_TX_C_DN<15>")
	)
	(segment
		(start 16.228822 -14.740636)
		(end 18.612358 -13.147802)
		(width 0.12954)
		(layer "F.Cu")
		(net "P5E_CPU1_G1_TX_C_DN<15>")
	)
	(segment
		(start 15.951454 -15.018004)
		(end 16.228822 -14.740636)
		(width 0.12954)
		(layer "F.Cu")
		(net "P5E_CPU1_G1_TX_C_DN<15>")
	)
	(segment
		(start 15.804388 -15.536926)
		(end 15.804388 -15.372842)
		(width 0.12954)
		(layer "F.Cu")
		(net "P5E_CPU1_G1_TX_C_DN<15>")
	)
	(segment
		(start 18.598388 -16.7132)
		(end 18.828004 -16.158464)
		(width 0.12954)
		(layer "F.Cu")
		(net "P5E_CPU1_G1_TX_C_DN<14>")
	)
	(segment
		(start 20.946872 -11.881104)
		(end 20.946872 -11.26998)
		(width 0.12954)
		(layer "F.Cu")
		(net "P5E_CPU1_G1_TX_C_DN<14>")
	)
	(segment
		(start 18.302478 -17.356836)
		(end 18.598388 -17.060926)
		(width 0.12954)
		(layer "F.Cu")
		(net "P5E_CPU1_G1_TX_C_DN<14>")
	)
	(segment
		(start 20.847812 -13.135864)
		(end 21.085556 -12.352528)
		(width 0.12954)
		(layer "F.Cu")
		(net "P5E_CPU1_G1_TX_C_DN<14>")
	)
	(segment
		(start 21.085556 -12.352528)
		(end 21.085556 -12.019788)
		(width 0.12954)
		(layer "F.Cu")
		(net "P5E_CPU1_G1_TX_C_DN<14>")
	)
	(segment
		(start 18.598388 -17.060926)
		(end 18.598388 -16.7132)
		(width 0.12954)
		(layer "F.Cu")
		(net "P5E_CPU1_G1_TX_C_DN<14>")
	)
	(segment
		(start 18.828004 -16.158464)
		(end 20.847812 -13.135864)
		(width 0.12954)
		(layer "F.Cu")
		(net "P5E_CPU1_G1_TX_C_DN<14>")
	)
	(segment
		(start 21.085556 -12.019788)
		(end 20.946872 -11.881104)
		(width 0.12954)
		(layer "F.Cu")
		(net "P5E_CPU1_G1_TX_C_DN<14>")
	)
	(segment
		(start 21.460968 -15.129764)
		(end 22.312376 -13.855446)
		(width 0.12954)
		(layer "F.Cu")
		(net "P5E_CPU1_G1_TX_C_DN<13>")
	)
	(segment
		(start 22.312376 -13.855446)
		(end 22.64156 -13.158978)
		(width 0.12954)
		(layer "F.Cu")
		(net "P5E_CPU1_G1_TX_C_DN<13>")
	)
	(segment
		(start 21.392388 -15.536926)
		(end 21.392388 -15.29588)
		(width 0.12954)
		(layer "F.Cu")
		(net "P5E_CPU1_G1_TX_C_DN<13>")
	)
	(segment
		(start 22.885654 -12.019788)
		(end 22.74697 -11.881104)
		(width 0.12954)
		(layer "F.Cu")
		(net "P5E_CPU1_G1_TX_C_DN<13>")
	)
	(segment
		(start 22.885654 -12.355068)
		(end 22.885654 -12.019788)
		(width 0.12954)
		(layer "F.Cu")
		(net "P5E_CPU1_G1_TX_C_DN<13>")
	)
	(segment
		(start 21.096478 -15.832836)
		(end 21.392388 -15.536926)
		(width 0.12954)
		(layer "F.Cu")
		(net "P5E_CPU1_G1_TX_C_DN<13>")
	)
	(segment
		(start 22.74697 -11.881104)
		(end 22.74697 -11.26998)
		(width 0.12954)
		(layer "F.Cu")
		(net "P5E_CPU1_G1_TX_C_DN<13>")
	)
	(segment
		(start 21.392388 -15.29588)
		(end 21.460968 -15.129764)
		(width 0.12954)
		(layer "F.Cu")
		(net "P5E_CPU1_G1_TX_C_DN<13>")
	)
	(segment
		(start 22.64156 -13.158978)
		(end 22.885654 -12.355068)
		(width 0.12954)
		(layer "F.Cu")
		(net "P5E_CPU1_G1_TX_C_DN<13>")
	)
	(segment
		(start 23.890478 -17.356836)
		(end 24.186388 -17.060926)
		(width 0.12954)
		(layer "F.Cu")
		(net "P5E_CPU1_G1_TX_C_DN<12>")
	)
	(segment
		(start 24.685752 -14.21765)
		(end 24.685752 -12.019788)
		(width 0.12954)
		(layer "F.Cu")
		(net "P5E_CPU1_G1_TX_C_DN<12>")
	)
	(segment
		(start 24.186388 -16.728694)
		(end 24.685752 -14.21765)
		(width 0.12954)
		(layer "F.Cu")
		(net "P5E_CPU1_G1_TX_C_DN<12>")
	)
	(segment
		(start 24.685752 -12.019788)
		(end 24.547068 -11.881104)
		(width 0.12954)
		(layer "F.Cu")
		(net "P5E_CPU1_G1_TX_C_DN<12>")
	)
	(segment
		(start 24.547068 -11.881104)
		(end 24.547068 -11.26998)
		(width 0.12954)
		(layer "F.Cu")
		(net "P5E_CPU1_G1_TX_C_DN<12>")
	)
	(segment
		(start 24.186388 -17.060926)
		(end 24.186388 -16.728694)
		(width 0.12954)
		(layer "F.Cu")
		(net "P5E_CPU1_G1_TX_C_DN<12>")
	)
	(segment
		(start 26.485596 -12.4968)
		(end 26.485596 -12.019788)
		(width 0.12954)
		(layer "F.Cu")
		(net "P5E_CPU1_G1_TX_C_DN<11>")
	)
	(segment
		(start 26.980388 -14.98346)
		(end 26.485596 -12.4968)
		(width 0.12954)
		(layer "F.Cu")
		(net "P5E_CPU1_G1_TX_C_DN<11>")
	)
	(segment
		(start 26.346912 -11.881104)
		(end 26.346912 -11.26998)
		(width 0.12954)
		(layer "F.Cu")
		(net "P5E_CPU1_G1_TX_C_DN<11>")
	)
	(segment
		(start 26.684478 -15.832836)
		(end 26.980388 -15.536926)
		(width 0.12954)
		(layer "F.Cu")
		(net "P5E_CPU1_G1_TX_C_DN<11>")
	)
	(segment
		(start 26.980388 -15.536926)
		(end 26.980388 -14.98346)
		(width 0.12954)
		(layer "F.Cu")
		(net "P5E_CPU1_G1_TX_C_DN<11>")
	)
	(segment
		(start 26.485596 -12.019788)
		(end 26.346912 -11.881104)
		(width 0.12954)
		(layer "F.Cu")
		(net "P5E_CPU1_G1_TX_C_DN<11>")
	)
	(segment
		(start 28.285694 -12.019788)
		(end 28.14701 -11.881104)
		(width 0.12954)
		(layer "F.Cu")
		(net "P5E_CPU1_G1_TX_C_DN<10>")
	)
	(segment
		(start 28.285694 -12.400534)
		(end 28.285694 -12.019788)
		(width 0.12954)
		(layer "F.Cu")
		(net "P5E_CPU1_G1_TX_C_DN<10>")
	)
	(segment
		(start 29.774388 -17.060926)
		(end 29.774388 -16.750284)
		(width 0.12954)
		(layer "F.Cu")
		(net "P5E_CPU1_G1_TX_C_DN<10>")
	)
	(segment
		(start 29.143706 -15.228316)
		(end 28.285694 -12.400534)
		(width 0.12954)
		(layer "F.Cu")
		(net "P5E_CPU1_G1_TX_C_DN<10>")
	)
	(segment
		(start 29.774388 -16.750284)
		(end 29.143706 -15.228316)
		(width 0.12954)
		(layer "F.Cu")
		(net "P5E_CPU1_G1_TX_C_DN<10>")
	)
	(segment
		(start 29.478478 -17.356836)
		(end 29.774388 -17.060926)
		(width 0.12954)
		(layer "F.Cu")
		(net "P5E_CPU1_G1_TX_C_DN<10>")
	)
	(segment
		(start 28.14701 -11.881104)
		(end 28.14701 -11.26998)
		(width 0.12954)
		(layer "F.Cu")
		(net "P5E_CPU1_G1_TX_C_DN<10>")
	)
	(segment
		(start 58.05424 -17.060926)
		(end 58.05424 -16.893794)
		(width 0.12954)
		(layer "F.Cu")
		(net "P5E_CPU1_G1_TX_C_DN<0>")
	)
	(segment
		(start 57.669938 -15.966694)
		(end 56.203342 -13.22324)
		(width 0.12954)
		(layer "F.Cu")
		(net "P5E_CPU1_G1_TX_C_DN<0>")
	)
	(segment
		(start 58.05424 -16.893794)
		(end 57.669938 -15.966694)
		(width 0.12954)
		(layer "F.Cu")
		(net "P5E_CPU1_G1_TX_C_DN<0>")
	)
	(segment
		(start 57.75833 -17.356836)
		(end 58.05424 -17.060926)
		(width 0.12954)
		(layer "F.Cu")
		(net "P5E_CPU1_G1_TX_C_DN<0>")
	)
	(segment
		(start 56.203342 -13.22324)
		(end 55.805578 -12.262866)
		(width 0.12954)
		(layer "F.Cu")
		(net "P5E_CPU1_G1_TX_C_DN<0>")
	)
	(segment
		(start 55.805578 -12.019788)
		(end 55.666894 -11.881104)
		(width 0.12954)
		(layer "F.Cu")
		(net "P5E_CPU1_G1_TX_C_DN<0>")
	)
	(segment
		(start 55.805578 -12.262866)
		(end 55.805578 -12.019788)
		(width 0.12954)
		(layer "F.Cu")
		(net "P5E_CPU1_G1_TX_C_DN<0>")
	)
	(segment
		(start 55.666894 -11.881104)
		(end 55.666894 -11.26998)
		(width 0.12954)
		(layer "F.Cu")
		(net "P5E_CPU1_G1_TX_C_DN<0>")
	)
	(segment
		(start 367.067846 -276.250146)
		(end 367.534698 -276.516084)
		(width 0.12954)
		(layer "F.Cu")
		(net "P5E_CPU0_P3_TX_DP<9>")
	)
	(segment
		(start 381.701802 -378.39142)
		(end 381.405892 -378.68733)
		(width 0.12954)
		(layer "F.Cu")
		(net "P5E_CPU0_P3_TX_DP<9>")
	)
	(segment
		(start 381.431292 -377.41733)
		(end 381.701802 -377.68784)
		(width 0.12954)
		(layer "F.Cu")
		(net "P5E_CPU0_P3_TX_DP<9>")
	)
	(segment
		(start 381.701802 -377.68784)
		(end 381.701802 -378.39142)
		(width 0.12954)
		(layer "F.Cu")
		(net "P5E_CPU0_P3_TX_DP<9>")
	)
	(segment
		(start 369.092734 -291.560504)
		(end 369.13185 -291.583364)
		(width 0.1143)
		(layer "In11.Cu")
		(net "P5E_CPU0_P3_TX_DP<9>")
	)
	(segment
		(start 368.611404 -277.782782)
		(end 368.622072 -277.790402)
		(width 0.1143)
		(layer "In11.Cu")
		(net "P5E_CPU0_P3_TX_DP<9>")
	)
	(segment
		(start 369.6335 -280.0604)
		(end 369.602512 -280.07818)
		(width 0.1143)
		(layer "In11.Cu")
		(net "P5E_CPU0_P3_TX_DP<9>")
	)
	(segment
		(start 389.922004 -351.721166)
		(end 387.685534 -360.64952)
		(width 0.14224)
		(layer "In11.Cu")
		(net "P5E_CPU0_P3_TX_DP<9>")
	)
	(segment
		(start 369.60175 -280.078688)
		(end 369.600734 -280.079196)
		(width 0.1143)
		(layer "In11.Cu")
		(net "P5E_CPU0_P3_TX_DP<9>")
	)
	(segment
		(start 368.622072 -277.790402)
		(end 368.693192 -277.831804)
		(width 0.1143)
		(layer "In11.Cu")
		(net "P5E_CPU0_P3_TX_DP<9>")
	)
	(segment
		(start 369.59921 -280.080212)
		(end 369.562634 -280.101548)
		(width 0.1143)
		(layer "In11.Cu")
		(net "P5E_CPU0_P3_TX_DP<9>")
	)
	(segment
		(start 369.13185 -290.608512)
		(end 369.092734 -290.631372)
		(width 0.1143)
		(layer "In11.Cu")
		(net "P5E_CPU0_P3_TX_DP<9>")
	)
	(segment
		(start 369.092734 -285.08071)
		(end 369.13185 -285.10357)
		(width 0.1143)
		(layer "In11.Cu")
		(net "P5E_CPU0_P3_TX_DP<9>")
	)
	(segment
		(start 369.608354 -279.437338)
		(end 369.609624 -279.4381)
		(width 0.1143)
		(layer "In11.Cu")
		(net "P5E_CPU0_P3_TX_DP<9>")
	)
	(segment
		(start 369.13185 -282.508706)
		(end 369.092734 -282.531566)
		(width 0.1143)
		(layer "In11.Cu")
		(net "P5E_CPU0_P3_TX_DP<9>")
	)
	(segment
		(start 369.13185 -278.623522)
		(end 369.16233 -278.641302)
		(width 0.1143)
		(layer "In11.Cu")
		(net "P5E_CPU0_P3_TX_DP<9>")
	)
	(segment
		(start 368.1603 -276.985222)
		(end 368.191796 -277.00351)
		(width 0.1143)
		(layer "In11.Cu")
		(net "P5E_CPU0_P3_TX_DP<9>")
	)
	(segment
		(start 369.092734 -288.320734)
		(end 369.13185 -288.343594)
		(width 0.1143)
		(layer "In11.Cu")
		(net "P5E_CPU0_P3_TX_DP<9>")
	)
	(segment
		(start 389.922004 -340.63686)
		(end 389.922004 -351.721166)
		(width 0.14224)
		(layer "In11.Cu")
		(net "P5E_CPU0_P3_TX_DP<9>")
	)
	(segment
		(start 369.609624 -279.4381)
		(end 369.612164 -279.43937)
		(width 0.1143)
		(layer "In11.Cu")
		(net "P5E_CPU0_P3_TX_DP<9>")
	)
	(segment
		(start 369.871752 -296.538142)
		(end 369.826032 -296.583862)
		(width 0.1143)
		(layer "In11.Cu")
		(net "P5E_CPU0_P3_TX_DP<9>")
	)
	(segment
		(start 369.13185 -284.128718)
		(end 369.092734 -284.151578)
		(width 0.1143)
		(layer "In11.Cu")
		(net "P5E_CPU0_P3_TX_DP<9>")
	)
	(segment
		(start 369.13185 -289.963352)
		(end 369.16233 -289.981132)
		(width 0.1143)
		(layer "In11.Cu")
		(net "P5E_CPU0_P3_TX_DP<9>")
	)
	(segment
		(start 369.16233 -285.73095)
		(end 369.13185 -285.74873)
		(width 0.1143)
		(layer "In11.Cu")
		(net "P5E_CPU0_P3_TX_DP<9>")
	)
	(segment
		(start 368.159538 -276.984714)
		(end 368.1603 -276.985222)
		(width 0.1143)
		(layer "In11.Cu")
		(net "P5E_CPU0_P3_TX_DP<9>")
	)
	(segment
		(start 370.662708 -299.779944)
		(end 372.519702 -302.559212)
		(width 0.14224)
		(layer "In11.Cu")
		(net "P5E_CPU0_P3_TX_DP<9>")
	)
	(segment
		(start 369.13185 -292.228524)
		(end 369.092734 -292.251384)
		(width 0.1143)
		(layer "In11.Cu")
		(net "P5E_CPU0_P3_TX_DP<9>")
	)
	(segment
		(start 369.16233 -290.590732)
		(end 369.13185 -290.608512)
		(width 0.1143)
		(layer "In11.Cu")
		(net "P5E_CPU0_P3_TX_DP<9>")
	)
	(segment
		(start 367.83264 -276.516084)
		(end 367.915444 -276.598888)
		(width 0.1143)
		(layer "In11.Cu")
		(net "P5E_CPU0_P3_TX_DP<9>")
	)
	(segment
		(start 369.16233 -284.110938)
		(end 369.13185 -284.128718)
		(width 0.1143)
		(layer "In11.Cu")
		(net "P5E_CPU0_P3_TX_DP<9>")
	)
	(segment
		(start 369.16233 -288.97072)
		(end 369.13185 -288.9885)
		(width 0.1143)
		(layer "In11.Cu")
		(net "P5E_CPU0_P3_TX_DP<9>")
	)
	(segment
		(start 369.13185 -285.10357)
		(end 369.16233 -285.12135)
		(width 0.1143)
		(layer "In11.Cu")
		(net "P5E_CPU0_P3_TX_DP<9>")
	)
	(segment
		(start 369.607592 -279.43683)
		(end 369.608354 -279.437338)
		(width 0.1143)
		(layer "In11.Cu")
		(net "P5E_CPU0_P3_TX_DP<9>")
	)
	(segment
		(start 368.15268 -276.98065)
		(end 368.159538 -276.984714)
		(width 0.1143)
		(layer "In11.Cu")
		(net "P5E_CPU0_P3_TX_DP<9>")
	)
	(segment
		(start 369.612164 -279.43937)
		(end 369.6335 -279.451816)
		(width 0.1143)
		(layer "In11.Cu")
		(net "P5E_CPU0_P3_TX_DP<9>")
	)
	(segment
		(start 369.092734 -278.600662)
		(end 369.13185 -278.623522)
		(width 0.1143)
		(layer "In11.Cu")
		(net "P5E_CPU0_P3_TX_DP<9>")
	)
	(segment
		(start 369.13185 -283.483558)
		(end 369.16233 -283.501338)
		(width 0.1143)
		(layer "In11.Cu")
		(net "P5E_CPU0_P3_TX_DP<9>")
	)
	(segment
		(start 369.13185 -285.74873)
		(end 369.092734 -285.77159)
		(width 0.1143)
		(layer "In11.Cu")
		(net "P5E_CPU0_P3_TX_DP<9>")
	)
	(segment
		(start 369.570254 -279.41524)
		(end 369.60175 -279.433528)
		(width 0.1143)
		(layer "In11.Cu")
		(net "P5E_CPU0_P3_TX_DP<9>")
	)
	(segment
		(start 369.602512 -280.07818)
		(end 369.60175 -280.078688)
		(width 0.1143)
		(layer "In11.Cu")
		(net "P5E_CPU0_P3_TX_DP<9>")
	)
	(segment
		(start 369.78971 -296.168318)
		(end 369.871752 -296.25036)
		(width 0.1143)
		(layer "In11.Cu")
		(net "P5E_CPU0_P3_TX_DP<9>")
	)
	(segment
		(start 369.78971 -295.955974)
		(end 369.78971 -296.168318)
		(width 0.1143)
		(layer "In11.Cu")
		(net "P5E_CPU0_P3_TX_DP<9>")
	)
	(segment
		(start 369.602512 -279.434036)
		(end 369.605306 -279.43556)
		(width 0.1143)
		(layer "In11.Cu")
		(net "P5E_CPU0_P3_TX_DP<9>")
	)
	(segment
		(start 369.60175 -279.433528)
		(end 369.602512 -279.434036)
		(width 0.1143)
		(layer "In11.Cu")
		(net "P5E_CPU0_P3_TX_DP<9>")
	)
	(segment
		(start 368.192558 -277.004018)
		(end 368.195352 -277.005542)
		(width 0.1143)
		(layer "In11.Cu")
		(net "P5E_CPU0_P3_TX_DP<9>")
	)
	(segment
		(start 369.13185 -288.9885)
		(end 369.092734 -289.01136)
		(width 0.1143)
		(layer "In11.Cu")
		(net "P5E_CPU0_P3_TX_DP<9>")
	)
	(segment
		(start 381.722122 -376.329956)
		(end 381.722122 -377.1265)
		(width 0.14224)
		(layer "In11.Cu")
		(net "P5E_CPU0_P3_TX_DP<9>")
	)
	(segment
		(start 384.720338 -318.93764)
		(end 386.423408 -323.048376)
		(width 0.14224)
		(layer "In11.Cu")
		(net "P5E_CPU0_P3_TX_DP<9>")
	)
	(segment
		(start 369.092734 -294.800528)
		(end 369.13185 -294.823388)
		(width 0.1143)
		(layer "In11.Cu")
		(net "P5E_CPU0_P3_TX_DP<9>")
	)
	(segment
		(start 372.519702 -302.559212)
		(end 379.283976 -310.801766)
		(width 0.14224)
		(layer "In11.Cu")
		(net "P5E_CPU0_P3_TX_DP<9>")
	)
	(segment
		(start 369.871752 -296.25036)
		(end 369.871752 -296.538142)
		(width 0.1143)
		(layer "In11.Cu")
		(net "P5E_CPU0_P3_TX_DP<9>")
	)
	(segment
		(start 369.092734 -283.460698)
		(end 369.13185 -283.483558)
		(width 0.1143)
		(layer "In11.Cu")
		(net "P5E_CPU0_P3_TX_DP<9>")
	)
	(segment
		(start 368.693192 -277.831804)
		(end 368.693446 -277.831804)
		(width 0.1143)
		(layer "In11.Cu")
		(net "P5E_CPU0_P3_TX_DP<9>")
	)
	(segment
		(start 368.379502 -277.32609)
		(end 368.379502 -277.329138)
		(width 0.1143)
		(layer "In11.Cu")
		(net "P5E_CPU0_P3_TX_DP<9>")
	)
	(segment
		(start 368.19205 -277.003764)
		(end 368.192558 -277.004018)
		(width 0.1143)
		(layer "In11.Cu")
		(net "P5E_CPU0_P3_TX_DP<9>")
	)
	(segment
		(start 369.13185 -288.343594)
		(end 369.164362 -288.36239)
		(width 0.1143)
		(layer "In11.Cu")
		(net "P5E_CPU0_P3_TX_DP<9>")
	)
	(segment
		(start 369.826032 -297.022012)
		(end 370.662708 -299.779944)
		(width 0.14224)
		(layer "In11.Cu")
		(net "P5E_CPU0_P3_TX_DP<9>")
	)
	(segment
		(start 369.092734 -286.700722)
		(end 369.13185 -286.723582)
		(width 0.1143)
		(layer "In11.Cu")
		(net "P5E_CPU0_P3_TX_DP<9>")
	)
	(segment
		(start 367.534698 -276.516084)
		(end 367.83264 -276.516084)
		(width 0.1143)
		(layer "In11.Cu")
		(net "P5E_CPU0_P3_TX_DP<9>")
	)
	(segment
		(start 369.606068 -279.436068)
		(end 369.607592 -279.43683)
		(width 0.1143)
		(layer "In11.Cu")
		(net "P5E_CPU0_P3_TX_DP<9>")
	)
	(segment
		(start 369.826032 -296.61231)
		(end 369.826032 -297.022012)
		(width 0.14224)
		(layer "In11.Cu")
		(net "P5E_CPU0_P3_TX_DP<9>")
	)
	(segment
		(start 369.092734 -281.840686)
		(end 369.13185 -281.863546)
		(width 0.1143)
		(layer "In11.Cu")
		(net "P5E_CPU0_P3_TX_DP<9>")
	)
	(segment
		(start 369.569492 -279.414732)
		(end 369.570254 -279.41524)
		(width 0.1143)
		(layer "In11.Cu")
		(net "P5E_CPU0_P3_TX_DP<9>")
	)
	(segment
		(start 369.605306 -279.43556)
		(end 369.606068 -279.436068)
		(width 0.1143)
		(layer "In11.Cu")
		(net "P5E_CPU0_P3_TX_DP<9>")
	)
	(segment
		(start 369.16233 -292.210744)
		(end 369.13185 -292.228524)
		(width 0.1143)
		(layer "In11.Cu")
		(net "P5E_CPU0_P3_TX_DP<9>")
	)
	(segment
		(start 369.13185 -286.723582)
		(end 369.164362 -286.742378)
		(width 0.1143)
		(layer "In11.Cu")
		(net "P5E_CPU0_P3_TX_DP<9>")
	)
	(segment
		(start 369.13185 -293.203376)
		(end 369.16233 -293.221156)
		(width 0.1143)
		(layer "In11.Cu")
		(net "P5E_CPU0_P3_TX_DP<9>")
	)
	(segment
		(start 369.13185 -291.583364)
		(end 369.16233 -291.601144)
		(width 0.1143)
		(layer "In11.Cu")
		(net "P5E_CPU0_P3_TX_DP<9>")
	)
	(segment
		(start 369.562634 -279.410668)
		(end 369.569492 -279.414732)
		(width 0.1143)
		(layer "In11.Cu")
		(net "P5E_CPU0_P3_TX_DP<9>")
	)
	(segment
		(start 369.319302 -295.145968)
		(end 369.319556 -295.145968)
		(width 0.1143)
		(layer "In11.Cu")
		(net "P5E_CPU0_P3_TX_DP<9>")
	)
	(segment
		(start 368.191796 -277.00351)
		(end 368.19205 -277.003764)
		(width 0.1143)
		(layer "In11.Cu")
		(net "P5E_CPU0_P3_TX_DP<9>")
	)
	(segment
		(start 369.092734 -293.180516)
		(end 369.13185 -293.203376)
		(width 0.1143)
		(layer "In11.Cu")
		(net "P5E_CPU0_P3_TX_DP<9>")
	)
	(segment
		(start 369.13185 -293.848536)
		(end 369.092734 -293.871396)
		(width 0.1143)
		(layer "In11.Cu")
		(net "P5E_CPU0_P3_TX_DP<9>")
	)
	(segment
		(start 369.565428 -295.612312)
		(end 369.6335 -295.651682)
		(width 0.1143)
		(layer "In11.Cu")
		(net "P5E_CPU0_P3_TX_DP<9>")
	)
	(segment
		(start 368.195352 -277.005542)
		(end 368.221514 -277.020782)
		(width 0.1143)
		(layer "In11.Cu")
		(net "P5E_CPU0_P3_TX_DP<9>")
	)
	(segment
		(start 379.283976 -310.801766)
		(end 384.720338 -318.93764)
		(width 0.14224)
		(layer "In11.Cu")
		(net "P5E_CPU0_P3_TX_DP<9>")
	)
	(segment
		(start 381.722122 -377.1265)
		(end 381.431292 -377.41733)
		(width 0.14224)
		(layer "In11.Cu")
		(net "P5E_CPU0_P3_TX_DP<9>")
	)
	(segment
		(start 369.13185 -294.823388)
		(end 369.16233 -294.841168)
		(width 0.1143)
		(layer "In11.Cu")
		(net "P5E_CPU0_P3_TX_DP<9>")
	)
	(segment
		(start 369.16233 -282.490926)
		(end 369.13185 -282.508706)
		(width 0.1143)
		(layer "In11.Cu")
		(net "P5E_CPU0_P3_TX_DP<9>")
	)
	(segment
		(start 369.16233 -287.350708)
		(end 369.095274 -287.389824)
		(width 0.1143)
		(layer "In11.Cu")
		(net "P5E_CPU0_P3_TX_DP<9>")
	)
	(segment
		(start 369.16233 -293.830756)
		(end 369.13185 -293.848536)
		(width 0.1143)
		(layer "In11.Cu")
		(net "P5E_CPU0_P3_TX_DP<9>")
	)
	(segment
		(start 369.600734 -280.079196)
		(end 369.59921 -280.080212)
		(width 0.1143)
		(layer "In11.Cu")
		(net "P5E_CPU0_P3_TX_DP<9>")
	)
	(segment
		(start 386.423408 -323.048376)
		(end 389.922004 -340.63686)
		(width 0.14224)
		(layer "In11.Cu")
		(net "P5E_CPU0_P3_TX_DP<9>")
	)
	(segment
		(start 382.196594 -374.878092)
		(end 381.987552 -375.26976)
		(width 0.14224)
		(layer "In11.Cu")
		(net "P5E_CPU0_P3_TX_DP<9>")
	)
	(segment
		(start 369.13185 -280.888694)
		(end 369.092734 -280.911554)
		(width 0.1143)
		(layer "In11.Cu")
		(net "P5E_CPU0_P3_TX_DP<9>")
	)
	(segment
		(start 369.092734 -289.940492)
		(end 369.13185 -289.963352)
		(width 0.1143)
		(layer "In11.Cu")
		(net "P5E_CPU0_P3_TX_DP<9>")
	)
	(segment
		(start 369.826032 -296.583862)
		(end 369.826032 -296.61231)
		(width 0.1143)
		(layer "In11.Cu")
		(net "P5E_CPU0_P3_TX_DP<9>")
	)
	(segment
		(start 369.13185 -281.863546)
		(end 369.16233 -281.881326)
		(width 0.1143)
		(layer "In11.Cu")
		(net "P5E_CPU0_P3_TX_DP<9>")
	)
	(segment
		(start 369.16233 -280.870914)
		(end 369.13185 -280.888694)
		(width 0.1143)
		(layer "In11.Cu")
		(net "P5E_CPU0_P3_TX_DP<9>")
	)
	(arc
		(start 369.092734 -292.251384)
		(mid 368.849407 -292.71595)
		(end 369.092734 -293.180516)
		(width 0.1143)
		(layer "In11.Cu")
		(net "P5E_CPU0_P3_TX_DP<9>")
	)
	(arc
		(start 381.987552 -375.26976)
		(mid 381.789499 -375.783499)
		(end 381.722122 -376.329956)
		(width 0.14224)
		(layer "In11.Cu")
		(net "P5E_CPU0_P3_TX_DP<9>")
	)
	(arc
		(start 367.919254 -276.621748)
		(mid 368.000687 -276.824146)
		(end 368.15268 -276.98065)
		(width 0.1143)
		(layer "In11.Cu")
		(net "P5E_CPU0_P3_TX_DP<9>")
	)
	(arc
		(start 369.164362 -286.742378)
		(mid 369.278291 -286.875525)
		(end 369.319302 -287.045908)
		(width 0.1143)
		(layer "In11.Cu")
		(net "P5E_CPU0_P3_TX_DP<9>")
	)
	(arc
		(start 369.16233 -281.881326)
		(mid 369.319307 -282.186126)
		(end 369.16233 -282.490926)
		(width 0.1143)
		(layer "In11.Cu")
		(net "P5E_CPU0_P3_TX_DP<9>")
	)
	(arc
		(start 368.379502 -277.329138)
		(mid 368.440792 -277.583897)
		(end 368.611404 -277.782782)
		(width 0.1143)
		(layer "In11.Cu")
		(net "P5E_CPU0_P3_TX_DP<9>")
	)
	(arc
		(start 368.849402 -287.856168)
		(mid 368.913917 -288.118387)
		(end 369.092734 -288.320734)
		(width 0.1143)
		(layer "In11.Cu")
		(net "P5E_CPU0_P3_TX_DP<9>")
	)
	(arc
		(start 369.16233 -278.641302)
		(mid 369.277757 -278.774678)
		(end 369.319302 -278.946102)
		(width 0.1143)
		(layer "In11.Cu")
		(net "P5E_CPU0_P3_TX_DP<9>")
	)
	(arc
		(start 368.693446 -277.831804)
		(mid 368.808122 -277.965138)
		(end 368.849402 -278.136096)
		(width 0.1143)
		(layer "In11.Cu")
		(net "P5E_CPU0_P3_TX_DP<9>")
	)
	(arc
		(start 369.16233 -283.501338)
		(mid 369.319307 -283.806138)
		(end 369.16233 -284.110938)
		(width 0.1143)
		(layer "In11.Cu")
		(net "P5E_CPU0_P3_TX_DP<9>")
	)
	(arc
		(start 369.16233 -289.981132)
		(mid 369.319307 -290.285932)
		(end 369.16233 -290.590732)
		(width 0.1143)
		(layer "In11.Cu")
		(net "P5E_CPU0_P3_TX_DP<9>")
	)
	(arc
		(start 368.221514 -277.020782)
		(mid 368.337561 -277.154253)
		(end 368.379502 -277.32609)
		(width 0.1143)
		(layer "In11.Cu")
		(net "P5E_CPU0_P3_TX_DP<9>")
	)
	(arc
		(start 369.6335 -295.651682)
		(mid 369.669363 -295.681074)
		(end 369.701318 -295.714674)
		(width 0.1143)
		(layer "In11.Cu")
		(net "P5E_CPU0_P3_TX_DP<9>")
	)
	(arc
		(start 369.16233 -291.601144)
		(mid 369.319307 -291.905944)
		(end 369.16233 -292.210744)
		(width 0.1143)
		(layer "In11.Cu")
		(net "P5E_CPU0_P3_TX_DP<9>")
	)
	(arc
		(start 368.849402 -278.136096)
		(mid 368.913917 -278.398315)
		(end 369.092734 -278.600662)
		(width 0.1143)
		(layer "In11.Cu")
		(net "P5E_CPU0_P3_TX_DP<9>")
	)
	(arc
		(start 369.319302 -280.566114)
		(mid 369.277753 -280.737536)
		(end 369.16233 -280.870914)
		(width 0.1143)
		(layer "In11.Cu")
		(net "P5E_CPU0_P3_TX_DP<9>")
	)
	(arc
		(start 369.092734 -280.911554)
		(mid 368.849407 -281.37612)
		(end 369.092734 -281.840686)
		(width 0.1143)
		(layer "In11.Cu")
		(net "P5E_CPU0_P3_TX_DP<9>")
	)
	(arc
		(start 369.319302 -288.66592)
		(mid 369.277753 -288.837342)
		(end 369.16233 -288.97072)
		(width 0.1143)
		(layer "In11.Cu")
		(net "P5E_CPU0_P3_TX_DP<9>")
	)
	(arc
		(start 369.6335 -279.451816)
		(mid 369.789428 -279.756108)
		(end 369.6335 -280.0604)
		(width 0.1143)
		(layer "In11.Cu")
		(net "P5E_CPU0_P3_TX_DP<9>")
	)
	(arc
		(start 369.16233 -293.221156)
		(mid 369.319307 -293.525956)
		(end 369.16233 -293.830756)
		(width 0.1143)
		(layer "In11.Cu")
		(net "P5E_CPU0_P3_TX_DP<9>")
	)
	(arc
		(start 369.16233 -285.12135)
		(mid 369.319307 -285.42615)
		(end 369.16233 -285.73095)
		(width 0.1143)
		(layer "In11.Cu")
		(net "P5E_CPU0_P3_TX_DP<9>")
	)
	(arc
		(start 369.319302 -278.946102)
		(mid 369.383817 -279.208321)
		(end 369.562634 -279.410668)
		(width 0.1143)
		(layer "In11.Cu")
		(net "P5E_CPU0_P3_TX_DP<9>")
	)
	(arc
		(start 369.319302 -287.045908)
		(mid 369.277753 -287.21733)
		(end 369.16233 -287.350708)
		(width 0.1143)
		(layer "In11.Cu")
		(net "P5E_CPU0_P3_TX_DP<9>")
	)
	(arc
		(start 369.562634 -280.101548)
		(mid 369.383821 -280.303898)
		(end 369.319302 -280.566114)
		(width 0.1143)
		(layer "In11.Cu")
		(net "P5E_CPU0_P3_TX_DP<9>")
	)
	(arc
		(start 369.16233 -294.841168)
		(mid 369.277757 -294.974544)
		(end 369.319302 -295.145968)
		(width 0.1143)
		(layer "In11.Cu")
		(net "P5E_CPU0_P3_TX_DP<9>")
	)
	(arc
		(start 369.092734 -284.151578)
		(mid 368.849407 -284.616144)
		(end 369.092734 -285.08071)
		(width 0.1143)
		(layer "In11.Cu")
		(net "P5E_CPU0_P3_TX_DP<9>")
	)
	(arc
		(start 369.319556 -295.145968)
		(mid 369.384792 -295.409559)
		(end 369.565428 -295.612312)
		(width 0.1143)
		(layer "In11.Cu")
		(net "P5E_CPU0_P3_TX_DP<9>")
	)
	(arc
		(start 369.701318 -295.714674)
		(mid 369.764299 -295.828442)
		(end 369.78971 -295.955974)
		(width 0.1143)
		(layer "In11.Cu")
		(net "P5E_CPU0_P3_TX_DP<9>")
	)
	(arc
		(start 369.092734 -289.01136)
		(mid 368.849407 -289.475926)
		(end 369.092734 -289.940492)
		(width 0.1143)
		(layer "In11.Cu")
		(net "P5E_CPU0_P3_TX_DP<9>")
	)
	(arc
		(start 387.685534 -360.64952)
		(mid 385.37813 -367.932412)
		(end 382.196594 -374.878092)
		(width 0.14224)
		(layer "In11.Cu")
		(net "P5E_CPU0_P3_TX_DP<9>")
	)
	(arc
		(start 369.092734 -290.631372)
		(mid 368.849407 -291.095938)
		(end 369.092734 -291.560504)
		(width 0.1143)
		(layer "In11.Cu")
		(net "P5E_CPU0_P3_TX_DP<9>")
	)
	(arc
		(start 369.092734 -293.871396)
		(mid 368.849407 -294.335962)
		(end 369.092734 -294.800528)
		(width 0.1143)
		(layer "In11.Cu")
		(net "P5E_CPU0_P3_TX_DP<9>")
	)
	(arc
		(start 367.915444 -276.598888)
		(mid 367.917232 -276.610337)
		(end 367.919254 -276.621748)
		(width 0.1143)
		(layer "In11.Cu")
		(net "P5E_CPU0_P3_TX_DP<9>")
	)
	(arc
		(start 369.092734 -282.531566)
		(mid 368.849407 -282.996132)
		(end 369.092734 -283.460698)
		(width 0.1143)
		(layer "In11.Cu")
		(net "P5E_CPU0_P3_TX_DP<9>")
	)
	(arc
		(start 369.164362 -288.36239)
		(mid 369.278291 -288.495537)
		(end 369.319302 -288.66592)
		(width 0.1143)
		(layer "In11.Cu")
		(net "P5E_CPU0_P3_TX_DP<9>")
	)
	(arc
		(start 369.092734 -285.77159)
		(mid 368.849407 -286.236156)
		(end 369.092734 -286.700722)
		(width 0.1143)
		(layer "In11.Cu")
		(net "P5E_CPU0_P3_TX_DP<9>")
	)
	(arc
		(start 369.095274 -287.389824)
		(mid 368.914622 -287.592569)
		(end 368.849402 -287.856168)
		(width 0.1143)
		(layer "In11.Cu")
		(net "P5E_CPU0_P3_TX_DP<9>")
	)
	(segment
		(start 380.000002 -380.15164)
		(end 380.000002 -380.85522)
		(width 0.12954)
		(layer "F.Cu")
		(net "P5E_CPU0_P3_TX_DP<8>")
	)
	(segment
		(start 380.000002 -380.85522)
		(end 379.704092 -381.15113)
		(width 0.12954)
		(layer "F.Cu")
		(net "P5E_CPU0_P3_TX_DP<8>")
	)
	(segment
		(start 367.067846 -277.870158)
		(end 367.534698 -278.136096)
		(width 0.12954)
		(layer "F.Cu")
		(net "P5E_CPU0_P3_TX_DP<8>")
	)
	(segment
		(start 379.729492 -379.88113)
		(end 380.000002 -380.15164)
		(width 0.12954)
		(layer "F.Cu")
		(net "P5E_CPU0_P3_TX_DP<8>")
	)
	(segment
		(start 368.227356 -287.347406)
		(end 368.223546 -287.3502)
		(width 0.1143)
		(layer "In11.Cu")
		(net "P5E_CPU0_P3_TX_DP<8>")
	)
	(segment
		(start 368.1603 -283.46527)
		(end 368.191796 -283.483558)
		(width 0.1143)
		(layer "In11.Cu")
		(net "P5E_CPU0_P3_TX_DP<8>")
	)
	(segment
		(start 388.987538 -340.71814)
		(end 388.987538 -349.184468)
		(width 0.14224)
		(layer "In11.Cu")
		(net "P5E_CPU0_P3_TX_DP<8>")
	)
	(segment
		(start 378.684282 -311.602628)
		(end 383.839212 -319.317116)
		(width 0.14224)
		(layer "In11.Cu")
		(net "P5E_CPU0_P3_TX_DP<8>")
	)
	(segment
		(start 368.15268 -278.600662)
		(end 368.159538 -278.604726)
		(width 0.1143)
		(layer "In11.Cu")
		(net "P5E_CPU0_P3_TX_DP<8>")
	)
	(segment
		(start 388.485634 -353.25304)
		(end 386.99948 -359.185464)
		(width 0.14224)
		(layer "In11.Cu")
		(net "P5E_CPU0_P3_TX_DP<8>")
	)
	(segment
		(start 368.19459 -289.96513)
		(end 368.195098 -289.96513)
		(width 0.1143)
		(layer "In11.Cu")
		(net "P5E_CPU0_P3_TX_DP<8>")
	)
	(segment
		(start 368.849656 -296.188892)
		(end 368.92611 -296.265346)
		(width 0.1143)
		(layer "In11.Cu")
		(net "P5E_CPU0_P3_TX_DP<8>")
	)
	(segment
		(start 368.88039 -296.61231)
		(end 368.88039 -296.659554)
		(width 0.14224)
		(layer "In11.Cu")
		(net "P5E_CPU0_P3_TX_DP<8>")
	)
	(segment
		(start 368.159538 -283.464762)
		(end 368.1603 -283.46527)
		(width 0.1143)
		(layer "In11.Cu")
		(net "P5E_CPU0_P3_TX_DP<8>")
	)
	(segment
		(start 368.192558 -278.62403)
		(end 368.192558 -278.623776)
		(width 0.1143)
		(layer "In11.Cu")
		(net "P5E_CPU0_P3_TX_DP<8>")
	)
	(segment
		(start 369.825016 -300.235112)
		(end 371.884702 -303.317402)
		(width 0.14224)
		(layer "In11.Cu")
		(net "P5E_CPU0_P3_TX_DP<8>")
	)
	(segment
		(start 368.379502 -295.14165)
		(end 368.379502 -295.145968)
		(width 0.1143)
		(layer "In11.Cu")
		(net "P5E_CPU0_P3_TX_DP<8>")
	)
	(segment
		(start 380.020322 -379.5903)
		(end 379.729492 -379.88113)
		(width 0.14224)
		(layer "In11.Cu")
		(net "P5E_CPU0_P3_TX_DP<8>")
	)
	(segment
		(start 368.191796 -289.963352)
		(end 368.192558 -289.96386)
		(width 0.1143)
		(layer "In11.Cu")
		(net "P5E_CPU0_P3_TX_DP<8>")
	)
	(segment
		(start 368.66195 -279.433528)
		(end 368.693446 -279.45207)
		(width 0.1143)
		(layer "In11.Cu")
		(net "P5E_CPU0_P3_TX_DP<8>")
	)
	(segment
		(start 368.191796 -292.228524)
		(end 368.19078 -292.229032)
		(width 0.1143)
		(layer "In11.Cu")
		(net "P5E_CPU0_P3_TX_DP<8>")
	)
	(segment
		(start 368.186208 -292.231826)
		(end 368.15268 -292.251384)
		(width 0.1143)
		(layer "In11.Cu")
		(net "P5E_CPU0_P3_TX_DP<8>")
	)
	(segment
		(start 368.192558 -290.608258)
		(end 368.191796 -290.608512)
		(width 0.1143)
		(layer "In11.Cu")
		(net "P5E_CPU0_P3_TX_DP<8>")
	)
	(segment
		(start 368.92611 -296.265346)
		(end 368.92611 -296.538142)
		(width 0.1143)
		(layer "In11.Cu")
		(net "P5E_CPU0_P3_TX_DP<8>")
	)
	(segment
		(start 368.191796 -278.623522)
		(end 368.192558 -278.62403)
		(width 0.1143)
		(layer "In11.Cu")
		(net "P5E_CPU0_P3_TX_DP<8>")
	)
	(segment
		(start 368.191796 -293.203376)
		(end 368.192558 -293.203884)
		(width 0.1143)
		(layer "In11.Cu")
		(net "P5E_CPU0_P3_TX_DP<8>")
	)
	(segment
		(start 368.223546 -291.601652)
		(end 368.228626 -291.605208)
		(width 0.1143)
		(layer "In11.Cu")
		(net "P5E_CPU0_P3_TX_DP<8>")
	)
	(segment
		(start 368.191796 -281.863546)
		(end 368.192558 -281.864054)
		(width 0.1143)
		(layer "In11.Cu")
		(net "P5E_CPU0_P3_TX_DP<8>")
	)
	(segment
		(start 368.19078 -294.82288)
		(end 368.194336 -294.824658)
		(width 0.1143)
		(layer "In11.Cu")
		(net "P5E_CPU0_P3_TX_DP<8>")
	)
	(segment
		(start 368.849402 -295.955974)
		(end 368.849656 -295.95572)
		(width 0.1143)
		(layer "In11.Cu")
		(net "P5E_CPU0_P3_TX_DP<8>")
	)
	(segment
		(start 368.15268 -291.560504)
		(end 368.19078 -291.582856)
		(width 0.1143)
		(layer "In11.Cu")
		(net "P5E_CPU0_P3_TX_DP<8>")
	)
	(segment
		(start 368.19078 -285.749238)
		(end 368.15268 -285.77159)
		(width 0.1143)
		(layer "In11.Cu")
		(net "P5E_CPU0_P3_TX_DP<8>")
	)
	(segment
		(start 368.192558 -281.864054)
		(end 368.19459 -281.865324)
		(width 0.1143)
		(layer "In11.Cu")
		(net "P5E_CPU0_P3_TX_DP<8>")
	)
	(segment
		(start 368.19078 -290.60902)
		(end 368.15268 -290.631372)
		(width 0.1143)
		(layer "In11.Cu")
		(net "P5E_CPU0_P3_TX_DP<8>")
	)
	(segment
		(start 368.19078 -281.863038)
		(end 368.191796 -281.863546)
		(width 0.1143)
		(layer "In11.Cu")
		(net "P5E_CPU0_P3_TX_DP<8>")
	)
	(segment
		(start 368.194844 -285.746952)
		(end 368.192558 -285.748476)
		(width 0.1143)
		(layer "In11.Cu")
		(net "P5E_CPU0_P3_TX_DP<8>")
	)
	(segment
		(start 368.19459 -293.205154)
		(end 368.195098 -293.205154)
		(width 0.1143)
		(layer "In11.Cu")
		(net "P5E_CPU0_P3_TX_DP<8>")
	)
	(segment
		(start 368.192558 -282.508452)
		(end 368.191796 -282.508706)
		(width 0.1143)
		(layer "In11.Cu")
		(net "P5E_CPU0_P3_TX_DP<8>")
	)
	(segment
		(start 368.15268 -293.180516)
		(end 368.19078 -293.202868)
		(width 0.1143)
		(layer "In11.Cu")
		(net "P5E_CPU0_P3_TX_DP<8>")
	)
	(segment
		(start 368.228626 -292.20668)
		(end 368.223546 -292.210236)
		(width 0.1143)
		(layer "In11.Cu")
		(net "P5E_CPU0_P3_TX_DP<8>")
	)
	(segment
		(start 368.19078 -282.509214)
		(end 368.15268 -282.531566)
		(width 0.1143)
		(layer "In11.Cu")
		(net "P5E_CPU0_P3_TX_DP<8>")
	)
	(segment
		(start 368.19078 -289.962844)
		(end 368.191796 -289.963352)
		(width 0.1143)
		(layer "In11.Cu")
		(net "P5E_CPU0_P3_TX_DP<8>")
	)
	(segment
		(start 368.192558 -285.748476)
		(end 368.191796 -285.74873)
		(width 0.1143)
		(layer "In11.Cu")
		(net "P5E_CPU0_P3_TX_DP<8>")
	)
	(segment
		(start 368.15903 -288.32429)
		(end 368.194844 -288.345118)
		(width 0.1143)
		(layer "In11.Cu")
		(net "P5E_CPU0_P3_TX_DP<8>")
	)
	(segment
		(start 368.192558 -293.848282)
		(end 368.191796 -293.848536)
		(width 0.1143)
		(layer "In11.Cu")
		(net "P5E_CPU0_P3_TX_DP<8>")
	)
	(segment
		(start 368.192558 -284.128464)
		(end 368.191796 -284.128718)
		(width 0.1143)
		(layer "In11.Cu")
		(net "P5E_CPU0_P3_TX_DP<8>")
	)
	(segment
		(start 368.195352 -285.746952)
		(end 368.194844 -285.746952)
		(width 0.1143)
		(layer "In11.Cu")
		(net "P5E_CPU0_P3_TX_DP<8>")
	)
	(segment
		(start 368.19459 -281.865324)
		(end 368.195098 -281.865324)
		(width 0.1143)
		(layer "In11.Cu")
		(net "P5E_CPU0_P3_TX_DP<8>")
	)
	(segment
		(start 367.83264 -278.136096)
		(end 367.915444 -278.2189)
		(width 0.1143)
		(layer "In11.Cu")
		(net "P5E_CPU0_P3_TX_DP<8>")
	)
	(segment
		(start 368.191796 -288.9885)
		(end 368.19078 -288.989008)
		(width 0.1143)
		(layer "In11.Cu")
		(net "P5E_CPU0_P3_TX_DP<8>")
	)
	(segment
		(start 368.15268 -286.700722)
		(end 368.225324 -286.74314)
		(width 0.1143)
		(layer "In11.Cu")
		(net "P5E_CPU0_P3_TX_DP<8>")
	)
	(segment
		(start 381.095504 -374.490742)
		(end 380.1745 -376.21464)
		(width 0.14224)
		(layer "In11.Cu")
		(net "P5E_CPU0_P3_TX_DP<8>")
	)
	(segment
		(start 368.15268 -289.940492)
		(end 368.19078 -289.962844)
		(width 0.1143)
		(layer "In11.Cu")
		(net "P5E_CPU0_P3_TX_DP<8>")
	)
	(segment
		(start 385.554474 -323.459094)
		(end 388.987538 -340.71814)
		(width 0.14224)
		(layer "In11.Cu")
		(net "P5E_CPU0_P3_TX_DP<8>")
	)
	(segment
		(start 368.191796 -284.128718)
		(end 368.19078 -284.129226)
		(width 0.1143)
		(layer "In11.Cu")
		(net "P5E_CPU0_P3_TX_DP<8>")
	)
	(segment
		(start 368.187224 -292.231318)
		(end 368.186208 -292.231826)
		(width 0.1143)
		(layer "In11.Cu")
		(net "P5E_CPU0_P3_TX_DP<8>")
	)
	(segment
		(start 368.193574 -278.624284)
		(end 368.20729 -278.632158)
		(width 0.1143)
		(layer "In11.Cu")
		(net "P5E_CPU0_P3_TX_DP<8>")
	)
	(segment
		(start 368.15268 -283.460698)
		(end 368.159538 -283.464762)
		(width 0.1143)
		(layer "In11.Cu")
		(net "P5E_CPU0_P3_TX_DP<8>")
	)
	(segment
		(start 368.19078 -285.103062)
		(end 368.191796 -285.10357)
		(width 0.1143)
		(layer "In11.Cu")
		(net "P5E_CPU0_P3_TX_DP<8>")
	)
	(segment
		(start 368.195352 -282.506928)
		(end 368.194844 -282.506928)
		(width 0.1143)
		(layer "In11.Cu")
		(net "P5E_CPU0_P3_TX_DP<8>")
	)
	(segment
		(start 383.839212 -319.317116)
		(end 385.554474 -323.459094)
		(width 0.14224)
		(layer "In11.Cu")
		(net "P5E_CPU0_P3_TX_DP<8>")
	)
	(segment
		(start 368.191796 -291.583364)
		(end 368.192558 -291.583872)
		(width 0.1143)
		(layer "In11.Cu")
		(net "P5E_CPU0_P3_TX_DP<8>")
	)
	(segment
		(start 368.192558 -283.484066)
		(end 368.19459 -283.485336)
		(width 0.1143)
		(layer "In11.Cu")
		(net "P5E_CPU0_P3_TX_DP<8>")
	)
	(segment
		(start 368.195352 -290.606734)
		(end 368.194844 -290.606734)
		(width 0.1143)
		(layer "In11.Cu")
		(net "P5E_CPU0_P3_TX_DP<8>")
	)
	(segment
		(start 368.158776 -288.32429)
		(end 368.15903 -288.32429)
		(width 0.1143)
		(layer "In11.Cu")
		(net "P5E_CPU0_P3_TX_DP<8>")
	)
	(segment
		(start 368.192558 -292.228016)
		(end 368.191796 -292.228524)
		(width 0.1143)
		(layer "In11.Cu")
		(net "P5E_CPU0_P3_TX_DP<8>")
	)
	(segment
		(start 368.19078 -284.129226)
		(end 368.15268 -284.151578)
		(width 0.1143)
		(layer "In11.Cu")
		(net "P5E_CPU0_P3_TX_DP<8>")
	)
	(segment
		(start 368.192558 -280.888186)
		(end 368.191796 -280.888694)
		(width 0.1143)
		(layer "In11.Cu")
		(net "P5E_CPU0_P3_TX_DP<8>")
	)
	(segment
		(start 368.19078 -288.989008)
		(end 368.15268 -289.01136)
		(width 0.1143)
		(layer "In11.Cu")
		(net "P5E_CPU0_P3_TX_DP<8>")
	)
	(segment
		(start 368.194844 -290.606734)
		(end 368.192558 -290.608258)
		(width 0.1143)
		(layer "In11.Cu")
		(net "P5E_CPU0_P3_TX_DP<8>")
	)
	(segment
		(start 368.19459 -285.105348)
		(end 368.195098 -285.105348)
		(width 0.1143)
		(layer "In11.Cu")
		(net "P5E_CPU0_P3_TX_DP<8>")
	)
	(segment
		(start 367.534698 -278.136096)
		(end 367.83264 -278.136096)
		(width 0.1143)
		(layer "In11.Cu")
		(net "P5E_CPU0_P3_TX_DP<8>")
	)
	(segment
		(start 368.15268 -285.08071)
		(end 368.19078 -285.103062)
		(width 0.1143)
		(layer "In11.Cu")
		(net "P5E_CPU0_P3_TX_DP<8>")
	)
	(segment
		(start 368.191796 -285.10357)
		(end 368.192558 -285.104078)
		(width 0.1143)
		(layer "In11.Cu")
		(net "P5E_CPU0_P3_TX_DP<8>")
	)
	(segment
		(start 368.392202 -278.953468)
		(end 368.392202 -278.965914)
		(width 0.1143)
		(layer "In11.Cu")
		(net "P5E_CPU0_P3_TX_DP<8>")
	)
	(segment
		(start 368.88039 -296.583862)
		(end 368.88039 -296.61231)
		(width 0.1143)
		(layer "In11.Cu")
		(net "P5E_CPU0_P3_TX_DP<8>")
	)
	(segment
		(start 368.159538 -278.604726)
		(end 368.1603 -278.605234)
		(width 0.1143)
		(layer "In11.Cu")
		(net "P5E_CPU0_P3_TX_DP<8>")
	)
	(segment
		(start 368.15268 -288.320734)
		(end 368.158776 -288.32429)
		(width 0.1143)
		(layer "In11.Cu")
		(net "P5E_CPU0_P3_TX_DP<8>")
	)
	(segment
		(start 368.367564 -280.574496)
		(end 368.367564 -280.585926)
		(width 0.1143)
		(layer "In11.Cu")
		(net "P5E_CPU0_P3_TX_DP<8>")
	)
	(segment
		(start 368.194844 -293.846758)
		(end 368.192558 -293.848282)
		(width 0.1143)
		(layer "In11.Cu")
		(net "P5E_CPU0_P3_TX_DP<8>")
	)
	(segment
		(start 380.020322 -376.831352)
		(end 380.020322 -379.5903)
		(width 0.14224)
		(layer "In11.Cu")
		(net "P5E_CPU0_P3_TX_DP<8>")
	)
	(segment
		(start 368.379502 -287.045908)
		(end 368.379502 -287.05048)
		(width 0.1143)
		(layer "In11.Cu")
		(net "P5E_CPU0_P3_TX_DP<8>")
	)
	(segment
		(start 368.646456 -295.62425)
		(end 368.693446 -295.651936)
		(width 0.1143)
		(layer "In11.Cu")
		(net "P5E_CPU0_P3_TX_DP<8>")
	)
	(segment
		(start 368.880898 -297.122342)
		(end 369.825016 -300.235112)
		(width 0.14224)
		(layer "In11.Cu")
		(net "P5E_CPU0_P3_TX_DP<8>")
	)
	(segment
		(start 368.191796 -285.74873)
		(end 368.19078 -285.749238)
		(width 0.1143)
		(layer "In11.Cu")
		(net "P5E_CPU0_P3_TX_DP<8>")
	)
	(segment
		(start 368.192558 -293.203884)
		(end 368.19459 -293.205154)
		(width 0.1143)
		(layer "In11.Cu")
		(net "P5E_CPU0_P3_TX_DP<8>")
	)
	(segment
		(start 368.19078 -291.582856)
		(end 368.191796 -291.583364)
		(width 0.1143)
		(layer "In11.Cu")
		(net "P5E_CPU0_P3_TX_DP<8>")
	)
	(segment
		(start 368.194844 -282.506928)
		(end 368.192558 -282.508452)
		(width 0.1143)
		(layer "In11.Cu")
		(net "P5E_CPU0_P3_TX_DP<8>")
	)
	(segment
		(start 368.194336 -294.824658)
		(end 368.224562 -294.842692)
		(width 0.1143)
		(layer "In11.Cu")
		(net "P5E_CPU0_P3_TX_DP<8>")
	)
	(segment
		(start 368.192558 -278.623776)
		(end 368.193574 -278.624284)
		(width 0.1143)
		(layer "In11.Cu")
		(net "P5E_CPU0_P3_TX_DP<8>")
	)
	(segment
		(start 368.191796 -280.888694)
		(end 368.19078 -280.889202)
		(width 0.1143)
		(layer "In11.Cu")
		(net "P5E_CPU0_P3_TX_DP<8>")
	)
	(segment
		(start 368.192558 -291.583872)
		(end 368.223546 -291.601652)
		(width 0.1143)
		(layer "In11.Cu")
		(net "P5E_CPU0_P3_TX_DP<8>")
	)
	(segment
		(start 368.192558 -288.988246)
		(end 368.191796 -288.9885)
		(width 0.1143)
		(layer "In11.Cu")
		(net "P5E_CPU0_P3_TX_DP<8>")
	)
	(segment
		(start 368.693446 -280.0604)
		(end 368.648742 -280.086308)
		(width 0.1143)
		(layer "In11.Cu")
		(net "P5E_CPU0_P3_TX_DP<8>")
	)
	(segment
		(start 368.1603 -278.605234)
		(end 368.191796 -278.623522)
		(width 0.1143)
		(layer "In11.Cu")
		(net "P5E_CPU0_P3_TX_DP<8>")
	)
	(segment
		(start 368.15268 -294.800528)
		(end 368.19078 -294.82288)
		(width 0.1143)
		(layer "In11.Cu")
		(net "P5E_CPU0_P3_TX_DP<8>")
	)
	(segment
		(start 368.849656 -295.95572)
		(end 368.849656 -296.188892)
		(width 0.1143)
		(layer "In11.Cu")
		(net "P5E_CPU0_P3_TX_DP<8>")
	)
	(segment
		(start 368.195352 -284.12694)
		(end 368.194844 -284.12694)
		(width 0.1143)
		(layer "In11.Cu")
		(net "P5E_CPU0_P3_TX_DP<8>")
	)
	(segment
		(start 368.195352 -288.986722)
		(end 368.194844 -288.986722)
		(width 0.1143)
		(layer "In11.Cu")
		(net "P5E_CPU0_P3_TX_DP<8>")
	)
	(segment
		(start 368.194844 -288.345118)
		(end 368.195098 -288.345118)
		(width 0.1143)
		(layer "In11.Cu")
		(net "P5E_CPU0_P3_TX_DP<8>")
	)
	(segment
		(start 368.19078 -280.889202)
		(end 368.15268 -280.911554)
		(width 0.1143)
		(layer "In11.Cu")
		(net "P5E_CPU0_P3_TX_DP<8>")
	)
	(segment
		(start 368.622834 -295.610534)
		(end 368.646202 -295.62425)
		(width 0.1143)
		(layer "In11.Cu")
		(net "P5E_CPU0_P3_TX_DP<8>")
	)
	(segment
		(start 368.19078 -292.229032)
		(end 368.188748 -292.230302)
		(width 0.1143)
		(layer "In11.Cu")
		(net "P5E_CPU0_P3_TX_DP<8>")
	)
	(segment
		(start 368.191796 -290.608512)
		(end 368.19078 -290.60902)
		(width 0.1143)
		(layer "In11.Cu")
		(net "P5E_CPU0_P3_TX_DP<8>")
	)
	(segment
		(start 368.194844 -288.986722)
		(end 368.192558 -288.988246)
		(width 0.1143)
		(layer "In11.Cu")
		(net "P5E_CPU0_P3_TX_DP<8>")
	)
	(segment
		(start 368.191796 -283.483558)
		(end 368.192558 -283.484066)
		(width 0.1143)
		(layer "In11.Cu")
		(net "P5E_CPU0_P3_TX_DP<8>")
	)
	(segment
		(start 368.192558 -289.96386)
		(end 368.19459 -289.96513)
		(width 0.1143)
		(layer "In11.Cu")
		(net "P5E_CPU0_P3_TX_DP<8>")
	)
	(segment
		(start 368.880898 -296.660062)
		(end 368.880898 -297.122342)
		(width 0.14224)
		(layer "In11.Cu")
		(net "P5E_CPU0_P3_TX_DP<8>")
	)
	(segment
		(start 368.192558 -285.104078)
		(end 368.19459 -285.105348)
		(width 0.1143)
		(layer "In11.Cu")
		(net "P5E_CPU0_P3_TX_DP<8>")
	)
	(segment
		(start 368.19078 -293.202868)
		(end 368.191796 -293.203376)
		(width 0.1143)
		(layer "In11.Cu")
		(net "P5E_CPU0_P3_TX_DP<8>")
	)
	(segment
		(start 368.88039 -296.659554)
		(end 368.880898 -296.660062)
		(width 0.14224)
		(layer "In11.Cu")
		(net "P5E_CPU0_P3_TX_DP<8>")
	)
	(segment
		(start 368.15268 -281.840686)
		(end 368.19078 -281.863038)
		(width 0.1143)
		(layer "In11.Cu")
		(net "P5E_CPU0_P3_TX_DP<8>")
	)
	(segment
		(start 368.194844 -284.12694)
		(end 368.192558 -284.128464)
		(width 0.1143)
		(layer "In11.Cu")
		(net "P5E_CPU0_P3_TX_DP<8>")
	)
	(segment
		(start 368.188748 -292.230302)
		(end 368.187224 -292.231318)
		(width 0.1143)
		(layer "In11.Cu")
		(net "P5E_CPU0_P3_TX_DP<8>")
	)
	(segment
		(start 368.195352 -293.846758)
		(end 368.194844 -293.846758)
		(width 0.1143)
		(layer "In11.Cu")
		(net "P5E_CPU0_P3_TX_DP<8>")
	)
	(segment
		(start 368.191796 -282.508706)
		(end 368.19078 -282.509214)
		(width 0.1143)
		(layer "In11.Cu")
		(net "P5E_CPU0_P3_TX_DP<8>")
	)
	(segment
		(start 368.223546 -287.3502)
		(end 368.15522 -287.389824)
		(width 0.1143)
		(layer "In11.Cu")
		(net "P5E_CPU0_P3_TX_DP<8>")
	)
	(segment
		(start 368.223546 -292.210236)
		(end 368.192558 -292.228016)
		(width 0.1143)
		(layer "In11.Cu")
		(net "P5E_CPU0_P3_TX_DP<8>")
	)
	(segment
		(start 368.19459 -283.485336)
		(end 368.195098 -283.485336)
		(width 0.1143)
		(layer "In11.Cu")
		(net "P5E_CPU0_P3_TX_DP<8>")
	)
	(segment
		(start 368.191796 -293.848536)
		(end 368.19078 -293.849044)
		(width 0.1143)
		(layer "In11.Cu")
		(net "P5E_CPU0_P3_TX_DP<8>")
	)
	(segment
		(start 368.19078 -293.849044)
		(end 368.15268 -293.871396)
		(width 0.1143)
		(layer "In11.Cu")
		(net "P5E_CPU0_P3_TX_DP<8>")
	)
	(segment
		(start 371.884702 -303.317402)
		(end 378.684282 -311.602628)
		(width 0.14224)
		(layer "In11.Cu")
		(net "P5E_CPU0_P3_TX_DP<8>")
	)
	(segment
		(start 368.92611 -296.538142)
		(end 368.88039 -296.583862)
		(width 0.1143)
		(layer "In11.Cu")
		(net "P5E_CPU0_P3_TX_DP<8>")
	)
	(segment
		(start 368.646202 -295.62425)
		(end 368.646456 -295.62425)
		(width 0.1143)
		(layer "In11.Cu")
		(net "P5E_CPU0_P3_TX_DP<8>")
	)
	(arc
		(start 386.99948 -359.185464)
		(mid 384.517537 -367.019421)
		(end 381.095504 -374.490742)
		(width 0.14224)
		(layer "In11.Cu")
		(net "P5E_CPU0_P3_TX_DP<8>")
	)
	(arc
		(start 368.648742 -280.086308)
		(mid 368.442883 -280.292809)
		(end 368.367564 -280.574496)
		(width 0.1143)
		(layer "In11.Cu")
		(net "P5E_CPU0_P3_TX_DP<8>")
	)
	(arc
		(start 368.829082 -279.634442)
		(mid 368.831703 -279.869851)
		(end 368.693446 -280.0604)
		(width 0.1143)
		(layer "In11.Cu")
		(net "P5E_CPU0_P3_TX_DP<8>")
	)
	(arc
		(start 368.15522 -287.389824)
		(mid 367.974568 -287.592569)
		(end 367.909348 -287.856168)
		(width 0.1143)
		(layer "In11.Cu")
		(net "P5E_CPU0_P3_TX_DP<8>")
	)
	(arc
		(start 368.224562 -294.842692)
		(mid 368.338445 -294.973306)
		(end 368.379502 -295.14165)
		(width 0.1143)
		(layer "In11.Cu")
		(net "P5E_CPU0_P3_TX_DP<8>")
	)
	(arc
		(start 368.15268 -284.151578)
		(mid 367.909353 -284.616144)
		(end 368.15268 -285.08071)
		(width 0.1143)
		(layer "In11.Cu")
		(net "P5E_CPU0_P3_TX_DP<8>")
	)
	(arc
		(start 368.195098 -288.345118)
		(mid 368.379831 -288.66581)
		(end 368.195352 -288.986722)
		(width 0.1143)
		(layer "In11.Cu")
		(net "P5E_CPU0_P3_TX_DP<8>")
	)
	(arc
		(start 368.693446 -295.651936)
		(mid 368.808122 -295.785127)
		(end 368.849402 -295.955974)
		(width 0.1143)
		(layer "In11.Cu")
		(net "P5E_CPU0_P3_TX_DP<8>")
	)
	(arc
		(start 368.693446 -279.45207)
		(mid 368.775427 -279.53272)
		(end 368.829082 -279.634442)
		(width 0.1143)
		(layer "In11.Cu")
		(net "P5E_CPU0_P3_TX_DP<8>")
	)
	(arc
		(start 368.228626 -291.605208)
		(mid 368.382724 -291.905944)
		(end 368.228626 -292.20668)
		(width 0.1143)
		(layer "In11.Cu")
		(net "P5E_CPU0_P3_TX_DP<8>")
	)
	(arc
		(start 368.379502 -295.145968)
		(mid 368.444017 -295.408187)
		(end 368.622834 -295.610534)
		(width 0.1143)
		(layer "In11.Cu")
		(net "P5E_CPU0_P3_TX_DP<8>")
	)
	(arc
		(start 380.1745 -376.21464)
		(mid 380.059423 -376.513496)
		(end 380.020322 -376.831352)
		(width 0.14224)
		(layer "In11.Cu")
		(net "P5E_CPU0_P3_TX_DP<8>")
	)
	(arc
		(start 367.909348 -287.856168)
		(mid 367.973863 -288.118387)
		(end 368.15268 -288.320734)
		(width 0.1143)
		(layer "In11.Cu")
		(net "P5E_CPU0_P3_TX_DP<8>")
	)
	(arc
		(start 367.915444 -278.2189)
		(mid 367.917232 -278.230349)
		(end 367.919254 -278.24176)
		(width 0.1143)
		(layer "In11.Cu")
		(net "P5E_CPU0_P3_TX_DP<8>")
	)
	(arc
		(start 368.195098 -281.865324)
		(mid 368.379831 -282.186016)
		(end 368.195352 -282.506928)
		(width 0.1143)
		(layer "In11.Cu")
		(net "P5E_CPU0_P3_TX_DP<8>")
	)
	(arc
		(start 368.20729 -278.632158)
		(mid 368.342678 -278.768107)
		(end 368.392202 -278.953468)
		(width 0.1143)
		(layer "In11.Cu")
		(net "P5E_CPU0_P3_TX_DP<8>")
	)
	(arc
		(start 368.195098 -285.105348)
		(mid 368.379831 -285.42604)
		(end 368.195352 -285.746952)
		(width 0.1143)
		(layer "In11.Cu")
		(net "P5E_CPU0_P3_TX_DP<8>")
	)
	(arc
		(start 388.987538 -349.184468)
		(mid 388.86157 -351.234172)
		(end 388.485634 -353.25304)
		(width 0.14224)
		(layer "In11.Cu")
		(net "P5E_CPU0_P3_TX_DP<8>")
	)
	(arc
		(start 368.367564 -280.585926)
		(mid 368.320653 -280.760555)
		(end 368.192558 -280.888186)
		(width 0.1143)
		(layer "In11.Cu")
		(net "P5E_CPU0_P3_TX_DP<8>")
	)
	(arc
		(start 368.379502 -287.05048)
		(mid 368.339247 -287.217293)
		(end 368.227356 -287.347406)
		(width 0.1143)
		(layer "In11.Cu")
		(net "P5E_CPU0_P3_TX_DP<8>")
	)
	(arc
		(start 368.15268 -290.631372)
		(mid 367.909353 -291.095938)
		(end 368.15268 -291.560504)
		(width 0.1143)
		(layer "In11.Cu")
		(net "P5E_CPU0_P3_TX_DP<8>")
	)
	(arc
		(start 368.392202 -278.965914)
		(mid 368.464467 -279.235843)
		(end 368.66195 -279.433528)
		(width 0.1143)
		(layer "In11.Cu")
		(net "P5E_CPU0_P3_TX_DP<8>")
	)
	(arc
		(start 368.195098 -289.96513)
		(mid 368.379831 -290.285822)
		(end 368.195352 -290.606734)
		(width 0.1143)
		(layer "In11.Cu")
		(net "P5E_CPU0_P3_TX_DP<8>")
	)
	(arc
		(start 368.15268 -292.251384)
		(mid 367.909353 -292.71595)
		(end 368.15268 -293.180516)
		(width 0.1143)
		(layer "In11.Cu")
		(net "P5E_CPU0_P3_TX_DP<8>")
	)
	(arc
		(start 368.15268 -282.531566)
		(mid 367.909353 -282.996132)
		(end 368.15268 -283.460698)
		(width 0.1143)
		(layer "In11.Cu")
		(net "P5E_CPU0_P3_TX_DP<8>")
	)
	(arc
		(start 367.919254 -278.24176)
		(mid 368.000687 -278.444158)
		(end 368.15268 -278.600662)
		(width 0.1143)
		(layer "In11.Cu")
		(net "P5E_CPU0_P3_TX_DP<8>")
	)
	(arc
		(start 368.195098 -283.485336)
		(mid 368.379831 -283.806028)
		(end 368.195352 -284.12694)
		(width 0.1143)
		(layer "In11.Cu")
		(net "P5E_CPU0_P3_TX_DP<8>")
	)
	(arc
		(start 368.225324 -286.74314)
		(mid 368.338731 -286.876029)
		(end 368.379502 -287.045908)
		(width 0.1143)
		(layer "In11.Cu")
		(net "P5E_CPU0_P3_TX_DP<8>")
	)
	(arc
		(start 368.15268 -293.871396)
		(mid 367.909353 -294.335962)
		(end 368.15268 -294.800528)
		(width 0.1143)
		(layer "In11.Cu")
		(net "P5E_CPU0_P3_TX_DP<8>")
	)
	(arc
		(start 368.15268 -289.01136)
		(mid 367.909353 -289.475926)
		(end 368.15268 -289.940492)
		(width 0.1143)
		(layer "In11.Cu")
		(net "P5E_CPU0_P3_TX_DP<8>")
	)
	(arc
		(start 368.15268 -285.77159)
		(mid 367.909353 -286.236156)
		(end 368.15268 -286.700722)
		(width 0.1143)
		(layer "In11.Cu")
		(net "P5E_CPU0_P3_TX_DP<8>")
	)
	(arc
		(start 368.195098 -293.205154)
		(mid 368.379831 -293.525846)
		(end 368.195352 -293.846758)
		(width 0.1143)
		(layer "In11.Cu")
		(net "P5E_CPU0_P3_TX_DP<8>")
	)
	(arc
		(start 368.15268 -280.911554)
		(mid 367.909353 -281.37612)
		(end 368.15268 -281.840686)
		(width 0.1143)
		(layer "In11.Cu")
		(net "P5E_CPU0_P3_TX_DP<8>")
	)
	(segment
		(start 364.247938 -274.630134)
		(end 364.71479 -274.896072)
		(width 0.12954)
		(layer "F.Cu")
		(net "P5E_CPU0_P3_TX_DP<3>")
	)
	(segment
		(start 367.816892 -377.41733)
		(end 368.087402 -377.68784)
		(width 0.12954)
		(layer "F.Cu")
		(net "P5E_CPU0_P3_TX_DP<3>")
	)
	(segment
		(start 368.087402 -378.39142)
		(end 367.791492 -378.68733)
		(width 0.12954)
		(layer "F.Cu")
		(net "P5E_CPU0_P3_TX_DP<3>")
	)
	(segment
		(start 368.087402 -377.68784)
		(end 368.087402 -378.39142)
		(width 0.12954)
		(layer "F.Cu")
		(net "P5E_CPU0_P3_TX_DP<3>")
	)
	(segment
		(start 365.012732 -274.896072)
		(end 365.082582 -274.965922)
		(width 0.1143)
		(layer "In11.Cu")
		(net "P5E_CPU0_P3_TX_DP<3>")
	)
	(segment
		(start 363.452664 -291.560504)
		(end 363.459522 -291.564568)
		(width 0.1143)
		(layer "In11.Cu")
		(net "P5E_CPU0_P3_TX_DP<3>")
	)
	(segment
		(start 363.922818 -279.410668)
		(end 363.961934 -279.433528)
		(width 0.1143)
		(layer "In11.Cu")
		(net "P5E_CPU0_P3_TX_DP<3>")
	)
	(segment
		(start 363.961934 -278.458676)
		(end 363.922818 -278.481536)
		(width 0.1143)
		(layer "In11.Cu")
		(net "P5E_CPU0_P3_TX_DP<3>")
	)
	(segment
		(start 363.490764 -280.889202)
		(end 363.48924 -280.890218)
		(width 0.1143)
		(layer "In11.Cu")
		(net "P5E_CPU0_P3_TX_DP<3>")
	)
	(segment
		(start 363.49178 -284.128718)
		(end 363.490764 -284.129226)
		(width 0.1143)
		(layer "In11.Cu")
		(net "P5E_CPU0_P3_TX_DP<3>")
	)
	(segment
		(start 363.52353 -285.730442)
		(end 363.492542 -285.748222)
		(width 0.1143)
		(layer "In11.Cu")
		(net "P5E_CPU0_P3_TX_DP<3>")
	)
	(segment
		(start 369.133374 -307.766974)
		(end 376.472958 -316.710822)
		(width 0.14224)
		(layer "In11.Cu")
		(net "P5E_CPU0_P3_TX_DP<3>")
	)
	(segment
		(start 364.71479 -274.896072)
		(end 365.012732 -274.896072)
		(width 0.1143)
		(layer "In11.Cu")
		(net "P5E_CPU0_P3_TX_DP<3>")
	)
	(segment
		(start 363.490764 -292.229032)
		(end 363.48924 -292.230048)
		(width 0.1143)
		(layer "In11.Cu")
		(net "P5E_CPU0_P3_TX_DP<3>")
	)
	(segment
		(start 363.490764 -288.989008)
		(end 363.48924 -288.990024)
		(width 0.1143)
		(layer "In11.Cu")
		(net "P5E_CPU0_P3_TX_DP<3>")
	)
	(segment
		(start 363.493812 -281.864816)
		(end 363.52353 -281.881834)
		(width 0.1143)
		(layer "In11.Cu")
		(net "P5E_CPU0_P3_TX_DP<3>")
	)
	(segment
		(start 363.490764 -282.509214)
		(end 363.48924 -282.51023)
		(width 0.1143)
		(layer "In11.Cu")
		(net "P5E_CPU0_P3_TX_DP<3>")
	)
	(segment
		(start 363.452664 -283.460698)
		(end 363.459522 -283.464762)
		(width 0.1143)
		(layer "In11.Cu")
		(net "P5E_CPU0_P3_TX_DP<3>")
	)
	(segment
		(start 363.460284 -283.46527)
		(end 363.49178 -283.483558)
		(width 0.1143)
		(layer "In11.Cu")
		(net "P5E_CPU0_P3_TX_DP<3>")
	)
	(segment
		(start 363.49178 -294.823388)
		(end 363.492542 -294.823896)
		(width 0.1143)
		(layer "In11.Cu")
		(net "P5E_CPU0_P3_TX_DP<3>")
	)
	(segment
		(start 363.492542 -291.583872)
		(end 363.493812 -291.584634)
		(width 0.1143)
		(layer "In11.Cu")
		(net "P5E_CPU0_P3_TX_DP<3>")
	)
	(segment
		(start 363.52353 -290.590224)
		(end 363.492542 -290.608004)
		(width 0.1143)
		(layer "In11.Cu")
		(net "P5E_CPU0_P3_TX_DP<3>")
	)
	(segment
		(start 363.452664 -285.08071)
		(end 363.459522 -285.084774)
		(width 0.1143)
		(layer "In11.Cu")
		(net "P5E_CPU0_P3_TX_DP<3>")
	)
	(segment
		(start 363.492542 -289.96386)
		(end 363.493812 -289.964622)
		(width 0.1143)
		(layer "In11.Cu")
		(net "P5E_CPU0_P3_TX_DP<3>")
	)
	(segment
		(start 363.492542 -288.987992)
		(end 363.49178 -288.9885)
		(width 0.1143)
		(layer "In11.Cu")
		(net "P5E_CPU0_P3_TX_DP<3>")
	)
	(segment
		(start 363.492542 -284.12821)
		(end 363.49178 -284.128718)
		(width 0.1143)
		(layer "In11.Cu")
		(net "P5E_CPU0_P3_TX_DP<3>")
	)
	(segment
		(start 364.10392 -296.446956)
		(end 364.10392 -297.056048)
		(width 0.14224)
		(layer "In11.Cu")
		(net "P5E_CPU0_P3_TX_DP<3>")
	)
	(segment
		(start 363.452664 -294.800528)
		(end 363.459522 -294.804592)
		(width 0.1143)
		(layer "In11.Cu")
		(net "P5E_CPU0_P3_TX_DP<3>")
	)
	(segment
		(start 364.10392 -297.056048)
		(end 364.104682 -297.056048)
		(width 0.14224)
		(layer "In11.Cu")
		(net "P5E_CPU0_P3_TX_DP<3>")
	)
	(segment
		(start 363.460284 -285.085282)
		(end 363.49178 -285.10357)
		(width 0.1143)
		(layer "In11.Cu")
		(net "P5E_CPU0_P3_TX_DP<3>")
	)
	(segment
		(start 363.49178 -283.483558)
		(end 363.492542 -283.484066)
		(width 0.1143)
		(layer "In11.Cu")
		(net "P5E_CPU0_P3_TX_DP<3>")
	)
	(segment
		(start 363.992414 -278.440896)
		(end 363.961934 -278.458676)
		(width 0.1143)
		(layer "In11.Cu")
		(net "P5E_CPU0_P3_TX_DP<3>")
	)
	(segment
		(start 363.961934 -279.433528)
		(end 363.992414 -279.451308)
		(width 0.1143)
		(layer "In11.Cu")
		(net "P5E_CPU0_P3_TX_DP<3>")
	)
	(segment
		(start 363.492542 -292.228016)
		(end 363.49178 -292.228524)
		(width 0.1143)
		(layer "In11.Cu")
		(net "P5E_CPU0_P3_TX_DP<3>")
	)
	(segment
		(start 363.493812 -293.204646)
		(end 363.52353 -293.221664)
		(width 0.1143)
		(layer "In11.Cu")
		(net "P5E_CPU0_P3_TX_DP<3>")
	)
	(segment
		(start 363.49178 -281.863546)
		(end 363.492542 -281.864054)
		(width 0.1143)
		(layer "In11.Cu")
		(net "P5E_CPU0_P3_TX_DP<3>")
	)
	(segment
		(start 364.151926 -276.50948)
		(end 364.151672 -276.509226)
		(width 0.1143)
		(layer "In11.Cu")
		(net "P5E_CPU0_P3_TX_DP<3>")
	)
	(segment
		(start 364.14964 -295.955974)
		(end 364.14964 -296.372788)
		(width 0.1143)
		(layer "In11.Cu")
		(net "P5E_CPU0_P3_TX_DP<3>")
	)
	(segment
		(start 363.459522 -281.84475)
		(end 363.460284 -281.845258)
		(width 0.1143)
		(layer "In11.Cu")
		(net "P5E_CPU0_P3_TX_DP<3>")
	)
	(segment
		(start 363.49178 -290.608512)
		(end 363.490764 -290.60902)
		(width 0.1143)
		(layer "In11.Cu")
		(net "P5E_CPU0_P3_TX_DP<3>")
	)
	(segment
		(start 363.460284 -293.185088)
		(end 363.49178 -293.203376)
		(width 0.1143)
		(layer "In11.Cu")
		(net "P5E_CPU0_P3_TX_DP<3>")
	)
	(segment
		(start 363.48924 -285.750254)
		(end 363.452664 -285.77159)
		(width 0.1143)
		(layer "In11.Cu")
		(net "P5E_CPU0_P3_TX_DP<3>")
	)
	(segment
		(start 363.994446 -276.81428)
		(end 363.921294 -276.85746)
		(width 0.1143)
		(layer "In11.Cu")
		(net "P5E_CPU0_P3_TX_DP<3>")
	)
	(segment
		(start 363.459522 -294.804592)
		(end 363.460284 -294.8051)
		(width 0.1143)
		(layer "In11.Cu")
		(net "P5E_CPU0_P3_TX_DP<3>")
	)
	(segment
		(start 363.493812 -291.584634)
		(end 363.52353 -291.601652)
		(width 0.1143)
		(layer "In11.Cu")
		(net "P5E_CPU0_P3_TX_DP<3>")
	)
	(segment
		(start 363.460284 -281.845258)
		(end 363.49178 -281.863546)
		(width 0.1143)
		(layer "In11.Cu")
		(net "P5E_CPU0_P3_TX_DP<3>")
	)
	(segment
		(start 363.492542 -290.608004)
		(end 363.49178 -290.608512)
		(width 0.1143)
		(layer "In11.Cu")
		(net "P5E_CPU0_P3_TX_DP<3>")
	)
	(segment
		(start 363.459522 -291.564568)
		(end 363.460284 -291.565076)
		(width 0.1143)
		(layer "In11.Cu")
		(net "P5E_CPU0_P3_TX_DP<3>")
	)
	(segment
		(start 363.492542 -282.508198)
		(end 363.49178 -282.508706)
		(width 0.1143)
		(layer "In11.Cu")
		(net "P5E_CPU0_P3_TX_DP<3>")
	)
	(segment
		(start 363.492542 -293.203884)
		(end 363.493812 -293.204646)
		(width 0.1143)
		(layer "In11.Cu")
		(net "P5E_CPU0_P3_TX_DP<3>")
	)
	(segment
		(start 363.49178 -280.888694)
		(end 363.490764 -280.889202)
		(width 0.1143)
		(layer "In11.Cu")
		(net "P5E_CPU0_P3_TX_DP<3>")
	)
	(segment
		(start 363.49178 -293.203376)
		(end 363.492542 -293.203884)
		(width 0.1143)
		(layer "In11.Cu")
		(net "P5E_CPU0_P3_TX_DP<3>")
	)
	(segment
		(start 383.440686 -351.876614)
		(end 380.835916 -359.156)
		(width 0.14224)
		(layer "In11.Cu")
		(net "P5E_CPU0_P3_TX_DP<3>")
	)
	(segment
		(start 363.490764 -290.60902)
		(end 363.48924 -290.610036)
		(width 0.1143)
		(layer "In11.Cu")
		(net "P5E_CPU0_P3_TX_DP<3>")
	)
	(segment
		(start 363.922818 -295.610534)
		(end 363.992414 -295.651174)
		(width 0.1143)
		(layer "In11.Cu")
		(net "P5E_CPU0_P3_TX_DP<3>")
	)
	(segment
		(start 363.52353 -288.970212)
		(end 363.492542 -288.987992)
		(width 0.1143)
		(layer "In11.Cu")
		(net "P5E_CPU0_P3_TX_DP<3>")
	)
	(segment
		(start 384.198876 -341.298784)
		(end 384.198876 -347.507814)
		(width 0.14224)
		(layer "In11.Cu")
		(net "P5E_CPU0_P3_TX_DP<3>")
	)
	(segment
		(start 363.48924 -293.85006)
		(end 363.452664 -293.871396)
		(width 0.1143)
		(layer "In11.Cu")
		(net "P5E_CPU0_P3_TX_DP<3>")
	)
	(segment
		(start 364.10392 -296.418508)
		(end 364.10392 -296.446956)
		(width 0.1143)
		(layer "In11.Cu")
		(net "P5E_CPU0_P3_TX_DP<3>")
	)
	(segment
		(start 376.472958 -316.710822)
		(end 379.15723 -320.728086)
		(width 0.14224)
		(layer "In11.Cu")
		(net "P5E_CPU0_P3_TX_DP<3>")
	)
	(segment
		(start 363.49178 -285.10357)
		(end 363.492542 -285.104078)
		(width 0.1143)
		(layer "In11.Cu")
		(net "P5E_CPU0_P3_TX_DP<3>")
	)
	(segment
		(start 364.464092 -276.004782)
		(end 364.392972 -276.04593)
		(width 0.1143)
		(layer "In11.Cu")
		(net "P5E_CPU0_P3_TX_DP<3>")
	)
	(segment
		(start 363.452664 -288.320734)
		(end 363.49178 -288.343594)
		(width 0.1143)
		(layer "In11.Cu")
		(net "P5E_CPU0_P3_TX_DP<3>")
	)
	(segment
		(start 363.48924 -290.610036)
		(end 363.452664 -290.631372)
		(width 0.1143)
		(layer "In11.Cu")
		(net "P5E_CPU0_P3_TX_DP<3>")
	)
	(segment
		(start 363.49178 -293.848536)
		(end 363.490764 -293.849044)
		(width 0.1143)
		(layer "In11.Cu")
		(net "P5E_CPU0_P3_TX_DP<3>")
	)
	(segment
		(start 365.514128 -302.350424)
		(end 369.133374 -307.766974)
		(width 0.14224)
		(layer "In11.Cu")
		(net "P5E_CPU0_P3_TX_DP<3>")
	)
	(segment
		(start 363.52353 -282.490418)
		(end 363.492542 -282.508198)
		(width 0.1143)
		(layer "In11.Cu")
		(net "P5E_CPU0_P3_TX_DP<3>")
	)
	(segment
		(start 363.492542 -283.484066)
		(end 363.493812 -283.484828)
		(width 0.1143)
		(layer "In11.Cu")
		(net "P5E_CPU0_P3_TX_DP<3>")
	)
	(segment
		(start 364.14964 -296.372788)
		(end 364.10392 -296.418508)
		(width 0.1143)
		(layer "In11.Cu")
		(net "P5E_CPU0_P3_TX_DP<3>")
	)
	(segment
		(start 368.107722 -376.479054)
		(end 368.107722 -377.1265)
		(width 0.14224)
		(layer "In11.Cu")
		(net "P5E_CPU0_P3_TX_DP<3>")
	)
	(segment
		(start 363.460284 -291.565076)
		(end 363.49178 -291.583364)
		(width 0.1143)
		(layer "In11.Cu")
		(net "P5E_CPU0_P3_TX_DP<3>")
	)
	(segment
		(start 363.49178 -286.723582)
		(end 363.525308 -286.74314)
		(width 0.1143)
		(layer "In11.Cu")
		(net "P5E_CPU0_P3_TX_DP<3>")
	)
	(segment
		(start 379.15723 -320.728086)
		(end 380.985014 -325.141082)
		(width 0.14224)
		(layer "In11.Cu")
		(net "P5E_CPU0_P3_TX_DP<3>")
	)
	(segment
		(start 363.48924 -282.51023)
		(end 363.452664 -282.531566)
		(width 0.1143)
		(layer "In11.Cu")
		(net "P5E_CPU0_P3_TX_DP<3>")
	)
	(segment
		(start 363.48924 -284.130242)
		(end 363.452664 -284.151578)
		(width 0.1143)
		(layer "In11.Cu")
		(net "P5E_CPU0_P3_TX_DP<3>")
	)
	(segment
		(start 363.52353 -292.210236)
		(end 363.492542 -292.228016)
		(width 0.1143)
		(layer "In11.Cu")
		(net "P5E_CPU0_P3_TX_DP<3>")
	)
	(segment
		(start 363.490764 -284.129226)
		(end 363.48924 -284.130242)
		(width 0.1143)
		(layer "In11.Cu")
		(net "P5E_CPU0_P3_TX_DP<3>")
	)
	(segment
		(start 363.49178 -288.343594)
		(end 363.525308 -288.363152)
		(width 0.1143)
		(layer "In11.Cu")
		(net "P5E_CPU0_P3_TX_DP<3>")
	)
	(segment
		(start 363.48924 -292.230048)
		(end 363.452664 -292.251384)
		(width 0.1143)
		(layer "In11.Cu")
		(net "P5E_CPU0_P3_TX_DP<3>")
	)
	(segment
		(start 363.460284 -294.8051)
		(end 363.49178 -294.823388)
		(width 0.1143)
		(layer "In11.Cu")
		(net "P5E_CPU0_P3_TX_DP<3>")
	)
	(segment
		(start 363.492542 -280.888186)
		(end 363.49178 -280.888694)
		(width 0.1143)
		(layer "In11.Cu")
		(net "P5E_CPU0_P3_TX_DP<3>")
	)
	(segment
		(start 364.151926 -276.505924)
		(end 364.151926 -276.50948)
		(width 0.1143)
		(layer "In11.Cu")
		(net "P5E_CPU0_P3_TX_DP<3>")
	)
	(segment
		(start 375.895362 -367.50371)
		(end 368.23269 -376.149362)
		(width 0.14224)
		(layer "In11.Cu")
		(net "P5E_CPU0_P3_TX_DP<3>")
	)
	(segment
		(start 363.52353 -287.3502)
		(end 363.49178 -287.368488)
		(width 0.1143)
		(layer "In11.Cu")
		(net "P5E_CPU0_P3_TX_DP<3>")
	)
	(segment
		(start 363.490764 -289.962844)
		(end 363.49178 -289.963352)
		(width 0.1143)
		(layer "In11.Cu")
		(net "P5E_CPU0_P3_TX_DP<3>")
	)
	(segment
		(start 363.49178 -292.228524)
		(end 363.490764 -292.229032)
		(width 0.1143)
		(layer "In11.Cu")
		(net "P5E_CPU0_P3_TX_DP<3>")
	)
	(segment
		(start 363.452664 -281.840686)
		(end 363.459522 -281.84475)
		(width 0.1143)
		(layer "In11.Cu")
		(net "P5E_CPU0_P3_TX_DP<3>")
	)
	(segment
		(start 363.490764 -293.849044)
		(end 363.48924 -293.85006)
		(width 0.1143)
		(layer "In11.Cu")
		(net "P5E_CPU0_P3_TX_DP<3>")
	)
	(segment
		(start 363.992414 -280.060908)
		(end 363.961934 -280.078688)
		(width 0.1143)
		(layer "In11.Cu")
		(net "P5E_CPU0_P3_TX_DP<3>")
	)
	(segment
		(start 363.492542 -285.748222)
		(end 363.49178 -285.74873)
		(width 0.1143)
		(layer "In11.Cu")
		(net "P5E_CPU0_P3_TX_DP<3>")
	)
	(segment
		(start 363.452664 -293.180516)
		(end 363.459522 -293.18458)
		(width 0.1143)
		(layer "In11.Cu")
		(net "P5E_CPU0_P3_TX_DP<3>")
	)
	(segment
		(start 363.52353 -284.11043)
		(end 363.492542 -284.12821)
		(width 0.1143)
		(layer "In11.Cu")
		(net "P5E_CPU0_P3_TX_DP<3>")
	)
	(segment
		(start 363.492542 -285.104078)
		(end 363.493812 -285.10484)
		(width 0.1143)
		(layer "In11.Cu")
		(net "P5E_CPU0_P3_TX_DP<3>")
	)
	(segment
		(start 368.107722 -377.1265)
		(end 367.816892 -377.41733)
		(width 0.14224)
		(layer "In11.Cu")
		(net "P5E_CPU0_P3_TX_DP<3>")
	)
	(segment
		(start 363.49178 -291.583364)
		(end 363.492542 -291.583872)
		(width 0.1143)
		(layer "In11.Cu")
		(net "P5E_CPU0_P3_TX_DP<3>")
	)
	(segment
		(start 363.459522 -293.18458)
		(end 363.460284 -293.185088)
		(width 0.1143)
		(layer "In11.Cu")
		(net "P5E_CPU0_P3_TX_DP<3>")
	)
	(segment
		(start 363.48924 -280.890218)
		(end 363.452664 -280.911554)
		(width 0.1143)
		(layer "In11.Cu")
		(net "P5E_CPU0_P3_TX_DP<3>")
	)
	(segment
		(start 363.49178 -287.368488)
		(end 363.455204 -287.389824)
		(width 0.1143)
		(layer "In11.Cu")
		(net "P5E_CPU0_P3_TX_DP<3>")
	)
	(segment
		(start 364.933484 -275.200364)
		(end 364.899448 -275.220176)
		(width 0.1143)
		(layer "In11.Cu")
		(net "P5E_CPU0_P3_TX_DP<3>")
	)
	(segment
		(start 380.985014 -325.141082)
		(end 384.198876 -341.298784)
		(width 0.14224)
		(layer "In11.Cu")
		(net "P5E_CPU0_P3_TX_DP<3>")
	)
	(segment
		(start 363.49178 -282.508706)
		(end 363.490764 -282.509214)
		(width 0.1143)
		(layer "In11.Cu")
		(net "P5E_CPU0_P3_TX_DP<3>")
	)
	(segment
		(start 363.492542 -293.848028)
		(end 363.49178 -293.848536)
		(width 0.1143)
		(layer "In11.Cu")
		(net "P5E_CPU0_P3_TX_DP<3>")
	)
	(segment
		(start 363.49178 -288.9885)
		(end 363.490764 -288.989008)
		(width 0.1143)
		(layer "In11.Cu")
		(net "P5E_CPU0_P3_TX_DP<3>")
	)
	(segment
		(start 363.459522 -283.464762)
		(end 363.460284 -283.46527)
		(width 0.1143)
		(layer "In11.Cu")
		(net "P5E_CPU0_P3_TX_DP<3>")
	)
	(segment
		(start 364.104682 -297.705018)
		(end 365.514128 -302.350424)
		(width 0.14224)
		(layer "In11.Cu")
		(net "P5E_CPU0_P3_TX_DP<3>")
	)
	(segment
		(start 363.492542 -281.864054)
		(end 363.493812 -281.864816)
		(width 0.1143)
		(layer "In11.Cu")
		(net "P5E_CPU0_P3_TX_DP<3>")
	)
	(segment
		(start 384.198876 -347.507814)
		(end 384.198622 -347.50756)
		(width 0.14224)
		(layer "In11.Cu")
		(net "P5E_CPU0_P3_TX_DP<3>")
	)
	(segment
		(start 363.493812 -294.824658)
		(end 363.52353 -294.841676)
		(width 0.1143)
		(layer "In11.Cu")
		(net "P5E_CPU0_P3_TX_DP<3>")
	)
	(segment
		(start 363.49178 -285.74873)
		(end 363.490764 -285.749238)
		(width 0.1143)
		(layer "In11.Cu")
		(net "P5E_CPU0_P3_TX_DP<3>")
	)
	(segment
		(start 364.104682 -297.056048)
		(end 364.104682 -297.705018)
		(width 0.14224)
		(layer "In11.Cu")
		(net "P5E_CPU0_P3_TX_DP<3>")
	)
	(segment
		(start 363.52353 -293.830248)
		(end 363.492542 -293.848028)
		(width 0.1143)
		(layer "In11.Cu")
		(net "P5E_CPU0_P3_TX_DP<3>")
	)
	(segment
		(start 363.492542 -294.823896)
		(end 363.493812 -294.824658)
		(width 0.1143)
		(layer "In11.Cu")
		(net "P5E_CPU0_P3_TX_DP<3>")
	)
	(segment
		(start 363.954822 -277.809198)
		(end 363.99343 -277.832058)
		(width 0.1143)
		(layer "In11.Cu")
		(net "P5E_CPU0_P3_TX_DP<3>")
	)
	(segment
		(start 363.49178 -289.963352)
		(end 363.492542 -289.96386)
		(width 0.1143)
		(layer "In11.Cu")
		(net "P5E_CPU0_P3_TX_DP<3>")
	)
	(segment
		(start 363.452664 -286.700722)
		(end 363.49178 -286.723582)
		(width 0.1143)
		(layer "In11.Cu")
		(net "P5E_CPU0_P3_TX_DP<3>")
	)
	(segment
		(start 363.48924 -288.990024)
		(end 363.452664 -289.01136)
		(width 0.1143)
		(layer "In11.Cu")
		(net "P5E_CPU0_P3_TX_DP<3>")
	)
	(segment
		(start 363.459522 -285.084774)
		(end 363.460284 -285.085282)
		(width 0.1143)
		(layer "In11.Cu")
		(net "P5E_CPU0_P3_TX_DP<3>")
	)
	(segment
		(start 363.490764 -285.749238)
		(end 363.48924 -285.750254)
		(width 0.1143)
		(layer "In11.Cu")
		(net "P5E_CPU0_P3_TX_DP<3>")
	)
	(segment
		(start 363.493812 -283.484828)
		(end 363.52353 -283.501846)
		(width 0.1143)
		(layer "In11.Cu")
		(net "P5E_CPU0_P3_TX_DP<3>")
	)
	(segment
		(start 363.961934 -280.078688)
		(end 363.922818 -280.101548)
		(width 0.1143)
		(layer "In11.Cu")
		(net "P5E_CPU0_P3_TX_DP<3>")
	)
	(segment
		(start 363.493812 -289.964622)
		(end 363.52353 -289.98164)
		(width 0.1143)
		(layer "In11.Cu")
		(net "P5E_CPU0_P3_TX_DP<3>")
	)
	(segment
		(start 363.452664 -289.940492)
		(end 363.490764 -289.962844)
		(width 0.1143)
		(layer "In11.Cu")
		(net "P5E_CPU0_P3_TX_DP<3>")
	)
	(segment
		(start 363.52353 -280.870406)
		(end 363.492542 -280.888186)
		(width 0.1143)
		(layer "In11.Cu")
		(net "P5E_CPU0_P3_TX_DP<3>")
	)
	(segment
		(start 363.493812 -285.10484)
		(end 363.52353 -285.121858)
		(width 0.1143)
		(layer "In11.Cu")
		(net "P5E_CPU0_P3_TX_DP<3>")
	)
	(arc
		(start 363.452664 -285.77159)
		(mid 363.209337 -286.236156)
		(end 363.452664 -286.700722)
		(width 0.1143)
		(layer "In11.Cu")
		(net "P5E_CPU0_P3_TX_DP<3>")
	)
	(arc
		(start 363.679486 -295.145968)
		(mid 363.744001 -295.408187)
		(end 363.922818 -295.610534)
		(width 0.1143)
		(layer "In11.Cu")
		(net "P5E_CPU0_P3_TX_DP<3>")
	)
	(arc
		(start 384.198622 -347.50756)
		(mid 384.007776 -349.724722)
		(end 383.440686 -351.876614)
		(width 0.14224)
		(layer "In11.Cu")
		(net "P5E_CPU0_P3_TX_DP<3>")
	)
	(arc
		(start 363.452664 -293.871396)
		(mid 363.209337 -294.335962)
		(end 363.452664 -294.800528)
		(width 0.1143)
		(layer "In11.Cu")
		(net "P5E_CPU0_P3_TX_DP<3>")
	)
	(arc
		(start 364.151672 -276.509226)
		(mid 364.110042 -276.680805)
		(end 363.994446 -276.81428)
		(width 0.1143)
		(layer "In11.Cu")
		(net "P5E_CPU0_P3_TX_DP<3>")
	)
	(arc
		(start 363.52353 -293.221664)
		(mid 363.679458 -293.525956)
		(end 363.52353 -293.830248)
		(width 0.1143)
		(layer "In11.Cu")
		(net "P5E_CPU0_P3_TX_DP<3>")
	)
	(arc
		(start 363.455204 -287.389824)
		(mid 363.274552 -287.592569)
		(end 363.209332 -287.856168)
		(width 0.1143)
		(layer "In11.Cu")
		(net "P5E_CPU0_P3_TX_DP<3>")
	)
	(arc
		(start 363.52353 -281.881834)
		(mid 363.679458 -282.186126)
		(end 363.52353 -282.490418)
		(width 0.1143)
		(layer "In11.Cu")
		(net "P5E_CPU0_P3_TX_DP<3>")
	)
	(arc
		(start 364.392972 -276.04593)
		(mid 364.215738 -276.246218)
		(end 364.151926 -276.505924)
		(width 0.1143)
		(layer "In11.Cu")
		(net "P5E_CPU0_P3_TX_DP<3>")
	)
	(arc
		(start 368.23269 -376.149362)
		(mid 368.140003 -376.302761)
		(end 368.107722 -376.479054)
		(width 0.14224)
		(layer "In11.Cu")
		(net "P5E_CPU0_P3_TX_DP<3>")
	)
	(arc
		(start 363.921294 -276.85746)
		(mid 363.677463 -277.34247)
		(end 363.954822 -277.809198)
		(width 0.1143)
		(layer "In11.Cu")
		(net "P5E_CPU0_P3_TX_DP<3>")
	)
	(arc
		(start 363.679486 -280.566114)
		(mid 363.638231 -280.737085)
		(end 363.52353 -280.870406)
		(width 0.1143)
		(layer "In11.Cu")
		(net "P5E_CPU0_P3_TX_DP<3>")
	)
	(arc
		(start 363.452664 -290.631372)
		(mid 363.209337 -291.095938)
		(end 363.452664 -291.560504)
		(width 0.1143)
		(layer "In11.Cu")
		(net "P5E_CPU0_P3_TX_DP<3>")
	)
	(arc
		(start 363.452664 -284.151578)
		(mid 363.209337 -284.616144)
		(end 363.452664 -285.08071)
		(width 0.1143)
		(layer "In11.Cu")
		(net "P5E_CPU0_P3_TX_DP<3>")
	)
	(arc
		(start 364.096046 -277.943818)
		(mid 364.141324 -278.212565)
		(end 363.992414 -278.440896)
		(width 0.1143)
		(layer "In11.Cu")
		(net "P5E_CPU0_P3_TX_DP<3>")
	)
	(arc
		(start 364.899448 -275.220176)
		(mid 364.696456 -275.422456)
		(end 364.62208 -275.69922)
		(width 0.1143)
		(layer "In11.Cu")
		(net "P5E_CPU0_P3_TX_DP<3>")
	)
	(arc
		(start 363.679486 -287.045908)
		(mid 363.638231 -287.216879)
		(end 363.52353 -287.3502)
		(width 0.1143)
		(layer "In11.Cu")
		(net "P5E_CPU0_P3_TX_DP<3>")
	)
	(arc
		(start 363.52353 -283.501846)
		(mid 363.679458 -283.806138)
		(end 363.52353 -284.11043)
		(width 0.1143)
		(layer "In11.Cu")
		(net "P5E_CPU0_P3_TX_DP<3>")
	)
	(arc
		(start 363.52353 -285.121858)
		(mid 363.679458 -285.42615)
		(end 363.52353 -285.730442)
		(width 0.1143)
		(layer "In11.Cu")
		(net "P5E_CPU0_P3_TX_DP<3>")
	)
	(arc
		(start 363.922818 -280.101548)
		(mid 363.744005 -280.303898)
		(end 363.679486 -280.566114)
		(width 0.1143)
		(layer "In11.Cu")
		(net "P5E_CPU0_P3_TX_DP<3>")
	)
	(arc
		(start 363.452664 -282.531566)
		(mid 363.209337 -282.996132)
		(end 363.452664 -283.460698)
		(width 0.1143)
		(layer "In11.Cu")
		(net "P5E_CPU0_P3_TX_DP<3>")
	)
	(arc
		(start 363.209332 -287.856168)
		(mid 363.273847 -288.118387)
		(end 363.452664 -288.320734)
		(width 0.1143)
		(layer "In11.Cu")
		(net "P5E_CPU0_P3_TX_DP<3>")
	)
	(arc
		(start 363.52353 -291.601652)
		(mid 363.679458 -291.905944)
		(end 363.52353 -292.210236)
		(width 0.1143)
		(layer "In11.Cu")
		(net "P5E_CPU0_P3_TX_DP<3>")
	)
	(arc
		(start 363.992414 -279.451308)
		(mid 364.149391 -279.756108)
		(end 363.992414 -280.060908)
		(width 0.1143)
		(layer "In11.Cu")
		(net "P5E_CPU0_P3_TX_DP<3>")
	)
	(arc
		(start 363.992414 -295.651174)
		(mid 364.007436 -295.662492)
		(end 364.021878 -295.674542)
		(width 0.1143)
		(layer "In11.Cu")
		(net "P5E_CPU0_P3_TX_DP<3>")
	)
	(arc
		(start 363.52353 -294.841676)
		(mid 363.638206 -294.97501)
		(end 363.679486 -295.145968)
		(width 0.1143)
		(layer "In11.Cu")
		(net "P5E_CPU0_P3_TX_DP<3>")
	)
	(arc
		(start 363.525308 -286.74314)
		(mid 363.638715 -286.876029)
		(end 363.679486 -287.045908)
		(width 0.1143)
		(layer "In11.Cu")
		(net "P5E_CPU0_P3_TX_DP<3>")
	)
	(arc
		(start 363.52353 -289.98164)
		(mid 363.679458 -290.285932)
		(end 363.52353 -290.590224)
		(width 0.1143)
		(layer "In11.Cu")
		(net "P5E_CPU0_P3_TX_DP<3>")
	)
	(arc
		(start 363.922818 -278.481536)
		(mid 363.679491 -278.946102)
		(end 363.922818 -279.410668)
		(width 0.1143)
		(layer "In11.Cu")
		(net "P5E_CPU0_P3_TX_DP<3>")
	)
	(arc
		(start 363.679486 -288.66592)
		(mid 363.638231 -288.836891)
		(end 363.52353 -288.970212)
		(width 0.1143)
		(layer "In11.Cu")
		(net "P5E_CPU0_P3_TX_DP<3>")
	)
	(arc
		(start 363.525308 -288.363152)
		(mid 363.638715 -288.496041)
		(end 363.679486 -288.66592)
		(width 0.1143)
		(layer "In11.Cu")
		(net "P5E_CPU0_P3_TX_DP<3>")
	)
	(arc
		(start 363.452664 -280.911554)
		(mid 363.209337 -281.37612)
		(end 363.452664 -281.840686)
		(width 0.1143)
		(layer "In11.Cu")
		(net "P5E_CPU0_P3_TX_DP<3>")
	)
	(arc
		(start 363.452664 -289.01136)
		(mid 363.209337 -289.475926)
		(end 363.452664 -289.940492)
		(width 0.1143)
		(layer "In11.Cu")
		(net "P5E_CPU0_P3_TX_DP<3>")
	)
	(arc
		(start 380.835916 -359.156)
		(mid 378.765022 -363.566227)
		(end 375.895362 -367.50371)
		(width 0.14224)
		(layer "In11.Cu")
		(net "P5E_CPU0_P3_TX_DP<3>")
	)
	(arc
		(start 364.62208 -275.69922)
		(mid 364.58024 -275.871206)
		(end 364.464092 -276.004782)
		(width 0.1143)
		(layer "In11.Cu")
		(net "P5E_CPU0_P3_TX_DP<3>")
	)
	(arc
		(start 363.452664 -292.251384)
		(mid 363.209337 -292.71595)
		(end 363.452664 -293.180516)
		(width 0.1143)
		(layer "In11.Cu")
		(net "P5E_CPU0_P3_TX_DP<3>")
	)
	(arc
		(start 364.021878 -295.674542)
		(mid 364.116157 -295.801459)
		(end 364.14964 -295.955974)
		(width 0.1143)
		(layer "In11.Cu")
		(net "P5E_CPU0_P3_TX_DP<3>")
	)
	(arc
		(start 365.082582 -274.965922)
		(mid 365.030533 -275.097441)
		(end 364.933484 -275.200364)
		(width 0.1143)
		(layer "In11.Cu")
		(net "P5E_CPU0_P3_TX_DP<3>")
	)
	(arc
		(start 363.99343 -277.832058)
		(mid 364.050459 -277.882685)
		(end 364.096046 -277.943818)
		(width 0.1143)
		(layer "In11.Cu")
		(net "P5E_CPU0_P3_TX_DP<3>")
	)
	(segment
		(start 366.385602 -380.15164)
		(end 366.385602 -380.85522)
		(width 0.12954)
		(layer "F.Cu")
		(net "P5E_CPU0_P3_TX_DP<2>")
	)
	(segment
		(start 366.385602 -380.85522)
		(end 366.089692 -381.15113)
		(width 0.12954)
		(layer "F.Cu")
		(net "P5E_CPU0_P3_TX_DP<2>")
	)
	(segment
		(start 361.89793 -278.680164)
		(end 362.364782 -278.946102)
		(width 0.12954)
		(layer "F.Cu")
		(net "P5E_CPU0_P3_TX_DP<2>")
	)
	(segment
		(start 366.115092 -379.88113)
		(end 366.385602 -380.15164)
		(width 0.12954)
		(layer "F.Cu")
		(net "P5E_CPU0_P3_TX_DP<2>")
	)
	(segment
		(start 362.617258 -285.703264)
		(end 362.61548 -285.704788)
		(width 0.1143)
		(layer "In11.Cu")
		(net "P5E_CPU0_P3_TX_DP<2>")
	)
	(segment
		(start 362.543344 -285.098744)
		(end 362.54563 -285.100014)
		(width 0.1143)
		(layer "In11.Cu")
		(net "P5E_CPU0_P3_TX_DP<2>")
	)
	(segment
		(start 362.662724 -278.946102)
		(end 362.732574 -279.015952)
		(width 0.1143)
		(layer "In11.Cu")
		(net "P5E_CPU0_P3_TX_DP<2>")
	)
	(segment
		(start 362.550202 -293.836852)
		(end 362.50499 -293.86657)
		(width 0.1143)
		(layer "In11.Cu")
		(net "P5E_CPU0_P3_TX_DP<2>")
	)
	(segment
		(start 362.583476 -285.121858)
		(end 362.583984 -285.122112)
		(width 0.1143)
		(layer "In11.Cu")
		(net "P5E_CPU0_P3_TX_DP<2>")
	)
	(segment
		(start 362.5215 -289.945826)
		(end 362.583222 -289.98164)
		(width 0.1143)
		(layer "In11.Cu")
		(net "P5E_CPU0_P3_TX_DP<2>")
	)
	(segment
		(start 375.92889 -317.574676)
		(end 378.328936 -321.166744)
		(width 0.14224)
		(layer "In11.Cu")
		(net "P5E_CPU0_P3_TX_DP<2>")
	)
	(segment
		(start 362.65993 -288.435034)
		(end 362.660438 -288.435796)
		(width 0.1143)
		(layer "In11.Cu")
		(net "P5E_CPU0_P3_TX_DP<2>")
	)
	(segment
		(start 362.54944 -285.749238)
		(end 362.54944 -285.75)
		(width 0.1143)
		(layer "In11.Cu")
		(net "P5E_CPU0_P3_TX_DP<2>")
	)
	(segment
		(start 362.636816 -287.314132)
		(end 362.57738 -287.353502)
		(width 0.1143)
		(layer "In11.Cu")
		(net "P5E_CPU0_P3_TX_DP<2>")
	)
	(segment
		(start 362.51261 -293.180516)
		(end 362.519468 -293.18458)
		(width 0.1143)
		(layer "In11.Cu")
		(net "P5E_CPU0_P3_TX_DP<2>")
	)
	(segment
		(start 362.739178 -287.045908)
		(end 362.739432 -287.045654)
		(width 0.1143)
		(layer "In11.Cu")
		(net "P5E_CPU0_P3_TX_DP<2>")
	)
	(segment
		(start 362.603542 -280.855928)
		(end 362.583476 -280.870406)
		(width 0.1143)
		(layer "In11.Cu")
		(net "P5E_CPU0_P3_TX_DP<2>")
	)
	(segment
		(start 362.592366 -293.228268)
		(end 362.593128 -293.228776)
		(width 0.1143)
		(layer "In11.Cu")
		(net "P5E_CPU0_P3_TX_DP<2>")
	)
	(segment
		(start 362.555282 -293.205408)
		(end 362.556044 -293.205916)
		(width 0.1143)
		(layer "In11.Cu")
		(net "P5E_CPU0_P3_TX_DP<2>")
	)
	(segment
		(start 362.586016 -293.223442)
		(end 362.587286 -293.224458)
		(width 0.1143)
		(layer "In11.Cu")
		(net "P5E_CPU0_P3_TX_DP<2>")
	)
	(segment
		(start 362.401104 -284.22981)
		(end 362.339382 -284.342332)
		(width 0.1143)
		(layer "In11.Cu")
		(net "P5E_CPU0_P3_TX_DP<2>")
	)
	(segment
		(start 362.584238 -293.222172)
		(end 362.585 -293.22268)
		(width 0.1143)
		(layer "In11.Cu")
		(net "P5E_CPU0_P3_TX_DP<2>")
	)
	(segment
		(start 362.593128 -293.228776)
		(end 362.59516 -293.2303)
		(width 0.1143)
		(layer "In11.Cu")
		(net "P5E_CPU0_P3_TX_DP<2>")
	)
	(segment
		(start 362.51007 -288.318956)
		(end 362.546138 -288.340038)
		(width 0.1143)
		(layer "In11.Cu")
		(net "P5E_CPU0_P3_TX_DP<2>")
	)
	(segment
		(start 362.557568 -293.206678)
		(end 362.55833 -293.207186)
		(width 0.1143)
		(layer "In11.Cu")
		(net "P5E_CPU0_P3_TX_DP<2>")
	)
	(segment
		(start 362.573062 -288.976054)
		(end 362.573062 -288.976308)
		(width 0.1143)
		(layer "In11.Cu")
		(net "P5E_CPU0_P3_TX_DP<2>")
	)
	(segment
		(start 366.39881 -377.272296)
		(end 366.39881 -379.597412)
		(width 0.14224)
		(layer "In11.Cu")
		(net "P5E_CPU0_P3_TX_DP<2>")
	)
	(segment
		(start 362.549948 -288.342324)
		(end 362.551218 -288.343086)
		(width 0.1143)
		(layer "In11.Cu")
		(net "P5E_CPU0_P3_TX_DP<2>")
	)
	(segment
		(start 362.583476 -280.870406)
		(end 362.541058 -280.89479)
		(width 0.1143)
		(layer "In11.Cu")
		(net "P5E_CPU0_P3_TX_DP<2>")
	)
	(segment
		(start 382.643888 -351.028)
		(end 379.935994 -358.596692)
		(width 0.14224)
		(layer "In11.Cu")
		(net "P5E_CPU0_P3_TX_DP<2>")
	)
	(segment
		(start 362.551726 -282.508706)
		(end 362.544106 -282.513024)
		(width 0.1143)
		(layer "In11.Cu")
		(net "P5E_CPU0_P3_TX_DP<2>")
	)
	(segment
		(start 362.552742 -280.244042)
		(end 362.553504 -280.24455)
		(width 0.1143)
		(layer "In11.Cu")
		(net "P5E_CPU0_P3_TX_DP<2>")
	)
	(segment
		(start 362.739432 -287.045654)
		(end 362.739432 -287.123886)
		(width 0.1143)
		(layer "In11.Cu")
		(net "P5E_CPU0_P3_TX_DP<2>")
	)
	(segment
		(start 362.58754 -285.124906)
		(end 362.589826 -285.12643)
		(width 0.1143)
		(layer "In11.Cu")
		(net "P5E_CPU0_P3_TX_DP<2>")
	)
	(segment
		(start 362.551218 -288.343086)
		(end 362.586524 -288.364168)
		(width 0.1143)
		(layer "In11.Cu")
		(net "P5E_CPU0_P3_TX_DP<2>")
	)
	(segment
		(start 362.535216 -294.813736)
		(end 362.582714 -294.841168)
		(width 0.1143)
		(layer "In11.Cu")
		(net "P5E_CPU0_P3_TX_DP<2>")
	)
	(segment
		(start 362.551726 -293.203376)
		(end 362.552488 -293.203884)
		(width 0.1143)
		(layer "In11.Cu")
		(net "P5E_CPU0_P3_TX_DP<2>")
	)
	(segment
		(start 362.591096 -293.227252)
		(end 362.592366 -293.228268)
		(width 0.1143)
		(layer "In11.Cu")
		(net "P5E_CPU0_P3_TX_DP<2>")
	)
	(segment
		(start 362.982764 -295.610534)
		(end 363.05236 -295.651174)
		(width 0.1143)
		(layer "In11.Cu")
		(net "P5E_CPU0_P3_TX_DP<2>")
	)
	(segment
		(start 362.521754 -290.625784)
		(end 362.515404 -290.629594)
		(width 0.1143)
		(layer "In11.Cu")
		(net "P5E_CPU0_P3_TX_DP<2>")
	)
	(segment
		(start 364.6424 -302.742346)
		(end 368.52606 -308.554628)
		(width 0.14224)
		(layer "In11.Cu")
		(net "P5E_CPU0_P3_TX_DP<2>")
	)
	(segment
		(start 362.551726 -292.228524)
		(end 362.55071 -292.229032)
		(width 0.1143)
		(layer "In11.Cu")
		(net "P5E_CPU0_P3_TX_DP<2>")
	)
	(segment
		(start 362.553504 -280.24455)
		(end 362.55452 -280.245058)
		(width 0.1143)
		(layer "In11.Cu")
		(net "P5E_CPU0_P3_TX_DP<2>")
	)
	(segment
		(start 363.163866 -296.446956)
		(end 363.163866 -296.774108)
		(width 0.14224)
		(layer "In11.Cu")
		(net "P5E_CPU0_P3_TX_DP<2>")
	)
	(segment
		(start 362.52023 -293.185088)
		(end 362.551726 -293.203376)
		(width 0.1143)
		(layer "In11.Cu")
		(net "P5E_CPU0_P3_TX_DP<2>")
	)
	(segment
		(start 363.163358 -296.774616)
		(end 363.163358 -297.866816)
		(width 0.14224)
		(layer "In11.Cu")
		(net "P5E_CPU0_P3_TX_DP<2>")
	)
	(segment
		(start 362.548932 -288.341816)
		(end 362.549948 -288.342324)
		(width 0.1143)
		(layer "In11.Cu")
		(net "P5E_CPU0_P3_TX_DP<2>")
	)
	(segment
		(start 362.619798 -285.701232)
		(end 362.619544 -285.701232)
		(width 0.1143)
		(layer "In11.Cu")
		(net "P5E_CPU0_P3_TX_DP<2>")
	)
	(segment
		(start 362.515404 -291.562282)
		(end 362.521754 -291.566092)
		(width 0.1143)
		(layer "In11.Cu")
		(net "P5E_CPU0_P3_TX_DP<2>")
	)
	(segment
		(start 362.5469 -288.340546)
		(end 362.548932 -288.341816)
		(width 0.1143)
		(layer "In11.Cu")
		(net "P5E_CPU0_P3_TX_DP<2>")
	)
	(segment
		(start 378.328936 -321.166744)
		(end 380.066804 -325.36257)
		(width 0.14224)
		(layer "In11.Cu")
		(net "P5E_CPU0_P3_TX_DP<2>")
	)
	(segment
		(start 362.583476 -280.261822)
		(end 362.603542 -280.2763)
		(width 0.1143)
		(layer "In11.Cu")
		(net "P5E_CPU0_P3_TX_DP<2>")
	)
	(segment
		(start 362.563918 -293.829232)
		(end 362.550202 -293.836852)
		(width 0.1143)
		(layer "In11.Cu")
		(net "P5E_CPU0_P3_TX_DP<2>")
	)
	(segment
		(start 377.435872 -363.713522)
		(end 367.485168 -374.998488)
		(width 0.14224)
		(layer "In11.Cu")
		(net "P5E_CPU0_P3_TX_DP<2>")
	)
	(segment
		(start 362.614718 -285.70555)
		(end 362.613448 -285.706566)
		(width 0.1143)
		(layer "In11.Cu")
		(net "P5E_CPU0_P3_TX_DP<2>")
	)
	(segment
		(start 362.541058 -281.85745)
		(end 362.583476 -281.881834)
		(width 0.1143)
		(layer "In11.Cu")
		(net "P5E_CPU0_P3_TX_DP<2>")
	)
	(segment
		(start 362.55833 -293.207186)
		(end 362.559346 -293.207694)
		(width 0.1143)
		(layer "In11.Cu")
		(net "P5E_CPU0_P3_TX_DP<2>")
	)
	(segment
		(start 362.513372 -289.941)
		(end 362.520738 -289.945318)
		(width 0.1143)
		(layer "In11.Cu")
		(net "P5E_CPU0_P3_TX_DP<2>")
	)
	(segment
		(start 362.549186 -292.230048)
		(end 362.544614 -292.232588)
		(width 0.1143)
		(layer "In11.Cu")
		(net "P5E_CPU0_P3_TX_DP<2>")
	)
	(segment
		(start 362.556044 -293.205916)
		(end 362.557568 -293.206678)
		(width 0.1143)
		(layer "In11.Cu")
		(net "P5E_CPU0_P3_TX_DP<2>")
	)
	(segment
		(start 362.554266 -285.105094)
		(end 362.583476 -285.121858)
		(width 0.1143)
		(layer "In11.Cu")
		(net "P5E_CPU0_P3_TX_DP<2>")
	)
	(segment
		(start 362.364782 -278.946102)
		(end 362.662724 -278.946102)
		(width 0.1143)
		(layer "In11.Cu")
		(net "P5E_CPU0_P3_TX_DP<2>")
	)
	(segment
		(start 362.54309 -285.09849)
		(end 362.543344 -285.098744)
		(width 0.1143)
		(layer "In11.Cu")
		(net "P5E_CPU0_P3_TX_DP<2>")
	)
	(segment
		(start 362.521754 -291.566092)
		(end 362.583476 -291.601652)
		(width 0.1143)
		(layer "In11.Cu")
		(net "P5E_CPU0_P3_TX_DP<2>")
	)
	(segment
		(start 362.687616 -288.481262)
		(end 362.71581 -288.54273)
		(width 0.1143)
		(layer "In11.Cu")
		(net "P5E_CPU0_P3_TX_DP<2>")
	)
	(segment
		(start 362.534962 -287.377378)
		(end 362.486448 -287.404556)
		(width 0.1143)
		(layer "In11.Cu")
		(net "P5E_CPU0_P3_TX_DP<2>")
	)
	(segment
		(start 362.583476 -290.590224)
		(end 362.521754 -290.625784)
		(width 0.1143)
		(layer "In11.Cu")
		(net "P5E_CPU0_P3_TX_DP<2>")
	)
	(segment
		(start 362.544614 -292.232588)
		(end 362.51261 -292.251384)
		(width 0.1143)
		(layer "In11.Cu")
		(net "P5E_CPU0_P3_TX_DP<2>")
	)
	(segment
		(start 366.39881 -379.597412)
		(end 366.115092 -379.88113)
		(width 0.14224)
		(layer "In11.Cu")
		(net "P5E_CPU0_P3_TX_DP<2>")
	)
	(segment
		(start 363.163866 -296.418508)
		(end 363.163866 -296.446956)
		(width 0.1143)
		(layer "In11.Cu")
		(net "P5E_CPU0_P3_TX_DP<2>")
	)
	(segment
		(start 362.55198 -285.103824)
		(end 362.552742 -285.104078)
		(width 0.1143)
		(layer "In11.Cu")
		(net "P5E_CPU0_P3_TX_DP<2>")
	)
	(segment
		(start 362.583476 -284.11043)
		(end 362.552488 -284.12821)
		(width 0.1143)
		(layer "In11.Cu")
		(net "P5E_CPU0_P3_TX_DP<2>")
	)
	(segment
		(start 362.57738 -287.353502)
		(end 362.534962 -287.377378)
		(width 0.1143)
		(layer "In11.Cu")
		(net "P5E_CPU0_P3_TX_DP<2>")
	)
	(segment
		(start 362.546138 -288.340038)
		(end 362.5469 -288.340546)
		(width 0.1143)
		(layer "In11.Cu")
		(net "P5E_CPU0_P3_TX_DP<2>")
	)
	(segment
		(start 362.269532 -287.82518)
		(end 362.269532 -287.856168)
		(width 0.1143)
		(layer "In11.Cu")
		(net "P5E_CPU0_P3_TX_DP<2>")
	)
	(segment
		(start 362.559346 -293.207694)
		(end 362.584238 -293.222172)
		(width 0.1143)
		(layer "In11.Cu")
		(net "P5E_CPU0_P3_TX_DP<2>")
	)
	(segment
		(start 362.549186 -285.102046)
		(end 362.55198 -285.103824)
		(width 0.1143)
		(layer "In11.Cu")
		(net "P5E_CPU0_P3_TX_DP<2>")
	)
	(segment
		(start 383.256028 -341.395558)
		(end 383.256028 -347.50121)
		(width 0.14224)
		(layer "In11.Cu")
		(net "P5E_CPU0_P3_TX_DP<2>")
	)
	(segment
		(start 362.546392 -285.100522)
		(end 362.549186 -285.102046)
		(width 0.1143)
		(layer "In11.Cu")
		(net "P5E_CPU0_P3_TX_DP<2>")
	)
	(segment
		(start 362.583476 -279.250394)
		(end 362.5215 -279.2857)
		(width 0.1143)
		(layer "In11.Cu")
		(net "P5E_CPU0_P3_TX_DP<2>")
	)
	(segment
		(start 362.582714 -294.841168)
		(end 362.583476 -294.841676)
		(width 0.1143)
		(layer "In11.Cu")
		(net "P5E_CPU0_P3_TX_DP<2>")
	)
	(segment
		(start 362.519468 -293.18458)
		(end 362.52023 -293.185088)
		(width 0.1143)
		(layer "In11.Cu")
		(net "P5E_CPU0_P3_TX_DP<2>")
	)
	(segment
		(start 362.636816 -287.313878)
		(end 362.636816 -287.314132)
		(width 0.1143)
		(layer "In11.Cu")
		(net "P5E_CPU0_P3_TX_DP<2>")
	)
	(segment
		(start 362.552742 -285.104078)
		(end 362.554266 -285.105094)
		(width 0.1143)
		(layer "In11.Cu")
		(net "P5E_CPU0_P3_TX_DP<2>")
	)
	(segment
		(start 362.583476 -282.490418)
		(end 362.551726 -282.508706)
		(width 0.1143)
		(layer "In11.Cu")
		(net "P5E_CPU0_P3_TX_DP<2>")
	)
	(segment
		(start 362.613448 -285.706566)
		(end 362.54944 -285.749238)
		(width 0.1143)
		(layer "In11.Cu")
		(net "P5E_CPU0_P3_TX_DP<2>")
	)
	(segment
		(start 380.066804 -325.36257)
		(end 383.256028 -341.395558)
		(width 0.14224)
		(layer "In11.Cu")
		(net "P5E_CPU0_P3_TX_DP<2>")
	)
	(segment
		(start 363.163866 -296.774108)
		(end 363.163358 -296.774616)
		(width 0.14224)
		(layer "In11.Cu")
		(net "P5E_CPU0_P3_TX_DP<2>")
	)
	(segment
		(start 363.209586 -296.372788)
		(end 363.163866 -296.418508)
		(width 0.1143)
		(layer "In11.Cu")
		(net "P5E_CPU0_P3_TX_DP<2>")
	)
	(segment
		(start 362.573062 -288.976308)
		(end 362.513372 -289.010852)
		(width 0.1143)
		(layer "In11.Cu")
		(net "P5E_CPU0_P3_TX_DP<2>")
	)
	(segment
		(start 362.583222 -289.98164)
		(end 362.583476 -289.98164)
		(width 0.1143)
		(layer "In11.Cu")
		(net "P5E_CPU0_P3_TX_DP<2>")
	)
	(segment
		(start 362.685838 -288.477198)
		(end 362.687616 -288.481262)
		(width 0.1143)
		(layer "In11.Cu")
		(net "P5E_CPU0_P3_TX_DP<2>")
	)
	(segment
		(start 362.544106 -283.47924)
		(end 362.583476 -283.501846)
		(width 0.1143)
		(layer "In11.Cu")
		(net "P5E_CPU0_P3_TX_DP<2>")
	)
	(segment
		(start 362.61548 -285.704788)
		(end 362.614718 -285.70555)
		(width 0.1143)
		(layer "In11.Cu")
		(net "P5E_CPU0_P3_TX_DP<2>")
	)
	(segment
		(start 363.209586 -295.955974)
		(end 363.209586 -296.372788)
		(width 0.1143)
		(layer "In11.Cu")
		(net "P5E_CPU0_P3_TX_DP<2>")
	)
	(segment
		(start 362.552488 -292.228016)
		(end 362.551726 -292.228524)
		(width 0.1143)
		(layer "In11.Cu")
		(net "P5E_CPU0_P3_TX_DP<2>")
	)
	(segment
		(start 362.587286 -293.224458)
		(end 362.591096 -293.227252)
		(width 0.1143)
		(layer "In11.Cu")
		(net "P5E_CPU0_P3_TX_DP<2>")
	)
	(segment
		(start 362.58373 -285.122112)
		(end 362.58754 -285.124906)
		(width 0.1143)
		(layer "In11.Cu")
		(net "P5E_CPU0_P3_TX_DP<2>")
	)
	(segment
		(start 362.54563 -285.100014)
		(end 362.546392 -285.100522)
		(width 0.1143)
		(layer "In11.Cu")
		(net "P5E_CPU0_P3_TX_DP<2>")
	)
	(segment
		(start 362.513372 -289.010852)
		(end 362.50118 -289.019488)
		(width 0.1143)
		(layer "In11.Cu")
		(net "P5E_CPU0_P3_TX_DP<2>")
	)
	(segment
		(start 362.50118 -289.932364)
		(end 362.513372 -289.941)
		(width 0.1143)
		(layer "In11.Cu")
		(net "P5E_CPU0_P3_TX_DP<2>")
	)
	(segment
		(start 362.520738 -289.945318)
		(end 362.5215 -289.945826)
		(width 0.1143)
		(layer "In11.Cu")
		(net "P5E_CPU0_P3_TX_DP<2>")
	)
	(segment
		(start 362.585 -293.22268)
		(end 362.586016 -293.223442)
		(width 0.1143)
		(layer "In11.Cu")
		(net "P5E_CPU0_P3_TX_DP<2>")
	)
	(segment
		(start 362.457492 -284.175708)
		(end 362.401104 -284.22981)
		(width 0.1143)
		(layer "In11.Cu")
		(net "P5E_CPU0_P3_TX_DP<2>")
	)
	(segment
		(start 362.55071 -292.229032)
		(end 362.549186 -292.230048)
		(width 0.1143)
		(layer "In11.Cu")
		(net "P5E_CPU0_P3_TX_DP<2>")
	)
	(segment
		(start 362.552996 -280.243788)
		(end 362.552742 -280.244042)
		(width 0.1143)
		(layer "In11.Cu")
		(net "P5E_CPU0_P3_TX_DP<2>")
	)
	(segment
		(start 363.163358 -297.866816)
		(end 364.6424 -302.742346)
		(width 0.14224)
		(layer "In11.Cu")
		(net "P5E_CPU0_P3_TX_DP<2>")
	)
	(segment
		(start 362.552488 -284.12821)
		(end 362.457492 -284.175708)
		(width 0.1143)
		(layer "In11.Cu")
		(net "P5E_CPU0_P3_TX_DP<2>")
	)
	(segment
		(start 362.583984 -285.122112)
		(end 362.58373 -285.122112)
		(width 0.1143)
		(layer "In11.Cu")
		(net "P5E_CPU0_P3_TX_DP<2>")
	)
	(segment
		(start 362.583476 -292.210236)
		(end 362.552488 -292.228016)
		(width 0.1143)
		(layer "In11.Cu")
		(net "P5E_CPU0_P3_TX_DP<2>")
	)
	(segment
		(start 362.552488 -293.203884)
		(end 362.555282 -293.205408)
		(width 0.1143)
		(layer "In11.Cu")
		(net "P5E_CPU0_P3_TX_DP<2>")
	)
	(segment
		(start 362.5215 -279.2857)
		(end 362.421424 -279.385776)
		(width 0.1143)
		(layer "In11.Cu")
		(net "P5E_CPU0_P3_TX_DP<2>")
	)
	(segment
		(start 362.55452 -280.245058)
		(end 362.583476 -280.261822)
		(width 0.1143)
		(layer "In11.Cu")
		(net "P5E_CPU0_P3_TX_DP<2>")
	)
	(segment
		(start 368.52606 -308.554628)
		(end 375.92889 -317.574676)
		(width 0.14224)
		(layer "In11.Cu")
		(net "P5E_CPU0_P3_TX_DP<2>")
	)
	(segment
		(start 362.54944 -286.722312)
		(end 362.585508 -286.743394)
		(width 0.1143)
		(layer "In11.Cu")
		(net "P5E_CPU0_P3_TX_DP<2>")
	)
	(segment
		(start 377.51131 -363.611922)
		(end 377.511564 -363.611922)
		(width 0.14224)
		(layer "In11.Cu")
		(net "P5E_CPU0_P3_TX_DP<2>")
	)
	(segment
		(start 362.619544 -285.701232)
		(end 362.617258 -285.703264)
		(width 0.1143)
		(layer "In11.Cu")
		(net "P5E_CPU0_P3_TX_DP<2>")
	)
	(arc
		(start 362.413804 -287.459674)
		(mid 362.306933 -287.628719)
		(end 362.269532 -287.82518)
		(width 0.1143)
		(layer "In11.Cu")
		(net "P5E_CPU0_P3_TX_DP<2>")
	)
	(arc
		(start 362.585508 -286.743394)
		(mid 362.698526 -286.876255)
		(end 362.739178 -287.045908)
		(width 0.1143)
		(layer "In11.Cu")
		(net "P5E_CPU0_P3_TX_DP<2>")
	)
	(arc
		(start 362.269532 -287.856168)
		(mid 362.333208 -288.116972)
		(end 362.51007 -288.318956)
		(width 0.1143)
		(layer "In11.Cu")
		(net "P5E_CPU0_P3_TX_DP<2>")
	)
	(arc
		(start 362.583476 -281.881834)
		(mid 362.739404 -282.186126)
		(end 362.583476 -282.490418)
		(width 0.1143)
		(layer "In11.Cu")
		(net "P5E_CPU0_P3_TX_DP<2>")
	)
	(arc
		(start 362.544106 -282.513024)
		(mid 362.265929 -282.996132)
		(end 362.544106 -283.47924)
		(width 0.1143)
		(layer "In11.Cu")
		(net "P5E_CPU0_P3_TX_DP<2>")
	)
	(arc
		(start 362.583476 -294.841676)
		(mid 362.698152 -294.97501)
		(end 362.739432 -295.145968)
		(width 0.1143)
		(layer "In11.Cu")
		(net "P5E_CPU0_P3_TX_DP<2>")
	)
	(arc
		(start 362.339382 -284.342332)
		(mid 362.28854 -284.761541)
		(end 362.54309 -285.09849)
		(width 0.1143)
		(layer "In11.Cu")
		(net "P5E_CPU0_P3_TX_DP<2>")
	)
	(arc
		(start 362.50499 -293.86657)
		(mid 362.257259 -294.348489)
		(end 362.535216 -294.813736)
		(width 0.1143)
		(layer "In11.Cu")
		(net "P5E_CPU0_P3_TX_DP<2>")
	)
	(arc
		(start 362.421424 -279.385776)
		(mid 362.353302 -279.469329)
		(end 362.303314 -279.564846)
		(width 0.1143)
		(layer "In11.Cu")
		(net "P5E_CPU0_P3_TX_DP<2>")
	)
	(arc
		(start 362.583476 -289.98164)
		(mid 362.739404 -290.285932)
		(end 362.583476 -290.590224)
		(width 0.1143)
		(layer "In11.Cu")
		(net "P5E_CPU0_P3_TX_DP<2>")
	)
	(arc
		(start 377.511564 -363.611922)
		(mid 377.475828 -363.664294)
		(end 377.435872 -363.713522)
		(width 0.14224)
		(layer "In11.Cu")
		(net "P5E_CPU0_P3_TX_DP<2>")
	)
	(arc
		(start 362.739432 -287.123886)
		(mid 362.71197 -287.231761)
		(end 362.636816 -287.313878)
		(width 0.1143)
		(layer "In11.Cu")
		(net "P5E_CPU0_P3_TX_DP<2>")
	)
	(arc
		(start 362.739432 -295.145968)
		(mid 362.803947 -295.408187)
		(end 362.982764 -295.610534)
		(width 0.1143)
		(layer "In11.Cu")
		(net "P5E_CPU0_P3_TX_DP<2>")
	)
	(arc
		(start 362.486448 -287.404556)
		(mid 362.471602 -287.413315)
		(end 362.457238 -287.422844)
		(width 0.1143)
		(layer "In11.Cu")
		(net "P5E_CPU0_P3_TX_DP<2>")
	)
	(arc
		(start 362.499148 -291.550852)
		(mid 362.507226 -291.556638)
		(end 362.515404 -291.562282)
		(width 0.1143)
		(layer "In11.Cu")
		(net "P5E_CPU0_P3_TX_DP<2>")
	)
	(arc
		(start 362.583476 -291.601652)
		(mid 362.739404 -291.905944)
		(end 362.583476 -292.210236)
		(width 0.1143)
		(layer "In11.Cu")
		(net "P5E_CPU0_P3_TX_DP<2>")
	)
	(arc
		(start 362.603542 -280.2763)
		(mid 362.752049 -280.566114)
		(end 362.603542 -280.855928)
		(width 0.1143)
		(layer "In11.Cu")
		(net "P5E_CPU0_P3_TX_DP<2>")
	)
	(arc
		(start 362.541058 -280.89479)
		(mid 362.263912 -281.37612)
		(end 362.541058 -281.85745)
		(width 0.1143)
		(layer "In11.Cu")
		(net "P5E_CPU0_P3_TX_DP<2>")
	)
	(arc
		(start 362.54944 -285.75)
		(mid 362.269512 -286.236156)
		(end 362.54944 -286.722312)
		(width 0.1143)
		(layer "In11.Cu")
		(net "P5E_CPU0_P3_TX_DP<2>")
	)
	(arc
		(start 362.50118 -289.019488)
		(mid 362.266759 -289.475926)
		(end 362.50118 -289.932364)
		(width 0.1143)
		(layer "In11.Cu")
		(net "P5E_CPU0_P3_TX_DP<2>")
	)
	(arc
		(start 367.485168 -374.998488)
		(mid 367.07085 -375.545422)
		(end 366.741456 -376.14733)
		(width 0.14224)
		(layer "In11.Cu")
		(net "P5E_CPU0_P3_TX_DP<2>")
	)
	(arc
		(start 362.59516 -293.2303)
		(mid 362.742243 -293.538239)
		(end 362.563918 -293.829232)
		(width 0.1143)
		(layer "In11.Cu")
		(net "P5E_CPU0_P3_TX_DP<2>")
	)
	(arc
		(start 366.741456 -376.14733)
		(mid 366.486146 -376.684229)
		(end 366.39881 -377.272296)
		(width 0.14224)
		(layer "In11.Cu")
		(net "P5E_CPU0_P3_TX_DP<2>")
	)
	(arc
		(start 362.732574 -279.015952)
		(mid 362.680525 -279.147471)
		(end 362.583476 -279.250394)
		(width 0.1143)
		(layer "In11.Cu")
		(net "P5E_CPU0_P3_TX_DP<2>")
	)
	(arc
		(start 362.51261 -292.251384)
		(mid 362.269283 -292.71595)
		(end 362.51261 -293.180516)
		(width 0.1143)
		(layer "In11.Cu")
		(net "P5E_CPU0_P3_TX_DP<2>")
	)
	(arc
		(start 362.303314 -279.564846)
		(mid 362.297781 -279.952266)
		(end 362.552996 -280.243788)
		(width 0.1143)
		(layer "In11.Cu")
		(net "P5E_CPU0_P3_TX_DP<2>")
	)
	(arc
		(start 362.664502 -288.894774)
		(mid 362.622933 -288.940082)
		(end 362.573062 -288.976054)
		(width 0.1143)
		(layer "In11.Cu")
		(net "P5E_CPU0_P3_TX_DP<2>")
	)
	(arc
		(start 363.081824 -295.674542)
		(mid 363.176103 -295.801459)
		(end 363.209586 -295.955974)
		(width 0.1143)
		(layer "In11.Cu")
		(net "P5E_CPU0_P3_TX_DP<2>")
	)
	(arc
		(start 362.499148 -290.641024)
		(mid 362.276264 -291.095938)
		(end 362.499148 -291.550852)
		(width 0.1143)
		(layer "In11.Cu")
		(net "P5E_CPU0_P3_TX_DP<2>")
	)
	(arc
		(start 362.583476 -283.501846)
		(mid 362.739404 -283.806138)
		(end 362.583476 -284.11043)
		(width 0.1143)
		(layer "In11.Cu")
		(net "P5E_CPU0_P3_TX_DP<2>")
	)
	(arc
		(start 363.05236 -295.651174)
		(mid 363.067382 -295.662492)
		(end 363.081824 -295.674542)
		(width 0.1143)
		(layer "In11.Cu")
		(net "P5E_CPU0_P3_TX_DP<2>")
	)
	(arc
		(start 362.660438 -288.435796)
		(mid 362.674344 -288.455757)
		(end 362.685838 -288.477198)
		(width 0.1143)
		(layer "In11.Cu")
		(net "P5E_CPU0_P3_TX_DP<2>")
	)
	(arc
		(start 362.589826 -285.12643)
		(mid 362.746175 -285.406463)
		(end 362.619798 -285.701232)
		(width 0.1143)
		(layer "In11.Cu")
		(net "P5E_CPU0_P3_TX_DP<2>")
	)
	(arc
		(start 383.256028 -347.50121)
		(mid 383.10181 -349.290961)
		(end 382.643888 -351.028)
		(width 0.14224)
		(layer "In11.Cu")
		(net "P5E_CPU0_P3_TX_DP<2>")
	)
	(arc
		(start 362.457238 -287.422844)
		(mid 362.434715 -287.440309)
		(end 362.413804 -287.459674)
		(width 0.1143)
		(layer "In11.Cu")
		(net "P5E_CPU0_P3_TX_DP<2>")
	)
	(arc
		(start 362.71581 -288.54273)
		(mid 362.742087 -288.726342)
		(end 362.664502 -288.894774)
		(width 0.1143)
		(layer "In11.Cu")
		(net "P5E_CPU0_P3_TX_DP<2>")
	)
	(arc
		(start 362.515404 -290.629594)
		(mid 362.507226 -290.635237)
		(end 362.499148 -290.641024)
		(width 0.1143)
		(layer "In11.Cu")
		(net "P5E_CPU0_P3_TX_DP<2>")
	)
	(arc
		(start 379.935994 -358.596692)
		(mid 378.857609 -361.169071)
		(end 377.51131 -363.611922)
		(width 0.14224)
		(layer "In11.Cu")
		(net "P5E_CPU0_P3_TX_DP<2>")
	)
	(arc
		(start 362.586524 -288.364168)
		(mid 362.625646 -288.397095)
		(end 362.65993 -288.435034)
		(width 0.1143)
		(layer "In11.Cu")
		(net "P5E_CPU0_P3_TX_DP<2>")
	)
	(segment
		(start 364.53064 -384.35026)
		(end 364.80115 -384.62077)
		(width 0.12954)
		(layer "F.Cu")
		(net "P5E_CPU0_P3_TX_DP<1>")
	)
	(segment
		(start 361.89793 -277.060152)
		(end 362.364782 -277.32609)
		(width 0.12954)
		(layer "F.Cu")
		(net "P5E_CPU0_P3_TX_DP<1>")
	)
	(segment
		(start 364.80115 -384.62077)
		(end 365.50473 -384.62077)
		(width 0.12954)
		(layer "F.Cu")
		(net "P5E_CPU0_P3_TX_DP<1>")
	)
	(segment
		(start 365.50473 -384.62077)
		(end 365.80064 -384.32486)
		(width 0.12954)
		(layer "F.Cu")
		(net "P5E_CPU0_P3_TX_DP<1>")
	)
	(segment
		(start 361.575604 -289.94227)
		(end 361.611926 -289.963352)
		(width 0.1143)
		(layer "In11.Cu")
		(net "P5E_CPU0_P3_TX_DP<1>")
	)
	(segment
		(start 367.869724 -309.250842)
		(end 375.272808 -318.271398)
		(width 0.14224)
		(layer "In11.Cu")
		(net "P5E_CPU0_P3_TX_DP<1>")
	)
	(segment
		(start 362.583476 -277.630382)
		(end 362.551726 -277.64867)
		(width 0.1143)
		(layer "In11.Cu")
		(net "P5E_CPU0_P3_TX_DP<1>")
	)
	(segment
		(start 364.86084 -382.006094)
		(end 365.787432 -382.932686)
		(width 0.14224)
		(layer "In11.Cu")
		(net "P5E_CPU0_P3_TX_DP<1>")
	)
	(segment
		(start 361.574334 -294.801544)
		(end 361.643422 -294.84193)
		(width 0.1143)
		(layer "In11.Cu")
		(net "P5E_CPU0_P3_TX_DP<1>")
	)
	(segment
		(start 361.642406 -280.870914)
		(end 361.611926 -280.888694)
		(width 0.1143)
		(layer "In11.Cu")
		(net "P5E_CPU0_P3_TX_DP<1>")
	)
	(segment
		(start 362.269278 -295.955974)
		(end 362.269532 -295.95572)
		(width 0.1143)
		(layer "In11.Cu")
		(net "P5E_CPU0_P3_TX_DP<1>")
	)
	(segment
		(start 375.891298 -363.944154)
		(end 368.346228 -372.26875)
		(width 0.14224)
		(layer "In11.Cu")
		(net "P5E_CPU0_P3_TX_DP<1>")
	)
	(segment
		(start 362.269532 -296.386758)
		(end 362.223812 -296.432478)
		(width 0.1143)
		(layer "In11.Cu")
		(net "P5E_CPU0_P3_TX_DP<1>")
	)
	(segment
		(start 366.640618 -373.946166)
		(end 366.65027 -374.139968)
		(width 0.14224)
		(layer "In11.Cu")
		(net "P5E_CPU0_P3_TX_DP<1>")
	)
	(segment
		(start 368.152426 -372.278402)
		(end 367.86566 -372.594632)
		(width 0.14224)
		(layer "In11.Cu")
		(net "P5E_CPU0_P3_TX_DP<1>")
	)
	(segment
		(start 375.272808 -318.271398)
		(end 377.474734 -321.566794)
		(width 0.14224)
		(layer "In11.Cu")
		(net "P5E_CPU0_P3_TX_DP<1>")
	)
	(segment
		(start 365.915956 -384.536188)
		(end 365.848392 -384.603752)
		(width 0.14224)
		(layer "In11.Cu")
		(net "P5E_CPU0_P3_TX_DP<1>")
	)
	(segment
		(start 362.269532 -278.133302)
		(end 362.269532 -278.136096)
		(width 0.1143)
		(layer "In11.Cu")
		(net "P5E_CPU0_P3_TX_DP<1>")
	)
	(segment
		(start 362.551726 -277.64867)
		(end 362.513118 -277.671276)
		(width 0.1143)
		(layer "In11.Cu")
		(net "P5E_CPU0_P3_TX_DP<1>")
	)
	(segment
		(start 361.606846 -292.231318)
		(end 361.605322 -292.231318)
		(width 0.1143)
		(layer "In11.Cu")
		(net "P5E_CPU0_P3_TX_DP<1>")
	)
	(segment
		(start 361.611418 -288.343086)
		(end 361.616498 -288.346134)
		(width 0.1143)
		(layer "In11.Cu")
		(net "P5E_CPU0_P3_TX_DP<1>")
	)
	(segment
		(start 361.643676 -293.829994)
		(end 361.574334 -293.87038)
		(width 0.1143)
		(layer "In11.Cu")
		(net "P5E_CPU0_P3_TX_DP<1>")
	)
	(segment
		(start 364.423198 -379.13437)
		(end 364.423198 -379.56109)
		(width 0.14224)
		(layer "In11.Cu")
		(net "P5E_CPU0_P3_TX_DP<1>")
	)
	(segment
		(start 361.608116 -281.86126)
		(end 361.612688 -281.864054)
		(width 0.1143)
		(layer "In11.Cu")
		(net "P5E_CPU0_P3_TX_DP<1>")
	)
	(segment
		(start 364.82147 -384.64109)
		(end 364.53064 -384.35026)
		(width 0.14224)
		(layer "In11.Cu")
		(net "P5E_CPU0_P3_TX_DP<1>")
	)
	(segment
		(start 361.61345 -288.987738)
		(end 361.612434 -288.988246)
		(width 0.1143)
		(layer "In11.Cu")
		(net "P5E_CPU0_P3_TX_DP<1>")
	)
	(segment
		(start 361.611926 -289.963352)
		(end 361.642406 -289.981132)
		(width 0.1143)
		(layer "In11.Cu")
		(net "P5E_CPU0_P3_TX_DP<1>")
	)
	(segment
		(start 361.575604 -291.562282)
		(end 361.581192 -291.56533)
		(width 0.1143)
		(layer "In11.Cu")
		(net "P5E_CPU0_P3_TX_DP<1>")
	)
	(segment
		(start 361.631484 -291.595048)
		(end 361.631992 -291.595048)
		(width 0.1143)
		(layer "In11.Cu")
		(net "P5E_CPU0_P3_TX_DP<1>")
	)
	(segment
		(start 361.613958 -293.204646)
		(end 361.61472 -293.205154)
		(width 0.1143)
		(layer "In11.Cu")
		(net "P5E_CPU0_P3_TX_DP<1>")
	)
	(segment
		(start 361.642406 -282.490926)
		(end 361.611926 -282.508706)
		(width 0.1143)
		(layer "In11.Cu")
		(net "P5E_CPU0_P3_TX_DP<1>")
	)
	(segment
		(start 361.581192 -291.56533)
		(end 361.631484 -291.595048)
		(width 0.1143)
		(layer "In11.Cu")
		(net "P5E_CPU0_P3_TX_DP<1>")
	)
	(segment
		(start 367.121186 -373.620284)
		(end 366.927384 -373.629682)
		(width 0.14224)
		(layer "In11.Cu")
		(net "P5E_CPU0_P3_TX_DP<1>")
	)
	(segment
		(start 361.642406 -279.250902)
		(end 361.574588 -279.29078)
		(width 0.1143)
		(layer "In11.Cu")
		(net "P5E_CPU0_P3_TX_DP<1>")
	)
	(segment
		(start 364.423198 -380.68885)
		(end 364.560358 -380.82601)
		(width 0.14224)
		(layer "In11.Cu")
		(net "P5E_CPU0_P3_TX_DP<1>")
	)
	(segment
		(start 361.605322 -292.231318)
		(end 361.603036 -292.233604)
		(width 0.1143)
		(layer "In11.Cu")
		(net "P5E_CPU0_P3_TX_DP<1>")
	)
	(segment
		(start 366.65027 -374.139968)
		(end 365.598456 -375.30024)
		(width 0.14224)
		(layer "In11.Cu")
		(net "P5E_CPU0_P3_TX_DP<1>")
	)
	(segment
		(start 362.223812 -297.994832)
		(end 363.783118 -303.13503)
		(width 0.14224)
		(layer "In11.Cu")
		(net "P5E_CPU0_P3_TX_DP<1>")
	)
	(segment
		(start 361.57281 -280.220674)
		(end 361.642406 -280.261314)
		(width 0.1143)
		(layer "In11.Cu")
		(net "P5E_CPU0_P3_TX_DP<1>")
	)
	(segment
		(start 361.329478 -286.236156)
		(end 361.329732 -286.236156)
		(width 0.1143)
		(layer "In11.Cu")
		(net "P5E_CPU0_P3_TX_DP<1>")
	)
	(segment
		(start 361.639104 -292.212522)
		(end 361.606846 -292.231318)
		(width 0.1143)
		(layer "In11.Cu")
		(net "P5E_CPU0_P3_TX_DP<1>")
	)
	(segment
		(start 377.474734 -321.566794)
		(end 379.15342 -325.61911)
		(width 0.14224)
		(layer "In11.Cu")
		(net "P5E_CPU0_P3_TX_DP<1>")
	)
	(segment
		(start 364.560358 -379.69825)
		(end 364.560358 -380.12497)
		(width 0.14224)
		(layer "In11.Cu")
		(net "P5E_CPU0_P3_TX_DP<1>")
	)
	(segment
		(start 361.603036 -293.198296)
		(end 361.613958 -293.204646)
		(width 0.1143)
		(layer "In11.Cu")
		(net "P5E_CPU0_P3_TX_DP<1>")
	)
	(segment
		(start 361.642406 -284.110938)
		(end 361.612688 -284.12821)
		(width 0.1143)
		(layer "In11.Cu")
		(net "P5E_CPU0_P3_TX_DP<1>")
	)
	(segment
		(start 361.573318 -286.700976)
		(end 361.644438 -286.742378)
		(width 0.1143)
		(layer "In11.Cu")
		(net "P5E_CPU0_P3_TX_DP<1>")
	)
	(segment
		(start 362.044234 -295.61155)
		(end 362.113576 -295.651936)
		(width 0.1143)
		(layer "In11.Cu")
		(net "P5E_CPU0_P3_TX_DP<1>")
	)
	(segment
		(start 362.223812 -296.446956)
		(end 362.223812 -297.994832)
		(width 0.14224)
		(layer "In11.Cu")
		(net "P5E_CPU0_P3_TX_DP<1>")
	)
	(segment
		(start 368.346228 -372.26875)
		(end 368.152426 -372.278402)
		(width 0.14224)
		(layer "In11.Cu")
		(net "P5E_CPU0_P3_TX_DP<1>")
	)
	(segment
		(start 361.61472 -293.205154)
		(end 361.615736 -293.205662)
		(width 0.1143)
		(layer "In11.Cu")
		(net "P5E_CPU0_P3_TX_DP<1>")
	)
	(segment
		(start 361.329732 -286.236156)
		(end 361.329732 -286.23895)
		(width 0.1143)
		(layer "In11.Cu")
		(net "P5E_CPU0_P3_TX_DP<1>")
	)
	(segment
		(start 364.560358 -380.12497)
		(end 364.423198 -380.26213)
		(width 0.14224)
		(layer "In11.Cu")
		(net "P5E_CPU0_P3_TX_DP<1>")
	)
	(segment
		(start 361.575604 -288.322512)
		(end 361.611418 -288.343086)
		(width 0.1143)
		(layer "In11.Cu")
		(net "P5E_CPU0_P3_TX_DP<1>")
	)
	(segment
		(start 362.269532 -295.95572)
		(end 362.269532 -296.386758)
		(width 0.1143)
		(layer "In11.Cu")
		(net "P5E_CPU0_P3_TX_DP<1>")
	)
	(segment
		(start 361.611926 -282.508706)
		(end 361.608116 -282.510992)
		(width 0.1143)
		(layer "In11.Cu")
		(net "P5E_CPU0_P3_TX_DP<1>")
	)
	(segment
		(start 362.223812 -296.432478)
		(end 362.223812 -296.446956)
		(width 0.1143)
		(layer "In11.Cu")
		(net "P5E_CPU0_P3_TX_DP<1>")
	)
	(segment
		(start 361.62615 -288.979864)
		(end 361.61345 -288.987738)
		(width 0.1143)
		(layer "In11.Cu")
		(net "P5E_CPU0_P3_TX_DP<1>")
	)
	(segment
		(start 362.662724 -277.32609)
		(end 362.732574 -277.39594)
		(width 0.1143)
		(layer "In11.Cu")
		(net "P5E_CPU0_P3_TX_DP<1>")
	)
	(segment
		(start 361.612434 -288.988246)
		(end 361.574334 -289.010344)
		(width 0.1143)
		(layer "In11.Cu")
		(net "P5E_CPU0_P3_TX_DP<1>")
	)
	(segment
		(start 361.612688 -284.12821)
		(end 361.611926 -284.128718)
		(width 0.1143)
		(layer "In11.Cu")
		(net "P5E_CPU0_P3_TX_DP<1>")
	)
	(segment
		(start 361.611926 -280.888694)
		(end 361.608116 -280.89098)
		(width 0.1143)
		(layer "In11.Cu")
		(net "P5E_CPU0_P3_TX_DP<1>")
	)
	(segment
		(start 361.812332 -291.909246)
		(end 361.812332 -291.91077)
		(width 0.1143)
		(layer "In11.Cu")
		(net "P5E_CPU0_P3_TX_DP<1>")
	)
	(segment
		(start 367.86566 -372.594632)
		(end 367.875058 -372.788434)
		(width 0.14224)
		(layer "In11.Cu")
		(net "P5E_CPU0_P3_TX_DP<1>")
	)
	(segment
		(start 364.560358 -378.99721)
		(end 364.423198 -379.13437)
		(width 0.14224)
		(layer "In11.Cu")
		(net "P5E_CPU0_P3_TX_DP<1>")
	)
	(segment
		(start 381.681228 -350.688656)
		(end 379.50902 -356.759256)
		(width 0.14224)
		(layer "In11.Cu")
		(net "P5E_CPU0_P3_TX_DP<1>")
	)
	(segment
		(start 361.611926 -290.608512)
		(end 361.575604 -290.629594)
		(width 0.1143)
		(layer "In11.Cu")
		(net "P5E_CPU0_P3_TX_DP<1>")
	)
	(segment
		(start 361.611672 -285.10357)
		(end 361.611926 -285.10357)
		(width 0.1143)
		(layer "In11.Cu")
		(net "P5E_CPU0_P3_TX_DP<1>")
	)
	(segment
		(start 366.927384 -373.629682)
		(end 366.640618 -373.946166)
		(width 0.14224)
		(layer "In11.Cu")
		(net "P5E_CPU0_P3_TX_DP<1>")
	)
	(segment
		(start 361.642406 -287.350708)
		(end 361.578398 -287.388046)
		(width 0.1143)
		(layer "In11.Cu")
		(net "P5E_CPU0_P3_TX_DP<1>")
	)
	(segment
		(start 361.608116 -283.481272)
		(end 361.612688 -283.484066)
		(width 0.1143)
		(layer "In11.Cu")
		(net "P5E_CPU0_P3_TX_DP<1>")
	)
	(segment
		(start 365.758476 -384.64109)
		(end 364.82147 -384.64109)
		(width 0.14224)
		(layer "In11.Cu")
		(net "P5E_CPU0_P3_TX_DP<1>")
	)
	(segment
		(start 362.364782 -277.32609)
		(end 362.662724 -277.32609)
		(width 0.1143)
		(layer "In11.Cu")
		(net "P5E_CPU0_P3_TX_DP<1>")
	)
	(segment
		(start 367.875058 -372.788434)
		(end 367.121186 -373.620284)
		(width 0.14224)
		(layer "In11.Cu")
		(net "P5E_CPU0_P3_TX_DP<1>")
	)
	(segment
		(start 361.611926 -285.10357)
		(end 361.642406 -285.12135)
		(width 0.1143)
		(layer "In11.Cu")
		(net "P5E_CPU0_P3_TX_DP<1>")
	)
	(segment
		(start 363.783118 -303.13503)
		(end 367.869724 -309.250842)
		(width 0.14224)
		(layer "In11.Cu")
		(net "P5E_CPU0_P3_TX_DP<1>")
	)
	(segment
		(start 361.612688 -283.484066)
		(end 361.642406 -283.501338)
		(width 0.1143)
		(layer "In11.Cu")
		(net "P5E_CPU0_P3_TX_DP<1>")
	)
	(segment
		(start 361.615736 -293.205662)
		(end 361.643168 -293.221664)
		(width 0.1143)
		(layer "In11.Cu")
		(net "P5E_CPU0_P3_TX_DP<1>")
	)
	(segment
		(start 361.611926 -284.128718)
		(end 361.611672 -284.128972)
		(width 0.1143)
		(layer "In11.Cu")
		(net "P5E_CPU0_P3_TX_DP<1>")
	)
	(segment
		(start 361.612688 -281.864054)
		(end 361.642406 -281.881326)
		(width 0.1143)
		(layer "In11.Cu")
		(net "P5E_CPU0_P3_TX_DP<1>")
	)
	(segment
		(start 364.423198 -379.56109)
		(end 364.560358 -379.69825)
		(width 0.14224)
		(layer "In11.Cu")
		(net "P5E_CPU0_P3_TX_DP<1>")
	)
	(segment
		(start 364.423198 -380.26213)
		(end 364.423198 -380.68885)
		(width 0.14224)
		(layer "In11.Cu")
		(net "P5E_CPU0_P3_TX_DP<1>")
	)
	(segment
		(start 362.113576 -278.440388)
		(end 362.04271 -278.481536)
		(width 0.1143)
		(layer "In11.Cu")
		(net "P5E_CPU0_P3_TX_DP<1>")
	)
	(segment
		(start 361.642406 -290.590732)
		(end 361.611926 -290.608512)
		(width 0.1143)
		(layer "In11.Cu")
		(net "P5E_CPU0_P3_TX_DP<1>")
	)
	(segment
		(start 382.316228 -341.52078)
		(end 382.316482 -347.02877)
		(width 0.14224)
		(layer "In11.Cu")
		(net "P5E_CPU0_P3_TX_DP<1>")
	)
	(segment
		(start 364.560358 -377.99137)
		(end 364.560358 -378.99721)
		(width 0.14224)
		(layer "In11.Cu")
		(net "P5E_CPU0_P3_TX_DP<1>")
	)
	(segment
		(start 365.953294 -383.33299)
		(end 365.953294 -384.446272)
		(width 0.14224)
		(layer "In11.Cu")
		(net "P5E_CPU0_P3_TX_DP<1>")
	)
	(segment
		(start 364.560358 -380.82601)
		(end 364.560358 -381.28067)
		(width 0.14224)
		(layer "In11.Cu")
		(net "P5E_CPU0_P3_TX_DP<1>")
	)
	(segment
		(start 361.642406 -285.73095)
		(end 361.57281 -285.77159)
		(width 0.1143)
		(layer "In11.Cu")
		(net "P5E_CPU0_P3_TX_DP<1>")
	)
	(segment
		(start 379.15342 -325.61911)
		(end 382.316228 -341.52078)
		(width 0.14224)
		(layer "In11.Cu")
		(net "P5E_CPU0_P3_TX_DP<1>")
	)
	(arc
		(start 361.642406 -283.501338)
		(mid 361.799383 -283.806138)
		(end 361.642406 -284.110938)
		(width 0.1143)
		(layer "In11.Cu")
		(net "P5E_CPU0_P3_TX_DP<1>")
	)
	(arc
		(start 361.799378 -287.045908)
		(mid 361.757829 -287.21733)
		(end 361.642406 -287.350708)
		(width 0.1143)
		(layer "In11.Cu")
		(net "P5E_CPU0_P3_TX_DP<1>")
	)
	(arc
		(start 361.608116 -282.510992)
		(mid 361.329697 -282.996132)
		(end 361.608116 -283.481272)
		(width 0.1143)
		(layer "In11.Cu")
		(net "P5E_CPU0_P3_TX_DP<1>")
	)
	(arc
		(start 362.113576 -295.651936)
		(mid 362.228161 -295.785147)
		(end 362.269278 -295.955974)
		(width 0.1143)
		(layer "In11.Cu")
		(net "P5E_CPU0_P3_TX_DP<1>")
	)
	(arc
		(start 362.269532 -278.136096)
		(mid 362.228277 -278.307067)
		(end 362.113576 -278.440388)
		(width 0.1143)
		(layer "In11.Cu")
		(net "P5E_CPU0_P3_TX_DP<1>")
	)
	(arc
		(start 365.953294 -384.446272)
		(mid 365.943592 -384.494956)
		(end 365.915956 -384.536188)
		(width 0.14224)
		(layer "In11.Cu")
		(net "P5E_CPU0_P3_TX_DP<1>")
	)
	(arc
		(start 361.329732 -287.856168)
		(mid 361.394968 -288.119759)
		(end 361.575604 -288.322512)
		(width 0.1143)
		(layer "In11.Cu")
		(net "P5E_CPU0_P3_TX_DP<1>")
	)
	(arc
		(start 361.644438 -286.742378)
		(mid 361.758367 -286.875525)
		(end 361.799378 -287.045908)
		(width 0.1143)
		(layer "In11.Cu")
		(net "P5E_CPU0_P3_TX_DP<1>")
	)
	(arc
		(start 379.50902 -356.759256)
		(mid 377.951394 -360.407658)
		(end 375.969022 -363.843824)
		(width 0.14224)
		(layer "In11.Cu")
		(net "P5E_CPU0_P3_TX_DP<1>")
	)
	(arc
		(start 361.642406 -289.981132)
		(mid 361.799383 -290.285932)
		(end 361.642406 -290.590732)
		(width 0.1143)
		(layer "In11.Cu")
		(net "P5E_CPU0_P3_TX_DP<1>")
	)
	(arc
		(start 361.642406 -281.881326)
		(mid 361.799383 -282.186126)
		(end 361.642406 -282.490926)
		(width 0.1143)
		(layer "In11.Cu")
		(net "P5E_CPU0_P3_TX_DP<1>")
	)
	(arc
		(start 361.643422 -294.84193)
		(mid 361.758265 -294.975078)
		(end 361.799632 -295.145968)
		(width 0.1143)
		(layer "In11.Cu")
		(net "P5E_CPU0_P3_TX_DP<1>")
	)
	(arc
		(start 361.642406 -280.261314)
		(mid 361.799383 -280.566114)
		(end 361.642406 -280.870914)
		(width 0.1143)
		(layer "In11.Cu")
		(net "P5E_CPU0_P3_TX_DP<1>")
	)
	(arc
		(start 361.616498 -288.346134)
		(mid 361.800183 -288.660279)
		(end 361.62615 -288.979864)
		(width 0.1143)
		(layer "In11.Cu")
		(net "P5E_CPU0_P3_TX_DP<1>")
	)
	(arc
		(start 361.578398 -287.388046)
		(mid 361.395736 -287.591127)
		(end 361.329732 -287.856168)
		(width 0.1143)
		(layer "In11.Cu")
		(net "P5E_CPU0_P3_TX_DP<1>")
	)
	(arc
		(start 365.848392 -384.603752)
		(mid 365.807152 -384.631371)
		(end 365.758476 -384.64109)
		(width 0.14224)
		(layer "In11.Cu")
		(net "P5E_CPU0_P3_TX_DP<1>")
	)
	(arc
		(start 361.574588 -279.29078)
		(mid 361.400065 -279.498628)
		(end 361.329478 -279.76068)
		(width 0.1143)
		(layer "In11.Cu")
		(net "P5E_CPU0_P3_TX_DP<1>")
	)
	(arc
		(start 361.575604 -290.629594)
		(mid 361.330496 -291.06622)
		(end 361.52836 -291.526214)
		(width 0.1143)
		(layer "In11.Cu")
		(net "P5E_CPU0_P3_TX_DP<1>")
	)
	(arc
		(start 361.608116 -280.89098)
		(mid 361.329697 -281.37612)
		(end 361.608116 -281.86126)
		(width 0.1143)
		(layer "In11.Cu")
		(net "P5E_CPU0_P3_TX_DP<1>")
	)
	(arc
		(start 361.574334 -289.010344)
		(mid 361.329514 -289.476665)
		(end 361.575604 -289.94227)
		(width 0.1143)
		(layer "In11.Cu")
		(net "P5E_CPU0_P3_TX_DP<1>")
	)
	(arc
		(start 361.603036 -292.233604)
		(mid 361.329764 -292.71595)
		(end 361.603036 -293.198296)
		(width 0.1143)
		(layer "In11.Cu")
		(net "P5E_CPU0_P3_TX_DP<1>")
	)
	(arc
		(start 364.560358 -381.28067)
		(mid 364.63845 -381.673267)
		(end 364.86084 -382.006094)
		(width 0.14224)
		(layer "In11.Cu")
		(net "P5E_CPU0_P3_TX_DP<1>")
	)
	(arc
		(start 382.316482 -347.02877)
		(mid 382.156446 -348.886066)
		(end 381.681228 -350.688656)
		(width 0.14224)
		(layer "In11.Cu")
		(net "P5E_CPU0_P3_TX_DP<1>")
	)
	(arc
		(start 361.329478 -279.76068)
		(mid 361.395041 -280.020358)
		(end 361.57281 -280.220674)
		(width 0.1143)
		(layer "In11.Cu")
		(net "P5E_CPU0_P3_TX_DP<1>")
	)
	(arc
		(start 361.631992 -291.595048)
		(mid 361.764006 -291.728122)
		(end 361.812332 -291.909246)
		(width 0.1143)
		(layer "In11.Cu")
		(net "P5E_CPU0_P3_TX_DP<1>")
	)
	(arc
		(start 361.574334 -293.87038)
		(mid 361.329513 -294.335962)
		(end 361.574334 -294.801544)
		(width 0.1143)
		(layer "In11.Cu")
		(net "P5E_CPU0_P3_TX_DP<1>")
	)
	(arc
		(start 361.799378 -278.946102)
		(mid 361.757829 -279.117524)
		(end 361.642406 -279.250902)
		(width 0.1143)
		(layer "In11.Cu")
		(net "P5E_CPU0_P3_TX_DP<1>")
	)
	(arc
		(start 361.57281 -285.77159)
		(mid 361.393997 -285.97394)
		(end 361.329478 -286.236156)
		(width 0.1143)
		(layer "In11.Cu")
		(net "P5E_CPU0_P3_TX_DP<1>")
	)
	(arc
		(start 362.732574 -277.39594)
		(mid 362.680525 -277.527459)
		(end 362.583476 -277.630382)
		(width 0.1143)
		(layer "In11.Cu")
		(net "P5E_CPU0_P3_TX_DP<1>")
	)
	(arc
		(start 361.329732 -286.23895)
		(mid 361.39435 -286.500112)
		(end 361.573318 -286.700976)
		(width 0.1143)
		(layer "In11.Cu")
		(net "P5E_CPU0_P3_TX_DP<1>")
	)
	(arc
		(start 375.969022 -363.843824)
		(mid 375.932092 -363.895486)
		(end 375.891298 -363.944154)
		(width 0.14224)
		(layer "In11.Cu")
		(net "P5E_CPU0_P3_TX_DP<1>")
	)
	(arc
		(start 361.642406 -285.12135)
		(mid 361.799383 -285.42615)
		(end 361.642406 -285.73095)
		(width 0.1143)
		(layer "In11.Cu")
		(net "P5E_CPU0_P3_TX_DP<1>")
	)
	(arc
		(start 362.04271 -278.481536)
		(mid 361.863897 -278.683886)
		(end 361.799378 -278.946102)
		(width 0.1143)
		(layer "In11.Cu")
		(net "P5E_CPU0_P3_TX_DP<1>")
	)
	(arc
		(start 361.799632 -295.145968)
		(mid 361.86445 -295.408957)
		(end 362.044234 -295.61155)
		(width 0.1143)
		(layer "In11.Cu")
		(net "P5E_CPU0_P3_TX_DP<1>")
	)
	(arc
		(start 361.643168 -293.221664)
		(mid 361.799413 -293.525676)
		(end 361.643676 -293.829994)
		(width 0.1143)
		(layer "In11.Cu")
		(net "P5E_CPU0_P3_TX_DP<1>")
	)
	(arc
		(start 361.812332 -291.91077)
		(mid 361.765952 -292.084749)
		(end 361.639104 -292.212522)
		(width 0.1143)
		(layer "In11.Cu")
		(net "P5E_CPU0_P3_TX_DP<1>")
	)
	(arc
		(start 361.52836 -291.526214)
		(mid 361.551509 -291.544868)
		(end 361.575604 -291.562282)
		(width 0.1143)
		(layer "In11.Cu")
		(net "P5E_CPU0_P3_TX_DP<1>")
	)
	(arc
		(start 361.611672 -284.128972)
		(mid 361.331908 -284.616334)
		(end 361.611672 -285.10357)
		(width 0.1143)
		(layer "In11.Cu")
		(net "P5E_CPU0_P3_TX_DP<1>")
	)
	(arc
		(start 365.787432 -382.932686)
		(mid 365.910204 -383.116333)
		(end 365.953294 -383.33299)
		(width 0.14224)
		(layer "In11.Cu")
		(net "P5E_CPU0_P3_TX_DP<1>")
	)
	(arc
		(start 365.598456 -375.30024)
		(mid 364.8289 -376.54917)
		(end 364.560358 -377.99137)
		(width 0.14224)
		(layer "In11.Cu")
		(net "P5E_CPU0_P3_TX_DP<1>")
	)
	(arc
		(start 362.513118 -277.671276)
		(mid 362.334188 -277.87216)
		(end 362.269532 -278.133302)
		(width 0.1143)
		(layer "In11.Cu")
		(net "P5E_CPU0_P3_TX_DP<1>")
	)
	(segment
		(start 394.107162 -388.149338)
		(end 393.403582 -388.149338)
		(width 0.12954)
		(layer "F.Cu")
		(net "P5E_CPU0_P3_TX_DP<15>")
	)
	(segment
		(start 372.707916 -276.250146)
		(end 373.174768 -276.516084)
		(width 0.12954)
		(layer "F.Cu")
		(net "P5E_CPU0_P3_TX_DP<15>")
	)
	(segment
		(start 394.377672 -387.878828)
		(end 394.107162 -388.149338)
		(width 0.12954)
		(layer "F.Cu")
		(net "P5E_CPU0_P3_TX_DP<15>")
	)
	(segment
		(start 393.403582 -388.149338)
		(end 393.107672 -387.853428)
		(width 0.12954)
		(layer "F.Cu")
		(net "P5E_CPU0_P3_TX_DP<15>")
	)
	(segment
		(start 373.47271 -276.516084)
		(end 373.174768 -276.516084)
		(width 0.1143)
		(layer "In11.Cu")
		(net "P5E_CPU0_P3_TX_DP<15>")
	)
	(segment
		(start 374.732804 -292.251384)
		(end 374.77192 -292.228524)
		(width 0.1143)
		(layer "In11.Cu")
		(net "P5E_CPU0_P3_TX_DP<15>")
	)
	(segment
		(start 374.8024 -281.881326)
		(end 374.77192 -281.863546)
		(width 0.1143)
		(layer "In11.Cu")
		(net "P5E_CPU0_P3_TX_DP<15>")
	)
	(segment
		(start 396.861538 -374.440704)
		(end 396.861538 -374.013984)
		(width 0.14224)
		(layer "In11.Cu")
		(net "P5E_CPU0_P3_TX_DP<15>")
	)
	(segment
		(start 374.77192 -291.583364)
		(end 374.732804 -291.560504)
		(width 0.1143)
		(layer "In11.Cu")
		(net "P5E_CPU0_P3_TX_DP<15>")
	)
	(segment
		(start 374.77192 -290.608512)
		(end 374.8024 -290.590732)
		(width 0.1143)
		(layer "In11.Cu")
		(net "P5E_CPU0_P3_TX_DP<15>")
	)
	(segment
		(start 373.80037 -276.985222)
		(end 373.799608 -276.984714)
		(width 0.1143)
		(layer "In11.Cu")
		(net "P5E_CPU0_P3_TX_DP<15>")
	)
	(segment
		(start 392.153394 -321.996816)
		(end 389.660638 -315.979556)
		(width 0.14224)
		(layer "In11.Cu")
		(net "P5E_CPU0_P3_TX_DP<15>")
	)
	(segment
		(start 375.248424 -295.637204)
		(end 375.247662 -295.636696)
		(width 0.1143)
		(layer "In11.Cu")
		(net "P5E_CPU0_P3_TX_DP<15>")
	)
	(segment
		(start 374.77192 -283.483558)
		(end 374.732804 -283.460698)
		(width 0.1143)
		(layer "In11.Cu")
		(net "P5E_CPU0_P3_TX_DP<15>")
	)
	(segment
		(start 375.246138 -279.436068)
		(end 375.245376 -279.43556)
		(width 0.1143)
		(layer "In11.Cu")
		(net "P5E_CPU0_P3_TX_DP<15>")
	)
	(segment
		(start 375.668032 -296.809414)
		(end 375.713752 -296.763694)
		(width 0.1143)
		(layer "In11.Cu")
		(net "P5E_CPU0_P3_TX_DP<15>")
	)
	(segment
		(start 395.85519 -382.658366)
		(end 396.85722 -380.237746)
		(width 0.14224)
		(layer "In11.Cu")
		(net "P5E_CPU0_P3_TX_DP<15>")
	)
	(segment
		(start 394.377672 -387.878828)
		(end 394.668502 -388.169658)
		(width 0.14224)
		(layer "In11.Cu")
		(net "P5E_CPU0_P3_TX_DP<15>")
	)
	(segment
		(start 375.24182 -295.633394)
		(end 375.240804 -295.632886)
		(width 0.1143)
		(layer "In11.Cu")
		(net "P5E_CPU0_P3_TX_DP<15>")
	)
	(segment
		(start 374.732804 -284.151578)
		(end 374.77192 -284.128718)
		(width 0.1143)
		(layer "In11.Cu")
		(net "P5E_CPU0_P3_TX_DP<15>")
	)
	(segment
		(start 396.998698 -375.705624)
		(end 396.861538 -375.568464)
		(width 0.14224)
		(layer "In11.Cu")
		(net "P5E_CPU0_P3_TX_DP<15>")
	)
	(segment
		(start 374.262142 -277.790402)
		(end 374.251474 -277.782782)
		(width 0.1143)
		(layer "In11.Cu")
		(net "P5E_CPU0_P3_TX_DP<15>")
	)
	(segment
		(start 374.77192 -285.10357)
		(end 374.732804 -285.08071)
		(width 0.1143)
		(layer "In11.Cu")
		(net "P5E_CPU0_P3_TX_DP<15>")
	)
	(segment
		(start 373.83212 -277.003764)
		(end 373.831866 -277.00351)
		(width 0.1143)
		(layer "In11.Cu")
		(net "P5E_CPU0_P3_TX_DP<15>")
	)
	(segment
		(start 375.27357 -279.451816)
		(end 375.252234 -279.43937)
		(width 0.1143)
		(layer "In11.Cu")
		(net "P5E_CPU0_P3_TX_DP<15>")
	)
	(segment
		(start 374.8024 -291.601144)
		(end 374.77192 -291.583364)
		(width 0.1143)
		(layer "In11.Cu")
		(net "P5E_CPU0_P3_TX_DP<15>")
	)
	(segment
		(start 375.209562 -279.414732)
		(end 375.202704 -279.410668)
		(width 0.1143)
		(layer "In11.Cu")
		(net "P5E_CPU0_P3_TX_DP<15>")
	)
	(segment
		(start 375.245376 -295.635426)
		(end 375.242582 -295.633902)
		(width 0.1143)
		(layer "In11.Cu")
		(net "P5E_CPU0_P3_TX_DP<15>")
	)
	(segment
		(start 396.998698 -377.961144)
		(end 396.861538 -377.823984)
		(width 0.14224)
		(layer "In11.Cu")
		(net "P5E_CPU0_P3_TX_DP<15>")
	)
	(segment
		(start 396.998698 -374.577864)
		(end 396.861538 -374.440704)
		(width 0.14224)
		(layer "In11.Cu")
		(net "P5E_CPU0_P3_TX_DP<15>")
	)
	(segment
		(start 396.998698 -373.876824)
		(end 396.998698 -372.611396)
		(width 0.14224)
		(layer "In11.Cu")
		(net "P5E_CPU0_P3_TX_DP<15>")
	)
	(segment
		(start 374.77192 -281.863546)
		(end 374.732804 -281.840686)
		(width 0.1143)
		(layer "In11.Cu")
		(net "P5E_CPU0_P3_TX_DP<15>")
	)
	(segment
		(start 396.998698 -376.132344)
		(end 396.998698 -375.705624)
		(width 0.14224)
		(layer "In11.Cu")
		(net "P5E_CPU0_P3_TX_DP<15>")
	)
	(segment
		(start 375.249694 -295.637966)
		(end 375.248424 -295.637204)
		(width 0.1143)
		(layer "In11.Cu")
		(net "P5E_CPU0_P3_TX_DP<15>")
	)
	(segment
		(start 396.998698 -375.004584)
		(end 396.998698 -374.577864)
		(width 0.14224)
		(layer "In11.Cu")
		(net "P5E_CPU0_P3_TX_DP<15>")
	)
	(segment
		(start 396.861538 -377.823984)
		(end 396.861538 -377.397264)
		(width 0.14224)
		(layer "In11.Cu")
		(net "P5E_CPU0_P3_TX_DP<15>")
	)
	(segment
		(start 375.245376 -279.43556)
		(end 375.242582 -279.434036)
		(width 0.1143)
		(layer "In11.Cu")
		(net "P5E_CPU0_P3_TX_DP<15>")
	)
	(segment
		(start 375.24182 -279.433528)
		(end 375.210324 -279.41524)
		(width 0.1143)
		(layer "In11.Cu")
		(net "P5E_CPU0_P3_TX_DP<15>")
	)
	(segment
		(start 374.77192 -288.9885)
		(end 374.8024 -288.97072)
		(width 0.1143)
		(layer "In11.Cu")
		(net "P5E_CPU0_P3_TX_DP<15>")
	)
	(segment
		(start 375.242582 -279.434036)
		(end 375.24182 -279.433528)
		(width 0.1143)
		(layer "In11.Cu")
		(net "P5E_CPU0_P3_TX_DP<15>")
	)
	(segment
		(start 375.210324 -279.41524)
		(end 375.209562 -279.414732)
		(width 0.1143)
		(layer "In11.Cu")
		(net "P5E_CPU0_P3_TX_DP<15>")
	)
	(segment
		(start 396.536672 -363.212888)
		(end 395.732762 -355.047296)
		(width 0.14224)
		(layer "In11.Cu")
		(net "P5E_CPU0_P3_TX_DP<15>")
	)
	(segment
		(start 374.8024 -289.981132)
		(end 374.77192 -289.963352)
		(width 0.1143)
		(layer "In11.Cu")
		(net "P5E_CPU0_P3_TX_DP<15>")
	)
	(segment
		(start 374.8024 -278.641302)
		(end 374.77192 -278.623522)
		(width 0.1143)
		(layer "In11.Cu")
		(net "P5E_CPU0_P3_TX_DP<15>")
	)
	(segment
		(start 374.732804 -289.01136)
		(end 374.77192 -288.9885)
		(width 0.1143)
		(layer "In11.Cu")
		(net "P5E_CPU0_P3_TX_DP<15>")
	)
	(segment
		(start 374.732804 -290.631372)
		(end 374.77192 -290.608512)
		(width 0.1143)
		(layer "In11.Cu")
		(net "P5E_CPU0_P3_TX_DP<15>")
	)
	(segment
		(start 382.9304 -305.906932)
		(end 375.737882 -297.142916)
		(width 0.14224)
		(layer "In11.Cu")
		(net "P5E_CPU0_P3_TX_DP<15>")
	)
	(segment
		(start 396.998698 -377.260104)
		(end 396.998698 -376.833384)
		(width 0.14224)
		(layer "In11.Cu")
		(net "P5E_CPU0_P3_TX_DP<15>")
	)
	(segment
		(start 375.248424 -279.437338)
		(end 375.247662 -279.43683)
		(width 0.1143)
		(layer "In11.Cu")
		(net "P5E_CPU0_P3_TX_DP<15>")
	)
	(segment
		(start 375.24182 -280.078688)
		(end 375.242582 -280.07818)
		(width 0.1143)
		(layer "In11.Cu")
		(net "P5E_CPU0_P3_TX_DP<15>")
	)
	(segment
		(start 396.861538 -374.013984)
		(end 396.998698 -373.876824)
		(width 0.14224)
		(layer "In11.Cu")
		(net "P5E_CPU0_P3_TX_DP<15>")
	)
	(segment
		(start 374.77192 -286.723582)
		(end 374.732804 -286.700722)
		(width 0.1143)
		(layer "In11.Cu")
		(net "P5E_CPU0_P3_TX_DP<15>")
	)
	(segment
		(start 395.50594 -388.13232)
		(end 395.558264 -388.079996)
		(width 0.14224)
		(layer "In11.Cu")
		(net "P5E_CPU0_P3_TX_DP<15>")
	)
	(segment
		(start 374.77192 -280.888694)
		(end 374.8024 -280.870914)
		(width 0.1143)
		(layer "In11.Cu")
		(net "P5E_CPU0_P3_TX_DP<15>")
	)
	(segment
		(start 375.252234 -279.43937)
		(end 375.249694 -279.4381)
		(width 0.1143)
		(layer "In11.Cu")
		(net "P5E_CPU0_P3_TX_DP<15>")
	)
	(segment
		(start 374.8024 -293.221156)
		(end 374.77192 -293.203376)
		(width 0.1143)
		(layer "In11.Cu")
		(net "P5E_CPU0_P3_TX_DP<15>")
	)
	(segment
		(start 375.737882 -297.142916)
		(end 375.668032 -296.913046)
		(width 0.14224)
		(layer "In11.Cu")
		(net "P5E_CPU0_P3_TX_DP<15>")
	)
	(segment
		(start 396.998698 -376.833384)
		(end 396.861538 -376.696224)
		(width 0.14224)
		(layer "In11.Cu")
		(net "P5E_CPU0_P3_TX_DP<15>")
	)
	(segment
		(start 374.77192 -289.963352)
		(end 374.732804 -289.940492)
		(width 0.1143)
		(layer "In11.Cu")
		(net "P5E_CPU0_P3_TX_DP<15>")
	)
	(segment
		(start 375.246138 -295.635934)
		(end 375.245376 -295.635426)
		(width 0.1143)
		(layer "In11.Cu")
		(net "P5E_CPU0_P3_TX_DP<15>")
	)
	(segment
		(start 396.861538 -376.696224)
		(end 396.861538 -376.269504)
		(width 0.14224)
		(layer "In11.Cu")
		(net "P5E_CPU0_P3_TX_DP<15>")
	)
	(segment
		(start 374.8024 -283.501338)
		(end 374.77192 -283.483558)
		(width 0.1143)
		(layer "In11.Cu")
		(net "P5E_CPU0_P3_TX_DP<15>")
	)
	(segment
		(start 395.595602 -387.99008)
		(end 395.595602 -383.963926)
		(width 0.14224)
		(layer "In11.Cu")
		(net "P5E_CPU0_P3_TX_DP<15>")
	)
	(segment
		(start 375.202704 -280.101548)
		(end 375.23928 -280.080212)
		(width 0.1143)
		(layer "In11.Cu")
		(net "P5E_CPU0_P3_TX_DP<15>")
	)
	(segment
		(start 373.555514 -276.598888)
		(end 373.47271 -276.516084)
		(width 0.1143)
		(layer "In11.Cu")
		(net "P5E_CPU0_P3_TX_DP<15>")
	)
	(segment
		(start 374.77192 -278.623522)
		(end 374.732804 -278.600662)
		(width 0.1143)
		(layer "In11.Cu")
		(net "P5E_CPU0_P3_TX_DP<15>")
	)
	(segment
		(start 374.77192 -292.228524)
		(end 374.8024 -292.210744)
		(width 0.1143)
		(layer "In11.Cu")
		(net "P5E_CPU0_P3_TX_DP<15>")
	)
	(segment
		(start 374.77192 -285.74873)
		(end 374.8024 -285.73095)
		(width 0.1143)
		(layer "In11.Cu")
		(net "P5E_CPU0_P3_TX_DP<15>")
	)
	(segment
		(start 396.998698 -379.5268)
		(end 396.998698 -377.961144)
		(width 0.14224)
		(layer "In11.Cu")
		(net "P5E_CPU0_P3_TX_DP<15>")
	)
	(segment
		(start 375.3358 -295.722548)
		(end 375.252234 -295.639236)
		(width 0.1143)
		(layer "In11.Cu")
		(net "P5E_CPU0_P3_TX_DP<15>")
	)
	(segment
		(start 374.333262 -277.831804)
		(end 374.262142 -277.790402)
		(width 0.1143)
		(layer "In11.Cu")
		(net "P5E_CPU0_P3_TX_DP<15>")
	)
	(segment
		(start 396.861538 -375.141744)
		(end 396.998698 -375.004584)
		(width 0.14224)
		(layer "In11.Cu")
		(net "P5E_CPU0_P3_TX_DP<15>")
	)
	(segment
		(start 373.835422 -277.005542)
		(end 373.832628 -277.004018)
		(width 0.1143)
		(layer "In11.Cu")
		(net "P5E_CPU0_P3_TX_DP<15>")
	)
	(segment
		(start 374.732804 -282.531566)
		(end 374.77192 -282.508706)
		(width 0.1143)
		(layer "In11.Cu")
		(net "P5E_CPU0_P3_TX_DP<15>")
	)
	(segment
		(start 374.804432 -286.742378)
		(end 374.77192 -286.723582)
		(width 0.1143)
		(layer "In11.Cu")
		(net "P5E_CPU0_P3_TX_DP<15>")
	)
	(segment
		(start 394.668502 -388.169658)
		(end 395.416024 -388.169658)
		(width 0.14224)
		(layer "In11.Cu")
		(net "P5E_CPU0_P3_TX_DP<15>")
	)
	(segment
		(start 374.77192 -282.508706)
		(end 374.8024 -282.490926)
		(width 0.1143)
		(layer "In11.Cu")
		(net "P5E_CPU0_P3_TX_DP<15>")
	)
	(segment
		(start 374.8024 -285.12135)
		(end 374.77192 -285.10357)
		(width 0.1143)
		(layer "In11.Cu")
		(net "P5E_CPU0_P3_TX_DP<15>")
	)
	(segment
		(start 375.242582 -280.07818)
		(end 375.27357 -280.0604)
		(width 0.1143)
		(layer "In11.Cu")
		(net "P5E_CPU0_P3_TX_DP<15>")
	)
	(segment
		(start 375.668032 -296.913046)
		(end 375.668032 -296.837862)
		(width 0.14224)
		(layer "In11.Cu")
		(net "P5E_CPU0_P3_TX_DP<15>")
	)
	(segment
		(start 374.77192 -293.848536)
		(end 374.8024 -293.830756)
		(width 0.1143)
		(layer "In11.Cu")
		(net "P5E_CPU0_P3_TX_DP<15>")
	)
	(segment
		(start 375.249694 -279.4381)
		(end 375.248424 -279.437338)
		(width 0.1143)
		(layer "In11.Cu")
		(net "P5E_CPU0_P3_TX_DP<15>")
	)
	(segment
		(start 375.668032 -296.837862)
		(end 375.668032 -296.809414)
		(width 0.1143)
		(layer "In11.Cu")
		(net "P5E_CPU0_P3_TX_DP<15>")
	)
	(segment
		(start 374.77192 -288.343594)
		(end 374.732804 -288.320734)
		(width 0.1143)
		(layer "In11.Cu")
		(net "P5E_CPU0_P3_TX_DP<15>")
	)
	(segment
		(start 395.732762 -339.99297)
		(end 392.153394 -321.996816)
		(width 0.14224)
		(layer "In11.Cu")
		(net "P5E_CPU0_P3_TX_DP<15>")
	)
	(segment
		(start 375.240804 -280.079196)
		(end 375.24182 -280.078688)
		(width 0.1143)
		(layer "In11.Cu")
		(net "P5E_CPU0_P3_TX_DP<15>")
	)
	(segment
		(start 396.861538 -376.269504)
		(end 396.998698 -376.132344)
		(width 0.14224)
		(layer "In11.Cu")
		(net "P5E_CPU0_P3_TX_DP<15>")
	)
	(segment
		(start 374.732804 -285.77159)
		(end 374.77192 -285.74873)
		(width 0.1143)
		(layer "In11.Cu")
		(net "P5E_CPU0_P3_TX_DP<15>")
	)
	(segment
		(start 375.247662 -279.43683)
		(end 375.246138 -279.436068)
		(width 0.1143)
		(layer "In11.Cu")
		(net "P5E_CPU0_P3_TX_DP<15>")
	)
	(segment
		(start 374.732804 -293.871396)
		(end 374.77192 -293.848536)
		(width 0.1143)
		(layer "In11.Cu")
		(net "P5E_CPU0_P3_TX_DP<15>")
	)
	(segment
		(start 375.240804 -295.632886)
		(end 375.202704 -295.610534)
		(width 0.1143)
		(layer "In11.Cu")
		(net "P5E_CPU0_P3_TX_DP<15>")
	)
	(segment
		(start 373.861584 -277.020782)
		(end 373.835422 -277.005542)
		(width 0.1143)
		(layer "In11.Cu")
		(net "P5E_CPU0_P3_TX_DP<15>")
	)
	(segment
		(start 375.252234 -295.639236)
		(end 375.249694 -295.637966)
		(width 0.1143)
		(layer "In11.Cu")
		(net "P5E_CPU0_P3_TX_DP<15>")
	)
	(segment
		(start 374.333516 -277.831804)
		(end 374.333262 -277.831804)
		(width 0.1143)
		(layer "In11.Cu")
		(net "P5E_CPU0_P3_TX_DP<15>")
	)
	(segment
		(start 374.732804 -280.911554)
		(end 374.77192 -280.888694)
		(width 0.1143)
		(layer "In11.Cu")
		(net "P5E_CPU0_P3_TX_DP<15>")
	)
	(segment
		(start 373.799608 -276.984714)
		(end 373.79275 -276.98065)
		(width 0.1143)
		(layer "In11.Cu")
		(net "P5E_CPU0_P3_TX_DP<15>")
	)
	(segment
		(start 396.861538 -377.397264)
		(end 396.998698 -377.260104)
		(width 0.14224)
		(layer "In11.Cu")
		(net "P5E_CPU0_P3_TX_DP<15>")
	)
	(segment
		(start 375.23928 -280.080212)
		(end 375.240804 -280.079196)
		(width 0.1143)
		(layer "In11.Cu")
		(net "P5E_CPU0_P3_TX_DP<15>")
	)
	(segment
		(start 389.660638 -315.979556)
		(end 382.9304 -305.906932)
		(width 0.14224)
		(layer "In11.Cu")
		(net "P5E_CPU0_P3_TX_DP<15>")
	)
	(segment
		(start 395.732762 -355.047296)
		(end 395.732762 -339.99297)
		(width 0.14224)
		(layer "In11.Cu")
		(net "P5E_CPU0_P3_TX_DP<15>")
	)
	(segment
		(start 396.861538 -375.568464)
		(end 396.861538 -375.141744)
		(width 0.14224)
		(layer "In11.Cu")
		(net "P5E_CPU0_P3_TX_DP<15>")
	)
	(segment
		(start 375.247662 -295.636696)
		(end 375.246138 -295.635934)
		(width 0.1143)
		(layer "In11.Cu")
		(net "P5E_CPU0_P3_TX_DP<15>")
	)
	(segment
		(start 375.242582 -295.633902)
		(end 375.24182 -295.633394)
		(width 0.1143)
		(layer "In11.Cu")
		(net "P5E_CPU0_P3_TX_DP<15>")
	)
	(segment
		(start 373.831866 -277.00351)
		(end 373.80037 -276.985222)
		(width 0.1143)
		(layer "In11.Cu")
		(net "P5E_CPU0_P3_TX_DP<15>")
	)
	(segment
		(start 374.77192 -294.823388)
		(end 374.732804 -294.800528)
		(width 0.1143)
		(layer "In11.Cu")
		(net "P5E_CPU0_P3_TX_DP<15>")
	)
	(segment
		(start 373.832628 -277.004018)
		(end 373.83212 -277.003764)
		(width 0.1143)
		(layer "In11.Cu")
		(net "P5E_CPU0_P3_TX_DP<15>")
	)
	(segment
		(start 374.77192 -284.128718)
		(end 374.8024 -284.110938)
		(width 0.1143)
		(layer "In11.Cu")
		(net "P5E_CPU0_P3_TX_DP<15>")
	)
	(segment
		(start 374.77192 -293.203376)
		(end 374.732804 -293.180516)
		(width 0.1143)
		(layer "In11.Cu")
		(net "P5E_CPU0_P3_TX_DP<15>")
	)
	(segment
		(start 375.713752 -296.763694)
		(end 375.713752 -296.635424)
		(width 0.1143)
		(layer "In11.Cu")
		(net "P5E_CPU0_P3_TX_DP<15>")
	)
	(segment
		(start 374.735344 -287.389824)
		(end 374.8024 -287.350708)
		(width 0.1143)
		(layer "In11.Cu")
		(net "P5E_CPU0_P3_TX_DP<15>")
	)
	(segment
		(start 396.998698 -372.611396)
		(end 396.536672 -363.212888)
		(width 0.14224)
		(layer "In11.Cu")
		(net "P5E_CPU0_P3_TX_DP<15>")
	)
	(segment
		(start 374.019572 -277.329138)
		(end 374.019572 -277.32609)
		(width 0.1143)
		(layer "In11.Cu")
		(net "P5E_CPU0_P3_TX_DP<15>")
	)
	(segment
		(start 374.8024 -294.841168)
		(end 374.77192 -294.823388)
		(width 0.1143)
		(layer "In11.Cu")
		(net "P5E_CPU0_P3_TX_DP<15>")
	)
	(segment
		(start 374.804432 -288.36239)
		(end 374.77192 -288.343594)
		(width 0.1143)
		(layer "In11.Cu")
		(net "P5E_CPU0_P3_TX_DP<15>")
	)
	(arc
		(start 374.8024 -280.870914)
		(mid 374.917827 -280.737538)
		(end 374.959372 -280.566114)
		(width 0.1143)
		(layer "In11.Cu")
		(net "P5E_CPU0_P3_TX_DP<15>")
	)
	(arc
		(start 374.732804 -291.560504)
		(mid 374.489477 -291.095938)
		(end 374.732804 -290.631372)
		(width 0.1143)
		(layer "In11.Cu")
		(net "P5E_CPU0_P3_TX_DP<15>")
	)
	(arc
		(start 396.85722 -380.237746)
		(mid 396.962963 -379.889239)
		(end 396.998698 -379.5268)
		(width 0.14224)
		(layer "In11.Cu")
		(net "P5E_CPU0_P3_TX_DP<15>")
	)
	(arc
		(start 374.732804 -293.180516)
		(mid 374.489477 -292.71595)
		(end 374.732804 -292.251384)
		(width 0.1143)
		(layer "In11.Cu")
		(net "P5E_CPU0_P3_TX_DP<15>")
	)
	(arc
		(start 374.732804 -294.800528)
		(mid 374.489477 -294.335962)
		(end 374.732804 -293.871396)
		(width 0.1143)
		(layer "In11.Cu")
		(net "P5E_CPU0_P3_TX_DP<15>")
	)
	(arc
		(start 374.019572 -277.32609)
		(mid 373.977693 -277.154221)
		(end 373.861584 -277.020782)
		(width 0.1143)
		(layer "In11.Cu")
		(net "P5E_CPU0_P3_TX_DP<15>")
	)
	(arc
		(start 374.959372 -287.045908)
		(mid 374.918406 -286.875502)
		(end 374.804432 -286.742378)
		(width 0.1143)
		(layer "In11.Cu")
		(net "P5E_CPU0_P3_TX_DP<15>")
	)
	(arc
		(start 374.251474 -277.782782)
		(mid 374.080823 -277.583917)
		(end 374.019572 -277.329138)
		(width 0.1143)
		(layer "In11.Cu")
		(net "P5E_CPU0_P3_TX_DP<15>")
	)
	(arc
		(start 374.732804 -283.460698)
		(mid 374.489477 -282.996132)
		(end 374.732804 -282.531566)
		(width 0.1143)
		(layer "In11.Cu")
		(net "P5E_CPU0_P3_TX_DP<15>")
	)
	(arc
		(start 374.8024 -287.350708)
		(mid 374.917827 -287.217332)
		(end 374.959372 -287.045908)
		(width 0.1143)
		(layer "In11.Cu")
		(net "P5E_CPU0_P3_TX_DP<15>")
	)
	(arc
		(start 374.8024 -293.830756)
		(mid 374.959377 -293.525956)
		(end 374.8024 -293.221156)
		(width 0.1143)
		(layer "In11.Cu")
		(net "P5E_CPU0_P3_TX_DP<15>")
	)
	(arc
		(start 374.959372 -295.145968)
		(mid 374.917823 -294.974546)
		(end 374.8024 -294.841168)
		(width 0.1143)
		(layer "In11.Cu")
		(net "P5E_CPU0_P3_TX_DP<15>")
	)
	(arc
		(start 375.27357 -280.0604)
		(mid 375.429498 -279.756108)
		(end 375.27357 -279.451816)
		(width 0.1143)
		(layer "In11.Cu")
		(net "P5E_CPU0_P3_TX_DP<15>")
	)
	(arc
		(start 373.79275 -276.98065)
		(mid 373.640763 -276.824142)
		(end 373.559324 -276.621748)
		(width 0.1143)
		(layer "In11.Cu")
		(net "P5E_CPU0_P3_TX_DP<15>")
	)
	(arc
		(start 374.732804 -289.940492)
		(mid 374.489477 -289.475926)
		(end 374.732804 -289.01136)
		(width 0.1143)
		(layer "In11.Cu")
		(net "P5E_CPU0_P3_TX_DP<15>")
	)
	(arc
		(start 374.8024 -292.210744)
		(mid 374.959377 -291.905944)
		(end 374.8024 -291.601144)
		(width 0.1143)
		(layer "In11.Cu")
		(net "P5E_CPU0_P3_TX_DP<15>")
	)
	(arc
		(start 374.8024 -282.490926)
		(mid 374.959377 -282.186126)
		(end 374.8024 -281.881326)
		(width 0.1143)
		(layer "In11.Cu")
		(net "P5E_CPU0_P3_TX_DP<15>")
	)
	(arc
		(start 374.732804 -285.08071)
		(mid 374.489477 -284.616144)
		(end 374.732804 -284.151578)
		(width 0.1143)
		(layer "In11.Cu")
		(net "P5E_CPU0_P3_TX_DP<15>")
	)
	(arc
		(start 374.489472 -287.856168)
		(mid 374.554708 -287.592577)
		(end 374.735344 -287.389824)
		(width 0.1143)
		(layer "In11.Cu")
		(net "P5E_CPU0_P3_TX_DP<15>")
	)
	(arc
		(start 395.416024 -388.169658)
		(mid 395.464708 -388.159956)
		(end 395.50594 -388.13232)
		(width 0.14224)
		(layer "In11.Cu")
		(net "P5E_CPU0_P3_TX_DP<15>")
	)
	(arc
		(start 374.732804 -288.320734)
		(mid 374.553991 -288.118384)
		(end 374.489472 -287.856168)
		(width 0.1143)
		(layer "In11.Cu")
		(net "P5E_CPU0_P3_TX_DP<15>")
	)
	(arc
		(start 374.489472 -278.136096)
		(mid 374.448217 -277.965125)
		(end 374.333516 -277.831804)
		(width 0.1143)
		(layer "In11.Cu")
		(net "P5E_CPU0_P3_TX_DP<15>")
	)
	(arc
		(start 374.732804 -286.700722)
		(mid 374.489477 -286.236156)
		(end 374.732804 -285.77159)
		(width 0.1143)
		(layer "In11.Cu")
		(net "P5E_CPU0_P3_TX_DP<15>")
	)
	(arc
		(start 395.595602 -383.963926)
		(mid 395.66113 -383.298368)
		(end 395.85519 -382.658366)
		(width 0.14224)
		(layer "In11.Cu")
		(net "P5E_CPU0_P3_TX_DP<15>")
	)
	(arc
		(start 374.732804 -278.600662)
		(mid 374.553991 -278.398312)
		(end 374.489472 -278.136096)
		(width 0.1143)
		(layer "In11.Cu")
		(net "P5E_CPU0_P3_TX_DP<15>")
	)
	(arc
		(start 374.959372 -280.566114)
		(mid 375.023887 -280.303895)
		(end 375.202704 -280.101548)
		(width 0.1143)
		(layer "In11.Cu")
		(net "P5E_CPU0_P3_TX_DP<15>")
	)
	(arc
		(start 374.8024 -290.590732)
		(mid 374.959377 -290.285932)
		(end 374.8024 -289.981132)
		(width 0.1143)
		(layer "In11.Cu")
		(net "P5E_CPU0_P3_TX_DP<15>")
	)
	(arc
		(start 374.959372 -278.946102)
		(mid 374.917823 -278.77468)
		(end 374.8024 -278.641302)
		(width 0.1143)
		(layer "In11.Cu")
		(net "P5E_CPU0_P3_TX_DP<15>")
	)
	(arc
		(start 374.8024 -285.73095)
		(mid 374.959377 -285.42615)
		(end 374.8024 -285.12135)
		(width 0.1143)
		(layer "In11.Cu")
		(net "P5E_CPU0_P3_TX_DP<15>")
	)
	(arc
		(start 395.558264 -388.079996)
		(mid 395.585883 -388.038756)
		(end 395.595602 -387.99008)
		(width 0.14224)
		(layer "In11.Cu")
		(net "P5E_CPU0_P3_TX_DP<15>")
	)
	(arc
		(start 375.202704 -279.410668)
		(mid 375.023891 -279.208318)
		(end 374.959372 -278.946102)
		(width 0.1143)
		(layer "In11.Cu")
		(net "P5E_CPU0_P3_TX_DP<15>")
	)
	(arc
		(start 375.713752 -296.635424)
		(mid 375.615577 -296.141392)
		(end 375.3358 -295.722548)
		(width 0.1143)
		(layer "In11.Cu")
		(net "P5E_CPU0_P3_TX_DP<15>")
	)
	(arc
		(start 374.8024 -284.110938)
		(mid 374.959377 -283.806138)
		(end 374.8024 -283.501338)
		(width 0.1143)
		(layer "In11.Cu")
		(net "P5E_CPU0_P3_TX_DP<15>")
	)
	(arc
		(start 375.202704 -295.610534)
		(mid 375.023891 -295.408184)
		(end 374.959372 -295.145968)
		(width 0.1143)
		(layer "In11.Cu")
		(net "P5E_CPU0_P3_TX_DP<15>")
	)
	(arc
		(start 374.8024 -288.97072)
		(mid 374.917827 -288.837344)
		(end 374.959372 -288.66592)
		(width 0.1143)
		(layer "In11.Cu")
		(net "P5E_CPU0_P3_TX_DP<15>")
	)
	(arc
		(start 374.732804 -281.840686)
		(mid 374.489477 -281.37612)
		(end 374.732804 -280.911554)
		(width 0.1143)
		(layer "In11.Cu")
		(net "P5E_CPU0_P3_TX_DP<15>")
	)
	(arc
		(start 373.559324 -276.621748)
		(mid 373.557301 -276.610338)
		(end 373.555514 -276.598888)
		(width 0.1143)
		(layer "In11.Cu")
		(net "P5E_CPU0_P3_TX_DP<15>")
	)
	(arc
		(start 374.959372 -288.66592)
		(mid 374.918406 -288.495514)
		(end 374.804432 -288.36239)
		(width 0.1143)
		(layer "In11.Cu")
		(net "P5E_CPU0_P3_TX_DP<15>")
	)
	(segment
		(start 394.377672 -385.338828)
		(end 394.107162 -385.068318)
		(width 0.12954)
		(layer "F.Cu")
		(net "P5E_CPU0_P3_TX_DP<14>")
	)
	(segment
		(start 394.107162 -385.068318)
		(end 393.403582 -385.068318)
		(width 0.12954)
		(layer "F.Cu")
		(net "P5E_CPU0_P3_TX_DP<14>")
	)
	(segment
		(start 372.707916 -277.870158)
		(end 373.174768 -278.136096)
		(width 0.12954)
		(layer "F.Cu")
		(net "P5E_CPU0_P3_TX_DP<14>")
	)
	(segment
		(start 393.403582 -385.068318)
		(end 393.107672 -385.364228)
		(width 0.12954)
		(layer "F.Cu")
		(net "P5E_CPU0_P3_TX_DP<14>")
	)
	(segment
		(start 373.79275 -288.320734)
		(end 373.798846 -288.32429)
		(width 0.1143)
		(layer "In11.Cu")
		(net "P5E_CPU0_P3_TX_DP<14>")
	)
	(segment
		(start 373.83085 -280.889202)
		(end 373.79275 -280.911554)
		(width 0.1143)
		(layer "In11.Cu")
		(net "P5E_CPU0_P3_TX_DP<14>")
	)
	(segment
		(start 373.79275 -278.600662)
		(end 373.799608 -278.604726)
		(width 0.1143)
		(layer "In11.Cu")
		(net "P5E_CPU0_P3_TX_DP<14>")
	)
	(segment
		(start 373.867426 -287.347406)
		(end 373.863616 -287.3502)
		(width 0.1143)
		(layer "In11.Cu")
		(net "P5E_CPU0_P3_TX_DP<14>")
	)
	(segment
		(start 373.83466 -283.485336)
		(end 373.835168 -283.485336)
		(width 0.1143)
		(layer "In11.Cu")
		(net "P5E_CPU0_P3_TX_DP<14>")
	)
	(segment
		(start 374.032272 -278.953468)
		(end 374.032272 -278.965914)
		(width 0.1143)
		(layer "In11.Cu")
		(net "P5E_CPU0_P3_TX_DP<14>")
	)
	(segment
		(start 373.832628 -293.203884)
		(end 373.83466 -293.205154)
		(width 0.1143)
		(layer "In11.Cu")
		(net "P5E_CPU0_P3_TX_DP<14>")
	)
	(segment
		(start 374.723152 -297.020742)
		(end 374.882156 -297.544744)
		(width 0.14224)
		(layer "In11.Cu")
		(net "P5E_CPU0_P3_TX_DP<14>")
	)
	(segment
		(start 373.831866 -293.848536)
		(end 373.83085 -293.849044)
		(width 0.1143)
		(layer "In11.Cu")
		(net "P5E_CPU0_P3_TX_DP<14>")
	)
	(segment
		(start 374.489726 -295.955974)
		(end 374.489726 -296.127678)
		(width 0.1143)
		(layer "In11.Cu")
		(net "P5E_CPU0_P3_TX_DP<14>")
	)
	(segment
		(start 373.79275 -293.180516)
		(end 373.83085 -293.202868)
		(width 0.1143)
		(layer "In11.Cu")
		(net "P5E_CPU0_P3_TX_DP<14>")
	)
	(segment
		(start 373.832628 -289.96386)
		(end 373.83466 -289.96513)
		(width 0.1143)
		(layer "In11.Cu")
		(net "P5E_CPU0_P3_TX_DP<14>")
	)
	(segment
		(start 373.834914 -284.12694)
		(end 373.832628 -284.128464)
		(width 0.1143)
		(layer "In11.Cu")
		(net "P5E_CPU0_P3_TX_DP<14>")
	)
	(segment
		(start 373.832628 -278.623776)
		(end 373.833644 -278.624284)
		(width 0.1143)
		(layer "In11.Cu")
		(net "P5E_CPU0_P3_TX_DP<14>")
	)
	(segment
		(start 373.83085 -282.509214)
		(end 373.79275 -282.531566)
		(width 0.1143)
		(layer "In11.Cu")
		(net "P5E_CPU0_P3_TX_DP<14>")
	)
	(segment
		(start 393.513564 -385.047998)
		(end 394.086842 -385.047998)
		(width 0.14224)
		(layer "In11.Cu")
		(net "P5E_CPU0_P3_TX_DP<14>")
	)
	(segment
		(start 374.723152 -296.837862)
		(end 374.723152 -296.86631)
		(width 0.1143)
		(layer "In11.Cu")
		(net "P5E_CPU0_P3_TX_DP<14>")
	)
	(segment
		(start 373.83085 -291.582856)
		(end 373.831866 -291.583364)
		(width 0.1143)
		(layer "In11.Cu")
		(net "P5E_CPU0_P3_TX_DP<14>")
	)
	(segment
		(start 373.835422 -288.986722)
		(end 373.834914 -288.986722)
		(width 0.1143)
		(layer "In11.Cu")
		(net "P5E_CPU0_P3_TX_DP<14>")
	)
	(segment
		(start 373.834914 -290.606734)
		(end 373.832628 -290.608258)
		(width 0.1143)
		(layer "In11.Cu")
		(net "P5E_CPU0_P3_TX_DP<14>")
	)
	(segment
		(start 373.863616 -291.601652)
		(end 373.868696 -291.605208)
		(width 0.1143)
		(layer "In11.Cu")
		(net "P5E_CPU0_P3_TX_DP<14>")
	)
	(segment
		(start 373.799608 -283.464762)
		(end 373.80037 -283.46527)
		(width 0.1143)
		(layer "In11.Cu")
		(net "P5E_CPU0_P3_TX_DP<14>")
	)
	(segment
		(start 373.831866 -291.583364)
		(end 373.832628 -291.583872)
		(width 0.1143)
		(layer "In11.Cu")
		(net "P5E_CPU0_P3_TX_DP<14>")
	)
	(segment
		(start 373.826278 -292.231826)
		(end 373.79275 -292.251384)
		(width 0.1143)
		(layer "In11.Cu")
		(net "P5E_CPU0_P3_TX_DP<14>")
	)
	(segment
		(start 373.83085 -294.82288)
		(end 373.834406 -294.824658)
		(width 0.1143)
		(layer "In11.Cu")
		(net "P5E_CPU0_P3_TX_DP<14>")
	)
	(segment
		(start 374.601232 -296.396664)
		(end 374.768872 -296.564304)
		(width 0.1143)
		(layer "In11.Cu")
		(net "P5E_CPU0_P3_TX_DP<14>")
	)
	(segment
		(start 373.83085 -289.962844)
		(end 373.831866 -289.963352)
		(width 0.1143)
		(layer "In11.Cu")
		(net "P5E_CPU0_P3_TX_DP<14>")
	)
	(segment
		(start 388.839202 -316.456568)
		(end 391.221722 -322.204588)
		(width 0.14224)
		(layer "In11.Cu")
		(net "P5E_CPU0_P3_TX_DP<14>")
	)
	(segment
		(start 374.333516 -280.0604)
		(end 374.288812 -280.086308)
		(width 0.1143)
		(layer "In11.Cu")
		(net "P5E_CPU0_P3_TX_DP<14>")
	)
	(segment
		(start 373.79275 -289.940492)
		(end 373.83085 -289.962844)
		(width 0.1143)
		(layer "In11.Cu")
		(net "P5E_CPU0_P3_TX_DP<14>")
	)
	(segment
		(start 373.83085 -285.103062)
		(end 373.831866 -285.10357)
		(width 0.1143)
		(layer "In11.Cu")
		(net "P5E_CPU0_P3_TX_DP<14>")
	)
	(segment
		(start 394.771118 -355.632512)
		(end 395.53642 -371.208554)
		(width 0.14224)
		(layer "In11.Cu")
		(net "P5E_CPU0_P3_TX_DP<14>")
	)
	(segment
		(start 373.83085 -292.229032)
		(end 373.828818 -292.230302)
		(width 0.1143)
		(layer "In11.Cu")
		(net "P5E_CPU0_P3_TX_DP<14>")
	)
	(segment
		(start 373.79275 -281.840686)
		(end 373.83085 -281.863038)
		(width 0.1143)
		(layer "In11.Cu")
		(net "P5E_CPU0_P3_TX_DP<14>")
	)
	(segment
		(start 373.831866 -282.508706)
		(end 373.83085 -282.509214)
		(width 0.1143)
		(layer "In11.Cu")
		(net "P5E_CPU0_P3_TX_DP<14>")
	)
	(segment
		(start 392.935968 -383.864358)
		(end 392.935968 -384.473704)
		(width 0.14224)
		(layer "In11.Cu")
		(net "P5E_CPU0_P3_TX_DP<14>")
	)
	(segment
		(start 374.882156 -297.544744)
		(end 375.56313 -298.563538)
		(width 0.14224)
		(layer "In11.Cu")
		(net "P5E_CPU0_P3_TX_DP<14>")
	)
	(segment
		(start 373.831866 -284.128718)
		(end 373.83085 -284.129226)
		(width 0.1143)
		(layer "In11.Cu")
		(net "P5E_CPU0_P3_TX_DP<14>")
	)
	(segment
		(start 373.827294 -292.231318)
		(end 373.826278 -292.231826)
		(width 0.1143)
		(layer "In11.Cu")
		(net "P5E_CPU0_P3_TX_DP<14>")
	)
	(segment
		(start 373.828818 -292.230302)
		(end 373.827294 -292.231318)
		(width 0.1143)
		(layer "In11.Cu")
		(net "P5E_CPU0_P3_TX_DP<14>")
	)
	(segment
		(start 394.771118 -340.048596)
		(end 394.771118 -355.632512)
		(width 0.14224)
		(layer "In11.Cu")
		(net "P5E_CPU0_P3_TX_DP<14>")
	)
	(segment
		(start 373.798846 -288.32429)
		(end 373.7991 -288.32429)
		(width 0.1143)
		(layer "In11.Cu")
		(net "P5E_CPU0_P3_TX_DP<14>")
	)
	(segment
		(start 374.30202 -279.433528)
		(end 374.333516 -279.45207)
		(width 0.1143)
		(layer "In11.Cu")
		(net "P5E_CPU0_P3_TX_DP<14>")
	)
	(segment
		(start 373.834914 -288.986722)
		(end 373.832628 -288.988246)
		(width 0.1143)
		(layer "In11.Cu")
		(net "P5E_CPU0_P3_TX_DP<14>")
	)
	(segment
		(start 374.019572 -287.045908)
		(end 374.019572 -287.05048)
		(width 0.1143)
		(layer "In11.Cu")
		(net "P5E_CPU0_P3_TX_DP<14>")
	)
	(segment
		(start 373.832628 -292.228016)
		(end 373.831866 -292.228524)
		(width 0.1143)
		(layer "In11.Cu")
		(net "P5E_CPU0_P3_TX_DP<14>")
	)
	(segment
		(start 373.834914 -285.746952)
		(end 373.832628 -285.748476)
		(width 0.1143)
		(layer "In11.Cu")
		(net "P5E_CPU0_P3_TX_DP<14>")
	)
	(segment
		(start 373.832628 -280.888186)
		(end 373.831866 -280.888694)
		(width 0.1143)
		(layer "In11.Cu")
		(net "P5E_CPU0_P3_TX_DP<14>")
	)
	(segment
		(start 373.174768 -278.136096)
		(end 373.47271 -278.136096)
		(width 0.1143)
		(layer "In11.Cu")
		(net "P5E_CPU0_P3_TX_DP<14>")
	)
	(segment
		(start 373.83085 -293.849044)
		(end 373.79275 -293.871396)
		(width 0.1143)
		(layer "In11.Cu")
		(net "P5E_CPU0_P3_TX_DP<14>")
	)
	(segment
		(start 373.832628 -290.608258)
		(end 373.831866 -290.608512)
		(width 0.1143)
		(layer "In11.Cu")
		(net "P5E_CPU0_P3_TX_DP<14>")
	)
	(segment
		(start 373.832628 -285.748476)
		(end 373.831866 -285.74873)
		(width 0.1143)
		(layer "In11.Cu")
		(net "P5E_CPU0_P3_TX_DP<14>")
	)
	(segment
		(start 373.83085 -284.129226)
		(end 373.79275 -284.151578)
		(width 0.1143)
		(layer "In11.Cu")
		(net "P5E_CPU0_P3_TX_DP<14>")
	)
	(segment
		(start 373.831866 -280.888694)
		(end 373.83085 -280.889202)
		(width 0.1143)
		(layer "In11.Cu")
		(net "P5E_CPU0_P3_TX_DP<14>")
	)
	(segment
		(start 373.831866 -293.203376)
		(end 373.832628 -293.203884)
		(width 0.1143)
		(layer "In11.Cu")
		(net "P5E_CPU0_P3_TX_DP<14>")
	)
	(segment
		(start 382.669542 -307.22316)
		(end 388.839202 -316.456568)
		(width 0.14224)
		(layer "In11.Cu")
		(net "P5E_CPU0_P3_TX_DP<14>")
	)
	(segment
		(start 373.83466 -281.865324)
		(end 373.835168 -281.865324)
		(width 0.1143)
		(layer "In11.Cu")
		(net "P5E_CPU0_P3_TX_DP<14>")
	)
	(segment
		(start 373.831866 -290.608512)
		(end 373.83085 -290.60902)
		(width 0.1143)
		(layer "In11.Cu")
		(net "P5E_CPU0_P3_TX_DP<14>")
	)
	(segment
		(start 373.832628 -291.583872)
		(end 373.863616 -291.601652)
		(width 0.1143)
		(layer "In11.Cu")
		(net "P5E_CPU0_P3_TX_DP<14>")
	)
	(segment
		(start 373.832628 -278.62403)
		(end 373.832628 -278.623776)
		(width 0.1143)
		(layer "In11.Cu")
		(net "P5E_CPU0_P3_TX_DP<14>")
	)
	(segment
		(start 373.832628 -293.848282)
		(end 373.831866 -293.848536)
		(width 0.1143)
		(layer "In11.Cu")
		(net "P5E_CPU0_P3_TX_DP<14>")
	)
	(segment
		(start 393.065762 -384.78714)
		(end 393.19454 -384.915918)
		(width 0.14224)
		(layer "In11.Cu")
		(net "P5E_CPU0_P3_TX_DP<14>")
	)
	(segment
		(start 373.832628 -284.128464)
		(end 373.831866 -284.128718)
		(width 0.1143)
		(layer "In11.Cu")
		(net "P5E_CPU0_P3_TX_DP<14>")
	)
	(segment
		(start 373.834914 -293.846758)
		(end 373.832628 -293.848282)
		(width 0.1143)
		(layer "In11.Cu")
		(net "P5E_CPU0_P3_TX_DP<14>")
	)
	(segment
		(start 373.835422 -284.12694)
		(end 373.834914 -284.12694)
		(width 0.1143)
		(layer "In11.Cu")
		(net "P5E_CPU0_P3_TX_DP<14>")
	)
	(segment
		(start 373.83466 -289.96513)
		(end 373.835168 -289.96513)
		(width 0.1143)
		(layer "In11.Cu")
		(net "P5E_CPU0_P3_TX_DP<14>")
	)
	(segment
		(start 373.835422 -285.746952)
		(end 373.834914 -285.746952)
		(width 0.1143)
		(layer "In11.Cu")
		(net "P5E_CPU0_P3_TX_DP<14>")
	)
	(segment
		(start 373.831866 -285.74873)
		(end 373.83085 -285.749238)
		(width 0.1143)
		(layer "In11.Cu")
		(net "P5E_CPU0_P3_TX_DP<14>")
	)
	(segment
		(start 373.83085 -290.60902)
		(end 373.79275 -290.631372)
		(width 0.1143)
		(layer "In11.Cu")
		(net "P5E_CPU0_P3_TX_DP<14>")
	)
	(segment
		(start 374.007634 -280.574496)
		(end 374.007634 -280.585926)
		(width 0.1143)
		(layer "In11.Cu")
		(net "P5E_CPU0_P3_TX_DP<14>")
	)
	(segment
		(start 391.221722 -322.204588)
		(end 394.771118 -340.048596)
		(width 0.14224)
		(layer "In11.Cu")
		(net "P5E_CPU0_P3_TX_DP<14>")
	)
	(segment
		(start 373.83085 -285.749238)
		(end 373.79275 -285.77159)
		(width 0.1143)
		(layer "In11.Cu")
		(net "P5E_CPU0_P3_TX_DP<14>")
	)
	(segment
		(start 373.832628 -285.104078)
		(end 373.83466 -285.105348)
		(width 0.1143)
		(layer "In11.Cu")
		(net "P5E_CPU0_P3_TX_DP<14>")
	)
	(segment
		(start 373.831866 -289.963352)
		(end 373.832628 -289.96386)
		(width 0.1143)
		(layer "In11.Cu")
		(net "P5E_CPU0_P3_TX_DP<14>")
	)
	(segment
		(start 373.868696 -292.20668)
		(end 373.863616 -292.210236)
		(width 0.1143)
		(layer "In11.Cu")
		(net "P5E_CPU0_P3_TX_DP<14>")
	)
	(segment
		(start 373.835422 -282.506928)
		(end 373.834914 -282.506928)
		(width 0.1143)
		(layer "In11.Cu")
		(net "P5E_CPU0_P3_TX_DP<14>")
	)
	(segment
		(start 373.834406 -294.824658)
		(end 373.864632 -294.842692)
		(width 0.1143)
		(layer "In11.Cu")
		(net "P5E_CPU0_P3_TX_DP<14>")
	)
	(segment
		(start 373.80037 -283.46527)
		(end 373.831866 -283.483558)
		(width 0.1143)
		(layer "In11.Cu")
		(net "P5E_CPU0_P3_TX_DP<14>")
	)
	(segment
		(start 373.832628 -283.484066)
		(end 373.83466 -283.485336)
		(width 0.1143)
		(layer "In11.Cu")
		(net "P5E_CPU0_P3_TX_DP<14>")
	)
	(segment
		(start 373.79275 -286.700722)
		(end 373.865394 -286.74314)
		(width 0.1143)
		(layer "In11.Cu")
		(net "P5E_CPU0_P3_TX_DP<14>")
	)
	(segment
		(start 373.83085 -281.863038)
		(end 373.831866 -281.863546)
		(width 0.1143)
		(layer "In11.Cu")
		(net "P5E_CPU0_P3_TX_DP<14>")
	)
	(segment
		(start 373.80037 -278.605234)
		(end 373.831866 -278.623522)
		(width 0.1143)
		(layer "In11.Cu")
		(net "P5E_CPU0_P3_TX_DP<14>")
	)
	(segment
		(start 373.833644 -278.624284)
		(end 373.84736 -278.632158)
		(width 0.1143)
		(layer "In11.Cu")
		(net "P5E_CPU0_P3_TX_DP<14>")
	)
	(segment
		(start 373.831866 -288.9885)
		(end 373.83085 -288.989008)
		(width 0.1143)
		(layer "In11.Cu")
		(net "P5E_CPU0_P3_TX_DP<14>")
	)
	(segment
		(start 394.086842 -385.047998)
		(end 394.377672 -385.338828)
		(width 0.14224)
		(layer "In11.Cu")
		(net "P5E_CPU0_P3_TX_DP<14>")
	)
	(segment
		(start 373.834914 -288.345118)
		(end 373.835168 -288.345118)
		(width 0.1143)
		(layer "In11.Cu")
		(net "P5E_CPU0_P3_TX_DP<14>")
	)
	(segment
		(start 373.863616 -287.3502)
		(end 373.79529 -287.389824)
		(width 0.1143)
		(layer "In11.Cu")
		(net "P5E_CPU0_P3_TX_DP<14>")
	)
	(segment
		(start 373.832628 -282.508452)
		(end 373.831866 -282.508706)
		(width 0.1143)
		(layer "In11.Cu")
		(net "P5E_CPU0_P3_TX_DP<14>")
	)
	(segment
		(start 373.834914 -282.506928)
		(end 373.832628 -282.508452)
		(width 0.1143)
		(layer "In11.Cu")
		(net "P5E_CPU0_P3_TX_DP<14>")
	)
	(segment
		(start 373.831866 -292.228524)
		(end 373.83085 -292.229032)
		(width 0.1143)
		(layer "In11.Cu")
		(net "P5E_CPU0_P3_TX_DP<14>")
	)
	(segment
		(start 373.831866 -281.863546)
		(end 373.832628 -281.864054)
		(width 0.1143)
		(layer "In11.Cu")
		(net "P5E_CPU0_P3_TX_DP<14>")
	)
	(segment
		(start 373.799608 -278.604726)
		(end 373.80037 -278.605234)
		(width 0.1143)
		(layer "In11.Cu")
		(net "P5E_CPU0_P3_TX_DP<14>")
	)
	(segment
		(start 373.79275 -285.08071)
		(end 373.83085 -285.103062)
		(width 0.1143)
		(layer "In11.Cu")
		(net "P5E_CPU0_P3_TX_DP<14>")
	)
	(segment
		(start 374.303798 -295.63441)
		(end 374.333516 -295.651682)
		(width 0.1143)
		(layer "In11.Cu")
		(net "P5E_CPU0_P3_TX_DP<14>")
	)
	(segment
		(start 374.768872 -296.792142)
		(end 374.723152 -296.837862)
		(width 0.1143)
		(layer "In11.Cu")
		(net "P5E_CPU0_P3_TX_DP<14>")
	)
	(segment
		(start 373.832628 -281.864054)
		(end 373.83466 -281.865324)
		(width 0.1143)
		(layer "In11.Cu")
		(net "P5E_CPU0_P3_TX_DP<14>")
	)
	(segment
		(start 374.768872 -296.564304)
		(end 374.768872 -296.792142)
		(width 0.1143)
		(layer "In11.Cu")
		(net "P5E_CPU0_P3_TX_DP<14>")
	)
	(segment
		(start 373.83085 -293.202868)
		(end 373.831866 -293.203376)
		(width 0.1143)
		(layer "In11.Cu")
		(net "P5E_CPU0_P3_TX_DP<14>")
	)
	(segment
		(start 375.56313 -298.563538)
		(end 382.669542 -307.22316)
		(width 0.14224)
		(layer "In11.Cu")
		(net "P5E_CPU0_P3_TX_DP<14>")
	)
	(segment
		(start 373.83466 -285.105348)
		(end 373.835168 -285.105348)
		(width 0.1143)
		(layer "In11.Cu")
		(net "P5E_CPU0_P3_TX_DP<14>")
	)
	(segment
		(start 374.401334 -295.714674)
		(end 374.401588 -295.714928)
		(width 0.1143)
		(layer "In11.Cu")
		(net "P5E_CPU0_P3_TX_DP<14>")
	)
	(segment
		(start 373.47271 -278.136096)
		(end 373.555514 -278.2189)
		(width 0.1143)
		(layer "In11.Cu")
		(net "P5E_CPU0_P3_TX_DP<14>")
	)
	(segment
		(start 373.832628 -288.988246)
		(end 373.831866 -288.9885)
		(width 0.1143)
		(layer "In11.Cu")
		(net "P5E_CPU0_P3_TX_DP<14>")
	)
	(segment
		(start 373.831866 -285.10357)
		(end 373.832628 -285.104078)
		(width 0.1143)
		(layer "In11.Cu")
		(net "P5E_CPU0_P3_TX_DP<14>")
	)
	(segment
		(start 373.83085 -288.989008)
		(end 373.79275 -289.01136)
		(width 0.1143)
		(layer "In11.Cu")
		(net "P5E_CPU0_P3_TX_DP<14>")
	)
	(segment
		(start 373.863616 -292.210236)
		(end 373.832628 -292.228016)
		(width 0.1143)
		(layer "In11.Cu")
		(net "P5E_CPU0_P3_TX_DP<14>")
	)
	(segment
		(start 373.79275 -291.560504)
		(end 373.83085 -291.582856)
		(width 0.1143)
		(layer "In11.Cu")
		(net "P5E_CPU0_P3_TX_DP<14>")
	)
	(segment
		(start 373.83466 -293.205154)
		(end 373.835168 -293.205154)
		(width 0.1143)
		(layer "In11.Cu")
		(net "P5E_CPU0_P3_TX_DP<14>")
	)
	(segment
		(start 394.39596 -382.123188)
		(end 393.134342 -383.384552)
		(width 0.14224)
		(layer "In11.Cu")
		(net "P5E_CPU0_P3_TX_DP<14>")
	)
	(segment
		(start 395.53642 -371.208554)
		(end 395.53642 -379.203966)
		(width 0.14224)
		(layer "In11.Cu")
		(net "P5E_CPU0_P3_TX_DP<14>")
	)
	(segment
		(start 395.53642 -379.203966)
		(end 395.536928 -379.347476)
		(width 0.14224)
		(layer "In11.Cu")
		(net "P5E_CPU0_P3_TX_DP<14>")
	)
	(segment
		(start 373.79275 -294.800528)
		(end 373.83085 -294.82288)
		(width 0.1143)
		(layer "In11.Cu")
		(net "P5E_CPU0_P3_TX_DP<14>")
	)
	(segment
		(start 373.831866 -278.623522)
		(end 373.832628 -278.62403)
		(width 0.1143)
		(layer "In11.Cu")
		(net "P5E_CPU0_P3_TX_DP<14>")
	)
	(segment
		(start 373.79275 -283.460698)
		(end 373.799608 -283.464762)
		(width 0.1143)
		(layer "In11.Cu")
		(net "P5E_CPU0_P3_TX_DP<14>")
	)
	(segment
		(start 373.7991 -288.32429)
		(end 373.834914 -288.345118)
		(width 0.1143)
		(layer "In11.Cu")
		(net "P5E_CPU0_P3_TX_DP<14>")
	)
	(segment
		(start 373.835422 -293.846758)
		(end 373.834914 -293.846758)
		(width 0.1143)
		(layer "In11.Cu")
		(net "P5E_CPU0_P3_TX_DP<14>")
	)
	(segment
		(start 373.831866 -283.483558)
		(end 373.832628 -283.484066)
		(width 0.1143)
		(layer "In11.Cu")
		(net "P5E_CPU0_P3_TX_DP<14>")
	)
	(segment
		(start 374.723152 -296.86631)
		(end 374.723152 -297.020742)
		(width 0.14224)
		(layer "In11.Cu")
		(net "P5E_CPU0_P3_TX_DP<14>")
	)
	(segment
		(start 373.835422 -290.606734)
		(end 373.834914 -290.606734)
		(width 0.1143)
		(layer "In11.Cu")
		(net "P5E_CPU0_P3_TX_DP<14>")
	)
	(arc
		(start 373.835168 -288.345118)
		(mid 374.019901 -288.66581)
		(end 373.835422 -288.986722)
		(width 0.1143)
		(layer "In11.Cu")
		(net "P5E_CPU0_P3_TX_DP<14>")
	)
	(arc
		(start 374.288812 -280.086308)
		(mid 374.082953 -280.292809)
		(end 374.007634 -280.574496)
		(width 0.1143)
		(layer "In11.Cu")
		(net "P5E_CPU0_P3_TX_DP<14>")
	)
	(arc
		(start 374.019572 -295.14165)
		(mid 374.095726 -295.426072)
		(end 374.303798 -295.63441)
		(width 0.1143)
		(layer "In11.Cu")
		(net "P5E_CPU0_P3_TX_DP<14>")
	)
	(arc
		(start 392.935968 -384.473704)
		(mid 392.969707 -384.643321)
		(end 393.065762 -384.78714)
		(width 0.14224)
		(layer "In11.Cu")
		(net "P5E_CPU0_P3_TX_DP<14>")
	)
	(arc
		(start 373.79275 -285.77159)
		(mid 373.549423 -286.236156)
		(end 373.79275 -286.700722)
		(width 0.1143)
		(layer "In11.Cu")
		(net "P5E_CPU0_P3_TX_DP<14>")
	)
	(arc
		(start 373.79529 -287.389824)
		(mid 373.614638 -287.592569)
		(end 373.549418 -287.856168)
		(width 0.1143)
		(layer "In11.Cu")
		(net "P5E_CPU0_P3_TX_DP<14>")
	)
	(arc
		(start 374.333516 -279.45207)
		(mid 374.415497 -279.53272)
		(end 374.469152 -279.634442)
		(width 0.1143)
		(layer "In11.Cu")
		(net "P5E_CPU0_P3_TX_DP<14>")
	)
	(arc
		(start 373.79275 -284.151578)
		(mid 373.549423 -284.616144)
		(end 373.79275 -285.08071)
		(width 0.1143)
		(layer "In11.Cu")
		(net "P5E_CPU0_P3_TX_DP<14>")
	)
	(arc
		(start 373.79275 -289.01136)
		(mid 373.549423 -289.475926)
		(end 373.79275 -289.940492)
		(width 0.1143)
		(layer "In11.Cu")
		(net "P5E_CPU0_P3_TX_DP<14>")
	)
	(arc
		(start 373.79275 -282.531566)
		(mid 373.549423 -282.996132)
		(end 373.79275 -283.460698)
		(width 0.1143)
		(layer "In11.Cu")
		(net "P5E_CPU0_P3_TX_DP<14>")
	)
	(arc
		(start 373.559324 -278.24176)
		(mid 373.640757 -278.444158)
		(end 373.79275 -278.600662)
		(width 0.1143)
		(layer "In11.Cu")
		(net "P5E_CPU0_P3_TX_DP<14>")
	)
	(arc
		(start 373.549418 -287.856168)
		(mid 373.613933 -288.118387)
		(end 373.79275 -288.320734)
		(width 0.1143)
		(layer "In11.Cu")
		(net "P5E_CPU0_P3_TX_DP<14>")
	)
	(arc
		(start 374.007634 -280.585926)
		(mid 373.960723 -280.760555)
		(end 373.832628 -280.888186)
		(width 0.1143)
		(layer "In11.Cu")
		(net "P5E_CPU0_P3_TX_DP<14>")
	)
	(arc
		(start 373.835168 -293.205154)
		(mid 374.019901 -293.525846)
		(end 373.835422 -293.846758)
		(width 0.1143)
		(layer "In11.Cu")
		(net "P5E_CPU0_P3_TX_DP<14>")
	)
	(arc
		(start 373.84736 -278.632158)
		(mid 373.982748 -278.768107)
		(end 374.032272 -278.953468)
		(width 0.1143)
		(layer "In11.Cu")
		(net "P5E_CPU0_P3_TX_DP<14>")
	)
	(arc
		(start 373.835168 -289.96513)
		(mid 374.019901 -290.285822)
		(end 373.835422 -290.606734)
		(width 0.1143)
		(layer "In11.Cu")
		(net "P5E_CPU0_P3_TX_DP<14>")
	)
	(arc
		(start 395.536928 -379.347476)
		(mid 395.244413 -380.849591)
		(end 394.39596 -382.123188)
		(width 0.14224)
		(layer "In11.Cu")
		(net "P5E_CPU0_P3_TX_DP<14>")
	)
	(arc
		(start 374.469152 -279.634442)
		(mid 374.471773 -279.869851)
		(end 374.333516 -280.0604)
		(width 0.1143)
		(layer "In11.Cu")
		(net "P5E_CPU0_P3_TX_DP<14>")
	)
	(arc
		(start 373.865394 -286.74314)
		(mid 373.978801 -286.876029)
		(end 374.019572 -287.045908)
		(width 0.1143)
		(layer "In11.Cu")
		(net "P5E_CPU0_P3_TX_DP<14>")
	)
	(arc
		(start 373.555514 -278.2189)
		(mid 373.557302 -278.230349)
		(end 373.559324 -278.24176)
		(width 0.1143)
		(layer "In11.Cu")
		(net "P5E_CPU0_P3_TX_DP<14>")
	)
	(arc
		(start 374.019572 -287.05048)
		(mid 373.979317 -287.217293)
		(end 373.867426 -287.347406)
		(width 0.1143)
		(layer "In11.Cu")
		(net "P5E_CPU0_P3_TX_DP<14>")
	)
	(arc
		(start 373.79275 -290.631372)
		(mid 373.549423 -291.095938)
		(end 373.79275 -291.560504)
		(width 0.1143)
		(layer "In11.Cu")
		(net "P5E_CPU0_P3_TX_DP<14>")
	)
	(arc
		(start 373.864632 -294.842692)
		(mid 373.978515 -294.973306)
		(end 374.019572 -295.14165)
		(width 0.1143)
		(layer "In11.Cu")
		(net "P5E_CPU0_P3_TX_DP<14>")
	)
	(arc
		(start 373.79275 -280.911554)
		(mid 373.549423 -281.37612)
		(end 373.79275 -281.840686)
		(width 0.1143)
		(layer "In11.Cu")
		(net "P5E_CPU0_P3_TX_DP<14>")
	)
	(arc
		(start 393.19454 -384.915918)
		(mid 393.340924 -385.013665)
		(end 393.513564 -385.047998)
		(width 0.14224)
		(layer "In11.Cu")
		(net "P5E_CPU0_P3_TX_DP<14>")
	)
	(arc
		(start 393.134342 -383.384552)
		(mid 392.987388 -383.604718)
		(end 392.935968 -383.864358)
		(width 0.14224)
		(layer "In11.Cu")
		(net "P5E_CPU0_P3_TX_DP<14>")
	)
	(arc
		(start 373.868696 -291.605208)
		(mid 374.022794 -291.905944)
		(end 373.868696 -292.20668)
		(width 0.1143)
		(layer "In11.Cu")
		(net "P5E_CPU0_P3_TX_DP<14>")
	)
	(arc
		(start 373.79275 -292.251384)
		(mid 373.549423 -292.71595)
		(end 373.79275 -293.180516)
		(width 0.1143)
		(layer "In11.Cu")
		(net "P5E_CPU0_P3_TX_DP<14>")
	)
	(arc
		(start 373.835168 -285.105348)
		(mid 374.019901 -285.42604)
		(end 373.835422 -285.746952)
		(width 0.1143)
		(layer "In11.Cu")
		(net "P5E_CPU0_P3_TX_DP<14>")
	)
	(arc
		(start 374.333516 -295.651682)
		(mid 374.369379 -295.681074)
		(end 374.401334 -295.714674)
		(width 0.1143)
		(layer "In11.Cu")
		(net "P5E_CPU0_P3_TX_DP<14>")
	)
	(arc
		(start 373.835168 -281.865324)
		(mid 374.019901 -282.186016)
		(end 373.835422 -282.506928)
		(width 0.1143)
		(layer "In11.Cu")
		(net "P5E_CPU0_P3_TX_DP<14>")
	)
	(arc
		(start 373.835168 -283.485336)
		(mid 374.019901 -283.806028)
		(end 373.835422 -284.12694)
		(width 0.1143)
		(layer "In11.Cu")
		(net "P5E_CPU0_P3_TX_DP<14>")
	)
	(arc
		(start 374.032272 -278.965914)
		(mid 374.104537 -279.235843)
		(end 374.30202 -279.433528)
		(width 0.1143)
		(layer "In11.Cu")
		(net "P5E_CPU0_P3_TX_DP<14>")
	)
	(arc
		(start 374.401588 -295.714928)
		(mid 374.466955 -295.827663)
		(end 374.489726 -295.955974)
		(width 0.1143)
		(layer "In11.Cu")
		(net "P5E_CPU0_P3_TX_DP<14>")
	)
	(arc
		(start 373.79275 -293.871396)
		(mid 373.549423 -294.335962)
		(end 373.79275 -294.800528)
		(width 0.1143)
		(layer "In11.Cu")
		(net "P5E_CPU0_P3_TX_DP<14>")
	)
	(arc
		(start 374.489726 -296.127678)
		(mid 374.518704 -296.273272)
		(end 374.601232 -296.396664)
		(width 0.1143)
		(layer "In11.Cu")
		(net "P5E_CPU0_P3_TX_DP<14>")
	)
	(segment
		(start 372.707916 -274.630134)
		(end 373.174768 -274.896072)
		(width 0.12954)
		(layer "F.Cu")
		(net "P5E_CPU0_P3_TX_DP<13>")
	)
	(segment
		(start 391.616692 -378.68733)
		(end 391.912602 -378.39142)
		(width 0.12954)
		(layer "F.Cu")
		(net "P5E_CPU0_P3_TX_DP<13>")
	)
	(segment
		(start 391.912602 -377.68784)
		(end 391.642092 -377.41733)
		(width 0.12954)
		(layer "F.Cu")
		(net "P5E_CPU0_P3_TX_DP<13>")
	)
	(segment
		(start 391.912602 -378.39142)
		(end 391.912602 -377.68784)
		(width 0.12954)
		(layer "F.Cu")
		(net "P5E_CPU0_P3_TX_DP<13>")
	)
	(segment
		(start 372.859554 -294.804592)
		(end 372.860316 -294.8051)
		(width 0.1143)
		(layer "In11.Cu")
		(net "P5E_CPU0_P3_TX_DP<13>")
	)
	(segment
		(start 372.890796 -284.129226)
		(end 372.889272 -284.130242)
		(width 0.1143)
		(layer "In11.Cu")
		(net "P5E_CPU0_P3_TX_DP<13>")
	)
	(segment
		(start 372.890796 -276.029166)
		(end 372.889272 -276.030182)
		(width 0.1143)
		(layer "In11.Cu")
		(net "P5E_CPU0_P3_TX_DP<13>")
	)
	(segment
		(start 372.893844 -293.204646)
		(end 372.895368 -293.205408)
		(width 0.1143)
		(layer "In11.Cu")
		(net "P5E_CPU0_P3_TX_DP<13>")
	)
	(segment
		(start 372.896638 -281.86634)
		(end 372.8974 -281.866848)
		(width 0.1143)
		(layer "In11.Cu")
		(net "P5E_CPU0_P3_TX_DP<13>")
	)
	(segment
		(start 372.891812 -277.00351)
		(end 372.892574 -277.004018)
		(width 0.1143)
		(layer "In11.Cu")
		(net "P5E_CPU0_P3_TX_DP<13>")
	)
	(segment
		(start 372.895368 -293.205408)
		(end 372.896638 -293.20617)
		(width 0.1143)
		(layer "In11.Cu")
		(net "P5E_CPU0_P3_TX_DP<13>")
	)
	(segment
		(start 372.889272 -280.890218)
		(end 372.888256 -280.890726)
		(width 0.1143)
		(layer "In11.Cu")
		(net "P5E_CPU0_P3_TX_DP<13>")
	)
	(segment
		(start 372.852696 -286.700722)
		(end 372.891812 -286.723582)
		(width 0.1143)
		(layer "In11.Cu")
		(net "P5E_CPU0_P3_TX_DP<13>")
	)
	(segment
		(start 391.932922 -377.1265)
		(end 391.642092 -377.41733)
		(width 0.14224)
		(layer "In11.Cu")
		(net "P5E_CPU0_P3_TX_DP<13>")
	)
	(segment
		(start 372.887494 -284.131258)
		(end 372.885716 -284.132274)
		(width 0.1143)
		(layer "In11.Cu")
		(net "P5E_CPU0_P3_TX_DP<13>")
	)
	(segment
		(start 373.47271 -274.896072)
		(end 373.54256 -274.965922)
		(width 0.1143)
		(layer "In11.Cu")
		(net "P5E_CPU0_P3_TX_DP<13>")
	)
	(segment
		(start 372.889272 -276.030182)
		(end 372.888256 -276.03069)
		(width 0.1143)
		(layer "In11.Cu")
		(net "P5E_CPU0_P3_TX_DP<13>")
	)
	(segment
		(start 372.893844 -294.824658)
		(end 372.895368 -294.82542)
		(width 0.1143)
		(layer "In11.Cu")
		(net "P5E_CPU0_P3_TX_DP<13>")
	)
	(segment
		(start 372.891812 -292.228524)
		(end 372.890796 -292.229032)
		(width 0.1143)
		(layer "In11.Cu")
		(net "P5E_CPU0_P3_TX_DP<13>")
	)
	(segment
		(start 372.888256 -284.13075)
		(end 372.887494 -284.131258)
		(width 0.1143)
		(layer "In11.Cu")
		(net "P5E_CPU0_P3_TX_DP<13>")
	)
	(segment
		(start 372.891812 -278.623522)
		(end 372.892574 -278.62403)
		(width 0.1143)
		(layer "In11.Cu")
		(net "P5E_CPU0_P3_TX_DP<13>")
	)
	(segment
		(start 372.888256 -276.03069)
		(end 372.887494 -276.031198)
		(width 0.1143)
		(layer "In11.Cu")
		(net "P5E_CPU0_P3_TX_DP<13>")
	)
	(segment
		(start 372.902226 -289.969194)
		(end 372.923562 -289.98164)
		(width 0.1143)
		(layer "In11.Cu")
		(net "P5E_CPU0_P3_TX_DP<13>")
	)
	(segment
		(start 372.923562 -284.11043)
		(end 372.892574 -284.12821)
		(width 0.1143)
		(layer "In11.Cu")
		(net "P5E_CPU0_P3_TX_DP<13>")
	)
	(segment
		(start 372.899686 -281.868118)
		(end 372.902226 -281.869388)
		(width 0.1143)
		(layer "In11.Cu")
		(net "P5E_CPU0_P3_TX_DP<13>")
	)
	(segment
		(start 372.887494 -276.031198)
		(end 372.885716 -276.032214)
		(width 0.1143)
		(layer "In11.Cu")
		(net "P5E_CPU0_P3_TX_DP<13>")
	)
	(segment
		(start 373.77878 -296.93489)
		(end 373.77878 -297.13174)
		(width 0.14224)
		(layer "In11.Cu")
		(net "P5E_CPU0_P3_TX_DP<13>")
	)
	(segment
		(start 372.898416 -277.00732)
		(end 372.899686 -277.008082)
		(width 0.1143)
		(layer "In11.Cu")
		(net "P5E_CPU0_P3_TX_DP<13>")
	)
	(segment
		(start 373.361712 -295.633394)
		(end 373.361966 -295.633394)
		(width 0.1143)
		(layer "In11.Cu")
		(net "P5E_CPU0_P3_TX_DP<13>")
	)
	(segment
		(start 372.888256 -290.610544)
		(end 372.887494 -290.611052)
		(width 0.1143)
		(layer "In11.Cu")
		(net "P5E_CPU0_P3_TX_DP<13>")
	)
	(segment
		(start 372.923562 -288.970212)
		(end 372.892574 -288.987992)
		(width 0.1143)
		(layer "In11.Cu")
		(net "P5E_CPU0_P3_TX_DP<13>")
	)
	(segment
		(start 372.892574 -294.823896)
		(end 372.893844 -294.824658)
		(width 0.1143)
		(layer "In11.Cu")
		(net "P5E_CPU0_P3_TX_DP<13>")
	)
	(segment
		(start 372.899686 -278.628094)
		(end 372.902226 -278.629364)
		(width 0.1143)
		(layer "In11.Cu")
		(net "P5E_CPU0_P3_TX_DP<13>")
	)
	(segment
		(start 372.892574 -285.748222)
		(end 372.891812 -285.74873)
		(width 0.1143)
		(layer "In11.Cu")
		(net "P5E_CPU0_P3_TX_DP<13>")
	)
	(segment
		(start 372.859554 -278.604726)
		(end 372.860316 -278.605234)
		(width 0.1143)
		(layer "In11.Cu")
		(net "P5E_CPU0_P3_TX_DP<13>")
	)
	(segment
		(start 372.887494 -292.231064)
		(end 372.885716 -292.23208)
		(width 0.1143)
		(layer "In11.Cu")
		(net "P5E_CPU0_P3_TX_DP<13>")
	)
	(segment
		(start 372.884192 -276.03323)
		(end 372.852696 -276.051518)
		(width 0.1143)
		(layer "In11.Cu")
		(net "P5E_CPU0_P3_TX_DP<13>")
	)
	(segment
		(start 372.890796 -293.849044)
		(end 372.889272 -293.85006)
		(width 0.1143)
		(layer "In11.Cu")
		(net "P5E_CPU0_P3_TX_DP<13>")
	)
	(segment
		(start 372.891812 -282.508706)
		(end 372.890796 -282.509214)
		(width 0.1143)
		(layer "In11.Cu")
		(net "P5E_CPU0_P3_TX_DP<13>")
	)
	(segment
		(start 373.823992 -296.792142)
		(end 373.778272 -296.837862)
		(width 0.1143)
		(layer "In11.Cu")
		(net "P5E_CPU0_P3_TX_DP<13>")
	)
	(segment
		(start 372.923562 -282.490418)
		(end 372.892574 -282.508198)
		(width 0.1143)
		(layer "In11.Cu")
		(net "P5E_CPU0_P3_TX_DP<13>")
	)
	(segment
		(start 372.8974 -278.626824)
		(end 372.898416 -278.627332)
		(width 0.1143)
		(layer "In11.Cu")
		(net "P5E_CPU0_P3_TX_DP<13>")
	)
	(segment
		(start 372.892574 -292.228016)
		(end 372.891812 -292.228524)
		(width 0.1143)
		(layer "In11.Cu")
		(net "P5E_CPU0_P3_TX_DP<13>")
	)
	(segment
		(start 372.891812 -290.608512)
		(end 372.890796 -290.60902)
		(width 0.1143)
		(layer "In11.Cu")
		(net "P5E_CPU0_P3_TX_DP<13>")
	)
	(segment
		(start 372.860316 -294.8051)
		(end 372.891812 -294.823388)
		(width 0.1143)
		(layer "In11.Cu")
		(net "P5E_CPU0_P3_TX_DP<13>")
	)
	(segment
		(start 372.898416 -293.207186)
		(end 372.899686 -293.207948)
		(width 0.1143)
		(layer "In11.Cu")
		(net "P5E_CPU0_P3_TX_DP<13>")
	)
	(segment
		(start 372.887494 -288.99104)
		(end 372.885716 -288.992056)
		(width 0.1143)
		(layer "In11.Cu")
		(net "P5E_CPU0_P3_TX_DP<13>")
	)
	(segment
		(start 372.852696 -281.840686)
		(end 372.859554 -281.84475)
		(width 0.1143)
		(layer "In11.Cu")
		(net "P5E_CPU0_P3_TX_DP<13>")
	)
	(segment
		(start 372.885716 -284.132274)
		(end 372.884192 -284.13329)
		(width 0.1143)
		(layer "In11.Cu")
		(net "P5E_CPU0_P3_TX_DP<13>")
	)
	(segment
		(start 372.890796 -285.749238)
		(end 372.889272 -285.750254)
		(width 0.1143)
		(layer "In11.Cu")
		(net "P5E_CPU0_P3_TX_DP<13>")
	)
	(segment
		(start 372.860316 -278.605234)
		(end 372.891812 -278.623522)
		(width 0.1143)
		(layer "In11.Cu")
		(net "P5E_CPU0_P3_TX_DP<13>")
	)
	(segment
		(start 372.899686 -277.008082)
		(end 372.902226 -277.009352)
		(width 0.1143)
		(layer "In11.Cu")
		(net "P5E_CPU0_P3_TX_DP<13>")
	)
	(segment
		(start 372.888256 -285.750762)
		(end 372.887494 -285.75127)
		(width 0.1143)
		(layer "In11.Cu")
		(net "P5E_CPU0_P3_TX_DP<13>")
	)
	(segment
		(start 393.817348 -340.211664)
		(end 393.817348 -354.620322)
		(width 0.14224)
		(layer "In11.Cu")
		(net "P5E_CPU0_P3_TX_DP<13>")
	)
	(segment
		(start 372.890796 -290.60902)
		(end 372.889272 -290.610036)
		(width 0.1143)
		(layer "In11.Cu")
		(net "P5E_CPU0_P3_TX_DP<13>")
	)
	(segment
		(start 372.852696 -294.800528)
		(end 372.859554 -294.804592)
		(width 0.1143)
		(layer "In11.Cu")
		(net "P5E_CPU0_P3_TX_DP<13>")
	)
	(segment
		(start 372.860316 -276.985222)
		(end 372.891812 -277.00351)
		(width 0.1143)
		(layer "In11.Cu")
		(net "P5E_CPU0_P3_TX_DP<13>")
	)
	(segment
		(start 372.891812 -284.128718)
		(end 372.890796 -284.129226)
		(width 0.1143)
		(layer "In11.Cu")
		(net "P5E_CPU0_P3_TX_DP<13>")
	)
	(segment
		(start 372.884192 -290.613084)
		(end 372.852696 -290.631372)
		(width 0.1143)
		(layer "In11.Cu")
		(net "P5E_CPU0_P3_TX_DP<13>")
	)
	(segment
		(start 372.891812 -285.10357)
		(end 372.892574 -285.104078)
		(width 0.1143)
		(layer "In11.Cu")
		(net "P5E_CPU0_P3_TX_DP<13>")
	)
	(segment
		(start 372.885716 -277.652226)
		(end 372.884192 -277.653242)
		(width 0.1143)
		(layer "In11.Cu")
		(net "P5E_CPU0_P3_TX_DP<13>")
	)
	(segment
		(start 372.859554 -293.18458)
		(end 372.860316 -293.185088)
		(width 0.1143)
		(layer "In11.Cu")
		(net "P5E_CPU0_P3_TX_DP<13>")
	)
	(segment
		(start 372.891812 -287.368488)
		(end 372.855236 -287.389824)
		(width 0.1143)
		(layer "In11.Cu")
		(net "P5E_CPU0_P3_TX_DP<13>")
	)
	(segment
		(start 372.892574 -278.62403)
		(end 372.893844 -278.624792)
		(width 0.1143)
		(layer "In11.Cu")
		(net "P5E_CPU0_P3_TX_DP<13>")
	)
	(segment
		(start 372.892574 -290.608004)
		(end 372.891812 -290.608512)
		(width 0.1143)
		(layer "In11.Cu")
		(net "P5E_CPU0_P3_TX_DP<13>")
	)
	(segment
		(start 372.892574 -277.004018)
		(end 372.893844 -277.00478)
		(width 0.1143)
		(layer "In11.Cu")
		(net "P5E_CPU0_P3_TX_DP<13>")
	)
	(segment
		(start 373.77878 -297.13174)
		(end 374.037098 -297.983656)
		(width 0.14224)
		(layer "In11.Cu")
		(net "P5E_CPU0_P3_TX_DP<13>")
	)
	(segment
		(start 373.392446 -275.200872)
		(end 373.361966 -275.218652)
		(width 0.1143)
		(layer "In11.Cu")
		(net "P5E_CPU0_P3_TX_DP<13>")
	)
	(segment
		(start 372.852696 -285.08071)
		(end 372.890796 -285.103062)
		(width 0.1143)
		(layer "In11.Cu")
		(net "P5E_CPU0_P3_TX_DP<13>")
	)
	(segment
		(start 372.902226 -281.869388)
		(end 372.923562 -281.881834)
		(width 0.1143)
		(layer "In11.Cu")
		(net "P5E_CPU0_P3_TX_DP<13>")
	)
	(segment
		(start 372.892574 -285.104078)
		(end 372.893844 -285.10484)
		(width 0.1143)
		(layer "In11.Cu")
		(net "P5E_CPU0_P3_TX_DP<13>")
	)
	(segment
		(start 372.923562 -292.210236)
		(end 372.892574 -292.228016)
		(width 0.1143)
		(layer "In11.Cu")
		(net "P5E_CPU0_P3_TX_DP<13>")
	)
	(segment
		(start 372.852696 -283.460698)
		(end 372.890796 -283.48305)
		(width 0.1143)
		(layer "In11.Cu")
		(net "P5E_CPU0_P3_TX_DP<13>")
	)
	(segment
		(start 373.32285 -279.410668)
		(end 373.361966 -279.433528)
		(width 0.1143)
		(layer "In11.Cu")
		(net "P5E_CPU0_P3_TX_DP<13>")
	)
	(segment
		(start 372.892574 -289.96386)
		(end 372.893844 -289.964622)
		(width 0.1143)
		(layer "In11.Cu")
		(net "P5E_CPU0_P3_TX_DP<13>")
	)
	(segment
		(start 372.899686 -294.82796)
		(end 372.902226 -294.82923)
		(width 0.1143)
		(layer "In11.Cu")
		(net "P5E_CPU0_P3_TX_DP<13>")
	)
	(segment
		(start 373.778272 -296.934382)
		(end 373.77878 -296.93489)
		(width 0.14224)
		(layer "In11.Cu")
		(net "P5E_CPU0_P3_TX_DP<13>")
	)
	(segment
		(start 372.859554 -289.944556)
		(end 372.860316 -289.945064)
		(width 0.1143)
		(layer "In11.Cu")
		(net "P5E_CPU0_P3_TX_DP<13>")
	)
	(segment
		(start 372.8974 -293.206678)
		(end 372.898416 -293.207186)
		(width 0.1143)
		(layer "In11.Cu")
		(net "P5E_CPU0_P3_TX_DP<13>")
	)
	(segment
		(start 372.889272 -292.230048)
		(end 372.888256 -292.230556)
		(width 0.1143)
		(layer "In11.Cu")
		(net "P5E_CPU0_P3_TX_DP<13>")
	)
	(segment
		(start 374.037098 -297.983656)
		(end 374.741186 -299.036994)
		(width 0.14224)
		(layer "In11.Cu")
		(net "P5E_CPU0_P3_TX_DP<13>")
	)
	(segment
		(start 391.936478 -373.59463)
		(end 391.647172 -374.29313)
		(width 0.14224)
		(layer "In11.Cu")
		(net "P5E_CPU0_P3_TX_DP<13>")
	)
	(segment
		(start 372.888256 -292.230556)
		(end 372.887494 -292.231064)
		(width 0.1143)
		(layer "In11.Cu")
		(net "P5E_CPU0_P3_TX_DP<13>")
	)
	(segment
		(start 372.923562 -276.01037)
		(end 372.892574 -276.02815)
		(width 0.1143)
		(layer "In11.Cu")
		(net "P5E_CPU0_P3_TX_DP<13>")
	)
	(segment
		(start 372.892574 -276.02815)
		(end 372.891812 -276.028658)
		(width 0.1143)
		(layer "In11.Cu")
		(net "P5E_CPU0_P3_TX_DP<13>")
	)
	(segment
		(start 373.32412 -295.61155)
		(end 373.361712 -295.633394)
		(width 0.1143)
		(layer "In11.Cu")
		(net "P5E_CPU0_P3_TX_DP<13>")
	)
	(segment
		(start 372.884192 -284.13329)
		(end 372.852696 -284.151578)
		(width 0.1143)
		(layer "In11.Cu")
		(net "P5E_CPU0_P3_TX_DP<13>")
	)
	(segment
		(start 372.889272 -277.650194)
		(end 372.888256 -277.650702)
		(width 0.1143)
		(layer "In11.Cu")
		(net "P5E_CPU0_P3_TX_DP<13>")
	)
	(segment
		(start 372.891812 -286.723582)
		(end 372.92534 -286.74314)
		(width 0.1143)
		(layer "In11.Cu")
		(net "P5E_CPU0_P3_TX_DP<13>")
	)
	(segment
		(start 373.361966 -279.433528)
		(end 373.392446 -279.451308)
		(width 0.1143)
		(layer "In11.Cu")
		(net "P5E_CPU0_P3_TX_DP<13>")
	)
	(segment
		(start 373.549672 -296.183812)
		(end 373.823992 -296.458132)
		(width 0.1143)
		(layer "In11.Cu")
		(net "P5E_CPU0_P3_TX_DP<13>")
	)
	(segment
		(start 372.889272 -282.51023)
		(end 372.888256 -282.510738)
		(width 0.1143)
		(layer "In11.Cu")
		(net "P5E_CPU0_P3_TX_DP<13>")
	)
	(segment
		(start 372.892574 -281.864054)
		(end 372.893844 -281.864816)
		(width 0.1143)
		(layer "In11.Cu")
		(net "P5E_CPU0_P3_TX_DP<13>")
	)
	(segment
		(start 372.892574 -291.583872)
		(end 372.893844 -291.584634)
		(width 0.1143)
		(layer "In11.Cu")
		(net "P5E_CPU0_P3_TX_DP<13>")
	)
	(segment
		(start 372.895368 -289.965384)
		(end 372.896638 -289.966146)
		(width 0.1143)
		(layer "In11.Cu")
		(net "P5E_CPU0_P3_TX_DP<13>")
	)
	(segment
		(start 372.887494 -282.511246)
		(end 372.885716 -282.512262)
		(width 0.1143)
		(layer "In11.Cu")
		(net "P5E_CPU0_P3_TX_DP<13>")
	)
	(segment
		(start 372.860316 -281.845258)
		(end 372.891812 -281.863546)
		(width 0.1143)
		(layer "In11.Cu")
		(net "P5E_CPU0_P3_TX_DP<13>")
	)
	(segment
		(start 372.893844 -281.864816)
		(end 372.895368 -281.865578)
		(width 0.1143)
		(layer "In11.Cu")
		(net "P5E_CPU0_P3_TX_DP<13>")
	)
	(segment
		(start 372.899686 -293.207948)
		(end 372.902226 -293.209218)
		(width 0.1143)
		(layer "In11.Cu")
		(net "P5E_CPU0_P3_TX_DP<13>")
	)
	(segment
		(start 372.859554 -281.84475)
		(end 372.860316 -281.845258)
		(width 0.1143)
		(layer "In11.Cu")
		(net "P5E_CPU0_P3_TX_DP<13>")
	)
	(segment
		(start 372.896638 -294.826182)
		(end 372.8974 -294.82669)
		(width 0.1143)
		(layer "In11.Cu")
		(net "P5E_CPU0_P3_TX_DP<13>")
	)
	(segment
		(start 372.891812 -283.483558)
		(end 372.892574 -283.484066)
		(width 0.1143)
		(layer "In11.Cu")
		(net "P5E_CPU0_P3_TX_DP<13>")
	)
	(segment
		(start 372.923562 -280.870406)
		(end 372.892574 -280.888186)
		(width 0.1143)
		(layer "In11.Cu")
		(net "P5E_CPU0_P3_TX_DP<13>")
	)
	(segment
		(start 372.902226 -294.82923)
		(end 372.923562 -294.841676)
		(width 0.1143)
		(layer "In11.Cu")
		(net "P5E_CPU0_P3_TX_DP<13>")
	)
	(segment
		(start 372.891812 -294.823388)
		(end 372.892574 -294.823896)
		(width 0.1143)
		(layer "In11.Cu")
		(net "P5E_CPU0_P3_TX_DP<13>")
	)
	(segment
		(start 372.852696 -278.600662)
		(end 372.859554 -278.604726)
		(width 0.1143)
		(layer "In11.Cu")
		(net "P5E_CPU0_P3_TX_DP<13>")
	)
	(segment
		(start 372.890796 -283.48305)
		(end 372.891812 -283.483558)
		(width 0.1143)
		(layer "In11.Cu")
		(net "P5E_CPU0_P3_TX_DP<13>")
	)
	(segment
		(start 372.890796 -285.103062)
		(end 372.891812 -285.10357)
		(width 0.1143)
		(layer "In11.Cu")
		(net "P5E_CPU0_P3_TX_DP<13>")
	)
	(segment
		(start 372.895368 -278.625554)
		(end 372.896638 -278.626316)
		(width 0.1143)
		(layer "In11.Cu")
		(net "P5E_CPU0_P3_TX_DP<13>")
	)
	(segment
		(start 372.893844 -277.00478)
		(end 372.895368 -277.005542)
		(width 0.1143)
		(layer "In11.Cu")
		(net "P5E_CPU0_P3_TX_DP<13>")
	)
	(segment
		(start 372.891812 -281.863546)
		(end 372.892574 -281.864054)
		(width 0.1143)
		(layer "In11.Cu")
		(net "P5E_CPU0_P3_TX_DP<13>")
	)
	(segment
		(start 372.896638 -278.626316)
		(end 372.8974 -278.626824)
		(width 0.1143)
		(layer "In11.Cu")
		(net "P5E_CPU0_P3_TX_DP<13>")
	)
	(segment
		(start 372.887494 -285.75127)
		(end 372.885716 -285.752286)
		(width 0.1143)
		(layer "In11.Cu")
		(net "P5E_CPU0_P3_TX_DP<13>")
	)
	(segment
		(start 372.902226 -293.209218)
		(end 372.923562 -293.221664)
		(width 0.1143)
		(layer "In11.Cu")
		(net "P5E_CPU0_P3_TX_DP<13>")
	)
	(segment
		(start 372.888256 -277.650702)
		(end 372.887494 -277.65121)
		(width 0.1143)
		(layer "In11.Cu")
		(net "P5E_CPU0_P3_TX_DP<13>")
	)
	(segment
		(start 372.889272 -284.130242)
		(end 372.888256 -284.13075)
		(width 0.1143)
		(layer "In11.Cu")
		(net "P5E_CPU0_P3_TX_DP<13>")
	)
	(segment
		(start 372.923562 -293.830248)
		(end 372.891812 -293.848536)
		(width 0.1143)
		(layer "In11.Cu")
		(net "P5E_CPU0_P3_TX_DP<13>")
	)
	(segment
		(start 372.885716 -276.032214)
		(end 372.884192 -276.03323)
		(width 0.1143)
		(layer "In11.Cu")
		(net "P5E_CPU0_P3_TX_DP<13>")
	)
	(segment
		(start 372.891812 -293.203376)
		(end 372.892574 -293.203884)
		(width 0.1143)
		(layer "In11.Cu")
		(net "P5E_CPU0_P3_TX_DP<13>")
	)
	(segment
		(start 372.923562 -287.3502)
		(end 372.891812 -287.368488)
		(width 0.1143)
		(layer "In11.Cu")
		(net "P5E_CPU0_P3_TX_DP<13>")
	)
	(segment
		(start 372.884192 -277.653242)
		(end 372.852696 -277.67153)
		(width 0.1143)
		(layer "In11.Cu")
		(net "P5E_CPU0_P3_TX_DP<13>")
	)
	(segment
		(start 372.893844 -285.10484)
		(end 372.923562 -285.121858)
		(width 0.1143)
		(layer "In11.Cu")
		(net "P5E_CPU0_P3_TX_DP<13>")
	)
	(segment
		(start 372.889272 -293.85006)
		(end 372.852696 -293.871396)
		(width 0.1143)
		(layer "In11.Cu")
		(net "P5E_CPU0_P3_TX_DP<13>")
	)
	(segment
		(start 373.361966 -275.218652)
		(end 373.32285 -275.241512)
		(width 0.1143)
		(layer "In11.Cu")
		(net "P5E_CPU0_P3_TX_DP<13>")
	)
	(segment
		(start 372.891812 -288.9885)
		(end 372.890796 -288.989008)
		(width 0.1143)
		(layer "In11.Cu")
		(net "P5E_CPU0_P3_TX_DP<13>")
	)
	(segment
		(start 372.896638 -277.006304)
		(end 372.8974 -277.006812)
		(width 0.1143)
		(layer "In11.Cu")
		(net "P5E_CPU0_P3_TX_DP<13>")
	)
	(segment
		(start 391.730992 -375.87428)
		(end 391.82294 -375.966228)
		(width 0.14224)
		(layer "In11.Cu")
		(net "P5E_CPU0_P3_TX_DP<13>")
	)
	(segment
		(start 372.891812 -293.848536)
		(end 372.890796 -293.849044)
		(width 0.1143)
		(layer "In11.Cu")
		(net "P5E_CPU0_P3_TX_DP<13>")
	)
	(segment
		(start 372.887494 -280.891234)
		(end 372.885716 -280.89225)
		(width 0.1143)
		(layer "In11.Cu")
		(net "P5E_CPU0_P3_TX_DP<13>")
	)
	(segment
		(start 372.892574 -284.12821)
		(end 372.891812 -284.128718)
		(width 0.1143)
		(layer "In11.Cu")
		(net "P5E_CPU0_P3_TX_DP<13>")
	)
	(segment
		(start 372.898416 -289.967162)
		(end 372.899686 -289.967924)
		(width 0.1143)
		(layer "In11.Cu")
		(net "P5E_CPU0_P3_TX_DP<13>")
	)
	(segment
		(start 372.852696 -288.320734)
		(end 372.891812 -288.343594)
		(width 0.1143)
		(layer "In11.Cu")
		(net "P5E_CPU0_P3_TX_DP<13>")
	)
	(segment
		(start 372.885716 -282.512262)
		(end 372.884192 -282.513278)
		(width 0.1143)
		(layer "In11.Cu")
		(net "P5E_CPU0_P3_TX_DP<13>")
	)
	(segment
		(start 372.891812 -288.343594)
		(end 372.92534 -288.363152)
		(width 0.1143)
		(layer "In11.Cu")
		(net "P5E_CPU0_P3_TX_DP<13>")
	)
	(segment
		(start 372.8974 -277.006812)
		(end 372.898416 -277.00732)
		(width 0.1143)
		(layer "In11.Cu")
		(net "P5E_CPU0_P3_TX_DP<13>")
	)
	(segment
		(start 372.852696 -276.98065)
		(end 372.859554 -276.984714)
		(width 0.1143)
		(layer "In11.Cu")
		(net "P5E_CPU0_P3_TX_DP<13>")
	)
	(segment
		(start 372.884192 -288.993072)
		(end 372.852696 -289.01136)
		(width 0.1143)
		(layer "In11.Cu")
		(net "P5E_CPU0_P3_TX_DP<13>")
	)
	(segment
		(start 372.923562 -290.590224)
		(end 372.892574 -290.608004)
		(width 0.1143)
		(layer "In11.Cu")
		(net "P5E_CPU0_P3_TX_DP<13>")
	)
	(segment
		(start 372.884192 -280.893266)
		(end 372.852696 -280.911554)
		(width 0.1143)
		(layer "In11.Cu")
		(net "P5E_CPU0_P3_TX_DP<13>")
	)
	(segment
		(start 372.852696 -293.180516)
		(end 372.859554 -293.18458)
		(width 0.1143)
		(layer "In11.Cu")
		(net "P5E_CPU0_P3_TX_DP<13>")
	)
	(segment
		(start 373.549672 -295.955974)
		(end 373.549672 -296.183812)
		(width 0.1143)
		(layer "In11.Cu")
		(net "P5E_CPU0_P3_TX_DP<13>")
	)
	(segment
		(start 372.895368 -281.865578)
		(end 372.896638 -281.86634)
		(width 0.1143)
		(layer "In11.Cu")
		(net "P5E_CPU0_P3_TX_DP<13>")
	)
	(segment
		(start 372.898416 -281.867356)
		(end 372.899686 -281.868118)
		(width 0.1143)
		(layer "In11.Cu")
		(net "P5E_CPU0_P3_TX_DP<13>")
	)
	(segment
		(start 372.888256 -288.990532)
		(end 372.887494 -288.99104)
		(width 0.1143)
		(layer "In11.Cu")
		(net "P5E_CPU0_P3_TX_DP<13>")
	)
	(segment
		(start 381.837438 -307.683916)
		(end 387.955282 -316.839854)
		(width 0.14224)
		(layer "In11.Cu")
		(net "P5E_CPU0_P3_TX_DP<13>")
	)
	(segment
		(start 372.885716 -288.992056)
		(end 372.884192 -288.993072)
		(width 0.1143)
		(layer "In11.Cu")
		(net "P5E_CPU0_P3_TX_DP<13>")
	)
	(segment
		(start 372.852696 -289.940492)
		(end 372.859554 -289.944556)
		(width 0.1143)
		(layer "In11.Cu")
		(net "P5E_CPU0_P3_TX_DP<13>")
	)
	(segment
		(start 372.896638 -293.20617)
		(end 372.8974 -293.206678)
		(width 0.1143)
		(layer "In11.Cu")
		(net "P5E_CPU0_P3_TX_DP<13>")
	)
	(segment
		(start 372.895368 -294.82542)
		(end 372.896638 -294.826182)
		(width 0.1143)
		(layer "In11.Cu")
		(net "P5E_CPU0_P3_TX_DP<13>")
	)
	(segment
		(start 372.8974 -294.82669)
		(end 372.898416 -294.827198)
		(width 0.1143)
		(layer "In11.Cu")
		(net "P5E_CPU0_P3_TX_DP<13>")
	)
	(segment
		(start 372.891812 -276.028658)
		(end 372.890796 -276.029166)
		(width 0.1143)
		(layer "In11.Cu")
		(net "P5E_CPU0_P3_TX_DP<13>")
	)
	(segment
		(start 372.890796 -280.889202)
		(end 372.889272 -280.890218)
		(width 0.1143)
		(layer "In11.Cu")
		(net "P5E_CPU0_P3_TX_DP<13>")
	)
	(segment
		(start 372.852696 -291.560504)
		(end 372.890796 -291.582856)
		(width 0.1143)
		(layer "In11.Cu")
		(net "P5E_CPU0_P3_TX_DP<13>")
	)
	(segment
		(start 372.885716 -280.89225)
		(end 372.884192 -280.893266)
		(width 0.1143)
		(layer "In11.Cu")
		(net "P5E_CPU0_P3_TX_DP<13>")
	)
	(segment
		(start 373.778272 -296.86631)
		(end 373.778272 -296.934382)
		(width 0.14224)
		(layer "In11.Cu")
		(net "P5E_CPU0_P3_TX_DP<13>")
	)
	(segment
		(start 372.888256 -280.890726)
		(end 372.887494 -280.891234)
		(width 0.1143)
		(layer "In11.Cu")
		(net "P5E_CPU0_P3_TX_DP<13>")
	)
	(segment
		(start 372.891812 -291.583364)
		(end 372.892574 -291.583872)
		(width 0.1143)
		(layer "In11.Cu")
		(net "P5E_CPU0_P3_TX_DP<13>")
	)
	(segment
		(start 372.860316 -289.945064)
		(end 372.891812 -289.963352)
		(width 0.1143)
		(layer "In11.Cu")
		(net "P5E_CPU0_P3_TX_DP<13>")
	)
	(segment
		(start 372.889272 -288.990024)
		(end 372.888256 -288.990532)
		(width 0.1143)
		(layer "In11.Cu")
		(net "P5E_CPU0_P3_TX_DP<13>")
	)
	(segment
		(start 372.892574 -283.484066)
		(end 372.893844 -283.484828)
		(width 0.1143)
		(layer "In11.Cu")
		(net "P5E_CPU0_P3_TX_DP<13>")
	)
	(segment
		(start 373.778272 -296.837862)
		(end 373.778272 -296.86631)
		(width 0.1143)
		(layer "In11.Cu")
		(net "P5E_CPU0_P3_TX_DP<13>")
	)
	(segment
		(start 372.892574 -282.508198)
		(end 372.891812 -282.508706)
		(width 0.1143)
		(layer "In11.Cu")
		(net "P5E_CPU0_P3_TX_DP<13>")
	)
	(segment
		(start 372.8974 -281.866848)
		(end 372.898416 -281.867356)
		(width 0.1143)
		(layer "In11.Cu")
		(net "P5E_CPU0_P3_TX_DP<13>")
	)
	(segment
		(start 372.896638 -289.966146)
		(end 372.8974 -289.966654)
		(width 0.1143)
		(layer "In11.Cu")
		(net "P5E_CPU0_P3_TX_DP<13>")
	)
	(segment
		(start 372.888256 -282.510738)
		(end 372.887494 -282.511246)
		(width 0.1143)
		(layer "In11.Cu")
		(net "P5E_CPU0_P3_TX_DP<13>")
	)
	(segment
		(start 372.892574 -293.203884)
		(end 372.893844 -293.204646)
		(width 0.1143)
		(layer "In11.Cu")
		(net "P5E_CPU0_P3_TX_DP<13>")
	)
	(segment
		(start 372.891812 -289.963352)
		(end 372.892574 -289.96386)
		(width 0.1143)
		(layer "In11.Cu")
		(net "P5E_CPU0_P3_TX_DP<13>")
	)
	(segment
		(start 372.8974 -289.966654)
		(end 372.898416 -289.967162)
		(width 0.1143)
		(layer "In11.Cu")
		(net "P5E_CPU0_P3_TX_DP<13>")
	)
	(segment
		(start 391.932922 -376.231404)
		(end 391.932922 -377.1265)
		(width 0.14224)
		(layer "In11.Cu")
		(net "P5E_CPU0_P3_TX_DP<13>")
	)
	(segment
		(start 372.891812 -277.64867)
		(end 372.890796 -277.649178)
		(width 0.1143)
		(layer "In11.Cu")
		(net "P5E_CPU0_P3_TX_DP<13>")
	)
	(segment
		(start 372.890796 -282.509214)
		(end 372.889272 -282.51023)
		(width 0.1143)
		(layer "In11.Cu")
		(net "P5E_CPU0_P3_TX_DP<13>")
	)
	(segment
		(start 372.884192 -292.233096)
		(end 372.852696 -292.251384)
		(width 0.1143)
		(layer "In11.Cu")
		(net "P5E_CPU0_P3_TX_DP<13>")
	)
	(segment
		(start 372.887494 -290.611052)
		(end 372.885716 -290.612068)
		(width 0.1143)
		(layer "In11.Cu")
		(net "P5E_CPU0_P3_TX_DP<13>")
	)
	(segment
		(start 372.923562 -277.630382)
		(end 372.892574 -277.648162)
		(width 0.1143)
		(layer "In11.Cu")
		(net "P5E_CPU0_P3_TX_DP<13>")
	)
	(segment
		(start 372.890796 -288.989008)
		(end 372.889272 -288.990024)
		(width 0.1143)
		(layer "In11.Cu")
		(net "P5E_CPU0_P3_TX_DP<13>")
	)
	(segment
		(start 393.811252 -354.74656)
		(end 391.966958 -373.472202)
		(width 0.14224)
		(layer "In11.Cu")
		(net "P5E_CPU0_P3_TX_DP<13>")
	)
	(segment
		(start 391.601198 -374.52427)
		(end 391.601198 -375.560844)
		(width 0.14224)
		(layer "In11.Cu")
		(net "P5E_CPU0_P3_TX_DP<13>")
	)
	(segment
		(start 372.923562 -285.730442)
		(end 372.892574 -285.748222)
		(width 0.1143)
		(layer "In11.Cu")
		(net "P5E_CPU0_P3_TX_DP<13>")
	)
	(segment
		(start 372.890796 -277.649178)
		(end 372.889272 -277.650194)
		(width 0.1143)
		(layer "In11.Cu")
		(net "P5E_CPU0_P3_TX_DP<13>")
	)
	(segment
		(start 372.895368 -277.005542)
		(end 372.896638 -277.006304)
		(width 0.1143)
		(layer "In11.Cu")
		(net "P5E_CPU0_P3_TX_DP<13>")
	)
	(segment
		(start 372.860316 -293.185088)
		(end 372.891812 -293.203376)
		(width 0.1143)
		(layer "In11.Cu")
		(net "P5E_CPU0_P3_TX_DP<13>")
	)
	(segment
		(start 372.902226 -277.009352)
		(end 372.923562 -277.021798)
		(width 0.1143)
		(layer "In11.Cu")
		(net "P5E_CPU0_P3_TX_DP<13>")
	)
	(segment
		(start 372.885716 -290.612068)
		(end 372.884192 -290.613084)
		(width 0.1143)
		(layer "In11.Cu")
		(net "P5E_CPU0_P3_TX_DP<13>")
	)
	(segment
		(start 372.893844 -283.484828)
		(end 372.923562 -283.501846)
		(width 0.1143)
		(layer "In11.Cu")
		(net "P5E_CPU0_P3_TX_DP<13>")
	)
	(segment
		(start 372.890796 -292.229032)
		(end 372.889272 -292.230048)
		(width 0.1143)
		(layer "In11.Cu")
		(net "P5E_CPU0_P3_TX_DP<13>")
	)
	(segment
		(start 373.392446 -280.060908)
		(end 373.361966 -280.078688)
		(width 0.1143)
		(layer "In11.Cu")
		(net "P5E_CPU0_P3_TX_DP<13>")
	)
	(segment
		(start 372.893844 -289.964622)
		(end 372.895368 -289.965384)
		(width 0.1143)
		(layer "In11.Cu")
		(net "P5E_CPU0_P3_TX_DP<13>")
	)
	(segment
		(start 373.174768 -274.896072)
		(end 373.47271 -274.896072)
		(width 0.1143)
		(layer "In11.Cu")
		(net "P5E_CPU0_P3_TX_DP<13>")
	)
	(segment
		(start 372.885716 -292.23208)
		(end 372.884192 -292.233096)
		(width 0.1143)
		(layer "In11.Cu")
		(net "P5E_CPU0_P3_TX_DP<13>")
	)
	(segment
		(start 372.892574 -277.648162)
		(end 372.891812 -277.64867)
		(width 0.1143)
		(layer "In11.Cu")
		(net "P5E_CPU0_P3_TX_DP<13>")
	)
	(segment
		(start 372.892574 -280.888186)
		(end 372.891812 -280.888694)
		(width 0.1143)
		(layer "In11.Cu")
		(net "P5E_CPU0_P3_TX_DP<13>")
	)
	(segment
		(start 372.890796 -291.582856)
		(end 372.891812 -291.583364)
		(width 0.1143)
		(layer "In11.Cu")
		(net "P5E_CPU0_P3_TX_DP<13>")
	)
	(segment
		(start 372.885716 -285.752286)
		(end 372.884192 -285.753302)
		(width 0.1143)
		(layer "In11.Cu")
		(net "P5E_CPU0_P3_TX_DP<13>")
	)
	(segment
		(start 372.889272 -290.610036)
		(end 372.888256 -290.610544)
		(width 0.1143)
		(layer "In11.Cu")
		(net "P5E_CPU0_P3_TX_DP<13>")
	)
	(segment
		(start 372.889272 -285.750254)
		(end 372.888256 -285.750762)
		(width 0.1143)
		(layer "In11.Cu")
		(net "P5E_CPU0_P3_TX_DP<13>")
	)
	(segment
		(start 372.891812 -280.888694)
		(end 372.890796 -280.889202)
		(width 0.1143)
		(layer "In11.Cu")
		(net "P5E_CPU0_P3_TX_DP<13>")
	)
	(segment
		(start 372.887494 -277.65121)
		(end 372.885716 -277.652226)
		(width 0.1143)
		(layer "In11.Cu")
		(net "P5E_CPU0_P3_TX_DP<13>")
	)
	(segment
		(start 372.891812 -285.74873)
		(end 372.890796 -285.749238)
		(width 0.1143)
		(layer "In11.Cu")
		(net "P5E_CPU0_P3_TX_DP<13>")
	)
	(segment
		(start 373.823992 -296.458132)
		(end 373.823992 -296.792142)
		(width 0.1143)
		(layer "In11.Cu")
		(net "P5E_CPU0_P3_TX_DP<13>")
	)
	(segment
		(start 372.902226 -278.629364)
		(end 372.923562 -278.64181)
		(width 0.1143)
		(layer "In11.Cu")
		(net "P5E_CPU0_P3_TX_DP<13>")
	)
	(segment
		(start 373.361966 -280.078688)
		(end 373.32285 -280.101548)
		(width 0.1143)
		(layer "In11.Cu")
		(net "P5E_CPU0_P3_TX_DP<13>")
	)
	(segment
		(start 372.898416 -294.827198)
		(end 372.899686 -294.82796)
		(width 0.1143)
		(layer "In11.Cu")
		(net "P5E_CPU0_P3_TX_DP<13>")
	)
	(segment
		(start 372.898416 -278.627332)
		(end 372.899686 -278.628094)
		(width 0.1143)
		(layer "In11.Cu")
		(net "P5E_CPU0_P3_TX_DP<13>")
	)
	(segment
		(start 372.884192 -285.753302)
		(end 372.852696 -285.77159)
		(width 0.1143)
		(layer "In11.Cu")
		(net "P5E_CPU0_P3_TX_DP<13>")
	)
	(segment
		(start 373.361966 -295.633394)
		(end 373.392446 -295.651174)
		(width 0.1143)
		(layer "In11.Cu")
		(net "P5E_CPU0_P3_TX_DP<13>")
	)
	(segment
		(start 372.899686 -289.967924)
		(end 372.902226 -289.969194)
		(width 0.1143)
		(layer "In11.Cu")
		(net "P5E_CPU0_P3_TX_DP<13>")
	)
	(segment
		(start 372.893844 -291.584634)
		(end 372.923562 -291.601652)
		(width 0.1143)
		(layer "In11.Cu")
		(net "P5E_CPU0_P3_TX_DP<13>")
	)
	(segment
		(start 372.893844 -278.624792)
		(end 372.895368 -278.625554)
		(width 0.1143)
		(layer "In11.Cu")
		(net "P5E_CPU0_P3_TX_DP<13>")
	)
	(segment
		(start 372.859554 -276.984714)
		(end 372.860316 -276.985222)
		(width 0.1143)
		(layer "In11.Cu")
		(net "P5E_CPU0_P3_TX_DP<13>")
	)
	(segment
		(start 372.884192 -282.513278)
		(end 372.852696 -282.531566)
		(width 0.1143)
		(layer "In11.Cu")
		(net "P5E_CPU0_P3_TX_DP<13>")
	)
	(segment
		(start 388.014972 -316.95136)
		(end 390.276842 -322.411598)
		(width 0.14224)
		(layer "In11.Cu")
		(net "P5E_CPU0_P3_TX_DP<13>")
	)
	(segment
		(start 372.892574 -288.987992)
		(end 372.891812 -288.9885)
		(width 0.1143)
		(layer "In11.Cu")
		(net "P5E_CPU0_P3_TX_DP<13>")
	)
	(segment
		(start 390.313672 -322.532502)
		(end 393.804902 -340.085934)
		(width 0.14224)
		(layer "In11.Cu")
		(net "P5E_CPU0_P3_TX_DP<13>")
	)
	(segment
		(start 374.741186 -299.036994)
		(end 381.837438 -307.683916)
		(width 0.14224)
		(layer "In11.Cu")
		(net "P5E_CPU0_P3_TX_DP<13>")
	)
	(arc
		(start 373.392446 -279.451308)
		(mid 373.549423 -279.756108)
		(end 373.392446 -280.060908)
		(width 0.1143)
		(layer "In11.Cu")
		(net "P5E_CPU0_P3_TX_DP<13>")
	)
	(arc
		(start 372.923562 -281.881834)
		(mid 373.07949 -282.186126)
		(end 372.923562 -282.490418)
		(width 0.1143)
		(layer "In11.Cu")
		(net "P5E_CPU0_P3_TX_DP<13>")
	)
	(arc
		(start 373.392446 -295.651174)
		(mid 373.400789 -295.657409)
		(end 373.408956 -295.663874)
		(width 0.1143)
		(layer "In11.Cu")
		(net "P5E_CPU0_P3_TX_DP<13>")
	)
	(arc
		(start 372.852696 -280.911554)
		(mid 372.609369 -281.37612)
		(end 372.852696 -281.840686)
		(width 0.1143)
		(layer "In11.Cu")
		(net "P5E_CPU0_P3_TX_DP<13>")
	)
	(arc
		(start 372.852696 -277.67153)
		(mid 372.609369 -278.136096)
		(end 372.852696 -278.600662)
		(width 0.1143)
		(layer "In11.Cu")
		(net "P5E_CPU0_P3_TX_DP<13>")
	)
	(arc
		(start 391.601198 -375.560844)
		(mid 391.634937 -375.730461)
		(end 391.730992 -375.87428)
		(width 0.14224)
		(layer "In11.Cu")
		(net "P5E_CPU0_P3_TX_DP<13>")
	)
	(arc
		(start 372.609364 -287.856168)
		(mid 372.673879 -288.118387)
		(end 372.852696 -288.320734)
		(width 0.1143)
		(layer "In11.Cu")
		(net "P5E_CPU0_P3_TX_DP<13>")
	)
	(arc
		(start 373.32285 -275.241512)
		(mid 373.144037 -275.443862)
		(end 373.079518 -275.706078)
		(width 0.1143)
		(layer "In11.Cu")
		(net "P5E_CPU0_P3_TX_DP<13>")
	)
	(arc
		(start 372.852696 -290.631372)
		(mid 372.609369 -291.095938)
		(end 372.852696 -291.560504)
		(width 0.1143)
		(layer "In11.Cu")
		(net "P5E_CPU0_P3_TX_DP<13>")
	)
	(arc
		(start 372.923562 -289.98164)
		(mid 373.07949 -290.285932)
		(end 372.923562 -290.590224)
		(width 0.1143)
		(layer "In11.Cu")
		(net "P5E_CPU0_P3_TX_DP<13>")
	)
	(arc
		(start 372.852696 -282.531566)
		(mid 372.609369 -282.996132)
		(end 372.852696 -283.460698)
		(width 0.1143)
		(layer "In11.Cu")
		(net "P5E_CPU0_P3_TX_DP<13>")
	)
	(arc
		(start 393.817348 -354.620322)
		(mid 393.815849 -354.683516)
		(end 393.811252 -354.74656)
		(width 0.14224)
		(layer "In11.Cu")
		(net "P5E_CPU0_P3_TX_DP<13>")
	)
	(arc
		(start 372.852696 -284.151578)
		(mid 372.609369 -284.616144)
		(end 372.852696 -285.08071)
		(width 0.1143)
		(layer "In11.Cu")
		(net "P5E_CPU0_P3_TX_DP<13>")
	)
	(arc
		(start 373.079518 -278.946102)
		(mid 373.144033 -279.208321)
		(end 373.32285 -279.410668)
		(width 0.1143)
		(layer "In11.Cu")
		(net "P5E_CPU0_P3_TX_DP<13>")
	)
	(arc
		(start 390.276842 -322.411598)
		(mid 390.298232 -322.471144)
		(end 390.313672 -322.532502)
		(width 0.14224)
		(layer "In11.Cu")
		(net "P5E_CPU0_P3_TX_DP<13>")
	)
	(arc
		(start 372.92534 -288.363152)
		(mid 373.038747 -288.496041)
		(end 373.079518 -288.66592)
		(width 0.1143)
		(layer "In11.Cu")
		(net "P5E_CPU0_P3_TX_DP<13>")
	)
	(arc
		(start 372.852696 -285.77159)
		(mid 372.609369 -286.236156)
		(end 372.852696 -286.700722)
		(width 0.1143)
		(layer "In11.Cu")
		(net "P5E_CPU0_P3_TX_DP<13>")
	)
	(arc
		(start 393.804902 -340.085934)
		(mid 393.814205 -340.148494)
		(end 393.817348 -340.211664)
		(width 0.14224)
		(layer "In11.Cu")
		(net "P5E_CPU0_P3_TX_DP<13>")
	)
	(arc
		(start 373.079518 -288.66592)
		(mid 373.038263 -288.836891)
		(end 372.923562 -288.970212)
		(width 0.1143)
		(layer "In11.Cu")
		(net "P5E_CPU0_P3_TX_DP<13>")
	)
	(arc
		(start 391.647172 -374.29313)
		(mid 391.612816 -374.406438)
		(end 391.601198 -374.52427)
		(width 0.14224)
		(layer "In11.Cu")
		(net "P5E_CPU0_P3_TX_DP<13>")
	)
	(arc
		(start 372.852696 -292.251384)
		(mid 372.609369 -292.71595)
		(end 372.852696 -293.180516)
		(width 0.1143)
		(layer "In11.Cu")
		(net "P5E_CPU0_P3_TX_DP<13>")
	)
	(arc
		(start 372.923562 -278.64181)
		(mid 373.038238 -278.775144)
		(end 373.079518 -278.946102)
		(width 0.1143)
		(layer "In11.Cu")
		(net "P5E_CPU0_P3_TX_DP<13>")
	)
	(arc
		(start 372.852696 -276.051518)
		(mid 372.609369 -276.516084)
		(end 372.852696 -276.98065)
		(width 0.1143)
		(layer "In11.Cu")
		(net "P5E_CPU0_P3_TX_DP<13>")
	)
	(arc
		(start 372.923562 -277.021798)
		(mid 373.07949 -277.32609)
		(end 372.923562 -277.630382)
		(width 0.1143)
		(layer "In11.Cu")
		(net "P5E_CPU0_P3_TX_DP<13>")
	)
	(arc
		(start 373.079518 -287.045908)
		(mid 373.038263 -287.216879)
		(end 372.923562 -287.3502)
		(width 0.1143)
		(layer "In11.Cu")
		(net "P5E_CPU0_P3_TX_DP<13>")
	)
	(arc
		(start 373.54256 -274.965922)
		(mid 373.490143 -275.097853)
		(end 373.392446 -275.200872)
		(width 0.1143)
		(layer "In11.Cu")
		(net "P5E_CPU0_P3_TX_DP<13>")
	)
	(arc
		(start 387.955282 -316.839854)
		(mid 387.987869 -316.894139)
		(end 388.014972 -316.95136)
		(width 0.14224)
		(layer "In11.Cu")
		(net "P5E_CPU0_P3_TX_DP<13>")
	)
	(arc
		(start 372.855236 -287.389824)
		(mid 372.674584 -287.592569)
		(end 372.609364 -287.856168)
		(width 0.1143)
		(layer "In11.Cu")
		(net "P5E_CPU0_P3_TX_DP<13>")
	)
	(arc
		(start 372.92534 -286.74314)
		(mid 373.038747 -286.876029)
		(end 373.079518 -287.045908)
		(width 0.1143)
		(layer "In11.Cu")
		(net "P5E_CPU0_P3_TX_DP<13>")
	)
	(arc
		(start 391.82294 -375.966228)
		(mid 391.904341 -376.087863)
		(end 391.932922 -376.231404)
		(width 0.14224)
		(layer "In11.Cu")
		(net "P5E_CPU0_P3_TX_DP<13>")
	)
	(arc
		(start 373.32285 -280.101548)
		(mid 373.144037 -280.303898)
		(end 373.079518 -280.566114)
		(width 0.1143)
		(layer "In11.Cu")
		(net "P5E_CPU0_P3_TX_DP<13>")
	)
	(arc
		(start 373.079518 -295.145968)
		(mid 373.14439 -295.408931)
		(end 373.32412 -295.61155)
		(width 0.1143)
		(layer "In11.Cu")
		(net "P5E_CPU0_P3_TX_DP<13>")
	)
	(arc
		(start 372.852696 -293.871396)
		(mid 372.609369 -294.335962)
		(end 372.852696 -294.800528)
		(width 0.1143)
		(layer "In11.Cu")
		(net "P5E_CPU0_P3_TX_DP<13>")
	)
	(arc
		(start 373.079518 -280.566114)
		(mid 373.038263 -280.737085)
		(end 372.923562 -280.870406)
		(width 0.1143)
		(layer "In11.Cu")
		(net "P5E_CPU0_P3_TX_DP<13>")
	)
	(arc
		(start 372.923562 -285.121858)
		(mid 373.07949 -285.42615)
		(end 372.923562 -285.730442)
		(width 0.1143)
		(layer "In11.Cu")
		(net "P5E_CPU0_P3_TX_DP<13>")
	)
	(arc
		(start 372.923562 -283.501846)
		(mid 373.07949 -283.806138)
		(end 372.923562 -284.11043)
		(width 0.1143)
		(layer "In11.Cu")
		(net "P5E_CPU0_P3_TX_DP<13>")
	)
	(arc
		(start 372.923562 -291.601652)
		(mid 373.07949 -291.905944)
		(end 372.923562 -292.210236)
		(width 0.1143)
		(layer "In11.Cu")
		(net "P5E_CPU0_P3_TX_DP<13>")
	)
	(arc
		(start 373.079518 -275.706078)
		(mid 373.038263 -275.877049)
		(end 372.923562 -276.01037)
		(width 0.1143)
		(layer "In11.Cu")
		(net "P5E_CPU0_P3_TX_DP<13>")
	)
	(arc
		(start 372.923562 -293.221664)
		(mid 373.07949 -293.525956)
		(end 372.923562 -293.830248)
		(width 0.1143)
		(layer "In11.Cu")
		(net "P5E_CPU0_P3_TX_DP<13>")
	)
	(arc
		(start 391.966958 -373.472202)
		(mid 391.956217 -373.534535)
		(end 391.936478 -373.59463)
		(width 0.14224)
		(layer "In11.Cu")
		(net "P5E_CPU0_P3_TX_DP<13>")
	)
	(arc
		(start 373.408956 -295.663874)
		(mid 373.512606 -295.793895)
		(end 373.549672 -295.955974)
		(width 0.1143)
		(layer "In11.Cu")
		(net "P5E_CPU0_P3_TX_DP<13>")
	)
	(arc
		(start 372.852696 -289.01136)
		(mid 372.609369 -289.475926)
		(end 372.852696 -289.940492)
		(width 0.1143)
		(layer "In11.Cu")
		(net "P5E_CPU0_P3_TX_DP<13>")
	)
	(arc
		(start 372.923562 -294.841676)
		(mid 373.038238 -294.97501)
		(end 373.079518 -295.145968)
		(width 0.1143)
		(layer "In11.Cu")
		(net "P5E_CPU0_P3_TX_DP<13>")
	)
	(segment
		(start 388.509002 -378.39142)
		(end 388.213092 -378.68733)
		(width 0.12954)
		(layer "F.Cu")
		(net "P5E_CPU0_P3_TX_DP<12>")
	)
	(segment
		(start 369.888008 -276.250146)
		(end 370.35486 -276.516084)
		(width 0.12954)
		(layer "F.Cu")
		(net "P5E_CPU0_P3_TX_DP<12>")
	)
	(segment
		(start 388.238492 -377.41733)
		(end 388.509002 -377.68784)
		(width 0.12954)
		(layer "F.Cu")
		(net "P5E_CPU0_P3_TX_DP<12>")
	)
	(segment
		(start 388.509002 -377.68784)
		(end 388.509002 -378.39142)
		(width 0.12954)
		(layer "F.Cu")
		(net "P5E_CPU0_P3_TX_DP<12>")
	)
	(segment
		(start 371.982492 -284.110938)
		(end 371.952012 -284.128718)
		(width 0.1143)
		(layer "In11.Cu")
		(net "P5E_CPU0_P3_TX_DP<12>")
	)
	(segment
		(start 372.429786 -279.4381)
		(end 372.432326 -279.43937)
		(width 0.1143)
		(layer "In11.Cu")
		(net "P5E_CPU0_P3_TX_DP<12>")
	)
	(segment
		(start 388.529322 -375.854214)
		(end 388.529322 -377.1265)
		(width 0.14224)
		(layer "In11.Cu")
		(net "P5E_CPU0_P3_TX_DP<12>")
	)
	(segment
		(start 371.011958 -277.00351)
		(end 371.012212 -277.003764)
		(width 0.1143)
		(layer "In11.Cu")
		(net "P5E_CPU0_P3_TX_DP<12>")
	)
	(segment
		(start 371.952012 -278.623522)
		(end 371.982492 -278.641302)
		(width 0.1143)
		(layer "In11.Cu")
		(net "P5E_CPU0_P3_TX_DP<12>")
	)
	(segment
		(start 372.609364 -295.956228)
		(end 372.609364 -296.207688)
		(width 0.1143)
		(layer "In11.Cu")
		(net "P5E_CPU0_P3_TX_DP<12>")
	)
	(segment
		(start 372.419372 -280.080212)
		(end 372.382796 -280.101548)
		(width 0.1143)
		(layer "In11.Cu")
		(net "P5E_CPU0_P3_TX_DP<12>")
	)
	(segment
		(start 372.858538 -296.792142)
		(end 372.812818 -296.837862)
		(width 0.1143)
		(layer "In11.Cu")
		(net "P5E_CPU0_P3_TX_DP<12>")
	)
	(segment
		(start 371.952012 -286.723582)
		(end 371.984524 -286.742378)
		(width 0.1143)
		(layer "In11.Cu")
		(net "P5E_CPU0_P3_TX_DP<12>")
	)
	(segment
		(start 371.952012 -282.508706)
		(end 371.912896 -282.531566)
		(width 0.1143)
		(layer "In11.Cu")
		(net "P5E_CPU0_P3_TX_DP<12>")
	)
	(segment
		(start 371.912896 -286.700722)
		(end 371.952012 -286.723582)
		(width 0.1143)
		(layer "In11.Cu")
		(net "P5E_CPU0_P3_TX_DP<12>")
	)
	(segment
		(start 370.972842 -276.98065)
		(end 370.9797 -276.984714)
		(width 0.1143)
		(layer "In11.Cu")
		(net "P5E_CPU0_P3_TX_DP<12>")
	)
	(segment
		(start 371.952012 -280.888694)
		(end 371.912896 -280.911554)
		(width 0.1143)
		(layer "In11.Cu")
		(net "P5E_CPU0_P3_TX_DP<12>")
	)
	(segment
		(start 373.182388 -298.408344)
		(end 374.29821 -300.07814)
		(width 0.14224)
		(layer "In11.Cu")
		(net "P5E_CPU0_P3_TX_DP<12>")
	)
	(segment
		(start 370.980462 -276.985222)
		(end 371.011958 -277.00351)
		(width 0.1143)
		(layer "In11.Cu")
		(net "P5E_CPU0_P3_TX_DP<12>")
	)
	(segment
		(start 371.912896 -281.840686)
		(end 371.952012 -281.863546)
		(width 0.1143)
		(layer "In11.Cu")
		(net "P5E_CPU0_P3_TX_DP<12>")
	)
	(segment
		(start 371.952012 -294.823388)
		(end 371.982492 -294.841168)
		(width 0.1143)
		(layer "In11.Cu")
		(net "P5E_CPU0_P3_TX_DP<12>")
	)
	(segment
		(start 371.952012 -281.863546)
		(end 371.982492 -281.881326)
		(width 0.1143)
		(layer "In11.Cu")
		(net "P5E_CPU0_P3_TX_DP<12>")
	)
	(segment
		(start 372.420896 -280.079196)
		(end 372.419372 -280.080212)
		(width 0.1143)
		(layer "In11.Cu")
		(net "P5E_CPU0_P3_TX_DP<12>")
	)
	(segment
		(start 372.813326 -296.890948)
		(end 372.813326 -297.19143)
		(width 0.14224)
		(layer "In11.Cu")
		(net "P5E_CPU0_P3_TX_DP<12>")
	)
	(segment
		(start 389.083296 -322.033138)
		(end 392.86942 -340.280752)
		(width 0.14224)
		(layer "In11.Cu")
		(net "P5E_CPU0_P3_TX_DP<12>")
	)
	(segment
		(start 371.912896 -283.460698)
		(end 371.952012 -283.483558)
		(width 0.1143)
		(layer "In11.Cu")
		(net "P5E_CPU0_P3_TX_DP<12>")
	)
	(segment
		(start 371.982492 -288.97072)
		(end 371.952012 -288.9885)
		(width 0.1143)
		(layer "In11.Cu")
		(net "P5E_CPU0_P3_TX_DP<12>")
	)
	(segment
		(start 371.431566 -277.782782)
		(end 371.442234 -277.790402)
		(width 0.1143)
		(layer "In11.Cu")
		(net "P5E_CPU0_P3_TX_DP<12>")
	)
	(segment
		(start 371.952012 -285.74873)
		(end 371.912896 -285.77159)
		(width 0.1143)
		(layer "In11.Cu")
		(net "P5E_CPU0_P3_TX_DP<12>")
	)
	(segment
		(start 374.29821 -300.07814)
		(end 381.188214 -308.473602)
		(width 0.14224)
		(layer "In11.Cu")
		(net "P5E_CPU0_P3_TX_DP<12>")
	)
	(segment
		(start 371.982492 -285.73095)
		(end 371.952012 -285.74873)
		(width 0.1143)
		(layer "In11.Cu")
		(net "P5E_CPU0_P3_TX_DP<12>")
	)
	(segment
		(start 371.982492 -290.590732)
		(end 371.952012 -290.608512)
		(width 0.1143)
		(layer "In11.Cu")
		(net "P5E_CPU0_P3_TX_DP<12>")
	)
	(segment
		(start 371.912896 -289.940492)
		(end 371.952012 -289.963352)
		(width 0.1143)
		(layer "In11.Cu")
		(net "P5E_CPU0_P3_TX_DP<12>")
	)
	(segment
		(start 370.9797 -276.984714)
		(end 370.980462 -276.985222)
		(width 0.1143)
		(layer "In11.Cu")
		(net "P5E_CPU0_P3_TX_DP<12>")
	)
	(segment
		(start 371.513354 -277.831804)
		(end 371.513608 -277.831804)
		(width 0.1143)
		(layer "In11.Cu")
		(net "P5E_CPU0_P3_TX_DP<12>")
	)
	(segment
		(start 371.912896 -285.08071)
		(end 371.952012 -285.10357)
		(width 0.1143)
		(layer "In11.Cu")
		(net "P5E_CPU0_P3_TX_DP<12>")
	)
	(segment
		(start 381.188214 -308.473602)
		(end 387.18236 -317.444628)
		(width 0.14224)
		(layer "In11.Cu")
		(net "P5E_CPU0_P3_TX_DP<12>")
	)
	(segment
		(start 372.858538 -296.456862)
		(end 372.858538 -296.792142)
		(width 0.1143)
		(layer "In11.Cu")
		(net "P5E_CPU0_P3_TX_DP<12>")
	)
	(segment
		(start 371.952012 -293.848536)
		(end 371.912896 -293.871396)
		(width 0.1143)
		(layer "In11.Cu")
		(net "P5E_CPU0_P3_TX_DP<12>")
	)
	(segment
		(start 371.442234 -277.790402)
		(end 371.513354 -277.831804)
		(width 0.1143)
		(layer "In11.Cu")
		(net "P5E_CPU0_P3_TX_DP<12>")
	)
	(segment
		(start 371.912896 -288.320734)
		(end 371.952012 -288.343594)
		(width 0.1143)
		(layer "In11.Cu")
		(net "P5E_CPU0_P3_TX_DP<12>")
	)
	(segment
		(start 371.982492 -282.490926)
		(end 371.952012 -282.508706)
		(width 0.1143)
		(layer "In11.Cu")
		(net "P5E_CPU0_P3_TX_DP<12>")
	)
	(segment
		(start 371.015514 -277.005542)
		(end 371.041676 -277.020782)
		(width 0.1143)
		(layer "In11.Cu")
		(net "P5E_CPU0_P3_TX_DP<12>")
	)
	(segment
		(start 371.012212 -277.003764)
		(end 371.01272 -277.004018)
		(width 0.1143)
		(layer "In11.Cu")
		(net "P5E_CPU0_P3_TX_DP<12>")
	)
	(segment
		(start 372.812818 -296.89044)
		(end 372.813326 -296.890948)
		(width 0.14224)
		(layer "In11.Cu")
		(net "P5E_CPU0_P3_TX_DP<12>")
	)
	(segment
		(start 372.428516 -279.437338)
		(end 372.429786 -279.4381)
		(width 0.1143)
		(layer "In11.Cu")
		(net "P5E_CPU0_P3_TX_DP<12>")
	)
	(segment
		(start 372.812818 -296.86631)
		(end 372.812818 -296.89044)
		(width 0.14224)
		(layer "In11.Cu")
		(net "P5E_CPU0_P3_TX_DP<12>")
	)
	(segment
		(start 372.421912 -279.433528)
		(end 372.422674 -279.434036)
		(width 0.1143)
		(layer "In11.Cu")
		(net "P5E_CPU0_P3_TX_DP<12>")
	)
	(segment
		(start 371.912896 -291.560504)
		(end 371.952012 -291.583364)
		(width 0.1143)
		(layer "In11.Cu")
		(net "P5E_CPU0_P3_TX_DP<12>")
	)
	(segment
		(start 372.382796 -295.610534)
		(end 372.452392 -295.651174)
		(width 0.1143)
		(layer "In11.Cu")
		(net "P5E_CPU0_P3_TX_DP<12>")
	)
	(segment
		(start 372.421912 -280.078688)
		(end 372.420896 -280.079196)
		(width 0.1143)
		(layer "In11.Cu")
		(net "P5E_CPU0_P3_TX_DP<12>")
	)
	(segment
		(start 372.813326 -297.19143)
		(end 373.182388 -298.408344)
		(width 0.14224)
		(layer "In11.Cu")
		(net "P5E_CPU0_P3_TX_DP<12>")
	)
	(segment
		(start 371.912896 -294.800528)
		(end 371.952012 -294.823388)
		(width 0.1143)
		(layer "In11.Cu")
		(net "P5E_CPU0_P3_TX_DP<12>")
	)
	(segment
		(start 371.982492 -293.830756)
		(end 371.952012 -293.848536)
		(width 0.1143)
		(layer "In11.Cu")
		(net "P5E_CPU0_P3_TX_DP<12>")
	)
	(segment
		(start 372.389654 -279.414732)
		(end 372.390416 -279.41524)
		(width 0.1143)
		(layer "In11.Cu")
		(net "P5E_CPU0_P3_TX_DP<12>")
	)
	(segment
		(start 371.952012 -290.608512)
		(end 371.912896 -290.631372)
		(width 0.1143)
		(layer "In11.Cu")
		(net "P5E_CPU0_P3_TX_DP<12>")
	)
	(segment
		(start 371.912896 -293.180516)
		(end 371.952012 -293.203376)
		(width 0.1143)
		(layer "In11.Cu")
		(net "P5E_CPU0_P3_TX_DP<12>")
	)
	(segment
		(start 372.453662 -280.0604)
		(end 372.422674 -280.07818)
		(width 0.1143)
		(layer "In11.Cu")
		(net "P5E_CPU0_P3_TX_DP<12>")
	)
	(segment
		(start 372.609618 -295.955974)
		(end 372.609364 -295.956228)
		(width 0.1143)
		(layer "In11.Cu")
		(net "P5E_CPU0_P3_TX_DP<12>")
	)
	(segment
		(start 370.652802 -276.516084)
		(end 370.735606 -276.598888)
		(width 0.1143)
		(layer "In11.Cu")
		(net "P5E_CPU0_P3_TX_DP<12>")
	)
	(segment
		(start 372.425468 -279.43556)
		(end 372.42623 -279.436068)
		(width 0.1143)
		(layer "In11.Cu")
		(net "P5E_CPU0_P3_TX_DP<12>")
	)
	(segment
		(start 387.18236 -317.444628)
		(end 389.083296 -322.033138)
		(width 0.14224)
		(layer "In11.Cu")
		(net "P5E_CPU0_P3_TX_DP<12>")
	)
	(segment
		(start 371.952012 -292.228524)
		(end 371.912896 -292.251384)
		(width 0.1143)
		(layer "In11.Cu")
		(net "P5E_CPU0_P3_TX_DP<12>")
	)
	(segment
		(start 371.952012 -293.203376)
		(end 371.982492 -293.221156)
		(width 0.1143)
		(layer "In11.Cu")
		(net "P5E_CPU0_P3_TX_DP<12>")
	)
	(segment
		(start 371.952012 -284.128718)
		(end 371.912896 -284.151578)
		(width 0.1143)
		(layer "In11.Cu")
		(net "P5E_CPU0_P3_TX_DP<12>")
	)
	(segment
		(start 371.952012 -288.9885)
		(end 371.912896 -289.01136)
		(width 0.1143)
		(layer "In11.Cu")
		(net "P5E_CPU0_P3_TX_DP<12>")
	)
	(segment
		(start 371.982492 -287.350708)
		(end 371.915436 -287.389824)
		(width 0.1143)
		(layer "In11.Cu")
		(net "P5E_CPU0_P3_TX_DP<12>")
	)
	(segment
		(start 371.912896 -278.600662)
		(end 371.952012 -278.623522)
		(width 0.1143)
		(layer "In11.Cu")
		(net "P5E_CPU0_P3_TX_DP<12>")
	)
	(segment
		(start 372.432326 -279.43937)
		(end 372.453662 -279.451816)
		(width 0.1143)
		(layer "In11.Cu")
		(net "P5E_CPU0_P3_TX_DP<12>")
	)
	(segment
		(start 372.422674 -280.07818)
		(end 372.421912 -280.078688)
		(width 0.1143)
		(layer "In11.Cu")
		(net "P5E_CPU0_P3_TX_DP<12>")
	)
	(segment
		(start 372.812818 -296.837862)
		(end 372.812818 -296.86631)
		(width 0.1143)
		(layer "In11.Cu")
		(net "P5E_CPU0_P3_TX_DP<12>")
	)
	(segment
		(start 371.982492 -280.870914)
		(end 371.952012 -280.888694)
		(width 0.1143)
		(layer "In11.Cu")
		(net "P5E_CPU0_P3_TX_DP<12>")
	)
	(segment
		(start 371.952012 -289.963352)
		(end 371.982492 -289.981132)
		(width 0.1143)
		(layer "In11.Cu")
		(net "P5E_CPU0_P3_TX_DP<12>")
	)
	(segment
		(start 370.35486 -276.516084)
		(end 370.652802 -276.516084)
		(width 0.1143)
		(layer "In11.Cu")
		(net "P5E_CPU0_P3_TX_DP<12>")
	)
	(segment
		(start 371.952012 -285.10357)
		(end 371.982492 -285.12135)
		(width 0.1143)
		(layer "In11.Cu")
		(net "P5E_CPU0_P3_TX_DP<12>")
	)
	(segment
		(start 371.952012 -283.483558)
		(end 371.982492 -283.501338)
		(width 0.1143)
		(layer "In11.Cu")
		(net "P5E_CPU0_P3_TX_DP<12>")
	)
	(segment
		(start 371.01272 -277.004018)
		(end 371.015514 -277.005542)
		(width 0.1143)
		(layer "In11.Cu")
		(net "P5E_CPU0_P3_TX_DP<12>")
	)
	(segment
		(start 372.382796 -279.410668)
		(end 372.389654 -279.414732)
		(width 0.1143)
		(layer "In11.Cu")
		(net "P5E_CPU0_P3_TX_DP<12>")
	)
	(segment
		(start 392.86942 -352.398584)
		(end 388.8486 -372.61165)
		(width 0.14224)
		(layer "In11.Cu")
		(net "P5E_CPU0_P3_TX_DP<12>")
	)
	(segment
		(start 372.42623 -279.436068)
		(end 372.427754 -279.43683)
		(width 0.1143)
		(layer "In11.Cu")
		(net "P5E_CPU0_P3_TX_DP<12>")
	)
	(segment
		(start 388.529322 -377.1265)
		(end 388.238492 -377.41733)
		(width 0.14224)
		(layer "In11.Cu")
		(net "P5E_CPU0_P3_TX_DP<12>")
	)
	(segment
		(start 392.86942 -340.280752)
		(end 392.86942 -352.398584)
		(width 0.14224)
		(layer "In11.Cu")
		(net "P5E_CPU0_P3_TX_DP<12>")
	)
	(segment
		(start 371.199664 -277.32609)
		(end 371.199664 -277.329138)
		(width 0.1143)
		(layer "In11.Cu")
		(net "P5E_CPU0_P3_TX_DP<12>")
	)
	(segment
		(start 371.982492 -292.210744)
		(end 371.952012 -292.228524)
		(width 0.1143)
		(layer "In11.Cu")
		(net "P5E_CPU0_P3_TX_DP<12>")
	)
	(segment
		(start 372.427754 -279.43683)
		(end 372.428516 -279.437338)
		(width 0.1143)
		(layer "In11.Cu")
		(net "P5E_CPU0_P3_TX_DP<12>")
	)
	(segment
		(start 371.952012 -288.343594)
		(end 371.984524 -288.36239)
		(width 0.1143)
		(layer "In11.Cu")
		(net "P5E_CPU0_P3_TX_DP<12>")
	)
	(segment
		(start 372.422674 -279.434036)
		(end 372.425468 -279.43556)
		(width 0.1143)
		(layer "In11.Cu")
		(net "P5E_CPU0_P3_TX_DP<12>")
	)
	(segment
		(start 372.609364 -296.207688)
		(end 372.858538 -296.456862)
		(width 0.1143)
		(layer "In11.Cu")
		(net "P5E_CPU0_P3_TX_DP<12>")
	)
	(segment
		(start 372.390416 -279.41524)
		(end 372.421912 -279.433528)
		(width 0.1143)
		(layer "In11.Cu")
		(net "P5E_CPU0_P3_TX_DP<12>")
	)
	(segment
		(start 371.952012 -291.583364)
		(end 371.982492 -291.601144)
		(width 0.1143)
		(layer "In11.Cu")
		(net "P5E_CPU0_P3_TX_DP<12>")
	)
	(arc
		(start 371.912896 -289.01136)
		(mid 371.669569 -289.475926)
		(end 371.912896 -289.940492)
		(width 0.1143)
		(layer "In11.Cu")
		(net "P5E_CPU0_P3_TX_DP<12>")
	)
	(arc
		(start 371.912896 -292.251384)
		(mid 371.669569 -292.71595)
		(end 371.912896 -293.180516)
		(width 0.1143)
		(layer "In11.Cu")
		(net "P5E_CPU0_P3_TX_DP<12>")
	)
	(arc
		(start 371.041676 -277.020782)
		(mid 371.157723 -277.154253)
		(end 371.199664 -277.32609)
		(width 0.1143)
		(layer "In11.Cu")
		(net "P5E_CPU0_P3_TX_DP<12>")
	)
	(arc
		(start 371.982492 -293.221156)
		(mid 372.139469 -293.525956)
		(end 371.982492 -293.830756)
		(width 0.1143)
		(layer "In11.Cu")
		(net "P5E_CPU0_P3_TX_DP<12>")
	)
	(arc
		(start 371.669564 -278.136096)
		(mid 371.734079 -278.398315)
		(end 371.912896 -278.600662)
		(width 0.1143)
		(layer "In11.Cu")
		(net "P5E_CPU0_P3_TX_DP<12>")
	)
	(arc
		(start 372.382796 -280.101548)
		(mid 372.203983 -280.303898)
		(end 372.139464 -280.566114)
		(width 0.1143)
		(layer "In11.Cu")
		(net "P5E_CPU0_P3_TX_DP<12>")
	)
	(arc
		(start 371.982492 -281.881326)
		(mid 372.139469 -282.186126)
		(end 371.982492 -282.490926)
		(width 0.1143)
		(layer "In11.Cu")
		(net "P5E_CPU0_P3_TX_DP<12>")
	)
	(arc
		(start 372.468902 -295.663874)
		(mid 372.572552 -295.793895)
		(end 372.609618 -295.955974)
		(width 0.1143)
		(layer "In11.Cu")
		(net "P5E_CPU0_P3_TX_DP<12>")
	)
	(arc
		(start 372.139464 -288.66592)
		(mid 372.097915 -288.837342)
		(end 371.982492 -288.97072)
		(width 0.1143)
		(layer "In11.Cu")
		(net "P5E_CPU0_P3_TX_DP<12>")
	)
	(arc
		(start 371.669564 -287.856168)
		(mid 371.734079 -288.118387)
		(end 371.912896 -288.320734)
		(width 0.1143)
		(layer "In11.Cu")
		(net "P5E_CPU0_P3_TX_DP<12>")
	)
	(arc
		(start 372.139464 -278.946102)
		(mid 372.203979 -279.208321)
		(end 372.382796 -279.410668)
		(width 0.1143)
		(layer "In11.Cu")
		(net "P5E_CPU0_P3_TX_DP<12>")
	)
	(arc
		(start 371.915436 -287.389824)
		(mid 371.734784 -287.592569)
		(end 371.669564 -287.856168)
		(width 0.1143)
		(layer "In11.Cu")
		(net "P5E_CPU0_P3_TX_DP<12>")
	)
	(arc
		(start 372.452392 -295.651174)
		(mid 372.460735 -295.657409)
		(end 372.468902 -295.663874)
		(width 0.1143)
		(layer "In11.Cu")
		(net "P5E_CPU0_P3_TX_DP<12>")
	)
	(arc
		(start 372.453662 -279.451816)
		(mid 372.60959 -279.756108)
		(end 372.453662 -280.0604)
		(width 0.1143)
		(layer "In11.Cu")
		(net "P5E_CPU0_P3_TX_DP<12>")
	)
	(arc
		(start 371.982492 -278.641302)
		(mid 372.097919 -278.774678)
		(end 372.139464 -278.946102)
		(width 0.1143)
		(layer "In11.Cu")
		(net "P5E_CPU0_P3_TX_DP<12>")
	)
	(arc
		(start 371.912896 -285.77159)
		(mid 371.669569 -286.236156)
		(end 371.912896 -286.700722)
		(width 0.1143)
		(layer "In11.Cu")
		(net "P5E_CPU0_P3_TX_DP<12>")
	)
	(arc
		(start 371.912896 -290.631372)
		(mid 371.669569 -291.095938)
		(end 371.912896 -291.560504)
		(width 0.1143)
		(layer "In11.Cu")
		(net "P5E_CPU0_P3_TX_DP<12>")
	)
	(arc
		(start 372.139464 -295.145968)
		(mid 372.203979 -295.408187)
		(end 372.382796 -295.610534)
		(width 0.1143)
		(layer "In11.Cu")
		(net "P5E_CPU0_P3_TX_DP<12>")
	)
	(arc
		(start 388.8486 -372.61165)
		(mid 388.609307 -374.225089)
		(end 388.529322 -375.854214)
		(width 0.14224)
		(layer "In11.Cu")
		(net "P5E_CPU0_P3_TX_DP<12>")
	)
	(arc
		(start 372.139464 -287.045908)
		(mid 372.097915 -287.21733)
		(end 371.982492 -287.350708)
		(width 0.1143)
		(layer "In11.Cu")
		(net "P5E_CPU0_P3_TX_DP<12>")
	)
	(arc
		(start 371.982492 -283.501338)
		(mid 372.139469 -283.806138)
		(end 371.982492 -284.110938)
		(width 0.1143)
		(layer "In11.Cu")
		(net "P5E_CPU0_P3_TX_DP<12>")
	)
	(arc
		(start 371.912896 -293.871396)
		(mid 371.669569 -294.335962)
		(end 371.912896 -294.800528)
		(width 0.1143)
		(layer "In11.Cu")
		(net "P5E_CPU0_P3_TX_DP<12>")
	)
	(arc
		(start 372.139464 -280.566114)
		(mid 372.097915 -280.737536)
		(end 371.982492 -280.870914)
		(width 0.1143)
		(layer "In11.Cu")
		(net "P5E_CPU0_P3_TX_DP<12>")
	)
	(arc
		(start 371.984524 -288.36239)
		(mid 372.098453 -288.495537)
		(end 372.139464 -288.66592)
		(width 0.1143)
		(layer "In11.Cu")
		(net "P5E_CPU0_P3_TX_DP<12>")
	)
	(arc
		(start 371.513608 -277.831804)
		(mid 371.628284 -277.965138)
		(end 371.669564 -278.136096)
		(width 0.1143)
		(layer "In11.Cu")
		(net "P5E_CPU0_P3_TX_DP<12>")
	)
	(arc
		(start 371.984524 -286.742378)
		(mid 372.098453 -286.875525)
		(end 372.139464 -287.045908)
		(width 0.1143)
		(layer "In11.Cu")
		(net "P5E_CPU0_P3_TX_DP<12>")
	)
	(arc
		(start 370.739416 -276.621748)
		(mid 370.820849 -276.824146)
		(end 370.972842 -276.98065)
		(width 0.1143)
		(layer "In11.Cu")
		(net "P5E_CPU0_P3_TX_DP<12>")
	)
	(arc
		(start 371.199664 -277.329138)
		(mid 371.260954 -277.583897)
		(end 371.431566 -277.782782)
		(width 0.1143)
		(layer "In11.Cu")
		(net "P5E_CPU0_P3_TX_DP<12>")
	)
	(arc
		(start 371.982492 -285.12135)
		(mid 372.139469 -285.42615)
		(end 371.982492 -285.73095)
		(width 0.1143)
		(layer "In11.Cu")
		(net "P5E_CPU0_P3_TX_DP<12>")
	)
	(arc
		(start 371.912896 -282.531566)
		(mid 371.669569 -282.996132)
		(end 371.912896 -283.460698)
		(width 0.1143)
		(layer "In11.Cu")
		(net "P5E_CPU0_P3_TX_DP<12>")
	)
	(arc
		(start 371.982492 -291.601144)
		(mid 372.139469 -291.905944)
		(end 371.982492 -292.210744)
		(width 0.1143)
		(layer "In11.Cu")
		(net "P5E_CPU0_P3_TX_DP<12>")
	)
	(arc
		(start 371.912896 -280.911554)
		(mid 371.669569 -281.37612)
		(end 371.912896 -281.840686)
		(width 0.1143)
		(layer "In11.Cu")
		(net "P5E_CPU0_P3_TX_DP<12>")
	)
	(arc
		(start 370.735606 -276.598888)
		(mid 370.737394 -276.610337)
		(end 370.739416 -276.621748)
		(width 0.1143)
		(layer "In11.Cu")
		(net "P5E_CPU0_P3_TX_DP<12>")
	)
	(arc
		(start 371.912896 -284.151578)
		(mid 371.669569 -284.616144)
		(end 371.912896 -285.08071)
		(width 0.1143)
		(layer "In11.Cu")
		(net "P5E_CPU0_P3_TX_DP<12>")
	)
	(arc
		(start 371.982492 -289.981132)
		(mid 372.139469 -290.285932)
		(end 371.982492 -290.590732)
		(width 0.1143)
		(layer "In11.Cu")
		(net "P5E_CPU0_P3_TX_DP<12>")
	)
	(arc
		(start 371.982492 -294.841168)
		(mid 372.097919 -294.974544)
		(end 372.139464 -295.145968)
		(width 0.1143)
		(layer "In11.Cu")
		(net "P5E_CPU0_P3_TX_DP<12>")
	)
	(segment
		(start 386.807202 -380.15164)
		(end 386.807202 -380.85522)
		(width 0.12954)
		(layer "F.Cu")
		(net "P5E_CPU0_P3_TX_DP<11>")
	)
	(segment
		(start 386.807202 -380.85522)
		(end 386.511292 -381.15113)
		(width 0.12954)
		(layer "F.Cu")
		(net "P5E_CPU0_P3_TX_DP<11>")
	)
	(segment
		(start 386.536692 -379.88113)
		(end 386.807202 -380.15164)
		(width 0.12954)
		(layer "F.Cu")
		(net "P5E_CPU0_P3_TX_DP<11>")
	)
	(segment
		(start 369.888008 -277.870158)
		(end 370.35486 -278.136096)
		(width 0.12954)
		(layer "F.Cu")
		(net "P5E_CPU0_P3_TX_DP<11>")
	)
	(segment
		(start 371.01272 -281.864054)
		(end 371.014752 -281.865324)
		(width 0.1143)
		(layer "In11.Cu")
		(net "P5E_CPU0_P3_TX_DP<11>")
	)
	(segment
		(start 370.978938 -288.32429)
		(end 370.979192 -288.32429)
		(width 0.1143)
		(layer "In11.Cu")
		(net "P5E_CPU0_P3_TX_DP<11>")
	)
	(segment
		(start 371.011958 -289.963352)
		(end 371.01272 -289.96386)
		(width 0.1143)
		(layer "In11.Cu")
		(net "P5E_CPU0_P3_TX_DP<11>")
	)
	(segment
		(start 371.015006 -293.846758)
		(end 371.01272 -293.848282)
		(width 0.1143)
		(layer "In11.Cu")
		(net "P5E_CPU0_P3_TX_DP<11>")
	)
	(segment
		(start 371.010942 -282.509214)
		(end 370.972842 -282.531566)
		(width 0.1143)
		(layer "In11.Cu")
		(net "P5E_CPU0_P3_TX_DP<11>")
	)
	(segment
		(start 370.35486 -278.136096)
		(end 370.652802 -278.136096)
		(width 0.1143)
		(layer "In11.Cu")
		(net "P5E_CPU0_P3_TX_DP<11>")
	)
	(segment
		(start 371.01272 -285.104078)
		(end 371.014752 -285.105348)
		(width 0.1143)
		(layer "In11.Cu")
		(net "P5E_CPU0_P3_TX_DP<11>")
	)
	(segment
		(start 371.007386 -292.231318)
		(end 371.00637 -292.231826)
		(width 0.1143)
		(layer "In11.Cu")
		(net "P5E_CPU0_P3_TX_DP<11>")
	)
	(segment
		(start 371.011958 -285.74873)
		(end 371.010942 -285.749238)
		(width 0.1143)
		(layer "In11.Cu")
		(net "P5E_CPU0_P3_TX_DP<11>")
	)
	(segment
		(start 371.011958 -293.848536)
		(end 371.010942 -293.849044)
		(width 0.1143)
		(layer "In11.Cu")
		(net "P5E_CPU0_P3_TX_DP<11>")
	)
	(segment
		(start 371.011958 -278.623522)
		(end 371.01272 -278.62403)
		(width 0.1143)
		(layer "In11.Cu")
		(net "P5E_CPU0_P3_TX_DP<11>")
	)
	(segment
		(start 371.01272 -291.583872)
		(end 371.043708 -291.601652)
		(width 0.1143)
		(layer "In11.Cu")
		(net "P5E_CPU0_P3_TX_DP<11>")
	)
	(segment
		(start 371.01272 -293.848282)
		(end 371.011958 -293.848536)
		(width 0.1143)
		(layer "In11.Cu")
		(net "P5E_CPU0_P3_TX_DP<11>")
	)
	(segment
		(start 371.043708 -291.601652)
		(end 371.048788 -291.605208)
		(width 0.1143)
		(layer "In11.Cu")
		(net "P5E_CPU0_P3_TX_DP<11>")
	)
	(segment
		(start 370.972842 -283.460698)
		(end 370.9797 -283.464762)
		(width 0.1143)
		(layer "In11.Cu")
		(net "P5E_CPU0_P3_TX_DP<11>")
	)
	(segment
		(start 371.01272 -290.608258)
		(end 371.011958 -290.608512)
		(width 0.1143)
		(layer "In11.Cu")
		(net "P5E_CPU0_P3_TX_DP<11>")
	)
	(segment
		(start 371.014752 -285.105348)
		(end 371.01526 -285.105348)
		(width 0.1143)
		(layer "In11.Cu")
		(net "P5E_CPU0_P3_TX_DP<11>")
	)
	(segment
		(start 371.01272 -278.623776)
		(end 371.013736 -278.624284)
		(width 0.1143)
		(layer "In11.Cu")
		(net "P5E_CPU0_P3_TX_DP<11>")
	)
	(segment
		(start 371.199664 -287.045908)
		(end 371.199664 -287.05048)
		(width 0.1143)
		(layer "In11.Cu")
		(net "P5E_CPU0_P3_TX_DP<11>")
	)
	(segment
		(start 371.014752 -283.485336)
		(end 371.01526 -283.485336)
		(width 0.1143)
		(layer "In11.Cu")
		(net "P5E_CPU0_P3_TX_DP<11>")
	)
	(segment
		(start 371.187726 -280.574496)
		(end 371.187726 -280.585926)
		(width 0.1143)
		(layer "In11.Cu")
		(net "P5E_CPU0_P3_TX_DP<11>")
	)
	(segment
		(start 371.48262 -295.633902)
		(end 371.513608 -295.651682)
		(width 0.1143)
		(layer "In11.Cu")
		(net "P5E_CPU0_P3_TX_DP<11>")
	)
	(segment
		(start 370.9797 -278.604726)
		(end 370.980462 -278.605234)
		(width 0.1143)
		(layer "In11.Cu")
		(net "P5E_CPU0_P3_TX_DP<11>")
	)
	(segment
		(start 371.011958 -288.9885)
		(end 371.010942 -288.989008)
		(width 0.1143)
		(layer "In11.Cu")
		(net "P5E_CPU0_P3_TX_DP<11>")
	)
	(segment
		(start 371.014498 -294.824658)
		(end 371.044724 -294.842692)
		(width 0.1143)
		(layer "In11.Cu")
		(net "P5E_CPU0_P3_TX_DP<11>")
	)
	(segment
		(start 370.652802 -278.136096)
		(end 370.735606 -278.2189)
		(width 0.1143)
		(layer "In11.Cu")
		(net "P5E_CPU0_P3_TX_DP<11>")
	)
	(segment
		(start 371.015514 -284.12694)
		(end 371.015006 -284.12694)
		(width 0.1143)
		(layer "In11.Cu")
		(net "P5E_CPU0_P3_TX_DP<11>")
	)
	(segment
		(start 371.010942 -291.582856)
		(end 371.011958 -291.583364)
		(width 0.1143)
		(layer "In11.Cu")
		(net "P5E_CPU0_P3_TX_DP<11>")
	)
	(segment
		(start 371.015514 -293.846758)
		(end 371.015006 -293.846758)
		(width 0.1143)
		(layer "In11.Cu")
		(net "P5E_CPU0_P3_TX_DP<11>")
	)
	(segment
		(start 371.442742 -295.610534)
		(end 371.480842 -295.632886)
		(width 0.1143)
		(layer "In11.Cu")
		(net "P5E_CPU0_P3_TX_DP<11>")
	)
	(segment
		(start 371.00637 -292.231826)
		(end 370.972842 -292.251384)
		(width 0.1143)
		(layer "In11.Cu")
		(net "P5E_CPU0_P3_TX_DP<11>")
	)
	(segment
		(start 386.827522 -379.5903)
		(end 386.536692 -379.88113)
		(width 0.14224)
		(layer "In11.Cu")
		(net "P5E_CPU0_P3_TX_DP<11>")
	)
	(segment
		(start 371.014752 -289.96513)
		(end 371.01526 -289.96513)
		(width 0.1143)
		(layer "In11.Cu")
		(net "P5E_CPU0_P3_TX_DP<11>")
	)
	(segment
		(start 370.972842 -281.840686)
		(end 371.010942 -281.863038)
		(width 0.1143)
		(layer "In11.Cu")
		(net "P5E_CPU0_P3_TX_DP<11>")
	)
	(segment
		(start 371.010942 -281.863038)
		(end 371.011958 -281.863546)
		(width 0.1143)
		(layer "In11.Cu")
		(net "P5E_CPU0_P3_TX_DP<11>")
	)
	(segment
		(start 370.980462 -283.46527)
		(end 371.011958 -283.483558)
		(width 0.1143)
		(layer "In11.Cu")
		(net "P5E_CPU0_P3_TX_DP<11>")
	)
	(segment
		(start 371.669564 -296.207942)
		(end 371.913658 -296.452036)
		(width 0.1143)
		(layer "In11.Cu")
		(net "P5E_CPU0_P3_TX_DP<11>")
	)
	(segment
		(start 371.01272 -285.748476)
		(end 371.011958 -285.74873)
		(width 0.1143)
		(layer "In11.Cu")
		(net "P5E_CPU0_P3_TX_DP<11>")
	)
	(segment
		(start 371.01272 -288.988246)
		(end 371.011958 -288.9885)
		(width 0.1143)
		(layer "In11.Cu")
		(net "P5E_CPU0_P3_TX_DP<11>")
	)
	(segment
		(start 370.972842 -293.180516)
		(end 371.010942 -293.202868)
		(width 0.1143)
		(layer "In11.Cu")
		(net "P5E_CPU0_P3_TX_DP<11>")
	)
	(segment
		(start 370.9797 -283.464762)
		(end 370.980462 -283.46527)
		(width 0.1143)
		(layer "In11.Cu")
		(net "P5E_CPU0_P3_TX_DP<11>")
	)
	(segment
		(start 371.011958 -281.863546)
		(end 371.01272 -281.864054)
		(width 0.1143)
		(layer "In11.Cu")
		(net "P5E_CPU0_P3_TX_DP<11>")
	)
	(segment
		(start 371.480842 -295.632886)
		(end 371.481858 -295.633394)
		(width 0.1143)
		(layer "In11.Cu")
		(net "P5E_CPU0_P3_TX_DP<11>")
	)
	(segment
		(start 371.015514 -282.506928)
		(end 371.015006 -282.506928)
		(width 0.1143)
		(layer "In11.Cu")
		(net "P5E_CPU0_P3_TX_DP<11>")
	)
	(segment
		(start 371.043708 -287.3502)
		(end 370.975382 -287.389824)
		(width 0.1143)
		(layer "In11.Cu")
		(net "P5E_CPU0_P3_TX_DP<11>")
	)
	(segment
		(start 371.01272 -293.203884)
		(end 371.014752 -293.205154)
		(width 0.1143)
		(layer "In11.Cu")
		(net "P5E_CPU0_P3_TX_DP<11>")
	)
	(segment
		(start 386.827522 -376.277632)
		(end 386.827522 -379.5903)
		(width 0.14224)
		(layer "In11.Cu")
		(net "P5E_CPU0_P3_TX_DP<11>")
	)
	(segment
		(start 371.01272 -289.96386)
		(end 371.014752 -289.96513)
		(width 0.1143)
		(layer "In11.Cu")
		(net "P5E_CPU0_P3_TX_DP<11>")
	)
	(segment
		(start 371.010942 -284.129226)
		(end 370.972842 -284.151578)
		(width 0.1143)
		(layer "In11.Cu")
		(net "P5E_CPU0_P3_TX_DP<11>")
	)
	(segment
		(start 371.047518 -287.347406)
		(end 371.043708 -287.3502)
		(width 0.1143)
		(layer "In11.Cu")
		(net "P5E_CPU0_P3_TX_DP<11>")
	)
	(segment
		(start 373.562372 -300.679358)
		(end 380.421134 -309.036466)
		(width 0.14224)
		(layer "In11.Cu")
		(net "P5E_CPU0_P3_TX_DP<11>")
	)
	(segment
		(start 370.972842 -289.940492)
		(end 371.010942 -289.962844)
		(width 0.1143)
		(layer "In11.Cu")
		(net "P5E_CPU0_P3_TX_DP<11>")
	)
	(segment
		(start 371.010942 -280.889202)
		(end 370.972842 -280.911554)
		(width 0.1143)
		(layer "In11.Cu")
		(net "P5E_CPU0_P3_TX_DP<11>")
	)
	(segment
		(start 371.482112 -279.433528)
		(end 371.513608 -279.45207)
		(width 0.1143)
		(layer "In11.Cu")
		(net "P5E_CPU0_P3_TX_DP<11>")
	)
	(segment
		(start 371.011958 -280.888694)
		(end 371.010942 -280.889202)
		(width 0.1143)
		(layer "In11.Cu")
		(net "P5E_CPU0_P3_TX_DP<11>")
	)
	(segment
		(start 371.015006 -284.12694)
		(end 371.01272 -284.128464)
		(width 0.1143)
		(layer "In11.Cu")
		(net "P5E_CPU0_P3_TX_DP<11>")
	)
	(segment
		(start 371.669564 -295.955974)
		(end 371.669564 -296.207942)
		(width 0.1143)
		(layer "In11.Cu")
		(net "P5E_CPU0_P3_TX_DP<11>")
	)
	(segment
		(start 371.01272 -278.62403)
		(end 371.01272 -278.623776)
		(width 0.1143)
		(layer "In11.Cu")
		(net "P5E_CPU0_P3_TX_DP<11>")
	)
	(segment
		(start 371.043708 -292.210236)
		(end 371.01272 -292.228016)
		(width 0.1143)
		(layer "In11.Cu")
		(net "P5E_CPU0_P3_TX_DP<11>")
	)
	(segment
		(start 371.010942 -285.103062)
		(end 371.011958 -285.10357)
		(width 0.1143)
		(layer "In11.Cu")
		(net "P5E_CPU0_P3_TX_DP<11>")
	)
	(segment
		(start 371.011958 -292.228524)
		(end 371.010942 -292.229032)
		(width 0.1143)
		(layer "In11.Cu")
		(net "P5E_CPU0_P3_TX_DP<11>")
	)
	(segment
		(start 371.014752 -293.205154)
		(end 371.01526 -293.205154)
		(width 0.1143)
		(layer "In11.Cu")
		(net "P5E_CPU0_P3_TX_DP<11>")
	)
	(segment
		(start 371.01272 -284.128464)
		(end 371.011958 -284.128718)
		(width 0.1143)
		(layer "In11.Cu")
		(net "P5E_CPU0_P3_TX_DP<11>")
	)
	(segment
		(start 371.015514 -290.606734)
		(end 371.015006 -290.606734)
		(width 0.1143)
		(layer "In11.Cu")
		(net "P5E_CPU0_P3_TX_DP<11>")
	)
	(segment
		(start 371.048788 -292.20668)
		(end 371.043708 -292.210236)
		(width 0.1143)
		(layer "In11.Cu")
		(net "P5E_CPU0_P3_TX_DP<11>")
	)
	(segment
		(start 371.199664 -295.14165)
		(end 371.199664 -295.145968)
		(width 0.1143)
		(layer "In11.Cu")
		(net "P5E_CPU0_P3_TX_DP<11>")
	)
	(segment
		(start 370.972842 -286.700722)
		(end 371.045486 -286.74314)
		(width 0.1143)
		(layer "In11.Cu")
		(net "P5E_CPU0_P3_TX_DP<11>")
	)
	(segment
		(start 370.972842 -294.800528)
		(end 371.010942 -294.82288)
		(width 0.1143)
		(layer "In11.Cu")
		(net "P5E_CPU0_P3_TX_DP<11>")
	)
	(segment
		(start 371.867938 -296.905172)
		(end 371.868446 -296.90568)
		(width 0.14224)
		(layer "In11.Cu")
		(net "P5E_CPU0_P3_TX_DP<11>")
	)
	(segment
		(start 371.867938 -296.837862)
		(end 371.867938 -296.86631)
		(width 0.1143)
		(layer "In11.Cu")
		(net "P5E_CPU0_P3_TX_DP<11>")
	)
	(segment
		(start 370.980462 -278.605234)
		(end 371.011958 -278.623522)
		(width 0.1143)
		(layer "In11.Cu")
		(net "P5E_CPU0_P3_TX_DP<11>")
	)
	(segment
		(start 371.010942 -285.749238)
		(end 370.972842 -285.77159)
		(width 0.1143)
		(layer "In11.Cu")
		(net "P5E_CPU0_P3_TX_DP<11>")
	)
	(segment
		(start 380.421134 -309.036466)
		(end 386.339588 -317.893954)
		(width 0.14224)
		(layer "In11.Cu")
		(net "P5E_CPU0_P3_TX_DP<11>")
	)
	(segment
		(start 371.013736 -278.624284)
		(end 371.027452 -278.632158)
		(width 0.1143)
		(layer "In11.Cu")
		(net "P5E_CPU0_P3_TX_DP<11>")
	)
	(segment
		(start 371.199664 -295.145968)
		(end 371.19941 -295.145968)
		(width 0.1143)
		(layer "In11.Cu")
		(net "P5E_CPU0_P3_TX_DP<11>")
	)
	(segment
		(start 371.00891 -292.230302)
		(end 371.007386 -292.231318)
		(width 0.1143)
		(layer "In11.Cu")
		(net "P5E_CPU0_P3_TX_DP<11>")
	)
	(segment
		(start 371.011958 -285.10357)
		(end 371.01272 -285.104078)
		(width 0.1143)
		(layer "In11.Cu")
		(net "P5E_CPU0_P3_TX_DP<11>")
	)
	(segment
		(start 371.015514 -285.746952)
		(end 371.015006 -285.746952)
		(width 0.1143)
		(layer "In11.Cu")
		(net "P5E_CPU0_P3_TX_DP<11>")
	)
	(segment
		(start 371.010942 -292.229032)
		(end 371.00891 -292.230302)
		(width 0.1143)
		(layer "In11.Cu")
		(net "P5E_CPU0_P3_TX_DP<11>")
	)
	(segment
		(start 371.015514 -288.986722)
		(end 371.015006 -288.986722)
		(width 0.1143)
		(layer "In11.Cu")
		(net "P5E_CPU0_P3_TX_DP<11>")
	)
	(segment
		(start 391.80516 -340.545166)
		(end 391.80516 -352.674428)
		(width 0.14224)
		(layer "In11.Cu")
		(net "P5E_CPU0_P3_TX_DP<11>")
	)
	(segment
		(start 371.015006 -282.506928)
		(end 371.01272 -282.508452)
		(width 0.1143)
		(layer "In11.Cu")
		(net "P5E_CPU0_P3_TX_DP<11>")
	)
	(segment
		(start 371.212364 -278.953468)
		(end 371.212364 -278.965914)
		(width 0.1143)
		(layer "In11.Cu")
		(net "P5E_CPU0_P3_TX_DP<11>")
	)
	(segment
		(start 386.339588 -317.893954)
		(end 388.186676 -322.352924)
		(width 0.14224)
		(layer "In11.Cu")
		(net "P5E_CPU0_P3_TX_DP<11>")
	)
	(segment
		(start 371.913658 -296.792142)
		(end 371.867938 -296.837862)
		(width 0.1143)
		(layer "In11.Cu")
		(net "P5E_CPU0_P3_TX_DP<11>")
	)
	(segment
		(start 371.481858 -295.633394)
		(end 371.48262 -295.633902)
		(width 0.1143)
		(layer "In11.Cu")
		(net "P5E_CPU0_P3_TX_DP<11>")
	)
	(segment
		(start 371.011958 -284.128718)
		(end 371.010942 -284.129226)
		(width 0.1143)
		(layer "In11.Cu")
		(net "P5E_CPU0_P3_TX_DP<11>")
	)
	(segment
		(start 371.513608 -280.0604)
		(end 371.468904 -280.086308)
		(width 0.1143)
		(layer "In11.Cu")
		(net "P5E_CPU0_P3_TX_DP<11>")
	)
	(segment
		(start 371.010942 -293.202868)
		(end 371.011958 -293.203376)
		(width 0.1143)
		(layer "In11.Cu")
		(net "P5E_CPU0_P3_TX_DP<11>")
	)
	(segment
		(start 371.868446 -297.314366)
		(end 372.32971 -298.834556)
		(width 0.14224)
		(layer "In11.Cu")
		(net "P5E_CPU0_P3_TX_DP<11>")
	)
	(segment
		(start 371.011958 -290.608512)
		(end 371.010942 -290.60902)
		(width 0.1143)
		(layer "In11.Cu")
		(net "P5E_CPU0_P3_TX_DP<11>")
	)
	(segment
		(start 370.972842 -288.320734)
		(end 370.978938 -288.32429)
		(width 0.1143)
		(layer "In11.Cu")
		(net "P5E_CPU0_P3_TX_DP<11>")
	)
	(segment
		(start 388.186676 -322.352924)
		(end 391.80516 -340.545166)
		(width 0.14224)
		(layer "In11.Cu")
		(net "P5E_CPU0_P3_TX_DP<11>")
	)
	(segment
		(start 371.015006 -288.986722)
		(end 371.01272 -288.988246)
		(width 0.1143)
		(layer "In11.Cu")
		(net "P5E_CPU0_P3_TX_DP<11>")
	)
	(segment
		(start 371.01272 -292.228016)
		(end 371.011958 -292.228524)
		(width 0.1143)
		(layer "In11.Cu")
		(net "P5E_CPU0_P3_TX_DP<11>")
	)
	(segment
		(start 372.32971 -298.834556)
		(end 373.562372 -300.679358)
		(width 0.14224)
		(layer "In11.Cu")
		(net "P5E_CPU0_P3_TX_DP<11>")
	)
	(segment
		(start 371.010942 -293.849044)
		(end 370.972842 -293.871396)
		(width 0.1143)
		(layer "In11.Cu")
		(net "P5E_CPU0_P3_TX_DP<11>")
	)
	(segment
		(start 371.868446 -296.90568)
		(end 371.868446 -297.314366)
		(width 0.14224)
		(layer "In11.Cu")
		(net "P5E_CPU0_P3_TX_DP<11>")
	)
	(segment
		(start 371.010942 -288.989008)
		(end 370.972842 -289.01136)
		(width 0.1143)
		(layer "In11.Cu")
		(net "P5E_CPU0_P3_TX_DP<11>")
	)
	(segment
		(start 371.010942 -290.60902)
		(end 370.972842 -290.631372)
		(width 0.1143)
		(layer "In11.Cu")
		(net "P5E_CPU0_P3_TX_DP<11>")
	)
	(segment
		(start 371.011958 -293.203376)
		(end 371.01272 -293.203884)
		(width 0.1143)
		(layer "In11.Cu")
		(net "P5E_CPU0_P3_TX_DP<11>")
	)
	(segment
		(start 371.01272 -283.484066)
		(end 371.014752 -283.485336)
		(width 0.1143)
		(layer "In11.Cu")
		(net "P5E_CPU0_P3_TX_DP<11>")
	)
	(segment
		(start 371.011958 -291.583364)
		(end 371.01272 -291.583872)
		(width 0.1143)
		(layer "In11.Cu")
		(net "P5E_CPU0_P3_TX_DP<11>")
	)
	(segment
		(start 387.991604 -371.846856)
		(end 386.998972 -375.120154)
		(width 0.14224)
		(layer "In11.Cu")
		(net "P5E_CPU0_P3_TX_DP<11>")
	)
	(segment
		(start 371.015006 -288.345118)
		(end 371.01526 -288.345118)
		(width 0.1143)
		(layer "In11.Cu")
		(net "P5E_CPU0_P3_TX_DP<11>")
	)
	(segment
		(start 371.015006 -290.606734)
		(end 371.01272 -290.608258)
		(width 0.1143)
		(layer "In11.Cu")
		(net "P5E_CPU0_P3_TX_DP<11>")
	)
	(segment
		(start 371.011958 -283.483558)
		(end 371.01272 -283.484066)
		(width 0.1143)
		(layer "In11.Cu")
		(net "P5E_CPU0_P3_TX_DP<11>")
	)
	(segment
		(start 371.913658 -296.452036)
		(end 371.913658 -296.792142)
		(width 0.1143)
		(layer "In11.Cu")
		(net "P5E_CPU0_P3_TX_DP<11>")
	)
	(segment
		(start 371.01272 -280.888186)
		(end 371.011958 -280.888694)
		(width 0.1143)
		(layer "In11.Cu")
		(net "P5E_CPU0_P3_TX_DP<11>")
	)
	(segment
		(start 391.80516 -352.674428)
		(end 387.991604 -371.846856)
		(width 0.14224)
		(layer "In11.Cu")
		(net "P5E_CPU0_P3_TX_DP<11>")
	)
	(segment
		(start 371.014752 -281.865324)
		(end 371.01526 -281.865324)
		(width 0.1143)
		(layer "In11.Cu")
		(net "P5E_CPU0_P3_TX_DP<11>")
	)
	(segment
		(start 370.979192 -288.32429)
		(end 371.015006 -288.345118)
		(width 0.1143)
		(layer "In11.Cu")
		(net "P5E_CPU0_P3_TX_DP<11>")
	)
	(segment
		(start 371.010942 -289.962844)
		(end 371.011958 -289.963352)
		(width 0.1143)
		(layer "In11.Cu")
		(net "P5E_CPU0_P3_TX_DP<11>")
	)
	(segment
		(start 370.972842 -285.08071)
		(end 371.010942 -285.103062)
		(width 0.1143)
		(layer "In11.Cu")
		(net "P5E_CPU0_P3_TX_DP<11>")
	)
	(segment
		(start 371.01272 -282.508452)
		(end 371.011958 -282.508706)
		(width 0.1143)
		(layer "In11.Cu")
		(net "P5E_CPU0_P3_TX_DP<11>")
	)
	(segment
		(start 371.015006 -285.746952)
		(end 371.01272 -285.748476)
		(width 0.1143)
		(layer "In11.Cu")
		(net "P5E_CPU0_P3_TX_DP<11>")
	)
	(segment
		(start 371.011958 -282.508706)
		(end 371.010942 -282.509214)
		(width 0.1143)
		(layer "In11.Cu")
		(net "P5E_CPU0_P3_TX_DP<11>")
	)
	(segment
		(start 370.972842 -278.600662)
		(end 370.9797 -278.604726)
		(width 0.1143)
		(layer "In11.Cu")
		(net "P5E_CPU0_P3_TX_DP<11>")
	)
	(segment
		(start 371.010942 -294.82288)
		(end 371.014498 -294.824658)
		(width 0.1143)
		(layer "In11.Cu")
		(net "P5E_CPU0_P3_TX_DP<11>")
	)
	(segment
		(start 371.867938 -296.86631)
		(end 371.867938 -296.905172)
		(width 0.14224)
		(layer "In11.Cu")
		(net "P5E_CPU0_P3_TX_DP<11>")
	)
	(segment
		(start 370.972842 -291.560504)
		(end 371.010942 -291.582856)
		(width 0.1143)
		(layer "In11.Cu")
		(net "P5E_CPU0_P3_TX_DP<11>")
	)
	(arc
		(start 370.739416 -278.24176)
		(mid 370.820849 -278.444158)
		(end 370.972842 -278.600662)
		(width 0.1143)
		(layer "In11.Cu")
		(net "P5E_CPU0_P3_TX_DP<11>")
	)
	(arc
		(start 371.187726 -280.585926)
		(mid 371.140815 -280.760555)
		(end 371.01272 -280.888186)
		(width 0.1143)
		(layer "In11.Cu")
		(net "P5E_CPU0_P3_TX_DP<11>")
	)
	(arc
		(start 371.513608 -295.651682)
		(mid 371.628284 -295.785016)
		(end 371.669564 -295.955974)
		(width 0.1143)
		(layer "In11.Cu")
		(net "P5E_CPU0_P3_TX_DP<11>")
	)
	(arc
		(start 371.01526 -293.205154)
		(mid 371.199993 -293.525846)
		(end 371.015514 -293.846758)
		(width 0.1143)
		(layer "In11.Cu")
		(net "P5E_CPU0_P3_TX_DP<11>")
	)
	(arc
		(start 386.998972 -375.120154)
		(mid 386.87056 -375.692571)
		(end 386.827522 -376.277632)
		(width 0.14224)
		(layer "In11.Cu")
		(net "P5E_CPU0_P3_TX_DP<11>")
	)
	(arc
		(start 370.735606 -278.2189)
		(mid 370.737394 -278.230349)
		(end 370.739416 -278.24176)
		(width 0.1143)
		(layer "In11.Cu")
		(net "P5E_CPU0_P3_TX_DP<11>")
	)
	(arc
		(start 370.972842 -292.251384)
		(mid 370.729515 -292.71595)
		(end 370.972842 -293.180516)
		(width 0.1143)
		(layer "In11.Cu")
		(net "P5E_CPU0_P3_TX_DP<11>")
	)
	(arc
		(start 370.72951 -287.856168)
		(mid 370.794025 -288.118387)
		(end 370.972842 -288.320734)
		(width 0.1143)
		(layer "In11.Cu")
		(net "P5E_CPU0_P3_TX_DP<11>")
	)
	(arc
		(start 371.649244 -279.634442)
		(mid 371.651865 -279.869851)
		(end 371.513608 -280.0604)
		(width 0.1143)
		(layer "In11.Cu")
		(net "P5E_CPU0_P3_TX_DP<11>")
	)
	(arc
		(start 370.972842 -284.151578)
		(mid 370.729515 -284.616144)
		(end 370.972842 -285.08071)
		(width 0.1143)
		(layer "In11.Cu")
		(net "P5E_CPU0_P3_TX_DP<11>")
	)
	(arc
		(start 371.01526 -285.105348)
		(mid 371.199993 -285.42604)
		(end 371.015514 -285.746952)
		(width 0.1143)
		(layer "In11.Cu")
		(net "P5E_CPU0_P3_TX_DP<11>")
	)
	(arc
		(start 371.048788 -291.605208)
		(mid 371.202886 -291.905944)
		(end 371.048788 -292.20668)
		(width 0.1143)
		(layer "In11.Cu")
		(net "P5E_CPU0_P3_TX_DP<11>")
	)
	(arc
		(start 371.19941 -295.145968)
		(mid 371.263925 -295.408187)
		(end 371.442742 -295.610534)
		(width 0.1143)
		(layer "In11.Cu")
		(net "P5E_CPU0_P3_TX_DP<11>")
	)
	(arc
		(start 371.045486 -286.74314)
		(mid 371.158893 -286.876029)
		(end 371.199664 -287.045908)
		(width 0.1143)
		(layer "In11.Cu")
		(net "P5E_CPU0_P3_TX_DP<11>")
	)
	(arc
		(start 371.513608 -279.45207)
		(mid 371.595589 -279.53272)
		(end 371.649244 -279.634442)
		(width 0.1143)
		(layer "In11.Cu")
		(net "P5E_CPU0_P3_TX_DP<11>")
	)
	(arc
		(start 371.199664 -287.05048)
		(mid 371.159409 -287.217293)
		(end 371.047518 -287.347406)
		(width 0.1143)
		(layer "In11.Cu")
		(net "P5E_CPU0_P3_TX_DP<11>")
	)
	(arc
		(start 370.972842 -290.631372)
		(mid 370.729515 -291.095938)
		(end 370.972842 -291.560504)
		(width 0.1143)
		(layer "In11.Cu")
		(net "P5E_CPU0_P3_TX_DP<11>")
	)
	(arc
		(start 370.972842 -285.77159)
		(mid 370.729515 -286.236156)
		(end 370.972842 -286.700722)
		(width 0.1143)
		(layer "In11.Cu")
		(net "P5E_CPU0_P3_TX_DP<11>")
	)
	(arc
		(start 370.972842 -280.911554)
		(mid 370.729515 -281.37612)
		(end 370.972842 -281.840686)
		(width 0.1143)
		(layer "In11.Cu")
		(net "P5E_CPU0_P3_TX_DP<11>")
	)
	(arc
		(start 371.01526 -288.345118)
		(mid 371.199993 -288.66581)
		(end 371.015514 -288.986722)
		(width 0.1143)
		(layer "In11.Cu")
		(net "P5E_CPU0_P3_TX_DP<11>")
	)
	(arc
		(start 370.972842 -289.01136)
		(mid 370.729515 -289.475926)
		(end 370.972842 -289.940492)
		(width 0.1143)
		(layer "In11.Cu")
		(net "P5E_CPU0_P3_TX_DP<11>")
	)
	(arc
		(start 370.972842 -282.531566)
		(mid 370.729515 -282.996132)
		(end 370.972842 -283.460698)
		(width 0.1143)
		(layer "In11.Cu")
		(net "P5E_CPU0_P3_TX_DP<11>")
	)
	(arc
		(start 371.212364 -278.965914)
		(mid 371.284629 -279.235843)
		(end 371.482112 -279.433528)
		(width 0.1143)
		(layer "In11.Cu")
		(net "P5E_CPU0_P3_TX_DP<11>")
	)
	(arc
		(start 371.01526 -283.485336)
		(mid 371.199993 -283.806028)
		(end 371.015514 -284.12694)
		(width 0.1143)
		(layer "In11.Cu")
		(net "P5E_CPU0_P3_TX_DP<11>")
	)
	(arc
		(start 371.027452 -278.632158)
		(mid 371.16284 -278.768107)
		(end 371.212364 -278.953468)
		(width 0.1143)
		(layer "In11.Cu")
		(net "P5E_CPU0_P3_TX_DP<11>")
	)
	(arc
		(start 371.468904 -280.086308)
		(mid 371.263045 -280.292809)
		(end 371.187726 -280.574496)
		(width 0.1143)
		(layer "In11.Cu")
		(net "P5E_CPU0_P3_TX_DP<11>")
	)
	(arc
		(start 370.972842 -293.871396)
		(mid 370.729515 -294.335962)
		(end 370.972842 -294.800528)
		(width 0.1143)
		(layer "In11.Cu")
		(net "P5E_CPU0_P3_TX_DP<11>")
	)
	(arc
		(start 370.975382 -287.389824)
		(mid 370.79473 -287.592569)
		(end 370.72951 -287.856168)
		(width 0.1143)
		(layer "In11.Cu")
		(net "P5E_CPU0_P3_TX_DP<11>")
	)
	(arc
		(start 371.01526 -281.865324)
		(mid 371.199993 -282.186016)
		(end 371.015514 -282.506928)
		(width 0.1143)
		(layer "In11.Cu")
		(net "P5E_CPU0_P3_TX_DP<11>")
	)
	(arc
		(start 371.044724 -294.842692)
		(mid 371.158607 -294.973306)
		(end 371.199664 -295.14165)
		(width 0.1143)
		(layer "In11.Cu")
		(net "P5E_CPU0_P3_TX_DP<11>")
	)
	(arc
		(start 371.01526 -289.96513)
		(mid 371.199993 -290.285822)
		(end 371.015514 -290.606734)
		(width 0.1143)
		(layer "In11.Cu")
		(net "P5E_CPU0_P3_TX_DP<11>")
	)
	(segment
		(start 384.834892 -382.34493)
		(end 385.105402 -382.61544)
		(width 0.12954)
		(layer "F.Cu")
		(net "P5E_CPU0_P3_TX_DP<10>")
	)
	(segment
		(start 385.105402 -383.31902)
		(end 384.809492 -383.61493)
		(width 0.12954)
		(layer "F.Cu")
		(net "P5E_CPU0_P3_TX_DP<10>")
	)
	(segment
		(start 385.105402 -382.61544)
		(end 385.105402 -383.31902)
		(width 0.12954)
		(layer "F.Cu")
		(net "P5E_CPU0_P3_TX_DP<10>")
	)
	(segment
		(start 369.888008 -274.630134)
		(end 370.35486 -274.896072)
		(width 0.12954)
		(layer "F.Cu")
		(net "P5E_CPU0_P3_TX_DP<10>")
	)
	(segment
		(start 370.070888 -283.48305)
		(end 370.071904 -283.483558)
		(width 0.1143)
		(layer "In11.Cu")
		(net "P5E_CPU0_P3_TX_DP<10>")
	)
	(segment
		(start 370.071904 -284.128718)
		(end 370.070888 -284.129226)
		(width 0.1143)
		(layer "In11.Cu")
		(net "P5E_CPU0_P3_TX_DP<10>")
	)
	(segment
		(start 370.069364 -293.85006)
		(end 370.032788 -293.871396)
		(width 0.1143)
		(layer "In11.Cu")
		(net "P5E_CPU0_P3_TX_DP<10>")
	)
	(segment
		(start 370.070888 -282.509214)
		(end 370.069364 -282.51023)
		(width 0.1143)
		(layer "In11.Cu")
		(net "P5E_CPU0_P3_TX_DP<10>")
	)
	(segment
		(start 370.07673 -281.86634)
		(end 370.077492 -281.866848)
		(width 0.1143)
		(layer "In11.Cu")
		(net "P5E_CPU0_P3_TX_DP<10>")
	)
	(segment
		(start 370.068348 -282.510738)
		(end 370.067586 -282.511246)
		(width 0.1143)
		(layer "In11.Cu")
		(net "P5E_CPU0_P3_TX_DP<10>")
	)
	(segment
		(start 370.073936 -290.607242)
		(end 370.072666 -290.608004)
		(width 0.1143)
		(layer "In11.Cu")
		(net "P5E_CPU0_P3_TX_DP<10>")
	)
	(segment
		(start 370.572538 -280.060908)
		(end 370.542058 -280.078688)
		(width 0.1143)
		(layer "In11.Cu")
		(net "P5E_CPU0_P3_TX_DP<10>")
	)
	(segment
		(start 370.072666 -285.748222)
		(end 370.071904 -285.74873)
		(width 0.1143)
		(layer "In11.Cu")
		(net "P5E_CPU0_P3_TX_DP<10>")
	)
	(segment
		(start 370.070888 -288.989008)
		(end 370.069364 -288.990024)
		(width 0.1143)
		(layer "In11.Cu")
		(net "P5E_CPU0_P3_TX_DP<10>")
	)
	(segment
		(start 370.065808 -284.132274)
		(end 370.064284 -284.13329)
		(width 0.1143)
		(layer "In11.Cu")
		(net "P5E_CPU0_P3_TX_DP<10>")
	)
	(segment
		(start 370.039646 -294.804592)
		(end 370.040408 -294.8051)
		(width 0.1143)
		(layer "In11.Cu")
		(net "P5E_CPU0_P3_TX_DP<10>")
	)
	(segment
		(start 370.552218 -295.639236)
		(end 370.573554 -295.651682)
		(width 0.1143)
		(layer "In11.Cu")
		(net "P5E_CPU0_P3_TX_DP<10>")
	)
	(segment
		(start 370.071904 -285.10357)
		(end 370.072666 -285.104078)
		(width 0.1143)
		(layer "In11.Cu")
		(net "P5E_CPU0_P3_TX_DP<10>")
	)
	(segment
		(start 385.483608 -318.317372)
		(end 387.310122 -322.726558)
		(width 0.14224)
		(layer "In11.Cu")
		(net "P5E_CPU0_P3_TX_DP<10>")
	)
	(segment
		(start 370.065808 -282.512262)
		(end 370.064284 -282.513278)
		(width 0.1143)
		(layer "In11.Cu")
		(net "P5E_CPU0_P3_TX_DP<10>")
	)
	(segment
		(start 379.775466 -309.775098)
		(end 385.483608 -318.317372)
		(width 0.14224)
		(layer "In11.Cu")
		(net "P5E_CPU0_P3_TX_DP<10>")
	)
	(segment
		(start 370.071904 -285.74873)
		(end 370.070888 -285.749238)
		(width 0.1143)
		(layer "In11.Cu")
		(net "P5E_CPU0_P3_TX_DP<10>")
	)
	(segment
		(start 370.078508 -277.00732)
		(end 370.079778 -277.008082)
		(width 0.1143)
		(layer "In11.Cu")
		(net "P5E_CPU0_P3_TX_DP<10>")
	)
	(segment
		(start 370.072666 -283.484066)
		(end 370.073936 -283.484828)
		(width 0.1143)
		(layer "In11.Cu")
		(net "P5E_CPU0_P3_TX_DP<10>")
	)
	(segment
		(start 370.07546 -293.205408)
		(end 370.07673 -293.20617)
		(width 0.1143)
		(layer "In11.Cu")
		(net "P5E_CPU0_P3_TX_DP<10>")
	)
	(segment
		(start 370.770658 -296.918888)
		(end 371.501924 -299.329348)
		(width 0.14224)
		(layer "In11.Cu")
		(net "P5E_CPU0_P3_TX_DP<10>")
	)
	(segment
		(start 370.073936 -278.624792)
		(end 370.07546 -278.625554)
		(width 0.1143)
		(layer "In11.Cu")
		(net "P5E_CPU0_P3_TX_DP<10>")
	)
	(segment
		(start 370.816378 -296.538142)
		(end 370.770658 -296.583862)
		(width 0.1143)
		(layer "In11.Cu")
		(net "P5E_CPU0_P3_TX_DP<10>")
	)
	(segment
		(start 370.032788 -286.700722)
		(end 370.071904 -286.723582)
		(width 0.1143)
		(layer "In11.Cu")
		(net "P5E_CPU0_P3_TX_DP<10>")
	)
	(segment
		(start 370.069364 -290.610036)
		(end 370.068348 -290.610544)
		(width 0.1143)
		(layer "In11.Cu")
		(net "P5E_CPU0_P3_TX_DP<10>")
	)
	(segment
		(start 372.811802 -301.289466)
		(end 379.775466 -309.775098)
		(width 0.14224)
		(layer "In11.Cu")
		(net "P5E_CPU0_P3_TX_DP<10>")
	)
	(segment
		(start 370.067586 -277.65121)
		(end 370.065808 -277.652226)
		(width 0.1143)
		(layer "In11.Cu")
		(net "P5E_CPU0_P3_TX_DP<10>")
	)
	(segment
		(start 390.842754 -352.036126)
		(end 389.236966 -360.109516)
		(width 0.14224)
		(layer "In11.Cu")
		(net "P5E_CPU0_P3_TX_DP<10>")
	)
	(segment
		(start 370.770658 -296.583862)
		(end 370.770658 -296.61231)
		(width 0.1143)
		(layer "In11.Cu")
		(net "P5E_CPU0_P3_TX_DP<10>")
	)
	(segment
		(start 370.032788 -294.800528)
		(end 370.039646 -294.804592)
		(width 0.1143)
		(layer "In11.Cu")
		(net "P5E_CPU0_P3_TX_DP<10>")
	)
	(segment
		(start 370.502688 -295.610534)
		(end 370.540788 -295.632886)
		(width 0.1143)
		(layer "In11.Cu")
		(net "P5E_CPU0_P3_TX_DP<10>")
	)
	(segment
		(start 370.071904 -288.9885)
		(end 370.070888 -288.989008)
		(width 0.1143)
		(layer "In11.Cu")
		(net "P5E_CPU0_P3_TX_DP<10>")
	)
	(segment
		(start 370.032788 -293.180516)
		(end 370.039646 -293.18458)
		(width 0.1143)
		(layer "In11.Cu")
		(net "P5E_CPU0_P3_TX_DP<10>")
	)
	(segment
		(start 370.032788 -276.98065)
		(end 370.039646 -276.984714)
		(width 0.1143)
		(layer "In11.Cu")
		(net "P5E_CPU0_P3_TX_DP<10>")
	)
	(segment
		(start 370.547646 -295.636696)
		(end 370.548408 -295.637204)
		(width 0.1143)
		(layer "In11.Cu")
		(net "P5E_CPU0_P3_TX_DP<10>")
	)
	(segment
		(start 370.069364 -285.750254)
		(end 370.068348 -285.750762)
		(width 0.1143)
		(layer "In11.Cu")
		(net "P5E_CPU0_P3_TX_DP<10>")
	)
	(segment
		(start 370.067586 -284.131258)
		(end 370.065808 -284.132274)
		(width 0.1143)
		(layer "In11.Cu")
		(net "P5E_CPU0_P3_TX_DP<10>")
	)
	(segment
		(start 387.310122 -322.726558)
		(end 390.848088 -340.513924)
		(width 0.14224)
		(layer "In11.Cu")
		(net "P5E_CPU0_P3_TX_DP<10>")
	)
	(segment
		(start 370.068348 -288.990532)
		(end 370.067586 -288.99104)
		(width 0.1143)
		(layer "In11.Cu")
		(net "P5E_CPU0_P3_TX_DP<10>")
	)
	(segment
		(start 370.072666 -293.203884)
		(end 370.073936 -293.204646)
		(width 0.1143)
		(layer "In11.Cu")
		(net "P5E_CPU0_P3_TX_DP<10>")
	)
	(segment
		(start 370.071904 -280.888694)
		(end 370.070888 -280.889202)
		(width 0.1143)
		(layer "In11.Cu")
		(net "P5E_CPU0_P3_TX_DP<10>")
	)
	(segment
		(start 370.072666 -277.648162)
		(end 370.071904 -277.64867)
		(width 0.1143)
		(layer "In11.Cu")
		(net "P5E_CPU0_P3_TX_DP<10>")
	)
	(segment
		(start 370.071904 -286.723582)
		(end 370.105432 -286.74314)
		(width 0.1143)
		(layer "In11.Cu")
		(net "P5E_CPU0_P3_TX_DP<10>")
	)
	(segment
		(start 370.064284 -285.753302)
		(end 370.032788 -285.77159)
		(width 0.1143)
		(layer "In11.Cu")
		(net "P5E_CPU0_P3_TX_DP<10>")
	)
	(segment
		(start 370.073936 -285.74746)
		(end 370.072666 -285.748222)
		(width 0.1143)
		(layer "In11.Cu")
		(net "P5E_CPU0_P3_TX_DP<10>")
	)
	(segment
		(start 370.064284 -288.993072)
		(end 370.032788 -289.01136)
		(width 0.1143)
		(layer "In11.Cu")
		(net "P5E_CPU0_P3_TX_DP<10>")
	)
	(segment
		(start 370.065808 -285.752286)
		(end 370.064284 -285.753302)
		(width 0.1143)
		(layer "In11.Cu")
		(net "P5E_CPU0_P3_TX_DP<10>")
	)
	(segment
		(start 370.071904 -283.483558)
		(end 370.072666 -283.484066)
		(width 0.1143)
		(layer "In11.Cu")
		(net "P5E_CPU0_P3_TX_DP<10>")
	)
	(segment
		(start 370.07546 -289.965384)
		(end 370.07673 -289.966146)
		(width 0.1143)
		(layer "In11.Cu")
		(net "P5E_CPU0_P3_TX_DP<10>")
	)
	(segment
		(start 370.07673 -277.006304)
		(end 370.077492 -277.006812)
		(width 0.1143)
		(layer "In11.Cu")
		(net "P5E_CPU0_P3_TX_DP<10>")
	)
	(segment
		(start 370.032788 -278.600662)
		(end 370.039646 -278.604726)
		(width 0.1143)
		(layer "In11.Cu")
		(net "P5E_CPU0_P3_TX_DP<10>")
	)
	(segment
		(start 370.064284 -292.233096)
		(end 370.032788 -292.251384)
		(width 0.1143)
		(layer "In11.Cu")
		(net "P5E_CPU0_P3_TX_DP<10>")
	)
	(segment
		(start 370.073936 -294.824658)
		(end 370.07546 -294.82542)
		(width 0.1143)
		(layer "In11.Cu")
		(net "P5E_CPU0_P3_TX_DP<10>")
	)
	(segment
		(start 370.072666 -291.583872)
		(end 370.073936 -291.584634)
		(width 0.1143)
		(layer "In11.Cu")
		(net "P5E_CPU0_P3_TX_DP<10>")
	)
	(segment
		(start 370.032788 -283.460698)
		(end 370.070888 -283.48305)
		(width 0.1143)
		(layer "In11.Cu")
		(net "P5E_CPU0_P3_TX_DP<10>")
	)
	(segment
		(start 370.548408 -295.637204)
		(end 370.549678 -295.637966)
		(width 0.1143)
		(layer "In11.Cu")
		(net "P5E_CPU0_P3_TX_DP<10>")
	)
	(segment
		(start 370.077492 -293.206678)
		(end 370.078508 -293.207186)
		(width 0.1143)
		(layer "In11.Cu")
		(net "P5E_CPU0_P3_TX_DP<10>")
	)
	(segment
		(start 370.070888 -292.229032)
		(end 370.069364 -292.230048)
		(width 0.1143)
		(layer "In11.Cu")
		(net "P5E_CPU0_P3_TX_DP<10>")
	)
	(segment
		(start 370.071904 -277.00351)
		(end 370.072666 -277.004018)
		(width 0.1143)
		(layer "In11.Cu")
		(net "P5E_CPU0_P3_TX_DP<10>")
	)
	(segment
		(start 370.073936 -280.887424)
		(end 370.072666 -280.888186)
		(width 0.1143)
		(layer "In11.Cu")
		(net "P5E_CPU0_P3_TX_DP<10>")
	)
	(segment
		(start 370.073936 -277.6474)
		(end 370.072666 -277.648162)
		(width 0.1143)
		(layer "In11.Cu")
		(net "P5E_CPU0_P3_TX_DP<10>")
	)
	(segment
		(start 370.039646 -293.18458)
		(end 370.040408 -293.185088)
		(width 0.1143)
		(layer "In11.Cu")
		(net "P5E_CPU0_P3_TX_DP<10>")
	)
	(segment
		(start 370.103654 -282.490418)
		(end 370.073936 -282.507436)
		(width 0.1143)
		(layer "In11.Cu")
		(net "P5E_CPU0_P3_TX_DP<10>")
	)
	(segment
		(start 370.068348 -292.230556)
		(end 370.067586 -292.231064)
		(width 0.1143)
		(layer "In11.Cu")
		(net "P5E_CPU0_P3_TX_DP<10>")
	)
	(segment
		(start 370.070888 -277.649178)
		(end 370.069364 -277.650194)
		(width 0.1143)
		(layer "In11.Cu")
		(net "P5E_CPU0_P3_TX_DP<10>")
	)
	(segment
		(start 370.25961 -295.145968)
		(end 370.259356 -295.145968)
		(width 0.1143)
		(layer "In11.Cu")
		(net "P5E_CPU0_P3_TX_DP<10>")
	)
	(segment
		(start 370.077492 -294.82669)
		(end 370.078508 -294.827198)
		(width 0.1143)
		(layer "In11.Cu")
		(net "P5E_CPU0_P3_TX_DP<10>")
	)
	(segment
		(start 370.572538 -275.200872)
		(end 370.542058 -275.218652)
		(width 0.1143)
		(layer "In11.Cu")
		(net "P5E_CPU0_P3_TX_DP<10>")
	)
	(segment
		(start 370.082318 -277.009352)
		(end 370.103654 -277.021798)
		(width 0.1143)
		(layer "In11.Cu")
		(net "P5E_CPU0_P3_TX_DP<10>")
	)
	(segment
		(start 370.078508 -281.867356)
		(end 370.079778 -281.868118)
		(width 0.1143)
		(layer "In11.Cu")
		(net "P5E_CPU0_P3_TX_DP<10>")
	)
	(segment
		(start 370.073936 -289.964622)
		(end 370.07546 -289.965384)
		(width 0.1143)
		(layer "In11.Cu")
		(net "P5E_CPU0_P3_TX_DP<10>")
	)
	(segment
		(start 370.072666 -282.508198)
		(end 370.071904 -282.508706)
		(width 0.1143)
		(layer "In11.Cu")
		(net "P5E_CPU0_P3_TX_DP<10>")
	)
	(segment
		(start 370.540788 -295.632886)
		(end 370.541804 -295.633394)
		(width 0.1143)
		(layer "In11.Cu")
		(net "P5E_CPU0_P3_TX_DP<10>")
	)
	(segment
		(start 370.07673 -278.626316)
		(end 370.077492 -278.626824)
		(width 0.1143)
		(layer "In11.Cu")
		(net "P5E_CPU0_P3_TX_DP<10>")
	)
	(segment
		(start 370.07546 -277.005542)
		(end 370.07673 -277.006304)
		(width 0.1143)
		(layer "In11.Cu")
		(net "P5E_CPU0_P3_TX_DP<10>")
	)
	(segment
		(start 370.542566 -295.633902)
		(end 370.54536 -295.635426)
		(width 0.1143)
		(layer "In11.Cu")
		(net "P5E_CPU0_P3_TX_DP<10>")
	)
	(segment
		(start 370.070888 -276.029166)
		(end 370.069364 -276.030182)
		(width 0.1143)
		(layer "In11.Cu")
		(net "P5E_CPU0_P3_TX_DP<10>")
	)
	(segment
		(start 370.067586 -285.75127)
		(end 370.065808 -285.752286)
		(width 0.1143)
		(layer "In11.Cu")
		(net "P5E_CPU0_P3_TX_DP<10>")
	)
	(segment
		(start 370.065808 -288.992056)
		(end 370.064284 -288.993072)
		(width 0.1143)
		(layer "In11.Cu")
		(net "P5E_CPU0_P3_TX_DP<10>")
	)
	(segment
		(start 370.103654 -277.630382)
		(end 370.073936 -277.6474)
		(width 0.1143)
		(layer "In11.Cu")
		(net "P5E_CPU0_P3_TX_DP<10>")
	)
	(segment
		(start 370.103654 -287.3502)
		(end 370.071904 -287.368488)
		(width 0.1143)
		(layer "In11.Cu")
		(net "P5E_CPU0_P3_TX_DP<10>")
	)
	(segment
		(start 370.073936 -288.98723)
		(end 370.072666 -288.987992)
		(width 0.1143)
		(layer "In11.Cu")
		(net "P5E_CPU0_P3_TX_DP<10>")
	)
	(segment
		(start 370.067586 -292.231064)
		(end 370.065808 -292.23208)
		(width 0.1143)
		(layer "In11.Cu")
		(net "P5E_CPU0_P3_TX_DP<10>")
	)
	(segment
		(start 370.069364 -288.990024)
		(end 370.068348 -288.990532)
		(width 0.1143)
		(layer "In11.Cu")
		(net "P5E_CPU0_P3_TX_DP<10>")
	)
	(segment
		(start 370.103654 -292.210236)
		(end 370.073936 -292.227254)
		(width 0.1143)
		(layer "In11.Cu")
		(net "P5E_CPU0_P3_TX_DP<10>")
	)
	(segment
		(start 370.072666 -284.12821)
		(end 370.071904 -284.128718)
		(width 0.1143)
		(layer "In11.Cu")
		(net "P5E_CPU0_P3_TX_DP<10>")
	)
	(segment
		(start 389.132826 -360.508804)
		(end 385.296918 -373.16791)
		(width 0.14224)
		(layer "In11.Cu")
		(net "P5E_CPU0_P3_TX_DP<10>")
	)
	(segment
		(start 370.071904 -287.368488)
		(end 370.035328 -287.389824)
		(width 0.1143)
		(layer "In11.Cu")
		(net "P5E_CPU0_P3_TX_DP<10>")
	)
	(segment
		(start 370.072666 -281.864054)
		(end 370.073936 -281.864816)
		(width 0.1143)
		(layer "In11.Cu")
		(net "P5E_CPU0_P3_TX_DP<10>")
	)
	(segment
		(start 370.078508 -293.207186)
		(end 370.079778 -293.207948)
		(width 0.1143)
		(layer "In11.Cu")
		(net "P5E_CPU0_P3_TX_DP<10>")
	)
	(segment
		(start 370.073936 -284.127448)
		(end 370.072666 -284.12821)
		(width 0.1143)
		(layer "In11.Cu")
		(net "P5E_CPU0_P3_TX_DP<10>")
	)
	(segment
		(start 370.079778 -293.207948)
		(end 370.082318 -293.209218)
		(width 0.1143)
		(layer "In11.Cu")
		(net "P5E_CPU0_P3_TX_DP<10>")
	)
	(segment
		(start 370.542058 -275.218652)
		(end 370.502942 -275.241512)
		(width 0.1143)
		(layer "In11.Cu")
		(net "P5E_CPU0_P3_TX_DP<10>")
	)
	(segment
		(start 370.069364 -277.650194)
		(end 370.068348 -277.650702)
		(width 0.1143)
		(layer "In11.Cu")
		(net "P5E_CPU0_P3_TX_DP<10>")
	)
	(segment
		(start 370.077492 -289.966654)
		(end 370.078508 -289.967162)
		(width 0.1143)
		(layer "In11.Cu")
		(net "P5E_CPU0_P3_TX_DP<10>")
	)
	(segment
		(start 370.07673 -289.966146)
		(end 370.077492 -289.966654)
		(width 0.1143)
		(layer "In11.Cu")
		(net "P5E_CPU0_P3_TX_DP<10>")
	)
	(segment
		(start 370.040408 -289.945064)
		(end 370.071904 -289.963352)
		(width 0.1143)
		(layer "In11.Cu")
		(net "P5E_CPU0_P3_TX_DP<10>")
	)
	(segment
		(start 370.082318 -289.969194)
		(end 370.103654 -289.98164)
		(width 0.1143)
		(layer "In11.Cu")
		(net "P5E_CPU0_P3_TX_DP<10>")
	)
	(segment
		(start 370.502942 -279.410668)
		(end 370.542058 -279.433528)
		(width 0.1143)
		(layer "In11.Cu")
		(net "P5E_CPU0_P3_TX_DP<10>")
	)
	(segment
		(start 370.039646 -289.944556)
		(end 370.040408 -289.945064)
		(width 0.1143)
		(layer "In11.Cu")
		(net "P5E_CPU0_P3_TX_DP<10>")
	)
	(segment
		(start 370.073936 -276.027388)
		(end 370.072666 -276.02815)
		(width 0.1143)
		(layer "In11.Cu")
		(net "P5E_CPU0_P3_TX_DP<10>")
	)
	(segment
		(start 370.071904 -278.623522)
		(end 370.072666 -278.62403)
		(width 0.1143)
		(layer "In11.Cu")
		(net "P5E_CPU0_P3_TX_DP<10>")
	)
	(segment
		(start 370.071904 -294.823388)
		(end 370.072666 -294.823896)
		(width 0.1143)
		(layer "In11.Cu")
		(net "P5E_CPU0_P3_TX_DP<10>")
	)
	(segment
		(start 370.072666 -278.62403)
		(end 370.073936 -278.624792)
		(width 0.1143)
		(layer "In11.Cu")
		(net "P5E_CPU0_P3_TX_DP<10>")
	)
	(segment
		(start 370.070888 -284.129226)
		(end 370.069364 -284.130242)
		(width 0.1143)
		(layer "In11.Cu")
		(net "P5E_CPU0_P3_TX_DP<10>")
	)
	(segment
		(start 370.072666 -288.987992)
		(end 370.071904 -288.9885)
		(width 0.1143)
		(layer "In11.Cu")
		(net "P5E_CPU0_P3_TX_DP<10>")
	)
	(segment
		(start 370.072666 -277.004018)
		(end 370.073936 -277.00478)
		(width 0.1143)
		(layer "In11.Cu")
		(net "P5E_CPU0_P3_TX_DP<10>")
	)
	(segment
		(start 370.073936 -292.227254)
		(end 370.072666 -292.228016)
		(width 0.1143)
		(layer "In11.Cu")
		(net "P5E_CPU0_P3_TX_DP<10>")
	)
	(segment
		(start 370.064284 -290.613084)
		(end 370.032788 -290.631372)
		(width 0.1143)
		(layer "In11.Cu")
		(net "P5E_CPU0_P3_TX_DP<10>")
	)
	(segment
		(start 389.212328 -360.215942)
		(end 389.166608 -360.389932)
		(width 0.14224)
		(layer "In11.Cu")
		(net "P5E_CPU0_P3_TX_DP<10>")
	)
	(segment
		(start 370.816378 -296.278554)
		(end 370.816378 -296.538142)
		(width 0.1143)
		(layer "In11.Cu")
		(net "P5E_CPU0_P3_TX_DP<10>")
	)
	(segment
		(start 370.072666 -290.608004)
		(end 370.071904 -290.608512)
		(width 0.1143)
		(layer "In11.Cu")
		(net "P5E_CPU0_P3_TX_DP<10>")
	)
	(segment
		(start 370.073936 -291.584634)
		(end 370.103654 -291.601652)
		(width 0.1143)
		(layer "In11.Cu")
		(net "P5E_CPU0_P3_TX_DP<10>")
	)
	(segment
		(start 370.040408 -281.845258)
		(end 370.071904 -281.863546)
		(width 0.1143)
		(layer "In11.Cu")
		(net "P5E_CPU0_P3_TX_DP<10>")
	)
	(segment
		(start 370.071904 -288.343594)
		(end 370.105432 -288.363152)
		(width 0.1143)
		(layer "In11.Cu")
		(net "P5E_CPU0_P3_TX_DP<10>")
	)
	(segment
		(start 370.039646 -278.604726)
		(end 370.040408 -278.605234)
		(width 0.1143)
		(layer "In11.Cu")
		(net "P5E_CPU0_P3_TX_DP<10>")
	)
	(segment
		(start 370.068348 -276.03069)
		(end 370.067586 -276.031198)
		(width 0.1143)
		(layer "In11.Cu")
		(net "P5E_CPU0_P3_TX_DP<10>")
	)
	(segment
		(start 370.068348 -277.650702)
		(end 370.067586 -277.65121)
		(width 0.1143)
		(layer "In11.Cu")
		(net "P5E_CPU0_P3_TX_DP<10>")
	)
	(segment
		(start 370.040408 -278.605234)
		(end 370.071904 -278.623522)
		(width 0.1143)
		(layer "In11.Cu")
		(net "P5E_CPU0_P3_TX_DP<10>")
	)
	(segment
		(start 370.103654 -290.590224)
		(end 370.073936 -290.607242)
		(width 0.1143)
		(layer "In11.Cu")
		(net "P5E_CPU0_P3_TX_DP<10>")
	)
	(segment
		(start 370.065808 -290.612068)
		(end 370.064284 -290.613084)
		(width 0.1143)
		(layer "In11.Cu")
		(net "P5E_CPU0_P3_TX_DP<10>")
	)
	(segment
		(start 370.071904 -281.863546)
		(end 370.072666 -281.864054)
		(width 0.1143)
		(layer "In11.Cu")
		(net "P5E_CPU0_P3_TX_DP<10>")
	)
	(segment
		(start 370.067586 -282.511246)
		(end 370.065808 -282.512262)
		(width 0.1143)
		(layer "In11.Cu")
		(net "P5E_CPU0_P3_TX_DP<10>")
	)
	(segment
		(start 370.54536 -295.635426)
		(end 370.546122 -295.635934)
		(width 0.1143)
		(layer "In11.Cu")
		(net "P5E_CPU0_P3_TX_DP<10>")
	)
	(segment
		(start 370.068348 -285.750762)
		(end 370.067586 -285.75127)
		(width 0.1143)
		(layer "In11.Cu")
		(net "P5E_CPU0_P3_TX_DP<10>")
	)
	(segment
		(start 370.077492 -278.626824)
		(end 370.078508 -278.627332)
		(width 0.1143)
		(layer "In11.Cu")
		(net "P5E_CPU0_P3_TX_DP<10>")
	)
	(segment
		(start 370.729764 -296.19194)
		(end 370.816378 -296.278554)
		(width 0.1143)
		(layer "In11.Cu")
		(net "P5E_CPU0_P3_TX_DP<10>")
	)
	(segment
		(start 370.070888 -291.582856)
		(end 370.071904 -291.583364)
		(width 0.1143)
		(layer "In11.Cu")
		(net "P5E_CPU0_P3_TX_DP<10>")
	)
	(segment
		(start 370.541804 -295.633394)
		(end 370.542566 -295.633902)
		(width 0.1143)
		(layer "In11.Cu")
		(net "P5E_CPU0_P3_TX_DP<10>")
	)
	(segment
		(start 370.103654 -285.730442)
		(end 370.073936 -285.74746)
		(width 0.1143)
		(layer "In11.Cu")
		(net "P5E_CPU0_P3_TX_DP<10>")
	)
	(segment
		(start 370.067586 -290.611052)
		(end 370.065808 -290.612068)
		(width 0.1143)
		(layer "In11.Cu")
		(net "P5E_CPU0_P3_TX_DP<10>")
	)
	(segment
		(start 370.072666 -289.96386)
		(end 370.073936 -289.964622)
		(width 0.1143)
		(layer "In11.Cu")
		(net "P5E_CPU0_P3_TX_DP<10>")
	)
	(segment
		(start 370.064284 -282.513278)
		(end 370.032788 -282.531566)
		(width 0.1143)
		(layer "In11.Cu")
		(net "P5E_CPU0_P3_TX_DP<10>")
	)
	(segment
		(start 370.069364 -280.890218)
		(end 370.068348 -280.890726)
		(width 0.1143)
		(layer "In11.Cu")
		(net "P5E_CPU0_P3_TX_DP<10>")
	)
	(segment
		(start 370.546122 -295.635934)
		(end 370.547646 -295.636696)
		(width 0.1143)
		(layer "In11.Cu")
		(net "P5E_CPU0_P3_TX_DP<10>")
	)
	(segment
		(start 370.542058 -280.078688)
		(end 370.502942 -280.101548)
		(width 0.1143)
		(layer "In11.Cu")
		(net "P5E_CPU0_P3_TX_DP<10>")
	)
	(segment
		(start 370.073936 -282.507436)
		(end 370.072666 -282.508198)
		(width 0.1143)
		(layer "In11.Cu")
		(net "P5E_CPU0_P3_TX_DP<10>")
	)
	(segment
		(start 370.065808 -277.652226)
		(end 370.064284 -277.653242)
		(width 0.1143)
		(layer "In11.Cu")
		(net "P5E_CPU0_P3_TX_DP<10>")
	)
	(segment
		(start 370.069364 -284.130242)
		(end 370.068348 -284.13075)
		(width 0.1143)
		(layer "In11.Cu")
		(net "P5E_CPU0_P3_TX_DP<10>")
	)
	(segment
		(start 370.079778 -278.628094)
		(end 370.082318 -278.629364)
		(width 0.1143)
		(layer "In11.Cu")
		(net "P5E_CPU0_P3_TX_DP<10>")
	)
	(segment
		(start 370.082318 -281.869388)
		(end 370.103654 -281.881834)
		(width 0.1143)
		(layer "In11.Cu")
		(net "P5E_CPU0_P3_TX_DP<10>")
	)
	(segment
		(start 370.070888 -280.889202)
		(end 370.069364 -280.890218)
		(width 0.1143)
		(layer "In11.Cu")
		(net "P5E_CPU0_P3_TX_DP<10>")
	)
	(segment
		(start 370.078508 -278.627332)
		(end 370.079778 -278.628094)
		(width 0.1143)
		(layer "In11.Cu")
		(net "P5E_CPU0_P3_TX_DP<10>")
	)
	(segment
		(start 370.072666 -285.104078)
		(end 370.073936 -285.10484)
		(width 0.1143)
		(layer "In11.Cu")
		(net "P5E_CPU0_P3_TX_DP<10>")
	)
	(segment
		(start 370.078508 -294.827198)
		(end 370.079778 -294.82796)
		(width 0.1143)
		(layer "In11.Cu")
		(net "P5E_CPU0_P3_TX_DP<10>")
	)
	(segment
		(start 370.070888 -293.849044)
		(end 370.069364 -293.85006)
		(width 0.1143)
		(layer "In11.Cu")
		(net "P5E_CPU0_P3_TX_DP<10>")
	)
	(segment
		(start 370.770658 -296.61231)
		(end 370.770658 -296.918888)
		(width 0.14224)
		(layer "In11.Cu")
		(net "P5E_CPU0_P3_TX_DP<10>")
	)
	(segment
		(start 370.073936 -281.864816)
		(end 370.07546 -281.865578)
		(width 0.1143)
		(layer "In11.Cu")
		(net "P5E_CPU0_P3_TX_DP<10>")
	)
	(segment
		(start 370.07673 -293.20617)
		(end 370.077492 -293.206678)
		(width 0.1143)
		(layer "In11.Cu")
		(net "P5E_CPU0_P3_TX_DP<10>")
	)
	(segment
		(start 370.072666 -276.02815)
		(end 370.071904 -276.028658)
		(width 0.1143)
		(layer "In11.Cu")
		(net "P5E_CPU0_P3_TX_DP<10>")
	)
	(segment
		(start 370.073936 -283.484828)
		(end 370.103654 -283.501846)
		(width 0.1143)
		(layer "In11.Cu")
		(net "P5E_CPU0_P3_TX_DP<10>")
	)
	(segment
		(start 370.064284 -277.653242)
		(end 370.032788 -277.67153)
		(width 0.1143)
		(layer "In11.Cu")
		(net "P5E_CPU0_P3_TX_DP<10>")
	)
	(segment
		(start 370.068348 -284.13075)
		(end 370.067586 -284.131258)
		(width 0.1143)
		(layer "In11.Cu")
		(net "P5E_CPU0_P3_TX_DP<10>")
	)
	(segment
		(start 370.040408 -276.985222)
		(end 370.071904 -277.00351)
		(width 0.1143)
		(layer "In11.Cu")
		(net "P5E_CPU0_P3_TX_DP<10>")
	)
	(segment
		(start 370.064284 -276.03323)
		(end 370.032788 -276.051518)
		(width 0.1143)
		(layer "In11.Cu")
		(net "P5E_CPU0_P3_TX_DP<10>")
	)
	(segment
		(start 370.032788 -289.940492)
		(end 370.039646 -289.944556)
		(width 0.1143)
		(layer "In11.Cu")
		(net "P5E_CPU0_P3_TX_DP<10>")
	)
	(segment
		(start 370.067586 -288.99104)
		(end 370.065808 -288.992056)
		(width 0.1143)
		(layer "In11.Cu")
		(net "P5E_CPU0_P3_TX_DP<10>")
	)
	(segment
		(start 370.071904 -277.64867)
		(end 370.070888 -277.649178)
		(width 0.1143)
		(layer "In11.Cu")
		(net "P5E_CPU0_P3_TX_DP<10>")
	)
	(segment
		(start 370.082318 -294.82923)
		(end 370.103654 -294.841676)
		(width 0.1143)
		(layer "In11.Cu")
		(net "P5E_CPU0_P3_TX_DP<10>")
	)
	(segment
		(start 370.072666 -292.228016)
		(end 370.071904 -292.228524)
		(width 0.1143)
		(layer "In11.Cu")
		(net "P5E_CPU0_P3_TX_DP<10>")
	)
	(segment
		(start 370.069364 -292.230048)
		(end 370.068348 -292.230556)
		(width 0.1143)
		(layer "In11.Cu")
		(net "P5E_CPU0_P3_TX_DP<10>")
	)
	(segment
		(start 370.103654 -293.830248)
		(end 370.071904 -293.848536)
		(width 0.1143)
		(layer "In11.Cu")
		(net "P5E_CPU0_P3_TX_DP<10>")
	)
	(segment
		(start 370.067586 -276.031198)
		(end 370.065808 -276.032214)
		(width 0.1143)
		(layer "In11.Cu")
		(net "P5E_CPU0_P3_TX_DP<10>")
	)
	(segment
		(start 370.032788 -285.08071)
		(end 370.070888 -285.103062)
		(width 0.1143)
		(layer "In11.Cu")
		(net "P5E_CPU0_P3_TX_DP<10>")
	)
	(segment
		(start 370.079778 -281.868118)
		(end 370.082318 -281.869388)
		(width 0.1143)
		(layer "In11.Cu")
		(net "P5E_CPU0_P3_TX_DP<10>")
	)
	(segment
		(start 370.078508 -289.967162)
		(end 370.079778 -289.967924)
		(width 0.1143)
		(layer "In11.Cu")
		(net "P5E_CPU0_P3_TX_DP<10>")
	)
	(segment
		(start 370.072666 -280.888186)
		(end 370.071904 -280.888694)
		(width 0.1143)
		(layer "In11.Cu")
		(net "P5E_CPU0_P3_TX_DP<10>")
	)
	(segment
		(start 370.071904 -290.608512)
		(end 370.070888 -290.60902)
		(width 0.1143)
		(layer "In11.Cu")
		(net "P5E_CPU0_P3_TX_DP<10>")
	)
	(segment
		(start 370.073936 -285.10484)
		(end 370.103654 -285.121858)
		(width 0.1143)
		(layer "In11.Cu")
		(net "P5E_CPU0_P3_TX_DP<10>")
	)
	(segment
		(start 370.065808 -276.032214)
		(end 370.064284 -276.03323)
		(width 0.1143)
		(layer "In11.Cu")
		(net "P5E_CPU0_P3_TX_DP<10>")
	)
	(segment
		(start 370.032788 -291.560504)
		(end 370.070888 -291.582856)
		(width 0.1143)
		(layer "In11.Cu")
		(net "P5E_CPU0_P3_TX_DP<10>")
	)
	(segment
		(start 370.077492 -277.006812)
		(end 370.078508 -277.00732)
		(width 0.1143)
		(layer "In11.Cu")
		(net "P5E_CPU0_P3_TX_DP<10>")
	)
	(segment
		(start 370.071904 -293.848536)
		(end 370.070888 -293.849044)
		(width 0.1143)
		(layer "In11.Cu")
		(net "P5E_CPU0_P3_TX_DP<10>")
	)
	(segment
		(start 370.729764 -295.955974)
		(end 370.729764 -296.19194)
		(width 0.1143)
		(layer "In11.Cu")
		(net "P5E_CPU0_P3_TX_DP<10>")
	)
	(segment
		(start 370.069364 -282.51023)
		(end 370.068348 -282.510738)
		(width 0.1143)
		(layer "In11.Cu")
		(net "P5E_CPU0_P3_TX_DP<10>")
	)
	(segment
		(start 370.549678 -295.637966)
		(end 370.552218 -295.639236)
		(width 0.1143)
		(layer "In11.Cu")
		(net "P5E_CPU0_P3_TX_DP<10>")
	)
	(segment
		(start 370.032788 -281.840686)
		(end 370.039646 -281.84475)
		(width 0.1143)
		(layer "In11.Cu")
		(net "P5E_CPU0_P3_TX_DP<10>")
	)
	(segment
		(start 370.07546 -281.865578)
		(end 370.07673 -281.86634)
		(width 0.1143)
		(layer "In11.Cu")
		(net "P5E_CPU0_P3_TX_DP<10>")
	)
	(segment
		(start 370.070888 -285.103062)
		(end 370.071904 -285.10357)
		(width 0.1143)
		(layer "In11.Cu")
		(net "P5E_CPU0_P3_TX_DP<10>")
	)
	(segment
		(start 370.542058 -279.433528)
		(end 370.572538 -279.451308)
		(width 0.1143)
		(layer "In11.Cu")
		(net "P5E_CPU0_P3_TX_DP<10>")
	)
	(segment
		(start 370.103654 -284.11043)
		(end 370.073936 -284.127448)
		(width 0.1143)
		(layer "In11.Cu")
		(net "P5E_CPU0_P3_TX_DP<10>")
	)
	(segment
		(start 385.078478 -382.101344)
		(end 384.834892 -382.34493)
		(width 0.14224)
		(layer "In11.Cu")
		(net "P5E_CPU0_P3_TX_DP<10>")
	)
	(segment
		(start 370.071904 -291.583364)
		(end 370.072666 -291.583872)
		(width 0.1143)
		(layer "In11.Cu")
		(net "P5E_CPU0_P3_TX_DP<10>")
	)
	(segment
		(start 370.065808 -292.23208)
		(end 370.064284 -292.233096)
		(width 0.1143)
		(layer "In11.Cu")
		(net "P5E_CPU0_P3_TX_DP<10>")
	)
	(segment
		(start 370.07546 -278.625554)
		(end 370.07673 -278.626316)
		(width 0.1143)
		(layer "In11.Cu")
		(net "P5E_CPU0_P3_TX_DP<10>")
	)
	(segment
		(start 370.071904 -289.963352)
		(end 370.072666 -289.96386)
		(width 0.1143)
		(layer "In11.Cu")
		(net "P5E_CPU0_P3_TX_DP<10>")
	)
	(segment
		(start 370.082318 -293.209218)
		(end 370.103654 -293.221664)
		(width 0.1143)
		(layer "In11.Cu")
		(net "P5E_CPU0_P3_TX_DP<10>")
	)
	(segment
		(start 370.652802 -274.896072)
		(end 370.722652 -274.965922)
		(width 0.1143)
		(layer "In11.Cu")
		(net "P5E_CPU0_P3_TX_DP<10>")
	)
	(segment
		(start 370.079778 -289.967924)
		(end 370.082318 -289.969194)
		(width 0.1143)
		(layer "In11.Cu")
		(net "P5E_CPU0_P3_TX_DP<10>")
	)
	(segment
		(start 370.039646 -276.984714)
		(end 370.040408 -276.985222)
		(width 0.1143)
		(layer "In11.Cu")
		(net "P5E_CPU0_P3_TX_DP<10>")
	)
	(segment
		(start 370.040408 -293.185088)
		(end 370.071904 -293.203376)
		(width 0.1143)
		(layer "In11.Cu")
		(net "P5E_CPU0_P3_TX_DP<10>")
	)
	(segment
		(start 370.069364 -276.030182)
		(end 370.068348 -276.03069)
		(width 0.1143)
		(layer "In11.Cu")
		(net "P5E_CPU0_P3_TX_DP<10>")
	)
	(segment
		(start 370.103654 -276.01037)
		(end 370.073936 -276.027388)
		(width 0.1143)
		(layer "In11.Cu")
		(net "P5E_CPU0_P3_TX_DP<10>")
	)
	(segment
		(start 370.067586 -280.891234)
		(end 370.065808 -280.89225)
		(width 0.1143)
		(layer "In11.Cu")
		(net "P5E_CPU0_P3_TX_DP<10>")
	)
	(segment
		(start 371.501924 -299.329348)
		(end 372.811802 -301.289466)
		(width 0.14224)
		(layer "In11.Cu")
		(net "P5E_CPU0_P3_TX_DP<10>")
	)
	(segment
		(start 370.071904 -292.228524)
		(end 370.070888 -292.229032)
		(width 0.1143)
		(layer "In11.Cu")
		(net "P5E_CPU0_P3_TX_DP<10>")
	)
	(segment
		(start 370.065808 -280.89225)
		(end 370.064284 -280.893266)
		(width 0.1143)
		(layer "In11.Cu")
		(net "P5E_CPU0_P3_TX_DP<10>")
	)
	(segment
		(start 370.07673 -294.826182)
		(end 370.077492 -294.82669)
		(width 0.1143)
		(layer "In11.Cu")
		(net "P5E_CPU0_P3_TX_DP<10>")
	)
	(segment
		(start 385.125722 -374.324372)
		(end 385.125722 -381.987298)
		(width 0.14224)
		(layer "In11.Cu")
		(net "P5E_CPU0_P3_TX_DP<10>")
	)
	(segment
		(start 370.073936 -277.00478)
		(end 370.07546 -277.005542)
		(width 0.1143)
		(layer "In11.Cu")
		(net "P5E_CPU0_P3_TX_DP<10>")
	)
	(segment
		(start 370.071904 -293.203376)
		(end 370.072666 -293.203884)
		(width 0.1143)
		(layer "In11.Cu")
		(net "P5E_CPU0_P3_TX_DP<10>")
	)
	(segment
		(start 370.07546 -294.82542)
		(end 370.07673 -294.826182)
		(width 0.1143)
		(layer "In11.Cu")
		(net "P5E_CPU0_P3_TX_DP<10>")
	)
	(segment
		(start 370.103654 -288.970212)
		(end 370.073936 -288.98723)
		(width 0.1143)
		(layer "In11.Cu")
		(net "P5E_CPU0_P3_TX_DP<10>")
	)
	(segment
		(start 370.068348 -290.610544)
		(end 370.067586 -290.611052)
		(width 0.1143)
		(layer "In11.Cu")
		(net "P5E_CPU0_P3_TX_DP<10>")
	)
	(segment
		(start 370.071904 -282.508706)
		(end 370.070888 -282.509214)
		(width 0.1143)
		(layer "In11.Cu")
		(net "P5E_CPU0_P3_TX_DP<10>")
	)
	(segment
		(start 370.35486 -274.896072)
		(end 370.652802 -274.896072)
		(width 0.1143)
		(layer "In11.Cu")
		(net "P5E_CPU0_P3_TX_DP<10>")
	)
	(segment
		(start 370.064284 -280.893266)
		(end 370.032788 -280.911554)
		(width 0.1143)
		(layer "In11.Cu")
		(net "P5E_CPU0_P3_TX_DP<10>")
	)
	(segment
		(start 370.064284 -284.13329)
		(end 370.032788 -284.151578)
		(width 0.1143)
		(layer "In11.Cu")
		(net "P5E_CPU0_P3_TX_DP<10>")
	)
	(segment
		(start 370.040408 -294.8051)
		(end 370.071904 -294.823388)
		(width 0.1143)
		(layer "In11.Cu")
		(net "P5E_CPU0_P3_TX_DP<10>")
	)
	(segment
		(start 370.070888 -290.60902)
		(end 370.069364 -290.610036)
		(width 0.1143)
		(layer "In11.Cu")
		(net "P5E_CPU0_P3_TX_DP<10>")
	)
	(segment
		(start 370.068348 -280.890726)
		(end 370.067586 -280.891234)
		(width 0.1143)
		(layer "In11.Cu")
		(net "P5E_CPU0_P3_TX_DP<10>")
	)
	(segment
		(start 390.8552 -340.585044)
		(end 390.8552 -351.910142)
		(width 0.14224)
		(layer "In11.Cu")
		(net "P5E_CPU0_P3_TX_DP<10>")
	)
	(segment
		(start 370.103654 -280.870406)
		(end 370.073936 -280.887424)
		(width 0.1143)
		(layer "In11.Cu")
		(net "P5E_CPU0_P3_TX_DP<10>")
	)
	(segment
		(start 370.071904 -276.028658)
		(end 370.070888 -276.029166)
		(width 0.1143)
		(layer "In11.Cu")
		(net "P5E_CPU0_P3_TX_DP<10>")
	)
	(segment
		(start 370.082318 -278.629364)
		(end 370.103654 -278.64181)
		(width 0.1143)
		(layer "In11.Cu")
		(net "P5E_CPU0_P3_TX_DP<10>")
	)
	(segment
		(start 370.070888 -285.749238)
		(end 370.069364 -285.750254)
		(width 0.1143)
		(layer "In11.Cu")
		(net "P5E_CPU0_P3_TX_DP<10>")
	)
	(segment
		(start 370.073936 -293.204646)
		(end 370.07546 -293.205408)
		(width 0.1143)
		(layer "In11.Cu")
		(net "P5E_CPU0_P3_TX_DP<10>")
	)
	(segment
		(start 370.039646 -281.84475)
		(end 370.040408 -281.845258)
		(width 0.1143)
		(layer "In11.Cu")
		(net "P5E_CPU0_P3_TX_DP<10>")
	)
	(segment
		(start 370.079778 -294.82796)
		(end 370.082318 -294.82923)
		(width 0.1143)
		(layer "In11.Cu")
		(net "P5E_CPU0_P3_TX_DP<10>")
	)
	(segment
		(start 370.079778 -277.008082)
		(end 370.082318 -277.009352)
		(width 0.1143)
		(layer "In11.Cu")
		(net "P5E_CPU0_P3_TX_DP<10>")
	)
	(segment
		(start 370.077492 -281.866848)
		(end 370.078508 -281.867356)
		(width 0.1143)
		(layer "In11.Cu")
		(net "P5E_CPU0_P3_TX_DP<10>")
	)
	(segment
		(start 370.072666 -294.823896)
		(end 370.073936 -294.824658)
		(width 0.1143)
		(layer "In11.Cu")
		(net "P5E_CPU0_P3_TX_DP<10>")
	)
	(segment
		(start 370.032788 -288.320734)
		(end 370.071904 -288.343594)
		(width 0.1143)
		(layer "In11.Cu")
		(net "P5E_CPU0_P3_TX_DP<10>")
	)
	(arc
		(start 389.166608 -360.389932)
		(mid 389.150254 -360.449521)
		(end 389.132826 -360.508804)
		(width 0.14224)
		(layer "In11.Cu")
		(net "P5E_CPU0_P3_TX_DP<10>")
	)
	(arc
		(start 370.25961 -288.66592)
		(mid 370.218355 -288.836891)
		(end 370.103654 -288.970212)
		(width 0.1143)
		(layer "In11.Cu")
		(net "P5E_CPU0_P3_TX_DP<10>")
	)
	(arc
		(start 370.103654 -289.98164)
		(mid 370.259582 -290.285932)
		(end 370.103654 -290.590224)
		(width 0.1143)
		(layer "In11.Cu")
		(net "P5E_CPU0_P3_TX_DP<10>")
	)
	(arc
		(start 370.032788 -290.631372)
		(mid 369.789461 -291.095938)
		(end 370.032788 -291.560504)
		(width 0.1143)
		(layer "In11.Cu")
		(net "P5E_CPU0_P3_TX_DP<10>")
	)
	(arc
		(start 390.8552 -351.910142)
		(mid 390.852086 -351.973442)
		(end 390.842754 -352.036126)
		(width 0.14224)
		(layer "In11.Cu")
		(net "P5E_CPU0_P3_TX_DP<10>")
	)
	(arc
		(start 370.032788 -289.01136)
		(mid 369.789461 -289.475926)
		(end 370.032788 -289.940492)
		(width 0.1143)
		(layer "In11.Cu")
		(net "P5E_CPU0_P3_TX_DP<10>")
	)
	(arc
		(start 385.125722 -381.987298)
		(mid 385.113445 -382.049021)
		(end 385.078478 -382.101344)
		(width 0.14224)
		(layer "In11.Cu")
		(net "P5E_CPU0_P3_TX_DP<10>")
	)
	(arc
		(start 370.103654 -278.64181)
		(mid 370.21833 -278.775144)
		(end 370.25961 -278.946102)
		(width 0.1143)
		(layer "In11.Cu")
		(net "P5E_CPU0_P3_TX_DP<10>")
	)
	(arc
		(start 370.259356 -295.145968)
		(mid 370.323871 -295.408187)
		(end 370.502688 -295.610534)
		(width 0.1143)
		(layer "In11.Cu")
		(net "P5E_CPU0_P3_TX_DP<10>")
	)
	(arc
		(start 370.032788 -284.151578)
		(mid 369.789461 -284.616144)
		(end 370.032788 -285.08071)
		(width 0.1143)
		(layer "In11.Cu")
		(net "P5E_CPU0_P3_TX_DP<10>")
	)
	(arc
		(start 370.502942 -275.241512)
		(mid 370.324129 -275.443862)
		(end 370.25961 -275.706078)
		(width 0.1143)
		(layer "In11.Cu")
		(net "P5E_CPU0_P3_TX_DP<10>")
	)
	(arc
		(start 370.103654 -291.601652)
		(mid 370.259582 -291.905944)
		(end 370.103654 -292.210236)
		(width 0.1143)
		(layer "In11.Cu")
		(net "P5E_CPU0_P3_TX_DP<10>")
	)
	(arc
		(start 370.032788 -277.67153)
		(mid 369.789461 -278.136096)
		(end 370.032788 -278.600662)
		(width 0.1143)
		(layer "In11.Cu")
		(net "P5E_CPU0_P3_TX_DP<10>")
	)
	(arc
		(start 370.032788 -276.051518)
		(mid 369.789461 -276.516084)
		(end 370.032788 -276.98065)
		(width 0.1143)
		(layer "In11.Cu")
		(net "P5E_CPU0_P3_TX_DP<10>")
	)
	(arc
		(start 370.103654 -283.501846)
		(mid 370.259582 -283.806138)
		(end 370.103654 -284.11043)
		(width 0.1143)
		(layer "In11.Cu")
		(net "P5E_CPU0_P3_TX_DP<10>")
	)
	(arc
		(start 370.722652 -274.965922)
		(mid 370.670235 -275.097853)
		(end 370.572538 -275.200872)
		(width 0.1143)
		(layer "In11.Cu")
		(net "P5E_CPU0_P3_TX_DP<10>")
	)
	(arc
		(start 370.103654 -281.881834)
		(mid 370.259582 -282.186126)
		(end 370.103654 -282.490418)
		(width 0.1143)
		(layer "In11.Cu")
		(net "P5E_CPU0_P3_TX_DP<10>")
	)
	(arc
		(start 370.103654 -277.021798)
		(mid 370.259582 -277.32609)
		(end 370.103654 -277.630382)
		(width 0.1143)
		(layer "In11.Cu")
		(net "P5E_CPU0_P3_TX_DP<10>")
	)
	(arc
		(start 370.032788 -282.531566)
		(mid 369.789461 -282.996132)
		(end 370.032788 -283.460698)
		(width 0.1143)
		(layer "In11.Cu")
		(net "P5E_CPU0_P3_TX_DP<10>")
	)
	(arc
		(start 370.573554 -295.651682)
		(mid 370.609417 -295.681074)
		(end 370.641372 -295.714674)
		(width 0.1143)
		(layer "In11.Cu")
		(net "P5E_CPU0_P3_TX_DP<10>")
	)
	(arc
		(start 369.789456 -287.856168)
		(mid 369.853971 -288.118387)
		(end 370.032788 -288.320734)
		(width 0.1143)
		(layer "In11.Cu")
		(net "P5E_CPU0_P3_TX_DP<10>")
	)
	(arc
		(start 370.25961 -275.706078)
		(mid 370.218355 -275.877049)
		(end 370.103654 -276.01037)
		(width 0.1143)
		(layer "In11.Cu")
		(net "P5E_CPU0_P3_TX_DP<10>")
	)
	(arc
		(start 370.103654 -294.841676)
		(mid 370.21833 -294.97501)
		(end 370.25961 -295.145968)
		(width 0.1143)
		(layer "In11.Cu")
		(net "P5E_CPU0_P3_TX_DP<10>")
	)
	(arc
		(start 385.296918 -373.16791)
		(mid 385.168694 -373.739832)
		(end 385.125722 -374.324372)
		(width 0.14224)
		(layer "In11.Cu")
		(net "P5E_CPU0_P3_TX_DP<10>")
	)
	(arc
		(start 370.103654 -285.121858)
		(mid 370.259582 -285.42615)
		(end 370.103654 -285.730442)
		(width 0.1143)
		(layer "In11.Cu")
		(net "P5E_CPU0_P3_TX_DP<10>")
	)
	(arc
		(start 390.848088 -340.513924)
		(mid 390.85339 -340.549309)
		(end 390.8552 -340.585044)
		(width 0.14224)
		(layer "In11.Cu")
		(net "P5E_CPU0_P3_TX_DP<10>")
	)
	(arc
		(start 370.25961 -278.946102)
		(mid 370.324125 -279.208321)
		(end 370.502942 -279.410668)
		(width 0.1143)
		(layer "In11.Cu")
		(net "P5E_CPU0_P3_TX_DP<10>")
	)
	(arc
		(start 370.103654 -293.221664)
		(mid 370.259582 -293.525956)
		(end 370.103654 -293.830248)
		(width 0.1143)
		(layer "In11.Cu")
		(net "P5E_CPU0_P3_TX_DP<10>")
	)
	(arc
		(start 370.25961 -287.045908)
		(mid 370.218355 -287.216879)
		(end 370.103654 -287.3502)
		(width 0.1143)
		(layer "In11.Cu")
		(net "P5E_CPU0_P3_TX_DP<10>")
	)
	(arc
		(start 370.032788 -285.77159)
		(mid 369.789461 -286.236156)
		(end 370.032788 -286.700722)
		(width 0.1143)
		(layer "In11.Cu")
		(net "P5E_CPU0_P3_TX_DP<10>")
	)
	(arc
		(start 370.032788 -280.911554)
		(mid 369.789461 -281.37612)
		(end 370.032788 -281.840686)
		(width 0.1143)
		(layer "In11.Cu")
		(net "P5E_CPU0_P3_TX_DP<10>")
	)
	(arc
		(start 370.032788 -293.871396)
		(mid 369.789461 -294.335962)
		(end 370.032788 -294.800528)
		(width 0.1143)
		(layer "In11.Cu")
		(net "P5E_CPU0_P3_TX_DP<10>")
	)
	(arc
		(start 370.105432 -286.74314)
		(mid 370.218839 -286.876029)
		(end 370.25961 -287.045908)
		(width 0.1143)
		(layer "In11.Cu")
		(net "P5E_CPU0_P3_TX_DP<10>")
	)
	(arc
		(start 370.502942 -280.101548)
		(mid 370.324129 -280.303898)
		(end 370.25961 -280.566114)
		(width 0.1143)
		(layer "In11.Cu")
		(net "P5E_CPU0_P3_TX_DP<10>")
	)
	(arc
		(start 370.25961 -280.566114)
		(mid 370.218355 -280.737085)
		(end 370.103654 -280.870406)
		(width 0.1143)
		(layer "In11.Cu")
		(net "P5E_CPU0_P3_TX_DP<10>")
	)
	(arc
		(start 370.035328 -287.389824)
		(mid 369.854676 -287.592569)
		(end 369.789456 -287.856168)
		(width 0.1143)
		(layer "In11.Cu")
		(net "P5E_CPU0_P3_TX_DP<10>")
	)
	(arc
		(start 370.572538 -279.451308)
		(mid 370.729515 -279.756108)
		(end 370.572538 -280.060908)
		(width 0.1143)
		(layer "In11.Cu")
		(net "P5E_CPU0_P3_TX_DP<10>")
	)
	(arc
		(start 370.032788 -292.251384)
		(mid 369.789461 -292.71595)
		(end 370.032788 -293.180516)
		(width 0.1143)
		(layer "In11.Cu")
		(net "P5E_CPU0_P3_TX_DP<10>")
	)
	(arc
		(start 370.105432 -288.363152)
		(mid 370.218839 -288.496041)
		(end 370.25961 -288.66592)
		(width 0.1143)
		(layer "In11.Cu")
		(net "P5E_CPU0_P3_TX_DP<10>")
	)
	(arc
		(start 370.641372 -295.714674)
		(mid 370.706903 -295.827505)
		(end 370.729764 -295.955974)
		(width 0.1143)
		(layer "In11.Cu")
		(net "P5E_CPU0_P3_TX_DP<10>")
	)
	(arc
		(start 389.236966 -360.109516)
		(mid 389.22545 -360.162915)
		(end 389.212328 -360.215942)
		(width 0.14224)
		(layer "In11.Cu")
		(net "P5E_CPU0_P3_TX_DP<10>")
	)
	(segment
		(start 364.53064 -390.75106)
		(end 364.80115 -390.48055)
		(width 0.12954)
		(layer "F.Cu")
		(net "P5E_CPU0_P3_TX_DP<0>")
	)
	(segment
		(start 361.89793 -275.44014)
		(end 362.364782 -275.706078)
		(width 0.12954)
		(layer "F.Cu")
		(net "P5E_CPU0_P3_TX_DP<0>")
	)
	(segment
		(start 365.50473 -390.48055)
		(end 365.80064 -390.77646)
		(width 0.12954)
		(layer "F.Cu")
		(net "P5E_CPU0_P3_TX_DP<0>")
	)
	(segment
		(start 364.80115 -390.48055)
		(end 365.50473 -390.48055)
		(width 0.12954)
		(layer "F.Cu")
		(net "P5E_CPU0_P3_TX_DP<0>")
	)
	(segment
		(start 362.074206 -276.842982)
		(end 362.072682 -276.843998)
		(width 0.1143)
		(layer "In11.Cu")
		(net "P5E_CPU0_P3_TX_DP<0>")
	)
	(segment
		(start 362.071412 -276.844506)
		(end 362.069888 -276.845522)
		(width 0.1143)
		(layer "In11.Cu")
		(net "P5E_CPU0_P3_TX_DP<0>")
	)
	(segment
		(start 361.642406 -277.63089)
		(end 361.611926 -277.64867)
		(width 0.1143)
		(layer "In11.Cu")
		(net "P5E_CPU0_P3_TX_DP<0>")
	)
	(segment
		(start 363.470444 -377.246388)
		(end 363.470444 -382.969262)
		(width 0.14224)
		(layer "In11.Cu")
		(net "P5E_CPU0_P3_TX_DP<0>")
	)
	(segment
		(start 361.11434 -278.055578)
		(end 361.094274 -278.075644)
		(width 0.1143)
		(layer "In11.Cu")
		(net "P5E_CPU0_P3_TX_DP<0>")
	)
	(segment
		(start 362.804456 -384.331464)
		(end 362.804456 -389.399526)
		(width 0.14224)
		(layer "In11.Cu")
		(net "P5E_CPU0_P3_TX_DP<0>")
	)
	(segment
		(start 362.077 -276.841458)
		(end 362.075984 -276.841966)
		(width 0.1143)
		(layer "In11.Cu")
		(net "P5E_CPU0_P3_TX_DP<0>")
	)
	(segment
		(start 378.266198 -325.987664)
		(end 381.382016 -341.650828)
		(width 0.14224)
		(layer "In11.Cu")
		(net "P5E_CPU0_P3_TX_DP<0>")
	)
	(segment
		(start 360.614468 -278.55545)
		(end 360.614468 -295.710356)
		(width 0.14224)
		(layer "In11.Cu")
		(net "P5E_CPU0_P3_TX_DP<0>")
	)
	(segment
		(start 362.066586 -276.8473)
		(end 362.04271 -276.861524)
		(width 0.1143)
		(layer "In11.Cu")
		(net "P5E_CPU0_P3_TX_DP<0>")
	)
	(segment
		(start 374.683782 -363.297216)
		(end 374.683782 -363.29747)
		(width 0.14224)
		(layer "In11.Cu")
		(net "P5E_CPU0_P3_TX_DP<0>")
	)
	(segment
		(start 361.611926 -277.64867)
		(end 361.611672 -277.648924)
		(width 0.1143)
		(layer "In11.Cu")
		(net "P5E_CPU0_P3_TX_DP<0>")
	)
	(segment
		(start 374.684036 -363.297216)
		(end 374.683782 -363.297216)
		(width 0.14224)
		(layer "In11.Cu")
		(net "P5E_CPU0_P3_TX_DP<0>")
	)
	(segment
		(start 375.019824 -319.571116)
		(end 376.568208 -321.888612)
		(width 0.14224)
		(layer "In11.Cu")
		(net "P5E_CPU0_P3_TX_DP<0>")
	)
	(segment
		(start 381.382016 -341.650828)
		(end 381.382016 -346.830904)
		(width 0.14224)
		(layer "In11.Cu")
		(net "P5E_CPU0_P3_TX_DP<0>")
	)
	(segment
		(start 374.683782 -363.29747)
		(end 365.872268 -373.012208)
		(width 0.14224)
		(layer "In11.Cu")
		(net "P5E_CPU0_P3_TX_DP<0>")
	)
	(segment
		(start 362.847382 -303.477422)
		(end 367.385854 -310.269636)
		(width 0.14224)
		(layer "In11.Cu")
		(net "P5E_CPU0_P3_TX_DP<0>")
	)
	(segment
		(start 360.614468 -295.710356)
		(end 360.733086 -296.509694)
		(width 0.14224)
		(layer "In11.Cu")
		(net "P5E_CPU0_P3_TX_DP<0>")
	)
	(segment
		(start 364.240572 -390.46023)
		(end 364.53064 -390.750298)
		(width 0.14224)
		(layer "In11.Cu")
		(net "P5E_CPU0_P3_TX_DP<0>")
	)
	(segment
		(start 362.081826 -276.838664)
		(end 362.08081 -276.839172)
		(width 0.1143)
		(layer "In11.Cu")
		(net "P5E_CPU0_P3_TX_DP<0>")
	)
	(segment
		(start 362.269532 -276.51329)
		(end 362.269532 -276.516084)
		(width 0.1143)
		(layer "In11.Cu")
		(net "P5E_CPU0_P3_TX_DP<0>")
	)
	(segment
		(start 360.733086 -296.509694)
		(end 362.847382 -303.477422)
		(width 0.14224)
		(layer "In11.Cu")
		(net "P5E_CPU0_P3_TX_DP<0>")
	)
	(segment
		(start 376.568208 -321.888612)
		(end 378.266198 -325.987664)
		(width 0.14224)
		(layer "In11.Cu")
		(net "P5E_CPU0_P3_TX_DP<0>")
	)
	(segment
		(start 362.075984 -276.841966)
		(end 362.074206 -276.842982)
		(width 0.1143)
		(layer "In11.Cu")
		(net "P5E_CPU0_P3_TX_DP<0>")
	)
	(segment
		(start 362.072682 -276.843998)
		(end 362.071412 -276.844506)
		(width 0.1143)
		(layer "In11.Cu")
		(net "P5E_CPU0_P3_TX_DP<0>")
	)
	(segment
		(start 362.364782 -275.706078)
		(end 362.662724 -275.706078)
		(width 0.1143)
		(layer "In11.Cu")
		(net "P5E_CPU0_P3_TX_DP<0>")
	)
	(segment
		(start 362.113576 -276.820376)
		(end 362.082588 -276.838156)
		(width 0.1143)
		(layer "In11.Cu")
		(net "P5E_CPU0_P3_TX_DP<0>")
	)
	(segment
		(start 361.094274 -278.075644)
		(end 360.614468 -278.55545)
		(width 0.14224)
		(layer "In11.Cu")
		(net "P5E_CPU0_P3_TX_DP<0>")
	)
	(segment
		(start 364.53064 -390.750298)
		(end 364.53064 -390.75106)
		(width 0.14224)
		(layer "In11.Cu")
		(net "P5E_CPU0_P3_TX_DP<0>")
	)
	(segment
		(start 363.10824 -383.843784)
		(end 362.93425 -384.017774)
		(width 0.14224)
		(layer "In11.Cu")
		(net "P5E_CPU0_P3_TX_DP<0>")
	)
	(segment
		(start 362.082588 -276.838156)
		(end 362.081826 -276.838664)
		(width 0.1143)
		(layer "In11.Cu")
		(net "P5E_CPU0_P3_TX_DP<0>")
	)
	(segment
		(start 362.662724 -275.706078)
		(end 362.732574 -275.775928)
		(width 0.1143)
		(layer "In11.Cu")
		(net "P5E_CPU0_P3_TX_DP<0>")
	)
	(segment
		(start 362.08081 -276.839172)
		(end 362.077 -276.841458)
		(width 0.1143)
		(layer "In11.Cu")
		(net "P5E_CPU0_P3_TX_DP<0>")
	)
	(segment
		(start 380.699518 -350.493838)
		(end 378.755656 -355.53015)
		(width 0.14224)
		(layer "In11.Cu")
		(net "P5E_CPU0_P3_TX_DP<0>")
	)
	(segment
		(start 362.069888 -276.845522)
		(end 362.066586 -276.8473)
		(width 0.1143)
		(layer "In11.Cu")
		(net "P5E_CPU0_P3_TX_DP<0>")
	)
	(segment
		(start 362.583476 -276.01037)
		(end 362.513118 -276.051264)
		(width 0.1143)
		(layer "In11.Cu")
		(net "P5E_CPU0_P3_TX_DP<0>")
	)
	(segment
		(start 375.01957 -319.571116)
		(end 375.019824 -319.571116)
		(width 0.14224)
		(layer "In11.Cu")
		(net "P5E_CPU0_P3_TX_DP<0>")
	)
	(segment
		(start 363.13999 -390.209532)
		(end 363.2708 -390.340342)
		(width 0.14224)
		(layer "In11.Cu")
		(net "P5E_CPU0_P3_TX_DP<0>")
	)
	(segment
		(start 361.178602 -278.055578)
		(end 361.11434 -278.055578)
		(width 0.1143)
		(layer "In11.Cu")
		(net "P5E_CPU0_P3_TX_DP<0>")
	)
	(segment
		(start 367.385854 -310.269636)
		(end 375.01957 -319.571116)
		(width 0.14224)
		(layer "In11.Cu")
		(net "P5E_CPU0_P3_TX_DP<0>")
	)
	(segment
		(start 361.496356 -277.737824)
		(end 361.178602 -278.055578)
		(width 0.1143)
		(layer "In11.Cu")
		(net "P5E_CPU0_P3_TX_DP<0>")
	)
	(segment
		(start 363.56036 -390.46023)
		(end 364.240572 -390.46023)
		(width 0.14224)
		(layer "In11.Cu")
		(net "P5E_CPU0_P3_TX_DP<0>")
	)
	(arc
		(start 362.93425 -384.017774)
		(mid 362.838114 -384.161697)
		(end 362.804456 -384.331464)
		(width 0.14224)
		(layer "In11.Cu")
		(net "P5E_CPU0_P3_TX_DP<0>")
	)
	(arc
		(start 363.2708 -390.340342)
		(mid 363.403665 -390.429057)
		(end 363.56036 -390.46023)
		(width 0.14224)
		(layer "In11.Cu")
		(net "P5E_CPU0_P3_TX_DP<0>")
	)
	(arc
		(start 362.04271 -276.861524)
		(mid 361.863897 -277.063874)
		(end 361.799378 -277.32609)
		(width 0.1143)
		(layer "In11.Cu")
		(net "P5E_CPU0_P3_TX_DP<0>")
	)
	(arc
		(start 363.470444 -382.969262)
		(mid 363.376372 -383.442576)
		(end 363.10824 -383.843784)
		(width 0.14224)
		(layer "In11.Cu")
		(net "P5E_CPU0_P3_TX_DP<0>")
	)
	(arc
		(start 362.732574 -275.775928)
		(mid 362.680525 -275.907447)
		(end 362.583476 -276.01037)
		(width 0.1143)
		(layer "In11.Cu")
		(net "P5E_CPU0_P3_TX_DP<0>")
	)
	(arc
		(start 363.50575 -377.030742)
		(mid 363.479238 -377.137115)
		(end 363.470444 -377.246388)
		(width 0.14224)
		(layer "In11.Cu")
		(net "P5E_CPU0_P3_TX_DP<0>")
	)
	(arc
		(start 362.269532 -276.516084)
		(mid 362.228277 -276.687055)
		(end 362.113576 -276.820376)
		(width 0.1143)
		(layer "In11.Cu")
		(net "P5E_CPU0_P3_TX_DP<0>")
	)
	(arc
		(start 374.762014 -363.197648)
		(mid 374.724829 -363.248845)
		(end 374.684036 -363.297216)
		(width 0.14224)
		(layer "In11.Cu")
		(net "P5E_CPU0_P3_TX_DP<0>")
	)
	(arc
		(start 362.513118 -276.051264)
		(mid 362.334188 -276.252148)
		(end 362.269532 -276.51329)
		(width 0.1143)
		(layer "In11.Cu")
		(net "P5E_CPU0_P3_TX_DP<0>")
	)
	(arc
		(start 361.799378 -277.32609)
		(mid 361.757829 -277.497512)
		(end 361.642406 -277.63089)
		(width 0.1143)
		(layer "In11.Cu")
		(net "P5E_CPU0_P3_TX_DP<0>")
	)
	(arc
		(start 365.872268 -373.012208)
		(mid 364.48281 -374.900046)
		(end 363.50575 -377.030742)
		(width 0.14224)
		(layer "In11.Cu")
		(net "P5E_CPU0_P3_TX_DP<0>")
	)
	(arc
		(start 362.804456 -389.399526)
		(mid 362.891602 -389.83793)
		(end 363.13999 -390.209532)
		(width 0.14224)
		(layer "In11.Cu")
		(net "P5E_CPU0_P3_TX_DP<0>")
	)
	(arc
		(start 378.755656 -355.53015)
		(mid 376.973518 -359.475717)
		(end 374.762014 -363.197648)
		(width 0.14224)
		(layer "In11.Cu")
		(net "P5E_CPU0_P3_TX_DP<0>")
	)
	(arc
		(start 361.611672 -277.648924)
		(mid 361.551131 -277.689634)
		(end 361.496356 -277.737824)
		(width 0.1143)
		(layer "In11.Cu")
		(net "P5E_CPU0_P3_TX_DP<0>")
	)
	(arc
		(start 381.382016 -346.830904)
		(mid 381.209912 -348.693887)
		(end 380.699518 -350.493838)
		(width 0.14224)
		(layer "In11.Cu")
		(net "P5E_CPU0_P3_TX_DP<0>")
	)
	(segment
		(start 382.024382 -377.68784)
		(end 382.024382 -378.39142)
		(width 0.12954)
		(layer "F.Cu")
		(net "P5E_CPU0_P3_TX_DN<9>")
	)
	(segment
		(start 368.0079 -276.250146)
		(end 368.474752 -276.516084)
		(width 0.12954)
		(layer "F.Cu")
		(net "P5E_CPU0_P3_TX_DN<9>")
	)
	(segment
		(start 382.294892 -377.41733)
		(end 382.024382 -377.68784)
		(width 0.12954)
		(layer "F.Cu")
		(net "P5E_CPU0_P3_TX_DN<9>")
	)
	(segment
		(start 382.024382 -378.39142)
		(end 382.320292 -378.68733)
		(width 0.12954)
		(layer "F.Cu")
		(net "P5E_CPU0_P3_TX_DN<9>")
	)
	(segment
		(start 369.227608 -285.913576)
		(end 369.197128 -285.931356)
		(width 0.1143)
		(layer "In11.Cu")
		(net "P5E_CPU0_P3_TX_DN<9>")
	)
	(segment
		(start 369.98021 -295.955974)
		(end 369.98021 -296.089324)
		(width 0.1143)
		(layer "In11.Cu")
		(net "P5E_CPU0_P3_TX_DN<9>")
	)
	(segment
		(start 369.736878 -280.220674)
		(end 369.697762 -280.243534)
		(width 0.1143)
		(layer "In11.Cu")
		(net "P5E_CPU0_P3_TX_DN<9>")
	)
	(segment
		(start 369.266724 -281.03068)
		(end 369.227608 -281.05354)
		(width 0.1143)
		(layer "In11.Cu")
		(net "P5E_CPU0_P3_TX_DN<9>")
	)
	(segment
		(start 369.266724 -290.750498)
		(end 369.227608 -290.773358)
		(width 0.1143)
		(layer "In11.Cu")
		(net "P5E_CPU0_P3_TX_DN<9>")
	)
	(segment
		(start 369.697 -280.244042)
		(end 369.69573 -280.244804)
		(width 0.1143)
		(layer "In11.Cu")
		(net "P5E_CPU0_P3_TX_DN<9>")
	)
	(segment
		(start 369.697762 -280.243534)
		(end 369.697 -280.244042)
		(width 0.1143)
		(layer "In11.Cu")
		(net "P5E_CPU0_P3_TX_DN<9>")
	)
	(segment
		(start 370.062252 -296.538142)
		(end 370.107972 -296.583862)
		(width 0.1143)
		(layer "In11.Cu")
		(net "P5E_CPU0_P3_TX_DN<9>")
	)
	(segment
		(start 369.666012 -279.250394)
		(end 369.697 -279.268174)
		(width 0.1143)
		(layer "In11.Cu")
		(net "P5E_CPU0_P3_TX_DN<9>")
	)
	(segment
		(start 368.287046 -276.838156)
		(end 368.287808 -276.838664)
		(width 0.1143)
		(layer "In11.Cu")
		(net "P5E_CPU0_P3_TX_DN<9>")
	)
	(segment
		(start 369.266724 -282.650692)
		(end 369.227608 -282.673552)
		(width 0.1143)
		(layer "In11.Cu")
		(net "P5E_CPU0_P3_TX_DN<9>")
	)
	(segment
		(start 370.107972 -296.61231)
		(end 370.107972 -296.980102)
		(width 0.14224)
		(layer "In11.Cu")
		(net "P5E_CPU0_P3_TX_DN<9>")
	)
	(segment
		(start 382.004062 -377.1265)
		(end 382.294892 -377.41733)
		(width 0.14224)
		(layer "In11.Cu")
		(net "P5E_CPU0_P3_TX_DN<9>")
	)
	(segment
		(start 379.510798 -310.633618)
		(end 384.970274 -318.804036)
		(width 0.14224)
		(layer "In11.Cu")
		(net "P5E_CPU0_P3_TX_DN<9>")
	)
	(segment
		(start 368.723164 -277.62835)
		(end 368.725958 -277.630382)
		(width 0.1143)
		(layer "In11.Cu")
		(net "P5E_CPU0_P3_TX_DN<9>")
	)
	(segment
		(start 369.227608 -289.153346)
		(end 369.197128 -289.171126)
		(width 0.1143)
		(layer "In11.Cu")
		(net "P5E_CPU0_P3_TX_DN<9>")
	)
	(segment
		(start 386.69468 -322.96608)
		(end 390.203944 -340.60892)
		(width 0.14224)
		(layer "In11.Cu")
		(net "P5E_CPU0_P3_TX_DN<9>")
	)
	(segment
		(start 369.227608 -291.418518)
		(end 369.266724 -291.441378)
		(width 0.1143)
		(layer "In11.Cu")
		(net "P5E_CPU0_P3_TX_DN<9>")
	)
	(segment
		(start 372.746524 -302.391064)
		(end 379.510798 -310.633618)
		(width 0.14224)
		(layer "In11.Cu")
		(net "P5E_CPU0_P3_TX_DN<9>")
	)
	(segment
		(start 369.227608 -294.013382)
		(end 369.197128 -294.031162)
		(width 0.1143)
		(layer "In11.Cu")
		(net "P5E_CPU0_P3_TX_DN<9>")
	)
	(segment
		(start 369.227608 -281.6987)
		(end 369.266724 -281.72156)
		(width 0.1143)
		(layer "In11.Cu")
		(net "P5E_CPU0_P3_TX_DN<9>")
	)
	(segment
		(start 369.197128 -293.02075)
		(end 369.227608 -293.03853)
		(width 0.1143)
		(layer "In11.Cu")
		(net "P5E_CPU0_P3_TX_DN<9>")
	)
	(segment
		(start 369.197128 -291.400738)
		(end 369.227608 -291.418518)
		(width 0.1143)
		(layer "In11.Cu")
		(net "P5E_CPU0_P3_TX_DN<9>")
	)
	(segment
		(start 369.266724 -293.990522)
		(end 369.227608 -294.013382)
		(width 0.1143)
		(layer "In11.Cu")
		(net "P5E_CPU0_P3_TX_DN<9>")
	)
	(segment
		(start 384.970274 -318.804036)
		(end 386.69468 -322.96608)
		(width 0.14224)
		(layer "In11.Cu")
		(net "P5E_CPU0_P3_TX_DN<9>")
	)
	(segment
		(start 369.227608 -284.293564)
		(end 369.197128 -284.311344)
		(width 0.1143)
		(layer "In11.Cu")
		(net "P5E_CPU0_P3_TX_DN<9>")
	)
	(segment
		(start 368.287808 -276.838664)
		(end 368.29111 -276.840696)
		(width 0.1143)
		(layer "In11.Cu")
		(net "P5E_CPU0_P3_TX_DN<9>")
	)
	(segment
		(start 369.197128 -294.640762)
		(end 369.227608 -294.658542)
		(width 0.1143)
		(layer "In11.Cu")
		(net "P5E_CPU0_P3_TX_DN<9>")
	)
	(segment
		(start 369.697762 -279.268682)
		(end 369.698778 -279.26919)
		(width 0.1143)
		(layer "In11.Cu")
		(net "P5E_CPU0_P3_TX_DN<9>")
	)
	(segment
		(start 369.227608 -284.938724)
		(end 369.266724 -284.961584)
		(width 0.1143)
		(layer "In11.Cu")
		(net "P5E_CPU0_P3_TX_DN<9>")
	)
	(segment
		(start 370.920518 -299.658024)
		(end 372.746524 -302.391064)
		(width 0.14224)
		(layer "In11.Cu")
		(net "P5E_CPU0_P3_TX_DN<9>")
	)
	(segment
		(start 369.227608 -292.39337)
		(end 369.197128 -292.41115)
		(width 0.1143)
		(layer "In11.Cu")
		(net "P5E_CPU0_P3_TX_DN<9>")
	)
	(segment
		(start 370.062252 -296.171366)
		(end 370.062252 -296.538142)
		(width 0.1143)
		(layer "In11.Cu")
		(net "P5E_CPU0_P3_TX_DN<9>")
	)
	(segment
		(start 369.197128 -278.440896)
		(end 369.227608 -278.458676)
		(width 0.1143)
		(layer "In11.Cu")
		(net "P5E_CPU0_P3_TX_DN<9>")
	)
	(segment
		(start 369.227608 -289.798506)
		(end 369.266724 -289.821366)
		(width 0.1143)
		(layer "In11.Cu")
		(net "P5E_CPU0_P3_TX_DN<9>")
	)
	(segment
		(start 369.227608 -290.773358)
		(end 369.197128 -290.791138)
		(width 0.1143)
		(layer "In11.Cu")
		(net "P5E_CPU0_P3_TX_DN<9>")
	)
	(segment
		(start 369.266724 -284.270704)
		(end 369.227608 -284.293564)
		(width 0.1143)
		(layer "In11.Cu")
		(net "P5E_CPU0_P3_TX_DN<9>")
	)
	(segment
		(start 369.197128 -289.780726)
		(end 369.227608 -289.798506)
		(width 0.1143)
		(layer "In11.Cu")
		(net "P5E_CPU0_P3_TX_DN<9>")
	)
	(segment
		(start 369.227608 -293.03853)
		(end 369.266724 -293.06139)
		(width 0.1143)
		(layer "In11.Cu")
		(net "P5E_CPU0_P3_TX_DN<9>")
	)
	(segment
		(start 368.29111 -276.840696)
		(end 368.32413 -276.859746)
		(width 0.1143)
		(layer "In11.Cu")
		(net "P5E_CPU0_P3_TX_DN<9>")
	)
	(segment
		(start 369.197128 -284.920944)
		(end 369.227608 -284.938724)
		(width 0.1143)
		(layer "In11.Cu")
		(net "P5E_CPU0_P3_TX_DN<9>")
	)
	(segment
		(start 369.701318 -279.270714)
		(end 369.736878 -279.291542)
		(width 0.1143)
		(layer "In11.Cu")
		(net "P5E_CPU0_P3_TX_DN<9>")
	)
	(segment
		(start 369.266724 -285.890716)
		(end 369.227608 -285.913576)
		(width 0.1143)
		(layer "In11.Cu")
		(net "P5E_CPU0_P3_TX_DN<9>")
	)
	(segment
		(start 369.227608 -278.458676)
		(end 369.266724 -278.481536)
		(width 0.1143)
		(layer "In11.Cu")
		(net "P5E_CPU0_P3_TX_DN<9>")
	)
	(segment
		(start 382.445514 -375.011188)
		(end 382.236472 -375.402602)
		(width 0.14224)
		(layer "In11.Cu")
		(net "P5E_CPU0_P3_TX_DN<9>")
	)
	(segment
		(start 382.004062 -376.33021)
		(end 382.004062 -377.1265)
		(width 0.14224)
		(layer "In11.Cu")
		(net "P5E_CPU0_P3_TX_DN<9>")
	)
	(segment
		(start 369.195096 -286.539686)
		(end 369.227608 -286.558482)
		(width 0.1143)
		(layer "In11.Cu")
		(net "P5E_CPU0_P3_TX_DN<9>")
	)
	(segment
		(start 369.264184 -287.512252)
		(end 369.197128 -287.551368)
		(width 0.1143)
		(layer "In11.Cu")
		(net "P5E_CPU0_P3_TX_DN<9>")
	)
	(segment
		(start 390.203944 -351.755964)
		(end 387.959092 -360.7181)
		(width 0.14224)
		(layer "In11.Cu")
		(net "P5E_CPU0_P3_TX_DN<9>")
	)
	(segment
		(start 368.256058 -276.820376)
		(end 368.287046 -276.838156)
		(width 0.1143)
		(layer "In11.Cu")
		(net "P5E_CPU0_P3_TX_DN<9>")
	)
	(segment
		(start 369.698778 -279.26919)
		(end 369.700302 -279.270206)
		(width 0.1143)
		(layer "In11.Cu")
		(net "P5E_CPU0_P3_TX_DN<9>")
	)
	(segment
		(start 368.474752 -276.516084)
		(end 368.17681 -276.516084)
		(width 0.1143)
		(layer "In11.Cu")
		(net "P5E_CPU0_P3_TX_DN<9>")
	)
	(segment
		(start 370.107972 -296.980102)
		(end 370.920518 -299.658024)
		(width 0.14224)
		(layer "In11.Cu")
		(net "P5E_CPU0_P3_TX_DN<9>")
	)
	(segment
		(start 369.227608 -283.318712)
		(end 369.266724 -283.341572)
		(width 0.1143)
		(layer "In11.Cu")
		(net "P5E_CPU0_P3_TX_DN<9>")
	)
	(segment
		(start 368.570002 -277.32609)
		(end 368.570002 -277.329138)
		(width 0.1143)
		(layer "In11.Cu")
		(net "P5E_CPU0_P3_TX_DN<9>")
	)
	(segment
		(start 368.17681 -276.516084)
		(end 368.10696 -276.585934)
		(width 0.1143)
		(layer "In11.Cu")
		(net "P5E_CPU0_P3_TX_DN<9>")
	)
	(segment
		(start 369.227608 -282.673552)
		(end 369.197128 -282.691332)
		(width 0.1143)
		(layer "In11.Cu")
		(net "P5E_CPU0_P3_TX_DN<9>")
	)
	(segment
		(start 368.725958 -277.630382)
		(end 368.796824 -277.67153)
		(width 0.1143)
		(layer "In11.Cu")
		(net "P5E_CPU0_P3_TX_DN<9>")
	)
	(segment
		(start 369.195096 -288.159698)
		(end 369.227608 -288.178494)
		(width 0.1143)
		(layer "In11.Cu")
		(net "P5E_CPU0_P3_TX_DN<9>")
	)
	(segment
		(start 369.697 -279.268174)
		(end 369.697762 -279.268682)
		(width 0.1143)
		(layer "In11.Cu")
		(net "P5E_CPU0_P3_TX_DN<9>")
	)
	(segment
		(start 370.107972 -296.583862)
		(end 370.107972 -296.61231)
		(width 0.1143)
		(layer "In11.Cu")
		(net "P5E_CPU0_P3_TX_DN<9>")
	)
	(segment
		(start 369.667536 -295.451022)
		(end 369.736878 -295.491408)
		(width 0.1143)
		(layer "In11.Cu")
		(net "P5E_CPU0_P3_TX_DN<9>")
	)
	(segment
		(start 369.197128 -281.68092)
		(end 369.227608 -281.6987)
		(width 0.1143)
		(layer "In11.Cu")
		(net "P5E_CPU0_P3_TX_DN<9>")
	)
	(segment
		(start 369.700302 -279.270206)
		(end 369.701318 -279.270714)
		(width 0.1143)
		(layer "In11.Cu")
		(net "P5E_CPU0_P3_TX_DN<9>")
	)
	(segment
		(start 369.227608 -294.658542)
		(end 369.266724 -294.681402)
		(width 0.1143)
		(layer "In11.Cu")
		(net "P5E_CPU0_P3_TX_DN<9>")
	)
	(segment
		(start 369.266724 -289.130486)
		(end 369.227608 -289.153346)
		(width 0.1143)
		(layer "In11.Cu")
		(net "P5E_CPU0_P3_TX_DN<9>")
	)
	(segment
		(start 390.203944 -340.60892)
		(end 390.203944 -351.755964)
		(width 0.14224)
		(layer "In11.Cu")
		(net "P5E_CPU0_P3_TX_DN<9>")
	)
	(segment
		(start 369.69573 -280.244804)
		(end 369.666012 -280.261822)
		(width 0.1143)
		(layer "In11.Cu")
		(net "P5E_CPU0_P3_TX_DN<9>")
	)
	(segment
		(start 369.197128 -283.300932)
		(end 369.227608 -283.318712)
		(width 0.1143)
		(layer "In11.Cu")
		(net "P5E_CPU0_P3_TX_DN<9>")
	)
	(segment
		(start 369.227608 -281.05354)
		(end 369.197128 -281.07132)
		(width 0.1143)
		(layer "In11.Cu")
		(net "P5E_CPU0_P3_TX_DN<9>")
	)
	(segment
		(start 369.227608 -286.558482)
		(end 369.266724 -286.581342)
		(width 0.1143)
		(layer "In11.Cu")
		(net "P5E_CPU0_P3_TX_DN<9>")
	)
	(segment
		(start 369.227608 -288.178494)
		(end 369.266724 -288.201354)
		(width 0.1143)
		(layer "In11.Cu")
		(net "P5E_CPU0_P3_TX_DN<9>")
	)
	(segment
		(start 369.98021 -296.089324)
		(end 370.062252 -296.171366)
		(width 0.1143)
		(layer "In11.Cu")
		(net "P5E_CPU0_P3_TX_DN<9>")
	)
	(segment
		(start 369.266724 -292.37051)
		(end 369.227608 -292.39337)
		(width 0.1143)
		(layer "In11.Cu")
		(net "P5E_CPU0_P3_TX_DN<9>")
	)
	(arc
		(start 369.197128 -294.031162)
		(mid 369.040151 -294.335962)
		(end 369.197128 -294.640762)
		(width 0.1143)
		(layer "In11.Cu")
		(net "P5E_CPU0_P3_TX_DN<9>")
	)
	(arc
		(start 369.040156 -287.856168)
		(mid 369.081122 -288.026574)
		(end 369.195096 -288.159698)
		(width 0.1143)
		(layer "In11.Cu")
		(net "P5E_CPU0_P3_TX_DN<9>")
	)
	(arc
		(start 369.666012 -280.261822)
		(mid 369.551336 -280.395156)
		(end 369.510056 -280.566114)
		(width 0.1143)
		(layer "In11.Cu")
		(net "P5E_CPU0_P3_TX_DN<9>")
	)
	(arc
		(start 369.510056 -278.946102)
		(mid 369.551311 -279.117073)
		(end 369.666012 -279.250394)
		(width 0.1143)
		(layer "In11.Cu")
		(net "P5E_CPU0_P3_TX_DN<9>")
	)
	(arc
		(start 369.266724 -291.441378)
		(mid 369.510051 -291.905944)
		(end 369.266724 -292.37051)
		(width 0.1143)
		(layer "In11.Cu")
		(net "P5E_CPU0_P3_TX_DN<9>")
	)
	(arc
		(start 369.736878 -295.491408)
		(mid 369.798129 -295.540601)
		(end 369.85194 -295.597834)
		(width 0.1143)
		(layer "In11.Cu")
		(net "P5E_CPU0_P3_TX_DN<9>")
	)
	(arc
		(start 369.266724 -286.581342)
		(mid 369.445537 -286.783692)
		(end 369.510056 -287.045908)
		(width 0.1143)
		(layer "In11.Cu")
		(net "P5E_CPU0_P3_TX_DN<9>")
	)
	(arc
		(start 369.266724 -293.06139)
		(mid 369.510051 -293.525956)
		(end 369.266724 -293.990522)
		(width 0.1143)
		(layer "In11.Cu")
		(net "P5E_CPU0_P3_TX_DN<9>")
	)
	(arc
		(start 369.266724 -278.481536)
		(mid 369.445537 -278.683886)
		(end 369.510056 -278.946102)
		(width 0.1143)
		(layer "In11.Cu")
		(net "P5E_CPU0_P3_TX_DN<9>")
	)
	(arc
		(start 369.266724 -294.681402)
		(mid 369.445537 -294.883752)
		(end 369.510056 -295.145968)
		(width 0.1143)
		(layer "In11.Cu")
		(net "P5E_CPU0_P3_TX_DN<9>")
	)
	(arc
		(start 369.197128 -281.07132)
		(mid 369.040151 -281.37612)
		(end 369.197128 -281.68092)
		(width 0.1143)
		(layer "In11.Cu")
		(net "P5E_CPU0_P3_TX_DN<9>")
	)
	(arc
		(start 369.266724 -281.72156)
		(mid 369.510051 -282.186126)
		(end 369.266724 -282.650692)
		(width 0.1143)
		(layer "In11.Cu")
		(net "P5E_CPU0_P3_TX_DN<9>")
	)
	(arc
		(start 369.510056 -295.145968)
		(mid 369.551807 -295.317588)
		(end 369.667536 -295.451022)
		(width 0.1143)
		(layer "In11.Cu")
		(net "P5E_CPU0_P3_TX_DN<9>")
	)
	(arc
		(start 369.197128 -282.691332)
		(mid 369.040151 -282.996132)
		(end 369.197128 -283.300932)
		(width 0.1143)
		(layer "In11.Cu")
		(net "P5E_CPU0_P3_TX_DN<9>")
	)
	(arc
		(start 368.796824 -277.67153)
		(mid 368.975637 -277.87388)
		(end 369.040156 -278.136096)
		(width 0.1143)
		(layer "In11.Cu")
		(net "P5E_CPU0_P3_TX_DN<9>")
	)
	(arc
		(start 368.10696 -276.585934)
		(mid 368.159009 -276.717453)
		(end 368.256058 -276.820376)
		(width 0.1143)
		(layer "In11.Cu")
		(net "P5E_CPU0_P3_TX_DN<9>")
	)
	(arc
		(start 369.266724 -284.961584)
		(mid 369.510051 -285.42615)
		(end 369.266724 -285.890716)
		(width 0.1143)
		(layer "In11.Cu")
		(net "P5E_CPU0_P3_TX_DN<9>")
	)
	(arc
		(start 369.510056 -287.045908)
		(mid 369.44482 -287.309499)
		(end 369.264184 -287.512252)
		(width 0.1143)
		(layer "In11.Cu")
		(net "P5E_CPU0_P3_TX_DN<9>")
	)
	(arc
		(start 369.197128 -284.311344)
		(mid 369.040151 -284.616144)
		(end 369.197128 -284.920944)
		(width 0.1143)
		(layer "In11.Cu")
		(net "P5E_CPU0_P3_TX_DN<9>")
	)
	(arc
		(start 369.510056 -280.566114)
		(mid 369.445541 -280.828333)
		(end 369.266724 -281.03068)
		(width 0.1143)
		(layer "In11.Cu")
		(net "P5E_CPU0_P3_TX_DN<9>")
	)
	(arc
		(start 368.570002 -277.329138)
		(mid 368.610448 -277.497253)
		(end 368.723164 -277.62835)
		(width 0.1143)
		(layer "In11.Cu")
		(net "P5E_CPU0_P3_TX_DN<9>")
	)
	(arc
		(start 369.266724 -289.821366)
		(mid 369.510051 -290.285932)
		(end 369.266724 -290.750498)
		(width 0.1143)
		(layer "In11.Cu")
		(net "P5E_CPU0_P3_TX_DN<9>")
	)
	(arc
		(start 369.266724 -288.201354)
		(mid 369.510051 -288.66592)
		(end 369.266724 -289.130486)
		(width 0.1143)
		(layer "In11.Cu")
		(net "P5E_CPU0_P3_TX_DN<9>")
	)
	(arc
		(start 369.197128 -285.931356)
		(mid 369.081701 -286.064732)
		(end 369.040156 -286.236156)
		(width 0.1143)
		(layer "In11.Cu")
		(net "P5E_CPU0_P3_TX_DN<9>")
	)
	(arc
		(start 368.32413 -276.859746)
		(mid 368.504782 -277.062491)
		(end 368.570002 -277.32609)
		(width 0.1143)
		(layer "In11.Cu")
		(net "P5E_CPU0_P3_TX_DN<9>")
	)
	(arc
		(start 369.197128 -289.171126)
		(mid 369.040151 -289.475926)
		(end 369.197128 -289.780726)
		(width 0.1143)
		(layer "In11.Cu")
		(net "P5E_CPU0_P3_TX_DN<9>")
	)
	(arc
		(start 387.959092 -360.7181)
		(mid 385.641364 -368.034013)
		(end 382.445514 -375.011188)
		(width 0.14224)
		(layer "In11.Cu")
		(net "P5E_CPU0_P3_TX_DN<9>")
	)
	(arc
		(start 369.040156 -278.136096)
		(mid 369.081705 -278.307518)
		(end 369.197128 -278.440896)
		(width 0.1143)
		(layer "In11.Cu")
		(net "P5E_CPU0_P3_TX_DN<9>")
	)
	(arc
		(start 369.197128 -287.551368)
		(mid 369.081701 -287.684744)
		(end 369.040156 -287.856168)
		(width 0.1143)
		(layer "In11.Cu")
		(net "P5E_CPU0_P3_TX_DN<9>")
	)
	(arc
		(start 369.98021 -295.9481)
		(mid 369.980225 -295.952037)
		(end 369.98021 -295.955974)
		(width 0.1143)
		(layer "In11.Cu")
		(net "P5E_CPU0_P3_TX_DN<9>")
	)
	(arc
		(start 369.040156 -286.236156)
		(mid 369.081122 -286.406562)
		(end 369.195096 -286.539686)
		(width 0.1143)
		(layer "In11.Cu")
		(net "P5E_CPU0_P3_TX_DN<9>")
	)
	(arc
		(start 369.266724 -283.341572)
		(mid 369.510051 -283.806138)
		(end 369.266724 -284.270704)
		(width 0.1143)
		(layer "In11.Cu")
		(net "P5E_CPU0_P3_TX_DN<9>")
	)
	(arc
		(start 369.85194 -295.597834)
		(mid 369.943333 -295.762981)
		(end 369.98021 -295.9481)
		(width 0.1143)
		(layer "In11.Cu")
		(net "P5E_CPU0_P3_TX_DN<9>")
	)
	(arc
		(start 382.236472 -375.402602)
		(mid 382.063068 -375.852076)
		(end 382.004062 -376.33021)
		(width 0.14224)
		(layer "In11.Cu")
		(net "P5E_CPU0_P3_TX_DN<9>")
	)
	(arc
		(start 369.197128 -290.791138)
		(mid 369.040151 -291.095938)
		(end 369.197128 -291.400738)
		(width 0.1143)
		(layer "In11.Cu")
		(net "P5E_CPU0_P3_TX_DN<9>")
	)
	(arc
		(start 369.197128 -292.41115)
		(mid 369.040151 -292.71595)
		(end 369.197128 -293.02075)
		(width 0.1143)
		(layer "In11.Cu")
		(net "P5E_CPU0_P3_TX_DN<9>")
	)
	(arc
		(start 369.736878 -279.291542)
		(mid 369.980205 -279.756108)
		(end 369.736878 -280.220674)
		(width 0.1143)
		(layer "In11.Cu")
		(net "P5E_CPU0_P3_TX_DN<9>")
	)
	(segment
		(start 368.0079 -277.870158)
		(end 368.474752 -278.136096)
		(width 0.12954)
		(layer "F.Cu")
		(net "P5E_CPU0_P3_TX_DN<8>")
	)
	(segment
		(start 380.593092 -379.88113)
		(end 380.322582 -380.15164)
		(width 0.12954)
		(layer "F.Cu")
		(net "P5E_CPU0_P3_TX_DN<8>")
	)
	(segment
		(start 380.322582 -380.15164)
		(end 380.322582 -380.85522)
		(width 0.12954)
		(layer "F.Cu")
		(net "P5E_CPU0_P3_TX_DN<8>")
	)
	(segment
		(start 380.322582 -380.85522)
		(end 380.618492 -381.15113)
		(width 0.12954)
		(layer "F.Cu")
		(net "P5E_CPU0_P3_TX_DN<8>")
	)
	(segment
		(start 368.256058 -281.680412)
		(end 368.287808 -281.6987)
		(width 0.1143)
		(layer "In11.Cu")
		(net "P5E_CPU0_P3_TX_DN<8>")
	)
	(segment
		(start 369.040156 -295.955974)
		(end 369.040156 -296.109898)
		(width 0.1143)
		(layer "In11.Cu")
		(net "P5E_CPU0_P3_TX_DN<8>")
	)
	(segment
		(start 368.287808 -294.658542)
		(end 368.327686 -294.682164)
		(width 0.1143)
		(layer "In11.Cu")
		(net "P5E_CPU0_P3_TX_DN<8>")
	)
	(segment
		(start 369.040156 -296.109898)
		(end 369.11661 -296.186352)
		(width 0.1143)
		(layer "In11.Cu")
		(net "P5E_CPU0_P3_TX_DN<8>")
	)
	(segment
		(start 368.290856 -282.671774)
		(end 368.256058 -282.69184)
		(width 0.1143)
		(layer "In11.Cu")
		(net "P5E_CPU0_P3_TX_DN<8>")
	)
	(segment
		(start 368.287808 -293.03853)
		(end 368.290856 -293.040308)
		(width 0.1143)
		(layer "In11.Cu")
		(net "P5E_CPU0_P3_TX_DN<8>")
	)
	(segment
		(start 368.25428 -288.158936)
		(end 368.255042 -288.159444)
		(width 0.1143)
		(layer "In11.Cu")
		(net "P5E_CPU0_P3_TX_DN<8>")
	)
	(segment
		(start 368.558064 -280.574496)
		(end 368.558064 -280.585926)
		(width 0.1143)
		(layer "In11.Cu")
		(net "P5E_CPU0_P3_TX_DN<8>")
	)
	(segment
		(start 368.256058 -289.780218)
		(end 368.287808 -289.798506)
		(width 0.1143)
		(layer "In11.Cu")
		(net "P5E_CPU0_P3_TX_DN<8>")
	)
	(segment
		(start 368.474752 -278.136096)
		(end 368.17681 -278.136096)
		(width 0.1143)
		(layer "In11.Cu")
		(net "P5E_CPU0_P3_TX_DN<8>")
	)
	(segment
		(start 368.287046 -278.458168)
		(end 368.287808 -278.458676)
		(width 0.1143)
		(layer "In11.Cu")
		(net "P5E_CPU0_P3_TX_DN<8>")
	)
	(segment
		(start 368.287046 -283.318204)
		(end 368.287808 -283.318712)
		(width 0.1143)
		(layer "In11.Cu")
		(net "P5E_CPU0_P3_TX_DN<8>")
	)
	(segment
		(start 372.111524 -303.149254)
		(end 378.911104 -311.43448)
		(width 0.14224)
		(layer "In11.Cu")
		(net "P5E_CPU0_P3_TX_DN<8>")
	)
	(segment
		(start 369.16233 -296.61231)
		(end 369.162838 -296.612818)
		(width 0.14224)
		(layer "In11.Cu")
		(net "P5E_CPU0_P3_TX_DN<8>")
	)
	(segment
		(start 368.338862 -292.362128)
		(end 368.325908 -292.371526)
		(width 0.1143)
		(layer "In11.Cu")
		(net "P5E_CPU0_P3_TX_DN<8>")
	)
	(segment
		(start 368.582702 -278.953468)
		(end 368.582702 -278.965914)
		(width 0.1143)
		(layer "In11.Cu")
		(net "P5E_CPU0_P3_TX_DN<8>")
	)
	(segment
		(start 368.256058 -294.640254)
		(end 368.287808 -294.658542)
		(width 0.1143)
		(layer "In11.Cu")
		(net "P5E_CPU0_P3_TX_DN<8>")
	)
	(segment
		(start 368.287808 -291.418518)
		(end 368.287808 -291.418772)
		(width 0.1143)
		(layer "In11.Cu")
		(net "P5E_CPU0_P3_TX_DN<8>")
	)
	(segment
		(start 368.757708 -279.268682)
		(end 368.796824 -279.291542)
		(width 0.1143)
		(layer "In11.Cu")
		(net "P5E_CPU0_P3_TX_DN<8>")
	)
	(segment
		(start 368.287808 -289.798506)
		(end 368.290856 -289.800284)
		(width 0.1143)
		(layer "In11.Cu")
		(net "P5E_CPU0_P3_TX_DN<8>")
	)
	(segment
		(start 368.256058 -293.020242)
		(end 368.287808 -293.03853)
		(width 0.1143)
		(layer "In11.Cu")
		(net "P5E_CPU0_P3_TX_DN<8>")
	)
	(segment
		(start 369.16233 -296.583862)
		(end 369.16233 -296.61231)
		(width 0.1143)
		(layer "In11.Cu")
		(net "P5E_CPU0_P3_TX_DN<8>")
	)
	(segment
		(start 368.287808 -284.938724)
		(end 368.290856 -284.940502)
		(width 0.1143)
		(layer "In11.Cu")
		(net "P5E_CPU0_P3_TX_DN<8>")
	)
	(segment
		(start 368.25428 -286.538924)
		(end 368.328956 -286.582866)
		(width 0.1143)
		(layer "In11.Cu")
		(net "P5E_CPU0_P3_TX_DN<8>")
	)
	(segment
		(start 368.256058 -284.920436)
		(end 368.287808 -284.938724)
		(width 0.1143)
		(layer "In11.Cu")
		(net "P5E_CPU0_P3_TX_DN<8>")
	)
	(segment
		(start 388.759192 -353.32162)
		(end 387.273038 -359.254044)
		(width 0.14224)
		(layer "In11.Cu")
		(net "P5E_CPU0_P3_TX_DN<8>")
	)
	(segment
		(start 368.287808 -288.178494)
		(end 368.290856 -288.180272)
		(width 0.1143)
		(layer "In11.Cu")
		(net "P5E_CPU0_P3_TX_DN<8>")
	)
	(segment
		(start 368.290856 -290.77158)
		(end 368.256058 -290.791646)
		(width 0.1143)
		(layer "In11.Cu")
		(net "P5E_CPU0_P3_TX_DN<8>")
	)
	(segment
		(start 368.255042 -288.159444)
		(end 368.287808 -288.178494)
		(width 0.1143)
		(layer "In11.Cu")
		(net "P5E_CPU0_P3_TX_DN<8>")
	)
	(segment
		(start 368.287808 -281.05354)
		(end 368.256058 -281.071828)
		(width 0.1143)
		(layer "In11.Cu")
		(net "P5E_CPU0_P3_TX_DN<8>")
	)
	(segment
		(start 368.290856 -294.011604)
		(end 368.256058 -294.03167)
		(width 0.1143)
		(layer "In11.Cu")
		(net "P5E_CPU0_P3_TX_DN<8>")
	)
	(segment
		(start 380.302262 -379.5903)
		(end 380.593092 -379.88113)
		(width 0.14224)
		(layer "In11.Cu")
		(net "P5E_CPU0_P3_TX_DN<8>")
	)
	(segment
		(start 368.256058 -291.40023)
		(end 368.287808 -291.418518)
		(width 0.1143)
		(layer "In11.Cu")
		(net "P5E_CPU0_P3_TX_DN<8>")
	)
	(segment
		(start 368.288824 -278.459184)
		(end 368.302794 -278.467312)
		(width 0.1143)
		(layer "In11.Cu")
		(net "P5E_CPU0_P3_TX_DN<8>")
	)
	(segment
		(start 368.287808 -281.6987)
		(end 368.290856 -281.700478)
		(width 0.1143)
		(layer "In11.Cu")
		(net "P5E_CPU0_P3_TX_DN<8>")
	)
	(segment
		(start 368.290856 -289.151568)
		(end 368.256058 -289.171634)
		(width 0.1143)
		(layer "In11.Cu")
		(net "P5E_CPU0_P3_TX_DN<8>")
	)
	(segment
		(start 368.570002 -295.14165)
		(end 368.570002 -295.145968)
		(width 0.1143)
		(layer "In11.Cu")
		(net "P5E_CPU0_P3_TX_DN<8>")
	)
	(segment
		(start 369.11661 -296.538142)
		(end 369.16233 -296.583862)
		(width 0.1143)
		(layer "In11.Cu")
		(net "P5E_CPU0_P3_TX_DN<8>")
	)
	(segment
		(start 368.290856 -284.291786)
		(end 368.256058 -284.311852)
		(width 0.1143)
		(layer "In11.Cu")
		(net "P5E_CPU0_P3_TX_DN<8>")
	)
	(segment
		(start 368.570002 -295.145968)
		(end 368.570256 -295.145968)
		(width 0.1143)
		(layer "In11.Cu")
		(net "P5E_CPU0_P3_TX_DN<8>")
	)
	(segment
		(start 368.287808 -283.318712)
		(end 368.290856 -283.32049)
		(width 0.1143)
		(layer "In11.Cu")
		(net "P5E_CPU0_P3_TX_DN<8>")
	)
	(segment
		(start 384.089148 -319.183512)
		(end 385.825746 -323.376798)
		(width 0.14224)
		(layer "In11.Cu")
		(net "P5E_CPU0_P3_TX_DN<8>")
	)
	(segment
		(start 368.287808 -278.458676)
		(end 368.288824 -278.459184)
		(width 0.1143)
		(layer "In11.Cu")
		(net "P5E_CPU0_P3_TX_DN<8>")
	)
	(segment
		(start 368.17681 -278.136096)
		(end 368.10696 -278.205946)
		(width 0.1143)
		(layer "In11.Cu")
		(net "P5E_CPU0_P3_TX_DN<8>")
	)
	(segment
		(start 378.911104 -311.43448)
		(end 384.089148 -319.183512)
		(width 0.14224)
		(layer "In11.Cu")
		(net "P5E_CPU0_P3_TX_DN<8>")
	)
	(segment
		(start 368.32794 -287.51022)
		(end 368.256058 -287.551876)
		(width 0.1143)
		(layer "In11.Cu")
		(net "P5E_CPU0_P3_TX_DN<8>")
	)
	(segment
		(start 368.570002 -287.045908)
		(end 368.570002 -287.05048)
		(width 0.1143)
		(layer "In11.Cu")
		(net "P5E_CPU0_P3_TX_DN<8>")
	)
	(segment
		(start 370.082826 -300.113192)
		(end 372.111524 -303.149254)
		(width 0.14224)
		(layer "In11.Cu")
		(net "P5E_CPU0_P3_TX_DN<8>")
	)
	(segment
		(start 389.269478 -340.6902)
		(end 389.269478 -349.184468)
		(width 0.14224)
		(layer "In11.Cu")
		(net "P5E_CPU0_P3_TX_DN<8>")
	)
	(segment
		(start 368.325908 -291.440362)
		(end 368.338862 -291.44976)
		(width 0.1143)
		(layer "In11.Cu")
		(net "P5E_CPU0_P3_TX_DN<8>")
	)
	(segment
		(start 368.256058 -278.440388)
		(end 368.287046 -278.458168)
		(width 0.1143)
		(layer "In11.Cu")
		(net "P5E_CPU0_P3_TX_DN<8>")
	)
	(segment
		(start 368.297714 -281.047444)
		(end 368.287808 -281.05354)
		(width 0.1143)
		(layer "In11.Cu")
		(net "P5E_CPU0_P3_TX_DN<8>")
	)
	(segment
		(start 368.290856 -285.911798)
		(end 368.256058 -285.931864)
		(width 0.1143)
		(layer "In11.Cu")
		(net "P5E_CPU0_P3_TX_DN<8>")
	)
	(segment
		(start 381.344424 -374.623838)
		(end 380.42342 -376.347482)
		(width 0.14224)
		(layer "In11.Cu")
		(net "P5E_CPU0_P3_TX_DN<8>")
	)
	(segment
		(start 368.256058 -283.300424)
		(end 368.287046 -283.318204)
		(width 0.1143)
		(layer "In11.Cu")
		(net "P5E_CPU0_P3_TX_DN<8>")
	)
	(segment
		(start 369.162838 -296.612818)
		(end 369.162838 -297.080432)
		(width 0.14224)
		(layer "In11.Cu")
		(net "P5E_CPU0_P3_TX_DN<8>")
	)
	(segment
		(start 369.11661 -296.186352)
		(end 369.11661 -296.538142)
		(width 0.1143)
		(layer "In11.Cu")
		(net "P5E_CPU0_P3_TX_DN<8>")
	)
	(segment
		(start 385.825746 -323.376798)
		(end 389.269478 -340.6902)
		(width 0.14224)
		(layer "In11.Cu")
		(net "P5E_CPU0_P3_TX_DN<8>")
	)
	(segment
		(start 369.162838 -297.080432)
		(end 370.082826 -300.113192)
		(width 0.14224)
		(layer "In11.Cu")
		(net "P5E_CPU0_P3_TX_DN<8>")
	)
	(segment
		(start 368.287808 -291.418772)
		(end 368.325908 -291.440362)
		(width 0.1143)
		(layer "In11.Cu")
		(net "P5E_CPU0_P3_TX_DN<8>")
	)
	(segment
		(start 368.796824 -280.220674)
		(end 368.744754 -280.2509)
		(width 0.1143)
		(layer "In11.Cu")
		(net "P5E_CPU0_P3_TX_DN<8>")
	)
	(segment
		(start 368.33937 -287.501584)
		(end 368.32794 -287.51022)
		(width 0.1143)
		(layer "In11.Cu")
		(net "P5E_CPU0_P3_TX_DN<8>")
	)
	(segment
		(start 380.302262 -376.831352)
		(end 380.302262 -379.5903)
		(width 0.14224)
		(layer "In11.Cu")
		(net "P5E_CPU0_P3_TX_DN<8>")
	)
	(segment
		(start 368.727228 -295.450768)
		(end 368.796824 -295.491408)
		(width 0.1143)
		(layer "In11.Cu")
		(net "P5E_CPU0_P3_TX_DN<8>")
	)
	(segment
		(start 368.744754 -280.2509)
		(end 368.7445 -280.251154)
		(width 0.1143)
		(layer "In11.Cu")
		(net "P5E_CPU0_P3_TX_DN<8>")
	)
	(segment
		(start 368.325908 -292.371526)
		(end 368.256058 -292.411658)
		(width 0.1143)
		(layer "In11.Cu")
		(net "P5E_CPU0_P3_TX_DN<8>")
	)
	(arc
		(start 368.256058 -287.551876)
		(mid 368.141382 -287.68521)
		(end 368.100102 -287.856168)
		(width 0.1143)
		(layer "In11.Cu")
		(net "P5E_CPU0_P3_TX_DN<8>")
	)
	(arc
		(start 368.256058 -290.791646)
		(mid 368.10013 -291.095938)
		(end 368.256058 -291.40023)
		(width 0.1143)
		(layer "In11.Cu")
		(net "P5E_CPU0_P3_TX_DN<8>")
	)
	(arc
		(start 368.256058 -289.171634)
		(mid 368.10013 -289.475926)
		(end 368.256058 -289.780218)
		(width 0.1143)
		(layer "In11.Cu")
		(net "P5E_CPU0_P3_TX_DN<8>")
	)
	(arc
		(start 368.338862 -291.44976)
		(mid 368.573289 -291.905944)
		(end 368.338862 -292.362128)
		(width 0.1143)
		(layer "In11.Cu")
		(net "P5E_CPU0_P3_TX_DN<8>")
	)
	(arc
		(start 368.290856 -293.040308)
		(mid 368.570471 -293.525956)
		(end 368.290856 -294.011604)
		(width 0.1143)
		(layer "In11.Cu")
		(net "P5E_CPU0_P3_TX_DN<8>")
	)
	(arc
		(start 368.302794 -278.467312)
		(mid 368.507739 -278.672974)
		(end 368.582702 -278.953468)
		(width 0.1143)
		(layer "In11.Cu")
		(net "P5E_CPU0_P3_TX_DN<8>")
	)
	(arc
		(start 368.10696 -278.205946)
		(mid 368.159009 -278.337465)
		(end 368.256058 -278.440388)
		(width 0.1143)
		(layer "In11.Cu")
		(net "P5E_CPU0_P3_TX_DN<8>")
	)
	(arc
		(start 368.256058 -294.03167)
		(mid 368.10013 -294.335962)
		(end 368.256058 -294.640254)
		(width 0.1143)
		(layer "In11.Cu")
		(net "P5E_CPU0_P3_TX_DN<8>")
	)
	(arc
		(start 368.327686 -294.682164)
		(mid 368.505722 -294.881914)
		(end 368.570002 -295.14165)
		(width 0.1143)
		(layer "In11.Cu")
		(net "P5E_CPU0_P3_TX_DN<8>")
	)
	(arc
		(start 368.290856 -288.180272)
		(mid 368.570471 -288.66592)
		(end 368.290856 -289.151568)
		(width 0.1143)
		(layer "In11.Cu")
		(net "P5E_CPU0_P3_TX_DN<8>")
	)
	(arc
		(start 368.290856 -284.940502)
		(mid 368.570471 -285.42615)
		(end 368.290856 -285.911798)
		(width 0.1143)
		(layer "In11.Cu")
		(net "P5E_CPU0_P3_TX_DN<8>")
	)
	(arc
		(start 368.100102 -287.856168)
		(mid 368.140864 -288.026052)
		(end 368.25428 -288.158936)
		(width 0.1143)
		(layer "In11.Cu")
		(net "P5E_CPU0_P3_TX_DN<8>")
	)
	(arc
		(start 368.290856 -289.800284)
		(mid 368.570471 -290.285932)
		(end 368.290856 -290.77158)
		(width 0.1143)
		(layer "In11.Cu")
		(net "P5E_CPU0_P3_TX_DN<8>")
	)
	(arc
		(start 368.256058 -284.311852)
		(mid 368.10013 -284.616144)
		(end 368.256058 -284.920436)
		(width 0.1143)
		(layer "In11.Cu")
		(net "P5E_CPU0_P3_TX_DN<8>")
	)
	(arc
		(start 368.570256 -295.145968)
		(mid 368.611805 -295.31739)
		(end 368.727228 -295.450768)
		(width 0.1143)
		(layer "In11.Cu")
		(net "P5E_CPU0_P3_TX_DN<8>")
	)
	(arc
		(start 368.7445 -280.251154)
		(mid 368.60802 -280.387879)
		(end 368.558064 -280.574496)
		(width 0.1143)
		(layer "In11.Cu")
		(net "P5E_CPU0_P3_TX_DN<8>")
	)
	(arc
		(start 368.558064 -280.585926)
		(mid 368.488488 -280.85087)
		(end 368.297714 -281.047444)
		(width 0.1143)
		(layer "In11.Cu")
		(net "P5E_CPU0_P3_TX_DN<8>")
	)
	(arc
		(start 368.256058 -285.931864)
		(mid 368.141382 -286.065198)
		(end 368.100102 -286.236156)
		(width 0.1143)
		(layer "In11.Cu")
		(net "P5E_CPU0_P3_TX_DN<8>")
	)
	(arc
		(start 368.582702 -278.965914)
		(mid 368.629593 -279.14078)
		(end 368.757708 -279.268682)
		(width 0.1143)
		(layer "In11.Cu")
		(net "P5E_CPU0_P3_TX_DN<8>")
	)
	(arc
		(start 368.256058 -282.69184)
		(mid 368.10013 -282.996132)
		(end 368.256058 -283.300424)
		(width 0.1143)
		(layer "In11.Cu")
		(net "P5E_CPU0_P3_TX_DN<8>")
	)
	(arc
		(start 368.100102 -286.236156)
		(mid 368.140864 -286.40604)
		(end 368.25428 -286.538924)
		(width 0.1143)
		(layer "In11.Cu")
		(net "P5E_CPU0_P3_TX_DN<8>")
	)
	(arc
		(start 368.796824 -295.491408)
		(mid 368.975637 -295.693758)
		(end 369.040156 -295.955974)
		(width 0.1143)
		(layer "In11.Cu")
		(net "P5E_CPU0_P3_TX_DN<8>")
	)
	(arc
		(start 368.256058 -292.411658)
		(mid 368.10013 -292.71595)
		(end 368.256058 -293.020242)
		(width 0.1143)
		(layer "In11.Cu")
		(net "P5E_CPU0_P3_TX_DN<8>")
	)
	(arc
		(start 368.290856 -283.32049)
		(mid 368.570471 -283.806138)
		(end 368.290856 -284.291786)
		(width 0.1143)
		(layer "In11.Cu")
		(net "P5E_CPU0_P3_TX_DN<8>")
	)
	(arc
		(start 380.42342 -376.347482)
		(mid 380.333023 -376.58195)
		(end 380.302262 -376.831352)
		(width 0.14224)
		(layer "In11.Cu")
		(net "P5E_CPU0_P3_TX_DN<8>")
	)
	(arc
		(start 368.570002 -287.05048)
		(mid 368.509003 -287.303804)
		(end 368.33937 -287.501584)
		(width 0.1143)
		(layer "In11.Cu")
		(net "P5E_CPU0_P3_TX_DN<8>")
	)
	(arc
		(start 368.290856 -281.700478)
		(mid 368.570471 -282.186126)
		(end 368.290856 -282.671774)
		(width 0.1143)
		(layer "In11.Cu")
		(net "P5E_CPU0_P3_TX_DN<8>")
	)
	(arc
		(start 387.273038 -359.254044)
		(mid 384.780763 -367.121018)
		(end 381.344424 -374.623838)
		(width 0.14224)
		(layer "In11.Cu")
		(net "P5E_CPU0_P3_TX_DN<8>")
	)
	(arc
		(start 368.328956 -286.582866)
		(mid 368.506152 -286.784878)
		(end 368.570002 -287.045908)
		(width 0.1143)
		(layer "In11.Cu")
		(net "P5E_CPU0_P3_TX_DN<8>")
	)
	(arc
		(start 389.269478 -349.184468)
		(mid 389.141448 -351.268723)
		(end 388.759192 -353.32162)
		(width 0.14224)
		(layer "In11.Cu")
		(net "P5E_CPU0_P3_TX_DN<8>")
	)
	(arc
		(start 368.796824 -279.291542)
		(mid 369.040041 -279.756108)
		(end 368.796824 -280.220674)
		(width 0.1143)
		(layer "In11.Cu")
		(net "P5E_CPU0_P3_TX_DN<8>")
	)
	(arc
		(start 368.256058 -281.071828)
		(mid 368.10013 -281.37612)
		(end 368.256058 -281.680412)
		(width 0.1143)
		(layer "In11.Cu")
		(net "P5E_CPU0_P3_TX_DN<8>")
	)
	(segment
		(start 368.409982 -378.39142)
		(end 368.705892 -378.68733)
		(width 0.12954)
		(layer "F.Cu")
		(net "P5E_CPU0_P3_TX_DN<3>")
	)
	(segment
		(start 365.187992 -274.630134)
		(end 365.654844 -274.896072)
		(width 0.12954)
		(layer "F.Cu")
		(net "P5E_CPU0_P3_TX_DN<3>")
	)
	(segment
		(start 368.680492 -377.41733)
		(end 368.409982 -377.68784)
		(width 0.12954)
		(layer "F.Cu")
		(net "P5E_CPU0_P3_TX_DN<3>")
	)
	(segment
		(start 368.409982 -377.68784)
		(end 368.409982 -378.39142)
		(width 0.12954)
		(layer "F.Cu")
		(net "P5E_CPU0_P3_TX_DN<3>")
	)
	(segment
		(start 363.58703 -289.153854)
		(end 363.58576 -289.154616)
		(width 0.1143)
		(layer "In11.Cu")
		(net "P5E_CPU0_P3_TX_DN<3>")
	)
	(segment
		(start 363.58703 -281.054048)
		(end 363.58576 -281.05481)
		(width 0.1143)
		(layer "In11.Cu")
		(net "P5E_CPU0_P3_TX_DN<3>")
	)
	(segment
		(start 364.027212 -279.250902)
		(end 364.057692 -279.268682)
		(width 0.1143)
		(layer "In11.Cu")
		(net "P5E_CPU0_P3_TX_DN<3>")
	)
	(segment
		(start 363.587792 -285.913576)
		(end 363.58703 -285.914084)
		(width 0.1143)
		(layer "In11.Cu")
		(net "P5E_CPU0_P3_TX_DN<3>")
	)
	(segment
		(start 364.096808 -278.600662)
		(end 364.057692 -278.623522)
		(width 0.1143)
		(layer "In11.Cu")
		(net "P5E_CPU0_P3_TX_DN<3>")
	)
	(segment
		(start 363.58703 -281.698192)
		(end 363.587792 -281.6987)
		(width 0.1143)
		(layer "In11.Cu")
		(net "P5E_CPU0_P3_TX_DN<3>")
	)
	(segment
		(start 381.256286 -325.058786)
		(end 384.47345 -341.232744)
		(width 0.14224)
		(layer "In11.Cu")
		(net "P5E_CPU0_P3_TX_DN<3>")
	)
	(segment
		(start 363.58703 -290.773866)
		(end 363.58576 -290.774628)
		(width 0.1143)
		(layer "In11.Cu")
		(net "P5E_CPU0_P3_TX_DN<3>")
	)
	(segment
		(start 363.587792 -294.658542)
		(end 363.588808 -294.65905)
		(width 0.1143)
		(layer "In11.Cu")
		(net "P5E_CPU0_P3_TX_DN<3>")
	)
	(segment
		(start 363.587792 -284.938724)
		(end 363.588808 -284.939232)
		(width 0.1143)
		(layer "In11.Cu")
		(net "P5E_CPU0_P3_TX_DN<3>")
	)
	(segment
		(start 364.096808 -280.220674)
		(end 364.057692 -280.243534)
		(width 0.1143)
		(layer "In11.Cu")
		(net "P5E_CPU0_P3_TX_DN<3>")
	)
	(segment
		(start 364.057692 -280.243534)
		(end 364.027212 -280.261314)
		(width 0.1143)
		(layer "In11.Cu")
		(net "P5E_CPU0_P3_TX_DN<3>")
	)
	(segment
		(start 363.588808 -283.31922)
		(end 363.590332 -283.320236)
		(width 0.1143)
		(layer "In11.Cu")
		(net "P5E_CPU0_P3_TX_DN<3>")
	)
	(segment
		(start 363.58703 -294.658034)
		(end 363.587792 -294.658542)
		(width 0.1143)
		(layer "In11.Cu")
		(net "P5E_CPU0_P3_TX_DN<3>")
	)
	(segment
		(start 363.58703 -285.914084)
		(end 363.58576 -285.914846)
		(width 0.1143)
		(layer "In11.Cu")
		(net "P5E_CPU0_P3_TX_DN<3>")
	)
	(segment
		(start 363.590332 -284.940248)
		(end 363.626908 -284.961584)
		(width 0.1143)
		(layer "In11.Cu")
		(net "P5E_CPU0_P3_TX_DN<3>")
	)
	(segment
		(start 363.58576 -294.014652)
		(end 363.556042 -294.03167)
		(width 0.1143)
		(layer "In11.Cu")
		(net "P5E_CPU0_P3_TX_DN<3>")
	)
	(segment
		(start 363.58703 -284.938216)
		(end 363.587792 -284.938724)
		(width 0.1143)
		(layer "In11.Cu")
		(net "P5E_CPU0_P3_TX_DN<3>")
	)
	(segment
		(start 363.587792 -283.318712)
		(end 363.588808 -283.31922)
		(width 0.1143)
		(layer "In11.Cu")
		(net "P5E_CPU0_P3_TX_DN<3>")
	)
	(segment
		(start 363.587792 -289.798506)
		(end 363.588808 -289.799014)
		(width 0.1143)
		(layer "In11.Cu")
		(net "P5E_CPU0_P3_TX_DN<3>")
	)
	(segment
		(start 363.626908 -289.130486)
		(end 363.587792 -289.153346)
		(width 0.1143)
		(layer "In11.Cu")
		(net "P5E_CPU0_P3_TX_DN<3>")
	)
	(segment
		(start 363.58576 -290.774628)
		(end 363.556042 -290.791646)
		(width 0.1143)
		(layer "In11.Cu")
		(net "P5E_CPU0_P3_TX_DN<3>")
	)
	(segment
		(start 363.626908 -285.890716)
		(end 363.587792 -285.913576)
		(width 0.1143)
		(layer "In11.Cu")
		(net "P5E_CPU0_P3_TX_DN<3>")
	)
	(segment
		(start 363.626908 -281.03068)
		(end 363.587792 -281.05354)
		(width 0.1143)
		(layer "In11.Cu")
		(net "P5E_CPU0_P3_TX_DN<3>")
	)
	(segment
		(start 363.58703 -293.038022)
		(end 363.587792 -293.03853)
		(width 0.1143)
		(layer "In11.Cu")
		(net "P5E_CPU0_P3_TX_DN<3>")
	)
	(segment
		(start 363.626908 -282.650692)
		(end 363.587792 -282.673552)
		(width 0.1143)
		(layer "In11.Cu")
		(net "P5E_CPU0_P3_TX_DN<3>")
	)
	(segment
		(start 364.38586 -296.446956)
		(end 364.38586 -296.774108)
		(width 0.14224)
		(layer "In11.Cu")
		(net "P5E_CPU0_P3_TX_DN<3>")
	)
	(segment
		(start 363.590332 -294.660066)
		(end 363.626908 -294.681402)
		(width 0.1143)
		(layer "In11.Cu")
		(net "P5E_CPU0_P3_TX_DN<3>")
	)
	(segment
		(start 368.389662 -377.1265)
		(end 368.680492 -377.41733)
		(width 0.14224)
		(layer "In11.Cu")
		(net "P5E_CPU0_P3_TX_DN<3>")
	)
	(segment
		(start 363.626908 -293.990522)
		(end 363.587792 -294.013382)
		(width 0.1143)
		(layer "In11.Cu")
		(net "P5E_CPU0_P3_TX_DN<3>")
	)
	(segment
		(start 363.58703 -291.41801)
		(end 363.587792 -291.418518)
		(width 0.1143)
		(layer "In11.Cu")
		(net "P5E_CPU0_P3_TX_DN<3>")
	)
	(segment
		(start 363.58576 -281.05481)
		(end 363.556042 -281.071828)
		(width 0.1143)
		(layer "In11.Cu")
		(net "P5E_CPU0_P3_TX_DN<3>")
	)
	(segment
		(start 363.587792 -286.558482)
		(end 363.626908 -286.581342)
		(width 0.1143)
		(layer "In11.Cu")
		(net "P5E_CPU0_P3_TX_DN<3>")
	)
	(segment
		(start 363.588808 -293.039038)
		(end 363.590332 -293.040054)
		(width 0.1143)
		(layer "In11.Cu")
		(net "P5E_CPU0_P3_TX_DN<3>")
	)
	(segment
		(start 364.34014 -295.955466)
		(end 364.34014 -296.372788)
		(width 0.1143)
		(layer "In11.Cu")
		(net "P5E_CPU0_P3_TX_DN<3>")
	)
	(segment
		(start 384.47345 -341.232744)
		(end 384.473704 -341.23376)
		(width 0.14224)
		(layer "In11.Cu")
		(net "P5E_CPU0_P3_TX_DN<3>")
	)
	(segment
		(start 368.389662 -376.479054)
		(end 368.389662 -377.1265)
		(width 0.14224)
		(layer "In11.Cu")
		(net "P5E_CPU0_P3_TX_DN<3>")
	)
	(segment
		(start 363.587792 -293.03853)
		(end 363.588808 -293.039038)
		(width 0.1143)
		(layer "In11.Cu")
		(net "P5E_CPU0_P3_TX_DN<3>")
	)
	(segment
		(start 364.342426 -276.505924)
		(end 364.342426 -276.509226)
		(width 0.1143)
		(layer "In11.Cu")
		(net "P5E_CPU0_P3_TX_DN<3>")
	)
	(segment
		(start 363.587792 -281.6987)
		(end 363.588808 -281.699208)
		(width 0.1143)
		(layer "In11.Cu")
		(net "P5E_CPU0_P3_TX_DN<3>")
	)
	(segment
		(start 363.590332 -291.420042)
		(end 363.626908 -291.441378)
		(width 0.1143)
		(layer "In11.Cu")
		(net "P5E_CPU0_P3_TX_DN<3>")
	)
	(segment
		(start 363.556042 -281.680412)
		(end 363.58703 -281.698192)
		(width 0.1143)
		(layer "In11.Cu")
		(net "P5E_CPU0_P3_TX_DN<3>")
	)
	(segment
		(start 364.027212 -295.450768)
		(end 364.096808 -295.491408)
		(width 0.1143)
		(layer "In11.Cu")
		(net "P5E_CPU0_P3_TX_DN<3>")
	)
	(segment
		(start 363.554264 -288.158936)
		(end 363.587792 -288.178494)
		(width 0.1143)
		(layer "In11.Cu")
		(net "P5E_CPU0_P3_TX_DN<3>")
	)
	(segment
		(start 363.587792 -284.293564)
		(end 363.58703 -284.294072)
		(width 0.1143)
		(layer "In11.Cu")
		(net "P5E_CPU0_P3_TX_DN<3>")
	)
	(segment
		(start 364.34014 -296.372788)
		(end 364.38586 -296.418508)
		(width 0.1143)
		(layer "In11.Cu")
		(net "P5E_CPU0_P3_TX_DN<3>")
	)
	(segment
		(start 365.771938 -302.228504)
		(end 369.360196 -307.598826)
		(width 0.14224)
		(layer "In11.Cu")
		(net "P5E_CPU0_P3_TX_DN<3>")
	)
	(segment
		(start 363.626908 -292.37051)
		(end 363.587792 -292.39337)
		(width 0.1143)
		(layer "In11.Cu")
		(net "P5E_CPU0_P3_TX_DN<3>")
	)
	(segment
		(start 363.556042 -289.780218)
		(end 363.587792 -289.798506)
		(width 0.1143)
		(layer "In11.Cu")
		(net "P5E_CPU0_P3_TX_DN<3>")
	)
	(segment
		(start 363.587792 -294.013382)
		(end 363.58703 -294.01389)
		(width 0.1143)
		(layer "In11.Cu")
		(net "P5E_CPU0_P3_TX_DN<3>")
	)
	(segment
		(start 369.360196 -307.598826)
		(end 376.69978 -316.542674)
		(width 0.14224)
		(layer "In11.Cu")
		(net "P5E_CPU0_P3_TX_DN<3>")
	)
	(segment
		(start 363.58576 -289.154616)
		(end 363.556042 -289.171634)
		(width 0.1143)
		(layer "In11.Cu")
		(net "P5E_CPU0_P3_TX_DN<3>")
	)
	(segment
		(start 363.556042 -283.300424)
		(end 363.58703 -283.318204)
		(width 0.1143)
		(layer "In11.Cu")
		(net "P5E_CPU0_P3_TX_DN<3>")
	)
	(segment
		(start 363.590332 -293.040054)
		(end 363.626908 -293.06139)
		(width 0.1143)
		(layer "In11.Cu")
		(net "P5E_CPU0_P3_TX_DN<3>")
	)
	(segment
		(start 363.587792 -289.153346)
		(end 363.58703 -289.153854)
		(width 0.1143)
		(layer "In11.Cu")
		(net "P5E_CPU0_P3_TX_DN<3>")
	)
	(segment
		(start 364.057692 -277.64867)
		(end 364.096808 -277.67153)
		(width 0.1143)
		(layer "In11.Cu")
		(net "P5E_CPU0_P3_TX_DN<3>")
	)
	(segment
		(start 376.106436 -367.690654)
		(end 368.443764 -376.336306)
		(width 0.14224)
		(layer "In11.Cu")
		(net "P5E_CPU0_P3_TX_DN<3>")
	)
	(segment
		(start 364.386622 -296.774108)
		(end 364.386622 -297.663108)
		(width 0.14224)
		(layer "In11.Cu")
		(net "P5E_CPU0_P3_TX_DN<3>")
	)
	(segment
		(start 363.554264 -286.538924)
		(end 363.587792 -286.558482)
		(width 0.1143)
		(layer "In11.Cu")
		(net "P5E_CPU0_P3_TX_DN<3>")
	)
	(segment
		(start 363.58703 -294.01389)
		(end 363.58576 -294.014652)
		(width 0.1143)
		(layer "In11.Cu")
		(net "P5E_CPU0_P3_TX_DN<3>")
	)
	(segment
		(start 363.590332 -289.80003)
		(end 363.626908 -289.821366)
		(width 0.1143)
		(layer "In11.Cu")
		(net "P5E_CPU0_P3_TX_DN<3>")
	)
	(segment
		(start 363.587792 -281.05354)
		(end 363.58703 -281.054048)
		(width 0.1143)
		(layer "In11.Cu")
		(net "P5E_CPU0_P3_TX_DN<3>")
	)
	(segment
		(start 365.036862 -275.360638)
		(end 364.993682 -275.385784)
		(width 0.1143)
		(layer "In11.Cu")
		(net "P5E_CPU0_P3_TX_DN<3>")
	)
	(segment
		(start 363.587792 -288.178494)
		(end 363.626908 -288.201354)
		(width 0.1143)
		(layer "In11.Cu")
		(net "P5E_CPU0_P3_TX_DN<3>")
	)
	(segment
		(start 363.587792 -290.773358)
		(end 363.58703 -290.773866)
		(width 0.1143)
		(layer "In11.Cu")
		(net "P5E_CPU0_P3_TX_DN<3>")
	)
	(segment
		(start 363.588808 -294.65905)
		(end 363.590332 -294.660066)
		(width 0.1143)
		(layer "In11.Cu")
		(net "P5E_CPU0_P3_TX_DN<3>")
	)
	(segment
		(start 363.626908 -284.270704)
		(end 363.587792 -284.293564)
		(width 0.1143)
		(layer "In11.Cu")
		(net "P5E_CPU0_P3_TX_DN<3>")
	)
	(segment
		(start 363.626908 -290.750498)
		(end 363.587792 -290.773358)
		(width 0.1143)
		(layer "In11.Cu")
		(net "P5E_CPU0_P3_TX_DN<3>")
	)
	(segment
		(start 384.480816 -341.27059)
		(end 384.480816 -347.50756)
		(width 0.14224)
		(layer "In11.Cu")
		(net "P5E_CPU0_P3_TX_DN<3>")
	)
	(segment
		(start 363.58576 -284.294834)
		(end 363.556042 -284.311852)
		(width 0.1143)
		(layer "In11.Cu")
		(net "P5E_CPU0_P3_TX_DN<3>")
	)
	(segment
		(start 363.556042 -294.640254)
		(end 363.58703 -294.658034)
		(width 0.1143)
		(layer "In11.Cu")
		(net "P5E_CPU0_P3_TX_DN<3>")
	)
	(segment
		(start 363.556042 -293.020242)
		(end 363.58703 -293.038022)
		(width 0.1143)
		(layer "In11.Cu")
		(net "P5E_CPU0_P3_TX_DN<3>")
	)
	(segment
		(start 363.58576 -292.39464)
		(end 363.556042 -292.411658)
		(width 0.1143)
		(layer "In11.Cu")
		(net "P5E_CPU0_P3_TX_DN<3>")
	)
	(segment
		(start 363.587792 -287.533588)
		(end 363.556042 -287.551876)
		(width 0.1143)
		(layer "In11.Cu")
		(net "P5E_CPU0_P3_TX_DN<3>")
	)
	(segment
		(start 364.386622 -297.663108)
		(end 365.771938 -302.228504)
		(width 0.14224)
		(layer "In11.Cu")
		(net "P5E_CPU0_P3_TX_DN<3>")
	)
	(segment
		(start 364.053628 -277.64613)
		(end 364.057692 -277.64867)
		(width 0.1143)
		(layer "In11.Cu")
		(net "P5E_CPU0_P3_TX_DN<3>")
	)
	(segment
		(start 363.587792 -291.418518)
		(end 363.588808 -291.419026)
		(width 0.1143)
		(layer "In11.Cu")
		(net "P5E_CPU0_P3_TX_DN<3>")
	)
	(segment
		(start 363.590332 -281.700224)
		(end 363.626908 -281.72156)
		(width 0.1143)
		(layer "In11.Cu")
		(net "P5E_CPU0_P3_TX_DN<3>")
	)
	(segment
		(start 363.556042 -291.40023)
		(end 363.58703 -291.41801)
		(width 0.1143)
		(layer "In11.Cu")
		(net "P5E_CPU0_P3_TX_DN<3>")
	)
	(segment
		(start 363.58703 -283.318204)
		(end 363.587792 -283.318712)
		(width 0.1143)
		(layer "In11.Cu")
		(net "P5E_CPU0_P3_TX_DN<3>")
	)
	(segment
		(start 363.587792 -292.39337)
		(end 363.58703 -292.393878)
		(width 0.1143)
		(layer "In11.Cu")
		(net "P5E_CPU0_P3_TX_DN<3>")
	)
	(segment
		(start 364.057692 -279.268682)
		(end 364.096808 -279.291542)
		(width 0.1143)
		(layer "In11.Cu")
		(net "P5E_CPU0_P3_TX_DN<3>")
	)
	(segment
		(start 363.588808 -291.419026)
		(end 363.590332 -291.420042)
		(width 0.1143)
		(layer "In11.Cu")
		(net "P5E_CPU0_P3_TX_DN<3>")
	)
	(segment
		(start 379.407166 -320.594482)
		(end 381.256286 -325.058786)
		(width 0.14224)
		(layer "In11.Cu")
		(net "P5E_CPU0_P3_TX_DN<3>")
	)
	(segment
		(start 363.590332 -283.320236)
		(end 363.626908 -283.341572)
		(width 0.1143)
		(layer "In11.Cu")
		(net "P5E_CPU0_P3_TX_DN<3>")
	)
	(segment
		(start 365.356902 -274.896072)
		(end 365.274098 -274.978876)
		(width 0.1143)
		(layer "In11.Cu")
		(net "P5E_CPU0_P3_TX_DN<3>")
	)
	(segment
		(start 384.473704 -341.23376)
		(end 384.480816 -341.27059)
		(width 0.14224)
		(layer "In11.Cu")
		(net "P5E_CPU0_P3_TX_DN<3>")
	)
	(segment
		(start 364.38586 -296.774108)
		(end 364.386622 -296.774108)
		(width 0.14224)
		(layer "In11.Cu")
		(net "P5E_CPU0_P3_TX_DN<3>")
	)
	(segment
		(start 364.38586 -296.418508)
		(end 364.38586 -296.446956)
		(width 0.1143)
		(layer "In11.Cu")
		(net "P5E_CPU0_P3_TX_DN<3>")
	)
	(segment
		(start 363.58703 -292.393878)
		(end 363.58576 -292.39464)
		(width 0.1143)
		(layer "In11.Cu")
		(net "P5E_CPU0_P3_TX_DN<3>")
	)
	(segment
		(start 363.58703 -284.294072)
		(end 363.58576 -284.294834)
		(width 0.1143)
		(layer "In11.Cu")
		(net "P5E_CPU0_P3_TX_DN<3>")
	)
	(segment
		(start 364.097824 -276.974808)
		(end 364.024672 -277.017988)
		(width 0.1143)
		(layer "In11.Cu")
		(net "P5E_CPU0_P3_TX_DN<3>")
	)
	(segment
		(start 363.58576 -285.914846)
		(end 363.556042 -285.931864)
		(width 0.1143)
		(layer "In11.Cu")
		(net "P5E_CPU0_P3_TX_DN<3>")
	)
	(segment
		(start 365.654844 -274.896072)
		(end 365.356902 -274.896072)
		(width 0.1143)
		(layer "In11.Cu")
		(net "P5E_CPU0_P3_TX_DN<3>")
	)
	(segment
		(start 376.69978 -316.542674)
		(end 379.407166 -320.594482)
		(width 0.14224)
		(layer "In11.Cu")
		(net "P5E_CPU0_P3_TX_DN<3>")
	)
	(segment
		(start 363.58703 -282.67406)
		(end 363.58576 -282.674822)
		(width 0.1143)
		(layer "In11.Cu")
		(net "P5E_CPU0_P3_TX_DN<3>")
	)
	(segment
		(start 363.624368 -287.512252)
		(end 363.587792 -287.533588)
		(width 0.1143)
		(layer "In11.Cu")
		(net "P5E_CPU0_P3_TX_DN<3>")
	)
	(segment
		(start 363.588808 -281.699208)
		(end 363.590332 -281.700224)
		(width 0.1143)
		(layer "In11.Cu")
		(net "P5E_CPU0_P3_TX_DN<3>")
	)
	(segment
		(start 364.566708 -276.165564)
		(end 364.496096 -276.206712)
		(width 0.1143)
		(layer "In11.Cu")
		(net "P5E_CPU0_P3_TX_DN<3>")
	)
	(segment
		(start 363.587792 -282.673552)
		(end 363.58703 -282.67406)
		(width 0.1143)
		(layer "In11.Cu")
		(net "P5E_CPU0_P3_TX_DN<3>")
	)
	(segment
		(start 363.58576 -282.674822)
		(end 363.556042 -282.69184)
		(width 0.1143)
		(layer "In11.Cu")
		(net "P5E_CPU0_P3_TX_DN<3>")
	)
	(segment
		(start 363.556042 -284.920436)
		(end 363.58703 -284.938216)
		(width 0.1143)
		(layer "In11.Cu")
		(net "P5E_CPU0_P3_TX_DN<3>")
	)
	(segment
		(start 363.588808 -284.939232)
		(end 363.590332 -284.940248)
		(width 0.1143)
		(layer "In11.Cu")
		(net "P5E_CPU0_P3_TX_DN<3>")
	)
	(segment
		(start 364.057692 -278.623522)
		(end 364.027212 -278.641302)
		(width 0.1143)
		(layer "In11.Cu")
		(net "P5E_CPU0_P3_TX_DN<3>")
	)
	(segment
		(start 363.588808 -289.799014)
		(end 363.590332 -289.80003)
		(width 0.1143)
		(layer "In11.Cu")
		(net "P5E_CPU0_P3_TX_DN<3>")
	)
	(segment
		(start 383.70637 -351.97161)
		(end 381.1016 -359.250996)
		(width 0.14224)
		(layer "In11.Cu")
		(net "P5E_CPU0_P3_TX_DN<3>")
	)
	(arc
		(start 363.87024 -287.045908)
		(mid 363.805004 -287.309499)
		(end 363.624368 -287.512252)
		(width 0.1143)
		(layer "In11.Cu")
		(net "P5E_CPU0_P3_TX_DN<3>")
	)
	(arc
		(start 363.87024 -280.566114)
		(mid 363.805725 -280.828333)
		(end 363.626908 -281.03068)
		(width 0.1143)
		(layer "In11.Cu")
		(net "P5E_CPU0_P3_TX_DN<3>")
	)
	(arc
		(start 381.1016 -359.250996)
		(mid 379.007827 -363.709829)
		(end 376.106436 -367.690654)
		(width 0.14224)
		(layer "In11.Cu")
		(net "P5E_CPU0_P3_TX_DN<3>")
	)
	(arc
		(start 363.400086 -287.856168)
		(mid 363.440848 -288.026052)
		(end 363.554264 -288.158936)
		(width 0.1143)
		(layer "In11.Cu")
		(net "P5E_CPU0_P3_TX_DN<3>")
	)
	(arc
		(start 363.556042 -289.171634)
		(mid 363.400114 -289.475926)
		(end 363.556042 -289.780218)
		(width 0.1143)
		(layer "In11.Cu")
		(net "P5E_CPU0_P3_TX_DN<3>")
	)
	(arc
		(start 363.400086 -286.236156)
		(mid 363.440848 -286.40604)
		(end 363.554264 -286.538924)
		(width 0.1143)
		(layer "In11.Cu")
		(net "P5E_CPU0_P3_TX_DN<3>")
	)
	(arc
		(start 364.342426 -276.509226)
		(mid 364.277608 -276.772215)
		(end 364.097824 -276.974808)
		(width 0.1143)
		(layer "In11.Cu")
		(net "P5E_CPU0_P3_TX_DN<3>")
	)
	(arc
		(start 363.626908 -289.821366)
		(mid 363.870235 -290.285932)
		(end 363.626908 -290.750498)
		(width 0.1143)
		(layer "In11.Cu")
		(net "P5E_CPU0_P3_TX_DN<3>")
	)
	(arc
		(start 384.480816 -347.50756)
		(mid 384.285817 -349.772934)
		(end 383.70637 -351.97161)
		(width 0.14224)
		(layer "In11.Cu")
		(net "P5E_CPU0_P3_TX_DN<3>")
	)
	(arc
		(start 364.027212 -278.641302)
		(mid 363.870235 -278.946102)
		(end 364.027212 -279.250902)
		(width 0.1143)
		(layer "In11.Cu")
		(net "P5E_CPU0_P3_TX_DN<3>")
	)
	(arc
		(start 363.626908 -288.201354)
		(mid 363.870235 -288.66592)
		(end 363.626908 -289.130486)
		(width 0.1143)
		(layer "In11.Cu")
		(net "P5E_CPU0_P3_TX_DN<3>")
	)
	(arc
		(start 363.556042 -292.411658)
		(mid 363.400114 -292.71595)
		(end 363.556042 -293.020242)
		(width 0.1143)
		(layer "In11.Cu")
		(net "P5E_CPU0_P3_TX_DN<3>")
	)
	(arc
		(start 363.556042 -294.03167)
		(mid 363.400114 -294.335962)
		(end 363.556042 -294.640254)
		(width 0.1143)
		(layer "In11.Cu")
		(net "P5E_CPU0_P3_TX_DN<3>")
	)
	(arc
		(start 363.626908 -286.581342)
		(mid 363.805721 -286.783692)
		(end 363.87024 -287.045908)
		(width 0.1143)
		(layer "In11.Cu")
		(net "P5E_CPU0_P3_TX_DN<3>")
	)
	(arc
		(start 363.556042 -284.311852)
		(mid 363.400114 -284.616144)
		(end 363.556042 -284.920436)
		(width 0.1143)
		(layer "In11.Cu")
		(net "P5E_CPU0_P3_TX_DN<3>")
	)
	(arc
		(start 364.024672 -277.017988)
		(mid 363.86809 -277.339983)
		(end 364.053628 -277.64613)
		(width 0.1143)
		(layer "In11.Cu")
		(net "P5E_CPU0_P3_TX_DN<3>")
	)
	(arc
		(start 364.993682 -275.385784)
		(mid 364.861079 -275.518212)
		(end 364.81258 -275.69922)
		(width 0.1143)
		(layer "In11.Cu")
		(net "P5E_CPU0_P3_TX_DN<3>")
	)
	(arc
		(start 364.096808 -295.491408)
		(mid 364.275565 -295.693501)
		(end 364.34014 -295.955466)
		(width 0.1143)
		(layer "In11.Cu")
		(net "P5E_CPU0_P3_TX_DN<3>")
	)
	(arc
		(start 363.626908 -281.72156)
		(mid 363.870235 -282.186126)
		(end 363.626908 -282.650692)
		(width 0.1143)
		(layer "In11.Cu")
		(net "P5E_CPU0_P3_TX_DN<3>")
	)
	(arc
		(start 368.443764 -376.336306)
		(mid 368.403645 -376.402727)
		(end 368.389662 -376.479054)
		(width 0.14224)
		(layer "In11.Cu")
		(net "P5E_CPU0_P3_TX_DN<3>")
	)
	(arc
		(start 363.626908 -291.441378)
		(mid 363.870235 -291.905944)
		(end 363.626908 -292.37051)
		(width 0.1143)
		(layer "In11.Cu")
		(net "P5E_CPU0_P3_TX_DN<3>")
	)
	(arc
		(start 363.626908 -284.961584)
		(mid 363.870235 -285.42615)
		(end 363.626908 -285.890716)
		(width 0.1143)
		(layer "In11.Cu")
		(net "P5E_CPU0_P3_TX_DN<3>")
	)
	(arc
		(start 364.027212 -280.261314)
		(mid 363.911785 -280.39469)
		(end 363.87024 -280.566114)
		(width 0.1143)
		(layer "In11.Cu")
		(net "P5E_CPU0_P3_TX_DN<3>")
	)
	(arc
		(start 363.626908 -293.06139)
		(mid 363.870235 -293.525956)
		(end 363.626908 -293.990522)
		(width 0.1143)
		(layer "In11.Cu")
		(net "P5E_CPU0_P3_TX_DN<3>")
	)
	(arc
		(start 363.87024 -295.145968)
		(mid 363.911789 -295.31739)
		(end 364.027212 -295.450768)
		(width 0.1143)
		(layer "In11.Cu")
		(net "P5E_CPU0_P3_TX_DN<3>")
	)
	(arc
		(start 364.096808 -277.67153)
		(mid 364.340135 -278.136096)
		(end 364.096808 -278.600662)
		(width 0.1143)
		(layer "In11.Cu")
		(net "P5E_CPU0_P3_TX_DN<3>")
	)
	(arc
		(start 363.626908 -294.681402)
		(mid 363.805721 -294.883752)
		(end 363.87024 -295.145968)
		(width 0.1143)
		(layer "In11.Cu")
		(net "P5E_CPU0_P3_TX_DN<3>")
	)
	(arc
		(start 363.626908 -283.341572)
		(mid 363.870235 -283.806138)
		(end 363.626908 -284.270704)
		(width 0.1143)
		(layer "In11.Cu")
		(net "P5E_CPU0_P3_TX_DN<3>")
	)
	(arc
		(start 363.556042 -287.551876)
		(mid 363.441366 -287.68521)
		(end 363.400086 -287.856168)
		(width 0.1143)
		(layer "In11.Cu")
		(net "P5E_CPU0_P3_TX_DN<3>")
	)
	(arc
		(start 363.556042 -290.791646)
		(mid 363.400114 -291.095938)
		(end 363.556042 -291.40023)
		(width 0.1143)
		(layer "In11.Cu")
		(net "P5E_CPU0_P3_TX_DN<3>")
	)
	(arc
		(start 364.81258 -275.69922)
		(mid 364.747344 -275.962811)
		(end 364.566708 -276.165564)
		(width 0.1143)
		(layer "In11.Cu")
		(net "P5E_CPU0_P3_TX_DN<3>")
	)
	(arc
		(start 363.556042 -285.931864)
		(mid 363.441366 -286.065198)
		(end 363.400086 -286.236156)
		(width 0.1143)
		(layer "In11.Cu")
		(net "P5E_CPU0_P3_TX_DN<3>")
	)
	(arc
		(start 365.274098 -274.978876)
		(mid 365.27231 -274.990325)
		(end 365.270288 -275.001736)
		(width 0.1143)
		(layer "In11.Cu")
		(net "P5E_CPU0_P3_TX_DN<3>")
	)
	(arc
		(start 363.556042 -281.071828)
		(mid 363.400114 -281.37612)
		(end 363.556042 -281.680412)
		(width 0.1143)
		(layer "In11.Cu")
		(net "P5E_CPU0_P3_TX_DN<3>")
	)
	(arc
		(start 363.556042 -282.69184)
		(mid 363.400114 -282.996132)
		(end 363.556042 -283.300424)
		(width 0.1143)
		(layer "In11.Cu")
		(net "P5E_CPU0_P3_TX_DN<3>")
	)
	(arc
		(start 364.096808 -279.291542)
		(mid 364.340135 -279.756108)
		(end 364.096808 -280.220674)
		(width 0.1143)
		(layer "In11.Cu")
		(net "P5E_CPU0_P3_TX_DN<3>")
	)
	(arc
		(start 365.270288 -275.001736)
		(mid 365.188855 -275.204134)
		(end 365.036862 -275.360638)
		(width 0.1143)
		(layer "In11.Cu")
		(net "P5E_CPU0_P3_TX_DN<3>")
	)
	(arc
		(start 364.496096 -276.206712)
		(mid 364.383063 -276.337732)
		(end 364.342426 -276.505924)
		(width 0.1143)
		(layer "In11.Cu")
		(net "P5E_CPU0_P3_TX_DN<3>")
	)
	(segment
		(start 366.708182 -380.85522)
		(end 367.004092 -381.15113)
		(width 0.12954)
		(layer "F.Cu")
		(net "P5E_CPU0_P3_TX_DN<2>")
	)
	(segment
		(start 362.837984 -278.680164)
		(end 363.304836 -278.946102)
		(width 0.12954)
		(layer "F.Cu")
		(net "P5E_CPU0_P3_TX_DN<2>")
	)
	(segment
		(start 366.708182 -380.15164)
		(end 366.708182 -380.85522)
		(width 0.12954)
		(layer "F.Cu")
		(net "P5E_CPU0_P3_TX_DN<2>")
	)
	(segment
		(start 366.978692 -379.88113)
		(end 366.708182 -380.15164)
		(width 0.12954)
		(layer "F.Cu")
		(net "P5E_CPU0_P3_TX_DN<2>")
	)
	(segment
		(start 366.68075 -379.583188)
		(end 366.978692 -379.88113)
		(width 0.14224)
		(layer "In11.Cu")
		(net "P5E_CPU0_P3_TX_DN<2>")
	)
	(segment
		(start 362.61167 -289.77717)
		(end 362.61675 -289.780472)
		(width 0.1143)
		(layer "In11.Cu")
		(net "P5E_CPU0_P3_TX_DN<2>")
	)
	(segment
		(start 362.686092 -282.6512)
		(end 362.646468 -282.674314)
		(width 0.1143)
		(layer "In11.Cu")
		(net "P5E_CPU0_P3_TX_DN<2>")
	)
	(segment
		(start 362.697268 -288.208212)
		(end 362.697268 -288.208974)
		(width 0.1143)
		(layer "In11.Cu")
		(net "P5E_CPU0_P3_TX_DN<2>")
	)
	(segment
		(start 362.641134 -292.396926)
		(end 362.615988 -292.411912)
		(width 0.1143)
		(layer "In11.Cu")
		(net "P5E_CPU0_P3_TX_DN<2>")
	)
	(segment
		(start 363.445298 -297.824906)
		(end 364.90021 -302.620426)
		(width 0.14224)
		(layer "In11.Cu")
		(net "P5E_CPU0_P3_TX_DN<2>")
	)
	(segment
		(start 363.085888 -295.450006)
		(end 363.15523 -295.490392)
		(width 0.1143)
		(layer "In11.Cu")
		(net "P5E_CPU0_P3_TX_DN<2>")
	)
	(segment
		(start 362.657136 -280.084022)
		(end 362.65866 -280.085038)
		(width 0.1143)
		(layer "In11.Cu")
		(net "P5E_CPU0_P3_TX_DN<2>")
	)
	(segment
		(start 362.672122 -284.952948)
		(end 362.679996 -284.956758)
		(width 0.1143)
		(layer "In11.Cu")
		(net "P5E_CPU0_P3_TX_DN<2>")
	)
	(segment
		(start 362.642404 -286.555942)
		(end 362.688886 -286.582866)
		(width 0.1143)
		(layer "In11.Cu")
		(net "P5E_CPU0_P3_TX_DN<2>")
	)
	(segment
		(start 362.739432 -285.849822)
		(end 362.680758 -285.901384)
		(width 0.1143)
		(layer "In11.Cu")
		(net "P5E_CPU0_P3_TX_DN<2>")
	)
	(segment
		(start 362.701332 -293.071296)
		(end 362.701586 -293.07155)
		(width 0.1143)
		(layer "In11.Cu")
		(net "P5E_CPU0_P3_TX_DN<2>")
	)
	(segment
		(start 363.304836 -278.946102)
		(end 363.006894 -278.946102)
		(width 0.1143)
		(layer "In11.Cu")
		(net "P5E_CPU0_P3_TX_DN<2>")
	)
	(segment
		(start 368.752882 -308.38648)
		(end 376.155712 -317.406528)
		(width 0.14224)
		(layer "In11.Cu")
		(net "P5E_CPU0_P3_TX_DN<2>")
	)
	(segment
		(start 362.638848 -279.438354)
		(end 362.638594 -279.438354)
		(width 0.1143)
		(layer "In11.Cu")
		(net "P5E_CPU0_P3_TX_DN<2>")
	)
	(segment
		(start 363.006894 -278.946102)
		(end 362.92409 -279.028906)
		(width 0.1143)
		(layer "In11.Cu")
		(net "P5E_CPU0_P3_TX_DN<2>")
	)
	(segment
		(start 362.646468 -282.674314)
		(end 362.639102 -282.678378)
		(width 0.1143)
		(layer "In11.Cu")
		(net "P5E_CPU0_P3_TX_DN<2>")
	)
	(segment
		(start 362.636562 -281.69235)
		(end 362.686092 -281.721052)
		(width 0.1143)
		(layer "In11.Cu")
		(net "P5E_CPU0_P3_TX_DN<2>")
	)
	(segment
		(start 362.460032 -287.825434)
		(end 362.460032 -287.856422)
		(width 0.1143)
		(layer "In11.Cu")
		(net "P5E_CPU0_P3_TX_DN<2>")
	)
	(segment
		(start 362.63072 -294.64889)
		(end 362.654596 -294.662606)
		(width 0.1143)
		(layer "In11.Cu")
		(net "P5E_CPU0_P3_TX_DN<2>")
	)
	(segment
		(start 362.647992 -288.178748)
		(end 362.648754 -288.179256)
		(width 0.1143)
		(layer "In11.Cu")
		(net "P5E_CPU0_P3_TX_DN<2>")
	)
	(segment
		(start 362.686092 -284.271212)
		(end 362.642658 -284.296358)
		(width 0.1143)
		(layer "In11.Cu")
		(net "P5E_CPU0_P3_TX_DN<2>")
	)
	(segment
		(start 362.686092 -292.371272)
		(end 362.641134 -292.396926)
		(width 0.1143)
		(layer "In11.Cu")
		(net "P5E_CPU0_P3_TX_DN<2>")
	)
	(segment
		(start 362.686092 -290.751006)
		(end 362.617512 -290.790884)
		(width 0.1143)
		(layer "In11.Cu")
		(net "P5E_CPU0_P3_TX_DN<2>")
	)
	(segment
		(start 362.67644 -287.51657)
		(end 362.580174 -287.570672)
		(width 0.1143)
		(layer "In11.Cu")
		(net "P5E_CPU0_P3_TX_DN<2>")
	)
	(segment
		(start 362.643166 -279.436068)
		(end 362.643166 -279.435814)
		(width 0.1143)
		(layer "In11.Cu")
		(net "P5E_CPU0_P3_TX_DN<2>")
	)
	(segment
		(start 362.679996 -284.956758)
		(end 362.697776 -284.969204)
		(width 0.1143)
		(layer "In11.Cu")
		(net "P5E_CPU0_P3_TX_DN<2>")
	)
	(segment
		(start 362.929932 -287.045908)
		(end 362.929932 -287.12414)
		(width 0.1143)
		(layer "In11.Cu")
		(net "P5E_CPU0_P3_TX_DN<2>")
	)
	(segment
		(start 362.749084 -285.84144)
		(end 362.741972 -285.84779)
		(width 0.1143)
		(layer "In11.Cu")
		(net "P5E_CPU0_P3_TX_DN<2>")
	)
	(segment
		(start 362.70692 -293.075614)
		(end 362.709206 -293.077392)
		(width 0.1143)
		(layer "In11.Cu")
		(net "P5E_CPU0_P3_TX_DN<2>")
	)
	(segment
		(start 362.64088 -284.934914)
		(end 362.672122 -284.952948)
		(width 0.1143)
		(layer "In11.Cu")
		(net "P5E_CPU0_P3_TX_DN<2>")
	)
	(segment
		(start 362.668566 -289.141154)
		(end 362.616496 -289.17138)
		(width 0.1143)
		(layer "In11.Cu")
		(net "P5E_CPU0_P3_TX_DN<2>")
	)
	(segment
		(start 363.445806 -296.446956)
		(end 363.445806 -296.890948)
		(width 0.14224)
		(layer "In11.Cu")
		(net "P5E_CPU0_P3_TX_DN<2>")
	)
	(segment
		(start 362.687108 -281.030934)
		(end 362.636562 -281.05989)
		(width 0.1143)
		(layer "In11.Cu")
		(net "P5E_CPU0_P3_TX_DN<2>")
	)
	(segment
		(start 362.642658 -284.296358)
		(end 362.568744 -284.333442)
		(width 0.1143)
		(layer "In11.Cu")
		(net "P5E_CPU0_P3_TX_DN<2>")
	)
	(segment
		(start 363.445806 -296.890948)
		(end 363.445298 -296.891456)
		(width 0.14224)
		(layer "In11.Cu")
		(net "P5E_CPU0_P3_TX_DN<2>")
	)
	(segment
		(start 378.578872 -321.03314)
		(end 380.338076 -325.280274)
		(width 0.14224)
		(layer "In11.Cu")
		(net "P5E_CPU0_P3_TX_DN<2>")
	)
	(segment
		(start 362.693712 -294.685212)
		(end 362.694728 -294.68699)
		(width 0.1143)
		(layer "In11.Cu")
		(net "P5E_CPU0_P3_TX_DN<2>")
	)
	(segment
		(start 362.676948 -287.516316)
		(end 362.67644 -287.51657)
		(width 0.1143)
		(layer "In11.Cu")
		(net "P5E_CPU0_P3_TX_DN<2>")
	)
	(segment
		(start 383.537968 -341.367618)
		(end 383.537968 -347.501464)
		(width 0.14224)
		(layer "In11.Cu")
		(net "P5E_CPU0_P3_TX_DN<2>")
	)
	(segment
		(start 362.634784 -289.79114)
		(end 362.638086 -289.79114)
		(width 0.1143)
		(layer "In11.Cu")
		(net "P5E_CPU0_P3_TX_DN<2>")
	)
	(segment
		(start 376.155712 -317.406528)
		(end 378.578872 -321.03314)
		(width 0.14224)
		(layer "In11.Cu")
		(net "P5E_CPU0_P3_TX_DN<2>")
	)
	(segment
		(start 362.61675 -289.780472)
		(end 362.634784 -289.79114)
		(width 0.1143)
		(layer "In11.Cu")
		(net "P5E_CPU0_P3_TX_DN<2>")
	)
	(segment
		(start 362.704888 -293.07409)
		(end 362.70565 -293.074598)
		(width 0.1143)
		(layer "In11.Cu")
		(net "P5E_CPU0_P3_TX_DN<2>")
	)
	(segment
		(start 362.687362 -280.101548)
		(end 362.715048 -280.121614)
		(width 0.1143)
		(layer "In11.Cu")
		(net "P5E_CPU0_P3_TX_DN<2>")
	)
	(segment
		(start 362.648754 -280.078688)
		(end 362.65739 -280.084276)
		(width 0.1143)
		(layer "In11.Cu")
		(net "P5E_CPU0_P3_TX_DN<2>")
	)
	(segment
		(start 362.648754 -288.179256)
		(end 362.697268 -288.208212)
		(width 0.1143)
		(layer "In11.Cu")
		(net "P5E_CPU0_P3_TX_DN<2>")
	)
	(segment
		(start 362.858812 -288.397188)
		(end 362.85932 -288.398204)
		(width 0.1143)
		(layer "In11.Cu")
		(net "P5E_CPU0_P3_TX_DN<2>")
	)
	(segment
		(start 362.568744 -284.333442)
		(end 362.554266 -284.347158)
		(width 0.1143)
		(layer "In11.Cu")
		(net "P5E_CPU0_P3_TX_DN<2>")
	)
	(segment
		(start 362.715048 -281.010614)
		(end 362.687108 -281.030934)
		(width 0.1143)
		(layer "In11.Cu")
		(net "P5E_CPU0_P3_TX_DN<2>")
	)
	(segment
		(start 366.68075 -377.272042)
		(end 366.68075 -379.583188)
		(width 0.14224)
		(layer "In11.Cu")
		(net "P5E_CPU0_P3_TX_DN<2>")
	)
	(segment
		(start 377.6472 -363.900212)
		(end 367.69675 -375.184924)
		(width 0.14224)
		(layer "In11.Cu")
		(net "P5E_CPU0_P3_TX_DN<2>")
	)
	(segment
		(start 362.65866 -280.085038)
		(end 362.687362 -280.101548)
		(width 0.1143)
		(layer "In11.Cu")
		(net "P5E_CPU0_P3_TX_DN<2>")
	)
	(segment
		(start 364.90021 -302.620426)
		(end 368.752882 -308.38648)
		(width 0.14224)
		(layer "In11.Cu")
		(net "P5E_CPU0_P3_TX_DN<2>")
	)
	(segment
		(start 362.85932 -288.398204)
		(end 362.889292 -288.463482)
		(width 0.1143)
		(layer "In11.Cu")
		(net "P5E_CPU0_P3_TX_DN<2>")
	)
	(segment
		(start 362.6485 -294.000428)
		(end 362.610908 -294.025066)
		(width 0.1143)
		(layer "In11.Cu")
		(net "P5E_CPU0_P3_TX_DN<2>")
	)
	(segment
		(start 380.338076 -325.280274)
		(end 383.537968 -341.367618)
		(width 0.14224)
		(layer "In11.Cu")
		(net "P5E_CPU0_P3_TX_DN<2>")
	)
	(segment
		(start 362.613448 -288.158682)
		(end 362.647992 -288.178748)
		(width 0.1143)
		(layer "In11.Cu")
		(net "P5E_CPU0_P3_TX_DN<2>")
	)
	(segment
		(start 362.741972 -285.84779)
		(end 362.739432 -285.849822)
		(width 0.1143)
		(layer "In11.Cu")
		(net "P5E_CPU0_P3_TX_DN<2>")
	)
	(segment
		(start 362.686854 -279.410668)
		(end 362.643166 -279.436068)
		(width 0.1143)
		(layer "In11.Cu")
		(net "P5E_CPU0_P3_TX_DN<2>")
	)
	(segment
		(start 362.616242 -293.020242)
		(end 362.69041 -293.063422)
		(width 0.1143)
		(layer "In11.Cu")
		(net "P5E_CPU0_P3_TX_DN<2>")
	)
	(segment
		(start 362.742226 -287.472882)
		(end 362.676948 -287.516316)
		(width 0.1143)
		(layer "In11.Cu")
		(net "P5E_CPU0_P3_TX_DN<2>")
	)
	(segment
		(start 363.400086 -295.95572)
		(end 363.400086 -296.386758)
		(width 0.1143)
		(layer "In11.Cu")
		(net "P5E_CPU0_P3_TX_DN<2>")
	)
	(segment
		(start 362.65739 -280.084276)
		(end 362.657136 -280.084022)
		(width 0.1143)
		(layer "In11.Cu")
		(net "P5E_CPU0_P3_TX_DN<2>")
	)
	(segment
		(start 362.616496 -289.17138)
		(end 362.61421 -289.173158)
		(width 0.1143)
		(layer "In11.Cu")
		(net "P5E_CPU0_P3_TX_DN<2>")
	)
	(segment
		(start 362.703364 -293.07282)
		(end 362.704888 -293.07409)
		(width 0.1143)
		(layer "In11.Cu")
		(net "P5E_CPU0_P3_TX_DN<2>")
	)
	(segment
		(start 362.701586 -293.07155)
		(end 362.703364 -293.07282)
		(width 0.1143)
		(layer "In11.Cu")
		(net "P5E_CPU0_P3_TX_DN<2>")
	)
	(segment
		(start 362.63961 -283.31414)
		(end 362.686092 -283.34081)
		(width 0.1143)
		(layer "In11.Cu")
		(net "P5E_CPU0_P3_TX_DN<2>")
	)
	(segment
		(start 362.654596 -294.662606)
		(end 362.686346 -294.680894)
		(width 0.1143)
		(layer "In11.Cu")
		(net "P5E_CPU0_P3_TX_DN<2>")
	)
	(segment
		(start 362.69041 -293.063422)
		(end 362.701332 -293.071296)
		(width 0.1143)
		(layer "In11.Cu")
		(net "P5E_CPU0_P3_TX_DN<2>")
	)
	(segment
		(start 362.616496 -290.791646)
		(end 362.615988 -290.791646)
		(width 0.1143)
		(layer "In11.Cu")
		(net "P5E_CPU0_P3_TX_DN<2>")
	)
	(segment
		(start 362.579412 -287.57118)
		(end 362.578904 -287.57118)
		(width 0.1143)
		(layer "In11.Cu")
		(net "P5E_CPU0_P3_TX_DN<2>")
	)
	(segment
		(start 362.657644 -293.995094)
		(end 362.6485 -294.000428)
		(width 0.1143)
		(layer "In11.Cu")
		(net "P5E_CPU0_P3_TX_DN<2>")
	)
	(segment
		(start 362.6485 -280.078688)
		(end 362.648754 -280.078688)
		(width 0.1143)
		(layer "In11.Cu")
		(net "P5E_CPU0_P3_TX_DN<2>")
	)
	(segment
		(start 362.697776 -284.969204)
		(end 362.6993 -284.97022)
		(width 0.1143)
		(layer "In11.Cu")
		(net "P5E_CPU0_P3_TX_DN<2>")
	)
	(segment
		(start 362.580174 -287.570672)
		(end 362.579412 -287.57118)
		(width 0.1143)
		(layer "In11.Cu")
		(net "P5E_CPU0_P3_TX_DN<2>")
	)
	(segment
		(start 382.909572 -351.122996)
		(end 380.201678 -358.691688)
		(width 0.14224)
		(layer "In11.Cu")
		(net "P5E_CPU0_P3_TX_DN<2>")
	)
	(segment
		(start 362.460032 -287.856422)
		(end 362.460286 -287.856168)
		(width 0.1143)
		(layer "In11.Cu")
		(net "P5E_CPU0_P3_TX_DN<2>")
	)
	(segment
		(start 362.693458 -294.68572)
		(end 362.693712 -294.685212)
		(width 0.1143)
		(layer "In11.Cu")
		(net "P5E_CPU0_P3_TX_DN<2>")
	)
	(segment
		(start 362.61421 -289.173158)
		(end 362.611924 -289.174682)
		(width 0.1143)
		(layer "In11.Cu")
		(net "P5E_CPU0_P3_TX_DN<2>")
	)
	(segment
		(start 363.445298 -296.891456)
		(end 363.445298 -297.824906)
		(width 0.14224)
		(layer "In11.Cu")
		(net "P5E_CPU0_P3_TX_DN<2>")
	)
	(segment
		(start 363.445806 -296.432478)
		(end 363.445806 -296.446956)
		(width 0.1143)
		(layer "In11.Cu")
		(net "P5E_CPU0_P3_TX_DN<2>")
	)
	(segment
		(start 362.70565 -293.074598)
		(end 362.70692 -293.075614)
		(width 0.1143)
		(layer "In11.Cu")
		(net "P5E_CPU0_P3_TX_DN<2>")
	)
	(segment
		(start 362.554266 -284.347158)
		(end 362.50626 -284.43428)
		(width 0.1143)
		(layer "In11.Cu")
		(net "P5E_CPU0_P3_TX_DN<2>")
	)
	(segment
		(start 362.617512 -291.400992)
		(end 362.686092 -291.44087)
		(width 0.1143)
		(layer "In11.Cu")
		(net "P5E_CPU0_P3_TX_DN<2>")
	)
	(segment
		(start 362.638594 -279.438354)
		(end 362.556298 -279.52065)
		(width 0.1143)
		(layer "In11.Cu")
		(net "P5E_CPU0_P3_TX_DN<2>")
	)
	(segment
		(start 363.400086 -296.386758)
		(end 363.445806 -296.432478)
		(width 0.1143)
		(layer "In11.Cu")
		(net "P5E_CPU0_P3_TX_DN<2>")
	)
	(segment
		(start 362.50626 -284.43428)
		(end 362.50626 -284.434534)
		(width 0.1143)
		(layer "In11.Cu")
		(net "P5E_CPU0_P3_TX_DN<2>")
	)
	(arc
		(start 362.460286 -287.856168)
		(mid 362.500645 -288.025768)
		(end 362.613448 -288.158682)
		(width 0.1143)
		(layer "In11.Cu")
		(net "P5E_CPU0_P3_TX_DN<2>")
	)
	(arc
		(start 362.686092 -281.721052)
		(mid 362.929946 -282.186126)
		(end 362.686092 -282.6512)
		(width 0.1143)
		(layer "In11.Cu")
		(net "P5E_CPU0_P3_TX_DN<2>")
	)
	(arc
		(start 362.680758 -285.901384)
		(mid 362.664075 -285.911372)
		(end 362.644944 -285.914846)
		(width 0.1143)
		(layer "In11.Cu")
		(net "P5E_CPU0_P3_TX_DN<2>")
	)
	(arc
		(start 362.929932 -287.12414)
		(mid 362.879846 -287.322059)
		(end 362.742226 -287.472882)
		(width 0.1143)
		(layer "In11.Cu")
		(net "P5E_CPU0_P3_TX_DN<2>")
	)
	(arc
		(start 362.617512 -290.790884)
		(mid 362.617004 -290.791265)
		(end 362.616496 -290.791646)
		(width 0.1143)
		(layer "In11.Cu")
		(net "P5E_CPU0_P3_TX_DN<2>")
	)
	(arc
		(start 362.611924 -289.174682)
		(mid 362.457414 -289.475823)
		(end 362.61167 -289.77717)
		(width 0.1143)
		(layer "In11.Cu")
		(net "P5E_CPU0_P3_TX_DN<2>")
	)
	(arc
		(start 362.6993 -284.97022)
		(mid 362.936511 -285.393728)
		(end 362.749084 -285.84144)
		(width 0.1143)
		(layer "In11.Cu")
		(net "P5E_CPU0_P3_TX_DN<2>")
	)
	(arc
		(start 367.69675 -375.184924)
		(mid 367.301117 -375.708681)
		(end 366.988344 -376.28576)
		(width 0.14224)
		(layer "In11.Cu")
		(net "P5E_CPU0_P3_TX_DN<2>")
	)
	(arc
		(start 363.207554 -295.531286)
		(mid 363.349619 -295.72273)
		(end 363.400086 -295.95572)
		(width 0.1143)
		(layer "In11.Cu")
		(net "P5E_CPU0_P3_TX_DN<2>")
	)
	(arc
		(start 362.92028 -279.051766)
		(mid 362.838847 -279.254164)
		(end 362.686854 -279.410668)
		(width 0.1143)
		(layer "In11.Cu")
		(net "P5E_CPU0_P3_TX_DN<2>")
	)
	(arc
		(start 377.750832 -363.761274)
		(mid 377.701892 -363.832888)
		(end 377.6472 -363.900212)
		(width 0.14224)
		(layer "In11.Cu")
		(net "P5E_CPU0_P3_TX_DN<2>")
	)
	(arc
		(start 362.50626 -284.434534)
		(mid 362.47261 -284.711863)
		(end 362.64088 -284.934914)
		(width 0.1143)
		(layer "In11.Cu")
		(net "P5E_CPU0_P3_TX_DN<2>")
	)
	(arc
		(start 362.550964 -287.592008)
		(mid 362.483589 -287.700183)
		(end 362.460032 -287.825434)
		(width 0.1143)
		(layer "In11.Cu")
		(net "P5E_CPU0_P3_TX_DN<2>")
	)
	(arc
		(start 362.615988 -292.411912)
		(mid 362.460055 -292.716127)
		(end 362.616242 -293.020242)
		(width 0.1143)
		(layer "In11.Cu")
		(net "P5E_CPU0_P3_TX_DN<2>")
	)
	(arc
		(start 362.92409 -279.028906)
		(mid 362.922302 -279.040355)
		(end 362.92028 -279.051766)
		(width 0.1143)
		(layer "In11.Cu")
		(net "P5E_CPU0_P3_TX_DN<2>")
	)
	(arc
		(start 362.694728 -294.68699)
		(mid 362.867714 -294.888099)
		(end 362.929932 -295.145968)
		(width 0.1143)
		(layer "In11.Cu")
		(net "P5E_CPU0_P3_TX_DN<2>")
	)
	(arc
		(start 362.889292 -288.463482)
		(mid 362.931218 -288.750178)
		(end 362.812838 -289.014662)
		(width 0.1143)
		(layer "In11.Cu")
		(net "P5E_CPU0_P3_TX_DN<2>")
	)
	(arc
		(start 362.578904 -287.57118)
		(mid 362.564259 -287.580687)
		(end 362.550964 -287.592008)
		(width 0.1143)
		(layer "In11.Cu")
		(net "P5E_CPU0_P3_TX_DN<2>")
	)
	(arc
		(start 362.644944 -285.914846)
		(mid 362.460028 -286.234675)
		(end 362.642404 -286.555942)
		(width 0.1143)
		(layer "In11.Cu")
		(net "P5E_CPU0_P3_TX_DN<2>")
	)
	(arc
		(start 362.643166 -279.435814)
		(mid 362.641003 -279.437077)
		(end 362.638848 -279.438354)
		(width 0.1143)
		(layer "In11.Cu")
		(net "P5E_CPU0_P3_TX_DN<2>")
	)
	(arc
		(start 380.201678 -358.691688)
		(mid 379.111672 -361.291948)
		(end 377.750832 -363.761274)
		(width 0.14224)
		(layer "In11.Cu")
		(net "P5E_CPU0_P3_TX_DN<2>")
	)
	(arc
		(start 362.639102 -282.678378)
		(mid 362.456751 -282.996415)
		(end 362.63961 -283.31414)
		(width 0.1143)
		(layer "In11.Cu")
		(net "P5E_CPU0_P3_TX_DN<2>")
	)
	(arc
		(start 362.812838 -289.014662)
		(mid 362.746924 -289.085007)
		(end 362.668566 -289.141154)
		(width 0.1143)
		(layer "In11.Cu")
		(net "P5E_CPU0_P3_TX_DN<2>")
	)
	(arc
		(start 362.480606 -279.635458)
		(mid 362.476639 -279.886246)
		(end 362.641642 -280.075132)
		(width 0.1143)
		(layer "In11.Cu")
		(net "P5E_CPU0_P3_TX_DN<2>")
	)
	(arc
		(start 362.556298 -279.52065)
		(mid 362.512646 -279.574227)
		(end 362.480606 -279.635458)
		(width 0.1143)
		(layer "In11.Cu")
		(net "P5E_CPU0_P3_TX_DN<2>")
	)
	(arc
		(start 362.715048 -280.121614)
		(mid 362.942736 -280.566114)
		(end 362.715048 -281.010614)
		(width 0.1143)
		(layer "In11.Cu")
		(net "P5E_CPU0_P3_TX_DN<2>")
	)
	(arc
		(start 362.613956 -291.398452)
		(mid 362.61573 -291.399727)
		(end 362.617512 -291.400992)
		(width 0.1143)
		(layer "In11.Cu")
		(net "P5E_CPU0_P3_TX_DN<2>")
	)
	(arc
		(start 363.15523 -295.490392)
		(mid 363.181996 -295.510066)
		(end 363.207554 -295.531286)
		(width 0.1143)
		(layer "In11.Cu")
		(net "P5E_CPU0_P3_TX_DN<2>")
	)
	(arc
		(start 362.686092 -283.34081)
		(mid 362.930264 -283.806066)
		(end 362.686092 -284.271212)
		(width 0.1143)
		(layer "In11.Cu")
		(net "P5E_CPU0_P3_TX_DN<2>")
	)
	(arc
		(start 362.615988 -290.791646)
		(mid 362.466893 -291.09459)
		(end 362.613956 -291.398452)
		(width 0.1143)
		(layer "In11.Cu")
		(net "P5E_CPU0_P3_TX_DN<2>")
	)
	(arc
		(start 362.686346 -294.680894)
		(mid 362.689911 -294.683293)
		(end 362.693458 -294.68572)
		(width 0.1143)
		(layer "In11.Cu")
		(net "P5E_CPU0_P3_TX_DN<2>")
	)
	(arc
		(start 362.697268 -288.208974)
		(mid 362.757439 -288.259405)
		(end 362.810044 -288.317686)
		(width 0.1143)
		(layer "In11.Cu")
		(net "P5E_CPU0_P3_TX_DN<2>")
	)
	(arc
		(start 362.641642 -280.075132)
		(mid 362.645061 -280.076929)
		(end 362.6485 -280.078688)
		(width 0.1143)
		(layer "In11.Cu")
		(net "P5E_CPU0_P3_TX_DN<2>")
	)
	(arc
		(start 362.610908 -294.025066)
		(mid 362.447575 -294.342515)
		(end 362.63072 -294.64889)
		(width 0.1143)
		(layer "In11.Cu")
		(net "P5E_CPU0_P3_TX_DN<2>")
	)
	(arc
		(start 362.636562 -281.05989)
		(mid 362.454645 -281.37612)
		(end 362.636562 -281.69235)
		(width 0.1143)
		(layer "In11.Cu")
		(net "P5E_CPU0_P3_TX_DN<2>")
	)
	(arc
		(start 362.810044 -288.317686)
		(mid 362.836766 -288.356003)
		(end 362.858812 -288.397188)
		(width 0.1143)
		(layer "In11.Cu")
		(net "P5E_CPU0_P3_TX_DN<2>")
	)
	(arc
		(start 366.988344 -376.28576)
		(mid 366.759258 -376.755415)
		(end 366.68075 -377.272042)
		(width 0.14224)
		(layer "In11.Cu")
		(net "P5E_CPU0_P3_TX_DN<2>")
	)
	(arc
		(start 362.638086 -289.79114)
		(mid 362.929333 -290.257702)
		(end 362.686092 -290.751006)
		(width 0.1143)
		(layer "In11.Cu")
		(net "P5E_CPU0_P3_TX_DN<2>")
	)
	(arc
		(start 362.929932 -295.145968)
		(mid 362.971191 -295.316825)
		(end 363.085888 -295.450006)
		(width 0.1143)
		(layer "In11.Cu")
		(net "P5E_CPU0_P3_TX_DN<2>")
	)
	(arc
		(start 383.537968 -347.501464)
		(mid 383.37971 -349.339289)
		(end 382.909572 -351.122996)
		(width 0.14224)
		(layer "In11.Cu")
		(net "P5E_CPU0_P3_TX_DN<2>")
	)
	(arc
		(start 362.686092 -291.44087)
		(mid 362.930264 -291.906126)
		(end 362.686092 -292.371272)
		(width 0.1143)
		(layer "In11.Cu")
		(net "P5E_CPU0_P3_TX_DN<2>")
	)
	(arc
		(start 362.688886 -286.582866)
		(mid 362.866082 -286.784878)
		(end 362.929932 -287.045908)
		(width 0.1143)
		(layer "In11.Cu")
		(net "P5E_CPU0_P3_TX_DN<2>")
	)
	(arc
		(start 362.709206 -293.077392)
		(mid 362.932613 -293.550294)
		(end 362.657644 -293.995094)
		(width 0.1143)
		(layer "In11.Cu")
		(net "P5E_CPU0_P3_TX_DN<2>")
	)
	(segment
		(start 364.80115 -384.94335)
		(end 365.50473 -384.94335)
		(width 0.12954)
		(layer "F.Cu")
		(net "P5E_CPU0_P3_TX_DN<1>")
	)
	(segment
		(start 365.50473 -384.94335)
		(end 365.80064 -385.23926)
		(width 0.12954)
		(layer "F.Cu")
		(net "P5E_CPU0_P3_TX_DN<1>")
	)
	(segment
		(start 362.837984 -277.060152)
		(end 363.304836 -277.32609)
		(width 0.12954)
		(layer "F.Cu")
		(net "P5E_CPU0_P3_TX_DN<1>")
	)
	(segment
		(start 364.53064 -385.21386)
		(end 364.80115 -384.94335)
		(width 0.12954)
		(layer "F.Cu")
		(net "P5E_CPU0_P3_TX_DN<1>")
	)
	(segment
		(start 361.7468 -284.270704)
		(end 361.7087 -284.293056)
		(width 0.1143)
		(layer "In11.Cu")
		(net "P5E_CPU0_P3_TX_DN<1>")
	)
	(segment
		(start 361.705398 -281.697176)
		(end 361.708954 -281.699462)
		(width 0.1143)
		(layer "In11.Cu")
		(net "P5E_CPU0_P3_TX_DN<1>")
	)
	(segment
		(start 361.74426 -287.512252)
		(end 361.680252 -287.549336)
		(width 0.1143)
		(layer "In11.Cu")
		(net "P5E_CPU0_P3_TX_DN<1>")
	)
	(segment
		(start 364.842298 -377.99137)
		(end 364.842298 -381.28067)
		(width 0.14224)
		(layer "In11.Cu")
		(net "P5E_CPU0_P3_TX_DN<1>")
	)
	(segment
		(start 361.707684 -289.798506)
		(end 361.7468 -289.821366)
		(width 0.1143)
		(layer "In11.Cu")
		(net "P5E_CPU0_P3_TX_DN<1>")
	)
	(segment
		(start 361.7468 -281.03068)
		(end 361.708954 -281.052778)
		(width 0.1143)
		(layer "In11.Cu")
		(net "P5E_CPU0_P3_TX_DN<1>")
	)
	(segment
		(start 361.711494 -293.040816)
		(end 361.746038 -293.060882)
		(width 0.1143)
		(layer "In11.Cu")
		(net "P5E_CPU0_P3_TX_DN<1>")
	)
	(segment
		(start 362.192824 -278.614886)
		(end 362.192824 -278.61514)
		(width 0.1143)
		(layer "In11.Cu")
		(net "P5E_CPU0_P3_TX_DN<1>")
	)
	(segment
		(start 361.702858 -292.39591)
		(end 361.700826 -292.39718)
		(width 0.1143)
		(layer "In11.Cu")
		(net "P5E_CPU0_P3_TX_DN<1>")
	)
	(segment
		(start 361.652058 -291.380926)
		(end 361.728004 -291.430456)
		(width 0.1143)
		(layer "In11.Cu")
		(net "P5E_CPU0_P3_TX_DN<1>")
	)
	(segment
		(start 361.677204 -294.640762)
		(end 361.707684 -294.658542)
		(width 0.1143)
		(layer "In11.Cu")
		(net "P5E_CPU0_P3_TX_DN<1>")
	)
	(segment
		(start 361.727242 -289.141408)
		(end 361.726734 -289.141662)
		(width 0.1143)
		(layer "In11.Cu")
		(net "P5E_CPU0_P3_TX_DN<1>")
	)
	(segment
		(start 362.505752 -296.418508)
		(end 362.505752 -296.446956)
		(width 0.1143)
		(layer "In11.Cu")
		(net "P5E_CPU0_P3_TX_DN<1>")
	)
	(segment
		(start 361.67568 -280.059892)
		(end 361.707684 -280.078688)
		(width 0.1143)
		(layer "In11.Cu")
		(net "P5E_CPU0_P3_TX_DN<1>")
	)
	(segment
		(start 361.7468 -285.890716)
		(end 361.676188 -285.932118)
		(width 0.1143)
		(layer "In11.Cu")
		(net "P5E_CPU0_P3_TX_DN<1>")
	)
	(segment
		(start 376.100086 -364.133638)
		(end 365.807498 -375.489724)
		(width 0.14224)
		(layer "In11.Cu")
		(net "P5E_CPU0_P3_TX_DN<1>")
	)
	(segment
		(start 362.177584 -295.468548)
		(end 362.2167 -295.491408)
		(width 0.1143)
		(layer "In11.Cu")
		(net "P5E_CPU0_P3_TX_DN<1>")
	)
	(segment
		(start 361.707684 -280.078688)
		(end 361.7468 -280.101548)
		(width 0.1143)
		(layer "In11.Cu")
		(net "P5E_CPU0_P3_TX_DN<1>")
	)
	(segment
		(start 361.712256 -289.15106)
		(end 361.712256 -289.150806)
		(width 0.1143)
		(layer "In11.Cu")
		(net "P5E_CPU0_P3_TX_DN<1>")
	)
	(segment
		(start 362.460032 -278.133302)
		(end 362.460032 -278.136096)
		(width 0.1143)
		(layer "In11.Cu")
		(net "P5E_CPU0_P3_TX_DN<1>")
	)
	(segment
		(start 361.7468 -279.410668)
		(end 361.707684 -279.433528)
		(width 0.1143)
		(layer "In11.Cu")
		(net "P5E_CPU0_P3_TX_DN<1>")
	)
	(segment
		(start 361.677204 -289.780726)
		(end 361.707684 -289.798506)
		(width 0.1143)
		(layer "In11.Cu")
		(net "P5E_CPU0_P3_TX_DN<1>")
	)
	(segment
		(start 364.040928 -303.01311)
		(end 368.096546 -309.082694)
		(width 0.14224)
		(layer "In11.Cu")
		(net "P5E_CPU0_P3_TX_DN<1>")
	)
	(segment
		(start 375.49963 -318.10325)
		(end 377.72467 -321.43319)
		(width 0.14224)
		(layer "In11.Cu")
		(net "P5E_CPU0_P3_TX_DN<1>")
	)
	(segment
		(start 361.700826 -293.03472)
		(end 361.702096 -293.035228)
		(width 0.1143)
		(layer "In11.Cu")
		(net "P5E_CPU0_P3_TX_DN<1>")
	)
	(segment
		(start 362.460032 -295.955974)
		(end 362.460032 -296.372788)
		(width 0.1143)
		(layer "In11.Cu")
		(net "P5E_CPU0_P3_TX_DN<1>")
	)
	(segment
		(start 366.115346 -384.735578)
		(end 366.047782 -384.803142)
		(width 0.14224)
		(layer "In11.Cu")
		(net "P5E_CPU0_P3_TX_DN<1>")
	)
	(segment
		(start 361.704128 -281.696668)
		(end 361.705398 -281.697176)
		(width 0.1143)
		(layer "In11.Cu")
		(net "P5E_CPU0_P3_TX_DN<1>")
	)
	(segment
		(start 361.705398 -282.675076)
		(end 361.704382 -282.675584)
		(width 0.1143)
		(layer "In11.Cu")
		(net "P5E_CPU0_P3_TX_DN<1>")
	)
	(segment
		(start 361.708954 -282.67279)
		(end 361.705398 -282.675076)
		(width 0.1143)
		(layer "In11.Cu")
		(net "P5E_CPU0_P3_TX_DN<1>")
	)
	(segment
		(start 361.705398 -293.03726)
		(end 361.706922 -293.038276)
		(width 0.1143)
		(layer "In11.Cu")
		(net "P5E_CPU0_P3_TX_DN<1>")
	)
	(segment
		(start 361.707684 -279.433528)
		(end 361.682538 -279.448514)
		(width 0.1143)
		(layer "In11.Cu")
		(net "P5E_CPU0_P3_TX_DN<1>")
	)
	(segment
		(start 381.946912 -350.783652)
		(end 379.774704 -356.854252)
		(width 0.14224)
		(layer "In11.Cu")
		(net "P5E_CPU0_P3_TX_DN<1>")
	)
	(segment
		(start 361.702096 -293.035228)
		(end 361.704382 -293.036752)
		(width 0.1143)
		(layer "In11.Cu")
		(net "P5E_CPU0_P3_TX_DN<1>")
	)
	(segment
		(start 361.7087 -284.293056)
		(end 361.707938 -284.293564)
		(width 0.1143)
		(layer "In11.Cu")
		(net "P5E_CPU0_P3_TX_DN<1>")
	)
	(segment
		(start 377.72467 -321.43319)
		(end 379.424692 -325.536814)
		(width 0.14224)
		(layer "In11.Cu")
		(net "P5E_CPU0_P3_TX_DN<1>")
	)
	(segment
		(start 361.708954 -283.319474)
		(end 361.745276 -283.340556)
		(width 0.1143)
		(layer "In11.Cu")
		(net "P5E_CPU0_P3_TX_DN<1>")
	)
	(segment
		(start 361.704382 -293.036752)
		(end 361.705398 -293.03726)
		(width 0.1143)
		(layer "In11.Cu")
		(net "P5E_CPU0_P3_TX_DN<1>")
	)
	(segment
		(start 361.706922 -293.038276)
		(end 361.710732 -293.040308)
		(width 0.1143)
		(layer "In11.Cu")
		(net "P5E_CPU0_P3_TX_DN<1>")
	)
	(segment
		(start 361.712256 -289.150806)
		(end 361.707684 -289.153346)
		(width 0.1143)
		(layer "In11.Cu")
		(net "P5E_CPU0_P3_TX_DN<1>")
	)
	(segment
		(start 361.677712 -288.161222)
		(end 361.71378 -288.18205)
		(width 0.1143)
		(layer "In11.Cu")
		(net "P5E_CPU0_P3_TX_DN<1>")
	)
	(segment
		(start 361.520232 -286.22244)
		(end 361.520232 -286.23895)
		(width 0.1143)
		(layer "In11.Cu")
		(net "P5E_CPU0_P3_TX_DN<1>")
	)
	(segment
		(start 361.7468 -293.990522)
		(end 361.707684 -294.013382)
		(width 0.1143)
		(layer "In11.Cu")
		(net "P5E_CPU0_P3_TX_DN<1>")
	)
	(segment
		(start 368.096546 -309.082694)
		(end 375.49963 -318.10325)
		(width 0.14224)
		(layer "In11.Cu")
		(net "P5E_CPU0_P3_TX_DN<1>")
	)
	(segment
		(start 361.707684 -294.658542)
		(end 361.7468 -294.681402)
		(width 0.1143)
		(layer "In11.Cu")
		(net "P5E_CPU0_P3_TX_DN<1>")
	)
	(segment
		(start 362.215938 -278.601424)
		(end 362.192824 -278.614886)
		(width 0.1143)
		(layer "In11.Cu")
		(net "P5E_CPU0_P3_TX_DN<1>")
	)
	(segment
		(start 365.758476 -384.92303)
		(end 364.82147 -384.92303)
		(width 0.14224)
		(layer "In11.Cu")
		(net "P5E_CPU0_P3_TX_DN<1>")
	)
	(segment
		(start 379.424692 -325.536814)
		(end 382.598422 -341.493094)
		(width 0.14224)
		(layer "In11.Cu")
		(net "P5E_CPU0_P3_TX_DN<1>")
	)
	(segment
		(start 361.7468 -282.650692)
		(end 361.708954 -282.67279)
		(width 0.1143)
		(layer "In11.Cu")
		(net "P5E_CPU0_P3_TX_DN<1>")
	)
	(segment
		(start 361.69981 -284.933898)
		(end 361.745276 -284.960568)
		(width 0.1143)
		(layer "In11.Cu")
		(net "P5E_CPU0_P3_TX_DN<1>")
	)
	(segment
		(start 364.82147 -384.92303)
		(end 364.53064 -385.21386)
		(width 0.14224)
		(layer "In11.Cu")
		(net "P5E_CPU0_P3_TX_DN<1>")
	)
	(segment
		(start 362.686854 -277.790656)
		(end 362.615988 -277.832058)
		(width 0.1143)
		(layer "In11.Cu")
		(net "P5E_CPU0_P3_TX_DN<1>")
	)
	(segment
		(start 361.708954 -281.052778)
		(end 361.705398 -281.055064)
		(width 0.1143)
		(layer "In11.Cu")
		(net "P5E_CPU0_P3_TX_DN<1>")
	)
	(segment
		(start 362.147104 -295.450768)
		(end 362.177584 -295.468548)
		(width 0.1143)
		(layer "In11.Cu")
		(net "P5E_CPU0_P3_TX_DN<1>")
	)
	(segment
		(start 361.705398 -283.317188)
		(end 361.708954 -283.319474)
		(width 0.1143)
		(layer "In11.Cu")
		(net "P5E_CPU0_P3_TX_DN<1>")
	)
	(segment
		(start 361.707684 -289.153346)
		(end 361.677204 -289.171126)
		(width 0.1143)
		(layer "In11.Cu")
		(net "P5E_CPU0_P3_TX_DN<1>")
	)
	(segment
		(start 362.002832 -291.909246)
		(end 362.002832 -291.91077)
		(width 0.1143)
		(layer "In11.Cu")
		(net "P5E_CPU0_P3_TX_DN<1>")
	)
	(segment
		(start 362.189014 -278.617426)
		(end 362.146088 -278.64181)
		(width 0.1143)
		(layer "In11.Cu")
		(net "P5E_CPU0_P3_TX_DN<1>")
	)
	(segment
		(start 362.505752 -296.446956)
		(end 362.505752 -297.952922)
		(width 0.14224)
		(layer "In11.Cu")
		(net "P5E_CPU0_P3_TX_DN<1>")
	)
	(segment
		(start 361.704128 -283.31668)
		(end 361.705398 -283.317188)
		(width 0.1143)
		(layer "In11.Cu")
		(net "P5E_CPU0_P3_TX_DN<1>")
	)
	(segment
		(start 363.304836 -277.32609)
		(end 363.006894 -277.32609)
		(width 0.1143)
		(layer "In11.Cu")
		(net "P5E_CPU0_P3_TX_DN<1>")
	)
	(segment
		(start 361.740958 -292.373812)
		(end 361.702858 -292.39591)
		(width 0.1143)
		(layer "In11.Cu")
		(net "P5E_CPU0_P3_TX_DN<1>")
	)
	(segment
		(start 362.505752 -297.952922)
		(end 364.040928 -303.01311)
		(width 0.14224)
		(layer "In11.Cu")
		(net "P5E_CPU0_P3_TX_DN<1>")
	)
	(segment
		(start 361.705398 -281.055064)
		(end 361.704382 -281.055572)
		(width 0.1143)
		(layer "In11.Cu")
		(net "P5E_CPU0_P3_TX_DN<1>")
	)
	(segment
		(start 361.676188 -286.540194)
		(end 361.7468 -286.581342)
		(width 0.1143)
		(layer "In11.Cu")
		(net "P5E_CPU0_P3_TX_DN<1>")
	)
	(segment
		(start 366.235234 -383.332736)
		(end 366.235234 -384.446272)
		(width 0.14224)
		(layer "In11.Cu")
		(net "P5E_CPU0_P3_TX_DN<1>")
	)
	(segment
		(start 362.460032 -296.372788)
		(end 362.505752 -296.418508)
		(width 0.1143)
		(layer "In11.Cu")
		(net "P5E_CPU0_P3_TX_DN<1>")
	)
	(segment
		(start 382.598422 -341.493094)
		(end 382.598422 -347.02877)
		(width 0.14224)
		(layer "In11.Cu")
		(net "P5E_CPU0_P3_TX_DN<1>")
	)
	(segment
		(start 361.708954 -281.699462)
		(end 361.745276 -281.720544)
		(width 0.1143)
		(layer "In11.Cu")
		(net "P5E_CPU0_P3_TX_DN<1>")
	)
	(segment
		(start 363.006894 -277.32609)
		(end 362.92409 -277.408894)
		(width 0.1143)
		(layer "In11.Cu")
		(net "P5E_CPU0_P3_TX_DN<1>")
	)
	(segment
		(start 361.7468 -290.750498)
		(end 361.677204 -290.791138)
		(width 0.1143)
		(layer "In11.Cu")
		(net "P5E_CPU0_P3_TX_DN<1>")
	)
	(segment
		(start 361.707684 -294.013382)
		(end 361.677204 -294.031162)
		(width 0.1143)
		(layer "In11.Cu")
		(net "P5E_CPU0_P3_TX_DN<1>")
	)
	(segment
		(start 365.06023 -381.806704)
		(end 365.986822 -382.733296)
		(width 0.14224)
		(layer "In11.Cu")
		(net "P5E_CPU0_P3_TX_DN<1>")
	)
	(segment
		(start 361.726734 -289.141662)
		(end 361.712256 -289.15106)
		(width 0.1143)
		(layer "In11.Cu")
		(net "P5E_CPU0_P3_TX_DN<1>")
	)
	(segment
		(start 361.710732 -293.040308)
		(end 361.711494 -293.040816)
		(width 0.1143)
		(layer "In11.Cu")
		(net "P5E_CPU0_P3_TX_DN<1>")
	)
	(segment
		(start 362.192824 -278.61514)
		(end 362.189014 -278.617426)
		(width 0.1143)
		(layer "In11.Cu")
		(net "P5E_CPU0_P3_TX_DN<1>")
	)
	(arc
		(start 366.235234 -384.446272)
		(mid 366.204071 -384.60285)
		(end 366.115346 -384.735578)
		(width 0.14224)
		(layer "In11.Cu")
		(net "P5E_CPU0_P3_TX_DN<1>")
	)
	(arc
		(start 362.615988 -277.832058)
		(mid 362.50136 -277.963711)
		(end 362.460032 -278.133302)
		(width 0.1143)
		(layer "In11.Cu")
		(net "P5E_CPU0_P3_TX_DN<1>")
	)
	(arc
		(start 361.520232 -279.764236)
		(mid 361.563156 -279.930363)
		(end 361.67568 -280.059892)
		(width 0.1143)
		(layer "In11.Cu")
		(net "P5E_CPU0_P3_TX_DN<1>")
	)
	(arc
		(start 361.677204 -294.031162)
		(mid 361.520227 -294.335962)
		(end 361.677204 -294.640762)
		(width 0.1143)
		(layer "In11.Cu")
		(net "P5E_CPU0_P3_TX_DN<1>")
	)
	(arc
		(start 361.7468 -284.961584)
		(mid 361.990127 -285.42615)
		(end 361.7468 -285.890716)
		(width 0.1143)
		(layer "In11.Cu")
		(net "P5E_CPU0_P3_TX_DN<1>")
	)
	(arc
		(start 361.707938 -284.293564)
		(mid 361.52296 -284.611418)
		(end 361.69981 -284.933898)
		(width 0.1143)
		(layer "In11.Cu")
		(net "P5E_CPU0_P3_TX_DN<1>")
	)
	(arc
		(start 366.047782 -384.803142)
		(mid 365.915062 -384.891886)
		(end 365.758476 -384.92303)
		(width 0.14224)
		(layer "In11.Cu")
		(net "P5E_CPU0_P3_TX_DN<1>")
	)
	(arc
		(start 362.2167 -295.491408)
		(mid 362.395575 -295.693726)
		(end 362.460032 -295.955974)
		(width 0.1143)
		(layer "In11.Cu")
		(net "P5E_CPU0_P3_TX_DN<1>")
	)
	(arc
		(start 362.460032 -278.136096)
		(mid 362.39531 -278.398835)
		(end 362.215938 -278.601424)
		(width 0.1143)
		(layer "In11.Cu")
		(net "P5E_CPU0_P3_TX_DN<1>")
	)
	(arc
		(start 379.774704 -356.854252)
		(mid 378.203799 -360.53392)
		(end 376.20448 -363.999526)
		(width 0.14224)
		(layer "In11.Cu")
		(net "P5E_CPU0_P3_TX_DN<1>")
	)
	(arc
		(start 361.520232 -286.23895)
		(mid 361.561595 -286.408523)
		(end 361.676188 -286.540194)
		(width 0.1143)
		(layer "In11.Cu")
		(net "P5E_CPU0_P3_TX_DN<1>")
	)
	(arc
		(start 361.7468 -281.72156)
		(mid 361.990127 -282.186126)
		(end 361.7468 -282.650692)
		(width 0.1143)
		(layer "In11.Cu")
		(net "P5E_CPU0_P3_TX_DN<1>")
	)
	(arc
		(start 362.92409 -277.408894)
		(mid 362.922302 -277.420343)
		(end 362.92028 -277.431754)
		(width 0.1143)
		(layer "In11.Cu")
		(net "P5E_CPU0_P3_TX_DN<1>")
	)
	(arc
		(start 361.745276 -284.960568)
		(mid 361.746038 -284.961075)
		(end 361.7468 -284.961584)
		(width 0.1143)
		(layer "In11.Cu")
		(net "P5E_CPU0_P3_TX_DN<1>")
	)
	(arc
		(start 361.7468 -289.821366)
		(mid 361.990127 -290.285932)
		(end 361.7468 -290.750498)
		(width 0.1143)
		(layer "In11.Cu")
		(net "P5E_CPU0_P3_TX_DN<1>")
	)
	(arc
		(start 361.677204 -289.171126)
		(mid 361.520227 -289.475926)
		(end 361.677204 -289.780726)
		(width 0.1143)
		(layer "In11.Cu")
		(net "P5E_CPU0_P3_TX_DN<1>")
	)
	(arc
		(start 365.807498 -375.489724)
		(mid 365.092005 -376.650691)
		(end 364.842298 -377.99137)
		(width 0.14224)
		(layer "In11.Cu")
		(net "P5E_CPU0_P3_TX_DN<1>")
	)
	(arc
		(start 361.682538 -279.448514)
		(mid 361.567951 -279.589188)
		(end 361.520232 -279.764236)
		(width 0.1143)
		(layer "In11.Cu")
		(net "P5E_CPU0_P3_TX_DN<1>")
	)
	(arc
		(start 362.146088 -278.64181)
		(mid 362.031412 -278.775144)
		(end 361.990132 -278.946102)
		(width 0.1143)
		(layer "In11.Cu")
		(net "P5E_CPU0_P3_TX_DN<1>")
	)
	(arc
		(start 382.598422 -347.02877)
		(mid 382.434367 -348.934269)
		(end 381.946912 -350.783652)
		(width 0.14224)
		(layer "In11.Cu")
		(net "P5E_CPU0_P3_TX_DN<1>")
	)
	(arc
		(start 361.7468 -294.681402)
		(mid 361.925613 -294.883752)
		(end 361.990132 -295.145968)
		(width 0.1143)
		(layer "In11.Cu")
		(net "P5E_CPU0_P3_TX_DN<1>")
	)
	(arc
		(start 361.7468 -293.06139)
		(mid 361.990127 -293.525956)
		(end 361.7468 -293.990522)
		(width 0.1143)
		(layer "In11.Cu")
		(net "P5E_CPU0_P3_TX_DN<1>")
	)
	(arc
		(start 361.676188 -285.932118)
		(mid 361.564608 -286.059219)
		(end 361.520232 -286.22244)
		(width 0.1143)
		(layer "In11.Cu")
		(net "P5E_CPU0_P3_TX_DN<1>")
	)
	(arc
		(start 361.677204 -290.791138)
		(mid 361.520676 -291.079929)
		(end 361.652058 -291.380926)
		(width 0.1143)
		(layer "In11.Cu")
		(net "P5E_CPU0_P3_TX_DN<1>")
	)
	(arc
		(start 361.704382 -282.675584)
		(mid 361.5205 -282.996022)
		(end 361.704128 -283.31668)
		(width 0.1143)
		(layer "In11.Cu")
		(net "P5E_CPU0_P3_TX_DN<1>")
	)
	(arc
		(start 361.520232 -287.856168)
		(mid 361.561983 -288.027788)
		(end 361.677712 -288.161222)
		(width 0.1143)
		(layer "In11.Cu")
		(net "P5E_CPU0_P3_TX_DN<1>")
	)
	(arc
		(start 361.990132 -278.946102)
		(mid 361.925617 -279.208321)
		(end 361.7468 -279.410668)
		(width 0.1143)
		(layer "In11.Cu")
		(net "P5E_CPU0_P3_TX_DN<1>")
	)
	(arc
		(start 361.990132 -295.145968)
		(mid 362.031681 -295.31739)
		(end 362.147104 -295.450768)
		(width 0.1143)
		(layer "In11.Cu")
		(net "P5E_CPU0_P3_TX_DN<1>")
	)
	(arc
		(start 362.92028 -277.431754)
		(mid 362.838847 -277.634152)
		(end 362.686854 -277.790656)
		(width 0.1143)
		(layer "In11.Cu")
		(net "P5E_CPU0_P3_TX_DN<1>")
	)
	(arc
		(start 361.71378 -288.18205)
		(mid 361.990921 -288.65799)
		(end 361.727242 -289.141408)
		(width 0.1143)
		(layer "In11.Cu")
		(net "P5E_CPU0_P3_TX_DN<1>")
	)
	(arc
		(start 361.7468 -280.101548)
		(mid 361.990127 -280.566114)
		(end 361.7468 -281.03068)
		(width 0.1143)
		(layer "In11.Cu")
		(net "P5E_CPU0_P3_TX_DN<1>")
	)
	(arc
		(start 361.746038 -293.060882)
		(mid 361.746419 -293.061136)
		(end 361.7468 -293.06139)
		(width 0.1143)
		(layer "In11.Cu")
		(net "P5E_CPU0_P3_TX_DN<1>")
	)
	(arc
		(start 361.728004 -291.430456)
		(mid 361.929239 -291.633217)
		(end 362.002832 -291.909246)
		(width 0.1143)
		(layer "In11.Cu")
		(net "P5E_CPU0_P3_TX_DN<1>")
	)
	(arc
		(start 361.7468 -283.341572)
		(mid 361.990127 -283.806138)
		(end 361.7468 -284.270704)
		(width 0.1143)
		(layer "In11.Cu")
		(net "P5E_CPU0_P3_TX_DN<1>")
	)
	(arc
		(start 361.680252 -287.549336)
		(mid 361.562629 -287.683138)
		(end 361.520232 -287.856168)
		(width 0.1143)
		(layer "In11.Cu")
		(net "P5E_CPU0_P3_TX_DN<1>")
	)
	(arc
		(start 361.990132 -287.045908)
		(mid 361.924896 -287.309499)
		(end 361.74426 -287.512252)
		(width 0.1143)
		(layer "In11.Cu")
		(net "P5E_CPU0_P3_TX_DN<1>")
	)
	(arc
		(start 365.986822 -382.733296)
		(mid 366.170671 -383.008306)
		(end 366.235234 -383.332736)
		(width 0.14224)
		(layer "In11.Cu")
		(net "P5E_CPU0_P3_TX_DN<1>")
	)
	(arc
		(start 361.745276 -283.340556)
		(mid 361.746038 -283.341063)
		(end 361.7468 -283.341572)
		(width 0.1143)
		(layer "In11.Cu")
		(net "P5E_CPU0_P3_TX_DN<1>")
	)
	(arc
		(start 364.842298 -381.28067)
		(mid 364.898944 -381.565359)
		(end 365.06023 -381.806704)
		(width 0.14224)
		(layer "In11.Cu")
		(net "P5E_CPU0_P3_TX_DN<1>")
	)
	(arc
		(start 361.745276 -281.720544)
		(mid 361.746038 -281.721051)
		(end 361.7468 -281.72156)
		(width 0.1143)
		(layer "In11.Cu")
		(net "P5E_CPU0_P3_TX_DN<1>")
	)
	(arc
		(start 361.704382 -281.055572)
		(mid 361.5205 -281.37601)
		(end 361.704128 -281.696668)
		(width 0.1143)
		(layer "In11.Cu")
		(net "P5E_CPU0_P3_TX_DN<1>")
	)
	(arc
		(start 362.002832 -291.91077)
		(mid 361.932824 -292.176746)
		(end 361.740958 -292.373812)
		(width 0.1143)
		(layer "In11.Cu")
		(net "P5E_CPU0_P3_TX_DN<1>")
	)
	(arc
		(start 361.700826 -292.39718)
		(mid 361.520341 -292.71595)
		(end 361.700826 -293.03472)
		(width 0.1143)
		(layer "In11.Cu")
		(net "P5E_CPU0_P3_TX_DN<1>")
	)
	(arc
		(start 361.7468 -286.581342)
		(mid 361.925613 -286.783692)
		(end 361.990132 -287.045908)
		(width 0.1143)
		(layer "In11.Cu")
		(net "P5E_CPU0_P3_TX_DN<1>")
	)
	(arc
		(start 376.20448 -363.999526)
		(mid 376.154858 -364.068587)
		(end 376.100086 -364.133638)
		(width 0.14224)
		(layer "In11.Cu")
		(net "P5E_CPU0_P3_TX_DN<1>")
	)
	(segment
		(start 373.64797 -276.250146)
		(end 374.114822 -276.516084)
		(width 0.12954)
		(layer "F.Cu")
		(net "P5E_CPU0_P3_TX_DN<15>")
	)
	(segment
		(start 394.107162 -388.471918)
		(end 393.403582 -388.471918)
		(width 0.12954)
		(layer "F.Cu")
		(net "P5E_CPU0_P3_TX_DN<15>")
	)
	(segment
		(start 394.377672 -388.742428)
		(end 394.107162 -388.471918)
		(width 0.12954)
		(layer "F.Cu")
		(net "P5E_CPU0_P3_TX_DN<15>")
	)
	(segment
		(start 393.403582 -388.471918)
		(end 393.107672 -388.767828)
		(width 0.12954)
		(layer "F.Cu")
		(net "P5E_CPU0_P3_TX_DN<15>")
	)
	(segment
		(start 374.867678 -278.458676)
		(end 374.837198 -278.440896)
		(width 0.1143)
		(layer "In11.Cu")
		(net "P5E_CPU0_P3_TX_DN<15>")
	)
	(segment
		(start 396.014702 -339.96503)
		(end 392.424666 -321.91452)
		(width 0.14224)
		(layer "In11.Cu")
		(net "P5E_CPU0_P3_TX_DN<15>")
	)
	(segment
		(start 374.436894 -277.67153)
		(end 374.366028 -277.630382)
		(width 0.1143)
		(layer "In11.Cu")
		(net "P5E_CPU0_P3_TX_DN<15>")
	)
	(segment
		(start 374.837198 -285.931356)
		(end 374.867678 -285.913576)
		(width 0.1143)
		(layer "In11.Cu")
		(net "P5E_CPU0_P3_TX_DN<15>")
	)
	(segment
		(start 374.867678 -288.178494)
		(end 374.835166 -288.159698)
		(width 0.1143)
		(layer "In11.Cu")
		(net "P5E_CPU0_P3_TX_DN<15>")
	)
	(segment
		(start 373.927878 -276.838664)
		(end 373.927116 -276.838156)
		(width 0.1143)
		(layer "In11.Cu")
		(net "P5E_CPU0_P3_TX_DN<15>")
	)
	(segment
		(start 374.867678 -291.418518)
		(end 374.837198 -291.400738)
		(width 0.1143)
		(layer "In11.Cu")
		(net "P5E_CPU0_P3_TX_DN<15>")
	)
	(segment
		(start 394.668502 -388.451598)
		(end 395.416024 -388.451598)
		(width 0.14224)
		(layer "In11.Cu")
		(net "P5E_CPU0_P3_TX_DN<15>")
	)
	(segment
		(start 375.376948 -295.491408)
		(end 375.341388 -295.47058)
		(width 0.1143)
		(layer "In11.Cu")
		(net "P5E_CPU0_P3_TX_DN<15>")
	)
	(segment
		(start 375.991628 -297.00728)
		(end 375.949972 -296.871136)
		(width 0.14224)
		(layer "In11.Cu")
		(net "P5E_CPU0_P3_TX_DN<15>")
	)
	(segment
		(start 374.867678 -292.39337)
		(end 374.906794 -292.37051)
		(width 0.1143)
		(layer "In11.Cu")
		(net "P5E_CPU0_P3_TX_DN<15>")
	)
	(segment
		(start 374.867678 -283.318712)
		(end 374.837198 -283.300932)
		(width 0.1143)
		(layer "In11.Cu")
		(net "P5E_CPU0_P3_TX_DN<15>")
	)
	(segment
		(start 374.867678 -289.798506)
		(end 374.837198 -289.780726)
		(width 0.1143)
		(layer "In11.Cu")
		(net "P5E_CPU0_P3_TX_DN<15>")
	)
	(segment
		(start 373.9642 -276.859746)
		(end 373.93118 -276.840696)
		(width 0.1143)
		(layer "In11.Cu")
		(net "P5E_CPU0_P3_TX_DN<15>")
	)
	(segment
		(start 374.867678 -282.673552)
		(end 374.906794 -282.650692)
		(width 0.1143)
		(layer "In11.Cu")
		(net "P5E_CPU0_P3_TX_DN<15>")
	)
	(segment
		(start 374.210072 -277.329138)
		(end 374.210072 -277.32609)
		(width 0.1143)
		(layer "In11.Cu")
		(net "P5E_CPU0_P3_TX_DN<15>")
	)
	(segment
		(start 392.424666 -321.91452)
		(end 389.910574 -315.845952)
		(width 0.14224)
		(layer "In11.Cu")
		(net "P5E_CPU0_P3_TX_DN<15>")
	)
	(segment
		(start 374.837198 -281.07132)
		(end 374.867678 -281.05354)
		(width 0.1143)
		(layer "In11.Cu")
		(net "P5E_CPU0_P3_TX_DN<15>")
	)
	(segment
		(start 373.927116 -276.838156)
		(end 373.896128 -276.820376)
		(width 0.1143)
		(layer "In11.Cu")
		(net "P5E_CPU0_P3_TX_DN<15>")
	)
	(segment
		(start 374.867678 -281.6987)
		(end 374.837198 -281.68092)
		(width 0.1143)
		(layer "In11.Cu")
		(net "P5E_CPU0_P3_TX_DN<15>")
	)
	(segment
		(start 374.837198 -284.311344)
		(end 374.867678 -284.293564)
		(width 0.1143)
		(layer "In11.Cu")
		(net "P5E_CPU0_P3_TX_DN<15>")
	)
	(segment
		(start 374.867678 -289.153346)
		(end 374.906794 -289.130486)
		(width 0.1143)
		(layer "In11.Cu")
		(net "P5E_CPU0_P3_TX_DN<15>")
	)
	(segment
		(start 375.337832 -279.268682)
		(end 375.33707 -279.268174)
		(width 0.1143)
		(layer "In11.Cu")
		(net "P5E_CPU0_P3_TX_DN<15>")
	)
	(segment
		(start 394.377672 -388.742428)
		(end 394.668502 -388.451598)
		(width 0.14224)
		(layer "In11.Cu")
		(net "P5E_CPU0_P3_TX_DN<15>")
	)
	(segment
		(start 374.837198 -290.791138)
		(end 374.867678 -290.773358)
		(width 0.1143)
		(layer "In11.Cu")
		(net "P5E_CPU0_P3_TX_DN<15>")
	)
	(segment
		(start 374.906794 -283.341572)
		(end 374.867678 -283.318712)
		(width 0.1143)
		(layer "In11.Cu")
		(net "P5E_CPU0_P3_TX_DN<15>")
	)
	(segment
		(start 374.906794 -281.72156)
		(end 374.867678 -281.6987)
		(width 0.1143)
		(layer "In11.Cu")
		(net "P5E_CPU0_P3_TX_DN<15>")
	)
	(segment
		(start 374.906794 -293.06139)
		(end 374.867678 -293.03853)
		(width 0.1143)
		(layer "In11.Cu")
		(net "P5E_CPU0_P3_TX_DN<15>")
	)
	(segment
		(start 374.867678 -281.05354)
		(end 374.906794 -281.03068)
		(width 0.1143)
		(layer "In11.Cu")
		(net "P5E_CPU0_P3_TX_DN<15>")
	)
	(segment
		(start 397.280638 -379.527054)
		(end 397.280638 -372.604284)
		(width 0.14224)
		(layer "In11.Cu")
		(net "P5E_CPU0_P3_TX_DN<15>")
	)
	(segment
		(start 375.341388 -295.47058)
		(end 375.340372 -295.470072)
		(width 0.1143)
		(layer "In11.Cu")
		(net "P5E_CPU0_P3_TX_DN<15>")
	)
	(segment
		(start 396.818104 -363.19206)
		(end 396.014702 -355.033326)
		(width 0.14224)
		(layer "In11.Cu")
		(net "P5E_CPU0_P3_TX_DN<15>")
	)
	(segment
		(start 375.340372 -295.470072)
		(end 375.338848 -295.469056)
		(width 0.1143)
		(layer "In11.Cu")
		(net "P5E_CPU0_P3_TX_DN<15>")
	)
	(segment
		(start 389.910574 -315.845952)
		(end 383.157222 -305.738784)
		(width 0.14224)
		(layer "In11.Cu")
		(net "P5E_CPU0_P3_TX_DN<15>")
	)
	(segment
		(start 375.47042 -295.587674)
		(end 375.376948 -295.491408)
		(width 0.1143)
		(layer "In11.Cu")
		(net "P5E_CPU0_P3_TX_DN<15>")
	)
	(segment
		(start 374.867678 -285.913576)
		(end 374.906794 -285.890716)
		(width 0.1143)
		(layer "In11.Cu")
		(net "P5E_CPU0_P3_TX_DN<15>")
	)
	(segment
		(start 374.837198 -294.031162)
		(end 374.867678 -294.013382)
		(width 0.1143)
		(layer "In11.Cu")
		(net "P5E_CPU0_P3_TX_DN<15>")
	)
	(segment
		(start 374.906794 -284.961584)
		(end 374.867678 -284.938724)
		(width 0.1143)
		(layer "In11.Cu")
		(net "P5E_CPU0_P3_TX_DN<15>")
	)
	(segment
		(start 375.341388 -279.270714)
		(end 375.340372 -279.270206)
		(width 0.1143)
		(layer "In11.Cu")
		(net "P5E_CPU0_P3_TX_DN<15>")
	)
	(segment
		(start 375.338848 -279.26919)
		(end 375.337832 -279.268682)
		(width 0.1143)
		(layer "In11.Cu")
		(net "P5E_CPU0_P3_TX_DN<15>")
	)
	(segment
		(start 374.837198 -287.551368)
		(end 374.904254 -287.512252)
		(width 0.1143)
		(layer "In11.Cu")
		(net "P5E_CPU0_P3_TX_DN<15>")
	)
	(segment
		(start 374.867678 -294.658542)
		(end 374.837198 -294.640762)
		(width 0.1143)
		(layer "In11.Cu")
		(net "P5E_CPU0_P3_TX_DN<15>")
	)
	(segment
		(start 375.337832 -280.243534)
		(end 375.338848 -280.243026)
		(width 0.1143)
		(layer "In11.Cu")
		(net "P5E_CPU0_P3_TX_DN<15>")
	)
	(segment
		(start 383.157222 -305.738784)
		(end 375.991628 -297.00728)
		(width 0.14224)
		(layer "In11.Cu")
		(net "P5E_CPU0_P3_TX_DN<15>")
	)
	(segment
		(start 374.867678 -294.013382)
		(end 374.906794 -293.990522)
		(width 0.1143)
		(layer "In11.Cu")
		(net "P5E_CPU0_P3_TX_DN<15>")
	)
	(segment
		(start 395.70533 -388.33171)
		(end 395.757654 -388.279386)
		(width 0.14224)
		(layer "In11.Cu")
		(net "P5E_CPU0_P3_TX_DN<15>")
	)
	(segment
		(start 374.867678 -290.773358)
		(end 374.906794 -290.750498)
		(width 0.1143)
		(layer "In11.Cu")
		(net "P5E_CPU0_P3_TX_DN<15>")
	)
	(segment
		(start 373.74703 -276.585934)
		(end 373.81688 -276.516084)
		(width 0.1143)
		(layer "In11.Cu")
		(net "P5E_CPU0_P3_TX_DN<15>")
	)
	(segment
		(start 375.340372 -279.270206)
		(end 375.338848 -279.26919)
		(width 0.1143)
		(layer "In11.Cu")
		(net "P5E_CPU0_P3_TX_DN<15>")
	)
	(segment
		(start 374.366028 -277.630382)
		(end 374.363234 -277.62835)
		(width 0.1143)
		(layer "In11.Cu")
		(net "P5E_CPU0_P3_TX_DN<15>")
	)
	(segment
		(start 375.33707 -279.268174)
		(end 375.306082 -279.250394)
		(width 0.1143)
		(layer "In11.Cu")
		(net "P5E_CPU0_P3_TX_DN<15>")
	)
	(segment
		(start 375.3358 -280.244804)
		(end 375.33707 -280.244042)
		(width 0.1143)
		(layer "In11.Cu")
		(net "P5E_CPU0_P3_TX_DN<15>")
	)
	(segment
		(start 375.376948 -279.291542)
		(end 375.341388 -279.270714)
		(width 0.1143)
		(layer "In11.Cu")
		(net "P5E_CPU0_P3_TX_DN<15>")
	)
	(segment
		(start 375.338848 -280.243026)
		(end 375.376948 -280.220674)
		(width 0.1143)
		(layer "In11.Cu")
		(net "P5E_CPU0_P3_TX_DN<15>")
	)
	(segment
		(start 375.949972 -296.871136)
		(end 375.949972 -296.837862)
		(width 0.14224)
		(layer "In11.Cu")
		(net "P5E_CPU0_P3_TX_DN<15>")
	)
	(segment
		(start 374.906794 -289.821366)
		(end 374.867678 -289.798506)
		(width 0.1143)
		(layer "In11.Cu")
		(net "P5E_CPU0_P3_TX_DN<15>")
	)
	(segment
		(start 375.306082 -280.261822)
		(end 375.3358 -280.244804)
		(width 0.1143)
		(layer "In11.Cu")
		(net "P5E_CPU0_P3_TX_DN<15>")
	)
	(segment
		(start 374.906794 -291.441378)
		(end 374.867678 -291.418518)
		(width 0.1143)
		(layer "In11.Cu")
		(net "P5E_CPU0_P3_TX_DN<15>")
	)
	(segment
		(start 375.949972 -296.837862)
		(end 375.949972 -296.809414)
		(width 0.1143)
		(layer "In11.Cu")
		(net "P5E_CPU0_P3_TX_DN<15>")
	)
	(segment
		(start 375.904252 -296.763694)
		(end 375.904252 -296.635424)
		(width 0.1143)
		(layer "In11.Cu")
		(net "P5E_CPU0_P3_TX_DN<15>")
	)
	(segment
		(start 374.867678 -293.03853)
		(end 374.837198 -293.02075)
		(width 0.1143)
		(layer "In11.Cu")
		(net "P5E_CPU0_P3_TX_DN<15>")
	)
	(segment
		(start 397.280638 -372.604284)
		(end 396.818104 -363.19206)
		(width 0.14224)
		(layer "In11.Cu")
		(net "P5E_CPU0_P3_TX_DN<15>")
	)
	(segment
		(start 374.867678 -286.558482)
		(end 374.835166 -286.539686)
		(width 0.1143)
		(layer "In11.Cu")
		(net "P5E_CPU0_P3_TX_DN<15>")
	)
	(segment
		(start 395.877542 -387.99008)
		(end 395.877542 -383.96418)
		(width 0.14224)
		(layer "In11.Cu")
		(net "P5E_CPU0_P3_TX_DN<15>")
	)
	(segment
		(start 374.837198 -282.691332)
		(end 374.867678 -282.673552)
		(width 0.1143)
		(layer "In11.Cu")
		(net "P5E_CPU0_P3_TX_DN<15>")
	)
	(segment
		(start 373.81688 -276.516084)
		(end 374.114822 -276.516084)
		(width 0.1143)
		(layer "In11.Cu")
		(net "P5E_CPU0_P3_TX_DN<15>")
	)
	(segment
		(start 374.837198 -292.41115)
		(end 374.867678 -292.39337)
		(width 0.1143)
		(layer "In11.Cu")
		(net "P5E_CPU0_P3_TX_DN<15>")
	)
	(segment
		(start 374.867678 -284.293564)
		(end 374.906794 -284.270704)
		(width 0.1143)
		(layer "In11.Cu")
		(net "P5E_CPU0_P3_TX_DN<15>")
	)
	(segment
		(start 374.867678 -284.938724)
		(end 374.837198 -284.920944)
		(width 0.1143)
		(layer "In11.Cu")
		(net "P5E_CPU0_P3_TX_DN<15>")
	)
	(segment
		(start 375.337832 -295.468548)
		(end 375.306082 -295.45026)
		(width 0.1143)
		(layer "In11.Cu")
		(net "P5E_CPU0_P3_TX_DN<15>")
	)
	(segment
		(start 374.906794 -278.481536)
		(end 374.867678 -278.458676)
		(width 0.1143)
		(layer "In11.Cu")
		(net "P5E_CPU0_P3_TX_DN<15>")
	)
	(segment
		(start 396.115794 -382.766316)
		(end 397.117824 -380.345696)
		(width 0.14224)
		(layer "In11.Cu")
		(net "P5E_CPU0_P3_TX_DN<15>")
	)
	(segment
		(start 374.837198 -289.171126)
		(end 374.867678 -289.153346)
		(width 0.1143)
		(layer "In11.Cu")
		(net "P5E_CPU0_P3_TX_DN<15>")
	)
	(segment
		(start 375.33707 -280.244042)
		(end 375.337832 -280.243534)
		(width 0.1143)
		(layer "In11.Cu")
		(net "P5E_CPU0_P3_TX_DN<15>")
	)
	(segment
		(start 375.338848 -295.469056)
		(end 375.337832 -295.468548)
		(width 0.1143)
		(layer "In11.Cu")
		(net "P5E_CPU0_P3_TX_DN<15>")
	)
	(segment
		(start 374.906794 -286.581342)
		(end 374.867678 -286.558482)
		(width 0.1143)
		(layer "In11.Cu")
		(net "P5E_CPU0_P3_TX_DN<15>")
	)
	(segment
		(start 396.014702 -355.033326)
		(end 396.014702 -339.96503)
		(width 0.14224)
		(layer "In11.Cu")
		(net "P5E_CPU0_P3_TX_DN<15>")
	)
	(segment
		(start 374.906794 -288.201354)
		(end 374.867678 -288.178494)
		(width 0.1143)
		(layer "In11.Cu")
		(net "P5E_CPU0_P3_TX_DN<15>")
	)
	(segment
		(start 375.949972 -296.809414)
		(end 375.904252 -296.763694)
		(width 0.1143)
		(layer "In11.Cu")
		(net "P5E_CPU0_P3_TX_DN<15>")
	)
	(segment
		(start 374.906794 -294.681402)
		(end 374.867678 -294.658542)
		(width 0.1143)
		(layer "In11.Cu")
		(net "P5E_CPU0_P3_TX_DN<15>")
	)
	(segment
		(start 373.93118 -276.840696)
		(end 373.927878 -276.838664)
		(width 0.1143)
		(layer "In11.Cu")
		(net "P5E_CPU0_P3_TX_DN<15>")
	)
	(arc
		(start 395.416024 -388.451598)
		(mid 395.572602 -388.420435)
		(end 395.70533 -388.33171)
		(width 0.14224)
		(layer "In11.Cu")
		(net "P5E_CPU0_P3_TX_DN<15>")
	)
	(arc
		(start 374.906794 -284.270704)
		(mid 375.150121 -283.806138)
		(end 374.906794 -283.341572)
		(width 0.1143)
		(layer "In11.Cu")
		(net "P5E_CPU0_P3_TX_DN<15>")
	)
	(arc
		(start 374.835166 -288.159698)
		(mid 374.721237 -288.026551)
		(end 374.680226 -287.856168)
		(width 0.1143)
		(layer "In11.Cu")
		(net "P5E_CPU0_P3_TX_DN<15>")
	)
	(arc
		(start 374.835166 -286.539686)
		(mid 374.721237 -286.406539)
		(end 374.680226 -286.236156)
		(width 0.1143)
		(layer "In11.Cu")
		(net "P5E_CPU0_P3_TX_DN<15>")
	)
	(arc
		(start 374.906794 -290.750498)
		(mid 375.150121 -290.285932)
		(end 374.906794 -289.821366)
		(width 0.1143)
		(layer "In11.Cu")
		(net "P5E_CPU0_P3_TX_DN<15>")
	)
	(arc
		(start 374.904254 -287.512252)
		(mid 375.084906 -287.309507)
		(end 375.150126 -287.045908)
		(width 0.1143)
		(layer "In11.Cu")
		(net "P5E_CPU0_P3_TX_DN<15>")
	)
	(arc
		(start 373.896128 -276.820376)
		(mid 373.798993 -276.717507)
		(end 373.74703 -276.585934)
		(width 0.1143)
		(layer "In11.Cu")
		(net "P5E_CPU0_P3_TX_DN<15>")
	)
	(arc
		(start 374.680226 -278.136096)
		(mid 374.615711 -277.873877)
		(end 374.436894 -277.67153)
		(width 0.1143)
		(layer "In11.Cu")
		(net "P5E_CPU0_P3_TX_DN<15>")
	)
	(arc
		(start 374.906794 -282.650692)
		(mid 375.150121 -282.186126)
		(end 374.906794 -281.72156)
		(width 0.1143)
		(layer "In11.Cu")
		(net "P5E_CPU0_P3_TX_DN<15>")
	)
	(arc
		(start 374.837198 -284.920944)
		(mid 374.680221 -284.616144)
		(end 374.837198 -284.311344)
		(width 0.1143)
		(layer "In11.Cu")
		(net "P5E_CPU0_P3_TX_DN<15>")
	)
	(arc
		(start 375.150126 -287.045908)
		(mid 375.085611 -286.783689)
		(end 374.906794 -286.581342)
		(width 0.1143)
		(layer "In11.Cu")
		(net "P5E_CPU0_P3_TX_DN<15>")
	)
	(arc
		(start 395.757654 -388.279386)
		(mid 395.846398 -388.146666)
		(end 395.877542 -387.99008)
		(width 0.14224)
		(layer "In11.Cu")
		(net "P5E_CPU0_P3_TX_DN<15>")
	)
	(arc
		(start 374.837198 -278.440896)
		(mid 374.721771 -278.30752)
		(end 374.680226 -278.136096)
		(width 0.1143)
		(layer "In11.Cu")
		(net "P5E_CPU0_P3_TX_DN<15>")
	)
	(arc
		(start 375.306082 -279.250394)
		(mid 375.191406 -279.11706)
		(end 375.150126 -278.946102)
		(width 0.1143)
		(layer "In11.Cu")
		(net "P5E_CPU0_P3_TX_DN<15>")
	)
	(arc
		(start 374.906794 -289.130486)
		(mid 375.150121 -288.66592)
		(end 374.906794 -288.201354)
		(width 0.1143)
		(layer "In11.Cu")
		(net "P5E_CPU0_P3_TX_DN<15>")
	)
	(arc
		(start 374.837198 -291.400738)
		(mid 374.680221 -291.095938)
		(end 374.837198 -290.791138)
		(width 0.1143)
		(layer "In11.Cu")
		(net "P5E_CPU0_P3_TX_DN<15>")
	)
	(arc
		(start 374.680226 -286.236156)
		(mid 374.721775 -286.064734)
		(end 374.837198 -285.931356)
		(width 0.1143)
		(layer "In11.Cu")
		(net "P5E_CPU0_P3_TX_DN<15>")
	)
	(arc
		(start 374.680226 -287.856168)
		(mid 374.721775 -287.684746)
		(end 374.837198 -287.551368)
		(width 0.1143)
		(layer "In11.Cu")
		(net "P5E_CPU0_P3_TX_DN<15>")
	)
	(arc
		(start 375.306082 -295.45026)
		(mid 375.191406 -295.316926)
		(end 375.150126 -295.145968)
		(width 0.1143)
		(layer "In11.Cu")
		(net "P5E_CPU0_P3_TX_DN<15>")
	)
	(arc
		(start 375.150126 -278.946102)
		(mid 375.085611 -278.683883)
		(end 374.906794 -278.481536)
		(width 0.1143)
		(layer "In11.Cu")
		(net "P5E_CPU0_P3_TX_DN<15>")
	)
	(arc
		(start 395.877542 -383.96418)
		(mid 395.937675 -383.353513)
		(end 396.115794 -382.766316)
		(width 0.14224)
		(layer "In11.Cu")
		(net "P5E_CPU0_P3_TX_DN<15>")
	)
	(arc
		(start 397.117824 -380.345696)
		(mid 397.239548 -379.944391)
		(end 397.280638 -379.527054)
		(width 0.14224)
		(layer "In11.Cu")
		(net "P5E_CPU0_P3_TX_DN<15>")
	)
	(arc
		(start 374.210072 -277.32609)
		(mid 374.144836 -277.062499)
		(end 373.9642 -276.859746)
		(width 0.1143)
		(layer "In11.Cu")
		(net "P5E_CPU0_P3_TX_DN<15>")
	)
	(arc
		(start 374.837198 -294.640762)
		(mid 374.680221 -294.335962)
		(end 374.837198 -294.031162)
		(width 0.1143)
		(layer "In11.Cu")
		(net "P5E_CPU0_P3_TX_DN<15>")
	)
	(arc
		(start 374.837198 -281.68092)
		(mid 374.680221 -281.37612)
		(end 374.837198 -281.07132)
		(width 0.1143)
		(layer "In11.Cu")
		(net "P5E_CPU0_P3_TX_DN<15>")
	)
	(arc
		(start 375.376948 -280.220674)
		(mid 375.620275 -279.756108)
		(end 375.376948 -279.291542)
		(width 0.1143)
		(layer "In11.Cu")
		(net "P5E_CPU0_P3_TX_DN<15>")
	)
	(arc
		(start 374.906794 -292.37051)
		(mid 375.150121 -291.905944)
		(end 374.906794 -291.441378)
		(width 0.1143)
		(layer "In11.Cu")
		(net "P5E_CPU0_P3_TX_DN<15>")
	)
	(arc
		(start 374.906794 -285.890716)
		(mid 375.150121 -285.42615)
		(end 374.906794 -284.961584)
		(width 0.1143)
		(layer "In11.Cu")
		(net "P5E_CPU0_P3_TX_DN<15>")
	)
	(arc
		(start 374.906794 -293.990522)
		(mid 375.150121 -293.525956)
		(end 374.906794 -293.06139)
		(width 0.1143)
		(layer "In11.Cu")
		(net "P5E_CPU0_P3_TX_DN<15>")
	)
	(arc
		(start 374.837198 -293.02075)
		(mid 374.680221 -292.71595)
		(end 374.837198 -292.41115)
		(width 0.1143)
		(layer "In11.Cu")
		(net "P5E_CPU0_P3_TX_DN<15>")
	)
	(arc
		(start 374.837198 -289.780726)
		(mid 374.680221 -289.475926)
		(end 374.837198 -289.171126)
		(width 0.1143)
		(layer "In11.Cu")
		(net "P5E_CPU0_P3_TX_DN<15>")
	)
	(arc
		(start 374.363234 -277.62835)
		(mid 374.250593 -277.497214)
		(end 374.210072 -277.329138)
		(width 0.1143)
		(layer "In11.Cu")
		(net "P5E_CPU0_P3_TX_DN<15>")
	)
	(arc
		(start 375.904252 -296.635424)
		(mid 375.791541 -296.068408)
		(end 375.47042 -295.587674)
		(width 0.1143)
		(layer "In11.Cu")
		(net "P5E_CPU0_P3_TX_DN<15>")
	)
	(arc
		(start 375.150126 -295.145968)
		(mid 375.085611 -294.883749)
		(end 374.906794 -294.681402)
		(width 0.1143)
		(layer "In11.Cu")
		(net "P5E_CPU0_P3_TX_DN<15>")
	)
	(arc
		(start 374.906794 -281.03068)
		(mid 375.085607 -280.82833)
		(end 375.150126 -280.566114)
		(width 0.1143)
		(layer "In11.Cu")
		(net "P5E_CPU0_P3_TX_DN<15>")
	)
	(arc
		(start 375.150126 -280.566114)
		(mid 375.191381 -280.395143)
		(end 375.306082 -280.261822)
		(width 0.1143)
		(layer "In11.Cu")
		(net "P5E_CPU0_P3_TX_DN<15>")
	)
	(arc
		(start 374.837198 -283.300932)
		(mid 374.680221 -282.996132)
		(end 374.837198 -282.691332)
		(width 0.1143)
		(layer "In11.Cu")
		(net "P5E_CPU0_P3_TX_DN<15>")
	)
	(segment
		(start 373.64797 -277.870158)
		(end 374.114822 -278.136096)
		(width 0.12954)
		(layer "F.Cu")
		(net "P5E_CPU0_P3_TX_DN<14>")
	)
	(segment
		(start 393.403582 -384.745738)
		(end 393.107672 -384.449828)
		(width 0.12954)
		(layer "F.Cu")
		(net "P5E_CPU0_P3_TX_DN<14>")
	)
	(segment
		(start 394.377672 -384.475228)
		(end 394.107162 -384.745738)
		(width 0.12954)
		(layer "F.Cu")
		(net "P5E_CPU0_P3_TX_DN<14>")
	)
	(segment
		(start 394.107162 -384.745738)
		(end 393.403582 -384.745738)
		(width 0.12954)
		(layer "F.Cu")
		(net "P5E_CPU0_P3_TX_DN<14>")
	)
	(segment
		(start 373.96801 -287.51022)
		(end 373.896128 -287.551876)
		(width 0.1143)
		(layer "In11.Cu")
		(net "P5E_CPU0_P3_TX_DN<14>")
	)
	(segment
		(start 374.397778 -279.268682)
		(end 374.436894 -279.291542)
		(width 0.1143)
		(layer "In11.Cu")
		(net "P5E_CPU0_P3_TX_DN<14>")
	)
	(segment
		(start 373.927116 -283.318204)
		(end 373.927878 -283.318712)
		(width 0.1143)
		(layer "In11.Cu")
		(net "P5E_CPU0_P3_TX_DN<14>")
	)
	(segment
		(start 373.965978 -291.440362)
		(end 373.978932 -291.44976)
		(width 0.1143)
		(layer "In11.Cu")
		(net "P5E_CPU0_P3_TX_DN<14>")
	)
	(segment
		(start 373.896128 -284.920436)
		(end 373.927878 -284.938724)
		(width 0.1143)
		(layer "In11.Cu")
		(net "P5E_CPU0_P3_TX_DN<14>")
	)
	(segment
		(start 395.95552 -374.48617)
		(end 395.95552 -374.91289)
		(width 0.14224)
		(layer "In11.Cu")
		(net "P5E_CPU0_P3_TX_DN<14>")
	)
	(segment
		(start 374.399302 -295.469564)
		(end 374.43664 -295.4909)
		(width 0.1143)
		(layer "In11.Cu")
		(net "P5E_CPU0_P3_TX_DN<14>")
	)
	(segment
		(start 395.95552 -379.065536)
		(end 395.81836 -379.202696)
		(width 0.14224)
		(layer "In11.Cu")
		(net "P5E_CPU0_P3_TX_DN<14>")
	)
	(segment
		(start 373.930926 -282.671774)
		(end 373.896128 -282.69184)
		(width 0.1143)
		(layer "In11.Cu")
		(net "P5E_CPU0_P3_TX_DN<14>")
	)
	(segment
		(start 391.492994 -322.122292)
		(end 395.053058 -340.020656)
		(width 0.14224)
		(layer "In11.Cu")
		(net "P5E_CPU0_P3_TX_DN<14>")
	)
	(segment
		(start 374.198134 -280.574496)
		(end 374.198134 -280.585926)
		(width 0.1143)
		(layer "In11.Cu")
		(net "P5E_CPU0_P3_TX_DN<14>")
	)
	(segment
		(start 394.086842 -384.766058)
		(end 394.377672 -384.475228)
		(width 0.14224)
		(layer "In11.Cu")
		(net "P5E_CPU0_P3_TX_DN<14>")
	)
	(segment
		(start 374.384824 -280.2509)
		(end 374.38457 -280.251154)
		(width 0.1143)
		(layer "In11.Cu")
		(net "P5E_CPU0_P3_TX_DN<14>")
	)
	(segment
		(start 374.735852 -296.26179)
		(end 374.959372 -296.48531)
		(width 0.1143)
		(layer "In11.Cu")
		(net "P5E_CPU0_P3_TX_DN<14>")
	)
	(segment
		(start 374.959372 -296.48531)
		(end 374.959372 -296.792142)
		(width 0.1143)
		(layer "In11.Cu")
		(net "P5E_CPU0_P3_TX_DN<14>")
	)
	(segment
		(start 373.932196 -294.661082)
		(end 373.96801 -294.682164)
		(width 0.1143)
		(layer "In11.Cu")
		(net "P5E_CPU0_P3_TX_DN<14>")
	)
	(segment
		(start 375.005092 -296.837862)
		(end 375.005092 -296.86631)
		(width 0.1143)
		(layer "In11.Cu")
		(net "P5E_CPU0_P3_TX_DN<14>")
	)
	(segment
		(start 373.896128 -283.300424)
		(end 373.927116 -283.318204)
		(width 0.1143)
		(layer "In11.Cu")
		(net "P5E_CPU0_P3_TX_DN<14>")
	)
	(segment
		(start 373.937784 -281.047444)
		(end 373.927878 -281.05354)
		(width 0.1143)
		(layer "In11.Cu")
		(net "P5E_CPU0_P3_TX_DN<14>")
	)
	(segment
		(start 395.81836 -375.804684)
		(end 395.95552 -375.941844)
		(width 0.14224)
		(layer "In11.Cu")
		(net "P5E_CPU0_P3_TX_DN<14>")
	)
	(segment
		(start 373.927878 -283.318712)
		(end 373.930926 -283.32049)
		(width 0.1143)
		(layer "In11.Cu")
		(net "P5E_CPU0_P3_TX_DN<14>")
	)
	(segment
		(start 373.930926 -290.77158)
		(end 373.896128 -290.791646)
		(width 0.1143)
		(layer "In11.Cu")
		(net "P5E_CPU0_P3_TX_DN<14>")
	)
	(segment
		(start 373.930926 -285.911798)
		(end 373.896128 -285.931864)
		(width 0.1143)
		(layer "In11.Cu")
		(net "P5E_CPU0_P3_TX_DN<14>")
	)
	(segment
		(start 373.927878 -291.418518)
		(end 373.927878 -291.418772)
		(width 0.1143)
		(layer "In11.Cu")
		(net "P5E_CPU0_P3_TX_DN<14>")
	)
	(segment
		(start 395.053058 -340.020656)
		(end 395.053058 -355.6254)
		(width 0.14224)
		(layer "In11.Cu")
		(net "P5E_CPU0_P3_TX_DN<14>")
	)
	(segment
		(start 375.005092 -296.978832)
		(end 375.139966 -297.422824)
		(width 0.14224)
		(layer "In11.Cu")
		(net "P5E_CPU0_P3_TX_DN<14>")
	)
	(segment
		(start 375.005092 -296.86631)
		(end 375.005092 -296.978832)
		(width 0.14224)
		(layer "In11.Cu")
		(net "P5E_CPU0_P3_TX_DN<14>")
	)
	(segment
		(start 373.896128 -294.640254)
		(end 373.927878 -294.658542)
		(width 0.1143)
		(layer "In11.Cu")
		(net "P5E_CPU0_P3_TX_DN<14>")
	)
	(segment
		(start 373.896128 -278.440388)
		(end 373.927116 -278.458168)
		(width 0.1143)
		(layer "In11.Cu")
		(net "P5E_CPU0_P3_TX_DN<14>")
	)
	(segment
		(start 374.436894 -280.220674)
		(end 374.384824 -280.2509)
		(width 0.1143)
		(layer "In11.Cu")
		(net "P5E_CPU0_P3_TX_DN<14>")
	)
	(segment
		(start 373.978932 -292.362128)
		(end 373.965978 -292.371526)
		(width 0.1143)
		(layer "In11.Cu")
		(net "P5E_CPU0_P3_TX_DN<14>")
	)
	(segment
		(start 373.927116 -278.458168)
		(end 373.927878 -278.458676)
		(width 0.1143)
		(layer "In11.Cu")
		(net "P5E_CPU0_P3_TX_DN<14>")
	)
	(segment
		(start 373.89435 -286.538924)
		(end 373.969026 -286.582866)
		(width 0.1143)
		(layer "In11.Cu")
		(net "P5E_CPU0_P3_TX_DN<14>")
	)
	(segment
		(start 395.81836 -377.373896)
		(end 395.95552 -377.511056)
		(width 0.14224)
		(layer "In11.Cu")
		(net "P5E_CPU0_P3_TX_DN<14>")
	)
	(segment
		(start 374.680226 -295.95572)
		(end 374.680226 -296.127678)
		(width 0.1143)
		(layer "In11.Cu")
		(net "P5E_CPU0_P3_TX_DN<14>")
	)
	(segment
		(start 373.927878 -289.798506)
		(end 373.930926 -289.800284)
		(width 0.1143)
		(layer "In11.Cu")
		(net "P5E_CPU0_P3_TX_DN<14>")
	)
	(segment
		(start 395.81836 -378.501656)
		(end 395.95552 -378.638816)
		(width 0.14224)
		(layer "In11.Cu")
		(net "P5E_CPU0_P3_TX_DN<14>")
	)
	(segment
		(start 393.218162 -383.864358)
		(end 393.217908 -383.864104)
		(width 0.14224)
		(layer "In11.Cu")
		(net "P5E_CPU0_P3_TX_DN<14>")
	)
	(segment
		(start 374.210072 -287.045908)
		(end 374.210072 -287.05048)
		(width 0.1143)
		(layer "In11.Cu")
		(net "P5E_CPU0_P3_TX_DN<14>")
	)
	(segment
		(start 373.930926 -289.151568)
		(end 373.896128 -289.171634)
		(width 0.1143)
		(layer "In11.Cu")
		(net "P5E_CPU0_P3_TX_DN<14>")
	)
	(segment
		(start 395.81836 -375.05005)
		(end 395.81836 -375.804684)
		(width 0.14224)
		(layer "In11.Cu")
		(net "P5E_CPU0_P3_TX_DN<14>")
	)
	(segment
		(start 373.81688 -278.136096)
		(end 373.74703 -278.205946)
		(width 0.1143)
		(layer "In11.Cu")
		(net "P5E_CPU0_P3_TX_DN<14>")
	)
	(segment
		(start 373.896128 -291.40023)
		(end 373.927878 -291.418518)
		(width 0.1143)
		(layer "In11.Cu")
		(net "P5E_CPU0_P3_TX_DN<14>")
	)
	(segment
		(start 395.95552 -377.937776)
		(end 395.81836 -378.074936)
		(width 0.14224)
		(layer "In11.Cu")
		(net "P5E_CPU0_P3_TX_DN<14>")
	)
	(segment
		(start 395.053058 -355.6254)
		(end 395.81836 -371.201442)
		(width 0.14224)
		(layer "In11.Cu")
		(net "P5E_CPU0_P3_TX_DN<14>")
	)
	(segment
		(start 373.928894 -278.459184)
		(end 373.942864 -278.467312)
		(width 0.1143)
		(layer "In11.Cu")
		(net "P5E_CPU0_P3_TX_DN<14>")
	)
	(segment
		(start 395.95552 -376.368564)
		(end 395.81836 -376.505724)
		(width 0.14224)
		(layer "In11.Cu")
		(net "P5E_CPU0_P3_TX_DN<14>")
	)
	(segment
		(start 395.81836 -376.505724)
		(end 395.81836 -377.373896)
		(width 0.14224)
		(layer "In11.Cu")
		(net "P5E_CPU0_P3_TX_DN<14>")
	)
	(segment
		(start 373.927878 -293.03853)
		(end 373.930926 -293.040308)
		(width 0.1143)
		(layer "In11.Cu")
		(net "P5E_CPU0_P3_TX_DN<14>")
	)
	(segment
		(start 373.927878 -284.938724)
		(end 373.930926 -284.940502)
		(width 0.1143)
		(layer "In11.Cu")
		(net "P5E_CPU0_P3_TX_DN<14>")
	)
	(segment
		(start 373.927878 -281.6987)
		(end 373.930926 -281.700478)
		(width 0.1143)
		(layer "In11.Cu")
		(net "P5E_CPU0_P3_TX_DN<14>")
	)
	(segment
		(start 373.965978 -292.371526)
		(end 373.896128 -292.411658)
		(width 0.1143)
		(layer "In11.Cu")
		(net "P5E_CPU0_P3_TX_DN<14>")
	)
	(segment
		(start 373.930926 -294.011604)
		(end 373.896128 -294.03167)
		(width 0.1143)
		(layer "In11.Cu")
		(net "P5E_CPU0_P3_TX_DN<14>")
	)
	(segment
		(start 373.927878 -294.658542)
		(end 373.931434 -294.660574)
		(width 0.1143)
		(layer "In11.Cu")
		(net "P5E_CPU0_P3_TX_DN<14>")
	)
	(segment
		(start 374.222772 -278.953468)
		(end 374.222772 -278.965914)
		(width 0.1143)
		(layer "In11.Cu")
		(net "P5E_CPU0_P3_TX_DN<14>")
	)
	(segment
		(start 395.95552 -374.91289)
		(end 395.81836 -375.05005)
		(width 0.14224)
		(layer "In11.Cu")
		(net "P5E_CPU0_P3_TX_DN<14>")
	)
	(segment
		(start 373.896128 -289.780218)
		(end 373.927878 -289.798506)
		(width 0.1143)
		(layer "In11.Cu")
		(net "P5E_CPU0_P3_TX_DN<14>")
	)
	(segment
		(start 389.089138 -316.322964)
		(end 391.492994 -322.122292)
		(width 0.14224)
		(layer "In11.Cu")
		(net "P5E_CPU0_P3_TX_DN<14>")
	)
	(segment
		(start 373.895112 -288.159444)
		(end 373.927878 -288.178494)
		(width 0.1143)
		(layer "In11.Cu")
		(net "P5E_CPU0_P3_TX_DN<14>")
	)
	(segment
		(start 374.959372 -296.792142)
		(end 375.005092 -296.837862)
		(width 0.1143)
		(layer "In11.Cu")
		(net "P5E_CPU0_P3_TX_DN<14>")
	)
	(segment
		(start 373.896128 -293.020242)
		(end 373.927878 -293.03853)
		(width 0.1143)
		(layer "In11.Cu")
		(net "P5E_CPU0_P3_TX_DN<14>")
	)
	(segment
		(start 375.139966 -297.422824)
		(end 375.789952 -298.39539)
		(width 0.14224)
		(layer "In11.Cu")
		(net "P5E_CPU0_P3_TX_DN<14>")
	)
	(segment
		(start 395.95552 -377.511056)
		(end 395.95552 -377.937776)
		(width 0.14224)
		(layer "In11.Cu")
		(net "P5E_CPU0_P3_TX_DN<14>")
	)
	(segment
		(start 373.927878 -288.178494)
		(end 373.930926 -288.180272)
		(width 0.1143)
		(layer "In11.Cu")
		(net "P5E_CPU0_P3_TX_DN<14>")
	)
	(segment
		(start 373.97944 -287.501584)
		(end 373.96801 -287.51022)
		(width 0.1143)
		(layer "In11.Cu")
		(net "P5E_CPU0_P3_TX_DN<14>")
	)
	(segment
		(start 395.81836 -371.201442)
		(end 395.81836 -374.34901)
		(width 0.14224)
		(layer "In11.Cu")
		(net "P5E_CPU0_P3_TX_DN<14>")
	)
	(segment
		(start 382.896364 -307.055012)
		(end 389.089138 -316.322964)
		(width 0.14224)
		(layer "In11.Cu")
		(net "P5E_CPU0_P3_TX_DN<14>")
	)
	(segment
		(start 394.59535 -382.322578)
		(end 393.333986 -383.583942)
		(width 0.14224)
		(layer "In11.Cu")
		(net "P5E_CPU0_P3_TX_DN<14>")
	)
	(segment
		(start 395.81836 -374.34901)
		(end 395.95552 -374.48617)
		(width 0.14224)
		(layer "In11.Cu")
		(net "P5E_CPU0_P3_TX_DN<14>")
	)
	(segment
		(start 373.896128 -281.680412)
		(end 373.927878 -281.6987)
		(width 0.1143)
		(layer "In11.Cu")
		(net "P5E_CPU0_P3_TX_DN<14>")
	)
	(segment
		(start 393.265152 -384.58775)
		(end 393.39393 -384.716528)
		(width 0.14224)
		(layer "In11.Cu")
		(net "P5E_CPU0_P3_TX_DN<14>")
	)
	(segment
		(start 395.81836 -379.202696)
		(end 395.819122 -379.345952)
		(width 0.14224)
		(layer "In11.Cu")
		(net "P5E_CPU0_P3_TX_DN<14>")
	)
	(segment
		(start 395.95552 -375.941844)
		(end 395.95552 -376.368564)
		(width 0.14224)
		(layer "In11.Cu")
		(net "P5E_CPU0_P3_TX_DN<14>")
	)
	(segment
		(start 395.95552 -378.638816)
		(end 395.95552 -379.065536)
		(width 0.14224)
		(layer "In11.Cu")
		(net "P5E_CPU0_P3_TX_DN<14>")
	)
	(segment
		(start 373.927878 -281.05354)
		(end 373.896128 -281.071828)
		(width 0.1143)
		(layer "In11.Cu")
		(net "P5E_CPU0_P3_TX_DN<14>")
	)
	(segment
		(start 373.931434 -294.660574)
		(end 373.932196 -294.661082)
		(width 0.1143)
		(layer "In11.Cu")
		(net "P5E_CPU0_P3_TX_DN<14>")
	)
	(segment
		(start 373.927878 -278.458676)
		(end 373.928894 -278.459184)
		(width 0.1143)
		(layer "In11.Cu")
		(net "P5E_CPU0_P3_TX_DN<14>")
	)
	(segment
		(start 395.81836 -378.074936)
		(end 395.81836 -378.501656)
		(width 0.14224)
		(layer "In11.Cu")
		(net "P5E_CPU0_P3_TX_DN<14>")
	)
	(segment
		(start 393.217908 -383.864104)
		(end 393.217908 -384.473704)
		(width 0.14224)
		(layer "In11.Cu")
		(net "P5E_CPU0_P3_TX_DN<14>")
	)
	(segment
		(start 373.89435 -288.158936)
		(end 373.895112 -288.159444)
		(width 0.1143)
		(layer "In11.Cu")
		(net "P5E_CPU0_P3_TX_DN<14>")
	)
	(segment
		(start 373.927878 -291.418772)
		(end 373.965978 -291.440362)
		(width 0.1143)
		(layer "In11.Cu")
		(net "P5E_CPU0_P3_TX_DN<14>")
	)
	(segment
		(start 375.789952 -298.39539)
		(end 382.896364 -307.055012)
		(width 0.14224)
		(layer "In11.Cu")
		(net "P5E_CPU0_P3_TX_DN<14>")
	)
	(segment
		(start 374.114822 -278.136096)
		(end 373.81688 -278.136096)
		(width 0.1143)
		(layer "In11.Cu")
		(net "P5E_CPU0_P3_TX_DN<14>")
	)
	(segment
		(start 373.930926 -284.291786)
		(end 373.896128 -284.311852)
		(width 0.1143)
		(layer "In11.Cu")
		(net "P5E_CPU0_P3_TX_DN<14>")
	)
	(segment
		(start 393.513564 -384.766058)
		(end 394.086842 -384.766058)
		(width 0.14224)
		(layer "In11.Cu")
		(net "P5E_CPU0_P3_TX_DN<14>")
	)
	(arc
		(start 374.198134 -280.585926)
		(mid 374.128558 -280.85087)
		(end 373.937784 -281.047444)
		(width 0.1143)
		(layer "In11.Cu")
		(net "P5E_CPU0_P3_TX_DN<14>")
	)
	(arc
		(start 374.210072 -287.05048)
		(mid 374.149073 -287.303804)
		(end 373.97944 -287.501584)
		(width 0.1143)
		(layer "In11.Cu")
		(net "P5E_CPU0_P3_TX_DN<14>")
	)
	(arc
		(start 373.969026 -286.582866)
		(mid 374.146222 -286.784878)
		(end 374.210072 -287.045908)
		(width 0.1143)
		(layer "In11.Cu")
		(net "P5E_CPU0_P3_TX_DN<14>")
	)
	(arc
		(start 373.896128 -294.03167)
		(mid 373.7402 -294.335962)
		(end 373.896128 -294.640254)
		(width 0.1143)
		(layer "In11.Cu")
		(net "P5E_CPU0_P3_TX_DN<14>")
	)
	(arc
		(start 373.896128 -289.171634)
		(mid 373.7402 -289.475926)
		(end 373.896128 -289.780218)
		(width 0.1143)
		(layer "In11.Cu")
		(net "P5E_CPU0_P3_TX_DN<14>")
	)
	(arc
		(start 373.930926 -281.700478)
		(mid 374.210541 -282.186126)
		(end 373.930926 -282.671774)
		(width 0.1143)
		(layer "In11.Cu")
		(net "P5E_CPU0_P3_TX_DN<14>")
	)
	(arc
		(start 393.217908 -384.473704)
		(mid 393.230185 -384.535427)
		(end 393.265152 -384.58775)
		(width 0.14224)
		(layer "In11.Cu")
		(net "P5E_CPU0_P3_TX_DN<14>")
	)
	(arc
		(start 373.930926 -293.040308)
		(mid 374.210541 -293.525956)
		(end 373.930926 -294.011604)
		(width 0.1143)
		(layer "In11.Cu")
		(net "P5E_CPU0_P3_TX_DN<14>")
	)
	(arc
		(start 393.39393 -384.716528)
		(mid 393.448819 -384.753203)
		(end 393.513564 -384.766058)
		(width 0.14224)
		(layer "In11.Cu")
		(net "P5E_CPU0_P3_TX_DN<14>")
	)
	(arc
		(start 373.896128 -285.931864)
		(mid 373.781452 -286.065198)
		(end 373.740172 -286.236156)
		(width 0.1143)
		(layer "In11.Cu")
		(net "P5E_CPU0_P3_TX_DN<14>")
	)
	(arc
		(start 374.54713 -295.591992)
		(mid 374.64583 -295.762092)
		(end 374.680226 -295.95572)
		(width 0.1143)
		(layer "In11.Cu")
		(net "P5E_CPU0_P3_TX_DN<14>")
	)
	(arc
		(start 373.740172 -286.236156)
		(mid 373.780934 -286.40604)
		(end 373.89435 -286.538924)
		(width 0.1143)
		(layer "In11.Cu")
		(net "P5E_CPU0_P3_TX_DN<14>")
	)
	(arc
		(start 373.978932 -291.44976)
		(mid 374.213359 -291.905944)
		(end 373.978932 -292.362128)
		(width 0.1143)
		(layer "In11.Cu")
		(net "P5E_CPU0_P3_TX_DN<14>")
	)
	(arc
		(start 373.896128 -287.551876)
		(mid 373.781452 -287.68521)
		(end 373.740172 -287.856168)
		(width 0.1143)
		(layer "In11.Cu")
		(net "P5E_CPU0_P3_TX_DN<14>")
	)
	(arc
		(start 374.210326 -295.14165)
		(mid 374.260879 -295.33094)
		(end 374.399302 -295.469564)
		(width 0.1143)
		(layer "In11.Cu")
		(net "P5E_CPU0_P3_TX_DN<14>")
	)
	(arc
		(start 374.680226 -296.127678)
		(mid 374.694684 -296.200273)
		(end 374.735852 -296.26179)
		(width 0.1143)
		(layer "In11.Cu")
		(net "P5E_CPU0_P3_TX_DN<14>")
	)
	(arc
		(start 373.930926 -284.940502)
		(mid 374.210541 -285.42615)
		(end 373.930926 -285.911798)
		(width 0.1143)
		(layer "In11.Cu")
		(net "P5E_CPU0_P3_TX_DN<14>")
	)
	(arc
		(start 374.436894 -279.291542)
		(mid 374.680111 -279.756108)
		(end 374.436894 -280.220674)
		(width 0.1143)
		(layer "In11.Cu")
		(net "P5E_CPU0_P3_TX_DN<14>")
	)
	(arc
		(start 373.896128 -290.791646)
		(mid 373.7402 -291.095938)
		(end 373.896128 -291.40023)
		(width 0.1143)
		(layer "In11.Cu")
		(net "P5E_CPU0_P3_TX_DN<14>")
	)
	(arc
		(start 373.96801 -294.682164)
		(mid 374.145968 -294.881939)
		(end 374.210326 -295.14165)
		(width 0.1143)
		(layer "In11.Cu")
		(net "P5E_CPU0_P3_TX_DN<14>")
	)
	(arc
		(start 373.930926 -288.180272)
		(mid 374.210541 -288.66592)
		(end 373.930926 -289.151568)
		(width 0.1143)
		(layer "In11.Cu")
		(net "P5E_CPU0_P3_TX_DN<14>")
	)
	(arc
		(start 395.819122 -379.345952)
		(mid 395.505322 -380.956811)
		(end 394.59535 -382.322578)
		(width 0.14224)
		(layer "In11.Cu")
		(net "P5E_CPU0_P3_TX_DN<14>")
	)
	(arc
		(start 374.222772 -278.965914)
		(mid 374.269663 -279.14078)
		(end 374.397778 -279.268682)
		(width 0.1143)
		(layer "In11.Cu")
		(net "P5E_CPU0_P3_TX_DN<14>")
	)
	(arc
		(start 373.896128 -281.071828)
		(mid 373.7402 -281.37612)
		(end 373.896128 -281.680412)
		(width 0.1143)
		(layer "In11.Cu")
		(net "P5E_CPU0_P3_TX_DN<14>")
	)
	(arc
		(start 374.43664 -295.4909)
		(mid 374.495247 -295.537771)
		(end 374.54713 -295.591992)
		(width 0.1143)
		(layer "In11.Cu")
		(net "P5E_CPU0_P3_TX_DN<14>")
	)
	(arc
		(start 373.930926 -289.800284)
		(mid 374.210541 -290.285932)
		(end 373.930926 -290.77158)
		(width 0.1143)
		(layer "In11.Cu")
		(net "P5E_CPU0_P3_TX_DN<14>")
	)
	(arc
		(start 373.930926 -283.32049)
		(mid 374.210541 -283.806138)
		(end 373.930926 -284.291786)
		(width 0.1143)
		(layer "In11.Cu")
		(net "P5E_CPU0_P3_TX_DN<14>")
	)
	(arc
		(start 393.333986 -383.583942)
		(mid 393.248157 -383.712627)
		(end 393.218162 -383.864358)
		(width 0.14224)
		(layer "In11.Cu")
		(net "P5E_CPU0_P3_TX_DN<14>")
	)
	(arc
		(start 373.740172 -287.856168)
		(mid 373.780934 -288.026052)
		(end 373.89435 -288.158936)
		(width 0.1143)
		(layer "In11.Cu")
		(net "P5E_CPU0_P3_TX_DN<14>")
	)
	(arc
		(start 373.942864 -278.467312)
		(mid 374.147809 -278.672974)
		(end 374.222772 -278.953468)
		(width 0.1143)
		(layer "In11.Cu")
		(net "P5E_CPU0_P3_TX_DN<14>")
	)
	(arc
		(start 374.38457 -280.251154)
		(mid 374.24809 -280.387879)
		(end 374.198134 -280.574496)
		(width 0.1143)
		(layer "In11.Cu")
		(net "P5E_CPU0_P3_TX_DN<14>")
	)
	(arc
		(start 373.896128 -284.311852)
		(mid 373.7402 -284.616144)
		(end 373.896128 -284.920436)
		(width 0.1143)
		(layer "In11.Cu")
		(net "P5E_CPU0_P3_TX_DN<14>")
	)
	(arc
		(start 373.896128 -292.411658)
		(mid 373.7402 -292.71595)
		(end 373.896128 -293.020242)
		(width 0.1143)
		(layer "In11.Cu")
		(net "P5E_CPU0_P3_TX_DN<14>")
	)
	(arc
		(start 373.74703 -278.205946)
		(mid 373.799079 -278.337465)
		(end 373.896128 -278.440388)
		(width 0.1143)
		(layer "In11.Cu")
		(net "P5E_CPU0_P3_TX_DN<14>")
	)
	(arc
		(start 373.896128 -282.69184)
		(mid 373.7402 -282.996132)
		(end 373.896128 -283.300424)
		(width 0.1143)
		(layer "In11.Cu")
		(net "P5E_CPU0_P3_TX_DN<14>")
	)
	(segment
		(start 392.235182 -378.39142)
		(end 392.235182 -377.68784)
		(width 0.12954)
		(layer "F.Cu")
		(net "P5E_CPU0_P3_TX_DN<13>")
	)
	(segment
		(start 392.531092 -378.68733)
		(end 392.235182 -378.39142)
		(width 0.12954)
		(layer "F.Cu")
		(net "P5E_CPU0_P3_TX_DN<13>")
	)
	(segment
		(start 392.235182 -377.68784)
		(end 392.505692 -377.41733)
		(width 0.12954)
		(layer "F.Cu")
		(net "P5E_CPU0_P3_TX_DN<13>")
	)
	(segment
		(start 373.64797 -274.630134)
		(end 374.114822 -274.896072)
		(width 0.12954)
		(layer "F.Cu")
		(net "P5E_CPU0_P3_TX_DN<13>")
	)
	(segment
		(start 372.987062 -281.698192)
		(end 372.987824 -281.6987)
		(width 0.1143)
		(layer "In11.Cu")
		(net "P5E_CPU0_P3_TX_DN<13>")
	)
	(segment
		(start 372.98122 -284.297374)
		(end 372.980204 -284.297882)
		(width 0.1143)
		(layer "In11.Cu")
		(net "P5E_CPU0_P3_TX_DN<13>")
	)
	(segment
		(start 372.980204 -289.157664)
		(end 372.956074 -289.171634)
		(width 0.1143)
		(layer "In11.Cu")
		(net "P5E_CPU0_P3_TX_DN<13>")
	)
	(segment
		(start 372.98122 -290.777168)
		(end 372.980204 -290.777676)
		(width 0.1143)
		(layer "In11.Cu")
		(net "P5E_CPU0_P3_TX_DN<13>")
	)
	(segment
		(start 373.02694 -285.890716)
		(end 372.987824 -285.913576)
		(width 0.1143)
		(layer "In11.Cu")
		(net "P5E_CPU0_P3_TX_DN<13>")
	)
	(segment
		(start 373.02694 -290.750498)
		(end 372.987824 -290.773358)
		(width 0.1143)
		(layer "In11.Cu")
		(net "P5E_CPU0_P3_TX_DN<13>")
	)
	(segment
		(start 373.457724 -275.383498)
		(end 373.427244 -275.401278)
		(width 0.1143)
		(layer "In11.Cu")
		(net "P5E_CPU0_P3_TX_DN<13>")
	)
	(segment
		(start 373.457724 -279.268682)
		(end 373.49684 -279.291542)
		(width 0.1143)
		(layer "In11.Cu")
		(net "P5E_CPU0_P3_TX_DN<13>")
	)
	(segment
		(start 372.985792 -276.194774)
		(end 372.984268 -276.195536)
		(width 0.1143)
		(layer "In11.Cu")
		(net "P5E_CPU0_P3_TX_DN<13>")
	)
	(segment
		(start 372.983506 -289.155886)
		(end 372.981982 -289.156648)
		(width 0.1143)
		(layer "In11.Cu")
		(net "P5E_CPU0_P3_TX_DN<13>")
	)
	(segment
		(start 372.987062 -278.458168)
		(end 372.987824 -278.458676)
		(width 0.1143)
		(layer "In11.Cu")
		(net "P5E_CPU0_P3_TX_DN<13>")
	)
	(segment
		(start 374.968008 -298.868846)
		(end 382.06426 -307.515768)
		(width 0.14224)
		(layer "In11.Cu")
		(net "P5E_CPU0_P3_TX_DN<13>")
	)
	(segment
		(start 373.0244 -287.512252)
		(end 372.987824 -287.533588)
		(width 0.1143)
		(layer "In11.Cu")
		(net "P5E_CPU0_P3_TX_DN<13>")
	)
	(segment
		(start 372.987824 -291.418518)
		(end 372.98884 -291.419026)
		(width 0.1143)
		(layer "In11.Cu")
		(net "P5E_CPU0_P3_TX_DN<13>")
	)
	(segment
		(start 372.990364 -294.660066)
		(end 372.99138 -294.660574)
		(width 0.1143)
		(layer "In11.Cu")
		(net "P5E_CPU0_P3_TX_DN<13>")
	)
	(segment
		(start 372.984268 -292.395402)
		(end 372.983506 -292.39591)
		(width 0.1143)
		(layer "In11.Cu")
		(net "P5E_CPU0_P3_TX_DN<13>")
	)
	(segment
		(start 372.980204 -292.397688)
		(end 372.956074 -292.411658)
		(width 0.1143)
		(layer "In11.Cu")
		(net "P5E_CPU0_P3_TX_DN<13>")
	)
	(segment
		(start 372.987824 -288.178494)
		(end 373.02694 -288.201354)
		(width 0.1143)
		(layer "In11.Cu")
		(net "P5E_CPU0_P3_TX_DN<13>")
	)
	(segment
		(start 374.06072 -297.08983)
		(end 374.294908 -297.861736)
		(width 0.14224)
		(layer "In11.Cu")
		(net "P5E_CPU0_P3_TX_DN<13>")
	)
	(segment
		(start 372.983506 -290.775898)
		(end 372.981982 -290.77666)
		(width 0.1143)
		(layer "In11.Cu")
		(net "P5E_CPU0_P3_TX_DN<13>")
	)
	(segment
		(start 372.987824 -281.6987)
		(end 372.98884 -281.699208)
		(width 0.1143)
		(layer "In11.Cu")
		(net "P5E_CPU0_P3_TX_DN<13>")
	)
	(segment
		(start 392.214862 -377.1265)
		(end 392.505692 -377.41733)
		(width 0.14224)
		(layer "In11.Cu")
		(net "P5E_CPU0_P3_TX_DN<13>")
	)
	(segment
		(start 372.98122 -285.917386)
		(end 372.980204 -285.917894)
		(width 0.1143)
		(layer "In11.Cu")
		(net "P5E_CPU0_P3_TX_DN<13>")
	)
	(segment
		(start 372.956074 -291.40023)
		(end 372.987824 -291.418518)
		(width 0.1143)
		(layer "In11.Cu")
		(net "P5E_CPU0_P3_TX_DN<13>")
	)
	(segment
		(start 372.98122 -277.817326)
		(end 372.980204 -277.817834)
		(width 0.1143)
		(layer "In11.Cu")
		(net "P5E_CPU0_P3_TX_DN<13>")
	)
	(segment
		(start 374.014492 -296.379138)
		(end 374.014492 -296.792142)
		(width 0.1143)
		(layer "In11.Cu")
		(net "P5E_CPU0_P3_TX_DN<13>")
	)
	(segment
		(start 372.956074 -278.440388)
		(end 372.987062 -278.458168)
		(width 0.1143)
		(layer "In11.Cu")
		(net "P5E_CPU0_P3_TX_DN<13>")
	)
	(segment
		(start 372.990364 -289.80003)
		(end 372.99138 -289.800538)
		(width 0.1143)
		(layer "In11.Cu")
		(net "P5E_CPU0_P3_TX_DN<13>")
	)
	(segment
		(start 373.427244 -295.450768)
		(end 373.457724 -295.468548)
		(width 0.1143)
		(layer "In11.Cu")
		(net "P5E_CPU0_P3_TX_DN<13>")
	)
	(segment
		(start 372.981982 -290.77666)
		(end 372.98122 -290.777168)
		(width 0.1143)
		(layer "In11.Cu")
		(net "P5E_CPU0_P3_TX_DN<13>")
	)
	(segment
		(start 372.99138 -289.800538)
		(end 373.02694 -289.821366)
		(width 0.1143)
		(layer "In11.Cu")
		(net "P5E_CPU0_P3_TX_DN<13>")
	)
	(segment
		(start 394.099288 -340.18347)
		(end 394.099288 -354.620068)
		(width 0.14224)
		(layer "In11.Cu")
		(net "P5E_CPU0_P3_TX_DN<13>")
	)
	(segment
		(start 373.457724 -295.468548)
		(end 373.49684 -295.491408)
		(width 0.1143)
		(layer "In11.Cu")
		(net "P5E_CPU0_P3_TX_DN<13>")
	)
	(segment
		(start 372.980204 -276.197822)
		(end 372.956074 -276.211792)
		(width 0.1143)
		(layer "In11.Cu")
		(net "P5E_CPU0_P3_TX_DN<13>")
	)
	(segment
		(start 394.091922 -354.773992)
		(end 392.247628 -373.499634)
		(width 0.14224)
		(layer "In11.Cu")
		(net "P5E_CPU0_P3_TX_DN<13>")
	)
	(segment
		(start 372.987062 -281.054048)
		(end 372.985792 -281.05481)
		(width 0.1143)
		(layer "In11.Cu")
		(net "P5E_CPU0_P3_TX_DN<13>")
	)
	(segment
		(start 372.985792 -294.014652)
		(end 372.956074 -294.03167)
		(width 0.1143)
		(layer "In11.Cu")
		(net "P5E_CPU0_P3_TX_DN<13>")
	)
	(segment
		(start 372.99138 -294.660574)
		(end 373.02694 -294.681402)
		(width 0.1143)
		(layer "In11.Cu")
		(net "P5E_CPU0_P3_TX_DN<13>")
	)
	(segment
		(start 372.990364 -291.420042)
		(end 373.02694 -291.441378)
		(width 0.1143)
		(layer "In11.Cu")
		(net "P5E_CPU0_P3_TX_DN<13>")
	)
	(segment
		(start 372.990364 -276.840188)
		(end 372.99138 -276.840696)
		(width 0.1143)
		(layer "In11.Cu")
		(net "P5E_CPU0_P3_TX_DN<13>")
	)
	(segment
		(start 372.987062 -276.838156)
		(end 372.987824 -276.838664)
		(width 0.1143)
		(layer "In11.Cu")
		(net "P5E_CPU0_P3_TX_DN<13>")
	)
	(segment
		(start 372.983506 -282.676092)
		(end 372.981982 -282.676854)
		(width 0.1143)
		(layer "In11.Cu")
		(net "P5E_CPU0_P3_TX_DN<13>")
	)
	(segment
		(start 372.98122 -292.39718)
		(end 372.980204 -292.397688)
		(width 0.1143)
		(layer "In11.Cu")
		(net "P5E_CPU0_P3_TX_DN<13>")
	)
	(segment
		(start 372.980204 -281.057858)
		(end 372.956074 -281.071828)
		(width 0.1143)
		(layer "In11.Cu")
		(net "P5E_CPU0_P3_TX_DN<13>")
	)
	(segment
		(start 373.457724 -280.243534)
		(end 373.427244 -280.261314)
		(width 0.1143)
		(layer "In11.Cu")
		(net "P5E_CPU0_P3_TX_DN<13>")
	)
	(segment
		(start 382.06426 -307.515768)
		(end 388.240524 -316.759082)
		(width 0.14224)
		(layer "In11.Cu")
		(net "P5E_CPU0_P3_TX_DN<13>")
	)
	(segment
		(start 372.983506 -276.196044)
		(end 372.981982 -276.196806)
		(width 0.1143)
		(layer "In11.Cu")
		(net "P5E_CPU0_P3_TX_DN<13>")
	)
	(segment
		(start 372.98884 -284.939232)
		(end 372.990364 -284.940248)
		(width 0.1143)
		(layer "In11.Cu")
		(net "P5E_CPU0_P3_TX_DN<13>")
	)
	(segment
		(start 372.956074 -276.820376)
		(end 372.987062 -276.838156)
		(width 0.1143)
		(layer "In11.Cu")
		(net "P5E_CPU0_P3_TX_DN<13>")
	)
	(segment
		(start 372.987062 -289.797998)
		(end 372.987824 -289.798506)
		(width 0.1143)
		(layer "In11.Cu")
		(net "P5E_CPU0_P3_TX_DN<13>")
	)
	(segment
		(start 372.987824 -283.318712)
		(end 372.98884 -283.31922)
		(width 0.1143)
		(layer "In11.Cu")
		(net "P5E_CPU0_P3_TX_DN<13>")
	)
	(segment
		(start 372.98884 -291.419026)
		(end 372.990364 -291.420042)
		(width 0.1143)
		(layer "In11.Cu")
		(net "P5E_CPU0_P3_TX_DN<13>")
	)
	(segment
		(start 372.99138 -276.840696)
		(end 373.02694 -276.861524)
		(width 0.1143)
		(layer "In11.Cu")
		(net "P5E_CPU0_P3_TX_DN<13>")
	)
	(segment
		(start 372.990364 -293.040054)
		(end 372.99138 -293.040562)
		(width 0.1143)
		(layer "In11.Cu")
		(net "P5E_CPU0_P3_TX_DN<13>")
	)
	(segment
		(start 372.980204 -290.777676)
		(end 372.956074 -290.791646)
		(width 0.1143)
		(layer "In11.Cu")
		(net "P5E_CPU0_P3_TX_DN<13>")
	)
	(segment
		(start 373.02694 -293.990522)
		(end 372.98884 -294.012874)
		(width 0.1143)
		(layer "In11.Cu")
		(net "P5E_CPU0_P3_TX_DN<13>")
	)
	(segment
		(start 372.98884 -289.799014)
		(end 372.990364 -289.80003)
		(width 0.1143)
		(layer "In11.Cu")
		(net "P5E_CPU0_P3_TX_DN<13>")
	)
	(segment
		(start 372.987062 -294.01389)
		(end 372.985792 -294.014652)
		(width 0.1143)
		(layer "In11.Cu")
		(net "P5E_CPU0_P3_TX_DN<13>")
	)
	(segment
		(start 372.98884 -293.039038)
		(end 372.990364 -293.040054)
		(width 0.1143)
		(layer "In11.Cu")
		(net "P5E_CPU0_P3_TX_DN<13>")
	)
	(segment
		(start 373.02694 -282.650692)
		(end 372.987824 -282.673552)
		(width 0.1143)
		(layer "In11.Cu")
		(net "P5E_CPU0_P3_TX_DN<13>")
	)
	(segment
		(start 372.956074 -283.300424)
		(end 372.987824 -283.318712)
		(width 0.1143)
		(layer "In11.Cu")
		(net "P5E_CPU0_P3_TX_DN<13>")
	)
	(segment
		(start 372.984268 -277.815548)
		(end 372.983506 -277.816056)
		(width 0.1143)
		(layer "In11.Cu")
		(net "P5E_CPU0_P3_TX_DN<13>")
	)
	(segment
		(start 372.98884 -294.012874)
		(end 372.987824 -294.013382)
		(width 0.1143)
		(layer "In11.Cu")
		(net "P5E_CPU0_P3_TX_DN<13>")
	)
	(segment
		(start 372.980204 -285.917894)
		(end 372.956074 -285.931864)
		(width 0.1143)
		(layer "In11.Cu")
		(net "P5E_CPU0_P3_TX_DN<13>")
	)
	(segment
		(start 372.981982 -284.296866)
		(end 372.98122 -284.297374)
		(width 0.1143)
		(layer "In11.Cu")
		(net "P5E_CPU0_P3_TX_DN<13>")
	)
	(segment
		(start 372.956074 -293.020242)
		(end 372.987062 -293.038022)
		(width 0.1143)
		(layer "In11.Cu")
		(net "P5E_CPU0_P3_TX_DN<13>")
	)
	(segment
		(start 372.987824 -289.798506)
		(end 372.98884 -289.799014)
		(width 0.1143)
		(layer "In11.Cu")
		(net "P5E_CPU0_P3_TX_DN<13>")
	)
	(segment
		(start 372.987824 -284.293564)
		(end 372.987062 -284.294072)
		(width 0.1143)
		(layer "In11.Cu")
		(net "P5E_CPU0_P3_TX_DN<13>")
	)
	(segment
		(start 372.981982 -281.056842)
		(end 372.98122 -281.05735)
		(width 0.1143)
		(layer "In11.Cu")
		(net "P5E_CPU0_P3_TX_DN<13>")
	)
	(segment
		(start 391.930382 -375.67489)
		(end 392.02233 -375.766838)
		(width 0.14224)
		(layer "In11.Cu")
		(net "P5E_CPU0_P3_TX_DN<13>")
	)
	(segment
		(start 372.98122 -282.677362)
		(end 372.980204 -282.67787)
		(width 0.1143)
		(layer "In11.Cu")
		(net "P5E_CPU0_P3_TX_DN<13>")
	)
	(segment
		(start 373.02694 -289.130486)
		(end 372.987824 -289.153346)
		(width 0.1143)
		(layer "In11.Cu")
		(net "P5E_CPU0_P3_TX_DN<13>")
	)
	(segment
		(start 372.987062 -285.914084)
		(end 372.985792 -285.914846)
		(width 0.1143)
		(layer "In11.Cu")
		(net "P5E_CPU0_P3_TX_DN<13>")
	)
	(segment
		(start 372.983506 -292.39591)
		(end 372.981982 -292.396672)
		(width 0.1143)
		(layer "In11.Cu")
		(net "P5E_CPU0_P3_TX_DN<13>")
	)
	(segment
		(start 372.987824 -278.458676)
		(end 372.98884 -278.459184)
		(width 0.1143)
		(layer "In11.Cu")
		(net "P5E_CPU0_P3_TX_DN<13>")
	)
	(segment
		(start 373.740172 -295.955974)
		(end 373.740172 -296.104818)
		(width 0.1143)
		(layer "In11.Cu")
		(net "P5E_CPU0_P3_TX_DN<13>")
	)
	(segment
		(start 373.49684 -275.360638)
		(end 373.457724 -275.383498)
		(width 0.1143)
		(layer "In11.Cu")
		(net "P5E_CPU0_P3_TX_DN<13>")
	)
	(segment
		(start 392.214862 -376.231404)
		(end 392.214862 -377.1265)
		(width 0.14224)
		(layer "In11.Cu")
		(net "P5E_CPU0_P3_TX_DN<13>")
	)
	(segment
		(start 372.98122 -289.157156)
		(end 372.980204 -289.157664)
		(width 0.1143)
		(layer "In11.Cu")
		(net "P5E_CPU0_P3_TX_DN<13>")
	)
	(segment
		(start 372.98884 -278.459184)
		(end 372.990364 -278.4602)
		(width 0.1143)
		(layer "In11.Cu")
		(net "P5E_CPU0_P3_TX_DN<13>")
	)
	(segment
		(start 372.984268 -289.155378)
		(end 372.983506 -289.155886)
		(width 0.1143)
		(layer "In11.Cu")
		(net "P5E_CPU0_P3_TX_DN<13>")
	)
	(segment
		(start 373.49684 -280.220674)
		(end 373.457724 -280.243534)
		(width 0.1143)
		(layer "In11.Cu")
		(net "P5E_CPU0_P3_TX_DN<13>")
	)
	(segment
		(start 390.572498 -322.387976)
		(end 394.086842 -340.057486)
		(width 0.14224)
		(layer "In11.Cu")
		(net "P5E_CPU0_P3_TX_DN<13>")
	)
	(segment
		(start 374.060212 -296.86631)
		(end 374.060212 -296.876216)
		(width 0.14224)
		(layer "In11.Cu")
		(net "P5E_CPU0_P3_TX_DN<13>")
	)
	(segment
		(start 374.114822 -274.896072)
		(end 373.81688 -274.896072)
		(width 0.1143)
		(layer "In11.Cu")
		(net "P5E_CPU0_P3_TX_DN<13>")
	)
	(segment
		(start 373.02694 -276.170644)
		(end 372.987824 -276.193504)
		(width 0.1143)
		(layer "In11.Cu")
		(net "P5E_CPU0_P3_TX_DN<13>")
	)
	(segment
		(start 372.956074 -281.680412)
		(end 372.987062 -281.698192)
		(width 0.1143)
		(layer "In11.Cu")
		(net "P5E_CPU0_P3_TX_DN<13>")
	)
	(segment
		(start 372.956074 -289.780218)
		(end 372.987062 -289.797998)
		(width 0.1143)
		(layer "In11.Cu")
		(net "P5E_CPU0_P3_TX_DN<13>")
	)
	(segment
		(start 372.987062 -284.294072)
		(end 372.985792 -284.294834)
		(width 0.1143)
		(layer "In11.Cu")
		(net "P5E_CPU0_P3_TX_DN<13>")
	)
	(segment
		(start 373.02694 -284.270704)
		(end 372.987824 -284.293564)
		(width 0.1143)
		(layer "In11.Cu")
		(net "P5E_CPU0_P3_TX_DN<13>")
	)
	(segment
		(start 372.98884 -294.65905)
		(end 372.990364 -294.660066)
		(width 0.1143)
		(layer "In11.Cu")
		(net "P5E_CPU0_P3_TX_DN<13>")
	)
	(segment
		(start 374.060212 -296.837862)
		(end 374.060212 -296.86631)
		(width 0.1143)
		(layer "In11.Cu")
		(net "P5E_CPU0_P3_TX_DN<13>")
	)
	(segment
		(start 374.06072 -296.876724)
		(end 374.06072 -297.08983)
		(width 0.14224)
		(layer "In11.Cu")
		(net "P5E_CPU0_P3_TX_DN<13>")
	)
	(segment
		(start 372.987062 -276.194012)
		(end 372.985792 -276.194774)
		(width 0.1143)
		(layer "In11.Cu")
		(net "P5E_CPU0_P3_TX_DN<13>")
	)
	(segment
		(start 373.02694 -281.03068)
		(end 372.987824 -281.05354)
		(width 0.1143)
		(layer "In11.Cu")
		(net "P5E_CPU0_P3_TX_DN<13>")
	)
	(segment
		(start 372.987824 -285.913576)
		(end 372.987062 -285.914084)
		(width 0.1143)
		(layer "In11.Cu")
		(net "P5E_CPU0_P3_TX_DN<13>")
	)
	(segment
		(start 372.985792 -289.154616)
		(end 372.984268 -289.155378)
		(width 0.1143)
		(layer "In11.Cu")
		(net "P5E_CPU0_P3_TX_DN<13>")
	)
	(segment
		(start 372.99138 -278.460708)
		(end 373.02694 -278.481536)
		(width 0.1143)
		(layer "In11.Cu")
		(net "P5E_CPU0_P3_TX_DN<13>")
	)
	(segment
		(start 372.981982 -292.396672)
		(end 372.98122 -292.39718)
		(width 0.1143)
		(layer "In11.Cu")
		(net "P5E_CPU0_P3_TX_DN<13>")
	)
	(segment
		(start 372.987824 -289.153346)
		(end 372.987062 -289.153854)
		(width 0.1143)
		(layer "In11.Cu")
		(net "P5E_CPU0_P3_TX_DN<13>")
	)
	(segment
		(start 372.985792 -290.774628)
		(end 372.984268 -290.77539)
		(width 0.1143)
		(layer "In11.Cu")
		(net "P5E_CPU0_P3_TX_DN<13>")
	)
	(segment
		(start 372.954296 -288.158936)
		(end 372.987824 -288.178494)
		(width 0.1143)
		(layer "In11.Cu")
		(net "P5E_CPU0_P3_TX_DN<13>")
	)
	(segment
		(start 372.981982 -276.196806)
		(end 372.98122 -276.197314)
		(width 0.1143)
		(layer "In11.Cu")
		(net "P5E_CPU0_P3_TX_DN<13>")
	)
	(segment
		(start 374.060212 -296.876216)
		(end 374.06072 -296.876724)
		(width 0.14224)
		(layer "In11.Cu")
		(net "P5E_CPU0_P3_TX_DN<13>")
	)
	(segment
		(start 372.99138 -281.700732)
		(end 373.02694 -281.72156)
		(width 0.1143)
		(layer "In11.Cu")
		(net "P5E_CPU0_P3_TX_DN<13>")
	)
	(segment
		(start 372.954296 -286.538924)
		(end 372.987824 -286.558482)
		(width 0.1143)
		(layer "In11.Cu")
		(net "P5E_CPU0_P3_TX_DN<13>")
	)
	(segment
		(start 372.987824 -277.813516)
		(end 372.987062 -277.814024)
		(width 0.1143)
		(layer "In11.Cu")
		(net "P5E_CPU0_P3_TX_DN<13>")
	)
	(segment
		(start 372.985792 -292.39464)
		(end 372.984268 -292.395402)
		(width 0.1143)
		(layer "In11.Cu")
		(net "P5E_CPU0_P3_TX_DN<13>")
	)
	(segment
		(start 372.98122 -281.05735)
		(end 372.980204 -281.057858)
		(width 0.1143)
		(layer "In11.Cu")
		(net "P5E_CPU0_P3_TX_DN<13>")
	)
	(segment
		(start 372.980204 -282.67787)
		(end 372.956074 -282.69184)
		(width 0.1143)
		(layer "In11.Cu")
		(net "P5E_CPU0_P3_TX_DN<13>")
	)
	(segment
		(start 372.987824 -293.03853)
		(end 372.98884 -293.039038)
		(width 0.1143)
		(layer "In11.Cu")
		(net "P5E_CPU0_P3_TX_DN<13>")
	)
	(segment
		(start 372.990364 -281.700224)
		(end 372.99138 -281.700732)
		(width 0.1143)
		(layer "In11.Cu")
		(net "P5E_CPU0_P3_TX_DN<13>")
	)
	(segment
		(start 372.98122 -276.197314)
		(end 372.980204 -276.197822)
		(width 0.1143)
		(layer "In11.Cu")
		(net "P5E_CPU0_P3_TX_DN<13>")
	)
	(segment
		(start 372.987062 -282.67406)
		(end 372.985792 -282.674822)
		(width 0.1143)
		(layer "In11.Cu")
		(net "P5E_CPU0_P3_TX_DN<13>")
	)
	(segment
		(start 372.984268 -290.77539)
		(end 372.983506 -290.775898)
		(width 0.1143)
		(layer "In11.Cu")
		(net "P5E_CPU0_P3_TX_DN<13>")
	)
	(segment
		(start 372.990364 -283.320236)
		(end 373.02694 -283.341572)
		(width 0.1143)
		(layer "In11.Cu")
		(net "P5E_CPU0_P3_TX_DN<13>")
	)
	(segment
		(start 372.98884 -283.31922)
		(end 372.990364 -283.320236)
		(width 0.1143)
		(layer "In11.Cu")
		(net "P5E_CPU0_P3_TX_DN<13>")
	)
	(segment
		(start 373.02694 -292.37051)
		(end 372.987824 -292.39337)
		(width 0.1143)
		(layer "In11.Cu")
		(net "P5E_CPU0_P3_TX_DN<13>")
	)
	(segment
		(start 372.987824 -276.193504)
		(end 372.987062 -276.194012)
		(width 0.1143)
		(layer "In11.Cu")
		(net "P5E_CPU0_P3_TX_DN<13>")
	)
	(segment
		(start 372.987824 -282.673552)
		(end 372.987062 -282.67406)
		(width 0.1143)
		(layer "In11.Cu")
		(net "P5E_CPU0_P3_TX_DN<13>")
	)
	(segment
		(start 372.985792 -277.814786)
		(end 372.984268 -277.815548)
		(width 0.1143)
		(layer "In11.Cu")
		(net "P5E_CPU0_P3_TX_DN<13>")
	)
	(segment
		(start 372.987062 -293.038022)
		(end 372.987824 -293.03853)
		(width 0.1143)
		(layer "In11.Cu")
		(net "P5E_CPU0_P3_TX_DN<13>")
	)
	(segment
		(start 372.98884 -276.839172)
		(end 372.990364 -276.840188)
		(width 0.1143)
		(layer "In11.Cu")
		(net "P5E_CPU0_P3_TX_DN<13>")
	)
	(segment
		(start 372.987062 -289.153854)
		(end 372.985792 -289.154616)
		(width 0.1143)
		(layer "In11.Cu")
		(net "P5E_CPU0_P3_TX_DN<13>")
	)
	(segment
		(start 372.987824 -286.558482)
		(end 373.02694 -286.581342)
		(width 0.1143)
		(layer "In11.Cu")
		(net "P5E_CPU0_P3_TX_DN<13>")
	)
	(segment
		(start 372.99138 -293.040562)
		(end 373.02694 -293.06139)
		(width 0.1143)
		(layer "In11.Cu")
		(net "P5E_CPU0_P3_TX_DN<13>")
	)
	(segment
		(start 372.983506 -284.296104)
		(end 372.981982 -284.296866)
		(width 0.1143)
		(layer "In11.Cu")
		(net "P5E_CPU0_P3_TX_DN<13>")
	)
	(segment
		(start 372.987824 -281.05354)
		(end 372.987062 -281.054048)
		(width 0.1143)
		(layer "In11.Cu")
		(net "P5E_CPU0_P3_TX_DN<13>")
	)
	(segment
		(start 374.294908 -297.861736)
		(end 374.968008 -298.868846)
		(width 0.14224)
		(layer "In11.Cu")
		(net "P5E_CPU0_P3_TX_DN<13>")
	)
	(segment
		(start 372.987824 -284.938724)
		(end 372.98884 -284.939232)
		(width 0.1143)
		(layer "In11.Cu")
		(net "P5E_CPU0_P3_TX_DN<13>")
	)
	(segment
		(start 372.980204 -284.297882)
		(end 372.956074 -284.311852)
		(width 0.1143)
		(layer "In11.Cu")
		(net "P5E_CPU0_P3_TX_DN<13>")
	)
	(segment
		(start 372.985792 -284.294834)
		(end 372.984268 -284.295596)
		(width 0.1143)
		(layer "In11.Cu")
		(net "P5E_CPU0_P3_TX_DN<13>")
	)
	(segment
		(start 372.990364 -284.940248)
		(end 373.02694 -284.961584)
		(width 0.1143)
		(layer "In11.Cu")
		(net "P5E_CPU0_P3_TX_DN<13>")
	)
	(segment
		(start 372.983506 -277.816056)
		(end 372.981982 -277.816818)
		(width 0.1143)
		(layer "In11.Cu")
		(net "P5E_CPU0_P3_TX_DN<13>")
	)
	(segment
		(start 372.985792 -282.674822)
		(end 372.984268 -282.675584)
		(width 0.1143)
		(layer "In11.Cu")
		(net "P5E_CPU0_P3_TX_DN<13>")
	)
	(segment
		(start 372.981982 -285.916878)
		(end 372.98122 -285.917386)
		(width 0.1143)
		(layer "In11.Cu")
		(net "P5E_CPU0_P3_TX_DN<13>")
	)
	(segment
		(start 388.240524 -316.759082)
		(end 390.572498 -322.387976)
		(width 0.14224)
		(layer "In11.Cu")
		(net "P5E_CPU0_P3_TX_DN<13>")
	)
	(segment
		(start 372.956074 -294.640254)
		(end 372.987062 -294.658034)
		(width 0.1143)
		(layer "In11.Cu")
		(net "P5E_CPU0_P3_TX_DN<13>")
	)
	(segment
		(start 372.984268 -282.675584)
		(end 372.983506 -282.676092)
		(width 0.1143)
		(layer "In11.Cu")
		(net "P5E_CPU0_P3_TX_DN<13>")
	)
	(segment
		(start 372.980204 -277.817834)
		(end 372.956074 -277.831804)
		(width 0.1143)
		(layer "In11.Cu")
		(net "P5E_CPU0_P3_TX_DN<13>")
	)
	(segment
		(start 372.987062 -294.658034)
		(end 372.987824 -294.658542)
		(width 0.1143)
		(layer "In11.Cu")
		(net "P5E_CPU0_P3_TX_DN<13>")
	)
	(segment
		(start 372.956074 -284.920436)
		(end 372.987824 -284.938724)
		(width 0.1143)
		(layer "In11.Cu")
		(net "P5E_CPU0_P3_TX_DN<13>")
	)
	(segment
		(start 372.981982 -282.676854)
		(end 372.98122 -282.677362)
		(width 0.1143)
		(layer "In11.Cu")
		(net "P5E_CPU0_P3_TX_DN<13>")
	)
	(segment
		(start 374.014492 -296.792142)
		(end 374.060212 -296.837862)
		(width 0.1143)
		(layer "In11.Cu")
		(net "P5E_CPU0_P3_TX_DN<13>")
	)
	(segment
		(start 392.197082 -373.702326)
		(end 391.907776 -374.40108)
		(width 0.14224)
		(layer "In11.Cu")
		(net "P5E_CPU0_P3_TX_DN<13>")
	)
	(segment
		(start 391.883138 -374.524524)
		(end 391.883138 -375.560844)
		(width 0.14224)
		(layer "In11.Cu")
		(net "P5E_CPU0_P3_TX_DN<13>")
	)
	(segment
		(start 372.985792 -285.914846)
		(end 372.984268 -285.915608)
		(width 0.1143)
		(layer "In11.Cu")
		(net "P5E_CPU0_P3_TX_DN<13>")
	)
	(segment
		(start 372.987062 -290.773866)
		(end 372.985792 -290.774628)
		(width 0.1143)
		(layer "In11.Cu")
		(net "P5E_CPU0_P3_TX_DN<13>")
	)
	(segment
		(start 372.983506 -281.05608)
		(end 372.981982 -281.056842)
		(width 0.1143)
		(layer "In11.Cu")
		(net "P5E_CPU0_P3_TX_DN<13>")
	)
	(segment
		(start 372.984268 -276.195536)
		(end 372.983506 -276.196044)
		(width 0.1143)
		(layer "In11.Cu")
		(net "P5E_CPU0_P3_TX_DN<13>")
	)
	(segment
		(start 372.987824 -294.013382)
		(end 372.987062 -294.01389)
		(width 0.1143)
		(layer "In11.Cu")
		(net "P5E_CPU0_P3_TX_DN<13>")
	)
	(segment
		(start 372.984268 -284.295596)
		(end 372.983506 -284.296104)
		(width 0.1143)
		(layer "In11.Cu")
		(net "P5E_CPU0_P3_TX_DN<13>")
	)
	(segment
		(start 372.987824 -287.533588)
		(end 372.956074 -287.551876)
		(width 0.1143)
		(layer "In11.Cu")
		(net "P5E_CPU0_P3_TX_DN<13>")
	)
	(segment
		(start 372.987062 -277.814024)
		(end 372.985792 -277.814786)
		(width 0.1143)
		(layer "In11.Cu")
		(net "P5E_CPU0_P3_TX_DN<13>")
	)
	(segment
		(start 372.983506 -285.916116)
		(end 372.981982 -285.916878)
		(width 0.1143)
		(layer "In11.Cu")
		(net "P5E_CPU0_P3_TX_DN<13>")
	)
	(segment
		(start 372.990364 -278.4602)
		(end 372.99138 -278.460708)
		(width 0.1143)
		(layer "In11.Cu")
		(net "P5E_CPU0_P3_TX_DN<13>")
	)
	(segment
		(start 372.987824 -276.838664)
		(end 372.98884 -276.839172)
		(width 0.1143)
		(layer "In11.Cu")
		(net "P5E_CPU0_P3_TX_DN<13>")
	)
	(segment
		(start 372.981982 -277.816818)
		(end 372.98122 -277.817326)
		(width 0.1143)
		(layer "In11.Cu")
		(net "P5E_CPU0_P3_TX_DN<13>")
	)
	(segment
		(start 372.987824 -290.773358)
		(end 372.987062 -290.773866)
		(width 0.1143)
		(layer "In11.Cu")
		(net "P5E_CPU0_P3_TX_DN<13>")
	)
	(segment
		(start 372.984268 -281.055572)
		(end 372.983506 -281.05608)
		(width 0.1143)
		(layer "In11.Cu")
		(net "P5E_CPU0_P3_TX_DN<13>")
	)
	(segment
		(start 372.985792 -281.05481)
		(end 372.984268 -281.055572)
		(width 0.1143)
		(layer "In11.Cu")
		(net "P5E_CPU0_P3_TX_DN<13>")
	)
	(segment
		(start 372.984268 -285.915608)
		(end 372.983506 -285.916116)
		(width 0.1143)
		(layer "In11.Cu")
		(net "P5E_CPU0_P3_TX_DN<13>")
	)
	(segment
		(start 372.987824 -292.39337)
		(end 372.987062 -292.393878)
		(width 0.1143)
		(layer "In11.Cu")
		(net "P5E_CPU0_P3_TX_DN<13>")
	)
	(segment
		(start 373.740172 -296.104818)
		(end 374.014492 -296.379138)
		(width 0.1143)
		(layer "In11.Cu")
		(net "P5E_CPU0_P3_TX_DN<13>")
	)
	(segment
		(start 372.981982 -289.156648)
		(end 372.98122 -289.157156)
		(width 0.1143)
		(layer "In11.Cu")
		(net "P5E_CPU0_P3_TX_DN<13>")
	)
	(segment
		(start 373.81688 -274.896072)
		(end 373.734076 -274.978876)
		(width 0.1143)
		(layer "In11.Cu")
		(net "P5E_CPU0_P3_TX_DN<13>")
	)
	(segment
		(start 372.987824 -294.658542)
		(end 372.98884 -294.65905)
		(width 0.1143)
		(layer "In11.Cu")
		(net "P5E_CPU0_P3_TX_DN<13>")
	)
	(segment
		(start 373.02694 -277.790656)
		(end 372.987824 -277.813516)
		(width 0.1143)
		(layer "In11.Cu")
		(net "P5E_CPU0_P3_TX_DN<13>")
	)
	(segment
		(start 372.987062 -292.393878)
		(end 372.985792 -292.39464)
		(width 0.1143)
		(layer "In11.Cu")
		(net "P5E_CPU0_P3_TX_DN<13>")
	)
	(segment
		(start 373.427244 -279.250902)
		(end 373.457724 -279.268682)
		(width 0.1143)
		(layer "In11.Cu")
		(net "P5E_CPU0_P3_TX_DN<13>")
	)
	(segment
		(start 372.98884 -281.699208)
		(end 372.990364 -281.700224)
		(width 0.1143)
		(layer "In11.Cu")
		(net "P5E_CPU0_P3_TX_DN<13>")
	)
	(arc
		(start 394.086842 -340.057486)
		(mid 394.096154 -340.120172)
		(end 394.099288 -340.18347)
		(width 0.14224)
		(layer "In11.Cu")
		(net "P5E_CPU0_P3_TX_DN<13>")
	)
	(arc
		(start 373.49684 -295.491408)
		(mid 373.512791 -295.502818)
		(end 373.528336 -295.514776)
		(width 0.1143)
		(layer "In11.Cu")
		(net "P5E_CPU0_P3_TX_DN<13>")
	)
	(arc
		(start 373.02694 -276.861524)
		(mid 373.270267 -277.32609)
		(end 373.02694 -277.790656)
		(width 0.1143)
		(layer "In11.Cu")
		(net "P5E_CPU0_P3_TX_DN<13>")
	)
	(arc
		(start 373.02694 -278.481536)
		(mid 373.205753 -278.683886)
		(end 373.270272 -278.946102)
		(width 0.1143)
		(layer "In11.Cu")
		(net "P5E_CPU0_P3_TX_DN<13>")
	)
	(arc
		(start 373.270272 -280.566114)
		(mid 373.205757 -280.828333)
		(end 373.02694 -281.03068)
		(width 0.1143)
		(layer "In11.Cu")
		(net "P5E_CPU0_P3_TX_DN<13>")
	)
	(arc
		(start 373.02694 -286.581342)
		(mid 373.205753 -286.783692)
		(end 373.270272 -287.045908)
		(width 0.1143)
		(layer "In11.Cu")
		(net "P5E_CPU0_P3_TX_DN<13>")
	)
	(arc
		(start 372.956074 -281.071828)
		(mid 372.800146 -281.37612)
		(end 372.956074 -281.680412)
		(width 0.1143)
		(layer "In11.Cu")
		(net "P5E_CPU0_P3_TX_DN<13>")
	)
	(arc
		(start 373.02694 -289.821366)
		(mid 373.270267 -290.285932)
		(end 373.02694 -290.750498)
		(width 0.1143)
		(layer "In11.Cu")
		(net "P5E_CPU0_P3_TX_DN<13>")
	)
	(arc
		(start 392.02233 -375.766838)
		(mid 392.164802 -375.979968)
		(end 392.214862 -376.231404)
		(width 0.14224)
		(layer "In11.Cu")
		(net "P5E_CPU0_P3_TX_DN<13>")
	)
	(arc
		(start 373.270272 -295.145968)
		(mid 373.311821 -295.31739)
		(end 373.427244 -295.450768)
		(width 0.1143)
		(layer "In11.Cu")
		(net "P5E_CPU0_P3_TX_DN<13>")
	)
	(arc
		(start 373.02694 -284.961584)
		(mid 373.270267 -285.42615)
		(end 373.02694 -285.890716)
		(width 0.1143)
		(layer "In11.Cu")
		(net "P5E_CPU0_P3_TX_DN<13>")
	)
	(arc
		(start 373.02694 -294.681402)
		(mid 373.205753 -294.883752)
		(end 373.270272 -295.145968)
		(width 0.1143)
		(layer "In11.Cu")
		(net "P5E_CPU0_P3_TX_DN<13>")
	)
	(arc
		(start 372.956074 -285.931864)
		(mid 372.841398 -286.065198)
		(end 372.800118 -286.236156)
		(width 0.1143)
		(layer "In11.Cu")
		(net "P5E_CPU0_P3_TX_DN<13>")
	)
	(arc
		(start 391.883138 -375.560844)
		(mid 391.895415 -375.622567)
		(end 391.930382 -375.67489)
		(width 0.14224)
		(layer "In11.Cu")
		(net "P5E_CPU0_P3_TX_DN<13>")
	)
	(arc
		(start 394.099288 -354.620068)
		(mid 394.097498 -354.697121)
		(end 394.091922 -354.773992)
		(width 0.14224)
		(layer "In11.Cu")
		(net "P5E_CPU0_P3_TX_DN<13>")
	)
	(arc
		(start 372.956074 -277.831804)
		(mid 372.800146 -278.136096)
		(end 372.956074 -278.440388)
		(width 0.1143)
		(layer "In11.Cu")
		(net "P5E_CPU0_P3_TX_DN<13>")
	)
	(arc
		(start 373.270272 -275.706078)
		(mid 373.205757 -275.968297)
		(end 373.02694 -276.170644)
		(width 0.1143)
		(layer "In11.Cu")
		(net "P5E_CPU0_P3_TX_DN<13>")
	)
	(arc
		(start 373.02694 -288.201354)
		(mid 373.270267 -288.66592)
		(end 373.02694 -289.130486)
		(width 0.1143)
		(layer "In11.Cu")
		(net "P5E_CPU0_P3_TX_DN<13>")
	)
	(arc
		(start 372.956074 -287.551876)
		(mid 372.841398 -287.68521)
		(end 372.800118 -287.856168)
		(width 0.1143)
		(layer "In11.Cu")
		(net "P5E_CPU0_P3_TX_DN<13>")
	)
	(arc
		(start 373.427244 -275.401278)
		(mid 373.311817 -275.534654)
		(end 373.270272 -275.706078)
		(width 0.1143)
		(layer "In11.Cu")
		(net "P5E_CPU0_P3_TX_DN<13>")
	)
	(arc
		(start 373.528336 -295.514776)
		(mid 373.684459 -295.711268)
		(end 373.740172 -295.955974)
		(width 0.1143)
		(layer "In11.Cu")
		(net "P5E_CPU0_P3_TX_DN<13>")
	)
	(arc
		(start 373.02694 -281.72156)
		(mid 373.270267 -282.186126)
		(end 373.02694 -282.650692)
		(width 0.1143)
		(layer "In11.Cu")
		(net "P5E_CPU0_P3_TX_DN<13>")
	)
	(arc
		(start 373.730266 -275.001736)
		(mid 373.648833 -275.204134)
		(end 373.49684 -275.360638)
		(width 0.1143)
		(layer "In11.Cu")
		(net "P5E_CPU0_P3_TX_DN<13>")
	)
	(arc
		(start 392.247628 -373.499634)
		(mid 392.229827 -373.602843)
		(end 392.197082 -373.702326)
		(width 0.14224)
		(layer "In11.Cu")
		(net "P5E_CPU0_P3_TX_DN<13>")
	)
	(arc
		(start 372.956074 -294.03167)
		(mid 372.800146 -294.335962)
		(end 372.956074 -294.640254)
		(width 0.1143)
		(layer "In11.Cu")
		(net "P5E_CPU0_P3_TX_DN<13>")
	)
	(arc
		(start 373.02694 -293.06139)
		(mid 373.270267 -293.525956)
		(end 373.02694 -293.990522)
		(width 0.1143)
		(layer "In11.Cu")
		(net "P5E_CPU0_P3_TX_DN<13>")
	)
	(arc
		(start 373.734076 -274.978876)
		(mid 373.732288 -274.990325)
		(end 373.730266 -275.001736)
		(width 0.1143)
		(layer "In11.Cu")
		(net "P5E_CPU0_P3_TX_DN<13>")
	)
	(arc
		(start 372.956074 -292.411658)
		(mid 372.800146 -292.71595)
		(end 372.956074 -293.020242)
		(width 0.1143)
		(layer "In11.Cu")
		(net "P5E_CPU0_P3_TX_DN<13>")
	)
	(arc
		(start 372.956074 -276.211792)
		(mid 372.800146 -276.516084)
		(end 372.956074 -276.820376)
		(width 0.1143)
		(layer "In11.Cu")
		(net "P5E_CPU0_P3_TX_DN<13>")
	)
	(arc
		(start 372.956074 -290.791646)
		(mid 372.800146 -291.095938)
		(end 372.956074 -291.40023)
		(width 0.1143)
		(layer "In11.Cu")
		(net "P5E_CPU0_P3_TX_DN<13>")
	)
	(arc
		(start 373.270272 -278.946102)
		(mid 373.311821 -279.117524)
		(end 373.427244 -279.250902)
		(width 0.1143)
		(layer "In11.Cu")
		(net "P5E_CPU0_P3_TX_DN<13>")
	)
	(arc
		(start 373.02694 -283.341572)
		(mid 373.270267 -283.806138)
		(end 373.02694 -284.270704)
		(width 0.1143)
		(layer "In11.Cu")
		(net "P5E_CPU0_P3_TX_DN<13>")
	)
	(arc
		(start 373.427244 -280.261314)
		(mid 373.311817 -280.39469)
		(end 373.270272 -280.566114)
		(width 0.1143)
		(layer "In11.Cu")
		(net "P5E_CPU0_P3_TX_DN<13>")
	)
	(arc
		(start 372.956074 -282.69184)
		(mid 372.800146 -282.996132)
		(end 372.956074 -283.300424)
		(width 0.1143)
		(layer "In11.Cu")
		(net "P5E_CPU0_P3_TX_DN<13>")
	)
	(arc
		(start 372.956074 -289.171634)
		(mid 372.800146 -289.475926)
		(end 372.956074 -289.780218)
		(width 0.1143)
		(layer "In11.Cu")
		(net "P5E_CPU0_P3_TX_DN<13>")
	)
	(arc
		(start 373.49684 -279.291542)
		(mid 373.740167 -279.756108)
		(end 373.49684 -280.220674)
		(width 0.1143)
		(layer "In11.Cu")
		(net "P5E_CPU0_P3_TX_DN<13>")
	)
	(arc
		(start 372.956074 -284.311852)
		(mid 372.800146 -284.616144)
		(end 372.956074 -284.920436)
		(width 0.1143)
		(layer "In11.Cu")
		(net "P5E_CPU0_P3_TX_DN<13>")
	)
	(arc
		(start 373.270272 -287.045908)
		(mid 373.205036 -287.309499)
		(end 373.0244 -287.512252)
		(width 0.1143)
		(layer "In11.Cu")
		(net "P5E_CPU0_P3_TX_DN<13>")
	)
	(arc
		(start 373.02694 -291.441378)
		(mid 373.270267 -291.905944)
		(end 373.02694 -292.37051)
		(width 0.1143)
		(layer "In11.Cu")
		(net "P5E_CPU0_P3_TX_DN<13>")
	)
	(arc
		(start 391.907776 -374.40108)
		(mid 391.889353 -374.461586)
		(end 391.883138 -374.524524)
		(width 0.14224)
		(layer "In11.Cu")
		(net "P5E_CPU0_P3_TX_DN<13>")
	)
	(arc
		(start 372.800118 -286.236156)
		(mid 372.84088 -286.40604)
		(end 372.954296 -286.538924)
		(width 0.1143)
		(layer "In11.Cu")
		(net "P5E_CPU0_P3_TX_DN<13>")
	)
	(arc
		(start 372.800118 -287.856168)
		(mid 372.84088 -288.026052)
		(end 372.954296 -288.158936)
		(width 0.1143)
		(layer "In11.Cu")
		(net "P5E_CPU0_P3_TX_DN<13>")
	)
	(segment
		(start 388.831582 -378.39142)
		(end 389.127492 -378.68733)
		(width 0.12954)
		(layer "F.Cu")
		(net "P5E_CPU0_P3_TX_DN<12>")
	)
	(segment
		(start 389.102092 -377.41733)
		(end 388.831582 -377.68784)
		(width 0.12954)
		(layer "F.Cu")
		(net "P5E_CPU0_P3_TX_DN<12>")
	)
	(segment
		(start 370.828062 -276.250146)
		(end 371.294914 -276.516084)
		(width 0.12954)
		(layer "F.Cu")
		(net "P5E_CPU0_P3_TX_DN<12>")
	)
	(segment
		(start 388.831582 -377.68784)
		(end 388.831582 -378.39142)
		(width 0.12954)
		(layer "F.Cu")
		(net "P5E_CPU0_P3_TX_DN<12>")
	)
	(segment
		(start 372.04777 -286.558482)
		(end 372.086886 -286.581342)
		(width 0.1143)
		(layer "In11.Cu")
		(net "P5E_CPU0_P3_TX_DN<12>")
	)
	(segment
		(start 372.04777 -289.798506)
		(end 372.086886 -289.821366)
		(width 0.1143)
		(layer "In11.Cu")
		(net "P5E_CPU0_P3_TX_DN<12>")
	)
	(segment
		(start 372.55704 -280.220674)
		(end 372.517924 -280.243534)
		(width 0.1143)
		(layer "In11.Cu")
		(net "P5E_CPU0_P3_TX_DN<12>")
	)
	(segment
		(start 373.094758 -296.86631)
		(end 373.094758 -296.876216)
		(width 0.14224)
		(layer "In11.Cu")
		(net "P5E_CPU0_P3_TX_DN<12>")
	)
	(segment
		(start 372.486174 -279.250394)
		(end 372.517162 -279.268174)
		(width 0.1143)
		(layer "In11.Cu")
		(net "P5E_CPU0_P3_TX_DN<12>")
	)
	(segment
		(start 374.525032 -299.909992)
		(end 381.415036 -308.305454)
		(width 0.14224)
		(layer "In11.Cu")
		(net "P5E_CPU0_P3_TX_DN<12>")
	)
	(segment
		(start 384.419856 -312.80227)
		(end 384.419856 -312.802524)
		(width 0.14224)
		(layer "In11.Cu")
		(net "P5E_CPU0_P3_TX_DN<12>")
	)
	(segment
		(start 388.811262 -377.1265)
		(end 389.102092 -377.41733)
		(width 0.14224)
		(layer "In11.Cu")
		(net "P5E_CPU0_P3_TX_DN<12>")
	)
	(segment
		(start 393.15136 -352.426524)
		(end 389.125206 -372.666768)
		(width 0.14224)
		(layer "In11.Cu")
		(net "P5E_CPU0_P3_TX_DN<12>")
	)
	(segment
		(start 372.799864 -296.128694)
		(end 373.049038 -296.377868)
		(width 0.1143)
		(layer "In11.Cu")
		(net "P5E_CPU0_P3_TX_DN<12>")
	)
	(segment
		(start 372.086886 -281.03068)
		(end 372.04777 -281.05354)
		(width 0.1143)
		(layer "In11.Cu")
		(net "P5E_CPU0_P3_TX_DN<12>")
	)
	(segment
		(start 372.01729 -291.400738)
		(end 372.04777 -291.418518)
		(width 0.1143)
		(layer "In11.Cu")
		(net "P5E_CPU0_P3_TX_DN<12>")
	)
	(segment
		(start 372.086886 -282.650692)
		(end 372.04777 -282.673552)
		(width 0.1143)
		(layer "In11.Cu")
		(net "P5E_CPU0_P3_TX_DN<12>")
	)
	(segment
		(start 371.390164 -277.32609)
		(end 371.390164 -277.329138)
		(width 0.1143)
		(layer "In11.Cu")
		(net "P5E_CPU0_P3_TX_DN<12>")
	)
	(segment
		(start 372.01729 -281.68092)
		(end 372.04777 -281.6987)
		(width 0.1143)
		(layer "In11.Cu")
		(net "P5E_CPU0_P3_TX_DN<12>")
	)
	(segment
		(start 372.04777 -292.39337)
		(end 372.01729 -292.41115)
		(width 0.1143)
		(layer "In11.Cu")
		(net "P5E_CPU0_P3_TX_DN<12>")
	)
	(segment
		(start 372.04777 -294.013382)
		(end 372.01729 -294.031162)
		(width 0.1143)
		(layer "In11.Cu")
		(net "P5E_CPU0_P3_TX_DN<12>")
	)
	(segment
		(start 372.01729 -293.02075)
		(end 372.04777 -293.03853)
		(width 0.1143)
		(layer "In11.Cu")
		(net "P5E_CPU0_P3_TX_DN<12>")
	)
	(segment
		(start 372.04777 -284.938724)
		(end 372.086886 -284.961584)
		(width 0.1143)
		(layer "In11.Cu")
		(net "P5E_CPU0_P3_TX_DN<12>")
	)
	(segment
		(start 373.095266 -297.14952)
		(end 373.440198 -298.286424)
		(width 0.14224)
		(layer "In11.Cu")
		(net "P5E_CPU0_P3_TX_DN<12>")
	)
	(segment
		(start 372.015258 -286.539686)
		(end 372.04777 -286.558482)
		(width 0.1143)
		(layer "In11.Cu")
		(net "P5E_CPU0_P3_TX_DN<12>")
	)
	(segment
		(start 393.15136 -340.251796)
		(end 393.15136 -352.426524)
		(width 0.14224)
		(layer "In11.Cu")
		(net "P5E_CPU0_P3_TX_DN<12>")
	)
	(segment
		(start 372.04777 -281.05354)
		(end 372.01729 -281.07132)
		(width 0.1143)
		(layer "In11.Cu")
		(net "P5E_CPU0_P3_TX_DN<12>")
	)
	(segment
		(start 371.10797 -276.838664)
		(end 371.111272 -276.840696)
		(width 0.1143)
		(layer "In11.Cu")
		(net "P5E_CPU0_P3_TX_DN<12>")
	)
	(segment
		(start 381.415036 -308.305454)
		(end 384.419856 -312.80227)
		(width 0.14224)
		(layer "In11.Cu")
		(net "P5E_CPU0_P3_TX_DN<12>")
	)
	(segment
		(start 384.419856 -312.802524)
		(end 387.432296 -317.311024)
		(width 0.14224)
		(layer "In11.Cu")
		(net "P5E_CPU0_P3_TX_DN<12>")
	)
	(segment
		(start 388.811262 -375.854214)
		(end 388.811262 -377.1265)
		(width 0.14224)
		(layer "In11.Cu")
		(net "P5E_CPU0_P3_TX_DN<12>")
	)
	(segment
		(start 372.086886 -285.890716)
		(end 372.04777 -285.913576)
		(width 0.1143)
		(layer "In11.Cu")
		(net "P5E_CPU0_P3_TX_DN<12>")
	)
	(segment
		(start 372.52148 -279.270714)
		(end 372.55704 -279.291542)
		(width 0.1143)
		(layer "In11.Cu")
		(net "P5E_CPU0_P3_TX_DN<12>")
	)
	(segment
		(start 372.04777 -285.913576)
		(end 372.01729 -285.931356)
		(width 0.1143)
		(layer "In11.Cu")
		(net "P5E_CPU0_P3_TX_DN<12>")
	)
	(segment
		(start 373.095266 -296.876724)
		(end 373.095266 -297.14952)
		(width 0.14224)
		(layer "In11.Cu")
		(net "P5E_CPU0_P3_TX_DN<12>")
	)
	(segment
		(start 372.517162 -280.244042)
		(end 372.515892 -280.244804)
		(width 0.1143)
		(layer "In11.Cu")
		(net "P5E_CPU0_P3_TX_DN<12>")
	)
	(segment
		(start 373.440198 -298.286424)
		(end 374.525032 -299.909992)
		(width 0.14224)
		(layer "In11.Cu")
		(net "P5E_CPU0_P3_TX_DN<12>")
	)
	(segment
		(start 372.04777 -282.673552)
		(end 372.01729 -282.691332)
		(width 0.1143)
		(layer "In11.Cu")
		(net "P5E_CPU0_P3_TX_DN<12>")
	)
	(segment
		(start 372.04777 -288.178494)
		(end 372.086886 -288.201354)
		(width 0.1143)
		(layer "In11.Cu")
		(net "P5E_CPU0_P3_TX_DN<12>")
	)
	(segment
		(start 370.996972 -276.516084)
		(end 370.927122 -276.585934)
		(width 0.1143)
		(layer "In11.Cu")
		(net "P5E_CPU0_P3_TX_DN<12>")
	)
	(segment
		(start 371.294914 -276.516084)
		(end 370.996972 -276.516084)
		(width 0.1143)
		(layer "In11.Cu")
		(net "P5E_CPU0_P3_TX_DN<12>")
	)
	(segment
		(start 372.515892 -280.244804)
		(end 372.486174 -280.261822)
		(width 0.1143)
		(layer "In11.Cu")
		(net "P5E_CPU0_P3_TX_DN<12>")
	)
	(segment
		(start 372.01729 -284.920944)
		(end 372.04777 -284.938724)
		(width 0.1143)
		(layer "In11.Cu")
		(net "P5E_CPU0_P3_TX_DN<12>")
	)
	(segment
		(start 372.800118 -296.128694)
		(end 372.799864 -296.128694)
		(width 0.1143)
		(layer "In11.Cu")
		(net "P5E_CPU0_P3_TX_DN<12>")
	)
	(segment
		(start 372.520464 -279.270206)
		(end 372.52148 -279.270714)
		(width 0.1143)
		(layer "In11.Cu")
		(net "P5E_CPU0_P3_TX_DN<12>")
	)
	(segment
		(start 373.094758 -296.876216)
		(end 373.095266 -296.876724)
		(width 0.14224)
		(layer "In11.Cu")
		(net "P5E_CPU0_P3_TX_DN<12>")
	)
	(segment
		(start 372.01729 -289.780726)
		(end 372.04777 -289.798506)
		(width 0.1143)
		(layer "In11.Cu")
		(net "P5E_CPU0_P3_TX_DN<12>")
	)
	(segment
		(start 373.049038 -296.377868)
		(end 373.049038 -296.792142)
		(width 0.1143)
		(layer "In11.Cu")
		(net "P5E_CPU0_P3_TX_DN<12>")
	)
	(segment
		(start 373.049038 -296.792142)
		(end 373.094758 -296.837862)
		(width 0.1143)
		(layer "In11.Cu")
		(net "P5E_CPU0_P3_TX_DN<12>")
	)
	(segment
		(start 372.517162 -279.268174)
		(end 372.517924 -279.268682)
		(width 0.1143)
		(layer "In11.Cu")
		(net "P5E_CPU0_P3_TX_DN<12>")
	)
	(segment
		(start 371.107208 -276.838156)
		(end 371.10797 -276.838664)
		(width 0.1143)
		(layer "In11.Cu")
		(net "P5E_CPU0_P3_TX_DN<12>")
	)
	(segment
		(start 372.517924 -280.243534)
		(end 372.517162 -280.244042)
		(width 0.1143)
		(layer "In11.Cu")
		(net "P5E_CPU0_P3_TX_DN<12>")
	)
	(segment
		(start 372.086886 -284.270704)
		(end 372.04777 -284.293564)
		(width 0.1143)
		(layer "In11.Cu")
		(net "P5E_CPU0_P3_TX_DN<12>")
	)
	(segment
		(start 389.35406 -321.949826)
		(end 393.15136 -340.251796)
		(width 0.14224)
		(layer "In11.Cu")
		(net "P5E_CPU0_P3_TX_DN<12>")
	)
	(segment
		(start 372.084346 -287.512252)
		(end 372.01729 -287.551368)
		(width 0.1143)
		(layer "In11.Cu")
		(net "P5E_CPU0_P3_TX_DN<12>")
	)
	(segment
		(start 372.04777 -294.658542)
		(end 372.086886 -294.681402)
		(width 0.1143)
		(layer "In11.Cu")
		(net "P5E_CPU0_P3_TX_DN<12>")
	)
	(segment
		(start 371.07622 -276.820376)
		(end 371.107208 -276.838156)
		(width 0.1143)
		(layer "In11.Cu")
		(net "P5E_CPU0_P3_TX_DN<12>")
	)
	(segment
		(start 372.04777 -283.318712)
		(end 372.086886 -283.341572)
		(width 0.1143)
		(layer "In11.Cu")
		(net "P5E_CPU0_P3_TX_DN<12>")
	)
	(segment
		(start 372.04777 -281.6987)
		(end 372.086886 -281.72156)
		(width 0.1143)
		(layer "In11.Cu")
		(net "P5E_CPU0_P3_TX_DN<12>")
	)
	(segment
		(start 372.015258 -288.159698)
		(end 372.04777 -288.178494)
		(width 0.1143)
		(layer "In11.Cu")
		(net "P5E_CPU0_P3_TX_DN<12>")
	)
	(segment
		(start 372.04777 -293.03853)
		(end 372.086886 -293.06139)
		(width 0.1143)
		(layer "In11.Cu")
		(net "P5E_CPU0_P3_TX_DN<12>")
	)
	(segment
		(start 372.04777 -289.153346)
		(end 372.01729 -289.171126)
		(width 0.1143)
		(layer "In11.Cu")
		(net "P5E_CPU0_P3_TX_DN<12>")
	)
	(segment
		(start 387.432296 -317.311024)
		(end 389.35406 -321.949826)
		(width 0.14224)
		(layer "In11.Cu")
		(net "P5E_CPU0_P3_TX_DN<12>")
	)
	(segment
		(start 372.01729 -278.440896)
		(end 372.04777 -278.458676)
		(width 0.1143)
		(layer "In11.Cu")
		(net "P5E_CPU0_P3_TX_DN<12>")
	)
	(segment
		(start 372.04777 -278.458676)
		(end 372.086886 -278.481536)
		(width 0.1143)
		(layer "In11.Cu")
		(net "P5E_CPU0_P3_TX_DN<12>")
	)
	(segment
		(start 372.800118 -295.955974)
		(end 372.800118 -296.128694)
		(width 0.1143)
		(layer "In11.Cu")
		(net "P5E_CPU0_P3_TX_DN<12>")
	)
	(segment
		(start 372.086886 -293.990522)
		(end 372.04777 -294.013382)
		(width 0.1143)
		(layer "In11.Cu")
		(net "P5E_CPU0_P3_TX_DN<12>")
	)
	(segment
		(start 372.01729 -283.300932)
		(end 372.04777 -283.318712)
		(width 0.1143)
		(layer "In11.Cu")
		(net "P5E_CPU0_P3_TX_DN<12>")
	)
	(segment
		(start 371.54612 -277.630382)
		(end 371.616986 -277.67153)
		(width 0.1143)
		(layer "In11.Cu")
		(net "P5E_CPU0_P3_TX_DN<12>")
	)
	(segment
		(start 372.086886 -292.37051)
		(end 372.04777 -292.39337)
		(width 0.1143)
		(layer "In11.Cu")
		(net "P5E_CPU0_P3_TX_DN<12>")
	)
	(segment
		(start 372.086886 -290.750498)
		(end 372.04777 -290.773358)
		(width 0.1143)
		(layer "In11.Cu")
		(net "P5E_CPU0_P3_TX_DN<12>")
	)
	(segment
		(start 371.543326 -277.62835)
		(end 371.54612 -277.630382)
		(width 0.1143)
		(layer "In11.Cu")
		(net "P5E_CPU0_P3_TX_DN<12>")
	)
	(segment
		(start 372.51894 -279.26919)
		(end 372.520464 -279.270206)
		(width 0.1143)
		(layer "In11.Cu")
		(net "P5E_CPU0_P3_TX_DN<12>")
	)
	(segment
		(start 372.04777 -290.773358)
		(end 372.01729 -290.791138)
		(width 0.1143)
		(layer "In11.Cu")
		(net "P5E_CPU0_P3_TX_DN<12>")
	)
	(segment
		(start 372.51767 -295.468548)
		(end 372.556786 -295.491408)
		(width 0.1143)
		(layer "In11.Cu")
		(net "P5E_CPU0_P3_TX_DN<12>")
	)
	(segment
		(start 372.086886 -289.130486)
		(end 372.04777 -289.153346)
		(width 0.1143)
		(layer "In11.Cu")
		(net "P5E_CPU0_P3_TX_DN<12>")
	)
	(segment
		(start 371.111272 -276.840696)
		(end 371.144292 -276.859746)
		(width 0.1143)
		(layer "In11.Cu")
		(net "P5E_CPU0_P3_TX_DN<12>")
	)
	(segment
		(start 372.48719 -295.450768)
		(end 372.51767 -295.468548)
		(width 0.1143)
		(layer "In11.Cu")
		(net "P5E_CPU0_P3_TX_DN<12>")
	)
	(segment
		(start 372.04777 -291.418518)
		(end 372.086886 -291.441378)
		(width 0.1143)
		(layer "In11.Cu")
		(net "P5E_CPU0_P3_TX_DN<12>")
	)
	(segment
		(start 373.094758 -296.837862)
		(end 373.094758 -296.86631)
		(width 0.1143)
		(layer "In11.Cu")
		(net "P5E_CPU0_P3_TX_DN<12>")
	)
	(segment
		(start 372.517924 -279.268682)
		(end 372.51894 -279.26919)
		(width 0.1143)
		(layer "In11.Cu")
		(net "P5E_CPU0_P3_TX_DN<12>")
	)
	(segment
		(start 372.01729 -294.640762)
		(end 372.04777 -294.658542)
		(width 0.1143)
		(layer "In11.Cu")
		(net "P5E_CPU0_P3_TX_DN<12>")
	)
	(segment
		(start 372.04777 -284.293564)
		(end 372.01729 -284.311344)
		(width 0.1143)
		(layer "In11.Cu")
		(net "P5E_CPU0_P3_TX_DN<12>")
	)
	(arc
		(start 372.01729 -287.551368)
		(mid 371.901863 -287.684744)
		(end 371.860318 -287.856168)
		(width 0.1143)
		(layer "In11.Cu")
		(net "P5E_CPU0_P3_TX_DN<12>")
	)
	(arc
		(start 371.390164 -277.329138)
		(mid 371.43061 -277.497253)
		(end 371.543326 -277.62835)
		(width 0.1143)
		(layer "In11.Cu")
		(net "P5E_CPU0_P3_TX_DN<12>")
	)
	(arc
		(start 372.01729 -292.41115)
		(mid 371.860313 -292.71595)
		(end 372.01729 -293.02075)
		(width 0.1143)
		(layer "In11.Cu")
		(net "P5E_CPU0_P3_TX_DN<12>")
	)
	(arc
		(start 372.330218 -278.946102)
		(mid 372.371473 -279.117073)
		(end 372.486174 -279.250394)
		(width 0.1143)
		(layer "In11.Cu")
		(net "P5E_CPU0_P3_TX_DN<12>")
	)
	(arc
		(start 371.144292 -276.859746)
		(mid 371.324944 -277.062491)
		(end 371.390164 -277.32609)
		(width 0.1143)
		(layer "In11.Cu")
		(net "P5E_CPU0_P3_TX_DN<12>")
	)
	(arc
		(start 372.086886 -291.441378)
		(mid 372.330213 -291.905944)
		(end 372.086886 -292.37051)
		(width 0.1143)
		(layer "In11.Cu")
		(net "P5E_CPU0_P3_TX_DN<12>")
	)
	(arc
		(start 372.086886 -293.06139)
		(mid 372.330213 -293.525956)
		(end 372.086886 -293.990522)
		(width 0.1143)
		(layer "In11.Cu")
		(net "P5E_CPU0_P3_TX_DN<12>")
	)
	(arc
		(start 372.330218 -280.566114)
		(mid 372.265703 -280.828333)
		(end 372.086886 -281.03068)
		(width 0.1143)
		(layer "In11.Cu")
		(net "P5E_CPU0_P3_TX_DN<12>")
	)
	(arc
		(start 372.55704 -279.291542)
		(mid 372.800367 -279.756108)
		(end 372.55704 -280.220674)
		(width 0.1143)
		(layer "In11.Cu")
		(net "P5E_CPU0_P3_TX_DN<12>")
	)
	(arc
		(start 372.01729 -294.031162)
		(mid 371.860313 -294.335962)
		(end 372.01729 -294.640762)
		(width 0.1143)
		(layer "In11.Cu")
		(net "P5E_CPU0_P3_TX_DN<12>")
	)
	(arc
		(start 372.556786 -295.491408)
		(mid 372.572737 -295.502818)
		(end 372.588282 -295.514776)
		(width 0.1143)
		(layer "In11.Cu")
		(net "P5E_CPU0_P3_TX_DN<12>")
	)
	(arc
		(start 370.927122 -276.585934)
		(mid 370.979171 -276.717453)
		(end 371.07622 -276.820376)
		(width 0.1143)
		(layer "In11.Cu")
		(net "P5E_CPU0_P3_TX_DN<12>")
	)
	(arc
		(start 371.616986 -277.67153)
		(mid 371.795799 -277.87388)
		(end 371.860318 -278.136096)
		(width 0.1143)
		(layer "In11.Cu")
		(net "P5E_CPU0_P3_TX_DN<12>")
	)
	(arc
		(start 372.086886 -284.961584)
		(mid 372.330213 -285.42615)
		(end 372.086886 -285.890716)
		(width 0.1143)
		(layer "In11.Cu")
		(net "P5E_CPU0_P3_TX_DN<12>")
	)
	(arc
		(start 372.086886 -294.681402)
		(mid 372.265699 -294.883752)
		(end 372.330218 -295.145968)
		(width 0.1143)
		(layer "In11.Cu")
		(net "P5E_CPU0_P3_TX_DN<12>")
	)
	(arc
		(start 372.086886 -289.821366)
		(mid 372.330213 -290.285932)
		(end 372.086886 -290.750498)
		(width 0.1143)
		(layer "In11.Cu")
		(net "P5E_CPU0_P3_TX_DN<12>")
	)
	(arc
		(start 371.860318 -278.136096)
		(mid 371.901867 -278.307518)
		(end 372.01729 -278.440896)
		(width 0.1143)
		(layer "In11.Cu")
		(net "P5E_CPU0_P3_TX_DN<12>")
	)
	(arc
		(start 372.086886 -283.341572)
		(mid 372.330213 -283.806138)
		(end 372.086886 -284.270704)
		(width 0.1143)
		(layer "In11.Cu")
		(net "P5E_CPU0_P3_TX_DN<12>")
	)
	(arc
		(start 389.125206 -372.666768)
		(mid 388.889936 -374.252779)
		(end 388.811262 -375.854214)
		(width 0.14224)
		(layer "In11.Cu")
		(net "P5E_CPU0_P3_TX_DN<12>")
	)
	(arc
		(start 371.860318 -287.856168)
		(mid 371.901284 -288.026574)
		(end 372.015258 -288.159698)
		(width 0.1143)
		(layer "In11.Cu")
		(net "P5E_CPU0_P3_TX_DN<12>")
	)
	(arc
		(start 372.01729 -281.07132)
		(mid 371.860313 -281.37612)
		(end 372.01729 -281.68092)
		(width 0.1143)
		(layer "In11.Cu")
		(net "P5E_CPU0_P3_TX_DN<12>")
	)
	(arc
		(start 372.588282 -295.514776)
		(mid 372.744405 -295.711268)
		(end 372.800118 -295.955974)
		(width 0.1143)
		(layer "In11.Cu")
		(net "P5E_CPU0_P3_TX_DN<12>")
	)
	(arc
		(start 372.486174 -280.261822)
		(mid 372.371498 -280.395156)
		(end 372.330218 -280.566114)
		(width 0.1143)
		(layer "In11.Cu")
		(net "P5E_CPU0_P3_TX_DN<12>")
	)
	(arc
		(start 372.086886 -278.481536)
		(mid 372.265699 -278.683886)
		(end 372.330218 -278.946102)
		(width 0.1143)
		(layer "In11.Cu")
		(net "P5E_CPU0_P3_TX_DN<12>")
	)
	(arc
		(start 372.01729 -285.931356)
		(mid 371.901863 -286.064732)
		(end 371.860318 -286.236156)
		(width 0.1143)
		(layer "In11.Cu")
		(net "P5E_CPU0_P3_TX_DN<12>")
	)
	(arc
		(start 372.01729 -284.311344)
		(mid 371.860313 -284.616144)
		(end 372.01729 -284.920944)
		(width 0.1143)
		(layer "In11.Cu")
		(net "P5E_CPU0_P3_TX_DN<12>")
	)
	(arc
		(start 372.01729 -290.791138)
		(mid 371.860313 -291.095938)
		(end 372.01729 -291.400738)
		(width 0.1143)
		(layer "In11.Cu")
		(net "P5E_CPU0_P3_TX_DN<12>")
	)
	(arc
		(start 372.086886 -288.201354)
		(mid 372.330213 -288.66592)
		(end 372.086886 -289.130486)
		(width 0.1143)
		(layer "In11.Cu")
		(net "P5E_CPU0_P3_TX_DN<12>")
	)
	(arc
		(start 372.086886 -286.581342)
		(mid 372.265699 -286.783692)
		(end 372.330218 -287.045908)
		(width 0.1143)
		(layer "In11.Cu")
		(net "P5E_CPU0_P3_TX_DN<12>")
	)
	(arc
		(start 372.086886 -281.72156)
		(mid 372.330213 -282.186126)
		(end 372.086886 -282.650692)
		(width 0.1143)
		(layer "In11.Cu")
		(net "P5E_CPU0_P3_TX_DN<12>")
	)
	(arc
		(start 372.330218 -287.045908)
		(mid 372.264982 -287.309499)
		(end 372.084346 -287.512252)
		(width 0.1143)
		(layer "In11.Cu")
		(net "P5E_CPU0_P3_TX_DN<12>")
	)
	(arc
		(start 372.330218 -295.145968)
		(mid 372.371767 -295.31739)
		(end 372.48719 -295.450768)
		(width 0.1143)
		(layer "In11.Cu")
		(net "P5E_CPU0_P3_TX_DN<12>")
	)
	(arc
		(start 372.01729 -282.691332)
		(mid 371.860313 -282.996132)
		(end 372.01729 -283.300932)
		(width 0.1143)
		(layer "In11.Cu")
		(net "P5E_CPU0_P3_TX_DN<12>")
	)
	(arc
		(start 372.01729 -289.171126)
		(mid 371.860313 -289.475926)
		(end 372.01729 -289.780726)
		(width 0.1143)
		(layer "In11.Cu")
		(net "P5E_CPU0_P3_TX_DN<12>")
	)
	(arc
		(start 371.860318 -286.236156)
		(mid 371.901284 -286.406562)
		(end 372.015258 -286.539686)
		(width 0.1143)
		(layer "In11.Cu")
		(net "P5E_CPU0_P3_TX_DN<12>")
	)
	(segment
		(start 387.129782 -380.85522)
		(end 387.425692 -381.15113)
		(width 0.12954)
		(layer "F.Cu")
		(net "P5E_CPU0_P3_TX_DN<11>")
	)
	(segment
		(start 387.129782 -380.15164)
		(end 387.129782 -380.85522)
		(width 0.12954)
		(layer "F.Cu")
		(net "P5E_CPU0_P3_TX_DN<11>")
	)
	(segment
		(start 387.400292 -379.88113)
		(end 387.129782 -380.15164)
		(width 0.12954)
		(layer "F.Cu")
		(net "P5E_CPU0_P3_TX_DN<11>")
	)
	(segment
		(start 370.828062 -277.870158)
		(end 371.294914 -278.136096)
		(width 0.12954)
		(layer "F.Cu")
		(net "P5E_CPU0_P3_TX_DN<11>")
	)
	(segment
		(start 371.07622 -294.640254)
		(end 371.10797 -294.658542)
		(width 0.1143)
		(layer "In11.Cu")
		(net "P5E_CPU0_P3_TX_DN<11>")
	)
	(segment
		(start 371.07622 -289.780218)
		(end 371.10797 -289.798506)
		(width 0.1143)
		(layer "In11.Cu")
		(net "P5E_CPU0_P3_TX_DN<11>")
	)
	(segment
		(start 371.10797 -289.798506)
		(end 371.111018 -289.800284)
		(width 0.1143)
		(layer "In11.Cu")
		(net "P5E_CPU0_P3_TX_DN<11>")
	)
	(segment
		(start 371.074442 -288.158936)
		(end 371.075204 -288.159444)
		(width 0.1143)
		(layer "In11.Cu")
		(net "P5E_CPU0_P3_TX_DN<11>")
	)
	(segment
		(start 371.378226 -280.574496)
		(end 371.378226 -280.585926)
		(width 0.1143)
		(layer "In11.Cu")
		(net "P5E_CPU0_P3_TX_DN<11>")
	)
	(segment
		(start 371.111018 -290.77158)
		(end 371.07622 -290.791646)
		(width 0.1143)
		(layer "In11.Cu")
		(net "P5E_CPU0_P3_TX_DN<11>")
	)
	(segment
		(start 372.149878 -296.86631)
		(end 372.149878 -296.876216)
		(width 0.14224)
		(layer "In11.Cu")
		(net "P5E_CPU0_P3_TX_DN<11>")
	)
	(segment
		(start 387.109462 -376.277632)
		(end 387.109462 -379.5903)
		(width 0.14224)
		(layer "In11.Cu")
		(net "P5E_CPU0_P3_TX_DN<11>")
	)
	(segment
		(start 371.07622 -278.440388)
		(end 371.107208 -278.458168)
		(width 0.1143)
		(layer "In11.Cu")
		(net "P5E_CPU0_P3_TX_DN<11>")
	)
	(segment
		(start 371.390164 -295.14165)
		(end 371.390164 -295.145968)
		(width 0.1143)
		(layer "In11.Cu")
		(net "P5E_CPU0_P3_TX_DN<11>")
	)
	(segment
		(start 371.07622 -283.300424)
		(end 371.107208 -283.318204)
		(width 0.1143)
		(layer "In11.Cu")
		(net "P5E_CPU0_P3_TX_DN<11>")
	)
	(segment
		(start 371.074442 -286.538924)
		(end 371.149118 -286.582866)
		(width 0.1143)
		(layer "In11.Cu")
		(net "P5E_CPU0_P3_TX_DN<11>")
	)
	(segment
		(start 372.104158 -296.372788)
		(end 372.104158 -296.792142)
		(width 0.1143)
		(layer "In11.Cu")
		(net "P5E_CPU0_P3_TX_DN<11>")
	)
	(segment
		(start 371.07622 -281.680412)
		(end 371.10797 -281.6987)
		(width 0.1143)
		(layer "In11.Cu")
		(net "P5E_CPU0_P3_TX_DN<11>")
	)
	(segment
		(start 371.390164 -287.045908)
		(end 371.390164 -287.05048)
		(width 0.1143)
		(layer "In11.Cu")
		(net "P5E_CPU0_P3_TX_DN<11>")
	)
	(segment
		(start 371.10797 -284.938724)
		(end 371.111018 -284.940502)
		(width 0.1143)
		(layer "In11.Cu")
		(net "P5E_CPU0_P3_TX_DN<11>")
	)
	(segment
		(start 371.10797 -294.658542)
		(end 371.147848 -294.682164)
		(width 0.1143)
		(layer "In11.Cu")
		(net "P5E_CPU0_P3_TX_DN<11>")
	)
	(segment
		(start 371.108986 -278.459184)
		(end 371.122956 -278.467312)
		(width 0.1143)
		(layer "In11.Cu")
		(net "P5E_CPU0_P3_TX_DN<11>")
	)
	(segment
		(start 371.10797 -281.6987)
		(end 371.111018 -281.700478)
		(width 0.1143)
		(layer "In11.Cu")
		(net "P5E_CPU0_P3_TX_DN<11>")
	)
	(segment
		(start 371.159532 -287.501584)
		(end 371.148102 -287.51022)
		(width 0.1143)
		(layer "In11.Cu")
		(net "P5E_CPU0_P3_TX_DN<11>")
	)
	(segment
		(start 371.111018 -284.291786)
		(end 371.07622 -284.311852)
		(width 0.1143)
		(layer "In11.Cu")
		(net "P5E_CPU0_P3_TX_DN<11>")
	)
	(segment
		(start 371.117876 -281.047444)
		(end 371.10797 -281.05354)
		(width 0.1143)
		(layer "In11.Cu")
		(net "P5E_CPU0_P3_TX_DN<11>")
	)
	(segment
		(start 371.616986 -280.220674)
		(end 371.564916 -280.2509)
		(width 0.1143)
		(layer "In11.Cu")
		(net "P5E_CPU0_P3_TX_DN<11>")
	)
	(segment
		(start 380.647956 -308.868318)
		(end 386.589524 -317.76035)
		(width 0.14224)
		(layer "In11.Cu")
		(net "P5E_CPU0_P3_TX_DN<11>")
	)
	(segment
		(start 372.150386 -297.272456)
		(end 372.58752 -298.712636)
		(width 0.14224)
		(layer "In11.Cu")
		(net "P5E_CPU0_P3_TX_DN<11>")
	)
	(segment
		(start 371.10797 -288.178494)
		(end 371.111018 -288.180272)
		(width 0.1143)
		(layer "In11.Cu")
		(net "P5E_CPU0_P3_TX_DN<11>")
	)
	(segment
		(start 386.589524 -317.76035)
		(end 388.457948 -322.270628)
		(width 0.14224)
		(layer "In11.Cu")
		(net "P5E_CPU0_P3_TX_DN<11>")
	)
	(segment
		(start 371.10797 -291.418518)
		(end 371.10797 -291.418772)
		(width 0.1143)
		(layer "In11.Cu")
		(net "P5E_CPU0_P3_TX_DN<11>")
	)
	(segment
		(start 387.109462 -379.5903)
		(end 387.400292 -379.88113)
		(width 0.14224)
		(layer "In11.Cu")
		(net "P5E_CPU0_P3_TX_DN<11>")
	)
	(segment
		(start 371.860064 -296.128694)
		(end 372.104158 -296.372788)
		(width 0.1143)
		(layer "In11.Cu")
		(net "P5E_CPU0_P3_TX_DN<11>")
	)
	(segment
		(start 371.159024 -292.362128)
		(end 371.14607 -292.371526)
		(width 0.1143)
		(layer "In11.Cu")
		(net "P5E_CPU0_P3_TX_DN<11>")
	)
	(segment
		(start 371.148102 -287.51022)
		(end 371.07622 -287.551876)
		(width 0.1143)
		(layer "In11.Cu")
		(net "P5E_CPU0_P3_TX_DN<11>")
	)
	(segment
		(start 371.111018 -294.011604)
		(end 371.07622 -294.03167)
		(width 0.1143)
		(layer "In11.Cu")
		(net "P5E_CPU0_P3_TX_DN<11>")
	)
	(segment
		(start 371.14607 -292.371526)
		(end 371.07622 -292.411658)
		(width 0.1143)
		(layer "In11.Cu")
		(net "P5E_CPU0_P3_TX_DN<11>")
	)
	(segment
		(start 372.58752 -298.712636)
		(end 373.789194 -300.51121)
		(width 0.14224)
		(layer "In11.Cu")
		(net "P5E_CPU0_P3_TX_DN<11>")
	)
	(segment
		(start 371.07622 -284.920436)
		(end 371.10797 -284.938724)
		(width 0.1143)
		(layer "In11.Cu")
		(net "P5E_CPU0_P3_TX_DN<11>")
	)
	(segment
		(start 371.111018 -289.151568)
		(end 371.07622 -289.171634)
		(width 0.1143)
		(layer "In11.Cu")
		(net "P5E_CPU0_P3_TX_DN<11>")
	)
	(segment
		(start 388.457948 -322.270628)
		(end 392.0871 -340.517226)
		(width 0.14224)
		(layer "In11.Cu")
		(net "P5E_CPU0_P3_TX_DN<11>")
	)
	(segment
		(start 371.07622 -293.020242)
		(end 371.10797 -293.03853)
		(width 0.1143)
		(layer "In11.Cu")
		(net "P5E_CPU0_P3_TX_DN<11>")
	)
	(segment
		(start 371.107208 -278.458168)
		(end 371.10797 -278.458676)
		(width 0.1143)
		(layer "In11.Cu")
		(net "P5E_CPU0_P3_TX_DN<11>")
	)
	(segment
		(start 371.10797 -293.03853)
		(end 371.111018 -293.040308)
		(width 0.1143)
		(layer "In11.Cu")
		(net "P5E_CPU0_P3_TX_DN<11>")
	)
	(segment
		(start 371.07622 -291.40023)
		(end 371.10797 -291.418518)
		(width 0.1143)
		(layer "In11.Cu")
		(net "P5E_CPU0_P3_TX_DN<11>")
	)
	(segment
		(start 371.860064 -295.955974)
		(end 371.860064 -296.128694)
		(width 0.1143)
		(layer "In11.Cu")
		(net "P5E_CPU0_P3_TX_DN<11>")
	)
	(segment
		(start 373.789194 -300.51121)
		(end 380.647956 -308.868318)
		(width 0.14224)
		(layer "In11.Cu")
		(net "P5E_CPU0_P3_TX_DN<11>")
	)
	(segment
		(start 371.564916 -280.2509)
		(end 371.564662 -280.251154)
		(width 0.1143)
		(layer "In11.Cu")
		(net "P5E_CPU0_P3_TX_DN<11>")
	)
	(segment
		(start 371.111018 -282.671774)
		(end 371.07622 -282.69184)
		(width 0.1143)
		(layer "In11.Cu")
		(net "P5E_CPU0_P3_TX_DN<11>")
	)
	(segment
		(start 371.54612 -295.45026)
		(end 371.57787 -295.468548)
		(width 0.1143)
		(layer "In11.Cu")
		(net "P5E_CPU0_P3_TX_DN<11>")
	)
	(segment
		(start 371.111018 -285.911798)
		(end 371.07622 -285.931864)
		(width 0.1143)
		(layer "In11.Cu")
		(net "P5E_CPU0_P3_TX_DN<11>")
	)
	(segment
		(start 371.10797 -281.05354)
		(end 371.07622 -281.071828)
		(width 0.1143)
		(layer "In11.Cu")
		(net "P5E_CPU0_P3_TX_DN<11>")
	)
	(segment
		(start 371.402864 -278.953468)
		(end 371.402864 -278.965914)
		(width 0.1143)
		(layer "In11.Cu")
		(net "P5E_CPU0_P3_TX_DN<11>")
	)
	(segment
		(start 370.996972 -278.136096)
		(end 370.927122 -278.205946)
		(width 0.1143)
		(layer "In11.Cu")
		(net "P5E_CPU0_P3_TX_DN<11>")
	)
	(segment
		(start 371.57787 -295.468548)
		(end 371.616224 -295.490646)
		(width 0.1143)
		(layer "In11.Cu")
		(net "P5E_CPU0_P3_TX_DN<11>")
	)
	(segment
		(start 392.0871 -352.702368)
		(end 388.26567 -371.915436)
		(width 0.14224)
		(layer "In11.Cu")
		(net "P5E_CPU0_P3_TX_DN<11>")
	)
	(segment
		(start 372.150386 -296.876724)
		(end 372.150386 -297.272456)
		(width 0.14224)
		(layer "In11.Cu")
		(net "P5E_CPU0_P3_TX_DN<11>")
	)
	(segment
		(start 371.10797 -283.318712)
		(end 371.111018 -283.32049)
		(width 0.1143)
		(layer "In11.Cu")
		(net "P5E_CPU0_P3_TX_DN<11>")
	)
	(segment
		(start 388.26567 -371.915436)
		(end 387.268974 -375.201942)
		(width 0.14224)
		(layer "In11.Cu")
		(net "P5E_CPU0_P3_TX_DN<11>")
	)
	(segment
		(start 371.075204 -288.159444)
		(end 371.10797 -288.178494)
		(width 0.1143)
		(layer "In11.Cu")
		(net "P5E_CPU0_P3_TX_DN<11>")
	)
	(segment
		(start 392.0871 -340.517226)
		(end 392.0871 -352.702368)
		(width 0.14224)
		(layer "In11.Cu")
		(net "P5E_CPU0_P3_TX_DN<11>")
	)
	(segment
		(start 371.57787 -279.268682)
		(end 371.616986 -279.291542)
		(width 0.1143)
		(layer "In11.Cu")
		(net "P5E_CPU0_P3_TX_DN<11>")
	)
	(segment
		(start 372.149878 -296.837862)
		(end 372.149878 -296.86631)
		(width 0.1143)
		(layer "In11.Cu")
		(net "P5E_CPU0_P3_TX_DN<11>")
	)
	(segment
		(start 372.104158 -296.792142)
		(end 372.149878 -296.837862)
		(width 0.1143)
		(layer "In11.Cu")
		(net "P5E_CPU0_P3_TX_DN<11>")
	)
	(segment
		(start 371.294914 -278.136096)
		(end 370.996972 -278.136096)
		(width 0.1143)
		(layer "In11.Cu")
		(net "P5E_CPU0_P3_TX_DN<11>")
	)
	(segment
		(start 371.10797 -291.418772)
		(end 371.14607 -291.440362)
		(width 0.1143)
		(layer "In11.Cu")
		(net "P5E_CPU0_P3_TX_DN<11>")
	)
	(segment
		(start 371.10797 -278.458676)
		(end 371.108986 -278.459184)
		(width 0.1143)
		(layer "In11.Cu")
		(net "P5E_CPU0_P3_TX_DN<11>")
	)
	(segment
		(start 372.149878 -296.876216)
		(end 372.150386 -296.876724)
		(width 0.14224)
		(layer "In11.Cu")
		(net "P5E_CPU0_P3_TX_DN<11>")
	)
	(segment
		(start 371.14607 -291.440362)
		(end 371.159024 -291.44976)
		(width 0.1143)
		(layer "In11.Cu")
		(net "P5E_CPU0_P3_TX_DN<11>")
	)
	(segment
		(start 371.107208 -283.318204)
		(end 371.10797 -283.318712)
		(width 0.1143)
		(layer "In11.Cu")
		(net "P5E_CPU0_P3_TX_DN<11>")
	)
	(arc
		(start 371.378226 -280.585926)
		(mid 371.30865 -280.85087)
		(end 371.117876 -281.047444)
		(width 0.1143)
		(layer "In11.Cu")
		(net "P5E_CPU0_P3_TX_DN<11>")
	)
	(arc
		(start 370.920264 -287.856168)
		(mid 370.961026 -288.026052)
		(end 371.074442 -288.158936)
		(width 0.1143)
		(layer "In11.Cu")
		(net "P5E_CPU0_P3_TX_DN<11>")
	)
	(arc
		(start 371.07622 -285.931864)
		(mid 370.961544 -286.065198)
		(end 370.920264 -286.236156)
		(width 0.1143)
		(layer "In11.Cu")
		(net "P5E_CPU0_P3_TX_DN<11>")
	)
	(arc
		(start 371.616986 -279.291542)
		(mid 371.860203 -279.756108)
		(end 371.616986 -280.220674)
		(width 0.1143)
		(layer "In11.Cu")
		(net "P5E_CPU0_P3_TX_DN<11>")
	)
	(arc
		(start 371.111018 -284.940502)
		(mid 371.390633 -285.42615)
		(end 371.111018 -285.911798)
		(width 0.1143)
		(layer "In11.Cu")
		(net "P5E_CPU0_P3_TX_DN<11>")
	)
	(arc
		(start 371.07622 -292.411658)
		(mid 370.920292 -292.71595)
		(end 371.07622 -293.020242)
		(width 0.1143)
		(layer "In11.Cu")
		(net "P5E_CPU0_P3_TX_DN<11>")
	)
	(arc
		(start 371.111018 -288.180272)
		(mid 371.390633 -288.66592)
		(end 371.111018 -289.151568)
		(width 0.1143)
		(layer "In11.Cu")
		(net "P5E_CPU0_P3_TX_DN<11>")
	)
	(arc
		(start 371.111018 -289.800284)
		(mid 371.390633 -290.285932)
		(end 371.111018 -290.77158)
		(width 0.1143)
		(layer "In11.Cu")
		(net "P5E_CPU0_P3_TX_DN<11>")
	)
	(arc
		(start 371.159024 -291.44976)
		(mid 371.393451 -291.905944)
		(end 371.159024 -292.362128)
		(width 0.1143)
		(layer "In11.Cu")
		(net "P5E_CPU0_P3_TX_DN<11>")
	)
	(arc
		(start 371.390164 -295.145968)
		(mid 371.431419 -295.316939)
		(end 371.54612 -295.45026)
		(width 0.1143)
		(layer "In11.Cu")
		(net "P5E_CPU0_P3_TX_DN<11>")
	)
	(arc
		(start 371.147848 -294.682164)
		(mid 371.325884 -294.881914)
		(end 371.390164 -295.14165)
		(width 0.1143)
		(layer "In11.Cu")
		(net "P5E_CPU0_P3_TX_DN<11>")
	)
	(arc
		(start 371.390164 -287.05048)
		(mid 371.329165 -287.303804)
		(end 371.159532 -287.501584)
		(width 0.1143)
		(layer "In11.Cu")
		(net "P5E_CPU0_P3_TX_DN<11>")
	)
	(arc
		(start 371.402864 -278.965914)
		(mid 371.449755 -279.14078)
		(end 371.57787 -279.268682)
		(width 0.1143)
		(layer "In11.Cu")
		(net "P5E_CPU0_P3_TX_DN<11>")
	)
	(arc
		(start 371.07622 -281.071828)
		(mid 370.920292 -281.37612)
		(end 371.07622 -281.680412)
		(width 0.1143)
		(layer "In11.Cu")
		(net "P5E_CPU0_P3_TX_DN<11>")
	)
	(arc
		(start 371.07622 -282.69184)
		(mid 370.920292 -282.996132)
		(end 371.07622 -283.300424)
		(width 0.1143)
		(layer "In11.Cu")
		(net "P5E_CPU0_P3_TX_DN<11>")
	)
	(arc
		(start 371.122956 -278.467312)
		(mid 371.327901 -278.672974)
		(end 371.402864 -278.953468)
		(width 0.1143)
		(layer "In11.Cu")
		(net "P5E_CPU0_P3_TX_DN<11>")
	)
	(arc
		(start 371.07622 -290.791646)
		(mid 370.920292 -291.095938)
		(end 371.07622 -291.40023)
		(width 0.1143)
		(layer "In11.Cu")
		(net "P5E_CPU0_P3_TX_DN<11>")
	)
	(arc
		(start 371.07622 -289.171634)
		(mid 370.920292 -289.475926)
		(end 371.07622 -289.780218)
		(width 0.1143)
		(layer "In11.Cu")
		(net "P5E_CPU0_P3_TX_DN<11>")
	)
	(arc
		(start 371.564662 -280.251154)
		(mid 371.428182 -280.387879)
		(end 371.378226 -280.574496)
		(width 0.1143)
		(layer "In11.Cu")
		(net "P5E_CPU0_P3_TX_DN<11>")
	)
	(arc
		(start 371.149118 -286.582866)
		(mid 371.326314 -286.784878)
		(end 371.390164 -287.045908)
		(width 0.1143)
		(layer "In11.Cu")
		(net "P5E_CPU0_P3_TX_DN<11>")
	)
	(arc
		(start 371.07622 -284.311852)
		(mid 370.920292 -284.616144)
		(end 371.07622 -284.920436)
		(width 0.1143)
		(layer "In11.Cu")
		(net "P5E_CPU0_P3_TX_DN<11>")
	)
	(arc
		(start 370.920264 -286.236156)
		(mid 370.961026 -286.40604)
		(end 371.074442 -286.538924)
		(width 0.1143)
		(layer "In11.Cu")
		(net "P5E_CPU0_P3_TX_DN<11>")
	)
	(arc
		(start 371.07622 -294.03167)
		(mid 370.920292 -294.335962)
		(end 371.07622 -294.640254)
		(width 0.1143)
		(layer "In11.Cu")
		(net "P5E_CPU0_P3_TX_DN<11>")
	)
	(arc
		(start 371.616224 -295.490646)
		(mid 371.795476 -295.693269)
		(end 371.860064 -295.955974)
		(width 0.1143)
		(layer "In11.Cu")
		(net "P5E_CPU0_P3_TX_DN<11>")
	)
	(arc
		(start 370.927122 -278.205946)
		(mid 370.979171 -278.337465)
		(end 371.07622 -278.440388)
		(width 0.1143)
		(layer "In11.Cu")
		(net "P5E_CPU0_P3_TX_DN<11>")
	)
	(arc
		(start 371.111018 -281.700478)
		(mid 371.390633 -282.186126)
		(end 371.111018 -282.671774)
		(width 0.1143)
		(layer "In11.Cu")
		(net "P5E_CPU0_P3_TX_DN<11>")
	)
	(arc
		(start 371.111018 -293.040308)
		(mid 371.390633 -293.525956)
		(end 371.111018 -294.011604)
		(width 0.1143)
		(layer "In11.Cu")
		(net "P5E_CPU0_P3_TX_DN<11>")
	)
	(arc
		(start 371.111018 -283.32049)
		(mid 371.390633 -283.806138)
		(end 371.111018 -284.291786)
		(width 0.1143)
		(layer "In11.Cu")
		(net "P5E_CPU0_P3_TX_DN<11>")
	)
	(arc
		(start 387.268974 -375.201942)
		(mid 387.14956 -375.733906)
		(end 387.109462 -376.277632)
		(width 0.14224)
		(layer "In11.Cu")
		(net "P5E_CPU0_P3_TX_DN<11>")
	)
	(arc
		(start 371.07622 -287.551876)
		(mid 370.961544 -287.68521)
		(end 370.920264 -287.856168)
		(width 0.1143)
		(layer "In11.Cu")
		(net "P5E_CPU0_P3_TX_DN<11>")
	)
	(segment
		(start 385.698492 -382.34493)
		(end 385.427982 -382.61544)
		(width 0.12954)
		(layer "F.Cu")
		(net "P5E_CPU0_P3_TX_DN<10>")
	)
	(segment
		(start 385.427982 -383.31902)
		(end 385.723892 -383.61493)
		(width 0.12954)
		(layer "F.Cu")
		(net "P5E_CPU0_P3_TX_DN<10>")
	)
	(segment
		(start 385.427982 -382.61544)
		(end 385.427982 -383.31902)
		(width 0.12954)
		(layer "F.Cu")
		(net "P5E_CPU0_P3_TX_DN<10>")
	)
	(segment
		(start 370.828062 -274.630134)
		(end 371.294914 -274.896072)
		(width 0.12954)
		(layer "F.Cu")
		(net "P5E_CPU0_P3_TX_DN<10>")
	)
	(segment
		(start 370.161312 -281.05735)
		(end 370.160296 -281.057858)
		(width 0.1143)
		(layer "In11.Cu")
		(net "P5E_CPU0_P3_TX_DN<10>")
	)
	(segment
		(start 370.168932 -284.939232)
		(end 370.170456 -284.940248)
		(width 0.1143)
		(layer "In11.Cu")
		(net "P5E_CPU0_P3_TX_DN<10>")
	)
	(segment
		(start 370.167154 -278.458168)
		(end 370.167916 -278.458676)
		(width 0.1143)
		(layer "In11.Cu")
		(net "P5E_CPU0_P3_TX_DN<10>")
	)
	(segment
		(start 370.167154 -277.814024)
		(end 370.165884 -277.814786)
		(width 0.1143)
		(layer "In11.Cu")
		(net "P5E_CPU0_P3_TX_DN<10>")
	)
	(segment
		(start 370.167154 -290.773866)
		(end 370.165884 -290.774628)
		(width 0.1143)
		(layer "In11.Cu")
		(net "P5E_CPU0_P3_TX_DN<10>")
	)
	(segment
		(start 370.171472 -276.840696)
		(end 370.207032 -276.861524)
		(width 0.1143)
		(layer "In11.Cu")
		(net "P5E_CPU0_P3_TX_DN<10>")
	)
	(segment
		(start 370.207032 -282.650692)
		(end 370.168932 -282.673044)
		(width 0.1143)
		(layer "In11.Cu")
		(net "P5E_CPU0_P3_TX_DN<10>")
	)
	(segment
		(start 370.161312 -276.197314)
		(end 370.160296 -276.197822)
		(width 0.1143)
		(layer "In11.Cu")
		(net "P5E_CPU0_P3_TX_DN<10>")
	)
	(segment
		(start 370.167916 -294.658542)
		(end 370.168932 -294.65905)
		(width 0.1143)
		(layer "In11.Cu")
		(net "P5E_CPU0_P3_TX_DN<10>")
	)
	(segment
		(start 370.996972 -274.896072)
		(end 370.914168 -274.978876)
		(width 0.1143)
		(layer "In11.Cu")
		(net "P5E_CPU0_P3_TX_DN<10>")
	)
	(segment
		(start 370.160296 -290.777676)
		(end 370.136166 -290.791646)
		(width 0.1143)
		(layer "In11.Cu")
		(net "P5E_CPU0_P3_TX_DN<10>")
	)
	(segment
		(start 370.170456 -281.700224)
		(end 370.171472 -281.700732)
		(width 0.1143)
		(layer "In11.Cu")
		(net "P5E_CPU0_P3_TX_DN<10>")
	)
	(segment
		(start 370.168932 -284.293056)
		(end 370.167916 -284.293564)
		(width 0.1143)
		(layer "In11.Cu")
		(net "P5E_CPU0_P3_TX_DN<10>")
	)
	(segment
		(start 370.136166 -281.680412)
		(end 370.167154 -281.698192)
		(width 0.1143)
		(layer "In11.Cu")
		(net "P5E_CPU0_P3_TX_DN<10>")
	)
	(segment
		(start 370.160296 -281.057858)
		(end 370.136166 -281.071828)
		(width 0.1143)
		(layer "In11.Cu")
		(net "P5E_CPU0_P3_TX_DN<10>")
	)
	(segment
		(start 387.581394 -322.644262)
		(end 391.124694 -340.458806)
		(width 0.14224)
		(layer "In11.Cu")
		(net "P5E_CPU0_P3_TX_DN<10>")
	)
	(segment
		(start 370.16436 -281.055572)
		(end 370.163598 -281.05608)
		(width 0.1143)
		(layer "In11.Cu")
		(net "P5E_CPU0_P3_TX_DN<10>")
	)
	(segment
		(start 370.162074 -276.196806)
		(end 370.161312 -276.197314)
		(width 0.1143)
		(layer "In11.Cu")
		(net "P5E_CPU0_P3_TX_DN<10>")
	)
	(segment
		(start 370.167154 -276.838156)
		(end 370.167916 -276.838664)
		(width 0.1143)
		(layer "In11.Cu")
		(net "P5E_CPU0_P3_TX_DN<10>")
	)
	(segment
		(start 370.167916 -284.293564)
		(end 370.167154 -284.294072)
		(width 0.1143)
		(layer "In11.Cu")
		(net "P5E_CPU0_P3_TX_DN<10>")
	)
	(segment
		(start 370.207032 -281.03068)
		(end 370.168932 -281.053032)
		(width 0.1143)
		(layer "In11.Cu")
		(net "P5E_CPU0_P3_TX_DN<10>")
	)
	(segment
		(start 370.161312 -282.677362)
		(end 370.160296 -282.67787)
		(width 0.1143)
		(layer "In11.Cu")
		(net "P5E_CPU0_P3_TX_DN<10>")
	)
	(segment
		(start 370.606066 -295.45026)
		(end 370.637816 -295.468548)
		(width 0.1143)
		(layer "In11.Cu")
		(net "P5E_CPU0_P3_TX_DN<10>")
	)
	(segment
		(start 370.165884 -281.05481)
		(end 370.16436 -281.055572)
		(width 0.1143)
		(layer "In11.Cu")
		(net "P5E_CPU0_P3_TX_DN<10>")
	)
	(segment
		(start 370.165884 -290.774628)
		(end 370.16436 -290.77539)
		(width 0.1143)
		(layer "In11.Cu")
		(net "P5E_CPU0_P3_TX_DN<10>")
	)
	(segment
		(start 370.167916 -276.193504)
		(end 370.167154 -276.194012)
		(width 0.1143)
		(layer "In11.Cu")
		(net "P5E_CPU0_P3_TX_DN<10>")
	)
	(segment
		(start 371.006878 -296.19956)
		(end 371.006878 -296.538142)
		(width 0.1143)
		(layer "In11.Cu")
		(net "P5E_CPU0_P3_TX_DN<10>")
	)
	(segment
		(start 370.207032 -277.790656)
		(end 370.168932 -277.813008)
		(width 0.1143)
		(layer "In11.Cu")
		(net "P5E_CPU0_P3_TX_DN<10>")
	)
	(segment
		(start 370.167916 -291.418518)
		(end 370.168932 -291.419026)
		(width 0.1143)
		(layer "In11.Cu")
		(net "P5E_CPU0_P3_TX_DN<10>")
	)
	(segment
		(start 370.167916 -276.838664)
		(end 370.168932 -276.839172)
		(width 0.1143)
		(layer "In11.Cu")
		(net "P5E_CPU0_P3_TX_DN<10>")
	)
	(segment
		(start 370.136166 -291.40023)
		(end 370.167916 -291.418518)
		(width 0.1143)
		(layer "In11.Cu")
		(net "P5E_CPU0_P3_TX_DN<10>")
	)
	(segment
		(start 371.052598 -296.583862)
		(end 371.052598 -296.61231)
		(width 0.1143)
		(layer "In11.Cu")
		(net "P5E_CPU0_P3_TX_DN<10>")
	)
	(segment
		(start 370.168932 -293.039038)
		(end 370.170456 -293.040054)
		(width 0.1143)
		(layer "In11.Cu")
		(net "P5E_CPU0_P3_TX_DN<10>")
	)
	(segment
		(start 370.161312 -285.917386)
		(end 370.160296 -285.917894)
		(width 0.1143)
		(layer "In11.Cu")
		(net "P5E_CPU0_P3_TX_DN<10>")
	)
	(segment
		(start 370.162074 -290.77666)
		(end 370.161312 -290.777168)
		(width 0.1143)
		(layer "In11.Cu")
		(net "P5E_CPU0_P3_TX_DN<10>")
	)
	(segment
		(start 370.136166 -284.920436)
		(end 370.167916 -284.938724)
		(width 0.1143)
		(layer "In11.Cu")
		(net "P5E_CPU0_P3_TX_DN<10>")
	)
	(segment
		(start 370.161312 -284.297374)
		(end 370.160296 -284.297882)
		(width 0.1143)
		(layer "In11.Cu")
		(net "P5E_CPU0_P3_TX_DN<10>")
	)
	(segment
		(start 370.168932 -281.699208)
		(end 370.170456 -281.700224)
		(width 0.1143)
		(layer "In11.Cu")
		(net "P5E_CPU0_P3_TX_DN<10>")
	)
	(segment
		(start 370.676932 -280.220674)
		(end 370.637816 -280.243534)
		(width 0.1143)
		(layer "In11.Cu")
		(net "P5E_CPU0_P3_TX_DN<10>")
	)
	(segment
		(start 370.167916 -293.03853)
		(end 370.168932 -293.039038)
		(width 0.1143)
		(layer "In11.Cu")
		(net "P5E_CPU0_P3_TX_DN<10>")
	)
	(segment
		(start 370.163598 -276.196044)
		(end 370.162074 -276.196806)
		(width 0.1143)
		(layer "In11.Cu")
		(net "P5E_CPU0_P3_TX_DN<10>")
	)
	(segment
		(start 370.607336 -279.250902)
		(end 370.637816 -279.268682)
		(width 0.1143)
		(layer "In11.Cu")
		(net "P5E_CPU0_P3_TX_DN<10>")
	)
	(segment
		(start 370.167916 -283.318712)
		(end 370.168932 -283.31922)
		(width 0.1143)
		(layer "In11.Cu")
		(net "P5E_CPU0_P3_TX_DN<10>")
	)
	(segment
		(start 370.16436 -282.675584)
		(end 370.163598 -282.676092)
		(width 0.1143)
		(layer "In11.Cu")
		(net "P5E_CPU0_P3_TX_DN<10>")
	)
	(segment
		(start 370.207032 -292.37051)
		(end 370.168932 -292.392862)
		(width 0.1143)
		(layer "In11.Cu")
		(net "P5E_CPU0_P3_TX_DN<10>")
	)
	(segment
		(start 370.171472 -294.660574)
		(end 370.207032 -294.681402)
		(width 0.1143)
		(layer "In11.Cu")
		(net "P5E_CPU0_P3_TX_DN<10>")
	)
	(segment
		(start 370.16436 -285.915608)
		(end 370.163598 -285.916116)
		(width 0.1143)
		(layer "In11.Cu")
		(net "P5E_CPU0_P3_TX_DN<10>")
	)
	(segment
		(start 370.168932 -283.31922)
		(end 370.170456 -283.320236)
		(width 0.1143)
		(layer "In11.Cu")
		(net "P5E_CPU0_P3_TX_DN<10>")
	)
	(segment
		(start 370.167916 -277.813516)
		(end 370.167154 -277.814024)
		(width 0.1143)
		(layer "In11.Cu")
		(net "P5E_CPU0_P3_TX_DN<10>")
	)
	(segment
		(start 370.160296 -277.817834)
		(end 370.136166 -277.831804)
		(width 0.1143)
		(layer "In11.Cu")
		(net "P5E_CPU0_P3_TX_DN<10>")
	)
	(segment
		(start 370.162074 -285.916878)
		(end 370.161312 -285.917386)
		(width 0.1143)
		(layer "In11.Cu")
		(net "P5E_CPU0_P3_TX_DN<10>")
	)
	(segment
		(start 370.637816 -275.383498)
		(end 370.607336 -275.401278)
		(width 0.1143)
		(layer "In11.Cu")
		(net "P5E_CPU0_P3_TX_DN<10>")
	)
	(segment
		(start 370.207032 -276.170644)
		(end 370.168932 -276.192996)
		(width 0.1143)
		(layer "In11.Cu")
		(net "P5E_CPU0_P3_TX_DN<10>")
	)
	(segment
		(start 370.16436 -290.77539)
		(end 370.163598 -290.775898)
		(width 0.1143)
		(layer "In11.Cu")
		(net "P5E_CPU0_P3_TX_DN<10>")
	)
	(segment
		(start 370.168932 -276.839172)
		(end 370.170456 -276.840188)
		(width 0.1143)
		(layer "In11.Cu")
		(net "P5E_CPU0_P3_TX_DN<10>")
	)
	(segment
		(start 371.759734 -299.207428)
		(end 373.038624 -301.121318)
		(width 0.14224)
		(layer "In11.Cu")
		(net "P5E_CPU0_P3_TX_DN<10>")
	)
	(segment
		(start 370.171472 -278.460708)
		(end 370.207032 -278.481536)
		(width 0.1143)
		(layer "In11.Cu")
		(net "P5E_CPU0_P3_TX_DN<10>")
	)
	(segment
		(start 370.170456 -283.320236)
		(end 370.207032 -283.341572)
		(width 0.1143)
		(layer "In11.Cu")
		(net "P5E_CPU0_P3_TX_DN<10>")
	)
	(segment
		(start 370.160296 -289.157664)
		(end 370.136166 -289.171634)
		(width 0.1143)
		(layer "In11.Cu")
		(net "P5E_CPU0_P3_TX_DN<10>")
	)
	(segment
		(start 370.167916 -294.013382)
		(end 370.167154 -294.01389)
		(width 0.1143)
		(layer "In11.Cu")
		(net "P5E_CPU0_P3_TX_DN<10>")
	)
	(segment
		(start 370.160296 -285.917894)
		(end 370.136166 -285.931864)
		(width 0.1143)
		(layer "In11.Cu")
		(net "P5E_CPU0_P3_TX_DN<10>")
	)
	(segment
		(start 370.171472 -293.040562)
		(end 370.207032 -293.06139)
		(width 0.1143)
		(layer "In11.Cu")
		(net "P5E_CPU0_P3_TX_DN<10>")
	)
	(segment
		(start 371.052598 -296.61231)
		(end 371.052598 -296.876978)
		(width 0.14224)
		(layer "In11.Cu")
		(net "P5E_CPU0_P3_TX_DN<10>")
	)
	(segment
		(start 370.168932 -292.392862)
		(end 370.167916 -292.39337)
		(width 0.1143)
		(layer "In11.Cu")
		(net "P5E_CPU0_P3_TX_DN<10>")
	)
	(segment
		(start 370.167916 -278.458676)
		(end 370.168932 -278.459184)
		(width 0.1143)
		(layer "In11.Cu")
		(net "P5E_CPU0_P3_TX_DN<10>")
	)
	(segment
		(start 370.168932 -289.152838)
		(end 370.167916 -289.153346)
		(width 0.1143)
		(layer "In11.Cu")
		(net "P5E_CPU0_P3_TX_DN<10>")
	)
	(segment
		(start 370.163598 -284.296104)
		(end 370.162074 -284.296866)
		(width 0.1143)
		(layer "In11.Cu")
		(net "P5E_CPU0_P3_TX_DN<10>")
	)
	(segment
		(start 380.002288 -309.60695)
		(end 385.733544 -318.183768)
		(width 0.14224)
		(layer "In11.Cu")
		(net "P5E_CPU0_P3_TX_DN<10>")
	)
	(segment
		(start 370.168932 -294.65905)
		(end 370.170456 -294.660066)
		(width 0.1143)
		(layer "In11.Cu")
		(net "P5E_CPU0_P3_TX_DN<10>")
	)
	(segment
		(start 370.167154 -281.698192)
		(end 370.167916 -281.6987)
		(width 0.1143)
		(layer "In11.Cu")
		(net "P5E_CPU0_P3_TX_DN<10>")
	)
	(segment
		(start 370.161312 -290.777168)
		(end 370.160296 -290.777676)
		(width 0.1143)
		(layer "In11.Cu")
		(net "P5E_CPU0_P3_TX_DN<10>")
	)
	(segment
		(start 370.167154 -294.01389)
		(end 370.165884 -294.014652)
		(width 0.1143)
		(layer "In11.Cu")
		(net "P5E_CPU0_P3_TX_DN<10>")
	)
	(segment
		(start 370.920264 -296.112946)
		(end 371.006878 -296.19956)
		(width 0.1143)
		(layer "In11.Cu")
		(net "P5E_CPU0_P3_TX_DN<10>")
	)
	(segment
		(start 370.163598 -289.155886)
		(end 370.162074 -289.156648)
		(width 0.1143)
		(layer "In11.Cu")
		(net "P5E_CPU0_P3_TX_DN<10>")
	)
	(segment
		(start 370.450364 -295.145968)
		(end 370.45011 -295.145968)
		(width 0.1143)
		(layer "In11.Cu")
		(net "P5E_CPU0_P3_TX_DN<10>")
	)
	(segment
		(start 370.162074 -282.676854)
		(end 370.161312 -282.677362)
		(width 0.1143)
		(layer "In11.Cu")
		(net "P5E_CPU0_P3_TX_DN<10>")
	)
	(segment
		(start 370.167154 -289.153854)
		(end 370.165884 -289.154616)
		(width 0.1143)
		(layer "In11.Cu")
		(net "P5E_CPU0_P3_TX_DN<10>")
	)
	(segment
		(start 389.485124 -360.28757)
		(end 389.439404 -360.461814)
		(width 0.14224)
		(layer "In11.Cu")
		(net "P5E_CPU0_P3_TX_DN<10>")
	)
	(segment
		(start 370.167916 -288.178494)
		(end 370.207032 -288.201354)
		(width 0.1143)
		(layer "In11.Cu")
		(net "P5E_CPU0_P3_TX_DN<10>")
	)
	(segment
		(start 370.638832 -295.469056)
		(end 370.640356 -295.470072)
		(width 0.1143)
		(layer "In11.Cu")
		(net "P5E_CPU0_P3_TX_DN<10>")
	)
	(segment
		(start 370.168932 -278.459184)
		(end 370.170456 -278.4602)
		(width 0.1143)
		(layer "In11.Cu")
		(net "P5E_CPU0_P3_TX_DN<10>")
	)
	(segment
		(start 370.161312 -277.817326)
		(end 370.160296 -277.817834)
		(width 0.1143)
		(layer "In11.Cu")
		(net "P5E_CPU0_P3_TX_DN<10>")
	)
	(segment
		(start 370.207032 -293.990522)
		(end 370.168932 -294.012874)
		(width 0.1143)
		(layer "In11.Cu")
		(net "P5E_CPU0_P3_TX_DN<10>")
	)
	(segment
		(start 370.136166 -289.780218)
		(end 370.167154 -289.797998)
		(width 0.1143)
		(layer "In11.Cu")
		(net "P5E_CPU0_P3_TX_DN<10>")
	)
	(segment
		(start 370.165884 -276.194774)
		(end 370.16436 -276.195536)
		(width 0.1143)
		(layer "In11.Cu")
		(net "P5E_CPU0_P3_TX_DN<10>")
	)
	(segment
		(start 370.171472 -281.700732)
		(end 370.207032 -281.72156)
		(width 0.1143)
		(layer "In11.Cu")
		(net "P5E_CPU0_P3_TX_DN<10>")
	)
	(segment
		(start 370.136166 -293.020242)
		(end 370.167154 -293.038022)
		(width 0.1143)
		(layer "In11.Cu")
		(net "P5E_CPU0_P3_TX_DN<10>")
	)
	(segment
		(start 370.168932 -281.053032)
		(end 370.167916 -281.05354)
		(width 0.1143)
		(layer "In11.Cu")
		(net "P5E_CPU0_P3_TX_DN<10>")
	)
	(segment
		(start 370.162074 -277.816818)
		(end 370.161312 -277.817326)
		(width 0.1143)
		(layer "In11.Cu")
		(net "P5E_CPU0_P3_TX_DN<10>")
	)
	(segment
		(start 370.163598 -290.775898)
		(end 370.162074 -290.77666)
		(width 0.1143)
		(layer "In11.Cu")
		(net "P5E_CPU0_P3_TX_DN<10>")
	)
	(segment
		(start 373.038624 -301.121318)
		(end 376.511566 -305.353212)
		(width 0.14224)
		(layer "In11.Cu")
		(net "P5E_CPU0_P3_TX_DN<10>")
	)
	(segment
		(start 371.052598 -296.876978)
		(end 371.759734 -299.207428)
		(width 0.14224)
		(layer "In11.Cu")
		(net "P5E_CPU0_P3_TX_DN<10>")
	)
	(segment
		(start 370.787168 -295.591738)
		(end 370.786914 -295.591738)
		(width 0.1143)
		(layer "In11.Cu")
		(net "P5E_CPU0_P3_TX_DN<10>")
	)
	(segment
		(start 370.168932 -291.419026)
		(end 370.170456 -291.420042)
		(width 0.1143)
		(layer "In11.Cu")
		(net "P5E_CPU0_P3_TX_DN<10>")
	)
	(segment
		(start 370.170456 -294.660066)
		(end 370.171472 -294.660574)
		(width 0.1143)
		(layer "In11.Cu")
		(net "P5E_CPU0_P3_TX_DN<10>")
	)
	(segment
		(start 370.167154 -282.67406)
		(end 370.165884 -282.674822)
		(width 0.1143)
		(layer "In11.Cu")
		(net "P5E_CPU0_P3_TX_DN<10>")
	)
	(segment
		(start 370.163598 -292.39591)
		(end 370.162074 -292.396672)
		(width 0.1143)
		(layer "In11.Cu")
		(net "P5E_CPU0_P3_TX_DN<10>")
	)
	(segment
		(start 370.207032 -284.270704)
		(end 370.168932 -284.293056)
		(width 0.1143)
		(layer "In11.Cu")
		(net "P5E_CPU0_P3_TX_DN<10>")
	)
	(segment
		(start 371.006878 -296.538142)
		(end 371.052598 -296.583862)
		(width 0.1143)
		(layer "In11.Cu")
		(net "P5E_CPU0_P3_TX_DN<10>")
	)
	(segment
		(start 370.170456 -276.840188)
		(end 370.171472 -276.840696)
		(width 0.1143)
		(layer "In11.Cu")
		(net "P5E_CPU0_P3_TX_DN<10>")
	)
	(segment
		(start 370.167154 -276.194012)
		(end 370.165884 -276.194774)
		(width 0.1143)
		(layer "In11.Cu")
		(net "P5E_CPU0_P3_TX_DN<10>")
	)
	(segment
		(start 370.165884 -285.914846)
		(end 370.16436 -285.915608)
		(width 0.1143)
		(layer "In11.Cu")
		(net "P5E_CPU0_P3_TX_DN<10>")
	)
	(segment
		(start 370.167916 -292.39337)
		(end 370.167154 -292.393878)
		(width 0.1143)
		(layer "In11.Cu")
		(net "P5E_CPU0_P3_TX_DN<10>")
	)
	(segment
		(start 370.160296 -282.67787)
		(end 370.136166 -282.69184)
		(width 0.1143)
		(layer "In11.Cu")
		(net "P5E_CPU0_P3_TX_DN<10>")
	)
	(segment
		(start 370.160296 -276.197822)
		(end 370.136166 -276.211792)
		(width 0.1143)
		(layer "In11.Cu")
		(net "P5E_CPU0_P3_TX_DN<10>")
	)
	(segment
		(start 370.168932 -277.813008)
		(end 370.167916 -277.813516)
		(width 0.1143)
		(layer "In11.Cu")
		(net "P5E_CPU0_P3_TX_DN<10>")
	)
	(segment
		(start 370.165884 -284.294834)
		(end 370.16436 -284.295596)
		(width 0.1143)
		(layer "In11.Cu")
		(net "P5E_CPU0_P3_TX_DN<10>")
	)
	(segment
		(start 370.167916 -281.6987)
		(end 370.168932 -281.699208)
		(width 0.1143)
		(layer "In11.Cu")
		(net "P5E_CPU0_P3_TX_DN<10>")
	)
	(segment
		(start 370.165884 -294.014652)
		(end 370.136166 -294.03167)
		(width 0.1143)
		(layer "In11.Cu")
		(net "P5E_CPU0_P3_TX_DN<10>")
	)
	(segment
		(start 370.163598 -285.916116)
		(end 370.162074 -285.916878)
		(width 0.1143)
		(layer "In11.Cu")
		(net "P5E_CPU0_P3_TX_DN<10>")
	)
	(segment
		(start 370.637816 -279.268682)
		(end 370.676932 -279.291542)
		(width 0.1143)
		(layer "In11.Cu")
		(net "P5E_CPU0_P3_TX_DN<10>")
	)
	(segment
		(start 370.641372 -295.47058)
		(end 370.676932 -295.491408)
		(width 0.1143)
		(layer "In11.Cu")
		(net "P5E_CPU0_P3_TX_DN<10>")
	)
	(segment
		(start 370.167916 -289.153346)
		(end 370.167154 -289.153854)
		(width 0.1143)
		(layer "In11.Cu")
		(net "P5E_CPU0_P3_TX_DN<10>")
	)
	(segment
		(start 391.13714 -340.58479)
		(end 391.13714 -351.910396)
		(width 0.14224)
		(layer "In11.Cu")
		(net "P5E_CPU0_P3_TX_DN<10>")
	)
	(segment
		(start 378.252482 -307.47462)
		(end 380.002288 -309.60695)
		(width 0.14224)
		(layer "In11.Cu")
		(net "P5E_CPU0_P3_TX_DN<10>")
	)
	(segment
		(start 370.167916 -282.673552)
		(end 370.167154 -282.67406)
		(width 0.1143)
		(layer "In11.Cu")
		(net "P5E_CPU0_P3_TX_DN<10>")
	)
	(segment
		(start 370.16436 -277.815548)
		(end 370.163598 -277.816056)
		(width 0.1143)
		(layer "In11.Cu")
		(net "P5E_CPU0_P3_TX_DN<10>")
	)
	(segment
		(start 370.167154 -294.658034)
		(end 370.167916 -294.658542)
		(width 0.1143)
		(layer "In11.Cu")
		(net "P5E_CPU0_P3_TX_DN<10>")
	)
	(segment
		(start 370.204492 -287.512252)
		(end 370.167916 -287.533588)
		(width 0.1143)
		(layer "In11.Cu")
		(net "P5E_CPU0_P3_TX_DN<10>")
	)
	(segment
		(start 370.16436 -284.295596)
		(end 370.163598 -284.296104)
		(width 0.1143)
		(layer "In11.Cu")
		(net "P5E_CPU0_P3_TX_DN<10>")
	)
	(segment
		(start 370.160296 -292.397688)
		(end 370.136166 -292.411658)
		(width 0.1143)
		(layer "In11.Cu")
		(net "P5E_CPU0_P3_TX_DN<10>")
	)
	(segment
		(start 370.134388 -286.538924)
		(end 370.167916 -286.558482)
		(width 0.1143)
		(layer "In11.Cu")
		(net "P5E_CPU0_P3_TX_DN<10>")
	)
	(segment
		(start 370.167916 -287.533588)
		(end 370.136166 -287.551876)
		(width 0.1143)
		(layer "In11.Cu")
		(net "P5E_CPU0_P3_TX_DN<10>")
	)
	(segment
		(start 370.168932 -285.913068)
		(end 370.167916 -285.913576)
		(width 0.1143)
		(layer "In11.Cu")
		(net "P5E_CPU0_P3_TX_DN<10>")
	)
	(segment
		(start 370.170456 -284.940248)
		(end 370.207032 -284.961584)
		(width 0.1143)
		(layer "In11.Cu")
		(net "P5E_CPU0_P3_TX_DN<10>")
	)
	(segment
		(start 370.136166 -294.640254)
		(end 370.167154 -294.658034)
		(width 0.1143)
		(layer "In11.Cu")
		(net "P5E_CPU0_P3_TX_DN<10>")
	)
	(segment
		(start 370.167154 -284.294072)
		(end 370.165884 -284.294834)
		(width 0.1143)
		(layer "In11.Cu")
		(net "P5E_CPU0_P3_TX_DN<10>")
	)
	(segment
		(start 370.170456 -289.80003)
		(end 370.171472 -289.800538)
		(width 0.1143)
		(layer "In11.Cu")
		(net "P5E_CPU0_P3_TX_DN<10>")
	)
	(segment
		(start 370.170456 -293.040054)
		(end 370.171472 -293.040562)
		(width 0.1143)
		(layer "In11.Cu")
		(net "P5E_CPU0_P3_TX_DN<10>")
	)
	(segment
		(start 370.167154 -289.797998)
		(end 370.167916 -289.798506)
		(width 0.1143)
		(layer "In11.Cu")
		(net "P5E_CPU0_P3_TX_DN<10>")
	)
	(segment
		(start 370.167916 -290.773358)
		(end 370.167154 -290.773866)
		(width 0.1143)
		(layer "In11.Cu")
		(net "P5E_CPU0_P3_TX_DN<10>")
	)
	(segment
		(start 370.165884 -277.814786)
		(end 370.16436 -277.815548)
		(width 0.1143)
		(layer "In11.Cu")
		(net "P5E_CPU0_P3_TX_DN<10>")
	)
	(segment
		(start 370.207032 -289.130486)
		(end 370.168932 -289.152838)
		(width 0.1143)
		(layer "In11.Cu")
		(net "P5E_CPU0_P3_TX_DN<10>")
	)
	(segment
		(start 385.454906 -382.101344)
		(end 385.698492 -382.34493)
		(width 0.14224)
		(layer "In11.Cu")
		(net "P5E_CPU0_P3_TX_DN<10>")
	)
	(segment
		(start 370.167154 -292.393878)
		(end 370.165884 -292.39464)
		(width 0.1143)
		(layer "In11.Cu")
		(net "P5E_CPU0_P3_TX_DN<10>")
	)
	(segment
		(start 370.163598 -282.676092)
		(end 370.162074 -282.676854)
		(width 0.1143)
		(layer "In11.Cu")
		(net "P5E_CPU0_P3_TX_DN<10>")
	)
	(segment
		(start 370.136166 -278.440388)
		(end 370.167154 -278.458168)
		(width 0.1143)
		(layer "In11.Cu")
		(net "P5E_CPU0_P3_TX_DN<10>")
	)
	(segment
		(start 370.161312 -289.157156)
		(end 370.160296 -289.157664)
		(width 0.1143)
		(layer "In11.Cu")
		(net "P5E_CPU0_P3_TX_DN<10>")
	)
	(segment
		(start 370.165884 -289.154616)
		(end 370.16436 -289.155378)
		(width 0.1143)
		(layer "In11.Cu")
		(net "P5E_CPU0_P3_TX_DN<10>")
	)
	(segment
		(start 370.167916 -289.798506)
		(end 370.168932 -289.799014)
		(width 0.1143)
		(layer "In11.Cu")
		(net "P5E_CPU0_P3_TX_DN<10>")
	)
	(segment
		(start 370.167916 -285.913576)
		(end 370.167154 -285.914084)
		(width 0.1143)
		(layer "In11.Cu")
		(net "P5E_CPU0_P3_TX_DN<10>")
	)
	(segment
		(start 370.207032 -285.890716)
		(end 370.168932 -285.913068)
		(width 0.1143)
		(layer "In11.Cu")
		(net "P5E_CPU0_P3_TX_DN<10>")
	)
	(segment
		(start 370.160296 -284.297882)
		(end 370.136166 -284.311852)
		(width 0.1143)
		(layer "In11.Cu")
		(net "P5E_CPU0_P3_TX_DN<10>")
	)
	(segment
		(start 370.170456 -291.420042)
		(end 370.207032 -291.441378)
		(width 0.1143)
		(layer "In11.Cu")
		(net "P5E_CPU0_P3_TX_DN<10>")
	)
	(segment
		(start 370.920264 -295.95572)
		(end 370.920264 -296.112946)
		(width 0.1143)
		(layer "In11.Cu")
		(net "P5E_CPU0_P3_TX_DN<10>")
	)
	(segment
		(start 370.134388 -288.158936)
		(end 370.167916 -288.178494)
		(width 0.1143)
		(layer "In11.Cu")
		(net "P5E_CPU0_P3_TX_DN<10>")
	)
	(segment
		(start 370.163598 -277.816056)
		(end 370.162074 -277.816818)
		(width 0.1143)
		(layer "In11.Cu")
		(net "P5E_CPU0_P3_TX_DN<10>")
	)
	(segment
		(start 370.16436 -289.155378)
		(end 370.163598 -289.155886)
		(width 0.1143)
		(layer "In11.Cu")
		(net "P5E_CPU0_P3_TX_DN<10>")
	)
	(segment
		(start 370.167154 -293.038022)
		(end 370.167916 -293.03853)
		(width 0.1143)
		(layer "In11.Cu")
		(net "P5E_CPU0_P3_TX_DN<10>")
	)
	(segment
		(start 370.168932 -289.799014)
		(end 370.170456 -289.80003)
		(width 0.1143)
		(layer "In11.Cu")
		(net "P5E_CPU0_P3_TX_DN<10>")
	)
	(segment
		(start 370.162074 -289.156648)
		(end 370.161312 -289.157156)
		(width 0.1143)
		(layer "In11.Cu")
		(net "P5E_CPU0_P3_TX_DN<10>")
	)
	(segment
		(start 370.167916 -281.05354)
		(end 370.167154 -281.054048)
		(width 0.1143)
		(layer "In11.Cu")
		(net "P5E_CPU0_P3_TX_DN<10>")
	)
	(segment
		(start 370.171472 -289.800538)
		(end 370.207032 -289.821366)
		(width 0.1143)
		(layer "In11.Cu")
		(net "P5E_CPU0_P3_TX_DN<10>")
	)
	(segment
		(start 370.165884 -282.674822)
		(end 370.16436 -282.675584)
		(width 0.1143)
		(layer "In11.Cu")
		(net "P5E_CPU0_P3_TX_DN<10>")
	)
	(segment
		(start 370.168932 -276.192996)
		(end 370.167916 -276.193504)
		(width 0.1143)
		(layer "In11.Cu")
		(net "P5E_CPU0_P3_TX_DN<10>")
	)
	(segment
		(start 370.16436 -292.395402)
		(end 370.163598 -292.39591)
		(width 0.1143)
		(layer "In11.Cu")
		(net "P5E_CPU0_P3_TX_DN<10>")
	)
	(segment
		(start 370.161312 -292.39718)
		(end 370.160296 -292.397688)
		(width 0.1143)
		(layer "In11.Cu")
		(net "P5E_CPU0_P3_TX_DN<10>")
	)
	(segment
		(start 385.407662 -374.324372)
		(end 385.407662 -381.987298)
		(width 0.14224)
		(layer "In11.Cu")
		(net "P5E_CPU0_P3_TX_DN<10>")
	)
	(segment
		(start 370.136166 -276.820376)
		(end 370.167154 -276.838156)
		(width 0.1143)
		(layer "In11.Cu")
		(net "P5E_CPU0_P3_TX_DN<10>")
	)
	(segment
		(start 370.168932 -294.012874)
		(end 370.167916 -294.013382)
		(width 0.1143)
		(layer "In11.Cu")
		(net "P5E_CPU0_P3_TX_DN<10>")
	)
	(segment
		(start 370.162074 -292.396672)
		(end 370.161312 -292.39718)
		(width 0.1143)
		(layer "In11.Cu")
		(net "P5E_CPU0_P3_TX_DN<10>")
	)
	(segment
		(start 370.676932 -275.360638)
		(end 370.637816 -275.383498)
		(width 0.1143)
		(layer "In11.Cu")
		(net "P5E_CPU0_P3_TX_DN<10>")
	)
	(segment
		(start 370.167154 -285.914084)
		(end 370.165884 -285.914846)
		(width 0.1143)
		(layer "In11.Cu")
		(net "P5E_CPU0_P3_TX_DN<10>")
	)
	(segment
		(start 370.207032 -290.750498)
		(end 370.168932 -290.77285)
		(width 0.1143)
		(layer "In11.Cu")
		(net "P5E_CPU0_P3_TX_DN<10>")
	)
	(segment
		(start 370.167916 -286.558482)
		(end 370.207032 -286.581342)
		(width 0.1143)
		(layer "In11.Cu")
		(net "P5E_CPU0_P3_TX_DN<10>")
	)
	(segment
		(start 370.136166 -283.300424)
		(end 370.167916 -283.318712)
		(width 0.1143)
		(layer "In11.Cu")
		(net "P5E_CPU0_P3_TX_DN<10>")
	)
	(segment
		(start 370.168932 -282.673044)
		(end 370.167916 -282.673552)
		(width 0.1143)
		(layer "In11.Cu")
		(net "P5E_CPU0_P3_TX_DN<10>")
	)
	(segment
		(start 378.252482 -307.474366)
		(end 378.252482 -307.47462)
		(width 0.14224)
		(layer "In11.Cu")
		(net "P5E_CPU0_P3_TX_DN<10>")
	)
	(segment
		(start 376.51182 -305.353466)
		(end 378.252482 -307.474366)
		(width 0.14224)
		(layer "In11.Cu")
		(net "P5E_CPU0_P3_TX_DN<10>")
	)
	(segment
		(start 370.165884 -292.39464)
		(end 370.16436 -292.395402)
		(width 0.1143)
		(layer "In11.Cu")
		(net "P5E_CPU0_P3_TX_DN<10>")
	)
	(segment
		(start 370.167916 -284.938724)
		(end 370.168932 -284.939232)
		(width 0.1143)
		(layer "In11.Cu")
		(net "P5E_CPU0_P3_TX_DN<10>")
	)
	(segment
		(start 389.404098 -360.586528)
		(end 385.56692 -373.249698)
		(width 0.14224)
		(layer "In11.Cu")
		(net "P5E_CPU0_P3_TX_DN<10>")
	)
	(segment
		(start 370.637816 -280.243534)
		(end 370.607336 -280.261314)
		(width 0.1143)
		(layer "In11.Cu")
		(net "P5E_CPU0_P3_TX_DN<10>")
	)
	(segment
		(start 385.733544 -318.183768)
		(end 387.581394 -322.644262)
		(width 0.14224)
		(layer "In11.Cu")
		(net "P5E_CPU0_P3_TX_DN<10>")
	)
	(segment
		(start 376.511566 -305.353212)
		(end 376.51182 -305.353466)
		(width 0.14224)
		(layer "In11.Cu")
		(net "P5E_CPU0_P3_TX_DN<10>")
	)
	(segment
		(start 370.637816 -295.468548)
		(end 370.638832 -295.469056)
		(width 0.1143)
		(layer "In11.Cu")
		(net "P5E_CPU0_P3_TX_DN<10>")
	)
	(segment
		(start 370.640356 -295.470072)
		(end 370.641372 -295.47058)
		(width 0.1143)
		(layer "In11.Cu")
		(net "P5E_CPU0_P3_TX_DN<10>")
	)
	(segment
		(start 371.294914 -274.896072)
		(end 370.996972 -274.896072)
		(width 0.1143)
		(layer "In11.Cu")
		(net "P5E_CPU0_P3_TX_DN<10>")
	)
	(segment
		(start 370.170456 -278.4602)
		(end 370.171472 -278.460708)
		(width 0.1143)
		(layer "In11.Cu")
		(net "P5E_CPU0_P3_TX_DN<10>")
	)
	(segment
		(start 370.162074 -284.296866)
		(end 370.161312 -284.297374)
		(width 0.1143)
		(layer "In11.Cu")
		(net "P5E_CPU0_P3_TX_DN<10>")
	)
	(segment
		(start 370.16436 -276.195536)
		(end 370.163598 -276.196044)
		(width 0.1143)
		(layer "In11.Cu")
		(net "P5E_CPU0_P3_TX_DN<10>")
	)
	(segment
		(start 391.11936 -352.09099)
		(end 389.513572 -360.164634)
		(width 0.14224)
		(layer "In11.Cu")
		(net "P5E_CPU0_P3_TX_DN<10>")
	)
	(segment
		(start 370.162074 -281.056842)
		(end 370.161312 -281.05735)
		(width 0.1143)
		(layer "In11.Cu")
		(net "P5E_CPU0_P3_TX_DN<10>")
	)
	(segment
		(start 370.167154 -281.054048)
		(end 370.165884 -281.05481)
		(width 0.1143)
		(layer "In11.Cu")
		(net "P5E_CPU0_P3_TX_DN<10>")
	)
	(segment
		(start 370.163598 -281.05608)
		(end 370.162074 -281.056842)
		(width 0.1143)
		(layer "In11.Cu")
		(net "P5E_CPU0_P3_TX_DN<10>")
	)
	(segment
		(start 370.168932 -290.77285)
		(end 370.167916 -290.773358)
		(width 0.1143)
		(layer "In11.Cu")
		(net "P5E_CPU0_P3_TX_DN<10>")
	)
	(arc
		(start 370.607336 -275.401278)
		(mid 370.491909 -275.534654)
		(end 370.450364 -275.706078)
		(width 0.1143)
		(layer "In11.Cu")
		(net "P5E_CPU0_P3_TX_DN<10>")
	)
	(arc
		(start 370.136166 -290.791646)
		(mid 369.980238 -291.095938)
		(end 370.136166 -291.40023)
		(width 0.1143)
		(layer "In11.Cu")
		(net "P5E_CPU0_P3_TX_DN<10>")
	)
	(arc
		(start 369.98021 -286.236156)
		(mid 370.020972 -286.40604)
		(end 370.134388 -286.538924)
		(width 0.1143)
		(layer "In11.Cu")
		(net "P5E_CPU0_P3_TX_DN<10>")
	)
	(arc
		(start 370.450364 -280.566114)
		(mid 370.385849 -280.828333)
		(end 370.207032 -281.03068)
		(width 0.1143)
		(layer "In11.Cu")
		(net "P5E_CPU0_P3_TX_DN<10>")
	)
	(arc
		(start 370.136166 -276.211792)
		(mid 369.980238 -276.516084)
		(end 370.136166 -276.820376)
		(width 0.1143)
		(layer "In11.Cu")
		(net "P5E_CPU0_P3_TX_DN<10>")
	)
	(arc
		(start 370.207032 -289.821366)
		(mid 370.450359 -290.285932)
		(end 370.207032 -290.750498)
		(width 0.1143)
		(layer "In11.Cu")
		(net "P5E_CPU0_P3_TX_DN<10>")
	)
	(arc
		(start 391.124694 -340.458806)
		(mid 391.134006 -340.521492)
		(end 391.13714 -340.58479)
		(width 0.14224)
		(layer "In11.Cu")
		(net "P5E_CPU0_P3_TX_DN<10>")
	)
	(arc
		(start 370.450364 -278.946102)
		(mid 370.491913 -279.117524)
		(end 370.607336 -279.250902)
		(width 0.1143)
		(layer "In11.Cu")
		(net "P5E_CPU0_P3_TX_DN<10>")
	)
	(arc
		(start 370.450364 -275.706078)
		(mid 370.385849 -275.968297)
		(end 370.207032 -276.170644)
		(width 0.1143)
		(layer "In11.Cu")
		(net "P5E_CPU0_P3_TX_DN<10>")
	)
	(arc
		(start 370.136166 -281.071828)
		(mid 369.980238 -281.37612)
		(end 370.136166 -281.680412)
		(width 0.1143)
		(layer "In11.Cu")
		(net "P5E_CPU0_P3_TX_DN<10>")
	)
	(arc
		(start 370.136166 -282.69184)
		(mid 369.980238 -282.996132)
		(end 370.136166 -283.300424)
		(width 0.1143)
		(layer "In11.Cu")
		(net "P5E_CPU0_P3_TX_DN<10>")
	)
	(arc
		(start 369.98021 -287.856168)
		(mid 370.020972 -288.026052)
		(end 370.134388 -288.158936)
		(width 0.1143)
		(layer "In11.Cu")
		(net "P5E_CPU0_P3_TX_DN<10>")
	)
	(arc
		(start 370.136166 -289.171634)
		(mid 369.980238 -289.475926)
		(end 370.136166 -289.780218)
		(width 0.1143)
		(layer "In11.Cu")
		(net "P5E_CPU0_P3_TX_DN<10>")
	)
	(arc
		(start 370.136166 -294.03167)
		(mid 369.980238 -294.335962)
		(end 370.136166 -294.640254)
		(width 0.1143)
		(layer "In11.Cu")
		(net "P5E_CPU0_P3_TX_DN<10>")
	)
	(arc
		(start 370.136166 -277.831804)
		(mid 369.980238 -278.136096)
		(end 370.136166 -278.440388)
		(width 0.1143)
		(layer "In11.Cu")
		(net "P5E_CPU0_P3_TX_DN<10>")
	)
	(arc
		(start 370.207032 -284.961584)
		(mid 370.450359 -285.42615)
		(end 370.207032 -285.890716)
		(width 0.1143)
		(layer "In11.Cu")
		(net "P5E_CPU0_P3_TX_DN<10>")
	)
	(arc
		(start 370.676932 -279.291542)
		(mid 370.920259 -279.756108)
		(end 370.676932 -280.220674)
		(width 0.1143)
		(layer "In11.Cu")
		(net "P5E_CPU0_P3_TX_DN<10>")
	)
	(arc
		(start 370.676932 -295.491408)
		(mid 370.735369 -295.537926)
		(end 370.787168 -295.591738)
		(width 0.1143)
		(layer "In11.Cu")
		(net "P5E_CPU0_P3_TX_DN<10>")
	)
	(arc
		(start 370.207032 -286.581342)
		(mid 370.385845 -286.783692)
		(end 370.450364 -287.045908)
		(width 0.1143)
		(layer "In11.Cu")
		(net "P5E_CPU0_P3_TX_DN<10>")
	)
	(arc
		(start 370.207032 -291.441378)
		(mid 370.450359 -291.905944)
		(end 370.207032 -292.37051)
		(width 0.1143)
		(layer "In11.Cu")
		(net "P5E_CPU0_P3_TX_DN<10>")
	)
	(arc
		(start 370.450364 -287.045908)
		(mid 370.385128 -287.309499)
		(end 370.204492 -287.512252)
		(width 0.1143)
		(layer "In11.Cu")
		(net "P5E_CPU0_P3_TX_DN<10>")
	)
	(arc
		(start 370.207032 -278.481536)
		(mid 370.385845 -278.683886)
		(end 370.450364 -278.946102)
		(width 0.1143)
		(layer "In11.Cu")
		(net "P5E_CPU0_P3_TX_DN<10>")
	)
	(arc
		(start 370.136166 -292.411658)
		(mid 369.980238 -292.71595)
		(end 370.136166 -293.020242)
		(width 0.1143)
		(layer "In11.Cu")
		(net "P5E_CPU0_P3_TX_DN<10>")
	)
	(arc
		(start 385.407662 -381.987298)
		(mid 385.419939 -382.049021)
		(end 385.454906 -382.101344)
		(width 0.14224)
		(layer "In11.Cu")
		(net "P5E_CPU0_P3_TX_DN<10>")
	)
	(arc
		(start 370.136166 -287.551876)
		(mid 370.02149 -287.68521)
		(end 369.98021 -287.856168)
		(width 0.1143)
		(layer "In11.Cu")
		(net "P5E_CPU0_P3_TX_DN<10>")
	)
	(arc
		(start 370.910358 -275.001736)
		(mid 370.828925 -275.204134)
		(end 370.676932 -275.360638)
		(width 0.1143)
		(layer "In11.Cu")
		(net "P5E_CPU0_P3_TX_DN<10>")
	)
	(arc
		(start 370.786914 -295.591738)
		(mid 370.885778 -295.761934)
		(end 370.920264 -295.95572)
		(width 0.1143)
		(layer "In11.Cu")
		(net "P5E_CPU0_P3_TX_DN<10>")
	)
	(arc
		(start 391.13714 -351.910396)
		(mid 391.132688 -352.00113)
		(end 391.11936 -352.09099)
		(width 0.14224)
		(layer "In11.Cu")
		(net "P5E_CPU0_P3_TX_DN<10>")
	)
	(arc
		(start 385.56692 -373.249698)
		(mid 385.447693 -373.781167)
		(end 385.407662 -374.324372)
		(width 0.14224)
		(layer "In11.Cu")
		(net "P5E_CPU0_P3_TX_DN<10>")
	)
	(arc
		(start 370.914168 -274.978876)
		(mid 370.91238 -274.990325)
		(end 370.910358 -275.001736)
		(width 0.1143)
		(layer "In11.Cu")
		(net "P5E_CPU0_P3_TX_DN<10>")
	)
	(arc
		(start 370.607336 -280.261314)
		(mid 370.491909 -280.39469)
		(end 370.450364 -280.566114)
		(width 0.1143)
		(layer "In11.Cu")
		(net "P5E_CPU0_P3_TX_DN<10>")
	)
	(arc
		(start 389.439404 -360.461814)
		(mid 389.422296 -360.524325)
		(end 389.404098 -360.586528)
		(width 0.14224)
		(layer "In11.Cu")
		(net "P5E_CPU0_P3_TX_DN<10>")
	)
	(arc
		(start 370.207032 -281.72156)
		(mid 370.450359 -282.186126)
		(end 370.207032 -282.650692)
		(width 0.1143)
		(layer "In11.Cu")
		(net "P5E_CPU0_P3_TX_DN<10>")
	)
	(arc
		(start 370.45011 -295.145968)
		(mid 370.491365 -295.316939)
		(end 370.606066 -295.45026)
		(width 0.1143)
		(layer "In11.Cu")
		(net "P5E_CPU0_P3_TX_DN<10>")
	)
	(arc
		(start 389.513572 -360.164634)
		(mid 389.500276 -360.226317)
		(end 389.485124 -360.28757)
		(width 0.14224)
		(layer "In11.Cu")
		(net "P5E_CPU0_P3_TX_DN<10>")
	)
	(arc
		(start 370.207032 -294.681402)
		(mid 370.385845 -294.883752)
		(end 370.450364 -295.145968)
		(width 0.1143)
		(layer "In11.Cu")
		(net "P5E_CPU0_P3_TX_DN<10>")
	)
	(arc
		(start 370.207032 -283.341572)
		(mid 370.450359 -283.806138)
		(end 370.207032 -284.270704)
		(width 0.1143)
		(layer "In11.Cu")
		(net "P5E_CPU0_P3_TX_DN<10>")
	)
	(arc
		(start 370.136166 -285.931864)
		(mid 370.02149 -286.065198)
		(end 369.98021 -286.236156)
		(width 0.1143)
		(layer "In11.Cu")
		(net "P5E_CPU0_P3_TX_DN<10>")
	)
	(arc
		(start 370.136166 -284.311852)
		(mid 369.980238 -284.616144)
		(end 370.136166 -284.920436)
		(width 0.1143)
		(layer "In11.Cu")
		(net "P5E_CPU0_P3_TX_DN<10>")
	)
	(arc
		(start 370.207032 -276.861524)
		(mid 370.450359 -277.32609)
		(end 370.207032 -277.790656)
		(width 0.1143)
		(layer "In11.Cu")
		(net "P5E_CPU0_P3_TX_DN<10>")
	)
	(arc
		(start 370.207032 -293.06139)
		(mid 370.450359 -293.525956)
		(end 370.207032 -293.990522)
		(width 0.1143)
		(layer "In11.Cu")
		(net "P5E_CPU0_P3_TX_DN<10>")
	)
	(arc
		(start 370.207032 -288.201354)
		(mid 370.450359 -288.66592)
		(end 370.207032 -289.130486)
		(width 0.1143)
		(layer "In11.Cu")
		(net "P5E_CPU0_P3_TX_DN<10>")
	)
	(segment
		(start 365.50473 -390.15797)
		(end 365.80064 -389.86206)
		(width 0.12954)
		(layer "F.Cu")
		(net "P5E_CPU0_P3_TX_DN<0>")
	)
	(segment
		(start 364.80115 -390.15797)
		(end 365.50473 -390.15797)
		(width 0.12954)
		(layer "F.Cu")
		(net "P5E_CPU0_P3_TX_DN<0>")
	)
	(segment
		(start 364.53064 -389.88746)
		(end 364.80115 -390.15797)
		(width 0.12954)
		(layer "F.Cu")
		(net "P5E_CPU0_P3_TX_DN<0>")
	)
	(segment
		(start 362.837984 -275.44014)
		(end 363.304836 -275.706078)
		(width 0.12954)
		(layer "F.Cu")
		(net "P5E_CPU0_P3_TX_DN<0>")
	)
	(segment
		(start 360.896408 -295.689528)
		(end 361.00893 -296.447718)
		(width 0.14224)
		(layer "In11.Cu")
		(net "P5E_CPU0_P3_TX_DN<0>")
	)
	(segment
		(start 362.177838 -277.00351)
		(end 362.177076 -277.004018)
		(width 0.1143)
		(layer "In11.Cu")
		(net "P5E_CPU0_P3_TX_DN<0>")
	)
	(segment
		(start 363.889544 -382.269492)
		(end 363.752384 -382.406652)
		(width 0.14224)
		(layer "In11.Cu")
		(net "P5E_CPU0_P3_TX_DN<0>")
	)
	(segment
		(start 363.086396 -385.590034)
		(end 363.223556 -385.727194)
		(width 0.14224)
		(layer "In11.Cu")
		(net "P5E_CPU0_P3_TX_DN<0>")
	)
	(segment
		(start 363.223556 -385.727194)
		(end 363.223556 -386.153914)
		(width 0.14224)
		(layer "In11.Cu")
		(net "P5E_CPU0_P3_TX_DN<0>")
	)
	(segment
		(start 362.164376 -277.01113)
		(end 362.146088 -277.021798)
		(width 0.1143)
		(layer "In11.Cu")
		(net "P5E_CPU0_P3_TX_DN<0>")
	)
	(segment
		(start 363.752384 -381.705612)
		(end 363.889544 -381.842772)
		(width 0.14224)
		(layer "In11.Cu")
		(net "P5E_CPU0_P3_TX_DN<0>")
	)
	(segment
		(start 361.293918 -278.27478)
		(end 360.896408 -278.67229)
		(width 0.14224)
		(layer "In11.Cu")
		(net "P5E_CPU0_P3_TX_DN<0>")
	)
	(segment
		(start 361.313984 -278.254714)
		(end 361.293918 -278.27478)
		(width 0.1143)
		(layer "In11.Cu")
		(net "P5E_CPU0_P3_TX_DN<0>")
	)
	(segment
		(start 362.177076 -277.004018)
		(end 362.175806 -277.00478)
		(width 0.1143)
		(layer "In11.Cu")
		(net "P5E_CPU0_P3_TX_DN<0>")
	)
	(segment
		(start 362.460032 -276.51329)
		(end 362.460032 -276.516084)
		(width 0.1143)
		(layer "In11.Cu")
		(net "P5E_CPU0_P3_TX_DN<0>")
	)
	(segment
		(start 381.663956 -341.622888)
		(end 381.663956 -346.831158)
		(width 0.14224)
		(layer "In11.Cu")
		(net "P5E_CPU0_P3_TX_DN<0>")
	)
	(segment
		(start 363.086396 -387.418834)
		(end 363.086396 -388.107428)
		(width 0.14224)
		(layer "In11.Cu")
		(net "P5E_CPU0_P3_TX_DN<0>")
	)
	(segment
		(start 374.892824 -363.4867)
		(end 366.08131 -373.201692)
		(width 0.14224)
		(layer "In11.Cu")
		(net "P5E_CPU0_P3_TX_DN<0>")
	)
	(segment
		(start 362.17225 -277.006812)
		(end 362.17098 -277.007574)
		(width 0.1143)
		(layer "In11.Cu")
		(net "P5E_CPU0_P3_TX_DN<0>")
	)
	(segment
		(start 361.7468 -277.790656)
		(end 361.707684 -277.813516)
		(width 0.1143)
		(layer "In11.Cu")
		(net "P5E_CPU0_P3_TX_DN<0>")
	)
	(segment
		(start 362.169456 -277.008336)
		(end 362.168186 -277.009098)
		(width 0.1143)
		(layer "In11.Cu")
		(net "P5E_CPU0_P3_TX_DN<0>")
	)
	(segment
		(start 380.962662 -350.595438)
		(end 379.0188 -355.63175)
		(width 0.14224)
		(layer "In11.Cu")
		(net "P5E_CPU0_P3_TX_DN<0>")
	)
	(segment
		(start 363.006894 -275.706078)
		(end 362.92409 -275.788882)
		(width 0.1143)
		(layer "In11.Cu")
		(net "P5E_CPU0_P3_TX_DN<0>")
	)
	(segment
		(start 363.086396 -386.291074)
		(end 363.086396 -386.717794)
		(width 0.14224)
		(layer "In11.Cu")
		(net "P5E_CPU0_P3_TX_DN<0>")
	)
	(segment
		(start 361.00893 -296.447718)
		(end 363.105192 -303.355502)
		(width 0.14224)
		(layer "In11.Cu")
		(net "P5E_CPU0_P3_TX_DN<0>")
	)
	(segment
		(start 367.612676 -310.101488)
		(end 375.246646 -319.402968)
		(width 0.14224)
		(layer "In11.Cu")
		(net "P5E_CPU0_P3_TX_DN<0>")
	)
	(segment
		(start 362.686854 -276.170644)
		(end 362.615988 -276.212046)
		(width 0.1143)
		(layer "In11.Cu")
		(net "P5E_CPU0_P3_TX_DN<0>")
	)
	(segment
		(start 363.223556 -387.281674)
		(end 363.086396 -387.418834)
		(width 0.14224)
		(layer "In11.Cu")
		(net "P5E_CPU0_P3_TX_DN<0>")
	)
	(segment
		(start 361.63123 -277.872444)
		(end 361.313984 -278.18969)
		(width 0.1143)
		(layer "In11.Cu")
		(net "P5E_CPU0_P3_TX_DN<0>")
	)
	(segment
		(start 363.086396 -388.808468)
		(end 363.086396 -389.399526)
		(width 0.14224)
		(layer "In11.Cu")
		(net "P5E_CPU0_P3_TX_DN<0>")
	)
	(segment
		(start 363.752384 -377.246134)
		(end 363.752384 -381.705612)
		(width 0.14224)
		(layer "In11.Cu")
		(net "P5E_CPU0_P3_TX_DN<0>")
	)
	(segment
		(start 362.216192 -276.981412)
		(end 362.17987 -277.00224)
		(width 0.1143)
		(layer "In11.Cu")
		(net "P5E_CPU0_P3_TX_DN<0>")
	)
	(segment
		(start 363.223556 -386.153914)
		(end 363.086396 -386.291074)
		(width 0.14224)
		(layer "In11.Cu")
		(net "P5E_CPU0_P3_TX_DN<0>")
	)
	(segment
		(start 363.889544 -381.842772)
		(end 363.889544 -382.269492)
		(width 0.14224)
		(layer "In11.Cu")
		(net "P5E_CPU0_P3_TX_DN<0>")
	)
	(segment
		(start 360.896408 -278.67229)
		(end 360.896408 -295.689528)
		(width 0.14224)
		(layer "In11.Cu")
		(net "P5E_CPU0_P3_TX_DN<0>")
	)
	(segment
		(start 363.33938 -390.010142)
		(end 363.47019 -390.140952)
		(width 0.14224)
		(layer "In11.Cu")
		(net "P5E_CPU0_P3_TX_DN<0>")
	)
	(segment
		(start 378.53747 -325.905368)
		(end 381.663956 -341.622888)
		(width 0.14224)
		(layer "In11.Cu")
		(net "P5E_CPU0_P3_TX_DN<0>")
	)
	(segment
		(start 362.173012 -277.006304)
		(end 362.17225 -277.006812)
		(width 0.1143)
		(layer "In11.Cu")
		(net "P5E_CPU0_P3_TX_DN<0>")
	)
	(segment
		(start 375.246646 -319.402968)
		(end 376.818144 -321.755008)
		(width 0.14224)
		(layer "In11.Cu")
		(net "P5E_CPU0_P3_TX_DN<0>")
	)
	(segment
		(start 362.17987 -277.00224)
		(end 362.177838 -277.00351)
		(width 0.1143)
		(layer "In11.Cu")
		(net "P5E_CPU0_P3_TX_DN<0>")
	)
	(segment
		(start 363.086396 -388.107428)
		(end 363.223556 -388.244588)
		(width 0.14224)
		(layer "In11.Cu")
		(net "P5E_CPU0_P3_TX_DN<0>")
	)
	(segment
		(start 363.223556 -388.671308)
		(end 363.086396 -388.808468)
		(width 0.14224)
		(layer "In11.Cu")
		(net "P5E_CPU0_P3_TX_DN<0>")
	)
	(segment
		(start 363.223556 -386.854954)
		(end 363.223556 -387.281674)
		(width 0.14224)
		(layer "In11.Cu")
		(net "P5E_CPU0_P3_TX_DN<0>")
	)
	(segment
		(start 362.174282 -277.005542)
		(end 362.173012 -277.006304)
		(width 0.1143)
		(layer "In11.Cu")
		(net "P5E_CPU0_P3_TX_DN<0>")
	)
	(segment
		(start 362.17098 -277.007574)
		(end 362.169456 -277.008336)
		(width 0.1143)
		(layer "In11.Cu")
		(net "P5E_CPU0_P3_TX_DN<0>")
	)
	(segment
		(start 361.313984 -278.18969)
		(end 361.313984 -278.254714)
		(width 0.1143)
		(layer "In11.Cu")
		(net "P5E_CPU0_P3_TX_DN<0>")
	)
	(segment
		(start 364.23981 -390.17829)
		(end 364.53064 -389.88746)
		(width 0.14224)
		(layer "In11.Cu")
		(net "P5E_CPU0_P3_TX_DN<0>")
	)
	(segment
		(start 363.56036 -390.17829)
		(end 364.23981 -390.17829)
		(width 0.14224)
		(layer "In11.Cu")
		(net "P5E_CPU0_P3_TX_DN<0>")
	)
	(segment
		(start 362.175806 -277.00478)
		(end 362.174282 -277.005542)
		(width 0.1143)
		(layer "In11.Cu")
		(net "P5E_CPU0_P3_TX_DN<0>")
	)
	(segment
		(start 363.086396 -384.33121)
		(end 363.086396 -385.590034)
		(width 0.14224)
		(layer "In11.Cu")
		(net "P5E_CPU0_P3_TX_DN<0>")
	)
	(segment
		(start 376.818144 -321.755008)
		(end 378.53747 -325.905368)
		(width 0.14224)
		(layer "In11.Cu")
		(net "P5E_CPU0_P3_TX_DN<0>")
	)
	(segment
		(start 363.223556 -388.244588)
		(end 363.223556 -388.671308)
		(width 0.14224)
		(layer "In11.Cu")
		(net "P5E_CPU0_P3_TX_DN<0>")
	)
	(segment
		(start 363.304836 -275.706078)
		(end 363.006894 -275.706078)
		(width 0.1143)
		(layer "In11.Cu")
		(net "P5E_CPU0_P3_TX_DN<0>")
	)
	(segment
		(start 363.086396 -386.717794)
		(end 363.223556 -386.854954)
		(width 0.14224)
		(layer "In11.Cu")
		(net "P5E_CPU0_P3_TX_DN<0>")
	)
	(segment
		(start 362.165138 -277.010622)
		(end 362.164376 -277.01113)
		(width 0.1143)
		(layer "In11.Cu")
		(net "P5E_CPU0_P3_TX_DN<0>")
	)
	(segment
		(start 363.105192 -303.355502)
		(end 367.612676 -310.101488)
		(width 0.14224)
		(layer "In11.Cu")
		(net "P5E_CPU0_P3_TX_DN<0>")
	)
	(segment
		(start 363.30763 -384.043174)
		(end 363.13364 -384.217164)
		(width 0.14224)
		(layer "In11.Cu")
		(net "P5E_CPU0_P3_TX_DN<0>")
	)
	(segment
		(start 363.752384 -382.406652)
		(end 363.752384 -382.969516)
		(width 0.14224)
		(layer "In11.Cu")
		(net "P5E_CPU0_P3_TX_DN<0>")
	)
	(segment
		(start 362.168186 -277.009098)
		(end 362.165138 -277.010622)
		(width 0.1143)
		(layer "In11.Cu")
		(net "P5E_CPU0_P3_TX_DN<0>")
	)
	(arc
		(start 362.146088 -277.021798)
		(mid 362.031412 -277.155132)
		(end 361.990132 -277.32609)
		(width 0.1143)
		(layer "In11.Cu")
		(net "P5E_CPU0_P3_TX_DN<0>")
	)
	(arc
		(start 361.707684 -277.813516)
		(mid 361.667539 -277.840492)
		(end 361.63123 -277.872444)
		(width 0.1143)
		(layer "In11.Cu")
		(net "P5E_CPU0_P3_TX_DN<0>")
	)
	(arc
		(start 366.08131 -373.201692)
		(mid 364.726029 -375.043123)
		(end 363.772958 -377.12142)
		(width 0.14224)
		(layer "In11.Cu")
		(net "P5E_CPU0_P3_TX_DN<0>")
	)
	(arc
		(start 363.086396 -389.399526)
		(mid 363.152164 -389.729983)
		(end 363.33938 -390.010142)
		(width 0.14224)
		(layer "In11.Cu")
		(net "P5E_CPU0_P3_TX_DN<0>")
	)
	(arc
		(start 381.663956 -346.831158)
		(mid 381.487147 -348.745686)
		(end 380.962662 -350.595438)
		(width 0.14224)
		(layer "In11.Cu")
		(net "P5E_CPU0_P3_TX_DN<0>")
	)
	(arc
		(start 379.0188 -355.63175)
		(mid 377.223633 -359.606081)
		(end 374.995948 -363.355128)
		(width 0.14224)
		(layer "In11.Cu")
		(net "P5E_CPU0_P3_TX_DN<0>")
	)
	(arc
		(start 363.752384 -382.969516)
		(mid 363.636802 -383.550587)
		(end 363.30763 -384.043174)
		(width 0.14224)
		(layer "In11.Cu")
		(net "P5E_CPU0_P3_TX_DN<0>")
	)
	(arc
		(start 363.13364 -384.217164)
		(mid 363.098678 -384.269489)
		(end 363.086396 -384.33121)
		(width 0.14224)
		(layer "In11.Cu")
		(net "P5E_CPU0_P3_TX_DN<0>")
	)
	(arc
		(start 362.615988 -276.212046)
		(mid 362.50136 -276.343699)
		(end 362.460032 -276.51329)
		(width 0.1143)
		(layer "In11.Cu")
		(net "P5E_CPU0_P3_TX_DN<0>")
	)
	(arc
		(start 362.92409 -275.788882)
		(mid 362.922302 -275.800331)
		(end 362.92028 -275.811742)
		(width 0.1143)
		(layer "In11.Cu")
		(net "P5E_CPU0_P3_TX_DN<0>")
	)
	(arc
		(start 374.995948 -363.355128)
		(mid 374.946768 -363.422781)
		(end 374.892824 -363.4867)
		(width 0.14224)
		(layer "In11.Cu")
		(net "P5E_CPU0_P3_TX_DN<0>")
	)
	(arc
		(start 363.772958 -377.12142)
		(mid 363.757535 -377.182931)
		(end 363.752384 -377.246134)
		(width 0.14224)
		(layer "In11.Cu")
		(net "P5E_CPU0_P3_TX_DN<0>")
	)
	(arc
		(start 361.990132 -277.32609)
		(mid 361.925617 -277.588309)
		(end 361.7468 -277.790656)
		(width 0.1143)
		(layer "In11.Cu")
		(net "P5E_CPU0_P3_TX_DN<0>")
	)
	(arc
		(start 363.47019 -390.140952)
		(mid 363.51156 -390.168595)
		(end 363.56036 -390.17829)
		(width 0.14224)
		(layer "In11.Cu")
		(net "P5E_CPU0_P3_TX_DN<0>")
	)
	(arc
		(start 362.92028 -275.811742)
		(mid 362.838847 -276.01414)
		(end 362.686854 -276.170644)
		(width 0.1143)
		(layer "In11.Cu")
		(net "P5E_CPU0_P3_TX_DN<0>")
	)
	(arc
		(start 362.460032 -276.516084)
		(mid 362.395432 -276.778783)
		(end 362.216192 -276.981412)
		(width 0.1143)
		(layer "In11.Cu")
		(net "P5E_CPU0_P3_TX_DN<0>")
	)
	(segment
		(start 380.94158 -391.978896)
		(end 381.018034 -391.902442)
		(width 0.1016)
		(layer "F.Cu")
		(net "P5E_CPU0_P3_TX_C_DP<9>")
	)
	(segment
		(start 381.018034 -391.902442)
		(end 381.018034 -391.784586)
		(width 0.1016)
		(layer "F.Cu")
		(net "P5E_CPU0_P3_TX_C_DP<9>")
	)
	(segment
		(start 380.716028 -391.6172)
		(end 380.716028 -391.88771)
		(width 0.1016)
		(layer "F.Cu")
		(net "P5E_CPU0_P3_TX_C_DP<9>")
	)
	(segment
		(start 381.755142 -379.56998)
		(end 381.755142 -379.909578)
		(width 0.1016)
		(layer "F.Cu")
		(net "P5E_CPU0_P3_TX_C_DP<9>")
	)
	(segment
		(start 383.3622 -383.548382)
		(end 381.1524 -385.758182)
		(width 0.1016)
		(layer "F.Cu")
		(net "P5E_CPU0_P3_TX_C_DP<9>")
	)
	(segment
		(start 380.807214 -391.978896)
		(end 380.94158 -391.978896)
		(width 0.1016)
		(layer "F.Cu")
		(net "P5E_CPU0_P3_TX_C_DP<9>")
	)
	(segment
		(start 381.008636 -391.324592)
		(end 380.716028 -391.6172)
		(width 0.1016)
		(layer "F.Cu")
		(net "P5E_CPU0_P3_TX_C_DP<9>")
	)
	(segment
		(start 382.07061 -380.67107)
		(end 383.233676 -381.834136)
		(width 0.1016)
		(layer "F.Cu")
		(net "P5E_CPU0_P3_TX_C_DP<9>")
	)
	(segment
		(start 381.405892 -379.22073)
		(end 381.755142 -379.56998)
		(width 0.1016)
		(layer "F.Cu")
		(net "P5E_CPU0_P3_TX_C_DP<9>")
	)
	(segment
		(start 380.716028 -391.88771)
		(end 380.807214 -391.978896)
		(width 0.1016)
		(layer "F.Cu")
		(net "P5E_CPU0_P3_TX_C_DP<9>")
	)
	(segment
		(start 381.008636 -386.105908)
		(end 381.008636 -391.324592)
		(width 0.1016)
		(layer "F.Cu")
		(net "P5E_CPU0_P3_TX_C_DP<9>")
	)
	(segment
		(start 383.433574 -382.315466)
		(end 383.433574 -383.376932)
		(width 0.1016)
		(layer "F.Cu")
		(net "P5E_CPU0_P3_TX_C_DP<9>")
	)
	(arc
		(start 383.433574 -383.376932)
		(mid 383.414909 -383.469735)
		(end 383.3622 -383.548382)
		(width 0.1016)
		(layer "F.Cu")
		(net "P5E_CPU0_P3_TX_C_DP<9>")
	)
	(arc
		(start 381.755142 -379.909578)
		(mid 381.837174 -380.321688)
		(end 382.07061 -380.67107)
		(width 0.1016)
		(layer "F.Cu")
		(net "P5E_CPU0_P3_TX_C_DP<9>")
	)
	(arc
		(start 383.233676 -381.834136)
		(mid 383.381537 -382.054913)
		(end 383.433574 -382.315466)
		(width 0.1016)
		(layer "F.Cu")
		(net "P5E_CPU0_P3_TX_C_DP<9>")
	)
	(arc
		(start 381.1524 -385.758182)
		(mid 381.045966 -385.91775)
		(end 381.008636 -386.105908)
		(width 0.1016)
		(layer "F.Cu")
		(net "P5E_CPU0_P3_TX_C_DP<9>")
	)
	(segment
		(start 379.607064 -391.978896)
		(end 379.74143 -391.978896)
		(width 0.1016)
		(layer "F.Cu")
		(net "P5E_CPU0_P3_TX_C_DP<8>")
	)
	(segment
		(start 379.515878 -391.88771)
		(end 379.607064 -391.978896)
		(width 0.1016)
		(layer "F.Cu")
		(net "P5E_CPU0_P3_TX_C_DP<8>")
	)
	(segment
		(start 379.74143 -391.978896)
		(end 379.817884 -391.902442)
		(width 0.1016)
		(layer "F.Cu")
		(net "P5E_CPU0_P3_TX_C_DP<8>")
	)
	(segment
		(start 379.515878 -391.6172)
		(end 379.515878 -391.88771)
		(width 0.1016)
		(layer "F.Cu")
		(net "P5E_CPU0_P3_TX_C_DP<8>")
	)
	(segment
		(start 379.817884 -391.902442)
		(end 379.817884 -391.784586)
		(width 0.1016)
		(layer "F.Cu")
		(net "P5E_CPU0_P3_TX_C_DP<8>")
	)
	(segment
		(start 379.808486 -385.70027)
		(end 379.808486 -391.324592)
		(width 0.1016)
		(layer "F.Cu")
		(net "P5E_CPU0_P3_TX_C_DP<8>")
	)
	(segment
		(start 379.808486 -391.324592)
		(end 379.515878 -391.6172)
		(width 0.1016)
		(layer "F.Cu")
		(net "P5E_CPU0_P3_TX_C_DP<8>")
	)
	(segment
		(start 379.704092 -381.68453)
		(end 380.005844 -381.986282)
		(width 0.1016)
		(layer "F.Cu")
		(net "P5E_CPU0_P3_TX_C_DP<8>")
	)
	(segment
		(start 380.053342 -382.10109)
		(end 380.053342 -384.99923)
		(width 0.1016)
		(layer "F.Cu")
		(net "P5E_CPU0_P3_TX_C_DP<8>")
	)
	(arc
		(start 380.053342 -384.99923)
		(mid 380.029126 -385.14275)
		(end 379.959362 -385.270502)
		(width 0.1016)
		(layer "F.Cu")
		(net "P5E_CPU0_P3_TX_C_DP<8>")
	)
	(arc
		(start 380.005844 -381.986282)
		(mid 380.040986 -382.038971)
		(end 380.053342 -382.10109)
		(width 0.1016)
		(layer "F.Cu")
		(net "P5E_CPU0_P3_TX_C_DP<8>")
	)
	(arc
		(start 379.959362 -385.270502)
		(mid 379.907866 -385.345163)
		(end 379.866144 -385.425696)
		(width 0.1016)
		(layer "F.Cu")
		(net "P5E_CPU0_P3_TX_C_DP<8>")
	)
	(arc
		(start 379.866144 -385.425696)
		(mid 379.82299 -385.559976)
		(end 379.808486 -385.70027)
		(width 0.1016)
		(layer "F.Cu")
		(net "P5E_CPU0_P3_TX_C_DP<8>")
	)
	(segment
		(start 378.407168 -391.978896)
		(end 378.541534 -391.978896)
		(width 0.1016)
		(layer "F.Cu")
		(net "P5E_CPU0_P3_TX_C_DP<7>")
	)
	(segment
		(start 378.351542 -384.56489)
		(end 378.351542 -386.289804)
		(width 0.1016)
		(layer "F.Cu")
		(net "P5E_CPU0_P3_TX_C_DP<7>")
	)
	(segment
		(start 378.315982 -391.88771)
		(end 378.407168 -391.978896)
		(width 0.1016)
		(layer "F.Cu")
		(net "P5E_CPU0_P3_TX_C_DP<7>")
	)
	(segment
		(start 378.617988 -391.902442)
		(end 378.617988 -391.784586)
		(width 0.1016)
		(layer "F.Cu")
		(net "P5E_CPU0_P3_TX_C_DP<7>")
	)
	(segment
		(start 378.541534 -391.978896)
		(end 378.617988 -391.902442)
		(width 0.1016)
		(layer "F.Cu")
		(net "P5E_CPU0_P3_TX_C_DP<7>")
	)
	(segment
		(start 378.002292 -384.14833)
		(end 378.304044 -384.450082)
		(width 0.1016)
		(layer "F.Cu")
		(net "P5E_CPU0_P3_TX_C_DP<7>")
	)
	(segment
		(start 378.59081 -387.046216)
		(end 378.60859 -391.324592)
		(width 0.1016)
		(layer "F.Cu")
		(net "P5E_CPU0_P3_TX_C_DP<7>")
	)
	(segment
		(start 378.60859 -391.324592)
		(end 378.315982 -391.6172)
		(width 0.1016)
		(layer "F.Cu")
		(net "P5E_CPU0_P3_TX_C_DP<7>")
	)
	(segment
		(start 378.315982 -391.6172)
		(end 378.315982 -391.88771)
		(width 0.1016)
		(layer "F.Cu")
		(net "P5E_CPU0_P3_TX_C_DP<7>")
	)
	(arc
		(start 378.304044 -384.450082)
		(mid 378.339186 -384.502771)
		(end 378.351542 -384.56489)
		(width 0.1016)
		(layer "F.Cu")
		(net "P5E_CPU0_P3_TX_C_DP<7>")
	)
	(arc
		(start 378.351542 -386.289804)
		(mid 378.39222 -386.553596)
		(end 378.510292 -386.792978)
		(width 0.1016)
		(layer "F.Cu")
		(net "P5E_CPU0_P3_TX_C_DP<7>")
	)
	(arc
		(start 378.510292 -386.792978)
		(mid 378.569854 -386.913463)
		(end 378.59081 -387.046216)
		(width 0.1016)
		(layer "F.Cu")
		(net "P5E_CPU0_P3_TX_C_DP<7>")
	)
	(segment
		(start 376.809254 -387.115558)
		(end 376.84583 -387.205474)
		(width 0.1016)
		(layer "F.Cu")
		(net "P5E_CPU0_P3_TX_C_DP<6>")
	)
	(segment
		(start 374.598692 -379.22073)
		(end 374.947942 -379.56998)
		(width 0.1016)
		(layer "F.Cu")
		(net "P5E_CPU0_P3_TX_C_DP<6>")
	)
	(segment
		(start 377.207018 -391.978896)
		(end 377.341384 -391.978896)
		(width 0.1016)
		(layer "F.Cu")
		(net "P5E_CPU0_P3_TX_C_DP<6>")
	)
	(segment
		(start 376.667268 -382.268984)
		(end 376.667268 -386.388102)
		(width 0.1016)
		(layer "F.Cu")
		(net "P5E_CPU0_P3_TX_C_DP<6>")
	)
	(segment
		(start 377.341384 -391.978896)
		(end 377.417838 -391.902442)
		(width 0.1016)
		(layer "F.Cu")
		(net "P5E_CPU0_P3_TX_C_DP<6>")
	)
	(segment
		(start 377.115832 -391.6172)
		(end 377.115832 -391.88771)
		(width 0.1016)
		(layer "F.Cu")
		(net "P5E_CPU0_P3_TX_C_DP<6>")
	)
	(segment
		(start 377.40844 -390.076436)
		(end 377.40844 -391.324592)
		(width 0.1016)
		(layer "F.Cu")
		(net "P5E_CPU0_P3_TX_C_DP<6>")
	)
	(segment
		(start 377.115832 -391.88771)
		(end 377.207018 -391.978896)
		(width 0.1016)
		(layer "F.Cu")
		(net "P5E_CPU0_P3_TX_C_DP<6>")
	)
	(segment
		(start 374.947942 -379.56998)
		(end 374.947942 -379.86208)
		(width 0.1016)
		(layer "F.Cu")
		(net "P5E_CPU0_P3_TX_C_DP<6>")
	)
	(segment
		(start 375.274332 -380.649734)
		(end 376.50674 -381.882142)
		(width 0.1016)
		(layer "F.Cu")
		(net "P5E_CPU0_P3_TX_C_DP<6>")
	)
	(segment
		(start 377.417838 -391.902442)
		(end 377.417838 -391.784586)
		(width 0.1016)
		(layer "F.Cu")
		(net "P5E_CPU0_P3_TX_C_DP<6>")
	)
	(segment
		(start 377.40844 -391.324592)
		(end 377.115832 -391.6172)
		(width 0.1016)
		(layer "F.Cu")
		(net "P5E_CPU0_P3_TX_C_DP<6>")
	)
	(arc
		(start 374.947942 -379.86208)
		(mid 375.032811 -380.288367)
		(end 375.274332 -380.649734)
		(width 0.1016)
		(layer "F.Cu")
		(net "P5E_CPU0_P3_TX_C_DP<6>")
	)
	(arc
		(start 376.50674 -381.882142)
		(mid 376.625497 -382.059597)
		(end 376.667268 -382.268984)
		(width 0.1016)
		(layer "F.Cu")
		(net "P5E_CPU0_P3_TX_C_DP<6>")
	)
	(arc
		(start 376.84583 -387.205474)
		(mid 377.266399 -388.613663)
		(end 377.40844 -390.076436)
		(width 0.1016)
		(layer "F.Cu")
		(net "P5E_CPU0_P3_TX_C_DP<6>")
	)
	(arc
		(start 376.667268 -386.388102)
		(mid 376.703073 -386.758698)
		(end 376.809254 -387.115558)
		(width 0.1016)
		(layer "F.Cu")
		(net "P5E_CPU0_P3_TX_C_DP<6>")
	)
	(segment
		(start 376.208544 -391.324592)
		(end 375.915936 -391.6172)
		(width 0.1016)
		(layer "F.Cu")
		(net "P5E_CPU0_P3_TX_C_DP<5>")
	)
	(segment
		(start 372.896892 -381.68453)
		(end 373.246142 -382.03378)
		(width 0.1016)
		(layer "F.Cu")
		(net "P5E_CPU0_P3_TX_C_DP<5>")
	)
	(segment
		(start 376.217942 -391.902442)
		(end 376.217942 -391.784586)
		(width 0.1016)
		(layer "F.Cu")
		(net "P5E_CPU0_P3_TX_C_DP<5>")
	)
	(segment
		(start 373.610124 -384.943858)
		(end 375.540016 -387.830822)
		(width 0.1016)
		(layer "F.Cu")
		(net "P5E_CPU0_P3_TX_C_DP<5>")
	)
	(segment
		(start 376.208544 -390.033764)
		(end 376.208544 -391.324592)
		(width 0.1016)
		(layer "F.Cu")
		(net "P5E_CPU0_P3_TX_C_DP<5>")
	)
	(segment
		(start 373.246142 -382.03378)
		(end 373.246142 -383.744216)
		(width 0.1016)
		(layer "F.Cu")
		(net "P5E_CPU0_P3_TX_C_DP<5>")
	)
	(segment
		(start 375.915936 -391.88771)
		(end 376.007122 -391.978896)
		(width 0.1016)
		(layer "F.Cu")
		(net "P5E_CPU0_P3_TX_C_DP<5>")
	)
	(segment
		(start 376.007122 -391.978896)
		(end 376.141488 -391.978896)
		(width 0.1016)
		(layer "F.Cu")
		(net "P5E_CPU0_P3_TX_C_DP<5>")
	)
	(segment
		(start 375.915936 -391.6172)
		(end 375.915936 -391.88771)
		(width 0.1016)
		(layer "F.Cu")
		(net "P5E_CPU0_P3_TX_C_DP<5>")
	)
	(segment
		(start 376.141488 -391.978896)
		(end 376.217942 -391.902442)
		(width 0.1016)
		(layer "F.Cu")
		(net "P5E_CPU0_P3_TX_C_DP<5>")
	)
	(arc
		(start 373.246142 -383.744216)
		(mid 373.339147 -384.371034)
		(end 373.610124 -384.943858)
		(width 0.1016)
		(layer "F.Cu")
		(net "P5E_CPU0_P3_TX_C_DP<5>")
	)
	(arc
		(start 375.540016 -387.830822)
		(mid 376.037722 -388.882692)
		(end 376.208544 -390.033764)
		(width 0.1016)
		(layer "F.Cu")
		(net "P5E_CPU0_P3_TX_C_DP<5>")
	)
	(segment
		(start 375.008648 -391.324592)
		(end 374.71604 -391.6172)
		(width 0.1016)
		(layer "F.Cu")
		(net "P5E_CPU0_P3_TX_C_DP<4>")
	)
	(segment
		(start 374.807226 -391.978896)
		(end 374.941592 -391.978896)
		(width 0.1016)
		(layer "F.Cu")
		(net "P5E_CPU0_P3_TX_C_DP<4>")
	)
	(segment
		(start 374.71604 -391.88771)
		(end 374.807226 -391.978896)
		(width 0.1016)
		(layer "F.Cu")
		(net "P5E_CPU0_P3_TX_C_DP<4>")
	)
	(segment
		(start 374.941592 -391.978896)
		(end 375.018046 -391.902442)
		(width 0.1016)
		(layer "F.Cu")
		(net "P5E_CPU0_P3_TX_C_DP<4>")
	)
	(segment
		(start 371.78869 -385.303776)
		(end 374.67667 -388.822438)
		(width 0.1016)
		(layer "F.Cu")
		(net "P5E_CPU0_P3_TX_C_DP<4>")
	)
	(segment
		(start 371.544342 -384.71475)
		(end 371.78869 -385.303776)
		(width 0.1016)
		(layer "F.Cu")
		(net "P5E_CPU0_P3_TX_C_DP<4>")
	)
	(segment
		(start 375.008648 -389.954008)
		(end 375.008648 -391.324592)
		(width 0.1016)
		(layer "F.Cu")
		(net "P5E_CPU0_P3_TX_C_DP<4>")
	)
	(segment
		(start 374.71604 -391.6172)
		(end 374.71604 -391.88771)
		(width 0.1016)
		(layer "F.Cu")
		(net "P5E_CPU0_P3_TX_C_DP<4>")
	)
	(segment
		(start 375.018046 -391.902442)
		(end 375.018046 -391.784586)
		(width 0.1016)
		(layer "F.Cu")
		(net "P5E_CPU0_P3_TX_C_DP<4>")
	)
	(segment
		(start 371.195092 -384.14833)
		(end 371.544342 -384.49758)
		(width 0.1016)
		(layer "F.Cu")
		(net "P5E_CPU0_P3_TX_C_DP<4>")
	)
	(segment
		(start 371.544342 -384.49758)
		(end 371.544342 -384.71475)
		(width 0.1016)
		(layer "F.Cu")
		(net "P5E_CPU0_P3_TX_C_DP<4>")
	)
	(arc
		(start 374.67667 -388.822438)
		(mid 374.923799 -389.364422)
		(end 375.008648 -389.954008)
		(width 0.1016)
		(layer "F.Cu")
		(net "P5E_CPU0_P3_TX_C_DP<4>")
	)
	(segment
		(start 373.808498 -389.99668)
		(end 373.808498 -391.324592)
		(width 0.1016)
		(layer "F.Cu")
		(net "P5E_CPU0_P3_TX_C_DP<3>")
	)
	(segment
		(start 373.607076 -391.978896)
		(end 373.741442 -391.978896)
		(width 0.1016)
		(layer "F.Cu")
		(net "P5E_CPU0_P3_TX_C_DP<3>")
	)
	(segment
		(start 371.04701 -386.446014)
		(end 373.690134 -389.666734)
		(width 0.1016)
		(layer "F.Cu")
		(net "P5E_CPU0_P3_TX_C_DP<3>")
	)
	(segment
		(start 369.513104 -381.67691)
		(end 369.774216 -381.938022)
		(width 0.1016)
		(layer "F.Cu")
		(net "P5E_CPU0_P3_TX_C_DP<3>")
	)
	(segment
		(start 373.808498 -391.324592)
		(end 373.51589 -391.6172)
		(width 0.1016)
		(layer "F.Cu")
		(net "P5E_CPU0_P3_TX_C_DP<3>")
	)
	(segment
		(start 369.513104 -381.676656)
		(end 369.513104 -381.67691)
		(width 0.1016)
		(layer "F.Cu")
		(net "P5E_CPU0_P3_TX_C_DP<3>")
	)
	(segment
		(start 368.140742 -379.56998)
		(end 368.140742 -379.95352)
		(width 0.1016)
		(layer "F.Cu")
		(net "P5E_CPU0_P3_TX_C_DP<3>")
	)
	(segment
		(start 367.791492 -379.22073)
		(end 368.140742 -379.56998)
		(width 0.1016)
		(layer "F.Cu")
		(net "P5E_CPU0_P3_TX_C_DP<3>")
	)
	(segment
		(start 370.775992 -385.99364)
		(end 371.04701 -386.446014)
		(width 0.1016)
		(layer "F.Cu")
		(net "P5E_CPU0_P3_TX_C_DP<3>")
	)
	(segment
		(start 373.741442 -391.978896)
		(end 373.817896 -391.902442)
		(width 0.1016)
		(layer "F.Cu")
		(net "P5E_CPU0_P3_TX_C_DP<3>")
	)
	(segment
		(start 373.817896 -391.902442)
		(end 373.817896 -391.784586)
		(width 0.1016)
		(layer "F.Cu")
		(net "P5E_CPU0_P3_TX_C_DP<3>")
	)
	(segment
		(start 369.915948 -383.916682)
		(end 370.775992 -385.99364)
		(width 0.1016)
		(layer "F.Cu")
		(net "P5E_CPU0_P3_TX_C_DP<3>")
	)
	(segment
		(start 368.388392 -380.552198)
		(end 369.513104 -381.676656)
		(width 0.1016)
		(layer "F.Cu")
		(net "P5E_CPU0_P3_TX_C_DP<3>")
	)
	(segment
		(start 373.51589 -391.88771)
		(end 373.607076 -391.978896)
		(width 0.1016)
		(layer "F.Cu")
		(net "P5E_CPU0_P3_TX_C_DP<3>")
	)
	(segment
		(start 373.51589 -391.6172)
		(end 373.51589 -391.88771)
		(width 0.1016)
		(layer "F.Cu")
		(net "P5E_CPU0_P3_TX_C_DP<3>")
	)
	(segment
		(start 369.850416 -382.120902)
		(end 369.850416 -383.585466)
		(width 0.1016)
		(layer "F.Cu")
		(net "P5E_CPU0_P3_TX_C_DP<3>")
	)
	(arc
		(start 369.850416 -383.585466)
		(mid 369.866884 -383.754298)
		(end 369.915948 -383.916682)
		(width 0.1016)
		(layer "F.Cu")
		(net "P5E_CPU0_P3_TX_C_DP<3>")
	)
	(arc
		(start 368.140742 -379.95352)
		(mid 368.204999 -380.277503)
		(end 368.388392 -380.552198)
		(width 0.1016)
		(layer "F.Cu")
		(net "P5E_CPU0_P3_TX_C_DP<3>")
	)
	(arc
		(start 373.690134 -389.666734)
		(mid 373.777991 -389.821418)
		(end 373.808498 -389.99668)
		(width 0.1016)
		(layer "F.Cu")
		(net "P5E_CPU0_P3_TX_C_DP<3>")
	)
	(arc
		(start 369.774216 -381.938022)
		(mid 369.830554 -382.021869)
		(end 369.850416 -382.120902)
		(width 0.1016)
		(layer "F.Cu")
		(net "P5E_CPU0_P3_TX_C_DP<3>")
	)
	(segment
		(start 367.165636 -383.6162)
		(end 368.080544 -383.995168)
		(width 0.1016)
		(layer "F.Cu")
		(net "P5E_CPU0_P3_TX_C_DP<2>")
	)
	(segment
		(start 369.810792 -386.807456)
		(end 369.953286 -387.044692)
		(width 0.1016)
		(layer "F.Cu")
		(net "P5E_CPU0_P3_TX_C_DP<2>")
	)
	(segment
		(start 372.315994 -391.88771)
		(end 372.40718 -391.978896)
		(width 0.1016)
		(layer "F.Cu")
		(net "P5E_CPU0_P3_TX_C_DP<2>")
	)
	(segment
		(start 372.40718 -391.978896)
		(end 372.541546 -391.978896)
		(width 0.1016)
		(layer "F.Cu")
		(net "P5E_CPU0_P3_TX_C_DP<2>")
	)
	(segment
		(start 368.131852 -384.029458)
		(end 368.931444 -384.82905)
		(width 0.1016)
		(layer "F.Cu")
		(net "P5E_CPU0_P3_TX_C_DP<2>")
	)
	(segment
		(start 366.438942 -382.03378)
		(end 366.438942 -382.664208)
		(width 0.1016)
		(layer "F.Cu")
		(net "P5E_CPU0_P3_TX_C_DP<2>")
	)
	(segment
		(start 366.089692 -381.68453)
		(end 366.438942 -382.03378)
		(width 0.1016)
		(layer "F.Cu")
		(net "P5E_CPU0_P3_TX_C_DP<2>")
	)
	(segment
		(start 366.696752 -383.286762)
		(end 366.744758 -383.334768)
		(width 0.1016)
		(layer "F.Cu")
		(net "P5E_CPU0_P3_TX_C_DP<2>")
	)
	(segment
		(start 370.231162 -387.439154)
		(end 372.437406 -390.124696)
		(width 0.1016)
		(layer "F.Cu")
		(net "P5E_CPU0_P3_TX_C_DP<2>")
	)
	(segment
		(start 372.608602 -391.324592)
		(end 372.315994 -391.6172)
		(width 0.1016)
		(layer "F.Cu")
		(net "P5E_CPU0_P3_TX_C_DP<2>")
	)
	(segment
		(start 372.618 -391.902442)
		(end 372.618 -391.784586)
		(width 0.1016)
		(layer "F.Cu")
		(net "P5E_CPU0_P3_TX_C_DP<2>")
	)
	(segment
		(start 372.608602 -390.60247)
		(end 372.608602 -391.324592)
		(width 0.1016)
		(layer "F.Cu")
		(net "P5E_CPU0_P3_TX_C_DP<2>")
	)
	(segment
		(start 372.315994 -391.6172)
		(end 372.315994 -391.88771)
		(width 0.1016)
		(layer "F.Cu")
		(net "P5E_CPU0_P3_TX_C_DP<2>")
	)
	(segment
		(start 369.088924 -385.064508)
		(end 369.810792 -386.807456)
		(width 0.1016)
		(layer "F.Cu")
		(net "P5E_CPU0_P3_TX_C_DP<2>")
	)
	(segment
		(start 372.541546 -391.978896)
		(end 372.618 -391.902442)
		(width 0.1016)
		(layer "F.Cu")
		(net "P5E_CPU0_P3_TX_C_DP<2>")
	)
	(arc
		(start 366.438942 -382.664208)
		(mid 366.505941 -383.001123)
		(end 366.696752 -383.286762)
		(width 0.1016)
		(layer "F.Cu")
		(net "P5E_CPU0_P3_TX_C_DP<2>")
	)
	(arc
		(start 372.437406 -390.124696)
		(mid 372.564458 -390.348722)
		(end 372.608602 -390.60247)
		(width 0.1016)
		(layer "F.Cu")
		(net "P5E_CPU0_P3_TX_C_DP<2>")
	)
	(arc
		(start 369.953286 -387.044692)
		(mid 370.084978 -387.247028)
		(end 370.231162 -387.439154)
		(width 0.1016)
		(layer "F.Cu")
		(net "P5E_CPU0_P3_TX_C_DP<2>")
	)
	(arc
		(start 366.744758 -383.334768)
		(mid 366.941342 -383.496205)
		(end 367.165636 -383.6162)
		(width 0.1016)
		(layer "F.Cu")
		(net "P5E_CPU0_P3_TX_C_DP<2>")
	)
	(arc
		(start 368.931444 -384.82905)
		(mid 369.021806 -384.939008)
		(end 369.088924 -385.064508)
		(width 0.1016)
		(layer "F.Cu")
		(net "P5E_CPU0_P3_TX_C_DP<2>")
	)
	(arc
		(start 368.080544 -383.995168)
		(mid 368.107892 -384.009779)
		(end 368.131852 -384.029458)
		(width 0.1016)
		(layer "F.Cu")
		(net "P5E_CPU0_P3_TX_C_DP<2>")
	)
	(segment
		(start 369.718844 -388.493254)
		(end 370.32946 -389.104124)
		(width 0.1016)
		(layer "F.Cu")
		(net "P5E_CPU0_P3_TX_C_DP<1>")
	)
	(segment
		(start 371.624352 -391.51941)
		(end 371.717824 -391.612882)
		(width 0.1016)
		(layer "F.Cu")
		(net "P5E_CPU0_P3_TX_C_DP<1>")
	)
	(segment
		(start 366.33404 -384.32486)
		(end 366.661446 -384.652266)
		(width 0.1016)
		(layer "F.Cu")
		(net "P5E_CPU0_P3_TX_C_DP<1>")
	)
	(segment
		(start 369.190524 -387.736588)
		(end 369.484148 -388.176008)
		(width 0.1016)
		(layer "F.Cu")
		(net "P5E_CPU0_P3_TX_C_DP<1>")
	)
	(segment
		(start 371.624352 -390.893808)
		(end 371.624352 -391.51941)
		(width 0.1016)
		(layer "F.Cu")
		(net "P5E_CPU0_P3_TX_C_DP<1>")
	)
	(segment
		(start 371.501162 -390.59612)
		(end 371.624352 -390.893808)
		(width 0.1016)
		(layer "F.Cu")
		(net "P5E_CPU0_P3_TX_C_DP<1>")
	)
	(segment
		(start 368.24539 -385.598416)
		(end 369.033044 -387.500876)
		(width 0.1016)
		(layer "F.Cu")
		(net "P5E_CPU0_P3_TX_C_DP<1>")
	)
	(segment
		(start 370.32946 -389.104124)
		(end 371.35816 -390.358122)
		(width 0.1016)
		(layer "F.Cu")
		(net "P5E_CPU0_P3_TX_C_DP<1>")
	)
	(segment
		(start 369.19027 -387.736588)
		(end 369.190524 -387.736588)
		(width 0.1016)
		(layer "F.Cu")
		(net "P5E_CPU0_P3_TX_C_DP<1>")
	)
	(segment
		(start 366.661446 -384.652266)
		(end 366.789208 -384.652266)
		(width 0.1016)
		(layer "F.Cu")
		(net "P5E_CPU0_P3_TX_C_DP<1>")
	)
	(segment
		(start 369.484148 -388.176262)
		(end 369.59794 -388.346442)
		(width 0.1016)
		(layer "F.Cu")
		(net "P5E_CPU0_P3_TX_C_DP<1>")
	)
	(segment
		(start 367.779046 -385.061968)
		(end 368.105182 -385.388104)
		(width 0.1016)
		(layer "F.Cu")
		(net "P5E_CPU0_P3_TX_C_DP<1>")
	)
	(segment
		(start 371.717824 -391.612882)
		(end 371.717824 -392.30427)
		(width 0.1016)
		(layer "F.Cu")
		(net "P5E_CPU0_P3_TX_C_DP<1>")
	)
	(segment
		(start 369.033044 -387.500876)
		(end 369.19027 -387.736588)
		(width 0.1016)
		(layer "F.Cu")
		(net "P5E_CPU0_P3_TX_C_DP<1>")
	)
	(segment
		(start 371.35816 -390.358122)
		(end 371.501162 -390.59612)
		(width 0.1016)
		(layer "F.Cu")
		(net "P5E_CPU0_P3_TX_C_DP<1>")
	)
	(segment
		(start 369.484148 -388.176008)
		(end 369.484148 -388.176262)
		(width 0.1016)
		(layer "F.Cu")
		(net "P5E_CPU0_P3_TX_C_DP<1>")
	)
	(arc
		(start 369.59794 -388.346442)
		(mid 369.654786 -388.422818)
		(end 369.718844 -388.493254)
		(width 0.1016)
		(layer "F.Cu")
		(net "P5E_CPU0_P3_TX_C_DP<1>")
	)
	(arc
		(start 368.105182 -385.388104)
		(mid 368.185654 -385.486348)
		(end 368.24539 -385.598416)
		(width 0.1016)
		(layer "F.Cu")
		(net "P5E_CPU0_P3_TX_C_DP<1>")
	)
	(arc
		(start 366.789208 -384.652266)
		(mid 367.324896 -384.758634)
		(end 367.779046 -385.061968)
		(width 0.1016)
		(layer "F.Cu")
		(net "P5E_CPU0_P3_TX_C_DP<1>")
	)
	(segment
		(start 388.3025 -391.700004)
		(end 388.217918 -391.784586)
		(width 0.1016)
		(layer "F.Cu")
		(net "P5E_CPU0_P3_TX_C_DP<15>")
	)
	(segment
		(start 391.23493 -388.202678)
		(end 390.520174 -388.202678)
		(width 0.1016)
		(layer "F.Cu")
		(net "P5E_CPU0_P3_TX_C_DP<15>")
	)
	(segment
		(start 388.3025 -391.492232)
		(end 388.3025 -391.700004)
		(width 0.1016)
		(layer "F.Cu")
		(net "P5E_CPU0_P3_TX_C_DP<15>")
	)
	(segment
		(start 388.20852 -390.587484)
		(end 388.20852 -391.398252)
		(width 0.1016)
		(layer "F.Cu")
		(net "P5E_CPU0_P3_TX_C_DP<15>")
	)
	(segment
		(start 392.574272 -387.853428)
		(end 392.225022 -388.202678)
		(width 0.1016)
		(layer "F.Cu")
		(net "P5E_CPU0_P3_TX_C_DP<15>")
	)
	(segment
		(start 391.76325 -388.202678)
		(end 391.65149 -388.090918)
		(width 0.1016)
		(layer "F.Cu")
		(net "P5E_CPU0_P3_TX_C_DP<15>")
	)
	(segment
		(start 392.225022 -388.202678)
		(end 391.76325 -388.202678)
		(width 0.1016)
		(layer "F.Cu")
		(net "P5E_CPU0_P3_TX_C_DP<15>")
	)
	(segment
		(start 391.34669 -388.090918)
		(end 391.23493 -388.202678)
		(width 0.1016)
		(layer "F.Cu")
		(net "P5E_CPU0_P3_TX_C_DP<15>")
	)
	(segment
		(start 388.20852 -391.398252)
		(end 388.3025 -391.492232)
		(width 0.1016)
		(layer "F.Cu")
		(net "P5E_CPU0_P3_TX_C_DP<15>")
	)
	(segment
		(start 390.266174 -388.30758)
		(end 388.365238 -390.208516)
		(width 0.1016)
		(layer "F.Cu")
		(net "P5E_CPU0_P3_TX_C_DP<15>")
	)
	(segment
		(start 391.65149 -388.090918)
		(end 391.34669 -388.090918)
		(width 0.1016)
		(layer "F.Cu")
		(net "P5E_CPU0_P3_TX_C_DP<15>")
	)
	(arc
		(start 388.365238 -390.208516)
		(mid 388.249173 -390.382404)
		(end 388.20852 -390.587484)
		(width 0.1016)
		(layer "F.Cu")
		(net "P5E_CPU0_P3_TX_C_DP<15>")
	)
	(arc
		(start 390.520174 -388.202678)
		(mid 390.382721 -388.229832)
		(end 390.266174 -388.30758)
		(width 0.1016)
		(layer "F.Cu")
		(net "P5E_CPU0_P3_TX_C_DP<15>")
	)
	(segment
		(start 392.229086 -385.10083)
		(end 391.914634 -385.10083)
		(width 0.1016)
		(layer "F.Cu")
		(net "P5E_CPU0_P3_TX_C_DP<14>")
	)
	(segment
		(start 391.914634 -385.10083)
		(end 387.42239 -389.593074)
		(width 0.1016)
		(layer "F.Cu")
		(net "P5E_CPU0_P3_TX_C_DP<14>")
	)
	(segment
		(start 392.574272 -385.364228)
		(end 392.368786 -385.158742)
		(width 0.1016)
		(layer "F.Cu")
		(net "P5E_CPU0_P3_TX_C_DP<14>")
	)
	(segment
		(start 392.368786 -385.158742)
		(end 392.229086 -385.10083)
		(width 0.1016)
		(layer "F.Cu")
		(net "P5E_CPU0_P3_TX_C_DP<14>")
	)
	(segment
		(start 387.224524 -391.30859)
		(end 387.318504 -391.40257)
		(width 0.1016)
		(layer "F.Cu")
		(net "P5E_CPU0_P3_TX_C_DP<14>")
	)
	(segment
		(start 387.224524 -390.070848)
		(end 387.224524 -391.30859)
		(width 0.1016)
		(layer "F.Cu")
		(net "P5E_CPU0_P3_TX_C_DP<14>")
	)
	(segment
		(start 387.318504 -392.303762)
		(end 387.317996 -392.30427)
		(width 0.1016)
		(layer "F.Cu")
		(net "P5E_CPU0_P3_TX_C_DP<14>")
	)
	(segment
		(start 387.318504 -391.40257)
		(end 387.318504 -392.303762)
		(width 0.1016)
		(layer "F.Cu")
		(net "P5E_CPU0_P3_TX_C_DP<14>")
	)
	(segment
		(start 387.224778 -390.071102)
		(end 387.224524 -390.070848)
		(width 0.1016)
		(layer "F.Cu")
		(net "P5E_CPU0_P3_TX_C_DP<14>")
	)
	(arc
		(start 387.42239 -389.593074)
		(mid 387.276064 -389.812439)
		(end 387.224778 -390.071102)
		(width 0.1016)
		(layer "F.Cu")
		(net "P5E_CPU0_P3_TX_C_DP<14>")
	)
	(segment
		(start 391.965942 -379.56998)
		(end 391.965942 -379.909578)
		(width 0.1016)
		(layer "F.Cu")
		(net "P5E_CPU0_P3_TX_C_DP<13>")
	)
	(segment
		(start 393.467336 -382.93548)
		(end 393.041886 -383.36093)
		(width 0.1016)
		(layer "F.Cu")
		(net "P5E_CPU0_P3_TX_C_DP<13>")
	)
	(segment
		(start 385.607052 -391.978896)
		(end 385.741418 -391.978896)
		(width 0.1016)
		(layer "F.Cu")
		(net "P5E_CPU0_P3_TX_C_DP<13>")
	)
	(segment
		(start 385.515866 -391.6172)
		(end 385.515866 -391.88771)
		(width 0.1016)
		(layer "F.Cu")
		(net "P5E_CPU0_P3_TX_C_DP<13>")
	)
	(segment
		(start 393.640056 -382.248156)
		(end 393.640056 -382.518666)
		(width 0.1016)
		(layer "F.Cu")
		(net "P5E_CPU0_P3_TX_C_DP<13>")
	)
	(segment
		(start 392.280902 -380.670816)
		(end 393.485624 -381.875538)
		(width 0.1016)
		(layer "F.Cu")
		(net "P5E_CPU0_P3_TX_C_DP<13>")
	)
	(segment
		(start 392.756898 -383.47904)
		(end 391.876026 -383.47904)
		(width 0.1016)
		(layer "F.Cu")
		(net "P5E_CPU0_P3_TX_C_DP<13>")
	)
	(segment
		(start 391.305542 -383.715006)
		(end 385.908804 -389.111744)
		(width 0.1016)
		(layer "F.Cu")
		(net "P5E_CPU0_P3_TX_C_DP<13>")
	)
	(segment
		(start 385.741418 -391.978896)
		(end 385.817872 -391.902442)
		(width 0.1016)
		(layer "F.Cu")
		(net "P5E_CPU0_P3_TX_C_DP<13>")
	)
	(segment
		(start 385.808474 -391.324592)
		(end 385.515866 -391.6172)
		(width 0.1016)
		(layer "F.Cu")
		(net "P5E_CPU0_P3_TX_C_DP<13>")
	)
	(segment
		(start 391.616692 -379.22073)
		(end 391.965942 -379.56998)
		(width 0.1016)
		(layer "F.Cu")
		(net "P5E_CPU0_P3_TX_C_DP<13>")
	)
	(segment
		(start 385.817872 -391.902442)
		(end 385.817872 -391.784586)
		(width 0.1016)
		(layer "F.Cu")
		(net "P5E_CPU0_P3_TX_C_DP<13>")
	)
	(segment
		(start 385.515866 -391.88771)
		(end 385.607052 -391.978896)
		(width 0.1016)
		(layer "F.Cu")
		(net "P5E_CPU0_P3_TX_C_DP<13>")
	)
	(segment
		(start 385.808474 -389.354822)
		(end 385.808474 -391.324592)
		(width 0.1016)
		(layer "F.Cu")
		(net "P5E_CPU0_P3_TX_C_DP<13>")
	)
	(arc
		(start 391.965942 -379.909578)
		(mid 392.047682 -380.321543)
		(end 392.280902 -380.670816)
		(width 0.1016)
		(layer "F.Cu")
		(net "P5E_CPU0_P3_TX_C_DP<13>")
	)
	(arc
		(start 393.640056 -382.518666)
		(mid 393.595165 -382.744257)
		(end 393.467336 -382.93548)
		(width 0.1016)
		(layer "F.Cu")
		(net "P5E_CPU0_P3_TX_C_DP<13>")
	)
	(arc
		(start 393.485624 -381.875538)
		(mid 393.599909 -382.046482)
		(end 393.640056 -382.248156)
		(width 0.1016)
		(layer "F.Cu")
		(net "P5E_CPU0_P3_TX_C_DP<13>")
	)
	(arc
		(start 385.908804 -389.111744)
		(mid 385.834505 -389.223313)
		(end 385.808474 -389.354822)
		(width 0.1016)
		(layer "F.Cu")
		(net "P5E_CPU0_P3_TX_C_DP<13>")
	)
	(arc
		(start 391.876026 -383.47904)
		(mid 391.567289 -383.540246)
		(end 391.305542 -383.715006)
		(width 0.1016)
		(layer "F.Cu")
		(net "P5E_CPU0_P3_TX_C_DP<13>")
	)
	(arc
		(start 393.041886 -383.36093)
		(mid 392.911147 -383.44835)
		(end 392.756898 -383.47904)
		(width 0.1016)
		(layer "F.Cu")
		(net "P5E_CPU0_P3_TX_C_DP<13>")
	)
	(segment
		(start 390.272016 -382.039368)
		(end 390.272016 -382.944878)
		(width 0.1016)
		(layer "F.Cu")
		(net "P5E_CPU0_P3_TX_C_DP<12>")
	)
	(segment
		(start 388.814564 -380.529338)
		(end 390.234678 -381.949198)
		(width 0.1016)
		(layer "F.Cu")
		(net "P5E_CPU0_P3_TX_C_DP<12>")
	)
	(segment
		(start 384.407156 -391.978896)
		(end 384.541522 -391.978896)
		(width 0.1016)
		(layer "F.Cu")
		(net "P5E_CPU0_P3_TX_C_DP<12>")
	)
	(segment
		(start 384.608578 -389.116062)
		(end 384.608578 -391.324592)
		(width 0.1016)
		(layer "F.Cu")
		(net "P5E_CPU0_P3_TX_C_DP<12>")
	)
	(segment
		(start 384.541522 -391.978896)
		(end 384.617976 -391.902442)
		(width 0.1016)
		(layer "F.Cu")
		(net "P5E_CPU0_P3_TX_C_DP<12>")
	)
	(segment
		(start 384.617976 -391.902442)
		(end 384.617976 -391.784586)
		(width 0.1016)
		(layer "F.Cu")
		(net "P5E_CPU0_P3_TX_C_DP<12>")
	)
	(segment
		(start 390.199372 -383.119376)
		(end 384.895598 -388.42315)
		(width 0.1016)
		(layer "F.Cu")
		(net "P5E_CPU0_P3_TX_C_DP<12>")
	)
	(segment
		(start 384.31597 -391.88771)
		(end 384.407156 -391.978896)
		(width 0.1016)
		(layer "F.Cu")
		(net "P5E_CPU0_P3_TX_C_DP<12>")
	)
	(segment
		(start 384.608578 -391.324592)
		(end 384.31597 -391.6172)
		(width 0.1016)
		(layer "F.Cu")
		(net "P5E_CPU0_P3_TX_C_DP<12>")
	)
	(segment
		(start 388.213092 -379.22073)
		(end 388.562342 -379.56998)
		(width 0.1016)
		(layer "F.Cu")
		(net "P5E_CPU0_P3_TX_C_DP<12>")
	)
	(segment
		(start 388.562342 -379.56998)
		(end 388.562342 -379.9205)
		(width 0.1016)
		(layer "F.Cu")
		(net "P5E_CPU0_P3_TX_C_DP<12>")
	)
	(segment
		(start 384.31597 -391.6172)
		(end 384.31597 -391.88771)
		(width 0.1016)
		(layer "F.Cu")
		(net "P5E_CPU0_P3_TX_C_DP<12>")
	)
	(arc
		(start 390.234678 -381.949198)
		(mid 390.262321 -381.990568)
		(end 390.272016 -382.039368)
		(width 0.1016)
		(layer "F.Cu")
		(net "P5E_CPU0_P3_TX_C_DP<12>")
	)
	(arc
		(start 388.562342 -379.9205)
		(mid 388.627886 -380.250013)
		(end 388.814564 -380.529338)
		(width 0.1016)
		(layer "F.Cu")
		(net "P5E_CPU0_P3_TX_C_DP<12>")
	)
	(arc
		(start 384.895598 -388.42315)
		(mid 384.683177 -388.741061)
		(end 384.608578 -389.116062)
		(width 0.1016)
		(layer "F.Cu")
		(net "P5E_CPU0_P3_TX_C_DP<12>")
	)
	(arc
		(start 390.272016 -382.944878)
		(mid 390.253022 -383.039333)
		(end 390.199372 -383.119376)
		(width 0.1016)
		(layer "F.Cu")
		(net "P5E_CPU0_P3_TX_C_DP<12>")
	)
	(segment
		(start 383.207006 -391.978896)
		(end 383.341372 -391.978896)
		(width 0.1016)
		(layer "F.Cu")
		(net "P5E_CPU0_P3_TX_C_DP<11>")
	)
	(segment
		(start 383.11582 -391.88771)
		(end 383.207006 -391.978896)
		(width 0.1016)
		(layer "F.Cu")
		(net "P5E_CPU0_P3_TX_C_DP<11>")
	)
	(segment
		(start 383.417826 -391.902442)
		(end 383.417826 -391.784586)
		(width 0.1016)
		(layer "F.Cu")
		(net "P5E_CPU0_P3_TX_C_DP<11>")
	)
	(segment
		(start 383.11582 -391.6172)
		(end 383.11582 -391.88771)
		(width 0.1016)
		(layer "F.Cu")
		(net "P5E_CPU0_P3_TX_C_DP<11>")
	)
	(segment
		(start 383.408428 -388.266178)
		(end 383.408428 -391.324592)
		(width 0.1016)
		(layer "F.Cu")
		(net "P5E_CPU0_P3_TX_C_DP<11>")
	)
	(segment
		(start 386.511292 -381.68453)
		(end 386.860542 -382.03378)
		(width 0.1016)
		(layer "F.Cu")
		(net "P5E_CPU0_P3_TX_C_DP<11>")
	)
	(segment
		(start 383.341372 -391.978896)
		(end 383.417826 -391.902442)
		(width 0.1016)
		(layer "F.Cu")
		(net "P5E_CPU0_P3_TX_C_DP<11>")
	)
	(segment
		(start 386.823204 -384.708654)
		(end 383.507742 -388.024116)
		(width 0.1016)
		(layer "F.Cu")
		(net "P5E_CPU0_P3_TX_C_DP<11>")
	)
	(segment
		(start 383.408428 -391.324592)
		(end 383.11582 -391.6172)
		(width 0.1016)
		(layer "F.Cu")
		(net "P5E_CPU0_P3_TX_C_DP<11>")
	)
	(segment
		(start 386.860542 -382.03378)
		(end 386.860542 -384.618484)
		(width 0.1016)
		(layer "F.Cu")
		(net "P5E_CPU0_P3_TX_C_DP<11>")
	)
	(arc
		(start 383.507742 -388.024116)
		(mid 383.434181 -388.135332)
		(end 383.408428 -388.266178)
		(width 0.1016)
		(layer "F.Cu")
		(net "P5E_CPU0_P3_TX_C_DP<11>")
	)
	(arc
		(start 386.860542 -384.618484)
		(mid 386.850836 -384.667279)
		(end 386.823204 -384.708654)
		(width 0.1016)
		(layer "F.Cu")
		(net "P5E_CPU0_P3_TX_C_DP<11>")
	)
	(segment
		(start 381.915924 -391.88771)
		(end 382.00711 -391.978896)
		(width 0.1016)
		(layer "F.Cu")
		(net "P5E_CPU0_P3_TX_C_DP<10>")
	)
	(segment
		(start 382.00711 -391.978896)
		(end 382.141476 -391.978896)
		(width 0.1016)
		(layer "F.Cu")
		(net "P5E_CPU0_P3_TX_C_DP<10>")
	)
	(segment
		(start 382.208532 -391.324592)
		(end 381.915924 -391.6172)
		(width 0.1016)
		(layer "F.Cu")
		(net "P5E_CPU0_P3_TX_C_DP<10>")
	)
	(segment
		(start 383.54127 -385.811522)
		(end 382.487932 -386.86486)
		(width 0.1016)
		(layer "F.Cu")
		(net "P5E_CPU0_P3_TX_C_DP<10>")
	)
	(segment
		(start 385.120388 -384.674872)
		(end 384.138932 -385.656328)
		(width 0.1016)
		(layer "F.Cu")
		(net "P5E_CPU0_P3_TX_C_DP<10>")
	)
	(segment
		(start 382.208532 -387.286754)
		(end 382.208532 -391.324592)
		(width 0.1016)
		(layer "F.Cu")
		(net "P5E_CPU0_P3_TX_C_DP<10>")
	)
	(segment
		(start 384.809492 -384.14833)
		(end 385.157726 -384.496564)
		(width 0.1016)
		(layer "F.Cu")
		(net "P5E_CPU0_P3_TX_C_DP<10>")
	)
	(segment
		(start 382.141476 -391.978896)
		(end 382.21793 -391.902442)
		(width 0.1016)
		(layer "F.Cu")
		(net "P5E_CPU0_P3_TX_C_DP<10>")
	)
	(segment
		(start 382.487932 -386.86486)
		(end 382.487678 -386.86486)
		(width 0.1016)
		(layer "F.Cu")
		(net "P5E_CPU0_P3_TX_C_DP<10>")
	)
	(segment
		(start 384.024632 -385.703572)
		(end 383.801874 -385.703572)
		(width 0.1016)
		(layer "F.Cu")
		(net "P5E_CPU0_P3_TX_C_DP<10>")
	)
	(segment
		(start 381.915924 -391.6172)
		(end 381.915924 -391.88771)
		(width 0.1016)
		(layer "F.Cu")
		(net "P5E_CPU0_P3_TX_C_DP<10>")
	)
	(segment
		(start 382.487678 -386.86486)
		(end 382.308862 -387.043676)
		(width 0.1016)
		(layer "F.Cu")
		(net "P5E_CPU0_P3_TX_C_DP<10>")
	)
	(segment
		(start 382.21793 -391.902442)
		(end 382.21793 -391.784586)
		(width 0.1016)
		(layer "F.Cu")
		(net "P5E_CPU0_P3_TX_C_DP<10>")
	)
	(segment
		(start 385.157726 -384.496564)
		(end 385.157726 -384.584702)
		(width 0.1016)
		(layer "F.Cu")
		(net "P5E_CPU0_P3_TX_C_DP<10>")
	)
	(arc
		(start 382.308862 -387.043676)
		(mid 382.234563 -387.155245)
		(end 382.208532 -387.286754)
		(width 0.1016)
		(layer "F.Cu")
		(net "P5E_CPU0_P3_TX_C_DP<10>")
	)
	(arc
		(start 383.801874 -385.703572)
		(mid 383.660834 -385.731627)
		(end 383.54127 -385.811522)
		(width 0.1016)
		(layer "F.Cu")
		(net "P5E_CPU0_P3_TX_C_DP<10>")
	)
	(arc
		(start 384.138932 -385.656328)
		(mid 384.086477 -385.691315)
		(end 384.024632 -385.703572)
		(width 0.1016)
		(layer "F.Cu")
		(net "P5E_CPU0_P3_TX_C_DP<10>")
	)
	(arc
		(start 385.157726 -384.584702)
		(mid 385.14802 -384.633497)
		(end 385.120388 -384.674872)
		(width 0.1016)
		(layer "F.Cu")
		(net "P5E_CPU0_P3_TX_C_DP<10>")
	)
	(segment
		(start 366.989868 -390.425432)
		(end 367.101628 -390.537192)
		(width 0.1016)
		(layer "F.Cu")
		(net "P5E_CPU0_P3_TX_C_DP<0>")
	)
	(segment
		(start 368.351308 -390.425432)
		(end 368.85245 -390.425432)
		(width 0.1016)
		(layer "F.Cu")
		(net "P5E_CPU0_P3_TX_C_DP<0>")
	)
	(segment
		(start 369.050316 -390.464802)
		(end 369.655598 -390.714738)
		(width 0.1016)
		(layer "F.Cu")
		(net "P5E_CPU0_P3_TX_C_DP<0>")
	)
	(segment
		(start 370.208556 -391.199624)
		(end 370.208556 -391.324592)
		(width 0.1016)
		(layer "F.Cu")
		(net "P5E_CPU0_P3_TX_C_DP<0>")
	)
	(segment
		(start 368.239548 -390.537192)
		(end 368.351308 -390.425432)
		(width 0.1016)
		(layer "F.Cu")
		(net "P5E_CPU0_P3_TX_C_DP<0>")
	)
	(segment
		(start 370.217954 -391.902442)
		(end 370.217954 -391.784586)
		(width 0.1016)
		(layer "F.Cu")
		(net "P5E_CPU0_P3_TX_C_DP<0>")
	)
	(segment
		(start 369.915948 -391.6172)
		(end 369.915948 -391.88771)
		(width 0.1016)
		(layer "F.Cu")
		(net "P5E_CPU0_P3_TX_C_DP<0>")
	)
	(segment
		(start 370.208556 -391.324592)
		(end 369.915948 -391.6172)
		(width 0.1016)
		(layer "F.Cu")
		(net "P5E_CPU0_P3_TX_C_DP<0>")
	)
	(segment
		(start 366.33404 -390.77646)
		(end 366.685068 -390.425432)
		(width 0.1016)
		(layer "F.Cu")
		(net "P5E_CPU0_P3_TX_C_DP<0>")
	)
	(segment
		(start 370.1415 -391.978896)
		(end 370.217954 -391.902442)
		(width 0.1016)
		(layer "F.Cu")
		(net "P5E_CPU0_P3_TX_C_DP<0>")
	)
	(segment
		(start 367.822988 -390.425432)
		(end 367.934748 -390.537192)
		(width 0.1016)
		(layer "F.Cu")
		(net "P5E_CPU0_P3_TX_C_DP<0>")
	)
	(segment
		(start 367.518188 -390.425432)
		(end 367.822988 -390.425432)
		(width 0.1016)
		(layer "F.Cu")
		(net "P5E_CPU0_P3_TX_C_DP<0>")
	)
	(segment
		(start 367.406428 -390.537192)
		(end 367.518188 -390.425432)
		(width 0.1016)
		(layer "F.Cu")
		(net "P5E_CPU0_P3_TX_C_DP<0>")
	)
	(segment
		(start 367.934748 -390.537192)
		(end 368.239548 -390.537192)
		(width 0.1016)
		(layer "F.Cu")
		(net "P5E_CPU0_P3_TX_C_DP<0>")
	)
	(segment
		(start 369.915948 -391.88771)
		(end 370.007134 -391.978896)
		(width 0.1016)
		(layer "F.Cu")
		(net "P5E_CPU0_P3_TX_C_DP<0>")
	)
	(segment
		(start 367.101628 -390.537192)
		(end 367.406428 -390.537192)
		(width 0.1016)
		(layer "F.Cu")
		(net "P5E_CPU0_P3_TX_C_DP<0>")
	)
	(segment
		(start 369.86718 -390.85647)
		(end 370.208556 -391.199624)
		(width 0.1016)
		(layer "F.Cu")
		(net "P5E_CPU0_P3_TX_C_DP<0>")
	)
	(segment
		(start 370.007134 -391.978896)
		(end 370.1415 -391.978896)
		(width 0.1016)
		(layer "F.Cu")
		(net "P5E_CPU0_P3_TX_C_DP<0>")
	)
	(segment
		(start 366.685068 -390.425432)
		(end 366.989868 -390.425432)
		(width 0.1016)
		(layer "F.Cu")
		(net "P5E_CPU0_P3_TX_C_DP<0>")
	)
	(arc
		(start 368.85245 -390.425432)
		(mid 368.953315 -390.435399)
		(end 369.050316 -390.464802)
		(width 0.1016)
		(layer "F.Cu")
		(net "P5E_CPU0_P3_TX_C_DP<0>")
	)
	(arc
		(start 369.655598 -390.714738)
		(mid 369.768429 -390.775093)
		(end 369.86718 -390.85647)
		(width 0.1016)
		(layer "F.Cu")
		(net "P5E_CPU0_P3_TX_C_DP<0>")
	)
	(segment
		(start 382.223518 -380.518162)
		(end 383.386584 -381.681228)
		(width 0.1016)
		(layer "F.Cu")
		(net "P5E_CPU0_P3_TX_C_DN<9>")
	)
	(segment
		(start 382.654302 -384.720084)
		(end 382.438402 -384.935984)
		(width 0.1016)
		(layer "F.Cu")
		(net "P5E_CPU0_P3_TX_C_DN<9>")
	)
	(segment
		(start 381.971042 -379.56998)
		(end 381.971042 -379.909324)
		(width 0.1016)
		(layer "F.Cu")
		(net "P5E_CPU0_P3_TX_C_DN<9>")
	)
	(segment
		(start 382.280414 -384.935984)
		(end 381.305308 -385.91109)
		(width 0.1016)
		(layer "F.Cu")
		(net "P5E_CPU0_P3_TX_C_DN<9>")
	)
	(segment
		(start 381.224536 -386.105908)
		(end 381.224536 -391.51941)
		(width 0.1016)
		(layer "F.Cu")
		(net "P5E_CPU0_P3_TX_C_DN<9>")
	)
	(segment
		(start 382.320292 -379.22073)
		(end 381.971042 -379.56998)
		(width 0.1016)
		(layer "F.Cu")
		(net "P5E_CPU0_P3_TX_C_DN<9>")
	)
	(segment
		(start 381.318008 -391.612882)
		(end 381.318008 -392.30427)
		(width 0.1016)
		(layer "F.Cu")
		(net "P5E_CPU0_P3_TX_C_DN<9>")
	)
	(segment
		(start 381.224536 -391.51941)
		(end 381.318008 -391.612882)
		(width 0.1016)
		(layer "F.Cu")
		(net "P5E_CPU0_P3_TX_C_DN<9>")
	)
	(segment
		(start 383.515108 -383.70129)
		(end 382.654302 -384.562096)
		(width 0.1016)
		(layer "F.Cu")
		(net "P5E_CPU0_P3_TX_C_DN<9>")
	)
	(segment
		(start 382.438402 -384.935984)
		(end 382.280414 -384.935984)
		(width 0.1016)
		(layer "F.Cu")
		(net "P5E_CPU0_P3_TX_C_DN<9>")
	)
	(segment
		(start 383.649474 -382.315466)
		(end 383.649474 -383.376932)
		(width 0.1016)
		(layer "F.Cu")
		(net "P5E_CPU0_P3_TX_C_DN<9>")
	)
	(segment
		(start 382.654302 -384.562096)
		(end 382.654302 -384.720084)
		(width 0.1016)
		(layer "F.Cu")
		(net "P5E_CPU0_P3_TX_C_DN<9>")
	)
	(arc
		(start 383.386584 -381.681228)
		(mid 383.581101 -381.972204)
		(end 383.649474 -382.315466)
		(width 0.1016)
		(layer "F.Cu")
		(net "P5E_CPU0_P3_TX_C_DN<9>")
	)
	(arc
		(start 381.971042 -379.909324)
		(mid 382.036772 -380.238827)
		(end 382.223518 -380.518162)
		(width 0.1016)
		(layer "F.Cu")
		(net "P5E_CPU0_P3_TX_C_DN<9>")
	)
	(arc
		(start 383.649474 -383.376932)
		(mid 383.614556 -383.552478)
		(end 383.515108 -383.70129)
		(width 0.1016)
		(layer "F.Cu")
		(net "P5E_CPU0_P3_TX_C_DN<9>")
	)
	(arc
		(start 381.305308 -385.91109)
		(mid 381.24553 -386.000459)
		(end 381.224536 -386.105908)
		(width 0.1016)
		(layer "F.Cu")
		(net "P5E_CPU0_P3_TX_C_DN<9>")
	)
	(segment
		(start 380.269242 -382.10109)
		(end 380.269242 -383.22504)
		(width 0.1016)
		(layer "F.Cu")
		(net "P5E_CPU0_P3_TX_C_DN<8>")
	)
	(segment
		(start 380.618492 -381.68453)
		(end 380.31674 -381.986282)
		(width 0.1016)
		(layer "F.Cu")
		(net "P5E_CPU0_P3_TX_C_DN<8>")
	)
	(segment
		(start 380.381002 -383.3368)
		(end 380.381002 -383.6416)
		(width 0.1016)
		(layer "F.Cu")
		(net "P5E_CPU0_P3_TX_C_DN<8>")
	)
	(segment
		(start 380.381002 -383.6416)
		(end 380.269242 -383.75336)
		(width 0.1016)
		(layer "F.Cu")
		(net "P5E_CPU0_P3_TX_C_DN<8>")
	)
	(segment
		(start 380.269242 -383.75336)
		(end 380.269242 -384.998976)
		(width 0.1016)
		(layer "F.Cu")
		(net "P5E_CPU0_P3_TX_C_DN<8>")
	)
	(segment
		(start 380.024386 -391.51941)
		(end 380.117858 -391.612882)
		(width 0.1016)
		(layer "F.Cu")
		(net "P5E_CPU0_P3_TX_C_DN<8>")
	)
	(segment
		(start 380.024386 -385.700016)
		(end 380.024386 -391.51941)
		(width 0.1016)
		(layer "F.Cu")
		(net "P5E_CPU0_P3_TX_C_DN<8>")
	)
	(segment
		(start 380.269242 -383.22504)
		(end 380.381002 -383.3368)
		(width 0.1016)
		(layer "F.Cu")
		(net "P5E_CPU0_P3_TX_C_DN<8>")
	)
	(segment
		(start 380.117858 -391.612882)
		(end 380.117858 -392.30427)
		(width 0.1016)
		(layer "F.Cu")
		(net "P5E_CPU0_P3_TX_C_DN<8>")
	)
	(arc
		(start 380.063756 -385.512818)
		(mid 380.034292 -385.604364)
		(end 380.024386 -385.700016)
		(width 0.1016)
		(layer "F.Cu")
		(net "P5E_CPU0_P3_TX_C_DN<8>")
	)
	(arc
		(start 380.269242 -384.998976)
		(mid 380.233245 -385.213347)
		(end 380.129034 -385.404106)
		(width 0.1016)
		(layer "F.Cu")
		(net "P5E_CPU0_P3_TX_C_DN<8>")
	)
	(arc
		(start 380.129034 -385.404106)
		(mid 380.09297 -385.456405)
		(end 380.063756 -385.512818)
		(width 0.1016)
		(layer "F.Cu")
		(net "P5E_CPU0_P3_TX_C_DN<8>")
	)
	(arc
		(start 380.31674 -381.986282)
		(mid 380.281598 -382.038971)
		(end 380.269242 -382.10109)
		(width 0.1016)
		(layer "F.Cu")
		(net "P5E_CPU0_P3_TX_C_DN<8>")
	)
	(segment
		(start 378.82449 -391.51941)
		(end 378.917962 -391.612882)
		(width 0.1016)
		(layer "F.Cu")
		(net "P5E_CPU0_P3_TX_C_DN<7>")
	)
	(segment
		(start 378.80671 -387.0452)
		(end 378.82449 -391.32383)
		(width 0.1016)
		(layer "F.Cu")
		(net "P5E_CPU0_P3_TX_C_DN<7>")
	)
	(segment
		(start 378.82449 -391.32383)
		(end 378.82449 -391.51941)
		(width 0.1016)
		(layer "F.Cu")
		(net "P5E_CPU0_P3_TX_C_DN<7>")
	)
	(segment
		(start 378.567442 -384.564636)
		(end 378.567442 -385.45643)
		(width 0.1016)
		(layer "F.Cu")
		(net "P5E_CPU0_P3_TX_C_DN<7>")
	)
	(segment
		(start 378.567442 -385.45643)
		(end 378.679202 -385.56819)
		(width 0.1016)
		(layer "F.Cu")
		(net "P5E_CPU0_P3_TX_C_DN<7>")
	)
	(segment
		(start 378.567442 -385.98475)
		(end 378.567442 -386.28955)
		(width 0.1016)
		(layer "F.Cu")
		(net "P5E_CPU0_P3_TX_C_DN<7>")
	)
	(segment
		(start 378.679202 -385.56819)
		(end 378.679202 -385.87299)
		(width 0.1016)
		(layer "F.Cu")
		(net "P5E_CPU0_P3_TX_C_DN<7>")
	)
	(segment
		(start 378.917962 -391.612882)
		(end 378.917962 -392.30427)
		(width 0.1016)
		(layer "F.Cu")
		(net "P5E_CPU0_P3_TX_C_DN<7>")
	)
	(segment
		(start 378.916692 -384.14833)
		(end 378.614686 -384.450336)
		(width 0.1016)
		(layer "F.Cu")
		(net "P5E_CPU0_P3_TX_C_DN<7>")
	)
	(segment
		(start 378.679202 -385.87299)
		(end 378.567442 -385.98475)
		(width 0.1016)
		(layer "F.Cu")
		(net "P5E_CPU0_P3_TX_C_DN<7>")
	)
	(arc
		(start 378.686822 -386.668518)
		(mid 378.775521 -386.847706)
		(end 378.80671 -387.0452)
		(width 0.1016)
		(layer "F.Cu")
		(net "P5E_CPU0_P3_TX_C_DN<7>")
	)
	(arc
		(start 378.614686 -384.450336)
		(mid 378.579699 -384.502791)
		(end 378.567442 -384.564636)
		(width 0.1016)
		(layer "F.Cu")
		(net "P5E_CPU0_P3_TX_C_DN<7>")
	)
	(arc
		(start 378.567442 -386.28955)
		(mid 378.597984 -386.488219)
		(end 378.686822 -386.668518)
		(width 0.1016)
		(layer "F.Cu")
		(net "P5E_CPU0_P3_TX_C_DN<7>")
	)
	(segment
		(start 376.883168 -383.231136)
		(end 376.994928 -383.342896)
		(width 0.1016)
		(layer "F.Cu")
		(net "P5E_CPU0_P3_TX_C_DN<6>")
	)
	(segment
		(start 377.009406 -387.034278)
		(end 377.045982 -387.124194)
		(width 0.1016)
		(layer "F.Cu")
		(net "P5E_CPU0_P3_TX_C_DN<6>")
	)
	(segment
		(start 377.62434 -390.076182)
		(end 377.62434 -391.51941)
		(width 0.1016)
		(layer "F.Cu")
		(net "P5E_CPU0_P3_TX_C_DN<6>")
	)
	(segment
		(start 375.163842 -379.56998)
		(end 375.163842 -379.861826)
		(width 0.1016)
		(layer "F.Cu")
		(net "P5E_CPU0_P3_TX_C_DN<6>")
	)
	(segment
		(start 375.42724 -380.496826)
		(end 376.659648 -381.729234)
		(width 0.1016)
		(layer "F.Cu")
		(net "P5E_CPU0_P3_TX_C_DN<6>")
	)
	(segment
		(start 377.718066 -391.613136)
		(end 377.718066 -392.30427)
		(width 0.1016)
		(layer "F.Cu")
		(net "P5E_CPU0_P3_TX_C_DN<6>")
	)
	(segment
		(start 376.994928 -383.647696)
		(end 376.883168 -383.759456)
		(width 0.1016)
		(layer "F.Cu")
		(net "P5E_CPU0_P3_TX_C_DN<6>")
	)
	(segment
		(start 376.883168 -383.759456)
		(end 376.883168 -386.388356)
		(width 0.1016)
		(layer "F.Cu")
		(net "P5E_CPU0_P3_TX_C_DN<6>")
	)
	(segment
		(start 375.513092 -379.22073)
		(end 375.163842 -379.56998)
		(width 0.1016)
		(layer "F.Cu")
		(net "P5E_CPU0_P3_TX_C_DN<6>")
	)
	(segment
		(start 376.883168 -382.26873)
		(end 376.883168 -383.231136)
		(width 0.1016)
		(layer "F.Cu")
		(net "P5E_CPU0_P3_TX_C_DN<6>")
	)
	(segment
		(start 376.994928 -383.342896)
		(end 376.994928 -383.647696)
		(width 0.1016)
		(layer "F.Cu")
		(net "P5E_CPU0_P3_TX_C_DN<6>")
	)
	(segment
		(start 377.62434 -391.51941)
		(end 377.718066 -391.613136)
		(width 0.1016)
		(layer "F.Cu")
		(net "P5E_CPU0_P3_TX_C_DN<6>")
	)
	(arc
		(start 375.163842 -379.861826)
		(mid 375.232409 -380.205506)
		(end 375.42724 -380.496826)
		(width 0.1016)
		(layer "F.Cu")
		(net "P5E_CPU0_P3_TX_C_DN<6>")
	)
	(arc
		(start 377.045982 -387.124194)
		(mid 377.478348 -388.572135)
		(end 377.62434 -390.076182)
		(width 0.1016)
		(layer "F.Cu")
		(net "P5E_CPU0_P3_TX_C_DN<6>")
	)
	(arc
		(start 376.883168 -386.388356)
		(mid 376.915041 -386.717425)
		(end 377.009406 -387.034278)
		(width 0.1016)
		(layer "F.Cu")
		(net "P5E_CPU0_P3_TX_C_DN<6>")
	)
	(arc
		(start 376.659648 -381.729234)
		(mid 376.825013 -381.97677)
		(end 376.883168 -382.26873)
		(width 0.1016)
		(layer "F.Cu")
		(net "P5E_CPU0_P3_TX_C_DN<6>")
	)
	(segment
		(start 373.462042 -383.439416)
		(end 373.462042 -383.744216)
		(width 0.1016)
		(layer "F.Cu")
		(net "P5E_CPU0_P3_TX_C_DN<5>")
	)
	(segment
		(start 373.573802 -383.022856)
		(end 373.573802 -383.327656)
		(width 0.1016)
		(layer "F.Cu")
		(net "P5E_CPU0_P3_TX_C_DN<5>")
	)
	(segment
		(start 373.462042 -382.911096)
		(end 373.573802 -383.022856)
		(width 0.1016)
		(layer "F.Cu")
		(net "P5E_CPU0_P3_TX_C_DN<5>")
	)
	(segment
		(start 376.424444 -390.033764)
		(end 376.424444 -391.51941)
		(width 0.1016)
		(layer "F.Cu")
		(net "P5E_CPU0_P3_TX_C_DN<5>")
	)
	(segment
		(start 376.517916 -391.612882)
		(end 376.517916 -392.30427)
		(width 0.1016)
		(layer "F.Cu")
		(net "P5E_CPU0_P3_TX_C_DN<5>")
	)
	(segment
		(start 373.789702 -384.82397)
		(end 375.719594 -387.710934)
		(width 0.1016)
		(layer "F.Cu")
		(net "P5E_CPU0_P3_TX_C_DN<5>")
	)
	(segment
		(start 373.811292 -381.68453)
		(end 373.462042 -382.03378)
		(width 0.1016)
		(layer "F.Cu")
		(net "P5E_CPU0_P3_TX_C_DN<5>")
	)
	(segment
		(start 376.424444 -391.51941)
		(end 376.517916 -391.612882)
		(width 0.1016)
		(layer "F.Cu")
		(net "P5E_CPU0_P3_TX_C_DN<5>")
	)
	(segment
		(start 373.462042 -382.03378)
		(end 373.462042 -382.911096)
		(width 0.1016)
		(layer "F.Cu")
		(net "P5E_CPU0_P3_TX_C_DN<5>")
	)
	(segment
		(start 373.573802 -383.327656)
		(end 373.462042 -383.439416)
		(width 0.1016)
		(layer "F.Cu")
		(net "P5E_CPU0_P3_TX_C_DN<5>")
	)
	(arc
		(start 373.462042 -383.744216)
		(mid 373.545763 -384.308402)
		(end 373.789702 -384.82397)
		(width 0.1016)
		(layer "F.Cu")
		(net "P5E_CPU0_P3_TX_C_DN<5>")
	)
	(arc
		(start 375.719594 -387.710934)
		(mid 376.244357 -388.820055)
		(end 376.424444 -390.033764)
		(width 0.1016)
		(layer "F.Cu")
		(net "P5E_CPU0_P3_TX_C_DN<5>")
	)
	(segment
		(start 371.760242 -384.67157)
		(end 371.975888 -385.191508)
		(width 0.1016)
		(layer "F.Cu")
		(net "P5E_CPU0_P3_TX_C_DN<4>")
	)
	(segment
		(start 375.224548 -391.51941)
		(end 375.31802 -391.612882)
		(width 0.1016)
		(layer "F.Cu")
		(net "P5E_CPU0_P3_TX_C_DN<4>")
	)
	(segment
		(start 371.760242 -384.49758)
		(end 371.760242 -384.67157)
		(width 0.1016)
		(layer "F.Cu")
		(net "P5E_CPU0_P3_TX_C_DN<4>")
	)
	(segment
		(start 371.975888 -385.191508)
		(end 372.517924 -385.851908)
		(width 0.1016)
		(layer "F.Cu")
		(net "P5E_CPU0_P3_TX_C_DN<4>")
	)
	(segment
		(start 372.868698 -386.103114)
		(end 372.853458 -386.260594)
		(width 0.1016)
		(layer "F.Cu")
		(net "P5E_CPU0_P3_TX_C_DN<4>")
	)
	(segment
		(start 375.224548 -389.955278)
		(end 375.224548 -391.51941)
		(width 0.1016)
		(layer "F.Cu")
		(net "P5E_CPU0_P3_TX_C_DN<4>")
	)
	(segment
		(start 372.109492 -384.14833)
		(end 371.760242 -384.49758)
		(width 0.1016)
		(layer "F.Cu")
		(net "P5E_CPU0_P3_TX_C_DN<4>")
	)
	(segment
		(start 375.31802 -391.612882)
		(end 375.31802 -392.30427)
		(width 0.1016)
		(layer "F.Cu")
		(net "P5E_CPU0_P3_TX_C_DN<4>")
	)
	(segment
		(start 372.67515 -385.867402)
		(end 372.868698 -386.103114)
		(width 0.1016)
		(layer "F.Cu")
		(net "P5E_CPU0_P3_TX_C_DN<4>")
	)
	(segment
		(start 372.517924 -385.851908)
		(end 372.67515 -385.867402)
		(width 0.1016)
		(layer "F.Cu")
		(net "P5E_CPU0_P3_TX_C_DN<4>")
	)
	(segment
		(start 372.853458 -386.260594)
		(end 374.851422 -388.69493)
		(width 0.1016)
		(layer "F.Cu")
		(net "P5E_CPU0_P3_TX_C_DN<4>")
	)
	(arc
		(start 375.224548 -389.954262)
		(mid 375.224548 -389.95477)
		(end 375.224548 -389.955278)
		(width 0.1016)
		(layer "F.Cu")
		(net "P5E_CPU0_P3_TX_C_DN<4>")
	)
	(arc
		(start 374.851422 -388.69493)
		(mid 375.129074 -389.297208)
		(end 375.224548 -389.9535)
		(width 0.1016)
		(layer "F.Cu")
		(net "P5E_CPU0_P3_TX_C_DN<4>")
	)
	(arc
		(start 375.224548 -389.9535)
		(mid 375.224548 -389.953881)
		(end 375.224548 -389.954262)
		(width 0.1016)
		(layer "F.Cu")
		(net "P5E_CPU0_P3_TX_C_DN<4>")
	)
	(segment
		(start 371.224048 -386.3213)
		(end 373.857012 -389.529574)
		(width 0.1016)
		(layer "F.Cu")
		(net "P5E_CPU0_P3_TX_C_DN<3>")
	)
	(segment
		(start 370.115592 -383.834132)
		(end 370.96954 -385.896358)
		(width 0.1016)
		(layer "F.Cu")
		(net "P5E_CPU0_P3_TX_C_DN<3>")
	)
	(segment
		(start 368.705892 -379.22073)
		(end 368.356642 -379.56998)
		(width 0.1016)
		(layer "F.Cu")
		(net "P5E_CPU0_P3_TX_C_DN<3>")
	)
	(segment
		(start 370.96954 -385.896358)
		(end 371.224048 -386.3213)
		(width 0.1016)
		(layer "F.Cu")
		(net "P5E_CPU0_P3_TX_C_DN<3>")
	)
	(segment
		(start 369.292124 -381.150114)
		(end 369.450112 -381.150114)
		(width 0.1016)
		(layer "F.Cu")
		(net "P5E_CPU0_P3_TX_C_DN<3>")
	)
	(segment
		(start 374.024398 -389.996426)
		(end 374.024398 -391.51941)
		(width 0.1016)
		(layer "F.Cu")
		(net "P5E_CPU0_P3_TX_C_DN<3>")
	)
	(segment
		(start 370.066316 -382.120902)
		(end 370.066316 -383.585466)
		(width 0.1016)
		(layer "F.Cu")
		(net "P5E_CPU0_P3_TX_C_DN<3>")
	)
	(segment
		(start 369.666012 -381.524002)
		(end 369.927124 -381.785114)
		(width 0.1016)
		(layer "F.Cu")
		(net "P5E_CPU0_P3_TX_C_DN<3>")
	)
	(segment
		(start 374.11787 -391.612882)
		(end 374.11787 -392.30427)
		(width 0.1016)
		(layer "F.Cu")
		(net "P5E_CPU0_P3_TX_C_DN<3>")
	)
	(segment
		(start 369.666012 -381.366014)
		(end 369.666012 -381.524002)
		(width 0.1016)
		(layer "F.Cu")
		(net "P5E_CPU0_P3_TX_C_DN<3>")
	)
	(segment
		(start 368.5413 -380.39929)
		(end 369.292124 -381.150114)
		(width 0.1016)
		(layer "F.Cu")
		(net "P5E_CPU0_P3_TX_C_DN<3>")
	)
	(segment
		(start 374.024398 -391.51941)
		(end 374.11787 -391.612882)
		(width 0.1016)
		(layer "F.Cu")
		(net "P5E_CPU0_P3_TX_C_DN<3>")
	)
	(segment
		(start 369.450112 -381.150114)
		(end 369.666012 -381.366014)
		(width 0.1016)
		(layer "F.Cu")
		(net "P5E_CPU0_P3_TX_C_DN<3>")
	)
	(segment
		(start 368.356642 -379.56998)
		(end 368.356642 -379.95352)
		(width 0.1016)
		(layer "F.Cu")
		(net "P5E_CPU0_P3_TX_C_DN<3>")
	)
	(arc
		(start 370.066316 -383.585466)
		(mid 370.078696 -383.71223)
		(end 370.115592 -383.834132)
		(width 0.1016)
		(layer "F.Cu")
		(net "P5E_CPU0_P3_TX_C_DN<3>")
	)
	(arc
		(start 369.927124 -381.785114)
		(mid 370.030118 -381.939161)
		(end 370.066316 -382.120902)
		(width 0.1016)
		(layer "F.Cu")
		(net "P5E_CPU0_P3_TX_C_DN<3>")
	)
	(arc
		(start 368.356642 -379.95352)
		(mid 368.40463 -380.194774)
		(end 368.5413 -380.39929)
		(width 0.1016)
		(layer "F.Cu")
		(net "P5E_CPU0_P3_TX_C_DN<3>")
	)
	(arc
		(start 373.857012 -389.529574)
		(mid 373.98123 -389.748463)
		(end 374.024398 -389.996426)
		(width 0.1016)
		(layer "F.Cu")
		(net "P5E_CPU0_P3_TX_C_DN<3>")
	)
	(segment
		(start 372.824502 -390.602216)
		(end 372.824502 -391.51941)
		(width 0.1016)
		(layer "F.Cu")
		(net "P5E_CPU0_P3_TX_C_DN<2>")
	)
	(segment
		(start 368.953288 -384.545078)
		(end 369.084352 -384.676142)
		(width 0.1016)
		(layer "F.Cu")
		(net "P5E_CPU0_P3_TX_C_DN<2>")
	)
	(segment
		(start 367.24844 -383.416556)
		(end 368.163348 -383.795524)
		(width 0.1016)
		(layer "F.Cu")
		(net "P5E_CPU0_P3_TX_C_DN<2>")
	)
	(segment
		(start 368.953288 -384.38709)
		(end 368.953288 -384.545078)
		(width 0.1016)
		(layer "F.Cu")
		(net "P5E_CPU0_P3_TX_C_DN<2>")
	)
	(segment
		(start 368.28476 -383.87655)
		(end 368.5794 -384.17119)
		(width 0.1016)
		(layer "F.Cu")
		(net "P5E_CPU0_P3_TX_C_DN<2>")
	)
	(segment
		(start 368.5794 -384.17119)
		(end 368.737388 -384.17119)
		(width 0.1016)
		(layer "F.Cu")
		(net "P5E_CPU0_P3_TX_C_DN<2>")
	)
	(segment
		(start 366.654842 -382.03378)
		(end 366.654842 -382.664208)
		(width 0.1016)
		(layer "F.Cu")
		(net "P5E_CPU0_P3_TX_C_DN<2>")
	)
	(segment
		(start 366.84966 -383.133854)
		(end 366.897666 -383.18186)
		(width 0.1016)
		(layer "F.Cu")
		(net "P5E_CPU0_P3_TX_C_DN<2>")
	)
	(segment
		(start 372.917974 -391.612882)
		(end 372.917974 -392.30427)
		(width 0.1016)
		(layer "F.Cu")
		(net "P5E_CPU0_P3_TX_C_DN<2>")
	)
	(segment
		(start 370.004086 -386.70992)
		(end 370.138452 -386.93344)
		(width 0.1016)
		(layer "F.Cu")
		(net "P5E_CPU0_P3_TX_C_DN<2>")
	)
	(segment
		(start 372.824502 -391.51941)
		(end 372.917974 -391.612882)
		(width 0.1016)
		(layer "F.Cu")
		(net "P5E_CPU0_P3_TX_C_DN<2>")
	)
	(segment
		(start 369.288568 -384.981704)
		(end 370.004086 -386.70992)
		(width 0.1016)
		(layer "F.Cu")
		(net "P5E_CPU0_P3_TX_C_DN<2>")
	)
	(segment
		(start 368.737388 -384.17119)
		(end 368.953288 -384.38709)
		(width 0.1016)
		(layer "F.Cu")
		(net "P5E_CPU0_P3_TX_C_DN<2>")
	)
	(segment
		(start 370.398294 -387.301994)
		(end 372.604284 -389.987536)
		(width 0.1016)
		(layer "F.Cu")
		(net "P5E_CPU0_P3_TX_C_DN<2>")
	)
	(segment
		(start 367.004092 -381.68453)
		(end 366.654842 -382.03378)
		(width 0.1016)
		(layer "F.Cu")
		(net "P5E_CPU0_P3_TX_C_DN<2>")
	)
	(arc
		(start 372.604284 -389.987536)
		(mid 372.767773 -390.275755)
		(end 372.824502 -390.602216)
		(width 0.1016)
		(layer "F.Cu")
		(net "P5E_CPU0_P3_TX_C_DN<2>")
	)
	(arc
		(start 368.163348 -383.795524)
		(mid 368.228055 -383.830045)
		(end 368.28476 -383.87655)
		(width 0.1016)
		(layer "F.Cu")
		(net "P5E_CPU0_P3_TX_C_DN<2>")
	)
	(arc
		(start 366.654842 -382.664208)
		(mid 366.705587 -382.91838)
		(end 366.84966 -383.133854)
		(width 0.1016)
		(layer "F.Cu")
		(net "P5E_CPU0_P3_TX_C_DN<2>")
	)
	(arc
		(start 369.084352 -384.676142)
		(mid 369.201517 -384.818861)
		(end 369.288568 -384.981704)
		(width 0.1016)
		(layer "F.Cu")
		(net "P5E_CPU0_P3_TX_C_DN<2>")
	)
	(arc
		(start 370.138452 -386.93344)
		(mid 370.261611 -387.122484)
		(end 370.398294 -387.301994)
		(width 0.1016)
		(layer "F.Cu")
		(net "P5E_CPU0_P3_TX_C_DN<2>")
	)
	(arc
		(start 366.897666 -383.18186)
		(mid 367.061504 -383.316467)
		(end 367.24844 -383.416556)
		(width 0.1016)
		(layer "F.Cu")
		(net "P5E_CPU0_P3_TX_C_DN<2>")
	)
	(segment
		(start 368.979958 -388.01167)
		(end 369.149376 -388.265162)
		(width 0.1016)
		(layer "F.Cu")
		(net "P5E_CPU0_P3_TX_C_DN<1>")
	)
	(segment
		(start 369.149376 -388.265162)
		(end 369.30457 -388.29615)
		(width 0.1016)
		(layer "F.Cu")
		(net "P5E_CPU0_P3_TX_C_DN<1>")
	)
	(segment
		(start 369.30457 -388.29615)
		(end 369.418362 -388.46633)
		(width 0.1016)
		(layer "F.Cu")
		(net "P5E_CPU0_P3_TX_C_DN<1>")
	)
	(segment
		(start 371.115844 -391.6172)
		(end 371.115844 -391.88771)
		(width 0.1016)
		(layer "F.Cu")
		(net "P5E_CPU0_P3_TX_C_DN<1>")
	)
	(segment
		(start 371.408452 -391.324592)
		(end 371.115844 -391.6172)
		(width 0.1016)
		(layer "F.Cu")
		(net "P5E_CPU0_P3_TX_C_DN<1>")
	)
	(segment
		(start 371.41785 -391.902442)
		(end 371.41785 -391.784586)
		(width 0.1016)
		(layer "F.Cu")
		(net "P5E_CPU0_P3_TX_C_DN<1>")
	)
	(segment
		(start 366.705134 -384.868166)
		(end 366.789208 -384.868166)
		(width 0.1016)
		(layer "F.Cu")
		(net "P5E_CPU0_P3_TX_C_DN<1>")
	)
	(segment
		(start 369.010692 -387.856476)
		(end 368.979958 -388.01167)
		(width 0.1016)
		(layer "F.Cu")
		(net "P5E_CPU0_P3_TX_C_DN<1>")
	)
	(segment
		(start 369.565936 -388.646162)
		(end 370.169186 -389.249412)
		(width 0.1016)
		(layer "F.Cu")
		(net "P5E_CPU0_P3_TX_C_DN<1>")
	)
	(segment
		(start 371.307614 -390.693656)
		(end 371.408452 -390.936734)
		(width 0.1016)
		(layer "F.Cu")
		(net "P5E_CPU0_P3_TX_C_DN<1>")
	)
	(segment
		(start 371.20703 -391.978896)
		(end 371.341396 -391.978896)
		(width 0.1016)
		(layer "F.Cu")
		(net "P5E_CPU0_P3_TX_C_DN<1>")
	)
	(segment
		(start 371.341396 -391.978896)
		(end 371.41785 -391.902442)
		(width 0.1016)
		(layer "F.Cu")
		(net "P5E_CPU0_P3_TX_C_DN<1>")
	)
	(segment
		(start 370.169186 -389.249412)
		(end 371.181122 -390.482836)
		(width 0.1016)
		(layer "F.Cu")
		(net "P5E_CPU0_P3_TX_C_DN<1>")
	)
	(segment
		(start 371.181122 -390.482836)
		(end 371.307614 -390.693656)
		(width 0.1016)
		(layer "F.Cu")
		(net "P5E_CPU0_P3_TX_C_DN<1>")
	)
	(segment
		(start 368.495834 -386.768594)
		(end 368.435382 -386.91439)
		(width 0.1016)
		(layer "F.Cu")
		(net "P5E_CPU0_P3_TX_C_DN<1>")
	)
	(segment
		(start 366.33404 -385.23926)
		(end 366.705134 -384.868166)
		(width 0.1016)
		(layer "F.Cu")
		(net "P5E_CPU0_P3_TX_C_DN<1>")
	)
	(segment
		(start 367.626138 -385.214876)
		(end 367.952274 -385.541012)
		(width 0.1016)
		(layer "F.Cu")
		(net "P5E_CPU0_P3_TX_C_DN<1>")
	)
	(segment
		(start 368.841528 -387.603238)
		(end 369.010692 -387.856476)
		(width 0.1016)
		(layer "F.Cu")
		(net "P5E_CPU0_P3_TX_C_DN<1>")
	)
	(segment
		(start 368.435382 -386.91439)
		(end 368.551968 -387.19633)
		(width 0.1016)
		(layer "F.Cu")
		(net "P5E_CPU0_P3_TX_C_DN<1>")
	)
	(segment
		(start 368.551968 -387.19633)
		(end 368.698272 -387.256782)
		(width 0.1016)
		(layer "F.Cu")
		(net "P5E_CPU0_P3_TX_C_DN<1>")
	)
	(segment
		(start 371.115844 -391.88771)
		(end 371.20703 -391.978896)
		(width 0.1016)
		(layer "F.Cu")
		(net "P5E_CPU0_P3_TX_C_DN<1>")
	)
	(segment
		(start 368.045746 -385.680966)
		(end 368.495834 -386.768594)
		(width 0.1016)
		(layer "F.Cu")
		(net "P5E_CPU0_P3_TX_C_DN<1>")
	)
	(segment
		(start 368.698272 -387.256782)
		(end 368.841528 -387.603238)
		(width 0.1016)
		(layer "F.Cu")
		(net "P5E_CPU0_P3_TX_C_DN<1>")
	)
	(segment
		(start 371.408452 -390.936734)
		(end 371.408452 -391.324592)
		(width 0.1016)
		(layer "F.Cu")
		(net "P5E_CPU0_P3_TX_C_DN<1>")
	)
	(arc
		(start 369.418362 -388.46633)
		(mid 369.487733 -388.55987)
		(end 369.565936 -388.646162)
		(width 0.1016)
		(layer "F.Cu")
		(net "P5E_CPU0_P3_TX_C_DN<1>")
	)
	(arc
		(start 366.789208 -384.868166)
		(mid 367.242153 -384.95828)
		(end 367.626138 -385.214876)
		(width 0.1016)
		(layer "F.Cu")
		(net "P5E_CPU0_P3_TX_C_DN<1>")
	)
	(arc
		(start 367.952274 -385.541012)
		(mid 368.005913 -385.60638)
		(end 368.045746 -385.680966)
		(width 0.1016)
		(layer "F.Cu")
		(net "P5E_CPU0_P3_TX_C_DN<1>")
	)
	(segment
		(start 388.5184 -391.40257)
		(end 388.5184 -392.303762)
		(width 0.1016)
		(layer "F.Cu")
		(net "P5E_CPU0_P3_TX_C_DN<15>")
	)
	(segment
		(start 392.225022 -388.418578)
		(end 390.520174 -388.418578)
		(width 0.1016)
		(layer "F.Cu")
		(net "P5E_CPU0_P3_TX_C_DN<15>")
	)
	(segment
		(start 390.419082 -388.460488)
		(end 388.518146 -390.361424)
		(width 0.1016)
		(layer "F.Cu")
		(net "P5E_CPU0_P3_TX_C_DN<15>")
	)
	(segment
		(start 388.5184 -392.303762)
		(end 388.517892 -392.30427)
		(width 0.1016)
		(layer "F.Cu")
		(net "P5E_CPU0_P3_TX_C_DN<15>")
	)
	(segment
		(start 392.574272 -388.767828)
		(end 392.225022 -388.418578)
		(width 0.1016)
		(layer "F.Cu")
		(net "P5E_CPU0_P3_TX_C_DN<15>")
	)
	(segment
		(start 388.42442 -391.30859)
		(end 388.5184 -391.40257)
		(width 0.1016)
		(layer "F.Cu")
		(net "P5E_CPU0_P3_TX_C_DN<15>")
	)
	(segment
		(start 388.42442 -390.587484)
		(end 388.42442 -391.30859)
		(width 0.1016)
		(layer "F.Cu")
		(net "P5E_CPU0_P3_TX_C_DN<15>")
	)
	(arc
		(start 388.518146 -390.361424)
		(mid 388.448791 -390.465127)
		(end 388.42442 -390.587484)
		(width 0.1016)
		(layer "F.Cu")
		(net "P5E_CPU0_P3_TX_C_DN<15>")
	)
	(arc
		(start 390.520174 -388.418578)
		(mid 390.46545 -388.429463)
		(end 390.419082 -388.460488)
		(width 0.1016)
		(layer "F.Cu")
		(net "P5E_CPU0_P3_TX_C_DN<15>")
	)
	(segment
		(start 387.008624 -391.398252)
		(end 387.102604 -391.492232)
		(width 0.1016)
		(layer "F.Cu")
		(net "P5E_CPU0_P3_TX_C_DN<14>")
	)
	(segment
		(start 387.008624 -390.071102)
		(end 387.008624 -391.398252)
		(width 0.1016)
		(layer "F.Cu")
		(net "P5E_CPU0_P3_TX_C_DN<14>")
	)
	(segment
		(start 392.13917 -384.88493)
		(end 391.824972 -384.88493)
		(width 0.1016)
		(layer "F.Cu")
		(net "P5E_CPU0_P3_TX_C_DN<14>")
	)
	(segment
		(start 387.102604 -391.492232)
		(end 387.102604 -391.700004)
		(width 0.1016)
		(layer "F.Cu")
		(net "P5E_CPU0_P3_TX_C_DN<14>")
	)
	(segment
		(start 392.574272 -384.449828)
		(end 392.13917 -384.88493)
		(width 0.1016)
		(layer "F.Cu")
		(net "P5E_CPU0_P3_TX_C_DN<14>")
	)
	(segment
		(start 387.102604 -391.700004)
		(end 387.018022 -391.784586)
		(width 0.1016)
		(layer "F.Cu")
		(net "P5E_CPU0_P3_TX_C_DN<14>")
	)
	(segment
		(start 391.824972 -384.88493)
		(end 387.269482 -389.44042)
		(width 0.1016)
		(layer "F.Cu")
		(net "P5E_CPU0_P3_TX_C_DN<14>")
	)
	(arc
		(start 387.269482 -389.44042)
		(mid 387.076358 -389.729824)
		(end 387.008624 -390.071102)
		(width 0.1016)
		(layer "F.Cu")
		(net "P5E_CPU0_P3_TX_C_DN<14>")
	)
	(segment
		(start 393.42314 -381.507238)
		(end 393.638532 -381.72263)
		(width 0.1016)
		(layer "F.Cu")
		(net "P5E_CPU0_P3_TX_C_DN<13>")
	)
	(segment
		(start 386.024374 -389.354822)
		(end 386.024374 -391.51941)
		(width 0.1016)
		(layer "F.Cu")
		(net "P5E_CPU0_P3_TX_C_DN<13>")
	)
	(segment
		(start 393.20724 -381.13335)
		(end 393.42314 -381.34925)
		(width 0.1016)
		(layer "F.Cu")
		(net "P5E_CPU0_P3_TX_C_DN<13>")
	)
	(segment
		(start 392.531092 -379.22073)
		(end 392.181842 -379.56998)
		(width 0.1016)
		(layer "F.Cu")
		(net "P5E_CPU0_P3_TX_C_DN<13>")
	)
	(segment
		(start 393.855956 -382.248156)
		(end 393.855956 -382.518666)
		(width 0.1016)
		(layer "F.Cu")
		(net "P5E_CPU0_P3_TX_C_DN<13>")
	)
	(segment
		(start 392.756898 -383.69494)
		(end 391.876026 -383.69494)
		(width 0.1016)
		(layer "F.Cu")
		(net "P5E_CPU0_P3_TX_C_DN<13>")
	)
	(segment
		(start 393.620244 -383.088388)
		(end 393.194794 -383.513838)
		(width 0.1016)
		(layer "F.Cu")
		(net "P5E_CPU0_P3_TX_C_DN<13>")
	)
	(segment
		(start 392.43381 -380.517908)
		(end 393.049252 -381.13335)
		(width 0.1016)
		(layer "F.Cu")
		(net "P5E_CPU0_P3_TX_C_DN<13>")
	)
	(segment
		(start 392.181842 -379.56998)
		(end 392.181842 -379.909832)
		(width 0.1016)
		(layer "F.Cu")
		(net "P5E_CPU0_P3_TX_C_DN<13>")
	)
	(segment
		(start 393.049252 -381.13335)
		(end 393.20724 -381.13335)
		(width 0.1016)
		(layer "F.Cu")
		(net "P5E_CPU0_P3_TX_C_DN<13>")
	)
	(segment
		(start 392.181842 -379.909832)
		(end 392.182096 -379.909578)
		(width 0.1016)
		(layer "F.Cu")
		(net "P5E_CPU0_P3_TX_C_DN<13>")
	)
	(segment
		(start 386.117846 -391.612882)
		(end 386.117846 -392.30427)
		(width 0.1016)
		(layer "F.Cu")
		(net "P5E_CPU0_P3_TX_C_DN<13>")
	)
	(segment
		(start 391.45845 -383.867914)
		(end 386.061712 -389.264652)
		(width 0.1016)
		(layer "F.Cu")
		(net "P5E_CPU0_P3_TX_C_DN<13>")
	)
	(segment
		(start 393.42314 -381.34925)
		(end 393.42314 -381.507238)
		(width 0.1016)
		(layer "F.Cu")
		(net "P5E_CPU0_P3_TX_C_DN<13>")
	)
	(segment
		(start 386.024374 -391.51941)
		(end 386.117846 -391.612882)
		(width 0.1016)
		(layer "F.Cu")
		(net "P5E_CPU0_P3_TX_C_DN<13>")
	)
	(arc
		(start 391.876026 -383.69494)
		(mid 391.650032 -383.739893)
		(end 391.45845 -383.867914)
		(width 0.1016)
		(layer "F.Cu")
		(net "P5E_CPU0_P3_TX_C_DN<13>")
	)
	(arc
		(start 392.182096 -379.909578)
		(mid 392.247465 -380.238771)
		(end 392.43381 -380.517908)
		(width 0.1016)
		(layer "F.Cu")
		(net "P5E_CPU0_P3_TX_C_DN<13>")
	)
	(arc
		(start 386.061712 -389.264652)
		(mid 386.034069 -389.306022)
		(end 386.024374 -389.354822)
		(width 0.1016)
		(layer "F.Cu")
		(net "P5E_CPU0_P3_TX_C_DN<13>")
	)
	(arc
		(start 393.194794 -383.513838)
		(mid 392.993856 -383.647915)
		(end 392.756898 -383.69494)
		(width 0.1016)
		(layer "F.Cu")
		(net "P5E_CPU0_P3_TX_C_DN<13>")
	)
	(arc
		(start 393.855956 -382.518666)
		(mid 393.794812 -382.827)
		(end 393.620244 -383.088388)
		(width 0.1016)
		(layer "F.Cu")
		(net "P5E_CPU0_P3_TX_C_DN<13>")
	)
	(arc
		(start 393.638532 -381.72263)
		(mid 393.799527 -381.963759)
		(end 393.855956 -382.248156)
		(width 0.1016)
		(layer "F.Cu")
		(net "P5E_CPU0_P3_TX_C_DN<13>")
	)
	(segment
		(start 390.352026 -383.272284)
		(end 385.048506 -388.576058)
		(width 0.1016)
		(layer "F.Cu")
		(net "P5E_CPU0_P3_TX_C_DN<12>")
	)
	(segment
		(start 390.487916 -382.039368)
		(end 390.487916 -382.945132)
		(width 0.1016)
		(layer "F.Cu")
		(net "P5E_CPU0_P3_TX_C_DN<12>")
	)
	(segment
		(start 389.898636 -381.307594)
		(end 390.056624 -381.307594)
		(width 0.1016)
		(layer "F.Cu")
		(net "P5E_CPU0_P3_TX_C_DN<12>")
	)
	(segment
		(start 390.056624 -381.307594)
		(end 390.272524 -381.523494)
		(width 0.1016)
		(layer "F.Cu")
		(net "P5E_CPU0_P3_TX_C_DN<12>")
	)
	(segment
		(start 384.91795 -391.612882)
		(end 384.91795 -392.30427)
		(width 0.1016)
		(layer "F.Cu")
		(net "P5E_CPU0_P3_TX_C_DN<12>")
	)
	(segment
		(start 389.127492 -379.22073)
		(end 388.778242 -379.56998)
		(width 0.1016)
		(layer "F.Cu")
		(net "P5E_CPU0_P3_TX_C_DN<12>")
	)
	(segment
		(start 390.272524 -381.681482)
		(end 390.387586 -381.796544)
		(width 0.1016)
		(layer "F.Cu")
		(net "P5E_CPU0_P3_TX_C_DN<12>")
	)
	(segment
		(start 384.824478 -389.116062)
		(end 384.824478 -391.51941)
		(width 0.1016)
		(layer "F.Cu")
		(net "P5E_CPU0_P3_TX_C_DN<12>")
	)
	(segment
		(start 390.272524 -381.523494)
		(end 390.272524 -381.681482)
		(width 0.1016)
		(layer "F.Cu")
		(net "P5E_CPU0_P3_TX_C_DN<12>")
	)
	(segment
		(start 388.778242 -379.56998)
		(end 388.778242 -379.9205)
		(width 0.1016)
		(layer "F.Cu")
		(net "P5E_CPU0_P3_TX_C_DN<12>")
	)
	(segment
		(start 388.967472 -380.37643)
		(end 389.898636 -381.307594)
		(width 0.1016)
		(layer "F.Cu")
		(net "P5E_CPU0_P3_TX_C_DN<12>")
	)
	(segment
		(start 384.824478 -391.51941)
		(end 384.91795 -391.612882)
		(width 0.1016)
		(layer "F.Cu")
		(net "P5E_CPU0_P3_TX_C_DN<12>")
	)
	(arc
		(start 390.487916 -382.945132)
		(mid 390.452488 -383.122209)
		(end 390.352026 -383.272284)
		(width 0.1016)
		(layer "F.Cu")
		(net "P5E_CPU0_P3_TX_C_DN<12>")
	)
	(arc
		(start 390.387586 -381.796544)
		(mid 390.46189 -381.907982)
		(end 390.487916 -382.039368)
		(width 0.1016)
		(layer "F.Cu")
		(net "P5E_CPU0_P3_TX_C_DN<12>")
	)
	(arc
		(start 385.048506 -388.576058)
		(mid 384.882741 -388.82377)
		(end 384.824478 -389.116062)
		(width 0.1016)
		(layer "F.Cu")
		(net "P5E_CPU0_P3_TX_C_DN<12>")
	)
	(arc
		(start 388.778242 -379.9205)
		(mid 388.827533 -380.16727)
		(end 388.967472 -380.37643)
		(width 0.1016)
		(layer "F.Cu")
		(net "P5E_CPU0_P3_TX_C_DN<12>")
	)
	(segment
		(start 387.425692 -381.68453)
		(end 387.076442 -382.03378)
		(width 0.1016)
		(layer "F.Cu")
		(net "P5E_CPU0_P3_TX_C_DN<11>")
	)
	(segment
		(start 387.076442 -382.03378)
		(end 387.076442 -383.403856)
		(width 0.1016)
		(layer "F.Cu")
		(net "P5E_CPU0_P3_TX_C_DN<11>")
	)
	(segment
		(start 387.188202 -383.515616)
		(end 387.188202 -383.820416)
		(width 0.1016)
		(layer "F.Cu")
		(net "P5E_CPU0_P3_TX_C_DN<11>")
	)
	(segment
		(start 386.976112 -384.861562)
		(end 383.661666 -388.176008)
		(width 0.1016)
		(layer "F.Cu")
		(net "P5E_CPU0_P3_TX_C_DN<11>")
	)
	(segment
		(start 387.076442 -383.403856)
		(end 387.188202 -383.515616)
		(width 0.1016)
		(layer "F.Cu")
		(net "P5E_CPU0_P3_TX_C_DN<11>")
	)
	(segment
		(start 383.624328 -391.51941)
		(end 383.718054 -391.613136)
		(width 0.1016)
		(layer "F.Cu")
		(net "P5E_CPU0_P3_TX_C_DN<11>")
	)
	(segment
		(start 387.188202 -383.820416)
		(end 387.076442 -383.932176)
		(width 0.1016)
		(layer "F.Cu")
		(net "P5E_CPU0_P3_TX_C_DN<11>")
	)
	(segment
		(start 383.624328 -388.266178)
		(end 383.624328 -391.51941)
		(width 0.1016)
		(layer "F.Cu")
		(net "P5E_CPU0_P3_TX_C_DN<11>")
	)
	(segment
		(start 383.718054 -391.613136)
		(end 383.718054 -392.30427)
		(width 0.1016)
		(layer "F.Cu")
		(net "P5E_CPU0_P3_TX_C_DN<11>")
	)
	(segment
		(start 387.076442 -383.932176)
		(end 387.076442 -384.618484)
		(width 0.1016)
		(layer "F.Cu")
		(net "P5E_CPU0_P3_TX_C_DN<11>")
	)
	(arc
		(start 383.661666 -388.176008)
		(mid 383.634023 -388.217378)
		(end 383.624328 -388.266178)
		(width 0.1016)
		(layer "F.Cu")
		(net "P5E_CPU0_P3_TX_C_DN<11>")
	)
	(arc
		(start 387.076442 -384.618484)
		(mid 387.050483 -384.750022)
		(end 386.976112 -384.861562)
		(width 0.1016)
		(layer "F.Cu")
		(net "P5E_CPU0_P3_TX_C_DN<11>")
	)
	(segment
		(start 384.024378 -385.919472)
		(end 383.802128 -385.919472)
		(width 0.1016)
		(layer "F.Cu")
		(net "P5E_CPU0_P3_TX_C_DN<10>")
	)
	(segment
		(start 382.640586 -387.017768)
		(end 382.46177 -387.196584)
		(width 0.1016)
		(layer "F.Cu")
		(net "P5E_CPU0_P3_TX_C_DN<10>")
	)
	(segment
		(start 385.373626 -384.498596)
		(end 385.373626 -384.584702)
		(width 0.1016)
		(layer "F.Cu")
		(net "P5E_CPU0_P3_TX_C_DN<10>")
	)
	(segment
		(start 385.273296 -384.82778)
		(end 384.291586 -385.809236)
		(width 0.1016)
		(layer "F.Cu")
		(net "P5E_CPU0_P3_TX_C_DN<10>")
	)
	(segment
		(start 382.424432 -391.51941)
		(end 382.517904 -391.612882)
		(width 0.1016)
		(layer "F.Cu")
		(net "P5E_CPU0_P3_TX_C_DN<10>")
	)
	(segment
		(start 382.517904 -391.612882)
		(end 382.517904 -392.30427)
		(width 0.1016)
		(layer "F.Cu")
		(net "P5E_CPU0_P3_TX_C_DN<10>")
	)
	(segment
		(start 383.693924 -385.96443)
		(end 383.01422 -386.644388)
		(width 0.1016)
		(layer "F.Cu")
		(net "P5E_CPU0_P3_TX_C_DN<10>")
	)
	(segment
		(start 382.798574 -387.017768)
		(end 382.640586 -387.017768)
		(width 0.1016)
		(layer "F.Cu")
		(net "P5E_CPU0_P3_TX_C_DN<10>")
	)
	(segment
		(start 383.01422 -386.644388)
		(end 383.01422 -386.802122)
		(width 0.1016)
		(layer "F.Cu")
		(net "P5E_CPU0_P3_TX_C_DN<10>")
	)
	(segment
		(start 382.424432 -387.286754)
		(end 382.424432 -391.51941)
		(width 0.1016)
		(layer "F.Cu")
		(net "P5E_CPU0_P3_TX_C_DN<10>")
	)
	(segment
		(start 383.01422 -386.802122)
		(end 382.798574 -387.017768)
		(width 0.1016)
		(layer "F.Cu")
		(net "P5E_CPU0_P3_TX_C_DN<10>")
	)
	(segment
		(start 385.723892 -384.14833)
		(end 385.373626 -384.498596)
		(width 0.1016)
		(layer "F.Cu")
		(net "P5E_CPU0_P3_TX_C_DN<10>")
	)
	(arc
		(start 385.373626 -384.584702)
		(mid 385.347667 -384.71624)
		(end 385.273296 -384.82778)
		(width 0.1016)
		(layer "F.Cu")
		(net "P5E_CPU0_P3_TX_C_DN<10>")
	)
	(arc
		(start 384.291586 -385.809236)
		(mid 384.168946 -385.890932)
		(end 384.024378 -385.919472)
		(width 0.1016)
		(layer "F.Cu")
		(net "P5E_CPU0_P3_TX_C_DN<10>")
	)
	(arc
		(start 383.802128 -385.919472)
		(mid 383.743544 -385.931161)
		(end 383.693924 -385.96443)
		(width 0.1016)
		(layer "F.Cu")
		(net "P5E_CPU0_P3_TX_C_DN<10>")
	)
	(arc
		(start 382.46177 -387.196584)
		(mid 382.434127 -387.237954)
		(end 382.424432 -387.286754)
		(width 0.1016)
		(layer "F.Cu")
		(net "P5E_CPU0_P3_TX_C_DN<10>")
	)
	(segment
		(start 370.424456 -391.109708)
		(end 370.424456 -391.51941)
		(width 0.1016)
		(layer "F.Cu")
		(net "P5E_CPU0_P3_TX_C_DN<0>")
	)
	(segment
		(start 370.020342 -390.70407)
		(end 370.424456 -391.109708)
		(width 0.1016)
		(layer "F.Cu")
		(net "P5E_CPU0_P3_TX_C_DN<0>")
	)
	(segment
		(start 369.132866 -390.265158)
		(end 369.737894 -390.515094)
		(width 0.1016)
		(layer "F.Cu")
		(net "P5E_CPU0_P3_TX_C_DN<0>")
	)
	(segment
		(start 370.424456 -391.51941)
		(end 370.517928 -391.612882)
		(width 0.1016)
		(layer "F.Cu")
		(net "P5E_CPU0_P3_TX_C_DN<0>")
	)
	(segment
		(start 366.681512 -390.209532)
		(end 368.852704 -390.209532)
		(width 0.1016)
		(layer "F.Cu")
		(net "P5E_CPU0_P3_TX_C_DN<0>")
	)
	(segment
		(start 366.33404 -389.86206)
		(end 366.681512 -390.209532)
		(width 0.1016)
		(layer "F.Cu")
		(net "P5E_CPU0_P3_TX_C_DN<0>")
	)
	(segment
		(start 370.517928 -391.612882)
		(end 370.517928 -392.30427)
		(width 0.1016)
		(layer "F.Cu")
		(net "P5E_CPU0_P3_TX_C_DN<0>")
	)
	(arc
		(start 369.737894 -390.515094)
		(mid 369.888526 -390.595523)
		(end 370.020342 -390.70407)
		(width 0.1016)
		(layer "F.Cu")
		(net "P5E_CPU0_P3_TX_C_DN<0>")
	)
	(arc
		(start 368.852704 -390.209532)
		(mid 368.995523 -390.223564)
		(end 369.132866 -390.265158)
		(width 0.1016)
		(layer "F.Cu")
		(net "P5E_CPU0_P3_TX_C_DN<0>")
	)
	(segment
		(start 374.3706 -394.385292)
		(end 374.8913 -394.385292)
		(width 0.127)
		(layer "F.Cu")
		(net "P5E_CPU0_P3_RX_DP<3>")
	)
	(segment
		(start 365.187992 -287.59023)
		(end 365.654844 -287.856168)
		(width 0.12954)
		(layer "F.Cu")
		(net "P5E_CPU0_P3_RX_DP<3>")
	)
	(segment
		(start 364.566962 -291.441378)
		(end 364.560104 -291.437314)
		(width 0.1143)
		(layer "In4.Cu")
		(net "P5E_CPU0_P3_RX_DP<3>")
	)
	(segment
		(start 364.534958 -289.149282)
		(end 364.566962 -289.130486)
		(width 0.1143)
		(layer "In4.Cu")
		(net "P5E_CPU0_P3_RX_DP<3>")
	)
	(segment
		(start 377.743466 -318.453008)
		(end 375.93905 -315.077856)
		(width 0.14224)
		(layer "In4.Cu")
		(net "P5E_CPU0_P3_RX_DP<3>")
	)
	(segment
		(start 364.551214 -295.61663)
		(end 364.561882 -295.611042)
		(width 0.1143)
		(layer "In4.Cu")
		(net "P5E_CPU0_P3_RX_DP<3>")
	)
	(segment
		(start 364.528862 -294.012874)
		(end 364.530386 -294.011858)
		(width 0.1143)
		(layer "In4.Cu")
		(net "P5E_CPU0_P3_RX_DP<3>")
	)
	(segment
		(start 364.518448 -289.15868)
		(end 364.519972 -289.157918)
		(width 0.1143)
		(layer "In4.Cu")
		(net "P5E_CPU0_P3_RX_DP<3>")
	)
	(segment
		(start 364.566962 -293.06139)
		(end 364.530386 -293.040054)
		(width 0.1143)
		(layer "In4.Cu")
		(net "P5E_CPU0_P3_RX_DP<3>")
	)
	(segment
		(start 364.523528 -294.015922)
		(end 364.52429 -294.015414)
		(width 0.1143)
		(layer "In4.Cu")
		(net "P5E_CPU0_P3_RX_DP<3>")
	)
	(segment
		(start 364.965234 -288.36239)
		(end 364.997746 -288.343594)
		(width 0.1143)
		(layer "In4.Cu")
		(net "P5E_CPU0_P3_RX_DP<3>")
	)
	(segment
		(start 364.527084 -292.393878)
		(end 364.527846 -292.39337)
		(width 0.1143)
		(layer "In4.Cu")
		(net "P5E_CPU0_P3_RX_DP<3>")
	)
	(segment
		(start 364.528862 -294.65905)
		(end 364.527846 -294.658542)
		(width 0.1143)
		(layer "In4.Cu")
		(net "P5E_CPU0_P3_RX_DP<3>")
	)
	(segment
		(start 367.371884 -304.638964)
		(end 365.890556 -302.421544)
		(width 0.14224)
		(layer "In4.Cu")
		(net "P5E_CPU0_P3_RX_DP<3>")
	)
	(segment
		(start 370.232686 -375.915682)
		(end 382.359408 -355.683566)
		(width 0.14224)
		(layer "In4.Cu")
		(net "P5E_CPU0_P3_RX_DP<3>")
	)
	(segment
		(start 364.386114 -296.35831)
		(end 364.386114 -296.329862)
		(width 0.1143)
		(layer "In4.Cu")
		(net "P5E_CPU0_P3_RX_DP<3>")
	)
	(segment
		(start 364.027212 -289.981132)
		(end 364.057692 -289.963352)
		(width 0.1143)
		(layer "In4.Cu")
		(net "P5E_CPU0_P3_RX_DP<3>")
	)
	(segment
		(start 364.527846 -292.39337)
		(end 364.528862 -292.392862)
		(width 0.1143)
		(layer "In4.Cu")
		(net "P5E_CPU0_P3_RX_DP<3>")
	)
	(segment
		(start 364.06582 -290.613338)
		(end 364.027212 -290.590732)
		(width 0.1143)
		(layer "In4.Cu")
		(net "P5E_CPU0_P3_RX_DP<3>")
	)
	(segment
		(start 364.519972 -292.397942)
		(end 364.521242 -292.39718)
		(width 0.1143)
		(layer "In4.Cu")
		(net "P5E_CPU0_P3_RX_DP<3>")
	)
	(segment
		(start 364.560104 -291.437314)
		(end 364.559342 -291.436806)
		(width 0.1143)
		(layer "In4.Cu")
		(net "P5E_CPU0_P3_RX_DP<3>")
	)
	(segment
		(start 364.527846 -294.658542)
		(end 364.496096 -294.640254)
		(width 0.1143)
		(layer "In4.Cu")
		(net "P5E_CPU0_P3_RX_DP<3>")
	)
	(segment
		(start 364.527846 -293.03853)
		(end 364.496096 -293.020242)
		(width 0.1143)
		(layer "In4.Cu")
		(net "P5E_CPU0_P3_RX_DP<3>")
	)
	(segment
		(start 375.16054 -393.930632)
		(end 375.248678 -393.842494)
		(width 0.14224)
		(layer "In4.Cu")
		(net "P5E_CPU0_P3_RX_DP<3>")
	)
	(segment
		(start 364.522004 -292.396672)
		(end 364.523528 -292.39591)
		(width 0.1143)
		(layer "In4.Cu")
		(net "P5E_CPU0_P3_RX_DP<3>")
	)
	(segment
		(start 375.141998 -390.249664)
		(end 374.78081 -388.43331)
		(width 0.14224)
		(layer "In4.Cu")
		(net "P5E_CPU0_P3_RX_DP<3>")
	)
	(segment
		(start 364.523528 -292.39591)
		(end 364.52429 -292.395402)
		(width 0.1143)
		(layer "In4.Cu")
		(net "P5E_CPU0_P3_RX_DP<3>")
	)
	(segment
		(start 364.527084 -291.41801)
		(end 364.52429 -291.416486)
		(width 0.1143)
		(layer "In4.Cu")
		(net "P5E_CPU0_P3_RX_DP<3>")
	)
	(segment
		(start 364.518448 -294.018716)
		(end 364.519972 -294.017954)
		(width 0.1143)
		(layer "In4.Cu")
		(net "P5E_CPU0_P3_RX_DP<3>")
	)
	(segment
		(start 364.52429 -294.015414)
		(end 364.527084 -294.01389)
		(width 0.1143)
		(layer "In4.Cu")
		(net "P5E_CPU0_P3_RX_DP<3>")
	)
	(segment
		(start 364.997746 -288.343594)
		(end 365.036862 -288.320734)
		(width 0.1143)
		(layer "In4.Cu")
		(net "P5E_CPU0_P3_RX_DP<3>")
	)
	(segment
		(start 364.523528 -289.155886)
		(end 364.52429 -289.155378)
		(width 0.1143)
		(layer "In4.Cu")
		(net "P5E_CPU0_P3_RX_DP<3>")
	)
	(segment
		(start 364.522004 -294.016684)
		(end 364.523528 -294.015922)
		(width 0.1143)
		(layer "In4.Cu")
		(net "P5E_CPU0_P3_RX_DP<3>")
	)
	(segment
		(start 375.24055 -392.134852)
		(end 375.24055 -391.249154)
		(width 0.14224)
		(layer "In4.Cu")
		(net "P5E_CPU0_P3_RX_DP<3>")
	)
	(segment
		(start 364.527084 -294.01389)
		(end 364.527846 -294.013382)
		(width 0.1143)
		(layer "In4.Cu")
		(net "P5E_CPU0_P3_RX_DP<3>")
	)
	(segment
		(start 364.496096 -289.171634)
		(end 364.51667 -289.159696)
		(width 0.1143)
		(layer "In4.Cu")
		(net "P5E_CPU0_P3_RX_DP<3>")
	)
	(segment
		(start 364.517686 -294.019224)
		(end 364.518448 -294.018716)
		(width 0.1143)
		(layer "In4.Cu")
		(net "P5E_CPU0_P3_RX_DP<3>")
	)
	(segment
		(start 364.527846 -289.153346)
		(end 364.528862 -289.152838)
		(width 0.1143)
		(layer "In4.Cu")
		(net "P5E_CPU0_P3_RX_DP<3>")
	)
	(segment
		(start 364.521242 -292.39718)
		(end 364.522004 -292.396672)
		(width 0.1143)
		(layer "In4.Cu")
		(net "P5E_CPU0_P3_RX_DP<3>")
	)
	(segment
		(start 374.938036 -392.437366)
		(end 375.24055 -392.134852)
		(width 0.14224)
		(layer "In4.Cu")
		(net "P5E_CPU0_P3_RX_DP<3>")
	)
	(segment
		(start 364.340394 -296.284142)
		(end 364.340394 -295.954704)
		(width 0.1143)
		(layer "In4.Cu")
		(net "P5E_CPU0_P3_RX_DP<3>")
	)
	(segment
		(start 364.057692 -289.963352)
		(end 364.096808 -289.940492)
		(width 0.1143)
		(layer "In4.Cu")
		(net "P5E_CPU0_P3_RX_DP<3>")
	)
	(segment
		(start 373.60733 -386.237734)
		(end 370.181124 -382.811528)
		(width 0.14224)
		(layer "In4.Cu")
		(net "P5E_CPU0_P3_RX_DP<3>")
	)
	(segment
		(start 364.517686 -289.159188)
		(end 364.518448 -289.15868)
		(width 0.1143)
		(layer "In4.Cu")
		(net "P5E_CPU0_P3_RX_DP<3>")
	)
	(segment
		(start 364.521242 -294.017192)
		(end 364.522004 -294.016684)
		(width 0.1143)
		(layer "In4.Cu")
		(net "P5E_CPU0_P3_RX_DP<3>")
	)
	(segment
		(start 365.274098 -287.938972)
		(end 365.356902 -287.856168)
		(width 0.1143)
		(layer "In4.Cu")
		(net "P5E_CPU0_P3_RX_DP<3>")
	)
	(segment
		(start 364.518448 -292.398704)
		(end 364.519972 -292.397942)
		(width 0.1143)
		(layer "In4.Cu")
		(net "P5E_CPU0_P3_RX_DP<3>")
	)
	(segment
		(start 364.51667 -294.019732)
		(end 364.517686 -294.019224)
		(width 0.1143)
		(layer "In4.Cu")
		(net "P5E_CPU0_P3_RX_DP<3>")
	)
	(segment
		(start 364.53318 -291.421566)
		(end 364.532164 -291.421058)
		(width 0.1143)
		(layer "In4.Cu")
		(net "P5E_CPU0_P3_RX_DP<3>")
	)
	(segment
		(start 364.495842 -295.651682)
		(end 364.499398 -295.649142)
		(width 0.1143)
		(layer "In4.Cu")
		(net "P5E_CPU0_P3_RX_DP<3>")
	)
	(segment
		(start 364.523528 -291.415978)
		(end 364.522004 -291.415216)
		(width 0.1143)
		(layer "In4.Cu")
		(net "P5E_CPU0_P3_RX_DP<3>")
	)
	(segment
		(start 375.248678 -393.428982)
		(end 374.932702 -393.113006)
		(width 0.14224)
		(layer "In4.Cu")
		(net "P5E_CPU0_P3_RX_DP<3>")
	)
	(segment
		(start 364.532164 -291.421058)
		(end 364.53064 -291.420042)
		(width 0.1143)
		(layer "In4.Cu")
		(net "P5E_CPU0_P3_RX_DP<3>")
	)
	(segment
		(start 364.528862 -293.039038)
		(end 364.527846 -293.03853)
		(width 0.1143)
		(layer "In4.Cu")
		(net "P5E_CPU0_P3_RX_DP<3>")
	)
	(segment
		(start 364.52429 -291.416486)
		(end 364.523528 -291.415978)
		(width 0.1143)
		(layer "In4.Cu")
		(net "P5E_CPU0_P3_RX_DP<3>")
	)
	(segment
		(start 370.091462 -382.59512)
		(end 370.091462 -376.426222)
		(width 0.14224)
		(layer "In4.Cu")
		(net "P5E_CPU0_P3_RX_DP<3>")
	)
	(segment
		(start 364.530386 -292.391846)
		(end 364.534958 -292.389306)
		(width 0.1143)
		(layer "In4.Cu")
		(net "P5E_CPU0_P3_RX_DP<3>")
	)
	(segment
		(start 364.496096 -294.03167)
		(end 364.51667 -294.019732)
		(width 0.1143)
		(layer "In4.Cu")
		(net "P5E_CPU0_P3_RX_DP<3>")
	)
	(segment
		(start 364.386114 -298.763436)
		(end 364.386114 -296.35831)
		(width 0.14224)
		(layer "In4.Cu")
		(net "P5E_CPU0_P3_RX_DP<3>")
	)
	(segment
		(start 375.248678 -393.842494)
		(end 375.248678 -393.428982)
		(width 0.14224)
		(layer "In4.Cu")
		(net "P5E_CPU0_P3_RX_DP<3>")
	)
	(segment
		(start 364.519972 -294.017954)
		(end 364.521242 -294.017192)
		(width 0.1143)
		(layer "In4.Cu")
		(net "P5E_CPU0_P3_RX_DP<3>")
	)
	(segment
		(start 364.517686 -292.399212)
		(end 364.518448 -292.398704)
		(width 0.1143)
		(layer "In4.Cu")
		(net "P5E_CPU0_P3_RX_DP<3>")
	)
	(segment
		(start 364.527084 -289.153854)
		(end 364.527846 -289.153346)
		(width 0.1143)
		(layer "In4.Cu")
		(net "P5E_CPU0_P3_RX_DP<3>")
	)
	(segment
		(start 364.530386 -294.011858)
		(end 364.534958 -294.009318)
		(width 0.1143)
		(layer "In4.Cu")
		(net "P5E_CPU0_P3_RX_DP<3>")
	)
	(segment
		(start 364.534958 -292.389306)
		(end 364.566962 -292.37051)
		(width 0.1143)
		(layer "In4.Cu")
		(net "P5E_CPU0_P3_RX_DP<3>")
	)
	(segment
		(start 364.527846 -291.418518)
		(end 364.527084 -291.41801)
		(width 0.1143)
		(layer "In4.Cu")
		(net "P5E_CPU0_P3_RX_DP<3>")
	)
	(segment
		(start 364.522004 -291.415216)
		(end 364.521242 -291.414708)
		(width 0.1143)
		(layer "In4.Cu")
		(net "P5E_CPU0_P3_RX_DP<3>")
	)
	(segment
		(start 364.534704 -291.422582)
		(end 364.53318 -291.421566)
		(width 0.1143)
		(layer "In4.Cu")
		(net "P5E_CPU0_P3_RX_DP<3>")
	)
	(segment
		(start 364.528862 -289.152838)
		(end 364.530386 -289.151822)
		(width 0.1143)
		(layer "In4.Cu")
		(net "P5E_CPU0_P3_RX_DP<3>")
	)
	(segment
		(start 374.8913 -394.385292)
		(end 374.986296 -394.031216)
		(width 0.14224)
		(layer "In4.Cu")
		(net "P5E_CPU0_P3_RX_DP<3>")
	)
	(segment
		(start 370.091462 -376.426222)
		(end 370.091716 -376.426476)
		(width 0.14224)
		(layer "In4.Cu")
		(net "P5E_CPU0_P3_RX_DP<3>")
	)
	(segment
		(start 364.530386 -293.040054)
		(end 364.528862 -293.039038)
		(width 0.1143)
		(layer "In4.Cu")
		(net "P5E_CPU0_P3_RX_DP<3>")
	)
	(segment
		(start 364.528862 -291.419026)
		(end 364.527846 -291.418518)
		(width 0.1143)
		(layer "In4.Cu")
		(net "P5E_CPU0_P3_RX_DP<3>")
	)
	(segment
		(start 374.932702 -393.113006)
		(end 374.938036 -392.437366)
		(width 0.14224)
		(layer "In4.Cu")
		(net "P5E_CPU0_P3_RX_DP<3>")
	)
	(segment
		(start 382.414018 -355.528372)
		(end 383.19456 -349.781622)
		(width 0.14224)
		(layer "In4.Cu")
		(net "P5E_CPU0_P3_RX_DP<3>")
	)
	(segment
		(start 364.521242 -291.414708)
		(end 364.518448 -291.413184)
		(width 0.1143)
		(layer "In4.Cu")
		(net "P5E_CPU0_P3_RX_DP<3>")
	)
	(segment
		(start 364.565946 -294.68064)
		(end 364.531148 -294.660574)
		(width 0.1143)
		(layer "In4.Cu")
		(net "P5E_CPU0_P3_RX_DP<3>")
	)
	(segment
		(start 374.986296 -394.031216)
		(end 375.16054 -393.930632)
		(width 0.14224)
		(layer "In4.Cu")
		(net "P5E_CPU0_P3_RX_DP<3>")
	)
	(segment
		(start 364.527846 -294.013382)
		(end 364.528862 -294.012874)
		(width 0.1143)
		(layer "In4.Cu")
		(net "P5E_CPU0_P3_RX_DP<3>")
	)
	(segment
		(start 364.8075 -295.14546)
		(end 364.8075 -295.140634)
		(width 0.1143)
		(layer "In4.Cu")
		(net "P5E_CPU0_P3_RX_DP<3>")
	)
	(segment
		(start 375.93905 -315.077856)
		(end 367.371884 -304.638964)
		(width 0.14224)
		(layer "In4.Cu")
		(net "P5E_CPU0_P3_RX_DP<3>")
	)
	(segment
		(start 364.345728 -291.113464)
		(end 364.345728 -291.101272)
		(width 0.1143)
		(layer "In4.Cu")
		(net "P5E_CPU0_P3_RX_DP<3>")
	)
	(segment
		(start 383.19456 -337.438746)
		(end 381.97028 -330.620624)
		(width 0.14224)
		(layer "In4.Cu")
		(net "P5E_CPU0_P3_RX_DP<3>")
	)
	(segment
		(start 364.340394 -295.954704)
		(end 364.339886 -295.954704)
		(width 0.1143)
		(layer "In4.Cu")
		(net "P5E_CPU0_P3_RX_DP<3>")
	)
	(segment
		(start 364.531148 -294.660574)
		(end 364.528862 -294.65905)
		(width 0.1143)
		(layer "In4.Cu")
		(net "P5E_CPU0_P3_RX_DP<3>")
	)
	(segment
		(start 364.51667 -292.39972)
		(end 364.517686 -292.399212)
		(width 0.1143)
		(layer "In4.Cu")
		(net "P5E_CPU0_P3_RX_DP<3>")
	)
	(segment
		(start 364.528862 -292.392862)
		(end 364.530386 -292.391846)
		(width 0.1143)
		(layer "In4.Cu")
		(net "P5E_CPU0_P3_RX_DP<3>")
	)
	(segment
		(start 364.559342 -291.436806)
		(end 364.534704 -291.422582)
		(width 0.1143)
		(layer "In4.Cu")
		(net "P5E_CPU0_P3_RX_DP<3>")
	)
	(segment
		(start 365.356902 -287.856168)
		(end 365.654844 -287.856168)
		(width 0.1143)
		(layer "In4.Cu")
		(net "P5E_CPU0_P3_RX_DP<3>")
	)
	(segment
		(start 364.534958 -294.009318)
		(end 364.566962 -293.990522)
		(width 0.1143)
		(layer "In4.Cu")
		(net "P5E_CPU0_P3_RX_DP<3>")
	)
	(segment
		(start 364.52429 -292.395402)
		(end 364.527084 -292.393878)
		(width 0.1143)
		(layer "In4.Cu")
		(net "P5E_CPU0_P3_RX_DP<3>")
	)
	(segment
		(start 364.52429 -289.155378)
		(end 364.527084 -289.153854)
		(width 0.1143)
		(layer "In4.Cu")
		(net "P5E_CPU0_P3_RX_DP<3>")
	)
	(segment
		(start 364.53064 -291.420042)
		(end 364.528862 -291.419026)
		(width 0.1143)
		(layer "In4.Cu")
		(net "P5E_CPU0_P3_RX_DP<3>")
	)
	(segment
		(start 379.87224 -324.58152)
		(end 377.743466 -318.453008)
		(width 0.14224)
		(layer "In4.Cu")
		(net "P5E_CPU0_P3_RX_DP<3>")
	)
	(segment
		(start 364.522004 -289.156648)
		(end 364.523528 -289.155886)
		(width 0.1143)
		(layer "In4.Cu")
		(net "P5E_CPU0_P3_RX_DP<3>")
	)
	(segment
		(start 364.51667 -289.159696)
		(end 364.517686 -289.159188)
		(width 0.1143)
		(layer "In4.Cu")
		(net "P5E_CPU0_P3_RX_DP<3>")
	)
	(segment
		(start 379.87224 -324.581774)
		(end 379.87224 -324.58152)
		(width 0.14224)
		(layer "In4.Cu")
		(net "P5E_CPU0_P3_RX_DP<3>")
	)
	(segment
		(start 364.496096 -292.411658)
		(end 364.51667 -292.39972)
		(width 0.1143)
		(layer "In4.Cu")
		(net "P5E_CPU0_P3_RX_DP<3>")
	)
	(segment
		(start 383.19456 -349.781622)
		(end 383.19456 -337.438746)
		(width 0.14224)
		(layer "In4.Cu")
		(net "P5E_CPU0_P3_RX_DP<3>")
	)
	(segment
		(start 364.519972 -289.157918)
		(end 364.521242 -289.157156)
		(width 0.1143)
		(layer "In4.Cu")
		(net "P5E_CPU0_P3_RX_DP<3>")
	)
	(segment
		(start 364.530386 -289.151822)
		(end 364.534958 -289.149282)
		(width 0.1143)
		(layer "In4.Cu")
		(net "P5E_CPU0_P3_RX_DP<3>")
	)
	(segment
		(start 365.890556 -302.421544)
		(end 364.395766 -298.812204)
		(width 0.14224)
		(layer "In4.Cu")
		(net "P5E_CPU0_P3_RX_DP<3>")
	)
	(segment
		(start 364.386114 -296.329862)
		(end 364.340394 -296.284142)
		(width 0.1143)
		(layer "In4.Cu")
		(net "P5E_CPU0_P3_RX_DP<3>")
	)
	(segment
		(start 364.521242 -289.157156)
		(end 364.522004 -289.156648)
		(width 0.1143)
		(layer "In4.Cu")
		(net "P5E_CPU0_P3_RX_DP<3>")
	)
	(segment
		(start 381.97028 -330.620624)
		(end 379.87224 -324.581774)
		(width 0.14224)
		(layer "In4.Cu")
		(net "P5E_CPU0_P3_RX_DP<3>")
	)
	(arc
		(start 374.78081 -388.43331)
		(mid 374.356956 -387.248463)
		(end 373.60733 -386.237734)
		(width 0.14224)
		(layer "In4.Cu")
		(net "P5E_CPU0_P3_RX_DP<3>")
	)
	(arc
		(start 364.561882 -295.611042)
		(mid 364.742328 -295.408647)
		(end 364.8075 -295.14546)
		(width 0.1143)
		(layer "In4.Cu")
		(net "P5E_CPU0_P3_RX_DP<3>")
	)
	(arc
		(start 364.566962 -292.37051)
		(mid 364.810289 -291.905944)
		(end 364.566962 -291.441378)
		(width 0.1143)
		(layer "In4.Cu")
		(net "P5E_CPU0_P3_RX_DP<3>")
	)
	(arc
		(start 364.345982 -295.900348)
		(mid 364.398101 -295.762272)
		(end 364.495842 -295.651682)
		(width 0.1143)
		(layer "In4.Cu")
		(net "P5E_CPU0_P3_RX_DP<3>")
	)
	(arc
		(start 364.518448 -291.413184)
		(mid 364.392014 -291.286421)
		(end 364.345728 -291.113464)
		(width 0.1143)
		(layer "In4.Cu")
		(net "P5E_CPU0_P3_RX_DP<3>")
	)
	(arc
		(start 364.34014 -289.475926)
		(mid 364.381395 -289.304955)
		(end 364.496096 -289.171634)
		(width 0.1143)
		(layer "In4.Cu")
		(net "P5E_CPU0_P3_RX_DP<3>")
	)
	(arc
		(start 364.810294 -288.66592)
		(mid 364.85126 -288.495514)
		(end 364.965234 -288.36239)
		(width 0.1143)
		(layer "In4.Cu")
		(net "P5E_CPU0_P3_RX_DP<3>")
	)
	(arc
		(start 364.027212 -290.590732)
		(mid 363.870235 -290.285932)
		(end 364.027212 -289.981132)
		(width 0.1143)
		(layer "In4.Cu")
		(net "P5E_CPU0_P3_RX_DP<3>")
	)
	(arc
		(start 364.499398 -295.649142)
		(mid 364.525071 -295.632511)
		(end 364.551214 -295.61663)
		(width 0.1143)
		(layer "In4.Cu")
		(net "P5E_CPU0_P3_RX_DP<3>")
	)
	(arc
		(start 364.566962 -293.990522)
		(mid 364.810289 -293.525956)
		(end 364.566962 -293.06139)
		(width 0.1143)
		(layer "In4.Cu")
		(net "P5E_CPU0_P3_RX_DP<3>")
	)
	(arc
		(start 364.096808 -289.940492)
		(mid 364.275621 -289.738142)
		(end 364.34014 -289.475926)
		(width 0.1143)
		(layer "In4.Cu")
		(net "P5E_CPU0_P3_RX_DP<3>")
	)
	(arc
		(start 364.496096 -294.640254)
		(mid 364.340168 -294.335962)
		(end 364.496096 -294.03167)
		(width 0.1143)
		(layer "In4.Cu")
		(net "P5E_CPU0_P3_RX_DP<3>")
	)
	(arc
		(start 365.036862 -288.320734)
		(mid 365.188849 -288.164226)
		(end 365.270288 -287.961832)
		(width 0.1143)
		(layer "In4.Cu")
		(net "P5E_CPU0_P3_RX_DP<3>")
	)
	(arc
		(start 364.395766 -298.812204)
		(mid 364.388521 -298.788297)
		(end 364.386114 -298.763436)
		(width 0.14224)
		(layer "In4.Cu")
		(net "P5E_CPU0_P3_RX_DP<3>")
	)
	(arc
		(start 364.345728 -291.101272)
		(mid 364.270775 -290.820023)
		(end 364.06582 -290.613338)
		(width 0.1143)
		(layer "In4.Cu")
		(net "P5E_CPU0_P3_RX_DP<3>")
	)
	(arc
		(start 364.339886 -295.952672)
		(mid 364.342093 -295.926412)
		(end 364.345982 -295.900348)
		(width 0.1143)
		(layer "In4.Cu")
		(net "P5E_CPU0_P3_RX_DP<3>")
	)
	(arc
		(start 364.339886 -295.954704)
		(mid 364.339885 -295.953688)
		(end 364.339886 -295.952672)
		(width 0.1143)
		(layer "In4.Cu")
		(net "P5E_CPU0_P3_RX_DP<3>")
	)
	(arc
		(start 364.566962 -289.130486)
		(mid 364.745775 -288.928136)
		(end 364.810294 -288.66592)
		(width 0.1143)
		(layer "In4.Cu")
		(net "P5E_CPU0_P3_RX_DP<3>")
	)
	(arc
		(start 382.359408 -355.683566)
		(mid 382.394581 -355.608739)
		(end 382.414018 -355.528372)
		(width 0.14224)
		(layer "In4.Cu")
		(net "P5E_CPU0_P3_RX_DP<3>")
	)
	(arc
		(start 364.8075 -295.140634)
		(mid 364.743496 -294.880823)
		(end 364.565946 -294.68064)
		(width 0.1143)
		(layer "In4.Cu")
		(net "P5E_CPU0_P3_RX_DP<3>")
	)
	(arc
		(start 370.181124 -382.811528)
		(mid 370.114781 -382.712239)
		(end 370.091462 -382.59512)
		(width 0.14224)
		(layer "In4.Cu")
		(net "P5E_CPU0_P3_RX_DP<3>")
	)
	(arc
		(start 370.091716 -376.426476)
		(mid 370.127489 -376.161494)
		(end 370.232686 -375.915682)
		(width 0.14224)
		(layer "In4.Cu")
		(net "P5E_CPU0_P3_RX_DP<3>")
	)
	(arc
		(start 365.270288 -287.961832)
		(mid 365.272311 -287.950422)
		(end 365.274098 -287.938972)
		(width 0.1143)
		(layer "In4.Cu")
		(net "P5E_CPU0_P3_RX_DP<3>")
	)
	(arc
		(start 375.24055 -391.249154)
		(mid 375.215831 -390.746987)
		(end 375.141998 -390.249664)
		(width 0.14224)
		(layer "In4.Cu")
		(net "P5E_CPU0_P3_RX_DP<3>")
	)
	(arc
		(start 364.496096 -293.020242)
		(mid 364.340168 -292.71595)
		(end 364.496096 -292.411658)
		(width 0.1143)
		(layer "In4.Cu")
		(net "P5E_CPU0_P3_RX_DP<3>")
	)
	(segment
		(start 373.17045 -394.385292)
		(end 373.69115 -394.385292)
		(width 0.127)
		(layer "F.Cu")
		(net "P5E_CPU0_P3_RX_DP<2>")
	)
	(segment
		(start 362.837984 -290.019994)
		(end 363.304836 -290.285932)
		(width 0.12954)
		(layer "F.Cu")
		(net "P5E_CPU0_P3_RX_DP<2>")
	)
	(segment
		(start 363.577632 -291.412676)
		(end 363.556042 -291.40023)
		(width 0.1143)
		(layer "In4.Cu")
		(net "P5E_CPU0_P3_RX_DP<2>")
	)
	(segment
		(start 363.626908 -291.441378)
		(end 363.598206 -291.424614)
		(width 0.1143)
		(layer "In4.Cu")
		(net "P5E_CPU0_P3_RX_DP<2>")
	)
	(segment
		(start 376.886978 -318.829182)
		(end 375.176288 -315.629036)
		(width 0.14224)
		(layer "In4.Cu")
		(net "P5E_CPU0_P3_RX_DP<2>")
	)
	(segment
		(start 363.58195 -294.016684)
		(end 363.583474 -294.015922)
		(width 0.1143)
		(layer "In4.Cu")
		(net "P5E_CPU0_P3_RX_DP<2>")
	)
	(segment
		(start 382.257808 -349.644208)
		(end 382.257808 -337.534504)
		(width 0.14224)
		(layer "In4.Cu")
		(net "P5E_CPU0_P3_RX_DP<2>")
	)
	(segment
		(start 363.156754 -290.631372)
		(end 363.087158 -290.590732)
		(width 0.1143)
		(layer "In4.Cu")
		(net "P5E_CPU0_P3_RX_DP<2>")
	)
	(segment
		(start 363.583474 -292.39591)
		(end 363.584236 -292.395402)
		(width 0.1143)
		(layer "In4.Cu")
		(net "P5E_CPU0_P3_RX_DP<2>")
	)
	(segment
		(start 374.0404 -392.088116)
		(end 374.0404 -391.194544)
		(width 0.14224)
		(layer "In4.Cu")
		(net "P5E_CPU0_P3_RX_DP<2>")
	)
	(segment
		(start 363.578394 -291.413184)
		(end 363.577632 -291.412676)
		(width 0.1143)
		(layer "In4.Cu")
		(net "P5E_CPU0_P3_RX_DP<2>")
	)
	(segment
		(start 363.445806 -298.934886)
		(end 363.445806 -296.35831)
		(width 0.14224)
		(layer "In4.Cu")
		(net "P5E_CPU0_P3_RX_DP<2>")
	)
	(segment
		(start 363.583474 -294.015922)
		(end 363.584236 -294.015414)
		(width 0.1143)
		(layer "In4.Cu")
		(net "P5E_CPU0_P3_RX_DP<2>")
	)
	(segment
		(start 363.445806 -296.35831)
		(end 363.445806 -296.329862)
		(width 0.1143)
		(layer "In4.Cu")
		(net "P5E_CPU0_P3_RX_DP<2>")
	)
	(segment
		(start 363.584236 -294.015414)
		(end 363.58703 -294.01389)
		(width 0.1143)
		(layer "In4.Cu")
		(net "P5E_CPU0_P3_RX_DP<2>")
	)
	(segment
		(start 363.58576 -295.634664)
		(end 363.58703 -295.633902)
		(width 0.1143)
		(layer "In4.Cu")
		(net "P5E_CPU0_P3_RX_DP<2>")
	)
	(segment
		(start 363.578394 -294.653208)
		(end 363.577632 -294.6527)
		(width 0.1143)
		(layer "In4.Cu")
		(net "P5E_CPU0_P3_RX_DP<2>")
	)
	(segment
		(start 363.587792 -295.633394)
		(end 363.588808 -295.632886)
		(width 0.1143)
		(layer "In4.Cu")
		(net "P5E_CPU0_P3_RX_DP<2>")
	)
	(segment
		(start 381.634238 -353.845876)
		(end 382.257808 -349.644208)
		(width 0.14224)
		(layer "In4.Cu")
		(net "P5E_CPU0_P3_RX_DP<2>")
	)
	(segment
		(start 363.59719 -294.66413)
		(end 363.595158 -294.66286)
		(width 0.1143)
		(layer "In4.Cu")
		(net "P5E_CPU0_P3_RX_DP<2>")
	)
	(segment
		(start 363.58703 -294.01389)
		(end 363.587792 -294.013382)
		(width 0.1143)
		(layer "In4.Cu")
		(net "P5E_CPU0_P3_RX_DP<2>")
	)
	(segment
		(start 365.068866 -302.878998)
		(end 363.455458 -298.983654)
		(width 0.14224)
		(layer "In4.Cu")
		(net "P5E_CPU0_P3_RX_DP<2>")
	)
	(segment
		(start 363.581188 -292.39718)
		(end 363.58195 -292.396672)
		(width 0.1143)
		(layer "In4.Cu")
		(net "P5E_CPU0_P3_RX_DP<2>")
	)
	(segment
		(start 366.801654 -376.097038)
		(end 381.569722 -354.013262)
		(width 0.14224)
		(layer "In4.Cu")
		(net "P5E_CPU0_P3_RX_DP<2>")
	)
	(segment
		(start 363.595158 -294.66286)
		(end 363.578394 -294.653208)
		(width 0.1143)
		(layer "In4.Cu")
		(net "P5E_CPU0_P3_RX_DP<2>")
	)
	(segment
		(start 363.581188 -294.017192)
		(end 363.58195 -294.016684)
		(width 0.1143)
		(layer "In4.Cu")
		(net "P5E_CPU0_P3_RX_DP<2>")
	)
	(segment
		(start 368.389662 -382.345438)
		(end 368.389662 -379.562106)
		(width 0.14224)
		(layer "In4.Cu")
		(net "P5E_CPU0_P3_RX_DP<2>")
	)
	(segment
		(start 373.944134 -390.21512)
		(end 373.655082 -388.761478)
		(width 0.14224)
		(layer "In4.Cu")
		(net "P5E_CPU0_P3_RX_DP<2>")
	)
	(segment
		(start 363.556042 -295.651682)
		(end 363.58068 -295.637458)
		(width 0.1143)
		(layer "In4.Cu")
		(net "P5E_CPU0_P3_RX_DP<2>")
	)
	(segment
		(start 363.626908 -293.06139)
		(end 363.598206 -293.044626)
		(width 0.1143)
		(layer "In4.Cu")
		(net "P5E_CPU0_P3_RX_DP<2>")
	)
	(segment
		(start 363.590332 -292.391846)
		(end 363.626908 -292.37051)
		(width 0.1143)
		(layer "In4.Cu")
		(net "P5E_CPU0_P3_RX_DP<2>")
	)
	(segment
		(start 363.588808 -295.632886)
		(end 363.590586 -295.63187)
		(width 0.1143)
		(layer "In4.Cu")
		(net "P5E_CPU0_P3_RX_DP<2>")
	)
	(segment
		(start 363.598206 -293.044626)
		(end 363.59719 -293.044118)
		(width 0.1143)
		(layer "In4.Cu")
		(net "P5E_CPU0_P3_RX_DP<2>")
	)
	(segment
		(start 363.445806 -296.329862)
		(end 363.400086 -296.284142)
		(width 0.1143)
		(layer "In4.Cu")
		(net "P5E_CPU0_P3_RX_DP<2>")
	)
	(segment
		(start 373.69115 -394.385292)
		(end 373.786146 -394.031216)
		(width 0.14224)
		(layer "In4.Cu")
		(net "P5E_CPU0_P3_RX_DP<2>")
	)
	(segment
		(start 374.048528 -393.428982)
		(end 373.732552 -393.113006)
		(width 0.14224)
		(layer "In4.Cu")
		(net "P5E_CPU0_P3_RX_DP<2>")
	)
	(segment
		(start 366.63249 -305.218338)
		(end 365.068866 -302.878998)
		(width 0.14224)
		(layer "In4.Cu")
		(net "P5E_CPU0_P3_RX_DP<2>")
	)
	(segment
		(start 363.58322 -295.635934)
		(end 363.58576 -295.634664)
		(width 0.1143)
		(layer "In4.Cu")
		(net "P5E_CPU0_P3_RX_DP<2>")
	)
	(segment
		(start 363.588808 -294.012874)
		(end 363.590332 -294.011858)
		(width 0.1143)
		(layer "In4.Cu")
		(net "P5E_CPU0_P3_RX_DP<2>")
	)
	(segment
		(start 382.251458 -337.462114)
		(end 381.065786 -330.859384)
		(width 0.14224)
		(layer "In4.Cu")
		(net "P5E_CPU0_P3_RX_DP<2>")
	)
	(segment
		(start 372.990872 -387.518656)
		(end 368.794284 -383.322068)
		(width 0.14224)
		(layer "In4.Cu")
		(net "P5E_CPU0_P3_RX_DP<2>")
	)
	(segment
		(start 374.048528 -393.842494)
		(end 374.048528 -393.428982)
		(width 0.14224)
		(layer "In4.Cu")
		(net "P5E_CPU0_P3_RX_DP<2>")
	)
	(segment
		(start 363.577632 -293.032688)
		(end 363.556042 -293.020242)
		(width 0.1143)
		(layer "In4.Cu")
		(net "P5E_CPU0_P3_RX_DP<2>")
	)
	(segment
		(start 363.598206 -291.424614)
		(end 363.59719 -291.424106)
		(width 0.1143)
		(layer "In4.Cu")
		(net "P5E_CPU0_P3_RX_DP<2>")
	)
	(segment
		(start 363.579918 -294.017954)
		(end 363.581188 -294.017192)
		(width 0.1143)
		(layer "In4.Cu")
		(net "P5E_CPU0_P3_RX_DP<2>")
	)
	(segment
		(start 362.937044 -290.355782)
		(end 363.006894 -290.285932)
		(width 0.1143)
		(layer "In4.Cu")
		(net "P5E_CPU0_P3_RX_DP<2>")
	)
	(segment
		(start 363.587792 -292.39337)
		(end 363.588808 -292.392862)
		(width 0.1143)
		(layer "In4.Cu")
		(net "P5E_CPU0_P3_RX_DP<2>")
	)
	(segment
		(start 363.579918 -292.397942)
		(end 363.581188 -292.39718)
		(width 0.1143)
		(layer "In4.Cu")
		(net "P5E_CPU0_P3_RX_DP<2>")
	)
	(segment
		(start 363.006894 -290.285932)
		(end 363.304836 -290.285932)
		(width 0.1143)
		(layer "In4.Cu")
		(net "P5E_CPU0_P3_RX_DP<2>")
	)
	(segment
		(start 366.61979 -377.737878)
		(end 366.61979 -376.696224)
		(width 0.14224)
		(layer "In4.Cu")
		(net "P5E_CPU0_P3_RX_DP<2>")
	)
	(segment
		(start 367.122964 -378.43587)
		(end 366.89919 -378.343414)
		(width 0.14224)
		(layer "In4.Cu")
		(net "P5E_CPU0_P3_RX_DP<2>")
	)
	(segment
		(start 363.578394 -293.033196)
		(end 363.577632 -293.032688)
		(width 0.1143)
		(layer "In4.Cu")
		(net "P5E_CPU0_P3_RX_DP<2>")
	)
	(segment
		(start 363.595158 -293.042848)
		(end 363.578394 -293.033196)
		(width 0.1143)
		(layer "In4.Cu")
		(net "P5E_CPU0_P3_RX_DP<2>")
	)
	(segment
		(start 363.58703 -295.633902)
		(end 363.587792 -295.633394)
		(width 0.1143)
		(layer "In4.Cu")
		(net "P5E_CPU0_P3_RX_DP<2>")
	)
	(segment
		(start 363.400086 -296.284142)
		(end 363.400086 -295.955974)
		(width 0.1143)
		(layer "In4.Cu")
		(net "P5E_CPU0_P3_RX_DP<2>")
	)
	(segment
		(start 373.738394 -392.390122)
		(end 374.0404 -392.088116)
		(width 0.14224)
		(layer "In4.Cu")
		(net "P5E_CPU0_P3_RX_DP<2>")
	)
	(segment
		(start 366.620044 -377.737624)
		(end 366.61979 -377.737878)
		(width 0.14224)
		(layer "In4.Cu")
		(net "P5E_CPU0_P3_RX_DP<2>")
	)
	(segment
		(start 363.590586 -295.63187)
		(end 363.626908 -295.610534)
		(width 0.1143)
		(layer "In4.Cu")
		(net "P5E_CPU0_P3_RX_DP<2>")
	)
	(segment
		(start 373.96039 -393.930632)
		(end 374.048528 -393.842494)
		(width 0.14224)
		(layer "In4.Cu")
		(net "P5E_CPU0_P3_RX_DP<2>")
	)
	(segment
		(start 363.58195 -292.396672)
		(end 363.583474 -292.39591)
		(width 0.1143)
		(layer "In4.Cu")
		(net "P5E_CPU0_P3_RX_DP<2>")
	)
	(segment
		(start 363.58703 -292.393878)
		(end 363.587792 -292.39337)
		(width 0.1143)
		(layer "In4.Cu")
		(net "P5E_CPU0_P3_RX_DP<2>")
	)
	(segment
		(start 363.595158 -291.422836)
		(end 363.578394 -291.413184)
		(width 0.1143)
		(layer "In4.Cu")
		(net "P5E_CPU0_P3_RX_DP<2>")
	)
	(segment
		(start 363.626908 -294.681402)
		(end 363.598206 -294.664638)
		(width 0.1143)
		(layer "In4.Cu")
		(net "P5E_CPU0_P3_RX_DP<2>")
	)
	(segment
		(start 363.577632 -294.6527)
		(end 363.556042 -294.640254)
		(width 0.1143)
		(layer "In4.Cu")
		(net "P5E_CPU0_P3_RX_DP<2>")
	)
	(segment
		(start 381.065786 -330.859384)
		(end 376.886978 -318.829182)
		(width 0.14224)
		(layer "In4.Cu")
		(net "P5E_CPU0_P3_RX_DP<2>")
	)
	(segment
		(start 363.59719 -291.424106)
		(end 363.595158 -291.422836)
		(width 0.1143)
		(layer "In4.Cu")
		(net "P5E_CPU0_P3_RX_DP<2>")
	)
	(segment
		(start 363.58068 -295.637458)
		(end 363.58322 -295.635934)
		(width 0.1143)
		(layer "In4.Cu")
		(net "P5E_CPU0_P3_RX_DP<2>")
	)
	(segment
		(start 363.587792 -294.013382)
		(end 363.588808 -294.012874)
		(width 0.1143)
		(layer "In4.Cu")
		(net "P5E_CPU0_P3_RX_DP<2>")
	)
	(segment
		(start 373.786146 -394.031216)
		(end 373.96039 -393.930632)
		(width 0.14224)
		(layer "In4.Cu")
		(net "P5E_CPU0_P3_RX_DP<2>")
	)
	(segment
		(start 363.590332 -294.011858)
		(end 363.626908 -293.990522)
		(width 0.1143)
		(layer "In4.Cu")
		(net "P5E_CPU0_P3_RX_DP<2>")
	)
	(segment
		(start 367.94694 -378.708666)
		(end 367.588038 -378.56033)
		(width 0.14224)
		(layer "In4.Cu")
		(net "P5E_CPU0_P3_RX_DP<2>")
	)
	(segment
		(start 363.556042 -292.411658)
		(end 363.579918 -292.397942)
		(width 0.1143)
		(layer "In4.Cu")
		(net "P5E_CPU0_P3_RX_DP<2>")
	)
	(segment
		(start 373.732552 -393.113006)
		(end 373.738394 -392.390122)
		(width 0.14224)
		(layer "In4.Cu")
		(net "P5E_CPU0_P3_RX_DP<2>")
	)
	(segment
		(start 363.598206 -294.664638)
		(end 363.59719 -294.66413)
		(width 0.1143)
		(layer "In4.Cu")
		(net "P5E_CPU0_P3_RX_DP<2>")
	)
	(segment
		(start 363.556042 -294.03167)
		(end 363.579918 -294.017954)
		(width 0.1143)
		(layer "In4.Cu")
		(net "P5E_CPU0_P3_RX_DP<2>")
	)
	(segment
		(start 363.59719 -293.044118)
		(end 363.595158 -293.042848)
		(width 0.1143)
		(layer "In4.Cu")
		(net "P5E_CPU0_P3_RX_DP<2>")
	)
	(segment
		(start 375.176288 -315.629036)
		(end 366.63249 -305.218338)
		(width 0.14224)
		(layer "In4.Cu")
		(net "P5E_CPU0_P3_RX_DP<2>")
	)
	(segment
		(start 363.588808 -292.392862)
		(end 363.590332 -292.391846)
		(width 0.1143)
		(layer "In4.Cu")
		(net "P5E_CPU0_P3_RX_DP<2>")
	)
	(segment
		(start 363.584236 -292.395402)
		(end 363.58703 -292.393878)
		(width 0.1143)
		(layer "In4.Cu")
		(net "P5E_CPU0_P3_RX_DP<2>")
	)
	(arc
		(start 363.556042 -293.020242)
		(mid 363.400114 -292.71595)
		(end 363.556042 -292.411658)
		(width 0.1143)
		(layer "In4.Cu")
		(net "P5E_CPU0_P3_RX_DP<2>")
	)
	(arc
		(start 373.655082 -388.761478)
		(mid 373.415167 -388.090798)
		(end 372.990872 -387.518656)
		(width 0.14224)
		(layer "In4.Cu")
		(net "P5E_CPU0_P3_RX_DP<2>")
	)
	(arc
		(start 363.400086 -291.095938)
		(mid 363.335571 -290.833719)
		(end 363.156754 -290.631372)
		(width 0.1143)
		(layer "In4.Cu")
		(net "P5E_CPU0_P3_RX_DP<2>")
	)
	(arc
		(start 363.400086 -295.955974)
		(mid 363.441341 -295.785003)
		(end 363.556042 -295.651682)
		(width 0.1143)
		(layer "In4.Cu")
		(net "P5E_CPU0_P3_RX_DP<2>")
	)
	(arc
		(start 363.626908 -295.610534)
		(mid 363.870235 -295.145968)
		(end 363.626908 -294.681402)
		(width 0.1143)
		(layer "In4.Cu")
		(net "P5E_CPU0_P3_RX_DP<2>")
	)
	(arc
		(start 382.257808 -337.534504)
		(mid 382.256238 -337.498168)
		(end 382.251458 -337.462114)
		(width 0.14224)
		(layer "In4.Cu")
		(net "P5E_CPU0_P3_RX_DP<2>")
	)
	(arc
		(start 367.355882 -378.498354)
		(mid 367.237375 -378.474746)
		(end 367.122964 -378.43587)
		(width 0.14224)
		(layer "In4.Cu")
		(net "P5E_CPU0_P3_RX_DP<2>")
	)
	(arc
		(start 363.455458 -298.983654)
		(mid 363.448213 -298.959747)
		(end 363.445806 -298.934886)
		(width 0.14224)
		(layer "In4.Cu")
		(net "P5E_CPU0_P3_RX_DP<2>")
	)
	(arc
		(start 367.588038 -378.56033)
		(mid 367.473981 -378.521774)
		(end 367.355882 -378.498354)
		(width 0.14224)
		(layer "In4.Cu")
		(net "P5E_CPU0_P3_RX_DP<2>")
	)
	(arc
		(start 366.798606 -378.266198)
		(mid 366.665787 -378.016616)
		(end 366.620044 -377.737624)
		(width 0.14224)
		(layer "In4.Cu")
		(net "P5E_CPU0_P3_RX_DP<2>")
	)
	(arc
		(start 363.626908 -292.37051)
		(mid 363.870235 -291.905944)
		(end 363.626908 -291.441378)
		(width 0.1143)
		(layer "In4.Cu")
		(net "P5E_CPU0_P3_RX_DP<2>")
	)
	(arc
		(start 366.89919 -378.343414)
		(mid 366.843803 -378.311448)
		(end 366.798606 -378.266198)
		(width 0.14224)
		(layer "In4.Cu")
		(net "P5E_CPU0_P3_RX_DP<2>")
	)
	(arc
		(start 368.794284 -383.322068)
		(mid 368.494832 -382.874001)
		(end 368.389662 -382.345438)
		(width 0.14224)
		(layer "In4.Cu")
		(net "P5E_CPU0_P3_RX_DP<2>")
	)
	(arc
		(start 368.19586 -378.920248)
		(mid 368.088079 -378.794839)
		(end 367.94694 -378.708666)
		(width 0.14224)
		(layer "In4.Cu")
		(net "P5E_CPU0_P3_RX_DP<2>")
	)
	(arc
		(start 366.61979 -376.696224)
		(mid 366.666258 -376.383136)
		(end 366.801654 -376.097038)
		(width 0.14224)
		(layer "In4.Cu")
		(net "P5E_CPU0_P3_RX_DP<2>")
	)
	(arc
		(start 363.556042 -291.40023)
		(mid 363.441366 -291.266896)
		(end 363.400086 -291.095938)
		(width 0.1143)
		(layer "In4.Cu")
		(net "P5E_CPU0_P3_RX_DP<2>")
	)
	(arc
		(start 363.556042 -294.640254)
		(mid 363.400114 -294.335962)
		(end 363.556042 -294.03167)
		(width 0.1143)
		(layer "In4.Cu")
		(net "P5E_CPU0_P3_RX_DP<2>")
	)
	(arc
		(start 363.626908 -293.990522)
		(mid 363.870235 -293.525956)
		(end 363.626908 -293.06139)
		(width 0.1143)
		(layer "In4.Cu")
		(net "P5E_CPU0_P3_RX_DP<2>")
	)
	(arc
		(start 363.087158 -290.590732)
		(mid 362.989393 -290.487756)
		(end 362.937044 -290.355782)
		(width 0.1143)
		(layer "In4.Cu")
		(net "P5E_CPU0_P3_RX_DP<2>")
	)
	(arc
		(start 381.569722 -354.013262)
		(mid 381.611292 -353.933155)
		(end 381.634238 -353.845876)
		(width 0.14224)
		(layer "In4.Cu")
		(net "P5E_CPU0_P3_RX_DP<2>")
	)
	(arc
		(start 374.0404 -391.194544)
		(mid 374.016313 -390.702469)
		(end 373.944134 -390.21512)
		(width 0.14224)
		(layer "In4.Cu")
		(net "P5E_CPU0_P3_RX_DP<2>")
	)
	(arc
		(start 368.374168 -379.384814)
		(mid 368.306715 -379.144201)
		(end 368.19586 -378.920248)
		(width 0.14224)
		(layer "In4.Cu")
		(net "P5E_CPU0_P3_RX_DP<2>")
	)
	(arc
		(start 368.389662 -379.562106)
		(mid 368.385927 -379.47311)
		(end 368.374168 -379.384814)
		(width 0.14224)
		(layer "In4.Cu")
		(net "P5E_CPU0_P3_RX_DP<2>")
	)
	(segment
		(start 362.837984 -288.399982)
		(end 363.304836 -288.66592)
		(width 0.12954)
		(layer "F.Cu")
		(net "P5E_CPU0_P3_RX_DP<1>")
	)
	(segment
		(start 371.970554 -394.385292)
		(end 372.491254 -394.385292)
		(width 0.127)
		(layer "F.Cu")
		(net "P5E_CPU0_P3_RX_DP<1>")
	)
	(segment
		(start 362.643928 -289.155632)
		(end 362.646214 -289.154362)
		(width 0.1143)
		(layer "In4.Cu")
		(net "P5E_CPU0_P3_RX_DP<1>")
	)
	(segment
		(start 362.698284 -294.68953)
		(end 362.686092 -294.680894)
		(width 0.1143)
		(layer "In4.Cu")
		(net "P5E_CPU0_P3_RX_DP<1>")
	)
	(segment
		(start 381.322326 -337.563968)
		(end 380.162816 -331.108812)
		(width 0.14224)
		(layer "In4.Cu")
		(net "P5E_CPU0_P3_RX_DP<1>")
	)
	(segment
		(start 362.615988 -294.03167)
		(end 362.646976 -294.01389)
		(width 0.1143)
		(layer "In4.Cu")
		(net "P5E_CPU0_P3_RX_DP<1>")
	)
	(segment
		(start 362.615988 -292.411658)
		(end 362.641388 -292.396926)
		(width 0.1143)
		(layer "In4.Cu")
		(net "P5E_CPU0_P3_RX_DP<1>")
	)
	(segment
		(start 362.92409 -288.748724)
		(end 363.006894 -288.66592)
		(width 0.1143)
		(layer "In4.Cu")
		(net "P5E_CPU0_P3_RX_DP<1>")
	)
	(segment
		(start 376.032014 -319.210182)
		(end 374.422924 -316.197742)
		(width 0.14224)
		(layer "In4.Cu")
		(net "P5E_CPU0_P3_RX_DP<1>")
	)
	(segment
		(start 362.505752 -298.997116)
		(end 362.505752 -296.35831)
		(width 0.14224)
		(layer "In4.Cu")
		(net "P5E_CPU0_P3_RX_DP<1>")
	)
	(segment
		(start 372.760494 -393.930632)
		(end 372.848632 -393.842494)
		(width 0.14224)
		(layer "In4.Cu")
		(net "P5E_CPU0_P3_RX_DP<1>")
	)
	(segment
		(start 362.652564 -294.66159)
		(end 362.648754 -294.65905)
		(width 0.1143)
		(layer "In4.Cu")
		(net "P5E_CPU0_P3_RX_DP<1>")
	)
	(segment
		(start 362.646976 -292.393878)
		(end 362.647738 -292.39337)
		(width 0.1143)
		(layer "In4.Cu")
		(net "P5E_CPU0_P3_RX_DP<1>")
	)
	(segment
		(start 362.64342 -295.635934)
		(end 362.644182 -295.635426)
		(width 0.1143)
		(layer "In4.Cu")
		(net "P5E_CPU0_P3_RX_DP<1>")
	)
	(segment
		(start 362.505752 -296.35831)
		(end 362.505752 -296.329862)
		(width 0.1143)
		(layer "In4.Cu")
		(net "P5E_CPU0_P3_RX_DP<1>")
	)
	(segment
		(start 362.644182 -292.395402)
		(end 362.646976 -292.393878)
		(width 0.1143)
		(layer "In4.Cu")
		(net "P5E_CPU0_P3_RX_DP<1>")
	)
	(segment
		(start 362.505752 -296.329862)
		(end 362.460032 -296.284142)
		(width 0.1143)
		(layer "In4.Cu")
		(net "P5E_CPU0_P3_RX_DP<1>")
	)
	(segment
		(start 362.685076 -292.372034)
		(end 362.698284 -292.362382)
		(width 0.1143)
		(layer "In4.Cu")
		(net "P5E_CPU0_P3_RX_DP<1>")
	)
	(segment
		(start 362.461048 -291.101018)
		(end 362.454444 -291.000688)
		(width 0.1143)
		(layer "In4.Cu")
		(net "P5E_CPU0_P3_RX_DP<1>")
	)
	(segment
		(start 362.646976 -294.01389)
		(end 362.647738 -294.013382)
		(width 0.1143)
		(layer "In4.Cu")
		(net "P5E_CPU0_P3_RX_DP<1>")
	)
	(segment
		(start 362.647738 -292.39337)
		(end 362.685076 -292.372034)
		(width 0.1143)
		(layer "In4.Cu")
		(net "P5E_CPU0_P3_RX_DP<1>")
	)
	(segment
		(start 363.006894 -288.66592)
		(end 363.304836 -288.66592)
		(width 0.1143)
		(layer "In4.Cu")
		(net "P5E_CPU0_P3_RX_DP<1>")
	)
	(segment
		(start 362.641388 -292.396926)
		(end 362.64342 -292.39591)
		(width 0.1143)
		(layer "In4.Cu")
		(net "P5E_CPU0_P3_RX_DP<1>")
	)
	(segment
		(start 362.63961 -295.63822)
		(end 362.641642 -295.63695)
		(width 0.1143)
		(layer "In4.Cu")
		(net "P5E_CPU0_P3_RX_DP<1>")
	)
	(segment
		(start 372.840504 -391.959592)
		(end 372.840504 -391.024872)
		(width 0.14224)
		(layer "In4.Cu")
		(net "P5E_CPU0_P3_RX_DP<1>")
	)
	(segment
		(start 362.455714 -289.48126)
		(end 362.455714 -289.480752)
		(width 0.1143)
		(layer "In4.Cu")
		(net "P5E_CPU0_P3_RX_DP<1>")
	)
	(segment
		(start 362.647738 -293.03853)
		(end 362.615988 -293.020242)
		(width 0.1143)
		(layer "In4.Cu")
		(net "P5E_CPU0_P3_RX_DP<1>")
	)
	(segment
		(start 362.177838 -289.963352)
		(end 362.178346 -289.963098)
		(width 0.1143)
		(layer "In4.Cu")
		(net "P5E_CPU0_P3_RX_DP<1>")
	)
	(segment
		(start 362.454444 -291.000688)
		(end 362.448602 -290.995862)
		(width 0.1143)
		(layer "In4.Cu")
		(net "P5E_CPU0_P3_RX_DP<1>")
	)
	(segment
		(start 365.88954 -305.79187)
		(end 364.241842 -303.32553)
		(width 0.14224)
		(layer "In4.Cu")
		(net "P5E_CPU0_P3_RX_DP<1>")
	)
	(segment
		(start 362.146088 -289.98164)
		(end 362.177838 -289.963352)
		(width 0.1143)
		(layer "In4.Cu")
		(net "P5E_CPU0_P3_RX_DP<1>")
	)
	(segment
		(start 364.851442 -379.3236)
		(end 364.851442 -377.74626)
		(width 0.14224)
		(layer "In4.Cu")
		(net "P5E_CPU0_P3_RX_DP<1>")
	)
	(segment
		(start 362.642404 -295.636442)
		(end 362.64342 -295.635934)
		(width 0.1143)
		(layer "In4.Cu")
		(net "P5E_CPU0_P3_RX_DP<1>")
	)
	(segment
		(start 362.698284 -291.449506)
		(end 362.686092 -291.44087)
		(width 0.1143)
		(layer "In4.Cu")
		(net "P5E_CPU0_P3_RX_DP<1>")
	)
	(segment
		(start 362.648754 -289.152838)
		(end 362.686854 -289.130486)
		(width 0.1143)
		(layer "In4.Cu")
		(net "P5E_CPU0_P3_RX_DP<1>")
	)
	(segment
		(start 362.641642 -295.63695)
		(end 362.642404 -295.636442)
		(width 0.1143)
		(layer "In4.Cu")
		(net "P5E_CPU0_P3_RX_DP<1>")
	)
	(segment
		(start 380.44882 -353.752404)
		(end 381.322326 -349.365316)
		(width 0.14224)
		(layer "In4.Cu")
		(net "P5E_CPU0_P3_RX_DP<1>")
	)
	(segment
		(start 372.777766 -390.388602)
		(end 372.621048 -389.601202)
		(width 0.14224)
		(layer "In4.Cu")
		(net "P5E_CPU0_P3_RX_DP<1>")
	)
	(segment
		(start 362.686854 -293.06139)
		(end 362.650278 -293.040054)
		(width 0.1143)
		(layer "In4.Cu")
		(net "P5E_CPU0_P3_RX_DP<1>")
	)
	(segment
		(start 362.615988 -295.651682)
		(end 362.63961 -295.63822)
		(width 0.1143)
		(layer "In4.Cu")
		(net "P5E_CPU0_P3_RX_DP<1>")
	)
	(segment
		(start 362.648754 -294.65905)
		(end 362.647738 -294.658542)
		(width 0.1143)
		(layer "In4.Cu")
		(net "P5E_CPU0_P3_RX_DP<1>")
	)
	(segment
		(start 372.848632 -393.428982)
		(end 372.532656 -393.113006)
		(width 0.14224)
		(layer "In4.Cu")
		(net "P5E_CPU0_P3_RX_DP<1>")
	)
	(segment
		(start 362.647738 -289.153346)
		(end 362.648754 -289.152838)
		(width 0.1143)
		(layer "In4.Cu")
		(net "P5E_CPU0_P3_RX_DP<1>")
	)
	(segment
		(start 362.646976 -295.633902)
		(end 362.647738 -295.633394)
		(width 0.1143)
		(layer "In4.Cu")
		(net "P5E_CPU0_P3_RX_DP<1>")
	)
	(segment
		(start 381.322326 -349.365316)
		(end 381.322326 -337.563968)
		(width 0.14224)
		(layer "In4.Cu")
		(net "P5E_CPU0_P3_RX_DP<1>")
	)
	(segment
		(start 374.422924 -316.197742)
		(end 374.422924 -316.197488)
		(width 0.14224)
		(layer "In4.Cu")
		(net "P5E_CPU0_P3_RX_DP<1>")
	)
	(segment
		(start 372.539514 -392.260582)
		(end 372.840504 -391.959592)
		(width 0.14224)
		(layer "In4.Cu")
		(net "P5E_CPU0_P3_RX_DP<1>")
	)
	(segment
		(start 362.177838 -290.608512)
		(end 362.146088 -290.590224)
		(width 0.1143)
		(layer "In4.Cu")
		(net "P5E_CPU0_P3_RX_DP<1>")
	)
	(segment
		(start 362.650278 -293.040054)
		(end 362.648754 -293.039038)
		(width 0.1143)
		(layer "In4.Cu")
		(net "P5E_CPU0_P3_RX_DP<1>")
	)
	(segment
		(start 362.647738 -295.633394)
		(end 362.64977 -295.632378)
		(width 0.1143)
		(layer "In4.Cu")
		(net "P5E_CPU0_P3_RX_DP<1>")
	)
	(segment
		(start 362.646722 -291.41801)
		(end 362.645706 -291.417502)
		(width 0.1143)
		(layer "In4.Cu")
		(net "P5E_CPU0_P3_RX_DP<1>")
	)
	(segment
		(start 365.181388 -376.658632)
		(end 380.38786 -353.899724)
		(width 0.14224)
		(layer "In4.Cu")
		(net "P5E_CPU0_P3_RX_DP<1>")
	)
	(segment
		(start 362.64342 -292.39591)
		(end 362.644182 -292.395402)
		(width 0.1143)
		(layer "In4.Cu")
		(net "P5E_CPU0_P3_RX_DP<1>")
	)
	(segment
		(start 372.059708 -388.551166)
		(end 366.27943 -382.770888)
		(width 0.14224)
		(layer "In4.Cu")
		(net "P5E_CPU0_P3_RX_DP<1>")
	)
	(segment
		(start 362.647738 -294.658542)
		(end 362.646976 -294.658034)
		(width 0.1143)
		(layer "In4.Cu")
		(net "P5E_CPU0_P3_RX_DP<1>")
	)
	(segment
		(start 362.646214 -289.154362)
		(end 362.647738 -289.153346)
		(width 0.1143)
		(layer "In4.Cu")
		(net "P5E_CPU0_P3_RX_DP<1>")
	)
	(segment
		(start 380.162816 -331.108812)
		(end 376.032014 -319.210182)
		(width 0.14224)
		(layer "In4.Cu")
		(net "P5E_CPU0_P3_RX_DP<1>")
	)
	(segment
		(start 362.645706 -291.417502)
		(end 362.621322 -291.403278)
		(width 0.1143)
		(layer "In4.Cu")
		(net "P5E_CPU0_P3_RX_DP<1>")
	)
	(segment
		(start 374.422924 -316.197488)
		(end 374.409716 -316.17285)
		(width 0.14224)
		(layer "In4.Cu")
		(net "P5E_CPU0_P3_RX_DP<1>")
	)
	(segment
		(start 374.409716 -316.17285)
		(end 365.88954 -305.79187)
		(width 0.14224)
		(layer "In4.Cu")
		(net "P5E_CPU0_P3_RX_DP<1>")
	)
	(segment
		(start 372.532656 -393.113006)
		(end 372.539514 -392.260582)
		(width 0.14224)
		(layer "In4.Cu")
		(net "P5E_CPU0_P3_RX_DP<1>")
	)
	(segment
		(start 362.644182 -295.635426)
		(end 362.646976 -295.633902)
		(width 0.1143)
		(layer "In4.Cu")
		(net "P5E_CPU0_P3_RX_DP<1>")
	)
	(segment
		(start 362.686092 -294.680894)
		(end 362.652564 -294.66159)
		(width 0.1143)
		(layer "In4.Cu")
		(net "P5E_CPU0_P3_RX_DP<1>")
	)
	(segment
		(start 362.652056 -295.630854)
		(end 362.686092 -295.611042)
		(width 0.1143)
		(layer "In4.Cu")
		(net "P5E_CPU0_P3_RX_DP<1>")
	)
	(segment
		(start 362.460794 -291.101018)
		(end 362.461048 -291.101018)
		(width 0.1143)
		(layer "In4.Cu")
		(net "P5E_CPU0_P3_RX_DP<1>")
	)
	(segment
		(start 362.646976 -294.658034)
		(end 362.615988 -294.640254)
		(width 0.1143)
		(layer "In4.Cu")
		(net "P5E_CPU0_P3_RX_DP<1>")
	)
	(segment
		(start 362.647484 -291.418518)
		(end 362.646722 -291.41801)
		(width 0.1143)
		(layer "In4.Cu")
		(net "P5E_CPU0_P3_RX_DP<1>")
	)
	(segment
		(start 372.58625 -394.031216)
		(end 372.760494 -393.930632)
		(width 0.14224)
		(layer "In4.Cu")
		(net "P5E_CPU0_P3_RX_DP<1>")
	)
	(segment
		(start 364.241842 -303.32553)
		(end 362.55833 -299.261022)
		(width 0.14224)
		(layer "In4.Cu")
		(net "P5E_CPU0_P3_RX_DP<1>")
	)
	(segment
		(start 362.647738 -294.013382)
		(end 362.648754 -294.012874)
		(width 0.1143)
		(layer "In4.Cu")
		(net "P5E_CPU0_P3_RX_DP<1>")
	)
	(segment
		(start 362.648754 -293.039038)
		(end 362.647738 -293.03853)
		(width 0.1143)
		(layer "In4.Cu")
		(net "P5E_CPU0_P3_RX_DP<1>")
	)
	(segment
		(start 362.686092 -291.44087)
		(end 362.647484 -291.418518)
		(width 0.1143)
		(layer "In4.Cu")
		(net "P5E_CPU0_P3_RX_DP<1>")
	)
	(segment
		(start 362.648754 -294.012874)
		(end 362.686854 -293.990522)
		(width 0.1143)
		(layer "In4.Cu")
		(net "P5E_CPU0_P3_RX_DP<1>")
	)
	(segment
		(start 362.64977 -295.632378)
		(end 362.652056 -295.630854)
		(width 0.1143)
		(layer "In4.Cu")
		(net "P5E_CPU0_P3_RX_DP<1>")
	)
	(segment
		(start 372.848632 -393.842494)
		(end 372.848632 -393.428982)
		(width 0.14224)
		(layer "In4.Cu")
		(net "P5E_CPU0_P3_RX_DP<1>")
	)
	(segment
		(start 372.491254 -394.385292)
		(end 372.58625 -394.031216)
		(width 0.14224)
		(layer "In4.Cu")
		(net "P5E_CPU0_P3_RX_DP<1>")
	)
	(segment
		(start 362.686092 -295.611042)
		(end 362.698284 -295.602406)
		(width 0.1143)
		(layer "In4.Cu")
		(net "P5E_CPU0_P3_RX_DP<1>")
	)
	(segment
		(start 362.460032 -296.284142)
		(end 362.460032 -295.955974)
		(width 0.1143)
		(layer "In4.Cu")
		(net "P5E_CPU0_P3_RX_DP<1>")
	)
	(arc
		(start 380.38786 -353.899724)
		(mid 380.425601 -353.829067)
		(end 380.44882 -353.752404)
		(width 0.14224)
		(layer "In4.Cu")
		(net "P5E_CPU0_P3_RX_DP<1>")
	)
	(arc
		(start 362.686854 -289.130486)
		(mid 362.838841 -288.973978)
		(end 362.92028 -288.771584)
		(width 0.1143)
		(layer "In4.Cu")
		(net "P5E_CPU0_P3_RX_DP<1>")
	)
	(arc
		(start 362.448602 -290.995862)
		(mid 362.355989 -290.772301)
		(end 362.177838 -290.608512)
		(width 0.1143)
		(layer "In4.Cu")
		(net "P5E_CPU0_P3_RX_DP<1>")
	)
	(arc
		(start 362.61421 -291.39769)
		(mid 362.513029 -291.262003)
		(end 362.460794 -291.101018)
		(width 0.1143)
		(layer "In4.Cu")
		(net "P5E_CPU0_P3_RX_DP<1>")
	)
	(arc
		(start 362.698284 -295.602406)
		(mid 362.932705 -295.145968)
		(end 362.698284 -294.68953)
		(width 0.1143)
		(layer "In4.Cu")
		(net "P5E_CPU0_P3_RX_DP<1>")
	)
	(arc
		(start 362.621322 -291.403278)
		(mid 362.617749 -291.400506)
		(end 362.61421 -291.39769)
		(width 0.1143)
		(layer "In4.Cu")
		(net "P5E_CPU0_P3_RX_DP<1>")
	)
	(arc
		(start 366.27943 -382.770888)
		(mid 365.222565 -381.189273)
		(end 364.851442 -379.3236)
		(width 0.14224)
		(layer "In4.Cu")
		(net "P5E_CPU0_P3_RX_DP<1>")
	)
	(arc
		(start 362.460032 -295.955974)
		(mid 362.501287 -295.785003)
		(end 362.615988 -295.651682)
		(width 0.1143)
		(layer "In4.Cu")
		(net "P5E_CPU0_P3_RX_DP<1>")
	)
	(arc
		(start 362.615988 -294.640254)
		(mid 362.466891 -294.335962)
		(end 362.615988 -294.03167)
		(width 0.1143)
		(layer "In4.Cu")
		(net "P5E_CPU0_P3_RX_DP<1>")
	)
	(arc
		(start 362.455714 -289.480752)
		(mid 362.506162 -289.292918)
		(end 362.643928 -289.155632)
		(width 0.1143)
		(layer "In4.Cu")
		(net "P5E_CPU0_P3_RX_DP<1>")
	)
	(arc
		(start 362.698284 -292.362382)
		(mid 362.932705 -291.905944)
		(end 362.698284 -291.449506)
		(width 0.1143)
		(layer "In4.Cu")
		(net "P5E_CPU0_P3_RX_DP<1>")
	)
	(arc
		(start 372.840504 -391.024872)
		(mid 372.824764 -390.705196)
		(end 372.777766 -390.388602)
		(width 0.14224)
		(layer "In4.Cu")
		(net "P5E_CPU0_P3_RX_DP<1>")
	)
	(arc
		(start 362.55833 -299.261022)
		(mid 362.519034 -299.131659)
		(end 362.505752 -298.997116)
		(width 0.14224)
		(layer "In4.Cu")
		(net "P5E_CPU0_P3_RX_DP<1>")
	)
	(arc
		(start 362.92028 -288.771584)
		(mid 362.922303 -288.760174)
		(end 362.92409 -288.748724)
		(width 0.1143)
		(layer "In4.Cu")
		(net "P5E_CPU0_P3_RX_DP<1>")
	)
	(arc
		(start 362.146088 -290.590224)
		(mid 361.99016 -290.285932)
		(end 362.146088 -289.98164)
		(width 0.1143)
		(layer "In4.Cu")
		(net "P5E_CPU0_P3_RX_DP<1>")
	)
	(arc
		(start 372.621048 -389.601202)
		(mid 372.418222 -389.034572)
		(end 372.059708 -388.551166)
		(width 0.14224)
		(layer "In4.Cu")
		(net "P5E_CPU0_P3_RX_DP<1>")
	)
	(arc
		(start 362.615988 -293.020242)
		(mid 362.46006 -292.71595)
		(end 362.615988 -292.411658)
		(width 0.1143)
		(layer "In4.Cu")
		(net "P5E_CPU0_P3_RX_DP<1>")
	)
	(arc
		(start 362.178346 -289.963098)
		(mid 362.381394 -289.759235)
		(end 362.455714 -289.48126)
		(width 0.1143)
		(layer "In4.Cu")
		(net "P5E_CPU0_P3_RX_DP<1>")
	)
	(arc
		(start 364.851442 -377.74626)
		(mid 364.935744 -377.177974)
		(end 365.181388 -376.658632)
		(width 0.14224)
		(layer "In4.Cu")
		(net "P5E_CPU0_P3_RX_DP<1>")
	)
	(arc
		(start 362.686854 -293.990522)
		(mid 362.930181 -293.525956)
		(end 362.686854 -293.06139)
		(width 0.1143)
		(layer "In4.Cu")
		(net "P5E_CPU0_P3_RX_DP<1>")
	)
	(segment
		(start 388.770622 -394.385292)
		(end 389.291322 -394.385292)
		(width 0.127)
		(layer "F.Cu")
		(net "P5E_CPU0_P3_RX_DP<15>")
	)
	(segment
		(start 373.64797 -285.970218)
		(end 374.114822 -286.236156)
		(width 0.12954)
		(layer "F.Cu")
		(net "P5E_CPU0_P3_RX_DP<15>")
	)
	(segment
		(start 374.906794 -289.130486)
		(end 374.867678 -289.153346)
		(width 0.1143)
		(layer "In4.Cu")
		(net "P5E_CPU0_P3_RX_DP<15>")
	)
	(segment
		(start 375.807732 -294.658542)
		(end 375.846848 -294.681402)
		(width 0.1143)
		(layer "In4.Cu")
		(net "P5E_CPU0_P3_RX_DP<15>")
	)
	(segment
		(start 374.114822 -286.236156)
		(end 373.81688 -286.236156)
		(width 0.1143)
		(layer "In4.Cu")
		(net "P5E_CPU0_P3_RX_DP<15>")
	)
	(segment
		(start 374.428766 -287.386776)
		(end 374.434354 -287.389824)
		(width 0.1143)
		(layer "In4.Cu")
		(net "P5E_CPU0_P3_RX_DP<15>")
	)
	(segment
		(start 394.529564 -367.697766)
		(end 394.530072 -367.69929)
		(width 0.14224)
		(layer "In4.Cu")
		(net "P5E_CPU0_P3_RX_DP<15>")
	)
	(segment
		(start 375.338848 -290.60902)
		(end 375.369328 -290.6268)
		(width 0.1143)
		(layer "In4.Cu")
		(net "P5E_CPU0_P3_RX_DP<15>")
	)
	(segment
		(start 375.807732 -292.39337)
		(end 375.777252 -292.41115)
		(width 0.1143)
		(layer "In4.Cu")
		(net "P5E_CPU0_P3_RX_DP<15>")
	)
	(segment
		(start 375.331736 -290.604956)
		(end 375.332498 -290.605464)
		(width 0.1143)
		(layer "In4.Cu")
		(net "P5E_CPU0_P3_RX_DP<15>")
	)
	(segment
		(start 374.39092 -287.364932)
		(end 374.428766 -287.386776)
		(width 0.1143)
		(layer "In4.Cu")
		(net "P5E_CPU0_P3_RX_DP<15>")
	)
	(segment
		(start 375.37009 -290.627308)
		(end 375.376948 -290.631372)
		(width 0.1143)
		(layer "In4.Cu")
		(net "P5E_CPU0_P3_RX_DP<15>")
	)
	(segment
		(start 375.711466 -296.36466)
		(end 375.711466 -296.393108)
		(width 0.1143)
		(layer "In4.Cu")
		(net "P5E_CPU0_P3_RX_DP<15>")
	)
	(segment
		(start 385.97332 -309.55488)
		(end 388.355078 -313.868308)
		(width 0.14224)
		(layer "In4.Cu")
		(net "P5E_CPU0_P3_RX_DP<15>")
	)
	(segment
		(start 396.4813 -378.963174)
		(end 395.903196 -381.869442)
		(width 0.14224)
		(layer "In4.Cu")
		(net "P5E_CPU0_P3_RX_DP<15>")
	)
	(segment
		(start 375.3358 -290.607242)
		(end 375.33707 -290.608004)
		(width 0.1143)
		(layer "In4.Cu")
		(net "P5E_CPU0_P3_RX_DP<15>")
	)
	(segment
		(start 375.332498 -290.605464)
		(end 375.333514 -290.605972)
		(width 0.1143)
		(layer "In4.Cu")
		(net "P5E_CPU0_P3_RX_DP<15>")
	)
	(segment
		(start 375.369328 -290.6268)
		(end 375.37009 -290.627308)
		(width 0.1143)
		(layer "In4.Cu")
		(net "P5E_CPU0_P3_RX_DP<15>")
	)
	(segment
		(start 395.90218 -383.421636)
		(end 395.901672 -383.422144)
		(width 0.14224)
		(layer "In4.Cu")
		(net "P5E_CPU0_P3_RX_DP<15>")
	)
	(segment
		(start 375.777252 -293.02075)
		(end 375.807732 -293.03853)
		(width 0.1143)
		(layer "In4.Cu")
		(net "P5E_CPU0_P3_RX_DP<15>")
	)
	(segment
		(start 375.846848 -293.990522)
		(end 375.807732 -294.013382)
		(width 0.1143)
		(layer "In4.Cu")
		(net "P5E_CPU0_P3_RX_DP<15>")
	)
	(segment
		(start 375.846848 -292.37051)
		(end 375.807732 -292.39337)
		(width 0.1143)
		(layer "In4.Cu")
		(net "P5E_CPU0_P3_RX_DP<15>")
	)
	(segment
		(start 374.835166 -288.159698)
		(end 374.867678 -288.178494)
		(width 0.1143)
		(layer "In4.Cu")
		(net "P5E_CPU0_P3_RX_DP<15>")
	)
	(segment
		(start 375.732802 -296.59453)
		(end 377.46686 -299.189394)
		(width 0.14224)
		(layer "In4.Cu")
		(net "P5E_CPU0_P3_RX_DP<15>")
	)
	(segment
		(start 395.90218 -383.071624)
		(end 395.90218 -383.421636)
		(width 0.14224)
		(layer "In4.Cu")
		(net "P5E_CPU0_P3_RX_DP<15>")
	)
	(segment
		(start 375.329196 -290.603686)
		(end 375.331736 -290.604956)
		(width 0.1143)
		(layer "In4.Cu")
		(net "P5E_CPU0_P3_RX_DP<15>")
	)
	(segment
		(start 392.95451 -327.666858)
		(end 394.518388 -336.373216)
		(width 0.14224)
		(layer "In4.Cu")
		(net "P5E_CPU0_P3_RX_DP<15>")
	)
	(segment
		(start 389.386318 -394.031216)
		(end 389.291322 -394.385292)
		(width 0.14224)
		(layer "In4.Cu")
		(net "P5E_CPU0_P3_RX_DP<15>")
	)
	(segment
		(start 375.334276 -290.60648)
		(end 375.3358 -290.607242)
		(width 0.1143)
		(layer "In4.Cu")
		(net "P5E_CPU0_P3_RX_DP<15>")
	)
	(segment
		(start 374.837198 -289.780726)
		(end 374.867678 -289.798506)
		(width 0.1143)
		(layer "In4.Cu")
		(net "P5E_CPU0_P3_RX_DP<15>")
	)
	(segment
		(start 394.530072 -367.69929)
		(end 394.530072 -367.699036)
		(width 0.14224)
		(layer "In4.Cu")
		(net "P5E_CPU0_P3_RX_DP<15>")
	)
	(segment
		(start 375.853198 -295.605962)
		(end 375.741946 -295.717214)
		(width 0.1143)
		(layer "In4.Cu")
		(net "P5E_CPU0_P3_RX_DP<15>")
	)
	(segment
		(start 375.807732 -293.03853)
		(end 375.846848 -293.06139)
		(width 0.1143)
		(layer "In4.Cu")
		(net "P5E_CPU0_P3_RX_DP<15>")
	)
	(segment
		(start 395.903196 -381.869442)
		(end 395.90218 -383.071624)
		(width 0.14224)
		(layer "In4.Cu")
		(net "P5E_CPU0_P3_RX_DP<15>")
	)
	(segment
		(start 394.529564 -336.4992)
		(end 394.529564 -367.697766)
		(width 0.14224)
		(layer "In4.Cu")
		(net "P5E_CPU0_P3_RX_DP<15>")
	)
	(segment
		(start 374.867678 -289.798506)
		(end 374.906794 -289.821366)
		(width 0.1143)
		(layer "In4.Cu")
		(net "P5E_CPU0_P3_RX_DP<15>")
	)
	(segment
		(start 375.741946 -295.717214)
		(end 375.741692 -295.717214)
		(width 0.1143)
		(layer "In4.Cu")
		(net "P5E_CPU0_P3_RX_DP<15>")
	)
	(segment
		(start 375.665746 -295.900348)
		(end 375.665746 -296.31894)
		(width 0.1143)
		(layer "In4.Cu")
		(net "P5E_CPU0_P3_RX_DP<15>")
	)
	(segment
		(start 375.306082 -290.590224)
		(end 375.329196 -290.603686)
		(width 0.1143)
		(layer "In4.Cu")
		(net "P5E_CPU0_P3_RX_DP<15>")
	)
	(segment
		(start 388.355078 -313.868308)
		(end 392.95451 -327.666858)
		(width 0.14224)
		(layer "In4.Cu")
		(net "P5E_CPU0_P3_RX_DP<15>")
	)
	(segment
		(start 395.901672 -383.422144)
		(end 395.901672 -384.12293)
		(width 0.14224)
		(layer "In4.Cu")
		(net "P5E_CPU0_P3_RX_DP<15>")
	)
	(segment
		(start 391.067798 -391.887202)
		(end 390.198102 -392.769344)
		(width 0.14224)
		(layer "In4.Cu")
		(net "P5E_CPU0_P3_RX_DP<15>")
	)
	(segment
		(start 396.4813 -374.131586)
		(end 396.4813 -378.963174)
		(width 0.14224)
		(layer "In4.Cu")
		(net "P5E_CPU0_P3_RX_DP<15>")
	)
	(segment
		(start 375.665746 -296.31894)
		(end 375.711466 -296.36466)
		(width 0.1143)
		(layer "In4.Cu")
		(net "P5E_CPU0_P3_RX_DP<15>")
	)
	(segment
		(start 375.807732 -294.013382)
		(end 375.777252 -294.031162)
		(width 0.1143)
		(layer "In4.Cu")
		(net "P5E_CPU0_P3_RX_DP<15>")
	)
	(segment
		(start 374.867678 -288.178494)
		(end 374.906794 -288.201354)
		(width 0.1143)
		(layer "In4.Cu")
		(net "P5E_CPU0_P3_RX_DP<15>")
	)
	(segment
		(start 395.667738 -389.664702)
		(end 395.423644 -389.908796)
		(width 0.14224)
		(layer "In4.Cu")
		(net "P5E_CPU0_P3_RX_DP<15>")
	)
	(segment
		(start 373.81688 -286.236156)
		(end 373.74703 -286.306006)
		(width 0.1143)
		(layer "In4.Cu")
		(net "P5E_CPU0_P3_RX_DP<15>")
	)
	(segment
		(start 375.337832 -290.608512)
		(end 375.338848 -290.60902)
		(width 0.1143)
		(layer "In4.Cu")
		(net "P5E_CPU0_P3_RX_DP<15>")
	)
	(segment
		(start 374.867678 -289.153346)
		(end 374.837198 -289.171126)
		(width 0.1143)
		(layer "In4.Cu")
		(net "P5E_CPU0_P3_RX_DP<15>")
	)
	(segment
		(start 394.530072 -367.699036)
		(end 396.4813 -374.131586)
		(width 0.14224)
		(layer "In4.Cu")
		(net "P5E_CPU0_P3_RX_DP<15>")
	)
	(segment
		(start 395.901672 -384.12293)
		(end 395.896592 -384.12801)
		(width 0.14224)
		(layer "In4.Cu")
		(net "P5E_CPU0_P3_RX_DP<15>")
	)
	(segment
		(start 373.896128 -286.540194)
		(end 373.935498 -286.563308)
		(width 0.1143)
		(layer "In4.Cu")
		(net "P5E_CPU0_P3_RX_DP<15>")
	)
	(segment
		(start 375.777252 -294.640762)
		(end 375.807732 -294.658542)
		(width 0.1143)
		(layer "In4.Cu")
		(net "P5E_CPU0_P3_RX_DP<15>")
	)
	(segment
		(start 377.46686 -299.189394)
		(end 385.97332 -309.55488)
		(width 0.14224)
		(layer "In4.Cu")
		(net "P5E_CPU0_P3_RX_DP<15>")
	)
	(segment
		(start 375.333514 -290.605972)
		(end 375.334276 -290.60648)
		(width 0.1143)
		(layer "In4.Cu")
		(net "P5E_CPU0_P3_RX_DP<15>")
	)
	(segment
		(start 375.807732 -291.418518)
		(end 375.846848 -291.441378)
		(width 0.1143)
		(layer "In4.Cu")
		(net "P5E_CPU0_P3_RX_DP<15>")
	)
	(segment
		(start 394.827252 -390.307068)
		(end 391.172446 -391.817352)
		(width 0.14224)
		(layer "In4.Cu")
		(net "P5E_CPU0_P3_RX_DP<15>")
	)
	(segment
		(start 395.896592 -384.12801)
		(end 395.896592 -389.112252)
		(width 0.14224)
		(layer "In4.Cu")
		(net "P5E_CPU0_P3_RX_DP<15>")
	)
	(segment
		(start 375.777252 -291.400738)
		(end 375.807732 -291.418518)
		(width 0.1143)
		(layer "In4.Cu")
		(net "P5E_CPU0_P3_RX_DP<15>")
	)
	(segment
		(start 389.63346 -393.888468)
		(end 389.386318 -394.031216)
		(width 0.14224)
		(layer "In4.Cu")
		(net "P5E_CPU0_P3_RX_DP<15>")
	)
	(segment
		(start 375.33707 -290.608004)
		(end 375.337832 -290.608512)
		(width 0.1143)
		(layer "In4.Cu")
		(net "P5E_CPU0_P3_RX_DP<15>")
	)
	(segment
		(start 375.711466 -296.393108)
		(end 375.711466 -296.523918)
		(width 0.14224)
		(layer "In4.Cu")
		(net "P5E_CPU0_P3_RX_DP<15>")
	)
	(segment
		(start 390.198102 -392.769344)
		(end 389.63346 -393.888468)
		(width 0.14224)
		(layer "In4.Cu")
		(net "P5E_CPU0_P3_RX_DP<15>")
	)
	(arc
		(start 395.896592 -389.112252)
		(mid 395.837119 -389.411244)
		(end 395.667738 -389.664702)
		(width 0.14224)
		(layer "In4.Cu")
		(net "P5E_CPU0_P3_RX_DP<15>")
	)
	(arc
		(start 375.711466 -296.523918)
		(mid 375.716868 -296.560819)
		(end 375.732802 -296.59453)
		(width 0.14224)
		(layer "In4.Cu")
		(net "P5E_CPU0_P3_RX_DP<15>")
	)
	(arc
		(start 374.212612 -287.046924)
		(mid 374.26024 -287.229203)
		(end 374.39092 -287.364932)
		(width 0.1143)
		(layer "In4.Cu")
		(net "P5E_CPU0_P3_RX_DP<15>")
	)
	(arc
		(start 391.172446 -391.817352)
		(mid 391.116667 -391.847102)
		(end 391.067798 -391.887202)
		(width 0.14224)
		(layer "In4.Cu")
		(net "P5E_CPU0_P3_RX_DP<15>")
	)
	(arc
		(start 374.906794 -289.821366)
		(mid 375.085607 -290.023716)
		(end 375.150126 -290.285932)
		(width 0.1143)
		(layer "In4.Cu")
		(net "P5E_CPU0_P3_RX_DP<15>")
	)
	(arc
		(start 394.518388 -336.373216)
		(mid 394.526783 -336.435959)
		(end 394.529564 -336.4992)
		(width 0.14224)
		(layer "In4.Cu")
		(net "P5E_CPU0_P3_RX_DP<15>")
	)
	(arc
		(start 375.741692 -295.717214)
		(mid 375.685496 -295.801222)
		(end 375.665746 -295.900348)
		(width 0.1143)
		(layer "In4.Cu")
		(net "P5E_CPU0_P3_RX_DP<15>")
	)
	(arc
		(start 374.434354 -287.389824)
		(mid 374.615006 -287.592569)
		(end 374.680226 -287.856168)
		(width 0.1143)
		(layer "In4.Cu")
		(net "P5E_CPU0_P3_RX_DP<15>")
	)
	(arc
		(start 375.846848 -294.681402)
		(mid 375.93387 -294.760532)
		(end 376.003058 -294.855646)
		(width 0.1143)
		(layer "In4.Cu")
		(net "P5E_CPU0_P3_RX_DP<15>")
	)
	(arc
		(start 375.846848 -291.441378)
		(mid 376.090175 -291.905944)
		(end 375.846848 -292.37051)
		(width 0.1143)
		(layer "In4.Cu")
		(net "P5E_CPU0_P3_RX_DP<15>")
	)
	(arc
		(start 374.680226 -287.856168)
		(mid 374.721192 -288.026574)
		(end 374.835166 -288.159698)
		(width 0.1143)
		(layer "In4.Cu")
		(net "P5E_CPU0_P3_RX_DP<15>")
	)
	(arc
		(start 375.62028 -291.095938)
		(mid 375.661829 -291.26736)
		(end 375.777252 -291.400738)
		(width 0.1143)
		(layer "In4.Cu")
		(net "P5E_CPU0_P3_RX_DP<15>")
	)
	(arc
		(start 395.423644 -389.908796)
		(mid 395.1451 -390.137362)
		(end 394.827252 -390.307068)
		(width 0.14224)
		(layer "In4.Cu")
		(net "P5E_CPU0_P3_RX_DP<15>")
	)
	(arc
		(start 374.906794 -288.201354)
		(mid 375.150121 -288.66592)
		(end 374.906794 -289.130486)
		(width 0.1143)
		(layer "In4.Cu")
		(net "P5E_CPU0_P3_RX_DP<15>")
	)
	(arc
		(start 373.935498 -286.563308)
		(mid 374.13841 -286.768224)
		(end 374.212612 -287.046924)
		(width 0.1143)
		(layer "In4.Cu")
		(net "P5E_CPU0_P3_RX_DP<15>")
	)
	(arc
		(start 375.777252 -292.41115)
		(mid 375.620275 -292.71595)
		(end 375.777252 -293.02075)
		(width 0.1143)
		(layer "In4.Cu")
		(net "P5E_CPU0_P3_RX_DP<15>")
	)
	(arc
		(start 373.74703 -286.306006)
		(mid 373.797076 -286.434178)
		(end 373.890032 -286.535622)
		(width 0.1143)
		(layer "In4.Cu")
		(net "P5E_CPU0_P3_RX_DP<15>")
	)
	(arc
		(start 375.150126 -290.285932)
		(mid 375.191381 -290.456903)
		(end 375.306082 -290.590224)
		(width 0.1143)
		(layer "In4.Cu")
		(net "P5E_CPU0_P3_RX_DP<15>")
	)
	(arc
		(start 375.846848 -293.06139)
		(mid 376.090175 -293.525956)
		(end 375.846848 -293.990522)
		(width 0.1143)
		(layer "In4.Cu")
		(net "P5E_CPU0_P3_RX_DP<15>")
	)
	(arc
		(start 375.777252 -294.031162)
		(mid 375.620275 -294.335962)
		(end 375.777252 -294.640762)
		(width 0.1143)
		(layer "In4.Cu")
		(net "P5E_CPU0_P3_RX_DP<15>")
	)
	(arc
		(start 375.376948 -290.631372)
		(mid 375.555761 -290.833722)
		(end 375.62028 -291.095938)
		(width 0.1143)
		(layer "In4.Cu")
		(net "P5E_CPU0_P3_RX_DP<15>")
	)
	(arc
		(start 373.890032 -286.535622)
		(mid 373.893068 -286.537923)
		(end 373.896128 -286.540194)
		(width 0.1143)
		(layer "In4.Cu")
		(net "P5E_CPU0_P3_RX_DP<15>")
	)
	(arc
		(start 374.837198 -289.171126)
		(mid 374.680221 -289.475926)
		(end 374.837198 -289.780726)
		(width 0.1143)
		(layer "In4.Cu")
		(net "P5E_CPU0_P3_RX_DP<15>")
	)
	(arc
		(start 376.003058 -294.855646)
		(mid 376.07006 -295.259161)
		(end 375.853198 -295.605962)
		(width 0.1143)
		(layer "In4.Cu")
		(net "P5E_CPU0_P3_RX_DP<15>")
	)
	(segment
		(start 387.570472 -394.385292)
		(end 388.091172 -394.385292)
		(width 0.127)
		(layer "F.Cu")
		(net "P5E_CPU0_P3_RX_DP<14>")
	)
	(segment
		(start 373.64797 -289.209988)
		(end 374.114822 -289.475926)
		(width 0.12954)
		(layer "F.Cu")
		(net "P5E_CPU0_P3_RX_DP<14>")
	)
	(segment
		(start 374.867678 -292.39337)
		(end 374.906794 -292.37051)
		(width 0.1143)
		(layer "In4.Cu")
		(net "P5E_CPU0_P3_RX_DP<14>")
	)
	(segment
		(start 389.587232 -321.070732)
		(end 389.586978 -321.070478)
		(width 0.14224)
		(layer "In4.Cu")
		(net "P5E_CPU0_P3_RX_DP<14>")
	)
	(segment
		(start 388.186168 -394.031216)
		(end 388.360412 -393.930632)
		(width 0.14224)
		(layer "In4.Cu")
		(net "P5E_CPU0_P3_RX_DP<14>")
	)
	(segment
		(start 393.585192 -336.965798)
		(end 391.954512 -327.886822)
		(width 0.14224)
		(layer "In4.Cu")
		(net "P5E_CPU0_P3_RX_DP<14>")
	)
	(segment
		(start 395.3002 -374.27789)
		(end 393.591796 -368.646456)
		(width 0.14224)
		(layer "In4.Cu")
		(net "P5E_CPU0_P3_RX_DP<14>")
	)
	(segment
		(start 373.74703 -289.545776)
		(end 373.81688 -289.475926)
		(width 0.1143)
		(layer "In4.Cu")
		(net "P5E_CPU0_P3_RX_DP<14>")
	)
	(segment
		(start 388.476744 -390.642094)
		(end 394.013182 -382.355598)
		(width 0.14224)
		(layer "In4.Cu")
		(net "P5E_CPU0_P3_RX_DP<14>")
	)
	(segment
		(start 388.132574 -393.113006)
		(end 388.134606 -392.845544)
		(width 0.14224)
		(layer "In4.Cu")
		(net "P5E_CPU0_P3_RX_DP<14>")
	)
	(segment
		(start 374.680226 -296.32656)
		(end 374.680226 -295.955974)
		(width 0.1143)
		(layer "In4.Cu")
		(net "P5E_CPU0_P3_RX_DP<14>")
	)
	(segment
		(start 374.430036 -290.627308)
		(end 374.429274 -290.6268)
		(width 0.1143)
		(layer "In4.Cu")
		(net "P5E_CPU0_P3_RX_DP<14>")
	)
	(segment
		(start 374.398794 -290.60902)
		(end 374.397778 -290.608512)
		(width 0.1143)
		(layer "In4.Cu")
		(net "P5E_CPU0_P3_RX_DP<14>")
	)
	(segment
		(start 388.440422 -392.539728)
		(end 388.440422 -390.761474)
		(width 0.14224)
		(layer "In4.Cu")
		(net "P5E_CPU0_P3_RX_DP<14>")
	)
	(segment
		(start 388.360412 -393.930632)
		(end 388.44855 -393.842494)
		(width 0.14224)
		(layer "In4.Cu")
		(net "P5E_CPU0_P3_RX_DP<14>")
	)
	(segment
		(start 374.837198 -295.651174)
		(end 374.867678 -295.633394)
		(width 0.1143)
		(layer "In4.Cu")
		(net "P5E_CPU0_P3_RX_DP<14>")
	)
	(segment
		(start 374.906794 -294.681402)
		(end 374.867678 -294.658542)
		(width 0.1143)
		(layer "In4.Cu")
		(net "P5E_CPU0_P3_RX_DP<14>")
	)
	(segment
		(start 387.219698 -314.254896)
		(end 384.606546 -309.364888)
		(width 0.14224)
		(layer "In4.Cu")
		(net "P5E_CPU0_P3_RX_DP<14>")
	)
	(segment
		(start 374.867678 -293.03853)
		(end 374.837198 -293.02075)
		(width 0.1143)
		(layer "In4.Cu")
		(net "P5E_CPU0_P3_RX_DP<14>")
	)
	(segment
		(start 374.867678 -294.013382)
		(end 374.906794 -293.990522)
		(width 0.1143)
		(layer "In4.Cu")
		(net "P5E_CPU0_P3_RX_DP<14>")
	)
	(segment
		(start 389.586978 -321.070478)
		(end 387.219698 -314.254896)
		(width 0.14224)
		(layer "In4.Cu")
		(net "P5E_CPU0_P3_RX_DP<14>")
	)
	(segment
		(start 373.81688 -289.475926)
		(end 374.114822 -289.475926)
		(width 0.1143)
		(layer "In4.Cu")
		(net "P5E_CPU0_P3_RX_DP<14>")
	)
	(segment
		(start 384.606546 -309.364888)
		(end 376.035824 -298.921932)
		(width 0.14224)
		(layer "In4.Cu")
		(net "P5E_CPU0_P3_RX_DP<14>")
	)
	(segment
		(start 374.906794 -291.441378)
		(end 374.867678 -291.418518)
		(width 0.1143)
		(layer "In4.Cu")
		(net "P5E_CPU0_P3_RX_DP<14>")
	)
	(segment
		(start 374.867678 -291.418518)
		(end 374.837198 -291.400738)
		(width 0.1143)
		(layer "In4.Cu")
		(net "P5E_CPU0_P3_RX_DP<14>")
	)
	(segment
		(start 374.837198 -292.41115)
		(end 374.867678 -292.39337)
		(width 0.1143)
		(layer "In4.Cu")
		(net "P5E_CPU0_P3_RX_DP<14>")
	)
	(segment
		(start 389.586978 -321.070732)
		(end 389.587232 -321.070732)
		(width 0.14224)
		(layer "In4.Cu")
		(net "P5E_CPU0_P3_RX_DP<14>")
	)
	(segment
		(start 388.134606 -392.845544)
		(end 388.440422 -392.539728)
		(width 0.14224)
		(layer "In4.Cu")
		(net "P5E_CPU0_P3_RX_DP<14>")
	)
	(segment
		(start 374.906794 -293.06139)
		(end 374.867678 -293.03853)
		(width 0.1143)
		(layer "In4.Cu")
		(net "P5E_CPU0_P3_RX_DP<14>")
	)
	(segment
		(start 393.585192 -368.60353)
		(end 393.585192 -336.965798)
		(width 0.14224)
		(layer "In4.Cu")
		(net "P5E_CPU0_P3_RX_DP<14>")
	)
	(segment
		(start 391.954512 -327.886822)
		(end 389.586978 -321.070732)
		(width 0.14224)
		(layer "In4.Cu")
		(net "P5E_CPU0_P3_RX_DP<14>")
	)
	(segment
		(start 388.091172 -394.385292)
		(end 388.186168 -394.031216)
		(width 0.14224)
		(layer "In4.Cu")
		(net "P5E_CPU0_P3_RX_DP<14>")
	)
	(segment
		(start 375.136664 -297.617896)
		(end 375.032524 -297.428158)
		(width 0.14224)
		(layer "In4.Cu")
		(net "P5E_CPU0_P3_RX_DP<14>")
	)
	(segment
		(start 373.930672 -289.800284)
		(end 373.927878 -289.798506)
		(width 0.1143)
		(layer "In4.Cu")
		(net "P5E_CPU0_P3_RX_DP<14>")
	)
	(segment
		(start 388.44855 -393.428982)
		(end 388.132574 -393.113006)
		(width 0.14224)
		(layer "In4.Cu")
		(net "P5E_CPU0_P3_RX_DP<14>")
	)
	(segment
		(start 374.867678 -295.633394)
		(end 374.906794 -295.610534)
		(width 0.1143)
		(layer "In4.Cu")
		(net "P5E_CPU0_P3_RX_DP<14>")
	)
	(segment
		(start 395.3002 -378.008134)
		(end 395.3002 -374.27789)
		(width 0.14224)
		(layer "In4.Cu")
		(net "P5E_CPU0_P3_RX_DP<14>")
	)
	(segment
		(start 374.867678 -294.658542)
		(end 374.837198 -294.640762)
		(width 0.1143)
		(layer "In4.Cu")
		(net "P5E_CPU0_P3_RX_DP<14>")
	)
	(segment
		(start 374.725946 -296.400728)
		(end 374.725946 -296.37228)
		(width 0.1143)
		(layer "In4.Cu")
		(net "P5E_CPU0_P3_RX_DP<14>")
	)
	(segment
		(start 374.725946 -296.590466)
		(end 374.725946 -296.400728)
		(width 0.14224)
		(layer "In4.Cu")
		(net "P5E_CPU0_P3_RX_DP<14>")
	)
	(segment
		(start 376.035824 -298.921932)
		(end 375.136664 -297.617896)
		(width 0.14224)
		(layer "In4.Cu")
		(net "P5E_CPU0_P3_RX_DP<14>")
	)
	(segment
		(start 374.725946 -296.37228)
		(end 374.680226 -296.32656)
		(width 0.1143)
		(layer "In4.Cu")
		(net "P5E_CPU0_P3_RX_DP<14>")
	)
	(segment
		(start 374.436894 -290.631372)
		(end 374.430036 -290.627308)
		(width 0.1143)
		(layer "In4.Cu")
		(net "P5E_CPU0_P3_RX_DP<14>")
	)
	(segment
		(start 373.927878 -289.798506)
		(end 373.926862 -289.797998)
		(width 0.1143)
		(layer "In4.Cu")
		(net "P5E_CPU0_P3_RX_DP<14>")
	)
	(segment
		(start 374.397778 -290.608512)
		(end 374.397016 -290.608004)
		(width 0.1143)
		(layer "In4.Cu")
		(net "P5E_CPU0_P3_RX_DP<14>")
	)
	(segment
		(start 375.032524 -297.428158)
		(end 374.763284 -296.77868)
		(width 0.14224)
		(layer "In4.Cu")
		(net "P5E_CPU0_P3_RX_DP<14>")
	)
	(segment
		(start 394.013182 -382.355598)
		(end 395.26972 -378.215398)
		(width 0.14224)
		(layer "In4.Cu")
		(net "P5E_CPU0_P3_RX_DP<14>")
	)
	(segment
		(start 388.44855 -393.842494)
		(end 388.44855 -393.428982)
		(width 0.14224)
		(layer "In4.Cu")
		(net "P5E_CPU0_P3_RX_DP<14>")
	)
	(segment
		(start 374.837198 -294.031162)
		(end 374.867678 -294.013382)
		(width 0.1143)
		(layer "In4.Cu")
		(net "P5E_CPU0_P3_RX_DP<14>")
	)
	(segment
		(start 374.429274 -290.6268)
		(end 374.398794 -290.60902)
		(width 0.1143)
		(layer "In4.Cu")
		(net "P5E_CPU0_P3_RX_DP<14>")
	)
	(segment
		(start 373.926862 -289.797998)
		(end 373.896128 -289.780218)
		(width 0.1143)
		(layer "In4.Cu")
		(net "P5E_CPU0_P3_RX_DP<14>")
	)
	(arc
		(start 374.763284 -296.77868)
		(mid 374.735359 -296.68641)
		(end 374.725946 -296.590466)
		(width 0.14224)
		(layer "In4.Cu")
		(net "P5E_CPU0_P3_RX_DP<14>")
	)
	(arc
		(start 374.906794 -292.37051)
		(mid 375.150121 -291.905944)
		(end 374.906794 -291.441378)
		(width 0.1143)
		(layer "In4.Cu")
		(net "P5E_CPU0_P3_RX_DP<14>")
	)
	(arc
		(start 374.906794 -295.610534)
		(mid 375.150121 -295.145968)
		(end 374.906794 -294.681402)
		(width 0.1143)
		(layer "In4.Cu")
		(net "P5E_CPU0_P3_RX_DP<14>")
	)
	(arc
		(start 395.26972 -378.215398)
		(mid 395.292619 -378.112893)
		(end 395.3002 -378.008134)
		(width 0.14224)
		(layer "In4.Cu")
		(net "P5E_CPU0_P3_RX_DP<14>")
	)
	(arc
		(start 374.837198 -293.02075)
		(mid 374.680221 -292.71595)
		(end 374.837198 -292.41115)
		(width 0.1143)
		(layer "In4.Cu")
		(net "P5E_CPU0_P3_RX_DP<14>")
	)
	(arc
		(start 374.680226 -291.095938)
		(mid 374.615711 -290.833719)
		(end 374.436894 -290.631372)
		(width 0.1143)
		(layer "In4.Cu")
		(net "P5E_CPU0_P3_RX_DP<14>")
	)
	(arc
		(start 374.397016 -290.608004)
		(mid 374.259614 -290.471171)
		(end 374.20931 -290.2839)
		(width 0.1143)
		(layer "In4.Cu")
		(net "P5E_CPU0_P3_RX_DP<14>")
	)
	(arc
		(start 374.906794 -293.990522)
		(mid 375.150121 -293.525956)
		(end 374.906794 -293.06139)
		(width 0.1143)
		(layer "In4.Cu")
		(net "P5E_CPU0_P3_RX_DP<14>")
	)
	(arc
		(start 373.896128 -289.780218)
		(mid 373.798993 -289.677349)
		(end 373.74703 -289.545776)
		(width 0.1143)
		(layer "In4.Cu")
		(net "P5E_CPU0_P3_RX_DP<14>")
	)
	(arc
		(start 374.837198 -294.640762)
		(mid 374.680221 -294.335962)
		(end 374.837198 -294.031162)
		(width 0.1143)
		(layer "In4.Cu")
		(net "P5E_CPU0_P3_RX_DP<14>")
	)
	(arc
		(start 374.837198 -291.400738)
		(mid 374.721771 -291.267362)
		(end 374.680226 -291.095938)
		(width 0.1143)
		(layer "In4.Cu")
		(net "P5E_CPU0_P3_RX_DP<14>")
	)
	(arc
		(start 374.20931 -290.2839)
		(mid 374.134671 -290.004823)
		(end 373.930672 -289.800284)
		(width 0.1143)
		(layer "In4.Cu")
		(net "P5E_CPU0_P3_RX_DP<14>")
	)
	(arc
		(start 393.591796 -368.646456)
		(mid 393.58691 -368.625237)
		(end 393.585192 -368.60353)
		(width 0.14224)
		(layer "In4.Cu")
		(net "P5E_CPU0_P3_RX_DP<14>")
	)
	(arc
		(start 388.440422 -390.761474)
		(mid 388.449751 -390.699101)
		(end 388.476744 -390.642094)
		(width 0.14224)
		(layer "In4.Cu")
		(net "P5E_CPU0_P3_RX_DP<14>")
	)
	(arc
		(start 374.680226 -295.955974)
		(mid 374.721775 -295.784552)
		(end 374.837198 -295.651174)
		(width 0.1143)
		(layer "In4.Cu")
		(net "P5E_CPU0_P3_RX_DP<14>")
	)
	(segment
		(start 373.64797 -290.83)
		(end 374.114822 -291.095938)
		(width 0.12954)
		(layer "F.Cu")
		(net "P5E_CPU0_P3_RX_DP<13>")
	)
	(segment
		(start 386.370576 -394.385292)
		(end 386.891276 -394.385292)
		(width 0.127)
		(layer "F.Cu")
		(net "P5E_CPU0_P3_RX_DP<13>")
	)
	(segment
		(start 393.526772 -378.951998)
		(end 393.528804 -378.948696)
		(width 0.14224)
		(layer "In4.Cu")
		(net "P5E_CPU0_P3_RX_DP<13>")
	)
	(segment
		(start 392.604752 -336.956908)
		(end 391.036556 -328.22642)
		(width 0.14224)
		(layer "In4.Cu")
		(net "P5E_CPU0_P3_RX_DP<13>")
	)
	(segment
		(start 374.200166 -297.865292)
		(end 373.834406 -296.982134)
		(width 0.14224)
		(layer "In4.Cu")
		(net "P5E_CPU0_P3_RX_DP<13>")
	)
	(segment
		(start 373.785892 -296.322496)
		(end 373.740172 -296.276776)
		(width 0.1143)
		(layer "In4.Cu")
		(net "P5E_CPU0_P3_RX_DP<13>")
	)
	(segment
		(start 373.785892 -296.738548)
		(end 373.785892 -296.350944)
		(width 0.14224)
		(layer "In4.Cu")
		(net "P5E_CPU0_P3_RX_DP<13>")
	)
	(segment
		(start 373.740172 -296.276776)
		(end 373.740172 -295.955974)
		(width 0.1143)
		(layer "In4.Cu")
		(net "P5E_CPU0_P3_RX_DP<13>")
	)
	(segment
		(start 386.935218 -392.807698)
		(end 387.193282 -392.549888)
		(width 0.14224)
		(layer "In4.Cu")
		(net "P5E_CPU0_P3_RX_DP<13>")
	)
	(segment
		(start 392.604752 -368.517932)
		(end 392.604752 -336.956908)
		(width 0.14224)
		(layer "In4.Cu")
		(net "P5E_CPU0_P3_RX_DP<13>")
	)
	(segment
		(start 386.891276 -394.385292)
		(end 386.986272 -394.031216)
		(width 0.14224)
		(layer "In4.Cu")
		(net "P5E_CPU0_P3_RX_DP<13>")
	)
	(segment
		(start 373.896128 -294.03167)
		(end 373.925846 -294.014652)
		(width 0.1143)
		(layer "In4.Cu")
		(net "P5E_CPU0_P3_RX_DP<13>")
	)
	(segment
		(start 391.036556 -328.22642)
		(end 386.257292 -314.46724)
		(width 0.14224)
		(layer "In4.Cu")
		(net "P5E_CPU0_P3_RX_DP<13>")
	)
	(segment
		(start 387.248654 -393.428982)
		(end 386.932678 -393.113006)
		(width 0.14224)
		(layer "In4.Cu")
		(net "P5E_CPU0_P3_RX_DP<13>")
	)
	(segment
		(start 373.74703 -291.165788)
		(end 373.81688 -291.095938)
		(width 0.1143)
		(layer "In4.Cu")
		(net "P5E_CPU0_P3_RX_DP<13>")
	)
	(segment
		(start 373.927878 -294.013382)
		(end 373.928386 -294.013382)
		(width 0.1143)
		(layer "In4.Cu")
		(net "P5E_CPU0_P3_RX_DP<13>")
	)
	(segment
		(start 373.928386 -293.03853)
		(end 373.927878 -293.03853)
		(width 0.1143)
		(layer "In4.Cu")
		(net "P5E_CPU0_P3_RX_DP<13>")
	)
	(segment
		(start 386.986272 -394.031216)
		(end 387.160516 -393.930632)
		(width 0.14224)
		(layer "In4.Cu")
		(net "P5E_CPU0_P3_RX_DP<13>")
	)
	(segment
		(start 387.544564 -389.94588)
		(end 387.544564 -389.946134)
		(width 0.14224)
		(layer "In4.Cu")
		(net "P5E_CPU0_P3_RX_DP<13>")
	)
	(segment
		(start 394.026898 -377.199652)
		(end 394.026898 -375.82221)
		(width 0.14224)
		(layer "In4.Cu")
		(net "P5E_CPU0_P3_RX_DP<13>")
	)
	(segment
		(start 373.927878 -293.03853)
		(end 373.896128 -293.020242)
		(width 0.1143)
		(layer "In4.Cu")
		(net "P5E_CPU0_P3_RX_DP<13>")
	)
	(segment
		(start 373.925846 -294.014652)
		(end 373.927116 -294.01389)
		(width 0.1143)
		(layer "In4.Cu")
		(net "P5E_CPU0_P3_RX_DP<13>")
	)
	(segment
		(start 373.927878 -294.658542)
		(end 373.896128 -294.640254)
		(width 0.1143)
		(layer "In4.Cu")
		(net "P5E_CPU0_P3_RX_DP<13>")
	)
	(segment
		(start 373.81688 -291.095938)
		(end 374.114822 -291.095938)
		(width 0.1143)
		(layer "In4.Cu")
		(net "P5E_CPU0_P3_RX_DP<13>")
	)
	(segment
		(start 387.160516 -393.930632)
		(end 387.248654 -393.842494)
		(width 0.14224)
		(layer "In4.Cu")
		(net "P5E_CPU0_P3_RX_DP<13>")
	)
	(segment
		(start 387.248654 -393.842494)
		(end 387.248654 -393.428982)
		(width 0.14224)
		(layer "In4.Cu")
		(net "P5E_CPU0_P3_RX_DP<13>")
	)
	(segment
		(start 373.785892 -296.350944)
		(end 373.785892 -296.322496)
		(width 0.1143)
		(layer "In4.Cu")
		(net "P5E_CPU0_P3_RX_DP<13>")
	)
	(segment
		(start 387.240526 -392.435842)
		(end 387.240526 -391.054844)
		(width 0.14224)
		(layer "In4.Cu")
		(net "P5E_CPU0_P3_RX_DP<13>")
	)
	(segment
		(start 386.257292 -314.46724)
		(end 383.780792 -309.83428)
		(width 0.14224)
		(layer "In4.Cu")
		(net "P5E_CPU0_P3_RX_DP<13>")
	)
	(segment
		(start 394.009626 -375.64441)
		(end 392.617198 -368.643662)
		(width 0.14224)
		(layer "In4.Cu")
		(net "P5E_CPU0_P3_RX_DP<13>")
	)
	(segment
		(start 373.896128 -295.651682)
		(end 373.927878 -295.633394)
		(width 0.1143)
		(layer "In4.Cu")
		(net "P5E_CPU0_P3_RX_DP<13>")
	)
	(segment
		(start 386.932678 -393.113006)
		(end 386.935218 -392.807698)
		(width 0.14224)
		(layer "In4.Cu")
		(net "P5E_CPU0_P3_RX_DP<13>")
	)
	(segment
		(start 373.927878 -291.418518)
		(end 373.896128 -291.40023)
		(width 0.1143)
		(layer "In4.Cu")
		(net "P5E_CPU0_P3_RX_DP<13>")
	)
	(segment
		(start 383.780792 -309.83428)
		(end 375.0945 -299.249084)
		(width 0.14224)
		(layer "In4.Cu")
		(net "P5E_CPU0_P3_RX_DP<13>")
	)
	(segment
		(start 373.927116 -294.01389)
		(end 373.927878 -294.013382)
		(width 0.1143)
		(layer "In4.Cu")
		(net "P5E_CPU0_P3_RX_DP<13>")
	)
	(segment
		(start 387.558788 -389.919464)
		(end 387.558788 -389.91921)
		(width 0.14224)
		(layer "In4.Cu")
		(net "P5E_CPU0_P3_RX_DP<13>")
	)
	(segment
		(start 373.896128 -292.411658)
		(end 373.927878 -292.39337)
		(width 0.1143)
		(layer "In4.Cu")
		(net "P5E_CPU0_P3_RX_DP<13>")
	)
	(segment
		(start 387.558788 -389.91921)
		(end 393.526772 -378.951998)
		(width 0.14224)
		(layer "In4.Cu")
		(net "P5E_CPU0_P3_RX_DP<13>")
	)
	(segment
		(start 375.0945 -299.249084)
		(end 374.321324 -298.091606)
		(width 0.14224)
		(layer "In4.Cu")
		(net "P5E_CPU0_P3_RX_DP<13>")
	)
	(arc
		(start 373.927878 -292.39337)
		(mid 374.208525 -291.905944)
		(end 373.927878 -291.418518)
		(width 0.1143)
		(layer "In4.Cu")
		(net "P5E_CPU0_P3_RX_DP<13>")
	)
	(arc
		(start 374.321324 -298.091606)
		(mid 374.255193 -297.981421)
		(end 374.200166 -297.865292)
		(width 0.14224)
		(layer "In4.Cu")
		(net "P5E_CPU0_P3_RX_DP<13>")
	)
	(arc
		(start 373.927878 -295.633394)
		(mid 374.208525 -295.145968)
		(end 373.927878 -294.658542)
		(width 0.1143)
		(layer "In4.Cu")
		(net "P5E_CPU0_P3_RX_DP<13>")
	)
	(arc
		(start 387.240526 -391.054844)
		(mid 387.243195 -390.991373)
		(end 387.251194 -390.928352)
		(width 0.14224)
		(layer "In4.Cu")
		(net "P5E_CPU0_P3_RX_DP<13>")
	)
	(arc
		(start 387.544564 -389.946134)
		(mid 387.551634 -389.932777)
		(end 387.558788 -389.919464)
		(width 0.14224)
		(layer "In4.Cu")
		(net "P5E_CPU0_P3_RX_DP<13>")
	)
	(arc
		(start 387.251194 -390.928352)
		(mid 387.277211 -390.779114)
		(end 387.304788 -390.630156)
		(width 0.14224)
		(layer "In4.Cu")
		(net "P5E_CPU0_P3_RX_DP<13>")
	)
	(arc
		(start 373.896128 -291.40023)
		(mid 373.798993 -291.297361)
		(end 373.74703 -291.165788)
		(width 0.1143)
		(layer "In4.Cu")
		(net "P5E_CPU0_P3_RX_DP<13>")
	)
	(arc
		(start 373.896128 -293.020242)
		(mid 373.7402 -292.71595)
		(end 373.896128 -292.411658)
		(width 0.1143)
		(layer "In4.Cu")
		(net "P5E_CPU0_P3_RX_DP<13>")
	)
	(arc
		(start 373.896128 -294.640254)
		(mid 373.7402 -294.335962)
		(end 373.896128 -294.03167)
		(width 0.1143)
		(layer "In4.Cu")
		(net "P5E_CPU0_P3_RX_DP<13>")
	)
	(arc
		(start 373.834406 -296.982134)
		(mid 373.798167 -296.862729)
		(end 373.785892 -296.738548)
		(width 0.14224)
		(layer "In4.Cu")
		(net "P5E_CPU0_P3_RX_DP<13>")
	)
	(arc
		(start 387.304788 -390.630156)
		(mid 387.39917 -390.279081)
		(end 387.544564 -389.94588)
		(width 0.14224)
		(layer "In4.Cu")
		(net "P5E_CPU0_P3_RX_DP<13>")
	)
	(arc
		(start 392.617198 -368.643662)
		(mid 392.607895 -368.581102)
		(end 392.604752 -368.517932)
		(width 0.14224)
		(layer "In4.Cu")
		(net "P5E_CPU0_P3_RX_DP<13>")
	)
	(arc
		(start 393.528804 -378.948696)
		(mid 393.899933 -378.108942)
		(end 394.026898 -377.199652)
		(width 0.14224)
		(layer "In4.Cu")
		(net "P5E_CPU0_P3_RX_DP<13>")
	)
	(arc
		(start 373.928386 -294.013382)
		(mid 374.209033 -293.525956)
		(end 373.928386 -293.03853)
		(width 0.1143)
		(layer "In4.Cu")
		(net "P5E_CPU0_P3_RX_DP<13>")
	)
	(arc
		(start 394.026898 -375.82221)
		(mid 394.02256 -375.732892)
		(end 394.009626 -375.64441)
		(width 0.14224)
		(layer "In4.Cu")
		(net "P5E_CPU0_P3_RX_DP<13>")
	)
	(arc
		(start 387.193282 -392.549888)
		(mid 387.228298 -392.497578)
		(end 387.240526 -392.435842)
		(width 0.14224)
		(layer "In4.Cu")
		(net "P5E_CPU0_P3_RX_DP<13>")
	)
	(arc
		(start 373.740172 -295.955974)
		(mid 373.781427 -295.785003)
		(end 373.896128 -295.651682)
		(width 0.1143)
		(layer "In4.Cu")
		(net "P5E_CPU0_P3_RX_DP<13>")
	)
	(segment
		(start 373.64797 -287.59023)
		(end 374.114822 -287.856168)
		(width 0.12954)
		(layer "F.Cu")
		(net "P5E_CPU0_P3_RX_DP<12>")
	)
	(segment
		(start 385.170426 -394.385292)
		(end 385.691126 -394.385292)
		(width 0.127)
		(layer "F.Cu")
		(net "P5E_CPU0_P3_RX_DP<12>")
	)
	(segment
		(start 385.732528 -393.113006)
		(end 385.735576 -392.752326)
		(width 0.14224)
		(layer "In4.Cu")
		(net "P5E_CPU0_P3_RX_DP<12>")
	)
	(segment
		(start 372.984268 -291.416486)
		(end 372.983506 -291.415978)
		(width 0.1143)
		(layer "In4.Cu")
		(net "P5E_CPU0_P3_RX_DP<12>")
	)
	(segment
		(start 372.98884 -292.392862)
		(end 372.990364 -292.391846)
		(width 0.1143)
		(layer "In4.Cu")
		(net "P5E_CPU0_P3_RX_DP<12>")
	)
	(segment
		(start 372.994682 -291.422582)
		(end 372.993158 -291.421566)
		(width 0.1143)
		(layer "In4.Cu")
		(net "P5E_CPU0_P3_RX_DP<12>")
	)
	(segment
		(start 372.976394 -294.019986)
		(end 372.977664 -294.019224)
		(width 0.1143)
		(layer "In4.Cu")
		(net "P5E_CPU0_P3_RX_DP<12>")
	)
	(segment
		(start 372.990618 -291.420042)
		(end 372.98884 -291.419026)
		(width 0.1143)
		(layer "In4.Cu")
		(net "P5E_CPU0_P3_RX_DP<12>")
	)
	(segment
		(start 372.974362 -294.649398)
		(end 372.952772 -294.636952)
		(width 0.1143)
		(layer "In4.Cu")
		(net "P5E_CPU0_P3_RX_DP<12>")
	)
	(segment
		(start 372.987824 -289.153346)
		(end 372.990364 -289.152076)
		(width 0.1143)
		(layer "In4.Cu")
		(net "P5E_CPU0_P3_RX_DP<12>")
	)
	(segment
		(start 372.956328 -289.171634)
		(end 372.977664 -289.159188)
		(width 0.1143)
		(layer "In4.Cu")
		(net "P5E_CPU0_P3_RX_DP<12>")
	)
	(segment
		(start 372.987062 -289.153854)
		(end 372.987824 -289.153346)
		(width 0.1143)
		(layer "In4.Cu")
		(net "P5E_CPU0_P3_RX_DP<12>")
	)
	(segment
		(start 373.02694 -294.681402)
		(end 372.990364 -294.660066)
		(width 0.1143)
		(layer "In4.Cu")
		(net "P5E_CPU0_P3_RX_DP<12>")
	)
	(segment
		(start 372.993412 -294.01008)
		(end 372.994174 -294.009572)
		(width 0.1143)
		(layer "In4.Cu")
		(net "P5E_CPU0_P3_RX_DP<12>")
	)
	(segment
		(start 372.993412 -292.390068)
		(end 372.994174 -292.38956)
		(width 0.1143)
		(layer "In4.Cu")
		(net "P5E_CPU0_P3_RX_DP<12>")
	)
	(segment
		(start 372.987824 -292.39337)
		(end 372.98884 -292.392862)
		(width 0.1143)
		(layer "In4.Cu")
		(net "P5E_CPU0_P3_RX_DP<12>")
	)
	(segment
		(start 385.786122 -394.031216)
		(end 385.960366 -393.930632)
		(width 0.14224)
		(layer "In4.Cu")
		(net "P5E_CPU0_P3_RX_DP<12>")
	)
	(segment
		(start 373.02694 -291.441378)
		(end 373.020082 -291.437314)
		(width 0.1143)
		(layer "In4.Cu")
		(net "P5E_CPU0_P3_RX_DP<12>")
	)
	(segment
		(start 373.020082 -291.437314)
		(end 373.01932 -291.436806)
		(width 0.1143)
		(layer "In4.Cu")
		(net "P5E_CPU0_P3_RX_DP<12>")
	)
	(segment
		(start 372.95582 -295.651682)
		(end 372.98757 -295.633394)
		(width 0.1143)
		(layer "In4.Cu")
		(net "P5E_CPU0_P3_RX_DP<12>")
	)
	(segment
		(start 372.994174 -294.009572)
		(end 373.02694 -293.990522)
		(width 0.1143)
		(layer "In4.Cu")
		(net "P5E_CPU0_P3_RX_DP<12>")
	)
	(segment
		(start 372.979442 -292.398704)
		(end 372.980204 -292.398196)
		(width 0.1143)
		(layer "In4.Cu")
		(net "P5E_CPU0_P3_RX_DP<12>")
	)
	(segment
		(start 372.987824 -294.013382)
		(end 372.98884 -294.012874)
		(width 0.1143)
		(layer "In4.Cu")
		(net "P5E_CPU0_P3_RX_DP<12>")
	)
	(segment
		(start 372.845584 -296.411142)
		(end 372.799864 -296.365422)
		(width 0.1143)
		(layer "In4.Cu")
		(net "P5E_CPU0_P3_RX_DP<12>")
	)
	(segment
		(start 372.987062 -291.41801)
		(end 372.984268 -291.416486)
		(width 0.1143)
		(layer "In4.Cu")
		(net "P5E_CPU0_P3_RX_DP<12>")
	)
	(segment
		(start 372.98884 -294.012874)
		(end 372.990364 -294.011858)
		(width 0.1143)
		(layer "In4.Cu")
		(net "P5E_CPU0_P3_RX_DP<12>")
	)
	(segment
		(start 372.987824 -293.03853)
		(end 372.956074 -293.020242)
		(width 0.1143)
		(layer "In4.Cu")
		(net "P5E_CPU0_P3_RX_DP<12>")
	)
	(segment
		(start 372.98757 -295.633394)
		(end 373.02821 -295.609518)
		(width 0.1143)
		(layer "In4.Cu")
		(net "P5E_CPU0_P3_RX_DP<12>")
	)
	(segment
		(start 372.984268 -289.155378)
		(end 372.987062 -289.153854)
		(width 0.1143)
		(layer "In4.Cu")
		(net "P5E_CPU0_P3_RX_DP<12>")
	)
	(segment
		(start 372.974616 -292.40099)
		(end 372.978172 -292.399212)
		(width 0.1143)
		(layer "In4.Cu")
		(net "P5E_CPU0_P3_RX_DP<12>")
	)
	(segment
		(start 386.200904 -390.173464)
		(end 388.739634 -384.04419)
		(width 0.14224)
		(layer "In4.Cu")
		(net "P5E_CPU0_P3_RX_DP<12>")
	)
	(segment
		(start 373.270272 -295.146476)
		(end 373.270272 -295.145968)
		(width 0.1143)
		(layer "In4.Cu")
		(net "P5E_CPU0_P3_RX_DP<12>")
	)
	(segment
		(start 372.978426 -294.018716)
		(end 372.97995 -294.017954)
		(width 0.1143)
		(layer "In4.Cu")
		(net "P5E_CPU0_P3_RX_DP<12>")
	)
	(segment
		(start 372.981982 -294.016684)
		(end 372.983506 -294.015922)
		(width 0.1143)
		(layer "In4.Cu")
		(net "P5E_CPU0_P3_RX_DP<12>")
	)
	(segment
		(start 372.990364 -294.011858)
		(end 372.992142 -294.010842)
		(width 0.1143)
		(layer "In4.Cu")
		(net "P5E_CPU0_P3_RX_DP<12>")
	)
	(segment
		(start 372.990364 -293.040054)
		(end 372.98884 -293.039038)
		(width 0.1143)
		(layer "In4.Cu")
		(net "P5E_CPU0_P3_RX_DP<12>")
	)
	(segment
		(start 385.44881 -314.982098)
		(end 382.942846 -310.294782)
		(width 0.14224)
		(layer "In4.Cu")
		(net "P5E_CPU0_P3_RX_DP<12>")
	)
	(segment
		(start 373.438928 -288.354516)
		(end 373.49684 -288.320734)
		(width 0.1143)
		(layer "In4.Cu")
		(net "P5E_CPU0_P3_RX_DP<12>")
	)
	(segment
		(start 372.985792 -292.39464)
		(end 372.987062 -292.393878)
		(width 0.1143)
		(layer "In4.Cu")
		(net "P5E_CPU0_P3_RX_DP<12>")
	)
	(segment
		(start 382.942846 -310.294782)
		(end 374.294654 -299.75556)
		(width 0.14224)
		(layer "In4.Cu")
		(net "P5E_CPU0_P3_RX_DP<12>")
	)
	(segment
		(start 372.977664 -294.019224)
		(end 372.978426 -294.018716)
		(width 0.1143)
		(layer "In4.Cu")
		(net "P5E_CPU0_P3_RX_DP<12>")
	)
	(segment
		(start 372.98122 -294.017192)
		(end 372.981982 -294.016684)
		(width 0.1143)
		(layer "In4.Cu")
		(net "P5E_CPU0_P3_RX_DP<12>")
	)
	(segment
		(start 372.992142 -292.39083)
		(end 372.993412 -292.390068)
		(width 0.1143)
		(layer "In4.Cu")
		(net "P5E_CPU0_P3_RX_DP<12>")
	)
	(segment
		(start 372.983506 -294.015922)
		(end 372.984268 -294.015414)
		(width 0.1143)
		(layer "In4.Cu")
		(net "P5E_CPU0_P3_RX_DP<12>")
	)
	(segment
		(start 372.973854 -292.401244)
		(end 372.974616 -292.40099)
		(width 0.1143)
		(layer "In4.Cu")
		(net "P5E_CPU0_P3_RX_DP<12>")
	)
	(segment
		(start 386.040376 -390.979914)
		(end 386.04063 -390.980168)
		(width 0.14224)
		(layer "In4.Cu")
		(net "P5E_CPU0_P3_RX_DP<12>")
	)
	(segment
		(start 372.98884 -293.039038)
		(end 372.987824 -293.03853)
		(width 0.1143)
		(layer "In4.Cu")
		(net "P5E_CPU0_P3_RX_DP<12>")
	)
	(segment
		(start 390.102344 -328.380344)
		(end 385.44881 -314.982098)
		(width 0.14224)
		(layer "In4.Cu")
		(net "P5E_CPU0_P3_RX_DP<12>")
	)
	(segment
		(start 372.980204 -292.398196)
		(end 372.981474 -292.397434)
		(width 0.1143)
		(layer "In4.Cu")
		(net "P5E_CPU0_P3_RX_DP<12>")
	)
	(segment
		(start 385.691126 -394.385292)
		(end 385.786122 -394.031216)
		(width 0.14224)
		(layer "In4.Cu")
		(net "P5E_CPU0_P3_RX_DP<12>")
	)
	(segment
		(start 372.98884 -291.419026)
		(end 372.987824 -291.418518)
		(width 0.1143)
		(layer "In4.Cu")
		(net "P5E_CPU0_P3_RX_DP<12>")
	)
	(segment
		(start 373.02694 -293.06139)
		(end 372.990364 -293.040054)
		(width 0.1143)
		(layer "In4.Cu")
		(net "P5E_CPU0_P3_RX_DP<12>")
	)
	(segment
		(start 373.430292 -298.462192)
		(end 372.893082 -297.166284)
		(width 0.14224)
		(layer "In4.Cu")
		(net "P5E_CPU0_P3_RX_DP<12>")
	)
	(segment
		(start 385.735576 -392.752326)
		(end 386.040376 -392.447526)
		(width 0.14224)
		(layer "In4.Cu")
		(net "P5E_CPU0_P3_RX_DP<12>")
	)
	(segment
		(start 391.58418 -371.389656)
		(end 391.58418 -336.63128)
		(width 0.14224)
		(layer "In4.Cu")
		(net "P5E_CPU0_P3_RX_DP<12>")
	)
	(segment
		(start 386.048504 -393.428982)
		(end 385.732528 -393.113006)
		(width 0.14224)
		(layer "In4.Cu")
		(net "P5E_CPU0_P3_RX_DP<12>")
	)
	(segment
		(start 372.845584 -296.927778)
		(end 372.845584 -296.43959)
		(width 0.14224)
		(layer "In4.Cu")
		(net "P5E_CPU0_P3_RX_DP<12>")
	)
	(segment
		(start 390.513062 -376.815096)
		(end 391.576306 -371.469666)
		(width 0.14224)
		(layer "In4.Cu")
		(net "P5E_CPU0_P3_RX_DP<12>")
	)
	(segment
		(start 372.97995 -294.017954)
		(end 372.98122 -294.017192)
		(width 0.1143)
		(layer "In4.Cu")
		(net "P5E_CPU0_P3_RX_DP<12>")
	)
	(segment
		(start 372.983506 -291.415978)
		(end 372.981982 -291.415216)
		(width 0.1143)
		(layer "In4.Cu")
		(net "P5E_CPU0_P3_RX_DP<12>")
	)
	(segment
		(start 372.799864 -296.365422)
		(end 372.799864 -295.955974)
		(width 0.1143)
		(layer "In4.Cu")
		(net "P5E_CPU0_P3_RX_DP<12>")
	)
	(segment
		(start 372.981982 -289.156648)
		(end 372.983506 -289.155886)
		(width 0.1143)
		(layer "In4.Cu")
		(net "P5E_CPU0_P3_RX_DP<12>")
	)
	(segment
		(start 372.984268 -294.015414)
		(end 372.987062 -294.01389)
		(width 0.1143)
		(layer "In4.Cu")
		(net "P5E_CPU0_P3_RX_DP<12>")
	)
	(segment
		(start 386.040376 -392.447526)
		(end 386.040376 -390.979914)
		(width 0.14224)
		(layer "In4.Cu")
		(net "P5E_CPU0_P3_RX_DP<12>")
	)
	(segment
		(start 372.978172 -292.399212)
		(end 372.979442 -292.398704)
		(width 0.1143)
		(layer "In4.Cu")
		(net "P5E_CPU0_P3_RX_DP<12>")
	)
	(segment
		(start 372.987062 -292.393878)
		(end 372.987824 -292.39337)
		(width 0.1143)
		(layer "In4.Cu")
		(net "P5E_CPU0_P3_RX_DP<12>")
	)
	(segment
		(start 372.956074 -292.411658)
		(end 372.973854 -292.401244)
		(width 0.1143)
		(layer "In4.Cu")
		(net "P5E_CPU0_P3_RX_DP<12>")
	)
	(segment
		(start 372.992142 -291.421058)
		(end 372.990618 -291.420042)
		(width 0.1143)
		(layer "In4.Cu")
		(net "P5E_CPU0_P3_RX_DP<12>")
	)
	(segment
		(start 372.994936 -289.149282)
		(end 373.001794 -289.145472)
		(width 0.1143)
		(layer "In4.Cu")
		(net "P5E_CPU0_P3_RX_DP<12>")
	)
	(segment
		(start 372.4783 -289.97402)
		(end 372.533164 -289.941762)
		(width 0.1143)
		(layer "In4.Cu")
		(net "P5E_CPU0_P3_RX_DP<12>")
	)
	(segment
		(start 388.739634 -384.04419)
		(end 389.320278 -383.175002)
		(width 0.14224)
		(layer "In4.Cu")
		(net "P5E_CPU0_P3_RX_DP<12>")
	)
	(segment
		(start 373.01932 -291.436806)
		(end 372.994682 -291.422582)
		(width 0.1143)
		(layer "In4.Cu")
		(net "P5E_CPU0_P3_RX_DP<12>")
	)
	(segment
		(start 385.960366 -393.930632)
		(end 386.048504 -393.842494)
		(width 0.14224)
		(layer "In4.Cu")
		(net "P5E_CPU0_P3_RX_DP<12>")
	)
	(segment
		(start 372.556786 -290.631372)
		(end 372.507002 -290.602416)
		(width 0.1143)
		(layer "In4.Cu")
		(net "P5E_CPU0_P3_RX_DP<12>")
	)
	(segment
		(start 372.993158 -291.421566)
		(end 372.992142 -291.421058)
		(width 0.1143)
		(layer "In4.Cu")
		(net "P5E_CPU0_P3_RX_DP<12>")
	)
	(segment
		(start 372.987062 -294.01389)
		(end 372.987824 -294.013382)
		(width 0.1143)
		(layer "In4.Cu")
		(net "P5E_CPU0_P3_RX_DP<12>")
	)
	(segment
		(start 373.001794 -289.145472)
		(end 373.02694 -289.13074)
		(width 0.1143)
		(layer "In4.Cu")
		(net "P5E_CPU0_P3_RX_DP<12>")
	)
	(segment
		(start 372.990364 -294.660066)
		(end 372.974362 -294.649398)
		(width 0.1143)
		(layer "In4.Cu")
		(net "P5E_CPU0_P3_RX_DP<12>")
	)
	(segment
		(start 372.98122 -289.157156)
		(end 372.981982 -289.156648)
		(width 0.1143)
		(layer "In4.Cu")
		(net "P5E_CPU0_P3_RX_DP<12>")
	)
	(segment
		(start 372.990364 -292.391846)
		(end 372.992142 -292.39083)
		(width 0.1143)
		(layer "In4.Cu")
		(net "P5E_CPU0_P3_RX_DP<12>")
	)
	(segment
		(start 372.981474 -292.397434)
		(end 372.985792 -292.39464)
		(width 0.1143)
		(layer "In4.Cu")
		(net "P5E_CPU0_P3_RX_DP<12>")
	)
	(segment
		(start 372.97995 -289.157918)
		(end 372.98122 -289.157156)
		(width 0.1143)
		(layer "In4.Cu")
		(net "P5E_CPU0_P3_RX_DP<12>")
	)
	(segment
		(start 372.952772 -294.028368)
		(end 372.953026 -294.028114)
		(width 0.1143)
		(layer "In4.Cu")
		(net "P5E_CPU0_P3_RX_DP<12>")
	)
	(segment
		(start 386.048504 -393.842494)
		(end 386.048504 -393.428982)
		(width 0.14224)
		(layer "In4.Cu")
		(net "P5E_CPU0_P3_RX_DP<12>")
	)
	(segment
		(start 374.294654 -299.75556)
		(end 373.430292 -298.462192)
		(width 0.14224)
		(layer "In4.Cu")
		(net "P5E_CPU0_P3_RX_DP<12>")
	)
	(segment
		(start 391.58418 -336.63128)
		(end 390.102344 -328.380344)
		(width 0.14224)
		(layer "In4.Cu")
		(net "P5E_CPU0_P3_RX_DP<12>")
	)
	(segment
		(start 373.734076 -287.938972)
		(end 373.81688 -287.856168)
		(width 0.1143)
		(layer "In4.Cu")
		(net "P5E_CPU0_P3_RX_DP<12>")
	)
	(segment
		(start 372.974616 -294.021002)
		(end 372.976394 -294.019986)
		(width 0.1143)
		(layer "In4.Cu")
		(net "P5E_CPU0_P3_RX_DP<12>")
	)
	(segment
		(start 372.983506 -289.155886)
		(end 372.984268 -289.155378)
		(width 0.1143)
		(layer "In4.Cu")
		(net "P5E_CPU0_P3_RX_DP<12>")
	)
	(segment
		(start 372.978426 -289.15868)
		(end 372.97995 -289.157918)
		(width 0.1143)
		(layer "In4.Cu")
		(net "P5E_CPU0_P3_RX_DP<12>")
	)
	(segment
		(start 372.987824 -291.418518)
		(end 372.987062 -291.41801)
		(width 0.1143)
		(layer "In4.Cu")
		(net "P5E_CPU0_P3_RX_DP<12>")
	)
	(segment
		(start 372.994174 -292.38956)
		(end 373.02694 -292.37051)
		(width 0.1143)
		(layer "In4.Cu")
		(net "P5E_CPU0_P3_RX_DP<12>")
	)
	(segment
		(start 372.953026 -294.028114)
		(end 372.974616 -294.021002)
		(width 0.1143)
		(layer "In4.Cu")
		(net "P5E_CPU0_P3_RX_DP<12>")
	)
	(segment
		(start 372.990364 -289.152076)
		(end 372.992142 -289.15106)
		(width 0.1143)
		(layer "In4.Cu")
		(net "P5E_CPU0_P3_RX_DP<12>")
	)
	(segment
		(start 372.992142 -294.010842)
		(end 372.993412 -294.01008)
		(width 0.1143)
		(layer "In4.Cu")
		(net "P5E_CPU0_P3_RX_DP<12>")
	)
	(segment
		(start 389.92556 -381.71374)
		(end 390.513062 -378.761244)
		(width 0.14224)
		(layer "In4.Cu")
		(net "P5E_CPU0_P3_RX_DP<12>")
	)
	(segment
		(start 372.981982 -291.415216)
		(end 372.98122 -291.414708)
		(width 0.1143)
		(layer "In4.Cu")
		(net "P5E_CPU0_P3_RX_DP<12>")
	)
	(segment
		(start 372.993412 -289.150298)
		(end 372.994936 -289.149282)
		(width 0.1143)
		(layer "In4.Cu")
		(net "P5E_CPU0_P3_RX_DP<12>")
	)
	(segment
		(start 390.513062 -378.761244)
		(end 390.513062 -376.815096)
		(width 0.14224)
		(layer "In4.Cu")
		(net "P5E_CPU0_P3_RX_DP<12>")
	)
	(segment
		(start 372.977664 -289.159188)
		(end 372.978426 -289.15868)
		(width 0.1143)
		(layer "In4.Cu")
		(net "P5E_CPU0_P3_RX_DP<12>")
	)
	(segment
		(start 372.845584 -296.43959)
		(end 372.845584 -296.411142)
		(width 0.1143)
		(layer "In4.Cu")
		(net "P5E_CPU0_P3_RX_DP<12>")
	)
	(segment
		(start 372.992142 -289.15106)
		(end 372.993412 -289.150298)
		(width 0.1143)
		(layer "In4.Cu")
		(net "P5E_CPU0_P3_RX_DP<12>")
	)
	(segment
		(start 373.81688 -287.856168)
		(end 374.114822 -287.856168)
		(width 0.1143)
		(layer "In4.Cu")
		(net "P5E_CPU0_P3_RX_DP<12>")
	)
	(arc
		(start 386.04063 -390.980168)
		(mid 386.081034 -390.568921)
		(end 386.200904 -390.173464)
		(width 0.14224)
		(layer "In4.Cu")
		(net "P5E_CPU0_P3_RX_DP<12>")
	)
	(arc
		(start 373.02694 -292.37051)
		(mid 373.270267 -291.905944)
		(end 373.02694 -291.441378)
		(width 0.1143)
		(layer "In4.Cu")
		(net "P5E_CPU0_P3_RX_DP<12>")
	)
	(arc
		(start 372.800118 -291.084254)
		(mid 372.732973 -290.828502)
		(end 372.556786 -290.631372)
		(width 0.1143)
		(layer "In4.Cu")
		(net "P5E_CPU0_P3_RX_DP<12>")
	)
	(arc
		(start 389.320278 -383.175002)
		(mid 389.69484 -382.474163)
		(end 389.92556 -381.71374)
		(width 0.14224)
		(layer "In4.Cu")
		(net "P5E_CPU0_P3_RX_DP<12>")
	)
	(arc
		(start 391.576306 -371.469666)
		(mid 391.582206 -371.429854)
		(end 391.58418 -371.389656)
		(width 0.14224)
		(layer "In4.Cu")
		(net "P5E_CPU0_P3_RX_DP<12>")
	)
	(arc
		(start 373.404384 -288.378646)
		(mid 373.421127 -288.365824)
		(end 373.438928 -288.354516)
		(width 0.1143)
		(layer "In4.Cu")
		(net "P5E_CPU0_P3_RX_DP<12>")
	)
	(arc
		(start 373.270272 -288.666174)
		(mid 373.305457 -288.507549)
		(end 373.404384 -288.378646)
		(width 0.1143)
		(layer "In4.Cu")
		(net "P5E_CPU0_P3_RX_DP<12>")
	)
	(arc
		(start 373.02821 -295.609518)
		(mid 373.206053 -295.407696)
		(end 373.270272 -295.146476)
		(width 0.1143)
		(layer "In4.Cu")
		(net "P5E_CPU0_P3_RX_DP<12>")
	)
	(arc
		(start 373.270272 -295.145968)
		(mid 373.205757 -294.883749)
		(end 373.02694 -294.681402)
		(width 0.1143)
		(layer "In4.Cu")
		(net "P5E_CPU0_P3_RX_DP<12>")
	)
	(arc
		(start 372.507002 -290.602416)
		(mid 372.32151 -290.295979)
		(end 372.4783 -289.97402)
		(width 0.1143)
		(layer "In4.Cu")
		(net "P5E_CPU0_P3_RX_DP<12>")
	)
	(arc
		(start 372.800372 -289.475926)
		(mid 372.841627 -289.304955)
		(end 372.956328 -289.171634)
		(width 0.1143)
		(layer "In4.Cu")
		(net "P5E_CPU0_P3_RX_DP<12>")
	)
	(arc
		(start 372.98122 -291.414708)
		(mid 372.850206 -291.271674)
		(end 372.800118 -291.084254)
		(width 0.1143)
		(layer "In4.Cu")
		(net "P5E_CPU0_P3_RX_DP<12>")
	)
	(arc
		(start 372.893082 -297.166284)
		(mid 372.857573 -297.049373)
		(end 372.845584 -296.927778)
		(width 0.14224)
		(layer "In4.Cu")
		(net "P5E_CPU0_P3_RX_DP<12>")
	)
	(arc
		(start 372.799864 -295.955974)
		(mid 372.844452 -295.786709)
		(end 372.95582 -295.651682)
		(width 0.1143)
		(layer "In4.Cu")
		(net "P5E_CPU0_P3_RX_DP<12>")
	)
	(arc
		(start 373.02694 -289.13074)
		(mid 373.205753 -288.92839)
		(end 373.270272 -288.666174)
		(width 0.1143)
		(layer "In4.Cu")
		(net "P5E_CPU0_P3_RX_DP<12>")
	)
	(arc
		(start 373.02694 -293.990522)
		(mid 373.270267 -293.525956)
		(end 373.02694 -293.06139)
		(width 0.1143)
		(layer "In4.Cu")
		(net "P5E_CPU0_P3_RX_DP<12>")
	)
	(arc
		(start 372.952772 -294.636952)
		(mid 372.796844 -294.33266)
		(end 372.952772 -294.028368)
		(width 0.1143)
		(layer "In4.Cu")
		(net "P5E_CPU0_P3_RX_DP<12>")
	)
	(arc
		(start 372.533164 -289.941762)
		(mid 372.728797 -289.744431)
		(end 372.800372 -289.475926)
		(width 0.1143)
		(layer "In4.Cu")
		(net "P5E_CPU0_P3_RX_DP<12>")
	)
	(arc
		(start 372.956074 -293.020242)
		(mid 372.800146 -292.71595)
		(end 372.956074 -292.411658)
		(width 0.1143)
		(layer "In4.Cu")
		(net "P5E_CPU0_P3_RX_DP<12>")
	)
	(arc
		(start 373.49684 -288.320734)
		(mid 373.648827 -288.164226)
		(end 373.730266 -287.961832)
		(width 0.1143)
		(layer "In4.Cu")
		(net "P5E_CPU0_P3_RX_DP<12>")
	)
	(arc
		(start 373.730266 -287.961832)
		(mid 373.732289 -287.950422)
		(end 373.734076 -287.938972)
		(width 0.1143)
		(layer "In4.Cu")
		(net "P5E_CPU0_P3_RX_DP<12>")
	)
	(segment
		(start 373.97055 -393.69238)
		(end 374.49125 -393.69238)
		(width 0.127)
		(layer "F.Cu")
		(net "P5E_CPU0_P3_RX_DN<3>")
	)
	(segment
		(start 364.247938 -287.59023)
		(end 364.71479 -287.856168)
		(width 0.12954)
		(layer "F.Cu")
		(net "P5E_CPU0_P3_RX_DN<3>")
	)
	(segment
		(start 364.431834 -292.228524)
		(end 364.432596 -292.228016)
		(width 0.1143)
		(layer "In4.Cu")
		(net "P5E_CPU0_P3_RX_DN<3>")
	)
	(segment
		(start 364.430818 -293.202868)
		(end 364.392718 -293.180516)
		(width 0.1143)
		(layer "In4.Cu")
		(net "P5E_CPU0_P3_RX_DN<3>")
	)
	(segment
		(start 364.463584 -294.841676)
		(end 364.436406 -294.826182)
		(width 0.1143)
		(layer "In4.Cu")
		(net "P5E_CPU0_P3_RX_DN<3>")
	)
	(segment
		(start 364.433866 -291.584634)
		(end 364.432596 -291.583872)
		(width 0.1143)
		(layer "In4.Cu")
		(net "P5E_CPU0_P3_RX_DN<3>")
	)
	(segment
		(start 364.420658 -293.85514)
		(end 364.42142 -293.854632)
		(width 0.1143)
		(layer "In4.Cu")
		(net "P5E_CPU0_P3_RX_DN<3>")
	)
	(segment
		(start 364.430818 -293.849044)
		(end 364.431834 -293.848536)
		(width 0.1143)
		(layer "In4.Cu")
		(net "P5E_CPU0_P3_RX_DN<3>")
	)
	(segment
		(start 381.696468 -330.692252)
		(end 379.5903 -324.62978)
		(width 0.14224)
		(layer "In4.Cu")
		(net "P5E_CPU0_P3_RX_DN<3>")
	)
	(segment
		(start 364.437168 -293.845488)
		(end 364.43793 -293.84498)
		(width 0.1143)
		(layer "In4.Cu")
		(net "P5E_CPU0_P3_RX_DN<3>")
	)
	(segment
		(start 374.49125 -393.69238)
		(end 374.844564 -393.787376)
		(width 0.14224)
		(layer "In4.Cu")
		(net "P5E_CPU0_P3_RX_DN<3>")
	)
	(segment
		(start 374.966738 -393.716764)
		(end 374.966738 -393.545822)
		(width 0.14224)
		(layer "In4.Cu")
		(net "P5E_CPU0_P3_RX_DN<3>")
	)
	(segment
		(start 364.155228 -291.113464)
		(end 364.155228 -291.101272)
		(width 0.1143)
		(layer "In4.Cu")
		(net "P5E_CPU0_P3_RX_DN<3>")
	)
	(segment
		(start 364.432596 -293.203884)
		(end 364.431834 -293.203376)
		(width 0.1143)
		(layer "In4.Cu")
		(net "P5E_CPU0_P3_RX_DN<3>")
	)
	(segment
		(start 364.437168 -292.225476)
		(end 364.43793 -292.224968)
		(width 0.1143)
		(layer "In4.Cu")
		(net "P5E_CPU0_P3_RX_DN<3>")
	)
	(segment
		(start 372.556532 -385.585716)
		(end 372.255034 -385.284218)
		(width 0.14224)
		(layer "In4.Cu")
		(net "P5E_CPU0_P3_RX_DN<3>")
	)
	(segment
		(start 364.420658 -288.995104)
		(end 364.42142 -288.994596)
		(width 0.1143)
		(layer "In4.Cu")
		(net "P5E_CPU0_P3_RX_DN<3>")
	)
	(segment
		(start 371.758972 -384.982212)
		(end 371.758972 -384.788156)
		(width 0.14224)
		(layer "In4.Cu")
		(net "P5E_CPU0_P3_RX_DN<3>")
	)
	(segment
		(start 364.438946 -292.22446)
		(end 364.463584 -292.210236)
		(width 0.1143)
		(layer "In4.Cu")
		(net "P5E_CPU0_P3_RX_DN<3>")
	)
	(segment
		(start 374.966738 -393.545822)
		(end 374.649746 -393.22883)
		(width 0.14224)
		(layer "In4.Cu")
		(net "P5E_CPU0_P3_RX_DN<3>")
	)
	(segment
		(start 370.961412 -384.184652)
		(end 370.961412 -383.990596)
		(width 0.14224)
		(layer "In4.Cu")
		(net "P5E_CPU0_P3_RX_DN<3>")
	)
	(segment
		(start 382.91262 -349.762318)
		(end 382.91262 -337.463892)
		(width 0.14224)
		(layer "In4.Cu")
		(net "P5E_CPU0_P3_RX_DN<3>")
	)
	(segment
		(start 364.428278 -291.581332)
		(end 364.425738 -291.579808)
		(width 0.1143)
		(layer "In4.Cu")
		(net "P5E_CPU0_P3_RX_DN<3>")
	)
	(segment
		(start 374.845072 -393.786868)
		(end 374.966738 -393.716764)
		(width 0.14224)
		(layer "In4.Cu")
		(net "P5E_CPU0_P3_RX_DN<3>")
	)
	(segment
		(start 364.433866 -288.98723)
		(end 364.43539 -288.986468)
		(width 0.1143)
		(layer "In4.Cu")
		(net "P5E_CPU0_P3_RX_DN<3>")
	)
	(segment
		(start 374.649746 -393.22883)
		(end 374.656858 -392.31951)
		(width 0.14224)
		(layer "In4.Cu")
		(net "P5E_CPU0_P3_RX_DN<3>")
	)
	(segment
		(start 364.42142 -293.854632)
		(end 364.428278 -293.850568)
		(width 0.1143)
		(layer "In4.Cu")
		(net "P5E_CPU0_P3_RX_DN<3>")
	)
	(segment
		(start 371.457474 -384.486658)
		(end 371.263418 -384.486658)
		(width 0.14224)
		(layer "In4.Cu")
		(net "P5E_CPU0_P3_RX_DN<3>")
	)
	(segment
		(start 364.424722 -291.579046)
		(end 364.424214 -291.578792)
		(width 0.1143)
		(layer "In4.Cu")
		(net "P5E_CPU0_P3_RX_DN<3>")
	)
	(segment
		(start 364.435644 -294.825674)
		(end 364.433866 -294.824658)
		(width 0.1143)
		(layer "In4.Cu")
		(net "P5E_CPU0_P3_RX_DN<3>")
	)
	(segment
		(start 364.438946 -293.844472)
		(end 364.463584 -293.830248)
		(width 0.1143)
		(layer "In4.Cu")
		(net "P5E_CPU0_P3_RX_DN<3>")
	)
	(segment
		(start 364.430818 -288.989008)
		(end 364.431834 -288.9885)
		(width 0.1143)
		(layer "In4.Cu")
		(net "P5E_CPU0_P3_RX_DN<3>")
	)
	(segment
		(start 373.05234 -386.081524)
		(end 372.858538 -386.081524)
		(width 0.14224)
		(layer "In4.Cu")
		(net "P5E_CPU0_P3_RX_DN<3>")
	)
	(segment
		(start 364.431834 -294.823388)
		(end 364.430818 -294.82288)
		(width 0.1143)
		(layer "In4.Cu")
		(net "P5E_CPU0_P3_RX_DN<3>")
	)
	(segment
		(start 372.060978 -385.284218)
		(end 371.758972 -384.982212)
		(width 0.14224)
		(layer "In4.Cu")
		(net "P5E_CPU0_P3_RX_DN<3>")
	)
	(segment
		(start 364.617 -295.145206)
		(end 364.617 -295.140634)
		(width 0.1143)
		(layer "In4.Cu")
		(net "P5E_CPU0_P3_RX_DN<3>")
	)
	(segment
		(start 375.703338 -315.235336)
		(end 367.145062 -304.807112)
		(width 0.14224)
		(layer "In4.Cu")
		(net "P5E_CPU0_P3_RX_DN<3>")
	)
	(segment
		(start 364.424214 -291.578792)
		(end 364.422944 -291.57803)
		(width 0.1143)
		(layer "In4.Cu")
		(net "P5E_CPU0_P3_RX_DN<3>")
	)
	(segment
		(start 364.429294 -292.230048)
		(end 364.430818 -292.229032)
		(width 0.1143)
		(layer "In4.Cu")
		(net "P5E_CPU0_P3_RX_DN<3>")
	)
	(segment
		(start 365.012732 -287.856168)
		(end 364.71479 -287.856168)
		(width 0.1143)
		(layer "In4.Cu")
		(net "P5E_CPU0_P3_RX_DN<3>")
	)
	(segment
		(start 364.457996 -295.45026)
		(end 364.461806 -295.448228)
		(width 0.1143)
		(layer "In4.Cu")
		(net "P5E_CPU0_P3_RX_DN<3>")
	)
	(segment
		(start 364.43539 -288.986468)
		(end 364.436152 -288.98596)
		(width 0.1143)
		(layer "In4.Cu")
		(net "P5E_CPU0_P3_RX_DN<3>")
	)
	(segment
		(start 364.428278 -288.990532)
		(end 364.429294 -288.990024)
		(width 0.1143)
		(layer "In4.Cu")
		(net "P5E_CPU0_P3_RX_DN<3>")
	)
	(segment
		(start 364.436406 -294.826182)
		(end 364.435644 -294.825674)
		(width 0.1143)
		(layer "In4.Cu")
		(net "P5E_CPU0_P3_RX_DN<3>")
	)
	(segment
		(start 365.64062 -302.555148)
		(end 364.135162 -298.9199)
		(width 0.14224)
		(layer "In4.Cu")
		(net "P5E_CPU0_P3_RX_DN<3>")
	)
	(segment
		(start 364.420658 -292.235128)
		(end 364.42142 -292.23462)
		(width 0.1143)
		(layer "In4.Cu")
		(net "P5E_CPU0_P3_RX_DN<3>")
	)
	(segment
		(start 364.392718 -293.871396)
		(end 364.420658 -293.85514)
		(width 0.1143)
		(layer "In4.Cu")
		(net "P5E_CPU0_P3_RX_DN<3>")
	)
	(segment
		(start 364.429294 -293.85006)
		(end 364.430818 -293.849044)
		(width 0.1143)
		(layer "In4.Cu")
		(net "P5E_CPU0_P3_RX_DN<3>")
	)
	(segment
		(start 364.149894 -296.284142)
		(end 364.149894 -295.977818)
		(width 0.1143)
		(layer "In4.Cu")
		(net "P5E_CPU0_P3_RX_DN<3>")
	)
	(segment
		(start 373.40794 -386.437124)
		(end 373.05234 -386.081524)
		(width 0.14224)
		(layer "In4.Cu")
		(net "P5E_CPU0_P3_RX_DN<3>")
	)
	(segment
		(start 370.961412 -383.990596)
		(end 369.981734 -383.010918)
		(width 0.14224)
		(layer "In4.Cu")
		(net "P5E_CPU0_P3_RX_DN<3>")
	)
	(segment
		(start 382.91262 -337.463892)
		(end 381.696468 -330.692252)
		(width 0.14224)
		(layer "In4.Cu")
		(net "P5E_CPU0_P3_RX_DN<3>")
	)
	(segment
		(start 364.43793 -293.84498)
		(end 364.438946 -293.844472)
		(width 0.1143)
		(layer "In4.Cu")
		(net "P5E_CPU0_P3_RX_DN<3>")
	)
	(segment
		(start 372.858538 -386.081524)
		(end 372.556532 -385.779518)
		(width 0.14224)
		(layer "In4.Cu")
		(net "P5E_CPU0_P3_RX_DN<3>")
	)
	(segment
		(start 365.082582 -287.926018)
		(end 365.012732 -287.856168)
		(width 0.1143)
		(layer "In4.Cu")
		(net "P5E_CPU0_P3_RX_DN<3>")
	)
	(segment
		(start 367.145062 -304.807112)
		(end 365.64062 -302.555148)
		(width 0.14224)
		(layer "In4.Cu")
		(net "P5E_CPU0_P3_RX_DN<3>")
	)
	(segment
		(start 364.425738 -291.579808)
		(end 364.424722 -291.579046)
		(width 0.1143)
		(layer "In4.Cu")
		(net "P5E_CPU0_P3_RX_DN<3>")
	)
	(segment
		(start 364.430818 -294.82288)
		(end 364.392718 -294.800528)
		(width 0.1143)
		(layer "In4.Cu")
		(net "P5E_CPU0_P3_RX_DN<3>")
	)
	(segment
		(start 363.969046 -290.777676)
		(end 363.924342 -290.751514)
		(width 0.1143)
		(layer "In4.Cu")
		(net "P5E_CPU0_P3_RX_DN<3>")
	)
	(segment
		(start 364.432596 -291.583872)
		(end 364.431834 -291.583364)
		(width 0.1143)
		(layer "In4.Cu")
		(net "P5E_CPU0_P3_RX_DN<3>")
	)
	(segment
		(start 364.431834 -293.848536)
		(end 364.432596 -293.848028)
		(width 0.1143)
		(layer "In4.Cu")
		(net "P5E_CPU0_P3_RX_DN<3>")
	)
	(segment
		(start 364.392718 -292.251384)
		(end 364.420658 -292.235128)
		(width 0.1143)
		(layer "In4.Cu")
		(net "P5E_CPU0_P3_RX_DN<3>")
	)
	(segment
		(start 364.430818 -291.582856)
		(end 364.429294 -291.58184)
		(width 0.1143)
		(layer "In4.Cu")
		(net "P5E_CPU0_P3_RX_DN<3>")
	)
	(segment
		(start 364.436152 -288.98596)
		(end 364.437168 -288.985452)
		(width 0.1143)
		(layer "In4.Cu")
		(net "P5E_CPU0_P3_RX_DN<3>")
	)
	(segment
		(start 364.104174 -296.35831)
		(end 364.104174 -296.329862)
		(width 0.1143)
		(layer "In4.Cu")
		(net "P5E_CPU0_P3_RX_DN<3>")
	)
	(segment
		(start 364.104174 -298.763182)
		(end 364.104174 -296.35831)
		(width 0.14224)
		(layer "In4.Cu")
		(net "P5E_CPU0_P3_RX_DN<3>")
	)
	(segment
		(start 382.134618 -355.490272)
		(end 382.91262 -349.762318)
		(width 0.14224)
		(layer "In4.Cu")
		(net "P5E_CPU0_P3_RX_DN<3>")
	)
	(segment
		(start 364.43539 -293.846504)
		(end 364.436152 -293.845996)
		(width 0.1143)
		(layer "In4.Cu")
		(net "P5E_CPU0_P3_RX_DN<3>")
	)
	(segment
		(start 363.969554 -290.77793)
		(end 363.969046 -290.777676)
		(width 0.1143)
		(layer "In4.Cu")
		(net "P5E_CPU0_P3_RX_DN<3>")
	)
	(segment
		(start 364.42142 -288.994596)
		(end 364.428278 -288.990532)
		(width 0.1143)
		(layer "In4.Cu")
		(net "P5E_CPU0_P3_RX_DN<3>")
	)
	(segment
		(start 372.255034 -385.284218)
		(end 372.060978 -385.284218)
		(width 0.14224)
		(layer "In4.Cu")
		(net "P5E_CPU0_P3_RX_DN<3>")
	)
	(segment
		(start 374.656858 -392.31951)
		(end 374.95861 -392.018012)
		(width 0.14224)
		(layer "In4.Cu")
		(net "P5E_CPU0_P3_RX_DN<3>")
	)
	(segment
		(start 371.758972 -384.788156)
		(end 371.457474 -384.486658)
		(width 0.14224)
		(layer "In4.Cu")
		(net "P5E_CPU0_P3_RX_DN<3>")
	)
	(segment
		(start 364.431834 -288.9885)
		(end 364.432596 -288.987992)
		(width 0.1143)
		(layer "In4.Cu")
		(net "P5E_CPU0_P3_RX_DN<3>")
	)
	(segment
		(start 374.865392 -390.304782)
		(end 374.504204 -388.488174)
		(width 0.14224)
		(layer "In4.Cu")
		(net "P5E_CPU0_P3_RX_DN<3>")
	)
	(segment
		(start 364.901988 -288.178494)
		(end 364.9345 -288.159698)
		(width 0.1143)
		(layer "In4.Cu")
		(net "P5E_CPU0_P3_RX_DN<3>")
	)
	(segment
		(start 364.431834 -291.583364)
		(end 364.430818 -291.582856)
		(width 0.1143)
		(layer "In4.Cu")
		(net "P5E_CPU0_P3_RX_DN<3>")
	)
	(segment
		(start 364.104174 -296.329862)
		(end 364.149894 -296.284142)
		(width 0.1143)
		(layer "In4.Cu")
		(net "P5E_CPU0_P3_RX_DN<3>")
	)
	(segment
		(start 364.428278 -292.230556)
		(end 364.429294 -292.230048)
		(width 0.1143)
		(layer "In4.Cu")
		(net "P5E_CPU0_P3_RX_DN<3>")
	)
	(segment
		(start 364.43793 -288.984944)
		(end 364.438946 -288.984436)
		(width 0.1143)
		(layer "In4.Cu")
		(net "P5E_CPU0_P3_RX_DN<3>")
	)
	(segment
		(start 364.436152 -292.225984)
		(end 364.437168 -292.225476)
		(width 0.1143)
		(layer "In4.Cu")
		(net "P5E_CPU0_P3_RX_DN<3>")
	)
	(segment
		(start 364.428278 -293.850568)
		(end 364.429294 -293.85006)
		(width 0.1143)
		(layer "In4.Cu")
		(net "P5E_CPU0_P3_RX_DN<3>")
	)
	(segment
		(start 369.990624 -375.770648)
		(end 382.1176 -355.538532)
		(width 0.14224)
		(layer "In4.Cu")
		(net "P5E_CPU0_P3_RX_DN<3>")
	)
	(segment
		(start 374.95861 -392.018012)
		(end 374.95861 -391.249408)
		(width 0.14224)
		(layer "In4.Cu")
		(net "P5E_CPU0_P3_RX_DN<3>")
	)
	(segment
		(start 364.432596 -294.823896)
		(end 364.431834 -294.823388)
		(width 0.1143)
		(layer "In4.Cu")
		(net "P5E_CPU0_P3_RX_DN<3>")
	)
	(segment
		(start 364.431834 -293.203376)
		(end 364.430818 -293.202868)
		(width 0.1143)
		(layer "In4.Cu")
		(net "P5E_CPU0_P3_RX_DN<3>")
	)
	(segment
		(start 369.809522 -382.59512)
		(end 369.809522 -376.426476)
		(width 0.14224)
		(layer "In4.Cu")
		(net "P5E_CPU0_P3_RX_DN<3>")
	)
	(segment
		(start 364.463584 -293.221664)
		(end 364.433866 -293.204646)
		(width 0.1143)
		(layer "In4.Cu")
		(net "P5E_CPU0_P3_RX_DN<3>")
	)
	(segment
		(start 363.922818 -289.821366)
		(end 363.961934 -289.798506)
		(width 0.1143)
		(layer "In4.Cu")
		(net "P5E_CPU0_P3_RX_DN<3>")
	)
	(segment
		(start 364.430818 -292.229032)
		(end 364.431834 -292.228524)
		(width 0.1143)
		(layer "In4.Cu")
		(net "P5E_CPU0_P3_RX_DN<3>")
	)
	(segment
		(start 364.436406 -291.585904)
		(end 364.433866 -291.584634)
		(width 0.1143)
		(layer "In4.Cu")
		(net "P5E_CPU0_P3_RX_DN<3>")
	)
	(segment
		(start 377.484386 -318.566546)
		(end 375.703338 -315.235336)
		(width 0.14224)
		(layer "In4.Cu")
		(net "P5E_CPU0_P3_RX_DN<3>")
	)
	(segment
		(start 364.433866 -293.204646)
		(end 364.432596 -293.203884)
		(width 0.1143)
		(layer "In4.Cu")
		(net "P5E_CPU0_P3_RX_DN<3>")
	)
	(segment
		(start 364.862872 -288.201354)
		(end 364.901988 -288.178494)
		(width 0.1143)
		(layer "In4.Cu")
		(net "P5E_CPU0_P3_RX_DN<3>")
	)
	(segment
		(start 364.436152 -293.845996)
		(end 364.437168 -293.845488)
		(width 0.1143)
		(layer "In4.Cu")
		(net "P5E_CPU0_P3_RX_DN<3>")
	)
	(segment
		(start 364.43793 -291.58692)
		(end 364.436406 -291.585904)
		(width 0.1143)
		(layer "In4.Cu")
		(net "P5E_CPU0_P3_RX_DN<3>")
	)
	(segment
		(start 364.438946 -291.587428)
		(end 364.43793 -291.58692)
		(width 0.1143)
		(layer "In4.Cu")
		(net "P5E_CPU0_P3_RX_DN<3>")
	)
	(segment
		(start 364.433866 -294.824658)
		(end 364.432596 -294.823896)
		(width 0.1143)
		(layer "In4.Cu")
		(net "P5E_CPU0_P3_RX_DN<3>")
	)
	(segment
		(start 364.437168 -288.985452)
		(end 364.43793 -288.984944)
		(width 0.1143)
		(layer "In4.Cu")
		(net "P5E_CPU0_P3_RX_DN<3>")
	)
	(segment
		(start 364.438946 -288.984436)
		(end 364.463584 -288.970212)
		(width 0.1143)
		(layer "In4.Cu")
		(net "P5E_CPU0_P3_RX_DN<3>")
	)
	(segment
		(start 379.5903 -324.62978)
		(end 379.5903 -324.629272)
		(width 0.14224)
		(layer "In4.Cu")
		(net "P5E_CPU0_P3_RX_DN<3>")
	)
	(segment
		(start 364.463584 -291.601652)
		(end 364.438946 -291.587428)
		(width 0.1143)
		(layer "In4.Cu")
		(net "P5E_CPU0_P3_RX_DN<3>")
	)
	(segment
		(start 364.43793 -292.224968)
		(end 364.438946 -292.22446)
		(width 0.1143)
		(layer "In4.Cu")
		(net "P5E_CPU0_P3_RX_DN<3>")
	)
	(segment
		(start 364.42142 -292.23462)
		(end 364.428278 -292.230556)
		(width 0.1143)
		(layer "In4.Cu")
		(net "P5E_CPU0_P3_RX_DN<3>")
	)
	(segment
		(start 363.961934 -289.798506)
		(end 363.992414 -289.780726)
		(width 0.1143)
		(layer "In4.Cu")
		(net "P5E_CPU0_P3_RX_DN<3>")
	)
	(segment
		(start 364.433866 -292.227254)
		(end 364.43539 -292.226492)
		(width 0.1143)
		(layer "In4.Cu")
		(net "P5E_CPU0_P3_RX_DN<3>")
	)
	(segment
		(start 371.263418 -384.486658)
		(end 370.961412 -384.184652)
		(width 0.14224)
		(layer "In4.Cu")
		(net "P5E_CPU0_P3_RX_DN<3>")
	)
	(segment
		(start 379.5903 -324.629272)
		(end 377.484386 -318.566546)
		(width 0.14224)
		(layer "In4.Cu")
		(net "P5E_CPU0_P3_RX_DN<3>")
	)
	(segment
		(start 364.432596 -292.228016)
		(end 364.433866 -292.227254)
		(width 0.1143)
		(layer "In4.Cu")
		(net "P5E_CPU0_P3_RX_DN<3>")
	)
	(segment
		(start 364.433866 -293.847266)
		(end 364.43539 -293.846504)
		(width 0.1143)
		(layer "In4.Cu")
		(net "P5E_CPU0_P3_RX_DN<3>")
	)
	(segment
		(start 364.43539 -292.226492)
		(end 364.436152 -292.225984)
		(width 0.1143)
		(layer "In4.Cu")
		(net "P5E_CPU0_P3_RX_DN<3>")
	)
	(segment
		(start 364.429294 -291.58184)
		(end 364.428278 -291.581332)
		(width 0.1143)
		(layer "In4.Cu")
		(net "P5E_CPU0_P3_RX_DN<3>")
	)
	(segment
		(start 364.392718 -289.01136)
		(end 364.420658 -288.995104)
		(width 0.1143)
		(layer "In4.Cu")
		(net "P5E_CPU0_P3_RX_DN<3>")
	)
	(segment
		(start 364.429294 -288.990024)
		(end 364.430818 -288.989008)
		(width 0.1143)
		(layer "In4.Cu")
		(net "P5E_CPU0_P3_RX_DN<3>")
	)
	(segment
		(start 364.432596 -288.987992)
		(end 364.433866 -288.98723)
		(width 0.1143)
		(layer "In4.Cu")
		(net "P5E_CPU0_P3_RX_DN<3>")
	)
	(segment
		(start 364.432596 -293.848028)
		(end 364.433866 -293.847266)
		(width 0.1143)
		(layer "In4.Cu")
		(net "P5E_CPU0_P3_RX_DN<3>")
	)
	(segment
		(start 372.556532 -385.779518)
		(end 372.556532 -385.585716)
		(width 0.14224)
		(layer "In4.Cu")
		(net "P5E_CPU0_P3_RX_DN<3>")
	)
	(segment
		(start 374.844564 -393.787376)
		(end 374.845072 -393.786868)
		(width 0.14224)
		(layer "In4.Cu")
		(net "P5E_CPU0_P3_RX_DN<3>")
	)
	(arc
		(start 364.393226 -295.4909)
		(mid 364.425299 -295.470083)
		(end 364.457996 -295.45026)
		(width 0.1143)
		(layer "In4.Cu")
		(net "P5E_CPU0_P3_RX_DN<3>")
	)
	(arc
		(start 364.392718 -293.180516)
		(mid 364.149391 -292.71595)
		(end 364.392718 -292.251384)
		(width 0.1143)
		(layer "In4.Cu")
		(net "P5E_CPU0_P3_RX_DN<3>")
	)
	(arc
		(start 374.95861 -391.249408)
		(mid 374.935216 -390.774804)
		(end 374.865392 -390.304782)
		(width 0.14224)
		(layer "In4.Cu")
		(net "P5E_CPU0_P3_RX_DN<3>")
	)
	(arc
		(start 364.149386 -295.947592)
		(mid 364.152445 -295.9068)
		(end 364.158276 -295.866312)
		(width 0.1143)
		(layer "In4.Cu")
		(net "P5E_CPU0_P3_RX_DN<3>")
	)
	(arc
		(start 364.377986 -295.501822)
		(mid 364.38556 -295.496297)
		(end 364.393226 -295.4909)
		(width 0.1143)
		(layer "In4.Cu")
		(net "P5E_CPU0_P3_RX_DN<3>")
	)
	(arc
		(start 374.504204 -388.488174)
		(mid 374.108222 -387.381327)
		(end 373.40794 -386.437124)
		(width 0.14224)
		(layer "In4.Cu")
		(net "P5E_CPU0_P3_RX_DN<3>")
	)
	(arc
		(start 369.809522 -376.426476)
		(mid 369.855574 -376.086277)
		(end 369.990624 -375.770648)
		(width 0.14224)
		(layer "In4.Cu")
		(net "P5E_CPU0_P3_RX_DN<3>")
	)
	(arc
		(start 363.924342 -290.751514)
		(mid 363.92358 -290.751007)
		(end 363.922818 -290.750498)
		(width 0.1143)
		(layer "In4.Cu")
		(net "P5E_CPU0_P3_RX_DN<3>")
	)
	(arc
		(start 364.135162 -298.9199)
		(mid 364.111959 -298.843066)
		(end 364.104174 -298.763182)
		(width 0.14224)
		(layer "In4.Cu")
		(net "P5E_CPU0_P3_RX_DN<3>")
	)
	(arc
		(start 364.392718 -294.800528)
		(mid 364.149391 -294.335962)
		(end 364.392718 -293.871396)
		(width 0.1143)
		(layer "In4.Cu")
		(net "P5E_CPU0_P3_RX_DN<3>")
	)
	(arc
		(start 364.158276 -295.866312)
		(mid 364.234686 -295.663909)
		(end 364.377986 -295.501822)
		(width 0.1143)
		(layer "In4.Cu")
		(net "P5E_CPU0_P3_RX_DN<3>")
	)
	(arc
		(start 364.9345 -288.159698)
		(mid 365.03094 -288.057043)
		(end 365.082582 -287.926018)
		(width 0.1143)
		(layer "In4.Cu")
		(net "P5E_CPU0_P3_RX_DN<3>")
	)
	(arc
		(start 364.463584 -293.830248)
		(mid 364.619512 -293.525956)
		(end 364.463584 -293.221664)
		(width 0.1143)
		(layer "In4.Cu")
		(net "P5E_CPU0_P3_RX_DN<3>")
	)
	(arc
		(start 364.461806 -295.448228)
		(mid 364.575901 -295.315407)
		(end 364.617 -295.145206)
		(width 0.1143)
		(layer "In4.Cu")
		(net "P5E_CPU0_P3_RX_DN<3>")
	)
	(arc
		(start 364.61954 -288.66592)
		(mid 364.684055 -288.403701)
		(end 364.862872 -288.201354)
		(width 0.1143)
		(layer "In4.Cu")
		(net "P5E_CPU0_P3_RX_DN<3>")
	)
	(arc
		(start 363.992414 -289.780726)
		(mid 364.107841 -289.64735)
		(end 364.149386 -289.475926)
		(width 0.1143)
		(layer "In4.Cu")
		(net "P5E_CPU0_P3_RX_DN<3>")
	)
	(arc
		(start 364.463584 -288.970212)
		(mid 364.57826 -288.836878)
		(end 364.61954 -288.66592)
		(width 0.1143)
		(layer "In4.Cu")
		(net "P5E_CPU0_P3_RX_DN<3>")
	)
	(arc
		(start 364.617 -295.140634)
		(mid 364.576392 -294.972641)
		(end 364.463584 -294.841676)
		(width 0.1143)
		(layer "In4.Cu")
		(net "P5E_CPU0_P3_RX_DN<3>")
	)
	(arc
		(start 364.149386 -289.475926)
		(mid 364.213901 -289.213707)
		(end 364.392718 -289.01136)
		(width 0.1143)
		(layer "In4.Cu")
		(net "P5E_CPU0_P3_RX_DN<3>")
	)
	(arc
		(start 364.155228 -291.101272)
		(mid 364.105509 -290.91484)
		(end 363.969554 -290.77793)
		(width 0.1143)
		(layer "In4.Cu")
		(net "P5E_CPU0_P3_RX_DN<3>")
	)
	(arc
		(start 364.463584 -292.210236)
		(mid 364.619512 -291.905944)
		(end 364.463584 -291.601652)
		(width 0.1143)
		(layer "In4.Cu")
		(net "P5E_CPU0_P3_RX_DN<3>")
	)
	(arc
		(start 363.922818 -290.750498)
		(mid 363.679491 -290.285932)
		(end 363.922818 -289.821366)
		(width 0.1143)
		(layer "In4.Cu")
		(net "P5E_CPU0_P3_RX_DN<3>")
	)
	(arc
		(start 364.149894 -295.977818)
		(mid 364.149437 -295.962708)
		(end 364.149386 -295.947592)
		(width 0.1143)
		(layer "In4.Cu")
		(net "P5E_CPU0_P3_RX_DN<3>")
	)
	(arc
		(start 382.1176 -355.538532)
		(mid 382.128557 -355.515266)
		(end 382.134618 -355.490272)
		(width 0.14224)
		(layer "In4.Cu")
		(net "P5E_CPU0_P3_RX_DN<3>")
	)
	(arc
		(start 364.422944 -291.57803)
		(mid 364.226953 -291.381554)
		(end 364.155228 -291.113464)
		(width 0.1143)
		(layer "In4.Cu")
		(net "P5E_CPU0_P3_RX_DN<3>")
	)
	(arc
		(start 369.981734 -383.010918)
		(mid 369.854266 -382.820148)
		(end 369.809522 -382.59512)
		(width 0.14224)
		(layer "In4.Cu")
		(net "P5E_CPU0_P3_RX_DN<3>")
	)
	(segment
		(start 361.89793 -290.019994)
		(end 362.364782 -290.285932)
		(width 0.12954)
		(layer "F.Cu")
		(net "P5E_CPU0_P3_RX_DN<2>")
	)
	(segment
		(start 372.770654 -393.69238)
		(end 373.291354 -393.69238)
		(width 0.127)
		(layer "F.Cu")
		(net "P5E_CPU0_P3_RX_DN<2>")
	)
	(segment
		(start 363.497876 -295.465246)
		(end 363.52353 -295.45026)
		(width 0.1143)
		(layer "In4.Cu")
		(net "P5E_CPU0_P3_RX_DN<2>")
	)
	(segment
		(start 363.481874 -294.8178)
		(end 363.452664 -294.800528)
		(width 0.1143)
		(layer "In4.Cu")
		(net "P5E_CPU0_P3_RX_DN<2>")
	)
	(segment
		(start 368.54384 -307.992018)
		(end 366.405668 -305.386486)
		(width 0.14224)
		(layer "In4.Cu")
		(net "P5E_CPU0_P3_RX_DN<2>")
	)
	(segment
		(start 363.493304 -295.467786)
		(end 363.494066 -295.467278)
		(width 0.1143)
		(layer "In4.Cu")
		(net "P5E_CPU0_P3_RX_DN<2>")
	)
	(segment
		(start 363.490764 -291.582856)
		(end 363.48924 -291.58184)
		(width 0.1143)
		(layer "In4.Cu")
		(net "P5E_CPU0_P3_RX_DN<2>")
	)
	(segment
		(start 363.488224 -291.581332)
		(end 363.4867 -291.580316)
		(width 0.1143)
		(layer "In4.Cu")
		(net "P5E_CPU0_P3_RX_DN<2>")
	)
	(segment
		(start 363.452664 -295.491408)
		(end 363.459522 -295.487344)
		(width 0.1143)
		(layer "In4.Cu")
		(net "P5E_CPU0_P3_RX_DN<2>")
	)
	(segment
		(start 363.498638 -294.827452)
		(end 363.496352 -294.825928)
		(width 0.1143)
		(layer "In4.Cu")
		(net "P5E_CPU0_P3_RX_DN<2>")
	)
	(segment
		(start 363.452664 -293.871396)
		(end 363.52353 -293.830248)
		(width 0.1143)
		(layer "In4.Cu")
		(net "P5E_CPU0_P3_RX_DN<2>")
	)
	(segment
		(start 363.48924 -293.201852)
		(end 363.488224 -293.201344)
		(width 0.1143)
		(layer "In4.Cu")
		(net "P5E_CPU0_P3_RX_DN<2>")
	)
	(segment
		(start 363.496352 -291.585904)
		(end 363.493812 -291.584634)
		(width 0.1143)
		(layer "In4.Cu")
		(net "P5E_CPU0_P3_RX_DN<2>")
	)
	(segment
		(start 363.459522 -295.487344)
		(end 363.460284 -295.486836)
		(width 0.1143)
		(layer "In4.Cu")
		(net "P5E_CPU0_P3_RX_DN<2>")
	)
	(segment
		(start 363.163866 -296.329862)
		(end 363.209586 -296.284142)
		(width 0.1143)
		(layer "In4.Cu")
		(net "P5E_CPU0_P3_RX_DN<2>")
	)
	(segment
		(start 363.48416 -294.81907)
		(end 363.48289 -294.818308)
		(width 0.1143)
		(layer "In4.Cu")
		(net "P5E_CPU0_P3_RX_DN<2>")
	)
	(segment
		(start 366.33785 -377.737624)
		(end 366.33785 -376.696224)
		(width 0.14224)
		(layer "In4.Cu")
		(net "P5E_CPU0_P3_RX_DN<2>")
	)
	(segment
		(start 363.481874 -293.197788)
		(end 363.452664 -293.180516)
		(width 0.1143)
		(layer "In4.Cu")
		(net "P5E_CPU0_P3_RX_DN<2>")
	)
	(segment
		(start 363.163866 -298.934632)
		(end 363.163866 -296.35831)
		(width 0.14224)
		(layer "In4.Cu")
		(net "P5E_CPU0_P3_RX_DN<2>")
	)
	(segment
		(start 372.791482 -387.718046)
		(end 372.20906 -387.135624)
		(width 0.14224)
		(layer "In4.Cu")
		(net "P5E_CPU0_P3_RX_DN<2>")
	)
	(segment
		(start 370.118132 -385.238752)
		(end 370.118132 -385.044696)
		(width 0.14224)
		(layer "In4.Cu")
		(net "P5E_CPU0_P3_RX_DN<2>")
	)
	(segment
		(start 373.449596 -393.22883)
		(end 373.457216 -392.272266)
		(width 0.14224)
		(layer "In4.Cu")
		(net "P5E_CPU0_P3_RX_DN<2>")
	)
	(segment
		(start 362.662724 -290.285932)
		(end 362.364782 -290.285932)
		(width 0.1143)
		(layer "In4.Cu")
		(net "P5E_CPU0_P3_RX_DN<2>")
	)
	(segment
		(start 363.209586 -296.284142)
		(end 363.209586 -295.955974)
		(width 0.1143)
		(layer "In4.Cu")
		(net "P5E_CPU0_P3_RX_DN<2>")
	)
	(segment
		(start 381.355092 -353.804474)
		(end 381.355346 -353.804474)
		(width 0.14224)
		(layer "In4.Cu")
		(net "P5E_CPU0_P3_RX_DN<2>")
	)
	(segment
		(start 363.492542 -293.203884)
		(end 363.49178 -293.203376)
		(width 0.1143)
		(layer "In4.Cu")
		(net "P5E_CPU0_P3_RX_DN<2>")
	)
	(segment
		(start 364.81893 -303.012602)
		(end 363.194854 -299.09135)
		(width 0.14224)
		(layer "In4.Cu")
		(net "P5E_CPU0_P3_RX_DN<2>")
	)
	(segment
		(start 363.495844 -295.466262)
		(end 363.497876 -295.465246)
		(width 0.1143)
		(layer "In4.Cu")
		(net "P5E_CPU0_P3_RX_DN<2>")
	)
	(segment
		(start 363.500924 -291.588698)
		(end 363.499654 -291.587936)
		(width 0.1143)
		(layer "In4.Cu")
		(net "P5E_CPU0_P3_RX_DN<2>")
	)
	(segment
		(start 363.488224 -294.821356)
		(end 363.4867 -294.82034)
		(width 0.1143)
		(layer "In4.Cu")
		(net "P5E_CPU0_P3_RX_DN<2>")
	)
	(segment
		(start 371.411754 -386.338318)
		(end 371.217698 -386.338318)
		(width 0.14224)
		(layer "In4.Cu")
		(net "P5E_CPU0_P3_RX_DN<2>")
	)
	(segment
		(start 363.05236 -290.791138)
		(end 362.982764 -290.750498)
		(width 0.1143)
		(layer "In4.Cu")
		(net "P5E_CPU0_P3_RX_DN<2>")
	)
	(segment
		(start 363.492542 -291.583872)
		(end 363.49178 -291.583364)
		(width 0.1143)
		(layer "In4.Cu")
		(net "P5E_CPU0_P3_RX_DN<2>")
	)
	(segment
		(start 363.494066 -295.467278)
		(end 363.495082 -295.46677)
		(width 0.1143)
		(layer "In4.Cu")
		(net "P5E_CPU0_P3_RX_DN<2>")
	)
	(segment
		(start 371.217698 -386.338318)
		(end 370.915692 -386.036312)
		(width 0.14224)
		(layer "In4.Cu")
		(net "P5E_CPU0_P3_RX_DN<2>")
	)
	(segment
		(start 370.915692 -385.842256)
		(end 370.614194 -385.540758)
		(width 0.14224)
		(layer "In4.Cu")
		(net "P5E_CPU0_P3_RX_DN<2>")
	)
	(segment
		(start 363.493812 -291.584634)
		(end 363.492542 -291.583872)
		(width 0.1143)
		(layer "In4.Cu")
		(net "P5E_CPU0_P3_RX_DN<2>")
	)
	(segment
		(start 367.015014 -378.696474)
		(end 366.791494 -378.604018)
		(width 0.14224)
		(layer "In4.Cu")
		(net "P5E_CPU0_P3_RX_DN<2>")
	)
	(segment
		(start 373.291354 -393.69238)
		(end 373.644414 -393.787376)
		(width 0.14224)
		(layer "In4.Cu")
		(net "P5E_CPU0_P3_RX_DN<2>")
	)
	(segment
		(start 363.4867 -293.200328)
		(end 363.48416 -293.199058)
		(width 0.1143)
		(layer "In4.Cu")
		(net "P5E_CPU0_P3_RX_DN<2>")
	)
	(segment
		(start 363.493812 -293.204646)
		(end 363.492542 -293.203884)
		(width 0.1143)
		(layer "In4.Cu")
		(net "P5E_CPU0_P3_RX_DN<2>")
	)
	(segment
		(start 363.500924 -293.20871)
		(end 363.499654 -293.207948)
		(width 0.1143)
		(layer "In4.Cu")
		(net "P5E_CPU0_P3_RX_DN<2>")
	)
	(segment
		(start 363.48289 -294.818308)
		(end 363.481874 -294.8178)
		(width 0.1143)
		(layer "In4.Cu")
		(net "P5E_CPU0_P3_RX_DN<2>")
	)
	(segment
		(start 363.495082 -295.46677)
		(end 363.495844 -295.466262)
		(width 0.1143)
		(layer "In4.Cu")
		(net "P5E_CPU0_P3_RX_DN<2>")
	)
	(segment
		(start 378.709682 -324.936612)
		(end 378.709428 -324.936612)
		(width 0.14224)
		(layer "In4.Cu")
		(net "P5E_CPU0_P3_RX_DN<2>")
	)
	(segment
		(start 363.481874 -291.577776)
		(end 363.452664 -291.560504)
		(width 0.1143)
		(layer "In4.Cu")
		(net "P5E_CPU0_P3_RX_DN<2>")
	)
	(segment
		(start 363.484922 -295.472612)
		(end 363.493304 -295.467786)
		(width 0.1143)
		(layer "In4.Cu")
		(net "P5E_CPU0_P3_RX_DN<2>")
	)
	(segment
		(start 363.502448 -294.829484)
		(end 363.500924 -294.828722)
		(width 0.1143)
		(layer "In4.Cu")
		(net "P5E_CPU0_P3_RX_DN<2>")
	)
	(segment
		(start 366.567212 -375.94032)
		(end 381.33528 -353.856544)
		(width 0.14224)
		(layer "In4.Cu")
		(net "P5E_CPU0_P3_RX_DN<2>")
	)
	(segment
		(start 373.644414 -393.787376)
		(end 373.644922 -393.786868)
		(width 0.14224)
		(layer "In4.Cu")
		(net "P5E_CPU0_P3_RX_DN<2>")
	)
	(segment
		(start 370.672868 -310.586374)
		(end 370.673122 -310.586374)
		(width 0.14224)
		(layer "In4.Cu")
		(net "P5E_CPU0_P3_RX_DN<2>")
	)
	(segment
		(start 363.496352 -293.205916)
		(end 363.493812 -293.204646)
		(width 0.1143)
		(layer "In4.Cu")
		(net "P5E_CPU0_P3_RX_DN<2>")
	)
	(segment
		(start 363.499654 -294.82796)
		(end 363.498638 -294.827452)
		(width 0.1143)
		(layer "In4.Cu")
		(net "P5E_CPU0_P3_RX_DN<2>")
	)
	(segment
		(start 368.543586 -307.992018)
		(end 368.54384 -307.992018)
		(width 0.14224)
		(layer "In4.Cu")
		(net "P5E_CPU0_P3_RX_DN<2>")
	)
	(segment
		(start 363.49178 -291.583364)
		(end 363.490764 -291.582856)
		(width 0.1143)
		(layer "In4.Cu")
		(net "P5E_CPU0_P3_RX_DN<2>")
	)
	(segment
		(start 363.500924 -294.828722)
		(end 363.499654 -294.82796)
		(width 0.1143)
		(layer "In4.Cu")
		(net "P5E_CPU0_P3_RX_DN<2>")
	)
	(segment
		(start 370.118132 -385.044696)
		(end 368.594894 -383.521458)
		(width 0.14224)
		(layer "In4.Cu")
		(net "P5E_CPU0_P3_RX_DN<2>")
	)
	(segment
		(start 363.492542 -294.823896)
		(end 363.49178 -294.823388)
		(width 0.1143)
		(layer "In4.Cu")
		(net "P5E_CPU0_P3_RX_DN<2>")
	)
	(segment
		(start 363.48289 -291.578284)
		(end 363.481874 -291.577776)
		(width 0.1143)
		(layer "In4.Cu")
		(net "P5E_CPU0_P3_RX_DN<2>")
	)
	(segment
		(start 373.75846 -391.19429)
		(end 373.758206 -391.194544)
		(width 0.14224)
		(layer "In4.Cu")
		(net "P5E_CPU0_P3_RX_DN<2>")
	)
	(segment
		(start 380.791974 -330.931012)
		(end 378.709682 -324.936612)
		(width 0.14224)
		(layer "In4.Cu")
		(net "P5E_CPU0_P3_RX_DN<2>")
	)
	(segment
		(start 363.493812 -294.824658)
		(end 363.492542 -294.823896)
		(width 0.1143)
		(layer "In4.Cu")
		(net "P5E_CPU0_P3_RX_DN<2>")
	)
	(segment
		(start 376.627644 -318.94272)
		(end 374.940576 -315.786516)
		(width 0.14224)
		(layer "In4.Cu")
		(net "P5E_CPU0_P3_RX_DN<2>")
	)
	(segment
		(start 371.713252 -386.639816)
		(end 371.411754 -386.338318)
		(width 0.14224)
		(layer "In4.Cu")
		(net "P5E_CPU0_P3_RX_DN<2>")
	)
	(segment
		(start 373.644922 -393.786868)
		(end 373.766588 -393.716764)
		(width 0.14224)
		(layer "In4.Cu")
		(net "P5E_CPU0_P3_RX_DN<2>")
	)
	(segment
		(start 363.49178 -293.203376)
		(end 363.490764 -293.202868)
		(width 0.1143)
		(layer "In4.Cu")
		(net "P5E_CPU0_P3_RX_DN<2>")
	)
	(segment
		(start 370.614194 -385.540758)
		(end 370.420138 -385.540758)
		(width 0.14224)
		(layer "In4.Cu")
		(net "P5E_CPU0_P3_RX_DN<2>")
	)
	(segment
		(start 373.667528 -390.269984)
		(end 373.378476 -388.816342)
		(width 0.14224)
		(layer "In4.Cu")
		(net "P5E_CPU0_P3_RX_DN<2>")
	)
	(segment
		(start 363.502448 -293.209472)
		(end 363.500924 -293.20871)
		(width 0.1143)
		(layer "In4.Cu")
		(net "P5E_CPU0_P3_RX_DN<2>")
	)
	(segment
		(start 363.163866 -296.35831)
		(end 363.163866 -296.329862)
		(width 0.1143)
		(layer "In4.Cu")
		(net "P5E_CPU0_P3_RX_DN<2>")
	)
	(segment
		(start 372.20906 -387.135624)
		(end 372.015258 -387.135624)
		(width 0.14224)
		(layer "In4.Cu")
		(net "P5E_CPU0_P3_RX_DN<2>")
	)
	(segment
		(start 363.4867 -294.82034)
		(end 363.48416 -294.81907)
		(width 0.1143)
		(layer "In4.Cu")
		(net "P5E_CPU0_P3_RX_DN<2>")
	)
	(segment
		(start 366.405668 -305.386486)
		(end 364.81893 -303.012602)
		(width 0.14224)
		(layer "In4.Cu")
		(net "P5E_CPU0_P3_RX_DN<2>")
	)
	(segment
		(start 381.355346 -353.804474)
		(end 381.975868 -349.62338)
		(width 0.14224)
		(layer "In4.Cu")
		(net "P5E_CPU0_P3_RX_DN<2>")
	)
	(segment
		(start 363.498638 -293.20744)
		(end 363.496352 -293.205916)
		(width 0.1143)
		(layer "In4.Cu")
		(net "P5E_CPU0_P3_RX_DN<2>")
	)
	(segment
		(start 363.499654 -293.207948)
		(end 363.498638 -293.20744)
		(width 0.1143)
		(layer "In4.Cu")
		(net "P5E_CPU0_P3_RX_DN<2>")
	)
	(segment
		(start 363.52353 -293.221664)
		(end 363.502448 -293.209472)
		(width 0.1143)
		(layer "In4.Cu")
		(net "P5E_CPU0_P3_RX_DN<2>")
	)
	(segment
		(start 362.745528 -290.368736)
		(end 362.662724 -290.285932)
		(width 0.1143)
		(layer "In4.Cu")
		(net "P5E_CPU0_P3_RX_DN<2>")
	)
	(segment
		(start 363.460284 -295.486836)
		(end 363.484922 -295.472612)
		(width 0.1143)
		(layer "In4.Cu")
		(net "P5E_CPU0_P3_RX_DN<2>")
	)
	(segment
		(start 370.673122 -310.586374)
		(end 368.543586 -307.992018)
		(width 0.14224)
		(layer "In4.Cu")
		(net "P5E_CPU0_P3_RX_DN<2>")
	)
	(segment
		(start 363.498638 -291.587428)
		(end 363.496352 -291.585904)
		(width 0.1143)
		(layer "In4.Cu")
		(net "P5E_CPU0_P3_RX_DN<2>")
	)
	(segment
		(start 363.48416 -293.199058)
		(end 363.48289 -293.198296)
		(width 0.1143)
		(layer "In4.Cu")
		(net "P5E_CPU0_P3_RX_DN<2>")
	)
	(segment
		(start 363.52353 -291.601652)
		(end 363.502448 -291.58946)
		(width 0.1143)
		(layer "In4.Cu")
		(net "P5E_CPU0_P3_RX_DN<2>")
	)
	(segment
		(start 373.457216 -392.272266)
		(end 373.75846 -391.971276)
		(width 0.14224)
		(layer "In4.Cu")
		(net "P5E_CPU0_P3_RX_DN<2>")
	)
	(segment
		(start 381.975868 -349.62338)
		(end 381.975868 -337.53425)
		(width 0.14224)
		(layer "In4.Cu")
		(net "P5E_CPU0_P3_RX_DN<2>")
	)
	(segment
		(start 368.107722 -382.345438)
		(end 368.107722 -379.561598)
		(width 0.14224)
		(layer "In4.Cu")
		(net "P5E_CPU0_P3_RX_DN<2>")
	)
	(segment
		(start 378.709428 -324.936612)
		(end 376.627644 -318.94272)
		(width 0.14224)
		(layer "In4.Cu")
		(net "P5E_CPU0_P3_RX_DN<2>")
	)
	(segment
		(start 371.713252 -386.833618)
		(end 371.713252 -386.639816)
		(width 0.14224)
		(layer "In4.Cu")
		(net "P5E_CPU0_P3_RX_DN<2>")
	)
	(segment
		(start 367.839244 -378.96927)
		(end 367.480342 -378.820934)
		(width 0.14224)
		(layer "In4.Cu")
		(net "P5E_CPU0_P3_RX_DN<2>")
	)
	(segment
		(start 370.915692 -386.036312)
		(end 370.915692 -385.842256)
		(width 0.14224)
		(layer "In4.Cu")
		(net "P5E_CPU0_P3_RX_DN<2>")
	)
	(segment
		(start 363.502448 -291.58946)
		(end 363.500924 -291.588698)
		(width 0.1143)
		(layer "In4.Cu")
		(net "P5E_CPU0_P3_RX_DN<2>")
	)
	(segment
		(start 363.49178 -294.823388)
		(end 363.490764 -294.82288)
		(width 0.1143)
		(layer "In4.Cu")
		(net "P5E_CPU0_P3_RX_DN<2>")
	)
	(segment
		(start 363.48289 -293.198296)
		(end 363.481874 -293.197788)
		(width 0.1143)
		(layer "In4.Cu")
		(net "P5E_CPU0_P3_RX_DN<2>")
	)
	(segment
		(start 363.48416 -291.579046)
		(end 363.48289 -291.578284)
		(width 0.1143)
		(layer "In4.Cu")
		(net "P5E_CPU0_P3_RX_DN<2>")
	)
	(segment
		(start 374.940576 -315.786516)
		(end 370.672868 -310.586374)
		(width 0.14224)
		(layer "In4.Cu")
		(net "P5E_CPU0_P3_RX_DN<2>")
	)
	(segment
		(start 363.490764 -293.202868)
		(end 363.48924 -293.201852)
		(width 0.1143)
		(layer "In4.Cu")
		(net "P5E_CPU0_P3_RX_DN<2>")
	)
	(segment
		(start 363.48924 -294.821864)
		(end 363.488224 -294.821356)
		(width 0.1143)
		(layer "In4.Cu")
		(net "P5E_CPU0_P3_RX_DN<2>")
	)
	(segment
		(start 363.52353 -294.841676)
		(end 363.502448 -294.829484)
		(width 0.1143)
		(layer "In4.Cu")
		(net "P5E_CPU0_P3_RX_DN<2>")
	)
	(segment
		(start 363.4867 -291.580316)
		(end 363.48416 -291.579046)
		(width 0.1143)
		(layer "In4.Cu")
		(net "P5E_CPU0_P3_RX_DN<2>")
	)
	(segment
		(start 363.499654 -291.587936)
		(end 363.498638 -291.587428)
		(width 0.1143)
		(layer "In4.Cu")
		(net "P5E_CPU0_P3_RX_DN<2>")
	)
	(segment
		(start 373.766588 -393.716764)
		(end 373.766588 -393.545822)
		(width 0.14224)
		(layer "In4.Cu")
		(net "P5E_CPU0_P3_RX_DN<2>")
	)
	(segment
		(start 370.420138 -385.540758)
		(end 370.118132 -385.238752)
		(width 0.14224)
		(layer "In4.Cu")
		(net "P5E_CPU0_P3_RX_DN<2>")
	)
	(segment
		(start 372.015258 -387.135624)
		(end 371.713252 -386.833618)
		(width 0.14224)
		(layer "In4.Cu")
		(net "P5E_CPU0_P3_RX_DN<2>")
	)
	(segment
		(start 363.48924 -291.58184)
		(end 363.488224 -291.581332)
		(width 0.1143)
		(layer "In4.Cu")
		(net "P5E_CPU0_P3_RX_DN<2>")
	)
	(segment
		(start 381.973836 -337.511644)
		(end 380.791974 -330.931012)
		(width 0.14224)
		(layer "In4.Cu")
		(net "P5E_CPU0_P3_RX_DN<2>")
	)
	(segment
		(start 363.488224 -293.201344)
		(end 363.4867 -293.200328)
		(width 0.1143)
		(layer "In4.Cu")
		(net "P5E_CPU0_P3_RX_DN<2>")
	)
	(segment
		(start 373.75846 -391.971276)
		(end 373.75846 -391.19429)
		(width 0.14224)
		(layer "In4.Cu")
		(net "P5E_CPU0_P3_RX_DN<2>")
	)
	(segment
		(start 373.766588 -393.545822)
		(end 373.449596 -393.22883)
		(width 0.14224)
		(layer "In4.Cu")
		(net "P5E_CPU0_P3_RX_DN<2>")
	)
	(segment
		(start 363.496352 -294.825928)
		(end 363.493812 -294.824658)
		(width 0.1143)
		(layer "In4.Cu")
		(net "P5E_CPU0_P3_RX_DN<2>")
	)
	(segment
		(start 363.490764 -294.82288)
		(end 363.48924 -294.821864)
		(width 0.1143)
		(layer "In4.Cu")
		(net "P5E_CPU0_P3_RX_DN<2>")
	)
	(segment
		(start 363.452664 -292.251384)
		(end 363.52353 -292.210236)
		(width 0.1143)
		(layer "In4.Cu")
		(net "P5E_CPU0_P3_RX_DN<2>")
	)
	(arc
		(start 368.594894 -383.521458)
		(mid 368.234316 -382.98191)
		(end 368.107722 -382.345438)
		(width 0.14224)
		(layer "In4.Cu")
		(net "P5E_CPU0_P3_RX_DN<2>")
	)
	(arc
		(start 362.749338 -290.391596)
		(mid 362.747315 -290.380186)
		(end 362.745528 -290.368736)
		(width 0.1143)
		(layer "In4.Cu")
		(net "P5E_CPU0_P3_RX_DN<2>")
	)
	(arc
		(start 363.209332 -291.095938)
		(mid 363.167783 -290.924516)
		(end 363.05236 -290.791138)
		(width 0.1143)
		(layer "In4.Cu")
		(net "P5E_CPU0_P3_RX_DN<2>")
	)
	(arc
		(start 363.52353 -293.830248)
		(mid 363.679458 -293.525956)
		(end 363.52353 -293.221664)
		(width 0.1143)
		(layer "In4.Cu")
		(net "P5E_CPU0_P3_RX_DN<2>")
	)
	(arc
		(start 373.378476 -388.816342)
		(mid 373.166434 -388.223661)
		(end 372.791482 -387.718046)
		(width 0.14224)
		(layer "In4.Cu")
		(net "P5E_CPU0_P3_RX_DN<2>")
	)
	(arc
		(start 363.452664 -293.180516)
		(mid 363.209337 -292.71595)
		(end 363.452664 -292.251384)
		(width 0.1143)
		(layer "In4.Cu")
		(net "P5E_CPU0_P3_RX_DN<2>")
	)
	(arc
		(start 363.452664 -294.800528)
		(mid 363.209337 -294.335962)
		(end 363.452664 -293.871396)
		(width 0.1143)
		(layer "In4.Cu")
		(net "P5E_CPU0_P3_RX_DN<2>")
	)
	(arc
		(start 362.982764 -290.750498)
		(mid 362.830777 -290.59399)
		(end 362.749338 -290.391596)
		(width 0.1143)
		(layer "In4.Cu")
		(net "P5E_CPU0_P3_RX_DN<2>")
	)
	(arc
		(start 381.33528 -353.856544)
		(mid 381.348076 -353.831609)
		(end 381.355092 -353.804474)
		(width 0.14224)
		(layer "In4.Cu")
		(net "P5E_CPU0_P3_RX_DN<2>")
	)
	(arc
		(start 367.480342 -378.820934)
		(mid 367.401096 -378.794216)
		(end 367.319052 -378.778008)
		(width 0.14224)
		(layer "In4.Cu")
		(net "P5E_CPU0_P3_RX_DN<2>")
	)
	(arc
		(start 366.33785 -376.696224)
		(mid 366.396457 -376.301259)
		(end 366.567212 -375.94032)
		(width 0.14224)
		(layer "In4.Cu")
		(net "P5E_CPU0_P3_RX_DN<2>")
	)
	(arc
		(start 373.758206 -391.194544)
		(mid 373.735569 -390.730037)
		(end 373.667528 -390.269984)
		(width 0.14224)
		(layer "In4.Cu")
		(net "P5E_CPU0_P3_RX_DN<2>")
	)
	(arc
		(start 368.107722 -379.561598)
		(mid 368.104554 -379.493861)
		(end 368.095022 -379.426724)
		(width 0.14224)
		(layer "In4.Cu")
		(net "P5E_CPU0_P3_RX_DN<2>")
	)
	(arc
		(start 363.209586 -295.955974)
		(mid 363.237502 -295.779998)
		(end 363.318806 -295.621456)
		(width 0.1143)
		(layer "In4.Cu")
		(net "P5E_CPU0_P3_RX_DN<2>")
	)
	(arc
		(start 381.975868 -337.53425)
		(mid 381.975362 -337.522901)
		(end 381.973836 -337.511644)
		(width 0.14224)
		(layer "In4.Cu")
		(net "P5E_CPU0_P3_RX_DN<2>")
	)
	(arc
		(start 367.95583 -379.06833)
		(mid 367.905323 -379.009648)
		(end 367.839244 -378.96927)
		(width 0.14224)
		(layer "In4.Cu")
		(net "P5E_CPU0_P3_RX_DN<2>")
	)
	(arc
		(start 366.791494 -378.604018)
		(mid 366.672014 -378.535058)
		(end 366.574578 -378.437394)
		(width 0.14224)
		(layer "In4.Cu")
		(net "P5E_CPU0_P3_RX_DN<2>")
	)
	(arc
		(start 367.319052 -378.778008)
		(mid 367.164362 -378.747202)
		(end 367.015014 -378.696474)
		(width 0.14224)
		(layer "In4.Cu")
		(net "P5E_CPU0_P3_RX_DN<2>")
	)
	(arc
		(start 366.574578 -378.437394)
		(mid 366.398635 -378.106992)
		(end 366.33785 -377.737624)
		(width 0.14224)
		(layer "In4.Cu")
		(net "P5E_CPU0_P3_RX_DN<2>")
	)
	(arc
		(start 363.52353 -292.210236)
		(mid 363.679458 -291.905944)
		(end 363.52353 -291.601652)
		(width 0.1143)
		(layer "In4.Cu")
		(net "P5E_CPU0_P3_RX_DN<2>")
	)
	(arc
		(start 363.452664 -291.560504)
		(mid 363.273851 -291.358154)
		(end 363.209332 -291.095938)
		(width 0.1143)
		(layer "In4.Cu")
		(net "P5E_CPU0_P3_RX_DN<2>")
	)
	(arc
		(start 363.318806 -295.621456)
		(mid 363.380325 -295.550862)
		(end 363.452664 -295.491408)
		(width 0.1143)
		(layer "In4.Cu")
		(net "P5E_CPU0_P3_RX_DN<2>")
	)
	(arc
		(start 363.194854 -299.09135)
		(mid 363.171651 -299.014516)
		(end 363.163866 -298.934632)
		(width 0.14224)
		(layer "In4.Cu")
		(net "P5E_CPU0_P3_RX_DN<2>")
	)
	(arc
		(start 363.52353 -295.45026)
		(mid 363.679458 -295.145968)
		(end 363.52353 -294.841676)
		(width 0.1143)
		(layer "In4.Cu")
		(net "P5E_CPU0_P3_RX_DN<2>")
	)
	(arc
		(start 368.095022 -379.426724)
		(mid 368.041775 -379.241179)
		(end 367.95583 -379.06833)
		(width 0.14224)
		(layer "In4.Cu")
		(net "P5E_CPU0_P3_RX_DN<2>")
	)
	(segment
		(start 361.89793 -288.399982)
		(end 362.364782 -288.66592)
		(width 0.12954)
		(layer "F.Cu")
		(net "P5E_CPU0_P3_RX_DN<1>")
	)
	(segment
		(start 371.570504 -393.69238)
		(end 372.091204 -393.69238)
		(width 0.127)
		(layer "F.Cu")
		(net "P5E_CPU0_P3_RX_DN<1>")
	)
	(segment
		(start 364.569502 -379.3236)
		(end 364.569502 -377.74626)
		(width 0.14224)
		(layer "In4.Cu")
		(net "P5E_CPU0_P3_RX_DN<1>")
	)
	(segment
		(start 363.991906 -303.459134)
		(end 362.297726 -299.368972)
		(width 0.14224)
		(layer "In4.Cu")
		(net "P5E_CPU0_P3_RX_DN<1>")
	)
	(segment
		(start 362.55452 -295.467024)
		(end 362.55579 -295.466262)
		(width 0.1143)
		(layer "In4.Cu")
		(net "P5E_CPU0_P3_RX_DN<1>")
	)
	(segment
		(start 362.223812 -296.329862)
		(end 362.269532 -296.284142)
		(width 0.1143)
		(layer "In4.Cu")
		(net "P5E_CPU0_P3_RX_DN<1>")
	)
	(segment
		(start 362.55071 -293.202868)
		(end 362.51261 -293.180516)
		(width 0.1143)
		(layer "In4.Cu")
		(net "P5E_CPU0_P3_RX_DN<1>")
	)
	(segment
		(start 381.040386 -349.337122)
		(end 381.040386 -337.589114)
		(width 0.14224)
		(layer "In4.Cu")
		(net "P5E_CPU0_P3_RX_DN<1>")
	)
	(segment
		(start 372.445026 -393.786868)
		(end 372.566692 -393.716764)
		(width 0.14224)
		(layer "In4.Cu")
		(net "P5E_CPU0_P3_RX_DN<1>")
	)
	(segment
		(start 362.551726 -295.468548)
		(end 362.553504 -295.467532)
		(width 0.1143)
		(layer "In4.Cu")
		(net "P5E_CPU0_P3_RX_DN<1>")
	)
	(segment
		(start 362.551726 -294.823388)
		(end 362.515404 -294.802306)
		(width 0.1143)
		(layer "In4.Cu")
		(net "P5E_CPU0_P3_RX_DN<1>")
	)
	(segment
		(start 362.223812 -298.99737)
		(end 362.223812 -296.35831)
		(width 0.14224)
		(layer "In4.Cu")
		(net "P5E_CPU0_P3_RX_DN<1>")
	)
	(segment
		(start 377.830842 -325.25208)
		(end 375.77268 -319.32372)
		(width 0.14224)
		(layer "In4.Cu")
		(net "P5E_CPU0_P3_RX_DN<1>")
	)
	(segment
		(start 372.258336 -392.142726)
		(end 372.558564 -391.842752)
		(width 0.14224)
		(layer "In4.Cu")
		(net "P5E_CPU0_P3_RX_DN<1>")
	)
	(segment
		(start 370.591842 -387.48208)
		(end 370.397786 -387.48208)
		(width 0.14224)
		(layer "In4.Cu")
		(net "P5E_CPU0_P3_RX_DN<1>")
	)
	(segment
		(start 362.270294 -291.105844)
		(end 362.267754 -291.069522)
		(width 0.1143)
		(layer "In4.Cu")
		(net "P5E_CPU0_P3_RX_DN<1>")
	)
	(segment
		(start 362.043472 -289.820858)
		(end 362.08589 -289.79622)
		(width 0.1143)
		(layer "In4.Cu")
		(net "P5E_CPU0_P3_RX_DN<1>")
	)
	(segment
		(start 362.552488 -294.823896)
		(end 362.551726 -294.823388)
		(width 0.1143)
		(layer "In4.Cu")
		(net "P5E_CPU0_P3_RX_DN<1>")
	)
	(segment
		(start 362.587794 -294.844724)
		(end 362.583476 -294.841676)
		(width 0.1143)
		(layer "In4.Cu")
		(net "P5E_CPU0_P3_RX_DN<1>")
	)
	(segment
		(start 362.269532 -296.284142)
		(end 362.269532 -295.955974)
		(width 0.1143)
		(layer "In4.Cu")
		(net "P5E_CPU0_P3_RX_DN<1>")
	)
	(segment
		(start 372.566692 -393.545822)
		(end 372.2497 -393.22883)
		(width 0.14224)
		(layer "In4.Cu")
		(net "P5E_CPU0_P3_RX_DN<1>")
	)
	(segment
		(start 362.51261 -292.251384)
		(end 362.549186 -292.230048)
		(width 0.1143)
		(layer "In4.Cu")
		(net "P5E_CPU0_P3_RX_DN<1>")
	)
	(segment
		(start 362.548678 -288.990278)
		(end 362.551726 -288.9885)
		(width 0.1143)
		(layer "In4.Cu")
		(net "P5E_CPU0_P3_RX_DN<1>")
	)
	(segment
		(start 364.946946 -376.501914)
		(end 380.153164 -353.743006)
		(width 0.14224)
		(layer "In4.Cu")
		(net "P5E_CPU0_P3_RX_DN<1>")
	)
	(segment
		(start 362.265214 -289.48126)
		(end 362.265214 -289.480752)
		(width 0.1143)
		(layer "In4.Cu")
		(net "P5E_CPU0_P3_RX_DN<1>")
	)
	(segment
		(start 362.270294 -291.115496)
		(end 362.270294 -291.105844)
		(width 0.1143)
		(layer "In4.Cu")
		(net "P5E_CPU0_P3_RX_DN<1>")
	)
	(segment
		(start 362.223812 -296.35831)
		(end 362.223812 -296.329862)
		(width 0.1143)
		(layer "In4.Cu")
		(net "P5E_CPU0_P3_RX_DN<1>")
	)
	(segment
		(start 362.549186 -295.470072)
		(end 362.55071 -295.469056)
		(width 0.1143)
		(layer "In4.Cu")
		(net "P5E_CPU0_P3_RX_DN<1>")
	)
	(segment
		(start 362.551726 -293.203376)
		(end 362.55071 -293.202868)
		(width 0.1143)
		(layer "In4.Cu")
		(net "P5E_CPU0_P3_RX_DN<1>")
	)
	(segment
		(start 377.830842 -325.251826)
		(end 377.830842 -325.25208)
		(width 0.14224)
		(layer "In4.Cu")
		(net "P5E_CPU0_P3_RX_DN<1>")
	)
	(segment
		(start 369.922552 -311.150762)
		(end 369.922806 -311.150762)
		(width 0.14224)
		(layer "In4.Cu")
		(net "P5E_CPU0_P3_RX_DN<1>")
	)
	(segment
		(start 370.09578 -387.180074)
		(end 370.09578 -386.986018)
		(width 0.14224)
		(layer "In4.Cu")
		(net "P5E_CPU0_P3_RX_DN<1>")
	)
	(segment
		(start 362.549186 -292.230048)
		(end 362.55071 -292.229032)
		(width 0.1143)
		(layer "In4.Cu")
		(net "P5E_CPU0_P3_RX_DN<1>")
	)
	(segment
		(start 362.51261 -295.491408)
		(end 362.544614 -295.472866)
		(width 0.1143)
		(layer "In4.Cu")
		(net "P5E_CPU0_P3_RX_DN<1>")
	)
	(segment
		(start 362.515404 -293.869618)
		(end 362.551726 -293.848536)
		(width 0.1143)
		(layer "In4.Cu")
		(net "P5E_CPU0_P3_RX_DN<1>")
	)
	(segment
		(start 362.553758 -293.204646)
		(end 362.552488 -293.203884)
		(width 0.1143)
		(layer "In4.Cu")
		(net "P5E_CPU0_P3_RX_DN<1>")
	)
	(segment
		(start 368.802666 -385.88696)
		(end 368.50066 -385.584954)
		(width 0.14224)
		(layer "In4.Cu")
		(net "P5E_CPU0_P3_RX_DN<1>")
	)
	(segment
		(start 368.50066 -385.584954)
		(end 368.50066 -385.390898)
		(width 0.14224)
		(layer "In4.Cu")
		(net "P5E_CPU0_P3_RX_DN<1>")
	)
	(segment
		(start 362.55071 -292.229032)
		(end 362.551726 -292.228524)
		(width 0.1143)
		(layer "In4.Cu")
		(net "P5E_CPU0_P3_RX_DN<1>")
	)
	(segment
		(start 372.444518 -393.787376)
		(end 372.445026 -393.786868)
		(width 0.14224)
		(layer "In4.Cu")
		(net "P5E_CPU0_P3_RX_DN<1>")
	)
	(segment
		(start 362.54182 -288.994596)
		(end 362.548678 -288.990278)
		(width 0.1143)
		(layer "In4.Cu")
		(net "P5E_CPU0_P3_RX_DN<1>")
	)
	(segment
		(start 362.556552 -295.465754)
		(end 362.583476 -295.45026)
		(width 0.1143)
		(layer "In4.Cu")
		(net "P5E_CPU0_P3_RX_DN<1>")
	)
	(segment
		(start 362.545376 -295.472358)
		(end 362.547408 -295.471088)
		(width 0.1143)
		(layer "In4.Cu")
		(net "P5E_CPU0_P3_RX_DN<1>")
	)
	(segment
		(start 362.267754 -291.069522)
		(end 362.265722 -291.069522)
		(width 0.1143)
		(layer "In4.Cu")
		(net "P5E_CPU0_P3_RX_DN<1>")
	)
	(segment
		(start 372.2497 -393.22883)
		(end 372.258336 -392.142726)
		(width 0.14224)
		(layer "In4.Cu")
		(net "P5E_CPU0_P3_RX_DN<1>")
	)
	(segment
		(start 362.551726 -293.848536)
		(end 362.583476 -293.830248)
		(width 0.1143)
		(layer "In4.Cu")
		(net "P5E_CPU0_P3_RX_DN<1>")
	)
	(segment
		(start 362.583476 -293.221664)
		(end 362.553758 -293.204646)
		(width 0.1143)
		(layer "In4.Cu")
		(net "P5E_CPU0_P3_RX_DN<1>")
	)
	(segment
		(start 362.551726 -292.228524)
		(end 362.583476 -292.209728)
		(width 0.1143)
		(layer "In4.Cu")
		(net "P5E_CPU0_P3_RX_DN<1>")
	)
	(segment
		(start 370.09578 -386.986018)
		(end 369.794282 -386.68452)
		(width 0.14224)
		(layer "In4.Cu")
		(net "P5E_CPU0_P3_RX_DN<1>")
	)
	(segment
		(start 381.040386 -337.589114)
		(end 379.889004 -331.18044)
		(width 0.14224)
		(layer "In4.Cu")
		(net "P5E_CPU0_P3_RX_DN<1>")
	)
	(segment
		(start 362.551726 -288.9885)
		(end 362.583476 -288.970212)
		(width 0.1143)
		(layer "In4.Cu")
		(net "P5E_CPU0_P3_RX_DN<1>")
	)
	(segment
		(start 362.585762 -292.208458)
		(end 362.587794 -292.207188)
		(width 0.1143)
		(layer "In4.Cu")
		(net "P5E_CPU0_P3_RX_DN<1>")
	)
	(segment
		(start 369.922806 -311.150762)
		(end 365.662718 -305.960018)
		(width 0.14224)
		(layer "In4.Cu")
		(net "P5E_CPU0_P3_RX_DN<1>")
	)
	(segment
		(start 362.551726 -291.583364)
		(end 362.55071 -291.582856)
		(width 0.1143)
		(layer "In4.Cu")
		(net "P5E_CPU0_P3_RX_DN<1>")
	)
	(segment
		(start 362.55071 -295.469056)
		(end 362.551726 -295.468548)
		(width 0.1143)
		(layer "In4.Cu")
		(net "P5E_CPU0_P3_RX_DN<1>")
	)
	(segment
		(start 381.040386 -349.337376)
		(end 381.040132 -349.337376)
		(width 0.14224)
		(layer "In4.Cu")
		(net "P5E_CPU0_P3_RX_DN<1>")
	)
	(segment
		(start 362.583476 -291.601652)
		(end 362.551726 -291.583364)
		(width 0.1143)
		(layer "In4.Cu")
		(net "P5E_CPU0_P3_RX_DN<1>")
	)
	(segment
		(start 372.558564 -391.842752)
		(end 372.558564 -391.025126)
		(width 0.14224)
		(layer "In4.Cu")
		(net "P5E_CPU0_P3_RX_DN<1>")
	)
	(segment
		(start 369.29822 -386.188458)
		(end 368.996722 -385.88696)
		(width 0.14224)
		(layer "In4.Cu")
		(net "P5E_CPU0_P3_RX_DN<1>")
	)
	(segment
		(start 362.583476 -294.841676)
		(end 362.552488 -294.823896)
		(width 0.1143)
		(layer "In4.Cu")
		(net "P5E_CPU0_P3_RX_DN<1>")
	)
	(segment
		(start 365.662718 -305.960018)
		(end 363.991906 -303.459134)
		(width 0.14224)
		(layer "In4.Cu")
		(net "P5E_CPU0_P3_RX_DN<1>")
	)
	(segment
		(start 379.889004 -331.18044)
		(end 377.830842 -325.251826)
		(width 0.14224)
		(layer "In4.Cu")
		(net "P5E_CPU0_P3_RX_DN<1>")
	)
	(segment
		(start 368.50066 -385.390898)
		(end 366.08004 -382.970278)
		(width 0.14224)
		(layer "In4.Cu")
		(net "P5E_CPU0_P3_RX_DN<1>")
	)
	(segment
		(start 369.794282 -386.68452)
		(end 369.600226 -386.68452)
		(width 0.14224)
		(layer "In4.Cu")
		(net "P5E_CPU0_P3_RX_DN<1>")
	)
	(segment
		(start 370.397786 -387.48208)
		(end 370.09578 -387.180074)
		(width 0.14224)
		(layer "In4.Cu")
		(net "P5E_CPU0_P3_RX_DN<1>")
	)
	(segment
		(start 369.29822 -386.382514)
		(end 369.29822 -386.188458)
		(width 0.14224)
		(layer "In4.Cu")
		(net "P5E_CPU0_P3_RX_DN<1>")
	)
	(segment
		(start 362.553504 -295.467532)
		(end 362.55452 -295.467024)
		(width 0.1143)
		(layer "In4.Cu")
		(net "P5E_CPU0_P3_RX_DN<1>")
	)
	(segment
		(start 362.547408 -295.471088)
		(end 362.549186 -295.470072)
		(width 0.1143)
		(layer "In4.Cu")
		(net "P5E_CPU0_P3_RX_DN<1>")
	)
	(segment
		(start 380.172214 -353.697286)
		(end 381.040386 -349.337376)
		(width 0.14224)
		(layer "In4.Cu")
		(net "P5E_CPU0_P3_RX_DN<1>")
	)
	(segment
		(start 362.732574 -288.73577)
		(end 362.662724 -288.66592)
		(width 0.1143)
		(layer "In4.Cu")
		(net "P5E_CPU0_P3_RX_DN<1>")
	)
	(segment
		(start 381.040132 -349.337376)
		(end 381.040386 -349.337122)
		(width 0.14224)
		(layer "In4.Cu")
		(net "P5E_CPU0_P3_RX_DN<1>")
	)
	(segment
		(start 372.091204 -393.69238)
		(end 372.444518 -393.787376)
		(width 0.14224)
		(layer "In4.Cu")
		(net "P5E_CPU0_P3_RX_DN<1>")
	)
	(segment
		(start 362.662724 -288.66592)
		(end 362.364782 -288.66592)
		(width 0.1143)
		(layer "In4.Cu")
		(net "P5E_CPU0_P3_RX_DN<1>")
	)
	(segment
		(start 374.174004 -316.33033)
		(end 369.922552 -311.150762)
		(width 0.14224)
		(layer "In4.Cu")
		(net "P5E_CPU0_P3_RX_DN<1>")
	)
	(segment
		(start 371.860318 -388.750556)
		(end 370.591842 -387.48208)
		(width 0.14224)
		(layer "In4.Cu")
		(net "P5E_CPU0_P3_RX_DN<1>")
	)
	(segment
		(start 380.172214 -353.69754)
		(end 380.172214 -353.697286)
		(width 0.14224)
		(layer "In4.Cu")
		(net "P5E_CPU0_P3_RX_DN<1>")
	)
	(segment
		(start 372.566692 -393.716764)
		(end 372.566692 -393.545822)
		(width 0.14224)
		(layer "In4.Cu")
		(net "P5E_CPU0_P3_RX_DN<1>")
	)
	(segment
		(start 362.583476 -295.45026)
		(end 362.587794 -295.447212)
		(width 0.1143)
		(layer "In4.Cu")
		(net "P5E_CPU0_P3_RX_DN<1>")
	)
	(segment
		(start 362.272326 -291.12972)
		(end 362.270294 -291.115496)
		(width 0.1143)
		(layer "In4.Cu")
		(net "P5E_CPU0_P3_RX_DN<1>")
	)
	(segment
		(start 362.082334 -290.773612)
		(end 362.043472 -290.751006)
		(width 0.1143)
		(layer "In4.Cu")
		(net "P5E_CPU0_P3_RX_DN<1>")
	)
	(segment
		(start 372.50116 -390.44372)
		(end 372.344442 -389.65632)
		(width 0.14224)
		(layer "In4.Cu")
		(net "P5E_CPU0_P3_RX_DN<1>")
	)
	(segment
		(start 362.544614 -295.472866)
		(end 362.545376 -295.472358)
		(width 0.1143)
		(layer "In4.Cu")
		(net "P5E_CPU0_P3_RX_DN<1>")
	)
	(segment
		(start 368.996722 -385.88696)
		(end 368.802666 -385.88696)
		(width 0.14224)
		(layer "In4.Cu")
		(net "P5E_CPU0_P3_RX_DN<1>")
	)
	(segment
		(start 362.583476 -292.209728)
		(end 362.585762 -292.208458)
		(width 0.1143)
		(layer "In4.Cu")
		(net "P5E_CPU0_P3_RX_DN<1>")
	)
	(segment
		(start 362.549948 -291.582348)
		(end 362.515658 -291.562282)
		(width 0.1143)
		(layer "In4.Cu")
		(net "P5E_CPU0_P3_RX_DN<1>")
	)
	(segment
		(start 375.77268 -319.32372)
		(end 374.174004 -316.33033)
		(width 0.14224)
		(layer "In4.Cu")
		(net "P5E_CPU0_P3_RX_DN<1>")
	)
	(segment
		(start 362.55071 -291.582856)
		(end 362.549948 -291.582348)
		(width 0.1143)
		(layer "In4.Cu")
		(net "P5E_CPU0_P3_RX_DN<1>")
	)
	(segment
		(start 362.55579 -295.466262)
		(end 362.556552 -295.465754)
		(width 0.1143)
		(layer "In4.Cu")
		(net "P5E_CPU0_P3_RX_DN<1>")
	)
	(segment
		(start 362.587794 -291.6047)
		(end 362.583476 -291.601652)
		(width 0.1143)
		(layer "In4.Cu")
		(net "P5E_CPU0_P3_RX_DN<1>")
	)
	(segment
		(start 369.600226 -386.68452)
		(end 369.29822 -386.382514)
		(width 0.14224)
		(layer "In4.Cu")
		(net "P5E_CPU0_P3_RX_DN<1>")
	)
	(segment
		(start 362.552488 -293.203884)
		(end 362.551726 -293.203376)
		(width 0.1143)
		(layer "In4.Cu")
		(net "P5E_CPU0_P3_RX_DN<1>")
	)
	(arc
		(start 362.034836 -290.74491)
		(mid 361.799647 -290.280647)
		(end 362.043472 -289.820858)
		(width 0.1143)
		(layer "In4.Cu")
		(net "P5E_CPU0_P3_RX_DN<1>")
	)
	(arc
		(start 362.378752 -295.621456)
		(mid 362.440271 -295.550862)
		(end 362.51261 -295.491408)
		(width 0.1143)
		(layer "In4.Cu")
		(net "P5E_CPU0_P3_RX_DN<1>")
	)
	(arc
		(start 362.08589 -289.79622)
		(mid 362.217245 -289.662465)
		(end 362.265214 -289.48126)
		(width 0.1143)
		(layer "In4.Cu")
		(net "P5E_CPU0_P3_RX_DN<1>")
	)
	(arc
		(start 364.569502 -377.74626)
		(mid 364.665943 -377.096097)
		(end 364.946946 -376.501914)
		(width 0.14224)
		(layer "In4.Cu")
		(net "P5E_CPU0_P3_RX_DN<1>")
	)
	(arc
		(start 362.587794 -292.207188)
		(mid 362.742199 -291.905944)
		(end 362.587794 -291.6047)
		(width 0.1143)
		(layer "In4.Cu")
		(net "P5E_CPU0_P3_RX_DN<1>")
	)
	(arc
		(start 362.515404 -294.802306)
		(mid 362.507226 -294.796663)
		(end 362.499148 -294.790876)
		(width 0.1143)
		(layer "In4.Cu")
		(net "P5E_CPU0_P3_RX_DN<1>")
	)
	(arc
		(start 372.344442 -389.65632)
		(mid 372.169561 -389.167527)
		(end 371.860318 -388.750556)
		(width 0.14224)
		(layer "In4.Cu")
		(net "P5E_CPU0_P3_RX_DN<1>")
	)
	(arc
		(start 362.583476 -288.970212)
		(mid 362.680611 -288.867343)
		(end 362.732574 -288.73577)
		(width 0.1143)
		(layer "In4.Cu")
		(net "P5E_CPU0_P3_RX_DN<1>")
	)
	(arc
		(start 362.583476 -293.830248)
		(mid 362.739404 -293.525956)
		(end 362.583476 -293.221664)
		(width 0.1143)
		(layer "In4.Cu")
		(net "P5E_CPU0_P3_RX_DN<1>")
	)
	(arc
		(start 362.265722 -291.069522)
		(mid 362.263867 -291.049262)
		(end 362.260896 -291.029136)
		(width 0.1143)
		(layer "In4.Cu")
		(net "P5E_CPU0_P3_RX_DN<1>")
	)
	(arc
		(start 380.153164 -353.743006)
		(mid 380.164934 -353.721212)
		(end 380.172214 -353.69754)
		(width 0.14224)
		(layer "In4.Cu")
		(net "P5E_CPU0_P3_RX_DN<1>")
	)
	(arc
		(start 362.04271 -290.750498)
		(mid 362.038761 -290.747721)
		(end 362.034836 -290.74491)
		(width 0.1143)
		(layer "In4.Cu")
		(net "P5E_CPU0_P3_RX_DN<1>")
	)
	(arc
		(start 362.587794 -295.447212)
		(mid 362.742199 -295.145968)
		(end 362.587794 -294.844724)
		(width 0.1143)
		(layer "In4.Cu")
		(net "P5E_CPU0_P3_RX_DN<1>")
	)
	(arc
		(start 362.487718 -291.540692)
		(mid 362.345527 -291.353278)
		(end 362.272326 -291.12972)
		(width 0.1143)
		(layer "In4.Cu")
		(net "P5E_CPU0_P3_RX_DN<1>")
	)
	(arc
		(start 362.499148 -293.881048)
		(mid 362.507226 -293.875262)
		(end 362.515404 -293.869618)
		(width 0.1143)
		(layer "In4.Cu")
		(net "P5E_CPU0_P3_RX_DN<1>")
	)
	(arc
		(start 366.08004 -382.970278)
		(mid 364.962104 -381.297168)
		(end 364.569502 -379.3236)
		(width 0.14224)
		(layer "In4.Cu")
		(net "P5E_CPU0_P3_RX_DN<1>")
	)
	(arc
		(start 362.043472 -290.751006)
		(mid 362.043091 -290.750752)
		(end 362.04271 -290.750498)
		(width 0.1143)
		(layer "In4.Cu")
		(net "P5E_CPU0_P3_RX_DN<1>")
	)
	(arc
		(start 362.499148 -294.790876)
		(mid 362.276264 -294.335962)
		(end 362.499148 -293.881048)
		(width 0.1143)
		(layer "In4.Cu")
		(net "P5E_CPU0_P3_RX_DN<1>")
	)
	(arc
		(start 362.265214 -289.480752)
		(mid 362.339196 -289.201068)
		(end 362.54182 -288.994596)
		(width 0.1143)
		(layer "In4.Cu")
		(net "P5E_CPU0_P3_RX_DN<1>")
	)
	(arc
		(start 362.515658 -291.562282)
		(mid 362.501518 -291.551707)
		(end 362.487718 -291.540692)
		(width 0.1143)
		(layer "In4.Cu")
		(net "P5E_CPU0_P3_RX_DN<1>")
	)
	(arc
		(start 362.297726 -299.368972)
		(mid 362.242497 -299.186807)
		(end 362.223812 -298.99737)
		(width 0.14224)
		(layer "In4.Cu")
		(net "P5E_CPU0_P3_RX_DN<1>")
	)
	(arc
		(start 362.51261 -293.180516)
		(mid 362.269283 -292.71595)
		(end 362.51261 -292.251384)
		(width 0.1143)
		(layer "In4.Cu")
		(net "P5E_CPU0_P3_RX_DN<1>")
	)
	(arc
		(start 362.260896 -291.029136)
		(mid 362.199836 -290.881649)
		(end 362.082334 -290.773612)
		(width 0.1143)
		(layer "In4.Cu")
		(net "P5E_CPU0_P3_RX_DN<1>")
	)
	(arc
		(start 362.269532 -295.955974)
		(mid 362.297448 -295.779998)
		(end 362.378752 -295.621456)
		(width 0.1143)
		(layer "In4.Cu")
		(net "P5E_CPU0_P3_RX_DN<1>")
	)
	(arc
		(start 372.558564 -391.025126)
		(mid 372.544148 -390.733013)
		(end 372.50116 -390.44372)
		(width 0.14224)
		(layer "In4.Cu")
		(net "P5E_CPU0_P3_RX_DN<1>")
	)
	(segment
		(start 372.707916 -285.970218)
		(end 373.174768 -286.236156)
		(width 0.12954)
		(layer "F.Cu")
		(net "P5E_CPU0_P3_RX_DN<15>")
	)
	(segment
		(start 388.370572 -393.69238)
		(end 388.891272 -393.69238)
		(width 0.127)
		(layer "F.Cu")
		(net "P5E_CPU0_P3_RX_DN<15>")
	)
	(segment
		(start 375.243852 -290.774628)
		(end 375.245376 -290.77539)
		(width 0.1143)
		(layer "In4.Cu")
		(net "P5E_CPU0_P3_RX_DN<15>")
	)
	(segment
		(start 393.46378 -332.09865)
		(end 394.240766 -336.422746)
		(width 0.14224)
		(layer "In4.Cu")
		(net "P5E_CPU0_P3_RX_DN<15>")
	)
	(segment
		(start 394.247624 -336.498946)
		(end 394.247624 -367.740184)
		(width 0.14224)
		(layer "In4.Cu")
		(net "P5E_CPU0_P3_RX_DN<15>")
	)
	(segment
		(start 375.248678 -290.777422)
		(end 375.27357 -290.791646)
		(width 0.1143)
		(layer "In4.Cu")
		(net "P5E_CPU0_P3_RX_DN<15>")
	)
	(segment
		(start 375.711974 -291.583364)
		(end 375.742454 -291.601144)
		(width 0.1143)
		(layer "In4.Cu")
		(net "P5E_CPU0_P3_RX_DN<15>")
	)
	(segment
		(start 375.235216 -290.769548)
		(end 375.23928 -290.771834)
		(width 0.1143)
		(layer "In4.Cu")
		(net "P5E_CPU0_P3_RX_DN<15>")
	)
	(segment
		(start 395.468348 -389.465312)
		(end 395.224254 -389.709406)
		(width 0.14224)
		(layer "In4.Cu")
		(net "P5E_CPU0_P3_RX_DN<15>")
	)
	(segment
		(start 375.498106 -296.751248)
		(end 377.240038 -299.357542)
		(width 0.14224)
		(layer "In4.Cu")
		(net "P5E_CPU0_P3_RX_DN<15>")
	)
	(segment
		(start 389.245094 -393.786868)
		(end 388.891272 -393.69238)
		(width 0.14224)
		(layer "In4.Cu")
		(net "P5E_CPU0_P3_RX_DN<15>")
	)
	(segment
		(start 375.711974 -293.848536)
		(end 375.672858 -293.871396)
		(width 0.1143)
		(layer "In4.Cu")
		(net "P5E_CPU0_P3_RX_DN<15>")
	)
	(segment
		(start 396.19936 -374.173496)
		(end 396.19936 -378.935234)
		(width 0.14224)
		(layer "In4.Cu")
		(net "P5E_CPU0_P3_RX_DN<15>")
	)
	(segment
		(start 375.24182 -290.773358)
		(end 375.242582 -290.773866)
		(width 0.1143)
		(layer "In4.Cu")
		(net "P5E_CPU0_P3_RX_DN<15>")
	)
	(segment
		(start 395.477492 -388.447534)
		(end 395.614652 -388.584694)
		(width 0.14224)
		(layer "In4.Cu")
		(net "P5E_CPU0_P3_RX_DN<15>")
	)
	(segment
		(start 375.711974 -292.228524)
		(end 375.672858 -292.251384)
		(width 0.1143)
		(layer "In4.Cu")
		(net "P5E_CPU0_P3_RX_DN<15>")
	)
	(segment
		(start 375.736866 -295.454832)
		(end 375.726452 -295.46296)
		(width 0.1143)
		(layer "In4.Cu")
		(net "P5E_CPU0_P3_RX_DN<15>")
	)
	(segment
		(start 374.77192 -288.9885)
		(end 374.732804 -289.01136)
		(width 0.1143)
		(layer "In4.Cu")
		(net "P5E_CPU0_P3_RX_DN<15>")
	)
	(segment
		(start 386.328158 -310.781192)
		(end 388.095744 -313.9821)
		(width 0.14224)
		(layer "In4.Cu")
		(net "P5E_CPU0_P3_RX_DN<15>")
	)
	(segment
		(start 375.245376 -290.77539)
		(end 375.246138 -290.775898)
		(width 0.1143)
		(layer "In4.Cu")
		(net "P5E_CPU0_P3_RX_DN<15>")
	)
	(segment
		(start 375.240804 -290.77285)
		(end 375.24182 -290.773358)
		(width 0.1143)
		(layer "In4.Cu")
		(net "P5E_CPU0_P3_RX_DN<15>")
	)
	(segment
		(start 375.672858 -293.180516)
		(end 375.711974 -293.203376)
		(width 0.1143)
		(layer "In4.Cu")
		(net "P5E_CPU0_P3_RX_DN<15>")
	)
	(segment
		(start 375.742454 -293.830756)
		(end 375.711974 -293.848536)
		(width 0.1143)
		(layer "In4.Cu")
		(net "P5E_CPU0_P3_RX_DN<15>")
	)
	(segment
		(start 395.477492 -386.649722)
		(end 395.477492 -387.076442)
		(width 0.14224)
		(layer "In4.Cu")
		(net "P5E_CPU0_P3_RX_DN<15>")
	)
	(segment
		(start 375.242582 -290.773866)
		(end 375.243852 -290.774628)
		(width 0.1143)
		(layer "In4.Cu")
		(net "P5E_CPU0_P3_RX_DN<15>")
	)
	(segment
		(start 377.240038 -299.357542)
		(end 385.738878 -309.713884)
		(width 0.14224)
		(layer "In4.Cu")
		(net "P5E_CPU0_P3_RX_DN<15>")
	)
	(segment
		(start 392.680444 -327.736708)
		(end 393.464034 -332.09865)
		(width 0.14224)
		(layer "In4.Cu")
		(net "P5E_CPU0_P3_RX_DN<15>")
	)
	(segment
		(start 375.202704 -290.750498)
		(end 375.233692 -290.768532)
		(width 0.1143)
		(layer "In4.Cu")
		(net "P5E_CPU0_P3_RX_DN<15>")
	)
	(segment
		(start 395.621256 -381.841502)
		(end 395.62024 -383.07137)
		(width 0.14224)
		(layer "In4.Cu")
		(net "P5E_CPU0_P3_RX_DN<15>")
	)
	(segment
		(start 393.464034 -332.09865)
		(end 393.46378 -332.09865)
		(width 0.14224)
		(layer "In4.Cu")
		(net "P5E_CPU0_P3_RX_DN<15>")
	)
	(segment
		(start 394.247624 -367.740184)
		(end 394.248132 -367.741454)
		(width 0.14224)
		(layer "In4.Cu")
		(net "P5E_CPU0_P3_RX_DN<15>")
	)
	(segment
		(start 375.672858 -294.800528)
		(end 375.741438 -294.84066)
		(width 0.1143)
		(layer "In4.Cu")
		(net "P5E_CPU0_P3_RX_DN<15>")
	)
	(segment
		(start 373.79275 -286.700722)
		(end 373.838724 -286.727646)
		(width 0.1143)
		(layer "In4.Cu")
		(net "P5E_CPU0_P3_RX_DN<15>")
	)
	(segment
		(start 373.47271 -286.236156)
		(end 373.555514 -286.31896)
		(width 0.1143)
		(layer "In4.Cu")
		(net "P5E_CPU0_P3_RX_DN<15>")
	)
	(segment
		(start 395.62024 -383.07137)
		(end 395.62024 -383.421382)
		(width 0.14224)
		(layer "In4.Cu")
		(net "P5E_CPU0_P3_RX_DN<15>")
	)
	(segment
		(start 394.24737 -336.4992)
		(end 394.247624 -336.498946)
		(width 0.14224)
		(layer "In4.Cu")
		(net "P5E_CPU0_P3_RX_DN<15>")
	)
	(segment
		(start 375.233692 -290.768532)
		(end 375.235216 -290.769548)
		(width 0.1143)
		(layer "In4.Cu")
		(net "P5E_CPU0_P3_RX_DN<15>")
	)
	(segment
		(start 389.9662 -392.602974)
		(end 389.419592 -393.686284)
		(width 0.14224)
		(layer "In4.Cu")
		(net "P5E_CPU0_P3_RX_DN<15>")
	)
	(segment
		(start 395.477492 -383.99085)
		(end 395.614652 -384.12801)
		(width 0.14224)
		(layer "In4.Cu")
		(net "P5E_CPU0_P3_RX_DN<15>")
	)
	(segment
		(start 374.732804 -288.320734)
		(end 374.77192 -288.343594)
		(width 0.1143)
		(layer "In4.Cu")
		(net "P5E_CPU0_P3_RX_DN<15>")
	)
	(segment
		(start 395.614652 -388.584694)
		(end 395.614652 -389.112252)
		(width 0.14224)
		(layer "In4.Cu")
		(net "P5E_CPU0_P3_RX_DN<15>")
	)
	(segment
		(start 375.429526 -296.36466)
		(end 375.429526 -296.393108)
		(width 0.1143)
		(layer "In4.Cu")
		(net "P5E_CPU0_P3_RX_DN<15>")
	)
	(segment
		(start 375.429526 -296.393108)
		(end 375.429526 -296.523664)
		(width 0.14224)
		(layer "In4.Cu")
		(net "P5E_CPU0_P3_RX_DN<15>")
	)
	(segment
		(start 395.614652 -387.883654)
		(end 395.477492 -388.020814)
		(width 0.14224)
		(layer "In4.Cu")
		(net "P5E_CPU0_P3_RX_DN<15>")
	)
	(segment
		(start 374.77192 -288.343594)
		(end 374.804432 -288.36239)
		(width 0.1143)
		(layer "In4.Cu")
		(net "P5E_CPU0_P3_RX_DN<15>")
	)
	(segment
		(start 396.19936 -378.935234)
		(end 395.621256 -381.841502)
		(width 0.14224)
		(layer "In4.Cu")
		(net "P5E_CPU0_P3_RX_DN<15>")
	)
	(segment
		(start 395.477492 -383.56413)
		(end 395.477492 -383.99085)
		(width 0.14224)
		(layer "In4.Cu")
		(net "P5E_CPU0_P3_RX_DN<15>")
	)
	(segment
		(start 395.477492 -387.076442)
		(end 395.614652 -387.213602)
		(width 0.14224)
		(layer "In4.Cu")
		(net "P5E_CPU0_P3_RX_DN<15>")
	)
	(segment
		(start 390.868408 -391.687812)
		(end 389.9662 -392.602974)
		(width 0.14224)
		(layer "In4.Cu")
		(net "P5E_CPU0_P3_RX_DN<15>")
	)
	(segment
		(start 374.77192 -289.963352)
		(end 374.8024 -289.981132)
		(width 0.1143)
		(layer "In4.Cu")
		(net "P5E_CPU0_P3_RX_DN<15>")
	)
	(segment
		(start 394.248132 -367.741454)
		(end 396.19936 -374.173496)
		(width 0.14224)
		(layer "In4.Cu")
		(net "P5E_CPU0_P3_RX_DN<15>")
	)
	(segment
		(start 375.726452 -295.46296)
		(end 375.607072 -295.58234)
		(width 0.1143)
		(layer "In4.Cu")
		(net "P5E_CPU0_P3_RX_DN<15>")
	)
	(segment
		(start 375.475246 -296.31894)
		(end 375.429526 -296.36466)
		(width 0.1143)
		(layer "In4.Cu")
		(net "P5E_CPU0_P3_RX_DN<15>")
	)
	(segment
		(start 374.8024 -288.97072)
		(end 374.77192 -288.9885)
		(width 0.1143)
		(layer "In4.Cu")
		(net "P5E_CPU0_P3_RX_DN<15>")
	)
	(segment
		(start 375.711974 -293.203376)
		(end 375.742454 -293.221156)
		(width 0.1143)
		(layer "In4.Cu")
		(net "P5E_CPU0_P3_RX_DN<15>")
	)
	(segment
		(start 395.614652 -384.12801)
		(end 395.614652 -386.512562)
		(width 0.14224)
		(layer "In4.Cu")
		(net "P5E_CPU0_P3_RX_DN<15>")
	)
	(segment
		(start 389.419592 -393.686284)
		(end 389.245094 -393.786868)
		(width 0.14224)
		(layer "In4.Cu")
		(net "P5E_CPU0_P3_RX_DN<15>")
	)
	(segment
		(start 373.174768 -286.236156)
		(end 373.47271 -286.236156)
		(width 0.1143)
		(layer "In4.Cu")
		(net "P5E_CPU0_P3_RX_DN<15>")
	)
	(segment
		(start 374.301766 -287.533588)
		(end 374.333516 -287.551876)
		(width 0.1143)
		(layer "In4.Cu")
		(net "P5E_CPU0_P3_RX_DN<15>")
	)
	(segment
		(start 374.301512 -287.533588)
		(end 374.301766 -287.533588)
		(width 0.1143)
		(layer "In4.Cu")
		(net "P5E_CPU0_P3_RX_DN<15>")
	)
	(segment
		(start 395.62024 -383.421382)
		(end 395.477492 -383.56413)
		(width 0.14224)
		(layer "In4.Cu")
		(net "P5E_CPU0_P3_RX_DN<15>")
	)
	(segment
		(start 375.475246 -295.900348)
		(end 375.475246 -296.31894)
		(width 0.1143)
		(layer "In4.Cu")
		(net "P5E_CPU0_P3_RX_DN<15>")
	)
	(segment
		(start 375.246138 -290.775898)
		(end 375.248678 -290.777422)
		(width 0.1143)
		(layer "In4.Cu")
		(net "P5E_CPU0_P3_RX_DN<15>")
	)
	(segment
		(start 388.095744 -313.9821)
		(end 392.680444 -327.736708)
		(width 0.14224)
		(layer "In4.Cu")
		(net "P5E_CPU0_P3_RX_DN<15>")
	)
	(segment
		(start 374.732804 -289.940492)
		(end 374.77192 -289.963352)
		(width 0.1143)
		(layer "In4.Cu")
		(net "P5E_CPU0_P3_RX_DN<15>")
	)
	(segment
		(start 375.672858 -291.560504)
		(end 375.711974 -291.583364)
		(width 0.1143)
		(layer "In4.Cu")
		(net "P5E_CPU0_P3_RX_DN<15>")
	)
	(segment
		(start 395.477492 -388.020814)
		(end 395.477492 -388.447534)
		(width 0.14224)
		(layer "In4.Cu")
		(net "P5E_CPU0_P3_RX_DN<15>")
	)
	(segment
		(start 394.719556 -390.046464)
		(end 391.06475 -391.556748)
		(width 0.14224)
		(layer "In4.Cu")
		(net "P5E_CPU0_P3_RX_DN<15>")
	)
	(segment
		(start 395.614652 -387.213602)
		(end 395.614652 -387.883654)
		(width 0.14224)
		(layer "In4.Cu")
		(net "P5E_CPU0_P3_RX_DN<15>")
	)
	(segment
		(start 385.738878 -309.713884)
		(end 386.328158 -310.781192)
		(width 0.14224)
		(layer "In4.Cu")
		(net "P5E_CPU0_P3_RX_DN<15>")
	)
	(segment
		(start 395.614652 -386.512562)
		(end 395.477492 -386.649722)
		(width 0.14224)
		(layer "In4.Cu")
		(net "P5E_CPU0_P3_RX_DN<15>")
	)
	(segment
		(start 375.742454 -292.210744)
		(end 375.711974 -292.228524)
		(width 0.1143)
		(layer "In4.Cu")
		(net "P5E_CPU0_P3_RX_DN<15>")
	)
	(segment
		(start 375.23928 -290.771834)
		(end 375.240804 -290.77285)
		(width 0.1143)
		(layer "In4.Cu")
		(net "P5E_CPU0_P3_RX_DN<15>")
	)
	(arc
		(start 373.559324 -286.34182)
		(mid 373.640739 -286.544224)
		(end 373.79275 -286.700722)
		(width 0.1143)
		(layer "In4.Cu")
		(net "P5E_CPU0_P3_RX_DN<15>")
	)
	(arc
		(start 395.224254 -389.709406)
		(mid 394.988536 -389.90284)
		(end 394.719556 -390.046464)
		(width 0.14224)
		(layer "In4.Cu")
		(net "P5E_CPU0_P3_RX_DN<15>")
	)
	(arc
		(start 375.429526 -296.523664)
		(mid 375.446942 -296.642538)
		(end 375.498106 -296.751248)
		(width 0.14224)
		(layer "In4.Cu")
		(net "P5E_CPU0_P3_RX_DN<15>")
	)
	(arc
		(start 395.614652 -389.112252)
		(mid 395.576625 -389.303336)
		(end 395.468348 -389.465312)
		(width 0.14224)
		(layer "In4.Cu")
		(net "P5E_CPU0_P3_RX_DN<15>")
	)
	(arc
		(start 375.27357 -290.791646)
		(mid 375.388246 -290.92498)
		(end 375.429526 -291.095938)
		(width 0.1143)
		(layer "In4.Cu")
		(net "P5E_CPU0_P3_RX_DN<15>")
	)
	(arc
		(start 391.06475 -391.556748)
		(mid 390.960103 -391.61258)
		(end 390.868408 -391.687812)
		(width 0.14224)
		(layer "In4.Cu")
		(net "P5E_CPU0_P3_RX_DN<15>")
	)
	(arc
		(start 373.838724 -286.727646)
		(mid 373.973022 -286.862818)
		(end 374.022112 -287.046924)
		(width 0.1143)
		(layer "In4.Cu")
		(net "P5E_CPU0_P3_RX_DN<15>")
	)
	(arc
		(start 374.732804 -289.01136)
		(mid 374.489477 -289.475926)
		(end 374.732804 -289.940492)
		(width 0.1143)
		(layer "In4.Cu")
		(net "P5E_CPU0_P3_RX_DN<15>")
	)
	(arc
		(start 374.959372 -288.66592)
		(mid 374.917823 -288.837342)
		(end 374.8024 -288.97072)
		(width 0.1143)
		(layer "In4.Cu")
		(net "P5E_CPU0_P3_RX_DN<15>")
	)
	(arc
		(start 375.742454 -293.221156)
		(mid 375.899431 -293.525956)
		(end 375.742454 -293.830756)
		(width 0.1143)
		(layer "In4.Cu")
		(net "P5E_CPU0_P3_RX_DN<15>")
	)
	(arc
		(start 374.022112 -287.046924)
		(mid 374.096921 -287.327517)
		(end 374.301512 -287.533588)
		(width 0.1143)
		(layer "In4.Cu")
		(net "P5E_CPU0_P3_RX_DN<15>")
	)
	(arc
		(start 375.672858 -292.251384)
		(mid 375.429531 -292.71595)
		(end 375.672858 -293.180516)
		(width 0.1143)
		(layer "In4.Cu")
		(net "P5E_CPU0_P3_RX_DN<15>")
	)
	(arc
		(start 374.959372 -290.285932)
		(mid 375.023887 -290.548151)
		(end 375.202704 -290.750498)
		(width 0.1143)
		(layer "In4.Cu")
		(net "P5E_CPU0_P3_RX_DN<15>")
	)
	(arc
		(start 394.240766 -336.422746)
		(mid 394.245783 -336.460825)
		(end 394.24737 -336.4992)
		(width 0.14224)
		(layer "In4.Cu")
		(net "P5E_CPU0_P3_RX_DN<15>")
	)
	(arc
		(start 374.489472 -287.856168)
		(mid 374.553987 -288.118387)
		(end 374.732804 -288.320734)
		(width 0.1143)
		(layer "In4.Cu")
		(net "P5E_CPU0_P3_RX_DN<15>")
	)
	(arc
		(start 375.429526 -291.095938)
		(mid 375.494041 -291.358157)
		(end 375.672858 -291.560504)
		(width 0.1143)
		(layer "In4.Cu")
		(net "P5E_CPU0_P3_RX_DN<15>")
	)
	(arc
		(start 374.8024 -289.981132)
		(mid 374.917827 -290.114508)
		(end 374.959372 -290.285932)
		(width 0.1143)
		(layer "In4.Cu")
		(net "P5E_CPU0_P3_RX_DN<15>")
	)
	(arc
		(start 375.607072 -295.58234)
		(mid 375.509529 -295.728229)
		(end 375.475246 -295.900348)
		(width 0.1143)
		(layer "In4.Cu")
		(net "P5E_CPU0_P3_RX_DN<15>")
	)
	(arc
		(start 375.672858 -293.871396)
		(mid 375.429531 -294.335962)
		(end 375.672858 -294.800528)
		(width 0.1143)
		(layer "In4.Cu")
		(net "P5E_CPU0_P3_RX_DN<15>")
	)
	(arc
		(start 374.804432 -288.36239)
		(mid 374.918361 -288.495537)
		(end 374.959372 -288.66592)
		(width 0.1143)
		(layer "In4.Cu")
		(net "P5E_CPU0_P3_RX_DN<15>")
	)
	(arc
		(start 375.741438 -294.84066)
		(mid 375.890346 -295.148864)
		(end 375.736866 -295.454832)
		(width 0.1143)
		(layer "In4.Cu")
		(net "P5E_CPU0_P3_RX_DN<15>")
	)
	(arc
		(start 375.742454 -291.601144)
		(mid 375.899431 -291.905944)
		(end 375.742454 -292.210744)
		(width 0.1143)
		(layer "In4.Cu")
		(net "P5E_CPU0_P3_RX_DN<15>")
	)
	(arc
		(start 374.333516 -287.551876)
		(mid 374.448192 -287.68521)
		(end 374.489472 -287.856168)
		(width 0.1143)
		(layer "In4.Cu")
		(net "P5E_CPU0_P3_RX_DN<15>")
	)
	(arc
		(start 373.555514 -286.31896)
		(mid 373.557302 -286.330409)
		(end 373.559324 -286.34182)
		(width 0.1143)
		(layer "In4.Cu")
		(net "P5E_CPU0_P3_RX_DN<15>")
	)
	(segment
		(start 372.707916 -289.209988)
		(end 373.174768 -289.475926)
		(width 0.12954)
		(layer "F.Cu")
		(net "P5E_CPU0_P3_RX_DN<14>")
	)
	(segment
		(start 387.170676 -393.69238)
		(end 387.691376 -393.69238)
		(width 0.127)
		(layer "F.Cu")
		(net "P5E_CPU0_P3_RX_DN<14>")
	)
	(segment
		(start 373.835168 -289.96513)
		(end 373.832374 -289.963606)
		(width 0.1143)
		(layer "In4.Cu")
		(net "P5E_CPU0_P3_RX_DN<14>")
	)
	(segment
		(start 387.853428 -392.727942)
		(end 388.158482 -392.422888)
		(width 0.14224)
		(layer "In4.Cu")
		(net "P5E_CPU0_P3_RX_DN<14>")
	)
	(segment
		(start 388.044944 -393.786868)
		(end 388.16661 -393.716764)
		(width 0.14224)
		(layer "In4.Cu")
		(net "P5E_CPU0_P3_RX_DN<14>")
	)
	(segment
		(start 374.896126 -297.766232)
		(end 374.777762 -297.550332)
		(width 0.14224)
		(layer "In4.Cu")
		(net "P5E_CPU0_P3_RX_DN<14>")
	)
	(segment
		(start 393.303252 -336.990944)
		(end 391.6807 -327.95845)
		(width 0.14224)
		(layer "In4.Cu")
		(net "P5E_CPU0_P3_RX_DN<14>")
	)
	(segment
		(start 390.102852 -387.700266)
		(end 390.339834 -387.345682)
		(width 0.14224)
		(layer "In4.Cu")
		(net "P5E_CPU0_P3_RX_DN<14>")
	)
	(segment
		(start 391.410444 -385.74345)
		(end 393.755372 -382.233678)
		(width 0.14224)
		(layer "In4.Cu")
		(net "P5E_CPU0_P3_RX_DN<14>")
	)
	(segment
		(start 374.306338 -290.775898)
		(end 374.303798 -290.774628)
		(width 0.1143)
		(layer "In4.Cu")
		(net "P5E_CPU0_P3_RX_DN<14>")
	)
	(segment
		(start 374.303798 -290.774628)
		(end 374.302528 -290.773866)
		(width 0.1143)
		(layer "In4.Cu")
		(net "P5E_CPU0_P3_RX_DN<14>")
	)
	(segment
		(start 390.72947 -386.762498)
		(end 391.020808 -386.326634)
		(width 0.14224)
		(layer "In4.Cu")
		(net "P5E_CPU0_P3_RX_DN<14>")
	)
	(segment
		(start 374.77192 -291.583364)
		(end 374.732804 -291.560504)
		(width 0.1143)
		(layer "In4.Cu")
		(net "P5E_CPU0_P3_RX_DN<14>")
	)
	(segment
		(start 374.444006 -296.37228)
		(end 374.489726 -296.32656)
		(width 0.1143)
		(layer "In4.Cu")
		(net "P5E_CPU0_P3_RX_DN<14>")
	)
	(segment
		(start 388.044436 -393.787376)
		(end 388.044944 -393.786868)
		(width 0.14224)
		(layer "In4.Cu")
		(net "P5E_CPU0_P3_RX_DN<14>")
	)
	(segment
		(start 388.242302 -390.485376)
		(end 389.713216 -388.28345)
		(width 0.14224)
		(layer "In4.Cu")
		(net "P5E_CPU0_P3_RX_DN<14>")
	)
	(segment
		(start 375.810272 -299.091858)
		(end 374.896126 -297.766232)
		(width 0.14224)
		(layer "In4.Cu")
		(net "P5E_CPU0_P3_RX_DN<14>")
	)
	(segment
		(start 374.8024 -291.601144)
		(end 374.77192 -291.583364)
		(width 0.1143)
		(layer "In4.Cu")
		(net "P5E_CPU0_P3_RX_DN<14>")
	)
	(segment
		(start 389.67537 -388.093204)
		(end 389.912606 -387.738112)
		(width 0.14224)
		(layer "In4.Cu")
		(net "P5E_CPU0_P3_RX_DN<14>")
	)
	(segment
		(start 386.960364 -314.368434)
		(end 384.370834 -309.522368)
		(width 0.14224)
		(layer "In4.Cu")
		(net "P5E_CPU0_P3_RX_DN<14>")
	)
	(segment
		(start 389.320532 -321.163188)
		(end 389.320532 -321.163442)
		(width 0.14224)
		(layer "In4.Cu")
		(net "P5E_CPU0_P3_RX_DN<14>")
	)
	(segment
		(start 391.020808 -386.326634)
		(end 390.982962 -386.136388)
		(width 0.14224)
		(layer "In4.Cu")
		(net "P5E_CPU0_P3_RX_DN<14>")
	)
	(segment
		(start 374.444006 -296.590212)
		(end 374.444006 -296.400728)
		(width 0.14224)
		(layer "In4.Cu")
		(net "P5E_CPU0_P3_RX_DN<14>")
	)
	(segment
		(start 374.301766 -290.773358)
		(end 374.29186 -290.767262)
		(width 0.1143)
		(layer "In4.Cu")
		(net "P5E_CPU0_P3_RX_DN<14>")
	)
	(segment
		(start 374.77192 -292.228524)
		(end 374.8024 -292.210744)
		(width 0.1143)
		(layer "In4.Cu")
		(net "P5E_CPU0_P3_RX_DN<14>")
	)
	(segment
		(start 390.339834 -387.345682)
		(end 390.301988 -387.155436)
		(width 0.14224)
		(layer "In4.Cu")
		(net "P5E_CPU0_P3_RX_DN<14>")
	)
	(segment
		(start 388.158482 -392.422888)
		(end 388.158482 -390.76122)
		(width 0.14224)
		(layer "In4.Cu")
		(net "P5E_CPU0_P3_RX_DN<14>")
	)
	(segment
		(start 390.500362 -324.560692)
		(end 390.500616 -324.560692)
		(width 0.14224)
		(layer "In4.Cu")
		(net "P5E_CPU0_P3_RX_DN<14>")
	)
	(segment
		(start 374.307862 -290.776914)
		(end 374.306338 -290.775898)
		(width 0.1143)
		(layer "In4.Cu")
		(net "P5E_CPU0_P3_RX_DN<14>")
	)
	(segment
		(start 373.831612 -289.963098)
		(end 373.793512 -289.941)
		(width 0.1143)
		(layer "In4.Cu")
		(net "P5E_CPU0_P3_RX_DN<14>")
	)
	(segment
		(start 373.832374 -289.963606)
		(end 373.831612 -289.963098)
		(width 0.1143)
		(layer "In4.Cu")
		(net "P5E_CPU0_P3_RX_DN<14>")
	)
	(segment
		(start 373.47271 -289.475926)
		(end 373.174768 -289.475926)
		(width 0.1143)
		(layer "In4.Cu")
		(net "P5E_CPU0_P3_RX_DN<14>")
	)
	(segment
		(start 390.500616 -324.560692)
		(end 389.320532 -321.163188)
		(width 0.14224)
		(layer "In4.Cu")
		(net "P5E_CPU0_P3_RX_DN<14>")
	)
	(segment
		(start 374.77192 -293.848536)
		(end 374.8024 -293.830756)
		(width 0.1143)
		(layer "In4.Cu")
		(net "P5E_CPU0_P3_RX_DN<14>")
	)
	(segment
		(start 374.77192 -293.203376)
		(end 374.732804 -293.180516)
		(width 0.1143)
		(layer "In4.Cu")
		(net "P5E_CPU0_P3_RX_DN<14>")
	)
	(segment
		(start 374.444006 -296.400728)
		(end 374.444006 -296.37228)
		(width 0.1143)
		(layer "In4.Cu")
		(net "P5E_CPU0_P3_RX_DN<14>")
	)
	(segment
		(start 374.8024 -293.221156)
		(end 374.77192 -293.203376)
		(width 0.1143)
		(layer "In4.Cu")
		(net "P5E_CPU0_P3_RX_DN<14>")
	)
	(segment
		(start 390.982962 -386.136388)
		(end 391.220198 -385.781296)
		(width 0.14224)
		(layer "In4.Cu")
		(net "P5E_CPU0_P3_RX_DN<14>")
	)
	(segment
		(start 374.732804 -292.251384)
		(end 374.77192 -292.228524)
		(width 0.1143)
		(layer "In4.Cu")
		(net "P5E_CPU0_P3_RX_DN<14>")
	)
	(segment
		(start 389.320532 -321.163442)
		(end 386.960364 -314.368434)
		(width 0.14224)
		(layer "In4.Cu")
		(net "P5E_CPU0_P3_RX_DN<14>")
	)
	(segment
		(start 388.16661 -393.545822)
		(end 387.849618 -393.229084)
		(width 0.14224)
		(layer "In4.Cu")
		(net "P5E_CPU0_P3_RX_DN<14>")
	)
	(segment
		(start 387.849618 -393.229084)
		(end 387.853428 -392.727942)
		(width 0.14224)
		(layer "In4.Cu")
		(net "P5E_CPU0_P3_RX_DN<14>")
	)
	(segment
		(start 374.302528 -290.773866)
		(end 374.301766 -290.773358)
		(width 0.1143)
		(layer "In4.Cu")
		(net "P5E_CPU0_P3_RX_DN<14>")
	)
	(segment
		(start 374.734328 -295.490392)
		(end 374.8024 -295.450768)
		(width 0.1143)
		(layer "In4.Cu")
		(net "P5E_CPU0_P3_RX_DN<14>")
	)
	(segment
		(start 374.8024 -294.841168)
		(end 374.77192 -294.823388)
		(width 0.1143)
		(layer "In4.Cu")
		(net "P5E_CPU0_P3_RX_DN<14>")
	)
	(segment
		(start 387.691376 -393.69238)
		(end 388.044436 -393.787376)
		(width 0.14224)
		(layer "In4.Cu")
		(net "P5E_CPU0_P3_RX_DN<14>")
	)
	(segment
		(start 374.777762 -297.550332)
		(end 374.50268 -296.886376)
		(width 0.14224)
		(layer "In4.Cu")
		(net "P5E_CPU0_P3_RX_DN<14>")
	)
	(segment
		(start 389.713216 -388.28345)
		(end 389.67537 -388.093204)
		(width 0.14224)
		(layer "In4.Cu")
		(net "P5E_CPU0_P3_RX_DN<14>")
	)
	(segment
		(start 374.77192 -294.823388)
		(end 374.732804 -294.800528)
		(width 0.1143)
		(layer "In4.Cu")
		(net "P5E_CPU0_P3_RX_DN<14>")
	)
	(segment
		(start 373.555514 -289.55873)
		(end 373.47271 -289.475926)
		(width 0.1143)
		(layer "In4.Cu")
		(net "P5E_CPU0_P3_RX_DN<14>")
	)
	(segment
		(start 391.220198 -385.781296)
		(end 391.410444 -385.74345)
		(width 0.14224)
		(layer "In4.Cu")
		(net "P5E_CPU0_P3_RX_DN<14>")
	)
	(segment
		(start 390.539224 -386.800344)
		(end 390.72947 -386.762498)
		(width 0.14224)
		(layer "In4.Cu")
		(net "P5E_CPU0_P3_RX_DN<14>")
	)
	(segment
		(start 390.301988 -387.155436)
		(end 390.539224 -386.800344)
		(width 0.14224)
		(layer "In4.Cu")
		(net "P5E_CPU0_P3_RX_DN<14>")
	)
	(segment
		(start 395.01826 -378.008642)
		(end 395.01826 -374.3198)
		(width 0.14224)
		(layer "In4.Cu")
		(net "P5E_CPU0_P3_RX_DN<14>")
	)
	(segment
		(start 393.755372 -382.233678)
		(end 394.999718 -378.13361)
		(width 0.14224)
		(layer "In4.Cu")
		(net "P5E_CPU0_P3_RX_DN<14>")
	)
	(segment
		(start 374.489726 -296.32656)
		(end 374.489726 -295.955974)
		(width 0.1143)
		(layer "In4.Cu")
		(net "P5E_CPU0_P3_RX_DN<14>")
	)
	(segment
		(start 384.370834 -309.522368)
		(end 375.810272 -299.091858)
		(width 0.14224)
		(layer "In4.Cu")
		(net "P5E_CPU0_P3_RX_DN<14>")
	)
	(segment
		(start 393.303252 -368.603784)
		(end 393.303252 -336.990944)
		(width 0.14224)
		(layer "In4.Cu")
		(net "P5E_CPU0_P3_RX_DN<14>")
	)
	(segment
		(start 391.6807 -327.95845)
		(end 390.500362 -324.560692)
		(width 0.14224)
		(layer "In4.Cu")
		(net "P5E_CPU0_P3_RX_DN<14>")
	)
	(segment
		(start 388.16661 -393.716764)
		(end 388.16661 -393.545822)
		(width 0.14224)
		(layer "In4.Cu")
		(net "P5E_CPU0_P3_RX_DN<14>")
	)
	(segment
		(start 395.01826 -374.3198)
		(end 393.322048 -368.728752)
		(width 0.14224)
		(layer "In4.Cu")
		(net "P5E_CPU0_P3_RX_DN<14>")
	)
	(segment
		(start 374.333516 -290.791646)
		(end 374.307862 -290.776914)
		(width 0.1143)
		(layer "In4.Cu")
		(net "P5E_CPU0_P3_RX_DN<14>")
	)
	(segment
		(start 389.912606 -387.738112)
		(end 390.102852 -387.700266)
		(width 0.14224)
		(layer "In4.Cu")
		(net "P5E_CPU0_P3_RX_DN<14>")
	)
	(segment
		(start 374.732804 -293.871396)
		(end 374.77192 -293.848536)
		(width 0.1143)
		(layer "In4.Cu")
		(net "P5E_CPU0_P3_RX_DN<14>")
	)
	(arc
		(start 373.79275 -289.940492)
		(mid 373.640763 -289.783984)
		(end 373.559324 -289.58159)
		(width 0.1143)
		(layer "In4.Cu")
		(net "P5E_CPU0_P3_RX_DN<14>")
	)
	(arc
		(start 373.559324 -289.58159)
		(mid 373.557301 -289.57018)
		(end 373.555514 -289.55873)
		(width 0.1143)
		(layer "In4.Cu")
		(net "P5E_CPU0_P3_RX_DN<14>")
	)
	(arc
		(start 374.489726 -295.955974)
		(mid 374.554544 -295.692985)
		(end 374.734328 -295.490392)
		(width 0.1143)
		(layer "In4.Cu")
		(net "P5E_CPU0_P3_RX_DN<14>")
	)
	(arc
		(start 374.732804 -293.180516)
		(mid 374.489477 -292.71595)
		(end 374.732804 -292.251384)
		(width 0.1143)
		(layer "In4.Cu")
		(net "P5E_CPU0_P3_RX_DN<14>")
	)
	(arc
		(start 374.29186 -290.767262)
		(mid 374.091802 -290.561473)
		(end 374.01881 -290.2839)
		(width 0.1143)
		(layer "In4.Cu")
		(net "P5E_CPU0_P3_RX_DN<14>")
	)
	(arc
		(start 374.732804 -291.560504)
		(mid 374.553991 -291.358154)
		(end 374.489472 -291.095938)
		(width 0.1143)
		(layer "In4.Cu")
		(net "P5E_CPU0_P3_RX_DN<14>")
	)
	(arc
		(start 374.732804 -294.800528)
		(mid 374.489477 -294.335962)
		(end 374.732804 -293.871396)
		(width 0.1143)
		(layer "In4.Cu")
		(net "P5E_CPU0_P3_RX_DN<14>")
	)
	(arc
		(start 394.999718 -378.13361)
		(mid 395.013619 -378.071812)
		(end 395.01826 -378.008642)
		(width 0.14224)
		(layer "In4.Cu")
		(net "P5E_CPU0_P3_RX_DN<14>")
	)
	(arc
		(start 374.8024 -292.210744)
		(mid 374.959377 -291.905944)
		(end 374.8024 -291.601144)
		(width 0.1143)
		(layer "In4.Cu")
		(net "P5E_CPU0_P3_RX_DN<14>")
	)
	(arc
		(start 388.158482 -390.76122)
		(mid 388.179929 -390.617077)
		(end 388.242302 -390.485376)
		(width 0.14224)
		(layer "In4.Cu")
		(net "P5E_CPU0_P3_RX_DN<14>")
	)
	(arc
		(start 373.793512 -289.941)
		(mid 373.793131 -289.940746)
		(end 373.79275 -289.940492)
		(width 0.1143)
		(layer "In4.Cu")
		(net "P5E_CPU0_P3_RX_DN<14>")
	)
	(arc
		(start 374.01881 -290.2839)
		(mid 373.969621 -290.099949)
		(end 373.835168 -289.96513)
		(width 0.1143)
		(layer "In4.Cu")
		(net "P5E_CPU0_P3_RX_DN<14>")
	)
	(arc
		(start 374.50268 -296.886376)
		(mid 374.45875 -296.741184)
		(end 374.444006 -296.590212)
		(width 0.14224)
		(layer "In4.Cu")
		(net "P5E_CPU0_P3_RX_DN<14>")
	)
	(arc
		(start 374.489472 -291.095938)
		(mid 374.448217 -290.924967)
		(end 374.333516 -290.791646)
		(width 0.1143)
		(layer "In4.Cu")
		(net "P5E_CPU0_P3_RX_DN<14>")
	)
	(arc
		(start 374.8024 -293.830756)
		(mid 374.959377 -293.525956)
		(end 374.8024 -293.221156)
		(width 0.1143)
		(layer "In4.Cu")
		(net "P5E_CPU0_P3_RX_DN<14>")
	)
	(arc
		(start 374.8024 -295.450768)
		(mid 374.959377 -295.145968)
		(end 374.8024 -294.841168)
		(width 0.1143)
		(layer "In4.Cu")
		(net "P5E_CPU0_P3_RX_DN<14>")
	)
	(arc
		(start 393.303252 -368.60607)
		(mid 393.303251 -368.604927)
		(end 393.303252 -368.603784)
		(width 0.14224)
		(layer "In4.Cu")
		(net "P5E_CPU0_P3_RX_DN<14>")
	)
	(arc
		(start 393.322048 -368.728752)
		(mid 393.3082 -368.668093)
		(end 393.303252 -368.60607)
		(width 0.14224)
		(layer "In4.Cu")
		(net "P5E_CPU0_P3_RX_DN<14>")
	)
	(segment
		(start 372.707916 -290.83)
		(end 373.174768 -291.095938)
		(width 0.12954)
		(layer "F.Cu")
		(net "P5E_CPU0_P3_RX_DN<13>")
	)
	(segment
		(start 385.970526 -393.69238)
		(end 386.491226 -393.69238)
		(width 0.127)
		(layer "F.Cu")
		(net "P5E_CPU0_P3_RX_DN<13>")
	)
	(segment
		(start 393.744958 -377.199652)
		(end 393.744958 -375.822464)
		(width 0.14224)
		(layer "In4.Cu")
		(net "P5E_CPU0_P3_RX_DN<13>")
	)
	(segment
		(start 388.651496 -387.321044)
		(end 388.596632 -387.135116)
		(width 0.14224)
		(layer "In4.Cu")
		(net "P5E_CPU0_P3_RX_DN<13>")
	)
	(segment
		(start 373.815864 -294.814244)
		(end 373.79275 -294.800528)
		(width 0.1143)
		(layer "In4.Cu")
		(net "P5E_CPU0_P3_RX_DN<13>")
	)
	(segment
		(start 386.958586 -392.385296)
		(end 386.958586 -391.05459)
		(width 0.14224)
		(layer "In4.Cu")
		(net "P5E_CPU0_P3_RX_DN<13>")
	)
	(segment
		(start 373.832374 -294.823642)
		(end 373.815864 -294.814244)
		(width 0.1143)
		(layer "In4.Cu")
		(net "P5E_CPU0_P3_RX_DN<13>")
	)
	(segment
		(start 388.37997 -321.439032)
		(end 387.18871 -318.00927)
		(width 0.14224)
		(layer "In4.Cu")
		(net "P5E_CPU0_P3_RX_DN<13>")
	)
	(segment
		(start 387.188964 -318.008762)
		(end 385.997958 -314.580778)
		(width 0.14224)
		(layer "In4.Cu")
		(net "P5E_CPU0_P3_RX_DN<13>")
	)
	(segment
		(start 373.939562 -297.973242)
		(end 373.573802 -297.090084)
		(width 0.14224)
		(layer "In4.Cu")
		(net "P5E_CPU0_P3_RX_DN<13>")
	)
	(segment
		(start 373.79275 -292.251384)
		(end 373.832374 -292.22827)
		(width 0.1143)
		(layer "In4.Cu")
		(net "P5E_CPU0_P3_RX_DN<13>")
	)
	(segment
		(start 390.762744 -328.298048)
		(end 389.571484 -324.868286)
		(width 0.14224)
		(layer "In4.Cu")
		(net "P5E_CPU0_P3_RX_DN<13>")
	)
	(segment
		(start 386.845048 -393.786868)
		(end 386.966714 -393.716764)
		(width 0.14224)
		(layer "In4.Cu")
		(net "P5E_CPU0_P3_RX_DN<13>")
	)
	(segment
		(start 373.844058 -293.210234)
		(end 373.832628 -293.20363)
		(width 0.1143)
		(layer "In4.Cu")
		(net "P5E_CPU0_P3_RX_DN<13>")
	)
	(segment
		(start 383.54508 -309.99176)
		(end 374.867678 -299.417232)
		(width 0.14224)
		(layer "In4.Cu")
		(net "P5E_CPU0_P3_RX_DN<13>")
	)
	(segment
		(start 386.966714 -393.545822)
		(end 386.649722 -393.22883)
		(width 0.14224)
		(layer "In4.Cu")
		(net "P5E_CPU0_P3_RX_DN<13>")
	)
	(segment
		(start 388.596632 -387.135116)
		(end 388.800594 -386.759958)
		(width 0.14224)
		(layer "In4.Cu")
		(net "P5E_CPU0_P3_RX_DN<13>")
	)
	(segment
		(start 373.83085 -293.202868)
		(end 373.79275 -293.180516)
		(width 0.1143)
		(layer "In4.Cu")
		(net "P5E_CPU0_P3_RX_DN<13>")
	)
	(segment
		(start 373.79275 -293.871396)
		(end 373.829326 -293.85006)
		(width 0.1143)
		(layer "In4.Cu")
		(net "P5E_CPU0_P3_RX_DN<13>")
	)
	(segment
		(start 392.322812 -336.982054)
		(end 391.542524 -332.639924)
		(width 0.14224)
		(layer "In4.Cu")
		(net "P5E_CPU0_P3_RX_DN<13>")
	)
	(segment
		(start 386.65404 -392.689842)
		(end 386.958586 -392.385296)
		(width 0.14224)
		(layer "In4.Cu")
		(net "P5E_CPU0_P3_RX_DN<13>")
	)
	(segment
		(start 373.503952 -296.350944)
		(end 373.503952 -296.322496)
		(width 0.1143)
		(layer "In4.Cu")
		(net "P5E_CPU0_P3_RX_DN<13>")
	)
	(segment
		(start 391.542524 -332.639924)
		(end 391.542778 -332.639924)
		(width 0.14224)
		(layer "In4.Cu")
		(net "P5E_CPU0_P3_RX_DN<13>")
	)
	(segment
		(start 387.18871 -318.00927)
		(end 387.188964 -318.008762)
		(width 0.14224)
		(layer "In4.Cu")
		(net "P5E_CPU0_P3_RX_DN<13>")
	)
	(segment
		(start 389.339582 -385.769358)
		(end 389.526018 -385.714494)
		(width 0.14224)
		(layer "In4.Cu")
		(net "P5E_CPU0_P3_RX_DN<13>")
	)
	(segment
		(start 388.800594 -386.759958)
		(end 388.986776 -386.705094)
		(width 0.14224)
		(layer "In4.Cu")
		(net "P5E_CPU0_P3_RX_DN<13>")
	)
	(segment
		(start 392.322812 -368.518186)
		(end 392.322812 -336.982054)
		(width 0.14224)
		(layer "In4.Cu")
		(net "P5E_CPU0_P3_RX_DN<13>")
	)
	(segment
		(start 386.649722 -393.22883)
		(end 386.65404 -392.689842)
		(width 0.14224)
		(layer "In4.Cu")
		(net "P5E_CPU0_P3_RX_DN<13>")
	)
	(segment
		(start 373.832628 -293.20363)
		(end 373.831866 -293.203376)
		(width 0.1143)
		(layer "In4.Cu")
		(net "P5E_CPU0_P3_RX_DN<13>")
	)
	(segment
		(start 389.571484 -324.86854)
		(end 388.380224 -321.439032)
		(width 0.14224)
		(layer "In4.Cu")
		(net "P5E_CPU0_P3_RX_DN<13>")
	)
	(segment
		(start 373.829326 -293.85006)
		(end 373.83085 -293.849044)
		(width 0.1143)
		(layer "In4.Cu")
		(net "P5E_CPU0_P3_RX_DN<13>")
	)
	(segment
		(start 373.47271 -291.095938)
		(end 373.174768 -291.095938)
		(width 0.1143)
		(layer "In4.Cu")
		(net "P5E_CPU0_P3_RX_DN<13>")
	)
	(segment
		(start 373.831866 -293.848536)
		(end 373.843296 -293.841932)
		(width 0.1143)
		(layer "In4.Cu")
		(net "P5E_CPU0_P3_RX_DN<13>")
	)
	(segment
		(start 373.503952 -296.322496)
		(end 373.549672 -296.276776)
		(width 0.1143)
		(layer "In4.Cu")
		(net "P5E_CPU0_P3_RX_DN<13>")
	)
	(segment
		(start 373.793512 -295.4909)
		(end 373.832374 -295.468548)
		(width 0.1143)
		(layer "In4.Cu")
		(net "P5E_CPU0_P3_RX_DN<13>")
	)
	(segment
		(start 374.867678 -299.417232)
		(end 374.086882 -298.248324)
		(width 0.14224)
		(layer "In4.Cu")
		(net "P5E_CPU0_P3_RX_DN<13>")
	)
	(segment
		(start 385.997958 -314.580778)
		(end 383.54508 -309.99176)
		(width 0.14224)
		(layer "In4.Cu")
		(net "P5E_CPU0_P3_RX_DN<13>")
	)
	(segment
		(start 389.526018 -385.714494)
		(end 389.729726 -385.339844)
		(width 0.14224)
		(layer "In4.Cu")
		(net "P5E_CPU0_P3_RX_DN<13>")
	)
	(segment
		(start 373.555514 -291.178742)
		(end 373.47271 -291.095938)
		(width 0.1143)
		(layer "In4.Cu")
		(net "P5E_CPU0_P3_RX_DN<13>")
	)
	(segment
		(start 389.674862 -385.153662)
		(end 389.878824 -384.778758)
		(width 0.14224)
		(layer "In4.Cu")
		(net "P5E_CPU0_P3_RX_DN<13>")
	)
	(segment
		(start 373.832374 -291.583364)
		(end 373.793512 -291.561012)
		(width 0.1143)
		(layer "In4.Cu")
		(net "P5E_CPU0_P3_RX_DN<13>")
	)
	(segment
		(start 373.83085 -293.849044)
		(end 373.831866 -293.848536)
		(width 0.1143)
		(layer "In4.Cu")
		(net "P5E_CPU0_P3_RX_DN<13>")
	)
	(segment
		(start 373.549672 -296.276776)
		(end 373.549672 -295.955974)
		(width 0.1143)
		(layer "In4.Cu")
		(net "P5E_CPU0_P3_RX_DN<13>")
	)
	(segment
		(start 389.571484 -324.868286)
		(end 389.571484 -324.86854)
		(width 0.14224)
		(layer "In4.Cu")
		(net "P5E_CPU0_P3_RX_DN<13>")
	)
	(segment
		(start 391.542778 -332.639924)
		(end 390.762744 -328.298048)
		(width 0.14224)
		(layer "In4.Cu")
		(net "P5E_CPU0_P3_RX_DN<13>")
	)
	(segment
		(start 386.84454 -393.787376)
		(end 386.845048 -393.786868)
		(width 0.14224)
		(layer "In4.Cu")
		(net "P5E_CPU0_P3_RX_DN<13>")
	)
	(segment
		(start 393.73302 -375.69902)
		(end 393.036298 -372.19763)
		(width 0.14224)
		(layer "In4.Cu")
		(net "P5E_CPU0_P3_RX_DN<13>")
	)
	(segment
		(start 373.555768 -291.178742)
		(end 373.555514 -291.178742)
		(width 0.1143)
		(layer "In4.Cu")
		(net "P5E_CPU0_P3_RX_DN<13>")
	)
	(segment
		(start 393.28471 -378.80671)
		(end 393.289028 -378.800106)
		(width 0.14224)
		(layer "In4.Cu")
		(net "P5E_CPU0_P3_RX_DN<13>")
	)
	(segment
		(start 373.503952 -296.738802)
		(end 373.503952 -296.350944)
		(width 0.14224)
		(layer "In4.Cu")
		(net "P5E_CPU0_P3_RX_DN<13>")
	)
	(segment
		(start 390.06526 -384.72364)
		(end 390.06526 -384.723132)
		(width 0.14224)
		(layer "In4.Cu")
		(net "P5E_CPU0_P3_RX_DN<13>")
	)
	(segment
		(start 389.13562 -386.144262)
		(end 389.339582 -385.769358)
		(width 0.14224)
		(layer "In4.Cu")
		(net "P5E_CPU0_P3_RX_DN<13>")
	)
	(segment
		(start 373.831866 -293.203376)
		(end 373.83085 -293.202868)
		(width 0.1143)
		(layer "In4.Cu")
		(net "P5E_CPU0_P3_RX_DN<13>")
	)
	(segment
		(start 390.06526 -384.723132)
		(end 393.28471 -378.80671)
		(width 0.14224)
		(layer "In4.Cu")
		(net "P5E_CPU0_P3_RX_DN<13>")
	)
	(segment
		(start 388.986776 -386.705094)
		(end 389.190484 -386.330444)
		(width 0.14224)
		(layer "In4.Cu")
		(net "P5E_CPU0_P3_RX_DN<13>")
	)
	(segment
		(start 386.491226 -393.69238)
		(end 386.84454 -393.787376)
		(width 0.14224)
		(layer "In4.Cu")
		(net "P5E_CPU0_P3_RX_DN<13>")
	)
	(segment
		(start 389.190484 -386.330444)
		(end 389.13562 -386.144262)
		(width 0.14224)
		(layer "In4.Cu")
		(net "P5E_CPU0_P3_RX_DN<13>")
	)
	(segment
		(start 389.729726 -385.339844)
		(end 389.674862 -385.153662)
		(width 0.14224)
		(layer "In4.Cu")
		(net "P5E_CPU0_P3_RX_DN<13>")
	)
	(segment
		(start 393.036298 -372.19763)
		(end 393.036552 -372.19763)
		(width 0.14224)
		(layer "In4.Cu")
		(net "P5E_CPU0_P3_RX_DN<13>")
	)
	(segment
		(start 386.966714 -393.716764)
		(end 386.966714 -393.545822)
		(width 0.14224)
		(layer "In4.Cu")
		(net "P5E_CPU0_P3_RX_DN<13>")
	)
	(segment
		(start 389.878824 -384.778758)
		(end 390.06526 -384.72364)
		(width 0.14224)
		(layer "In4.Cu")
		(net "P5E_CPU0_P3_RX_DN<13>")
	)
	(segment
		(start 393.036552 -372.19763)
		(end 392.340592 -368.69878)
		(width 0.14224)
		(layer "In4.Cu")
		(net "P5E_CPU0_P3_RX_DN<13>")
	)
	(segment
		(start 388.380224 -321.439032)
		(end 388.37997 -321.439032)
		(width 0.14224)
		(layer "In4.Cu")
		(net "P5E_CPU0_P3_RX_DN<13>")
	)
	(segment
		(start 387.311138 -389.784336)
		(end 388.651496 -387.321044)
		(width 0.14224)
		(layer "In4.Cu")
		(net "P5E_CPU0_P3_RX_DN<13>")
	)
	(arc
		(start 373.832374 -295.468548)
		(mid 374.017792 -295.146158)
		(end 373.832374 -294.823642)
		(width 0.1143)
		(layer "In4.Cu")
		(net "P5E_CPU0_P3_RX_DN<13>")
	)
	(arc
		(start 386.958586 -391.05459)
		(mid 386.961762 -390.971655)
		(end 386.97154 -390.889236)
		(width 0.14224)
		(layer "In4.Cu")
		(net "P5E_CPU0_P3_RX_DN<13>")
	)
	(arc
		(start 393.744958 -375.822464)
		(mid 393.74197 -375.760453)
		(end 393.73302 -375.69902)
		(width 0.14224)
		(layer "In4.Cu")
		(net "P5E_CPU0_P3_RX_DN<13>")
	)
	(arc
		(start 373.79275 -294.800528)
		(mid 373.549423 -294.335962)
		(end 373.79275 -293.871396)
		(width 0.1143)
		(layer "In4.Cu")
		(net "P5E_CPU0_P3_RX_DN<13>")
	)
	(arc
		(start 392.340592 -368.69878)
		(mid 392.327276 -368.608919)
		(end 392.322812 -368.518186)
		(width 0.14224)
		(layer "In4.Cu")
		(net "P5E_CPU0_P3_RX_DN<13>")
	)
	(arc
		(start 386.97154 -390.889236)
		(mid 386.99877 -390.733129)
		(end 387.027674 -390.577324)
		(width 0.14224)
		(layer "In4.Cu")
		(net "P5E_CPU0_P3_RX_DN<13>")
	)
	(arc
		(start 373.573802 -297.090084)
		(mid 373.521582 -296.917882)
		(end 373.503952 -296.738802)
		(width 0.14224)
		(layer "In4.Cu")
		(net "P5E_CPU0_P3_RX_DN<13>")
	)
	(arc
		(start 373.832374 -292.22827)
		(mid 374.017792 -291.90588)
		(end 373.832374 -291.583364)
		(width 0.1143)
		(layer "In4.Cu")
		(net "P5E_CPU0_P3_RX_DN<13>")
	)
	(arc
		(start 373.793512 -291.561012)
		(mid 373.634956 -291.394564)
		(end 373.555768 -291.178742)
		(width 0.1143)
		(layer "In4.Cu")
		(net "P5E_CPU0_P3_RX_DN<13>")
	)
	(arc
		(start 373.79275 -293.180516)
		(mid 373.549423 -292.71595)
		(end 373.79275 -292.251384)
		(width 0.1143)
		(layer "In4.Cu")
		(net "P5E_CPU0_P3_RX_DN<13>")
	)
	(arc
		(start 393.289028 -378.800106)
		(mid 393.628725 -378.031708)
		(end 393.744958 -377.199652)
		(width 0.14224)
		(layer "In4.Cu")
		(net "P5E_CPU0_P3_RX_DN<13>")
	)
	(arc
		(start 387.295136 -389.814054)
		(mid 387.303091 -389.79917)
		(end 387.311138 -389.784336)
		(width 0.14224)
		(layer "In4.Cu")
		(net "P5E_CPU0_P3_RX_DN<13>")
	)
	(arc
		(start 387.027674 -390.577324)
		(mid 387.13296 -390.185723)
		(end 387.295136 -389.814054)
		(width 0.14224)
		(layer "In4.Cu")
		(net "P5E_CPU0_P3_RX_DN<13>")
	)
	(arc
		(start 373.549672 -295.955974)
		(mid 373.614331 -295.693417)
		(end 373.793512 -295.4909)
		(width 0.1143)
		(layer "In4.Cu")
		(net "P5E_CPU0_P3_RX_DN<13>")
	)
	(arc
		(start 374.086882 -298.248324)
		(mid 374.006456 -298.114406)
		(end 373.939562 -297.973242)
		(width 0.14224)
		(layer "In4.Cu")
		(net "P5E_CPU0_P3_RX_DN<13>")
	)
	(arc
		(start 373.843296 -293.841932)
		(mid 374.018246 -293.526346)
		(end 373.844058 -293.210234)
		(width 0.1143)
		(layer "In4.Cu")
		(net "P5E_CPU0_P3_RX_DN<13>")
	)
	(segment
		(start 384.77063 -393.69238)
		(end 385.29133 -393.69238)
		(width 0.127)
		(layer "F.Cu")
		(net "P5E_CPU0_P3_RX_DN<12>")
	)
	(segment
		(start 372.707916 -287.59023)
		(end 373.174768 -287.856168)
		(width 0.12954)
		(layer "F.Cu")
		(net "P5E_CPU0_P3_RX_DN<12>")
	)
	(segment
		(start 372.82755 -293.883842)
		(end 372.827296 -293.868856)
		(width 0.1143)
		(layer "In4.Cu")
		(net "P5E_CPU0_P3_RX_DN<12>")
	)
	(segment
		(start 386.611114 -388.445502)
		(end 386.536946 -388.266432)
		(width 0.14224)
		(layer "In4.Cu")
		(net "P5E_CPU0_P3_RX_DN<12>")
	)
	(segment
		(start 372.870222 -292.24097)
		(end 372.874286 -292.236906)
		(width 0.1143)
		(layer "In4.Cu")
		(net "P5E_CPU0_P3_RX_DN<12>")
	)
	(segment
		(start 385.9403 -390.065514)
		(end 386.179568 -389.48741)
		(width 0.14224)
		(layer "In4.Cu")
		(net "P5E_CPU0_P3_RX_DN<12>")
	)
	(segment
		(start 391.30224 -371.389656)
		(end 391.30224 -336.656426)
		(width 0.14224)
		(layer "In4.Cu")
		(net "P5E_CPU0_P3_RX_DN<12>")
	)
	(segment
		(start 372.563644 -296.927778)
		(end 372.563644 -296.43959)
		(width 0.14224)
		(layer "In4.Cu")
		(net "P5E_CPU0_P3_RX_DN<12>")
	)
	(segment
		(start 373.47271 -287.856168)
		(end 373.174768 -287.856168)
		(width 0.1143)
		(layer "In4.Cu")
		(net "P5E_CPU0_P3_RX_DN<12>")
	)
	(segment
		(start 372.8847 -291.579046)
		(end 372.88343 -291.578284)
		(width 0.1143)
		(layer "In4.Cu")
		(net "P5E_CPU0_P3_RX_DN<12>")
	)
	(segment
		(start 387.50875 -321.77355)
		(end 385.18973 -315.095636)
		(width 0.14224)
		(layer "In4.Cu")
		(net "P5E_CPU0_P3_RX_DN<12>")
	)
	(segment
		(start 372.90375 -288.981388)
		(end 372.904512 -288.98088)
		(width 0.1143)
		(layer "In4.Cu")
		(net "P5E_CPU0_P3_RX_DN<12>")
	)
	(segment
		(start 374.067832 -299.923708)
		(end 373.180356 -298.595796)
		(width 0.14224)
		(layer "In4.Cu")
		(net "P5E_CPU0_P3_RX_DN<12>")
	)
	(segment
		(start 372.889526 -294.822118)
		(end 372.884446 -294.818562)
		(width 0.1143)
		(layer "In4.Cu")
		(net "P5E_CPU0_P3_RX_DN<12>")
	)
	(segment
		(start 390.565386 -332.554072)
		(end 389.828532 -328.451972)
		(width 0.14224)
		(layer "In4.Cu")
		(net "P5E_CPU0_P3_RX_DN<12>")
	)
	(segment
		(start 387.042914 -387.40334)
		(end 386.968746 -387.22427)
		(width 0.14224)
		(layer "In4.Cu")
		(net "P5E_CPU0_P3_RX_DN<12>")
	)
	(segment
		(start 385.758436 -392.330432)
		(end 385.758436 -390.980168)
		(width 0.14224)
		(layer "In4.Cu")
		(net "P5E_CPU0_P3_RX_DN<12>")
	)
	(segment
		(start 389.648954 -381.658622)
		(end 390.231122 -378.733304)
		(width 0.14224)
		(layer "In4.Cu")
		(net "P5E_CPU0_P3_RX_DN<12>")
	)
	(segment
		(start 389.24865 -326.782176)
		(end 387.509004 -321.77355)
		(width 0.14224)
		(layer "In4.Cu")
		(net "P5E_CPU0_P3_RX_DN<12>")
	)
	(segment
		(start 385.29133 -393.69238)
		(end 385.64439 -393.787376)
		(width 0.14224)
		(layer "In4.Cu")
		(net "P5E_CPU0_P3_RX_DN<12>")
	)
	(segment
		(start 372.897908 -291.58692)
		(end 372.896384 -291.585904)
		(width 0.1143)
		(layer "In4.Cu")
		(net "P5E_CPU0_P3_RX_DN<12>")
	)
	(segment
		(start 372.893844 -294.824658)
		(end 372.892574 -294.823896)
		(width 0.1143)
		(layer "In4.Cu")
		(net "P5E_CPU0_P3_RX_DN<12>")
	)
	(segment
		(start 372.892574 -294.823896)
		(end 372.891812 -294.823388)
		(width 0.1143)
		(layer "In4.Cu")
		(net "P5E_CPU0_P3_RX_DN<12>")
	)
	(segment
		(start 372.893844 -293.204646)
		(end 372.892574 -293.203884)
		(width 0.1143)
		(layer "In4.Cu")
		(net "P5E_CPU0_P3_RX_DN<12>")
	)
	(segment
		(start 372.895368 -288.986468)
		(end 372.89613 -288.98596)
		(width 0.1143)
		(layer "In4.Cu")
		(net "P5E_CPU0_P3_RX_DN<12>")
	)
	(segment
		(start 372.898924 -291.587428)
		(end 372.897908 -291.58692)
		(width 0.1143)
		(layer "In4.Cu")
		(net "P5E_CPU0_P3_RX_DN<12>")
	)
	(segment
		(start 372.897146 -293.845488)
		(end 372.923562 -293.830248)
		(width 0.1143)
		(layer "In4.Cu")
		(net "P5E_CPU0_P3_RX_DN<12>")
	)
	(segment
		(start 386.700268 -387.87197)
		(end 386.879846 -387.797548)
		(width 0.14224)
		(layer "In4.Cu")
		(net "P5E_CPU0_P3_RX_DN<12>")
	)
	(segment
		(start 372.874286 -292.236906)
		(end 372.892574 -292.227762)
		(width 0.1143)
		(layer "In4.Cu")
		(net "P5E_CPU0_P3_RX_DN<12>")
	)
	(segment
		(start 387.311646 -386.755386)
		(end 387.311392 -386.755132)
		(width 0.14224)
		(layer "In4.Cu")
		(net "P5E_CPU0_P3_RX_DN<12>")
	)
	(segment
		(start 372.892574 -292.227762)
		(end 372.892574 -292.228016)
		(width 0.1143)
		(layer "In4.Cu")
		(net "P5E_CPU0_P3_RX_DN<12>")
	)
	(segment
		(start 382.707134 -310.452262)
		(end 374.067832 -299.923708)
		(width 0.14224)
		(layer "In4.Cu")
		(net "P5E_CPU0_P3_RX_DN<12>")
	)
	(segment
		(start 372.892574 -291.583872)
		(end 372.891812 -291.583364)
		(width 0.1143)
		(layer "In4.Cu")
		(net "P5E_CPU0_P3_RX_DN<12>")
	)
	(segment
		(start 373.343424 -288.18967)
		(end 373.391938 -288.161222)
		(width 0.1143)
		(layer "In4.Cu")
		(net "P5E_CPU0_P3_RX_DN<12>")
	)
	(segment
		(start 372.901718 -288.982658)
		(end 372.902988 -288.981388)
		(width 0.1143)
		(layer "In4.Cu")
		(net "P5E_CPU0_P3_RX_DN<12>")
	)
	(segment
		(start 372.890796 -293.202868)
		(end 372.852696 -293.180516)
		(width 0.1143)
		(layer "In4.Cu")
		(net "P5E_CPU0_P3_RX_DN<12>")
	)
	(segment
		(start 372.902988 -288.981388)
		(end 372.90375 -288.981388)
		(width 0.1143)
		(layer "In4.Cu")
		(net "P5E_CPU0_P3_RX_DN<12>")
	)
	(segment
		(start 372.853966 -295.490392)
		(end 372.924578 -295.449244)
		(width 0.1143)
		(layer "In4.Cu")
		(net "P5E_CPU0_P3_RX_DN<12>")
	)
	(segment
		(start 373.079772 -295.146222)
		(end 373.079772 -295.145968)
		(width 0.1143)
		(layer "In4.Cu")
		(net "P5E_CPU0_P3_RX_DN<12>")
	)
	(segment
		(start 372.889526 -288.98977)
		(end 372.890796 -288.989008)
		(width 0.1143)
		(layer "In4.Cu")
		(net "P5E_CPU0_P3_RX_DN<12>")
	)
	(segment
		(start 372.893844 -288.98723)
		(end 372.895368 -288.986468)
		(width 0.1143)
		(layer "In4.Cu")
		(net "P5E_CPU0_P3_RX_DN<12>")
	)
	(segment
		(start 372.892574 -293.203884)
		(end 372.891812 -293.203376)
		(width 0.1143)
		(layer "In4.Cu")
		(net "P5E_CPU0_P3_RX_DN<12>")
	)
	(segment
		(start 372.881144 -288.99485)
		(end 372.882668 -288.993834)
		(width 0.1143)
		(layer "In4.Cu")
		(net "P5E_CPU0_P3_RX_DN<12>")
	)
	(segment
		(start 372.852696 -292.251384)
		(end 372.867428 -292.242494)
		(width 0.1143)
		(layer "In4.Cu")
		(net "P5E_CPU0_P3_RX_DN<12>")
	)
	(segment
		(start 372.885716 -291.579808)
		(end 372.8847 -291.579046)
		(width 0.1143)
		(layer "In4.Cu")
		(net "P5E_CPU0_P3_RX_DN<12>")
	)
	(segment
		(start 385.454144 -392.63447)
		(end 385.758436 -392.330432)
		(width 0.14224)
		(layer "In4.Cu")
		(net "P5E_CPU0_P3_RX_DN<12>")
	)
	(segment
		(start 372.89613 -288.98596)
		(end 372.898162 -288.984944)
		(width 0.1143)
		(layer "In4.Cu")
		(net "P5E_CPU0_P3_RX_DN<12>")
	)
	(segment
		(start 372.904512 -288.98088)
		(end 372.906036 -288.980118)
		(width 0.1143)
		(layer "In4.Cu")
		(net "P5E_CPU0_P3_RX_DN<12>")
	)
	(segment
		(start 385.766564 -393.545822)
		(end 385.449572 -393.22883)
		(width 0.14224)
		(layer "In4.Cu")
		(net "P5E_CPU0_P3_RX_DN<12>")
	)
	(segment
		(start 390.231122 -378.733304)
		(end 390.231122 -376.787156)
		(width 0.14224)
		(layer "In4.Cu")
		(net "P5E_CPU0_P3_RX_DN<12>")
	)
	(segment
		(start 372.563644 -296.411142)
		(end 372.609364 -296.365422)
		(width 0.1143)
		(layer "In4.Cu")
		(net "P5E_CPU0_P3_RX_DN<12>")
	)
	(segment
		(start 373.391938 -288.161222)
		(end 373.393462 -288.160206)
		(width 0.1143)
		(layer "In4.Cu")
		(net "P5E_CPU0_P3_RX_DN<12>")
	)
	(segment
		(start 372.374668 -289.813746)
		(end 372.437152 -289.776916)
		(width 0.1143)
		(layer "In4.Cu")
		(net "P5E_CPU0_P3_RX_DN<12>")
	)
	(segment
		(start 372.888256 -291.581332)
		(end 372.885716 -291.579808)
		(width 0.1143)
		(layer "In4.Cu")
		(net "P5E_CPU0_P3_RX_DN<12>")
	)
	(segment
		(start 372.892574 -292.228016)
		(end 372.893844 -292.227254)
		(width 0.1143)
		(layer "In4.Cu")
		(net "P5E_CPU0_P3_RX_DN<12>")
	)
	(segment
		(start 391.30224 -336.656426)
		(end 390.933686 -334.604868)
		(width 0.14224)
		(layer "In4.Cu")
		(net "P5E_CPU0_P3_RX_DN<12>")
	)
	(segment
		(start 372.888256 -288.990532)
		(end 372.889272 -288.990024)
		(width 0.1143)
		(layer "In4.Cu")
		(net "P5E_CPU0_P3_RX_DN<12>")
	)
	(segment
		(start 385.644898 -393.786868)
		(end 385.766564 -393.716764)
		(width 0.14224)
		(layer "In4.Cu")
		(net "P5E_CPU0_P3_RX_DN<12>")
	)
	(segment
		(start 372.882668 -288.993834)
		(end 372.888256 -288.990532)
		(width 0.1143)
		(layer "In4.Cu")
		(net "P5E_CPU0_P3_RX_DN<12>")
	)
	(segment
		(start 372.906036 -288.980118)
		(end 372.91137 -288.977324)
		(width 0.1143)
		(layer "In4.Cu")
		(net "P5E_CPU0_P3_RX_DN<12>")
	)
	(segment
		(start 372.867428 -292.242494)
		(end 372.869206 -292.241478)
		(width 0.1143)
		(layer "In4.Cu")
		(net "P5E_CPU0_P3_RX_DN<12>")
	)
	(segment
		(start 386.179568 -389.48741)
		(end 386.1054 -389.30834)
		(width 0.14224)
		(layer "In4.Cu")
		(net "P5E_CPU0_P3_RX_DN<12>")
	)
	(segment
		(start 372.852442 -289.011614)
		(end 372.881144 -288.99485)
		(width 0.1143)
		(layer "In4.Cu")
		(net "P5E_CPU0_P3_RX_DN<12>")
	)
	(segment
		(start 390.933686 -334.604868)
		(end 390.933686 -334.605122)
		(width 0.14224)
		(layer "In4.Cu")
		(net "P5E_CPU0_P3_RX_DN<12>")
	)
	(segment
		(start 372.889272 -291.58184)
		(end 372.888256 -291.581332)
		(width 0.1143)
		(layer "In4.Cu")
		(net "P5E_CPU0_P3_RX_DN<12>")
	)
	(segment
		(start 385.766564 -393.716764)
		(end 385.766564 -393.545822)
		(width 0.14224)
		(layer "In4.Cu")
		(net "P5E_CPU0_P3_RX_DN<12>")
	)
	(segment
		(start 386.968746 -387.22427)
		(end 387.132068 -386.829808)
		(width 0.14224)
		(layer "In4.Cu")
		(net "P5E_CPU0_P3_RX_DN<12>")
	)
	(segment
		(start 372.891812 -291.583364)
		(end 372.890796 -291.582856)
		(width 0.1143)
		(layer "In4.Cu")
		(net "P5E_CPU0_P3_RX_DN<12>")
	)
	(segment
		(start 390.231122 -376.787156)
		(end 391.2997 -371.414802)
		(width 0.14224)
		(layer "In4.Cu")
		(net "P5E_CPU0_P3_RX_DN<12>")
	)
	(segment
		(start 372.901718 -288.982912)
		(end 372.901718 -288.982658)
		(width 0.1143)
		(layer "In4.Cu")
		(net "P5E_CPU0_P3_RX_DN<12>")
	)
	(segment
		(start 372.890796 -294.82288)
		(end 372.889526 -294.822118)
		(width 0.1143)
		(layer "In4.Cu")
		(net "P5E_CPU0_P3_RX_DN<12>")
	)
	(segment
		(start 372.923562 -293.221664)
		(end 372.893844 -293.204646)
		(width 0.1143)
		(layer "In4.Cu")
		(net "P5E_CPU0_P3_RX_DN<12>")
	)
	(segment
		(start 372.891812 -294.823388)
		(end 372.890796 -294.82288)
		(width 0.1143)
		(layer "In4.Cu")
		(net "P5E_CPU0_P3_RX_DN<12>")
	)
	(segment
		(start 372.894606 -292.227)
		(end 372.89613 -292.225984)
		(width 0.1143)
		(layer "In4.Cu")
		(net "P5E_CPU0_P3_RX_DN<12>")
	)
	(segment
		(start 372.890796 -288.989008)
		(end 372.891812 -288.9885)
		(width 0.1143)
		(layer "In4.Cu")
		(net "P5E_CPU0_P3_RX_DN<12>")
	)
	(segment
		(start 387.311392 -386.755132)
		(end 388.489698 -383.910586)
		(width 0.14224)
		(layer "In4.Cu")
		(net "P5E_CPU0_P3_RX_DN<12>")
	)
	(segment
		(start 372.895622 -293.84625)
		(end 372.897146 -293.845488)
		(width 0.1143)
		(layer "In4.Cu")
		(net "P5E_CPU0_P3_RX_DN<12>")
	)
	(segment
		(start 372.884446 -294.818562)
		(end 372.873778 -294.81145)
		(width 0.1143)
		(layer "In4.Cu")
		(net "P5E_CPU0_P3_RX_DN<12>")
	)
	(segment
		(start 372.89613 -292.225984)
		(end 372.897146 -292.225476)
		(width 0.1143)
		(layer "In4.Cu")
		(net "P5E_CPU0_P3_RX_DN<12>")
	)
	(segment
		(start 387.132068 -386.829808)
		(end 387.311646 -386.755386)
		(width 0.14224)
		(layer "In4.Cu")
		(net "P5E_CPU0_P3_RX_DN<12>")
	)
	(segment
		(start 372.563644 -296.43959)
		(end 372.563644 -296.411142)
		(width 0.1143)
		(layer "In4.Cu")
		(net "P5E_CPU0_P3_RX_DN<12>")
	)
	(segment
		(start 372.452392 -290.791138)
		(end 372.411752 -290.767516)
		(width 0.1143)
		(layer "In4.Cu")
		(net "P5E_CPU0_P3_RX_DN<12>")
	)
	(segment
		(start 372.892574 -288.987992)
		(end 372.893844 -288.98723)
		(width 0.1143)
		(layer "In4.Cu")
		(net "P5E_CPU0_P3_RX_DN<12>")
	)
	(segment
		(start 372.88343 -291.578284)
		(end 372.875302 -291.573204)
		(width 0.1143)
		(layer "In4.Cu")
		(net "P5E_CPU0_P3_RX_DN<12>")
	)
	(segment
		(start 372.923562 -294.841676)
		(end 372.893844 -294.824658)
		(width 0.1143)
		(layer "In4.Cu")
		(net "P5E_CPU0_P3_RX_DN<12>")
	)
	(segment
		(start 390.933686 -334.605122)
		(end 390.565132 -332.554072)
		(width 0.14224)
		(layer "In4.Cu")
		(net "P5E_CPU0_P3_RX_DN<12>")
	)
	(segment
		(start 387.509004 -321.77355)
		(end 387.50875 -321.77355)
		(width 0.14224)
		(layer "In4.Cu")
		(net "P5E_CPU0_P3_RX_DN<12>")
	)
	(segment
		(start 372.89359 -293.847012)
		(end 372.895622 -293.84625)
		(width 0.1143)
		(layer "In4.Cu")
		(net "P5E_CPU0_P3_RX_DN<12>")
	)
	(segment
		(start 385.64439 -393.787376)
		(end 385.644898 -393.786868)
		(width 0.14224)
		(layer "In4.Cu")
		(net "P5E_CPU0_P3_RX_DN<12>")
	)
	(segment
		(start 372.869206 -292.241478)
		(end 372.870222 -292.24097)
		(width 0.1143)
		(layer "In4.Cu")
		(net "P5E_CPU0_P3_RX_DN<12>")
	)
	(segment
		(start 372.898162 -288.984944)
		(end 372.898924 -288.984436)
		(width 0.1143)
		(layer "In4.Cu")
		(net "P5E_CPU0_P3_RX_DN<12>")
	)
	(segment
		(start 386.268722 -388.913878)
		(end 386.448046 -388.83971)
		(width 0.14224)
		(layer "In4.Cu")
		(net "P5E_CPU0_P3_RX_DN<12>")
	)
	(segment
		(start 372.896384 -291.585904)
		(end 372.893844 -291.584634)
		(width 0.1143)
		(layer "In4.Cu")
		(net "P5E_CPU0_P3_RX_DN<12>")
	)
	(segment
		(start 372.893844 -292.227254)
		(end 372.894606 -292.227)
		(width 0.1143)
		(layer "In4.Cu")
		(net "P5E_CPU0_P3_RX_DN<12>")
	)
	(segment
		(start 372.873778 -294.81145)
		(end 372.850156 -294.797734)
		(width 0.1143)
		(layer "In4.Cu")
		(net "P5E_CPU0_P3_RX_DN<12>")
	)
	(segment
		(start 388.489698 -383.910586)
		(end 389.085836 -383.018284)
		(width 0.14224)
		(layer "In4.Cu")
		(net "P5E_CPU0_P3_RX_DN<12>")
	)
	(segment
		(start 372.923562 -291.601652)
		(end 372.898924 -291.587428)
		(width 0.1143)
		(layer "In4.Cu")
		(net "P5E_CPU0_P3_RX_DN<12>")
	)
	(segment
		(start 385.18973 -315.095636)
		(end 382.707134 -310.452262)
		(width 0.14224)
		(layer "In4.Cu")
		(net "P5E_CPU0_P3_RX_DN<12>")
	)
	(segment
		(start 373.180356 -298.595796)
		(end 372.632478 -297.274234)
		(width 0.14224)
		(layer "In4.Cu")
		(net "P5E_CPU0_P3_RX_DN<12>")
	)
	(segment
		(start 386.879846 -387.797548)
		(end 387.042914 -387.40334)
		(width 0.14224)
		(layer "In4.Cu")
		(net "P5E_CPU0_P3_RX_DN<12>")
	)
	(segment
		(start 372.893844 -291.584634)
		(end 372.892574 -291.583872)
		(width 0.1143)
		(layer "In4.Cu")
		(net "P5E_CPU0_P3_RX_DN<12>")
	)
	(segment
		(start 386.448046 -388.83971)
		(end 386.611114 -388.445502)
		(width 0.14224)
		(layer "In4.Cu")
		(net "P5E_CPU0_P3_RX_DN<12>")
	)
	(segment
		(start 372.891812 -288.9885)
		(end 372.892574 -288.987992)
		(width 0.1143)
		(layer "In4.Cu")
		(net "P5E_CPU0_P3_RX_DN<12>")
	)
	(segment
		(start 372.898924 -288.984436)
		(end 372.901718 -288.982912)
		(width 0.1143)
		(layer "In4.Cu")
		(net "P5E_CPU0_P3_RX_DN<12>")
	)
	(segment
		(start 372.897146 -292.225476)
		(end 372.923562 -292.210236)
		(width 0.1143)
		(layer "In4.Cu")
		(net "P5E_CPU0_P3_RX_DN<12>")
	)
	(segment
		(start 372.827296 -293.868856)
		(end 372.89359 -293.847012)
		(width 0.1143)
		(layer "In4.Cu")
		(net "P5E_CPU0_P3_RX_DN<12>")
	)
	(segment
		(start 386.536946 -388.266432)
		(end 386.700268 -387.87197)
		(width 0.14224)
		(layer "In4.Cu")
		(net "P5E_CPU0_P3_RX_DN<12>")
	)
	(segment
		(start 386.1054 -389.30834)
		(end 386.268722 -388.913878)
		(width 0.14224)
		(layer "In4.Cu")
		(net "P5E_CPU0_P3_RX_DN<12>")
	)
	(segment
		(start 372.891812 -293.203376)
		(end 372.890796 -293.202868)
		(width 0.1143)
		(layer "In4.Cu")
		(net "P5E_CPU0_P3_RX_DN<12>")
	)
	(segment
		(start 385.449572 -393.22883)
		(end 385.454144 -392.63447)
		(width 0.14224)
		(layer "In4.Cu")
		(net "P5E_CPU0_P3_RX_DN<12>")
	)
	(segment
		(start 372.91137 -288.977324)
		(end 372.923562 -288.970212)
		(width 0.1143)
		(layer "In4.Cu")
		(net "P5E_CPU0_P3_RX_DN<12>")
	)
	(segment
		(start 390.565132 -332.554072)
		(end 390.565386 -332.554072)
		(width 0.14224)
		(layer "In4.Cu")
		(net "P5E_CPU0_P3_RX_DN<12>")
	)
	(segment
		(start 389.828532 -328.451972)
		(end 389.24865 -326.782176)
		(width 0.14224)
		(layer "In4.Cu")
		(net "P5E_CPU0_P3_RX_DN<12>")
	)
	(segment
		(start 372.889272 -288.990024)
		(end 372.889526 -288.98977)
		(width 0.1143)
		(layer "In4.Cu")
		(net "P5E_CPU0_P3_RX_DN<12>")
	)
	(segment
		(start 373.54256 -287.926018)
		(end 373.47271 -287.856168)
		(width 0.1143)
		(layer "In4.Cu")
		(net "P5E_CPU0_P3_RX_DN<12>")
	)
	(segment
		(start 372.609364 -296.365422)
		(end 372.609364 -295.955974)
		(width 0.1143)
		(layer "In4.Cu")
		(net "P5E_CPU0_P3_RX_DN<12>")
	)
	(segment
		(start 372.890796 -291.582856)
		(end 372.889272 -291.58184)
		(width 0.1143)
		(layer "In4.Cu")
		(net "P5E_CPU0_P3_RX_DN<12>")
	)
	(arc
		(start 372.875302 -291.573204)
		(mid 372.68282 -291.363253)
		(end 372.609364 -291.088064)
		(width 0.1143)
		(layer "In4.Cu")
		(net "P5E_CPU0_P3_RX_DN<12>")
	)
	(arc
		(start 372.853204 -295.4909)
		(mid 372.853585 -295.490646)
		(end 372.853966 -295.490392)
		(width 0.1143)
		(layer "In4.Cu")
		(net "P5E_CPU0_P3_RX_DN<12>")
	)
	(arc
		(start 372.923562 -293.830248)
		(mid 373.07949 -293.525956)
		(end 372.923562 -293.221664)
		(width 0.1143)
		(layer "In4.Cu")
		(net "P5E_CPU0_P3_RX_DN<12>")
	)
	(arc
		(start 372.609364 -295.9481)
		(mid 372.67471 -295.699877)
		(end 372.837964 -295.501822)
		(width 0.1143)
		(layer "In4.Cu")
		(net "P5E_CPU0_P3_RX_DN<12>")
	)
	(arc
		(start 372.609364 -291.088064)
		(mid 372.566067 -290.920988)
		(end 372.452392 -290.791138)
		(width 0.1143)
		(layer "In4.Cu")
		(net "P5E_CPU0_P3_RX_DN<12>")
	)
	(arc
		(start 372.924578 -295.449244)
		(mid 373.038673 -295.316423)
		(end 373.079772 -295.146222)
		(width 0.1143)
		(layer "In4.Cu")
		(net "P5E_CPU0_P3_RX_DN<12>")
	)
	(arc
		(start 372.437152 -289.776916)
		(mid 372.563589 -289.649414)
		(end 372.609872 -289.475926)
		(width 0.1143)
		(layer "In4.Cu")
		(net "P5E_CPU0_P3_RX_DN<12>")
	)
	(arc
		(start 385.758436 -390.980168)
		(mid 385.80431 -390.51388)
		(end 385.9403 -390.065514)
		(width 0.14224)
		(layer "In4.Cu")
		(net "P5E_CPU0_P3_RX_DN<12>")
	)
	(arc
		(start 372.852696 -293.180516)
		(mid 372.609369 -292.71595)
		(end 372.852696 -292.251384)
		(width 0.1143)
		(layer "In4.Cu")
		(net "P5E_CPU0_P3_RX_DN<12>")
	)
	(arc
		(start 372.609872 -289.475926)
		(mid 372.674169 -289.213998)
		(end 372.852442 -289.011614)
		(width 0.1143)
		(layer "In4.Cu")
		(net "P5E_CPU0_P3_RX_DN<12>")
	)
	(arc
		(start 372.850156 -294.797734)
		(mid 372.606364 -294.34658)
		(end 372.82755 -293.883842)
		(width 0.1143)
		(layer "In4.Cu")
		(net "P5E_CPU0_P3_RX_DN<12>")
	)
	(arc
		(start 372.411752 -290.767516)
		(mid 372.13094 -290.300806)
		(end 372.374668 -289.813746)
		(width 0.1143)
		(layer "In4.Cu")
		(net "P5E_CPU0_P3_RX_DN<12>")
	)
	(arc
		(start 389.085836 -383.018284)
		(mid 389.434336 -382.366176)
		(end 389.648954 -381.658622)
		(width 0.14224)
		(layer "In4.Cu")
		(net "P5E_CPU0_P3_RX_DN<12>")
	)
	(arc
		(start 373.079772 -295.145968)
		(mid 373.038432 -294.974953)
		(end 372.923562 -294.841676)
		(width 0.1143)
		(layer "In4.Cu")
		(net "P5E_CPU0_P3_RX_DN<12>")
	)
	(arc
		(start 373.393462 -288.160206)
		(mid 373.490469 -288.057415)
		(end 373.54256 -287.926018)
		(width 0.1143)
		(layer "In4.Cu")
		(net "P5E_CPU0_P3_RX_DN<12>")
	)
	(arc
		(start 372.632478 -297.274234)
		(mid 372.580964 -297.104401)
		(end 372.563644 -296.927778)
		(width 0.14224)
		(layer "In4.Cu")
		(net "P5E_CPU0_P3_RX_DN<12>")
	)
	(arc
		(start 372.837964 -295.501822)
		(mid 372.845538 -295.496297)
		(end 372.853204 -295.4909)
		(width 0.1143)
		(layer "In4.Cu")
		(net "P5E_CPU0_P3_RX_DN<12>")
	)
	(arc
		(start 373.079772 -288.666174)
		(mid 373.132808 -288.426979)
		(end 373.281956 -288.232596)
		(width 0.1143)
		(layer "In4.Cu")
		(net "P5E_CPU0_P3_RX_DN<12>")
	)
	(arc
		(start 373.281956 -288.232596)
		(mid 373.311755 -288.209794)
		(end 373.343424 -288.18967)
		(width 0.1143)
		(layer "In4.Cu")
		(net "P5E_CPU0_P3_RX_DN<12>")
	)
	(arc
		(start 372.609364 -295.955974)
		(mid 372.609351 -295.952037)
		(end 372.609364 -295.9481)
		(width 0.1143)
		(layer "In4.Cu")
		(net "P5E_CPU0_P3_RX_DN<12>")
	)
	(arc
		(start 391.2997 -371.414802)
		(mid 391.301587 -371.402291)
		(end 391.30224 -371.389656)
		(width 0.14224)
		(layer "In4.Cu")
		(net "P5E_CPU0_P3_RX_DN<12>")
	)
	(arc
		(start 372.923562 -292.210236)
		(mid 373.07949 -291.905944)
		(end 372.923562 -291.601652)
		(width 0.1143)
		(layer "In4.Cu")
		(net "P5E_CPU0_P3_RX_DN<12>")
	)
	(arc
		(start 372.923562 -288.970212)
		(mid 373.038405 -288.837064)
		(end 373.079772 -288.666174)
		(width 0.1143)
		(layer "In4.Cu")
		(net "P5E_CPU0_P3_RX_DN<12>")
	)
	(segment
		(start 415.889948 -383.548382)
		(end 413.680148 -385.758182)
		(width 0.1016)
		(layer "F.Cu")
		(net "P5E_CPU0_P2_TX_C_DP<9>")
	)
	(segment
		(start 413.243776 -391.88771)
		(end 413.334962 -391.978896)
		(width 0.1016)
		(layer "F.Cu")
		(net "P5E_CPU0_P2_TX_C_DP<9>")
	)
	(segment
		(start 413.536384 -386.105908)
		(end 413.536384 -391.324592)
		(width 0.1016)
		(layer "F.Cu")
		(net "P5E_CPU0_P2_TX_C_DP<9>")
	)
	(segment
		(start 415.961322 -382.315466)
		(end 415.961322 -383.376932)
		(width 0.1016)
		(layer "F.Cu")
		(net "P5E_CPU0_P2_TX_C_DP<9>")
	)
	(segment
		(start 413.334962 -391.978896)
		(end 413.469328 -391.978896)
		(width 0.1016)
		(layer "F.Cu")
		(net "P5E_CPU0_P2_TX_C_DP<9>")
	)
	(segment
		(start 413.545782 -391.902442)
		(end 413.545782 -391.784586)
		(width 0.1016)
		(layer "F.Cu")
		(net "P5E_CPU0_P2_TX_C_DP<9>")
	)
	(segment
		(start 413.536384 -391.324592)
		(end 413.243776 -391.6172)
		(width 0.1016)
		(layer "F.Cu")
		(net "P5E_CPU0_P2_TX_C_DP<9>")
	)
	(segment
		(start 413.93364 -379.22073)
		(end 414.28289 -379.56998)
		(width 0.1016)
		(layer "F.Cu")
		(net "P5E_CPU0_P2_TX_C_DP<9>")
	)
	(segment
		(start 413.243776 -391.6172)
		(end 413.243776 -391.88771)
		(width 0.1016)
		(layer "F.Cu")
		(net "P5E_CPU0_P2_TX_C_DP<9>")
	)
	(segment
		(start 414.28289 -379.56998)
		(end 414.28289 -379.909578)
		(width 0.1016)
		(layer "F.Cu")
		(net "P5E_CPU0_P2_TX_C_DP<9>")
	)
	(segment
		(start 413.469328 -391.978896)
		(end 413.545782 -391.902442)
		(width 0.1016)
		(layer "F.Cu")
		(net "P5E_CPU0_P2_TX_C_DP<9>")
	)
	(segment
		(start 414.598358 -380.67107)
		(end 415.761424 -381.834136)
		(width 0.1016)
		(layer "F.Cu")
		(net "P5E_CPU0_P2_TX_C_DP<9>")
	)
	(arc
		(start 415.961322 -383.376932)
		(mid 415.942657 -383.469735)
		(end 415.889948 -383.548382)
		(width 0.1016)
		(layer "F.Cu")
		(net "P5E_CPU0_P2_TX_C_DP<9>")
	)
	(arc
		(start 413.680148 -385.758182)
		(mid 413.573714 -385.91775)
		(end 413.536384 -386.105908)
		(width 0.1016)
		(layer "F.Cu")
		(net "P5E_CPU0_P2_TX_C_DP<9>")
	)
	(arc
		(start 415.761424 -381.834136)
		(mid 415.909285 -382.054913)
		(end 415.961322 -382.315466)
		(width 0.1016)
		(layer "F.Cu")
		(net "P5E_CPU0_P2_TX_C_DP<9>")
	)
	(arc
		(start 414.28289 -379.909578)
		(mid 414.364922 -380.321688)
		(end 414.598358 -380.67107)
		(width 0.1016)
		(layer "F.Cu")
		(net "P5E_CPU0_P2_TX_C_DP<9>")
	)
	(segment
		(start 412.043626 -391.88771)
		(end 412.134812 -391.978896)
		(width 0.1016)
		(layer "F.Cu")
		(net "P5E_CPU0_P2_TX_C_DP<8>")
	)
	(segment
		(start 412.336234 -385.70027)
		(end 412.336234 -391.324592)
		(width 0.1016)
		(layer "F.Cu")
		(net "P5E_CPU0_P2_TX_C_DP<8>")
	)
	(segment
		(start 412.134812 -391.978896)
		(end 412.269178 -391.978896)
		(width 0.1016)
		(layer "F.Cu")
		(net "P5E_CPU0_P2_TX_C_DP<8>")
	)
	(segment
		(start 412.336234 -391.324592)
		(end 412.043626 -391.6172)
		(width 0.1016)
		(layer "F.Cu")
		(net "P5E_CPU0_P2_TX_C_DP<8>")
	)
	(segment
		(start 412.58109 -382.10109)
		(end 412.58109 -384.99923)
		(width 0.1016)
		(layer "F.Cu")
		(net "P5E_CPU0_P2_TX_C_DP<8>")
	)
	(segment
		(start 412.043626 -391.6172)
		(end 412.043626 -391.88771)
		(width 0.1016)
		(layer "F.Cu")
		(net "P5E_CPU0_P2_TX_C_DP<8>")
	)
	(segment
		(start 412.269178 -391.978896)
		(end 412.345632 -391.902442)
		(width 0.1016)
		(layer "F.Cu")
		(net "P5E_CPU0_P2_TX_C_DP<8>")
	)
	(segment
		(start 412.23184 -381.68453)
		(end 412.533592 -381.986282)
		(width 0.1016)
		(layer "F.Cu")
		(net "P5E_CPU0_P2_TX_C_DP<8>")
	)
	(segment
		(start 412.345632 -391.902442)
		(end 412.345632 -391.784586)
		(width 0.1016)
		(layer "F.Cu")
		(net "P5E_CPU0_P2_TX_C_DP<8>")
	)
	(arc
		(start 412.393892 -385.425696)
		(mid 412.350738 -385.559976)
		(end 412.336234 -385.70027)
		(width 0.1016)
		(layer "F.Cu")
		(net "P5E_CPU0_P2_TX_C_DP<8>")
	)
	(arc
		(start 412.58109 -384.99923)
		(mid 412.556874 -385.14275)
		(end 412.48711 -385.270502)
		(width 0.1016)
		(layer "F.Cu")
		(net "P5E_CPU0_P2_TX_C_DP<8>")
	)
	(arc
		(start 412.533592 -381.986282)
		(mid 412.568734 -382.038971)
		(end 412.58109 -382.10109)
		(width 0.1016)
		(layer "F.Cu")
		(net "P5E_CPU0_P2_TX_C_DP<8>")
	)
	(arc
		(start 412.48711 -385.270502)
		(mid 412.435614 -385.345163)
		(end 412.393892 -385.425696)
		(width 0.1016)
		(layer "F.Cu")
		(net "P5E_CPU0_P2_TX_C_DP<8>")
	)
	(segment
		(start 410.53004 -384.14833)
		(end 410.831792 -384.450082)
		(width 0.1016)
		(layer "F.Cu")
		(net "P5E_CPU0_P2_TX_C_DP<7>")
	)
	(segment
		(start 411.145736 -391.902442)
		(end 411.145736 -391.784586)
		(width 0.1016)
		(layer "F.Cu")
		(net "P5E_CPU0_P2_TX_C_DP<7>")
	)
	(segment
		(start 411.069282 -391.978896)
		(end 411.145736 -391.902442)
		(width 0.1016)
		(layer "F.Cu")
		(net "P5E_CPU0_P2_TX_C_DP<7>")
	)
	(segment
		(start 411.136338 -391.324592)
		(end 410.84373 -391.6172)
		(width 0.1016)
		(layer "F.Cu")
		(net "P5E_CPU0_P2_TX_C_DP<7>")
	)
	(segment
		(start 411.118558 -387.046216)
		(end 411.136338 -391.324592)
		(width 0.1016)
		(layer "F.Cu")
		(net "P5E_CPU0_P2_TX_C_DP<7>")
	)
	(segment
		(start 410.84373 -391.6172)
		(end 410.84373 -391.88771)
		(width 0.1016)
		(layer "F.Cu")
		(net "P5E_CPU0_P2_TX_C_DP<7>")
	)
	(segment
		(start 410.84373 -391.88771)
		(end 410.934916 -391.978896)
		(width 0.1016)
		(layer "F.Cu")
		(net "P5E_CPU0_P2_TX_C_DP<7>")
	)
	(segment
		(start 410.87929 -384.56489)
		(end 410.87929 -386.289804)
		(width 0.1016)
		(layer "F.Cu")
		(net "P5E_CPU0_P2_TX_C_DP<7>")
	)
	(segment
		(start 410.934916 -391.978896)
		(end 411.069282 -391.978896)
		(width 0.1016)
		(layer "F.Cu")
		(net "P5E_CPU0_P2_TX_C_DP<7>")
	)
	(arc
		(start 410.831792 -384.450082)
		(mid 410.866934 -384.502771)
		(end 410.87929 -384.56489)
		(width 0.1016)
		(layer "F.Cu")
		(net "P5E_CPU0_P2_TX_C_DP<7>")
	)
	(arc
		(start 411.03804 -386.792978)
		(mid 411.097602 -386.913463)
		(end 411.118558 -387.046216)
		(width 0.1016)
		(layer "F.Cu")
		(net "P5E_CPU0_P2_TX_C_DP<7>")
	)
	(arc
		(start 410.87929 -386.289804)
		(mid 410.919968 -386.553596)
		(end 411.03804 -386.792978)
		(width 0.1016)
		(layer "F.Cu")
		(net "P5E_CPU0_P2_TX_C_DP<7>")
	)
	(segment
		(start 409.869132 -391.978896)
		(end 409.945586 -391.902442)
		(width 0.1016)
		(layer "F.Cu")
		(net "P5E_CPU0_P2_TX_C_DP<6>")
	)
	(segment
		(start 409.337002 -387.115558)
		(end 409.373578 -387.205474)
		(width 0.1016)
		(layer "F.Cu")
		(net "P5E_CPU0_P2_TX_C_DP<6>")
	)
	(segment
		(start 409.734766 -391.978896)
		(end 409.869132 -391.978896)
		(width 0.1016)
		(layer "F.Cu")
		(net "P5E_CPU0_P2_TX_C_DP<6>")
	)
	(segment
		(start 409.195016 -382.268984)
		(end 409.195016 -386.388102)
		(width 0.1016)
		(layer "F.Cu")
		(net "P5E_CPU0_P2_TX_C_DP<6>")
	)
	(segment
		(start 409.64358 -391.6172)
		(end 409.64358 -391.88771)
		(width 0.1016)
		(layer "F.Cu")
		(net "P5E_CPU0_P2_TX_C_DP<6>")
	)
	(segment
		(start 407.80208 -380.649734)
		(end 409.034488 -381.882142)
		(width 0.1016)
		(layer "F.Cu")
		(net "P5E_CPU0_P2_TX_C_DP<6>")
	)
	(segment
		(start 407.12644 -379.22073)
		(end 407.47569 -379.56998)
		(width 0.1016)
		(layer "F.Cu")
		(net "P5E_CPU0_P2_TX_C_DP<6>")
	)
	(segment
		(start 409.936188 -391.324592)
		(end 409.64358 -391.6172)
		(width 0.1016)
		(layer "F.Cu")
		(net "P5E_CPU0_P2_TX_C_DP<6>")
	)
	(segment
		(start 407.47569 -379.56998)
		(end 407.47569 -379.86208)
		(width 0.1016)
		(layer "F.Cu")
		(net "P5E_CPU0_P2_TX_C_DP<6>")
	)
	(segment
		(start 409.945586 -391.902442)
		(end 409.945586 -391.784586)
		(width 0.1016)
		(layer "F.Cu")
		(net "P5E_CPU0_P2_TX_C_DP<6>")
	)
	(segment
		(start 409.936188 -390.076436)
		(end 409.936188 -391.324592)
		(width 0.1016)
		(layer "F.Cu")
		(net "P5E_CPU0_P2_TX_C_DP<6>")
	)
	(segment
		(start 409.64358 -391.88771)
		(end 409.734766 -391.978896)
		(width 0.1016)
		(layer "F.Cu")
		(net "P5E_CPU0_P2_TX_C_DP<6>")
	)
	(arc
		(start 407.47569 -379.86208)
		(mid 407.560559 -380.288367)
		(end 407.80208 -380.649734)
		(width 0.1016)
		(layer "F.Cu")
		(net "P5E_CPU0_P2_TX_C_DP<6>")
	)
	(arc
		(start 409.373578 -387.205474)
		(mid 409.794147 -388.613663)
		(end 409.936188 -390.076436)
		(width 0.1016)
		(layer "F.Cu")
		(net "P5E_CPU0_P2_TX_C_DP<6>")
	)
	(arc
		(start 409.195016 -386.388102)
		(mid 409.230821 -386.758698)
		(end 409.337002 -387.115558)
		(width 0.1016)
		(layer "F.Cu")
		(net "P5E_CPU0_P2_TX_C_DP<6>")
	)
	(arc
		(start 409.034488 -381.882142)
		(mid 409.153245 -382.059597)
		(end 409.195016 -382.268984)
		(width 0.1016)
		(layer "F.Cu")
		(net "P5E_CPU0_P2_TX_C_DP<6>")
	)
	(segment
		(start 408.443684 -391.88771)
		(end 408.53487 -391.978896)
		(width 0.1016)
		(layer "F.Cu")
		(net "P5E_CPU0_P2_TX_C_DP<5>")
	)
	(segment
		(start 408.736292 -391.324592)
		(end 408.443684 -391.6172)
		(width 0.1016)
		(layer "F.Cu")
		(net "P5E_CPU0_P2_TX_C_DP<5>")
	)
	(segment
		(start 408.736292 -390.033764)
		(end 408.736292 -391.324592)
		(width 0.1016)
		(layer "F.Cu")
		(net "P5E_CPU0_P2_TX_C_DP<5>")
	)
	(segment
		(start 405.77389 -382.03378)
		(end 405.77389 -383.744216)
		(width 0.1016)
		(layer "F.Cu")
		(net "P5E_CPU0_P2_TX_C_DP<5>")
	)
	(segment
		(start 408.443684 -391.6172)
		(end 408.443684 -391.88771)
		(width 0.1016)
		(layer "F.Cu")
		(net "P5E_CPU0_P2_TX_C_DP<5>")
	)
	(segment
		(start 406.137872 -384.943858)
		(end 408.067764 -387.830822)
		(width 0.1016)
		(layer "F.Cu")
		(net "P5E_CPU0_P2_TX_C_DP<5>")
	)
	(segment
		(start 405.42464 -381.68453)
		(end 405.77389 -382.03378)
		(width 0.1016)
		(layer "F.Cu")
		(net "P5E_CPU0_P2_TX_C_DP<5>")
	)
	(segment
		(start 408.53487 -391.978896)
		(end 408.669236 -391.978896)
		(width 0.1016)
		(layer "F.Cu")
		(net "P5E_CPU0_P2_TX_C_DP<5>")
	)
	(segment
		(start 408.669236 -391.978896)
		(end 408.74569 -391.902442)
		(width 0.1016)
		(layer "F.Cu")
		(net "P5E_CPU0_P2_TX_C_DP<5>")
	)
	(segment
		(start 408.74569 -391.902442)
		(end 408.74569 -391.784586)
		(width 0.1016)
		(layer "F.Cu")
		(net "P5E_CPU0_P2_TX_C_DP<5>")
	)
	(arc
		(start 408.067764 -387.830822)
		(mid 408.56547 -388.882692)
		(end 408.736292 -390.033764)
		(width 0.1016)
		(layer "F.Cu")
		(net "P5E_CPU0_P2_TX_C_DP<5>")
	)
	(arc
		(start 405.77389 -383.744216)
		(mid 405.866895 -384.371034)
		(end 406.137872 -384.943858)
		(width 0.1016)
		(layer "F.Cu")
		(net "P5E_CPU0_P2_TX_C_DP<5>")
	)
	(segment
		(start 407.536396 -391.324592)
		(end 407.243788 -391.6172)
		(width 0.1016)
		(layer "F.Cu")
		(net "P5E_CPU0_P2_TX_C_DP<4>")
	)
	(segment
		(start 407.46934 -391.978896)
		(end 407.545794 -391.902442)
		(width 0.1016)
		(layer "F.Cu")
		(net "P5E_CPU0_P2_TX_C_DP<4>")
	)
	(segment
		(start 407.334974 -391.978896)
		(end 407.46934 -391.978896)
		(width 0.1016)
		(layer "F.Cu")
		(net "P5E_CPU0_P2_TX_C_DP<4>")
	)
	(segment
		(start 407.545794 -391.902442)
		(end 407.545794 -391.784586)
		(width 0.1016)
		(layer "F.Cu")
		(net "P5E_CPU0_P2_TX_C_DP<4>")
	)
	(segment
		(start 403.72284 -384.14833)
		(end 404.07209 -384.49758)
		(width 0.1016)
		(layer "F.Cu")
		(net "P5E_CPU0_P2_TX_C_DP<4>")
	)
	(segment
		(start 407.243788 -391.6172)
		(end 407.243788 -391.88771)
		(width 0.1016)
		(layer "F.Cu")
		(net "P5E_CPU0_P2_TX_C_DP<4>")
	)
	(segment
		(start 404.07209 -384.49758)
		(end 404.07209 -384.71475)
		(width 0.1016)
		(layer "F.Cu")
		(net "P5E_CPU0_P2_TX_C_DP<4>")
	)
	(segment
		(start 407.536396 -389.954008)
		(end 407.536396 -391.324592)
		(width 0.1016)
		(layer "F.Cu")
		(net "P5E_CPU0_P2_TX_C_DP<4>")
	)
	(segment
		(start 407.243788 -391.88771)
		(end 407.334974 -391.978896)
		(width 0.1016)
		(layer "F.Cu")
		(net "P5E_CPU0_P2_TX_C_DP<4>")
	)
	(segment
		(start 404.07209 -384.71475)
		(end 404.316438 -385.303776)
		(width 0.1016)
		(layer "F.Cu")
		(net "P5E_CPU0_P2_TX_C_DP<4>")
	)
	(segment
		(start 404.316438 -385.303776)
		(end 407.204418 -388.822438)
		(width 0.1016)
		(layer "F.Cu")
		(net "P5E_CPU0_P2_TX_C_DP<4>")
	)
	(arc
		(start 407.204418 -388.822438)
		(mid 407.451547 -389.364422)
		(end 407.536396 -389.954008)
		(width 0.1016)
		(layer "F.Cu")
		(net "P5E_CPU0_P2_TX_C_DP<4>")
	)
	(segment
		(start 403.574758 -386.446014)
		(end 406.217882 -389.666734)
		(width 0.1016)
		(layer "F.Cu")
		(net "P5E_CPU0_P2_TX_C_DP<3>")
	)
	(segment
		(start 402.040852 -381.676656)
		(end 402.040852 -381.67691)
		(width 0.1016)
		(layer "F.Cu")
		(net "P5E_CPU0_P2_TX_C_DP<3>")
	)
	(segment
		(start 406.336246 -391.324592)
		(end 406.043638 -391.6172)
		(width 0.1016)
		(layer "F.Cu")
		(net "P5E_CPU0_P2_TX_C_DP<3>")
	)
	(segment
		(start 403.30374 -385.99364)
		(end 403.574758 -386.446014)
		(width 0.1016)
		(layer "F.Cu")
		(net "P5E_CPU0_P2_TX_C_DP<3>")
	)
	(segment
		(start 406.336246 -389.99668)
		(end 406.336246 -391.324592)
		(width 0.1016)
		(layer "F.Cu")
		(net "P5E_CPU0_P2_TX_C_DP<3>")
	)
	(segment
		(start 406.043638 -391.6172)
		(end 406.043638 -391.88771)
		(width 0.1016)
		(layer "F.Cu")
		(net "P5E_CPU0_P2_TX_C_DP<3>")
	)
	(segment
		(start 400.66849 -379.56998)
		(end 400.66849 -379.95352)
		(width 0.1016)
		(layer "F.Cu")
		(net "P5E_CPU0_P2_TX_C_DP<3>")
	)
	(segment
		(start 406.345644 -391.902442)
		(end 406.345644 -391.784586)
		(width 0.1016)
		(layer "F.Cu")
		(net "P5E_CPU0_P2_TX_C_DP<3>")
	)
	(segment
		(start 402.040852 -381.67691)
		(end 402.301964 -381.938022)
		(width 0.1016)
		(layer "F.Cu")
		(net "P5E_CPU0_P2_TX_C_DP<3>")
	)
	(segment
		(start 402.378164 -382.120902)
		(end 402.378164 -383.585466)
		(width 0.1016)
		(layer "F.Cu")
		(net "P5E_CPU0_P2_TX_C_DP<3>")
	)
	(segment
		(start 406.134824 -391.978896)
		(end 406.26919 -391.978896)
		(width 0.1016)
		(layer "F.Cu")
		(net "P5E_CPU0_P2_TX_C_DP<3>")
	)
	(segment
		(start 402.443696 -383.916682)
		(end 403.30374 -385.99364)
		(width 0.1016)
		(layer "F.Cu")
		(net "P5E_CPU0_P2_TX_C_DP<3>")
	)
	(segment
		(start 400.91614 -380.552198)
		(end 402.040852 -381.676656)
		(width 0.1016)
		(layer "F.Cu")
		(net "P5E_CPU0_P2_TX_C_DP<3>")
	)
	(segment
		(start 400.31924 -379.22073)
		(end 400.66849 -379.56998)
		(width 0.1016)
		(layer "F.Cu")
		(net "P5E_CPU0_P2_TX_C_DP<3>")
	)
	(segment
		(start 406.26919 -391.978896)
		(end 406.345644 -391.902442)
		(width 0.1016)
		(layer "F.Cu")
		(net "P5E_CPU0_P2_TX_C_DP<3>")
	)
	(segment
		(start 406.043638 -391.88771)
		(end 406.134824 -391.978896)
		(width 0.1016)
		(layer "F.Cu")
		(net "P5E_CPU0_P2_TX_C_DP<3>")
	)
	(arc
		(start 406.217882 -389.666734)
		(mid 406.305739 -389.821418)
		(end 406.336246 -389.99668)
		(width 0.1016)
		(layer "F.Cu")
		(net "P5E_CPU0_P2_TX_C_DP<3>")
	)
	(arc
		(start 402.378164 -383.585466)
		(mid 402.394632 -383.754298)
		(end 402.443696 -383.916682)
		(width 0.1016)
		(layer "F.Cu")
		(net "P5E_CPU0_P2_TX_C_DP<3>")
	)
	(arc
		(start 402.301964 -381.938022)
		(mid 402.358302 -382.021869)
		(end 402.378164 -382.120902)
		(width 0.1016)
		(layer "F.Cu")
		(net "P5E_CPU0_P2_TX_C_DP<3>")
	)
	(arc
		(start 400.66849 -379.95352)
		(mid 400.732747 -380.277503)
		(end 400.91614 -380.552198)
		(width 0.1016)
		(layer "F.Cu")
		(net "P5E_CPU0_P2_TX_C_DP<3>")
	)
	(segment
		(start 405.145748 -391.902442)
		(end 405.145748 -391.784586)
		(width 0.1016)
		(layer "F.Cu")
		(net "P5E_CPU0_P2_TX_C_DP<2>")
	)
	(segment
		(start 404.934928 -391.978896)
		(end 405.069294 -391.978896)
		(width 0.1016)
		(layer "F.Cu")
		(net "P5E_CPU0_P2_TX_C_DP<2>")
	)
	(segment
		(start 398.96669 -382.03378)
		(end 398.96669 -382.664208)
		(width 0.1016)
		(layer "F.Cu")
		(net "P5E_CPU0_P2_TX_C_DP<2>")
	)
	(segment
		(start 402.33854 -386.807456)
		(end 402.481034 -387.044692)
		(width 0.1016)
		(layer "F.Cu")
		(net "P5E_CPU0_P2_TX_C_DP<2>")
	)
	(segment
		(start 401.616672 -385.064508)
		(end 402.33854 -386.807456)
		(width 0.1016)
		(layer "F.Cu")
		(net "P5E_CPU0_P2_TX_C_DP<2>")
	)
	(segment
		(start 404.843742 -391.88771)
		(end 404.934928 -391.978896)
		(width 0.1016)
		(layer "F.Cu")
		(net "P5E_CPU0_P2_TX_C_DP<2>")
	)
	(segment
		(start 402.75891 -387.439154)
		(end 404.965154 -390.124696)
		(width 0.1016)
		(layer "F.Cu")
		(net "P5E_CPU0_P2_TX_C_DP<2>")
	)
	(segment
		(start 405.069294 -391.978896)
		(end 405.145748 -391.902442)
		(width 0.1016)
		(layer "F.Cu")
		(net "P5E_CPU0_P2_TX_C_DP<2>")
	)
	(segment
		(start 405.13635 -390.60247)
		(end 405.13635 -391.324592)
		(width 0.1016)
		(layer "F.Cu")
		(net "P5E_CPU0_P2_TX_C_DP<2>")
	)
	(segment
		(start 400.6596 -384.029458)
		(end 401.459192 -384.82905)
		(width 0.1016)
		(layer "F.Cu")
		(net "P5E_CPU0_P2_TX_C_DP<2>")
	)
	(segment
		(start 404.843742 -391.6172)
		(end 404.843742 -391.88771)
		(width 0.1016)
		(layer "F.Cu")
		(net "P5E_CPU0_P2_TX_C_DP<2>")
	)
	(segment
		(start 398.61744 -381.68453)
		(end 398.96669 -382.03378)
		(width 0.1016)
		(layer "F.Cu")
		(net "P5E_CPU0_P2_TX_C_DP<2>")
	)
	(segment
		(start 405.13635 -391.324592)
		(end 404.843742 -391.6172)
		(width 0.1016)
		(layer "F.Cu")
		(net "P5E_CPU0_P2_TX_C_DP<2>")
	)
	(segment
		(start 399.693384 -383.6162)
		(end 400.608292 -383.995168)
		(width 0.1016)
		(layer "F.Cu")
		(net "P5E_CPU0_P2_TX_C_DP<2>")
	)
	(segment
		(start 399.2245 -383.286762)
		(end 399.272506 -383.334768)
		(width 0.1016)
		(layer "F.Cu")
		(net "P5E_CPU0_P2_TX_C_DP<2>")
	)
	(arc
		(start 401.459192 -384.82905)
		(mid 401.549554 -384.939008)
		(end 401.616672 -385.064508)
		(width 0.1016)
		(layer "F.Cu")
		(net "P5E_CPU0_P2_TX_C_DP<2>")
	)
	(arc
		(start 404.965154 -390.124696)
		(mid 405.092206 -390.348722)
		(end 405.13635 -390.60247)
		(width 0.1016)
		(layer "F.Cu")
		(net "P5E_CPU0_P2_TX_C_DP<2>")
	)
	(arc
		(start 399.272506 -383.334768)
		(mid 399.46909 -383.496205)
		(end 399.693384 -383.6162)
		(width 0.1016)
		(layer "F.Cu")
		(net "P5E_CPU0_P2_TX_C_DP<2>")
	)
	(arc
		(start 402.481034 -387.044692)
		(mid 402.612726 -387.247028)
		(end 402.75891 -387.439154)
		(width 0.1016)
		(layer "F.Cu")
		(net "P5E_CPU0_P2_TX_C_DP<2>")
	)
	(arc
		(start 400.608292 -383.995168)
		(mid 400.63564 -384.009779)
		(end 400.6596 -384.029458)
		(width 0.1016)
		(layer "F.Cu")
		(net "P5E_CPU0_P2_TX_C_DP<2>")
	)
	(arc
		(start 398.96669 -382.664208)
		(mid 399.033689 -383.001123)
		(end 399.2245 -383.286762)
		(width 0.1016)
		(layer "F.Cu")
		(net "P5E_CPU0_P2_TX_C_DP<2>")
	)
	(segment
		(start 401.560792 -387.500876)
		(end 401.718018 -387.736588)
		(width 0.1016)
		(layer "F.Cu")
		(net "P5E_CPU0_P2_TX_C_DP<1>")
	)
	(segment
		(start 399.189194 -384.652266)
		(end 399.316956 -384.652266)
		(width 0.1016)
		(layer "F.Cu")
		(net "P5E_CPU0_P2_TX_C_DP<1>")
	)
	(segment
		(start 402.011896 -388.176008)
		(end 402.011896 -388.176262)
		(width 0.1016)
		(layer "F.Cu")
		(net "P5E_CPU0_P2_TX_C_DP<1>")
	)
	(segment
		(start 400.306794 -385.061968)
		(end 400.63293 -385.388104)
		(width 0.1016)
		(layer "F.Cu")
		(net "P5E_CPU0_P2_TX_C_DP<1>")
	)
	(segment
		(start 398.861788 -384.32486)
		(end 399.189194 -384.652266)
		(width 0.1016)
		(layer "F.Cu")
		(net "P5E_CPU0_P2_TX_C_DP<1>")
	)
	(segment
		(start 404.245572 -391.612882)
		(end 404.245572 -392.30427)
		(width 0.1016)
		(layer "F.Cu")
		(net "P5E_CPU0_P2_TX_C_DP<1>")
	)
	(segment
		(start 403.885908 -390.358122)
		(end 404.02891 -390.59612)
		(width 0.1016)
		(layer "F.Cu")
		(net "P5E_CPU0_P2_TX_C_DP<1>")
	)
	(segment
		(start 400.773138 -385.598416)
		(end 401.560792 -387.500876)
		(width 0.1016)
		(layer "F.Cu")
		(net "P5E_CPU0_P2_TX_C_DP<1>")
	)
	(segment
		(start 402.857208 -389.104124)
		(end 403.885908 -390.358122)
		(width 0.1016)
		(layer "F.Cu")
		(net "P5E_CPU0_P2_TX_C_DP<1>")
	)
	(segment
		(start 404.02891 -390.59612)
		(end 404.1521 -390.893808)
		(width 0.1016)
		(layer "F.Cu")
		(net "P5E_CPU0_P2_TX_C_DP<1>")
	)
	(segment
		(start 402.011896 -388.176262)
		(end 402.125688 -388.346442)
		(width 0.1016)
		(layer "F.Cu")
		(net "P5E_CPU0_P2_TX_C_DP<1>")
	)
	(segment
		(start 401.718018 -387.736588)
		(end 401.718272 -387.736588)
		(width 0.1016)
		(layer "F.Cu")
		(net "P5E_CPU0_P2_TX_C_DP<1>")
	)
	(segment
		(start 404.1521 -390.893808)
		(end 404.1521 -391.51941)
		(width 0.1016)
		(layer "F.Cu")
		(net "P5E_CPU0_P2_TX_C_DP<1>")
	)
	(segment
		(start 404.1521 -391.51941)
		(end 404.245572 -391.612882)
		(width 0.1016)
		(layer "F.Cu")
		(net "P5E_CPU0_P2_TX_C_DP<1>")
	)
	(segment
		(start 402.246592 -388.493254)
		(end 402.857208 -389.104124)
		(width 0.1016)
		(layer "F.Cu")
		(net "P5E_CPU0_P2_TX_C_DP<1>")
	)
	(segment
		(start 401.718272 -387.736588)
		(end 402.011896 -388.176008)
		(width 0.1016)
		(layer "F.Cu")
		(net "P5E_CPU0_P2_TX_C_DP<1>")
	)
	(arc
		(start 399.316956 -384.652266)
		(mid 399.852644 -384.758634)
		(end 400.306794 -385.061968)
		(width 0.1016)
		(layer "F.Cu")
		(net "P5E_CPU0_P2_TX_C_DP<1>")
	)
	(arc
		(start 400.63293 -385.388104)
		(mid 400.713402 -385.486348)
		(end 400.773138 -385.598416)
		(width 0.1016)
		(layer "F.Cu")
		(net "P5E_CPU0_P2_TX_C_DP<1>")
	)
	(arc
		(start 402.125688 -388.346442)
		(mid 402.182534 -388.422818)
		(end 402.246592 -388.493254)
		(width 0.1016)
		(layer "F.Cu")
		(net "P5E_CPU0_P2_TX_C_DP<1>")
	)
	(segment
		(start 424.179238 -388.090918)
		(end 423.874438 -388.090918)
		(width 0.1016)
		(layer "F.Cu")
		(net "P5E_CPU0_P2_TX_C_DP<15>")
	)
	(segment
		(start 420.830248 -391.700004)
		(end 420.745666 -391.784586)
		(width 0.1016)
		(layer "F.Cu")
		(net "P5E_CPU0_P2_TX_C_DP<15>")
	)
	(segment
		(start 424.290998 -388.202678)
		(end 424.179238 -388.090918)
		(width 0.1016)
		(layer "F.Cu")
		(net "P5E_CPU0_P2_TX_C_DP<15>")
	)
	(segment
		(start 423.762678 -388.202678)
		(end 423.047922 -388.202678)
		(width 0.1016)
		(layer "F.Cu")
		(net "P5E_CPU0_P2_TX_C_DP<15>")
	)
	(segment
		(start 422.793922 -388.30758)
		(end 420.892986 -390.208516)
		(width 0.1016)
		(layer "F.Cu")
		(net "P5E_CPU0_P2_TX_C_DP<15>")
	)
	(segment
		(start 420.830248 -391.492232)
		(end 420.830248 -391.700004)
		(width 0.1016)
		(layer "F.Cu")
		(net "P5E_CPU0_P2_TX_C_DP<15>")
	)
	(segment
		(start 420.736268 -390.587484)
		(end 420.736268 -391.398252)
		(width 0.1016)
		(layer "F.Cu")
		(net "P5E_CPU0_P2_TX_C_DP<15>")
	)
	(segment
		(start 425.10202 -387.853428)
		(end 424.75277 -388.202678)
		(width 0.1016)
		(layer "F.Cu")
		(net "P5E_CPU0_P2_TX_C_DP<15>")
	)
	(segment
		(start 424.75277 -388.202678)
		(end 424.290998 -388.202678)
		(width 0.1016)
		(layer "F.Cu")
		(net "P5E_CPU0_P2_TX_C_DP<15>")
	)
	(segment
		(start 420.736268 -391.398252)
		(end 420.830248 -391.492232)
		(width 0.1016)
		(layer "F.Cu")
		(net "P5E_CPU0_P2_TX_C_DP<15>")
	)
	(segment
		(start 423.874438 -388.090918)
		(end 423.762678 -388.202678)
		(width 0.1016)
		(layer "F.Cu")
		(net "P5E_CPU0_P2_TX_C_DP<15>")
	)
	(arc
		(start 423.047922 -388.202678)
		(mid 422.910469 -388.229832)
		(end 422.793922 -388.30758)
		(width 0.1016)
		(layer "F.Cu")
		(net "P5E_CPU0_P2_TX_C_DP<15>")
	)
	(arc
		(start 420.892986 -390.208516)
		(mid 420.776921 -390.382404)
		(end 420.736268 -390.587484)
		(width 0.1016)
		(layer "F.Cu")
		(net "P5E_CPU0_P2_TX_C_DP<15>")
	)
	(segment
		(start 425.10202 -384.449828)
		(end 424.666918 -384.88493)
		(width 0.1016)
		(layer "F.Cu")
		(net "P5E_CPU0_P2_TX_C_DP<14>")
	)
	(segment
		(start 419.536372 -391.398252)
		(end 419.630352 -391.492232)
		(width 0.1016)
		(layer "F.Cu")
		(net "P5E_CPU0_P2_TX_C_DP<14>")
	)
	(segment
		(start 419.536372 -390.071102)
		(end 419.536372 -391.398252)
		(width 0.1016)
		(layer "F.Cu")
		(net "P5E_CPU0_P2_TX_C_DP<14>")
	)
	(segment
		(start 419.630352 -391.492232)
		(end 419.630352 -391.700004)
		(width 0.1016)
		(layer "F.Cu")
		(net "P5E_CPU0_P2_TX_C_DP<14>")
	)
	(segment
		(start 424.35272 -384.88493)
		(end 419.79723 -389.44042)
		(width 0.1016)
		(layer "F.Cu")
		(net "P5E_CPU0_P2_TX_C_DP<14>")
	)
	(segment
		(start 419.630352 -391.700004)
		(end 419.54577 -391.784586)
		(width 0.1016)
		(layer "F.Cu")
		(net "P5E_CPU0_P2_TX_C_DP<14>")
	)
	(segment
		(start 424.666918 -384.88493)
		(end 424.35272 -384.88493)
		(width 0.1016)
		(layer "F.Cu")
		(net "P5E_CPU0_P2_TX_C_DP<14>")
	)
	(arc
		(start 419.79723 -389.44042)
		(mid 419.604106 -389.729824)
		(end 419.536372 -390.071102)
		(width 0.1016)
		(layer "F.Cu")
		(net "P5E_CPU0_P2_TX_C_DP<14>")
	)
	(segment
		(start 425.995084 -382.93548)
		(end 425.569634 -383.36093)
		(width 0.1016)
		(layer "F.Cu")
		(net "P5E_CPU0_P2_TX_C_DP<13>")
	)
	(segment
		(start 418.34562 -391.902442)
		(end 418.34562 -391.784586)
		(width 0.1016)
		(layer "F.Cu")
		(net "P5E_CPU0_P2_TX_C_DP<13>")
	)
	(segment
		(start 425.284646 -383.47904)
		(end 424.403774 -383.47904)
		(width 0.1016)
		(layer "F.Cu")
		(net "P5E_CPU0_P2_TX_C_DP<13>")
	)
	(segment
		(start 424.14444 -379.22073)
		(end 424.49369 -379.56998)
		(width 0.1016)
		(layer "F.Cu")
		(net "P5E_CPU0_P2_TX_C_DP<13>")
	)
	(segment
		(start 418.043614 -391.88771)
		(end 418.1348 -391.978896)
		(width 0.1016)
		(layer "F.Cu")
		(net "P5E_CPU0_P2_TX_C_DP<13>")
	)
	(segment
		(start 424.49369 -379.56998)
		(end 424.49369 -379.909578)
		(width 0.1016)
		(layer "F.Cu")
		(net "P5E_CPU0_P2_TX_C_DP<13>")
	)
	(segment
		(start 418.336222 -391.324592)
		(end 418.043614 -391.6172)
		(width 0.1016)
		(layer "F.Cu")
		(net "P5E_CPU0_P2_TX_C_DP<13>")
	)
	(segment
		(start 423.83329 -383.715006)
		(end 418.436552 -389.111744)
		(width 0.1016)
		(layer "F.Cu")
		(net "P5E_CPU0_P2_TX_C_DP<13>")
	)
	(segment
		(start 418.043614 -391.6172)
		(end 418.043614 -391.88771)
		(width 0.1016)
		(layer "F.Cu")
		(net "P5E_CPU0_P2_TX_C_DP<13>")
	)
	(segment
		(start 418.1348 -391.978896)
		(end 418.269166 -391.978896)
		(width 0.1016)
		(layer "F.Cu")
		(net "P5E_CPU0_P2_TX_C_DP<13>")
	)
	(segment
		(start 418.269166 -391.978896)
		(end 418.34562 -391.902442)
		(width 0.1016)
		(layer "F.Cu")
		(net "P5E_CPU0_P2_TX_C_DP<13>")
	)
	(segment
		(start 418.336222 -389.354822)
		(end 418.336222 -391.324592)
		(width 0.1016)
		(layer "F.Cu")
		(net "P5E_CPU0_P2_TX_C_DP<13>")
	)
	(segment
		(start 424.80865 -380.670816)
		(end 426.013372 -381.875538)
		(width 0.1016)
		(layer "F.Cu")
		(net "P5E_CPU0_P2_TX_C_DP<13>")
	)
	(segment
		(start 426.167804 -382.248156)
		(end 426.167804 -382.518666)
		(width 0.1016)
		(layer "F.Cu")
		(net "P5E_CPU0_P2_TX_C_DP<13>")
	)
	(arc
		(start 425.569634 -383.36093)
		(mid 425.438895 -383.44835)
		(end 425.284646 -383.47904)
		(width 0.1016)
		(layer "F.Cu")
		(net "P5E_CPU0_P2_TX_C_DP<13>")
	)
	(arc
		(start 426.167804 -382.518666)
		(mid 426.122913 -382.744257)
		(end 425.995084 -382.93548)
		(width 0.1016)
		(layer "F.Cu")
		(net "P5E_CPU0_P2_TX_C_DP<13>")
	)
	(arc
		(start 424.49369 -379.909578)
		(mid 424.57543 -380.321543)
		(end 424.80865 -380.670816)
		(width 0.1016)
		(layer "F.Cu")
		(net "P5E_CPU0_P2_TX_C_DP<13>")
	)
	(arc
		(start 426.013372 -381.875538)
		(mid 426.127657 -382.046482)
		(end 426.167804 -382.248156)
		(width 0.1016)
		(layer "F.Cu")
		(net "P5E_CPU0_P2_TX_C_DP<13>")
	)
	(arc
		(start 424.403774 -383.47904)
		(mid 424.095037 -383.540246)
		(end 423.83329 -383.715006)
		(width 0.1016)
		(layer "F.Cu")
		(net "P5E_CPU0_P2_TX_C_DP<13>")
	)
	(arc
		(start 418.436552 -389.111744)
		(mid 418.362253 -389.223313)
		(end 418.336222 -389.354822)
		(width 0.1016)
		(layer "F.Cu")
		(net "P5E_CPU0_P2_TX_C_DP<13>")
	)
	(segment
		(start 417.145724 -391.902442)
		(end 417.145724 -391.784586)
		(width 0.1016)
		(layer "F.Cu")
		(net "P5E_CPU0_P2_TX_C_DP<12>")
	)
	(segment
		(start 421.09009 -379.56998)
		(end 421.09009 -379.9205)
		(width 0.1016)
		(layer "F.Cu")
		(net "P5E_CPU0_P2_TX_C_DP<12>")
	)
	(segment
		(start 422.72712 -383.119376)
		(end 417.423346 -388.42315)
		(width 0.1016)
		(layer "F.Cu")
		(net "P5E_CPU0_P2_TX_C_DP<12>")
	)
	(segment
		(start 421.342312 -380.529338)
		(end 422.762426 -381.949198)
		(width 0.1016)
		(layer "F.Cu")
		(net "P5E_CPU0_P2_TX_C_DP<12>")
	)
	(segment
		(start 417.136326 -389.116062)
		(end 417.136326 -391.324592)
		(width 0.1016)
		(layer "F.Cu")
		(net "P5E_CPU0_P2_TX_C_DP<12>")
	)
	(segment
		(start 417.06927 -391.978896)
		(end 417.145724 -391.902442)
		(width 0.1016)
		(layer "F.Cu")
		(net "P5E_CPU0_P2_TX_C_DP<12>")
	)
	(segment
		(start 422.799764 -382.039368)
		(end 422.799764 -382.944878)
		(width 0.1016)
		(layer "F.Cu")
		(net "P5E_CPU0_P2_TX_C_DP<12>")
	)
	(segment
		(start 416.843718 -391.88771)
		(end 416.934904 -391.978896)
		(width 0.1016)
		(layer "F.Cu")
		(net "P5E_CPU0_P2_TX_C_DP<12>")
	)
	(segment
		(start 420.74084 -379.22073)
		(end 421.09009 -379.56998)
		(width 0.1016)
		(layer "F.Cu")
		(net "P5E_CPU0_P2_TX_C_DP<12>")
	)
	(segment
		(start 416.934904 -391.978896)
		(end 417.06927 -391.978896)
		(width 0.1016)
		(layer "F.Cu")
		(net "P5E_CPU0_P2_TX_C_DP<12>")
	)
	(segment
		(start 416.843718 -391.6172)
		(end 416.843718 -391.88771)
		(width 0.1016)
		(layer "F.Cu")
		(net "P5E_CPU0_P2_TX_C_DP<12>")
	)
	(segment
		(start 417.136326 -391.324592)
		(end 416.843718 -391.6172)
		(width 0.1016)
		(layer "F.Cu")
		(net "P5E_CPU0_P2_TX_C_DP<12>")
	)
	(arc
		(start 421.09009 -379.9205)
		(mid 421.155634 -380.250013)
		(end 421.342312 -380.529338)
		(width 0.1016)
		(layer "F.Cu")
		(net "P5E_CPU0_P2_TX_C_DP<12>")
	)
	(arc
		(start 417.423346 -388.42315)
		(mid 417.210925 -388.741061)
		(end 417.136326 -389.116062)
		(width 0.1016)
		(layer "F.Cu")
		(net "P5E_CPU0_P2_TX_C_DP<12>")
	)
	(arc
		(start 422.762426 -381.949198)
		(mid 422.790069 -381.990568)
		(end 422.799764 -382.039368)
		(width 0.1016)
		(layer "F.Cu")
		(net "P5E_CPU0_P2_TX_C_DP<12>")
	)
	(arc
		(start 422.799764 -382.944878)
		(mid 422.78077 -383.039333)
		(end 422.72712 -383.119376)
		(width 0.1016)
		(layer "F.Cu")
		(net "P5E_CPU0_P2_TX_C_DP<12>")
	)
	(segment
		(start 415.643568 -391.88771)
		(end 415.734754 -391.978896)
		(width 0.1016)
		(layer "F.Cu")
		(net "P5E_CPU0_P2_TX_C_DP<11>")
	)
	(segment
		(start 415.734754 -391.978896)
		(end 415.86912 -391.978896)
		(width 0.1016)
		(layer "F.Cu")
		(net "P5E_CPU0_P2_TX_C_DP<11>")
	)
	(segment
		(start 415.936176 -388.266178)
		(end 415.936176 -391.324592)
		(width 0.1016)
		(layer "F.Cu")
		(net "P5E_CPU0_P2_TX_C_DP<11>")
	)
	(segment
		(start 419.350952 -384.708654)
		(end 416.03549 -388.024116)
		(width 0.1016)
		(layer "F.Cu")
		(net "P5E_CPU0_P2_TX_C_DP<11>")
	)
	(segment
		(start 415.643568 -391.6172)
		(end 415.643568 -391.88771)
		(width 0.1016)
		(layer "F.Cu")
		(net "P5E_CPU0_P2_TX_C_DP<11>")
	)
	(segment
		(start 415.945574 -391.902442)
		(end 415.945574 -391.784586)
		(width 0.1016)
		(layer "F.Cu")
		(net "P5E_CPU0_P2_TX_C_DP<11>")
	)
	(segment
		(start 415.936176 -391.324592)
		(end 415.643568 -391.6172)
		(width 0.1016)
		(layer "F.Cu")
		(net "P5E_CPU0_P2_TX_C_DP<11>")
	)
	(segment
		(start 419.38829 -382.03378)
		(end 419.38829 -384.618484)
		(width 0.1016)
		(layer "F.Cu")
		(net "P5E_CPU0_P2_TX_C_DP<11>")
	)
	(segment
		(start 415.86912 -391.978896)
		(end 415.945574 -391.902442)
		(width 0.1016)
		(layer "F.Cu")
		(net "P5E_CPU0_P2_TX_C_DP<11>")
	)
	(segment
		(start 419.03904 -381.68453)
		(end 419.38829 -382.03378)
		(width 0.1016)
		(layer "F.Cu")
		(net "P5E_CPU0_P2_TX_C_DP<11>")
	)
	(arc
		(start 419.38829 -384.618484)
		(mid 419.378584 -384.667279)
		(end 419.350952 -384.708654)
		(width 0.1016)
		(layer "F.Cu")
		(net "P5E_CPU0_P2_TX_C_DP<11>")
	)
	(arc
		(start 416.03549 -388.024116)
		(mid 415.961929 -388.135332)
		(end 415.936176 -388.266178)
		(width 0.1016)
		(layer "F.Cu")
		(net "P5E_CPU0_P2_TX_C_DP<11>")
	)
	(segment
		(start 415.01568 -386.86486)
		(end 415.015426 -386.86486)
		(width 0.1016)
		(layer "F.Cu")
		(net "P5E_CPU0_P2_TX_C_DP<10>")
	)
	(segment
		(start 415.015426 -386.86486)
		(end 414.83661 -387.043676)
		(width 0.1016)
		(layer "F.Cu")
		(net "P5E_CPU0_P2_TX_C_DP<10>")
	)
	(segment
		(start 414.443672 -391.6172)
		(end 414.443672 -391.88771)
		(width 0.1016)
		(layer "F.Cu")
		(net "P5E_CPU0_P2_TX_C_DP<10>")
	)
	(segment
		(start 416.55238 -385.703572)
		(end 416.329622 -385.703572)
		(width 0.1016)
		(layer "F.Cu")
		(net "P5E_CPU0_P2_TX_C_DP<10>")
	)
	(segment
		(start 414.73628 -391.324592)
		(end 414.443672 -391.6172)
		(width 0.1016)
		(layer "F.Cu")
		(net "P5E_CPU0_P2_TX_C_DP<10>")
	)
	(segment
		(start 417.648136 -384.674872)
		(end 416.66668 -385.656328)
		(width 0.1016)
		(layer "F.Cu")
		(net "P5E_CPU0_P2_TX_C_DP<10>")
	)
	(segment
		(start 414.443672 -391.88771)
		(end 414.534858 -391.978896)
		(width 0.1016)
		(layer "F.Cu")
		(net "P5E_CPU0_P2_TX_C_DP<10>")
	)
	(segment
		(start 414.73628 -387.286754)
		(end 414.73628 -391.324592)
		(width 0.1016)
		(layer "F.Cu")
		(net "P5E_CPU0_P2_TX_C_DP<10>")
	)
	(segment
		(start 414.534858 -391.978896)
		(end 414.669224 -391.978896)
		(width 0.1016)
		(layer "F.Cu")
		(net "P5E_CPU0_P2_TX_C_DP<10>")
	)
	(segment
		(start 414.745678 -391.902442)
		(end 414.745678 -391.784586)
		(width 0.1016)
		(layer "F.Cu")
		(net "P5E_CPU0_P2_TX_C_DP<10>")
	)
	(segment
		(start 416.069018 -385.811522)
		(end 415.01568 -386.86486)
		(width 0.1016)
		(layer "F.Cu")
		(net "P5E_CPU0_P2_TX_C_DP<10>")
	)
	(segment
		(start 414.669224 -391.978896)
		(end 414.745678 -391.902442)
		(width 0.1016)
		(layer "F.Cu")
		(net "P5E_CPU0_P2_TX_C_DP<10>")
	)
	(segment
		(start 417.685474 -384.496564)
		(end 417.685474 -384.584702)
		(width 0.1016)
		(layer "F.Cu")
		(net "P5E_CPU0_P2_TX_C_DP<10>")
	)
	(segment
		(start 417.33724 -384.14833)
		(end 417.685474 -384.496564)
		(width 0.1016)
		(layer "F.Cu")
		(net "P5E_CPU0_P2_TX_C_DP<10>")
	)
	(arc
		(start 416.329622 -385.703572)
		(mid 416.188582 -385.731627)
		(end 416.069018 -385.811522)
		(width 0.1016)
		(layer "F.Cu")
		(net "P5E_CPU0_P2_TX_C_DP<10>")
	)
	(arc
		(start 414.83661 -387.043676)
		(mid 414.762311 -387.155245)
		(end 414.73628 -387.286754)
		(width 0.1016)
		(layer "F.Cu")
		(net "P5E_CPU0_P2_TX_C_DP<10>")
	)
	(arc
		(start 416.66668 -385.656328)
		(mid 416.614225 -385.691315)
		(end 416.55238 -385.703572)
		(width 0.1016)
		(layer "F.Cu")
		(net "P5E_CPU0_P2_TX_C_DP<10>")
	)
	(arc
		(start 417.685474 -384.584702)
		(mid 417.675768 -384.633497)
		(end 417.648136 -384.674872)
		(width 0.1016)
		(layer "F.Cu")
		(net "P5E_CPU0_P2_TX_C_DP<10>")
	)
	(segment
		(start 402.443696 -391.88771)
		(end 402.534882 -391.978896)
		(width 0.1016)
		(layer "F.Cu")
		(net "P5E_CPU0_P2_TX_C_DP<0>")
	)
	(segment
		(start 399.629376 -390.537192)
		(end 399.934176 -390.537192)
		(width 0.1016)
		(layer "F.Cu")
		(net "P5E_CPU0_P2_TX_C_DP<0>")
	)
	(segment
		(start 402.736304 -391.199624)
		(end 402.736304 -391.324592)
		(width 0.1016)
		(layer "F.Cu")
		(net "P5E_CPU0_P2_TX_C_DP<0>")
	)
	(segment
		(start 400.879056 -390.425432)
		(end 401.380198 -390.425432)
		(width 0.1016)
		(layer "F.Cu")
		(net "P5E_CPU0_P2_TX_C_DP<0>")
	)
	(segment
		(start 400.767296 -390.537192)
		(end 400.879056 -390.425432)
		(width 0.1016)
		(layer "F.Cu")
		(net "P5E_CPU0_P2_TX_C_DP<0>")
	)
	(segment
		(start 401.578064 -390.464802)
		(end 402.183346 -390.714738)
		(width 0.1016)
		(layer "F.Cu")
		(net "P5E_CPU0_P2_TX_C_DP<0>")
	)
	(segment
		(start 402.443696 -391.6172)
		(end 402.443696 -391.88771)
		(width 0.1016)
		(layer "F.Cu")
		(net "P5E_CPU0_P2_TX_C_DP<0>")
	)
	(segment
		(start 398.861788 -390.77646)
		(end 399.212816 -390.425432)
		(width 0.1016)
		(layer "F.Cu")
		(net "P5E_CPU0_P2_TX_C_DP<0>")
	)
	(segment
		(start 399.517616 -390.425432)
		(end 399.629376 -390.537192)
		(width 0.1016)
		(layer "F.Cu")
		(net "P5E_CPU0_P2_TX_C_DP<0>")
	)
	(segment
		(start 400.462496 -390.537192)
		(end 400.767296 -390.537192)
		(width 0.1016)
		(layer "F.Cu")
		(net "P5E_CPU0_P2_TX_C_DP<0>")
	)
	(segment
		(start 402.736304 -391.324592)
		(end 402.443696 -391.6172)
		(width 0.1016)
		(layer "F.Cu")
		(net "P5E_CPU0_P2_TX_C_DP<0>")
	)
	(segment
		(start 399.212816 -390.425432)
		(end 399.517616 -390.425432)
		(width 0.1016)
		(layer "F.Cu")
		(net "P5E_CPU0_P2_TX_C_DP<0>")
	)
	(segment
		(start 402.669248 -391.978896)
		(end 402.745702 -391.902442)
		(width 0.1016)
		(layer "F.Cu")
		(net "P5E_CPU0_P2_TX_C_DP<0>")
	)
	(segment
		(start 400.045936 -390.425432)
		(end 400.350736 -390.425432)
		(width 0.1016)
		(layer "F.Cu")
		(net "P5E_CPU0_P2_TX_C_DP<0>")
	)
	(segment
		(start 402.745702 -391.902442)
		(end 402.745702 -391.784586)
		(width 0.1016)
		(layer "F.Cu")
		(net "P5E_CPU0_P2_TX_C_DP<0>")
	)
	(segment
		(start 402.534882 -391.978896)
		(end 402.669248 -391.978896)
		(width 0.1016)
		(layer "F.Cu")
		(net "P5E_CPU0_P2_TX_C_DP<0>")
	)
	(segment
		(start 400.350736 -390.425432)
		(end 400.462496 -390.537192)
		(width 0.1016)
		(layer "F.Cu")
		(net "P5E_CPU0_P2_TX_C_DP<0>")
	)
	(segment
		(start 399.934176 -390.537192)
		(end 400.045936 -390.425432)
		(width 0.1016)
		(layer "F.Cu")
		(net "P5E_CPU0_P2_TX_C_DP<0>")
	)
	(segment
		(start 402.394928 -390.85647)
		(end 402.736304 -391.199624)
		(width 0.1016)
		(layer "F.Cu")
		(net "P5E_CPU0_P2_TX_C_DP<0>")
	)
	(arc
		(start 402.183346 -390.714738)
		(mid 402.296177 -390.775093)
		(end 402.394928 -390.85647)
		(width 0.1016)
		(layer "F.Cu")
		(net "P5E_CPU0_P2_TX_C_DP<0>")
	)
	(arc
		(start 401.380198 -390.425432)
		(mid 401.481063 -390.435399)
		(end 401.578064 -390.464802)
		(width 0.1016)
		(layer "F.Cu")
		(net "P5E_CPU0_P2_TX_C_DP<0>")
	)
	(segment
		(start 416.177222 -382.315466)
		(end 416.177222 -383.376932)
		(width 0.1016)
		(layer "F.Cu")
		(net "P5E_CPU0_P2_TX_C_DN<9>")
	)
	(segment
		(start 414.751266 -380.518162)
		(end 415.914332 -381.681228)
		(width 0.1016)
		(layer "F.Cu")
		(net "P5E_CPU0_P2_TX_C_DN<9>")
	)
	(segment
		(start 414.96615 -384.935984)
		(end 414.808162 -384.935984)
		(width 0.1016)
		(layer "F.Cu")
		(net "P5E_CPU0_P2_TX_C_DN<9>")
	)
	(segment
		(start 413.752284 -391.51941)
		(end 413.845756 -391.612882)
		(width 0.1016)
		(layer "F.Cu")
		(net "P5E_CPU0_P2_TX_C_DN<9>")
	)
	(segment
		(start 414.84804 -379.22073)
		(end 414.49879 -379.56998)
		(width 0.1016)
		(layer "F.Cu")
		(net "P5E_CPU0_P2_TX_C_DN<9>")
	)
	(segment
		(start 415.18205 -384.720084)
		(end 414.96615 -384.935984)
		(width 0.1016)
		(layer "F.Cu")
		(net "P5E_CPU0_P2_TX_C_DN<9>")
	)
	(segment
		(start 414.808162 -384.935984)
		(end 413.833056 -385.91109)
		(width 0.1016)
		(layer "F.Cu")
		(net "P5E_CPU0_P2_TX_C_DN<9>")
	)
	(segment
		(start 414.49879 -379.56998)
		(end 414.49879 -379.909324)
		(width 0.1016)
		(layer "F.Cu")
		(net "P5E_CPU0_P2_TX_C_DN<9>")
	)
	(segment
		(start 416.042856 -383.70129)
		(end 415.18205 -384.562096)
		(width 0.1016)
		(layer "F.Cu")
		(net "P5E_CPU0_P2_TX_C_DN<9>")
	)
	(segment
		(start 415.18205 -384.562096)
		(end 415.18205 -384.720084)
		(width 0.1016)
		(layer "F.Cu")
		(net "P5E_CPU0_P2_TX_C_DN<9>")
	)
	(segment
		(start 413.845756 -391.612882)
		(end 413.845756 -392.30427)
		(width 0.1016)
		(layer "F.Cu")
		(net "P5E_CPU0_P2_TX_C_DN<9>")
	)
	(segment
		(start 413.752284 -386.105908)
		(end 413.752284 -391.51941)
		(width 0.1016)
		(layer "F.Cu")
		(net "P5E_CPU0_P2_TX_C_DN<9>")
	)
	(arc
		(start 413.833056 -385.91109)
		(mid 413.773278 -386.000459)
		(end 413.752284 -386.105908)
		(width 0.1016)
		(layer "F.Cu")
		(net "P5E_CPU0_P2_TX_C_DN<9>")
	)
	(arc
		(start 414.49879 -379.909324)
		(mid 414.56452 -380.238827)
		(end 414.751266 -380.518162)
		(width 0.1016)
		(layer "F.Cu")
		(net "P5E_CPU0_P2_TX_C_DN<9>")
	)
	(arc
		(start 415.914332 -381.681228)
		(mid 416.108849 -381.972204)
		(end 416.177222 -382.315466)
		(width 0.1016)
		(layer "F.Cu")
		(net "P5E_CPU0_P2_TX_C_DN<9>")
	)
	(arc
		(start 416.177222 -383.376932)
		(mid 416.142304 -383.552478)
		(end 416.042856 -383.70129)
		(width 0.1016)
		(layer "F.Cu")
		(net "P5E_CPU0_P2_TX_C_DN<9>")
	)
	(segment
		(start 412.90875 -383.6416)
		(end 412.79699 -383.75336)
		(width 0.1016)
		(layer "F.Cu")
		(net "P5E_CPU0_P2_TX_C_DN<8>")
	)
	(segment
		(start 412.90875 -383.3368)
		(end 412.90875 -383.6416)
		(width 0.1016)
		(layer "F.Cu")
		(net "P5E_CPU0_P2_TX_C_DN<8>")
	)
	(segment
		(start 412.645606 -391.612882)
		(end 412.645606 -392.30427)
		(width 0.1016)
		(layer "F.Cu")
		(net "P5E_CPU0_P2_TX_C_DN<8>")
	)
	(segment
		(start 412.79699 -382.10109)
		(end 412.79699 -383.22504)
		(width 0.1016)
		(layer "F.Cu")
		(net "P5E_CPU0_P2_TX_C_DN<8>")
	)
	(segment
		(start 412.79699 -383.75336)
		(end 412.79699 -384.998976)
		(width 0.1016)
		(layer "F.Cu")
		(net "P5E_CPU0_P2_TX_C_DN<8>")
	)
	(segment
		(start 412.552134 -385.700016)
		(end 412.552134 -391.51941)
		(width 0.1016)
		(layer "F.Cu")
		(net "P5E_CPU0_P2_TX_C_DN<8>")
	)
	(segment
		(start 412.79699 -383.22504)
		(end 412.90875 -383.3368)
		(width 0.1016)
		(layer "F.Cu")
		(net "P5E_CPU0_P2_TX_C_DN<8>")
	)
	(segment
		(start 412.552134 -391.51941)
		(end 412.645606 -391.612882)
		(width 0.1016)
		(layer "F.Cu")
		(net "P5E_CPU0_P2_TX_C_DN<8>")
	)
	(segment
		(start 413.14624 -381.68453)
		(end 412.844488 -381.986282)
		(width 0.1016)
		(layer "F.Cu")
		(net "P5E_CPU0_P2_TX_C_DN<8>")
	)
	(arc
		(start 412.591504 -385.512818)
		(mid 412.56204 -385.604364)
		(end 412.552134 -385.700016)
		(width 0.1016)
		(layer "F.Cu")
		(net "P5E_CPU0_P2_TX_C_DN<8>")
	)
	(arc
		(start 412.656782 -385.404106)
		(mid 412.620718 -385.456405)
		(end 412.591504 -385.512818)
		(width 0.1016)
		(layer "F.Cu")
		(net "P5E_CPU0_P2_TX_C_DN<8>")
	)
	(arc
		(start 412.844488 -381.986282)
		(mid 412.809346 -382.038971)
		(end 412.79699 -382.10109)
		(width 0.1016)
		(layer "F.Cu")
		(net "P5E_CPU0_P2_TX_C_DN<8>")
	)
	(arc
		(start 412.79699 -384.998976)
		(mid 412.760993 -385.213347)
		(end 412.656782 -385.404106)
		(width 0.1016)
		(layer "F.Cu")
		(net "P5E_CPU0_P2_TX_C_DN<8>")
	)
	(segment
		(start 411.09519 -384.564636)
		(end 411.09519 -385.45643)
		(width 0.1016)
		(layer "F.Cu")
		(net "P5E_CPU0_P2_TX_C_DN<7>")
	)
	(segment
		(start 411.352238 -391.32383)
		(end 411.352238 -391.51941)
		(width 0.1016)
		(layer "F.Cu")
		(net "P5E_CPU0_P2_TX_C_DN<7>")
	)
	(segment
		(start 411.20695 -385.56819)
		(end 411.20695 -385.87299)
		(width 0.1016)
		(layer "F.Cu")
		(net "P5E_CPU0_P2_TX_C_DN<7>")
	)
	(segment
		(start 411.44571 -391.612882)
		(end 411.44571 -392.30427)
		(width 0.1016)
		(layer "F.Cu")
		(net "P5E_CPU0_P2_TX_C_DN<7>")
	)
	(segment
		(start 411.352238 -391.51941)
		(end 411.44571 -391.612882)
		(width 0.1016)
		(layer "F.Cu")
		(net "P5E_CPU0_P2_TX_C_DN<7>")
	)
	(segment
		(start 411.09519 -385.45643)
		(end 411.20695 -385.56819)
		(width 0.1016)
		(layer "F.Cu")
		(net "P5E_CPU0_P2_TX_C_DN<7>")
	)
	(segment
		(start 411.44444 -384.14833)
		(end 411.142434 -384.450336)
		(width 0.1016)
		(layer "F.Cu")
		(net "P5E_CPU0_P2_TX_C_DN<7>")
	)
	(segment
		(start 411.20695 -385.87299)
		(end 411.09519 -385.98475)
		(width 0.1016)
		(layer "F.Cu")
		(net "P5E_CPU0_P2_TX_C_DN<7>")
	)
	(segment
		(start 411.09519 -385.98475)
		(end 411.09519 -386.28955)
		(width 0.1016)
		(layer "F.Cu")
		(net "P5E_CPU0_P2_TX_C_DN<7>")
	)
	(segment
		(start 411.334458 -387.0452)
		(end 411.352238 -391.32383)
		(width 0.1016)
		(layer "F.Cu")
		(net "P5E_CPU0_P2_TX_C_DN<7>")
	)
	(arc
		(start 411.21457 -386.668518)
		(mid 411.303269 -386.847706)
		(end 411.334458 -387.0452)
		(width 0.1016)
		(layer "F.Cu")
		(net "P5E_CPU0_P2_TX_C_DN<7>")
	)
	(arc
		(start 411.09519 -386.28955)
		(mid 411.125732 -386.488219)
		(end 411.21457 -386.668518)
		(width 0.1016)
		(layer "F.Cu")
		(net "P5E_CPU0_P2_TX_C_DN<7>")
	)
	(arc
		(start 411.142434 -384.450336)
		(mid 411.107447 -384.502791)
		(end 411.09519 -384.564636)
		(width 0.1016)
		(layer "F.Cu")
		(net "P5E_CPU0_P2_TX_C_DN<7>")
	)
	(segment
		(start 409.537154 -387.034278)
		(end 409.57373 -387.124194)
		(width 0.1016)
		(layer "F.Cu")
		(net "P5E_CPU0_P2_TX_C_DN<6>")
	)
	(segment
		(start 407.69159 -379.56998)
		(end 407.69159 -379.861826)
		(width 0.1016)
		(layer "F.Cu")
		(net "P5E_CPU0_P2_TX_C_DN<6>")
	)
	(segment
		(start 409.522676 -383.647696)
		(end 409.410916 -383.759456)
		(width 0.1016)
		(layer "F.Cu")
		(net "P5E_CPU0_P2_TX_C_DN<6>")
	)
	(segment
		(start 409.522676 -383.342896)
		(end 409.522676 -383.647696)
		(width 0.1016)
		(layer "F.Cu")
		(net "P5E_CPU0_P2_TX_C_DN<6>")
	)
	(segment
		(start 409.410916 -382.26873)
		(end 409.410916 -383.231136)
		(width 0.1016)
		(layer "F.Cu")
		(net "P5E_CPU0_P2_TX_C_DN<6>")
	)
	(segment
		(start 410.152088 -390.076182)
		(end 410.152088 -391.51941)
		(width 0.1016)
		(layer "F.Cu")
		(net "P5E_CPU0_P2_TX_C_DN<6>")
	)
	(segment
		(start 409.410916 -383.231136)
		(end 409.522676 -383.342896)
		(width 0.1016)
		(layer "F.Cu")
		(net "P5E_CPU0_P2_TX_C_DN<6>")
	)
	(segment
		(start 409.410916 -383.759456)
		(end 409.410916 -386.388356)
		(width 0.1016)
		(layer "F.Cu")
		(net "P5E_CPU0_P2_TX_C_DN<6>")
	)
	(segment
		(start 407.954988 -380.496826)
		(end 409.187396 -381.729234)
		(width 0.1016)
		(layer "F.Cu")
		(net "P5E_CPU0_P2_TX_C_DN<6>")
	)
	(segment
		(start 410.152088 -391.51941)
		(end 410.245814 -391.613136)
		(width 0.1016)
		(layer "F.Cu")
		(net "P5E_CPU0_P2_TX_C_DN<6>")
	)
	(segment
		(start 408.04084 -379.22073)
		(end 407.69159 -379.56998)
		(width 0.1016)
		(layer "F.Cu")
		(net "P5E_CPU0_P2_TX_C_DN<6>")
	)
	(segment
		(start 410.245814 -391.613136)
		(end 410.245814 -392.30427)
		(width 0.1016)
		(layer "F.Cu")
		(net "P5E_CPU0_P2_TX_C_DN<6>")
	)
	(arc
		(start 409.187396 -381.729234)
		(mid 409.352761 -381.97677)
		(end 409.410916 -382.26873)
		(width 0.1016)
		(layer "F.Cu")
		(net "P5E_CPU0_P2_TX_C_DN<6>")
	)
	(arc
		(start 409.410916 -386.388356)
		(mid 409.442789 -386.717425)
		(end 409.537154 -387.034278)
		(width 0.1016)
		(layer "F.Cu")
		(net "P5E_CPU0_P2_TX_C_DN<6>")
	)
	(arc
		(start 407.69159 -379.861826)
		(mid 407.760157 -380.205506)
		(end 407.954988 -380.496826)
		(width 0.1016)
		(layer "F.Cu")
		(net "P5E_CPU0_P2_TX_C_DN<6>")
	)
	(arc
		(start 409.57373 -387.124194)
		(mid 410.006096 -388.572135)
		(end 410.152088 -390.076182)
		(width 0.1016)
		(layer "F.Cu")
		(net "P5E_CPU0_P2_TX_C_DN<6>")
	)
	(segment
		(start 408.952192 -390.033764)
		(end 408.952192 -391.51941)
		(width 0.1016)
		(layer "F.Cu")
		(net "P5E_CPU0_P2_TX_C_DN<5>")
	)
	(segment
		(start 406.33904 -381.68453)
		(end 405.98979 -382.03378)
		(width 0.1016)
		(layer "F.Cu")
		(net "P5E_CPU0_P2_TX_C_DN<5>")
	)
	(segment
		(start 405.98979 -383.439416)
		(end 405.98979 -383.744216)
		(width 0.1016)
		(layer "F.Cu")
		(net "P5E_CPU0_P2_TX_C_DN<5>")
	)
	(segment
		(start 409.045664 -391.612882)
		(end 409.045664 -392.30427)
		(width 0.1016)
		(layer "F.Cu")
		(net "P5E_CPU0_P2_TX_C_DN<5>")
	)
	(segment
		(start 408.952192 -391.51941)
		(end 409.045664 -391.612882)
		(width 0.1016)
		(layer "F.Cu")
		(net "P5E_CPU0_P2_TX_C_DN<5>")
	)
	(segment
		(start 406.10155 -383.022856)
		(end 406.10155 -383.327656)
		(width 0.1016)
		(layer "F.Cu")
		(net "P5E_CPU0_P2_TX_C_DN<5>")
	)
	(segment
		(start 405.98979 -382.03378)
		(end 405.98979 -382.911096)
		(width 0.1016)
		(layer "F.Cu")
		(net "P5E_CPU0_P2_TX_C_DN<5>")
	)
	(segment
		(start 406.10155 -383.327656)
		(end 405.98979 -383.439416)
		(width 0.1016)
		(layer "F.Cu")
		(net "P5E_CPU0_P2_TX_C_DN<5>")
	)
	(segment
		(start 406.31745 -384.82397)
		(end 408.247342 -387.710934)
		(width 0.1016)
		(layer "F.Cu")
		(net "P5E_CPU0_P2_TX_C_DN<5>")
	)
	(segment
		(start 405.98979 -382.911096)
		(end 406.10155 -383.022856)
		(width 0.1016)
		(layer "F.Cu")
		(net "P5E_CPU0_P2_TX_C_DN<5>")
	)
	(arc
		(start 405.98979 -383.744216)
		(mid 406.073511 -384.308402)
		(end 406.31745 -384.82397)
		(width 0.1016)
		(layer "F.Cu")
		(net "P5E_CPU0_P2_TX_C_DN<5>")
	)
	(arc
		(start 408.247342 -387.710934)
		(mid 408.772105 -388.820055)
		(end 408.952192 -390.033764)
		(width 0.1016)
		(layer "F.Cu")
		(net "P5E_CPU0_P2_TX_C_DN<5>")
	)
	(segment
		(start 404.28799 -384.67157)
		(end 404.503636 -385.191508)
		(width 0.1016)
		(layer "F.Cu")
		(net "P5E_CPU0_P2_TX_C_DN<4>")
	)
	(segment
		(start 407.752296 -389.955278)
		(end 407.752296 -391.51941)
		(width 0.1016)
		(layer "F.Cu")
		(net "P5E_CPU0_P2_TX_C_DN<4>")
	)
	(segment
		(start 405.045672 -385.851908)
		(end 405.202898 -385.867402)
		(width 0.1016)
		(layer "F.Cu")
		(net "P5E_CPU0_P2_TX_C_DN<4>")
	)
	(segment
		(start 405.381206 -386.260594)
		(end 407.37917 -388.69493)
		(width 0.1016)
		(layer "F.Cu")
		(net "P5E_CPU0_P2_TX_C_DN<4>")
	)
	(segment
		(start 407.752296 -391.51941)
		(end 407.845768 -391.612882)
		(width 0.1016)
		(layer "F.Cu")
		(net "P5E_CPU0_P2_TX_C_DN<4>")
	)
	(segment
		(start 404.503636 -385.191508)
		(end 405.045672 -385.851908)
		(width 0.1016)
		(layer "F.Cu")
		(net "P5E_CPU0_P2_TX_C_DN<4>")
	)
	(segment
		(start 405.202898 -385.867402)
		(end 405.396446 -386.103114)
		(width 0.1016)
		(layer "F.Cu")
		(net "P5E_CPU0_P2_TX_C_DN<4>")
	)
	(segment
		(start 404.28799 -384.49758)
		(end 404.28799 -384.67157)
		(width 0.1016)
		(layer "F.Cu")
		(net "P5E_CPU0_P2_TX_C_DN<4>")
	)
	(segment
		(start 407.845768 -391.612882)
		(end 407.845768 -392.30427)
		(width 0.1016)
		(layer "F.Cu")
		(net "P5E_CPU0_P2_TX_C_DN<4>")
	)
	(segment
		(start 404.63724 -384.14833)
		(end 404.28799 -384.49758)
		(width 0.1016)
		(layer "F.Cu")
		(net "P5E_CPU0_P2_TX_C_DN<4>")
	)
	(segment
		(start 405.396446 -386.103114)
		(end 405.381206 -386.260594)
		(width 0.1016)
		(layer "F.Cu")
		(net "P5E_CPU0_P2_TX_C_DN<4>")
	)
	(arc
		(start 407.752296 -389.954262)
		(mid 407.752296 -389.95477)
		(end 407.752296 -389.955278)
		(width 0.1016)
		(layer "F.Cu")
		(net "P5E_CPU0_P2_TX_C_DN<4>")
	)
	(arc
		(start 407.37917 -388.69493)
		(mid 407.656822 -389.297208)
		(end 407.752296 -389.9535)
		(width 0.1016)
		(layer "F.Cu")
		(net "P5E_CPU0_P2_TX_C_DN<4>")
	)
	(arc
		(start 407.752296 -389.9535)
		(mid 407.752296 -389.953881)
		(end 407.752296 -389.954262)
		(width 0.1016)
		(layer "F.Cu")
		(net "P5E_CPU0_P2_TX_C_DN<4>")
	)
	(segment
		(start 402.19376 -381.366014)
		(end 402.19376 -381.524002)
		(width 0.1016)
		(layer "F.Cu")
		(net "P5E_CPU0_P2_TX_C_DN<3>")
	)
	(segment
		(start 406.552146 -389.996426)
		(end 406.552146 -391.51941)
		(width 0.1016)
		(layer "F.Cu")
		(net "P5E_CPU0_P2_TX_C_DN<3>")
	)
	(segment
		(start 402.64334 -383.834132)
		(end 403.497288 -385.896358)
		(width 0.1016)
		(layer "F.Cu")
		(net "P5E_CPU0_P2_TX_C_DN<3>")
	)
	(segment
		(start 401.97786 -381.150114)
		(end 402.19376 -381.366014)
		(width 0.1016)
		(layer "F.Cu")
		(net "P5E_CPU0_P2_TX_C_DN<3>")
	)
	(segment
		(start 401.819872 -381.150114)
		(end 401.97786 -381.150114)
		(width 0.1016)
		(layer "F.Cu")
		(net "P5E_CPU0_P2_TX_C_DN<3>")
	)
	(segment
		(start 401.069048 -380.39929)
		(end 401.819872 -381.150114)
		(width 0.1016)
		(layer "F.Cu")
		(net "P5E_CPU0_P2_TX_C_DN<3>")
	)
	(segment
		(start 402.594064 -382.120902)
		(end 402.594064 -383.585466)
		(width 0.1016)
		(layer "F.Cu")
		(net "P5E_CPU0_P2_TX_C_DN<3>")
	)
	(segment
		(start 403.497288 -385.896358)
		(end 403.751796 -386.3213)
		(width 0.1016)
		(layer "F.Cu")
		(net "P5E_CPU0_P2_TX_C_DN<3>")
	)
	(segment
		(start 401.23364 -379.22073)
		(end 400.88439 -379.56998)
		(width 0.1016)
		(layer "F.Cu")
		(net "P5E_CPU0_P2_TX_C_DN<3>")
	)
	(segment
		(start 402.19376 -381.524002)
		(end 402.454872 -381.785114)
		(width 0.1016)
		(layer "F.Cu")
		(net "P5E_CPU0_P2_TX_C_DN<3>")
	)
	(segment
		(start 406.645618 -391.612882)
		(end 406.645618 -392.30427)
		(width 0.1016)
		(layer "F.Cu")
		(net "P5E_CPU0_P2_TX_C_DN<3>")
	)
	(segment
		(start 403.751796 -386.3213)
		(end 406.38476 -389.529574)
		(width 0.1016)
		(layer "F.Cu")
		(net "P5E_CPU0_P2_TX_C_DN<3>")
	)
	(segment
		(start 406.552146 -391.51941)
		(end 406.645618 -391.612882)
		(width 0.1016)
		(layer "F.Cu")
		(net "P5E_CPU0_P2_TX_C_DN<3>")
	)
	(segment
		(start 400.88439 -379.56998)
		(end 400.88439 -379.95352)
		(width 0.1016)
		(layer "F.Cu")
		(net "P5E_CPU0_P2_TX_C_DN<3>")
	)
	(arc
		(start 402.594064 -383.585466)
		(mid 402.606444 -383.71223)
		(end 402.64334 -383.834132)
		(width 0.1016)
		(layer "F.Cu")
		(net "P5E_CPU0_P2_TX_C_DN<3>")
	)
	(arc
		(start 400.88439 -379.95352)
		(mid 400.932378 -380.194774)
		(end 401.069048 -380.39929)
		(width 0.1016)
		(layer "F.Cu")
		(net "P5E_CPU0_P2_TX_C_DN<3>")
	)
	(arc
		(start 406.38476 -389.529574)
		(mid 406.508978 -389.748463)
		(end 406.552146 -389.996426)
		(width 0.1016)
		(layer "F.Cu")
		(net "P5E_CPU0_P2_TX_C_DN<3>")
	)
	(arc
		(start 402.454872 -381.785114)
		(mid 402.557866 -381.939161)
		(end 402.594064 -382.120902)
		(width 0.1016)
		(layer "F.Cu")
		(net "P5E_CPU0_P2_TX_C_DN<3>")
	)
	(segment
		(start 399.53184 -381.68453)
		(end 399.18259 -382.03378)
		(width 0.1016)
		(layer "F.Cu")
		(net "P5E_CPU0_P2_TX_C_DN<2>")
	)
	(segment
		(start 405.35225 -390.602216)
		(end 405.35225 -391.51941)
		(width 0.1016)
		(layer "F.Cu")
		(net "P5E_CPU0_P2_TX_C_DN<2>")
	)
	(segment
		(start 402.926042 -387.301994)
		(end 405.132032 -389.987536)
		(width 0.1016)
		(layer "F.Cu")
		(net "P5E_CPU0_P2_TX_C_DN<2>")
	)
	(segment
		(start 400.812508 -383.87655)
		(end 401.107148 -384.17119)
		(width 0.1016)
		(layer "F.Cu")
		(net "P5E_CPU0_P2_TX_C_DN<2>")
	)
	(segment
		(start 399.377408 -383.133854)
		(end 399.425414 -383.18186)
		(width 0.1016)
		(layer "F.Cu")
		(net "P5E_CPU0_P2_TX_C_DN<2>")
	)
	(segment
		(start 401.481036 -384.545078)
		(end 401.6121 -384.676142)
		(width 0.1016)
		(layer "F.Cu")
		(net "P5E_CPU0_P2_TX_C_DN<2>")
	)
	(segment
		(start 405.445722 -391.612882)
		(end 405.445722 -392.30427)
		(width 0.1016)
		(layer "F.Cu")
		(net "P5E_CPU0_P2_TX_C_DN<2>")
	)
	(segment
		(start 401.816316 -384.981704)
		(end 402.531834 -386.70992)
		(width 0.1016)
		(layer "F.Cu")
		(net "P5E_CPU0_P2_TX_C_DN<2>")
	)
	(segment
		(start 399.776188 -383.416556)
		(end 400.691096 -383.795524)
		(width 0.1016)
		(layer "F.Cu")
		(net "P5E_CPU0_P2_TX_C_DN<2>")
	)
	(segment
		(start 401.265136 -384.17119)
		(end 401.481036 -384.38709)
		(width 0.1016)
		(layer "F.Cu")
		(net "P5E_CPU0_P2_TX_C_DN<2>")
	)
	(segment
		(start 401.481036 -384.38709)
		(end 401.481036 -384.545078)
		(width 0.1016)
		(layer "F.Cu")
		(net "P5E_CPU0_P2_TX_C_DN<2>")
	)
	(segment
		(start 402.531834 -386.70992)
		(end 402.6662 -386.93344)
		(width 0.1016)
		(layer "F.Cu")
		(net "P5E_CPU0_P2_TX_C_DN<2>")
	)
	(segment
		(start 401.107148 -384.17119)
		(end 401.265136 -384.17119)
		(width 0.1016)
		(layer "F.Cu")
		(net "P5E_CPU0_P2_TX_C_DN<2>")
	)
	(segment
		(start 405.35225 -391.51941)
		(end 405.445722 -391.612882)
		(width 0.1016)
		(layer "F.Cu")
		(net "P5E_CPU0_P2_TX_C_DN<2>")
	)
	(segment
		(start 399.18259 -382.03378)
		(end 399.18259 -382.664208)
		(width 0.1016)
		(layer "F.Cu")
		(net "P5E_CPU0_P2_TX_C_DN<2>")
	)
	(arc
		(start 402.6662 -386.93344)
		(mid 402.789359 -387.122484)
		(end 402.926042 -387.301994)
		(width 0.1016)
		(layer "F.Cu")
		(net "P5E_CPU0_P2_TX_C_DN<2>")
	)
	(arc
		(start 399.18259 -382.664208)
		(mid 399.233335 -382.91838)
		(end 399.377408 -383.133854)
		(width 0.1016)
		(layer "F.Cu")
		(net "P5E_CPU0_P2_TX_C_DN<2>")
	)
	(arc
		(start 399.425414 -383.18186)
		(mid 399.589252 -383.316467)
		(end 399.776188 -383.416556)
		(width 0.1016)
		(layer "F.Cu")
		(net "P5E_CPU0_P2_TX_C_DN<2>")
	)
	(arc
		(start 405.132032 -389.987536)
		(mid 405.295521 -390.275755)
		(end 405.35225 -390.602216)
		(width 0.1016)
		(layer "F.Cu")
		(net "P5E_CPU0_P2_TX_C_DN<2>")
	)
	(arc
		(start 401.6121 -384.676142)
		(mid 401.729265 -384.818861)
		(end 401.816316 -384.981704)
		(width 0.1016)
		(layer "F.Cu")
		(net "P5E_CPU0_P2_TX_C_DN<2>")
	)
	(arc
		(start 400.691096 -383.795524)
		(mid 400.755803 -383.830045)
		(end 400.812508 -383.87655)
		(width 0.1016)
		(layer "F.Cu")
		(net "P5E_CPU0_P2_TX_C_DN<2>")
	)
	(segment
		(start 398.861788 -385.23926)
		(end 399.232882 -384.868166)
		(width 0.1016)
		(layer "F.Cu")
		(net "P5E_CPU0_P2_TX_C_DN<1>")
	)
	(segment
		(start 401.22602 -387.256782)
		(end 401.369276 -387.603238)
		(width 0.1016)
		(layer "F.Cu")
		(net "P5E_CPU0_P2_TX_C_DN<1>")
	)
	(segment
		(start 401.832318 -388.29615)
		(end 401.94611 -388.46633)
		(width 0.1016)
		(layer "F.Cu")
		(net "P5E_CPU0_P2_TX_C_DN<1>")
	)
	(segment
		(start 403.9362 -391.324592)
		(end 403.643592 -391.6172)
		(width 0.1016)
		(layer "F.Cu")
		(net "P5E_CPU0_P2_TX_C_DN<1>")
	)
	(segment
		(start 401.079716 -387.19633)
		(end 401.22602 -387.256782)
		(width 0.1016)
		(layer "F.Cu")
		(net "P5E_CPU0_P2_TX_C_DN<1>")
	)
	(segment
		(start 403.734778 -391.978896)
		(end 403.869144 -391.978896)
		(width 0.1016)
		(layer "F.Cu")
		(net "P5E_CPU0_P2_TX_C_DN<1>")
	)
	(segment
		(start 401.507706 -388.01167)
		(end 401.677124 -388.265162)
		(width 0.1016)
		(layer "F.Cu")
		(net "P5E_CPU0_P2_TX_C_DN<1>")
	)
	(segment
		(start 402.696934 -389.249412)
		(end 403.70887 -390.482836)
		(width 0.1016)
		(layer "F.Cu")
		(net "P5E_CPU0_P2_TX_C_DN<1>")
	)
	(segment
		(start 401.369276 -387.603238)
		(end 401.53844 -387.856476)
		(width 0.1016)
		(layer "F.Cu")
		(net "P5E_CPU0_P2_TX_C_DN<1>")
	)
	(segment
		(start 403.9362 -390.936734)
		(end 403.9362 -391.324592)
		(width 0.1016)
		(layer "F.Cu")
		(net "P5E_CPU0_P2_TX_C_DN<1>")
	)
	(segment
		(start 401.677124 -388.265162)
		(end 401.832318 -388.29615)
		(width 0.1016)
		(layer "F.Cu")
		(net "P5E_CPU0_P2_TX_C_DN<1>")
	)
	(segment
		(start 402.093684 -388.646162)
		(end 402.696934 -389.249412)
		(width 0.1016)
		(layer "F.Cu")
		(net "P5E_CPU0_P2_TX_C_DN<1>")
	)
	(segment
		(start 403.643592 -391.88771)
		(end 403.734778 -391.978896)
		(width 0.1016)
		(layer "F.Cu")
		(net "P5E_CPU0_P2_TX_C_DN<1>")
	)
	(segment
		(start 403.945598 -391.902442)
		(end 403.945598 -391.784586)
		(width 0.1016)
		(layer "F.Cu")
		(net "P5E_CPU0_P2_TX_C_DN<1>")
	)
	(segment
		(start 403.835362 -390.693656)
		(end 403.9362 -390.936734)
		(width 0.1016)
		(layer "F.Cu")
		(net "P5E_CPU0_P2_TX_C_DN<1>")
	)
	(segment
		(start 401.023582 -386.768594)
		(end 400.96313 -386.91439)
		(width 0.1016)
		(layer "F.Cu")
		(net "P5E_CPU0_P2_TX_C_DN<1>")
	)
	(segment
		(start 401.53844 -387.856476)
		(end 401.507706 -388.01167)
		(width 0.1016)
		(layer "F.Cu")
		(net "P5E_CPU0_P2_TX_C_DN<1>")
	)
	(segment
		(start 400.96313 -386.91439)
		(end 401.079716 -387.19633)
		(width 0.1016)
		(layer "F.Cu")
		(net "P5E_CPU0_P2_TX_C_DN<1>")
	)
	(segment
		(start 400.573494 -385.680966)
		(end 401.023582 -386.768594)
		(width 0.1016)
		(layer "F.Cu")
		(net "P5E_CPU0_P2_TX_C_DN<1>")
	)
	(segment
		(start 403.643592 -391.6172)
		(end 403.643592 -391.88771)
		(width 0.1016)
		(layer "F.Cu")
		(net "P5E_CPU0_P2_TX_C_DN<1>")
	)
	(segment
		(start 403.70887 -390.482836)
		(end 403.835362 -390.693656)
		(width 0.1016)
		(layer "F.Cu")
		(net "P5E_CPU0_P2_TX_C_DN<1>")
	)
	(segment
		(start 399.232882 -384.868166)
		(end 399.316956 -384.868166)
		(width 0.1016)
		(layer "F.Cu")
		(net "P5E_CPU0_P2_TX_C_DN<1>")
	)
	(segment
		(start 400.153886 -385.214876)
		(end 400.480022 -385.541012)
		(width 0.1016)
		(layer "F.Cu")
		(net "P5E_CPU0_P2_TX_C_DN<1>")
	)
	(segment
		(start 403.869144 -391.978896)
		(end 403.945598 -391.902442)
		(width 0.1016)
		(layer "F.Cu")
		(net "P5E_CPU0_P2_TX_C_DN<1>")
	)
	(arc
		(start 401.94611 -388.46633)
		(mid 402.015481 -388.55987)
		(end 402.093684 -388.646162)
		(width 0.1016)
		(layer "F.Cu")
		(net "P5E_CPU0_P2_TX_C_DN<1>")
	)
	(arc
		(start 399.316956 -384.868166)
		(mid 399.769901 -384.95828)
		(end 400.153886 -385.214876)
		(width 0.1016)
		(layer "F.Cu")
		(net "P5E_CPU0_P2_TX_C_DN<1>")
	)
	(arc
		(start 400.480022 -385.541012)
		(mid 400.533661 -385.60638)
		(end 400.573494 -385.680966)
		(width 0.1016)
		(layer "F.Cu")
		(net "P5E_CPU0_P2_TX_C_DN<1>")
	)
	(segment
		(start 425.10202 -388.767828)
		(end 424.75277 -388.418578)
		(width 0.1016)
		(layer "F.Cu")
		(net "P5E_CPU0_P2_TX_C_DN<15>")
	)
	(segment
		(start 420.952168 -390.587484)
		(end 420.952168 -391.30859)
		(width 0.1016)
		(layer "F.Cu")
		(net "P5E_CPU0_P2_TX_C_DN<15>")
	)
	(segment
		(start 424.75277 -388.418578)
		(end 423.047922 -388.418578)
		(width 0.1016)
		(layer "F.Cu")
		(net "P5E_CPU0_P2_TX_C_DN<15>")
	)
	(segment
		(start 420.952168 -391.30859)
		(end 421.046148 -391.40257)
		(width 0.1016)
		(layer "F.Cu")
		(net "P5E_CPU0_P2_TX_C_DN<15>")
	)
	(segment
		(start 421.046148 -391.40257)
		(end 421.046148 -392.303762)
		(width 0.1016)
		(layer "F.Cu")
		(net "P5E_CPU0_P2_TX_C_DN<15>")
	)
	(segment
		(start 421.046148 -392.303762)
		(end 421.04564 -392.30427)
		(width 0.1016)
		(layer "F.Cu")
		(net "P5E_CPU0_P2_TX_C_DN<15>")
	)
	(segment
		(start 422.94683 -388.460488)
		(end 421.045894 -390.361424)
		(width 0.1016)
		(layer "F.Cu")
		(net "P5E_CPU0_P2_TX_C_DN<15>")
	)
	(arc
		(start 421.045894 -390.361424)
		(mid 420.976539 -390.465127)
		(end 420.952168 -390.587484)
		(width 0.1016)
		(layer "F.Cu")
		(net "P5E_CPU0_P2_TX_C_DN<15>")
	)
	(arc
		(start 423.047922 -388.418578)
		(mid 422.993198 -388.429463)
		(end 422.94683 -388.460488)
		(width 0.1016)
		(layer "F.Cu")
		(net "P5E_CPU0_P2_TX_C_DN<15>")
	)
	(segment
		(start 419.752272 -391.30859)
		(end 419.846252 -391.40257)
		(width 0.1016)
		(layer "F.Cu")
		(net "P5E_CPU0_P2_TX_C_DN<14>")
	)
	(segment
		(start 424.442382 -385.10083)
		(end 419.950138 -389.593074)
		(width 0.1016)
		(layer "F.Cu")
		(net "P5E_CPU0_P2_TX_C_DN<14>")
	)
	(segment
		(start 419.752526 -390.071102)
		(end 419.752272 -390.070848)
		(width 0.1016)
		(layer "F.Cu")
		(net "P5E_CPU0_P2_TX_C_DN<14>")
	)
	(segment
		(start 424.756834 -385.10083)
		(end 424.442382 -385.10083)
		(width 0.1016)
		(layer "F.Cu")
		(net "P5E_CPU0_P2_TX_C_DN<14>")
	)
	(segment
		(start 425.10202 -385.364228)
		(end 424.896534 -385.158742)
		(width 0.1016)
		(layer "F.Cu")
		(net "P5E_CPU0_P2_TX_C_DN<14>")
	)
	(segment
		(start 419.846252 -392.303762)
		(end 419.845744 -392.30427)
		(width 0.1016)
		(layer "F.Cu")
		(net "P5E_CPU0_P2_TX_C_DN<14>")
	)
	(segment
		(start 424.896534 -385.158742)
		(end 424.756834 -385.10083)
		(width 0.1016)
		(layer "F.Cu")
		(net "P5E_CPU0_P2_TX_C_DN<14>")
	)
	(segment
		(start 419.752272 -390.070848)
		(end 419.752272 -391.30859)
		(width 0.1016)
		(layer "F.Cu")
		(net "P5E_CPU0_P2_TX_C_DN<14>")
	)
	(segment
		(start 419.846252 -391.40257)
		(end 419.846252 -392.303762)
		(width 0.1016)
		(layer "F.Cu")
		(net "P5E_CPU0_P2_TX_C_DN<14>")
	)
	(arc
		(start 419.950138 -389.593074)
		(mid 419.803812 -389.812439)
		(end 419.752526 -390.071102)
		(width 0.1016)
		(layer "F.Cu")
		(net "P5E_CPU0_P2_TX_C_DN<14>")
	)
	(segment
		(start 425.05884 -379.22073)
		(end 424.70959 -379.56998)
		(width 0.1016)
		(layer "F.Cu")
		(net "P5E_CPU0_P2_TX_C_DN<13>")
	)
	(segment
		(start 425.577 -381.13335)
		(end 425.734988 -381.13335)
		(width 0.1016)
		(layer "F.Cu")
		(net "P5E_CPU0_P2_TX_C_DN<13>")
	)
	(segment
		(start 423.986198 -383.867914)
		(end 418.58946 -389.264652)
		(width 0.1016)
		(layer "F.Cu")
		(net "P5E_CPU0_P2_TX_C_DN<13>")
	)
	(segment
		(start 424.70959 -379.56998)
		(end 424.70959 -379.909832)
		(width 0.1016)
		(layer "F.Cu")
		(net "P5E_CPU0_P2_TX_C_DN<13>")
	)
	(segment
		(start 426.383704 -382.248156)
		(end 426.383704 -382.518666)
		(width 0.1016)
		(layer "F.Cu")
		(net "P5E_CPU0_P2_TX_C_DN<13>")
	)
	(segment
		(start 418.552122 -391.51941)
		(end 418.645594 -391.612882)
		(width 0.1016)
		(layer "F.Cu")
		(net "P5E_CPU0_P2_TX_C_DN<13>")
	)
	(segment
		(start 425.950888 -381.34925)
		(end 425.950888 -381.507238)
		(width 0.1016)
		(layer "F.Cu")
		(net "P5E_CPU0_P2_TX_C_DN<13>")
	)
	(segment
		(start 418.552122 -389.354822)
		(end 418.552122 -391.51941)
		(width 0.1016)
		(layer "F.Cu")
		(net "P5E_CPU0_P2_TX_C_DN<13>")
	)
	(segment
		(start 425.950888 -381.507238)
		(end 426.16628 -381.72263)
		(width 0.1016)
		(layer "F.Cu")
		(net "P5E_CPU0_P2_TX_C_DN<13>")
	)
	(segment
		(start 426.147992 -383.088388)
		(end 425.722542 -383.513838)
		(width 0.1016)
		(layer "F.Cu")
		(net "P5E_CPU0_P2_TX_C_DN<13>")
	)
	(segment
		(start 424.70959 -379.909832)
		(end 424.709844 -379.909578)
		(width 0.1016)
		(layer "F.Cu")
		(net "P5E_CPU0_P2_TX_C_DN<13>")
	)
	(segment
		(start 424.961558 -380.517908)
		(end 425.577 -381.13335)
		(width 0.1016)
		(layer "F.Cu")
		(net "P5E_CPU0_P2_TX_C_DN<13>")
	)
	(segment
		(start 425.284646 -383.69494)
		(end 424.403774 -383.69494)
		(width 0.1016)
		(layer "F.Cu")
		(net "P5E_CPU0_P2_TX_C_DN<13>")
	)
	(segment
		(start 418.645594 -391.612882)
		(end 418.645594 -392.30427)
		(width 0.1016)
		(layer "F.Cu")
		(net "P5E_CPU0_P2_TX_C_DN<13>")
	)
	(segment
		(start 425.734988 -381.13335)
		(end 425.950888 -381.34925)
		(width 0.1016)
		(layer "F.Cu")
		(net "P5E_CPU0_P2_TX_C_DN<13>")
	)
	(arc
		(start 426.16628 -381.72263)
		(mid 426.327275 -381.963759)
		(end 426.383704 -382.248156)
		(width 0.1016)
		(layer "F.Cu")
		(net "P5E_CPU0_P2_TX_C_DN<13>")
	)
	(arc
		(start 418.58946 -389.264652)
		(mid 418.561817 -389.306022)
		(end 418.552122 -389.354822)
		(width 0.1016)
		(layer "F.Cu")
		(net "P5E_CPU0_P2_TX_C_DN<13>")
	)
	(arc
		(start 424.403774 -383.69494)
		(mid 424.17778 -383.739893)
		(end 423.986198 -383.867914)
		(width 0.1016)
		(layer "F.Cu")
		(net "P5E_CPU0_P2_TX_C_DN<13>")
	)
	(arc
		(start 424.709844 -379.909578)
		(mid 424.775213 -380.238771)
		(end 424.961558 -380.517908)
		(width 0.1016)
		(layer "F.Cu")
		(net "P5E_CPU0_P2_TX_C_DN<13>")
	)
	(arc
		(start 426.383704 -382.518666)
		(mid 426.32256 -382.827)
		(end 426.147992 -383.088388)
		(width 0.1016)
		(layer "F.Cu")
		(net "P5E_CPU0_P2_TX_C_DN<13>")
	)
	(arc
		(start 425.722542 -383.513838)
		(mid 425.521604 -383.647915)
		(end 425.284646 -383.69494)
		(width 0.1016)
		(layer "F.Cu")
		(net "P5E_CPU0_P2_TX_C_DN<13>")
	)
	(segment
		(start 423.015664 -382.039368)
		(end 423.015664 -382.945132)
		(width 0.1016)
		(layer "F.Cu")
		(net "P5E_CPU0_P2_TX_C_DN<12>")
	)
	(segment
		(start 422.584372 -381.307594)
		(end 422.800272 -381.523494)
		(width 0.1016)
		(layer "F.Cu")
		(net "P5E_CPU0_P2_TX_C_DN<12>")
	)
	(segment
		(start 421.30599 -379.56998)
		(end 421.30599 -379.9205)
		(width 0.1016)
		(layer "F.Cu")
		(net "P5E_CPU0_P2_TX_C_DN<12>")
	)
	(segment
		(start 422.426384 -381.307594)
		(end 422.584372 -381.307594)
		(width 0.1016)
		(layer "F.Cu")
		(net "P5E_CPU0_P2_TX_C_DN<12>")
	)
	(segment
		(start 422.800272 -381.681482)
		(end 422.915334 -381.796544)
		(width 0.1016)
		(layer "F.Cu")
		(net "P5E_CPU0_P2_TX_C_DN<12>")
	)
	(segment
		(start 417.352226 -389.116062)
		(end 417.352226 -391.51941)
		(width 0.1016)
		(layer "F.Cu")
		(net "P5E_CPU0_P2_TX_C_DN<12>")
	)
	(segment
		(start 422.800272 -381.523494)
		(end 422.800272 -381.681482)
		(width 0.1016)
		(layer "F.Cu")
		(net "P5E_CPU0_P2_TX_C_DN<12>")
	)
	(segment
		(start 421.49522 -380.37643)
		(end 422.426384 -381.307594)
		(width 0.1016)
		(layer "F.Cu")
		(net "P5E_CPU0_P2_TX_C_DN<12>")
	)
	(segment
		(start 421.65524 -379.22073)
		(end 421.30599 -379.56998)
		(width 0.1016)
		(layer "F.Cu")
		(net "P5E_CPU0_P2_TX_C_DN<12>")
	)
	(segment
		(start 417.352226 -391.51941)
		(end 417.445698 -391.612882)
		(width 0.1016)
		(layer "F.Cu")
		(net "P5E_CPU0_P2_TX_C_DN<12>")
	)
	(segment
		(start 422.879774 -383.272284)
		(end 417.576254 -388.576058)
		(width 0.1016)
		(layer "F.Cu")
		(net "P5E_CPU0_P2_TX_C_DN<12>")
	)
	(segment
		(start 417.445698 -391.612882)
		(end 417.445698 -392.30427)
		(width 0.1016)
		(layer "F.Cu")
		(net "P5E_CPU0_P2_TX_C_DN<12>")
	)
	(arc
		(start 423.015664 -382.945132)
		(mid 422.980236 -383.122209)
		(end 422.879774 -383.272284)
		(width 0.1016)
		(layer "F.Cu")
		(net "P5E_CPU0_P2_TX_C_DN<12>")
	)
	(arc
		(start 417.576254 -388.576058)
		(mid 417.410489 -388.82377)
		(end 417.352226 -389.116062)
		(width 0.1016)
		(layer "F.Cu")
		(net "P5E_CPU0_P2_TX_C_DN<12>")
	)
	(arc
		(start 422.915334 -381.796544)
		(mid 422.989638 -381.907982)
		(end 423.015664 -382.039368)
		(width 0.1016)
		(layer "F.Cu")
		(net "P5E_CPU0_P2_TX_C_DN<12>")
	)
	(arc
		(start 421.30599 -379.9205)
		(mid 421.355281 -380.16727)
		(end 421.49522 -380.37643)
		(width 0.1016)
		(layer "F.Cu")
		(net "P5E_CPU0_P2_TX_C_DN<12>")
	)
	(segment
		(start 419.60419 -383.403856)
		(end 419.71595 -383.515616)
		(width 0.1016)
		(layer "F.Cu")
		(net "P5E_CPU0_P2_TX_C_DN<11>")
	)
	(segment
		(start 419.60419 -383.932176)
		(end 419.60419 -384.618484)
		(width 0.1016)
		(layer "F.Cu")
		(net "P5E_CPU0_P2_TX_C_DN<11>")
	)
	(segment
		(start 419.50386 -384.861562)
		(end 416.189414 -388.176008)
		(width 0.1016)
		(layer "F.Cu")
		(net "P5E_CPU0_P2_TX_C_DN<11>")
	)
	(segment
		(start 416.152076 -391.51941)
		(end 416.245802 -391.613136)
		(width 0.1016)
		(layer "F.Cu")
		(net "P5E_CPU0_P2_TX_C_DN<11>")
	)
	(segment
		(start 416.245802 -391.613136)
		(end 416.245802 -392.30427)
		(width 0.1016)
		(layer "F.Cu")
		(net "P5E_CPU0_P2_TX_C_DN<11>")
	)
	(segment
		(start 419.95344 -381.68453)
		(end 419.60419 -382.03378)
		(width 0.1016)
		(layer "F.Cu")
		(net "P5E_CPU0_P2_TX_C_DN<11>")
	)
	(segment
		(start 419.71595 -383.820416)
		(end 419.60419 -383.932176)
		(width 0.1016)
		(layer "F.Cu")
		(net "P5E_CPU0_P2_TX_C_DN<11>")
	)
	(segment
		(start 416.152076 -388.266178)
		(end 416.152076 -391.51941)
		(width 0.1016)
		(layer "F.Cu")
		(net "P5E_CPU0_P2_TX_C_DN<11>")
	)
	(segment
		(start 419.71595 -383.515616)
		(end 419.71595 -383.820416)
		(width 0.1016)
		(layer "F.Cu")
		(net "P5E_CPU0_P2_TX_C_DN<11>")
	)
	(segment
		(start 419.60419 -382.03378)
		(end 419.60419 -383.403856)
		(width 0.1016)
		(layer "F.Cu")
		(net "P5E_CPU0_P2_TX_C_DN<11>")
	)
	(arc
		(start 416.189414 -388.176008)
		(mid 416.161771 -388.217378)
		(end 416.152076 -388.266178)
		(width 0.1016)
		(layer "F.Cu")
		(net "P5E_CPU0_P2_TX_C_DN<11>")
	)
	(arc
		(start 419.60419 -384.618484)
		(mid 419.578231 -384.750022)
		(end 419.50386 -384.861562)
		(width 0.1016)
		(layer "F.Cu")
		(net "P5E_CPU0_P2_TX_C_DN<11>")
	)
	(segment
		(start 415.541968 -386.644388)
		(end 415.541968 -386.802122)
		(width 0.1016)
		(layer "F.Cu")
		(net "P5E_CPU0_P2_TX_C_DN<10>")
	)
	(segment
		(start 414.95218 -387.286754)
		(end 414.95218 -391.51941)
		(width 0.1016)
		(layer "F.Cu")
		(net "P5E_CPU0_P2_TX_C_DN<10>")
	)
	(segment
		(start 416.221672 -385.96443)
		(end 415.541968 -386.644388)
		(width 0.1016)
		(layer "F.Cu")
		(net "P5E_CPU0_P2_TX_C_DN<10>")
	)
	(segment
		(start 417.901374 -384.498596)
		(end 417.901374 -384.584702)
		(width 0.1016)
		(layer "F.Cu")
		(net "P5E_CPU0_P2_TX_C_DN<10>")
	)
	(segment
		(start 416.552126 -385.919472)
		(end 416.329876 -385.919472)
		(width 0.1016)
		(layer "F.Cu")
		(net "P5E_CPU0_P2_TX_C_DN<10>")
	)
	(segment
		(start 415.541968 -386.802122)
		(end 415.326322 -387.017768)
		(width 0.1016)
		(layer "F.Cu")
		(net "P5E_CPU0_P2_TX_C_DN<10>")
	)
	(segment
		(start 415.045652 -391.612882)
		(end 415.045652 -392.30427)
		(width 0.1016)
		(layer "F.Cu")
		(net "P5E_CPU0_P2_TX_C_DN<10>")
	)
	(segment
		(start 414.95218 -391.51941)
		(end 415.045652 -391.612882)
		(width 0.1016)
		(layer "F.Cu")
		(net "P5E_CPU0_P2_TX_C_DN<10>")
	)
	(segment
		(start 418.25164 -384.14833)
		(end 417.901374 -384.498596)
		(width 0.1016)
		(layer "F.Cu")
		(net "P5E_CPU0_P2_TX_C_DN<10>")
	)
	(segment
		(start 415.168334 -387.017768)
		(end 414.989518 -387.196584)
		(width 0.1016)
		(layer "F.Cu")
		(net "P5E_CPU0_P2_TX_C_DN<10>")
	)
	(segment
		(start 415.326322 -387.017768)
		(end 415.168334 -387.017768)
		(width 0.1016)
		(layer "F.Cu")
		(net "P5E_CPU0_P2_TX_C_DN<10>")
	)
	(segment
		(start 417.801044 -384.82778)
		(end 416.819334 -385.809236)
		(width 0.1016)
		(layer "F.Cu")
		(net "P5E_CPU0_P2_TX_C_DN<10>")
	)
	(arc
		(start 416.329876 -385.919472)
		(mid 416.271292 -385.931161)
		(end 416.221672 -385.96443)
		(width 0.1016)
		(layer "F.Cu")
		(net "P5E_CPU0_P2_TX_C_DN<10>")
	)
	(arc
		(start 414.989518 -387.196584)
		(mid 414.961875 -387.237954)
		(end 414.95218 -387.286754)
		(width 0.1016)
		(layer "F.Cu")
		(net "P5E_CPU0_P2_TX_C_DN<10>")
	)
	(arc
		(start 416.819334 -385.809236)
		(mid 416.696694 -385.890932)
		(end 416.552126 -385.919472)
		(width 0.1016)
		(layer "F.Cu")
		(net "P5E_CPU0_P2_TX_C_DN<10>")
	)
	(arc
		(start 417.901374 -384.584702)
		(mid 417.875415 -384.71624)
		(end 417.801044 -384.82778)
		(width 0.1016)
		(layer "F.Cu")
		(net "P5E_CPU0_P2_TX_C_DN<10>")
	)
	(segment
		(start 398.861788 -389.86206)
		(end 399.20926 -390.209532)
		(width 0.1016)
		(layer "F.Cu")
		(net "P5E_CPU0_P2_TX_C_DN<0>")
	)
	(segment
		(start 402.952204 -391.51941)
		(end 403.045676 -391.612882)
		(width 0.1016)
		(layer "F.Cu")
		(net "P5E_CPU0_P2_TX_C_DN<0>")
	)
	(segment
		(start 402.54809 -390.70407)
		(end 402.952204 -391.109708)
		(width 0.1016)
		(layer "F.Cu")
		(net "P5E_CPU0_P2_TX_C_DN<0>")
	)
	(segment
		(start 401.660614 -390.265158)
		(end 402.265642 -390.515094)
		(width 0.1016)
		(layer "F.Cu")
		(net "P5E_CPU0_P2_TX_C_DN<0>")
	)
	(segment
		(start 402.952204 -391.109708)
		(end 402.952204 -391.51941)
		(width 0.1016)
		(layer "F.Cu")
		(net "P5E_CPU0_P2_TX_C_DN<0>")
	)
	(segment
		(start 399.20926 -390.209532)
		(end 401.380452 -390.209532)
		(width 0.1016)
		(layer "F.Cu")
		(net "P5E_CPU0_P2_TX_C_DN<0>")
	)
	(segment
		(start 403.045676 -391.612882)
		(end 403.045676 -392.30427)
		(width 0.1016)
		(layer "F.Cu")
		(net "P5E_CPU0_P2_TX_C_DN<0>")
	)
	(arc
		(start 401.380452 -390.209532)
		(mid 401.523271 -390.223564)
		(end 401.660614 -390.265158)
		(width 0.1016)
		(layer "F.Cu")
		(net "P5E_CPU0_P2_TX_C_DN<0>")
	)
	(arc
		(start 402.265642 -390.515094)
		(mid 402.416274 -390.595523)
		(end 402.54809 -390.70407)
		(width 0.1016)
		(layer "F.Cu")
		(net "P5E_CPU0_P2_TX_C_DN<0>")
	)
	(segment
		(start 346.14358 -391.6172)
		(end 346.14358 -391.88771)
		(width 0.1016)
		(layer "F.Cu")
		(net "P5E_CPU0_P1_TX_C_DP<9>")
	)
	(segment
		(start 346.833444 -379.22073)
		(end 347.182694 -379.56998)
		(width 0.1016)
		(layer "F.Cu")
		(net "P5E_CPU0_P1_TX_C_DP<9>")
	)
	(segment
		(start 346.436188 -391.324592)
		(end 346.14358 -391.6172)
		(width 0.1016)
		(layer "F.Cu")
		(net "P5E_CPU0_P1_TX_C_DP<9>")
	)
	(segment
		(start 347.498162 -380.67107)
		(end 348.661228 -381.834136)
		(width 0.1016)
		(layer "F.Cu")
		(net "P5E_CPU0_P1_TX_C_DP<9>")
	)
	(segment
		(start 346.234766 -391.978896)
		(end 346.369132 -391.978896)
		(width 0.1016)
		(layer "F.Cu")
		(net "P5E_CPU0_P1_TX_C_DP<9>")
	)
	(segment
		(start 348.789752 -383.548382)
		(end 346.579952 -385.758182)
		(width 0.1016)
		(layer "F.Cu")
		(net "P5E_CPU0_P1_TX_C_DP<9>")
	)
	(segment
		(start 347.182694 -379.56998)
		(end 347.182694 -379.909578)
		(width 0.1016)
		(layer "F.Cu")
		(net "P5E_CPU0_P1_TX_C_DP<9>")
	)
	(segment
		(start 346.14358 -391.88771)
		(end 346.234766 -391.978896)
		(width 0.1016)
		(layer "F.Cu")
		(net "P5E_CPU0_P1_TX_C_DP<9>")
	)
	(segment
		(start 348.861126 -382.315466)
		(end 348.861126 -383.376932)
		(width 0.1016)
		(layer "F.Cu")
		(net "P5E_CPU0_P1_TX_C_DP<9>")
	)
	(segment
		(start 346.436188 -386.105908)
		(end 346.436188 -391.324592)
		(width 0.1016)
		(layer "F.Cu")
		(net "P5E_CPU0_P1_TX_C_DP<9>")
	)
	(segment
		(start 346.445586 -391.902442)
		(end 346.445586 -391.784586)
		(width 0.1016)
		(layer "F.Cu")
		(net "P5E_CPU0_P1_TX_C_DP<9>")
	)
	(segment
		(start 346.369132 -391.978896)
		(end 346.445586 -391.902442)
		(width 0.1016)
		(layer "F.Cu")
		(net "P5E_CPU0_P1_TX_C_DP<9>")
	)
	(arc
		(start 347.182694 -379.909578)
		(mid 347.264726 -380.321688)
		(end 347.498162 -380.67107)
		(width 0.1016)
		(layer "F.Cu")
		(net "P5E_CPU0_P1_TX_C_DP<9>")
	)
	(arc
		(start 348.861126 -383.376932)
		(mid 348.842461 -383.469735)
		(end 348.789752 -383.548382)
		(width 0.1016)
		(layer "F.Cu")
		(net "P5E_CPU0_P1_TX_C_DP<9>")
	)
	(arc
		(start 348.661228 -381.834136)
		(mid 348.809089 -382.054913)
		(end 348.861126 -382.315466)
		(width 0.1016)
		(layer "F.Cu")
		(net "P5E_CPU0_P1_TX_C_DP<9>")
	)
	(arc
		(start 346.579952 -385.758182)
		(mid 346.473518 -385.91775)
		(end 346.436188 -386.105908)
		(width 0.1016)
		(layer "F.Cu")
		(net "P5E_CPU0_P1_TX_C_DP<9>")
	)
	(segment
		(start 344.94343 -391.88771)
		(end 345.034616 -391.978896)
		(width 0.1016)
		(layer "F.Cu")
		(net "P5E_CPU0_P1_TX_C_DP<8>")
	)
	(segment
		(start 345.034616 -391.978896)
		(end 345.168982 -391.978896)
		(width 0.1016)
		(layer "F.Cu")
		(net "P5E_CPU0_P1_TX_C_DP<8>")
	)
	(segment
		(start 345.168982 -391.978896)
		(end 345.245436 -391.902442)
		(width 0.1016)
		(layer "F.Cu")
		(net "P5E_CPU0_P1_TX_C_DP<8>")
	)
	(segment
		(start 345.245436 -391.902442)
		(end 345.245436 -391.784586)
		(width 0.1016)
		(layer "F.Cu")
		(net "P5E_CPU0_P1_TX_C_DP<8>")
	)
	(segment
		(start 344.94343 -391.6172)
		(end 344.94343 -391.88771)
		(width 0.1016)
		(layer "F.Cu")
		(net "P5E_CPU0_P1_TX_C_DP<8>")
	)
	(segment
		(start 345.131644 -381.68453)
		(end 345.433396 -381.986282)
		(width 0.1016)
		(layer "F.Cu")
		(net "P5E_CPU0_P1_TX_C_DP<8>")
	)
	(segment
		(start 345.236038 -385.70027)
		(end 345.236038 -391.324592)
		(width 0.1016)
		(layer "F.Cu")
		(net "P5E_CPU0_P1_TX_C_DP<8>")
	)
	(segment
		(start 345.480894 -382.10109)
		(end 345.480894 -384.99923)
		(width 0.1016)
		(layer "F.Cu")
		(net "P5E_CPU0_P1_TX_C_DP<8>")
	)
	(segment
		(start 345.236038 -391.324592)
		(end 344.94343 -391.6172)
		(width 0.1016)
		(layer "F.Cu")
		(net "P5E_CPU0_P1_TX_C_DP<8>")
	)
	(arc
		(start 345.386914 -385.270502)
		(mid 345.335418 -385.345163)
		(end 345.293696 -385.425696)
		(width 0.1016)
		(layer "F.Cu")
		(net "P5E_CPU0_P1_TX_C_DP<8>")
	)
	(arc
		(start 345.480894 -384.99923)
		(mid 345.456678 -385.14275)
		(end 345.386914 -385.270502)
		(width 0.1016)
		(layer "F.Cu")
		(net "P5E_CPU0_P1_TX_C_DP<8>")
	)
	(arc
		(start 345.433396 -381.986282)
		(mid 345.468538 -382.038971)
		(end 345.480894 -382.10109)
		(width 0.1016)
		(layer "F.Cu")
		(net "P5E_CPU0_P1_TX_C_DP<8>")
	)
	(arc
		(start 345.293696 -385.425696)
		(mid 345.250542 -385.559976)
		(end 345.236038 -385.70027)
		(width 0.1016)
		(layer "F.Cu")
		(net "P5E_CPU0_P1_TX_C_DP<8>")
	)
	(segment
		(start 344.04554 -391.902442)
		(end 344.04554 -391.784586)
		(width 0.1016)
		(layer "F.Cu")
		(net "P5E_CPU0_P1_TX_C_DP<7>")
	)
	(segment
		(start 343.743534 -391.88771)
		(end 343.83472 -391.978896)
		(width 0.1016)
		(layer "F.Cu")
		(net "P5E_CPU0_P1_TX_C_DP<7>")
	)
	(segment
		(start 343.969086 -391.978896)
		(end 344.04554 -391.902442)
		(width 0.1016)
		(layer "F.Cu")
		(net "P5E_CPU0_P1_TX_C_DP<7>")
	)
	(segment
		(start 343.779094 -384.56489)
		(end 343.779094 -386.289804)
		(width 0.1016)
		(layer "F.Cu")
		(net "P5E_CPU0_P1_TX_C_DP<7>")
	)
	(segment
		(start 344.018362 -387.046216)
		(end 344.036142 -391.324592)
		(width 0.1016)
		(layer "F.Cu")
		(net "P5E_CPU0_P1_TX_C_DP<7>")
	)
	(segment
		(start 343.429844 -384.14833)
		(end 343.731596 -384.450082)
		(width 0.1016)
		(layer "F.Cu")
		(net "P5E_CPU0_P1_TX_C_DP<7>")
	)
	(segment
		(start 343.743534 -391.6172)
		(end 343.743534 -391.88771)
		(width 0.1016)
		(layer "F.Cu")
		(net "P5E_CPU0_P1_TX_C_DP<7>")
	)
	(segment
		(start 344.036142 -391.324592)
		(end 343.743534 -391.6172)
		(width 0.1016)
		(layer "F.Cu")
		(net "P5E_CPU0_P1_TX_C_DP<7>")
	)
	(segment
		(start 343.83472 -391.978896)
		(end 343.969086 -391.978896)
		(width 0.1016)
		(layer "F.Cu")
		(net "P5E_CPU0_P1_TX_C_DP<7>")
	)
	(arc
		(start 343.937844 -386.792978)
		(mid 343.997406 -386.913463)
		(end 344.018362 -387.046216)
		(width 0.1016)
		(layer "F.Cu")
		(net "P5E_CPU0_P1_TX_C_DP<7>")
	)
	(arc
		(start 343.779094 -386.289804)
		(mid 343.819772 -386.553596)
		(end 343.937844 -386.792978)
		(width 0.1016)
		(layer "F.Cu")
		(net "P5E_CPU0_P1_TX_C_DP<7>")
	)
	(arc
		(start 343.731596 -384.450082)
		(mid 343.766738 -384.502771)
		(end 343.779094 -384.56489)
		(width 0.1016)
		(layer "F.Cu")
		(net "P5E_CPU0_P1_TX_C_DP<7>")
	)
	(segment
		(start 342.835992 -390.076436)
		(end 342.835992 -391.324592)
		(width 0.1016)
		(layer "F.Cu")
		(net "P5E_CPU0_P1_TX_C_DP<6>")
	)
	(segment
		(start 340.375494 -379.56998)
		(end 340.375494 -379.86208)
		(width 0.1016)
		(layer "F.Cu")
		(net "P5E_CPU0_P1_TX_C_DP<6>")
	)
	(segment
		(start 342.63457 -391.978896)
		(end 342.768936 -391.978896)
		(width 0.1016)
		(layer "F.Cu")
		(net "P5E_CPU0_P1_TX_C_DP<6>")
	)
	(segment
		(start 342.543384 -391.88771)
		(end 342.63457 -391.978896)
		(width 0.1016)
		(layer "F.Cu")
		(net "P5E_CPU0_P1_TX_C_DP<6>")
	)
	(segment
		(start 342.543384 -391.6172)
		(end 342.543384 -391.88771)
		(width 0.1016)
		(layer "F.Cu")
		(net "P5E_CPU0_P1_TX_C_DP<6>")
	)
	(segment
		(start 340.026244 -379.22073)
		(end 340.375494 -379.56998)
		(width 0.1016)
		(layer "F.Cu")
		(net "P5E_CPU0_P1_TX_C_DP<6>")
	)
	(segment
		(start 340.701884 -380.649734)
		(end 341.934292 -381.882142)
		(width 0.1016)
		(layer "F.Cu")
		(net "P5E_CPU0_P1_TX_C_DP<6>")
	)
	(segment
		(start 342.236806 -387.115558)
		(end 342.273382 -387.205474)
		(width 0.1016)
		(layer "F.Cu")
		(net "P5E_CPU0_P1_TX_C_DP<6>")
	)
	(segment
		(start 342.768936 -391.978896)
		(end 342.84539 -391.902442)
		(width 0.1016)
		(layer "F.Cu")
		(net "P5E_CPU0_P1_TX_C_DP<6>")
	)
	(segment
		(start 342.84539 -391.902442)
		(end 342.84539 -391.784586)
		(width 0.1016)
		(layer "F.Cu")
		(net "P5E_CPU0_P1_TX_C_DP<6>")
	)
	(segment
		(start 342.835992 -391.324592)
		(end 342.543384 -391.6172)
		(width 0.1016)
		(layer "F.Cu")
		(net "P5E_CPU0_P1_TX_C_DP<6>")
	)
	(segment
		(start 342.09482 -382.268984)
		(end 342.09482 -386.388102)
		(width 0.1016)
		(layer "F.Cu")
		(net "P5E_CPU0_P1_TX_C_DP<6>")
	)
	(arc
		(start 341.934292 -381.882142)
		(mid 342.053049 -382.059597)
		(end 342.09482 -382.268984)
		(width 0.1016)
		(layer "F.Cu")
		(net "P5E_CPU0_P1_TX_C_DP<6>")
	)
	(arc
		(start 342.273382 -387.205474)
		(mid 342.693951 -388.613663)
		(end 342.835992 -390.076436)
		(width 0.1016)
		(layer "F.Cu")
		(net "P5E_CPU0_P1_TX_C_DP<6>")
	)
	(arc
		(start 342.09482 -386.388102)
		(mid 342.130625 -386.758698)
		(end 342.236806 -387.115558)
		(width 0.1016)
		(layer "F.Cu")
		(net "P5E_CPU0_P1_TX_C_DP<6>")
	)
	(arc
		(start 340.375494 -379.86208)
		(mid 340.460363 -380.288367)
		(end 340.701884 -380.649734)
		(width 0.1016)
		(layer "F.Cu")
		(net "P5E_CPU0_P1_TX_C_DP<6>")
	)
	(segment
		(start 341.343488 -391.88771)
		(end 341.434674 -391.978896)
		(width 0.1016)
		(layer "F.Cu")
		(net "P5E_CPU0_P1_TX_C_DP<5>")
	)
	(segment
		(start 341.636096 -390.033764)
		(end 341.636096 -391.324592)
		(width 0.1016)
		(layer "F.Cu")
		(net "P5E_CPU0_P1_TX_C_DP<5>")
	)
	(segment
		(start 341.56904 -391.978896)
		(end 341.645494 -391.902442)
		(width 0.1016)
		(layer "F.Cu")
		(net "P5E_CPU0_P1_TX_C_DP<5>")
	)
	(segment
		(start 338.673694 -382.03378)
		(end 338.673694 -383.744216)
		(width 0.1016)
		(layer "F.Cu")
		(net "P5E_CPU0_P1_TX_C_DP<5>")
	)
	(segment
		(start 341.636096 -391.324592)
		(end 341.343488 -391.6172)
		(width 0.1016)
		(layer "F.Cu")
		(net "P5E_CPU0_P1_TX_C_DP<5>")
	)
	(segment
		(start 341.434674 -391.978896)
		(end 341.56904 -391.978896)
		(width 0.1016)
		(layer "F.Cu")
		(net "P5E_CPU0_P1_TX_C_DP<5>")
	)
	(segment
		(start 341.645494 -391.902442)
		(end 341.645494 -391.784586)
		(width 0.1016)
		(layer "F.Cu")
		(net "P5E_CPU0_P1_TX_C_DP<5>")
	)
	(segment
		(start 341.343488 -391.6172)
		(end 341.343488 -391.88771)
		(width 0.1016)
		(layer "F.Cu")
		(net "P5E_CPU0_P1_TX_C_DP<5>")
	)
	(segment
		(start 339.037676 -384.943858)
		(end 340.967568 -387.830822)
		(width 0.1016)
		(layer "F.Cu")
		(net "P5E_CPU0_P1_TX_C_DP<5>")
	)
	(segment
		(start 338.324444 -381.68453)
		(end 338.673694 -382.03378)
		(width 0.1016)
		(layer "F.Cu")
		(net "P5E_CPU0_P1_TX_C_DP<5>")
	)
	(arc
		(start 338.673694 -383.744216)
		(mid 338.766699 -384.371034)
		(end 339.037676 -384.943858)
		(width 0.1016)
		(layer "F.Cu")
		(net "P5E_CPU0_P1_TX_C_DP<5>")
	)
	(arc
		(start 340.967568 -387.830822)
		(mid 341.465274 -388.882692)
		(end 341.636096 -390.033764)
		(width 0.1016)
		(layer "F.Cu")
		(net "P5E_CPU0_P1_TX_C_DP<5>")
	)
	(segment
		(start 336.971894 -384.71475)
		(end 337.216242 -385.303776)
		(width 0.1016)
		(layer "F.Cu")
		(net "P5E_CPU0_P1_TX_C_DP<4>")
	)
	(segment
		(start 340.4362 -391.324592)
		(end 340.143592 -391.6172)
		(width 0.1016)
		(layer "F.Cu")
		(net "P5E_CPU0_P1_TX_C_DP<4>")
	)
	(segment
		(start 340.369144 -391.978896)
		(end 340.445598 -391.902442)
		(width 0.1016)
		(layer "F.Cu")
		(net "P5E_CPU0_P1_TX_C_DP<4>")
	)
	(segment
		(start 340.143592 -391.6172)
		(end 340.143592 -391.88771)
		(width 0.1016)
		(layer "F.Cu")
		(net "P5E_CPU0_P1_TX_C_DP<4>")
	)
	(segment
		(start 337.216242 -385.303776)
		(end 340.104222 -388.822438)
		(width 0.1016)
		(layer "F.Cu")
		(net "P5E_CPU0_P1_TX_C_DP<4>")
	)
	(segment
		(start 336.622644 -384.14833)
		(end 336.971894 -384.49758)
		(width 0.1016)
		(layer "F.Cu")
		(net "P5E_CPU0_P1_TX_C_DP<4>")
	)
	(segment
		(start 340.234778 -391.978896)
		(end 340.369144 -391.978896)
		(width 0.1016)
		(layer "F.Cu")
		(net "P5E_CPU0_P1_TX_C_DP<4>")
	)
	(segment
		(start 340.445598 -391.902442)
		(end 340.445598 -391.784586)
		(width 0.1016)
		(layer "F.Cu")
		(net "P5E_CPU0_P1_TX_C_DP<4>")
	)
	(segment
		(start 340.4362 -389.954008)
		(end 340.4362 -391.324592)
		(width 0.1016)
		(layer "F.Cu")
		(net "P5E_CPU0_P1_TX_C_DP<4>")
	)
	(segment
		(start 340.143592 -391.88771)
		(end 340.234778 -391.978896)
		(width 0.1016)
		(layer "F.Cu")
		(net "P5E_CPU0_P1_TX_C_DP<4>")
	)
	(segment
		(start 336.971894 -384.49758)
		(end 336.971894 -384.71475)
		(width 0.1016)
		(layer "F.Cu")
		(net "P5E_CPU0_P1_TX_C_DP<4>")
	)
	(arc
		(start 340.104222 -388.822438)
		(mid 340.351351 -389.364422)
		(end 340.4362 -389.954008)
		(width 0.1016)
		(layer "F.Cu")
		(net "P5E_CPU0_P1_TX_C_DP<4>")
	)
	(segment
		(start 334.940656 -381.676656)
		(end 334.940656 -381.67691)
		(width 0.1016)
		(layer "F.Cu")
		(net "P5E_CPU0_P1_TX_C_DP<3>")
	)
	(segment
		(start 339.245448 -391.902442)
		(end 339.245448 -391.784586)
		(width 0.1016)
		(layer "F.Cu")
		(net "P5E_CPU0_P1_TX_C_DP<3>")
	)
	(segment
		(start 339.23605 -391.324592)
		(end 338.943442 -391.6172)
		(width 0.1016)
		(layer "F.Cu")
		(net "P5E_CPU0_P1_TX_C_DP<3>")
	)
	(segment
		(start 333.219044 -379.22073)
		(end 333.568294 -379.56998)
		(width 0.1016)
		(layer "F.Cu")
		(net "P5E_CPU0_P1_TX_C_DP<3>")
	)
	(segment
		(start 339.034628 -391.978896)
		(end 339.168994 -391.978896)
		(width 0.1016)
		(layer "F.Cu")
		(net "P5E_CPU0_P1_TX_C_DP<3>")
	)
	(segment
		(start 336.203544 -385.99364)
		(end 336.474562 -386.446014)
		(width 0.1016)
		(layer "F.Cu")
		(net "P5E_CPU0_P1_TX_C_DP<3>")
	)
	(segment
		(start 333.568294 -379.56998)
		(end 333.568294 -379.95352)
		(width 0.1016)
		(layer "F.Cu")
		(net "P5E_CPU0_P1_TX_C_DP<3>")
	)
	(segment
		(start 334.940656 -381.67691)
		(end 335.201768 -381.938022)
		(width 0.1016)
		(layer "F.Cu")
		(net "P5E_CPU0_P1_TX_C_DP<3>")
	)
	(segment
		(start 335.3435 -383.916682)
		(end 336.203544 -385.99364)
		(width 0.1016)
		(layer "F.Cu")
		(net "P5E_CPU0_P1_TX_C_DP<3>")
	)
	(segment
		(start 339.168994 -391.978896)
		(end 339.245448 -391.902442)
		(width 0.1016)
		(layer "F.Cu")
		(net "P5E_CPU0_P1_TX_C_DP<3>")
	)
	(segment
		(start 338.943442 -391.6172)
		(end 338.943442 -391.88771)
		(width 0.1016)
		(layer "F.Cu")
		(net "P5E_CPU0_P1_TX_C_DP<3>")
	)
	(segment
		(start 336.474562 -386.446014)
		(end 339.117686 -389.666734)
		(width 0.1016)
		(layer "F.Cu")
		(net "P5E_CPU0_P1_TX_C_DP<3>")
	)
	(segment
		(start 333.815944 -380.552198)
		(end 334.940656 -381.676656)
		(width 0.1016)
		(layer "F.Cu")
		(net "P5E_CPU0_P1_TX_C_DP<3>")
	)
	(segment
		(start 339.23605 -389.99668)
		(end 339.23605 -391.324592)
		(width 0.1016)
		(layer "F.Cu")
		(net "P5E_CPU0_P1_TX_C_DP<3>")
	)
	(segment
		(start 335.277968 -382.120902)
		(end 335.277968 -383.585466)
		(width 0.1016)
		(layer "F.Cu")
		(net "P5E_CPU0_P1_TX_C_DP<3>")
	)
	(segment
		(start 338.943442 -391.88771)
		(end 339.034628 -391.978896)
		(width 0.1016)
		(layer "F.Cu")
		(net "P5E_CPU0_P1_TX_C_DP<3>")
	)
	(arc
		(start 335.277968 -383.585466)
		(mid 335.294436 -383.754298)
		(end 335.3435 -383.916682)
		(width 0.1016)
		(layer "F.Cu")
		(net "P5E_CPU0_P1_TX_C_DP<3>")
	)
	(arc
		(start 335.201768 -381.938022)
		(mid 335.258106 -382.021869)
		(end 335.277968 -382.120902)
		(width 0.1016)
		(layer "F.Cu")
		(net "P5E_CPU0_P1_TX_C_DP<3>")
	)
	(arc
		(start 339.117686 -389.666734)
		(mid 339.205543 -389.821418)
		(end 339.23605 -389.99668)
		(width 0.1016)
		(layer "F.Cu")
		(net "P5E_CPU0_P1_TX_C_DP<3>")
	)
	(arc
		(start 333.568294 -379.95352)
		(mid 333.632551 -380.277503)
		(end 333.815944 -380.552198)
		(width 0.1016)
		(layer "F.Cu")
		(net "P5E_CPU0_P1_TX_C_DP<3>")
	)
	(segment
		(start 337.743546 -391.6172)
		(end 337.743546 -391.88771)
		(width 0.1016)
		(layer "F.Cu")
		(net "P5E_CPU0_P1_TX_C_DP<2>")
	)
	(segment
		(start 335.238344 -386.807456)
		(end 335.380838 -387.044692)
		(width 0.1016)
		(layer "F.Cu")
		(net "P5E_CPU0_P1_TX_C_DP<2>")
	)
	(segment
		(start 332.593188 -383.6162)
		(end 333.508096 -383.995168)
		(width 0.1016)
		(layer "F.Cu")
		(net "P5E_CPU0_P1_TX_C_DP<2>")
	)
	(segment
		(start 332.124304 -383.286762)
		(end 332.17231 -383.334768)
		(width 0.1016)
		(layer "F.Cu")
		(net "P5E_CPU0_P1_TX_C_DP<2>")
	)
	(segment
		(start 335.658714 -387.439154)
		(end 337.864958 -390.124696)
		(width 0.1016)
		(layer "F.Cu")
		(net "P5E_CPU0_P1_TX_C_DP<2>")
	)
	(segment
		(start 338.036154 -391.324592)
		(end 337.743546 -391.6172)
		(width 0.1016)
		(layer "F.Cu")
		(net "P5E_CPU0_P1_TX_C_DP<2>")
	)
	(segment
		(start 331.866494 -382.03378)
		(end 331.866494 -382.664208)
		(width 0.1016)
		(layer "F.Cu")
		(net "P5E_CPU0_P1_TX_C_DP<2>")
	)
	(segment
		(start 337.969098 -391.978896)
		(end 338.045552 -391.902442)
		(width 0.1016)
		(layer "F.Cu")
		(net "P5E_CPU0_P1_TX_C_DP<2>")
	)
	(segment
		(start 334.516476 -385.064508)
		(end 335.238344 -386.807456)
		(width 0.1016)
		(layer "F.Cu")
		(net "P5E_CPU0_P1_TX_C_DP<2>")
	)
	(segment
		(start 331.517244 -381.68453)
		(end 331.866494 -382.03378)
		(width 0.1016)
		(layer "F.Cu")
		(net "P5E_CPU0_P1_TX_C_DP<2>")
	)
	(segment
		(start 333.559404 -384.029458)
		(end 334.358996 -384.82905)
		(width 0.1016)
		(layer "F.Cu")
		(net "P5E_CPU0_P1_TX_C_DP<2>")
	)
	(segment
		(start 337.834732 -391.978896)
		(end 337.969098 -391.978896)
		(width 0.1016)
		(layer "F.Cu")
		(net "P5E_CPU0_P1_TX_C_DP<2>")
	)
	(segment
		(start 337.743546 -391.88771)
		(end 337.834732 -391.978896)
		(width 0.1016)
		(layer "F.Cu")
		(net "P5E_CPU0_P1_TX_C_DP<2>")
	)
	(segment
		(start 338.036154 -390.60247)
		(end 338.036154 -391.324592)
		(width 0.1016)
		(layer "F.Cu")
		(net "P5E_CPU0_P1_TX_C_DP<2>")
	)
	(segment
		(start 338.045552 -391.902442)
		(end 338.045552 -391.784586)
		(width 0.1016)
		(layer "F.Cu")
		(net "P5E_CPU0_P1_TX_C_DP<2>")
	)
	(arc
		(start 337.864958 -390.124696)
		(mid 337.99201 -390.348722)
		(end 338.036154 -390.60247)
		(width 0.1016)
		(layer "F.Cu")
		(net "P5E_CPU0_P1_TX_C_DP<2>")
	)
	(arc
		(start 334.358996 -384.82905)
		(mid 334.449358 -384.939008)
		(end 334.516476 -385.064508)
		(width 0.1016)
		(layer "F.Cu")
		(net "P5E_CPU0_P1_TX_C_DP<2>")
	)
	(arc
		(start 332.17231 -383.334768)
		(mid 332.368894 -383.496205)
		(end 332.593188 -383.6162)
		(width 0.1016)
		(layer "F.Cu")
		(net "P5E_CPU0_P1_TX_C_DP<2>")
	)
	(arc
		(start 335.380838 -387.044692)
		(mid 335.51253 -387.247028)
		(end 335.658714 -387.439154)
		(width 0.1016)
		(layer "F.Cu")
		(net "P5E_CPU0_P1_TX_C_DP<2>")
	)
	(arc
		(start 333.508096 -383.995168)
		(mid 333.535444 -384.009779)
		(end 333.559404 -384.029458)
		(width 0.1016)
		(layer "F.Cu")
		(net "P5E_CPU0_P1_TX_C_DP<2>")
	)
	(arc
		(start 331.866494 -382.664208)
		(mid 331.933493 -383.001123)
		(end 332.124304 -383.286762)
		(width 0.1016)
		(layer "F.Cu")
		(net "P5E_CPU0_P1_TX_C_DP<2>")
	)
	(segment
		(start 337.051904 -390.893808)
		(end 337.051904 -391.51941)
		(width 0.1016)
		(layer "F.Cu")
		(net "P5E_CPU0_P1_TX_C_DP<1>")
	)
	(segment
		(start 334.460596 -387.500876)
		(end 334.617822 -387.736588)
		(width 0.1016)
		(layer "F.Cu")
		(net "P5E_CPU0_P1_TX_C_DP<1>")
	)
	(segment
		(start 331.761592 -384.32486)
		(end 332.088998 -384.652266)
		(width 0.1016)
		(layer "F.Cu")
		(net "P5E_CPU0_P1_TX_C_DP<1>")
	)
	(segment
		(start 334.9117 -388.176262)
		(end 335.025492 -388.346442)
		(width 0.1016)
		(layer "F.Cu")
		(net "P5E_CPU0_P1_TX_C_DP<1>")
	)
	(segment
		(start 334.617822 -387.736588)
		(end 334.618076 -387.736588)
		(width 0.1016)
		(layer "F.Cu")
		(net "P5E_CPU0_P1_TX_C_DP<1>")
	)
	(segment
		(start 336.928714 -390.59612)
		(end 337.051904 -390.893808)
		(width 0.1016)
		(layer "F.Cu")
		(net "P5E_CPU0_P1_TX_C_DP<1>")
	)
	(segment
		(start 333.206598 -385.061968)
		(end 333.532734 -385.388104)
		(width 0.1016)
		(layer "F.Cu")
		(net "P5E_CPU0_P1_TX_C_DP<1>")
	)
	(segment
		(start 336.785712 -390.358122)
		(end 336.928714 -390.59612)
		(width 0.1016)
		(layer "F.Cu")
		(net "P5E_CPU0_P1_TX_C_DP<1>")
	)
	(segment
		(start 337.145376 -391.612882)
		(end 337.145376 -392.30427)
		(width 0.1016)
		(layer "F.Cu")
		(net "P5E_CPU0_P1_TX_C_DP<1>")
	)
	(segment
		(start 333.672942 -385.598416)
		(end 334.460596 -387.500876)
		(width 0.1016)
		(layer "F.Cu")
		(net "P5E_CPU0_P1_TX_C_DP<1>")
	)
	(segment
		(start 332.088998 -384.652266)
		(end 332.21676 -384.652266)
		(width 0.1016)
		(layer "F.Cu")
		(net "P5E_CPU0_P1_TX_C_DP<1>")
	)
	(segment
		(start 335.146396 -388.493254)
		(end 335.757012 -389.104124)
		(width 0.1016)
		(layer "F.Cu")
		(net "P5E_CPU0_P1_TX_C_DP<1>")
	)
	(segment
		(start 337.051904 -391.51941)
		(end 337.145376 -391.612882)
		(width 0.1016)
		(layer "F.Cu")
		(net "P5E_CPU0_P1_TX_C_DP<1>")
	)
	(segment
		(start 334.9117 -388.176008)
		(end 334.9117 -388.176262)
		(width 0.1016)
		(layer "F.Cu")
		(net "P5E_CPU0_P1_TX_C_DP<1>")
	)
	(segment
		(start 335.757012 -389.104124)
		(end 336.785712 -390.358122)
		(width 0.1016)
		(layer "F.Cu")
		(net "P5E_CPU0_P1_TX_C_DP<1>")
	)
	(segment
		(start 334.618076 -387.736588)
		(end 334.9117 -388.176008)
		(width 0.1016)
		(layer "F.Cu")
		(net "P5E_CPU0_P1_TX_C_DP<1>")
	)
	(arc
		(start 335.025492 -388.346442)
		(mid 335.082338 -388.422818)
		(end 335.146396 -388.493254)
		(width 0.1016)
		(layer "F.Cu")
		(net "P5E_CPU0_P1_TX_C_DP<1>")
	)
	(arc
		(start 332.21676 -384.652266)
		(mid 332.752448 -384.758634)
		(end 333.206598 -385.061968)
		(width 0.1016)
		(layer "F.Cu")
		(net "P5E_CPU0_P1_TX_C_DP<1>")
	)
	(arc
		(start 333.532734 -385.388104)
		(mid 333.613206 -385.486348)
		(end 333.672942 -385.598416)
		(width 0.1016)
		(layer "F.Cu")
		(net "P5E_CPU0_P1_TX_C_DP<1>")
	)
	(segment
		(start 353.636072 -390.587484)
		(end 353.636072 -391.398252)
		(width 0.1016)
		(layer "F.Cu")
		(net "P5E_CPU0_P1_TX_C_DP<15>")
	)
	(segment
		(start 358.001824 -387.853428)
		(end 357.652574 -388.202678)
		(width 0.1016)
		(layer "F.Cu")
		(net "P5E_CPU0_P1_TX_C_DP<15>")
	)
	(segment
		(start 357.652574 -388.202678)
		(end 357.190802 -388.202678)
		(width 0.1016)
		(layer "F.Cu")
		(net "P5E_CPU0_P1_TX_C_DP<15>")
	)
	(segment
		(start 353.730052 -391.700004)
		(end 353.64547 -391.784586)
		(width 0.1016)
		(layer "F.Cu")
		(net "P5E_CPU0_P1_TX_C_DP<15>")
	)
	(segment
		(start 353.636072 -391.398252)
		(end 353.730052 -391.492232)
		(width 0.1016)
		(layer "F.Cu")
		(net "P5E_CPU0_P1_TX_C_DP<15>")
	)
	(segment
		(start 356.774242 -388.090918)
		(end 356.662482 -388.202678)
		(width 0.1016)
		(layer "F.Cu")
		(net "P5E_CPU0_P1_TX_C_DP<15>")
	)
	(segment
		(start 357.079042 -388.090918)
		(end 356.774242 -388.090918)
		(width 0.1016)
		(layer "F.Cu")
		(net "P5E_CPU0_P1_TX_C_DP<15>")
	)
	(segment
		(start 355.693726 -388.30758)
		(end 353.79279 -390.208516)
		(width 0.1016)
		(layer "F.Cu")
		(net "P5E_CPU0_P1_TX_C_DP<15>")
	)
	(segment
		(start 356.662482 -388.202678)
		(end 355.947726 -388.202678)
		(width 0.1016)
		(layer "F.Cu")
		(net "P5E_CPU0_P1_TX_C_DP<15>")
	)
	(segment
		(start 353.730052 -391.492232)
		(end 353.730052 -391.700004)
		(width 0.1016)
		(layer "F.Cu")
		(net "P5E_CPU0_P1_TX_C_DP<15>")
	)
	(segment
		(start 357.190802 -388.202678)
		(end 357.079042 -388.090918)
		(width 0.1016)
		(layer "F.Cu")
		(net "P5E_CPU0_P1_TX_C_DP<15>")
	)
	(arc
		(start 355.947726 -388.202678)
		(mid 355.810273 -388.229832)
		(end 355.693726 -388.30758)
		(width 0.1016)
		(layer "F.Cu")
		(net "P5E_CPU0_P1_TX_C_DP<15>")
	)
	(arc
		(start 353.79279 -390.208516)
		(mid 353.676725 -390.382404)
		(end 353.636072 -390.587484)
		(width 0.1016)
		(layer "F.Cu")
		(net "P5E_CPU0_P1_TX_C_DP<15>")
	)
	(segment
		(start 357.656638 -385.10083)
		(end 357.342186 -385.10083)
		(width 0.1016)
		(layer "F.Cu")
		(net "P5E_CPU0_P1_TX_C_DP<14>")
	)
	(segment
		(start 352.746056 -391.40257)
		(end 352.746056 -392.303762)
		(width 0.1016)
		(layer "F.Cu")
		(net "P5E_CPU0_P1_TX_C_DP<14>")
	)
	(segment
		(start 352.65233 -390.071102)
		(end 352.652076 -390.070848)
		(width 0.1016)
		(layer "F.Cu")
		(net "P5E_CPU0_P1_TX_C_DP<14>")
	)
	(segment
		(start 352.746056 -392.303762)
		(end 352.745548 -392.30427)
		(width 0.1016)
		(layer "F.Cu")
		(net "P5E_CPU0_P1_TX_C_DP<14>")
	)
	(segment
		(start 352.652076 -390.070848)
		(end 352.652076 -391.30859)
		(width 0.1016)
		(layer "F.Cu")
		(net "P5E_CPU0_P1_TX_C_DP<14>")
	)
	(segment
		(start 357.796338 -385.158742)
		(end 357.656638 -385.10083)
		(width 0.1016)
		(layer "F.Cu")
		(net "P5E_CPU0_P1_TX_C_DP<14>")
	)
	(segment
		(start 352.652076 -391.30859)
		(end 352.746056 -391.40257)
		(width 0.1016)
		(layer "F.Cu")
		(net "P5E_CPU0_P1_TX_C_DP<14>")
	)
	(segment
		(start 358.001824 -385.364228)
		(end 357.796338 -385.158742)
		(width 0.1016)
		(layer "F.Cu")
		(net "P5E_CPU0_P1_TX_C_DP<14>")
	)
	(segment
		(start 357.342186 -385.10083)
		(end 352.849942 -389.593074)
		(width 0.1016)
		(layer "F.Cu")
		(net "P5E_CPU0_P1_TX_C_DP<14>")
	)
	(arc
		(start 352.849942 -389.593074)
		(mid 352.703616 -389.812439)
		(end 352.65233 -390.071102)
		(width 0.1016)
		(layer "F.Cu")
		(net "P5E_CPU0_P1_TX_C_DP<14>")
	)
	(segment
		(start 351.16897 -391.978896)
		(end 351.245424 -391.902442)
		(width 0.1016)
		(layer "F.Cu")
		(net "P5E_CPU0_P1_TX_C_DP<13>")
	)
	(segment
		(start 357.708454 -380.670816)
		(end 358.913176 -381.875538)
		(width 0.1016)
		(layer "F.Cu")
		(net "P5E_CPU0_P1_TX_C_DP<13>")
	)
	(segment
		(start 357.044244 -379.22073)
		(end 357.393494 -379.56998)
		(width 0.1016)
		(layer "F.Cu")
		(net "P5E_CPU0_P1_TX_C_DP<13>")
	)
	(segment
		(start 358.894888 -382.93548)
		(end 358.469438 -383.36093)
		(width 0.1016)
		(layer "F.Cu")
		(net "P5E_CPU0_P1_TX_C_DP<13>")
	)
	(segment
		(start 351.236026 -389.354822)
		(end 351.236026 -391.324592)
		(width 0.1016)
		(layer "F.Cu")
		(net "P5E_CPU0_P1_TX_C_DP<13>")
	)
	(segment
		(start 356.733094 -383.715006)
		(end 351.336356 -389.111744)
		(width 0.1016)
		(layer "F.Cu")
		(net "P5E_CPU0_P1_TX_C_DP<13>")
	)
	(segment
		(start 351.245424 -391.902442)
		(end 351.245424 -391.784586)
		(width 0.1016)
		(layer "F.Cu")
		(net "P5E_CPU0_P1_TX_C_DP<13>")
	)
	(segment
		(start 359.067608 -382.248156)
		(end 359.067608 -382.518666)
		(width 0.1016)
		(layer "F.Cu")
		(net "P5E_CPU0_P1_TX_C_DP<13>")
	)
	(segment
		(start 357.393494 -379.56998)
		(end 357.393494 -379.909578)
		(width 0.1016)
		(layer "F.Cu")
		(net "P5E_CPU0_P1_TX_C_DP<13>")
	)
	(segment
		(start 350.943418 -391.6172)
		(end 350.943418 -391.88771)
		(width 0.1016)
		(layer "F.Cu")
		(net "P5E_CPU0_P1_TX_C_DP<13>")
	)
	(segment
		(start 358.18445 -383.47904)
		(end 357.303578 -383.47904)
		(width 0.1016)
		(layer "F.Cu")
		(net "P5E_CPU0_P1_TX_C_DP<13>")
	)
	(segment
		(start 351.236026 -391.324592)
		(end 350.943418 -391.6172)
		(width 0.1016)
		(layer "F.Cu")
		(net "P5E_CPU0_P1_TX_C_DP<13>")
	)
	(segment
		(start 350.943418 -391.88771)
		(end 351.034604 -391.978896)
		(width 0.1016)
		(layer "F.Cu")
		(net "P5E_CPU0_P1_TX_C_DP<13>")
	)
	(segment
		(start 351.034604 -391.978896)
		(end 351.16897 -391.978896)
		(width 0.1016)
		(layer "F.Cu")
		(net "P5E_CPU0_P1_TX_C_DP<13>")
	)
	(arc
		(start 358.469438 -383.36093)
		(mid 358.338699 -383.44835)
		(end 358.18445 -383.47904)
		(width 0.1016)
		(layer "F.Cu")
		(net "P5E_CPU0_P1_TX_C_DP<13>")
	)
	(arc
		(start 358.913176 -381.875538)
		(mid 359.027461 -382.046482)
		(end 359.067608 -382.248156)
		(width 0.1016)
		(layer "F.Cu")
		(net "P5E_CPU0_P1_TX_C_DP<13>")
	)
	(arc
		(start 351.336356 -389.111744)
		(mid 351.262057 -389.223313)
		(end 351.236026 -389.354822)
		(width 0.1016)
		(layer "F.Cu")
		(net "P5E_CPU0_P1_TX_C_DP<13>")
	)
	(arc
		(start 357.393494 -379.909578)
		(mid 357.475234 -380.321543)
		(end 357.708454 -380.670816)
		(width 0.1016)
		(layer "F.Cu")
		(net "P5E_CPU0_P1_TX_C_DP<13>")
	)
	(arc
		(start 357.303578 -383.47904)
		(mid 356.994841 -383.540246)
		(end 356.733094 -383.715006)
		(width 0.1016)
		(layer "F.Cu")
		(net "P5E_CPU0_P1_TX_C_DP<13>")
	)
	(arc
		(start 359.067608 -382.518666)
		(mid 359.022717 -382.744257)
		(end 358.894888 -382.93548)
		(width 0.1016)
		(layer "F.Cu")
		(net "P5E_CPU0_P1_TX_C_DP<13>")
	)
	(segment
		(start 349.969074 -391.978896)
		(end 350.045528 -391.902442)
		(width 0.1016)
		(layer "F.Cu")
		(net "P5E_CPU0_P1_TX_C_DP<12>")
	)
	(segment
		(start 350.03613 -389.116062)
		(end 350.03613 -391.324592)
		(width 0.1016)
		(layer "F.Cu")
		(net "P5E_CPU0_P1_TX_C_DP<12>")
	)
	(segment
		(start 350.03613 -391.324592)
		(end 349.743522 -391.6172)
		(width 0.1016)
		(layer "F.Cu")
		(net "P5E_CPU0_P1_TX_C_DP<12>")
	)
	(segment
		(start 350.045528 -391.902442)
		(end 350.045528 -391.784586)
		(width 0.1016)
		(layer "F.Cu")
		(net "P5E_CPU0_P1_TX_C_DP<12>")
	)
	(segment
		(start 349.743522 -391.88771)
		(end 349.834708 -391.978896)
		(width 0.1016)
		(layer "F.Cu")
		(net "P5E_CPU0_P1_TX_C_DP<12>")
	)
	(segment
		(start 349.834708 -391.978896)
		(end 349.969074 -391.978896)
		(width 0.1016)
		(layer "F.Cu")
		(net "P5E_CPU0_P1_TX_C_DP<12>")
	)
	(segment
		(start 354.242116 -380.529338)
		(end 355.66223 -381.949198)
		(width 0.1016)
		(layer "F.Cu")
		(net "P5E_CPU0_P1_TX_C_DP<12>")
	)
	(segment
		(start 355.626924 -383.119376)
		(end 350.32315 -388.42315)
		(width 0.1016)
		(layer "F.Cu")
		(net "P5E_CPU0_P1_TX_C_DP<12>")
	)
	(segment
		(start 349.743522 -391.6172)
		(end 349.743522 -391.88771)
		(width 0.1016)
		(layer "F.Cu")
		(net "P5E_CPU0_P1_TX_C_DP<12>")
	)
	(segment
		(start 353.640644 -379.22073)
		(end 353.989894 -379.56998)
		(width 0.1016)
		(layer "F.Cu")
		(net "P5E_CPU0_P1_TX_C_DP<12>")
	)
	(segment
		(start 355.699568 -382.039368)
		(end 355.699568 -382.944878)
		(width 0.1016)
		(layer "F.Cu")
		(net "P5E_CPU0_P1_TX_C_DP<12>")
	)
	(segment
		(start 353.989894 -379.56998)
		(end 353.989894 -379.9205)
		(width 0.1016)
		(layer "F.Cu")
		(net "P5E_CPU0_P1_TX_C_DP<12>")
	)
	(arc
		(start 355.66223 -381.949198)
		(mid 355.689873 -381.990568)
		(end 355.699568 -382.039368)
		(width 0.1016)
		(layer "F.Cu")
		(net "P5E_CPU0_P1_TX_C_DP<12>")
	)
	(arc
		(start 353.989894 -379.9205)
		(mid 354.055438 -380.250013)
		(end 354.242116 -380.529338)
		(width 0.1016)
		(layer "F.Cu")
		(net "P5E_CPU0_P1_TX_C_DP<12>")
	)
	(arc
		(start 355.699568 -382.944878)
		(mid 355.680574 -383.039333)
		(end 355.626924 -383.119376)
		(width 0.1016)
		(layer "F.Cu")
		(net "P5E_CPU0_P1_TX_C_DP<12>")
	)
	(arc
		(start 350.32315 -388.42315)
		(mid 350.110729 -388.741061)
		(end 350.03613 -389.116062)
		(width 0.1016)
		(layer "F.Cu")
		(net "P5E_CPU0_P1_TX_C_DP<12>")
	)
	(segment
		(start 352.250756 -384.708654)
		(end 348.935294 -388.024116)
		(width 0.1016)
		(layer "F.Cu")
		(net "P5E_CPU0_P1_TX_C_DP<11>")
	)
	(segment
		(start 351.938844 -381.68453)
		(end 352.288094 -382.03378)
		(width 0.1016)
		(layer "F.Cu")
		(net "P5E_CPU0_P1_TX_C_DP<11>")
	)
	(segment
		(start 348.543372 -391.88771)
		(end 348.634558 -391.978896)
		(width 0.1016)
		(layer "F.Cu")
		(net "P5E_CPU0_P1_TX_C_DP<11>")
	)
	(segment
		(start 348.83598 -391.324592)
		(end 348.543372 -391.6172)
		(width 0.1016)
		(layer "F.Cu")
		(net "P5E_CPU0_P1_TX_C_DP<11>")
	)
	(segment
		(start 348.83598 -388.266178)
		(end 348.83598 -391.324592)
		(width 0.1016)
		(layer "F.Cu")
		(net "P5E_CPU0_P1_TX_C_DP<11>")
	)
	(segment
		(start 348.845378 -391.902442)
		(end 348.845378 -391.784586)
		(width 0.1016)
		(layer "F.Cu")
		(net "P5E_CPU0_P1_TX_C_DP<11>")
	)
	(segment
		(start 352.288094 -382.03378)
		(end 352.288094 -384.618484)
		(width 0.1016)
		(layer "F.Cu")
		(net "P5E_CPU0_P1_TX_C_DP<11>")
	)
	(segment
		(start 348.543372 -391.6172)
		(end 348.543372 -391.88771)
		(width 0.1016)
		(layer "F.Cu")
		(net "P5E_CPU0_P1_TX_C_DP<11>")
	)
	(segment
		(start 348.634558 -391.978896)
		(end 348.768924 -391.978896)
		(width 0.1016)
		(layer "F.Cu")
		(net "P5E_CPU0_P1_TX_C_DP<11>")
	)
	(segment
		(start 348.768924 -391.978896)
		(end 348.845378 -391.902442)
		(width 0.1016)
		(layer "F.Cu")
		(net "P5E_CPU0_P1_TX_C_DP<11>")
	)
	(arc
		(start 352.288094 -384.618484)
		(mid 352.278388 -384.667279)
		(end 352.250756 -384.708654)
		(width 0.1016)
		(layer "F.Cu")
		(net "P5E_CPU0_P1_TX_C_DP<11>")
	)
	(arc
		(start 348.935294 -388.024116)
		(mid 348.861733 -388.135332)
		(end 348.83598 -388.266178)
		(width 0.1016)
		(layer "F.Cu")
		(net "P5E_CPU0_P1_TX_C_DP<11>")
	)
	(segment
		(start 347.91523 -386.86486)
		(end 347.736414 -387.043676)
		(width 0.1016)
		(layer "F.Cu")
		(net "P5E_CPU0_P1_TX_C_DP<10>")
	)
	(segment
		(start 350.237044 -384.14833)
		(end 350.585278 -384.496564)
		(width 0.1016)
		(layer "F.Cu")
		(net "P5E_CPU0_P1_TX_C_DP<10>")
	)
	(segment
		(start 348.968822 -385.811522)
		(end 347.915484 -386.86486)
		(width 0.1016)
		(layer "F.Cu")
		(net "P5E_CPU0_P1_TX_C_DP<10>")
	)
	(segment
		(start 347.645482 -391.902442)
		(end 347.645482 -391.784586)
		(width 0.1016)
		(layer "F.Cu")
		(net "P5E_CPU0_P1_TX_C_DP<10>")
	)
	(segment
		(start 347.636084 -391.324592)
		(end 347.343476 -391.6172)
		(width 0.1016)
		(layer "F.Cu")
		(net "P5E_CPU0_P1_TX_C_DP<10>")
	)
	(segment
		(start 347.343476 -391.6172)
		(end 347.343476 -391.88771)
		(width 0.1016)
		(layer "F.Cu")
		(net "P5E_CPU0_P1_TX_C_DP<10>")
	)
	(segment
		(start 347.569028 -391.978896)
		(end 347.645482 -391.902442)
		(width 0.1016)
		(layer "F.Cu")
		(net "P5E_CPU0_P1_TX_C_DP<10>")
	)
	(segment
		(start 347.636084 -387.286754)
		(end 347.636084 -391.324592)
		(width 0.1016)
		(layer "F.Cu")
		(net "P5E_CPU0_P1_TX_C_DP<10>")
	)
	(segment
		(start 349.452184 -385.703572)
		(end 349.229426 -385.703572)
		(width 0.1016)
		(layer "F.Cu")
		(net "P5E_CPU0_P1_TX_C_DP<10>")
	)
	(segment
		(start 350.585278 -384.496564)
		(end 350.585278 -384.584702)
		(width 0.1016)
		(layer "F.Cu")
		(net "P5E_CPU0_P1_TX_C_DP<10>")
	)
	(segment
		(start 347.434662 -391.978896)
		(end 347.569028 -391.978896)
		(width 0.1016)
		(layer "F.Cu")
		(net "P5E_CPU0_P1_TX_C_DP<10>")
	)
	(segment
		(start 347.343476 -391.88771)
		(end 347.434662 -391.978896)
		(width 0.1016)
		(layer "F.Cu")
		(net "P5E_CPU0_P1_TX_C_DP<10>")
	)
	(segment
		(start 347.915484 -386.86486)
		(end 347.91523 -386.86486)
		(width 0.1016)
		(layer "F.Cu")
		(net "P5E_CPU0_P1_TX_C_DP<10>")
	)
	(segment
		(start 350.54794 -384.674872)
		(end 349.566484 -385.656328)
		(width 0.1016)
		(layer "F.Cu")
		(net "P5E_CPU0_P1_TX_C_DP<10>")
	)
	(arc
		(start 349.566484 -385.656328)
		(mid 349.514029 -385.691315)
		(end 349.452184 -385.703572)
		(width 0.1016)
		(layer "F.Cu")
		(net "P5E_CPU0_P1_TX_C_DP<10>")
	)
	(arc
		(start 347.736414 -387.043676)
		(mid 347.662115 -387.155245)
		(end 347.636084 -387.286754)
		(width 0.1016)
		(layer "F.Cu")
		(net "P5E_CPU0_P1_TX_C_DP<10>")
	)
	(arc
		(start 349.229426 -385.703572)
		(mid 349.088386 -385.731627)
		(end 348.968822 -385.811522)
		(width 0.1016)
		(layer "F.Cu")
		(net "P5E_CPU0_P1_TX_C_DP<10>")
	)
	(arc
		(start 350.585278 -384.584702)
		(mid 350.575572 -384.633497)
		(end 350.54794 -384.674872)
		(width 0.1016)
		(layer "F.Cu")
		(net "P5E_CPU0_P1_TX_C_DP<10>")
	)
	(segment
		(start 333.77886 -390.425432)
		(end 334.280002 -390.425432)
		(width 0.1016)
		(layer "F.Cu")
		(net "P5E_CPU0_P1_TX_C_DP<0>")
	)
	(segment
		(start 332.52918 -390.537192)
		(end 332.83398 -390.537192)
		(width 0.1016)
		(layer "F.Cu")
		(net "P5E_CPU0_P1_TX_C_DP<0>")
	)
	(segment
		(start 334.477868 -390.464802)
		(end 335.08315 -390.714738)
		(width 0.1016)
		(layer "F.Cu")
		(net "P5E_CPU0_P1_TX_C_DP<0>")
	)
	(segment
		(start 335.434686 -391.978896)
		(end 335.569052 -391.978896)
		(width 0.1016)
		(layer "F.Cu")
		(net "P5E_CPU0_P1_TX_C_DP<0>")
	)
	(segment
		(start 332.83398 -390.537192)
		(end 332.94574 -390.425432)
		(width 0.1016)
		(layer "F.Cu")
		(net "P5E_CPU0_P1_TX_C_DP<0>")
	)
	(segment
		(start 332.41742 -390.425432)
		(end 332.52918 -390.537192)
		(width 0.1016)
		(layer "F.Cu")
		(net "P5E_CPU0_P1_TX_C_DP<0>")
	)
	(segment
		(start 331.761592 -390.77646)
		(end 332.11262 -390.425432)
		(width 0.1016)
		(layer "F.Cu")
		(net "P5E_CPU0_P1_TX_C_DP<0>")
	)
	(segment
		(start 332.94574 -390.425432)
		(end 333.25054 -390.425432)
		(width 0.1016)
		(layer "F.Cu")
		(net "P5E_CPU0_P1_TX_C_DP<0>")
	)
	(segment
		(start 333.6671 -390.537192)
		(end 333.77886 -390.425432)
		(width 0.1016)
		(layer "F.Cu")
		(net "P5E_CPU0_P1_TX_C_DP<0>")
	)
	(segment
		(start 335.569052 -391.978896)
		(end 335.645506 -391.902442)
		(width 0.1016)
		(layer "F.Cu")
		(net "P5E_CPU0_P1_TX_C_DP<0>")
	)
	(segment
		(start 335.3435 -391.6172)
		(end 335.3435 -391.88771)
		(width 0.1016)
		(layer "F.Cu")
		(net "P5E_CPU0_P1_TX_C_DP<0>")
	)
	(segment
		(start 335.294732 -390.85647)
		(end 335.636108 -391.199624)
		(width 0.1016)
		(layer "F.Cu")
		(net "P5E_CPU0_P1_TX_C_DP<0>")
	)
	(segment
		(start 332.11262 -390.425432)
		(end 332.41742 -390.425432)
		(width 0.1016)
		(layer "F.Cu")
		(net "P5E_CPU0_P1_TX_C_DP<0>")
	)
	(segment
		(start 335.645506 -391.902442)
		(end 335.645506 -391.784586)
		(width 0.1016)
		(layer "F.Cu")
		(net "P5E_CPU0_P1_TX_C_DP<0>")
	)
	(segment
		(start 333.25054 -390.425432)
		(end 333.3623 -390.537192)
		(width 0.1016)
		(layer "F.Cu")
		(net "P5E_CPU0_P1_TX_C_DP<0>")
	)
	(segment
		(start 335.3435 -391.88771)
		(end 335.434686 -391.978896)
		(width 0.1016)
		(layer "F.Cu")
		(net "P5E_CPU0_P1_TX_C_DP<0>")
	)
	(segment
		(start 335.636108 -391.199624)
		(end 335.636108 -391.324592)
		(width 0.1016)
		(layer "F.Cu")
		(net "P5E_CPU0_P1_TX_C_DP<0>")
	)
	(segment
		(start 333.3623 -390.537192)
		(end 333.6671 -390.537192)
		(width 0.1016)
		(layer "F.Cu")
		(net "P5E_CPU0_P1_TX_C_DP<0>")
	)
	(segment
		(start 335.636108 -391.324592)
		(end 335.3435 -391.6172)
		(width 0.1016)
		(layer "F.Cu")
		(net "P5E_CPU0_P1_TX_C_DP<0>")
	)
	(arc
		(start 334.280002 -390.425432)
		(mid 334.380867 -390.435399)
		(end 334.477868 -390.464802)
		(width 0.1016)
		(layer "F.Cu")
		(net "P5E_CPU0_P1_TX_C_DP<0>")
	)
	(arc
		(start 335.08315 -390.714738)
		(mid 335.195981 -390.775093)
		(end 335.294732 -390.85647)
		(width 0.1016)
		(layer "F.Cu")
		(net "P5E_CPU0_P1_TX_C_DP<0>")
	)
	(segment
		(start 347.747844 -379.22073)
		(end 347.398594 -379.56998)
		(width 0.1016)
		(layer "F.Cu")
		(net "P5E_CPU0_P1_TX_C_DN<9>")
	)
	(segment
		(start 347.707966 -384.935984)
		(end 346.73286 -385.91109)
		(width 0.1016)
		(layer "F.Cu")
		(net "P5E_CPU0_P1_TX_C_DN<9>")
	)
	(segment
		(start 347.65107 -380.518162)
		(end 348.814136 -381.681228)
		(width 0.1016)
		(layer "F.Cu")
		(net "P5E_CPU0_P1_TX_C_DN<9>")
	)
	(segment
		(start 346.74556 -391.612882)
		(end 346.74556 -392.30427)
		(width 0.1016)
		(layer "F.Cu")
		(net "P5E_CPU0_P1_TX_C_DN<9>")
	)
	(segment
		(start 346.652088 -386.105908)
		(end 346.652088 -391.51941)
		(width 0.1016)
		(layer "F.Cu")
		(net "P5E_CPU0_P1_TX_C_DN<9>")
	)
	(segment
		(start 348.081854 -384.562096)
		(end 348.081854 -384.720084)
		(width 0.1016)
		(layer "F.Cu")
		(net "P5E_CPU0_P1_TX_C_DN<9>")
	)
	(segment
		(start 348.94266 -383.70129)
		(end 348.081854 -384.562096)
		(width 0.1016)
		(layer "F.Cu")
		(net "P5E_CPU0_P1_TX_C_DN<9>")
	)
	(segment
		(start 347.865954 -384.935984)
		(end 347.707966 -384.935984)
		(width 0.1016)
		(layer "F.Cu")
		(net "P5E_CPU0_P1_TX_C_DN<9>")
	)
	(segment
		(start 349.077026 -382.315466)
		(end 349.077026 -383.376932)
		(width 0.1016)
		(layer "F.Cu")
		(net "P5E_CPU0_P1_TX_C_DN<9>")
	)
	(segment
		(start 347.398594 -379.56998)
		(end 347.398594 -379.909324)
		(width 0.1016)
		(layer "F.Cu")
		(net "P5E_CPU0_P1_TX_C_DN<9>")
	)
	(segment
		(start 348.081854 -384.720084)
		(end 347.865954 -384.935984)
		(width 0.1016)
		(layer "F.Cu")
		(net "P5E_CPU0_P1_TX_C_DN<9>")
	)
	(segment
		(start 346.652088 -391.51941)
		(end 346.74556 -391.612882)
		(width 0.1016)
		(layer "F.Cu")
		(net "P5E_CPU0_P1_TX_C_DN<9>")
	)
	(arc
		(start 348.814136 -381.681228)
		(mid 349.008653 -381.972204)
		(end 349.077026 -382.315466)
		(width 0.1016)
		(layer "F.Cu")
		(net "P5E_CPU0_P1_TX_C_DN<9>")
	)
	(arc
		(start 349.077026 -383.376932)
		(mid 349.042108 -383.552478)
		(end 348.94266 -383.70129)
		(width 0.1016)
		(layer "F.Cu")
		(net "P5E_CPU0_P1_TX_C_DN<9>")
	)
	(arc
		(start 346.73286 -385.91109)
		(mid 346.673082 -386.000459)
		(end 346.652088 -386.105908)
		(width 0.1016)
		(layer "F.Cu")
		(net "P5E_CPU0_P1_TX_C_DN<9>")
	)
	(arc
		(start 347.398594 -379.909324)
		(mid 347.464324 -380.238827)
		(end 347.65107 -380.518162)
		(width 0.1016)
		(layer "F.Cu")
		(net "P5E_CPU0_P1_TX_C_DN<9>")
	)
	(segment
		(start 345.54541 -391.612882)
		(end 345.54541 -392.30427)
		(width 0.1016)
		(layer "F.Cu")
		(net "P5E_CPU0_P1_TX_C_DN<8>")
	)
	(segment
		(start 345.451938 -391.51941)
		(end 345.54541 -391.612882)
		(width 0.1016)
		(layer "F.Cu")
		(net "P5E_CPU0_P1_TX_C_DN<8>")
	)
	(segment
		(start 346.046044 -381.68453)
		(end 345.744292 -381.986282)
		(width 0.1016)
		(layer "F.Cu")
		(net "P5E_CPU0_P1_TX_C_DN<8>")
	)
	(segment
		(start 345.696794 -383.22504)
		(end 345.808554 -383.3368)
		(width 0.1016)
		(layer "F.Cu")
		(net "P5E_CPU0_P1_TX_C_DN<8>")
	)
	(segment
		(start 345.696794 -382.10109)
		(end 345.696794 -383.22504)
		(width 0.1016)
		(layer "F.Cu")
		(net "P5E_CPU0_P1_TX_C_DN<8>")
	)
	(segment
		(start 345.451938 -385.700016)
		(end 345.451938 -391.51941)
		(width 0.1016)
		(layer "F.Cu")
		(net "P5E_CPU0_P1_TX_C_DN<8>")
	)
	(segment
		(start 345.696794 -383.75336)
		(end 345.696794 -384.998976)
		(width 0.1016)
		(layer "F.Cu")
		(net "P5E_CPU0_P1_TX_C_DN<8>")
	)
	(segment
		(start 345.808554 -383.3368)
		(end 345.808554 -383.6416)
		(width 0.1016)
		(layer "F.Cu")
		(net "P5E_CPU0_P1_TX_C_DN<8>")
	)
	(segment
		(start 345.808554 -383.6416)
		(end 345.696794 -383.75336)
		(width 0.1016)
		(layer "F.Cu")
		(net "P5E_CPU0_P1_TX_C_DN<8>")
	)
	(arc
		(start 345.696794 -384.998976)
		(mid 345.660797 -385.213347)
		(end 345.556586 -385.404106)
		(width 0.1016)
		(layer "F.Cu")
		(net "P5E_CPU0_P1_TX_C_DN<8>")
	)
	(arc
		(start 345.491308 -385.512818)
		(mid 345.461844 -385.604364)
		(end 345.451938 -385.700016)
		(width 0.1016)
		(layer "F.Cu")
		(net "P5E_CPU0_P1_TX_C_DN<8>")
	)
	(arc
		(start 345.556586 -385.404106)
		(mid 345.520522 -385.456405)
		(end 345.491308 -385.512818)
		(width 0.1016)
		(layer "F.Cu")
		(net "P5E_CPU0_P1_TX_C_DN<8>")
	)
	(arc
		(start 345.744292 -381.986282)
		(mid 345.70915 -382.038971)
		(end 345.696794 -382.10109)
		(width 0.1016)
		(layer "F.Cu")
		(net "P5E_CPU0_P1_TX_C_DN<8>")
	)
	(segment
		(start 344.106754 -385.87299)
		(end 343.994994 -385.98475)
		(width 0.1016)
		(layer "F.Cu")
		(net "P5E_CPU0_P1_TX_C_DN<7>")
	)
	(segment
		(start 344.234262 -387.0452)
		(end 344.252042 -391.32383)
		(width 0.1016)
		(layer "F.Cu")
		(net "P5E_CPU0_P1_TX_C_DN<7>")
	)
	(segment
		(start 344.252042 -391.32383)
		(end 344.252042 -391.51941)
		(width 0.1016)
		(layer "F.Cu")
		(net "P5E_CPU0_P1_TX_C_DN<7>")
	)
	(segment
		(start 344.252042 -391.51941)
		(end 344.345514 -391.612882)
		(width 0.1016)
		(layer "F.Cu")
		(net "P5E_CPU0_P1_TX_C_DN<7>")
	)
	(segment
		(start 344.106754 -385.56819)
		(end 344.106754 -385.87299)
		(width 0.1016)
		(layer "F.Cu")
		(net "P5E_CPU0_P1_TX_C_DN<7>")
	)
	(segment
		(start 344.345514 -391.612882)
		(end 344.345514 -392.30427)
		(width 0.1016)
		(layer "F.Cu")
		(net "P5E_CPU0_P1_TX_C_DN<7>")
	)
	(segment
		(start 343.994994 -385.98475)
		(end 343.994994 -386.28955)
		(width 0.1016)
		(layer "F.Cu")
		(net "P5E_CPU0_P1_TX_C_DN<7>")
	)
	(segment
		(start 343.994994 -385.45643)
		(end 344.106754 -385.56819)
		(width 0.1016)
		(layer "F.Cu")
		(net "P5E_CPU0_P1_TX_C_DN<7>")
	)
	(segment
		(start 343.994994 -384.564636)
		(end 343.994994 -385.45643)
		(width 0.1016)
		(layer "F.Cu")
		(net "P5E_CPU0_P1_TX_C_DN<7>")
	)
	(segment
		(start 344.344244 -384.14833)
		(end 344.042238 -384.450336)
		(width 0.1016)
		(layer "F.Cu")
		(net "P5E_CPU0_P1_TX_C_DN<7>")
	)
	(arc
		(start 344.042238 -384.450336)
		(mid 344.007251 -384.502791)
		(end 343.994994 -384.564636)
		(width 0.1016)
		(layer "F.Cu")
		(net "P5E_CPU0_P1_TX_C_DN<7>")
	)
	(arc
		(start 343.994994 -386.28955)
		(mid 344.025536 -386.488219)
		(end 344.114374 -386.668518)
		(width 0.1016)
		(layer "F.Cu")
		(net "P5E_CPU0_P1_TX_C_DN<7>")
	)
	(arc
		(start 344.114374 -386.668518)
		(mid 344.203073 -386.847706)
		(end 344.234262 -387.0452)
		(width 0.1016)
		(layer "F.Cu")
		(net "P5E_CPU0_P1_TX_C_DN<7>")
	)
	(segment
		(start 340.940644 -379.22073)
		(end 340.591394 -379.56998)
		(width 0.1016)
		(layer "F.Cu")
		(net "P5E_CPU0_P1_TX_C_DN<6>")
	)
	(segment
		(start 340.854792 -380.496826)
		(end 342.0872 -381.729234)
		(width 0.1016)
		(layer "F.Cu")
		(net "P5E_CPU0_P1_TX_C_DN<6>")
	)
	(segment
		(start 342.42248 -383.647696)
		(end 342.31072 -383.759456)
		(width 0.1016)
		(layer "F.Cu")
		(net "P5E_CPU0_P1_TX_C_DN<6>")
	)
	(segment
		(start 343.051892 -391.51941)
		(end 343.145618 -391.613136)
		(width 0.1016)
		(layer "F.Cu")
		(net "P5E_CPU0_P1_TX_C_DN<6>")
	)
	(segment
		(start 343.051892 -390.076182)
		(end 343.051892 -391.51941)
		(width 0.1016)
		(layer "F.Cu")
		(net "P5E_CPU0_P1_TX_C_DN<6>")
	)
	(segment
		(start 340.591394 -379.56998)
		(end 340.591394 -379.861826)
		(width 0.1016)
		(layer "F.Cu")
		(net "P5E_CPU0_P1_TX_C_DN<6>")
	)
	(segment
		(start 342.31072 -383.759456)
		(end 342.31072 -386.388356)
		(width 0.1016)
		(layer "F.Cu")
		(net "P5E_CPU0_P1_TX_C_DN<6>")
	)
	(segment
		(start 342.31072 -382.26873)
		(end 342.31072 -383.231136)
		(width 0.1016)
		(layer "F.Cu")
		(net "P5E_CPU0_P1_TX_C_DN<6>")
	)
	(segment
		(start 342.436958 -387.034278)
		(end 342.473534 -387.124194)
		(width 0.1016)
		(layer "F.Cu")
		(net "P5E_CPU0_P1_TX_C_DN<6>")
	)
	(segment
		(start 342.42248 -383.342896)
		(end 342.42248 -383.647696)
		(width 0.1016)
		(layer "F.Cu")
		(net "P5E_CPU0_P1_TX_C_DN<6>")
	)
	(segment
		(start 343.145618 -391.613136)
		(end 343.145618 -392.30427)
		(width 0.1016)
		(layer "F.Cu")
		(net "P5E_CPU0_P1_TX_C_DN<6>")
	)
	(segment
		(start 342.31072 -383.231136)
		(end 342.42248 -383.342896)
		(width 0.1016)
		(layer "F.Cu")
		(net "P5E_CPU0_P1_TX_C_DN<6>")
	)
	(arc
		(start 342.0872 -381.729234)
		(mid 342.252565 -381.97677)
		(end 342.31072 -382.26873)
		(width 0.1016)
		(layer "F.Cu")
		(net "P5E_CPU0_P1_TX_C_DN<6>")
	)
	(arc
		(start 340.591394 -379.861826)
		(mid 340.659961 -380.205506)
		(end 340.854792 -380.496826)
		(width 0.1016)
		(layer "F.Cu")
		(net "P5E_CPU0_P1_TX_C_DN<6>")
	)
	(arc
		(start 342.473534 -387.124194)
		(mid 342.9059 -388.572135)
		(end 343.051892 -390.076182)
		(width 0.1016)
		(layer "F.Cu")
		(net "P5E_CPU0_P1_TX_C_DN<6>")
	)
	(arc
		(start 342.31072 -386.388356)
		(mid 342.342593 -386.717425)
		(end 342.436958 -387.034278)
		(width 0.1016)
		(layer "F.Cu")
		(net "P5E_CPU0_P1_TX_C_DN<6>")
	)
	(segment
		(start 341.945468 -391.612882)
		(end 341.945468 -392.30427)
		(width 0.1016)
		(layer "F.Cu")
		(net "P5E_CPU0_P1_TX_C_DN<5>")
	)
	(segment
		(start 338.889594 -382.911096)
		(end 339.001354 -383.022856)
		(width 0.1016)
		(layer "F.Cu")
		(net "P5E_CPU0_P1_TX_C_DN<5>")
	)
	(segment
		(start 339.001354 -383.022856)
		(end 339.001354 -383.327656)
		(width 0.1016)
		(layer "F.Cu")
		(net "P5E_CPU0_P1_TX_C_DN<5>")
	)
	(segment
		(start 339.238844 -381.68453)
		(end 338.889594 -382.03378)
		(width 0.1016)
		(layer "F.Cu")
		(net "P5E_CPU0_P1_TX_C_DN<5>")
	)
	(segment
		(start 339.001354 -383.327656)
		(end 338.889594 -383.439416)
		(width 0.1016)
		(layer "F.Cu")
		(net "P5E_CPU0_P1_TX_C_DN<5>")
	)
	(segment
		(start 341.851996 -391.51941)
		(end 341.945468 -391.612882)
		(width 0.1016)
		(layer "F.Cu")
		(net "P5E_CPU0_P1_TX_C_DN<5>")
	)
	(segment
		(start 339.217254 -384.82397)
		(end 341.147146 -387.710934)
		(width 0.1016)
		(layer "F.Cu")
		(net "P5E_CPU0_P1_TX_C_DN<5>")
	)
	(segment
		(start 341.851996 -390.033764)
		(end 341.851996 -391.51941)
		(width 0.1016)
		(layer "F.Cu")
		(net "P5E_CPU0_P1_TX_C_DN<5>")
	)
	(segment
		(start 338.889594 -383.439416)
		(end 338.889594 -383.744216)
		(width 0.1016)
		(layer "F.Cu")
		(net "P5E_CPU0_P1_TX_C_DN<5>")
	)
	(segment
		(start 338.889594 -382.03378)
		(end 338.889594 -382.911096)
		(width 0.1016)
		(layer "F.Cu")
		(net "P5E_CPU0_P1_TX_C_DN<5>")
	)
	(arc
		(start 338.889594 -383.744216)
		(mid 338.973315 -384.308402)
		(end 339.217254 -384.82397)
		(width 0.1016)
		(layer "F.Cu")
		(net "P5E_CPU0_P1_TX_C_DN<5>")
	)
	(arc
		(start 341.147146 -387.710934)
		(mid 341.671909 -388.820055)
		(end 341.851996 -390.033764)
		(width 0.1016)
		(layer "F.Cu")
		(net "P5E_CPU0_P1_TX_C_DN<5>")
	)
	(segment
		(start 337.945476 -385.851908)
		(end 338.102702 -385.867402)
		(width 0.1016)
		(layer "F.Cu")
		(net "P5E_CPU0_P1_TX_C_DN<4>")
	)
	(segment
		(start 338.102702 -385.867402)
		(end 338.29625 -386.103114)
		(width 0.1016)
		(layer "F.Cu")
		(net "P5E_CPU0_P1_TX_C_DN<4>")
	)
	(segment
		(start 337.187794 -384.67157)
		(end 337.40344 -385.191508)
		(width 0.1016)
		(layer "F.Cu")
		(net "P5E_CPU0_P1_TX_C_DN<4>")
	)
	(segment
		(start 338.29625 -386.103114)
		(end 338.28101 -386.260594)
		(width 0.1016)
		(layer "F.Cu")
		(net "P5E_CPU0_P1_TX_C_DN<4>")
	)
	(segment
		(start 338.28101 -386.260594)
		(end 340.278974 -388.69493)
		(width 0.1016)
		(layer "F.Cu")
		(net "P5E_CPU0_P1_TX_C_DN<4>")
	)
	(segment
		(start 340.6521 -389.955278)
		(end 340.6521 -391.51941)
		(width 0.1016)
		(layer "F.Cu")
		(net "P5E_CPU0_P1_TX_C_DN<4>")
	)
	(segment
		(start 337.187794 -384.49758)
		(end 337.187794 -384.67157)
		(width 0.1016)
		(layer "F.Cu")
		(net "P5E_CPU0_P1_TX_C_DN<4>")
	)
	(segment
		(start 337.537044 -384.14833)
		(end 337.187794 -384.49758)
		(width 0.1016)
		(layer "F.Cu")
		(net "P5E_CPU0_P1_TX_C_DN<4>")
	)
	(segment
		(start 337.40344 -385.191508)
		(end 337.945476 -385.851908)
		(width 0.1016)
		(layer "F.Cu")
		(net "P5E_CPU0_P1_TX_C_DN<4>")
	)
	(segment
		(start 340.6521 -391.51941)
		(end 340.745572 -391.612882)
		(width 0.1016)
		(layer "F.Cu")
		(net "P5E_CPU0_P1_TX_C_DN<4>")
	)
	(segment
		(start 340.745572 -391.612882)
		(end 340.745572 -392.30427)
		(width 0.1016)
		(layer "F.Cu")
		(net "P5E_CPU0_P1_TX_C_DN<4>")
	)
	(arc
		(start 340.6521 -389.9535)
		(mid 340.6521 -389.953881)
		(end 340.6521 -389.954262)
		(width 0.1016)
		(layer "F.Cu")
		(net "P5E_CPU0_P1_TX_C_DN<4>")
	)
	(arc
		(start 340.6521 -389.954262)
		(mid 340.6521 -389.95477)
		(end 340.6521 -389.955278)
		(width 0.1016)
		(layer "F.Cu")
		(net "P5E_CPU0_P1_TX_C_DN<4>")
	)
	(arc
		(start 340.278974 -388.69493)
		(mid 340.556626 -389.297208)
		(end 340.6521 -389.9535)
		(width 0.1016)
		(layer "F.Cu")
		(net "P5E_CPU0_P1_TX_C_DN<4>")
	)
	(segment
		(start 335.543144 -383.834132)
		(end 336.397092 -385.896358)
		(width 0.1016)
		(layer "F.Cu")
		(net "P5E_CPU0_P1_TX_C_DN<3>")
	)
	(segment
		(start 334.719676 -381.150114)
		(end 334.877664 -381.150114)
		(width 0.1016)
		(layer "F.Cu")
		(net "P5E_CPU0_P1_TX_C_DN<3>")
	)
	(segment
		(start 335.093564 -381.524002)
		(end 335.354676 -381.785114)
		(width 0.1016)
		(layer "F.Cu")
		(net "P5E_CPU0_P1_TX_C_DN<3>")
	)
	(segment
		(start 335.493868 -382.120902)
		(end 335.493868 -383.585466)
		(width 0.1016)
		(layer "F.Cu")
		(net "P5E_CPU0_P1_TX_C_DN<3>")
	)
	(segment
		(start 336.397092 -385.896358)
		(end 336.6516 -386.3213)
		(width 0.1016)
		(layer "F.Cu")
		(net "P5E_CPU0_P1_TX_C_DN<3>")
	)
	(segment
		(start 335.093564 -381.366014)
		(end 335.093564 -381.524002)
		(width 0.1016)
		(layer "F.Cu")
		(net "P5E_CPU0_P1_TX_C_DN<3>")
	)
	(segment
		(start 336.6516 -386.3213)
		(end 339.284564 -389.529574)
		(width 0.1016)
		(layer "F.Cu")
		(net "P5E_CPU0_P1_TX_C_DN<3>")
	)
	(segment
		(start 339.45195 -391.51941)
		(end 339.545422 -391.612882)
		(width 0.1016)
		(layer "F.Cu")
		(net "P5E_CPU0_P1_TX_C_DN<3>")
	)
	(segment
		(start 334.133444 -379.22073)
		(end 333.784194 -379.56998)
		(width 0.1016)
		(layer "F.Cu")
		(net "P5E_CPU0_P1_TX_C_DN<3>")
	)
	(segment
		(start 339.45195 -389.996426)
		(end 339.45195 -391.51941)
		(width 0.1016)
		(layer "F.Cu")
		(net "P5E_CPU0_P1_TX_C_DN<3>")
	)
	(segment
		(start 334.877664 -381.150114)
		(end 335.093564 -381.366014)
		(width 0.1016)
		(layer "F.Cu")
		(net "P5E_CPU0_P1_TX_C_DN<3>")
	)
	(segment
		(start 339.545422 -391.612882)
		(end 339.545422 -392.30427)
		(width 0.1016)
		(layer "F.Cu")
		(net "P5E_CPU0_P1_TX_C_DN<3>")
	)
	(segment
		(start 333.784194 -379.56998)
		(end 333.784194 -379.95352)
		(width 0.1016)
		(layer "F.Cu")
		(net "P5E_CPU0_P1_TX_C_DN<3>")
	)
	(segment
		(start 333.968852 -380.39929)
		(end 334.719676 -381.150114)
		(width 0.1016)
		(layer "F.Cu")
		(net "P5E_CPU0_P1_TX_C_DN<3>")
	)
	(arc
		(start 335.493868 -383.585466)
		(mid 335.506248 -383.71223)
		(end 335.543144 -383.834132)
		(width 0.1016)
		(layer "F.Cu")
		(net "P5E_CPU0_P1_TX_C_DN<3>")
	)
	(arc
		(start 333.784194 -379.95352)
		(mid 333.832182 -380.194774)
		(end 333.968852 -380.39929)
		(width 0.1016)
		(layer "F.Cu")
		(net "P5E_CPU0_P1_TX_C_DN<3>")
	)
	(arc
		(start 339.284564 -389.529574)
		(mid 339.408782 -389.748463)
		(end 339.45195 -389.996426)
		(width 0.1016)
		(layer "F.Cu")
		(net "P5E_CPU0_P1_TX_C_DN<3>")
	)
	(arc
		(start 335.354676 -381.785114)
		(mid 335.45767 -381.939161)
		(end 335.493868 -382.120902)
		(width 0.1016)
		(layer "F.Cu")
		(net "P5E_CPU0_P1_TX_C_DN<3>")
	)
	(segment
		(start 334.38084 -384.545078)
		(end 334.511904 -384.676142)
		(width 0.1016)
		(layer "F.Cu")
		(net "P5E_CPU0_P1_TX_C_DN<2>")
	)
	(segment
		(start 334.006952 -384.17119)
		(end 334.16494 -384.17119)
		(width 0.1016)
		(layer "F.Cu")
		(net "P5E_CPU0_P1_TX_C_DN<2>")
	)
	(segment
		(start 333.712312 -383.87655)
		(end 334.006952 -384.17119)
		(width 0.1016)
		(layer "F.Cu")
		(net "P5E_CPU0_P1_TX_C_DN<2>")
	)
	(segment
		(start 332.277212 -383.133854)
		(end 332.325218 -383.18186)
		(width 0.1016)
		(layer "F.Cu")
		(net "P5E_CPU0_P1_TX_C_DN<2>")
	)
	(segment
		(start 334.16494 -384.17119)
		(end 334.38084 -384.38709)
		(width 0.1016)
		(layer "F.Cu")
		(net "P5E_CPU0_P1_TX_C_DN<2>")
	)
	(segment
		(start 334.71612 -384.981704)
		(end 335.431638 -386.70992)
		(width 0.1016)
		(layer "F.Cu")
		(net "P5E_CPU0_P1_TX_C_DN<2>")
	)
	(segment
		(start 335.825846 -387.301994)
		(end 338.031836 -389.987536)
		(width 0.1016)
		(layer "F.Cu")
		(net "P5E_CPU0_P1_TX_C_DN<2>")
	)
	(segment
		(start 332.082394 -382.03378)
		(end 332.082394 -382.664208)
		(width 0.1016)
		(layer "F.Cu")
		(net "P5E_CPU0_P1_TX_C_DN<2>")
	)
	(segment
		(start 332.675992 -383.416556)
		(end 333.5909 -383.795524)
		(width 0.1016)
		(layer "F.Cu")
		(net "P5E_CPU0_P1_TX_C_DN<2>")
	)
	(segment
		(start 332.431644 -381.68453)
		(end 332.082394 -382.03378)
		(width 0.1016)
		(layer "F.Cu")
		(net "P5E_CPU0_P1_TX_C_DN<2>")
	)
	(segment
		(start 335.431638 -386.70992)
		(end 335.566004 -386.93344)
		(width 0.1016)
		(layer "F.Cu")
		(net "P5E_CPU0_P1_TX_C_DN<2>")
	)
	(segment
		(start 338.345526 -391.612882)
		(end 338.345526 -392.30427)
		(width 0.1016)
		(layer "F.Cu")
		(net "P5E_CPU0_P1_TX_C_DN<2>")
	)
	(segment
		(start 338.252054 -390.602216)
		(end 338.252054 -391.51941)
		(width 0.1016)
		(layer "F.Cu")
		(net "P5E_CPU0_P1_TX_C_DN<2>")
	)
	(segment
		(start 338.252054 -391.51941)
		(end 338.345526 -391.612882)
		(width 0.1016)
		(layer "F.Cu")
		(net "P5E_CPU0_P1_TX_C_DN<2>")
	)
	(segment
		(start 334.38084 -384.38709)
		(end 334.38084 -384.545078)
		(width 0.1016)
		(layer "F.Cu")
		(net "P5E_CPU0_P1_TX_C_DN<2>")
	)
	(arc
		(start 333.5909 -383.795524)
		(mid 333.655607 -383.830045)
		(end 333.712312 -383.87655)
		(width 0.1016)
		(layer "F.Cu")
		(net "P5E_CPU0_P1_TX_C_DN<2>")
	)
	(arc
		(start 332.082394 -382.664208)
		(mid 332.133139 -382.91838)
		(end 332.277212 -383.133854)
		(width 0.1016)
		(layer "F.Cu")
		(net "P5E_CPU0_P1_TX_C_DN<2>")
	)
	(arc
		(start 338.031836 -389.987536)
		(mid 338.195325 -390.275755)
		(end 338.252054 -390.602216)
		(width 0.1016)
		(layer "F.Cu")
		(net "P5E_CPU0_P1_TX_C_DN<2>")
	)
	(arc
		(start 332.325218 -383.18186)
		(mid 332.489056 -383.316467)
		(end 332.675992 -383.416556)
		(width 0.1016)
		(layer "F.Cu")
		(net "P5E_CPU0_P1_TX_C_DN<2>")
	)
	(arc
		(start 335.566004 -386.93344)
		(mid 335.689163 -387.122484)
		(end 335.825846 -387.301994)
		(width 0.1016)
		(layer "F.Cu")
		(net "P5E_CPU0_P1_TX_C_DN<2>")
	)
	(arc
		(start 334.511904 -384.676142)
		(mid 334.629069 -384.818861)
		(end 334.71612 -384.981704)
		(width 0.1016)
		(layer "F.Cu")
		(net "P5E_CPU0_P1_TX_C_DN<2>")
	)
	(segment
		(start 335.596738 -389.249412)
		(end 336.608674 -390.482836)
		(width 0.1016)
		(layer "F.Cu")
		(net "P5E_CPU0_P1_TX_C_DN<1>")
	)
	(segment
		(start 336.836004 -390.936734)
		(end 336.836004 -391.324592)
		(width 0.1016)
		(layer "F.Cu")
		(net "P5E_CPU0_P1_TX_C_DN<1>")
	)
	(segment
		(start 332.132686 -384.868166)
		(end 332.21676 -384.868166)
		(width 0.1016)
		(layer "F.Cu")
		(net "P5E_CPU0_P1_TX_C_DN<1>")
	)
	(segment
		(start 336.543396 -391.88771)
		(end 336.634582 -391.978896)
		(width 0.1016)
		(layer "F.Cu")
		(net "P5E_CPU0_P1_TX_C_DN<1>")
	)
	(segment
		(start 333.923386 -386.768594)
		(end 333.862934 -386.91439)
		(width 0.1016)
		(layer "F.Cu")
		(net "P5E_CPU0_P1_TX_C_DN<1>")
	)
	(segment
		(start 333.473298 -385.680966)
		(end 333.923386 -386.768594)
		(width 0.1016)
		(layer "F.Cu")
		(net "P5E_CPU0_P1_TX_C_DN<1>")
	)
	(segment
		(start 333.862934 -386.91439)
		(end 333.97952 -387.19633)
		(width 0.1016)
		(layer "F.Cu")
		(net "P5E_CPU0_P1_TX_C_DN<1>")
	)
	(segment
		(start 336.543396 -391.6172)
		(end 336.543396 -391.88771)
		(width 0.1016)
		(layer "F.Cu")
		(net "P5E_CPU0_P1_TX_C_DN<1>")
	)
	(segment
		(start 334.125824 -387.256782)
		(end 334.26908 -387.603238)
		(width 0.1016)
		(layer "F.Cu")
		(net "P5E_CPU0_P1_TX_C_DN<1>")
	)
	(segment
		(start 334.993488 -388.646162)
		(end 335.596738 -389.249412)
		(width 0.1016)
		(layer "F.Cu")
		(net "P5E_CPU0_P1_TX_C_DN<1>")
	)
	(segment
		(start 336.768948 -391.978896)
		(end 336.845402 -391.902442)
		(width 0.1016)
		(layer "F.Cu")
		(net "P5E_CPU0_P1_TX_C_DN<1>")
	)
	(segment
		(start 334.40751 -388.01167)
		(end 334.576928 -388.265162)
		(width 0.1016)
		(layer "F.Cu")
		(net "P5E_CPU0_P1_TX_C_DN<1>")
	)
	(segment
		(start 336.608674 -390.482836)
		(end 336.735166 -390.693656)
		(width 0.1016)
		(layer "F.Cu")
		(net "P5E_CPU0_P1_TX_C_DN<1>")
	)
	(segment
		(start 333.05369 -385.214876)
		(end 333.379826 -385.541012)
		(width 0.1016)
		(layer "F.Cu")
		(net "P5E_CPU0_P1_TX_C_DN<1>")
	)
	(segment
		(start 334.438244 -387.856476)
		(end 334.40751 -388.01167)
		(width 0.1016)
		(layer "F.Cu")
		(net "P5E_CPU0_P1_TX_C_DN<1>")
	)
	(segment
		(start 334.732122 -388.29615)
		(end 334.845914 -388.46633)
		(width 0.1016)
		(layer "F.Cu")
		(net "P5E_CPU0_P1_TX_C_DN<1>")
	)
	(segment
		(start 336.634582 -391.978896)
		(end 336.768948 -391.978896)
		(width 0.1016)
		(layer "F.Cu")
		(net "P5E_CPU0_P1_TX_C_DN<1>")
	)
	(segment
		(start 336.836004 -391.324592)
		(end 336.543396 -391.6172)
		(width 0.1016)
		(layer "F.Cu")
		(net "P5E_CPU0_P1_TX_C_DN<1>")
	)
	(segment
		(start 334.26908 -387.603238)
		(end 334.438244 -387.856476)
		(width 0.1016)
		(layer "F.Cu")
		(net "P5E_CPU0_P1_TX_C_DN<1>")
	)
	(segment
		(start 336.845402 -391.902442)
		(end 336.845402 -391.784586)
		(width 0.1016)
		(layer "F.Cu")
		(net "P5E_CPU0_P1_TX_C_DN<1>")
	)
	(segment
		(start 336.735166 -390.693656)
		(end 336.836004 -390.936734)
		(width 0.1016)
		(layer "F.Cu")
		(net "P5E_CPU0_P1_TX_C_DN<1>")
	)
	(segment
		(start 334.576928 -388.265162)
		(end 334.732122 -388.29615)
		(width 0.1016)
		(layer "F.Cu")
		(net "P5E_CPU0_P1_TX_C_DN<1>")
	)
	(segment
		(start 331.761592 -385.23926)
		(end 332.132686 -384.868166)
		(width 0.1016)
		(layer "F.Cu")
		(net "P5E_CPU0_P1_TX_C_DN<1>")
	)
	(segment
		(start 333.97952 -387.19633)
		(end 334.125824 -387.256782)
		(width 0.1016)
		(layer "F.Cu")
		(net "P5E_CPU0_P1_TX_C_DN<1>")
	)
	(arc
		(start 332.21676 -384.868166)
		(mid 332.669705 -384.95828)
		(end 333.05369 -385.214876)
		(width 0.1016)
		(layer "F.Cu")
		(net "P5E_CPU0_P1_TX_C_DN<1>")
	)
	(arc
		(start 334.845914 -388.46633)
		(mid 334.915285 -388.55987)
		(end 334.993488 -388.646162)
		(width 0.1016)
		(layer "F.Cu")
		(net "P5E_CPU0_P1_TX_C_DN<1>")
	)
	(arc
		(start 333.379826 -385.541012)
		(mid 333.433465 -385.60638)
		(end 333.473298 -385.680966)
		(width 0.1016)
		(layer "F.Cu")
		(net "P5E_CPU0_P1_TX_C_DN<1>")
	)
	(segment
		(start 357.652574 -388.418578)
		(end 355.947726 -388.418578)
		(width 0.1016)
		(layer "F.Cu")
		(net "P5E_CPU0_P1_TX_C_DN<15>")
	)
	(segment
		(start 353.945952 -391.40257)
		(end 353.945952 -392.303762)
		(width 0.1016)
		(layer "F.Cu")
		(net "P5E_CPU0_P1_TX_C_DN<15>")
	)
	(segment
		(start 358.001824 -388.767828)
		(end 357.652574 -388.418578)
		(width 0.1016)
		(layer "F.Cu")
		(net "P5E_CPU0_P1_TX_C_DN<15>")
	)
	(segment
		(start 355.846634 -388.460488)
		(end 353.945698 -390.361424)
		(width 0.1016)
		(layer "F.Cu")
		(net "P5E_CPU0_P1_TX_C_DN<15>")
	)
	(segment
		(start 353.851972 -390.587484)
		(end 353.851972 -391.30859)
		(width 0.1016)
		(layer "F.Cu")
		(net "P5E_CPU0_P1_TX_C_DN<15>")
	)
	(segment
		(start 353.851972 -391.30859)
		(end 353.945952 -391.40257)
		(width 0.1016)
		(layer "F.Cu")
		(net "P5E_CPU0_P1_TX_C_DN<15>")
	)
	(segment
		(start 353.945952 -392.303762)
		(end 353.945444 -392.30427)
		(width 0.1016)
		(layer "F.Cu")
		(net "P5E_CPU0_P1_TX_C_DN<15>")
	)
	(arc
		(start 355.947726 -388.418578)
		(mid 355.893002 -388.429463)
		(end 355.846634 -388.460488)
		(width 0.1016)
		(layer "F.Cu")
		(net "P5E_CPU0_P1_TX_C_DN<15>")
	)
	(arc
		(start 353.945698 -390.361424)
		(mid 353.876343 -390.465127)
		(end 353.851972 -390.587484)
		(width 0.1016)
		(layer "F.Cu")
		(net "P5E_CPU0_P1_TX_C_DN<15>")
	)
	(segment
		(start 352.530156 -391.492232)
		(end 352.530156 -391.700004)
		(width 0.1016)
		(layer "F.Cu")
		(net "P5E_CPU0_P1_TX_C_DN<14>")
	)
	(segment
		(start 352.436176 -391.398252)
		(end 352.530156 -391.492232)
		(width 0.1016)
		(layer "F.Cu")
		(net "P5E_CPU0_P1_TX_C_DN<14>")
	)
	(segment
		(start 352.530156 -391.700004)
		(end 352.445574 -391.784586)
		(width 0.1016)
		(layer "F.Cu")
		(net "P5E_CPU0_P1_TX_C_DN<14>")
	)
	(segment
		(start 352.436176 -390.071102)
		(end 352.436176 -391.398252)
		(width 0.1016)
		(layer "F.Cu")
		(net "P5E_CPU0_P1_TX_C_DN<14>")
	)
	(segment
		(start 357.566722 -384.88493)
		(end 357.252524 -384.88493)
		(width 0.1016)
		(layer "F.Cu")
		(net "P5E_CPU0_P1_TX_C_DN<14>")
	)
	(segment
		(start 358.001824 -384.449828)
		(end 357.566722 -384.88493)
		(width 0.1016)
		(layer "F.Cu")
		(net "P5E_CPU0_P1_TX_C_DN<14>")
	)
	(segment
		(start 357.252524 -384.88493)
		(end 352.697034 -389.44042)
		(width 0.1016)
		(layer "F.Cu")
		(net "P5E_CPU0_P1_TX_C_DN<14>")
	)
	(arc
		(start 352.697034 -389.44042)
		(mid 352.50391 -389.729824)
		(end 352.436176 -390.071102)
		(width 0.1016)
		(layer "F.Cu")
		(net "P5E_CPU0_P1_TX_C_DN<14>")
	)
	(segment
		(start 358.476804 -381.13335)
		(end 358.634792 -381.13335)
		(width 0.1016)
		(layer "F.Cu")
		(net "P5E_CPU0_P1_TX_C_DN<13>")
	)
	(segment
		(start 357.861362 -380.517908)
		(end 358.476804 -381.13335)
		(width 0.1016)
		(layer "F.Cu")
		(net "P5E_CPU0_P1_TX_C_DN<13>")
	)
	(segment
		(start 358.850692 -381.34925)
		(end 358.850692 -381.507238)
		(width 0.1016)
		(layer "F.Cu")
		(net "P5E_CPU0_P1_TX_C_DN<13>")
	)
	(segment
		(start 359.283508 -382.248156)
		(end 359.283508 -382.518666)
		(width 0.1016)
		(layer "F.Cu")
		(net "P5E_CPU0_P1_TX_C_DN<13>")
	)
	(segment
		(start 351.451926 -391.51941)
		(end 351.545398 -391.612882)
		(width 0.1016)
		(layer "F.Cu")
		(net "P5E_CPU0_P1_TX_C_DN<13>")
	)
	(segment
		(start 357.609394 -379.56998)
		(end 357.609394 -379.909832)
		(width 0.1016)
		(layer "F.Cu")
		(net "P5E_CPU0_P1_TX_C_DN<13>")
	)
	(segment
		(start 359.047796 -383.088388)
		(end 358.622346 -383.513838)
		(width 0.1016)
		(layer "F.Cu")
		(net "P5E_CPU0_P1_TX_C_DN<13>")
	)
	(segment
		(start 356.886002 -383.867914)
		(end 351.489264 -389.264652)
		(width 0.1016)
		(layer "F.Cu")
		(net "P5E_CPU0_P1_TX_C_DN<13>")
	)
	(segment
		(start 357.609394 -379.909832)
		(end 357.609648 -379.909578)
		(width 0.1016)
		(layer "F.Cu")
		(net "P5E_CPU0_P1_TX_C_DN<13>")
	)
	(segment
		(start 358.18445 -383.69494)
		(end 357.303578 -383.69494)
		(width 0.1016)
		(layer "F.Cu")
		(net "P5E_CPU0_P1_TX_C_DN<13>")
	)
	(segment
		(start 357.958644 -379.22073)
		(end 357.609394 -379.56998)
		(width 0.1016)
		(layer "F.Cu")
		(net "P5E_CPU0_P1_TX_C_DN<13>")
	)
	(segment
		(start 358.634792 -381.13335)
		(end 358.850692 -381.34925)
		(width 0.1016)
		(layer "F.Cu")
		(net "P5E_CPU0_P1_TX_C_DN<13>")
	)
	(segment
		(start 358.850692 -381.507238)
		(end 359.066084 -381.72263)
		(width 0.1016)
		(layer "F.Cu")
		(net "P5E_CPU0_P1_TX_C_DN<13>")
	)
	(segment
		(start 351.545398 -391.612882)
		(end 351.545398 -392.30427)
		(width 0.1016)
		(layer "F.Cu")
		(net "P5E_CPU0_P1_TX_C_DN<13>")
	)
	(segment
		(start 351.451926 -389.354822)
		(end 351.451926 -391.51941)
		(width 0.1016)
		(layer "F.Cu")
		(net "P5E_CPU0_P1_TX_C_DN<13>")
	)
	(arc
		(start 359.283508 -382.518666)
		(mid 359.222364 -382.827)
		(end 359.047796 -383.088388)
		(width 0.1016)
		(layer "F.Cu")
		(net "P5E_CPU0_P1_TX_C_DN<13>")
	)
	(arc
		(start 351.489264 -389.264652)
		(mid 351.461621 -389.306022)
		(end 351.451926 -389.354822)
		(width 0.1016)
		(layer "F.Cu")
		(net "P5E_CPU0_P1_TX_C_DN<13>")
	)
	(arc
		(start 357.609648 -379.909578)
		(mid 357.675017 -380.238771)
		(end 357.861362 -380.517908)
		(width 0.1016)
		(layer "F.Cu")
		(net "P5E_CPU0_P1_TX_C_DN<13>")
	)
	(arc
		(start 357.303578 -383.69494)
		(mid 357.077584 -383.739893)
		(end 356.886002 -383.867914)
		(width 0.1016)
		(layer "F.Cu")
		(net "P5E_CPU0_P1_TX_C_DN<13>")
	)
	(arc
		(start 359.066084 -381.72263)
		(mid 359.227079 -381.963759)
		(end 359.283508 -382.248156)
		(width 0.1016)
		(layer "F.Cu")
		(net "P5E_CPU0_P1_TX_C_DN<13>")
	)
	(arc
		(start 358.622346 -383.513838)
		(mid 358.421408 -383.647915)
		(end 358.18445 -383.69494)
		(width 0.1016)
		(layer "F.Cu")
		(net "P5E_CPU0_P1_TX_C_DN<13>")
	)
	(segment
		(start 355.326188 -381.307594)
		(end 355.484176 -381.307594)
		(width 0.1016)
		(layer "F.Cu")
		(net "P5E_CPU0_P1_TX_C_DN<12>")
	)
	(segment
		(start 355.779578 -383.272284)
		(end 350.476058 -388.576058)
		(width 0.1016)
		(layer "F.Cu")
		(net "P5E_CPU0_P1_TX_C_DN<12>")
	)
	(segment
		(start 355.915468 -382.039368)
		(end 355.915468 -382.945132)
		(width 0.1016)
		(layer "F.Cu")
		(net "P5E_CPU0_P1_TX_C_DN<12>")
	)
	(segment
		(start 350.345502 -391.612882)
		(end 350.345502 -392.30427)
		(width 0.1016)
		(layer "F.Cu")
		(net "P5E_CPU0_P1_TX_C_DN<12>")
	)
	(segment
		(start 354.205794 -379.56998)
		(end 354.205794 -379.9205)
		(width 0.1016)
		(layer "F.Cu")
		(net "P5E_CPU0_P1_TX_C_DN<12>")
	)
	(segment
		(start 350.25203 -389.116062)
		(end 350.25203 -391.51941)
		(width 0.1016)
		(layer "F.Cu")
		(net "P5E_CPU0_P1_TX_C_DN<12>")
	)
	(segment
		(start 354.555044 -379.22073)
		(end 354.205794 -379.56998)
		(width 0.1016)
		(layer "F.Cu")
		(net "P5E_CPU0_P1_TX_C_DN<12>")
	)
	(segment
		(start 355.484176 -381.307594)
		(end 355.700076 -381.523494)
		(width 0.1016)
		(layer "F.Cu")
		(net "P5E_CPU0_P1_TX_C_DN<12>")
	)
	(segment
		(start 350.25203 -391.51941)
		(end 350.345502 -391.612882)
		(width 0.1016)
		(layer "F.Cu")
		(net "P5E_CPU0_P1_TX_C_DN<12>")
	)
	(segment
		(start 355.700076 -381.523494)
		(end 355.700076 -381.681482)
		(width 0.1016)
		(layer "F.Cu")
		(net "P5E_CPU0_P1_TX_C_DN<12>")
	)
	(segment
		(start 355.700076 -381.681482)
		(end 355.815138 -381.796544)
		(width 0.1016)
		(layer "F.Cu")
		(net "P5E_CPU0_P1_TX_C_DN<12>")
	)
	(segment
		(start 354.395024 -380.37643)
		(end 355.326188 -381.307594)
		(width 0.1016)
		(layer "F.Cu")
		(net "P5E_CPU0_P1_TX_C_DN<12>")
	)
	(arc
		(start 350.476058 -388.576058)
		(mid 350.310293 -388.82377)
		(end 350.25203 -389.116062)
		(width 0.1016)
		(layer "F.Cu")
		(net "P5E_CPU0_P1_TX_C_DN<12>")
	)
	(arc
		(start 355.915468 -382.945132)
		(mid 355.88004 -383.122209)
		(end 355.779578 -383.272284)
		(width 0.1016)
		(layer "F.Cu")
		(net "P5E_CPU0_P1_TX_C_DN<12>")
	)
	(arc
		(start 355.815138 -381.796544)
		(mid 355.889442 -381.907982)
		(end 355.915468 -382.039368)
		(width 0.1016)
		(layer "F.Cu")
		(net "P5E_CPU0_P1_TX_C_DN<12>")
	)
	(arc
		(start 354.205794 -379.9205)
		(mid 354.255085 -380.16727)
		(end 354.395024 -380.37643)
		(width 0.1016)
		(layer "F.Cu")
		(net "P5E_CPU0_P1_TX_C_DN<12>")
	)
	(segment
		(start 352.503994 -383.932176)
		(end 352.503994 -384.618484)
		(width 0.1016)
		(layer "F.Cu")
		(net "P5E_CPU0_P1_TX_C_DN<11>")
	)
	(segment
		(start 349.05188 -391.51941)
		(end 349.145606 -391.613136)
		(width 0.1016)
		(layer "F.Cu")
		(net "P5E_CPU0_P1_TX_C_DN<11>")
	)
	(segment
		(start 349.145606 -391.613136)
		(end 349.145606 -392.30427)
		(width 0.1016)
		(layer "F.Cu")
		(net "P5E_CPU0_P1_TX_C_DN<11>")
	)
	(segment
		(start 352.615754 -383.820416)
		(end 352.503994 -383.932176)
		(width 0.1016)
		(layer "F.Cu")
		(net "P5E_CPU0_P1_TX_C_DN<11>")
	)
	(segment
		(start 352.503994 -382.03378)
		(end 352.503994 -383.403856)
		(width 0.1016)
		(layer "F.Cu")
		(net "P5E_CPU0_P1_TX_C_DN<11>")
	)
	(segment
		(start 349.05188 -388.266178)
		(end 349.05188 -391.51941)
		(width 0.1016)
		(layer "F.Cu")
		(net "P5E_CPU0_P1_TX_C_DN<11>")
	)
	(segment
		(start 352.853244 -381.68453)
		(end 352.503994 -382.03378)
		(width 0.1016)
		(layer "F.Cu")
		(net "P5E_CPU0_P1_TX_C_DN<11>")
	)
	(segment
		(start 352.615754 -383.515616)
		(end 352.615754 -383.820416)
		(width 0.1016)
		(layer "F.Cu")
		(net "P5E_CPU0_P1_TX_C_DN<11>")
	)
	(segment
		(start 352.403664 -384.861562)
		(end 349.089218 -388.176008)
		(width 0.1016)
		(layer "F.Cu")
		(net "P5E_CPU0_P1_TX_C_DN<11>")
	)
	(segment
		(start 352.503994 -383.403856)
		(end 352.615754 -383.515616)
		(width 0.1016)
		(layer "F.Cu")
		(net "P5E_CPU0_P1_TX_C_DN<11>")
	)
	(arc
		(start 352.503994 -384.618484)
		(mid 352.478035 -384.750022)
		(end 352.403664 -384.861562)
		(width 0.1016)
		(layer "F.Cu")
		(net "P5E_CPU0_P1_TX_C_DN<11>")
	)
	(arc
		(start 349.089218 -388.176008)
		(mid 349.061575 -388.217378)
		(end 349.05188 -388.266178)
		(width 0.1016)
		(layer "F.Cu")
		(net "P5E_CPU0_P1_TX_C_DN<11>")
	)
	(segment
		(start 350.801178 -384.498596)
		(end 350.801178 -384.584702)
		(width 0.1016)
		(layer "F.Cu")
		(net "P5E_CPU0_P1_TX_C_DN<10>")
	)
	(segment
		(start 348.441772 -386.802122)
		(end 348.226126 -387.017768)
		(width 0.1016)
		(layer "F.Cu")
		(net "P5E_CPU0_P1_TX_C_DN<10>")
	)
	(segment
		(start 350.700848 -384.82778)
		(end 349.719138 -385.809236)
		(width 0.1016)
		(layer "F.Cu")
		(net "P5E_CPU0_P1_TX_C_DN<10>")
	)
	(segment
		(start 348.068138 -387.017768)
		(end 347.889322 -387.196584)
		(width 0.1016)
		(layer "F.Cu")
		(net "P5E_CPU0_P1_TX_C_DN<10>")
	)
	(segment
		(start 349.45193 -385.919472)
		(end 349.22968 -385.919472)
		(width 0.1016)
		(layer "F.Cu")
		(net "P5E_CPU0_P1_TX_C_DN<10>")
	)
	(segment
		(start 347.945456 -391.612882)
		(end 347.945456 -392.30427)
		(width 0.1016)
		(layer "F.Cu")
		(net "P5E_CPU0_P1_TX_C_DN<10>")
	)
	(segment
		(start 348.441772 -386.644388)
		(end 348.441772 -386.802122)
		(width 0.1016)
		(layer "F.Cu")
		(net "P5E_CPU0_P1_TX_C_DN<10>")
	)
	(segment
		(start 349.121476 -385.96443)
		(end 348.441772 -386.644388)
		(width 0.1016)
		(layer "F.Cu")
		(net "P5E_CPU0_P1_TX_C_DN<10>")
	)
	(segment
		(start 351.151444 -384.14833)
		(end 350.801178 -384.498596)
		(width 0.1016)
		(layer "F.Cu")
		(net "P5E_CPU0_P1_TX_C_DN<10>")
	)
	(segment
		(start 347.851984 -387.286754)
		(end 347.851984 -391.51941)
		(width 0.1016)
		(layer "F.Cu")
		(net "P5E_CPU0_P1_TX_C_DN<10>")
	)
	(segment
		(start 347.851984 -391.51941)
		(end 347.945456 -391.612882)
		(width 0.1016)
		(layer "F.Cu")
		(net "P5E_CPU0_P1_TX_C_DN<10>")
	)
	(segment
		(start 348.226126 -387.017768)
		(end 348.068138 -387.017768)
		(width 0.1016)
		(layer "F.Cu")
		(net "P5E_CPU0_P1_TX_C_DN<10>")
	)
	(arc
		(start 347.889322 -387.196584)
		(mid 347.861679 -387.237954)
		(end 347.851984 -387.286754)
		(width 0.1016)
		(layer "F.Cu")
		(net "P5E_CPU0_P1_TX_C_DN<10>")
	)
	(arc
		(start 349.719138 -385.809236)
		(mid 349.596498 -385.890932)
		(end 349.45193 -385.919472)
		(width 0.1016)
		(layer "F.Cu")
		(net "P5E_CPU0_P1_TX_C_DN<10>")
	)
	(arc
		(start 349.22968 -385.919472)
		(mid 349.171096 -385.931161)
		(end 349.121476 -385.96443)
		(width 0.1016)
		(layer "F.Cu")
		(net "P5E_CPU0_P1_TX_C_DN<10>")
	)
	(arc
		(start 350.801178 -384.584702)
		(mid 350.775219 -384.71624)
		(end 350.700848 -384.82778)
		(width 0.1016)
		(layer "F.Cu")
		(net "P5E_CPU0_P1_TX_C_DN<10>")
	)
	(segment
		(start 335.852008 -391.51941)
		(end 335.94548 -391.612882)
		(width 0.1016)
		(layer "F.Cu")
		(net "P5E_CPU0_P1_TX_C_DN<0>")
	)
	(segment
		(start 335.447894 -390.70407)
		(end 335.852008 -391.109708)
		(width 0.1016)
		(layer "F.Cu")
		(net "P5E_CPU0_P1_TX_C_DN<0>")
	)
	(segment
		(start 331.761592 -389.86206)
		(end 332.109064 -390.209532)
		(width 0.1016)
		(layer "F.Cu")
		(net "P5E_CPU0_P1_TX_C_DN<0>")
	)
	(segment
		(start 335.852008 -391.109708)
		(end 335.852008 -391.51941)
		(width 0.1016)
		(layer "F.Cu")
		(net "P5E_CPU0_P1_TX_C_DN<0>")
	)
	(segment
		(start 332.109064 -390.209532)
		(end 334.280256 -390.209532)
		(width 0.1016)
		(layer "F.Cu")
		(net "P5E_CPU0_P1_TX_C_DN<0>")
	)
	(segment
		(start 334.560418 -390.265158)
		(end 335.165446 -390.515094)
		(width 0.1016)
		(layer "F.Cu")
		(net "P5E_CPU0_P1_TX_C_DN<0>")
	)
	(segment
		(start 335.94548 -391.612882)
		(end 335.94548 -392.30427)
		(width 0.1016)
		(layer "F.Cu")
		(net "P5E_CPU0_P1_TX_C_DN<0>")
	)
	(arc
		(start 335.165446 -390.515094)
		(mid 335.316078 -390.595523)
		(end 335.447894 -390.70407)
		(width 0.1016)
		(layer "F.Cu")
		(net "P5E_CPU0_P1_TX_C_DN<0>")
	)
	(arc
		(start 334.280256 -390.209532)
		(mid 334.423075 -390.223564)
		(end 334.560418 -390.265158)
		(width 0.1016)
		(layer "F.Cu")
		(net "P5E_CPU0_P1_TX_C_DN<0>")
	)
	(segment
		(start 313.90844 -391.324592)
		(end 313.615832 -391.6172)
		(width 0.1016)
		(layer "F.Cu")
		(net "P5E_CPU0_P0_TX_C_DP<9>")
	)
	(segment
		(start 314.305696 -379.22073)
		(end 314.654946 -379.56998)
		(width 0.1016)
		(layer "F.Cu")
		(net "P5E_CPU0_P0_TX_C_DP<9>")
	)
	(segment
		(start 313.615832 -391.88771)
		(end 313.707018 -391.978896)
		(width 0.1016)
		(layer "F.Cu")
		(net "P5E_CPU0_P0_TX_C_DP<9>")
	)
	(segment
		(start 316.333378 -382.315466)
		(end 316.333378 -383.376932)
		(width 0.1016)
		(layer "F.Cu")
		(net "P5E_CPU0_P0_TX_C_DP<9>")
	)
	(segment
		(start 313.707018 -391.978896)
		(end 313.841384 -391.978896)
		(width 0.1016)
		(layer "F.Cu")
		(net "P5E_CPU0_P0_TX_C_DP<9>")
	)
	(segment
		(start 314.654946 -379.56998)
		(end 314.654946 -379.909578)
		(width 0.1016)
		(layer "F.Cu")
		(net "P5E_CPU0_P0_TX_C_DP<9>")
	)
	(segment
		(start 313.841384 -391.978896)
		(end 313.917838 -391.902442)
		(width 0.1016)
		(layer "F.Cu")
		(net "P5E_CPU0_P0_TX_C_DP<9>")
	)
	(segment
		(start 314.970414 -380.67107)
		(end 316.13348 -381.834136)
		(width 0.1016)
		(layer "F.Cu")
		(net "P5E_CPU0_P0_TX_C_DP<9>")
	)
	(segment
		(start 316.262004 -383.548382)
		(end 314.052204 -385.758182)
		(width 0.1016)
		(layer "F.Cu")
		(net "P5E_CPU0_P0_TX_C_DP<9>")
	)
	(segment
		(start 313.615832 -391.6172)
		(end 313.615832 -391.88771)
		(width 0.1016)
		(layer "F.Cu")
		(net "P5E_CPU0_P0_TX_C_DP<9>")
	)
	(segment
		(start 313.90844 -386.105908)
		(end 313.90844 -391.324592)
		(width 0.1016)
		(layer "F.Cu")
		(net "P5E_CPU0_P0_TX_C_DP<9>")
	)
	(segment
		(start 313.917838 -391.902442)
		(end 313.917838 -391.784586)
		(width 0.1016)
		(layer "F.Cu")
		(net "P5E_CPU0_P0_TX_C_DP<9>")
	)
	(arc
		(start 314.052204 -385.758182)
		(mid 313.94577 -385.91775)
		(end 313.90844 -386.105908)
		(width 0.1016)
		(layer "F.Cu")
		(net "P5E_CPU0_P0_TX_C_DP<9>")
	)
	(arc
		(start 316.13348 -381.834136)
		(mid 316.281341 -382.054913)
		(end 316.333378 -382.315466)
		(width 0.1016)
		(layer "F.Cu")
		(net "P5E_CPU0_P0_TX_C_DP<9>")
	)
	(arc
		(start 314.654946 -379.909578)
		(mid 314.736978 -380.321688)
		(end 314.970414 -380.67107)
		(width 0.1016)
		(layer "F.Cu")
		(net "P5E_CPU0_P0_TX_C_DP<9>")
	)
	(arc
		(start 316.333378 -383.376932)
		(mid 316.314713 -383.469735)
		(end 316.262004 -383.548382)
		(width 0.1016)
		(layer "F.Cu")
		(net "P5E_CPU0_P0_TX_C_DP<9>")
	)
	(segment
		(start 312.717688 -391.902442)
		(end 312.717688 -391.784586)
		(width 0.1016)
		(layer "F.Cu")
		(net "P5E_CPU0_P0_TX_C_DP<8>")
	)
	(segment
		(start 312.415682 -391.88771)
		(end 312.506868 -391.978896)
		(width 0.1016)
		(layer "F.Cu")
		(net "P5E_CPU0_P0_TX_C_DP<8>")
	)
	(segment
		(start 312.415682 -391.6172)
		(end 312.415682 -391.88771)
		(width 0.1016)
		(layer "F.Cu")
		(net "P5E_CPU0_P0_TX_C_DP<8>")
	)
	(segment
		(start 312.70829 -391.324592)
		(end 312.415682 -391.6172)
		(width 0.1016)
		(layer "F.Cu")
		(net "P5E_CPU0_P0_TX_C_DP<8>")
	)
	(segment
		(start 312.953146 -382.10109)
		(end 312.953146 -384.99923)
		(width 0.1016)
		(layer "F.Cu")
		(net "P5E_CPU0_P0_TX_C_DP<8>")
	)
	(segment
		(start 312.603896 -381.68453)
		(end 312.905648 -381.986282)
		(width 0.1016)
		(layer "F.Cu")
		(net "P5E_CPU0_P0_TX_C_DP<8>")
	)
	(segment
		(start 312.641234 -391.978896)
		(end 312.717688 -391.902442)
		(width 0.1016)
		(layer "F.Cu")
		(net "P5E_CPU0_P0_TX_C_DP<8>")
	)
	(segment
		(start 312.506868 -391.978896)
		(end 312.641234 -391.978896)
		(width 0.1016)
		(layer "F.Cu")
		(net "P5E_CPU0_P0_TX_C_DP<8>")
	)
	(segment
		(start 312.70829 -385.70027)
		(end 312.70829 -391.324592)
		(width 0.1016)
		(layer "F.Cu")
		(net "P5E_CPU0_P0_TX_C_DP<8>")
	)
	(arc
		(start 312.859166 -385.270502)
		(mid 312.80767 -385.345163)
		(end 312.765948 -385.425696)
		(width 0.1016)
		(layer "F.Cu")
		(net "P5E_CPU0_P0_TX_C_DP<8>")
	)
	(arc
		(start 312.905648 -381.986282)
		(mid 312.94079 -382.038971)
		(end 312.953146 -382.10109)
		(width 0.1016)
		(layer "F.Cu")
		(net "P5E_CPU0_P0_TX_C_DP<8>")
	)
	(arc
		(start 312.953146 -384.99923)
		(mid 312.92893 -385.14275)
		(end 312.859166 -385.270502)
		(width 0.1016)
		(layer "F.Cu")
		(net "P5E_CPU0_P0_TX_C_DP<8>")
	)
	(arc
		(start 312.765948 -385.425696)
		(mid 312.722794 -385.559976)
		(end 312.70829 -385.70027)
		(width 0.1016)
		(layer "F.Cu")
		(net "P5E_CPU0_P0_TX_C_DP<8>")
	)
	(segment
		(start 310.902096 -384.14833)
		(end 311.203848 -384.450082)
		(width 0.1016)
		(layer "F.Cu")
		(net "P5E_CPU0_P0_TX_C_DP<7>")
	)
	(segment
		(start 311.251346 -384.56489)
		(end 311.251346 -386.289804)
		(width 0.1016)
		(layer "F.Cu")
		(net "P5E_CPU0_P0_TX_C_DP<7>")
	)
	(segment
		(start 311.517792 -391.902442)
		(end 311.517792 -391.784586)
		(width 0.1016)
		(layer "F.Cu")
		(net "P5E_CPU0_P0_TX_C_DP<7>")
	)
	(segment
		(start 311.306972 -391.978896)
		(end 311.441338 -391.978896)
		(width 0.1016)
		(layer "F.Cu")
		(net "P5E_CPU0_P0_TX_C_DP<7>")
	)
	(segment
		(start 311.441338 -391.978896)
		(end 311.517792 -391.902442)
		(width 0.1016)
		(layer "F.Cu")
		(net "P5E_CPU0_P0_TX_C_DP<7>")
	)
	(segment
		(start 311.215786 -391.6172)
		(end 311.215786 -391.88771)
		(width 0.1016)
		(layer "F.Cu")
		(net "P5E_CPU0_P0_TX_C_DP<7>")
	)
	(segment
		(start 311.508394 -391.324592)
		(end 311.215786 -391.6172)
		(width 0.1016)
		(layer "F.Cu")
		(net "P5E_CPU0_P0_TX_C_DP<7>")
	)
	(segment
		(start 311.490614 -387.046216)
		(end 311.508394 -391.324592)
		(width 0.1016)
		(layer "F.Cu")
		(net "P5E_CPU0_P0_TX_C_DP<7>")
	)
	(segment
		(start 311.215786 -391.88771)
		(end 311.306972 -391.978896)
		(width 0.1016)
		(layer "F.Cu")
		(net "P5E_CPU0_P0_TX_C_DP<7>")
	)
	(arc
		(start 311.251346 -386.289804)
		(mid 311.292024 -386.553596)
		(end 311.410096 -386.792978)
		(width 0.1016)
		(layer "F.Cu")
		(net "P5E_CPU0_P0_TX_C_DP<7>")
	)
	(arc
		(start 311.410096 -386.792978)
		(mid 311.469658 -386.913463)
		(end 311.490614 -387.046216)
		(width 0.1016)
		(layer "F.Cu")
		(net "P5E_CPU0_P0_TX_C_DP<7>")
	)
	(arc
		(start 311.203848 -384.450082)
		(mid 311.23899 -384.502771)
		(end 311.251346 -384.56489)
		(width 0.1016)
		(layer "F.Cu")
		(net "P5E_CPU0_P0_TX_C_DP<7>")
	)
	(segment
		(start 310.317642 -391.902442)
		(end 310.317642 -391.784586)
		(width 0.1016)
		(layer "F.Cu")
		(net "P5E_CPU0_P0_TX_C_DP<6>")
	)
	(segment
		(start 309.709058 -387.115558)
		(end 309.745634 -387.205474)
		(width 0.1016)
		(layer "F.Cu")
		(net "P5E_CPU0_P0_TX_C_DP<6>")
	)
	(segment
		(start 310.241188 -391.978896)
		(end 310.317642 -391.902442)
		(width 0.1016)
		(layer "F.Cu")
		(net "P5E_CPU0_P0_TX_C_DP<6>")
	)
	(segment
		(start 308.174136 -380.649734)
		(end 309.406544 -381.882142)
		(width 0.1016)
		(layer "F.Cu")
		(net "P5E_CPU0_P0_TX_C_DP<6>")
	)
	(segment
		(start 310.106822 -391.978896)
		(end 310.241188 -391.978896)
		(width 0.1016)
		(layer "F.Cu")
		(net "P5E_CPU0_P0_TX_C_DP<6>")
	)
	(segment
		(start 310.015636 -391.88771)
		(end 310.106822 -391.978896)
		(width 0.1016)
		(layer "F.Cu")
		(net "P5E_CPU0_P0_TX_C_DP<6>")
	)
	(segment
		(start 307.847746 -379.56998)
		(end 307.847746 -379.86208)
		(width 0.1016)
		(layer "F.Cu")
		(net "P5E_CPU0_P0_TX_C_DP<6>")
	)
	(segment
		(start 309.567072 -382.268984)
		(end 309.567072 -386.388102)
		(width 0.1016)
		(layer "F.Cu")
		(net "P5E_CPU0_P0_TX_C_DP<6>")
	)
	(segment
		(start 310.015636 -391.6172)
		(end 310.015636 -391.88771)
		(width 0.1016)
		(layer "F.Cu")
		(net "P5E_CPU0_P0_TX_C_DP<6>")
	)
	(segment
		(start 310.308244 -390.076436)
		(end 310.308244 -391.324592)
		(width 0.1016)
		(layer "F.Cu")
		(net "P5E_CPU0_P0_TX_C_DP<6>")
	)
	(segment
		(start 307.498496 -379.22073)
		(end 307.847746 -379.56998)
		(width 0.1016)
		(layer "F.Cu")
		(net "P5E_CPU0_P0_TX_C_DP<6>")
	)
	(segment
		(start 310.308244 -391.324592)
		(end 310.015636 -391.6172)
		(width 0.1016)
		(layer "F.Cu")
		(net "P5E_CPU0_P0_TX_C_DP<6>")
	)
	(arc
		(start 309.406544 -381.882142)
		(mid 309.525301 -382.059597)
		(end 309.567072 -382.268984)
		(width 0.1016)
		(layer "F.Cu")
		(net "P5E_CPU0_P0_TX_C_DP<6>")
	)
	(arc
		(start 307.847746 -379.86208)
		(mid 307.932615 -380.288367)
		(end 308.174136 -380.649734)
		(width 0.1016)
		(layer "F.Cu")
		(net "P5E_CPU0_P0_TX_C_DP<6>")
	)
	(arc
		(start 309.745634 -387.205474)
		(mid 310.166203 -388.613663)
		(end 310.308244 -390.076436)
		(width 0.1016)
		(layer "F.Cu")
		(net "P5E_CPU0_P0_TX_C_DP<6>")
	)
	(arc
		(start 309.567072 -386.388102)
		(mid 309.602877 -386.758698)
		(end 309.709058 -387.115558)
		(width 0.1016)
		(layer "F.Cu")
		(net "P5E_CPU0_P0_TX_C_DP<6>")
	)
	(segment
		(start 308.81574 -391.6172)
		(end 308.81574 -391.88771)
		(width 0.1016)
		(layer "F.Cu")
		(net "P5E_CPU0_P0_TX_C_DP<5>")
	)
	(segment
		(start 309.108348 -391.324592)
		(end 308.81574 -391.6172)
		(width 0.1016)
		(layer "F.Cu")
		(net "P5E_CPU0_P0_TX_C_DP<5>")
	)
	(segment
		(start 309.117746 -391.902442)
		(end 309.117746 -391.784586)
		(width 0.1016)
		(layer "F.Cu")
		(net "P5E_CPU0_P0_TX_C_DP<5>")
	)
	(segment
		(start 309.108348 -390.033764)
		(end 309.108348 -391.324592)
		(width 0.1016)
		(layer "F.Cu")
		(net "P5E_CPU0_P0_TX_C_DP<5>")
	)
	(segment
		(start 305.796696 -381.68453)
		(end 306.145946 -382.03378)
		(width 0.1016)
		(layer "F.Cu")
		(net "P5E_CPU0_P0_TX_C_DP<5>")
	)
	(segment
		(start 309.041292 -391.978896)
		(end 309.117746 -391.902442)
		(width 0.1016)
		(layer "F.Cu")
		(net "P5E_CPU0_P0_TX_C_DP<5>")
	)
	(segment
		(start 306.145946 -382.03378)
		(end 306.145946 -383.744216)
		(width 0.1016)
		(layer "F.Cu")
		(net "P5E_CPU0_P0_TX_C_DP<5>")
	)
	(segment
		(start 308.81574 -391.88771)
		(end 308.906926 -391.978896)
		(width 0.1016)
		(layer "F.Cu")
		(net "P5E_CPU0_P0_TX_C_DP<5>")
	)
	(segment
		(start 306.509928 -384.943858)
		(end 308.43982 -387.830822)
		(width 0.1016)
		(layer "F.Cu")
		(net "P5E_CPU0_P0_TX_C_DP<5>")
	)
	(segment
		(start 308.906926 -391.978896)
		(end 309.041292 -391.978896)
		(width 0.1016)
		(layer "F.Cu")
		(net "P5E_CPU0_P0_TX_C_DP<5>")
	)
	(arc
		(start 306.145946 -383.744216)
		(mid 306.238951 -384.371034)
		(end 306.509928 -384.943858)
		(width 0.1016)
		(layer "F.Cu")
		(net "P5E_CPU0_P0_TX_C_DP<5>")
	)
	(arc
		(start 308.43982 -387.830822)
		(mid 308.937526 -388.882692)
		(end 309.108348 -390.033764)
		(width 0.1016)
		(layer "F.Cu")
		(net "P5E_CPU0_P0_TX_C_DP<5>")
	)
	(segment
		(start 307.70703 -391.978896)
		(end 307.841396 -391.978896)
		(width 0.1016)
		(layer "F.Cu")
		(net "P5E_CPU0_P0_TX_C_DP<4>")
	)
	(segment
		(start 307.908452 -389.954008)
		(end 307.908452 -391.324592)
		(width 0.1016)
		(layer "F.Cu")
		(net "P5E_CPU0_P0_TX_C_DP<4>")
	)
	(segment
		(start 307.615844 -391.88771)
		(end 307.70703 -391.978896)
		(width 0.1016)
		(layer "F.Cu")
		(net "P5E_CPU0_P0_TX_C_DP<4>")
	)
	(segment
		(start 307.841396 -391.978896)
		(end 307.91785 -391.902442)
		(width 0.1016)
		(layer "F.Cu")
		(net "P5E_CPU0_P0_TX_C_DP<4>")
	)
	(segment
		(start 304.094896 -384.14833)
		(end 304.444146 -384.49758)
		(width 0.1016)
		(layer "F.Cu")
		(net "P5E_CPU0_P0_TX_C_DP<4>")
	)
	(segment
		(start 304.444146 -384.49758)
		(end 304.444146 -384.71475)
		(width 0.1016)
		(layer "F.Cu")
		(net "P5E_CPU0_P0_TX_C_DP<4>")
	)
	(segment
		(start 307.91785 -391.902442)
		(end 307.91785 -391.784586)
		(width 0.1016)
		(layer "F.Cu")
		(net "P5E_CPU0_P0_TX_C_DP<4>")
	)
	(segment
		(start 304.688494 -385.303776)
		(end 307.576474 -388.822438)
		(width 0.1016)
		(layer "F.Cu")
		(net "P5E_CPU0_P0_TX_C_DP<4>")
	)
	(segment
		(start 304.444146 -384.71475)
		(end 304.688494 -385.303776)
		(width 0.1016)
		(layer "F.Cu")
		(net "P5E_CPU0_P0_TX_C_DP<4>")
	)
	(segment
		(start 307.908452 -391.324592)
		(end 307.615844 -391.6172)
		(width 0.1016)
		(layer "F.Cu")
		(net "P5E_CPU0_P0_TX_C_DP<4>")
	)
	(segment
		(start 307.615844 -391.6172)
		(end 307.615844 -391.88771)
		(width 0.1016)
		(layer "F.Cu")
		(net "P5E_CPU0_P0_TX_C_DP<4>")
	)
	(arc
		(start 307.576474 -388.822438)
		(mid 307.823603 -389.364422)
		(end 307.908452 -389.954008)
		(width 0.1016)
		(layer "F.Cu")
		(net "P5E_CPU0_P0_TX_C_DP<4>")
	)
	(segment
		(start 306.641246 -391.978896)
		(end 306.7177 -391.902442)
		(width 0.1016)
		(layer "F.Cu")
		(net "P5E_CPU0_P0_TX_C_DP<3>")
	)
	(segment
		(start 306.415694 -391.6172)
		(end 306.415694 -391.88771)
		(width 0.1016)
		(layer "F.Cu")
		(net "P5E_CPU0_P0_TX_C_DP<3>")
	)
	(segment
		(start 301.040546 -379.56998)
		(end 301.040546 -379.95352)
		(width 0.1016)
		(layer "F.Cu")
		(net "P5E_CPU0_P0_TX_C_DP<3>")
	)
	(segment
		(start 302.815752 -383.916682)
		(end 303.675796 -385.99364)
		(width 0.1016)
		(layer "F.Cu")
		(net "P5E_CPU0_P0_TX_C_DP<3>")
	)
	(segment
		(start 301.288196 -380.552198)
		(end 302.412908 -381.676656)
		(width 0.1016)
		(layer "F.Cu")
		(net "P5E_CPU0_P0_TX_C_DP<3>")
	)
	(segment
		(start 306.7177 -391.902442)
		(end 306.7177 -391.784586)
		(width 0.1016)
		(layer "F.Cu")
		(net "P5E_CPU0_P0_TX_C_DP<3>")
	)
	(segment
		(start 300.691296 -379.22073)
		(end 301.040546 -379.56998)
		(width 0.1016)
		(layer "F.Cu")
		(net "P5E_CPU0_P0_TX_C_DP<3>")
	)
	(segment
		(start 302.412908 -381.676656)
		(end 302.412908 -381.67691)
		(width 0.1016)
		(layer "F.Cu")
		(net "P5E_CPU0_P0_TX_C_DP<3>")
	)
	(segment
		(start 302.75022 -382.120902)
		(end 302.75022 -383.585466)
		(width 0.1016)
		(layer "F.Cu")
		(net "P5E_CPU0_P0_TX_C_DP<3>")
	)
	(segment
		(start 306.708302 -391.324592)
		(end 306.415694 -391.6172)
		(width 0.1016)
		(layer "F.Cu")
		(net "P5E_CPU0_P0_TX_C_DP<3>")
	)
	(segment
		(start 303.675796 -385.99364)
		(end 303.946814 -386.446014)
		(width 0.1016)
		(layer "F.Cu")
		(net "P5E_CPU0_P0_TX_C_DP<3>")
	)
	(segment
		(start 306.415694 -391.88771)
		(end 306.50688 -391.978896)
		(width 0.1016)
		(layer "F.Cu")
		(net "P5E_CPU0_P0_TX_C_DP<3>")
	)
	(segment
		(start 302.412908 -381.67691)
		(end 302.67402 -381.938022)
		(width 0.1016)
		(layer "F.Cu")
		(net "P5E_CPU0_P0_TX_C_DP<3>")
	)
	(segment
		(start 303.946814 -386.446014)
		(end 306.589938 -389.666734)
		(width 0.1016)
		(layer "F.Cu")
		(net "P5E_CPU0_P0_TX_C_DP<3>")
	)
	(segment
		(start 306.50688 -391.978896)
		(end 306.641246 -391.978896)
		(width 0.1016)
		(layer "F.Cu")
		(net "P5E_CPU0_P0_TX_C_DP<3>")
	)
	(segment
		(start 306.708302 -389.99668)
		(end 306.708302 -391.324592)
		(width 0.1016)
		(layer "F.Cu")
		(net "P5E_CPU0_P0_TX_C_DP<3>")
	)
	(arc
		(start 302.67402 -381.938022)
		(mid 302.730358 -382.021869)
		(end 302.75022 -382.120902)
		(width 0.1016)
		(layer "F.Cu")
		(net "P5E_CPU0_P0_TX_C_DP<3>")
	)
	(arc
		(start 306.589938 -389.666734)
		(mid 306.677795 -389.821418)
		(end 306.708302 -389.99668)
		(width 0.1016)
		(layer "F.Cu")
		(net "P5E_CPU0_P0_TX_C_DP<3>")
	)
	(arc
		(start 302.75022 -383.585466)
		(mid 302.766688 -383.754298)
		(end 302.815752 -383.916682)
		(width 0.1016)
		(layer "F.Cu")
		(net "P5E_CPU0_P0_TX_C_DP<3>")
	)
	(arc
		(start 301.040546 -379.95352)
		(mid 301.104803 -380.277503)
		(end 301.288196 -380.552198)
		(width 0.1016)
		(layer "F.Cu")
		(net "P5E_CPU0_P0_TX_C_DP<3>")
	)
	(segment
		(start 301.988728 -385.064508)
		(end 302.710596 -386.807456)
		(width 0.1016)
		(layer "F.Cu")
		(net "P5E_CPU0_P0_TX_C_DP<2>")
	)
	(segment
		(start 299.596556 -383.286762)
		(end 299.644562 -383.334768)
		(width 0.1016)
		(layer "F.Cu")
		(net "P5E_CPU0_P0_TX_C_DP<2>")
	)
	(segment
		(start 298.989496 -381.68453)
		(end 299.338746 -382.03378)
		(width 0.1016)
		(layer "F.Cu")
		(net "P5E_CPU0_P0_TX_C_DP<2>")
	)
	(segment
		(start 305.517804 -391.902442)
		(end 305.517804 -391.784586)
		(width 0.1016)
		(layer "F.Cu")
		(net "P5E_CPU0_P0_TX_C_DP<2>")
	)
	(segment
		(start 300.06544 -383.6162)
		(end 300.980348 -383.995168)
		(width 0.1016)
		(layer "F.Cu")
		(net "P5E_CPU0_P0_TX_C_DP<2>")
	)
	(segment
		(start 303.130966 -387.439154)
		(end 305.33721 -390.124696)
		(width 0.1016)
		(layer "F.Cu")
		(net "P5E_CPU0_P0_TX_C_DP<2>")
	)
	(segment
		(start 305.215798 -391.88771)
		(end 305.306984 -391.978896)
		(width 0.1016)
		(layer "F.Cu")
		(net "P5E_CPU0_P0_TX_C_DP<2>")
	)
	(segment
		(start 305.508406 -390.60247)
		(end 305.508406 -391.324592)
		(width 0.1016)
		(layer "F.Cu")
		(net "P5E_CPU0_P0_TX_C_DP<2>")
	)
	(segment
		(start 302.710596 -386.807456)
		(end 302.85309 -387.044692)
		(width 0.1016)
		(layer "F.Cu")
		(net "P5E_CPU0_P0_TX_C_DP<2>")
	)
	(segment
		(start 305.306984 -391.978896)
		(end 305.44135 -391.978896)
		(width 0.1016)
		(layer "F.Cu")
		(net "P5E_CPU0_P0_TX_C_DP<2>")
	)
	(segment
		(start 301.031656 -384.029458)
		(end 301.831248 -384.82905)
		(width 0.1016)
		(layer "F.Cu")
		(net "P5E_CPU0_P0_TX_C_DP<2>")
	)
	(segment
		(start 305.508406 -391.324592)
		(end 305.215798 -391.6172)
		(width 0.1016)
		(layer "F.Cu")
		(net "P5E_CPU0_P0_TX_C_DP<2>")
	)
	(segment
		(start 305.215798 -391.6172)
		(end 305.215798 -391.88771)
		(width 0.1016)
		(layer "F.Cu")
		(net "P5E_CPU0_P0_TX_C_DP<2>")
	)
	(segment
		(start 299.338746 -382.03378)
		(end 299.338746 -382.664208)
		(width 0.1016)
		(layer "F.Cu")
		(net "P5E_CPU0_P0_TX_C_DP<2>")
	)
	(segment
		(start 305.44135 -391.978896)
		(end 305.517804 -391.902442)
		(width 0.1016)
		(layer "F.Cu")
		(net "P5E_CPU0_P0_TX_C_DP<2>")
	)
	(arc
		(start 301.831248 -384.82905)
		(mid 301.92161 -384.939008)
		(end 301.988728 -385.064508)
		(width 0.1016)
		(layer "F.Cu")
		(net "P5E_CPU0_P0_TX_C_DP<2>")
	)
	(arc
		(start 300.980348 -383.995168)
		(mid 301.007696 -384.009779)
		(end 301.031656 -384.029458)
		(width 0.1016)
		(layer "F.Cu")
		(net "P5E_CPU0_P0_TX_C_DP<2>")
	)
	(arc
		(start 305.33721 -390.124696)
		(mid 305.464262 -390.348722)
		(end 305.508406 -390.60247)
		(width 0.1016)
		(layer "F.Cu")
		(net "P5E_CPU0_P0_TX_C_DP<2>")
	)
	(arc
		(start 299.338746 -382.664208)
		(mid 299.405745 -383.001123)
		(end 299.596556 -383.286762)
		(width 0.1016)
		(layer "F.Cu")
		(net "P5E_CPU0_P0_TX_C_DP<2>")
	)
	(arc
		(start 299.644562 -383.334768)
		(mid 299.841146 -383.496205)
		(end 300.06544 -383.6162)
		(width 0.1016)
		(layer "F.Cu")
		(net "P5E_CPU0_P0_TX_C_DP<2>")
	)
	(arc
		(start 302.85309 -387.044692)
		(mid 302.984782 -387.247028)
		(end 303.130966 -387.439154)
		(width 0.1016)
		(layer "F.Cu")
		(net "P5E_CPU0_P0_TX_C_DP<2>")
	)
	(segment
		(start 303.229264 -389.104124)
		(end 304.257964 -390.358122)
		(width 0.1016)
		(layer "F.Cu")
		(net "P5E_CPU0_P0_TX_C_DP<1>")
	)
	(segment
		(start 304.400966 -390.59612)
		(end 304.524156 -390.893808)
		(width 0.1016)
		(layer "F.Cu")
		(net "P5E_CPU0_P0_TX_C_DP<1>")
	)
	(segment
		(start 302.090074 -387.736588)
		(end 302.090328 -387.736588)
		(width 0.1016)
		(layer "F.Cu")
		(net "P5E_CPU0_P0_TX_C_DP<1>")
	)
	(segment
		(start 302.090328 -387.736588)
		(end 302.383952 -388.176008)
		(width 0.1016)
		(layer "F.Cu")
		(net "P5E_CPU0_P0_TX_C_DP<1>")
	)
	(segment
		(start 304.617628 -391.612882)
		(end 304.617628 -392.30427)
		(width 0.1016)
		(layer "F.Cu")
		(net "P5E_CPU0_P0_TX_C_DP<1>")
	)
	(segment
		(start 301.145194 -385.598416)
		(end 301.932848 -387.500876)
		(width 0.1016)
		(layer "F.Cu")
		(net "P5E_CPU0_P0_TX_C_DP<1>")
	)
	(segment
		(start 302.383952 -388.176008)
		(end 302.383952 -388.176262)
		(width 0.1016)
		(layer "F.Cu")
		(net "P5E_CPU0_P0_TX_C_DP<1>")
	)
	(segment
		(start 302.383952 -388.176262)
		(end 302.497744 -388.346442)
		(width 0.1016)
		(layer "F.Cu")
		(net "P5E_CPU0_P0_TX_C_DP<1>")
	)
	(segment
		(start 301.932848 -387.500876)
		(end 302.090074 -387.736588)
		(width 0.1016)
		(layer "F.Cu")
		(net "P5E_CPU0_P0_TX_C_DP<1>")
	)
	(segment
		(start 304.524156 -391.51941)
		(end 304.617628 -391.612882)
		(width 0.1016)
		(layer "F.Cu")
		(net "P5E_CPU0_P0_TX_C_DP<1>")
	)
	(segment
		(start 299.56125 -384.652266)
		(end 299.689012 -384.652266)
		(width 0.1016)
		(layer "F.Cu")
		(net "P5E_CPU0_P0_TX_C_DP<1>")
	)
	(segment
		(start 300.67885 -385.061968)
		(end 301.004986 -385.388104)
		(width 0.1016)
		(layer "F.Cu")
		(net "P5E_CPU0_P0_TX_C_DP<1>")
	)
	(segment
		(start 304.257964 -390.358122)
		(end 304.400966 -390.59612)
		(width 0.1016)
		(layer "F.Cu")
		(net "P5E_CPU0_P0_TX_C_DP<1>")
	)
	(segment
		(start 299.233844 -384.32486)
		(end 299.56125 -384.652266)
		(width 0.1016)
		(layer "F.Cu")
		(net "P5E_CPU0_P0_TX_C_DP<1>")
	)
	(segment
		(start 302.618648 -388.493254)
		(end 303.229264 -389.104124)
		(width 0.1016)
		(layer "F.Cu")
		(net "P5E_CPU0_P0_TX_C_DP<1>")
	)
	(segment
		(start 304.524156 -390.893808)
		(end 304.524156 -391.51941)
		(width 0.1016)
		(layer "F.Cu")
		(net "P5E_CPU0_P0_TX_C_DP<1>")
	)
	(arc
		(start 299.689012 -384.652266)
		(mid 300.2247 -384.758634)
		(end 300.67885 -385.061968)
		(width 0.1016)
		(layer "F.Cu")
		(net "P5E_CPU0_P0_TX_C_DP<1>")
	)
	(arc
		(start 302.497744 -388.346442)
		(mid 302.55459 -388.422818)
		(end 302.618648 -388.493254)
		(width 0.1016)
		(layer "F.Cu")
		(net "P5E_CPU0_P0_TX_C_DP<1>")
	)
	(arc
		(start 301.004986 -385.388104)
		(mid 301.085458 -385.486348)
		(end 301.145194 -385.598416)
		(width 0.1016)
		(layer "F.Cu")
		(net "P5E_CPU0_P0_TX_C_DP<1>")
	)
	(segment
		(start 324.551294 -388.090918)
		(end 324.246494 -388.090918)
		(width 0.1016)
		(layer "F.Cu")
		(net "P5E_CPU0_P0_TX_C_DP<15>")
	)
	(segment
		(start 324.134734 -388.202678)
		(end 323.419978 -388.202678)
		(width 0.1016)
		(layer "F.Cu")
		(net "P5E_CPU0_P0_TX_C_DP<15>")
	)
	(segment
		(start 321.108324 -390.587484)
		(end 321.108324 -391.398252)
		(width 0.1016)
		(layer "F.Cu")
		(net "P5E_CPU0_P0_TX_C_DP<15>")
	)
	(segment
		(start 324.663054 -388.202678)
		(end 324.551294 -388.090918)
		(width 0.1016)
		(layer "F.Cu")
		(net "P5E_CPU0_P0_TX_C_DP<15>")
	)
	(segment
		(start 321.108324 -391.398252)
		(end 321.202304 -391.492232)
		(width 0.1016)
		(layer "F.Cu")
		(net "P5E_CPU0_P0_TX_C_DP<15>")
	)
	(segment
		(start 325.124826 -388.202678)
		(end 324.663054 -388.202678)
		(width 0.1016)
		(layer "F.Cu")
		(net "P5E_CPU0_P0_TX_C_DP<15>")
	)
	(segment
		(start 324.246494 -388.090918)
		(end 324.134734 -388.202678)
		(width 0.1016)
		(layer "F.Cu")
		(net "P5E_CPU0_P0_TX_C_DP<15>")
	)
	(segment
		(start 323.165978 -388.30758)
		(end 321.265042 -390.208516)
		(width 0.1016)
		(layer "F.Cu")
		(net "P5E_CPU0_P0_TX_C_DP<15>")
	)
	(segment
		(start 321.202304 -391.492232)
		(end 321.202304 -391.700004)
		(width 0.1016)
		(layer "F.Cu")
		(net "P5E_CPU0_P0_TX_C_DP<15>")
	)
	(segment
		(start 325.474076 -387.853428)
		(end 325.124826 -388.202678)
		(width 0.1016)
		(layer "F.Cu")
		(net "P5E_CPU0_P0_TX_C_DP<15>")
	)
	(segment
		(start 321.202304 -391.700004)
		(end 321.117722 -391.784586)
		(width 0.1016)
		(layer "F.Cu")
		(net "P5E_CPU0_P0_TX_C_DP<15>")
	)
	(arc
		(start 323.419978 -388.202678)
		(mid 323.282525 -388.229832)
		(end 323.165978 -388.30758)
		(width 0.1016)
		(layer "F.Cu")
		(net "P5E_CPU0_P0_TX_C_DP<15>")
	)
	(arc
		(start 321.265042 -390.208516)
		(mid 321.148977 -390.382404)
		(end 321.108324 -390.587484)
		(width 0.1016)
		(layer "F.Cu")
		(net "P5E_CPU0_P0_TX_C_DP<15>")
	)
	(segment
		(start 324.724776 -384.88493)
		(end 320.169286 -389.44042)
		(width 0.1016)
		(layer "F.Cu")
		(net "P5E_CPU0_P0_TX_C_DP<14>")
	)
	(segment
		(start 320.002408 -391.492232)
		(end 320.002408 -391.700004)
		(width 0.1016)
		(layer "F.Cu")
		(net "P5E_CPU0_P0_TX_C_DP<14>")
	)
	(segment
		(start 325.474076 -384.449828)
		(end 325.038974 -384.88493)
		(width 0.1016)
		(layer "F.Cu")
		(net "P5E_CPU0_P0_TX_C_DP<14>")
	)
	(segment
		(start 319.908428 -390.071102)
		(end 319.908428 -391.398252)
		(width 0.1016)
		(layer "F.Cu")
		(net "P5E_CPU0_P0_TX_C_DP<14>")
	)
	(segment
		(start 319.908428 -391.398252)
		(end 320.002408 -391.492232)
		(width 0.1016)
		(layer "F.Cu")
		(net "P5E_CPU0_P0_TX_C_DP<14>")
	)
	(segment
		(start 320.002408 -391.700004)
		(end 319.917826 -391.784586)
		(width 0.1016)
		(layer "F.Cu")
		(net "P5E_CPU0_P0_TX_C_DP<14>")
	)
	(segment
		(start 325.038974 -384.88493)
		(end 324.724776 -384.88493)
		(width 0.1016)
		(layer "F.Cu")
		(net "P5E_CPU0_P0_TX_C_DP<14>")
	)
	(arc
		(start 320.169286 -389.44042)
		(mid 319.976162 -389.729824)
		(end 319.908428 -390.071102)
		(width 0.1016)
		(layer "F.Cu")
		(net "P5E_CPU0_P0_TX_C_DP<14>")
	)
	(segment
		(start 326.322944 -381.507238)
		(end 326.538336 -381.72263)
		(width 0.1016)
		(layer "F.Cu")
		(net "P5E_CPU0_P0_TX_C_DP<13>")
	)
	(segment
		(start 326.322944 -381.34925)
		(end 326.322944 -381.507238)
		(width 0.1016)
		(layer "F.Cu")
		(net "P5E_CPU0_P0_TX_C_DP<13>")
	)
	(segment
		(start 318.924178 -391.51941)
		(end 319.01765 -391.612882)
		(width 0.1016)
		(layer "F.Cu")
		(net "P5E_CPU0_P0_TX_C_DP<13>")
	)
	(segment
		(start 318.924178 -389.354822)
		(end 318.924178 -391.51941)
		(width 0.1016)
		(layer "F.Cu")
		(net "P5E_CPU0_P0_TX_C_DP<13>")
	)
	(segment
		(start 319.01765 -391.612882)
		(end 319.01765 -392.30427)
		(width 0.1016)
		(layer "F.Cu")
		(net "P5E_CPU0_P0_TX_C_DP<13>")
	)
	(segment
		(start 325.081646 -379.56998)
		(end 325.081646 -379.909832)
		(width 0.1016)
		(layer "F.Cu")
		(net "P5E_CPU0_P0_TX_C_DP<13>")
	)
	(segment
		(start 324.358254 -383.867914)
		(end 318.961516 -389.264652)
		(width 0.1016)
		(layer "F.Cu")
		(net "P5E_CPU0_P0_TX_C_DP<13>")
	)
	(segment
		(start 326.107044 -381.13335)
		(end 326.322944 -381.34925)
		(width 0.1016)
		(layer "F.Cu")
		(net "P5E_CPU0_P0_TX_C_DP<13>")
	)
	(segment
		(start 325.081646 -379.909832)
		(end 325.0819 -379.909578)
		(width 0.1016)
		(layer "F.Cu")
		(net "P5E_CPU0_P0_TX_C_DP<13>")
	)
	(segment
		(start 326.520048 -383.088388)
		(end 326.094598 -383.513838)
		(width 0.1016)
		(layer "F.Cu")
		(net "P5E_CPU0_P0_TX_C_DP<13>")
	)
	(segment
		(start 325.430896 -379.22073)
		(end 325.081646 -379.56998)
		(width 0.1016)
		(layer "F.Cu")
		(net "P5E_CPU0_P0_TX_C_DP<13>")
	)
	(segment
		(start 325.333614 -380.517908)
		(end 325.949056 -381.13335)
		(width 0.1016)
		(layer "F.Cu")
		(net "P5E_CPU0_P0_TX_C_DP<13>")
	)
	(segment
		(start 325.656702 -383.69494)
		(end 324.77583 -383.69494)
		(width 0.1016)
		(layer "F.Cu")
		(net "P5E_CPU0_P0_TX_C_DP<13>")
	)
	(segment
		(start 325.949056 -381.13335)
		(end 326.107044 -381.13335)
		(width 0.1016)
		(layer "F.Cu")
		(net "P5E_CPU0_P0_TX_C_DP<13>")
	)
	(segment
		(start 326.75576 -382.248156)
		(end 326.75576 -382.518666)
		(width 0.1016)
		(layer "F.Cu")
		(net "P5E_CPU0_P0_TX_C_DP<13>")
	)
	(arc
		(start 318.961516 -389.264652)
		(mid 318.933873 -389.306022)
		(end 318.924178 -389.354822)
		(width 0.1016)
		(layer "F.Cu")
		(net "P5E_CPU0_P0_TX_C_DP<13>")
	)
	(arc
		(start 325.0819 -379.909578)
		(mid 325.147269 -380.238771)
		(end 325.333614 -380.517908)
		(width 0.1016)
		(layer "F.Cu")
		(net "P5E_CPU0_P0_TX_C_DP<13>")
	)
	(arc
		(start 324.77583 -383.69494)
		(mid 324.549836 -383.739893)
		(end 324.358254 -383.867914)
		(width 0.1016)
		(layer "F.Cu")
		(net "P5E_CPU0_P0_TX_C_DP<13>")
	)
	(arc
		(start 326.538336 -381.72263)
		(mid 326.699331 -381.963759)
		(end 326.75576 -382.248156)
		(width 0.1016)
		(layer "F.Cu")
		(net "P5E_CPU0_P0_TX_C_DP<13>")
	)
	(arc
		(start 326.75576 -382.518666)
		(mid 326.694616 -382.827)
		(end 326.520048 -383.088388)
		(width 0.1016)
		(layer "F.Cu")
		(net "P5E_CPU0_P0_TX_C_DP<13>")
	)
	(arc
		(start 326.094598 -383.513838)
		(mid 325.89366 -383.647915)
		(end 325.656702 -383.69494)
		(width 0.1016)
		(layer "F.Cu")
		(net "P5E_CPU0_P0_TX_C_DP<13>")
	)
	(segment
		(start 317.441326 -391.978896)
		(end 317.51778 -391.902442)
		(width 0.1016)
		(layer "F.Cu")
		(net "P5E_CPU0_P0_TX_C_DP<12>")
	)
	(segment
		(start 317.215774 -391.88771)
		(end 317.30696 -391.978896)
		(width 0.1016)
		(layer "F.Cu")
		(net "P5E_CPU0_P0_TX_C_DP<12>")
	)
	(segment
		(start 323.17182 -382.039368)
		(end 323.17182 -382.944878)
		(width 0.1016)
		(layer "F.Cu")
		(net "P5E_CPU0_P0_TX_C_DP<12>")
	)
	(segment
		(start 317.215774 -391.6172)
		(end 317.215774 -391.88771)
		(width 0.1016)
		(layer "F.Cu")
		(net "P5E_CPU0_P0_TX_C_DP<12>")
	)
	(segment
		(start 323.099176 -383.119376)
		(end 317.795402 -388.42315)
		(width 0.1016)
		(layer "F.Cu")
		(net "P5E_CPU0_P0_TX_C_DP<12>")
	)
	(segment
		(start 321.462146 -379.56998)
		(end 321.462146 -379.9205)
		(width 0.1016)
		(layer "F.Cu")
		(net "P5E_CPU0_P0_TX_C_DP<12>")
	)
	(segment
		(start 317.508382 -391.324592)
		(end 317.215774 -391.6172)
		(width 0.1016)
		(layer "F.Cu")
		(net "P5E_CPU0_P0_TX_C_DP<12>")
	)
	(segment
		(start 317.30696 -391.978896)
		(end 317.441326 -391.978896)
		(width 0.1016)
		(layer "F.Cu")
		(net "P5E_CPU0_P0_TX_C_DP<12>")
	)
	(segment
		(start 317.51778 -391.902442)
		(end 317.51778 -391.784586)
		(width 0.1016)
		(layer "F.Cu")
		(net "P5E_CPU0_P0_TX_C_DP<12>")
	)
	(segment
		(start 321.714368 -380.529338)
		(end 323.134482 -381.949198)
		(width 0.1016)
		(layer "F.Cu")
		(net "P5E_CPU0_P0_TX_C_DP<12>")
	)
	(segment
		(start 321.112896 -379.22073)
		(end 321.462146 -379.56998)
		(width 0.1016)
		(layer "F.Cu")
		(net "P5E_CPU0_P0_TX_C_DP<12>")
	)
	(segment
		(start 317.508382 -389.116062)
		(end 317.508382 -391.324592)
		(width 0.1016)
		(layer "F.Cu")
		(net "P5E_CPU0_P0_TX_C_DP<12>")
	)
	(arc
		(start 321.462146 -379.9205)
		(mid 321.52769 -380.250013)
		(end 321.714368 -380.529338)
		(width 0.1016)
		(layer "F.Cu")
		(net "P5E_CPU0_P0_TX_C_DP<12>")
	)
	(arc
		(start 323.134482 -381.949198)
		(mid 323.162125 -381.990568)
		(end 323.17182 -382.039368)
		(width 0.1016)
		(layer "F.Cu")
		(net "P5E_CPU0_P0_TX_C_DP<12>")
	)
	(arc
		(start 317.795402 -388.42315)
		(mid 317.582981 -388.741061)
		(end 317.508382 -389.116062)
		(width 0.1016)
		(layer "F.Cu")
		(net "P5E_CPU0_P0_TX_C_DP<12>")
	)
	(arc
		(start 323.17182 -382.944878)
		(mid 323.152826 -383.039333)
		(end 323.099176 -383.119376)
		(width 0.1016)
		(layer "F.Cu")
		(net "P5E_CPU0_P0_TX_C_DP<12>")
	)
	(segment
		(start 319.411096 -381.68453)
		(end 319.760346 -382.03378)
		(width 0.1016)
		(layer "F.Cu")
		(net "P5E_CPU0_P0_TX_C_DP<11>")
	)
	(segment
		(start 316.10681 -391.978896)
		(end 316.241176 -391.978896)
		(width 0.1016)
		(layer "F.Cu")
		(net "P5E_CPU0_P0_TX_C_DP<11>")
	)
	(segment
		(start 316.241176 -391.978896)
		(end 316.31763 -391.902442)
		(width 0.1016)
		(layer "F.Cu")
		(net "P5E_CPU0_P0_TX_C_DP<11>")
	)
	(segment
		(start 316.31763 -391.902442)
		(end 316.31763 -391.784586)
		(width 0.1016)
		(layer "F.Cu")
		(net "P5E_CPU0_P0_TX_C_DP<11>")
	)
	(segment
		(start 316.015624 -391.88771)
		(end 316.10681 -391.978896)
		(width 0.1016)
		(layer "F.Cu")
		(net "P5E_CPU0_P0_TX_C_DP<11>")
	)
	(segment
		(start 319.760346 -382.03378)
		(end 319.760346 -384.618484)
		(width 0.1016)
		(layer "F.Cu")
		(net "P5E_CPU0_P0_TX_C_DP<11>")
	)
	(segment
		(start 316.015624 -391.6172)
		(end 316.015624 -391.88771)
		(width 0.1016)
		(layer "F.Cu")
		(net "P5E_CPU0_P0_TX_C_DP<11>")
	)
	(segment
		(start 316.308232 -391.324592)
		(end 316.015624 -391.6172)
		(width 0.1016)
		(layer "F.Cu")
		(net "P5E_CPU0_P0_TX_C_DP<11>")
	)
	(segment
		(start 316.308232 -388.266178)
		(end 316.308232 -391.324592)
		(width 0.1016)
		(layer "F.Cu")
		(net "P5E_CPU0_P0_TX_C_DP<11>")
	)
	(segment
		(start 319.723008 -384.708654)
		(end 316.407546 -388.024116)
		(width 0.1016)
		(layer "F.Cu")
		(net "P5E_CPU0_P0_TX_C_DP<11>")
	)
	(arc
		(start 316.407546 -388.024116)
		(mid 316.333985 -388.135332)
		(end 316.308232 -388.266178)
		(width 0.1016)
		(layer "F.Cu")
		(net "P5E_CPU0_P0_TX_C_DP<11>")
	)
	(arc
		(start 319.760346 -384.618484)
		(mid 319.75064 -384.667279)
		(end 319.723008 -384.708654)
		(width 0.1016)
		(layer "F.Cu")
		(net "P5E_CPU0_P0_TX_C_DP<11>")
	)
	(segment
		(start 315.117734 -391.902442)
		(end 315.117734 -391.784586)
		(width 0.1016)
		(layer "F.Cu")
		(net "P5E_CPU0_P0_TX_C_DP<10>")
	)
	(segment
		(start 314.815728 -391.88771)
		(end 314.906914 -391.978896)
		(width 0.1016)
		(layer "F.Cu")
		(net "P5E_CPU0_P0_TX_C_DP<10>")
	)
	(segment
		(start 315.04128 -391.978896)
		(end 315.117734 -391.902442)
		(width 0.1016)
		(layer "F.Cu")
		(net "P5E_CPU0_P0_TX_C_DP<10>")
	)
	(segment
		(start 315.108336 -391.324592)
		(end 314.815728 -391.6172)
		(width 0.1016)
		(layer "F.Cu")
		(net "P5E_CPU0_P0_TX_C_DP<10>")
	)
	(segment
		(start 316.441074 -385.811522)
		(end 315.387736 -386.86486)
		(width 0.1016)
		(layer "F.Cu")
		(net "P5E_CPU0_P0_TX_C_DP<10>")
	)
	(segment
		(start 315.108336 -387.286754)
		(end 315.108336 -391.324592)
		(width 0.1016)
		(layer "F.Cu")
		(net "P5E_CPU0_P0_TX_C_DP<10>")
	)
	(segment
		(start 314.815728 -391.6172)
		(end 314.815728 -391.88771)
		(width 0.1016)
		(layer "F.Cu")
		(net "P5E_CPU0_P0_TX_C_DP<10>")
	)
	(segment
		(start 314.906914 -391.978896)
		(end 315.04128 -391.978896)
		(width 0.1016)
		(layer "F.Cu")
		(net "P5E_CPU0_P0_TX_C_DP<10>")
	)
	(segment
		(start 318.020192 -384.674872)
		(end 317.038736 -385.656328)
		(width 0.1016)
		(layer "F.Cu")
		(net "P5E_CPU0_P0_TX_C_DP<10>")
	)
	(segment
		(start 318.05753 -384.496564)
		(end 318.05753 -384.584702)
		(width 0.1016)
		(layer "F.Cu")
		(net "P5E_CPU0_P0_TX_C_DP<10>")
	)
	(segment
		(start 317.709296 -384.14833)
		(end 318.05753 -384.496564)
		(width 0.1016)
		(layer "F.Cu")
		(net "P5E_CPU0_P0_TX_C_DP<10>")
	)
	(segment
		(start 315.387736 -386.86486)
		(end 315.387482 -386.86486)
		(width 0.1016)
		(layer "F.Cu")
		(net "P5E_CPU0_P0_TX_C_DP<10>")
	)
	(segment
		(start 315.387482 -386.86486)
		(end 315.208666 -387.043676)
		(width 0.1016)
		(layer "F.Cu")
		(net "P5E_CPU0_P0_TX_C_DP<10>")
	)
	(segment
		(start 316.924436 -385.703572)
		(end 316.701678 -385.703572)
		(width 0.1016)
		(layer "F.Cu")
		(net "P5E_CPU0_P0_TX_C_DP<10>")
	)
	(arc
		(start 315.208666 -387.043676)
		(mid 315.134367 -387.155245)
		(end 315.108336 -387.286754)
		(width 0.1016)
		(layer "F.Cu")
		(net "P5E_CPU0_P0_TX_C_DP<10>")
	)
	(arc
		(start 316.701678 -385.703572)
		(mid 316.560638 -385.731627)
		(end 316.441074 -385.811522)
		(width 0.1016)
		(layer "F.Cu")
		(net "P5E_CPU0_P0_TX_C_DP<10>")
	)
	(arc
		(start 318.05753 -384.584702)
		(mid 318.047824 -384.633497)
		(end 318.020192 -384.674872)
		(width 0.1016)
		(layer "F.Cu")
		(net "P5E_CPU0_P0_TX_C_DP<10>")
	)
	(arc
		(start 317.038736 -385.656328)
		(mid 316.986281 -385.691315)
		(end 316.924436 -385.703572)
		(width 0.1016)
		(layer "F.Cu")
		(net "P5E_CPU0_P0_TX_C_DP<10>")
	)
	(segment
		(start 302.906938 -391.978896)
		(end 303.041304 -391.978896)
		(width 0.1016)
		(layer "F.Cu")
		(net "P5E_CPU0_P0_TX_C_DP<0>")
	)
	(segment
		(start 300.834552 -390.537192)
		(end 301.139352 -390.537192)
		(width 0.1016)
		(layer "F.Cu")
		(net "P5E_CPU0_P0_TX_C_DP<0>")
	)
	(segment
		(start 299.889672 -390.425432)
		(end 300.001432 -390.537192)
		(width 0.1016)
		(layer "F.Cu")
		(net "P5E_CPU0_P0_TX_C_DP<0>")
	)
	(segment
		(start 300.417992 -390.425432)
		(end 300.722792 -390.425432)
		(width 0.1016)
		(layer "F.Cu")
		(net "P5E_CPU0_P0_TX_C_DP<0>")
	)
	(segment
		(start 303.041304 -391.978896)
		(end 303.117758 -391.902442)
		(width 0.1016)
		(layer "F.Cu")
		(net "P5E_CPU0_P0_TX_C_DP<0>")
	)
	(segment
		(start 300.722792 -390.425432)
		(end 300.834552 -390.537192)
		(width 0.1016)
		(layer "F.Cu")
		(net "P5E_CPU0_P0_TX_C_DP<0>")
	)
	(segment
		(start 303.10836 -391.199624)
		(end 303.10836 -391.324592)
		(width 0.1016)
		(layer "F.Cu")
		(net "P5E_CPU0_P0_TX_C_DP<0>")
	)
	(segment
		(start 302.815752 -391.6172)
		(end 302.815752 -391.88771)
		(width 0.1016)
		(layer "F.Cu")
		(net "P5E_CPU0_P0_TX_C_DP<0>")
	)
	(segment
		(start 300.306232 -390.537192)
		(end 300.417992 -390.425432)
		(width 0.1016)
		(layer "F.Cu")
		(net "P5E_CPU0_P0_TX_C_DP<0>")
	)
	(segment
		(start 303.10836 -391.324592)
		(end 302.815752 -391.6172)
		(width 0.1016)
		(layer "F.Cu")
		(net "P5E_CPU0_P0_TX_C_DP<0>")
	)
	(segment
		(start 303.117758 -391.902442)
		(end 303.117758 -391.784586)
		(width 0.1016)
		(layer "F.Cu")
		(net "P5E_CPU0_P0_TX_C_DP<0>")
	)
	(segment
		(start 299.233844 -390.77646)
		(end 299.584872 -390.425432)
		(width 0.1016)
		(layer "F.Cu")
		(net "P5E_CPU0_P0_TX_C_DP<0>")
	)
	(segment
		(start 299.584872 -390.425432)
		(end 299.889672 -390.425432)
		(width 0.1016)
		(layer "F.Cu")
		(net "P5E_CPU0_P0_TX_C_DP<0>")
	)
	(segment
		(start 302.815752 -391.88771)
		(end 302.906938 -391.978896)
		(width 0.1016)
		(layer "F.Cu")
		(net "P5E_CPU0_P0_TX_C_DP<0>")
	)
	(segment
		(start 301.251112 -390.425432)
		(end 301.752254 -390.425432)
		(width 0.1016)
		(layer "F.Cu")
		(net "P5E_CPU0_P0_TX_C_DP<0>")
	)
	(segment
		(start 301.95012 -390.464802)
		(end 302.555402 -390.714738)
		(width 0.1016)
		(layer "F.Cu")
		(net "P5E_CPU0_P0_TX_C_DP<0>")
	)
	(segment
		(start 300.001432 -390.537192)
		(end 300.306232 -390.537192)
		(width 0.1016)
		(layer "F.Cu")
		(net "P5E_CPU0_P0_TX_C_DP<0>")
	)
	(segment
		(start 301.139352 -390.537192)
		(end 301.251112 -390.425432)
		(width 0.1016)
		(layer "F.Cu")
		(net "P5E_CPU0_P0_TX_C_DP<0>")
	)
	(segment
		(start 302.766984 -390.85647)
		(end 303.10836 -391.199624)
		(width 0.1016)
		(layer "F.Cu")
		(net "P5E_CPU0_P0_TX_C_DP<0>")
	)
	(arc
		(start 302.555402 -390.714738)
		(mid 302.668233 -390.775093)
		(end 302.766984 -390.85647)
		(width 0.1016)
		(layer "F.Cu")
		(net "P5E_CPU0_P0_TX_C_DP<0>")
	)
	(arc
		(start 301.752254 -390.425432)
		(mid 301.853119 -390.435399)
		(end 301.95012 -390.464802)
		(width 0.1016)
		(layer "F.Cu")
		(net "P5E_CPU0_P0_TX_C_DP<0>")
	)
	(segment
		(start 316.549278 -382.315466)
		(end 316.549278 -383.376932)
		(width 0.1016)
		(layer "F.Cu")
		(net "P5E_CPU0_P0_TX_C_DN<9>")
	)
	(segment
		(start 315.220096 -379.22073)
		(end 314.870846 -379.56998)
		(width 0.1016)
		(layer "F.Cu")
		(net "P5E_CPU0_P0_TX_C_DN<9>")
	)
	(segment
		(start 314.12434 -386.105908)
		(end 314.12434 -391.51941)
		(width 0.1016)
		(layer "F.Cu")
		(net "P5E_CPU0_P0_TX_C_DN<9>")
	)
	(segment
		(start 314.12434 -391.51941)
		(end 314.217812 -391.612882)
		(width 0.1016)
		(layer "F.Cu")
		(net "P5E_CPU0_P0_TX_C_DN<9>")
	)
	(segment
		(start 314.217812 -391.612882)
		(end 314.217812 -392.30427)
		(width 0.1016)
		(layer "F.Cu")
		(net "P5E_CPU0_P0_TX_C_DN<9>")
	)
	(segment
		(start 315.123322 -380.518162)
		(end 316.286388 -381.681228)
		(width 0.1016)
		(layer "F.Cu")
		(net "P5E_CPU0_P0_TX_C_DN<9>")
	)
	(segment
		(start 314.870846 -379.56998)
		(end 314.870846 -379.909324)
		(width 0.1016)
		(layer "F.Cu")
		(net "P5E_CPU0_P0_TX_C_DN<9>")
	)
	(segment
		(start 315.338206 -384.935984)
		(end 315.180218 -384.935984)
		(width 0.1016)
		(layer "F.Cu")
		(net "P5E_CPU0_P0_TX_C_DN<9>")
	)
	(segment
		(start 316.414912 -383.70129)
		(end 315.554106 -384.562096)
		(width 0.1016)
		(layer "F.Cu")
		(net "P5E_CPU0_P0_TX_C_DN<9>")
	)
	(segment
		(start 315.180218 -384.935984)
		(end 314.205112 -385.91109)
		(width 0.1016)
		(layer "F.Cu")
		(net "P5E_CPU0_P0_TX_C_DN<9>")
	)
	(segment
		(start 315.554106 -384.562096)
		(end 315.554106 -384.720084)
		(width 0.1016)
		(layer "F.Cu")
		(net "P5E_CPU0_P0_TX_C_DN<9>")
	)
	(segment
		(start 315.554106 -384.720084)
		(end 315.338206 -384.935984)
		(width 0.1016)
		(layer "F.Cu")
		(net "P5E_CPU0_P0_TX_C_DN<9>")
	)
	(arc
		(start 314.870846 -379.909324)
		(mid 314.936576 -380.238827)
		(end 315.123322 -380.518162)
		(width 0.1016)
		(layer "F.Cu")
		(net "P5E_CPU0_P0_TX_C_DN<9>")
	)
	(arc
		(start 316.549278 -383.376932)
		(mid 316.51436 -383.552478)
		(end 316.414912 -383.70129)
		(width 0.1016)
		(layer "F.Cu")
		(net "P5E_CPU0_P0_TX_C_DN<9>")
	)
	(arc
		(start 314.205112 -385.91109)
		(mid 314.145334 -386.000459)
		(end 314.12434 -386.105908)
		(width 0.1016)
		(layer "F.Cu")
		(net "P5E_CPU0_P0_TX_C_DN<9>")
	)
	(arc
		(start 316.286388 -381.681228)
		(mid 316.480905 -381.972204)
		(end 316.549278 -382.315466)
		(width 0.1016)
		(layer "F.Cu")
		(net "P5E_CPU0_P0_TX_C_DN<9>")
	)
	(segment
		(start 312.92419 -385.700016)
		(end 312.92419 -391.51941)
		(width 0.1016)
		(layer "F.Cu")
		(net "P5E_CPU0_P0_TX_C_DN<8>")
	)
	(segment
		(start 313.280806 -383.3368)
		(end 313.280806 -383.6416)
		(width 0.1016)
		(layer "F.Cu")
		(net "P5E_CPU0_P0_TX_C_DN<8>")
	)
	(segment
		(start 313.518296 -381.68453)
		(end 313.216544 -381.986282)
		(width 0.1016)
		(layer "F.Cu")
		(net "P5E_CPU0_P0_TX_C_DN<8>")
	)
	(segment
		(start 313.169046 -382.10109)
		(end 313.169046 -383.22504)
		(width 0.1016)
		(layer "F.Cu")
		(net "P5E_CPU0_P0_TX_C_DN<8>")
	)
	(segment
		(start 313.169046 -383.75336)
		(end 313.169046 -384.998976)
		(width 0.1016)
		(layer "F.Cu")
		(net "P5E_CPU0_P0_TX_C_DN<8>")
	)
	(segment
		(start 313.017662 -391.612882)
		(end 313.017662 -392.30427)
		(width 0.1016)
		(layer "F.Cu")
		(net "P5E_CPU0_P0_TX_C_DN<8>")
	)
	(segment
		(start 313.280806 -383.6416)
		(end 313.169046 -383.75336)
		(width 0.1016)
		(layer "F.Cu")
		(net "P5E_CPU0_P0_TX_C_DN<8>")
	)
	(segment
		(start 313.169046 -383.22504)
		(end 313.280806 -383.3368)
		(width 0.1016)
		(layer "F.Cu")
		(net "P5E_CPU0_P0_TX_C_DN<8>")
	)
	(segment
		(start 312.92419 -391.51941)
		(end 313.017662 -391.612882)
		(width 0.1016)
		(layer "F.Cu")
		(net "P5E_CPU0_P0_TX_C_DN<8>")
	)
	(arc
		(start 313.028838 -385.404106)
		(mid 312.992774 -385.456405)
		(end 312.96356 -385.512818)
		(width 0.1016)
		(layer "F.Cu")
		(net "P5E_CPU0_P0_TX_C_DN<8>")
	)
	(arc
		(start 312.96356 -385.512818)
		(mid 312.934096 -385.604364)
		(end 312.92419 -385.700016)
		(width 0.1016)
		(layer "F.Cu")
		(net "P5E_CPU0_P0_TX_C_DN<8>")
	)
	(arc
		(start 313.169046 -384.998976)
		(mid 313.133049 -385.213347)
		(end 313.028838 -385.404106)
		(width 0.1016)
		(layer "F.Cu")
		(net "P5E_CPU0_P0_TX_C_DN<8>")
	)
	(arc
		(start 313.216544 -381.986282)
		(mid 313.181402 -382.038971)
		(end 313.169046 -382.10109)
		(width 0.1016)
		(layer "F.Cu")
		(net "P5E_CPU0_P0_TX_C_DN<8>")
	)
	(segment
		(start 311.816496 -384.14833)
		(end 311.51449 -384.450336)
		(width 0.1016)
		(layer "F.Cu")
		(net "P5E_CPU0_P0_TX_C_DN<7>")
	)
	(segment
		(start 311.724294 -391.32383)
		(end 311.724294 -391.51941)
		(width 0.1016)
		(layer "F.Cu")
		(net "P5E_CPU0_P0_TX_C_DN<7>")
	)
	(segment
		(start 311.706514 -387.0452)
		(end 311.724294 -391.32383)
		(width 0.1016)
		(layer "F.Cu")
		(net "P5E_CPU0_P0_TX_C_DN<7>")
	)
	(segment
		(start 311.579006 -385.56819)
		(end 311.579006 -385.87299)
		(width 0.1016)
		(layer "F.Cu")
		(net "P5E_CPU0_P0_TX_C_DN<7>")
	)
	(segment
		(start 311.467246 -385.98475)
		(end 311.467246 -386.28955)
		(width 0.1016)
		(layer "F.Cu")
		(net "P5E_CPU0_P0_TX_C_DN<7>")
	)
	(segment
		(start 311.817766 -391.612882)
		(end 311.817766 -392.30427)
		(width 0.1016)
		(layer "F.Cu")
		(net "P5E_CPU0_P0_TX_C_DN<7>")
	)
	(segment
		(start 311.579006 -385.87299)
		(end 311.467246 -385.98475)
		(width 0.1016)
		(layer "F.Cu")
		(net "P5E_CPU0_P0_TX_C_DN<7>")
	)
	(segment
		(start 311.467246 -384.564636)
		(end 311.467246 -385.45643)
		(width 0.1016)
		(layer "F.Cu")
		(net "P5E_CPU0_P0_TX_C_DN<7>")
	)
	(segment
		(start 311.467246 -385.45643)
		(end 311.579006 -385.56819)
		(width 0.1016)
		(layer "F.Cu")
		(net "P5E_CPU0_P0_TX_C_DN<7>")
	)
	(segment
		(start 311.724294 -391.51941)
		(end 311.817766 -391.612882)
		(width 0.1016)
		(layer "F.Cu")
		(net "P5E_CPU0_P0_TX_C_DN<7>")
	)
	(arc
		(start 311.51449 -384.450336)
		(mid 311.479503 -384.502791)
		(end 311.467246 -384.564636)
		(width 0.1016)
		(layer "F.Cu")
		(net "P5E_CPU0_P0_TX_C_DN<7>")
	)
	(arc
		(start 311.586626 -386.668518)
		(mid 311.675325 -386.847706)
		(end 311.706514 -387.0452)
		(width 0.1016)
		(layer "F.Cu")
		(net "P5E_CPU0_P0_TX_C_DN<7>")
	)
	(arc
		(start 311.467246 -386.28955)
		(mid 311.497788 -386.488219)
		(end 311.586626 -386.668518)
		(width 0.1016)
		(layer "F.Cu")
		(net "P5E_CPU0_P0_TX_C_DN<7>")
	)
	(segment
		(start 309.90921 -387.034278)
		(end 309.945786 -387.124194)
		(width 0.1016)
		(layer "F.Cu")
		(net "P5E_CPU0_P0_TX_C_DN<6>")
	)
	(segment
		(start 310.524144 -391.51941)
		(end 310.61787 -391.613136)
		(width 0.1016)
		(layer "F.Cu")
		(net "P5E_CPU0_P0_TX_C_DN<6>")
	)
	(segment
		(start 308.412896 -379.22073)
		(end 308.063646 -379.56998)
		(width 0.1016)
		(layer "F.Cu")
		(net "P5E_CPU0_P0_TX_C_DN<6>")
	)
	(segment
		(start 309.782972 -383.231136)
		(end 309.894732 -383.342896)
		(width 0.1016)
		(layer "F.Cu")
		(net "P5E_CPU0_P0_TX_C_DN<6>")
	)
	(segment
		(start 310.61787 -391.613136)
		(end 310.61787 -392.30427)
		(width 0.1016)
		(layer "F.Cu")
		(net "P5E_CPU0_P0_TX_C_DN<6>")
	)
	(segment
		(start 309.782972 -383.759456)
		(end 309.782972 -386.388356)
		(width 0.1016)
		(layer "F.Cu")
		(net "P5E_CPU0_P0_TX_C_DN<6>")
	)
	(segment
		(start 308.063646 -379.56998)
		(end 308.063646 -379.861826)
		(width 0.1016)
		(layer "F.Cu")
		(net "P5E_CPU0_P0_TX_C_DN<6>")
	)
	(segment
		(start 310.524144 -390.076182)
		(end 310.524144 -391.51941)
		(width 0.1016)
		(layer "F.Cu")
		(net "P5E_CPU0_P0_TX_C_DN<6>")
	)
	(segment
		(start 308.327044 -380.496826)
		(end 309.559452 -381.729234)
		(width 0.1016)
		(layer "F.Cu")
		(net "P5E_CPU0_P0_TX_C_DN<6>")
	)
	(segment
		(start 309.894732 -383.647696)
		(end 309.782972 -383.759456)
		(width 0.1016)
		(layer "F.Cu")
		(net "P5E_CPU0_P0_TX_C_DN<6>")
	)
	(segment
		(start 309.894732 -383.342896)
		(end 309.894732 -383.647696)
		(width 0.1016)
		(layer "F.Cu")
		(net "P5E_CPU0_P0_TX_C_DN<6>")
	)
	(segment
		(start 309.782972 -382.26873)
		(end 309.782972 -383.231136)
		(width 0.1016)
		(layer "F.Cu")
		(net "P5E_CPU0_P0_TX_C_DN<6>")
	)
	(arc
		(start 309.559452 -381.729234)
		(mid 309.724817 -381.97677)
		(end 309.782972 -382.26873)
		(width 0.1016)
		(layer "F.Cu")
		(net "P5E_CPU0_P0_TX_C_DN<6>")
	)
	(arc
		(start 308.063646 -379.861826)
		(mid 308.132213 -380.205506)
		(end 308.327044 -380.496826)
		(width 0.1016)
		(layer "F.Cu")
		(net "P5E_CPU0_P0_TX_C_DN<6>")
	)
	(arc
		(start 309.945786 -387.124194)
		(mid 310.378152 -388.572135)
		(end 310.524144 -390.076182)
		(width 0.1016)
		(layer "F.Cu")
		(net "P5E_CPU0_P0_TX_C_DN<6>")
	)
	(arc
		(start 309.782972 -386.388356)
		(mid 309.814845 -386.717425)
		(end 309.90921 -387.034278)
		(width 0.1016)
		(layer "F.Cu")
		(net "P5E_CPU0_P0_TX_C_DN<6>")
	)
	(segment
		(start 306.689506 -384.82397)
		(end 308.619398 -387.710934)
		(width 0.1016)
		(layer "F.Cu")
		(net "P5E_CPU0_P0_TX_C_DN<5>")
	)
	(segment
		(start 306.361846 -383.439416)
		(end 306.361846 -383.744216)
		(width 0.1016)
		(layer "F.Cu")
		(net "P5E_CPU0_P0_TX_C_DN<5>")
	)
	(segment
		(start 309.324248 -391.51941)
		(end 309.41772 -391.612882)
		(width 0.1016)
		(layer "F.Cu")
		(net "P5E_CPU0_P0_TX_C_DN<5>")
	)
	(segment
		(start 306.711096 -381.68453)
		(end 306.361846 -382.03378)
		(width 0.1016)
		(layer "F.Cu")
		(net "P5E_CPU0_P0_TX_C_DN<5>")
	)
	(segment
		(start 306.473606 -383.022856)
		(end 306.473606 -383.327656)
		(width 0.1016)
		(layer "F.Cu")
		(net "P5E_CPU0_P0_TX_C_DN<5>")
	)
	(segment
		(start 309.324248 -390.033764)
		(end 309.324248 -391.51941)
		(width 0.1016)
		(layer "F.Cu")
		(net "P5E_CPU0_P0_TX_C_DN<5>")
	)
	(segment
		(start 309.41772 -391.612882)
		(end 309.41772 -392.30427)
		(width 0.1016)
		(layer "F.Cu")
		(net "P5E_CPU0_P0_TX_C_DN<5>")
	)
	(segment
		(start 306.361846 -382.03378)
		(end 306.361846 -382.911096)
		(width 0.1016)
		(layer "F.Cu")
		(net "P5E_CPU0_P0_TX_C_DN<5>")
	)
	(segment
		(start 306.361846 -382.911096)
		(end 306.473606 -383.022856)
		(width 0.1016)
		(layer "F.Cu")
		(net "P5E_CPU0_P0_TX_C_DN<5>")
	)
	(segment
		(start 306.473606 -383.327656)
		(end 306.361846 -383.439416)
		(width 0.1016)
		(layer "F.Cu")
		(net "P5E_CPU0_P0_TX_C_DN<5>")
	)
	(arc
		(start 306.361846 -383.744216)
		(mid 306.445567 -384.308402)
		(end 306.689506 -384.82397)
		(width 0.1016)
		(layer "F.Cu")
		(net "P5E_CPU0_P0_TX_C_DN<5>")
	)
	(arc
		(start 308.619398 -387.710934)
		(mid 309.144161 -388.820055)
		(end 309.324248 -390.033764)
		(width 0.1016)
		(layer "F.Cu")
		(net "P5E_CPU0_P0_TX_C_DN<5>")
	)
	(segment
		(start 308.217824 -391.612882)
		(end 308.217824 -392.30427)
		(width 0.1016)
		(layer "F.Cu")
		(net "P5E_CPU0_P0_TX_C_DN<4>")
	)
	(segment
		(start 308.124352 -391.51941)
		(end 308.217824 -391.612882)
		(width 0.1016)
		(layer "F.Cu")
		(net "P5E_CPU0_P0_TX_C_DN<4>")
	)
	(segment
		(start 305.753262 -386.260594)
		(end 307.751226 -388.69493)
		(width 0.1016)
		(layer "F.Cu")
		(net "P5E_CPU0_P0_TX_C_DN<4>")
	)
	(segment
		(start 305.009296 -384.14833)
		(end 304.660046 -384.49758)
		(width 0.1016)
		(layer "F.Cu")
		(net "P5E_CPU0_P0_TX_C_DN<4>")
	)
	(segment
		(start 304.660046 -384.49758)
		(end 304.660046 -384.67157)
		(width 0.1016)
		(layer "F.Cu")
		(net "P5E_CPU0_P0_TX_C_DN<4>")
	)
	(segment
		(start 305.417728 -385.851908)
		(end 305.574954 -385.867402)
		(width 0.1016)
		(layer "F.Cu")
		(net "P5E_CPU0_P0_TX_C_DN<4>")
	)
	(segment
		(start 308.124352 -389.955278)
		(end 308.124352 -391.51941)
		(width 0.1016)
		(layer "F.Cu")
		(net "P5E_CPU0_P0_TX_C_DN<4>")
	)
	(segment
		(start 305.768502 -386.103114)
		(end 305.753262 -386.260594)
		(width 0.1016)
		(layer "F.Cu")
		(net "P5E_CPU0_P0_TX_C_DN<4>")
	)
	(segment
		(start 304.875692 -385.191508)
		(end 305.417728 -385.851908)
		(width 0.1016)
		(layer "F.Cu")
		(net "P5E_CPU0_P0_TX_C_DN<4>")
	)
	(segment
		(start 305.574954 -385.867402)
		(end 305.768502 -386.103114)
		(width 0.1016)
		(layer "F.Cu")
		(net "P5E_CPU0_P0_TX_C_DN<4>")
	)
	(segment
		(start 304.660046 -384.67157)
		(end 304.875692 -385.191508)
		(width 0.1016)
		(layer "F.Cu")
		(net "P5E_CPU0_P0_TX_C_DN<4>")
	)
	(arc
		(start 308.124352 -389.954262)
		(mid 308.124352 -389.95477)
		(end 308.124352 -389.955278)
		(width 0.1016)
		(layer "F.Cu")
		(net "P5E_CPU0_P0_TX_C_DN<4>")
	)
	(arc
		(start 307.751226 -388.69493)
		(mid 308.028878 -389.297208)
		(end 308.124352 -389.9535)
		(width 0.1016)
		(layer "F.Cu")
		(net "P5E_CPU0_P0_TX_C_DN<4>")
	)
	(arc
		(start 308.124352 -389.9535)
		(mid 308.124352 -389.953881)
		(end 308.124352 -389.954262)
		(width 0.1016)
		(layer "F.Cu")
		(net "P5E_CPU0_P0_TX_C_DN<4>")
	)
	(segment
		(start 302.349916 -381.150114)
		(end 302.565816 -381.366014)
		(width 0.1016)
		(layer "F.Cu")
		(net "P5E_CPU0_P0_TX_C_DN<3>")
	)
	(segment
		(start 301.256446 -379.56998)
		(end 301.256446 -379.95352)
		(width 0.1016)
		(layer "F.Cu")
		(net "P5E_CPU0_P0_TX_C_DN<3>")
	)
	(segment
		(start 302.565816 -381.366014)
		(end 302.565816 -381.524002)
		(width 0.1016)
		(layer "F.Cu")
		(net "P5E_CPU0_P0_TX_C_DN<3>")
	)
	(segment
		(start 307.017674 -391.612882)
		(end 307.017674 -392.30427)
		(width 0.1016)
		(layer "F.Cu")
		(net "P5E_CPU0_P0_TX_C_DN<3>")
	)
	(segment
		(start 301.441104 -380.39929)
		(end 302.191928 -381.150114)
		(width 0.1016)
		(layer "F.Cu")
		(net "P5E_CPU0_P0_TX_C_DN<3>")
	)
	(segment
		(start 302.96612 -382.120902)
		(end 302.96612 -383.585466)
		(width 0.1016)
		(layer "F.Cu")
		(net "P5E_CPU0_P0_TX_C_DN<3>")
	)
	(segment
		(start 302.191928 -381.150114)
		(end 302.349916 -381.150114)
		(width 0.1016)
		(layer "F.Cu")
		(net "P5E_CPU0_P0_TX_C_DN<3>")
	)
	(segment
		(start 304.123852 -386.3213)
		(end 306.756816 -389.529574)
		(width 0.1016)
		(layer "F.Cu")
		(net "P5E_CPU0_P0_TX_C_DN<3>")
	)
	(segment
		(start 306.924202 -389.996426)
		(end 306.924202 -391.51941)
		(width 0.1016)
		(layer "F.Cu")
		(net "P5E_CPU0_P0_TX_C_DN<3>")
	)
	(segment
		(start 301.605696 -379.22073)
		(end 301.256446 -379.56998)
		(width 0.1016)
		(layer "F.Cu")
		(net "P5E_CPU0_P0_TX_C_DN<3>")
	)
	(segment
		(start 303.015396 -383.834132)
		(end 303.869344 -385.896358)
		(width 0.1016)
		(layer "F.Cu")
		(net "P5E_CPU0_P0_TX_C_DN<3>")
	)
	(segment
		(start 306.924202 -391.51941)
		(end 307.017674 -391.612882)
		(width 0.1016)
		(layer "F.Cu")
		(net "P5E_CPU0_P0_TX_C_DN<3>")
	)
	(segment
		(start 302.565816 -381.524002)
		(end 302.826928 -381.785114)
		(width 0.1016)
		(layer "F.Cu")
		(net "P5E_CPU0_P0_TX_C_DN<3>")
	)
	(segment
		(start 303.869344 -385.896358)
		(end 304.123852 -386.3213)
		(width 0.1016)
		(layer "F.Cu")
		(net "P5E_CPU0_P0_TX_C_DN<3>")
	)
	(arc
		(start 301.256446 -379.95352)
		(mid 301.304434 -380.194774)
		(end 301.441104 -380.39929)
		(width 0.1016)
		(layer "F.Cu")
		(net "P5E_CPU0_P0_TX_C_DN<3>")
	)
	(arc
		(start 306.756816 -389.529574)
		(mid 306.881034 -389.748463)
		(end 306.924202 -389.996426)
		(width 0.1016)
		(layer "F.Cu")
		(net "P5E_CPU0_P0_TX_C_DN<3>")
	)
	(arc
		(start 302.826928 -381.785114)
		(mid 302.929922 -381.939161)
		(end 302.96612 -382.120902)
		(width 0.1016)
		(layer "F.Cu")
		(net "P5E_CPU0_P0_TX_C_DN<3>")
	)
	(arc
		(start 302.96612 -383.585466)
		(mid 302.9785 -383.71223)
		(end 303.015396 -383.834132)
		(width 0.1016)
		(layer "F.Cu")
		(net "P5E_CPU0_P0_TX_C_DN<3>")
	)
	(segment
		(start 299.554646 -382.03378)
		(end 299.554646 -382.664208)
		(width 0.1016)
		(layer "F.Cu")
		(net "P5E_CPU0_P0_TX_C_DN<2>")
	)
	(segment
		(start 302.188372 -384.981704)
		(end 302.90389 -386.70992)
		(width 0.1016)
		(layer "F.Cu")
		(net "P5E_CPU0_P0_TX_C_DN<2>")
	)
	(segment
		(start 303.298098 -387.301994)
		(end 305.504088 -389.987536)
		(width 0.1016)
		(layer "F.Cu")
		(net "P5E_CPU0_P0_TX_C_DN<2>")
	)
	(segment
		(start 301.184564 -383.87655)
		(end 301.479204 -384.17119)
		(width 0.1016)
		(layer "F.Cu")
		(net "P5E_CPU0_P0_TX_C_DN<2>")
	)
	(segment
		(start 302.90389 -386.70992)
		(end 303.038256 -386.93344)
		(width 0.1016)
		(layer "F.Cu")
		(net "P5E_CPU0_P0_TX_C_DN<2>")
	)
	(segment
		(start 299.749464 -383.133854)
		(end 299.79747 -383.18186)
		(width 0.1016)
		(layer "F.Cu")
		(net "P5E_CPU0_P0_TX_C_DN<2>")
	)
	(segment
		(start 301.637192 -384.17119)
		(end 301.853092 -384.38709)
		(width 0.1016)
		(layer "F.Cu")
		(net "P5E_CPU0_P0_TX_C_DN<2>")
	)
	(segment
		(start 305.724306 -391.51941)
		(end 305.817778 -391.612882)
		(width 0.1016)
		(layer "F.Cu")
		(net "P5E_CPU0_P0_TX_C_DN<2>")
	)
	(segment
		(start 301.479204 -384.17119)
		(end 301.637192 -384.17119)
		(width 0.1016)
		(layer "F.Cu")
		(net "P5E_CPU0_P0_TX_C_DN<2>")
	)
	(segment
		(start 301.853092 -384.545078)
		(end 301.984156 -384.676142)
		(width 0.1016)
		(layer "F.Cu")
		(net "P5E_CPU0_P0_TX_C_DN<2>")
	)
	(segment
		(start 301.853092 -384.38709)
		(end 301.853092 -384.545078)
		(width 0.1016)
		(layer "F.Cu")
		(net "P5E_CPU0_P0_TX_C_DN<2>")
	)
	(segment
		(start 305.817778 -391.612882)
		(end 305.817778 -392.30427)
		(width 0.1016)
		(layer "F.Cu")
		(net "P5E_CPU0_P0_TX_C_DN<2>")
	)
	(segment
		(start 300.148244 -383.416556)
		(end 301.063152 -383.795524)
		(width 0.1016)
		(layer "F.Cu")
		(net "P5E_CPU0_P0_TX_C_DN<2>")
	)
	(segment
		(start 299.903896 -381.68453)
		(end 299.554646 -382.03378)
		(width 0.1016)
		(layer "F.Cu")
		(net "P5E_CPU0_P0_TX_C_DN<2>")
	)
	(segment
		(start 305.724306 -390.602216)
		(end 305.724306 -391.51941)
		(width 0.1016)
		(layer "F.Cu")
		(net "P5E_CPU0_P0_TX_C_DN<2>")
	)
	(arc
		(start 301.984156 -384.676142)
		(mid 302.101321 -384.818861)
		(end 302.188372 -384.981704)
		(width 0.1016)
		(layer "F.Cu")
		(net "P5E_CPU0_P0_TX_C_DN<2>")
	)
	(arc
		(start 299.554646 -382.664208)
		(mid 299.605391 -382.91838)
		(end 299.749464 -383.133854)
		(width 0.1016)
		(layer "F.Cu")
		(net "P5E_CPU0_P0_TX_C_DN<2>")
	)
	(arc
		(start 299.79747 -383.18186)
		(mid 299.961308 -383.316467)
		(end 300.148244 -383.416556)
		(width 0.1016)
		(layer "F.Cu")
		(net "P5E_CPU0_P0_TX_C_DN<2>")
	)
	(arc
		(start 305.504088 -389.987536)
		(mid 305.667577 -390.275755)
		(end 305.724306 -390.602216)
		(width 0.1016)
		(layer "F.Cu")
		(net "P5E_CPU0_P0_TX_C_DN<2>")
	)
	(arc
		(start 301.063152 -383.795524)
		(mid 301.127859 -383.830045)
		(end 301.184564 -383.87655)
		(width 0.1016)
		(layer "F.Cu")
		(net "P5E_CPU0_P0_TX_C_DN<2>")
	)
	(arc
		(start 303.038256 -386.93344)
		(mid 303.161415 -387.122484)
		(end 303.298098 -387.301994)
		(width 0.1016)
		(layer "F.Cu")
		(net "P5E_CPU0_P0_TX_C_DN<2>")
	)
	(segment
		(start 301.741332 -387.603238)
		(end 301.910496 -387.856476)
		(width 0.1016)
		(layer "F.Cu")
		(net "P5E_CPU0_P0_TX_C_DN<1>")
	)
	(segment
		(start 302.04918 -388.265162)
		(end 302.204374 -388.29615)
		(width 0.1016)
		(layer "F.Cu")
		(net "P5E_CPU0_P0_TX_C_DN<1>")
	)
	(segment
		(start 301.451772 -387.19633)
		(end 301.598076 -387.256782)
		(width 0.1016)
		(layer "F.Cu")
		(net "P5E_CPU0_P0_TX_C_DN<1>")
	)
	(segment
		(start 299.604938 -384.868166)
		(end 299.689012 -384.868166)
		(width 0.1016)
		(layer "F.Cu")
		(net "P5E_CPU0_P0_TX_C_DN<1>")
	)
	(segment
		(start 304.106834 -391.978896)
		(end 304.2412 -391.978896)
		(width 0.1016)
		(layer "F.Cu")
		(net "P5E_CPU0_P0_TX_C_DN<1>")
	)
	(segment
		(start 301.335186 -386.91439)
		(end 301.451772 -387.19633)
		(width 0.1016)
		(layer "F.Cu")
		(net "P5E_CPU0_P0_TX_C_DN<1>")
	)
	(segment
		(start 302.204374 -388.29615)
		(end 302.318166 -388.46633)
		(width 0.1016)
		(layer "F.Cu")
		(net "P5E_CPU0_P0_TX_C_DN<1>")
	)
	(segment
		(start 302.46574 -388.646162)
		(end 303.06899 -389.249412)
		(width 0.1016)
		(layer "F.Cu")
		(net "P5E_CPU0_P0_TX_C_DN<1>")
	)
	(segment
		(start 304.2412 -391.978896)
		(end 304.317654 -391.902442)
		(width 0.1016)
		(layer "F.Cu")
		(net "P5E_CPU0_P0_TX_C_DN<1>")
	)
	(segment
		(start 304.308256 -391.324592)
		(end 304.015648 -391.6172)
		(width 0.1016)
		(layer "F.Cu")
		(net "P5E_CPU0_P0_TX_C_DN<1>")
	)
	(segment
		(start 299.233844 -385.23926)
		(end 299.604938 -384.868166)
		(width 0.1016)
		(layer "F.Cu")
		(net "P5E_CPU0_P0_TX_C_DN<1>")
	)
	(segment
		(start 301.598076 -387.256782)
		(end 301.741332 -387.603238)
		(width 0.1016)
		(layer "F.Cu")
		(net "P5E_CPU0_P0_TX_C_DN<1>")
	)
	(segment
		(start 304.015648 -391.88771)
		(end 304.106834 -391.978896)
		(width 0.1016)
		(layer "F.Cu")
		(net "P5E_CPU0_P0_TX_C_DN<1>")
	)
	(segment
		(start 304.317654 -391.902442)
		(end 304.317654 -391.784586)
		(width 0.1016)
		(layer "F.Cu")
		(net "P5E_CPU0_P0_TX_C_DN<1>")
	)
	(segment
		(start 304.015648 -391.6172)
		(end 304.015648 -391.88771)
		(width 0.1016)
		(layer "F.Cu")
		(net "P5E_CPU0_P0_TX_C_DN<1>")
	)
	(segment
		(start 303.06899 -389.249412)
		(end 304.080926 -390.482836)
		(width 0.1016)
		(layer "F.Cu")
		(net "P5E_CPU0_P0_TX_C_DN<1>")
	)
	(segment
		(start 301.910496 -387.856476)
		(end 301.879762 -388.01167)
		(width 0.1016)
		(layer "F.Cu")
		(net "P5E_CPU0_P0_TX_C_DN<1>")
	)
	(segment
		(start 301.395638 -386.768594)
		(end 301.335186 -386.91439)
		(width 0.1016)
		(layer "F.Cu")
		(net "P5E_CPU0_P0_TX_C_DN<1>")
	)
	(segment
		(start 304.080926 -390.482836)
		(end 304.207418 -390.693656)
		(width 0.1016)
		(layer "F.Cu")
		(net "P5E_CPU0_P0_TX_C_DN<1>")
	)
	(segment
		(start 304.207418 -390.693656)
		(end 304.308256 -390.936734)
		(width 0.1016)
		(layer "F.Cu")
		(net "P5E_CPU0_P0_TX_C_DN<1>")
	)
	(segment
		(start 300.94555 -385.680966)
		(end 301.395638 -386.768594)
		(width 0.1016)
		(layer "F.Cu")
		(net "P5E_CPU0_P0_TX_C_DN<1>")
	)
	(segment
		(start 300.525942 -385.214876)
		(end 300.852078 -385.541012)
		(width 0.1016)
		(layer "F.Cu")
		(net "P5E_CPU0_P0_TX_C_DN<1>")
	)
	(segment
		(start 304.308256 -390.936734)
		(end 304.308256 -391.324592)
		(width 0.1016)
		(layer "F.Cu")
		(net "P5E_CPU0_P0_TX_C_DN<1>")
	)
	(segment
		(start 301.879762 -388.01167)
		(end 302.04918 -388.265162)
		(width 0.1016)
		(layer "F.Cu")
		(net "P5E_CPU0_P0_TX_C_DN<1>")
	)
	(arc
		(start 300.852078 -385.541012)
		(mid 300.905717 -385.60638)
		(end 300.94555 -385.680966)
		(width 0.1016)
		(layer "F.Cu")
		(net "P5E_CPU0_P0_TX_C_DN<1>")
	)
	(arc
		(start 302.318166 -388.46633)
		(mid 302.387537 -388.55987)
		(end 302.46574 -388.646162)
		(width 0.1016)
		(layer "F.Cu")
		(net "P5E_CPU0_P0_TX_C_DN<1>")
	)
	(arc
		(start 299.689012 -384.868166)
		(mid 300.141957 -384.95828)
		(end 300.525942 -385.214876)
		(width 0.1016)
		(layer "F.Cu")
		(net "P5E_CPU0_P0_TX_C_DN<1>")
	)
	(segment
		(start 321.324224 -391.30859)
		(end 321.418204 -391.40257)
		(width 0.1016)
		(layer "F.Cu")
		(net "P5E_CPU0_P0_TX_C_DN<15>")
	)
	(segment
		(start 321.418204 -392.303762)
		(end 321.417696 -392.30427)
		(width 0.1016)
		(layer "F.Cu")
		(net "P5E_CPU0_P0_TX_C_DN<15>")
	)
	(segment
		(start 321.418204 -391.40257)
		(end 321.418204 -392.303762)
		(width 0.1016)
		(layer "F.Cu")
		(net "P5E_CPU0_P0_TX_C_DN<15>")
	)
	(segment
		(start 325.474076 -388.767828)
		(end 325.124826 -388.418578)
		(width 0.1016)
		(layer "F.Cu")
		(net "P5E_CPU0_P0_TX_C_DN<15>")
	)
	(segment
		(start 325.124826 -388.418578)
		(end 323.419978 -388.418578)
		(width 0.1016)
		(layer "F.Cu")
		(net "P5E_CPU0_P0_TX_C_DN<15>")
	)
	(segment
		(start 323.318886 -388.460488)
		(end 321.41795 -390.361424)
		(width 0.1016)
		(layer "F.Cu")
		(net "P5E_CPU0_P0_TX_C_DN<15>")
	)
	(segment
		(start 321.324224 -390.587484)
		(end 321.324224 -391.30859)
		(width 0.1016)
		(layer "F.Cu")
		(net "P5E_CPU0_P0_TX_C_DN<15>")
	)
	(arc
		(start 321.41795 -390.361424)
		(mid 321.348595 -390.465127)
		(end 321.324224 -390.587484)
		(width 0.1016)
		(layer "F.Cu")
		(net "P5E_CPU0_P0_TX_C_DN<15>")
	)
	(arc
		(start 323.419978 -388.418578)
		(mid 323.365254 -388.429463)
		(end 323.318886 -388.460488)
		(width 0.1016)
		(layer "F.Cu")
		(net "P5E_CPU0_P0_TX_C_DN<15>")
	)
	(segment
		(start 320.124582 -390.071102)
		(end 320.124328 -390.070848)
		(width 0.1016)
		(layer "F.Cu")
		(net "P5E_CPU0_P0_TX_C_DN<14>")
	)
	(segment
		(start 320.124328 -391.30859)
		(end 320.218308 -391.40257)
		(width 0.1016)
		(layer "F.Cu")
		(net "P5E_CPU0_P0_TX_C_DN<14>")
	)
	(segment
		(start 325.474076 -385.364228)
		(end 325.26859 -385.158742)
		(width 0.1016)
		(layer "F.Cu")
		(net "P5E_CPU0_P0_TX_C_DN<14>")
	)
	(segment
		(start 320.218308 -391.40257)
		(end 320.218308 -392.303762)
		(width 0.1016)
		(layer "F.Cu")
		(net "P5E_CPU0_P0_TX_C_DN<14>")
	)
	(segment
		(start 325.26859 -385.158742)
		(end 325.12889 -385.10083)
		(width 0.1016)
		(layer "F.Cu")
		(net "P5E_CPU0_P0_TX_C_DN<14>")
	)
	(segment
		(start 324.814438 -385.10083)
		(end 320.322194 -389.593074)
		(width 0.1016)
		(layer "F.Cu")
		(net "P5E_CPU0_P0_TX_C_DN<14>")
	)
	(segment
		(start 320.218308 -392.303762)
		(end 320.2178 -392.30427)
		(width 0.1016)
		(layer "F.Cu")
		(net "P5E_CPU0_P0_TX_C_DN<14>")
	)
	(segment
		(start 320.124328 -390.070848)
		(end 320.124328 -391.30859)
		(width 0.1016)
		(layer "F.Cu")
		(net "P5E_CPU0_P0_TX_C_DN<14>")
	)
	(segment
		(start 325.12889 -385.10083)
		(end 324.814438 -385.10083)
		(width 0.1016)
		(layer "F.Cu")
		(net "P5E_CPU0_P0_TX_C_DN<14>")
	)
	(arc
		(start 320.322194 -389.593074)
		(mid 320.175868 -389.812439)
		(end 320.124582 -390.071102)
		(width 0.1016)
		(layer "F.Cu")
		(net "P5E_CPU0_P0_TX_C_DN<14>")
	)
	(segment
		(start 318.41567 -391.88771)
		(end 318.506856 -391.978896)
		(width 0.1016)
		(layer "F.Cu")
		(net "P5E_CPU0_P0_TX_C_DN<13>")
	)
	(segment
		(start 325.180706 -380.670816)
		(end 326.385428 -381.875538)
		(width 0.1016)
		(layer "F.Cu")
		(net "P5E_CPU0_P0_TX_C_DN<13>")
	)
	(segment
		(start 324.865746 -379.56998)
		(end 324.865746 -379.909578)
		(width 0.1016)
		(layer "F.Cu")
		(net "P5E_CPU0_P0_TX_C_DN<13>")
	)
	(segment
		(start 326.36714 -382.93548)
		(end 325.94169 -383.36093)
		(width 0.1016)
		(layer "F.Cu")
		(net "P5E_CPU0_P0_TX_C_DN<13>")
	)
	(segment
		(start 318.708278 -391.324592)
		(end 318.41567 -391.6172)
		(width 0.1016)
		(layer "F.Cu")
		(net "P5E_CPU0_P0_TX_C_DN<13>")
	)
	(segment
		(start 325.656702 -383.47904)
		(end 324.77583 -383.47904)
		(width 0.1016)
		(layer "F.Cu")
		(net "P5E_CPU0_P0_TX_C_DN<13>")
	)
	(segment
		(start 318.41567 -391.6172)
		(end 318.41567 -391.88771)
		(width 0.1016)
		(layer "F.Cu")
		(net "P5E_CPU0_P0_TX_C_DN<13>")
	)
	(segment
		(start 324.205346 -383.715006)
		(end 318.808608 -389.111744)
		(width 0.1016)
		(layer "F.Cu")
		(net "P5E_CPU0_P0_TX_C_DN<13>")
	)
	(segment
		(start 326.53986 -382.248156)
		(end 326.53986 -382.518666)
		(width 0.1016)
		(layer "F.Cu")
		(net "P5E_CPU0_P0_TX_C_DN<13>")
	)
	(segment
		(start 318.641222 -391.978896)
		(end 318.717676 -391.902442)
		(width 0.1016)
		(layer "F.Cu")
		(net "P5E_CPU0_P0_TX_C_DN<13>")
	)
)
